(kicad_pcb
	(version 20260206)
	(generator "pcbnew")
	(generator_version "10.0")
	(general
		(thickness 1.6)
		(legacy_teardrops no)
	)
	(paper "A4")
	(layers
		(0 "F.Cu" signal "TOP")
		(4 "In1.Cu" signal "GND")
		(6 "In2.Cu" signal "VCC")
		(8 "In3.Cu" signal "VCC1")
		(10 "In4.Cu" signal "GND1")
		(12 "In5.Cu" signal "IN1")
		(14 "In6.Cu" signal "GND2")
		(16 "In7.Cu" signal "IN2")
		(18 "In8.Cu" signal "GND3")
		(20 "In9.Cu" signal "IN3")
		(22 "In10.Cu" signal "GND4")
		(24 "In11.Cu" signal "IN4")
		(26 "In12.Cu" signal "GND5")
		(28 "In13.Cu" signal "IN5")
		(30 "In14.Cu" signal "GND6")
		(32 "In15.Cu" signal "IN6")
		(34 "In16.Cu" signal "GND7")
		(2 "B.Cu" signal "BOTTOM")
		(9 "F.Adhes" user "F.Adhesive")
		(11 "B.Adhes" user "B.Adhesive")
		(13 "F.Paste" user "Package Geometry/Pastemask Top")
		(15 "B.Paste" user "Package Geometry/Pastemask Bottom")
		(5 "F.SilkS" user "Ref Des/Silkscreen Top")
		(7 "B.SilkS" user "Ref Des/Silkscreen Bottom")
		(1 "F.Mask" user "Board Geometry/Soldermask Top")
		(3 "B.Mask" user "Board Geometry/Soldermask Bottom")
		(17 "Dwgs.User" user "User.Drawings")
		(19 "Cmts.User" user "User.Comments")
		(21 "Eco1.User" user "User.Eco1")
		(23 "Eco2.User" user "User.Eco2")
		(25 "Edge.Cuts" user "Board Geometry/Outline")
		(27 "Margin" user)
		(31 "F.CrtYd" user "Package Geometry/Place Bound Top")
		(29 "B.CrtYd" user "Package Geometry/Place Bound Bottom")
		(35 "F.Fab" user "Ref Des/Assembly Top")
		(33 "B.Fab" user "Ref Des/Assembly Bottom")
	)
	(setup
		(pad_to_mask_clearance 0)
		(allow_soldermask_bridges_in_footprints no)
		(tenting
			(front yes)
			(back yes)
		)
		(covering
			(front no)
			(back no)
		)
		(plugging
			(front no)
			(back no)
		)
		(capping no)
		(filling no)
		(pcbplotparams
			(layerselection 0x00000000_00000000_55555555_5755f5ff)
			(plot_on_all_layers_selection 0x00000000_00000000_00000000_00000000)
			(disableapertmacros no)
			(usegerberextensions no)
			(usegerberattributes yes)
			(usegerberadvancedattributes yes)
			(creategerberjobfile yes)
			(dashed_line_dash_ratio 12)
			(dashed_line_gap_ratio 3)
			(svgprecision 4)
			(plotframeref no)
			(mode 1)
			(useauxorigin no)
			(pdf_front_fp_property_popups yes)
			(pdf_back_fp_property_popups yes)
			(pdf_metadata yes)
			(pdf_single_document no)
			(dxfpolygonmode yes)
			(dxfimperialunits yes)
			(dxfusepcbnewfont yes)
			(psnegative no)
			(psa4output no)
			(plot_black_and_white yes)
			(sketchpadsonfab no)
			(plotpadnumbers no)
			(hidednponfab no)
			(sketchdnponfab yes)
			(crossoutdnponfab yes)
			(subtractmaskfromsilk no)
			(outputformat 1)
			(mirror no)
			(drillshape 1)
			(scaleselection 1)
			(outputdirectory "")
		)
	)
	(segment
		(start 280.762456 -209.76971)
		(end 266.312396 -195.31965)
		(width 0.15494)
		(layer "In13.Cu")
		(net "PRSNT_SSD13_R_N")
	)
	(segment
		(start 332.618334 -214.56904)
		(end 331.1906 -213.141306)
		(width 0.15494)
		(layer "In13.Cu")
		(net "PRSNT_SSD13_R_N")
	)
	(segment
		(start 331.1906 -213.141306)
		(end 331.1906 -211.30133)
		(width 0.15494)
		(layer "In13.Cu")
		(net "PRSNT_SSD13_R_N")
	)
	(segment
		(start 340.49462 -214.163148)
		(end 340.49462 -213.686644)
		(width 0.0889)
		(layer "In13.Cu")
		(net "PRSNT_SSD13_R_N")
	)
	(segment
		(start 331.1906 -211.30133)
		(end 329.49515 -209.60588)
		(width 0.15494)
		(layer "In13.Cu")
		(net "PRSNT_SSD13_R_N")
	)
	(segment
		(start 337.295998 -214.25789)
		(end 337.166204 -214.387684)
		(width 0.0889)
		(layer "In13.Cu")
		(net "PRSNT_SSD13_R_N")
	)
	(segment
		(start 259.454142 -194.7672)
		(end 259.208016 -194.521074)
		(width 0.15494)
		(layer "In13.Cu")
		(net "PRSNT_SSD13_R_N")
	)
	(segment
		(start 340.39302 -213.585044)
		(end 337.500722 -213.585044)
		(width 0.0889)
		(layer "In13.Cu")
		(net "PRSNT_SSD13_R_N")
	)
	(segment
		(start 261.344664 -195.31965)
		(end 260.792214 -194.7672)
		(width 0.15494)
		(layer "In13.Cu")
		(net "PRSNT_SSD13_R_N")
	)
	(segment
		(start 374.462802 -105.01757)
		(end 374.709944 -104.770428)
		(width 0.15494)
		(layer "In13.Cu")
		(net "PRSNT_SSD13_R_N")
	)
	(segment
		(start 259.208016 -193.362834)
		(end 256.332228 -190.487046)
		(width 0.15494)
		(layer "In13.Cu")
		(net "PRSNT_SSD13_R_N")
	)
	(segment
		(start 251.606304 -185.0898)
		(end 246.903748 -185.0898)
		(width 0.15494)
		(layer "In13.Cu")
		(net "PRSNT_SSD13_R_N")
	)
	(segment
		(start 321.68465 -209.76971)
		(end 280.762456 -209.76971)
		(width 0.15494)
		(layer "In13.Cu")
		(net "PRSNT_SSD13_R_N")
	)
	(segment
		(start 322.58381 -210.66887)
		(end 321.68465 -209.76971)
		(width 0.15494)
		(layer "In13.Cu")
		(net "PRSNT_SSD13_R_N")
	)
	(segment
		(start 266.312396 -195.31965)
		(end 261.344664 -195.31965)
		(width 0.15494)
		(layer "In13.Cu")
		(net "PRSNT_SSD13_R_N")
	)
	(segment
		(start 337.500722 -213.585044)
		(end 337.295998 -213.789768)
		(width 0.0889)
		(layer "In13.Cu")
		(net "PRSNT_SSD13_R_N")
	)
	(segment
		(start 256.332228 -189.815724)
		(end 251.606304 -185.0898)
		(width 0.15494)
		(layer "In13.Cu")
		(net "PRSNT_SSD13_R_N")
	)
	(segment
		(start 259.208016 -194.521074)
		(end 259.208016 -193.362834)
		(width 0.15494)
		(layer "In13.Cu")
		(net "PRSNT_SSD13_R_N")
	)
	(via
		(at 188.737748 -255.13284)
		(size 0.508)
		(drill 0.254)
		(layers "F.Cu" "B.Cu")
		(net "UART_PEX1_SDB_R_TX")
	)
	(via
		(at 370.383308 -243.913152)
		(size 0.508)
		(drill 0.254)
		(layers "F.Cu" "B.Cu")
		(net "UART_PEX1_SDB_R_TX")
	)
	(segment
		(start 370.872258 -244.402102)
		(end 370.383308 -243.913152)
		(width 0.13208)
		(layer "B.Cu")
		(net "UART_PEX1_SDB_R_TX")
	)
	(segment
		(start 193.357754 -271.55775)
		(end 188.737748 -266.937744)
		(width 0.13208)
		(layer "B.Cu")
		(net "UART_PEX1_SDB_R_TX")
	)
	(segment
		(start 371.37213 -244.585998)
		(end 371.188234 -244.402102)
		(width 0.13208)
		(layer "B.Cu")
		(net "UART_PEX1_SDB_R_TX")
	)
	(segment
		(start 194.3354 -282.257246)
		(end 194.189604 -282.11145)
		(width 0.13208)
		(layer "B.Cu")
		(net "UART_PEX1_SDB_R_TX")
	)
	(segment
		(start 194.189604 -282.11145)
		(end 193.656204 -282.11145)
		(width 0.13208)
		(layer "B.Cu")
		(net "UART_PEX1_SDB_R_TX")
	)
	(segment
		(start 188.737748 -266.937744)
		(end 188.737748 -255.13284)
		(width 0.13208)
		(layer "B.Cu")
		(net "UART_PEX1_SDB_R_TX")
	)
	(segment
		(start 371.188234 -244.402102)
		(end 370.872258 -244.402102)
		(width 0.13208)
		(layer "B.Cu")
		(net "UART_PEX1_SDB_R_TX")
	)
	(segment
		(start 372.370604 -244.585998)
		(end 371.37213 -244.585998)
		(width 0.13208)
		(layer "B.Cu")
		(net "UART_PEX1_SDB_R_TX")
	)
	(segment
		(start 193.357754 -281.813)
		(end 193.357754 -271.55775)
		(width 0.13208)
		(layer "B.Cu")
		(net "UART_PEX1_SDB_R_TX")
	)
	(segment
		(start 193.656204 -282.11145)
		(end 193.357754 -281.813)
		(width 0.13208)
		(layer "B.Cu")
		(net "UART_PEX1_SDB_R_TX")
	)
	(segment
		(start 191.823848 -289.324796)
		(end 194.06235 -289.324796)
		(width 0.13208)
		(layer "B.Cu")
		(net "UART_PEX1_SDB_R_TX")
	)
	(segment
		(start 194.06235 -289.324796)
		(end 194.3354 -289.051746)
		(width 0.13208)
		(layer "B.Cu")
		(net "UART_PEX1_SDB_R_TX")
	)
	(segment
		(start 194.3354 -289.051746)
		(end 194.3354 -282.257246)
		(width 0.13208)
		(layer "B.Cu")
		(net "UART_PEX1_SDB_R_TX")
	)
	(segment
		(start 260.83514 -262.0264)
		(end 269.971012 -262.0264)
		(width 0.15494)
		(layer "In13.Cu")
		(net "UART_PEX1_SDB_R_TX")
	)
	(segment
		(start 370.166392 -244.130068)
		(end 370.383308 -243.913152)
		(width 0.15494)
		(layer "In13.Cu")
		(net "UART_PEX1_SDB_R_TX")
	)
	(segment
		(start 359.839768 -244.130068)
		(end 370.166392 -244.130068)
		(width 0.15494)
		(layer "In13.Cu")
		(net "UART_PEX1_SDB_R_TX")
	)
	(segment
		(start 357.567992 -246.373142)
		(end 357.596694 -246.373142)
		(width 0.15494)
		(layer "In13.Cu")
		(net "UART_PEX1_SDB_R_TX")
	)
	(segment
		(start 220.175074 -254.002032)
		(end 220.808042 -254.635)
		(width 0.15494)
		(layer "In13.Cu")
		(net "UART_PEX1_SDB_R_TX")
	)
	(segment
		(start 257.404362 -262.274558)
		(end 260.586982 -262.274558)
		(width 0.15494)
		(layer "In13.Cu")
		(net "UART_PEX1_SDB_R_TX")
	)
	(segment
		(start 211.048346 -254.022352)
		(end 211.520532 -254.022352)
		(width 0.15494)
		(layer "In13.Cu")
		(net "UART_PEX1_SDB_R_TX")
	)
	(segment
		(start 188.737748 -255.13284)
		(end 209.937858 -255.13284)
		(width 0.15494)
		(layer "In13.Cu")
		(net "UART_PEX1_SDB_R_TX")
	)
	(segment
		(start 211.540852 -254.002032)
		(end 220.175074 -254.002032)
		(width 0.15494)
		(layer "In13.Cu")
		(net "UART_PEX1_SDB_R_TX")
	)
	(segment
		(start 270.314674 -261.71144)
		(end 272.04289 -259.983224)
		(width 0.15494)
		(layer "In13.Cu")
		(net "UART_PEX1_SDB_R_TX")
	)
	(segment
		(start 353.031806 -248.73458)
		(end 355.363526 -246.40286)
		(width 0.15494)
		(layer "In13.Cu")
		(net "UART_PEX1_SDB_R_TX")
	)
	(segment
		(start 348.07652 -248.73458)
		(end 353.031806 -248.73458)
		(width 0.15494)
		(layer "In13.Cu")
		(net "UART_PEX1_SDB_R_TX")
	)
	(segment
		(start 269.971012 -262.0264)
		(end 270.285972 -261.71144)
		(width 0.15494)
		(layer "In13.Cu")
		(net "UART_PEX1_SDB_R_TX")
	)
	(segment
		(start 230.7082 -254.635)
		(end 231.528366 -255.455166)
		(width 0.15494)
		(layer "In13.Cu")
		(net "UART_PEX1_SDB_R_TX")
	)
	(segment
		(start 309.998618 -262.32358)
		(end 313.008518 -259.31368)
		(width 0.15494)
		(layer "In13.Cu")
		(net "UART_PEX1_SDB_R_TX")
	)
	(segment
		(start 270.285972 -261.71144)
		(end 270.314674 -261.71144)
		(width 0.15494)
		(layer "In13.Cu")
		(net "UART_PEX1_SDB_R_TX")
	)
	(segment
		(start 220.808042 -254.635)
		(end 230.7082 -254.635)
		(width 0.15494)
		(layer "In13.Cu")
		(net "UART_PEX1_SDB_R_TX")
	)
	(segment
		(start 344.39606 -252.41504)
		(end 348.07652 -248.73458)
		(width 0.15494)
		(layer "In13.Cu")
		(net "UART_PEX1_SDB_R_TX")
	)
	(segment
		(start 211.520532 -254.022352)
		(end 211.540852 -254.002032)
		(width 0.15494)
		(layer "In13.Cu")
		(net "UART_PEX1_SDB_R_TX")
	)
	(segment
		(start 231.528366 -255.455166)
		(end 244.787166 -255.455166)
		(width 0.15494)
		(layer "In13.Cu")
		(net "UART_PEX1_SDB_R_TX")
	)
	(segment
		(start 329.521312 -258.75234)
		(end 330.765912 -257.50774)
		(width 0.15494)
		(layer "In13.Cu")
		(net "UART_PEX1_SDB_R_TX")
	)
	(segment
		(start 330.765912 -257.50774)
		(end 339.776054 -257.50774)
		(width 0.15494)
		(layer "In13.Cu")
		(net "UART_PEX1_SDB_R_TX")
	)
	(segment
		(start 252.150626 -262.818626)
		(end 256.860294 -262.818626)
		(width 0.15494)
		(layer "In13.Cu")
		(net "UART_PEX1_SDB_R_TX")
	)
	(segment
		(start 357.538274 -246.40286)
		(end 357.567992 -246.373142)
		(width 0.15494)
		(layer "In13.Cu")
		(net "UART_PEX1_SDB_R_TX")
	)
	(segment
		(start 313.008518 -259.31368)
		(end 323.67347 -259.31368)
		(width 0.15494)
		(layer "In13.Cu")
		(net "UART_PEX1_SDB_R_TX")
	)
	(segment
		(start 256.860294 -262.818626)
		(end 257.404362 -262.274558)
		(width 0.15494)
		(layer "In13.Cu")
		(net "UART_PEX1_SDB_R_TX")
	)
	(segment
		(start 324.23481 -258.75234)
		(end 329.521312 -258.75234)
		(width 0.15494)
		(layer "In13.Cu")
		(net "UART_PEX1_SDB_R_TX")
	)
	(segment
		(start 357.596694 -246.373142)
		(end 359.839768 -244.130068)
		(width 0.15494)
		(layer "In13.Cu")
		(net "UART_PEX1_SDB_R_TX")
	)
	(segment
		(start 355.363526 -246.40286)
		(end 357.538274 -246.40286)
		(width 0.15494)
		(layer "In13.Cu")
		(net "UART_PEX1_SDB_R_TX")
	)
	(segment
		(start 244.787166 -255.455166)
		(end 252.150626 -262.818626)
		(width 0.15494)
		(layer "In13.Cu")
		(net "UART_PEX1_SDB_R_TX")
	)
	(segment
		(start 272.04289 -259.983224)
		(end 274.200366 -259.983224)
		(width 0.15494)
		(layer "In13.Cu")
		(net "UART_PEX1_SDB_R_TX")
	)
	(segment
		(start 300.570646 -262.32358)
		(end 309.998618 -262.32358)
		(width 0.15494)
		(layer "In13.Cu")
		(net "UART_PEX1_SDB_R_TX")
	)
	(segment
		(start 274.200366 -259.983224)
		(end 274.43303 -259.75056)
		(width 0.15494)
		(layer "In13.Cu")
		(net "UART_PEX1_SDB_R_TX")
	)
	(segment
		(start 274.43303 -259.75056)
		(end 297.997626 -259.75056)
		(width 0.15494)
		(layer "In13.Cu")
		(net "UART_PEX1_SDB_R_TX")
	)
	(segment
		(start 297.997626 -259.75056)
		(end 300.570646 -262.32358)
		(width 0.15494)
		(layer "In13.Cu")
		(net "UART_PEX1_SDB_R_TX")
	)
	(segment
		(start 344.39606 -252.887734)
		(end 344.39606 -252.41504)
		(width 0.15494)
		(layer "In13.Cu")
		(net "UART_PEX1_SDB_R_TX")
	)
	(segment
		(start 209.937858 -255.13284)
		(end 211.048346 -254.022352)
		(width 0.15494)
		(layer "In13.Cu")
		(net "UART_PEX1_SDB_R_TX")
	)
	(segment
		(start 339.776054 -257.50774)
		(end 344.39606 -252.887734)
		(width 0.15494)
		(layer "In13.Cu")
		(net "UART_PEX1_SDB_R_TX")
	)
	(segment
		(start 260.586982 -262.274558)
		(end 260.83514 -262.0264)
		(width 0.15494)
		(layer "In13.Cu")
		(net "UART_PEX1_SDB_R_TX")
	)
	(segment
		(start 323.67347 -259.31368)
		(end 324.23481 -258.75234)
		(width 0.15494)
		(layer "In13.Cu")
		(net "UART_PEX1_SDB_R_TX")
	)
	(segment
		(start 398.368012 -19.453098)
		(end 400.316192 -19.453098)
		(width 0.13208)
		(layer "F.Cu")
		(net "SMB_ISO_SSD13_SDA")
	)
	(segment
		(start 397.556482 -20.222972)
		(end 398.326356 -19.453098)
		(width 0.13208)
		(layer "F.Cu")
		(net "SMB_ISO_SSD13_SDA")
	)
	(segment
		(start 397.556482 -20.467574)
		(end 397.556482 -20.222972)
		(width 0.13208)
		(layer "F.Cu")
		(net "SMB_ISO_SSD13_SDA")
	)
	(segment
		(start 401.235672 -18.533618)
		(end 401.235672 -16.439388)
		(width 0.13208)
		(layer "F.Cu")
		(net "SMB_ISO_SSD13_SDA")
	)
	(segment
		(start 401.762468 -23.337266)
		(end 401.762468 -23.946866)
		(width 0.13208)
		(layer "F.Cu")
		(net "SMB_ISO_SSD13_SDA")
	)
	(segment
		(start 398.326356 -19.453098)
		(end 398.368012 -19.453098)
		(width 0.13208)
		(layer "F.Cu")
		(net "SMB_ISO_SSD13_SDA")
	)
	(segment
		(start 400.316192 -19.453098)
		(end 401.235672 -18.533618)
		(width 0.13208)
		(layer "F.Cu")
		(net "SMB_ISO_SSD13_SDA")
	)
	(segment
		(start 401.235672 -16.439388)
		(end 401.311872 -16.363188)
		(width 0.13208)
		(layer "F.Cu")
		(net "SMB_ISO_SSD13_SDA")
	)
	(segment
		(start 401.311872 -16.363188)
		(end 401.311872 -15.351252)
		(width 0.13208)
		(layer "F.Cu")
		(net "SMB_ISO_SSD13_SDA")
	)
	(via
		(at 401.762468 -23.946866)
		(size 0.508)
		(drill 0.254)
		(layers "F.Cu" "B.Cu")
		(net "SMB_ISO_SSD13_SDA")
	)
	(via
		(at 401.311872 -15.351252)
		(size 0.508)
		(drill 0.254)
		(layers "F.Cu" "B.Cu")
		(net "SMB_ISO_SSD13_SDA")
	)
	(segment
		(start 403.412198 -17.52092)
		(end 401.311872 -15.420594)
		(width 0.13208)
		(layer "B.Cu")
		(net "SMB_ISO_SSD13_SDA")
	)
	(segment
		(start 401.311872 -15.420594)
		(end 401.311872 -15.351252)
		(width 0.13208)
		(layer "B.Cu")
		(net "SMB_ISO_SSD13_SDA")
	)
	(segment
		(start 403.412198 -22.297136)
		(end 403.412198 -17.52092)
		(width 0.13208)
		(layer "B.Cu")
		(net "SMB_ISO_SSD13_SDA")
	)
	(segment
		(start 401.762468 -23.946866)
		(end 403.412198 -22.297136)
		(width 0.13208)
		(layer "B.Cu")
		(net "SMB_ISO_SSD13_SDA")
	)
	(segment
		(start 327.533 -239.75695)
		(end 328.060304 -239.75695)
		(width 0.13208)
		(layer "F.Cu")
		(net "PRSNT_GPU_ISO")
	)
	(segment
		(start 327.533 -239.025938)
		(end 327.533 -239.75695)
		(width 0.13208)
		(layer "F.Cu")
		(net "PRSNT_GPU_ISO")
	)
	(segment
		(start 328.060304 -239.75695)
		(end 328.295 -239.522254)
		(width 0.13208)
		(layer "F.Cu")
		(net "PRSNT_GPU_ISO")
	)
	(segment
		(start 327.544938 -238.262922)
		(end 327.544938 -239.014)
		(width 0.13208)
		(layer "F.Cu")
		(net "PRSNT_GPU_ISO")
	)
	(segment
		(start 328.295 -239.522254)
		(end 328.295 -238.262922)
		(width 0.13208)
		(layer "F.Cu")
		(net "PRSNT_GPU_ISO")
	)
	(segment
		(start 327.544938 -239.014)
		(end 327.533 -239.025938)
		(width 0.13208)
		(layer "F.Cu")
		(net "PRSNT_GPU_ISO")
	)
	(via
		(at 327.544938 -239.014)
		(size 0.508)
		(drill 0.254)
		(layers "F.Cu" "B.Cu")
		(net "PRSNT_GPU_ISO")
	)
	(segment
		(start 349.821754 -64.619124)
		(end 352.320352 -64.619124)
		(width 0.13208)
		(layer "F.Cu")
		(net "PWRGD_P12V_SSD12_R")
	)
	(segment
		(start 349.936562 -61.487812)
		(end 349.30461 -62.119764)
		(width 0.13208)
		(layer "F.Cu")
		(net "PWRGD_P12V_SSD12_R")
	)
	(segment
		(start 352.320352 -64.619124)
		(end 352.668332 -64.967104)
		(width 0.13208)
		(layer "F.Cu")
		(net "PWRGD_P12V_SSD12_R")
	)
	(segment
		(start 349.30461 -62.119764)
		(end 349.30461 -64.10198)
		(width 0.13208)
		(layer "F.Cu")
		(net "PWRGD_P12V_SSD12_R")
	)
	(segment
		(start 374.968008 -53.051456)
		(end 375.623328 -53.051456)
		(width 0.13208)
		(layer "F.Cu")
		(net "PWRGD_P12V_SSD12_R")
	)
	(segment
		(start 339.693758 -211.18703)
		(end 339.293962 -210.787234)
		(width 0.13208)
		(layer "F.Cu")
		(net "PWRGD_P12V_SSD12_R")
	)
	(segment
		(start 351.78365 -61.487812)
		(end 349.936562 -61.487812)
		(width 0.13208)
		(layer "F.Cu")
		(net "PWRGD_P12V_SSD12_R")
	)
	(segment
		(start 354.571808 -65.75552)
		(end 363.028738 -65.75552)
		(width 0.13208)
		(layer "F.Cu")
		(net "PWRGD_P12V_SSD12_R")
	)
	(segment
		(start 352.668332 -64.967104)
		(end 354.571808 -65.75552)
		(width 0.13208)
		(layer "F.Cu")
		(net "PWRGD_P12V_SSD12_R")
	)
	(segment
		(start 349.30461 -64.10198)
		(end 349.821754 -64.619124)
		(width 0.13208)
		(layer "F.Cu")
		(net "PWRGD_P12V_SSD12_R")
	)
	(via
		(at 349.277432 -106.892852)
		(size 0.508)
		(drill 0.254)
		(layers "F.Cu" "B.Cu")
		(net "PWRGD_P12V_SSD12_R")
	)
	(via
		(at 375.623328 -53.051456)
		(size 0.508)
		(drill 0.254)
		(layers "F.Cu" "B.Cu")
		(net "PWRGD_P12V_SSD12_R")
	)
	(via
		(at 363.028738 -65.75552)
		(size 0.508)
		(drill 0.254)
		(layers "F.Cu" "B.Cu")
		(net "PWRGD_P12V_SSD12_R")
	)
	(via
		(at 339.293962 -210.787234)
		(size 0.4572)
		(drill 0.254)
		(layers "F.Cu" "B.Cu")
		(net "PWRGD_P12V_SSD12_R")
	)
	(segment
		(start 361.110276 -66.847974)
		(end 362.20273 -65.75552)
		(width 0.15494)
		(layer "In5.Cu")
		(net "PWRGD_P12V_SSD12_R")
	)
	(segment
		(start 373.561356 -57.501028)
		(end 373.94642 -57.886092)
		(width 0.15494)
		(layer "In5.Cu")
		(net "PWRGD_P12V_SSD12_R")
	)
	(segment
		(start 361.110276 -74.663554)
		(end 361.110276 -66.847974)
		(width 0.15494)
		(layer "In5.Cu")
		(net "PWRGD_P12V_SSD12_R")
	)
	(segment
		(start 362.20273 -65.75552)
		(end 363.028738 -65.75552)
		(width 0.15494)
		(layer "In5.Cu")
		(net "PWRGD_P12V_SSD12_R")
	)
	(segment
		(start 375.623328 -53.051456)
		(end 373.561356 -55.113428)
		(width 0.15494)
		(layer "In5.Cu")
		(net "PWRGD_P12V_SSD12_R")
	)
	(segment
		(start 373.561356 -55.113428)
		(end 373.561356 -57.501028)
		(width 0.15494)
		(layer "In5.Cu")
		(net "PWRGD_P12V_SSD12_R")
	)
	(segment
		(start 373.559832 -64.217042)
		(end 367.967768 -64.217042)
		(width 0.15494)
		(layer "In5.Cu")
		(net "PWRGD_P12V_SSD12_R")
	)
	(segment
		(start 355.133148 -92.014294)
		(end 355.133148 -80.640682)
		(width 0.15494)
		(layer "In5.Cu")
		(net "PWRGD_P12V_SSD12_R")
	)
	(segment
		(start 351.355914 -104.81437)
		(end 351.355914 -95.791528)
		(width 0.15494)
		(layer "In5.Cu")
		(net "PWRGD_P12V_SSD12_R")
	)
	(segment
		(start 355.133148 -80.640682)
		(end 361.110276 -74.663554)
		(width 0.15494)
		(layer "In5.Cu")
		(net "PWRGD_P12V_SSD12_R")
	)
	(segment
		(start 367.967768 -64.217042)
		(end 366.42929 -65.75552)
		(width 0.15494)
		(layer "In5.Cu")
		(net "PWRGD_P12V_SSD12_R")
	)
	(segment
		(start 349.277432 -106.892852)
		(end 351.355914 -104.81437)
		(width 0.15494)
		(layer "In5.Cu")
		(net "PWRGD_P12V_SSD12_R")
	)
	(segment
		(start 351.355914 -95.791528)
		(end 355.133148 -92.014294)
		(width 0.15494)
		(layer "In5.Cu")
		(net "PWRGD_P12V_SSD12_R")
	)
	(segment
		(start 373.94642 -57.886092)
		(end 373.94642 -63.830454)
		(width 0.15494)
		(layer "In5.Cu")
		(net "PWRGD_P12V_SSD12_R")
	)
	(segment
		(start 373.94642 -63.830454)
		(end 373.559832 -64.217042)
		(width 0.15494)
		(layer "In5.Cu")
		(net "PWRGD_P12V_SSD12_R")
	)
	(segment
		(start 366.42929 -65.75552)
		(end 363.028738 -65.75552)
		(width 0.15494)
		(layer "In5.Cu")
		(net "PWRGD_P12V_SSD12_R")
	)
	(segment
		(start 341.60587 -185.214514)
		(end 345.286076 -181.534308)
		(width 0.15494)
		(layer "In7.Cu")
		(net "PWRGD_P12V_SSD12_R")
	)
	(segment
		(start 350.370648 -107.986068)
		(end 349.277432 -106.892852)
		(width 0.15494)
		(layer "In7.Cu")
		(net "PWRGD_P12V_SSD12_R")
	)
	(segment
		(start 350.370648 -119.103394)
		(end 350.370648 -107.986068)
		(width 0.15494)
		(layer "In7.Cu")
		(net "PWRGD_P12V_SSD12_R")
	)
	(segment
		(start 350.309688 -119.222266)
		(end 350.309688 -119.164354)
		(width 0.15494)
		(layer "In7.Cu")
		(net "PWRGD_P12V_SSD12_R")
	)
	(segment
		(start 340.572598 -185.563002)
		(end 341.257382 -185.563002)
		(width 0.15494)
		(layer "In7.Cu")
		(net "PWRGD_P12V_SSD12_R")
	)
	(segment
		(start 339.293962 -210.787234)
		(end 338.7852 -210.278472)
		(width 0.15494)
		(layer "In7.Cu")
		(net "PWRGD_P12V_SSD12_R")
	)
	(segment
		(start 345.245436 -172.160692)
		(end 343.985596 -170.900852)
		(width 0.15494)
		(layer "In7.Cu")
		(net "PWRGD_P12V_SSD12_R")
	)
	(segment
		(start 339.085174 -199.537066)
		(end 338.7852 -199.237092)
		(width 0.15494)
		(layer "In7.Cu")
		(net "PWRGD_P12V_SSD12_R")
	)
	(segment
		(start 343.4842 -140.716)
		(end 343.4842 -126.047754)
		(width 0.15494)
		(layer "In7.Cu")
		(net "PWRGD_P12V_SSD12_R")
	)
	(segment
		(start 350.309688 -119.164354)
		(end 350.370648 -119.103394)
		(width 0.15494)
		(layer "In7.Cu")
		(net "PWRGD_P12V_SSD12_R")
	)
	(segment
		(start 339.6234 -207.278732)
		(end 339.6234 -205.357476)
		(width 0.15494)
		(layer "In7.Cu")
		(net "PWRGD_P12V_SSD12_R")
	)
	(segment
		(start 345.286076 -172.538644)
		(end 345.245436 -172.498004)
		(width 0.15494)
		(layer "In7.Cu")
		(net "PWRGD_P12V_SSD12_R")
	)
	(segment
		(start 339.085174 -204.81925)
		(end 339.085174 -199.537066)
		(width 0.15494)
		(layer "In7.Cu")
		(net "PWRGD_P12V_SSD12_R")
	)
	(segment
		(start 341.308182 -185.512202)
		(end 341.32266 -185.512202)
		(width 0.15494)
		(layer "In7.Cu")
		(net "PWRGD_P12V_SSD12_R")
	)
	(segment
		(start 345.245436 -172.498004)
		(end 345.245436 -172.160692)
		(width 0.15494)
		(layer "In7.Cu")
		(net "PWRGD_P12V_SSD12_R")
	)
	(segment
		(start 343.4842 -126.047754)
		(end 350.309688 -119.222266)
		(width 0.15494)
		(layer "In7.Cu")
		(net "PWRGD_P12V_SSD12_R")
	)
	(segment
		(start 338.7852 -208.116932)
		(end 339.6234 -207.278732)
		(width 0.15494)
		(layer "In7.Cu")
		(net "PWRGD_P12V_SSD12_R")
	)
	(segment
		(start 343.985596 -170.900852)
		(end 343.985596 -169.182796)
		(width 0.15494)
		(layer "In7.Cu")
		(net "PWRGD_P12V_SSD12_R")
	)
	(segment
		(start 343.985596 -169.182796)
		(end 342.5698 -167.767)
		(width 0.15494)
		(layer "In7.Cu")
		(net "PWRGD_P12V_SSD12_R")
	)
	(segment
		(start 342.5698 -141.6304)
		(end 343.4842 -140.716)
		(width 0.15494)
		(layer "In7.Cu")
		(net "PWRGD_P12V_SSD12_R")
	)
	(segment
		(start 338.7852 -210.278472)
		(end 338.7852 -208.116932)
		(width 0.15494)
		(layer "In7.Cu")
		(net "PWRGD_P12V_SSD12_R")
	)
	(segment
		(start 339.6234 -205.357476)
		(end 339.085174 -204.81925)
		(width 0.15494)
		(layer "In7.Cu")
		(net "PWRGD_P12V_SSD12_R")
	)
	(segment
		(start 341.60587 -185.228992)
		(end 341.60587 -185.214514)
		(width 0.15494)
		(layer "In7.Cu")
		(net "PWRGD_P12V_SSD12_R")
	)
	(segment
		(start 338.7852 -187.3504)
		(end 340.572598 -185.563002)
		(width 0.15494)
		(layer "In7.Cu")
		(net "PWRGD_P12V_SSD12_R")
	)
	(segment
		(start 341.32266 -185.512202)
		(end 341.60587 -185.228992)
		(width 0.15494)
		(layer "In7.Cu")
		(net "PWRGD_P12V_SSD12_R")
	)
	(segment
		(start 341.257382 -185.563002)
		(end 341.308182 -185.512202)
		(width 0.15494)
		(layer "In7.Cu")
		(net "PWRGD_P12V_SSD12_R")
	)
	(segment
		(start 338.7852 -199.237092)
		(end 338.7852 -187.3504)
		(width 0.15494)
		(layer "In7.Cu")
		(net "PWRGD_P12V_SSD12_R")
	)
	(segment
		(start 342.5698 -167.767)
		(end 342.5698 -141.6304)
		(width 0.15494)
		(layer "In7.Cu")
		(net "PWRGD_P12V_SSD12_R")
	)
	(segment
		(start 345.286076 -181.534308)
		(end 345.286076 -172.538644)
		(width 0.15494)
		(layer "In7.Cu")
		(net "PWRGD_P12V_SSD12_R")
	)
	(segment
		(start 166.580058 -51.670966)
		(end 167.231568 -51.019456)
		(width 0.13208)
		(layer "F.Cu")
		(net "P12V_SSD5_SS")
	)
	(segment
		(start 166.580058 -52.994814)
		(end 166.580058 -51.670966)
		(width 0.13208)
		(layer "F.Cu")
		(net "P12V_SSD5_SS")
	)
	(segment
		(start 166.247318 -53.144166)
		(end 166.430706 -53.144166)
		(width 0.13208)
		(layer "F.Cu")
		(net "P12V_SSD5_SS")
	)
	(segment
		(start 166.430706 -53.144166)
		(end 166.580058 -52.994814)
		(width 0.13208)
		(layer "F.Cu")
		(net "P12V_SSD5_SS")
	)
	(segment
		(start 167.231568 -51.019456)
		(end 167.967914 -51.019456)
		(width 0.13208)
		(layer "F.Cu")
		(net "P12V_SSD5_SS")
	)
	(via
		(at 167.231568 -51.019456)
		(size 0.508)
		(drill 0.254)
		(layers "F.Cu" "B.Cu")
		(net "P12V_SSD5_SS")
	)
	(via
		(at 371.348 -243.078)
		(size 0.508)
		(drill 0.254)
		(layers "F.Cu" "B.Cu")
		(net "UART_PEX0_SDB_R_TX")
	)
	(via
		(at 86.633558 -258.586224)
		(size 0.508)
		(drill 0.254)
		(layers "F.Cu" "B.Cu")
		(net "UART_PEX0_SDB_R_TX")
	)
	(segment
		(start 85.093048 -259.150358)
		(end 77.257656 -266.98575)
		(width 0.13208)
		(layer "B.Cu")
		(net "UART_PEX0_SDB_R_TX")
	)
	(segment
		(start 371.556026 -243.286026)
		(end 371.348 -243.078)
		(width 0.13208)
		(layer "B.Cu")
		(net "UART_PEX0_SDB_R_TX")
	)
	(segment
		(start 86.069424 -259.150358)
		(end 85.093048 -259.150358)
		(width 0.13208)
		(layer "B.Cu")
		(net "UART_PEX0_SDB_R_TX")
	)
	(segment
		(start 76.3397 -289.324796)
		(end 75.72375 -289.324796)
		(width 0.13208)
		(layer "B.Cu")
		(net "UART_PEX0_SDB_R_TX")
	)
	(segment
		(start 372.370604 -243.286026)
		(end 371.556026 -243.286026)
		(width 0.13208)
		(layer "B.Cu")
		(net "UART_PEX0_SDB_R_TX")
	)
	(segment
		(start 77.257656 -266.98575)
		(end 77.257656 -288.40684)
		(width 0.13208)
		(layer "B.Cu")
		(net "UART_PEX0_SDB_R_TX")
	)
	(segment
		(start 86.633558 -258.586224)
		(end 86.069424 -259.150358)
		(width 0.13208)
		(layer "B.Cu")
		(net "UART_PEX0_SDB_R_TX")
	)
	(segment
		(start 77.257656 -288.40684)
		(end 76.3397 -289.324796)
		(width 0.13208)
		(layer "B.Cu")
		(net "UART_PEX0_SDB_R_TX")
	)
	(segment
		(start 209.648806 -254.32639)
		(end 210.813396 -253.1618)
		(width 0.15494)
		(layer "In13.Cu")
		(net "UART_PEX0_SDB_R_TX")
	)
	(segment
		(start 343.93632 -252.697234)
		(end 343.93632 -252.22454)
		(width 0.15494)
		(layer "In13.Cu")
		(net "UART_PEX0_SDB_R_TX")
	)
	(segment
		(start 259.2578 -261.030212)
		(end 259.633212 -260.6548)
		(width 0.15494)
		(layer "In13.Cu")
		(net "UART_PEX0_SDB_R_TX")
	)
	(segment
		(start 250.52909 -260.288532)
		(end 250.8123 -260.571742)
		(width 0.15494)
		(layer "In13.Cu")
		(net "UART_PEX0_SDB_R_TX")
	)
	(segment
		(start 347.88602 -248.27484)
		(end 352.841306 -248.27484)
		(width 0.15494)
		(layer "In13.Cu")
		(net "UART_PEX0_SDB_R_TX")
	)
	(segment
		(start 252.611636 -262.3566)
		(end 256.301494 -262.3566)
		(width 0.15494)
		(layer "In13.Cu")
		(net "UART_PEX0_SDB_R_TX")
	)
	(segment
		(start 312.818018 -258.85394)
		(end 323.48297 -258.85394)
		(width 0.15494)
		(layer "In13.Cu")
		(net "UART_PEX0_SDB_R_TX")
	)
	(segment
		(start 250.826778 -260.571742)
		(end 252.611636 -262.3566)
		(width 0.15494)
		(layer "In13.Cu")
		(net "UART_PEX0_SDB_R_TX")
	)
	(segment
		(start 250.8123 -260.571742)
		(end 250.826778 -260.571742)
		(width 0.15494)
		(layer "In13.Cu")
		(net "UART_PEX0_SDB_R_TX")
	)
	(segment
		(start 99.020376 -258.586224)
		(end 113.368582 -244.238018)
		(width 0.15494)
		(layer "In13.Cu")
		(net "UART_PEX0_SDB_R_TX")
	)
	(segment
		(start 230.8987 -254.17526)
		(end 231.718866 -254.995426)
		(width 0.15494)
		(layer "In13.Cu")
		(net "UART_PEX0_SDB_R_TX")
	)
	(segment
		(start 179.69738 -254.32639)
		(end 209.648806 -254.32639)
		(width 0.15494)
		(layer "In13.Cu")
		(net "UART_PEX0_SDB_R_TX")
	)
	(segment
		(start 257.627882 -261.030212)
		(end 259.2578 -261.030212)
		(width 0.15494)
		(layer "In13.Cu")
		(net "UART_PEX0_SDB_R_TX")
	)
	(segment
		(start 265.7348 -261.493)
		(end 269.854172 -261.493)
		(width 0.15494)
		(layer "In13.Cu")
		(net "UART_PEX0_SDB_R_TX")
	)
	(segment
		(start 150.175468 -246.882412)
		(end 172.253402 -246.882412)
		(width 0.15494)
		(layer "In13.Cu")
		(net "UART_PEX0_SDB_R_TX")
	)
	(segment
		(start 210.813396 -253.1618)
		(end 220.065346 -253.1618)
		(width 0.15494)
		(layer "In13.Cu")
		(net "UART_PEX0_SDB_R_TX")
	)
	(segment
		(start 328.064368 -258.20624)
		(end 328.27976 -258.20624)
		(width 0.15494)
		(layer "In13.Cu")
		(net "UART_PEX0_SDB_R_TX")
	)
	(segment
		(start 272.085054 -259.29082)
		(end 298.188126 -259.29082)
		(width 0.15494)
		(layer "In13.Cu")
		(net "UART_PEX0_SDB_R_TX")
	)
	(segment
		(start 270.095726 -261.251446)
		(end 270.124428 -261.251446)
		(width 0.15494)
		(layer "In13.Cu")
		(net "UART_PEX0_SDB_R_TX")
	)
	(segment
		(start 328.064114 -258.205986)
		(end 328.064368 -258.20624)
		(width 0.15494)
		(layer "In13.Cu")
		(net "UART_PEX0_SDB_R_TX")
	)
	(segment
		(start 231.718866 -254.995426)
		(end 245.250462 -254.995426)
		(width 0.15494)
		(layer "In13.Cu")
		(net "UART_PEX0_SDB_R_TX")
	)
	(segment
		(start 136.078976 -243.774976)
		(end 138.86307 -246.55907)
		(width 0.15494)
		(layer "In13.Cu")
		(net "UART_PEX0_SDB_R_TX")
	)
	(segment
		(start 264.8966 -260.6548)
		(end 265.7348 -261.493)
		(width 0.15494)
		(layer "In13.Cu")
		(net "UART_PEX0_SDB_R_TX")
	)
	(segment
		(start 259.633212 -260.6548)
		(end 264.8966 -260.6548)
		(width 0.15494)
		(layer "In13.Cu")
		(net "UART_PEX0_SDB_R_TX")
	)
	(segment
		(start 149.852126 -246.55907)
		(end 150.175468 -246.882412)
		(width 0.15494)
		(layer "In13.Cu")
		(net "UART_PEX0_SDB_R_TX")
	)
	(segment
		(start 300.761146 -261.86384)
		(end 309.808118 -261.86384)
		(width 0.15494)
		(layer "In13.Cu")
		(net "UART_PEX0_SDB_R_TX")
	)
	(segment
		(start 245.250462 -254.995426)
		(end 250.52909 -260.274054)
		(width 0.15494)
		(layer "In13.Cu")
		(net "UART_PEX0_SDB_R_TX")
	)
	(segment
		(start 328.27976 -258.20624)
		(end 329.438 -257.048)
		(width 0.15494)
		(layer "In13.Cu")
		(net "UART_PEX0_SDB_R_TX")
	)
	(segment
		(start 298.188126 -259.29082)
		(end 300.761146 -261.86384)
		(width 0.15494)
		(layer "In13.Cu")
		(net "UART_PEX0_SDB_R_TX")
	)
	(segment
		(start 370.51488 -243.078)
		(end 371.348 -243.078)
		(width 0.15494)
		(layer "In13.Cu")
		(net "UART_PEX0_SDB_R_TX")
	)
	(segment
		(start 269.854172 -261.493)
		(end 270.095726 -261.251446)
		(width 0.15494)
		(layer "In13.Cu")
		(net "UART_PEX0_SDB_R_TX")
	)
	(segment
		(start 355.202744 -245.913402)
		(end 357.406194 -245.913402)
		(width 0.15494)
		(layer "In13.Cu")
		(net "UART_PEX0_SDB_R_TX")
	)
	(segment
		(start 250.52909 -260.274054)
		(end 250.52909 -260.288532)
		(width 0.15494)
		(layer "In13.Cu")
		(net "UART_PEX0_SDB_R_TX")
	)
	(segment
		(start 357.406194 -245.913402)
		(end 360.597196 -242.7224)
		(width 0.15494)
		(layer "In13.Cu")
		(net "UART_PEX0_SDB_R_TX")
	)
	(segment
		(start 172.253402 -246.882412)
		(end 179.69738 -254.32639)
		(width 0.15494)
		(layer "In13.Cu")
		(net "UART_PEX0_SDB_R_TX")
	)
	(segment
		(start 324.130924 -258.205986)
		(end 328.064114 -258.205986)
		(width 0.15494)
		(layer "In13.Cu")
		(net "UART_PEX0_SDB_R_TX")
	)
	(segment
		(start 323.48297 -258.85394)
		(end 324.130924 -258.205986)
		(width 0.15494)
		(layer "In13.Cu")
		(net "UART_PEX0_SDB_R_TX")
	)
	(segment
		(start 339.585554 -257.048)
		(end 343.93632 -252.697234)
		(width 0.15494)
		(layer "In13.Cu")
		(net "UART_PEX0_SDB_R_TX")
	)
	(segment
		(start 370.15928 -242.7224)
		(end 370.51488 -243.078)
		(width 0.15494)
		(layer "In13.Cu")
		(net "UART_PEX0_SDB_R_TX")
	)
	(segment
		(start 133.703822 -244.238018)
		(end 134.166864 -243.774976)
		(width 0.15494)
		(layer "In13.Cu")
		(net "UART_PEX0_SDB_R_TX")
	)
	(segment
		(start 256.301494 -262.3566)
		(end 257.627882 -261.030212)
		(width 0.15494)
		(layer "In13.Cu")
		(net "UART_PEX0_SDB_R_TX")
	)
	(segment
		(start 360.597196 -242.7224)
		(end 370.15928 -242.7224)
		(width 0.15494)
		(layer "In13.Cu")
		(net "UART_PEX0_SDB_R_TX")
	)
	(segment
		(start 134.166864 -243.774976)
		(end 136.078976 -243.774976)
		(width 0.15494)
		(layer "In13.Cu")
		(net "UART_PEX0_SDB_R_TX")
	)
	(segment
		(start 352.841306 -248.27484)
		(end 355.202744 -245.913402)
		(width 0.15494)
		(layer "In13.Cu")
		(net "UART_PEX0_SDB_R_TX")
	)
	(segment
		(start 221.078806 -254.17526)
		(end 230.8987 -254.17526)
		(width 0.15494)
		(layer "In13.Cu")
		(net "UART_PEX0_SDB_R_TX")
	)
	(segment
		(start 309.808118 -261.86384)
		(end 312.818018 -258.85394)
		(width 0.15494)
		(layer "In13.Cu")
		(net "UART_PEX0_SDB_R_TX")
	)
	(segment
		(start 113.368582 -244.238018)
		(end 133.703822 -244.238018)
		(width 0.15494)
		(layer "In13.Cu")
		(net "UART_PEX0_SDB_R_TX")
	)
	(segment
		(start 343.93632 -252.22454)
		(end 347.88602 -248.27484)
		(width 0.15494)
		(layer "In13.Cu")
		(net "UART_PEX0_SDB_R_TX")
	)
	(segment
		(start 86.633558 -258.586224)
		(end 99.020376 -258.586224)
		(width 0.15494)
		(layer "In13.Cu")
		(net "UART_PEX0_SDB_R_TX")
	)
	(segment
		(start 220.065346 -253.1618)
		(end 221.078806 -254.17526)
		(width 0.15494)
		(layer "In13.Cu")
		(net "UART_PEX0_SDB_R_TX")
	)
	(segment
		(start 270.124428 -261.251446)
		(end 272.085054 -259.29082)
		(width 0.15494)
		(layer "In13.Cu")
		(net "UART_PEX0_SDB_R_TX")
	)
	(segment
		(start 329.438 -257.048)
		(end 339.585554 -257.048)
		(width 0.15494)
		(layer "In13.Cu")
		(net "UART_PEX0_SDB_R_TX")
	)
	(segment
		(start 138.86307 -246.55907)
		(end 149.852126 -246.55907)
		(width 0.15494)
		(layer "In13.Cu")
		(net "UART_PEX0_SDB_R_TX")
	)
	(segment
		(start 452.585328 -16.439388)
		(end 452.585328 -18.407126)
		(width 0.13208)
		(layer "F.Cu")
		(net "SMB_ISO_SSD15_SCL")
	)
	(segment
		(start 452.759318 -23.355554)
		(end 452.759318 -23.965154)
		(width 0.13208)
		(layer "F.Cu")
		(net "SMB_ISO_SSD15_SCL")
	)
	(segment
		(start 452.585328 -18.407126)
		(end 452.001636 -18.990818)
		(width 0.13208)
		(layer "F.Cu")
		(net "SMB_ISO_SSD15_SCL")
	)
	(segment
		(start 450.32422 -18.437098)
		(end 450.367908 -18.437098)
		(width 0.13208)
		(layer "F.Cu")
		(net "SMB_ISO_SSD15_SCL")
	)
	(segment
		(start 449.556378 -17.419574)
		(end 449.556378 -17.669256)
		(width 0.13208)
		(layer "F.Cu")
		(net "SMB_ISO_SSD15_SCL")
	)
	(segment
		(start 449.556378 -17.669256)
		(end 450.32422 -18.437098)
		(width 0.13208)
		(layer "F.Cu")
		(net "SMB_ISO_SSD15_SCL")
	)
	(segment
		(start 452.585328 -16.439388)
		(end 452.585328 -15.370302)
		(width 0.13208)
		(layer "F.Cu")
		(net "SMB_ISO_SSD15_SCL")
	)
	(segment
		(start 450.921628 -18.990818)
		(end 450.367908 -18.437098)
		(width 0.13208)
		(layer "F.Cu")
		(net "SMB_ISO_SSD15_SCL")
	)
	(segment
		(start 452.001636 -18.990818)
		(end 450.921628 -18.990818)
		(width 0.13208)
		(layer "F.Cu")
		(net "SMB_ISO_SSD15_SCL")
	)
	(via
		(at 452.759318 -23.965154)
		(size 0.508)
		(drill 0.254)
		(layers "F.Cu" "B.Cu")
		(net "SMB_ISO_SSD15_SCL")
	)
	(via
		(at 452.585328 -15.370302)
		(size 0.508)
		(drill 0.254)
		(layers "F.Cu" "B.Cu")
		(net "SMB_ISO_SSD15_SCL")
	)
	(segment
		(start 452.759318 -23.965154)
		(end 453.168258 -23.556214)
		(width 0.13208)
		(layer "B.Cu")
		(net "SMB_ISO_SSD15_SCL")
	)
	(segment
		(start 453.168258 -16.346424)
		(end 452.585328 -15.763494)
		(width 0.13208)
		(layer "B.Cu")
		(net "SMB_ISO_SSD15_SCL")
	)
	(segment
		(start 453.168258 -23.556214)
		(end 453.168258 -16.346424)
		(width 0.13208)
		(layer "B.Cu")
		(net "SMB_ISO_SSD15_SCL")
	)
	(segment
		(start 452.585328 -15.763494)
		(end 452.585328 -15.370302)
		(width 0.13208)
		(layer "B.Cu")
		(net "SMB_ISO_SSD15_SCL")
	)
	(segment
		(start 318.303656 -27.04973)
		(end 318.32042 -27.066494)
		(width 0.13208)
		(layer "F.Cu")
		(net "PRSNT_SSD11_R_N")
	)
	(segment
		(start 317.308992 -27.04973)
		(end 318.303656 -27.04973)
		(width 0.13208)
		(layer "F.Cu")
		(net "PRSNT_SSD11_R_N")
	)
	(segment
		(start 338.893912 -210.254088)
		(end 339.217 -209.931)
		(width 0.13208)
		(layer "F.Cu")
		(net "PRSNT_SSD11_R_N")
	)
	(segment
		(start 317.308992 -26.03373)
		(end 317.308992 -27.04973)
		(width 0.13208)
		(layer "F.Cu")
		(net "PRSNT_SSD11_R_N")
	)
	(segment
		(start 316.775592 -36.515548)
		(end 317.596012 -36.515548)
		(width 0.13208)
		(layer "F.Cu")
		(net "PRSNT_SSD11_R_N")
	)
	(segment
		(start 338.893912 -211.18703)
		(end 338.893912 -210.254088)
		(width 0.0889)
		(layer "F.Cu")
		(net "PRSNT_SSD11_R_N")
	)
	(segment
		(start 318.32042 -27.066494)
		(end 319.142364 -27.066494)
		(width 0.13208)
		(layer "F.Cu")
		(net "PRSNT_SSD11_R_N")
	)
	(segment
		(start 339.217 -209.931)
		(end 339.293962 -209.931)
		(width 0.13208)
		(layer "F.Cu")
		(net "PRSNT_SSD11_R_N")
	)
	(segment
		(start 234.667552 -221.504256)
		(end 235.067348 -221.904052)
		(width 0.13208)
		(layer "F.Cu")
		(net "PRSNT_SSD11_R_N")
	)
	(via
		(at 319.142364 -27.066494)
		(size 0.508)
		(drill 0.254)
		(layers "F.Cu" "B.Cu")
		(net "PRSNT_SSD11_R_N")
	)
	(via
		(at 339.293962 -209.931)
		(size 0.508)
		(drill 0.254)
		(layers "F.Cu" "B.Cu")
		(net "PRSNT_SSD11_R_N")
	)
	(via
		(at 349.764096 -101.019102)
		(size 0.508)
		(drill 0.254)
		(layers "F.Cu" "B.Cu")
		(net "PRSNT_SSD11_R_N")
	)
	(via
		(at 326.242426 -91.281758)
		(size 0.508)
		(drill 0.254)
		(layers "F.Cu" "B.Cu")
		(net "PRSNT_SSD11_R_N")
	)
	(via
		(at 317.596012 -36.515548)
		(size 0.508)
		(drill 0.254)
		(layers "F.Cu" "B.Cu")
		(net "PRSNT_SSD11_R_N")
	)
	(via
		(at 235.067348 -221.904052)
		(size 0.4572)
		(drill 0.254)
		(layers "F.Cu" "B.Cu")
		(net "PRSNT_SSD11_R_N")
	)
	(via
		(at 246.021606 -183.498236)
		(size 0.508)
		(drill 0.254)
		(layers "F.Cu" "B.Cu")
		(net "PRSNT_SSD11_R_N")
	)
	(segment
		(start 326.77989 -91.819222)
		(end 326.242426 -91.281758)
		(width 0.13208)
		(layer "B.Cu")
		(net "PRSNT_SSD11_R_N")
	)
	(segment
		(start 344.0176 -93.6752)
		(end 333.716884 -93.6752)
		(width 0.13208)
		(layer "B.Cu")
		(net "PRSNT_SSD11_R_N")
	)
	(segment
		(start 349.764096 -99.421696)
		(end 344.0176 -93.6752)
		(width 0.13208)
		(layer "B.Cu")
		(net "PRSNT_SSD11_R_N")
	)
	(segment
		(start 349.764096 -101.019102)
		(end 349.764096 -99.421696)
		(width 0.13208)
		(layer "B.Cu")
		(net "PRSNT_SSD11_R_N")
	)
	(segment
		(start 331.860906 -91.819222)
		(end 326.77989 -91.819222)
		(width 0.13208)
		(layer "B.Cu")
		(net "PRSNT_SSD11_R_N")
	)
	(segment
		(start 333.716884 -93.6752)
		(end 331.860906 -91.819222)
		(width 0.13208)
		(layer "B.Cu")
		(net "PRSNT_SSD11_R_N")
	)
	(segment
		(start 315.9633 -29.696664)
		(end 318.59347 -27.066494)
		(width 0.15494)
		(layer "In5.Cu")
		(net "PRSNT_SSD11_R_N")
	)
	(segment
		(start 322.626228 -65.406524)
		(end 322.626228 -44.085256)
		(width 0.15494)
		(layer "In5.Cu")
		(net "PRSNT_SSD11_R_N")
	)
	(segment
		(start 317.605918 -39.064946)
		(end 317.605918 -36.525454)
		(width 0.15494)
		(layer "In5.Cu")
		(net "PRSNT_SSD11_R_N")
	)
	(segment
		(start 315.9633 -34.882836)
		(end 315.9633 -29.696664)
		(width 0.15494)
		(layer "In5.Cu")
		(net "PRSNT_SSD11_R_N")
	)
	(segment
		(start 318.59347 -27.066494)
		(end 319.142364 -27.066494)
		(width 0.15494)
		(layer "In5.Cu")
		(net "PRSNT_SSD11_R_N")
	)
	(segment
		(start 317.605918 -36.525454)
		(end 317.596012 -36.515548)
		(width 0.15494)
		(layer "In5.Cu")
		(net "PRSNT_SSD11_R_N")
	)
	(segment
		(start 324.203822 -66.984118)
		(end 322.626228 -65.406524)
		(width 0.15494)
		(layer "In5.Cu")
		(net "PRSNT_SSD11_R_N")
	)
	(segment
		(start 326.242426 -91.281758)
		(end 324.203822 -89.243154)
		(width 0.15494)
		(layer "In5.Cu")
		(net "PRSNT_SSD11_R_N")
	)
	(segment
		(start 322.626228 -44.085256)
		(end 317.605918 -39.064946)
		(width 0.15494)
		(layer "In5.Cu")
		(net "PRSNT_SSD11_R_N")
	)
	(segment
		(start 324.203822 -89.243154)
		(end 324.203822 -66.984118)
		(width 0.15494)
		(layer "In5.Cu")
		(net "PRSNT_SSD11_R_N")
	)
	(segment
		(start 317.596012 -36.515548)
		(end 315.9633 -34.882836)
		(width 0.15494)
		(layer "In5.Cu")
		(net "PRSNT_SSD11_R_N")
	)
	(segment
		(start 345.7194 -172.013118)
		(end 344.343736 -170.637454)
		(width 0.15494)
		(layer "In7.Cu")
		(net "PRSNT_SSD11_R_N")
	)
	(segment
		(start 340.106 -207.545432)
		(end 340.106 -187.855606)
		(width 0.15494)
		(layer "In7.Cu")
		(net "PRSNT_SSD11_R_N")
	)
	(segment
		(start 246.021606 -183.867806)
		(end 246.021606 -183.498236)
		(width 0.15494)
		(layer "In7.Cu")
		(net "PRSNT_SSD11_R_N")
	)
	(segment
		(start 345.7194 -182.242206)
		(end 345.7194 -172.013118)
		(width 0.15494)
		(layer "In7.Cu")
		(net "PRSNT_SSD11_R_N")
	)
	(segment
		(start 236.275118 -221.242382)
		(end 238.6584 -218.8591)
		(width 0.15494)
		(layer "In7.Cu")
		(net "PRSNT_SSD11_R_N")
	)
	(segment
		(start 246.50192 -204.119734)
		(end 246.50192 -202.255374)
		(width 0.15494)
		(layer "In7.Cu")
		(net "PRSNT_SSD11_R_N")
	)
	(segment
		(start 238.6584 -215.2396)
		(end 240.3856 -213.5124)
		(width 0.15494)
		(layer "In7.Cu")
		(net "PRSNT_SSD11_R_N")
	)
	(segment
		(start 342.92794 -167.591486)
		(end 342.92794 -141.856206)
		(width 0.15494)
		(layer "In7.Cu")
		(net "PRSNT_SSD11_R_N")
	)
	(segment
		(start 243.9162 -209.63509)
		(end 244.381274 -209.170016)
		(width 0.15494)
		(layer "In7.Cu")
		(net "PRSNT_SSD11_R_N")
	)
	(segment
		(start 343.8652 -126.238)
		(end 350.728788 -119.374412)
		(width 0.15494)
		(layer "In7.Cu")
		(net "PRSNT_SSD11_R_N")
	)
	(segment
		(start 244.381274 -207.815434)
		(end 244.664484 -207.532224)
		(width 0.15494)
		(layer "In7.Cu")
		(net "PRSNT_SSD11_R_N")
	)
	(segment
		(start 245.6688 -188.097668)
		(end 247.0912 -186.675268)
		(width 0.15494)
		(layer "In7.Cu")
		(net "PRSNT_SSD11_R_N")
	)
	(segment
		(start 240.284 -212.09)
		(end 241.0968 -211.2772)
		(width 0.15494)
		(layer "In7.Cu")
		(net "PRSNT_SSD11_R_N")
	)
	(segment
		(start 245.5672 -205.054454)
		(end 246.50192 -204.119734)
		(width 0.15494)
		(layer "In7.Cu")
		(net "PRSNT_SSD11_R_N")
	)
	(segment
		(start 245.021862 -207.532224)
		(end 245.5672 -206.986886)
		(width 0.15494)
		(layer "In7.Cu")
		(net "PRSNT_SSD11_R_N")
	)
	(segment
		(start 245.5672 -206.986886)
		(end 245.5672 -205.054454)
		(width 0.15494)
		(layer "In7.Cu")
		(net "PRSNT_SSD11_R_N")
	)
	(segment
		(start 240.284 -212.6234)
		(end 240.284 -212.09)
		(width 0.15494)
		(layer "In7.Cu")
		(net "PRSNT_SSD11_R_N")
	)
	(segment
		(start 240.3856 -213.5124)
		(end 240.3856 -212.725)
		(width 0.15494)
		(layer "In7.Cu")
		(net "PRSNT_SSD11_R_N")
	)
	(segment
		(start 350.728788 -119.374412)
		(end 350.728788 -101.983794)
		(width 0.15494)
		(layer "In7.Cu")
		(net "PRSNT_SSD11_R_N")
	)
	(segment
		(start 245.6688 -192.409572)
		(end 245.6688 -188.097668)
		(width 0.15494)
		(layer "In7.Cu")
		(net "PRSNT_SSD11_R_N")
	)
	(segment
		(start 236.005878 -221.511622)
		(end 236.275118 -221.242382)
		(width 0.0889)
		(layer "In7.Cu")
		(net "PRSNT_SSD11_R_N")
	)
	(segment
		(start 246.50192 -202.255374)
		(end 245.745 -201.498454)
		(width 0.15494)
		(layer "In7.Cu")
		(net "PRSNT_SSD11_R_N")
	)
	(segment
		(start 247.0912 -184.9374)
		(end 246.021606 -183.867806)
		(width 0.15494)
		(layer "In7.Cu")
		(net "PRSNT_SSD11_R_N")
	)
	(segment
		(start 244.664484 -207.532224)
		(end 245.021862 -207.532224)
		(width 0.15494)
		(layer "In7.Cu")
		(net "PRSNT_SSD11_R_N")
	)
	(segment
		(start 350.728788 -101.983794)
		(end 349.764096 -101.019102)
		(width 0.15494)
		(layer "In7.Cu")
		(net "PRSNT_SSD11_R_N")
	)
	(segment
		(start 238.6584 -218.8591)
		(end 238.6584 -215.2396)
		(width 0.15494)
		(layer "In7.Cu")
		(net "PRSNT_SSD11_R_N")
	)
	(segment
		(start 343.8652 -140.918946)
		(end 343.8652 -126.238)
		(width 0.15494)
		(layer "In7.Cu")
		(net "PRSNT_SSD11_R_N")
	)
	(segment
		(start 342.92794 -141.856206)
		(end 343.8652 -140.918946)
		(width 0.15494)
		(layer "In7.Cu")
		(net "PRSNT_SSD11_R_N")
	)
	(segment
		(start 340.106 -187.855606)
		(end 345.7194 -182.242206)
		(width 0.15494)
		(layer "In7.Cu")
		(net "PRSNT_SSD11_R_N")
	)
	(segment
		(start 240.3856 -212.725)
		(end 240.284 -212.6234)
		(width 0.15494)
		(layer "In7.Cu")
		(net "PRSNT_SSD11_R_N")
	)
	(segment
		(start 247.0912 -186.675268)
		(end 247.0912 -184.9374)
		(width 0.15494)
		(layer "In7.Cu")
		(net "PRSNT_SSD11_R_N")
	)
	(segment
		(start 235.459778 -221.511622)
		(end 236.005878 -221.511622)
		(width 0.0889)
		(layer "In7.Cu")
		(net "PRSNT_SSD11_R_N")
	)
	(segment
		(start 241.0968 -211.2772)
		(end 243.7384 -211.2772)
		(width 0.15494)
		(layer "In7.Cu")
		(net "PRSNT_SSD11_R_N")
	)
	(segment
		(start 235.067348 -221.904052)
		(end 235.459778 -221.511622)
		(width 0.0889)
		(layer "In7.Cu")
		(net "PRSNT_SSD11_R_N")
	)
	(segment
		(start 243.7384 -211.2772)
		(end 243.9162 -211.0994)
		(width 0.15494)
		(layer "In7.Cu")
		(net "PRSNT_SSD11_R_N")
	)
	(segment
		(start 245.745 -201.498454)
		(end 245.745 -198.474076)
		(width 0.15494)
		(layer "In7.Cu")
		(net "PRSNT_SSD11_R_N")
	)
	(segment
		(start 339.293962 -209.931)
		(end 339.293962 -208.35747)
		(width 0.15494)
		(layer "In7.Cu")
		(net "PRSNT_SSD11_R_N")
	)
	(segment
		(start 344.343736 -170.637454)
		(end 344.343736 -169.007282)
		(width 0.15494)
		(layer "In7.Cu")
		(net "PRSNT_SSD11_R_N")
	)
	(segment
		(start 244.381274 -209.170016)
		(end 244.381274 -207.815434)
		(width 0.15494)
		(layer "In7.Cu")
		(net "PRSNT_SSD11_R_N")
	)
	(segment
		(start 344.343736 -169.007282)
		(end 342.92794 -167.591486)
		(width 0.15494)
		(layer "In7.Cu")
		(net "PRSNT_SSD11_R_N")
	)
	(segment
		(start 243.9162 -211.0994)
		(end 243.9162 -209.63509)
		(width 0.15494)
		(layer "In7.Cu")
		(net "PRSNT_SSD11_R_N")
	)
	(segment
		(start 246.51589 -197.703186)
		(end 246.51589 -193.256662)
		(width 0.15494)
		(layer "In7.Cu")
		(net "PRSNT_SSD11_R_N")
	)
	(segment
		(start 339.293962 -208.35747)
		(end 340.106 -207.545432)
		(width 0.15494)
		(layer "In7.Cu")
		(net "PRSNT_SSD11_R_N")
	)
	(segment
		(start 246.51589 -193.256662)
		(end 245.6688 -192.409572)
		(width 0.15494)
		(layer "In7.Cu")
		(net "PRSNT_SSD11_R_N")
	)
	(segment
		(start 245.745 -198.474076)
		(end 246.51589 -197.703186)
		(width 0.15494)
		(layer "In7.Cu")
		(net "PRSNT_SSD11_R_N")
	)
	(segment
		(start 330.576936 -207.7466)
		(end 330.57719 -207.7466)
		(width 0.15494)
		(layer "In13.Cu")
		(net "PRSNT_SSD11_R_N")
	)
	(segment
		(start 263.271762 -189.438026)
		(end 281.812746 -207.97901)
		(width 0.15494)
		(layer "In13.Cu")
		(net "PRSNT_SSD11_R_N")
	)
	(segment
		(start 246.021606 -183.498236)
		(end 246.716042 -182.8038)
		(width 0.15494)
		(layer "In13.Cu")
		(net "PRSNT_SSD11_R_N")
	)
	(segment
		(start 252.043184 -182.8038)
		(end 258.67741 -189.438026)
		(width 0.15494)
		(layer "In13.Cu")
		(net "PRSNT_SSD11_R_N")
	)
	(segment
		(start 300.851824 -207.97901)
		(end 301.693834 -207.137)
		(width 0.15494)
		(layer "In13.Cu")
		(net "PRSNT_SSD11_R_N")
	)
	(segment
		(start 301.693834 -207.137)
		(end 326.96912 -207.137)
		(width 0.15494)
		(layer "In13.Cu")
		(net "PRSNT_SSD11_R_N")
	)
	(segment
		(start 281.812746 -207.97901)
		(end 300.851824 -207.97901)
		(width 0.15494)
		(layer "In13.Cu")
		(net "PRSNT_SSD11_R_N")
	)
	(segment
		(start 336.502502 -207.13954)
		(end 339.293962 -209.931)
		(width 0.15494)
		(layer "In13.Cu")
		(net "PRSNT_SSD11_R_N")
	)
	(segment
		(start 246.716042 -182.8038)
		(end 252.043184 -182.8038)
		(width 0.15494)
		(layer "In13.Cu")
		(net "PRSNT_SSD11_R_N")
	)
	(segment
		(start 258.67741 -189.438026)
		(end 263.271762 -189.438026)
		(width 0.15494)
		(layer "In13.Cu")
		(net "PRSNT_SSD11_R_N")
	)
	(segment
		(start 332.043786 -207.13954)
		(end 336.502502 -207.13954)
		(width 0.15494)
		(layer "In13.Cu")
		(net "PRSNT_SSD11_R_N")
	)
	(segment
		(start 330.57719 -207.7466)
		(end 332.043786 -207.13954)
		(width 0.15494)
		(layer "In13.Cu")
		(net "PRSNT_SSD11_R_N")
	)
	(segment
		(start 330.124562 -207.933798)
		(end 330.576936 -207.7466)
		(width 0.15494)
		(layer "In13.Cu")
		(net "PRSNT_SSD11_R_N")
	)
	(segment
		(start 326.96912 -207.137)
		(end 327.765918 -207.933798)
		(width 0.15494)
		(layer "In13.Cu")
		(net "PRSNT_SSD11_R_N")
	)
	(segment
		(start 327.765918 -207.933798)
		(end 330.124562 -207.933798)
		(width 0.15494)
		(layer "In13.Cu")
		(net "PRSNT_SSD11_R_N")
	)
	(via
		(at 381.016002 -221.066106)
		(size 0.6604)
		(drill 0.3302)
		(layers "F.Cu" "B.Cu")
		(net "UART_PEX1_SDB_BUF_R_RX")
	)
	(segment
		(start 382.271016 -221.94012)
		(end 382.683004 -221.94012)
		(width 0.13208)
		(layer "B.Cu")
		(net "UART_PEX1_SDB_BUF_R_RX")
	)
	(segment
		(start 381.397002 -221.066106)
		(end 382.271016 -221.94012)
		(width 0.13208)
		(layer "B.Cu")
		(net "UART_PEX1_SDB_BUF_R_RX")
	)
	(segment
		(start 381.016002 -221.066106)
		(end 381.397002 -221.066106)
		(width 0.13208)
		(layer "B.Cu")
		(net "UART_PEX1_SDB_BUF_R_RX")
	)
	(segment
		(start 379.765052 -221.066106)
		(end 381.016002 -221.066106)
		(width 0.13208)
		(layer "B.Cu")
		(net "UART_PEX1_SDB_BUF_R_RX")
	)
	(segment
		(start 336.35569 -5.747258)
		(end 336.32648 -5.776468)
		(width 0.13208)
		(layer "F.Cu")
		(net "SMB_SSD11_ISO_EN")
	)
	(segment
		(start 336.32648 -5.776468)
		(end 336.32648 -6.541516)
		(width 0.13208)
		(layer "F.Cu")
		(net "SMB_SSD11_ISO_EN")
	)
	(segment
		(start 338.098384 -5.747258)
		(end 336.35569 -5.747258)
		(width 0.13208)
		(layer "F.Cu")
		(net "SMB_SSD11_ISO_EN")
	)
	(via
		(at 336.32648 -5.776468)
		(size 0.508)
		(drill 0.254)
		(layers "F.Cu" "B.Cu")
		(net "SMB_SSD11_ISO_EN")
	)
	(segment
		(start 325.196454 -237.133892)
		(end 324.487286 -237.84306)
		(width 0.13208)
		(layer "F.Cu")
		(net "PRSNT_GPU_ISO_R_N")
	)
	(segment
		(start 225.067622 -215.904064)
		(end 224.667826 -215.504268)
		(width 0.13208)
		(layer "F.Cu")
		(net "PRSNT_GPU_ISO_R_N")
	)
	(segment
		(start 324.487286 -237.84306)
		(end 324.487286 -240.093754)
		(width 0.13208)
		(layer "F.Cu")
		(net "PRSNT_GPU_ISO_R_N")
	)
	(segment
		(start 324.487286 -240.093754)
		(end 325.560182 -241.16665)
		(width 0.13208)
		(layer "F.Cu")
		(net "PRSNT_GPU_ISO_R_N")
	)
	(via
		(at 224.667826 -215.504268)
		(size 0.4572)
		(drill 0.254)
		(layers "F.Cu" "B.Cu")
		(net "PRSNT_GPU_ISO_R_N")
	)
	(via
		(at 324.67677 -183.449214)
		(size 0.508)
		(drill 0.254)
		(layers "F.Cu" "B.Cu")
		(net "PRSNT_GPU_ISO_R_N")
	)
	(via
		(at 232.119932 -183.207406)
		(size 0.508)
		(drill 0.254)
		(layers "F.Cu" "B.Cu")
		(net "PRSNT_GPU_ISO_R_N")
	)
	(via
		(at 325.560182 -241.16665)
		(size 0.508)
		(drill 0.254)
		(layers "F.Cu" "B.Cu")
		(net "PRSNT_GPU_ISO_R_N")
	)
	(segment
		(start 224.65284 -210.881976)
		(end 224.4852 -211.049616)
		(width 0.15494)
		(layer "In7.Cu")
		(net "PRSNT_GPU_ISO_R_N")
	)
	(segment
		(start 224.2566 -213.7664)
		(end 224.2566 -215.093042)
		(width 0.0889)
		(layer "In7.Cu")
		(net "PRSNT_GPU_ISO_R_N")
	)
	(segment
		(start 324.09384 -239.700308)
		(end 324.09384 -237.579408)
		(width 0.15494)
		(layer "In7.Cu")
		(net "PRSNT_GPU_ISO_R_N")
	)
	(segment
		(start 233.39552 -202.697334)
		(end 233.39552 -203.712318)
		(width 0.15494)
		(layer "In7.Cu")
		(net "PRSNT_GPU_ISO_R_N")
	)
	(segment
		(start 320.36766 -224.189798)
		(end 320.36766 -190.929768)
		(width 0.15494)
		(layer "In7.Cu")
		(net "PRSNT_GPU_ISO_R_N")
	)
	(segment
		(start 232.119932 -183.207406)
		(end 232.119932 -183.576976)
		(width 0.15494)
		(layer "In7.Cu")
		(net "PRSNT_GPU_ISO_R_N")
	)
	(segment
		(start 321.744594 -230.925624)
		(end 321.744594 -225.566732)
		(width 0.15494)
		(layer "In7.Cu")
		(net "PRSNT_GPU_ISO_R_N")
	)
	(segment
		(start 224.4852 -212.5218)
		(end 224.2566 -212.7504)
		(width 0.15494)
		(layer "In7.Cu")
		(net "PRSNT_GPU_ISO_R_N")
	)
	(segment
		(start 324.09384 -237.579408)
		(end 324.47484 -237.198408)
		(width 0.15494)
		(layer "In7.Cu")
		(net "PRSNT_GPU_ISO_R_N")
	)
	(segment
		(start 321.744594 -225.566732)
		(end 320.36766 -224.189798)
		(width 0.15494)
		(layer "In7.Cu")
		(net "PRSNT_GPU_ISO_R_N")
	)
	(segment
		(start 324.67677 -186.620658)
		(end 324.67677 -183.449214)
		(width 0.15494)
		(layer "In7.Cu")
		(net "PRSNT_GPU_ISO_R_N")
	)
	(segment
		(start 324.47484 -237.198408)
		(end 324.47484 -235.522262)
		(width 0.15494)
		(layer "In7.Cu")
		(net "PRSNT_GPU_ISO_R_N")
	)
	(segment
		(start 232.875328 -204.23251)
		(end 231.131618 -204.23251)
		(width 0.15494)
		(layer "In7.Cu")
		(net "PRSNT_GPU_ISO_R_N")
	)
	(segment
		(start 234.395518 -201.67346)
		(end 233.395774 -202.673204)
		(width 0.15494)
		(layer "In7.Cu")
		(net "PRSNT_GPU_ISO_R_N")
	)
	(segment
		(start 233.395774 -202.69708)
		(end 233.39552 -202.697334)
		(width 0.15494)
		(layer "In7.Cu")
		(net "PRSNT_GPU_ISO_R_N")
	)
	(segment
		(start 228.802946 -208.296002)
		(end 226.297998 -208.296002)
		(width 0.15494)
		(layer "In7.Cu")
		(net "PRSNT_GPU_ISO_R_N")
	)
	(segment
		(start 322.697094 -233.744516)
		(end 322.697094 -231.878124)
		(width 0.15494)
		(layer "In7.Cu")
		(net "PRSNT_GPU_ISO_R_N")
	)
	(segment
		(start 230.093266 -205.270862)
		(end 230.093266 -207.005682)
		(width 0.15494)
		(layer "In7.Cu")
		(net "PRSNT_GPU_ISO_R_N")
	)
	(segment
		(start 224.4852 -211.049616)
		(end 224.4852 -212.5218)
		(width 0.15494)
		(layer "In7.Cu")
		(net "PRSNT_GPU_ISO_R_N")
	)
	(segment
		(start 226.297998 -208.296002)
		(end 224.65284 -209.94116)
		(width 0.15494)
		(layer "In7.Cu")
		(net "PRSNT_GPU_ISO_R_N")
	)
	(segment
		(start 224.2566 -215.093042)
		(end 224.667826 -215.504268)
		(width 0.0889)
		(layer "In7.Cu")
		(net "PRSNT_GPU_ISO_R_N")
	)
	(segment
		(start 325.560182 -241.16665)
		(end 324.09384 -239.700308)
		(width 0.15494)
		(layer "In7.Cu")
		(net "PRSNT_GPU_ISO_R_N")
	)
	(segment
		(start 233.395774 -202.673204)
		(end 233.395774 -202.69708)
		(width 0.15494)
		(layer "In7.Cu")
		(net "PRSNT_GPU_ISO_R_N")
	)
	(segment
		(start 322.697094 -231.878124)
		(end 321.744594 -230.925624)
		(width 0.15494)
		(layer "In7.Cu")
		(net "PRSNT_GPU_ISO_R_N")
	)
	(segment
		(start 233.39552 -203.712318)
		(end 232.875328 -204.23251)
		(width 0.15494)
		(layer "In7.Cu")
		(net "PRSNT_GPU_ISO_R_N")
	)
	(segment
		(start 324.47484 -235.522262)
		(end 322.697094 -233.744516)
		(width 0.15494)
		(layer "In7.Cu")
		(net "PRSNT_GPU_ISO_R_N")
	)
	(segment
		(start 239.610392 -197.117208)
		(end 235.05414 -201.67346)
		(width 0.15494)
		(layer "In7.Cu")
		(net "PRSNT_GPU_ISO_R_N")
	)
	(segment
		(start 224.2566 -212.7504)
		(end 224.2566 -213.7664)
		(width 0.15494)
		(layer "In7.Cu")
		(net "PRSNT_GPU_ISO_R_N")
	)
	(segment
		(start 230.093266 -207.005682)
		(end 228.802946 -208.296002)
		(width 0.15494)
		(layer "In7.Cu")
		(net "PRSNT_GPU_ISO_R_N")
	)
	(segment
		(start 224.65284 -209.94116)
		(end 224.65284 -210.881976)
		(width 0.15494)
		(layer "In7.Cu")
		(net "PRSNT_GPU_ISO_R_N")
	)
	(segment
		(start 320.36766 -190.929768)
		(end 324.67677 -186.620658)
		(width 0.15494)
		(layer "In7.Cu")
		(net "PRSNT_GPU_ISO_R_N")
	)
	(segment
		(start 231.131618 -204.23251)
		(end 230.093266 -205.270862)
		(width 0.15494)
		(layer "In7.Cu")
		(net "PRSNT_GPU_ISO_R_N")
	)
	(segment
		(start 239.610392 -191.067436)
		(end 239.610392 -197.117208)
		(width 0.15494)
		(layer "In7.Cu")
		(net "PRSNT_GPU_ISO_R_N")
	)
	(segment
		(start 232.119932 -183.576976)
		(end 239.610392 -191.067436)
		(width 0.15494)
		(layer "In7.Cu")
		(net "PRSNT_GPU_ISO_R_N")
	)
	(segment
		(start 235.05414 -201.67346)
		(end 234.395518 -201.67346)
		(width 0.15494)
		(layer "In7.Cu")
		(net "PRSNT_GPU_ISO_R_N")
	)
	(segment
		(start 282.262326 -181.493414)
		(end 253.070614 -181.493414)
		(width 0.15494)
		(layer "In15.Cu")
		(net "PRSNT_GPU_ISO_R_N")
	)
	(segment
		(start 250.675902 -183.888126)
		(end 249.111262 -183.888126)
		(width 0.15494)
		(layer "In15.Cu")
		(net "PRSNT_GPU_ISO_R_N")
	)
	(segment
		(start 295.972738 -182.007256)
		(end 295.947846 -182.032148)
		(width 0.15494)
		(layer "In15.Cu")
		(net "PRSNT_GPU_ISO_R_N")
	)
	(segment
		(start 234.825794 -181.878224)
		(end 233.496612 -183.207406)
		(width 0.15494)
		(layer "In15.Cu")
		(net "PRSNT_GPU_ISO_R_N")
	)
	(segment
		(start 296.418 -182.007256)
		(end 295.972738 -182.007256)
		(width 0.15494)
		(layer "In15.Cu")
		(net "PRSNT_GPU_ISO_R_N")
	)
	(segment
		(start 282.80106 -182.032148)
		(end 282.262326 -181.493414)
		(width 0.15494)
		(layer "In15.Cu")
		(net "PRSNT_GPU_ISO_R_N")
	)
	(segment
		(start 297.859958 -183.449214)
		(end 296.418 -182.007256)
		(width 0.15494)
		(layer "In15.Cu")
		(net "PRSNT_GPU_ISO_R_N")
	)
	(segment
		(start 324.67677 -183.449214)
		(end 297.859958 -183.449214)
		(width 0.15494)
		(layer "In15.Cu")
		(net "PRSNT_GPU_ISO_R_N")
	)
	(segment
		(start 253.070614 -181.493414)
		(end 250.675902 -183.888126)
		(width 0.15494)
		(layer "In15.Cu")
		(net "PRSNT_GPU_ISO_R_N")
	)
	(segment
		(start 247.10136 -181.878224)
		(end 234.825794 -181.878224)
		(width 0.15494)
		(layer "In15.Cu")
		(net "PRSNT_GPU_ISO_R_N")
	)
	(segment
		(start 249.111262 -183.888126)
		(end 247.10136 -181.878224)
		(width 0.15494)
		(layer "In15.Cu")
		(net "PRSNT_GPU_ISO_R_N")
	)
	(segment
		(start 233.496612 -183.207406)
		(end 232.119932 -183.207406)
		(width 0.15494)
		(layer "In15.Cu")
		(net "PRSNT_GPU_ISO_R_N")
	)
	(segment
		(start 295.947846 -182.032148)
		(end 282.80106 -182.032148)
		(width 0.15494)
		(layer "In15.Cu")
		(net "PRSNT_GPU_ISO_R_N")
	)
	(segment
		(start 141.967966 -54.067456)
		(end 141.86408 -53.96357)
		(width 0.13208)
		(layer "F.Cu")
		(net "P12V_SSD4_OCP")
	)
	(segment
		(start 140.24737 -54.144164)
		(end 140.675614 -54.144164)
		(width 0.13208)
		(layer "F.Cu")
		(net "P12V_SSD4_OCP")
	)
	(segment
		(start 140.856208 -53.96357)
		(end 141.254226 -53.96357)
		(width 0.13208)
		(layer "F.Cu")
		(net "P12V_SSD4_OCP")
	)
	(segment
		(start 140.675614 -54.144164)
		(end 140.856208 -53.96357)
		(width 0.13208)
		(layer "F.Cu")
		(net "P12V_SSD4_OCP")
	)
	(segment
		(start 141.86408 -53.96357)
		(end 141.254226 -53.96357)
		(width 0.13208)
		(layer "F.Cu")
		(net "P12V_SSD4_OCP")
	)
	(via
		(at 141.254226 -53.96357)
		(size 0.508)
		(drill 0.254)
		(layers "F.Cu" "B.Cu")
		(net "P12V_SSD4_OCP")
	)
	(via
		(at 381.143002 -223.860106)
		(size 0.6604)
		(drill 0.3302)
		(layers "F.Cu" "B.Cu")
		(net "UART_PEX0_SDB_BUF_R_RX")
	)
	(segment
		(start 381.763016 -223.240092)
		(end 382.683004 -223.240092)
		(width 0.13208)
		(layer "B.Cu")
		(net "UART_PEX0_SDB_BUF_R_RX")
	)
	(segment
		(start 379.892052 -223.860106)
		(end 381.143002 -223.860106)
		(width 0.13208)
		(layer "B.Cu")
		(net "UART_PEX0_SDB_BUF_R_RX")
	)
	(segment
		(start 379.765052 -223.733106)
		(end 379.892052 -223.860106)
		(width 0.13208)
		(layer "B.Cu")
		(net "UART_PEX0_SDB_BUF_R_RX")
	)
	(segment
		(start 381.143002 -223.860106)
		(end 381.763016 -223.240092)
		(width 0.13208)
		(layer "B.Cu")
		(net "UART_PEX0_SDB_BUF_R_RX")
	)
	(segment
		(start 334.990186 -10.175748)
		(end 334.990186 -10.134092)
		(width 0.13208)
		(layer "F.Cu")
		(net "SMB_ISO_SSD11_SDA")
	)
	(segment
		(start 334.070706 -7.266432)
		(end 334.990186 -8.185912)
		(width 0.13208)
		(layer "F.Cu")
		(net "SMB_ISO_SSD11_SDA")
	)
	(segment
		(start 330.743306 -6.68655)
		(end 331.323188 -7.266432)
		(width 0.13208)
		(layer "F.Cu")
		(net "SMB_ISO_SSD11_SDA")
	)
	(segment
		(start 331.976476 -7.266432)
		(end 334.070706 -7.266432)
		(width 0.13208)
		(layer "F.Cu")
		(net "SMB_ISO_SSD11_SDA")
	)
	(segment
		(start 338.874354 -6.739636)
		(end 339.483954 -6.739636)
		(width 0.13208)
		(layer "F.Cu")
		(net "SMB_ISO_SSD11_SDA")
	)
	(segment
		(start 336.004662 -10.945622)
		(end 335.76006 -10.945622)
		(width 0.13208)
		(layer "F.Cu")
		(net "SMB_ISO_SSD11_SDA")
	)
	(segment
		(start 335.76006 -10.945622)
		(end 334.990186 -10.175748)
		(width 0.13208)
		(layer "F.Cu")
		(net "SMB_ISO_SSD11_SDA")
	)
	(segment
		(start 334.990186 -8.185912)
		(end 334.990186 -10.134092)
		(width 0.13208)
		(layer "F.Cu")
		(net "SMB_ISO_SSD11_SDA")
	)
	(segment
		(start 331.323188 -7.266432)
		(end 331.976476 -7.266432)
		(width 0.13208)
		(layer "F.Cu")
		(net "SMB_ISO_SSD11_SDA")
	)
	(via
		(at 339.483954 -6.739636)
		(size 0.508)
		(drill 0.254)
		(layers "F.Cu" "B.Cu")
		(net "SMB_ISO_SSD11_SDA")
	)
	(via
		(at 330.743306 -6.68655)
		(size 0.508)
		(drill 0.254)
		(layers "F.Cu" "B.Cu")
		(net "SMB_ISO_SSD11_SDA")
	)
	(segment
		(start 338.933028 -6.739636)
		(end 337.39836 -5.204968)
		(width 0.13208)
		(layer "B.Cu")
		(net "SMB_ISO_SSD11_SDA")
	)
	(segment
		(start 333.019146 -5.204968)
		(end 331.537564 -6.68655)
		(width 0.13208)
		(layer "B.Cu")
		(net "SMB_ISO_SSD11_SDA")
	)
	(segment
		(start 337.39836 -5.204968)
		(end 333.019146 -5.204968)
		(width 0.13208)
		(layer "B.Cu")
		(net "SMB_ISO_SSD11_SDA")
	)
	(segment
		(start 339.483954 -6.739636)
		(end 338.933028 -6.739636)
		(width 0.13208)
		(layer "B.Cu")
		(net "SMB_ISO_SSD11_SDA")
	)
	(segment
		(start 331.537564 -6.68655)
		(end 330.743306 -6.68655)
		(width 0.13208)
		(layer "B.Cu")
		(net "SMB_ISO_SSD11_SDA")
	)
	(segment
		(start 426.75937 -23.355554)
		(end 426.75937 -23.965154)
		(width 0.13208)
		(layer "F.Cu")
		(net "SMB_ISO_SSD14_SCL")
	)
	(segment
		(start 426.58538 -16.439388)
		(end 426.58538 -18.396966)
		(width 0.13208)
		(layer "F.Cu")
		(net "SMB_ISO_SSD14_SCL")
	)
	(segment
		(start 423.55643 -17.669256)
		(end 424.324272 -18.437098)
		(width 0.13208)
		(layer "F.Cu")
		(net "SMB_ISO_SSD14_SCL")
	)
	(segment
		(start 424.324272 -18.437098)
		(end 424.36796 -18.437098)
		(width 0.13208)
		(layer "F.Cu")
		(net "SMB_ISO_SSD14_SCL")
	)
	(segment
		(start 426.58538 -16.439388)
		(end 426.58538 -15.370302)
		(width 0.13208)
		(layer "F.Cu")
		(net "SMB_ISO_SSD14_SCL")
	)
	(segment
		(start 423.55643 -17.419574)
		(end 423.55643 -17.669256)
		(width 0.13208)
		(layer "F.Cu")
		(net "SMB_ISO_SSD14_SCL")
	)
	(segment
		(start 425.991528 -18.990818)
		(end 424.92168 -18.990818)
		(width 0.13208)
		(layer "F.Cu")
		(net "SMB_ISO_SSD14_SCL")
	)
	(segment
		(start 424.92168 -18.990818)
		(end 424.36796 -18.437098)
		(width 0.13208)
		(layer "F.Cu")
		(net "SMB_ISO_SSD14_SCL")
	)
	(segment
		(start 426.58538 -18.396966)
		(end 425.991528 -18.990818)
		(width 0.13208)
		(layer "F.Cu")
		(net "SMB_ISO_SSD14_SCL")
	)
	(via
		(at 426.75937 -23.965154)
		(size 0.508)
		(drill 0.254)
		(layers "F.Cu" "B.Cu")
		(net "SMB_ISO_SSD14_SCL")
	)
	(via
		(at 426.58538 -15.370302)
		(size 0.508)
		(drill 0.254)
		(layers "F.Cu" "B.Cu")
		(net "SMB_ISO_SSD14_SCL")
	)
	(segment
		(start 426.75937 -23.965154)
		(end 428.034704 -22.68982)
		(width 0.13208)
		(layer "B.Cu")
		(net "SMB_ISO_SSD14_SCL")
	)
	(segment
		(start 428.034704 -16.819626)
		(end 426.58538 -15.370302)
		(width 0.13208)
		(layer "B.Cu")
		(net "SMB_ISO_SSD14_SCL")
	)
	(segment
		(start 428.034704 -22.68982)
		(end 428.034704 -16.819626)
		(width 0.13208)
		(layer "B.Cu")
		(net "SMB_ISO_SSD14_SCL")
	)
	(segment
		(start 329.692 -234.46105)
		(end 329.692 -235.077)
		(width 0.13208)
		(layer "F.Cu")
		(net "PRSNT_GPU_ISO_N")
	)
	(segment
		(start 328.854054 -237.133892)
		(end 329.045062 -236.942884)
		(width 0.13208)
		(layer "F.Cu")
		(net "PRSNT_GPU_ISO_N")
	)
	(segment
		(start 329.692 -235.077)
		(end 329.045062 -235.723938)
		(width 0.13208)
		(layer "F.Cu")
		(net "PRSNT_GPU_ISO_N")
	)
	(segment
		(start 325.996554 -237.133892)
		(end 328.854054 -237.133892)
		(width 0.13208)
		(layer "F.Cu")
		(net "PRSNT_GPU_ISO_N")
	)
	(segment
		(start 329.045062 -236.942884)
		(end 329.045062 -236.463078)
		(width 0.13208)
		(layer "F.Cu")
		(net "PRSNT_GPU_ISO_N")
	)
	(segment
		(start 330.708 -234.46105)
		(end 329.692 -234.46105)
		(width 0.13208)
		(layer "F.Cu")
		(net "PRSNT_GPU_ISO_N")
	)
	(segment
		(start 329.045062 -235.723938)
		(end 329.045062 -236.463078)
		(width 0.13208)
		(layer "F.Cu")
		(net "PRSNT_GPU_ISO_N")
	)
	(via
		(at 329.045062 -235.723938)
		(size 0.508)
		(drill 0.254)
		(layers "F.Cu" "B.Cu")
		(net "PRSNT_GPU_ISO_N")
	)
	(segment
		(start 192.67551 -54.144164)
		(end 192.856104 -53.96357)
		(width 0.13208)
		(layer "F.Cu")
		(net "P12V_SSD6_OCP")
	)
	(segment
		(start 193.967862 -54.067456)
		(end 193.863976 -53.96357)
		(width 0.13208)
		(layer "F.Cu")
		(net "P12V_SSD6_OCP")
	)
	(segment
		(start 192.247266 -54.144164)
		(end 192.67551 -54.144164)
		(width 0.13208)
		(layer "F.Cu")
		(net "P12V_SSD6_OCP")
	)
	(segment
		(start 192.856104 -53.96357)
		(end 193.254122 -53.96357)
		(width 0.13208)
		(layer "F.Cu")
		(net "P12V_SSD6_OCP")
	)
	(segment
		(start 193.863976 -53.96357)
		(end 193.254122 -53.96357)
		(width 0.13208)
		(layer "F.Cu")
		(net "P12V_SSD6_OCP")
	)
	(via
		(at 193.254122 -53.96357)
		(size 0.508)
		(drill 0.254)
		(layers "F.Cu" "B.Cu")
		(net "P12V_SSD6_OCP")
	)
	(segment
		(start 375.96064 -21.05279)
		(end 376.754898 -21.847048)
		(width 0.13208)
		(layer "F.Cu")
		(net "SMB_SSD12_ISO_EN")
	)
	(segment
		(start 375.96064 -20.789392)
		(end 375.96064 -21.05279)
		(width 0.13208)
		(layer "F.Cu")
		(net "SMB_SSD12_ISO_EN")
	)
	(segment
		(start 376.754898 -21.847048)
		(end 376.754898 -22.561296)
		(width 0.13208)
		(layer "F.Cu")
		(net "SMB_SSD12_ISO_EN")
	)
	(via
		(at 376.754898 -21.847048)
		(size 0.508)
		(drill 0.254)
		(layers "F.Cu" "B.Cu")
		(net "SMB_SSD12_ISO_EN")
	)
	(segment
		(start 221.562422 -22.537166)
		(end 221.562422 -22.097492)
		(width 0.13208)
		(layer "F.Cu")
		(net "SMB_BIC_I2C9_MUX0_SSD7_R_SDA")
	)
	(segment
		(start 138.585194 -95.074994)
		(end 138.585194 -94.671642)
		(width 0.13208)
		(layer "F.Cu")
		(net "SMB_BIC_I2C9_MUX0_SSD7_R_SDA")
	)
	(segment
		(start 221.790514 -76.225654)
		(end 221.78772 -76.223114)
		(width 0.13208)
		(layer "F.Cu")
		(net "SMB_BIC_I2C9_MUX0_SSD7_R_SDA")
	)
	(segment
		(start 136.845294 -94.671642)
		(end 138.585194 -94.671642)
		(width 0.13208)
		(layer "F.Cu")
		(net "SMB_BIC_I2C9_MUX0_SSD7_R_SDA")
	)
	(segment
		(start 196.052186 -78.006956)
		(end 188.875416 -78.006956)
		(width 0.13208)
		(layer "F.Cu")
		(net "SMB_BIC_I2C9_MUX0_SSD7_R_SDA")
	)
	(segment
		(start 177.169572 -89.7128)
		(end 152.6794 -89.7128)
		(width 0.13208)
		(layer "F.Cu")
		(net "SMB_BIC_I2C9_MUX0_SSD7_R_SDA")
	)
	(segment
		(start 207.833214 -76.4286)
		(end 207.035146 -75.630532)
		(width 0.13208)
		(layer "F.Cu")
		(net "SMB_BIC_I2C9_MUX0_SSD7_R_SDA")
	)
	(segment
		(start 140.716762 -95.242126)
		(end 140.358622 -95.242126)
		(width 0.13208)
		(layer "F.Cu")
		(net "SMB_BIC_I2C9_MUX0_SSD7_R_SDA")
	)
	(segment
		(start 221.808548 -76.20762)
		(end 221.790514 -76.225654)
		(width 0.13208)
		(layer "F.Cu")
		(net "SMB_BIC_I2C9_MUX0_SSD7_R_SDA")
	)
	(segment
		(start 198.42861 -75.630532)
		(end 196.052186 -78.006956)
		(width 0.13208)
		(layer "F.Cu")
		(net "SMB_BIC_I2C9_MUX0_SSD7_R_SDA")
	)
	(segment
		(start 221.78772 -76.223114)
		(end 221.287086 -76.223114)
		(width 0.13208)
		(layer "F.Cu")
		(net "SMB_BIC_I2C9_MUX0_SSD7_R_SDA")
	)
	(segment
		(start 221.035626 -21.570696)
		(end 221.035626 -20.789392)
		(width 0.13208)
		(layer "F.Cu")
		(net "SMB_BIC_I2C9_MUX0_SSD7_R_SDA")
	)
	(segment
		(start 152.6794 -89.7128)
		(end 148.2852 -94.107)
		(width 0.13208)
		(layer "F.Cu")
		(net "SMB_BIC_I2C9_MUX0_SSD7_R_SDA")
	)
	(segment
		(start 140.358622 -95.242126)
		(end 140.336016 -95.264732)
		(width 0.13208)
		(layer "F.Cu")
		(net "SMB_BIC_I2C9_MUX0_SSD7_R_SDA")
	)
	(segment
		(start 207.035146 -75.630532)
		(end 198.42861 -75.630532)
		(width 0.13208)
		(layer "F.Cu")
		(net "SMB_BIC_I2C9_MUX0_SSD7_R_SDA")
	)
	(segment
		(start 221.287086 -76.223114)
		(end 221.0816 -76.4286)
		(width 0.13208)
		(layer "F.Cu")
		(net "SMB_BIC_I2C9_MUX0_SSD7_R_SDA")
	)
	(segment
		(start 221.562422 -22.097492)
		(end 221.320614 -21.855684)
		(width 0.13208)
		(layer "F.Cu")
		(net "SMB_BIC_I2C9_MUX0_SSD7_R_SDA")
	)
	(segment
		(start 141.851888 -94.107)
		(end 140.716762 -95.242126)
		(width 0.13208)
		(layer "F.Cu")
		(net "SMB_BIC_I2C9_MUX0_SSD7_R_SDA")
	)
	(segment
		(start 148.2852 -94.107)
		(end 141.851888 -94.107)
		(width 0.13208)
		(layer "F.Cu")
		(net "SMB_BIC_I2C9_MUX0_SSD7_R_SDA")
	)
	(segment
		(start 188.875416 -78.006956)
		(end 177.169572 -89.7128)
		(width 0.13208)
		(layer "F.Cu")
		(net "SMB_BIC_I2C9_MUX0_SSD7_R_SDA")
	)
	(segment
		(start 221.320614 -21.855684)
		(end 221.035626 -21.570696)
		(width 0.13208)
		(layer "F.Cu")
		(net "SMB_BIC_I2C9_MUX0_SSD7_R_SDA")
	)
	(segment
		(start 138.774932 -95.264732)
		(end 138.585194 -95.074994)
		(width 0.13208)
		(layer "F.Cu")
		(net "SMB_BIC_I2C9_MUX0_SSD7_R_SDA")
	)
	(segment
		(start 221.0816 -76.4286)
		(end 207.833214 -76.4286)
		(width 0.13208)
		(layer "F.Cu")
		(net "SMB_BIC_I2C9_MUX0_SSD7_R_SDA")
	)
	(segment
		(start 140.336016 -95.264732)
		(end 138.774932 -95.264732)
		(width 0.13208)
		(layer "F.Cu")
		(net "SMB_BIC_I2C9_MUX0_SSD7_R_SDA")
	)
	(via
		(at 221.808548 -76.20762)
		(size 0.508)
		(drill 0.254)
		(layers "F.Cu" "B.Cu")
		(net "SMB_BIC_I2C9_MUX0_SSD7_R_SDA")
	)
	(via
		(at 221.320614 -21.855684)
		(size 0.508)
		(drill 0.254)
		(layers "F.Cu" "B.Cu")
		(net "SMB_BIC_I2C9_MUX0_SSD7_R_SDA")
	)
	(segment
		(start 223.69272 -41.1734)
		(end 223.69272 -63.125858)
		(width 0.15494)
		(layer "In5.Cu")
		(net "SMB_BIC_I2C9_MUX0_SSD7_R_SDA")
	)
	(segment
		(start 218.46032 -35.941)
		(end 223.69272 -41.1734)
		(width 0.15494)
		(layer "In5.Cu")
		(net "SMB_BIC_I2C9_MUX0_SSD7_R_SDA")
	)
	(segment
		(start 221.320614 -21.855684)
		(end 220.72473 -21.2598)
		(width 0.15494)
		(layer "In5.Cu")
		(net "SMB_BIC_I2C9_MUX0_SSD7_R_SDA")
	)
	(segment
		(start 222.7326 -64.085978)
		(end 222.7326 -73.034652)
		(width 0.15494)
		(layer "In5.Cu")
		(net "SMB_BIC_I2C9_MUX0_SSD7_R_SDA")
	)
	(segment
		(start 222.9866 -75.6158)
		(end 222.400368 -75.6158)
		(width 0.15494)
		(layer "In5.Cu")
		(net "SMB_BIC_I2C9_MUX0_SSD7_R_SDA")
	)
	(segment
		(start 223.605598 -74.996802)
		(end 222.9866 -75.6158)
		(width 0.15494)
		(layer "In5.Cu")
		(net "SMB_BIC_I2C9_MUX0_SSD7_R_SDA")
	)
	(segment
		(start 218.46032 -30.094174)
		(end 218.46032 -35.941)
		(width 0.15494)
		(layer "In5.Cu")
		(net "SMB_BIC_I2C9_MUX0_SSD7_R_SDA")
	)
	(segment
		(start 220.72473 -21.2598)
		(end 219.147136 -21.2598)
		(width 0.15494)
		(layer "In5.Cu")
		(net "SMB_BIC_I2C9_MUX0_SSD7_R_SDA")
	)
	(segment
		(start 219.147136 -21.2598)
		(end 218.313 -22.093936)
		(width 0.15494)
		(layer "In5.Cu")
		(net "SMB_BIC_I2C9_MUX0_SSD7_R_SDA")
	)
	(segment
		(start 223.605598 -73.90765)
		(end 223.605598 -74.996802)
		(width 0.15494)
		(layer "In5.Cu")
		(net "SMB_BIC_I2C9_MUX0_SSD7_R_SDA")
	)
	(segment
		(start 219.2274 -29.327094)
		(end 218.46032 -30.094174)
		(width 0.15494)
		(layer "In5.Cu")
		(net "SMB_BIC_I2C9_MUX0_SSD7_R_SDA")
	)
	(segment
		(start 218.313 -26.923746)
		(end 219.2274 -27.838146)
		(width 0.15494)
		(layer "In5.Cu")
		(net "SMB_BIC_I2C9_MUX0_SSD7_R_SDA")
	)
	(segment
		(start 218.313 -22.093936)
		(end 218.313 -26.923746)
		(width 0.15494)
		(layer "In5.Cu")
		(net "SMB_BIC_I2C9_MUX0_SSD7_R_SDA")
	)
	(segment
		(start 222.400368 -75.6158)
		(end 221.808548 -76.20762)
		(width 0.15494)
		(layer "In5.Cu")
		(net "SMB_BIC_I2C9_MUX0_SSD7_R_SDA")
	)
	(segment
		(start 219.2274 -27.838146)
		(end 219.2274 -29.327094)
		(width 0.15494)
		(layer "In5.Cu")
		(net "SMB_BIC_I2C9_MUX0_SSD7_R_SDA")
	)
	(segment
		(start 223.69272 -63.125858)
		(end 222.7326 -64.085978)
		(width 0.15494)
		(layer "In5.Cu")
		(net "SMB_BIC_I2C9_MUX0_SSD7_R_SDA")
	)
	(segment
		(start 222.7326 -73.034652)
		(end 223.605598 -73.90765)
		(width 0.15494)
		(layer "In5.Cu")
		(net "SMB_BIC_I2C9_MUX0_SSD7_R_SDA")
	)
	(segment
		(start 453.452484 -15.40764)
		(end 453.235568 -15.624556)
		(width 0.13208)
		(layer "F.Cu")
		(net "SMB_ISO_SSD15_SDA")
	)
	(segment
		(start 453.762364 -23.337266)
		(end 453.762364 -23.946866)
		(width 0.13208)
		(layer "F.Cu")
		(net "SMB_ISO_SSD15_SDA")
	)
	(segment
		(start 449.556378 -20.222972)
		(end 450.326252 -19.453098)
		(width 0.13208)
		(layer "F.Cu")
		(net "SMB_ISO_SSD15_SDA")
	)
	(segment
		(start 453.235568 -18.533618)
		(end 453.235568 -16.439388)
		(width 0.13208)
		(layer "F.Cu")
		(net "SMB_ISO_SSD15_SDA")
	)
	(segment
		(start 450.326252 -19.453098)
		(end 450.367908 -19.453098)
		(width 0.13208)
		(layer "F.Cu")
		(net "SMB_ISO_SSD15_SDA")
	)
	(segment
		(start 450.367908 -19.453098)
		(end 452.316088 -19.453098)
		(width 0.13208)
		(layer "F.Cu")
		(net "SMB_ISO_SSD15_SDA")
	)
	(segment
		(start 449.556378 -20.467574)
		(end 449.556378 -20.222972)
		(width 0.13208)
		(layer "F.Cu")
		(net "SMB_ISO_SSD15_SDA")
	)
	(segment
		(start 453.235568 -15.624556)
		(end 453.235568 -16.439388)
		(width 0.13208)
		(layer "F.Cu")
		(net "SMB_ISO_SSD15_SDA")
	)
	(segment
		(start 452.316088 -19.453098)
		(end 453.235568 -18.533618)
		(width 0.13208)
		(layer "F.Cu")
		(net "SMB_ISO_SSD15_SDA")
	)
	(via
		(at 453.762364 -23.946866)
		(size 0.508)
		(drill 0.254)
		(layers "F.Cu" "B.Cu")
		(net "SMB_ISO_SSD15_SDA")
	)
	(via
		(at 453.452484 -15.40764)
		(size 0.508)
		(drill 0.254)
		(layers "F.Cu" "B.Cu")
		(net "SMB_ISO_SSD15_SDA")
	)
	(segment
		(start 454.247504 -23.461726)
		(end 454.247504 -16.825722)
		(width 0.13208)
		(layer "B.Cu")
		(net "SMB_ISO_SSD15_SDA")
	)
	(segment
		(start 454.247504 -16.825722)
		(end 453.700134 -16.278352)
		(width 0.13208)
		(layer "B.Cu")
		(net "SMB_ISO_SSD15_SDA")
	)
	(segment
		(start 453.762364 -23.946866)
		(end 454.247504 -23.461726)
		(width 0.13208)
		(layer "B.Cu")
		(net "SMB_ISO_SSD15_SDA")
	)
	(segment
		(start 453.700134 -16.278352)
		(end 453.700134 -15.65529)
		(width 0.13208)
		(layer "B.Cu")
		(net "SMB_ISO_SSD15_SDA")
	)
	(segment
		(start 453.700134 -15.65529)
		(end 453.452484 -15.40764)
		(width 0.13208)
		(layer "B.Cu")
		(net "SMB_ISO_SSD15_SDA")
	)
	(segment
		(start 55.83301 -362.956094)
		(end 55.348124 -362.471208)
		(width 0.13462)
		(layer "F.Cu")
		(net "USB2_GPU_HMC_DP")
	)
	(segment
		(start 56.271922 -362.956094)
		(end 55.83301 -362.956094)
		(width 0.13462)
		(layer "F.Cu")
		(net "USB2_GPU_HMC_DP")
	)
	(via
		(at 50.100738 -392.193526)
		(size 0.4064)
		(drill 0.2032)
		(layers "F.Cu" "B.Cu")
		(net "USB2_GPU_HMC_DP")
	)
	(via
		(at 55.348124 -362.471208)
		(size 0.508)
		(drill 0.254)
		(layers "F.Cu" "B.Cu")
		(net "USB2_GPU_HMC_DP")
	)
	(segment
		(start 52.56657 -364.24743)
		(end 54.041802 -362.772198)
		(width 0.13462)
		(layer "B.Cu")
		(net "USB2_GPU_HMC_DP")
	)
	(segment
		(start 54.041802 -362.772198)
		(end 55.047134 -362.772198)
		(width 0.13462)
		(layer "B.Cu")
		(net "USB2_GPU_HMC_DP")
	)
	(segment
		(start 46.649386 -396.76451)
		(end 46.378622 -397.035274)
		(width 0.13462)
		(layer "B.Cu")
		(net "USB2_GPU_HMC_DP")
	)
	(segment
		(start 46.636686 -396.749016)
		(end 46.649386 -396.761716)
		(width 0.13462)
		(layer "B.Cu")
		(net "USB2_GPU_HMC_DP")
	)
	(segment
		(start 50.100738 -392.193526)
		(end 50.100738 -392.193018)
		(width 0.13462)
		(layer "B.Cu")
		(net "USB2_GPU_HMC_DP")
	)
	(segment
		(start 52.56657 -389.72744)
		(end 52.56657 -364.24743)
		(width 0.13462)
		(layer "B.Cu")
		(net "USB2_GPU_HMC_DP")
	)
	(segment
		(start 46.649386 -396.761716)
		(end 46.649386 -396.76451)
		(width 0.13462)
		(layer "B.Cu")
		(net "USB2_GPU_HMC_DP")
	)
	(segment
		(start 46.378622 -397.035274)
		(end 46.055026 -397.035274)
		(width 0.13462)
		(layer "B.Cu")
		(net "USB2_GPU_HMC_DP")
	)
	(segment
		(start 46.636686 -395.657578)
		(end 46.636686 -396.749016)
		(width 0.13462)
		(layer "B.Cu")
		(net "USB2_GPU_HMC_DP")
	)
	(segment
		(start 50.100738 -392.193526)
		(end 46.636686 -395.657578)
		(width 0.13462)
		(layer "B.Cu")
		(net "USB2_GPU_HMC_DP")
	)
	(segment
		(start 55.047134 -362.772198)
		(end 55.348124 -362.471208)
		(width 0.13462)
		(layer "B.Cu")
		(net "USB2_GPU_HMC_DP")
	)
	(segment
		(start 46.055026 -397.035274)
		(end 45.509942 -396.49019)
		(width 0.13462)
		(layer "B.Cu")
		(net "USB2_GPU_HMC_DP")
	)
	(segment
		(start 50.100738 -392.193018)
		(end 52.56657 -389.72744)
		(width 0.13462)
		(layer "B.Cu")
		(net "USB2_GPU_HMC_DP")
	)
	(segment
		(start 254.35179 -89.106756)
		(end 253.488444 -89.106756)
		(width 0.13208)
		(layer "F.Cu")
		(net "PU_CLK_PFT_LOST_N")
	)
	(segment
		(start 255.280414 -85.434932)
		(end 255.280414 -86.88451)
		(width 0.13208)
		(layer "F.Cu")
		(net "PU_CLK_PFT_LOST_N")
	)
	(segment
		(start 253.153672 -89.441528)
		(end 252.990096 -89.441528)
		(width 0.13208)
		(layer "F.Cu")
		(net "PU_CLK_PFT_LOST_N")
	)
	(segment
		(start 254.989076 -87.175848)
		(end 254.989076 -88.46947)
		(width 0.13208)
		(layer "F.Cu")
		(net "PU_CLK_PFT_LOST_N")
	)
	(segment
		(start 255.408938 -85.306408)
		(end 255.280414 -85.434932)
		(width 0.13208)
		(layer "F.Cu")
		(net "PU_CLK_PFT_LOST_N")
	)
	(segment
		(start 254.989076 -88.46947)
		(end 254.35179 -89.106756)
		(width 0.13208)
		(layer "F.Cu")
		(net "PU_CLK_PFT_LOST_N")
	)
	(segment
		(start 256.551938 -85.306408)
		(end 255.408938 -85.306408)
		(width 0.0889)
		(layer "F.Cu")
		(net "PU_CLK_PFT_LOST_N")
	)
	(segment
		(start 253.488444 -89.106756)
		(end 253.153672 -89.441528)
		(width 0.13208)
		(layer "F.Cu")
		(net "PU_CLK_PFT_LOST_N")
	)
	(segment
		(start 255.280414 -86.88451)
		(end 254.989076 -87.175848)
		(width 0.13208)
		(layer "F.Cu")
		(net "PU_CLK_PFT_LOST_N")
	)
	(via
		(at 252.990096 -89.441528)
		(size 0.508)
		(drill 0.254)
		(layers "F.Cu" "B.Cu")
		(net "PU_CLK_PFT_LOST_N")
	)
	(via
		(at 251.4473 -91.517978)
		(size 0.6604)
		(drill 0.3302)
		(layers "F.Cu" "B.Cu")
		(net "PU_CLK_PFT_LOST_N")
	)
	(segment
		(start 252.375162 -91.517978)
		(end 251.4473 -91.517978)
		(width 0.13208)
		(layer "B.Cu")
		(net "PU_CLK_PFT_LOST_N")
	)
	(segment
		(start 252.959362 -90.933778)
		(end 252.375162 -91.517978)
		(width 0.13208)
		(layer "B.Cu")
		(net "PU_CLK_PFT_LOST_N")
	)
	(segment
		(start 252.990096 -89.441528)
		(end 252.959362 -89.472262)
		(width 0.13208)
		(layer "B.Cu")
		(net "PU_CLK_PFT_LOST_N")
	)
	(segment
		(start 252.959362 -89.472262)
		(end 252.959362 -90.933778)
		(width 0.13208)
		(layer "B.Cu")
		(net "PU_CLK_PFT_LOST_N")
	)
	(segment
		(start 251.4473 -91.517978)
		(end 248.940574 -91.517978)
		(width 0.13208)
		(layer "B.Cu")
		(net "PU_CLK_PFT_LOST_N")
	)
	(segment
		(start 174.337218 -85.461856)
		(end 175.129444 -86.254082)
		(width 0.13208)
		(layer "F.Cu")
		(net "SMB_BIC_I2C9_MUX0_SSD5_R_SDA")
	)
	(segment
		(start 138.774932 -90.692732)
		(end 147.715732 -90.692732)
		(width 0.13208)
		(layer "F.Cu")
		(net "SMB_BIC_I2C9_MUX0_SSD5_R_SDA")
	)
	(segment
		(start 169.03573 -21.570696)
		(end 169.03573 -20.789392)
		(width 0.13208)
		(layer "F.Cu")
		(net "SMB_BIC_I2C9_MUX0_SSD5_R_SDA")
	)
	(segment
		(start 136.845294 -90.099642)
		(end 138.585194 -90.099642)
		(width 0.13208)
		(layer "F.Cu")
		(net "SMB_BIC_I2C9_MUX0_SSD5_R_SDA")
	)
	(segment
		(start 138.585194 -90.502994)
		(end 138.774932 -90.692732)
		(width 0.13208)
		(layer "F.Cu")
		(net "SMB_BIC_I2C9_MUX0_SSD5_R_SDA")
	)
	(segment
		(start 169.562526 -22.537166)
		(end 169.562526 -22.097492)
		(width 0.13208)
		(layer "F.Cu")
		(net "SMB_BIC_I2C9_MUX0_SSD5_R_SDA")
	)
	(segment
		(start 169.562526 -22.097492)
		(end 169.320718 -21.855684)
		(width 0.13208)
		(layer "F.Cu")
		(net "SMB_BIC_I2C9_MUX0_SSD5_R_SDA")
	)
	(segment
		(start 169.320718 -21.855684)
		(end 169.03573 -21.570696)
		(width 0.13208)
		(layer "F.Cu")
		(net "SMB_BIC_I2C9_MUX0_SSD5_R_SDA")
	)
	(segment
		(start 152.946608 -85.461856)
		(end 174.337218 -85.461856)
		(width 0.13208)
		(layer "F.Cu")
		(net "SMB_BIC_I2C9_MUX0_SSD5_R_SDA")
	)
	(segment
		(start 138.585194 -90.099642)
		(end 138.585194 -90.502994)
		(width 0.13208)
		(layer "F.Cu")
		(net "SMB_BIC_I2C9_MUX0_SSD5_R_SDA")
	)
	(segment
		(start 147.715732 -90.692732)
		(end 152.946608 -85.461856)
		(width 0.13208)
		(layer "F.Cu")
		(net "SMB_BIC_I2C9_MUX0_SSD5_R_SDA")
	)
	(via
		(at 169.320718 -21.855684)
		(size 0.508)
		(drill 0.254)
		(layers "F.Cu" "B.Cu")
		(net "SMB_BIC_I2C9_MUX0_SSD5_R_SDA")
	)
	(via
		(at 175.129444 -86.254082)
		(size 0.508)
		(drill 0.254)
		(layers "F.Cu" "B.Cu")
		(net "SMB_BIC_I2C9_MUX0_SSD5_R_SDA")
	)
	(segment
		(start 179.20462 -45.10786)
		(end 166.874444 -32.777684)
		(width 0.15494)
		(layer "In5.Cu")
		(net "SMB_BIC_I2C9_MUX0_SSD5_R_SDA")
	)
	(segment
		(start 166.874444 -29.580586)
		(end 167.3098 -29.14523)
		(width 0.15494)
		(layer "In5.Cu")
		(net "SMB_BIC_I2C9_MUX0_SSD5_R_SDA")
	)
	(segment
		(start 168.572434 -21.1074)
		(end 169.320718 -21.855684)
		(width 0.15494)
		(layer "In5.Cu")
		(net "SMB_BIC_I2C9_MUX0_SSD5_R_SDA")
	)
	(segment
		(start 166.874444 -32.777684)
		(end 166.874444 -29.580586)
		(width 0.15494)
		(layer "In5.Cu")
		(net "SMB_BIC_I2C9_MUX0_SSD5_R_SDA")
	)
	(segment
		(start 179.20462 -82.178906)
		(end 179.20462 -45.10786)
		(width 0.15494)
		(layer "In5.Cu")
		(net "SMB_BIC_I2C9_MUX0_SSD5_R_SDA")
	)
	(segment
		(start 166.243 -22.16404)
		(end 167.29964 -21.1074)
		(width 0.15494)
		(layer "In5.Cu")
		(net "SMB_BIC_I2C9_MUX0_SSD5_R_SDA")
	)
	(segment
		(start 166.243 -26.949146)
		(end 166.243 -22.16404)
		(width 0.15494)
		(layer "In5.Cu")
		(net "SMB_BIC_I2C9_MUX0_SSD5_R_SDA")
	)
	(segment
		(start 167.3098 -28.015946)
		(end 166.243 -26.949146)
		(width 0.15494)
		(layer "In5.Cu")
		(net "SMB_BIC_I2C9_MUX0_SSD5_R_SDA")
	)
	(segment
		(start 167.3098 -29.14523)
		(end 167.3098 -28.015946)
		(width 0.15494)
		(layer "In5.Cu")
		(net "SMB_BIC_I2C9_MUX0_SSD5_R_SDA")
	)
	(segment
		(start 167.29964 -21.1074)
		(end 168.572434 -21.1074)
		(width 0.15494)
		(layer "In5.Cu")
		(net "SMB_BIC_I2C9_MUX0_SSD5_R_SDA")
	)
	(segment
		(start 175.129444 -86.254082)
		(end 179.20462 -82.178906)
		(width 0.15494)
		(layer "In5.Cu")
		(net "SMB_BIC_I2C9_MUX0_SSD5_R_SDA")
	)
	(segment
		(start 308.267862 -19.453098)
		(end 310.216042 -19.453098)
		(width 0.13208)
		(layer "F.Cu")
		(net "SMB_ISO_SSD10_SDA")
	)
	(segment
		(start 311.135522 -16.439388)
		(end 311.211722 -16.363188)
		(width 0.13208)
		(layer "F.Cu")
		(net "SMB_ISO_SSD10_SDA")
	)
	(segment
		(start 311.662318 -23.337266)
		(end 311.662318 -23.946866)
		(width 0.13208)
		(layer "F.Cu")
		(net "SMB_ISO_SSD10_SDA")
	)
	(segment
		(start 307.456332 -20.222972)
		(end 308.226206 -19.453098)
		(width 0.13208)
		(layer "F.Cu")
		(net "SMB_ISO_SSD10_SDA")
	)
	(segment
		(start 311.211722 -16.363188)
		(end 311.211722 -15.351252)
		(width 0.13208)
		(layer "F.Cu")
		(net "SMB_ISO_SSD10_SDA")
	)
	(segment
		(start 311.135522 -18.533618)
		(end 311.135522 -16.439388)
		(width 0.13208)
		(layer "F.Cu")
		(net "SMB_ISO_SSD10_SDA")
	)
	(segment
		(start 308.226206 -19.453098)
		(end 308.267862 -19.453098)
		(width 0.13208)
		(layer "F.Cu")
		(net "SMB_ISO_SSD10_SDA")
	)
	(segment
		(start 307.456332 -20.467574)
		(end 307.456332 -20.222972)
		(width 0.13208)
		(layer "F.Cu")
		(net "SMB_ISO_SSD10_SDA")
	)
	(segment
		(start 310.216042 -19.453098)
		(end 311.135522 -18.533618)
		(width 0.13208)
		(layer "F.Cu")
		(net "SMB_ISO_SSD10_SDA")
	)
	(via
		(at 311.211722 -15.351252)
		(size 0.508)
		(drill 0.254)
		(layers "F.Cu" "B.Cu")
		(net "SMB_ISO_SSD10_SDA")
	)
	(via
		(at 311.662318 -23.946866)
		(size 0.508)
		(drill 0.254)
		(layers "F.Cu" "B.Cu")
		(net "SMB_ISO_SSD10_SDA")
	)
	(segment
		(start 311.662318 -23.946866)
		(end 313.254644 -22.35454)
		(width 0.13208)
		(layer "B.Cu")
		(net "SMB_ISO_SSD10_SDA")
	)
	(segment
		(start 313.254644 -17.971516)
		(end 311.211722 -15.928594)
		(width 0.13208)
		(layer "B.Cu")
		(net "SMB_ISO_SSD10_SDA")
	)
	(segment
		(start 311.211722 -15.928594)
		(end 311.211722 -15.351252)
		(width 0.13208)
		(layer "B.Cu")
		(net "SMB_ISO_SSD10_SDA")
	)
	(segment
		(start 313.254644 -22.35454)
		(end 313.254644 -17.971516)
		(width 0.13208)
		(layer "B.Cu")
		(net "SMB_ISO_SSD10_SDA")
	)
	(segment
		(start 344.89009 -227.583238)
		(end 344.49385 -227.186998)
		(width 0.13208)
		(layer "F.Cu")
		(net "SSD3_CLK_EN_N")
	)
	(segment
		(start 344.043 -233.66095)
		(end 344.043 -232.918)
		(width 0.13208)
		(layer "F.Cu")
		(net "SSD3_CLK_EN_N")
	)
	(segment
		(start 344.043 -232.918)
		(end 344.551 -232.41)
		(width 0.13208)
		(layer "F.Cu")
		(net "SSD3_CLK_EN_N")
	)
	(segment
		(start 344.551 -232.41)
		(end 344.89009 -232.07091)
		(width 0.13208)
		(layer "F.Cu")
		(net "SSD3_CLK_EN_N")
	)
	(segment
		(start 344.89009 -232.07091)
		(end 344.89009 -227.583238)
		(width 0.13208)
		(layer "F.Cu")
		(net "SSD3_CLK_EN_N")
	)
	(via
		(at 344.551 -232.41)
		(size 0.762)
		(drill 0.381)
		(layers "F.Cu" "B.Cu")
		(net "SSD3_CLK_EN_N")
	)
	(segment
		(start 192.580006 -51.670966)
		(end 193.231516 -51.019456)
		(width 0.13208)
		(layer "F.Cu")
		(net "P12V_SSD6_SS")
	)
	(segment
		(start 192.430654 -53.144166)
		(end 192.580006 -52.994814)
		(width 0.13208)
		(layer "F.Cu")
		(net "P12V_SSD6_SS")
	)
	(segment
		(start 192.580006 -52.994814)
		(end 192.580006 -51.670966)
		(width 0.13208)
		(layer "F.Cu")
		(net "P12V_SSD6_SS")
	)
	(segment
		(start 193.231516 -51.019456)
		(end 193.967862 -51.019456)
		(width 0.13208)
		(layer "F.Cu")
		(net "P12V_SSD6_SS")
	)
	(segment
		(start 192.247266 -53.144166)
		(end 192.430654 -53.144166)
		(width 0.13208)
		(layer "F.Cu")
		(net "P12V_SSD6_SS")
	)
	(via
		(at 193.231516 -51.019456)
		(size 0.508)
		(drill 0.254)
		(layers "F.Cu" "B.Cu")
		(net "P12V_SSD6_SS")
	)
	(segment
		(start 138.585194 -87.813642)
		(end 138.585194 -87.330026)
		(width 0.13208)
		(layer "F.Cu")
		(net "SMB_BIC_I2C9_MUX0_SSD4_R_SDA")
	)
	(segment
		(start 138.743182 -87.172038)
		(end 143.51127 -87.172038)
		(width 0.13208)
		(layer "F.Cu")
		(net "SMB_BIC_I2C9_MUX0_SSD4_R_SDA")
	)
	(segment
		(start 143.562578 -22.537166)
		(end 143.562578 -22.097492)
		(width 0.13208)
		(layer "F.Cu")
		(net "SMB_BIC_I2C9_MUX0_SSD4_R_SDA")
	)
	(segment
		(start 143.51127 -87.172038)
		(end 145.816066 -84.867242)
		(width 0.13208)
		(layer "F.Cu")
		(net "SMB_BIC_I2C9_MUX0_SSD4_R_SDA")
	)
	(segment
		(start 143.035782 -21.570696)
		(end 143.035782 -20.789392)
		(width 0.13208)
		(layer "F.Cu")
		(net "SMB_BIC_I2C9_MUX0_SSD4_R_SDA")
	)
	(segment
		(start 145.816066 -84.867242)
		(end 147.959318 -84.867242)
		(width 0.13208)
		(layer "F.Cu")
		(net "SMB_BIC_I2C9_MUX0_SSD4_R_SDA")
	)
	(segment
		(start 138.585194 -87.330026)
		(end 138.743182 -87.172038)
		(width 0.13208)
		(layer "F.Cu")
		(net "SMB_BIC_I2C9_MUX0_SSD4_R_SDA")
	)
	(segment
		(start 147.959318 -84.867242)
		(end 148.508466 -85.41639)
		(width 0.13208)
		(layer "F.Cu")
		(net "SMB_BIC_I2C9_MUX0_SSD4_R_SDA")
	)
	(segment
		(start 143.32077 -21.855684)
		(end 143.035782 -21.570696)
		(width 0.13208)
		(layer "F.Cu")
		(net "SMB_BIC_I2C9_MUX0_SSD4_R_SDA")
	)
	(segment
		(start 136.845294 -87.813642)
		(end 138.585194 -87.813642)
		(width 0.13208)
		(layer "F.Cu")
		(net "SMB_BIC_I2C9_MUX0_SSD4_R_SDA")
	)
	(segment
		(start 143.562578 -22.097492)
		(end 143.32077 -21.855684)
		(width 0.13208)
		(layer "F.Cu")
		(net "SMB_BIC_I2C9_MUX0_SSD4_R_SDA")
	)
	(via
		(at 148.508466 -85.41639)
		(size 0.508)
		(drill 0.254)
		(layers "F.Cu" "B.Cu")
		(net "SMB_BIC_I2C9_MUX0_SSD4_R_SDA")
	)
	(via
		(at 143.32077 -21.855684)
		(size 0.508)
		(drill 0.254)
		(layers "F.Cu" "B.Cu")
		(net "SMB_BIC_I2C9_MUX0_SSD4_R_SDA")
	)
	(segment
		(start 142.75689 -21.291804)
		(end 143.32077 -21.855684)
		(width 0.15494)
		(layer "In5.Cu")
		(net "SMB_BIC_I2C9_MUX0_SSD4_R_SDA")
	)
	(segment
		(start 141.115288 -21.291804)
		(end 142.75689 -21.291804)
		(width 0.15494)
		(layer "In5.Cu")
		(net "SMB_BIC_I2C9_MUX0_SSD4_R_SDA")
	)
	(segment
		(start 153.34996 -73.567036)
		(end 153.34996 -45.162724)
		(width 0.15494)
		(layer "In5.Cu")
		(net "SMB_BIC_I2C9_MUX0_SSD4_R_SDA")
	)
	(segment
		(start 140.936726 -32.74949)
		(end 140.936726 -29.44368)
		(width 0.15494)
		(layer "In5.Cu")
		(net "SMB_BIC_I2C9_MUX0_SSD4_R_SDA")
	)
	(segment
		(start 141.3256 -28.067254)
		(end 140.1064 -26.848054)
		(width 0.15494)
		(layer "In5.Cu")
		(net "SMB_BIC_I2C9_MUX0_SSD4_R_SDA")
	)
	(segment
		(start 141.3256 -29.054806)
		(end 141.3256 -28.067254)
		(width 0.15494)
		(layer "In5.Cu")
		(net "SMB_BIC_I2C9_MUX0_SSD4_R_SDA")
	)
	(segment
		(start 153.34996 -45.162724)
		(end 140.936726 -32.74949)
		(width 0.15494)
		(layer "In5.Cu")
		(net "SMB_BIC_I2C9_MUX0_SSD4_R_SDA")
	)
	(segment
		(start 140.1064 -22.300692)
		(end 141.115288 -21.291804)
		(width 0.15494)
		(layer "In5.Cu")
		(net "SMB_BIC_I2C9_MUX0_SSD4_R_SDA")
	)
	(segment
		(start 140.1064 -26.848054)
		(end 140.1064 -22.300692)
		(width 0.15494)
		(layer "In5.Cu")
		(net "SMB_BIC_I2C9_MUX0_SSD4_R_SDA")
	)
	(segment
		(start 140.936726 -29.44368)
		(end 141.3256 -29.054806)
		(width 0.15494)
		(layer "In5.Cu")
		(net "SMB_BIC_I2C9_MUX0_SSD4_R_SDA")
	)
	(segment
		(start 148.508466 -78.40853)
		(end 153.34996 -73.567036)
		(width 0.15494)
		(layer "In5.Cu")
		(net "SMB_BIC_I2C9_MUX0_SSD4_R_SDA")
	)
	(segment
		(start 148.508466 -85.41639)
		(end 148.508466 -78.40853)
		(width 0.15494)
		(layer "In5.Cu")
		(net "SMB_BIC_I2C9_MUX0_SSD4_R_SDA")
	)
	(segment
		(start 312.654696 -22.561296)
		(end 312.654696 -21.847048)
		(width 0.13208)
		(layer "F.Cu")
		(net "SMB_SSD10_ISO_EN")
	)
	(segment
		(start 311.860438 -21.05279)
		(end 311.860438 -20.789392)
		(width 0.13208)
		(layer "F.Cu")
		(net "SMB_SSD10_ISO_EN")
	)
	(segment
		(start 312.654696 -21.847048)
		(end 311.860438 -21.05279)
		(width 0.13208)
		(layer "F.Cu")
		(net "SMB_SSD10_ISO_EN")
	)
	(via
		(at 312.654696 -21.847048)
		(size 0.508)
		(drill 0.254)
		(layers "F.Cu" "B.Cu")
		(net "SMB_SSD10_ISO_EN")
	)
	(segment
		(start 59.373262 -390.47166)
		(end 59.373262 -391.097008)
		(width 0.13208)
		(layer "F.Cu")
		(net "RST_GPU_FPGA_PEX_RST_R_N")
	)
	(via
		(at 59.373262 -391.097008)
		(size 0.508)
		(drill 0.254)
		(layers "F.Cu" "B.Cu")
		(net "RST_GPU_FPGA_PEX_RST_R_N")
	)
	(segment
		(start 46.609 -414.02)
		(end 50.190146 -414.02)
		(width 0.15494)
		(layer "In9.Cu")
		(net "RST_GPU_FPGA_PEX_RST_R_N")
	)
	(segment
		(start 51.308 -393.5222)
		(end 52.690014 -392.140186)
		(width 0.15494)
		(layer "In9.Cu")
		(net "RST_GPU_FPGA_PEX_RST_R_N")
	)
	(segment
		(start 45.509942 -412.090108)
		(end 45.509942 -412.920942)
		(width 0.15494)
		(layer "In9.Cu")
		(net "RST_GPU_FPGA_PEX_RST_R_N")
	)
	(segment
		(start 51.308 -412.902146)
		(end 51.308 -393.5222)
		(width 0.15494)
		(layer "In9.Cu")
		(net "RST_GPU_FPGA_PEX_RST_R_N")
	)
	(segment
		(start 58.330084 -392.140186)
		(end 59.373262 -391.097008)
		(width 0.15494)
		(layer "In9.Cu")
		(net "RST_GPU_FPGA_PEX_RST_R_N")
	)
	(segment
		(start 50.190146 -414.02)
		(end 51.308 -412.902146)
		(width 0.15494)
		(layer "In9.Cu")
		(net "RST_GPU_FPGA_PEX_RST_R_N")
	)
	(segment
		(start 52.690014 -392.140186)
		(end 58.330084 -392.140186)
		(width 0.15494)
		(layer "In9.Cu")
		(net "RST_GPU_FPGA_PEX_RST_R_N")
	)
	(segment
		(start 45.509942 -412.920942)
		(end 46.609 -414.02)
		(width 0.15494)
		(layer "In9.Cu")
		(net "RST_GPU_FPGA_PEX_RST_R_N")
	)
	(segment
		(start 141.626336 -392.026394)
		(end 141.931644 -391.721086)
		(width 0.13208)
		(layer "F.Cu")
		(net "SMB_MB_BMC_SDA")
	)
	(segment
		(start 141.931644 -391.721086)
		(end 141.931644 -390.571736)
		(width 0.13208)
		(layer "F.Cu")
		(net "SMB_MB_BMC_SDA")
	)
	(via
		(at 141.626336 -392.026394)
		(size 0.508)
		(drill 0.254)
		(layers "F.Cu" "B.Cu")
		(net "SMB_MB_BMC_SDA")
	)
	(segment
		(start 138.9888 -409.679648)
		(end 136.029192 -412.639256)
		(width 0.15494)
		(layer "In9.Cu")
		(net "SMB_MB_BMC_SDA")
	)
	(segment
		(start 134.059168 -412.639256)
		(end 133.51002 -412.090108)
		(width 0.15494)
		(layer "In9.Cu")
		(net "SMB_MB_BMC_SDA")
	)
	(segment
		(start 136.029192 -412.639256)
		(end 134.059168 -412.639256)
		(width 0.15494)
		(layer "In9.Cu")
		(net "SMB_MB_BMC_SDA")
	)
	(segment
		(start 141.626336 -392.026394)
		(end 140.556742 -392.026394)
		(width 0.15494)
		(layer "In9.Cu")
		(net "SMB_MB_BMC_SDA")
	)
	(segment
		(start 138.9888 -393.594336)
		(end 138.9888 -409.679648)
		(width 0.15494)
		(layer "In9.Cu")
		(net "SMB_MB_BMC_SDA")
	)
	(segment
		(start 140.556742 -392.026394)
		(end 138.9888 -393.594336)
		(width 0.15494)
		(layer "In9.Cu")
		(net "SMB_MB_BMC_SDA")
	)
	(segment
		(start 195.562474 -22.537166)
		(end 195.562474 -22.097492)
		(width 0.13208)
		(layer "F.Cu")
		(net "SMB_BIC_I2C9_MUX0_SSD6_R_SDA")
	)
	(segment
		(start 177.012854 -88.529922)
		(end 188.741812 -76.800964)
		(width 0.13208)
		(layer "F.Cu")
		(net "SMB_BIC_I2C9_MUX0_SSD6_R_SDA")
	)
	(segment
		(start 195.562474 -22.097492)
		(end 195.320666 -21.855684)
		(width 0.13208)
		(layer "F.Cu")
		(net "SMB_BIC_I2C9_MUX0_SSD6_R_SDA")
	)
	(segment
		(start 195.079874 -76.800964)
		(end 198.875904 -73.004934)
		(width 0.13208)
		(layer "F.Cu")
		(net "SMB_BIC_I2C9_MUX0_SSD6_R_SDA")
	)
	(segment
		(start 138.585194 -92.385642)
		(end 138.585194 -92.788994)
		(width 0.13208)
		(layer "F.Cu")
		(net "SMB_BIC_I2C9_MUX0_SSD6_R_SDA")
	)
	(segment
		(start 198.875904 -73.004934)
		(end 200.73112 -73.004934)
		(width 0.13208)
		(layer "F.Cu")
		(net "SMB_BIC_I2C9_MUX0_SSD6_R_SDA")
	)
	(segment
		(start 195.035678 -21.570696)
		(end 195.035678 -20.789392)
		(width 0.13208)
		(layer "F.Cu")
		(net "SMB_BIC_I2C9_MUX0_SSD6_R_SDA")
	)
	(segment
		(start 195.320666 -21.855684)
		(end 195.035678 -21.570696)
		(width 0.13208)
		(layer "F.Cu")
		(net "SMB_BIC_I2C9_MUX0_SSD6_R_SDA")
	)
	(segment
		(start 138.774932 -92.978732)
		(end 147.457668 -92.978732)
		(width 0.13208)
		(layer "F.Cu")
		(net "SMB_BIC_I2C9_MUX0_SSD6_R_SDA")
	)
	(segment
		(start 151.906478 -88.529922)
		(end 177.012854 -88.529922)
		(width 0.13208)
		(layer "F.Cu")
		(net "SMB_BIC_I2C9_MUX0_SSD6_R_SDA")
	)
	(segment
		(start 136.845294 -92.385642)
		(end 138.585194 -92.385642)
		(width 0.13208)
		(layer "F.Cu")
		(net "SMB_BIC_I2C9_MUX0_SSD6_R_SDA")
	)
	(segment
		(start 188.741812 -76.800964)
		(end 195.079874 -76.800964)
		(width 0.13208)
		(layer "F.Cu")
		(net "SMB_BIC_I2C9_MUX0_SSD6_R_SDA")
	)
	(segment
		(start 147.457668 -92.978732)
		(end 151.906478 -88.529922)
		(width 0.13208)
		(layer "F.Cu")
		(net "SMB_BIC_I2C9_MUX0_SSD6_R_SDA")
	)
	(segment
		(start 138.585194 -92.788994)
		(end 138.774932 -92.978732)
		(width 0.13208)
		(layer "F.Cu")
		(net "SMB_BIC_I2C9_MUX0_SSD6_R_SDA")
	)
	(via
		(at 195.320666 -21.855684)
		(size 0.508)
		(drill 0.254)
		(layers "F.Cu" "B.Cu")
		(net "SMB_BIC_I2C9_MUX0_SSD6_R_SDA")
	)
	(via
		(at 200.73112 -73.004934)
		(size 0.508)
		(drill 0.254)
		(layers "F.Cu" "B.Cu")
		(net "SMB_BIC_I2C9_MUX0_SSD6_R_SDA")
	)
	(segment
		(start 192.2526 -27.000454)
		(end 192.2526 -22.154388)
		(width 0.15494)
		(layer "In5.Cu")
		(net "SMB_BIC_I2C9_MUX0_SSD6_R_SDA")
	)
	(segment
		(start 192.2526 -22.154388)
		(end 193.121788 -21.2852)
		(width 0.15494)
		(layer "In5.Cu")
		(net "SMB_BIC_I2C9_MUX0_SSD6_R_SDA")
	)
	(segment
		(start 205.258924 -45.257212)
		(end 193.018918 -33.017206)
		(width 0.15494)
		(layer "In5.Cu")
		(net "SMB_BIC_I2C9_MUX0_SSD6_R_SDA")
	)
	(segment
		(start 193.018918 -33.017206)
		(end 193.018918 -29.408628)
		(width 0.15494)
		(layer "In5.Cu")
		(net "SMB_BIC_I2C9_MUX0_SSD6_R_SDA")
	)
	(segment
		(start 193.121788 -21.2852)
		(end 194.750182 -21.2852)
		(width 0.15494)
		(layer "In5.Cu")
		(net "SMB_BIC_I2C9_MUX0_SSD6_R_SDA")
	)
	(segment
		(start 193.421 -29.006546)
		(end 193.421 -28.168854)
		(width 0.15494)
		(layer "In5.Cu")
		(net "SMB_BIC_I2C9_MUX0_SSD6_R_SDA")
	)
	(segment
		(start 193.421 -28.168854)
		(end 192.2526 -27.000454)
		(width 0.15494)
		(layer "In5.Cu")
		(net "SMB_BIC_I2C9_MUX0_SSD6_R_SDA")
	)
	(segment
		(start 200.73112 -73.004934)
		(end 200.73112 -68.470526)
		(width 0.15494)
		(layer "In5.Cu")
		(net "SMB_BIC_I2C9_MUX0_SSD6_R_SDA")
	)
	(segment
		(start 205.258924 -63.942722)
		(end 205.258924 -45.257212)
		(width 0.15494)
		(layer "In5.Cu")
		(net "SMB_BIC_I2C9_MUX0_SSD6_R_SDA")
	)
	(segment
		(start 193.018918 -29.408628)
		(end 193.421 -29.006546)
		(width 0.15494)
		(layer "In5.Cu")
		(net "SMB_BIC_I2C9_MUX0_SSD6_R_SDA")
	)
	(segment
		(start 194.750182 -21.2852)
		(end 195.320666 -21.855684)
		(width 0.15494)
		(layer "In5.Cu")
		(net "SMB_BIC_I2C9_MUX0_SSD6_R_SDA")
	)
	(segment
		(start 200.73112 -68.470526)
		(end 205.258924 -63.942722)
		(width 0.15494)
		(layer "In5.Cu")
		(net "SMB_BIC_I2C9_MUX0_SSD6_R_SDA")
	)
	(segment
		(start 62.8904 -378.586746)
		(end 59.195462 -382.281684)
		(width 0.13208)
		(layer "F.Cu")
		(net "SMB_GPU_2_R_SCL")
	)
	(segment
		(start 64.32677 -364.62843)
		(end 62.8904 -366.0648)
		(width 0.13208)
		(layer "F.Cu")
		(net "SMB_GPU_2_R_SCL")
	)
	(segment
		(start 100.42652 -377.387612)
		(end 98.180906 -375.141998)
		(width 0.13208)
		(layer "F.Cu")
		(net "SMB_GPU_2_R_SCL")
	)
	(segment
		(start 98.180906 -375.141998)
		(end 98.180906 -369.91036)
		(width 0.13208)
		(layer "F.Cu")
		(net "SMB_GPU_2_R_SCL")
	)
	(segment
		(start 92.898976 -364.62843)
		(end 64.32677 -364.62843)
		(width 0.13208)
		(layer "F.Cu")
		(net "SMB_GPU_2_R_SCL")
	)
	(segment
		(start 98.180906 -369.91036)
		(end 92.898976 -364.62843)
		(width 0.13208)
		(layer "F.Cu")
		(net "SMB_GPU_2_R_SCL")
	)
	(segment
		(start 59.195462 -382.281684)
		(end 58.612532 -382.281684)
		(width 0.13208)
		(layer "F.Cu")
		(net "SMB_GPU_2_R_SCL")
	)
	(segment
		(start 62.8904 -366.0648)
		(end 62.8904 -378.586746)
		(width 0.13208)
		(layer "F.Cu")
		(net "SMB_GPU_2_R_SCL")
	)
	(via
		(at 58.612532 -382.281684)
		(size 0.508)
		(drill 0.254)
		(layers "F.Cu" "B.Cu")
		(net "SMB_GPU_2_R_SCL")
	)
	(via
		(at 100.42652 -377.387612)
		(size 0.508)
		(drill 0.254)
		(layers "F.Cu" "B.Cu")
		(net "SMB_GPU_2_R_SCL")
	)
	(segment
		(start 100.42652 -377.387612)
		(end 99.455478 -377.387612)
		(width 0.13208)
		(layer "B.Cu")
		(net "SMB_GPU_2_R_SCL")
	)
	(segment
		(start 53.165756 -383.307844)
		(end 49.276 -387.1976)
		(width 0.15494)
		(layer "In9.Cu")
		(net "SMB_GPU_2_R_SCL")
	)
	(segment
		(start 46.213522 -380.293626)
		(end 45.509942 -379.590046)
		(width 0.15494)
		(layer "In9.Cu")
		(net "SMB_GPU_2_R_SCL")
	)
	(segment
		(start 47.117 -387.1976)
		(end 46.213522 -386.294122)
		(width 0.15494)
		(layer "In9.Cu")
		(net "SMB_GPU_2_R_SCL")
	)
	(segment
		(start 49.276 -387.1976)
		(end 47.117 -387.1976)
		(width 0.15494)
		(layer "In9.Cu")
		(net "SMB_GPU_2_R_SCL")
	)
	(segment
		(start 58.093864 -382.281684)
		(end 57.067704 -383.307844)
		(width 0.15494)
		(layer "In9.Cu")
		(net "SMB_GPU_2_R_SCL")
	)
	(segment
		(start 58.612532 -382.281684)
		(end 58.093864 -382.281684)
		(width 0.15494)
		(layer "In9.Cu")
		(net "SMB_GPU_2_R_SCL")
	)
	(segment
		(start 57.067704 -383.307844)
		(end 53.165756 -383.307844)
		(width 0.15494)
		(layer "In9.Cu")
		(net "SMB_GPU_2_R_SCL")
	)
	(segment
		(start 46.213522 -386.294122)
		(end 46.213522 -380.293626)
		(width 0.15494)
		(layer "In9.Cu")
		(net "SMB_GPU_2_R_SCL")
	)
	(segment
		(start 59.134502 -375.524268)
		(end 59.261502 -375.397268)
		(width 0.13208)
		(layer "F.Cu")
		(net "PRSNT_GPU_D_R_N")
	)
	(segment
		(start 59.261502 -375.397268)
		(end 59.261502 -375.081546)
		(width 0.13208)
		(layer "F.Cu")
		(net "PRSNT_GPU_D_R_N")
	)
	(segment
		(start 58.576972 -375.524268)
		(end 59.134502 -375.524268)
		(width 0.13208)
		(layer "F.Cu")
		(net "PRSNT_GPU_D_R_N")
	)
	(via
		(at 59.261502 -375.081546)
		(size 0.508)
		(drill 0.254)
		(layers "F.Cu" "B.Cu")
		(net "PRSNT_GPU_D_R_N")
	)
	(segment
		(start 73.636886 -368.51717)
		(end 74.109834 -368.990118)
		(width 0.15494)
		(layer "In15.Cu")
		(net "PRSNT_GPU_D_R_N")
	)
	(segment
		(start 65.825878 -368.51717)
		(end 73.636886 -368.51717)
		(width 0.15494)
		(layer "In15.Cu")
		(net "PRSNT_GPU_D_R_N")
	)
	(segment
		(start 59.261502 -375.081546)
		(end 65.825878 -368.51717)
		(width 0.15494)
		(layer "In15.Cu")
		(net "PRSNT_GPU_D_R_N")
	)
	(segment
		(start 142.748 -35.6362)
		(end 140.222732 -35.6362)
		(width 0.13208)
		(layer "F.Cu")
		(net "PWRGD_P3V3_SSD5_R")
	)
	(segment
		(start 150.711154 -61.386974)
		(end 150.711154 -62.051438)
		(width 0.13208)
		(layer "F.Cu")
		(net "PWRGD_P3V3_SSD5_R")
	)
	(segment
		(start 347.218 -228.284786)
		(end 347.218 -228.727)
		(width 0.13208)
		(layer "F.Cu")
		(net "PWRGD_P3V3_SSD5_R")
	)
	(segment
		(start 143.344392 -36.232592)
		(end 142.748 -35.6362)
		(width 0.13208)
		(layer "F.Cu")
		(net "PWRGD_P3V3_SSD5_R")
	)
	(segment
		(start 138.528044 -35.876738)
		(end 139.270994 -35.876738)
		(width 0.13208)
		(layer "F.Cu")
		(net "PWRGD_P3V3_SSD5_R")
	)
	(segment
		(start 347.290136 -227.583238)
		(end 347.290136 -228.21265)
		(width 0.13208)
		(layer "F.Cu")
		(net "PWRGD_P3V3_SSD5_R")
	)
	(segment
		(start 139.982194 -35.876738)
		(end 139.270994 -35.876738)
		(width 0.13208)
		(layer "F.Cu")
		(net "PWRGD_P3V3_SSD5_R")
	)
	(segment
		(start 346.893896 -227.186998)
		(end 347.290136 -227.583238)
		(width 0.13208)
		(layer "F.Cu")
		(net "PWRGD_P3V3_SSD5_R")
	)
	(segment
		(start 347.290136 -228.21265)
		(end 347.218 -228.284786)
		(width 0.13208)
		(layer "F.Cu")
		(net "PWRGD_P3V3_SSD5_R")
	)
	(segment
		(start 143.69542 -36.232592)
		(end 143.344392 -36.232592)
		(width 0.13208)
		(layer "F.Cu")
		(net "PWRGD_P3V3_SSD5_R")
	)
	(segment
		(start 140.222732 -35.6362)
		(end 139.982194 -35.876738)
		(width 0.13208)
		(layer "F.Cu")
		(net "PWRGD_P3V3_SSD5_R")
	)
	(via
		(at 150.39594 -227.485194)
		(size 0.508)
		(drill 0.254)
		(layers "F.Cu" "B.Cu")
		(net "PWRGD_P3V3_SSD5_R")
	)
	(via
		(at 347.218 -228.727)
		(size 0.508)
		(drill 0.254)
		(layers "F.Cu" "B.Cu")
		(net "PWRGD_P3V3_SSD5_R")
	)
	(via
		(at 150.711154 -62.051438)
		(size 0.508)
		(drill 0.254)
		(layers "F.Cu" "B.Cu")
		(net "PWRGD_P3V3_SSD5_R")
	)
	(via
		(at 139.270994 -35.876738)
		(size 0.508)
		(drill 0.254)
		(layers "F.Cu" "B.Cu")
		(net "PWRGD_P3V3_SSD5_R")
	)
	(segment
		(start 152.07234 -45.692822)
		(end 152.07234 -61.199268)
		(width 0.15494)
		(layer "In5.Cu")
		(net "PWRGD_P3V3_SSD5_R")
	)
	(segment
		(start 141.762226 -163.087304)
		(end 142.97533 -164.300408)
		(width 0.15494)
		(layer "In5.Cu")
		(net "PWRGD_P3V3_SSD5_R")
	)
	(segment
		(start 150.711154 -62.051438)
		(end 151.9682 -63.308484)
		(width 0.15494)
		(layer "In5.Cu")
		(net "PWRGD_P3V3_SSD5_R")
	)
	(segment
		(start 142.4178 -82.307684)
		(end 142.4178 -110.6932)
		(width 0.15494)
		(layer "In5.Cu")
		(net "PWRGD_P3V3_SSD5_R")
	)
	(segment
		(start 151.192992 -223.616774)
		(end 150.39594 -224.413826)
		(width 0.15494)
		(layer "In5.Cu")
		(net "PWRGD_P3V3_SSD5_R")
	)
	(segment
		(start 151.9682 -63.308484)
		(end 151.9682 -72.757284)
		(width 0.15494)
		(layer "In5.Cu")
		(net "PWRGD_P3V3_SSD5_R")
	)
	(segment
		(start 142.97533 -164.300408)
		(end 142.97533 -171.931076)
		(width 0.15494)
		(layer "In5.Cu")
		(net "PWRGD_P3V3_SSD5_R")
	)
	(segment
		(start 151.22017 -62.051438)
		(end 150.711154 -62.051438)
		(width 0.15494)
		(layer "In5.Cu")
		(net "PWRGD_P3V3_SSD5_R")
	)
	(segment
		(start 144.302226 -173.257972)
		(end 144.302226 -186.517026)
		(width 0.15494)
		(layer "In5.Cu")
		(net "PWRGD_P3V3_SSD5_R")
	)
	(segment
		(start 144.302226 -186.517026)
		(end 149.94255 -192.15735)
		(width 0.15494)
		(layer "In5.Cu")
		(net "PWRGD_P3V3_SSD5_R")
	)
	(segment
		(start 151.192992 -195.17614)
		(end 151.192992 -223.616774)
		(width 0.15494)
		(layer "In5.Cu")
		(net "PWRGD_P3V3_SSD5_R")
	)
	(segment
		(start 142.256256 -35.876738)
		(end 152.07234 -45.692822)
		(width 0.15494)
		(layer "In5.Cu")
		(net "PWRGD_P3V3_SSD5_R")
	)
	(segment
		(start 149.94255 -192.15735)
		(end 151.192992 -195.17614)
		(width 0.15494)
		(layer "In5.Cu")
		(net "PWRGD_P3V3_SSD5_R")
	)
	(segment
		(start 151.9682 -72.757284)
		(end 142.4178 -82.307684)
		(width 0.15494)
		(layer "In5.Cu")
		(net "PWRGD_P3V3_SSD5_R")
	)
	(segment
		(start 152.07234 -61.199268)
		(end 151.22017 -62.051438)
		(width 0.15494)
		(layer "In5.Cu")
		(net "PWRGD_P3V3_SSD5_R")
	)
	(segment
		(start 142.97533 -171.931076)
		(end 144.302226 -173.257972)
		(width 0.15494)
		(layer "In5.Cu")
		(net "PWRGD_P3V3_SSD5_R")
	)
	(segment
		(start 150.39594 -224.413826)
		(end 150.39594 -227.485194)
		(width 0.15494)
		(layer "In5.Cu")
		(net "PWRGD_P3V3_SSD5_R")
	)
	(segment
		(start 142.4178 -110.6932)
		(end 141.762226 -111.348774)
		(width 0.15494)
		(layer "In5.Cu")
		(net "PWRGD_P3V3_SSD5_R")
	)
	(segment
		(start 141.762226 -111.348774)
		(end 141.762226 -163.087304)
		(width 0.15494)
		(layer "In5.Cu")
		(net "PWRGD_P3V3_SSD5_R")
	)
	(segment
		(start 139.270994 -35.876738)
		(end 142.256256 -35.876738)
		(width 0.15494)
		(layer "In5.Cu")
		(net "PWRGD_P3V3_SSD5_R")
	)
	(segment
		(start 247.7643 -238.6076)
		(end 247.095772 -237.939072)
		(width 0.15494)
		(layer "In13.Cu")
		(net "PWRGD_P3V3_SSD5_R")
	)
	(segment
		(start 267.309346 -238.76)
		(end 264.921746 -236.3724)
		(width 0.15494)
		(layer "In13.Cu")
		(net "PWRGD_P3V3_SSD5_R")
	)
	(segment
		(start 344.547444 -234.808014)
		(end 344.547444 -235.401612)
		(width 0.15494)
		(layer "In13.Cu")
		(net "PWRGD_P3V3_SSD5_R")
	)
	(segment
		(start 150.39594 -231.760268)
		(end 150.39594 -227.485194)
		(width 0.15494)
		(layer "In13.Cu")
		(net "PWRGD_P3V3_SSD5_R")
	)
	(segment
		(start 337.41106 -240.61674)
		(end 306.365656 -240.61674)
		(width 0.15494)
		(layer "In13.Cu")
		(net "PWRGD_P3V3_SSD5_R")
	)
	(segment
		(start 340.44128 -237.58652)
		(end 337.41106 -240.61674)
		(width 0.15494)
		(layer "In13.Cu")
		(net "PWRGD_P3V3_SSD5_R")
	)
	(segment
		(start 342.49868 -236.672374)
		(end 341.584534 -237.58652)
		(width 0.15494)
		(layer "In13.Cu")
		(net "PWRGD_P3V3_SSD5_R")
	)
	(segment
		(start 246.207788 -237.600236)
		(end 245.23827 -237.600236)
		(width 0.15494)
		(layer "In13.Cu")
		(net "PWRGD_P3V3_SSD5_R")
	)
	(segment
		(start 347.726 -229.235)
		(end 347.726 -231.629458)
		(width 0.15494)
		(layer "In13.Cu")
		(net "PWRGD_P3V3_SSD5_R")
	)
	(segment
		(start 210.592416 -237.903004)
		(end 207.841596 -237.903004)
		(width 0.15494)
		(layer "In13.Cu")
		(net "PWRGD_P3V3_SSD5_R")
	)
	(segment
		(start 178.652678 -240.273078)
		(end 172.425868 -234.046268)
		(width 0.15494)
		(layer "In13.Cu")
		(net "PWRGD_P3V3_SSD5_R")
	)
	(segment
		(start 205.471522 -240.273078)
		(end 178.652678 -240.273078)
		(width 0.15494)
		(layer "In13.Cu")
		(net "PWRGD_P3V3_SSD5_R")
	)
	(segment
		(start 305.829716 -240.0808)
		(end 276.276054 -240.0808)
		(width 0.15494)
		(layer "In13.Cu")
		(net "PWRGD_P3V3_SSD5_R")
	)
	(segment
		(start 344.282522 -235.666534)
		(end 342.869266 -235.666534)
		(width 0.15494)
		(layer "In13.Cu")
		(net "PWRGD_P3V3_SSD5_R")
	)
	(segment
		(start 256.692146 -238.6076)
		(end 247.7643 -238.6076)
		(width 0.15494)
		(layer "In13.Cu")
		(net "PWRGD_P3V3_SSD5_R")
	)
	(segment
		(start 347.726 -231.629458)
		(end 344.547444 -234.808014)
		(width 0.15494)
		(layer "In13.Cu")
		(net "PWRGD_P3V3_SSD5_R")
	)
	(segment
		(start 152.68194 -234.046268)
		(end 150.39594 -231.760268)
		(width 0.15494)
		(layer "In13.Cu")
		(net "PWRGD_P3V3_SSD5_R")
	)
	(segment
		(start 261.451344 -236.3724)
		(end 260.130544 -237.6932)
		(width 0.15494)
		(layer "In13.Cu")
		(net "PWRGD_P3V3_SSD5_R")
	)
	(segment
		(start 276.276054 -240.0808)
		(end 274.955254 -238.76)
		(width 0.15494)
		(layer "In13.Cu")
		(net "PWRGD_P3V3_SSD5_R")
	)
	(segment
		(start 207.841596 -237.903004)
		(end 205.471522 -240.273078)
		(width 0.15494)
		(layer "In13.Cu")
		(net "PWRGD_P3V3_SSD5_R")
	)
	(segment
		(start 341.584534 -237.58652)
		(end 340.44128 -237.58652)
		(width 0.15494)
		(layer "In13.Cu")
		(net "PWRGD_P3V3_SSD5_R")
	)
	(segment
		(start 247.095772 -237.939072)
		(end 246.546624 -237.939072)
		(width 0.15494)
		(layer "In13.Cu")
		(net "PWRGD_P3V3_SSD5_R")
	)
	(segment
		(start 274.955254 -238.76)
		(end 267.309346 -238.76)
		(width 0.15494)
		(layer "In13.Cu")
		(net "PWRGD_P3V3_SSD5_R")
	)
	(segment
		(start 230.812848 -237.154466)
		(end 230.211122 -236.55274)
		(width 0.15494)
		(layer "In13.Cu")
		(net "PWRGD_P3V3_SSD5_R")
	)
	(segment
		(start 342.49868 -236.03712)
		(end 342.49868 -236.672374)
		(width 0.15494)
		(layer "In13.Cu")
		(net "PWRGD_P3V3_SSD5_R")
	)
	(segment
		(start 344.547444 -235.401612)
		(end 344.282522 -235.666534)
		(width 0.15494)
		(layer "In13.Cu")
		(net "PWRGD_P3V3_SSD5_R")
	)
	(segment
		(start 244.7925 -237.154466)
		(end 230.812848 -237.154466)
		(width 0.15494)
		(layer "In13.Cu")
		(net "PWRGD_P3V3_SSD5_R")
	)
	(segment
		(start 246.546624 -237.939072)
		(end 246.207788 -237.600236)
		(width 0.15494)
		(layer "In13.Cu")
		(net "PWRGD_P3V3_SSD5_R")
	)
	(segment
		(start 172.425868 -234.046268)
		(end 152.68194 -234.046268)
		(width 0.15494)
		(layer "In13.Cu")
		(net "PWRGD_P3V3_SSD5_R")
	)
	(segment
		(start 342.869266 -235.666534)
		(end 342.49868 -236.03712)
		(width 0.15494)
		(layer "In13.Cu")
		(net "PWRGD_P3V3_SSD5_R")
	)
	(segment
		(start 257.606546 -237.6932)
		(end 256.692146 -238.6076)
		(width 0.15494)
		(layer "In13.Cu")
		(net "PWRGD_P3V3_SSD5_R")
	)
	(segment
		(start 347.218 -228.727)
		(end 347.726 -229.235)
		(width 0.15494)
		(layer "In13.Cu")
		(net "PWRGD_P3V3_SSD5_R")
	)
	(segment
		(start 306.365656 -240.61674)
		(end 305.829716 -240.0808)
		(width 0.15494)
		(layer "In13.Cu")
		(net "PWRGD_P3V3_SSD5_R")
	)
	(segment
		(start 245.23827 -237.600236)
		(end 244.7925 -237.154466)
		(width 0.15494)
		(layer "In13.Cu")
		(net "PWRGD_P3V3_SSD5_R")
	)
	(segment
		(start 211.94268 -236.55274)
		(end 210.592416 -237.903004)
		(width 0.15494)
		(layer "In13.Cu")
		(net "PWRGD_P3V3_SSD5_R")
	)
	(segment
		(start 260.130544 -237.6932)
		(end 257.606546 -237.6932)
		(width 0.15494)
		(layer "In13.Cu")
		(net "PWRGD_P3V3_SSD5_R")
	)
	(segment
		(start 230.211122 -236.55274)
		(end 211.94268 -236.55274)
		(width 0.15494)
		(layer "In13.Cu")
		(net "PWRGD_P3V3_SSD5_R")
	)
	(segment
		(start 264.921746 -236.3724)
		(end 261.451344 -236.3724)
		(width 0.15494)
		(layer "In13.Cu")
		(net "PWRGD_P3V3_SSD5_R")
	)
	(segment
		(start 138.774932 -91.835732)
		(end 140.336016 -91.835732)
		(width 0.13208)
		(layer "F.Cu")
		(net "SMB_BIC_I2C9_MUX0_SSD5_R_SCL")
	)
	(segment
		(start 138.585194 -91.242642)
		(end 138.585194 -91.645994)
		(width 0.13208)
		(layer "F.Cu")
		(net "SMB_BIC_I2C9_MUX0_SSD5_R_SCL")
	)
	(segment
		(start 140.336016 -91.835732)
		(end 140.358622 -91.813126)
		(width 0.13208)
		(layer "F.Cu")
		(net "SMB_BIC_I2C9_MUX0_SSD5_R_SCL")
	)
	(segment
		(start 168.38549 -21.743162)
		(end 168.38549 -20.789392)
		(width 0.13208)
		(layer "F.Cu")
		(net "SMB_BIC_I2C9_MUX0_SSD5_R_SCL")
	)
	(segment
		(start 138.585194 -91.645994)
		(end 138.774932 -91.835732)
		(width 0.13208)
		(layer "F.Cu")
		(net "SMB_BIC_I2C9_MUX0_SSD5_R_SCL")
	)
	(segment
		(start 168.418002 -21.775674)
		(end 168.38549 -21.743162)
		(width 0.13208)
		(layer "F.Cu")
		(net "SMB_BIC_I2C9_MUX0_SSD5_R_SCL")
	)
	(segment
		(start 153.253186 -86.227158)
		(end 173.445678 -86.227158)
		(width 0.13208)
		(layer "F.Cu")
		(net "SMB_BIC_I2C9_MUX0_SSD5_R_SCL")
	)
	(segment
		(start 140.358622 -91.813126)
		(end 147.667218 -91.813126)
		(width 0.13208)
		(layer "F.Cu")
		(net "SMB_BIC_I2C9_MUX0_SSD5_R_SCL")
	)
	(segment
		(start 168.55948 -22.555454)
		(end 168.418002 -22.413976)
		(width 0.13208)
		(layer "F.Cu")
		(net "SMB_BIC_I2C9_MUX0_SSD5_R_SCL")
	)
	(segment
		(start 147.667218 -91.813126)
		(end 153.253186 -86.227158)
		(width 0.13208)
		(layer "F.Cu")
		(net "SMB_BIC_I2C9_MUX0_SSD5_R_SCL")
	)
	(segment
		(start 168.418002 -22.413976)
		(end 168.418002 -21.775674)
		(width 0.13208)
		(layer "F.Cu")
		(net "SMB_BIC_I2C9_MUX0_SSD5_R_SCL")
	)
	(segment
		(start 136.845294 -91.242642)
		(end 138.585194 -91.242642)
		(width 0.13208)
		(layer "F.Cu")
		(net "SMB_BIC_I2C9_MUX0_SSD5_R_SCL")
	)
	(via
		(at 168.418002 -21.775674)
		(size 0.508)
		(drill 0.254)
		(layers "F.Cu" "B.Cu")
		(net "SMB_BIC_I2C9_MUX0_SSD5_R_SCL")
	)
	(via
		(at 173.445678 -86.227158)
		(size 0.508)
		(drill 0.254)
		(layers "F.Cu" "B.Cu")
		(net "SMB_BIC_I2C9_MUX0_SSD5_R_SCL")
	)
	(segment
		(start 167.9956 -27.9654)
		(end 167.9956 -33.248346)
		(width 0.15494)
		(layer "In5.Cu")
		(net "SMB_BIC_I2C9_MUX0_SSD5_R_SCL")
	)
	(segment
		(start 168.418002 -21.775674)
		(end 167.377872 -21.775674)
		(width 0.15494)
		(layer "In5.Cu")
		(net "SMB_BIC_I2C9_MUX0_SSD5_R_SCL")
	)
	(segment
		(start 179.66436 -44.917106)
		(end 179.66436 -82.498946)
		(width 0.15494)
		(layer "In5.Cu")
		(net "SMB_BIC_I2C9_MUX0_SSD5_R_SCL")
	)
	(segment
		(start 167.377872 -21.775674)
		(end 166.816786 -22.33676)
		(width 0.15494)
		(layer "In5.Cu")
		(net "SMB_BIC_I2C9_MUX0_SSD5_R_SCL")
	)
	(segment
		(start 173.445678 -86.690454)
		(end 173.445678 -86.227158)
		(width 0.15494)
		(layer "In5.Cu")
		(net "SMB_BIC_I2C9_MUX0_SSD5_R_SCL")
	)
	(segment
		(start 173.572678 -86.817454)
		(end 173.445678 -86.690454)
		(width 0.15494)
		(layer "In5.Cu")
		(net "SMB_BIC_I2C9_MUX0_SSD5_R_SCL")
	)
	(segment
		(start 166.816786 -26.786586)
		(end 167.9956 -27.9654)
		(width 0.15494)
		(layer "In5.Cu")
		(net "SMB_BIC_I2C9_MUX0_SSD5_R_SCL")
	)
	(segment
		(start 175.345852 -86.817454)
		(end 173.572678 -86.817454)
		(width 0.15494)
		(layer "In5.Cu")
		(net "SMB_BIC_I2C9_MUX0_SSD5_R_SCL")
	)
	(segment
		(start 166.816786 -22.33676)
		(end 166.816786 -26.786586)
		(width 0.15494)
		(layer "In5.Cu")
		(net "SMB_BIC_I2C9_MUX0_SSD5_R_SCL")
	)
	(segment
		(start 179.66436 -82.498946)
		(end 175.345852 -86.817454)
		(width 0.15494)
		(layer "In5.Cu")
		(net "SMB_BIC_I2C9_MUX0_SSD5_R_SCL")
	)
	(segment
		(start 167.9956 -33.248346)
		(end 179.66436 -44.917106)
		(width 0.15494)
		(layer "In5.Cu")
		(net "SMB_BIC_I2C9_MUX0_SSD5_R_SCL")
	)
	(segment
		(start 63.874904 -364.19155)
		(end 93.123004 -364.19155)
		(width 0.13208)
		(layer "F.Cu")
		(net "SMB_GPU_2_R_SDA")
	)
	(segment
		(start 57.43829 -381.620268)
		(end 58.815986 -381.620268)
		(width 0.13208)
		(layer "F.Cu")
		(net "SMB_GPU_2_R_SDA")
	)
	(segment
		(start 98.721926 -369.790472)
		(end 98.721926 -374.80621)
		(width 0.13208)
		(layer "F.Cu")
		(net "SMB_GPU_2_R_SDA")
	)
	(segment
		(start 98.721926 -374.80621)
		(end 100.380546 -376.46483)
		(width 0.13208)
		(layer "F.Cu")
		(net "SMB_GPU_2_R_SDA")
	)
	(segment
		(start 62.4078 -378.028454)
		(end 62.4078 -365.658654)
		(width 0.13208)
		(layer "F.Cu")
		(net "SMB_GPU_2_R_SDA")
	)
	(segment
		(start 62.4078 -365.658654)
		(end 63.874904 -364.19155)
		(width 0.13208)
		(layer "F.Cu")
		(net "SMB_GPU_2_R_SDA")
	)
	(segment
		(start 100.380546 -376.46483)
		(end 100.380546 -376.484642)
		(width 0.13208)
		(layer "F.Cu")
		(net "SMB_GPU_2_R_SDA")
	)
	(segment
		(start 58.815986 -381.620268)
		(end 62.4078 -378.028454)
		(width 0.13208)
		(layer "F.Cu")
		(net "SMB_GPU_2_R_SDA")
	)
	(segment
		(start 93.123004 -364.19155)
		(end 98.721926 -369.790472)
		(width 0.13208)
		(layer "F.Cu")
		(net "SMB_GPU_2_R_SDA")
	)
	(via
		(at 100.380546 -376.484642)
		(size 0.508)
		(drill 0.254)
		(layers "F.Cu" "B.Cu")
		(net "SMB_GPU_2_R_SDA")
	)
	(via
		(at 57.43829 -381.620268)
		(size 0.508)
		(drill 0.254)
		(layers "F.Cu" "B.Cu")
		(net "SMB_GPU_2_R_SDA")
	)
	(segment
		(start 99.716844 -376.488706)
		(end 99.720908 -376.484642)
		(width 0.13208)
		(layer "B.Cu")
		(net "SMB_GPU_2_R_SDA")
	)
	(segment
		(start 99.3013 -376.488706)
		(end 99.716844 -376.488706)
		(width 0.13208)
		(layer "B.Cu")
		(net "SMB_GPU_2_R_SDA")
	)
	(segment
		(start 99.720908 -376.484642)
		(end 100.380546 -376.484642)
		(width 0.13208)
		(layer "B.Cu")
		(net "SMB_GPU_2_R_SDA")
	)
	(segment
		(start 49.106074 -386.69976)
		(end 47.441866 -386.69976)
		(width 0.15494)
		(layer "In9.Cu")
		(net "SMB_GPU_2_R_SDA")
	)
	(segment
		(start 46.736 -385.993894)
		(end 46.736 -379.516132)
		(width 0.15494)
		(layer "In9.Cu")
		(net "SMB_GPU_2_R_SDA")
	)
	(segment
		(start 56.85663 -382.201928)
		(end 56.44007 -382.201928)
		(width 0.15494)
		(layer "In9.Cu")
		(net "SMB_GPU_2_R_SDA")
	)
	(segment
		(start 47.441866 -386.69976)
		(end 46.736 -385.993894)
		(width 0.15494)
		(layer "In9.Cu")
		(net "SMB_GPU_2_R_SDA")
	)
	(segment
		(start 55.851806 -382.790192)
		(end 53.015642 -382.790192)
		(width 0.15494)
		(layer "In9.Cu")
		(net "SMB_GPU_2_R_SDA")
	)
	(segment
		(start 57.43829 -381.620268)
		(end 56.85663 -382.201928)
		(width 0.15494)
		(layer "In9.Cu")
		(net "SMB_GPU_2_R_SDA")
	)
	(segment
		(start 56.44007 -382.201928)
		(end 55.851806 -382.790192)
		(width 0.15494)
		(layer "In9.Cu")
		(net "SMB_GPU_2_R_SDA")
	)
	(segment
		(start 53.015642 -382.790192)
		(end 49.106074 -386.69976)
		(width 0.15494)
		(layer "In9.Cu")
		(net "SMB_GPU_2_R_SDA")
	)
	(segment
		(start 46.736 -379.516132)
		(end 45.509942 -378.290074)
		(width 0.15494)
		(layer "In9.Cu")
		(net "SMB_GPU_2_R_SDA")
	)
	(segment
		(start 194.737736 -35.6616)
		(end 195.308728 -36.232592)
		(width 0.13208)
		(layer "F.Cu")
		(net "PWRGD_P3V3_SSD7_R")
	)
	(segment
		(start 192.197228 -35.6616)
		(end 194.737736 -35.6616)
		(width 0.13208)
		(layer "F.Cu")
		(net "PWRGD_P3V3_SSD7_R")
	)
	(segment
		(start 191.98209 -35.876738)
		(end 192.197228 -35.6616)
		(width 0.13208)
		(layer "F.Cu")
		(net "PWRGD_P3V3_SSD7_R")
	)
	(segment
		(start 191.27089 -35.876738)
		(end 191.98209 -35.876738)
		(width 0.13208)
		(layer "F.Cu")
		(net "PWRGD_P3V3_SSD7_R")
	)
	(segment
		(start 195.308728 -36.232592)
		(end 195.695316 -36.232592)
		(width 0.13208)
		(layer "F.Cu")
		(net "PWRGD_P3V3_SSD7_R")
	)
	(segment
		(start 202.71105 -61.386974)
		(end 202.71105 -62.051438)
		(width 0.13208)
		(layer "F.Cu")
		(net "PWRGD_P3V3_SSD7_R")
	)
	(segment
		(start 191.27089 -35.876738)
		(end 190.52794 -35.876738)
		(width 0.13208)
		(layer "F.Cu")
		(net "PWRGD_P3V3_SSD7_R")
	)
	(segment
		(start 345.29395 -223.187006)
		(end 345.693746 -223.586802)
		(width 0.13208)
		(layer "F.Cu")
		(net "PWRGD_P3V3_SSD7_R")
	)
	(via
		(at 202.71105 -62.051438)
		(size 0.508)
		(drill 0.254)
		(layers "F.Cu" "B.Cu")
		(net "PWRGD_P3V3_SSD7_R")
	)
	(via
		(at 345.693746 -223.586802)
		(size 0.4572)
		(drill 0.254)
		(layers "F.Cu" "B.Cu")
		(net "PWRGD_P3V3_SSD7_R")
	)
	(via
		(at 191.27089 -35.876738)
		(size 0.508)
		(drill 0.254)
		(layers "F.Cu" "B.Cu")
		(net "PWRGD_P3V3_SSD7_R")
	)
	(via
		(at 245.74754 -220.718634)
		(size 0.508)
		(drill 0.254)
		(layers "F.Cu" "B.Cu")
		(net "PWRGD_P3V3_SSD7_R")
	)
	(via
		(at 181.076854 -208.6864)
		(size 0.508)
		(drill 0.254)
		(layers "F.Cu" "B.Cu")
		(net "PWRGD_P3V3_SSD7_R")
	)
	(via
		(at 246.204486 -213.190836)
		(size 0.508)
		(drill 0.254)
		(layers "F.Cu" "B.Cu")
		(net "PWRGD_P3V3_SSD7_R")
	)
	(segment
		(start 180.1876 -183.693054)
		(end 180.1876 -198.780654)
		(width 0.15494)
		(layer "In5.Cu")
		(net "PWRGD_P3V3_SSD7_R")
	)
	(segment
		(start 203.570078 -62.051438)
		(end 203.981304 -61.640212)
		(width 0.15494)
		(layer "In5.Cu")
		(net "PWRGD_P3V3_SSD7_R")
	)
	(segment
		(start 202.71105 -62.051438)
		(end 202.71105 -64.683132)
		(width 0.15494)
		(layer "In5.Cu")
		(net "PWRGD_P3V3_SSD7_R")
	)
	(segment
		(start 202.71105 -64.683132)
		(end 194.66052 -72.733662)
		(width 0.15494)
		(layer "In5.Cu")
		(net "PWRGD_P3V3_SSD7_R")
	)
	(segment
		(start 179.9082 -201.02322)
		(end 181.076854 -202.191874)
		(width 0.15494)
		(layer "In5.Cu")
		(net "PWRGD_P3V3_SSD7_R")
	)
	(segment
		(start 245.214902 -220.182948)
		(end 245.214902 -214.18042)
		(width 0.15494)
		(layer "In5.Cu")
		(net "PWRGD_P3V3_SSD7_R")
	)
	(segment
		(start 194.66052 -76.35494)
		(end 188.94552 -82.06994)
		(width 0.15494)
		(layer "In5.Cu")
		(net "PWRGD_P3V3_SSD7_R")
	)
	(segment
		(start 180.1876 -198.780654)
		(end 179.9082 -199.060054)
		(width 0.15494)
		(layer "In5.Cu")
		(net "PWRGD_P3V3_SSD7_R")
	)
	(segment
		(start 183.715914 -82.06994)
		(end 176.9364 -88.849454)
		(width 0.15494)
		(layer "In5.Cu")
		(net "PWRGD_P3V3_SSD7_R")
	)
	(segment
		(start 194.070478 -35.876738)
		(end 191.27089 -35.876738)
		(width 0.15494)
		(layer "In5.Cu")
		(net "PWRGD_P3V3_SSD7_R")
	)
	(segment
		(start 245.74754 -220.718634)
		(end 245.74754 -220.715586)
		(width 0.15494)
		(layer "In5.Cu")
		(net "PWRGD_P3V3_SSD7_R")
	)
	(segment
		(start 176.9364 -88.849454)
		(end 176.9364 -180.441854)
		(width 0.15494)
		(layer "In5.Cu")
		(net "PWRGD_P3V3_SSD7_R")
	)
	(segment
		(start 203.981304 -61.640212)
		(end 203.981304 -45.787564)
		(width 0.15494)
		(layer "In5.Cu")
		(net "PWRGD_P3V3_SSD7_R")
	)
	(segment
		(start 203.981304 -45.787564)
		(end 194.070478 -35.876738)
		(width 0.15494)
		(layer "In5.Cu")
		(net "PWRGD_P3V3_SSD7_R")
	)
	(segment
		(start 202.71105 -62.051438)
		(end 203.570078 -62.051438)
		(width 0.15494)
		(layer "In5.Cu")
		(net "PWRGD_P3V3_SSD7_R")
	)
	(segment
		(start 245.74754 -220.715586)
		(end 245.214902 -220.182948)
		(width 0.15494)
		(layer "In5.Cu")
		(net "PWRGD_P3V3_SSD7_R")
	)
	(segment
		(start 194.66052 -72.733662)
		(end 194.66052 -76.35494)
		(width 0.15494)
		(layer "In5.Cu")
		(net "PWRGD_P3V3_SSD7_R")
	)
	(segment
		(start 188.94552 -82.06994)
		(end 183.715914 -82.06994)
		(width 0.15494)
		(layer "In5.Cu")
		(net "PWRGD_P3V3_SSD7_R")
	)
	(segment
		(start 179.9082 -199.060054)
		(end 179.9082 -201.02322)
		(width 0.15494)
		(layer "In5.Cu")
		(net "PWRGD_P3V3_SSD7_R")
	)
	(segment
		(start 176.9364 -180.441854)
		(end 180.1876 -183.693054)
		(width 0.15494)
		(layer "In5.Cu")
		(net "PWRGD_P3V3_SSD7_R")
	)
	(segment
		(start 181.076854 -202.191874)
		(end 181.076854 -208.6864)
		(width 0.15494)
		(layer "In5.Cu")
		(net "PWRGD_P3V3_SSD7_R")
	)
	(segment
		(start 245.214902 -214.18042)
		(end 246.204486 -213.190836)
		(width 0.15494)
		(layer "In5.Cu")
		(net "PWRGD_P3V3_SSD7_R")
	)
	(segment
		(start 222.020384 -206.93634)
		(end 222.297244 -207.2132)
		(width 0.15494)
		(layer "In13.Cu")
		(net "PWRGD_P3V3_SSD7_R")
	)
	(segment
		(start 235.8644 -206.9592)
		(end 236.1946 -207.2894)
		(width 0.15494)
		(layer "In13.Cu")
		(net "PWRGD_P3V3_SSD7_R")
	)
	(segment
		(start 218.541346 -208.1276)
		(end 220.1418 -208.1276)
		(width 0.15494)
		(layer "In13.Cu")
		(net "PWRGD_P3V3_SSD7_R")
	)
	(segment
		(start 233.79176 -207.91424)
		(end 234.7468 -206.9592)
		(width 0.15494)
		(layer "In13.Cu")
		(net "PWRGD_P3V3_SSD7_R")
	)
	(segment
		(start 212.781896 -208.924144)
		(end 212.782404 -208.924144)
		(width 0.15494)
		(layer "In13.Cu")
		(net "PWRGD_P3V3_SSD7_R")
	)
	(segment
		(start 181.202584 -208.81213)
		(end 207.33766 -208.81213)
		(width 0.15494)
		(layer "In13.Cu")
		(net "PWRGD_P3V3_SSD7_R")
	)
	(segment
		(start 236.1946 -207.2894)
		(end 236.1946 -207.694276)
		(width 0.15494)
		(layer "In13.Cu")
		(net "PWRGD_P3V3_SSD7_R")
	)
	(segment
		(start 222.297244 -207.2132)
		(end 230.857044 -207.2132)
		(width 0.15494)
		(layer "In13.Cu")
		(net "PWRGD_P3V3_SSD7_R")
	)
	(segment
		(start 181.076854 -208.6864)
		(end 181.202584 -208.81213)
		(width 0.15494)
		(layer "In13.Cu")
		(net "PWRGD_P3V3_SSD7_R")
	)
	(segment
		(start 234.7468 -206.9592)
		(end 235.8644 -206.9592)
		(width 0.15494)
		(layer "In13.Cu")
		(net "PWRGD_P3V3_SSD7_R")
	)
	(segment
		(start 208.12633 -209.6008)
		(end 211.277454 -209.6008)
		(width 0.15494)
		(layer "In13.Cu")
		(net "PWRGD_P3V3_SSD7_R")
	)
	(segment
		(start 213.68258 -209.82432)
		(end 216.844626 -209.82432)
		(width 0.15494)
		(layer "In13.Cu")
		(net "PWRGD_P3V3_SSD7_R")
	)
	(segment
		(start 244.7036 -210.990434)
		(end 246.204486 -212.49132)
		(width 0.15494)
		(layer "In13.Cu")
		(net "PWRGD_P3V3_SSD7_R")
	)
	(segment
		(start 238.562134 -208.00568)
		(end 239.341914 -208.78546)
		(width 0.15494)
		(layer "In13.Cu")
		(net "PWRGD_P3V3_SSD7_R")
	)
	(segment
		(start 240.242852 -208.78546)
		(end 240.545366 -208.482946)
		(width 0.15494)
		(layer "In13.Cu")
		(net "PWRGD_P3V3_SSD7_R")
	)
	(segment
		(start 212.771736 -208.913984)
		(end 212.781896 -208.924144)
		(width 0.15494)
		(layer "In13.Cu")
		(net "PWRGD_P3V3_SSD7_R")
	)
	(segment
		(start 220.1418 -208.1276)
		(end 221.33306 -206.93634)
		(width 0.15494)
		(layer "In13.Cu")
		(net "PWRGD_P3V3_SSD7_R")
	)
	(segment
		(start 221.33306 -206.93634)
		(end 222.020384 -206.93634)
		(width 0.15494)
		(layer "In13.Cu")
		(net "PWRGD_P3V3_SSD7_R")
	)
	(segment
		(start 211.277454 -209.6008)
		(end 211.96427 -208.913984)
		(width 0.15494)
		(layer "In13.Cu")
		(net "PWRGD_P3V3_SSD7_R")
	)
	(segment
		(start 239.341914 -208.78546)
		(end 240.242852 -208.78546)
		(width 0.15494)
		(layer "In13.Cu")
		(net "PWRGD_P3V3_SSD7_R")
	)
	(segment
		(start 212.782404 -208.924144)
		(end 213.68258 -209.82432)
		(width 0.15494)
		(layer "In13.Cu")
		(net "PWRGD_P3V3_SSD7_R")
	)
	(segment
		(start 236.1946 -207.694276)
		(end 236.506004 -208.00568)
		(width 0.15494)
		(layer "In13.Cu")
		(net "PWRGD_P3V3_SSD7_R")
	)
	(segment
		(start 216.844626 -209.82432)
		(end 218.541346 -208.1276)
		(width 0.15494)
		(layer "In13.Cu")
		(net "PWRGD_P3V3_SSD7_R")
	)
	(segment
		(start 240.545366 -208.482946)
		(end 243.9162 -208.482946)
		(width 0.15494)
		(layer "In13.Cu")
		(net "PWRGD_P3V3_SSD7_R")
	)
	(segment
		(start 243.9162 -208.482946)
		(end 244.7036 -209.270346)
		(width 0.15494)
		(layer "In13.Cu")
		(net "PWRGD_P3V3_SSD7_R")
	)
	(segment
		(start 207.33766 -208.81213)
		(end 208.12633 -209.6008)
		(width 0.15494)
		(layer "In13.Cu")
		(net "PWRGD_P3V3_SSD7_R")
	)
	(segment
		(start 211.96427 -208.913984)
		(end 212.771736 -208.913984)
		(width 0.15494)
		(layer "In13.Cu")
		(net "PWRGD_P3V3_SSD7_R")
	)
	(segment
		(start 232.5497 -207.91424)
		(end 233.79176 -207.91424)
		(width 0.15494)
		(layer "In13.Cu")
		(net "PWRGD_P3V3_SSD7_R")
	)
	(segment
		(start 246.204486 -212.49132)
		(end 246.204486 -213.190836)
		(width 0.15494)
		(layer "In13.Cu")
		(net "PWRGD_P3V3_SSD7_R")
	)
	(segment
		(start 244.7036 -209.270346)
		(end 244.7036 -210.990434)
		(width 0.15494)
		(layer "In13.Cu")
		(net "PWRGD_P3V3_SSD7_R")
	)
	(segment
		(start 236.506004 -208.00568)
		(end 238.562134 -208.00568)
		(width 0.15494)
		(layer "In13.Cu")
		(net "PWRGD_P3V3_SSD7_R")
	)
	(segment
		(start 230.857044 -207.2132)
		(end 232.5497 -207.91424)
		(width 0.15494)
		(layer "In13.Cu")
		(net "PWRGD_P3V3_SSD7_R")
	)
	(segment
		(start 262.920226 -220.348556)
		(end 261.952486 -219.380816)
		(width 0.15494)
		(layer "In15.Cu")
		(net "PWRGD_P3V3_SSD7_R")
	)
	(segment
		(start 255.310132 -217.619072)
		(end 250.932188 -217.619072)
		(width 0.15494)
		(layer "In15.Cu")
		(net "PWRGD_P3V3_SSD7_R")
	)
	(segment
		(start 303.911508 -221.22892)
		(end 298.8818 -221.22892)
		(width 0.15494)
		(layer "In15.Cu")
		(net "PWRGD_P3V3_SSD7_R")
	)
	(segment
		(start 344.711528 -223.189292)
		(end 344.492326 -222.97009)
		(width 0.0889)
		(layer "In15.Cu")
		(net "PWRGD_P3V3_SSD7_R")
	)
	(segment
		(start 323.569076 -221.377002)
		(end 322.914518 -220.722444)
		(width 0.15494)
		(layer "In15.Cu")
		(net "PWRGD_P3V3_SSD7_R")
	)
	(segment
		(start 329.337416 -220.543374)
		(end 328.552556 -220.543374)
		(width 0.15494)
		(layer "In15.Cu")
		(net "PWRGD_P3V3_SSD7_R")
	)
	(segment
		(start 259.590794 -218.29014)
		(end 255.9812 -218.29014)
		(width 0.15494)
		(layer "In15.Cu")
		(net "PWRGD_P3V3_SSD7_R")
	)
	(segment
		(start 264.06729 -220.348556)
		(end 262.920226 -220.348556)
		(width 0.15494)
		(layer "In15.Cu")
		(net "PWRGD_P3V3_SSD7_R")
	)
	(segment
		(start 249.73026 -218.821)
		(end 247.645174 -218.821)
		(width 0.15494)
		(layer "In15.Cu")
		(net "PWRGD_P3V3_SSD7_R")
	)
	(segment
		(start 325.4756 -221.694756)
		(end 325.157846 -221.377002)
		(width 0.15494)
		(layer "In15.Cu")
		(net "PWRGD_P3V3_SSD7_R")
	)
	(segment
		(start 289.663378 -220.18498)
		(end 289.184588 -220.66377)
		(width 0.15494)
		(layer "In15.Cu")
		(net "PWRGD_P3V3_SSD7_R")
	)
	(segment
		(start 298.8818 -221.22892)
		(end 297.83786 -220.18498)
		(width 0.15494)
		(layer "In15.Cu")
		(net "PWRGD_P3V3_SSD7_R")
	)
	(segment
		(start 345.693746 -223.586802)
		(end 345.296236 -223.189292)
		(width 0.0889)
		(layer "In15.Cu")
		(net "PWRGD_P3V3_SSD7_R")
	)
	(segment
		(start 260.68147 -219.380816)
		(end 259.590794 -218.29014)
		(width 0.15494)
		(layer "In15.Cu")
		(net "PWRGD_P3V3_SSD7_R")
	)
	(segment
		(start 322.914518 -220.722444)
		(end 304.417984 -220.722444)
		(width 0.15494)
		(layer "In15.Cu")
		(net "PWRGD_P3V3_SSD7_R")
	)
	(segment
		(start 264.382504 -220.66377)
		(end 264.06729 -220.348556)
		(width 0.15494)
		(layer "In15.Cu")
		(net "PWRGD_P3V3_SSD7_R")
	)
	(segment
		(start 345.296236 -223.189292)
		(end 344.711528 -223.189292)
		(width 0.0889)
		(layer "In15.Cu")
		(net "PWRGD_P3V3_SSD7_R")
	)
	(segment
		(start 335.026254 -221.589346)
		(end 334.899 -221.7166)
		(width 0.0889)
		(layer "In15.Cu")
		(net "PWRGD_P3V3_SSD7_R")
	)
	(segment
		(start 344.306398 -221.589346)
		(end 335.026254 -221.589346)
		(width 0.0889)
		(layer "In15.Cu")
		(net "PWRGD_P3V3_SSD7_R")
	)
	(segment
		(start 261.952486 -219.380816)
		(end 260.68147 -219.380816)
		(width 0.15494)
		(layer "In15.Cu")
		(net "PWRGD_P3V3_SSD7_R")
	)
	(segment
		(start 250.932188 -217.619072)
		(end 249.73026 -218.821)
		(width 0.15494)
		(layer "In15.Cu")
		(net "PWRGD_P3V3_SSD7_R")
	)
	(segment
		(start 334.5942 -222.0214)
		(end 330.815442 -222.0214)
		(width 0.15494)
		(layer "In15.Cu")
		(net "PWRGD_P3V3_SSD7_R")
	)
	(segment
		(start 304.417984 -220.722444)
		(end 303.911508 -221.22892)
		(width 0.15494)
		(layer "In15.Cu")
		(net "PWRGD_P3V3_SSD7_R")
	)
	(segment
		(start 247.645174 -218.821)
		(end 245.74754 -220.718634)
		(width 0.15494)
		(layer "In15.Cu")
		(net "PWRGD_P3V3_SSD7_R")
	)
	(segment
		(start 328.552556 -220.543374)
		(end 327.401174 -221.694756)
		(width 0.15494)
		(layer "In15.Cu")
		(net "PWRGD_P3V3_SSD7_R")
	)
	(segment
		(start 334.899 -221.7166)
		(end 334.5942 -222.0214)
		(width 0.15494)
		(layer "In15.Cu")
		(net "PWRGD_P3V3_SSD7_R")
	)
	(segment
		(start 344.492326 -221.775274)
		(end 344.306398 -221.589346)
		(width 0.0889)
		(layer "In15.Cu")
		(net "PWRGD_P3V3_SSD7_R")
	)
	(segment
		(start 289.184588 -220.66377)
		(end 264.382504 -220.66377)
		(width 0.15494)
		(layer "In15.Cu")
		(net "PWRGD_P3V3_SSD7_R")
	)
	(segment
		(start 330.815442 -222.0214)
		(end 329.337416 -220.543374)
		(width 0.15494)
		(layer "In15.Cu")
		(net "PWRGD_P3V3_SSD7_R")
	)
	(segment
		(start 344.492326 -222.97009)
		(end 344.492326 -221.775274)
		(width 0.0889)
		(layer "In15.Cu")
		(net "PWRGD_P3V3_SSD7_R")
	)
	(segment
		(start 255.9812 -218.29014)
		(end 255.310132 -217.619072)
		(width 0.15494)
		(layer "In15.Cu")
		(net "PWRGD_P3V3_SSD7_R")
	)
	(segment
		(start 297.83786 -220.18498)
		(end 289.663378 -220.18498)
		(width 0.15494)
		(layer "In15.Cu")
		(net "PWRGD_P3V3_SSD7_R")
	)
	(segment
		(start 327.401174 -221.694756)
		(end 325.4756 -221.694756)
		(width 0.15494)
		(layer "In15.Cu")
		(net "PWRGD_P3V3_SSD7_R")
	)
	(segment
		(start 325.157846 -221.377002)
		(end 323.569076 -221.377002)
		(width 0.15494)
		(layer "In15.Cu")
		(net "PWRGD_P3V3_SSD7_R")
	)
	(segment
		(start 53.949854 -309.199788)
		(end 54.424834 -308.724808)
		(width 0.127)
		(layer "F.Cu")
		(net "TP_PEX0_TDO")
	)
	(via
		(at 53.949854 -309.199788)
		(size 0.6604)
		(drill 0.3302)
		(layers "F.Cu" "B.Cu")
		(net "TP_PEX0_TDO")
	)
	(via
		(at 54.424834 -308.724808)
		(size 0.4064)
		(drill 0.2032)
		(layers "F.Cu" "B.Cu")
		(net "TP_PEX0_TDO")
	)
	(segment
		(start 53.949854 -309.199788)
		(end 54.424834 -308.724808)
		(width 0.13208)
		(layer "B.Cu")
		(net "TP_PEX0_TDO")
	)
	(segment
		(start 142.418054 -22.413976)
		(end 142.559532 -22.555454)
		(width 0.13208)
		(layer "F.Cu")
		(net "SMB_BIC_I2C9_MUX0_SSD4_R_SCL")
	)
	(segment
		(start 142.418054 -21.775674)
		(end 142.418054 -22.413976)
		(width 0.13208)
		(layer "F.Cu")
		(net "SMB_BIC_I2C9_MUX0_SSD4_R_SCL")
	)
	(segment
		(start 142.385542 -21.743162)
		(end 142.418054 -21.775674)
		(width 0.13208)
		(layer "F.Cu")
		(net "SMB_BIC_I2C9_MUX0_SSD4_R_SCL")
	)
	(segment
		(start 143.88973 -88.414606)
		(end 146.861022 -85.443314)
		(width 0.13208)
		(layer "F.Cu")
		(net "SMB_BIC_I2C9_MUX0_SSD4_R_SCL")
	)
	(segment
		(start 138.585194 -88.54186)
		(end 138.712448 -88.414606)
		(width 0.13208)
		(layer "F.Cu")
		(net "SMB_BIC_I2C9_MUX0_SSD4_R_SCL")
	)
	(segment
		(start 142.385542 -20.789392)
		(end 142.385542 -21.743162)
		(width 0.13208)
		(layer "F.Cu")
		(net "SMB_BIC_I2C9_MUX0_SSD4_R_SCL")
	)
	(segment
		(start 138.585194 -88.956642)
		(end 138.585194 -88.54186)
		(width 0.13208)
		(layer "F.Cu")
		(net "SMB_BIC_I2C9_MUX0_SSD4_R_SCL")
	)
	(segment
		(start 136.845294 -88.956642)
		(end 138.585194 -88.956642)
		(width 0.13208)
		(layer "F.Cu")
		(net "SMB_BIC_I2C9_MUX0_SSD4_R_SCL")
	)
	(segment
		(start 138.712448 -88.414606)
		(end 143.88973 -88.414606)
		(width 0.13208)
		(layer "F.Cu")
		(net "SMB_BIC_I2C9_MUX0_SSD4_R_SCL")
	)
	(via
		(at 146.861022 -85.443314)
		(size 0.508)
		(drill 0.254)
		(layers "F.Cu" "B.Cu")
		(net "SMB_BIC_I2C9_MUX0_SSD4_R_SCL")
	)
	(via
		(at 142.418054 -21.775674)
		(size 0.508)
		(drill 0.254)
		(layers "F.Cu" "B.Cu")
		(net "SMB_BIC_I2C9_MUX0_SSD4_R_SCL")
	)
	(segment
		(start 142.2908 -33.45307)
		(end 142.2908 -28.2956)
		(width 0.15494)
		(layer "In5.Cu")
		(net "SMB_BIC_I2C9_MUX0_SSD4_R_SCL")
	)
	(segment
		(start 140.816838 -22.33676)
		(end 141.377924 -21.775674)
		(width 0.15494)
		(layer "In5.Cu")
		(net "SMB_BIC_I2C9_MUX0_SSD4_R_SCL")
	)
	(segment
		(start 142.2908 -28.2956)
		(end 140.816838 -26.821638)
		(width 0.15494)
		(layer "In5.Cu")
		(net "SMB_BIC_I2C9_MUX0_SSD4_R_SCL")
	)
	(segment
		(start 147.460716 -86.332822)
		(end 148.52142 -86.332822)
		(width 0.15494)
		(layer "In5.Cu")
		(net "SMB_BIC_I2C9_MUX0_SSD4_R_SCL")
	)
	(segment
		(start 149.232366 -78.478888)
		(end 153.8097 -73.901554)
		(width 0.15494)
		(layer "In5.Cu")
		(net "SMB_BIC_I2C9_MUX0_SSD4_R_SCL")
	)
	(segment
		(start 141.377924 -21.775674)
		(end 142.418054 -21.775674)
		(width 0.15494)
		(layer "In5.Cu")
		(net "SMB_BIC_I2C9_MUX0_SSD4_R_SCL")
	)
	(segment
		(start 140.816838 -26.821638)
		(end 140.816838 -22.33676)
		(width 0.15494)
		(layer "In5.Cu")
		(net "SMB_BIC_I2C9_MUX0_SSD4_R_SCL")
	)
	(segment
		(start 149.232366 -85.621876)
		(end 149.232366 -78.478888)
		(width 0.15494)
		(layer "In5.Cu")
		(net "SMB_BIC_I2C9_MUX0_SSD4_R_SCL")
	)
	(segment
		(start 153.8097 -44.97197)
		(end 142.2908 -33.45307)
		(width 0.15494)
		(layer "In5.Cu")
		(net "SMB_BIC_I2C9_MUX0_SSD4_R_SCL")
	)
	(segment
		(start 148.52142 -86.332822)
		(end 149.232366 -85.621876)
		(width 0.15494)
		(layer "In5.Cu")
		(net "SMB_BIC_I2C9_MUX0_SSD4_R_SCL")
	)
	(segment
		(start 146.861022 -85.733128)
		(end 147.460716 -86.332822)
		(width 0.15494)
		(layer "In5.Cu")
		(net "SMB_BIC_I2C9_MUX0_SSD4_R_SCL")
	)
	(segment
		(start 153.8097 -73.901554)
		(end 153.8097 -44.97197)
		(width 0.15494)
		(layer "In5.Cu")
		(net "SMB_BIC_I2C9_MUX0_SSD4_R_SCL")
	)
	(segment
		(start 146.861022 -85.443314)
		(end 146.861022 -85.733128)
		(width 0.15494)
		(layer "In5.Cu")
		(net "SMB_BIC_I2C9_MUX0_SSD4_R_SCL")
	)
	(segment
		(start 56.9468 -387.750812)
		(end 55.875174 -388.822438)
		(width 0.13208)
		(layer "F.Cu")
		(net "GPU_PWR_BRAKE_R_N")
	)
	(segment
		(start 58.286142 -387.750812)
		(end 56.9468 -387.750812)
		(width 0.13208)
		(layer "F.Cu")
		(net "GPU_PWR_BRAKE_R_N")
	)
	(via
		(at 55.875174 -388.822438)
		(size 0.508)
		(drill 0.254)
		(layers "F.Cu" "B.Cu")
		(net "GPU_PWR_BRAKE_R_N")
	)
	(segment
		(start 54.017418 -390.680194)
		(end 55.875174 -388.822438)
		(width 0.15494)
		(layer "In9.Cu")
		(net "GPU_PWR_BRAKE_R_N")
	)
	(segment
		(start 49.752504 -392.933682)
		(end 52.005992 -390.680194)
		(width 0.15494)
		(layer "In9.Cu")
		(net "GPU_PWR_BRAKE_R_N")
	)
	(segment
		(start 47.338488 -412.73349)
		(end 49.393856 -412.73349)
		(width 0.15494)
		(layer "In9.Cu")
		(net "GPU_PWR_BRAKE_R_N")
	)
	(segment
		(start 49.752504 -412.374842)
		(end 49.752504 -392.933682)
		(width 0.15494)
		(layer "In9.Cu")
		(net "GPU_PWR_BRAKE_R_N")
	)
	(segment
		(start 45.509942 -405.589994)
		(end 46.99 -407.070052)
		(width 0.15494)
		(layer "In9.Cu")
		(net "GPU_PWR_BRAKE_R_N")
	)
	(segment
		(start 46.99 -412.385002)
		(end 47.338488 -412.73349)
		(width 0.15494)
		(layer "In9.Cu")
		(net "GPU_PWR_BRAKE_R_N")
	)
	(segment
		(start 46.99 -407.070052)
		(end 46.99 -412.385002)
		(width 0.15494)
		(layer "In9.Cu")
		(net "GPU_PWR_BRAKE_R_N")
	)
	(segment
		(start 49.393856 -412.73349)
		(end 49.752504 -412.374842)
		(width 0.15494)
		(layer "In9.Cu")
		(net "GPU_PWR_BRAKE_R_N")
	)
	(segment
		(start 52.005992 -390.680194)
		(end 54.017418 -390.680194)
		(width 0.15494)
		(layer "In9.Cu")
		(net "GPU_PWR_BRAKE_R_N")
	)
	(segment
		(start 343.69375 -225.587052)
		(end 344.093546 -225.986848)
		(width 0.13208)
		(layer "F.Cu")
		(net "SSD3_PWRDIS")
	)
	(via
		(at 344.093546 -225.986848)
		(size 0.4572)
		(drill 0.254)
		(layers "F.Cu" "B.Cu")
		(net "SSD3_PWRDIS")
	)
	(via
		(at 342.519 -232.029)
		(size 0.6604)
		(drill 0.3302)
		(layers "F.Cu" "B.Cu")
		(net "SSD3_PWRDIS")
	)
	(segment
		(start 344.493596 -227.4316)
		(end 344.493596 -226.386898)
		(width 0.0889)
		(layer "B.Cu")
		(net "SSD3_PWRDIS")
	)
	(segment
		(start 342.011 -232.537)
		(end 342.519 -232.029)
		(width 0.13208)
		(layer "B.Cu")
		(net "SSD3_PWRDIS")
	)
	(segment
		(start 342.773 -231.155748)
		(end 342.93048 -230.998268)
		(width 0.13208)
		(layer "B.Cu")
		(net "SSD3_PWRDIS")
	)
	(segment
		(start 342.773 -231.775)
		(end 342.773 -231.155748)
		(width 0.13208)
		(layer "B.Cu")
		(net "SSD3_PWRDIS")
	)
	(segment
		(start 344.493596 -230.398828)
		(end 344.493596 -227.4316)
		(width 0.13208)
		(layer "B.Cu")
		(net "SSD3_PWRDIS")
	)
	(segment
		(start 342.93048 -230.998268)
		(end 343.894156 -230.998268)
		(width 0.13208)
		(layer "B.Cu")
		(net "SSD3_PWRDIS")
	)
	(segment
		(start 344.493596 -226.386898)
		(end 344.093546 -225.986848)
		(width 0.0889)
		(layer "B.Cu")
		(net "SSD3_PWRDIS")
	)
	(segment
		(start 343.894156 -230.998268)
		(end 344.493596 -230.398828)
		(width 0.13208)
		(layer "B.Cu")
		(net "SSD3_PWRDIS")
	)
	(segment
		(start 342.011 -233.15295)
		(end 342.011 -232.537)
		(width 0.13208)
		(layer "B.Cu")
		(net "SSD3_PWRDIS")
	)
	(segment
		(start 342.519 -232.029)
		(end 342.773 -231.775)
		(width 0.13208)
		(layer "B.Cu")
		(net "SSD3_PWRDIS")
	)
	(segment
		(start 50.575464 -54.144164)
		(end 50.756058 -53.96357)
		(width 0.13208)
		(layer "F.Cu")
		(net "P12V_SSD1_OCP")
	)
	(segment
		(start 51.867816 -54.067456)
		(end 51.76393 -53.96357)
		(width 0.13208)
		(layer "F.Cu")
		(net "P12V_SSD1_OCP")
	)
	(segment
		(start 51.76393 -53.96357)
		(end 51.154076 -53.96357)
		(width 0.13208)
		(layer "F.Cu")
		(net "P12V_SSD1_OCP")
	)
	(segment
		(start 50.14722 -54.144164)
		(end 50.575464 -54.144164)
		(width 0.13208)
		(layer "F.Cu")
		(net "P12V_SSD1_OCP")
	)
	(segment
		(start 50.756058 -53.96357)
		(end 51.154076 -53.96357)
		(width 0.13208)
		(layer "F.Cu")
		(net "P12V_SSD1_OCP")
	)
	(via
		(at 51.154076 -53.96357)
		(size 0.508)
		(drill 0.254)
		(layers "F.Cu" "B.Cu")
		(net "P12V_SSD1_OCP")
	)
	(segment
		(start 52.049934 -309.199788)
		(end 51.574954 -308.724808)
		(width 0.127)
		(layer "F.Cu")
		(net "TP_PEX0_TDI")
	)
	(via
		(at 52.049934 -309.199788)
		(size 0.6604)
		(drill 0.3302)
		(layers "F.Cu" "B.Cu")
		(net "TP_PEX0_TDI")
	)
	(via
		(at 51.574954 -308.724808)
		(size 0.4064)
		(drill 0.2032)
		(layers "F.Cu" "B.Cu")
		(net "TP_PEX0_TDI")
	)
	(segment
		(start 52.049934 -309.199788)
		(end 51.574954 -308.724808)
		(width 0.13208)
		(layer "B.Cu")
		(net "TP_PEX0_TDI")
	)
	(segment
		(start 138.585194 -96.217994)
		(end 138.585194 -95.814642)
		(width 0.13208)
		(layer "F.Cu")
		(net "SMB_BIC_I2C9_MUX0_SSD7_R_SCL")
	)
	(segment
		(start 140.336016 -96.407732)
		(end 138.774932 -96.407732)
		(width 0.13208)
		(layer "F.Cu")
		(net "SMB_BIC_I2C9_MUX0_SSD7_R_SCL")
	)
	(segment
		(start 220.417898 -22.413976)
		(end 220.417898 -21.775674)
		(width 0.13208)
		(layer "F.Cu")
		(net "SMB_BIC_I2C9_MUX0_SSD7_R_SCL")
	)
	(segment
		(start 136.845294 -95.814642)
		(end 138.585194 -95.814642)
		(width 0.13208)
		(layer "F.Cu")
		(net "SMB_BIC_I2C9_MUX0_SSD7_R_SCL")
	)
	(segment
		(start 207.652874 -76.871576)
		(end 206.85252 -76.071222)
		(width 0.13208)
		(layer "F.Cu")
		(net "SMB_BIC_I2C9_MUX0_SSD7_R_SCL")
	)
	(segment
		(start 198.611236 -76.071222)
		(end 196.234812 -78.447646)
		(width 0.13208)
		(layer "F.Cu")
		(net "SMB_BIC_I2C9_MUX0_SSD7_R_SCL")
	)
	(segment
		(start 153.054812 -90.277188)
		(end 148.743924 -94.588076)
		(width 0.13208)
		(layer "F.Cu")
		(net "SMB_BIC_I2C9_MUX0_SSD7_R_SCL")
	)
	(segment
		(start 189.058042 -78.447646)
		(end 177.341022 -90.164666)
		(width 0.13208)
		(layer "F.Cu")
		(net "SMB_BIC_I2C9_MUX0_SSD7_R_SCL")
	)
	(segment
		(start 196.234812 -78.447646)
		(end 189.058042 -78.447646)
		(width 0.13208)
		(layer "F.Cu")
		(net "SMB_BIC_I2C9_MUX0_SSD7_R_SCL")
	)
	(segment
		(start 206.85252 -76.071222)
		(end 198.611236 -76.071222)
		(width 0.13208)
		(layer "F.Cu")
		(net "SMB_BIC_I2C9_MUX0_SSD7_R_SCL")
	)
	(segment
		(start 221.5007 -76.871576)
		(end 207.652874 -76.871576)
		(width 0.13208)
		(layer "F.Cu")
		(net "SMB_BIC_I2C9_MUX0_SSD7_R_SCL")
	)
	(segment
		(start 148.743924 -94.588076)
		(end 142.513812 -94.588076)
		(width 0.13208)
		(layer "F.Cu")
		(net "SMB_BIC_I2C9_MUX0_SSD7_R_SCL")
	)
	(segment
		(start 138.774932 -96.407732)
		(end 138.585194 -96.217994)
		(width 0.13208)
		(layer "F.Cu")
		(net "SMB_BIC_I2C9_MUX0_SSD7_R_SCL")
	)
	(segment
		(start 140.716762 -96.385126)
		(end 140.358622 -96.385126)
		(width 0.13208)
		(layer "F.Cu")
		(net "SMB_BIC_I2C9_MUX0_SSD7_R_SCL")
	)
	(segment
		(start 220.417898 -21.775674)
		(end 220.385386 -21.743162)
		(width 0.13208)
		(layer "F.Cu")
		(net "SMB_BIC_I2C9_MUX0_SSD7_R_SCL")
	)
	(segment
		(start 177.341022 -90.164666)
		(end 177.340768 -90.164666)
		(width 0.13208)
		(layer "F.Cu")
		(net "SMB_BIC_I2C9_MUX0_SSD7_R_SCL")
	)
	(segment
		(start 177.340768 -90.164666)
		(end 177.228246 -90.277188)
		(width 0.13208)
		(layer "F.Cu")
		(net "SMB_BIC_I2C9_MUX0_SSD7_R_SCL")
	)
	(segment
		(start 220.385386 -21.743162)
		(end 220.385386 -20.789392)
		(width 0.13208)
		(layer "F.Cu")
		(net "SMB_BIC_I2C9_MUX0_SSD7_R_SCL")
	)
	(segment
		(start 142.513812 -94.588076)
		(end 140.716762 -96.385126)
		(width 0.13208)
		(layer "F.Cu")
		(net "SMB_BIC_I2C9_MUX0_SSD7_R_SCL")
	)
	(segment
		(start 177.228246 -90.277188)
		(end 153.054812 -90.277188)
		(width 0.13208)
		(layer "F.Cu")
		(net "SMB_BIC_I2C9_MUX0_SSD7_R_SCL")
	)
	(segment
		(start 220.559376 -22.555454)
		(end 220.417898 -22.413976)
		(width 0.13208)
		(layer "F.Cu")
		(net "SMB_BIC_I2C9_MUX0_SSD7_R_SCL")
	)
	(segment
		(start 140.358622 -96.385126)
		(end 140.336016 -96.407732)
		(width 0.13208)
		(layer "F.Cu")
		(net "SMB_BIC_I2C9_MUX0_SSD7_R_SCL")
	)
	(via
		(at 221.5007 -76.871576)
		(size 0.508)
		(drill 0.254)
		(layers "F.Cu" "B.Cu")
		(net "SMB_BIC_I2C9_MUX0_SSD7_R_SCL")
	)
	(via
		(at 220.417898 -21.775674)
		(size 0.508)
		(drill 0.254)
		(layers "F.Cu" "B.Cu")
		(net "SMB_BIC_I2C9_MUX0_SSD7_R_SCL")
	)
	(segment
		(start 224.065338 -75.187556)
		(end 223.177354 -76.07554)
		(width 0.15494)
		(layer "In5.Cu")
		(net "SMB_BIC_I2C9_MUX0_SSD7_R_SCL")
	)
	(segment
		(start 221.832424 -76.871576)
		(end 221.5007 -76.871576)
		(width 0.15494)
		(layer "In5.Cu")
		(net "SMB_BIC_I2C9_MUX0_SSD7_R_SCL")
	)
	(segment
		(start 218.816682 -22.33676)
		(end 218.816682 -26.716482)
		(width 0.15494)
		(layer "In5.Cu")
		(net "SMB_BIC_I2C9_MUX0_SSD7_R_SCL")
	)
	(segment
		(start 220.417898 -21.775674)
		(end 219.377768 -21.775674)
		(width 0.15494)
		(layer "In5.Cu")
		(net "SMB_BIC_I2C9_MUX0_SSD7_R_SCL")
	)
	(segment
		(start 224.15246 -40.9829)
		(end 224.15246 -63.5127)
		(width 0.15494)
		(layer "In5.Cu")
		(net "SMB_BIC_I2C9_MUX0_SSD7_R_SCL")
	)
	(segment
		(start 218.816682 -26.716482)
		(end 219.941394 -27.841194)
		(width 0.15494)
		(layer "In5.Cu")
		(net "SMB_BIC_I2C9_MUX0_SSD7_R_SCL")
	)
	(segment
		(start 219.377768 -21.775674)
		(end 218.816682 -22.33676)
		(width 0.15494)
		(layer "In5.Cu")
		(net "SMB_BIC_I2C9_MUX0_SSD7_R_SCL")
	)
	(segment
		(start 223.22282 -64.44234)
		(end 223.22282 -72.874378)
		(width 0.15494)
		(layer "In5.Cu")
		(net "SMB_BIC_I2C9_MUX0_SSD7_R_SCL")
	)
	(segment
		(start 218.92006 -35.7505)
		(end 224.15246 -40.9829)
		(width 0.15494)
		(layer "In5.Cu")
		(net "SMB_BIC_I2C9_MUX0_SSD7_R_SCL")
	)
	(segment
		(start 219.941394 -29.985208)
		(end 218.92006 -31.006542)
		(width 0.15494)
		(layer "In5.Cu")
		(net "SMB_BIC_I2C9_MUX0_SSD7_R_SCL")
	)
	(segment
		(start 222.62846 -76.07554)
		(end 221.832424 -76.871576)
		(width 0.15494)
		(layer "In5.Cu")
		(net "SMB_BIC_I2C9_MUX0_SSD7_R_SCL")
	)
	(segment
		(start 219.941394 -27.841194)
		(end 219.941394 -29.985208)
		(width 0.15494)
		(layer "In5.Cu")
		(net "SMB_BIC_I2C9_MUX0_SSD7_R_SCL")
	)
	(segment
		(start 224.065338 -73.716896)
		(end 224.065338 -75.187556)
		(width 0.15494)
		(layer "In5.Cu")
		(net "SMB_BIC_I2C9_MUX0_SSD7_R_SCL")
	)
	(segment
		(start 218.92006 -31.006542)
		(end 218.92006 -35.7505)
		(width 0.15494)
		(layer "In5.Cu")
		(net "SMB_BIC_I2C9_MUX0_SSD7_R_SCL")
	)
	(segment
		(start 224.15246 -63.5127)
		(end 223.22282 -64.44234)
		(width 0.15494)
		(layer "In5.Cu")
		(net "SMB_BIC_I2C9_MUX0_SSD7_R_SCL")
	)
	(segment
		(start 223.22282 -72.874378)
		(end 224.065338 -73.716896)
		(width 0.15494)
		(layer "In5.Cu")
		(net "SMB_BIC_I2C9_MUX0_SSD7_R_SCL")
	)
	(segment
		(start 223.177354 -76.07554)
		(end 222.62846 -76.07554)
		(width 0.15494)
		(layer "In5.Cu")
		(net "SMB_BIC_I2C9_MUX0_SSD7_R_SCL")
	)
	(segment
		(start 58.405268 -391.890504)
		(end 57.882028 -391.367264)
		(width 0.13208)
		(layer "F.Cu")
		(net "GPU_THERM_OVERT_N")
	)
	(segment
		(start 58.357262 -390.47166)
		(end 58.357262 -390.89203)
		(width 0.13208)
		(layer "F.Cu")
		(net "GPU_THERM_OVERT_N")
	)
	(segment
		(start 58.357262 -390.89203)
		(end 57.882028 -391.367264)
		(width 0.13208)
		(layer "F.Cu")
		(net "GPU_THERM_OVERT_N")
	)
	(segment
		(start 58.405268 -392.76274)
		(end 58.405268 -391.890504)
		(width 0.13208)
		(layer "F.Cu")
		(net "GPU_THERM_OVERT_N")
	)
	(via
		(at 57.882028 -391.367264)
		(size 0.508)
		(drill 0.254)
		(layers "F.Cu" "B.Cu")
		(net "GPU_THERM_OVERT_N")
	)
	(segment
		(start 46.867064 -413.541718)
		(end 49.966372 -413.541718)
		(width 0.15494)
		(layer "In9.Cu")
		(net "GPU_THERM_OVERT_N")
	)
	(segment
		(start 45.509942 -409.490164)
		(end 46.19625 -410.176472)
		(width 0.15494)
		(layer "In9.Cu")
		(net "GPU_THERM_OVERT_N")
	)
	(segment
		(start 50.7746 -393.319254)
		(end 52.42433 -391.669524)
		(width 0.15494)
		(layer "In9.Cu")
		(net "GPU_THERM_OVERT_N")
	)
	(segment
		(start 57.579768 -391.669524)
		(end 57.882028 -391.367264)
		(width 0.15494)
		(layer "In9.Cu")
		(net "GPU_THERM_OVERT_N")
	)
	(segment
		(start 46.19625 -412.870904)
		(end 46.867064 -413.541718)
		(width 0.15494)
		(layer "In9.Cu")
		(net "GPU_THERM_OVERT_N")
	)
	(segment
		(start 52.42433 -391.669524)
		(end 57.579768 -391.669524)
		(width 0.15494)
		(layer "In9.Cu")
		(net "GPU_THERM_OVERT_N")
	)
	(segment
		(start 49.966372 -413.541718)
		(end 50.7746 -412.73349)
		(width 0.15494)
		(layer "In9.Cu")
		(net "GPU_THERM_OVERT_N")
	)
	(segment
		(start 46.19625 -410.176472)
		(end 46.19625 -412.870904)
		(width 0.15494)
		(layer "In9.Cu")
		(net "GPU_THERM_OVERT_N")
	)
	(segment
		(start 50.7746 -412.73349)
		(end 50.7746 -393.319254)
		(width 0.15494)
		(layer "In9.Cu")
		(net "GPU_THERM_OVERT_N")
	)
	(segment
		(start 342.886792 -237.96117)
		(end 342.861392 -237.93577)
		(width 0.13208)
		(layer "F.Cu")
		(net "RST_SSD0_PERST_N")
	)
	(segment
		(start 342.886792 -240.291112)
		(end 342.886792 -237.96117)
		(width 0.13208)
		(layer "F.Cu")
		(net "RST_SSD0_PERST_N")
	)
	(segment
		(start 341.293958 -224.786952)
		(end 340.894162 -225.186748)
		(width 0.13208)
		(layer "F.Cu")
		(net "RST_SSD0_PERST_N")
	)
	(via
		(at 342.861392 -237.93577)
		(size 0.508)
		(drill 0.254)
		(layers "F.Cu" "B.Cu")
		(net "RST_SSD0_PERST_N")
	)
	(via
		(at 340.894162 -225.186748)
		(size 0.4572)
		(drill 0.254)
		(layers "F.Cu" "B.Cu")
		(net "RST_SSD0_PERST_N")
	)
	(segment
		(start 341.486998 -228.469444)
		(end 341.292942 -228.275388)
		(width 0.15494)
		(layer "In5.Cu")
		(net "RST_SSD0_PERST_N")
	)
	(segment
		(start 342.861392 -237.91037)
		(end 341.486998 -236.535976)
		(width 0.15494)
		(layer "In5.Cu")
		(net "RST_SSD0_PERST_N")
	)
	(segment
		(start 341.486998 -236.535976)
		(end 341.486998 -228.469444)
		(width 0.15494)
		(layer "In5.Cu")
		(net "RST_SSD0_PERST_N")
	)
	(segment
		(start 341.292942 -225.585528)
		(end 340.894162 -225.186748)
		(width 0.0889)
		(layer "In5.Cu")
		(net "RST_SSD0_PERST_N")
	)
	(segment
		(start 341.292942 -226.91217)
		(end 341.292942 -225.585528)
		(width 0.0889)
		(layer "In5.Cu")
		(net "RST_SSD0_PERST_N")
	)
	(segment
		(start 341.292942 -228.275388)
		(end 341.292942 -226.91217)
		(width 0.15494)
		(layer "In5.Cu")
		(net "RST_SSD0_PERST_N")
	)
	(segment
		(start 342.861392 -237.93577)
		(end 342.861392 -237.91037)
		(width 0.15494)
		(layer "In5.Cu")
		(net "RST_SSD0_PERST_N")
	)
	(segment
		(start 229.5398 -231.01935)
		(end 229.020116 -230.499666)
		(width 0.13208)
		(layer "F.Cu")
		(net "NIC0_MAIN_PWR_BIC_EN")
	)
	(segment
		(start 229.020116 -229.576376)
		(end 229.020116 -227.556568)
		(width 0.13208)
		(layer "F.Cu")
		(net "NIC0_MAIN_PWR_BIC_EN")
	)
	(segment
		(start 229.067614 -227.50907)
		(end 229.067614 -224.704148)
		(width 0.13208)
		(layer "F.Cu")
		(net "NIC0_MAIN_PWR_BIC_EN")
	)
	(segment
		(start 229.020116 -227.556568)
		(end 229.067614 -227.50907)
		(width 0.13208)
		(layer "F.Cu")
		(net "NIC0_MAIN_PWR_BIC_EN")
	)
	(segment
		(start 229.020116 -230.499666)
		(end 229.020116 -229.576376)
		(width 0.13208)
		(layer "F.Cu")
		(net "NIC0_MAIN_PWR_BIC_EN")
	)
	(via
		(at 229.020116 -229.576376)
		(size 0.762)
		(drill 0.381)
		(layers "F.Cu" "B.Cu")
		(net "NIC0_MAIN_PWR_BIC_EN")
	)
	(segment
		(start 50.14976 -308.249828)
		(end 49.67478 -308.724808)
		(width 0.13208)
		(layer "F.Cu")
		(net "TP_PEX0_TCK")
	)
	(via
		(at 49.1998 -309.199788)
		(size 0.6604)
		(drill 0.3302)
		(layers "F.Cu" "B.Cu")
		(net "TP_PEX0_TCK")
	)
	(via
		(at 49.67478 -308.724808)
		(size 0.4064)
		(drill 0.2032)
		(layers "F.Cu" "B.Cu")
		(net "TP_PEX0_TCK")
	)
	(segment
		(start 49.1998 -309.199788)
		(end 49.67478 -308.724808)
		(width 0.13208)
		(layer "B.Cu")
		(net "TP_PEX0_TCK")
	)
	(segment
		(start 138.585194 -93.528642)
		(end 138.585194 -93.931994)
		(width 0.13208)
		(layer "F.Cu")
		(net "SMB_BIC_I2C9_MUX0_SSD6_R_SCL")
	)
	(segment
		(start 138.774932 -94.121732)
		(end 140.336016 -94.121732)
		(width 0.13208)
		(layer "F.Cu")
		(net "SMB_BIC_I2C9_MUX0_SSD6_R_SCL")
	)
	(segment
		(start 194.559428 -22.555454)
		(end 194.41795 -22.413976)
		(width 0.13208)
		(layer "F.Cu")
		(net "SMB_BIC_I2C9_MUX0_SSD6_R_SCL")
	)
	(segment
		(start 138.585194 -93.931994)
		(end 138.774932 -94.121732)
		(width 0.13208)
		(layer "F.Cu")
		(net "SMB_BIC_I2C9_MUX0_SSD6_R_SCL")
	)
	(segment
		(start 152.109678 -89.164922)
		(end 177.02403 -89.164922)
		(width 0.13208)
		(layer "F.Cu")
		(net "SMB_BIC_I2C9_MUX0_SSD6_R_SCL")
	)
	(segment
		(start 147.701 -93.5736)
		(end 152.109678 -89.164922)
		(width 0.13208)
		(layer "F.Cu")
		(net "SMB_BIC_I2C9_MUX0_SSD6_R_SCL")
	)
	(segment
		(start 198.34987 -74.429112)
		(end 199.761094 -74.429112)
		(width 0.13208)
		(layer "F.Cu")
		(net "SMB_BIC_I2C9_MUX0_SSD6_R_SCL")
	)
	(segment
		(start 194.41795 -21.775674)
		(end 194.385438 -21.743162)
		(width 0.13208)
		(layer "F.Cu")
		(net "SMB_BIC_I2C9_MUX0_SSD6_R_SCL")
	)
	(segment
		(start 188.752988 -77.435964)
		(end 195.343018 -77.435964)
		(width 0.13208)
		(layer "F.Cu")
		(net "SMB_BIC_I2C9_MUX0_SSD6_R_SCL")
	)
	(segment
		(start 140.336016 -94.121732)
		(end 140.884148 -93.5736)
		(width 0.13208)
		(layer "F.Cu")
		(net "SMB_BIC_I2C9_MUX0_SSD6_R_SCL")
	)
	(segment
		(start 136.845294 -93.528642)
		(end 138.585194 -93.528642)
		(width 0.13208)
		(layer "F.Cu")
		(net "SMB_BIC_I2C9_MUX0_SSD6_R_SCL")
	)
	(segment
		(start 194.41795 -22.413976)
		(end 194.41795 -21.775674)
		(width 0.13208)
		(layer "F.Cu")
		(net "SMB_BIC_I2C9_MUX0_SSD6_R_SCL")
	)
	(segment
		(start 140.884148 -93.5736)
		(end 147.701 -93.5736)
		(width 0.13208)
		(layer "F.Cu")
		(net "SMB_BIC_I2C9_MUX0_SSD6_R_SCL")
	)
	(segment
		(start 194.385438 -21.743162)
		(end 194.385438 -20.789392)
		(width 0.13208)
		(layer "F.Cu")
		(net "SMB_BIC_I2C9_MUX0_SSD6_R_SCL")
	)
	(segment
		(start 177.02403 -89.164922)
		(end 188.752988 -77.435964)
		(width 0.13208)
		(layer "F.Cu")
		(net "SMB_BIC_I2C9_MUX0_SSD6_R_SCL")
	)
	(segment
		(start 195.343018 -77.435964)
		(end 198.34987 -74.429112)
		(width 0.13208)
		(layer "F.Cu")
		(net "SMB_BIC_I2C9_MUX0_SSD6_R_SCL")
	)
	(via
		(at 199.761094 -74.429112)
		(size 0.508)
		(drill 0.254)
		(layers "F.Cu" "B.Cu")
		(net "SMB_BIC_I2C9_MUX0_SSD6_R_SCL")
	)
	(via
		(at 194.41795 -21.775674)
		(size 0.508)
		(drill 0.254)
		(layers "F.Cu" "B.Cu")
		(net "SMB_BIC_I2C9_MUX0_SSD6_R_SCL")
	)
	(segment
		(start 201.4601 -73.464166)
		(end 201.4601 -68.391786)
		(width 0.15494)
		(layer "In5.Cu")
		(net "SMB_BIC_I2C9_MUX0_SSD6_R_SCL")
	)
	(segment
		(start 194.1068 -28.1432)
		(end 192.816734 -26.853134)
		(width 0.15494)
		(layer "In5.Cu")
		(net "SMB_BIC_I2C9_MUX0_SSD6_R_SCL")
	)
	(segment
		(start 205.718664 -45.066204)
		(end 194.282568 -33.630108)
		(width 0.15494)
		(layer "In5.Cu")
		(net "SMB_BIC_I2C9_MUX0_SSD6_R_SCL")
	)
	(segment
		(start 201.4601 -68.391786)
		(end 205.718664 -64.133222)
		(width 0.15494)
		(layer "In5.Cu")
		(net "SMB_BIC_I2C9_MUX0_SSD6_R_SCL")
	)
	(segment
		(start 194.1068 -33.454594)
		(end 194.1068 -28.1432)
		(width 0.15494)
		(layer "In5.Cu")
		(net "SMB_BIC_I2C9_MUX0_SSD6_R_SCL")
	)
	(segment
		(start 192.816734 -26.853134)
		(end 192.816734 -22.33676)
		(width 0.15494)
		(layer "In5.Cu")
		(net "SMB_BIC_I2C9_MUX0_SSD6_R_SCL")
	)
	(segment
		(start 199.761094 -74.429112)
		(end 200.495154 -74.429112)
		(width 0.15494)
		(layer "In5.Cu")
		(net "SMB_BIC_I2C9_MUX0_SSD6_R_SCL")
	)
	(segment
		(start 194.282568 -33.630108)
		(end 194.282314 -33.630108)
		(width 0.15494)
		(layer "In5.Cu")
		(net "SMB_BIC_I2C9_MUX0_SSD6_R_SCL")
	)
	(segment
		(start 192.816734 -22.33676)
		(end 193.37782 -21.775674)
		(width 0.15494)
		(layer "In5.Cu")
		(net "SMB_BIC_I2C9_MUX0_SSD6_R_SCL")
	)
	(segment
		(start 205.718664 -64.133222)
		(end 205.718664 -45.066204)
		(width 0.15494)
		(layer "In5.Cu")
		(net "SMB_BIC_I2C9_MUX0_SSD6_R_SCL")
	)
	(segment
		(start 194.282314 -33.630108)
		(end 194.1068 -33.454594)
		(width 0.15494)
		(layer "In5.Cu")
		(net "SMB_BIC_I2C9_MUX0_SSD6_R_SCL")
	)
	(segment
		(start 193.37782 -21.775674)
		(end 194.41795 -21.775674)
		(width 0.15494)
		(layer "In5.Cu")
		(net "SMB_BIC_I2C9_MUX0_SSD6_R_SCL")
	)
	(segment
		(start 200.495154 -74.429112)
		(end 201.4601 -73.464166)
		(width 0.15494)
		(layer "In5.Cu")
		(net "SMB_BIC_I2C9_MUX0_SSD6_R_SCL")
	)
	(segment
		(start 58.286142 -386.734812)
		(end 57.650634 -386.734812)
		(width 0.13208)
		(layer "F.Cu")
		(net "GPU_BASE_ID0_R")
	)
	(via
		(at 57.650634 -386.734812)
		(size 0.508)
		(drill 0.254)
		(layers "F.Cu" "B.Cu")
		(net "GPU_BASE_ID0_R")
	)
	(segment
		(start 49.276 -402.107146)
		(end 47.976028 -403.407118)
		(width 0.15494)
		(layer "In9.Cu")
		(net "GPU_BASE_ID0_R")
	)
	(segment
		(start 47.976028 -403.407118)
		(end 46.392846 -403.407118)
		(width 0.15494)
		(layer "In9.Cu")
		(net "GPU_BASE_ID0_R")
	)
	(segment
		(start 57.038748 -386.734812)
		(end 53.458872 -390.314688)
		(width 0.15494)
		(layer "In9.Cu")
		(net "GPU_BASE_ID0_R")
	)
	(segment
		(start 53.458872 -390.314688)
		(end 51.518312 -390.314688)
		(width 0.15494)
		(layer "In9.Cu")
		(net "GPU_BASE_ID0_R")
	)
	(segment
		(start 51.518312 -390.314688)
		(end 49.276 -392.557)
		(width 0.15494)
		(layer "In9.Cu")
		(net "GPU_BASE_ID0_R")
	)
	(segment
		(start 46.392846 -403.407118)
		(end 45.509942 -404.290022)
		(width 0.15494)
		(layer "In9.Cu")
		(net "GPU_BASE_ID0_R")
	)
	(segment
		(start 49.276 -392.557)
		(end 49.276 -402.107146)
		(width 0.15494)
		(layer "In9.Cu")
		(net "GPU_BASE_ID0_R")
	)
	(segment
		(start 57.650634 -386.734812)
		(end 57.038748 -386.734812)
		(width 0.15494)
		(layer "In9.Cu")
		(net "GPU_BASE_ID0_R")
	)
	(segment
		(start 329.311 -245.63705)
		(end 327.735184 -245.63705)
		(width 0.13208)
		(layer "F.Cu")
		(net "JP_FPGA_FRC_PWRON_N")
	)
	(segment
		(start 325.90359 -253.907036)
		(end 326.980042 -253.907036)
		(width 0.13208)
		(layer "F.Cu")
		(net "JP_FPGA_FRC_PWRON_N")
	)
	(segment
		(start 329.311 -245.63705)
		(end 329.311 -246.166132)
		(width 0.13208)
		(layer "F.Cu")
		(net "JP_FPGA_FRC_PWRON_N")
	)
	(segment
		(start 325.139812 -253.143258)
		(end 325.90359 -253.907036)
		(width 0.13208)
		(layer "F.Cu")
		(net "JP_FPGA_FRC_PWRON_N")
	)
	(segment
		(start 338.093812 -225.587052)
		(end 337.694016 -225.986848)
		(width 0.13208)
		(layer "F.Cu")
		(net "JP_FPGA_FRC_PWRON_N")
	)
	(segment
		(start 327.735184 -245.63705)
		(end 325.139812 -248.232422)
		(width 0.13208)
		(layer "F.Cu")
		(net "JP_FPGA_FRC_PWRON_N")
	)
	(segment
		(start 325.139812 -248.232422)
		(end 325.139812 -253.143258)
		(width 0.13208)
		(layer "F.Cu")
		(net "JP_FPGA_FRC_PWRON_N")
	)
	(segment
		(start 329.311 -246.166132)
		(end 329.579732 -246.434864)
		(width 0.13208)
		(layer "F.Cu")
		(net "JP_FPGA_FRC_PWRON_N")
	)
	(via
		(at 337.694016 -225.986848)
		(size 0.4572)
		(drill 0.254)
		(layers "F.Cu" "B.Cu")
		(net "JP_FPGA_FRC_PWRON_N")
	)
	(via
		(at 329.579732 -246.434864)
		(size 0.508)
		(drill 0.254)
		(layers "F.Cu" "B.Cu")
		(net "JP_FPGA_FRC_PWRON_N")
	)
	(segment
		(start 335.439258 -237.389416)
		(end 335.439258 -236.016546)
		(width 0.15494)
		(layer "In5.Cu")
		(net "JP_FPGA_FRC_PWRON_N")
	)
	(segment
		(start 335.993486 -232.886758)
		(end 336.917284 -231.96296)
		(width 0.15494)
		(layer "In5.Cu")
		(net "JP_FPGA_FRC_PWRON_N")
	)
	(segment
		(start 336.917284 -231.96296)
		(end 336.917284 -228.391466)
		(width 0.15494)
		(layer "In5.Cu")
		(net "JP_FPGA_FRC_PWRON_N")
	)
	(segment
		(start 334.264762 -238.563912)
		(end 335.439258 -237.389416)
		(width 0.15494)
		(layer "In5.Cu")
		(net "JP_FPGA_FRC_PWRON_N")
	)
	(segment
		(start 329.579732 -246.434864)
		(end 329.579732 -245.984268)
		(width 0.15494)
		(layer "In5.Cu")
		(net "JP_FPGA_FRC_PWRON_N")
	)
	(segment
		(start 329.579732 -245.984268)
		(end 329.79614 -245.76786)
		(width 0.15494)
		(layer "In5.Cu")
		(net "JP_FPGA_FRC_PWRON_N")
	)
	(segment
		(start 329.79614 -245.76786)
		(end 329.79614 -241.717068)
		(width 0.15494)
		(layer "In5.Cu")
		(net "JP_FPGA_FRC_PWRON_N")
	)
	(segment
		(start 338.091526 -226.939348)
		(end 338.091526 -226.384358)
		(width 0.0889)
		(layer "In5.Cu")
		(net "JP_FPGA_FRC_PWRON_N")
	)
	(segment
		(start 336.917284 -228.391466)
		(end 338.091526 -227.217224)
		(width 0.15494)
		(layer "In5.Cu")
		(net "JP_FPGA_FRC_PWRON_N")
	)
	(segment
		(start 338.091526 -227.217224)
		(end 338.091526 -226.939348)
		(width 0.15494)
		(layer "In5.Cu")
		(net "JP_FPGA_FRC_PWRON_N")
	)
	(segment
		(start 329.79614 -241.717068)
		(end 332.949296 -238.563912)
		(width 0.15494)
		(layer "In5.Cu")
		(net "JP_FPGA_FRC_PWRON_N")
	)
	(segment
		(start 335.439258 -236.016546)
		(end 335.993486 -235.462318)
		(width 0.15494)
		(layer "In5.Cu")
		(net "JP_FPGA_FRC_PWRON_N")
	)
	(segment
		(start 338.091526 -226.384358)
		(end 337.694016 -225.986848)
		(width 0.0889)
		(layer "In5.Cu")
		(net "JP_FPGA_FRC_PWRON_N")
	)
	(segment
		(start 335.993486 -235.462318)
		(end 335.993486 -232.886758)
		(width 0.15494)
		(layer "In5.Cu")
		(net "JP_FPGA_FRC_PWRON_N")
	)
	(segment
		(start 332.949296 -238.563912)
		(end 334.264762 -238.563912)
		(width 0.15494)
		(layer "In5.Cu")
		(net "JP_FPGA_FRC_PWRON_N")
	)
	(segment
		(start 349.293942 -215.987122)
		(end 349.693738 -215.587326)
		(width 0.13208)
		(layer "F.Cu")
		(net "PRSNT_NIC3_FPGA_N")
	)
	(segment
		(start 357.61295 -212.344)
		(end 356.997 -212.344)
		(width 0.13208)
		(layer "F.Cu")
		(net "PRSNT_NIC3_FPGA_N")
	)
	(via
		(at 349.693738 -215.587326)
		(size 0.4572)
		(drill 0.254)
		(layers "F.Cu" "B.Cu")
		(net "PRSNT_NIC3_FPGA_N")
	)
	(via
		(at 356.997 -212.344)
		(size 0.508)
		(drill 0.254)
		(layers "F.Cu" "B.Cu")
		(net "PRSNT_NIC3_FPGA_N")
	)
	(segment
		(start 353.925632 -212.875368)
		(end 356.465632 -212.875368)
		(width 0.15494)
		(layer "In9.Cu")
		(net "PRSNT_NIC3_FPGA_N")
	)
	(segment
		(start 350.096328 -215.184736)
		(end 351.616264 -215.184736)
		(width 0.0889)
		(layer "In9.Cu")
		(net "PRSNT_NIC3_FPGA_N")
	)
	(segment
		(start 356.465632 -212.875368)
		(end 356.997 -212.344)
		(width 0.15494)
		(layer "In9.Cu")
		(net "PRSNT_NIC3_FPGA_N")
	)
	(segment
		(start 351.616264 -215.184736)
		(end 353.925632 -212.875368)
		(width 0.15494)
		(layer "In9.Cu")
		(net "PRSNT_NIC3_FPGA_N")
	)
	(segment
		(start 349.693738 -215.587326)
		(end 350.096328 -215.184736)
		(width 0.0889)
		(layer "In9.Cu")
		(net "PRSNT_NIC3_FPGA_N")
	)
	(via
		(at 52.999894 -308.249828)
		(size 0.4064)
		(drill 0.2032)
		(layers "F.Cu" "B.Cu")
		(net "TP_PEX0_TRST_L")
	)
	(via
		(at 54.899814 -308.249828)
		(size 0.6604)
		(drill 0.3302)
		(layers "F.Cu" "B.Cu")
		(net "TP_PEX0_TRST_L")
	)
	(segment
		(start 52.999894 -308.249828)
		(end 54.899814 -308.249828)
		(width 0.13208)
		(layer "B.Cu")
		(net "TP_PEX0_TRST_L")
	)
	(segment
		(start 56.874918 -308.324758)
		(end 56.883808 -308.324758)
		(width 0.13208)
		(layer "B.Cu")
		(net "TP_PEX0_TRST_L")
	)
	(segment
		(start 56.799988 -308.249828)
		(end 56.874918 -308.324758)
		(width 0.13208)
		(layer "B.Cu")
		(net "TP_PEX0_TRST_L")
	)
	(segment
		(start 54.899814 -308.249828)
		(end 56.799988 -308.249828)
		(width 0.13208)
		(layer "B.Cu")
		(net "TP_PEX0_TRST_L")
	)
	(segment
		(start 134.366 -89.330022)
		(end 134.366 -90.6526)
		(width 0.13208)
		(layer "F.Cu")
		(net "SMB_BIC_I2C9_MUX0_SSD4_SCL")
	)
	(segment
		(start 134.366 -90.6526)
		(end 133.778244 -91.240356)
		(width 0.13208)
		(layer "F.Cu")
		(net "SMB_BIC_I2C9_MUX0_SSD4_SCL")
	)
	(segment
		(start 136.045194 -88.956642)
		(end 135.689594 -88.956642)
		(width 0.13208)
		(layer "F.Cu")
		(net "SMB_BIC_I2C9_MUX0_SSD4_SCL")
	)
	(segment
		(start 135.39343 -88.660478)
		(end 135.035544 -88.660478)
		(width 0.13208)
		(layer "F.Cu")
		(net "SMB_BIC_I2C9_MUX0_SSD4_SCL")
	)
	(segment
		(start 133.778244 -91.240356)
		(end 133.062726 -91.240356)
		(width 0.13208)
		(layer "F.Cu")
		(net "SMB_BIC_I2C9_MUX0_SSD4_SCL")
	)
	(segment
		(start 135.689594 -88.956642)
		(end 135.39343 -88.660478)
		(width 0.13208)
		(layer "F.Cu")
		(net "SMB_BIC_I2C9_MUX0_SSD4_SCL")
	)
	(segment
		(start 135.035544 -88.660478)
		(end 134.366 -89.330022)
		(width 0.13208)
		(layer "F.Cu")
		(net "SMB_BIC_I2C9_MUX0_SSD4_SCL")
	)
	(via
		(at 135.035544 -88.660478)
		(size 0.508)
		(drill 0.254)
		(layers "F.Cu" "B.Cu")
		(net "SMB_BIC_I2C9_MUX0_SSD4_SCL")
	)
	(segment
		(start 62.215268 -392.76274)
		(end 62.215268 -391.012426)
		(width 0.13208)
		(layer "F.Cu")
		(net "PRSNT_GPU_N")
	)
	(segment
		(start 62.215268 -391.012426)
		(end 62.207648 -391.004806)
		(width 0.13208)
		(layer "F.Cu")
		(net "PRSNT_GPU_N")
	)
	(segment
		(start 328.295 -236.463078)
		(end 328.295 -235.712)
		(width 0.13208)
		(layer "F.Cu")
		(net "PRSNT_GPU_N")
	)
	(via
		(at 328.295 -235.712)
		(size 0.508)
		(drill 0.254)
		(layers "F.Cu" "B.Cu")
		(net "PRSNT_GPU_N")
	)
	(via
		(at 201.538586 -363.00791)
		(size 0.508)
		(drill 0.254)
		(layers "F.Cu" "B.Cu")
		(net "PRSNT_GPU_N")
	)
	(via
		(at 271.69999 -237.081314)
		(size 0.508)
		(drill 0.254)
		(layers "F.Cu" "B.Cu")
		(net "PRSNT_GPU_N")
	)
	(via
		(at 62.207648 -391.004806)
		(size 0.508)
		(drill 0.254)
		(layers "F.Cu" "B.Cu")
		(net "PRSNT_GPU_N")
	)
	(via
		(at 104.394 -370.205)
		(size 0.508)
		(drill 0.254)
		(layers "F.Cu" "B.Cu")
		(net "PRSNT_GPU_N")
	)
	(segment
		(start 62.207648 -392.020806)
		(end 61.648848 -392.579606)
		(width 0.13208)
		(layer "B.Cu")
		(net "PRSNT_GPU_N")
	)
	(segment
		(start 62.207648 -391.004806)
		(end 62.207648 -392.020806)
		(width 0.13208)
		(layer "B.Cu")
		(net "PRSNT_GPU_N")
	)
	(segment
		(start 104.394 -370.205)
		(end 104.859074 -369.739926)
		(width 0.13208)
		(layer "B.Cu")
		(net "PRSNT_GPU_N")
	)
	(segment
		(start 52.305204 -392.579606)
		(end 51.306984 -393.577826)
		(width 0.13208)
		(layer "B.Cu")
		(net "PRSNT_GPU_N")
	)
	(segment
		(start 108.818172 -369.739926)
		(end 115.862354 -362.695744)
		(width 0.13208)
		(layer "B.Cu")
		(net "PRSNT_GPU_N")
	)
	(segment
		(start 198.642478 -363.384846)
		(end 201.16165 -363.384846)
		(width 0.13208)
		(layer "B.Cu")
		(net "PRSNT_GPU_N")
	)
	(segment
		(start 51.306984 -393.577826)
		(end 51.306984 -413.352742)
		(width 0.13208)
		(layer "B.Cu")
		(net "PRSNT_GPU_N")
	)
	(segment
		(start 61.648848 -392.579606)
		(end 52.305204 -392.579606)
		(width 0.13208)
		(layer "B.Cu")
		(net "PRSNT_GPU_N")
	)
	(segment
		(start 51.306984 -413.352742)
		(end 50.239168 -414.420558)
		(width 0.13208)
		(layer "B.Cu")
		(net "PRSNT_GPU_N")
	)
	(segment
		(start 50.239168 -414.420558)
		(end 46.472348 -414.420558)
		(width 0.13208)
		(layer "B.Cu")
		(net "PRSNT_GPU_N")
	)
	(segment
		(start 115.862354 -362.695744)
		(end 197.953376 -362.695744)
		(width 0.13208)
		(layer "B.Cu")
		(net "PRSNT_GPU_N")
	)
	(segment
		(start 104.859074 -369.739926)
		(end 108.818172 -369.739926)
		(width 0.13208)
		(layer "B.Cu")
		(net "PRSNT_GPU_N")
	)
	(segment
		(start 197.953376 -362.695744)
		(end 198.642478 -363.384846)
		(width 0.13208)
		(layer "B.Cu")
		(net "PRSNT_GPU_N")
	)
	(segment
		(start 42.349674 -413.329882)
		(end 41.1099 -412.090108)
		(width 0.13208)
		(layer "B.Cu")
		(net "PRSNT_GPU_N")
	)
	(segment
		(start 201.16165 -363.384846)
		(end 201.538586 -363.00791)
		(width 0.13208)
		(layer "B.Cu")
		(net "PRSNT_GPU_N")
	)
	(segment
		(start 46.472348 -414.420558)
		(end 45.381672 -413.329882)
		(width 0.13208)
		(layer "B.Cu")
		(net "PRSNT_GPU_N")
	)
	(segment
		(start 45.381672 -413.329882)
		(end 42.349674 -413.329882)
		(width 0.13208)
		(layer "B.Cu")
		(net "PRSNT_GPU_N")
	)
	(segment
		(start 254.216154 -302.8315)
		(end 256.163826 -298.129198)
		(width 0.15494)
		(layer "In5.Cu")
		(net "PRSNT_GPU_N")
	)
	(segment
		(start 271.69999 -245.095014)
		(end 271.69999 -237.081314)
		(width 0.15494)
		(layer "In5.Cu")
		(net "PRSNT_GPU_N")
	)
	(segment
		(start 244.989096 -322.015612)
		(end 252.03023 -305.017424)
		(width 0.15494)
		(layer "In5.Cu")
		(net "PRSNT_GPU_N")
	)
	(segment
		(start 272.821908 -269.223236)
		(end 275.674836 -266.370308)
		(width 0.15494)
		(layer "In5.Cu")
		(net "PRSNT_GPU_N")
	)
	(segment
		(start 275.674836 -266.370308)
		(end 275.674836 -249.06986)
		(width 0.15494)
		(layer "In5.Cu")
		(net "PRSNT_GPU_N")
	)
	(segment
		(start 203.862432 -362.602526)
		(end 203.862432 -362.103416)
		(width 0.15494)
		(layer "In5.Cu")
		(net "PRSNT_GPU_N")
	)
	(segment
		(start 232.86974 -345.317064)
		(end 232.86974 -334.134968)
		(width 0.15494)
		(layer "In5.Cu")
		(net "PRSNT_GPU_N")
	)
	(segment
		(start 256.163826 -298.129198)
		(end 256.163826 -279.01646)
		(width 0.15494)
		(layer "In5.Cu")
		(net "PRSNT_GPU_N")
	)
	(segment
		(start 201.538586 -363.00791)
		(end 203.456794 -363.00791)
		(width 0.15494)
		(layer "In5.Cu")
		(net "PRSNT_GPU_N")
	)
	(segment
		(start 275.674836 -249.06986)
		(end 271.69999 -245.095014)
		(width 0.15494)
		(layer "In5.Cu")
		(net "PRSNT_GPU_N")
	)
	(segment
		(start 207.38084 -358.585008)
		(end 219.601796 -358.585008)
		(width 0.15494)
		(layer "In5.Cu")
		(net "PRSNT_GPU_N")
	)
	(segment
		(start 219.601796 -358.585008)
		(end 232.86974 -345.317064)
		(width 0.15494)
		(layer "In5.Cu")
		(net "PRSNT_GPU_N")
	)
	(segment
		(start 203.708 -362.756958)
		(end 203.862432 -362.602526)
		(width 0.15494)
		(layer "In5.Cu")
		(net "PRSNT_GPU_N")
	)
	(segment
		(start 203.456794 -363.00791)
		(end 203.707746 -362.756958)
		(width 0.15494)
		(layer "In5.Cu")
		(net "PRSNT_GPU_N")
	)
	(segment
		(start 256.163826 -279.01646)
		(end 258.291076 -276.88921)
		(width 0.15494)
		(layer "In5.Cu")
		(net "PRSNT_GPU_N")
	)
	(segment
		(start 258.291076 -276.88921)
		(end 262.687562 -276.88921)
		(width 0.15494)
		(layer "In5.Cu")
		(net "PRSNT_GPU_N")
	)
	(segment
		(start 252.03023 -305.017424)
		(end 254.216154 -302.8315)
		(width 0.15494)
		(layer "In5.Cu")
		(net "PRSNT_GPU_N")
	)
	(segment
		(start 262.687562 -276.88921)
		(end 270.353536 -269.223236)
		(width 0.15494)
		(layer "In5.Cu")
		(net "PRSNT_GPU_N")
	)
	(segment
		(start 232.86974 -334.134968)
		(end 244.989096 -322.015612)
		(width 0.15494)
		(layer "In5.Cu")
		(net "PRSNT_GPU_N")
	)
	(segment
		(start 203.862432 -362.103416)
		(end 207.38084 -358.585008)
		(width 0.15494)
		(layer "In5.Cu")
		(net "PRSNT_GPU_N")
	)
	(segment
		(start 270.353536 -269.223236)
		(end 272.821908 -269.223236)
		(width 0.15494)
		(layer "In5.Cu")
		(net "PRSNT_GPU_N")
	)
	(segment
		(start 203.707746 -362.756958)
		(end 203.708 -362.756958)
		(width 0.15494)
		(layer "In5.Cu")
		(net "PRSNT_GPU_N")
	)
	(segment
		(start 325.101966 -237.127542)
		(end 325.748142 -237.127542)
		(width 0.15494)
		(layer "In15.Cu")
		(net "PRSNT_GPU_N")
	)
	(segment
		(start 320.613786 -238.047022)
		(end 324.18147 -238.047022)
		(width 0.15494)
		(layer "In15.Cu")
		(net "PRSNT_GPU_N")
	)
	(segment
		(start 326.566784 -236.3089)
		(end 327.6981 -236.3089)
		(width 0.15494)
		(layer "In15.Cu")
		(net "PRSNT_GPU_N")
	)
	(segment
		(start 97.20072 -377.39828)
		(end 97.20072 -384.53568)
		(width 0.15494)
		(layer "In15.Cu")
		(net "PRSNT_GPU_N")
	)
	(segment
		(start 319.442338 -236.875574)
		(end 320.613786 -238.047022)
		(width 0.15494)
		(layer "In15.Cu")
		(net "PRSNT_GPU_N")
	)
	(segment
		(start 104.394 -370.205)
		(end 97.20072 -377.39828)
		(width 0.15494)
		(layer "In15.Cu")
		(net "PRSNT_GPU_N")
	)
	(segment
		(start 325.748142 -237.127542)
		(end 326.566784 -236.3089)
		(width 0.15494)
		(layer "In15.Cu")
		(net "PRSNT_GPU_N")
	)
	(segment
		(start 62.770766 -390.441688)
		(end 62.207648 -391.004806)
		(width 0.15494)
		(layer "In15.Cu")
		(net "PRSNT_GPU_N")
	)
	(segment
		(start 324.18147 -238.047022)
		(end 325.101966 -237.127542)
		(width 0.15494)
		(layer "In15.Cu")
		(net "PRSNT_GPU_N")
	)
	(segment
		(start 91.294712 -390.441688)
		(end 62.770766 -390.441688)
		(width 0.15494)
		(layer "In15.Cu")
		(net "PRSNT_GPU_N")
	)
	(segment
		(start 271.90573 -236.875574)
		(end 319.442338 -236.875574)
		(width 0.15494)
		(layer "In15.Cu")
		(net "PRSNT_GPU_N")
	)
	(segment
		(start 97.20072 -384.53568)
		(end 91.294712 -390.441688)
		(width 0.15494)
		(layer "In15.Cu")
		(net "PRSNT_GPU_N")
	)
	(segment
		(start 327.6981 -236.3089)
		(end 328.295 -235.712)
		(width 0.15494)
		(layer "In15.Cu")
		(net "PRSNT_GPU_N")
	)
	(segment
		(start 271.69999 -237.081314)
		(end 271.90573 -236.875574)
		(width 0.15494)
		(layer "In15.Cu")
		(net "PRSNT_GPU_N")
	)
	(segment
		(start 117.695472 -36.232592)
		(end 117.308884 -36.232592)
		(width 0.13208)
		(layer "F.Cu")
		(net "PWRGD_P3V3_SSD4_R")
	)
	(segment
		(start 117.308884 -36.232592)
		(end 116.763292 -35.687)
		(width 0.13208)
		(layer "F.Cu")
		(net "PWRGD_P3V3_SSD4_R")
	)
	(segment
		(start 124.711206 -61.386974)
		(end 124.711206 -62.051438)
		(width 0.13208)
		(layer "F.Cu")
		(net "PWRGD_P3V3_SSD4_R")
	)
	(segment
		(start 112.528096 -35.876738)
		(end 113.271046 -35.876738)
		(width 0.13208)
		(layer "F.Cu")
		(net "PWRGD_P3V3_SSD4_R")
	)
	(segment
		(start 116.763292 -35.687)
		(end 114.171984 -35.687)
		(width 0.13208)
		(layer "F.Cu")
		(net "PWRGD_P3V3_SSD4_R")
	)
	(segment
		(start 113.982246 -35.876738)
		(end 113.271046 -35.876738)
		(width 0.13208)
		(layer "F.Cu")
		(net "PWRGD_P3V3_SSD4_R")
	)
	(segment
		(start 114.171984 -35.687)
		(end 113.982246 -35.876738)
		(width 0.13208)
		(layer "F.Cu")
		(net "PWRGD_P3V3_SSD4_R")
	)
	(segment
		(start 344.49385 -223.187006)
		(end 344.893646 -223.586802)
		(width 0.13208)
		(layer "F.Cu")
		(net "PWRGD_P3V3_SSD4_R")
	)
	(via
		(at 124.711206 -62.051438)
		(size 0.508)
		(drill 0.254)
		(layers "F.Cu" "B.Cu")
		(net "PWRGD_P3V3_SSD4_R")
	)
	(via
		(at 113.271046 -35.876738)
		(size 0.508)
		(drill 0.254)
		(layers "F.Cu" "B.Cu")
		(net "PWRGD_P3V3_SSD4_R")
	)
	(via
		(at 141.888464 -186.06262)
		(size 0.508)
		(drill 0.254)
		(layers "F.Cu" "B.Cu")
		(net "PWRGD_P3V3_SSD4_R")
	)
	(via
		(at 344.893646 -223.586802)
		(size 0.4572)
		(drill 0.254)
		(layers "F.Cu" "B.Cu")
		(net "PWRGD_P3V3_SSD4_R")
	)
	(segment
		(start 124.711206 -62.051438)
		(end 124.64923 -61.989462)
		(width 0.15494)
		(layer "In5.Cu")
		(net "PWRGD_P3V3_SSD4_R")
	)
	(segment
		(start 123.33859 -61.989462)
		(end 122.599958 -62.728094)
		(width 0.15494)
		(layer "In5.Cu")
		(net "PWRGD_P3V3_SSD4_R")
	)
	(segment
		(start 130.661918 -77.559154)
		(end 131.070604 -77.559154)
		(width 0.15494)
		(layer "In5.Cu")
		(net "PWRGD_P3V3_SSD4_R")
	)
	(segment
		(start 112.977168 -36.170616)
		(end 113.271046 -35.876738)
		(width 0.15494)
		(layer "In5.Cu")
		(net "PWRGD_P3V3_SSD4_R")
	)
	(segment
		(start 124.711206 -62.051438)
		(end 126.6571 -63.997332)
		(width 0.15494)
		(layer "In5.Cu")
		(net "PWRGD_P3V3_SSD4_R")
	)
	(segment
		(start 131.070604 -77.559154)
		(end 131.369562 -77.858112)
		(width 0.15494)
		(layer "In5.Cu")
		(net "PWRGD_P3V3_SSD4_R")
	)
	(segment
		(start 131.369562 -78.266798)
		(end 139.606274 -86.50351)
		(width 0.15494)
		(layer "In5.Cu")
		(net "PWRGD_P3V3_SSD4_R")
	)
	(segment
		(start 131.369562 -77.858112)
		(end 131.369562 -78.266798)
		(width 0.15494)
		(layer "In5.Cu")
		(net "PWRGD_P3V3_SSD4_R")
	)
	(segment
		(start 126.6571 -73.554336)
		(end 130.661918 -77.559154)
		(width 0.15494)
		(layer "In5.Cu")
		(net "PWRGD_P3V3_SSD4_R")
	)
	(segment
		(start 119.775224 -62.728094)
		(end 112.977168 -55.930038)
		(width 0.15494)
		(layer "In5.Cu")
		(net "PWRGD_P3V3_SSD4_R")
	)
	(segment
		(start 122.599958 -62.728094)
		(end 119.775224 -62.728094)
		(width 0.15494)
		(layer "In5.Cu")
		(net "PWRGD_P3V3_SSD4_R")
	)
	(segment
		(start 140.329666 -110.45952)
		(end 140.329666 -163.681664)
		(width 0.15494)
		(layer "In5.Cu")
		(net "PWRGD_P3V3_SSD4_R")
	)
	(segment
		(start 140.456666 -184.630822)
		(end 141.888464 -186.06262)
		(width 0.15494)
		(layer "In5.Cu")
		(net "PWRGD_P3V3_SSD4_R")
	)
	(segment
		(start 140.456666 -173.465744)
		(end 140.456666 -184.630822)
		(width 0.15494)
		(layer "In5.Cu")
		(net "PWRGD_P3V3_SSD4_R")
	)
	(segment
		(start 141.1224 -172.80001)
		(end 140.456666 -173.465744)
		(width 0.15494)
		(layer "In5.Cu")
		(net "PWRGD_P3V3_SSD4_R")
	)
	(segment
		(start 124.64923 -61.989462)
		(end 123.33859 -61.989462)
		(width 0.15494)
		(layer "In5.Cu")
		(net "PWRGD_P3V3_SSD4_R")
	)
	(segment
		(start 141.1224 -164.474398)
		(end 141.1224 -172.80001)
		(width 0.15494)
		(layer "In5.Cu")
		(net "PWRGD_P3V3_SSD4_R")
	)
	(segment
		(start 126.6571 -63.997332)
		(end 126.6571 -73.554336)
		(width 0.15494)
		(layer "In5.Cu")
		(net "PWRGD_P3V3_SSD4_R")
	)
	(segment
		(start 139.606274 -86.50351)
		(end 139.606274 -109.736128)
		(width 0.15494)
		(layer "In5.Cu")
		(net "PWRGD_P3V3_SSD4_R")
	)
	(segment
		(start 140.329666 -163.681664)
		(end 141.1224 -164.474398)
		(width 0.15494)
		(layer "In5.Cu")
		(net "PWRGD_P3V3_SSD4_R")
	)
	(segment
		(start 139.606274 -109.736128)
		(end 140.329666 -110.45952)
		(width 0.15494)
		(layer "In5.Cu")
		(net "PWRGD_P3V3_SSD4_R")
	)
	(segment
		(start 112.977168 -55.930038)
		(end 112.977168 -36.170616)
		(width 0.15494)
		(layer "In5.Cu")
		(net "PWRGD_P3V3_SSD4_R")
	)
	(segment
		(start 371.978174 -182.15102)
		(end 371.978174 -178.221386)
		(width 0.15494)
		(layer "In15.Cu")
		(net "PWRGD_P3V3_SSD4_R")
	)
	(segment
		(start 239.830102 -171.631102)
		(end 237.029752 -168.830752)
		(width 0.15494)
		(layer "In15.Cu")
		(net "PWRGD_P3V3_SSD4_R")
	)
	(segment
		(start 332.857856 -167.83685)
		(end 332.613254 -168.081452)
		(width 0.15494)
		(layer "In15.Cu")
		(net "PWRGD_P3V3_SSD4_R")
	)
	(segment
		(start 375.690892 -228.256846)
		(end 375.690892 -216.890092)
		(width 0.15494)
		(layer "In15.Cu")
		(net "PWRGD_P3V3_SSD4_R")
	)
	(segment
		(start 347.384624 -170.328082)
		(end 345.1987 -168.142158)
		(width 0.15494)
		(layer "In15.Cu")
		(net "PWRGD_P3V3_SSD4_R")
	)
	(segment
		(start 332.404466 -168.081452)
		(end 332.166214 -167.8432)
		(width 0.15494)
		(layer "In15.Cu")
		(net "PWRGD_P3V3_SSD4_R")
	)
	(segment
		(start 337.11261 -168.142158)
		(end 336.807302 -167.83685)
		(width 0.15494)
		(layer "In15.Cu")
		(net "PWRGD_P3V3_SSD4_R")
	)
	(segment
		(start 375.690892 -216.890092)
		(end 374.592088 -215.791288)
		(width 0.15494)
		(layer "In15.Cu")
		(net "PWRGD_P3V3_SSD4_R")
	)
	(segment
		(start 371.978174 -178.221386)
		(end 364.08487 -170.328082)
		(width 0.15494)
		(layer "In15.Cu")
		(net "PWRGD_P3V3_SSD4_R")
	)
	(segment
		(start 369.574064 -234.373674)
		(end 375.690892 -228.256846)
		(width 0.15494)
		(layer "In15.Cu")
		(net "PWRGD_P3V3_SSD4_R")
	)
	(segment
		(start 345.29141 -223.984566)
		(end 345.29141 -224.51441)
		(width 0.0889)
		(layer "In15.Cu")
		(net "PWRGD_P3V3_SSD4_R")
	)
	(segment
		(start 331.883004 -167.158416)
		(end 331.481684 -167.158416)
		(width 0.15494)
		(layer "In15.Cu")
		(net "PWRGD_P3V3_SSD4_R")
	)
	(segment
		(start 376.67692 -200.521316)
		(end 376.67692 -188.982604)
		(width 0.15494)
		(layer "In15.Cu")
		(net "PWRGD_P3V3_SSD4_R")
	)
	(segment
		(start 332.613254 -168.081452)
		(end 332.404466 -168.081452)
		(width 0.15494)
		(layer "In15.Cu")
		(net "PWRGD_P3V3_SSD4_R")
	)
	(segment
		(start 286.28848 -168.881044)
		(end 258.101846 -168.881044)
		(width 0.15494)
		(layer "In15.Cu")
		(net "PWRGD_P3V3_SSD4_R")
	)
	(segment
		(start 354.78212 -234.373674)
		(end 369.574064 -234.373674)
		(width 0.15494)
		(layer "In15.Cu")
		(net "PWRGD_P3V3_SSD4_R")
	)
	(segment
		(start 374.592088 -215.791288)
		(end 374.592088 -202.606148)
		(width 0.15494)
		(layer "In15.Cu")
		(net "PWRGD_P3V3_SSD4_R")
	)
	(segment
		(start 375.243598 -187.841128)
		(end 375.243598 -185.416444)
		(width 0.15494)
		(layer "In15.Cu")
		(net "PWRGD_P3V3_SSD4_R")
	)
	(segment
		(start 179.61864 -174.248826)
		(end 177.737516 -174.248826)
		(width 0.15494)
		(layer "In15.Cu")
		(net "PWRGD_P3V3_SSD4_R")
	)
	(segment
		(start 217.15476 -168.830752)
		(end 213.251288 -172.734224)
		(width 0.15494)
		(layer "In15.Cu")
		(net "PWRGD_P3V3_SSD4_R")
	)
	(segment
		(start 180.132736 -174.005748)
		(end 179.61864 -174.248826)
		(width 0.15494)
		(layer "In15.Cu")
		(net "PWRGD_P3V3_SSD4_R")
	)
	(segment
		(start 331.198474 -167.441626)
		(end 331.198474 -167.8432)
		(width 0.15494)
		(layer "In15.Cu")
		(net "PWRGD_P3V3_SSD4_R")
	)
	(segment
		(start 258.101846 -168.881044)
		(end 255.351788 -171.631102)
		(width 0.15494)
		(layer "In15.Cu")
		(net "PWRGD_P3V3_SSD4_R")
	)
	(segment
		(start 213.251288 -172.734224)
		(end 181.59476 -172.734224)
		(width 0.15494)
		(layer "In15.Cu")
		(net "PWRGD_P3V3_SSD4_R")
	)
	(segment
		(start 345.821762 -224.78492)
		(end 346.09532 -225.058478)
		(width 0.0889)
		(layer "In15.Cu")
		(net "PWRGD_P3V3_SSD4_R")
	)
	(segment
		(start 353.3013 -232.892854)
		(end 354.78212 -234.373674)
		(width 0.15494)
		(layer "In15.Cu")
		(net "PWRGD_P3V3_SSD4_R")
	)
	(segment
		(start 255.351788 -171.631102)
		(end 239.830102 -171.631102)
		(width 0.15494)
		(layer "In15.Cu")
		(net "PWRGD_P3V3_SSD4_R")
	)
	(segment
		(start 376.055128 -188.360812)
		(end 375.763282 -188.360812)
		(width 0.15494)
		(layer "In15.Cu")
		(net "PWRGD_P3V3_SSD4_R")
	)
	(segment
		(start 375.243598 -185.416444)
		(end 371.978174 -182.15102)
		(width 0.15494)
		(layer "In15.Cu")
		(net "PWRGD_P3V3_SSD4_R")
	)
	(segment
		(start 181.59476 -172.734224)
		(end 180.45811 -173.870874)
		(width 0.15494)
		(layer "In15.Cu")
		(net "PWRGD_P3V3_SSD4_R")
	)
	(segment
		(start 177.737516 -174.248826)
		(end 166.419784 -185.566558)
		(width 0.15494)
		(layer "In15.Cu")
		(net "PWRGD_P3V3_SSD4_R")
	)
	(segment
		(start 166.419784 -185.566558)
		(end 142.384526 -185.566558)
		(width 0.15494)
		(layer "In15.Cu")
		(net "PWRGD_P3V3_SSD4_R")
	)
	(segment
		(start 344.893646 -223.586802)
		(end 345.29141 -223.984566)
		(width 0.0889)
		(layer "In15.Cu")
		(net "PWRGD_P3V3_SSD4_R")
	)
	(segment
		(start 180.45811 -173.870874)
		(end 180.132736 -174.005748)
		(width 0.15494)
		(layer "In15.Cu")
		(net "PWRGD_P3V3_SSD4_R")
	)
	(segment
		(start 346.36456 -226.38766)
		(end 347.424248 -226.38766)
		(width 0.0889)
		(layer "In15.Cu")
		(net "PWRGD_P3V3_SSD4_R")
	)
	(segment
		(start 347.424248 -226.38766)
		(end 347.693742 -226.657154)
		(width 0.0889)
		(layer "In15.Cu")
		(net "PWRGD_P3V3_SSD4_R")
	)
	(segment
		(start 336.807302 -167.83685)
		(end 332.857856 -167.83685)
		(width 0.15494)
		(layer "In15.Cu")
		(net "PWRGD_P3V3_SSD4_R")
	)
	(segment
		(start 347.693742 -226.657154)
		(end 347.693742 -227.031296)
		(width 0.0889)
		(layer "In15.Cu")
		(net "PWRGD_P3V3_SSD4_R")
	)
	(segment
		(start 346.09532 -226.11842)
		(end 346.36456 -226.38766)
		(width 0.0889)
		(layer "In15.Cu")
		(net "PWRGD_P3V3_SSD4_R")
	)
	(segment
		(start 332.166214 -167.441626)
		(end 331.883004 -167.158416)
		(width 0.15494)
		(layer "In15.Cu")
		(net "PWRGD_P3V3_SSD4_R")
	)
	(segment
		(start 142.384526 -185.566558)
		(end 141.888464 -186.06262)
		(width 0.15494)
		(layer "In15.Cu")
		(net "PWRGD_P3V3_SSD4_R")
	)
	(segment
		(start 364.08487 -170.328082)
		(end 347.384624 -170.328082)
		(width 0.15494)
		(layer "In15.Cu")
		(net "PWRGD_P3V3_SSD4_R")
	)
	(segment
		(start 287.088072 -168.081452)
		(end 286.28848 -168.881044)
		(width 0.15494)
		(layer "In15.Cu")
		(net "PWRGD_P3V3_SSD4_R")
	)
	(segment
		(start 352.88982 -232.892854)
		(end 353.3013 -232.892854)
		(width 0.15494)
		(layer "In15.Cu")
		(net "PWRGD_P3V3_SSD4_R")
	)
	(segment
		(start 374.592088 -202.606148)
		(end 376.67692 -200.521316)
		(width 0.15494)
		(layer "In15.Cu")
		(net "PWRGD_P3V3_SSD4_R")
	)
	(segment
		(start 345.1987 -168.142158)
		(end 337.11261 -168.142158)
		(width 0.15494)
		(layer "In15.Cu")
		(net "PWRGD_P3V3_SSD4_R")
	)
	(segment
		(start 237.029752 -168.830752)
		(end 217.15476 -168.830752)
		(width 0.15494)
		(layer "In15.Cu")
		(net "PWRGD_P3V3_SSD4_R")
	)
	(segment
		(start 331.481684 -167.158416)
		(end 331.198474 -167.441626)
		(width 0.15494)
		(layer "In15.Cu")
		(net "PWRGD_P3V3_SSD4_R")
	)
	(segment
		(start 345.56192 -224.78492)
		(end 345.821762 -224.78492)
		(width 0.0889)
		(layer "In15.Cu")
		(net "PWRGD_P3V3_SSD4_R")
	)
	(segment
		(start 347.693742 -227.696776)
		(end 352.88982 -232.892854)
		(width 0.15494)
		(layer "In15.Cu")
		(net "PWRGD_P3V3_SSD4_R")
	)
	(segment
		(start 376.67692 -188.982604)
		(end 376.055128 -188.360812)
		(width 0.15494)
		(layer "In15.Cu")
		(net "PWRGD_P3V3_SSD4_R")
	)
	(segment
		(start 347.693742 -227.031296)
		(end 347.693742 -227.696776)
		(width 0.15494)
		(layer "In15.Cu")
		(net "PWRGD_P3V3_SSD4_R")
	)
	(segment
		(start 332.166214 -167.8432)
		(end 332.166214 -167.441626)
		(width 0.15494)
		(layer "In15.Cu")
		(net "PWRGD_P3V3_SSD4_R")
	)
	(segment
		(start 346.09532 -225.058478)
		(end 346.09532 -226.11842)
		(width 0.0889)
		(layer "In15.Cu")
		(net "PWRGD_P3V3_SSD4_R")
	)
	(segment
		(start 330.960222 -168.081452)
		(end 287.088072 -168.081452)
		(width 0.15494)
		(layer "In15.Cu")
		(net "PWRGD_P3V3_SSD4_R")
	)
	(segment
		(start 331.198474 -167.8432)
		(end 330.960222 -168.081452)
		(width 0.15494)
		(layer "In15.Cu")
		(net "PWRGD_P3V3_SSD4_R")
	)
	(segment
		(start 345.29141 -224.51441)
		(end 345.56192 -224.78492)
		(width 0.0889)
		(layer "In15.Cu")
		(net "PWRGD_P3V3_SSD4_R")
	)
	(segment
		(start 375.763282 -188.360812)
		(end 375.243598 -187.841128)
		(width 0.15494)
		(layer "In15.Cu")
		(net "PWRGD_P3V3_SSD4_R")
	)
	(segment
		(start 103.763826 -53.96357)
		(end 103.153972 -53.96357)
		(width 0.13208)
		(layer "F.Cu")
		(net "P12V_SSD3_OCP")
	)
	(segment
		(start 102.755954 -53.96357)
		(end 103.153972 -53.96357)
		(width 0.13208)
		(layer "F.Cu")
		(net "P12V_SSD3_OCP")
	)
	(segment
		(start 102.147116 -54.144164)
		(end 102.57536 -54.144164)
		(width 0.13208)
		(layer "F.Cu")
		(net "P12V_SSD3_OCP")
	)
	(segment
		(start 102.57536 -54.144164)
		(end 102.755954 -53.96357)
		(width 0.13208)
		(layer "F.Cu")
		(net "P12V_SSD3_OCP")
	)
	(segment
		(start 103.867712 -54.067456)
		(end 103.763826 -53.96357)
		(width 0.13208)
		(layer "F.Cu")
		(net "P12V_SSD3_OCP")
	)
	(via
		(at 103.153972 -53.96357)
		(size 0.508)
		(drill 0.254)
		(layers "F.Cu" "B.Cu")
		(net "P12V_SSD3_OCP")
	)
	(segment
		(start 421.249856 -291.149786)
		(end 420.774876 -290.674806)
		(width 0.13208)
		(layer "F.Cu")
		(net "UART_PEX3_SDB_BUF_RX")
	)
	(via
		(at 423.62501 -270.41856)
		(size 0.6604)
		(drill 0.3302)
		(layers "F.Cu" "B.Cu")
		(net "UART_PEX3_SDB_BUF_RX")
	)
	(via
		(at 388.770876 -248.907808)
		(size 0.508)
		(drill 0.254)
		(layers "F.Cu" "B.Cu")
		(net "UART_PEX3_SDB_BUF_RX")
	)
	(via
		(at 419.967156 -251.60986)
		(size 0.508)
		(drill 0.254)
		(layers "F.Cu" "B.Cu")
		(net "UART_PEX3_SDB_BUF_RX")
	)
	(via
		(at 420.774876 -290.674806)
		(size 0.4064)
		(drill 0.2032)
		(layers "F.Cu" "B.Cu")
		(net "UART_PEX3_SDB_BUF_RX")
	)
	(segment
		(start 424.306746 -283.0068)
		(end 423.773346 -283.0068)
		(width 0.13208)
		(layer "B.Cu")
		(net "UART_PEX3_SDB_BUF_RX")
	)
	(segment
		(start 423.773346 -283.0068)
		(end 423.62501 -282.858464)
		(width 0.13208)
		(layer "B.Cu")
		(net "UART_PEX3_SDB_BUF_RX")
	)
	(segment
		(start 424.5356 -283.235654)
		(end 424.306746 -283.0068)
		(width 0.13208)
		(layer "B.Cu")
		(net "UART_PEX3_SDB_BUF_RX")
	)
	(segment
		(start 423.610024 -287.974278)
		(end 423.737024 -287.847278)
		(width 0.13208)
		(layer "B.Cu")
		(net "UART_PEX3_SDB_BUF_RX")
	)
	(segment
		(start 423.610024 -288.456878)
		(end 423.610024 -287.974278)
		(width 0.13208)
		(layer "B.Cu")
		(net "UART_PEX3_SDB_BUF_RX")
	)
	(segment
		(start 423.268902 -288.798)
		(end 423.610024 -288.456878)
		(width 0.13208)
		(layer "B.Cu")
		(net "UART_PEX3_SDB_BUF_RX")
	)
	(segment
		(start 423.62501 -270.41856)
		(end 423.62501 -255.267714)
		(width 0.13208)
		(layer "B.Cu")
		(net "UART_PEX3_SDB_BUF_RX")
	)
	(segment
		(start 420.774876 -290.674806)
		(end 421.24503 -290.204652)
		(width 0.13208)
		(layer "B.Cu")
		(net "UART_PEX3_SDB_BUF_RX")
	)
	(segment
		(start 387.772656 -248.907808)
		(end 386.576824 -247.711976)
		(width 0.13208)
		(layer "B.Cu")
		(net "UART_PEX3_SDB_BUF_RX")
	)
	(segment
		(start 421.24503 -290.204652)
		(end 421.24503 -289.47618)
		(width 0.13208)
		(layer "B.Cu")
		(net "UART_PEX3_SDB_BUF_RX")
	)
	(segment
		(start 384.409696 -247.711976)
		(end 385.425696 -247.711976)
		(width 0.13208)
		(layer "B.Cu")
		(net "UART_PEX3_SDB_BUF_RX")
	)
	(segment
		(start 424.5356 -287.531302)
		(end 424.5356 -283.235654)
		(width 0.13208)
		(layer "B.Cu")
		(net "UART_PEX3_SDB_BUF_RX")
	)
	(segment
		(start 421.24503 -289.47618)
		(end 421.92321 -288.798)
		(width 0.13208)
		(layer "B.Cu")
		(net "UART_PEX3_SDB_BUF_RX")
	)
	(segment
		(start 423.62501 -255.267714)
		(end 419.967156 -251.60986)
		(width 0.13208)
		(layer "B.Cu")
		(net "UART_PEX3_SDB_BUF_RX")
	)
	(segment
		(start 386.576824 -247.711976)
		(end 385.425696 -247.711976)
		(width 0.13208)
		(layer "B.Cu")
		(net "UART_PEX3_SDB_BUF_RX")
	)
	(segment
		(start 424.219624 -287.847278)
		(end 424.5356 -287.531302)
		(width 0.13208)
		(layer "B.Cu")
		(net "UART_PEX3_SDB_BUF_RX")
	)
	(segment
		(start 423.62501 -282.858464)
		(end 423.62501 -270.41856)
		(width 0.13208)
		(layer "B.Cu")
		(net "UART_PEX3_SDB_BUF_RX")
	)
	(segment
		(start 423.737024 -287.847278)
		(end 424.219624 -287.847278)
		(width 0.13208)
		(layer "B.Cu")
		(net "UART_PEX3_SDB_BUF_RX")
	)
	(segment
		(start 421.92321 -288.798)
		(end 423.268902 -288.798)
		(width 0.13208)
		(layer "B.Cu")
		(net "UART_PEX3_SDB_BUF_RX")
	)
	(segment
		(start 388.770876 -248.907808)
		(end 387.772656 -248.907808)
		(width 0.13208)
		(layer "B.Cu")
		(net "UART_PEX3_SDB_BUF_RX")
	)
	(segment
		(start 416.243008 -248.907808)
		(end 418.94506 -251.60986)
		(width 0.15494)
		(layer "In13.Cu")
		(net "UART_PEX3_SDB_BUF_RX")
	)
	(segment
		(start 418.94506 -251.60986)
		(end 419.967156 -251.60986)
		(width 0.15494)
		(layer "In13.Cu")
		(net "UART_PEX3_SDB_BUF_RX")
	)
	(segment
		(start 388.770876 -248.907808)
		(end 416.243008 -248.907808)
		(width 0.15494)
		(layer "In13.Cu")
		(net "UART_PEX3_SDB_BUF_RX")
	)
	(segment
		(start 54.899814 -308.249828)
		(end 54.424834 -307.774848)
		(width 0.13208)
		(layer "F.Cu")
		(net "TP_PEX0_TMS")
	)
	(via
		(at 54.424834 -307.774848)
		(size 0.4064)
		(drill 0.2032)
		(layers "F.Cu" "B.Cu")
		(net "TP_PEX0_TMS")
	)
	(via
		(at 53.949854 -307.299868)
		(size 0.6604)
		(drill 0.3302)
		(layers "F.Cu" "B.Cu")
		(net "TP_PEX0_TMS")
	)
	(segment
		(start 54.424834 -307.774848)
		(end 53.949854 -307.299868)
		(width 0.13208)
		(layer "B.Cu")
		(net "TP_PEX0_TMS")
	)
	(segment
		(start 133.062726 -95.140526)
		(end 134.277354 -95.140526)
		(width 0.13208)
		(layer "F.Cu")
		(net "SMB_BIC_I2C9_MUX0_SSD7_SCL")
	)
	(segment
		(start 134.95147 -95.814642)
		(end 136.045194 -95.814642)
		(width 0.13208)
		(layer "F.Cu")
		(net "SMB_BIC_I2C9_MUX0_SSD7_SCL")
	)
	(segment
		(start 134.656576 -95.519748)
		(end 134.95147 -95.814642)
		(width 0.13208)
		(layer "F.Cu")
		(net "SMB_BIC_I2C9_MUX0_SSD7_SCL")
	)
	(segment
		(start 134.277354 -95.140526)
		(end 134.656576 -95.519748)
		(width 0.13208)
		(layer "F.Cu")
		(net "SMB_BIC_I2C9_MUX0_SSD7_SCL")
	)
	(via
		(at 134.656576 -95.519748)
		(size 0.508)
		(drill 0.254)
		(layers "F.Cu" "B.Cu")
		(net "SMB_BIC_I2C9_MUX0_SSD7_SCL")
	)
	(segment
		(start 345.694 -230.57612)
		(end 345.29395 -230.17607)
		(width 0.13208)
		(layer "F.Cu")
		(net "SSD4_PWRDIS")
	)
	(segment
		(start 345.694 -232.283)
		(end 345.694 -231.521)
		(width 0.13208)
		(layer "F.Cu")
		(net "SSD4_PWRDIS")
	)
	(segment
		(start 345.059 -233.66095)
		(end 345.059 -232.918)
		(width 0.13208)
		(layer "F.Cu")
		(net "SSD4_PWRDIS")
	)
	(segment
		(start 345.059 -232.918)
		(end 345.694 -232.283)
		(width 0.13208)
		(layer "F.Cu")
		(net "SSD4_PWRDIS")
	)
	(segment
		(start 345.694 -231.521)
		(end 345.694 -230.57612)
		(width 0.13208)
		(layer "F.Cu")
		(net "SSD4_PWRDIS")
	)
	(segment
		(start 345.29395 -230.17607)
		(end 345.29395 -227.987098)
		(width 0.13208)
		(layer "F.Cu")
		(net "SSD4_PWRDIS")
	)
	(via
		(at 345.694 -231.521)
		(size 0.762)
		(drill 0.381)
		(layers "F.Cu" "B.Cu")
		(net "SSD4_PWRDIS")
	)
	(segment
		(start 228.385116 -230.226616)
		(end 228.6508 -230.4923)
		(width 0.13208)
		(layer "F.Cu")
		(net "NIC2_MAIN_PWR_BIC_EN")
	)
	(segment
		(start 228.385116 -228.440488)
		(end 228.385116 -230.226616)
		(width 0.13208)
		(layer "F.Cu")
		(net "NIC2_MAIN_PWR_BIC_EN")
	)
	(segment
		(start 228.038406 -228.043232)
		(end 228.372162 -228.376988)
		(width 0.13208)
		(layer "F.Cu")
		(net "NIC2_MAIN_PWR_BIC_EN")
	)
	(segment
		(start 229.067614 -223.904048)
		(end 228.667564 -224.304098)
		(width 0.13208)
		(layer "F.Cu")
		(net "NIC2_MAIN_PWR_BIC_EN")
	)
	(segment
		(start 228.667564 -226.551236)
		(end 228.038406 -227.180394)
		(width 0.13208)
		(layer "F.Cu")
		(net "NIC2_MAIN_PWR_BIC_EN")
	)
	(segment
		(start 228.372162 -228.376988)
		(end 228.372162 -228.427534)
		(width 0.13208)
		(layer "F.Cu")
		(net "NIC2_MAIN_PWR_BIC_EN")
	)
	(segment
		(start 228.6508 -230.4923)
		(end 228.6508 -231.01935)
		(width 0.13208)
		(layer "F.Cu")
		(net "NIC2_MAIN_PWR_BIC_EN")
	)
	(segment
		(start 228.667564 -224.304098)
		(end 228.667564 -226.551236)
		(width 0.13208)
		(layer "F.Cu")
		(net "NIC2_MAIN_PWR_BIC_EN")
	)
	(segment
		(start 228.038406 -227.180394)
		(end 228.038406 -228.043232)
		(width 0.13208)
		(layer "F.Cu")
		(net "NIC2_MAIN_PWR_BIC_EN")
	)
	(segment
		(start 228.372162 -228.427534)
		(end 228.385116 -228.440488)
		(width 0.13208)
		(layer "F.Cu")
		(net "NIC2_MAIN_PWR_BIC_EN")
	)
	(via
		(at 228.372162 -228.427534)
		(size 0.762)
		(drill 0.381)
		(layers "F.Cu" "B.Cu")
		(net "NIC2_MAIN_PWR_BIC_EN")
	)
	(segment
		(start 282.347162 -54.144164)
		(end 282.775406 -54.144164)
		(width 0.13208)
		(layer "F.Cu")
		(net "P12V_SSD9_OCP")
	)
	(segment
		(start 282.956 -53.96357)
		(end 283.354018 -53.96357)
		(width 0.13208)
		(layer "F.Cu")
		(net "P12V_SSD9_OCP")
	)
	(segment
		(start 282.775406 -54.144164)
		(end 282.956 -53.96357)
		(width 0.13208)
		(layer "F.Cu")
		(net "P12V_SSD9_OCP")
	)
	(segment
		(start 284.067758 -54.067456)
		(end 283.963872 -53.96357)
		(width 0.13208)
		(layer "F.Cu")
		(net "P12V_SSD9_OCP")
	)
	(segment
		(start 283.963872 -53.96357)
		(end 283.354018 -53.96357)
		(width 0.13208)
		(layer "F.Cu")
		(net "P12V_SSD9_OCP")
	)
	(via
		(at 283.354018 -53.96357)
		(size 0.508)
		(drill 0.254)
		(layers "F.Cu" "B.Cu")
		(net "P12V_SSD9_OCP")
	)
	(segment
		(start 135.372094 -94.49054)
		(end 133.062726 -94.49054)
		(width 0.13208)
		(layer "F.Cu")
		(net "SMB_BIC_I2C9_MUX0_SSD7_SDA")
	)
	(segment
		(start 135.824976 -94.451424)
		(end 135.41121 -94.451424)
		(width 0.13208)
		(layer "F.Cu")
		(net "SMB_BIC_I2C9_MUX0_SSD7_SDA")
	)
	(segment
		(start 135.41121 -94.451424)
		(end 135.372094 -94.49054)
		(width 0.13208)
		(layer "F.Cu")
		(net "SMB_BIC_I2C9_MUX0_SSD7_SDA")
	)
	(segment
		(start 136.045194 -94.671642)
		(end 135.824976 -94.451424)
		(width 0.13208)
		(layer "F.Cu")
		(net "SMB_BIC_I2C9_MUX0_SSD7_SDA")
	)
	(via
		(at 135.41121 -94.451424)
		(size 0.508)
		(drill 0.254)
		(layers "F.Cu" "B.Cu")
		(net "SMB_BIC_I2C9_MUX0_SSD7_SDA")
	)
	(segment
		(start 57.776872 -375.524268)
		(end 57.776872 -374.528842)
		(width 0.13208)
		(layer "F.Cu")
		(net "PRSNT_GPU_D_N")
	)
	(segment
		(start 57.776872 -374.528842)
		(end 57.777126 -374.528588)
		(width 0.13208)
		(layer "F.Cu")
		(net "PRSNT_GPU_D_N")
	)
	(segment
		(start 57.777126 -374.317006)
		(end 57.34431 -373.88419)
		(width 0.13208)
		(layer "F.Cu")
		(net "PRSNT_GPU_D_N")
	)
	(segment
		(start 57.777126 -374.528588)
		(end 57.777126 -374.317006)
		(width 0.13208)
		(layer "F.Cu")
		(net "PRSNT_GPU_D_N")
	)
	(via
		(at 57.34431 -373.88419)
		(size 0.508)
		(drill 0.254)
		(layers "F.Cu" "B.Cu")
		(net "PRSNT_GPU_D_N")
	)
	(segment
		(start 55.804054 -375.424446)
		(end 54.923182 -375.424446)
		(width 0.15494)
		(layer "In9.Cu")
		(net "PRSNT_GPU_D_N")
	)
	(segment
		(start 57.34431 -373.88419)
		(end 55.804054 -375.424446)
		(width 0.15494)
		(layer "In9.Cu")
		(net "PRSNT_GPU_D_N")
	)
	(segment
		(start 50.698146 -367.0808)
		(end 32.01924 -367.0808)
		(width 0.15494)
		(layer "In9.Cu")
		(net "PRSNT_GPU_D_N")
	)
	(segment
		(start 52.832 -373.333264)
		(end 52.832 -369.214654)
		(width 0.15494)
		(layer "In9.Cu")
		(net "PRSNT_GPU_D_N")
	)
	(segment
		(start 54.923182 -375.424446)
		(end 52.832 -373.333264)
		(width 0.15494)
		(layer "In9.Cu")
		(net "PRSNT_GPU_D_N")
	)
	(segment
		(start 32.01924 -367.0808)
		(end 30.109922 -368.990118)
		(width 0.15494)
		(layer "In9.Cu")
		(net "PRSNT_GPU_D_N")
	)
	(segment
		(start 52.832 -369.214654)
		(end 50.698146 -367.0808)
		(width 0.15494)
		(layer "In9.Cu")
		(net "PRSNT_GPU_D_N")
	)
	(segment
		(start 347.966792 -240.291112)
		(end 347.966792 -239.675162)
		(width 0.13208)
		(layer "F.Cu")
		(net "SSD2_CLK_EN_N")
	)
	(segment
		(start 337.293966 -226.387152)
		(end 336.89417 -226.786948)
		(width 0.13208)
		(layer "F.Cu")
		(net "SSD2_CLK_EN_N")
	)
	(via
		(at 336.89417 -226.786948)
		(size 0.4572)
		(drill 0.254)
		(layers "F.Cu" "B.Cu")
		(net "SSD2_CLK_EN_N")
	)
	(via
		(at 347.966792 -239.675162)
		(size 0.508)
		(drill 0.254)
		(layers "F.Cu" "B.Cu")
		(net "SSD2_CLK_EN_N")
	)
	(segment
		(start 346.897198 -242.2398)
		(end 339.632798 -242.2398)
		(width 0.15494)
		(layer "In7.Cu")
		(net "SSD2_CLK_EN_N")
	)
	(segment
		(start 336.72907 -238.697262)
		(end 336.728816 -238.697262)
		(width 0.15494)
		(layer "In7.Cu")
		(net "SSD2_CLK_EN_N")
	)
	(segment
		(start 336.789522 -226.891596)
		(end 336.89417 -226.786948)
		(width 0.15494)
		(layer "In7.Cu")
		(net "SSD2_CLK_EN_N")
	)
	(segment
		(start 347.966792 -239.675162)
		(end 347.966792 -241.170206)
		(width 0.15494)
		(layer "In7.Cu")
		(net "SSD2_CLK_EN_N")
	)
	(segment
		(start 336.107786 -234.98048)
		(end 336.107786 -229.685342)
		(width 0.15494)
		(layer "In7.Cu")
		(net "SSD2_CLK_EN_N")
	)
	(segment
		(start 337.833208 -239.8014)
		(end 336.72907 -238.697262)
		(width 0.15494)
		(layer "In7.Cu")
		(net "SSD2_CLK_EN_N")
	)
	(segment
		(start 336.107786 -229.685342)
		(end 336.789522 -229.003606)
		(width 0.15494)
		(layer "In7.Cu")
		(net "SSD2_CLK_EN_N")
	)
	(segment
		(start 336.728816 -238.697262)
		(end 336.60207 -238.570516)
		(width 0.15494)
		(layer "In7.Cu")
		(net "SSD2_CLK_EN_N")
	)
	(segment
		(start 347.966792 -241.170206)
		(end 346.897198 -242.2398)
		(width 0.15494)
		(layer "In7.Cu")
		(net "SSD2_CLK_EN_N")
	)
	(segment
		(start 336.830162 -236.60735)
		(end 336.830162 -235.702856)
		(width 0.15494)
		(layer "In7.Cu")
		(net "SSD2_CLK_EN_N")
	)
	(segment
		(start 339.632798 -242.2398)
		(end 337.833208 -240.44021)
		(width 0.15494)
		(layer "In7.Cu")
		(net "SSD2_CLK_EN_N")
	)
	(segment
		(start 336.60207 -238.570516)
		(end 336.60207 -236.835442)
		(width 0.15494)
		(layer "In7.Cu")
		(net "SSD2_CLK_EN_N")
	)
	(segment
		(start 337.833208 -240.44021)
		(end 337.833208 -239.8014)
		(width 0.15494)
		(layer "In7.Cu")
		(net "SSD2_CLK_EN_N")
	)
	(segment
		(start 336.830162 -235.702856)
		(end 336.107786 -234.98048)
		(width 0.15494)
		(layer "In7.Cu")
		(net "SSD2_CLK_EN_N")
	)
	(segment
		(start 336.789522 -229.003606)
		(end 336.789522 -226.891596)
		(width 0.15494)
		(layer "In7.Cu")
		(net "SSD2_CLK_EN_N")
	)
	(segment
		(start 336.60207 -236.835442)
		(end 336.830162 -236.60735)
		(width 0.15494)
		(layer "In7.Cu")
		(net "SSD2_CLK_EN_N")
	)
	(segment
		(start 376.982482 -175.679608)
		(end 375.157746 -175.679608)
		(width 0.13208)
		(layer "F.Cu")
		(net "NIC3_PEX_PWR_EN_R")
	)
	(segment
		(start 375.157746 -175.679608)
		(end 375.105676 -175.627538)
		(width 0.13208)
		(layer "F.Cu")
		(net "NIC3_PEX_PWR_EN_R")
	)
	(segment
		(start 377.20905 -174.15002)
		(end 377.20905 -175.16602)
		(width 0.13208)
		(layer "F.Cu")
		(net "NIC3_PEX_PWR_EN_R")
	)
	(segment
		(start 377.20905 -175.45304)
		(end 376.982482 -175.679608)
		(width 0.13208)
		(layer "F.Cu")
		(net "NIC3_PEX_PWR_EN_R")
	)
	(segment
		(start 377.20905 -173.13402)
		(end 377.20905 -174.15002)
		(width 0.13208)
		(layer "F.Cu")
		(net "NIC3_PEX_PWR_EN_R")
	)
	(segment
		(start 348.493842 -215.987122)
		(end 348.893638 -215.587326)
		(width 0.13208)
		(layer "F.Cu")
		(net "NIC3_PEX_PWR_EN_R")
	)
	(segment
		(start 377.20905 -175.16602)
		(end 377.20905 -175.45304)
		(width 0.13208)
		(layer "F.Cu")
		(net "NIC3_PEX_PWR_EN_R")
	)
	(via
		(at 375.105676 -175.627538)
		(size 0.508)
		(drill 0.254)
		(layers "F.Cu" "B.Cu")
		(net "NIC3_PEX_PWR_EN_R")
	)
	(via
		(at 368.801904 -176.236376)
		(size 0.508)
		(drill 0.254)
		(layers "F.Cu" "B.Cu")
		(net "NIC3_PEX_PWR_EN_R")
	)
	(via
		(at 348.893638 -215.587326)
		(size 0.4572)
		(drill 0.254)
		(layers "F.Cu" "B.Cu")
		(net "NIC3_PEX_PWR_EN_R")
	)
	(segment
		(start 349.293688 -215.187276)
		(end 351.68459 -215.187276)
		(width 0.0889)
		(layer "In7.Cu")
		(net "NIC3_PEX_PWR_EN_R")
	)
	(segment
		(start 357.9368 -203.5302)
		(end 359.03027 -203.5302)
		(width 0.15494)
		(layer "In7.Cu")
		(net "NIC3_PEX_PWR_EN_R")
	)
	(segment
		(start 353.0092 -209.338672)
		(end 355.727 -206.620872)
		(width 0.15494)
		(layer "In7.Cu")
		(net "NIC3_PEX_PWR_EN_R")
	)
	(segment
		(start 348.893638 -215.587326)
		(end 349.293688 -215.187276)
		(width 0.0889)
		(layer "In7.Cu")
		(net "NIC3_PEX_PWR_EN_R")
	)
	(segment
		(start 359.03027 -203.5302)
		(end 363.65307 -198.9074)
		(width 0.15494)
		(layer "In7.Cu")
		(net "NIC3_PEX_PWR_EN_R")
	)
	(segment
		(start 368.801904 -193.643504)
		(end 368.801904 -176.236376)
		(width 0.15494)
		(layer "In7.Cu")
		(net "NIC3_PEX_PWR_EN_R")
	)
	(segment
		(start 368.001296 -195.913756)
		(end 368.001296 -194.444112)
		(width 0.15494)
		(layer "In7.Cu")
		(net "NIC3_PEX_PWR_EN_R")
	)
	(segment
		(start 368.001296 -194.444112)
		(end 368.801904 -193.643504)
		(width 0.15494)
		(layer "In7.Cu")
		(net "NIC3_PEX_PWR_EN_R")
	)
	(segment
		(start 355.727 -205.74)
		(end 357.9368 -203.5302)
		(width 0.15494)
		(layer "In7.Cu")
		(net "NIC3_PEX_PWR_EN_R")
	)
	(segment
		(start 355.727 -206.620872)
		(end 355.727 -205.74)
		(width 0.15494)
		(layer "In7.Cu")
		(net "NIC3_PEX_PWR_EN_R")
	)
	(segment
		(start 353.0092 -213.867746)
		(end 353.0092 -209.338672)
		(width 0.15494)
		(layer "In7.Cu")
		(net "NIC3_PEX_PWR_EN_R")
	)
	(segment
		(start 363.65307 -198.9074)
		(end 365.007652 -198.9074)
		(width 0.15494)
		(layer "In7.Cu")
		(net "NIC3_PEX_PWR_EN_R")
	)
	(segment
		(start 351.68459 -215.187276)
		(end 351.68713 -215.189816)
		(width 0.0889)
		(layer "In7.Cu")
		(net "NIC3_PEX_PWR_EN_R")
	)
	(segment
		(start 351.68713 -215.189816)
		(end 353.0092 -213.867746)
		(width 0.15494)
		(layer "In7.Cu")
		(net "NIC3_PEX_PWR_EN_R")
	)
	(segment
		(start 365.007652 -198.9074)
		(end 368.001296 -195.913756)
		(width 0.15494)
		(layer "In7.Cu")
		(net "NIC3_PEX_PWR_EN_R")
	)
	(segment
		(start 370.582444 -175.627538)
		(end 375.105676 -175.627538)
		(width 0.15494)
		(layer "In13.Cu")
		(net "NIC3_PEX_PWR_EN_R")
	)
	(segment
		(start 368.801904 -176.236376)
		(end 369.973606 -176.236376)
		(width 0.15494)
		(layer "In13.Cu")
		(net "NIC3_PEX_PWR_EN_R")
	)
	(segment
		(start 369.973606 -176.236376)
		(end 370.582444 -175.627538)
		(width 0.15494)
		(layer "In13.Cu")
		(net "NIC3_PEX_PWR_EN_R")
	)
	(segment
		(start 334.775302 -54.144164)
		(end 334.955896 -53.96357)
		(width 0.13208)
		(layer "F.Cu")
		(net "P12V_SSD11_OCP")
	)
	(segment
		(start 335.963768 -53.96357)
		(end 335.353914 -53.96357)
		(width 0.13208)
		(layer "F.Cu")
		(net "P12V_SSD11_OCP")
	)
	(segment
		(start 334.347058 -54.144164)
		(end 334.775302 -54.144164)
		(width 0.13208)
		(layer "F.Cu")
		(net "P12V_SSD11_OCP")
	)
	(segment
		(start 336.067654 -54.067456)
		(end 335.963768 -53.96357)
		(width 0.13208)
		(layer "F.Cu")
		(net "P12V_SSD11_OCP")
	)
	(segment
		(start 334.955896 -53.96357)
		(end 335.353914 -53.96357)
		(width 0.13208)
		(layer "F.Cu")
		(net "P12V_SSD11_OCP")
	)
	(via
		(at 335.353914 -53.96357)
		(size 0.508)
		(drill 0.254)
		(layers "F.Cu" "B.Cu")
		(net "P12V_SSD11_OCP")
	)
	(segment
		(start 305.149758 -291.149786)
		(end 304.674778 -290.674806)
		(width 0.13208)
		(layer "F.Cu")
		(net "UART_PEX2_SDB_BUF_RX")
	)
	(via
		(at 387.35127 -247.478042)
		(size 0.508)
		(drill 0.254)
		(layers "F.Cu" "B.Cu")
		(net "UART_PEX2_SDB_BUF_RX")
	)
	(via
		(at 304.674778 -290.674806)
		(size 0.4064)
		(drill 0.2032)
		(layers "F.Cu" "B.Cu")
		(net "UART_PEX2_SDB_BUF_RX")
	)
	(via
		(at 307.999892 -282.599892)
		(size 0.6604)
		(drill 0.3302)
		(layers "F.Cu" "B.Cu")
		(net "UART_PEX2_SDB_BUF_RX")
	)
	(via
		(at 316.5602 -261.0612)
		(size 0.508)
		(drill 0.254)
		(layers "F.Cu" "B.Cu")
		(net "UART_PEX2_SDB_BUF_RX")
	)
	(segment
		(start 308.149244 -288.7472)
		(end 308.454044 -288.4424)
		(width 0.13208)
		(layer "B.Cu")
		(net "UART_PEX2_SDB_BUF_RX")
	)
	(segment
		(start 308.454044 -288.4424)
		(end 308.454044 -283.054044)
		(width 0.13208)
		(layer "B.Cu")
		(net "UART_PEX2_SDB_BUF_RX")
	)
	(segment
		(start 307.4416 -288.7472)
		(end 308.149244 -288.7472)
		(width 0.13208)
		(layer "B.Cu")
		(net "UART_PEX2_SDB_BUF_RX")
	)
	(segment
		(start 306.8828 -289.306)
		(end 307.4416 -288.7472)
		(width 0.13208)
		(layer "B.Cu")
		(net "UART_PEX2_SDB_BUF_RX")
	)
	(segment
		(start 304.674778 -290.674806)
		(end 305.144932 -290.204652)
		(width 0.13208)
		(layer "B.Cu")
		(net "UART_PEX2_SDB_BUF_RX")
	)
	(segment
		(start 388.202678 -247.565164)
		(end 388.115556 -247.478042)
		(width 0.13208)
		(layer "B.Cu")
		(net "UART_PEX2_SDB_BUF_RX")
	)
	(segment
		(start 308.474872 -282.124912)
		(end 307.999892 -282.599892)
		(width 0.13208)
		(layer "B.Cu")
		(net "UART_PEX2_SDB_BUF_RX")
	)
	(segment
		(start 308.474872 -271.060926)
		(end 308.474872 -282.124912)
		(width 0.13208)
		(layer "B.Cu")
		(net "UART_PEX2_SDB_BUF_RX")
	)
	(segment
		(start 389.04672 -247.95861)
		(end 388.596124 -247.95861)
		(width 0.13208)
		(layer "B.Cu")
		(net "UART_PEX2_SDB_BUF_RX")
	)
	(segment
		(start 316.474348 -263.06145)
		(end 308.474872 -271.060926)
		(width 0.13208)
		(layer "B.Cu")
		(net "UART_PEX2_SDB_BUF_RX")
	)
	(segment
		(start 388.596124 -247.95861)
		(end 388.202678 -247.565164)
		(width 0.13208)
		(layer "B.Cu")
		(net "UART_PEX2_SDB_BUF_RX")
	)
	(segment
		(start 305.144932 -289.47618)
		(end 305.315112 -289.306)
		(width 0.13208)
		(layer "B.Cu")
		(net "UART_PEX2_SDB_BUF_RX")
	)
	(segment
		(start 316.5602 -261.0612)
		(end 316.474348 -261.147052)
		(width 0.13208)
		(layer "B.Cu")
		(net "UART_PEX2_SDB_BUF_RX")
	)
	(segment
		(start 388.115556 -247.478042)
		(end 387.35127 -247.478042)
		(width 0.13208)
		(layer "B.Cu")
		(net "UART_PEX2_SDB_BUF_RX")
	)
	(segment
		(start 305.315112 -289.306)
		(end 306.8828 -289.306)
		(width 0.13208)
		(layer "B.Cu")
		(net "UART_PEX2_SDB_BUF_RX")
	)
	(segment
		(start 316.474348 -261.147052)
		(end 316.474348 -263.06145)
		(width 0.13208)
		(layer "B.Cu")
		(net "UART_PEX2_SDB_BUF_RX")
	)
	(segment
		(start 389.443976 -247.561354)
		(end 389.04672 -247.95861)
		(width 0.13208)
		(layer "B.Cu")
		(net "UART_PEX2_SDB_BUF_RX")
	)
	(segment
		(start 305.144932 -290.204652)
		(end 305.144932 -289.47618)
		(width 0.13208)
		(layer "B.Cu")
		(net "UART_PEX2_SDB_BUF_RX")
	)
	(segment
		(start 308.454044 -283.054044)
		(end 307.999892 -282.599892)
		(width 0.13208)
		(layer "B.Cu")
		(net "UART_PEX2_SDB_BUF_RX")
	)
	(segment
		(start 316.5602 -261.0612)
		(end 316.8396 -261.3406)
		(width 0.15494)
		(layer "In15.Cu")
		(net "UART_PEX2_SDB_BUF_RX")
	)
	(segment
		(start 337.764628 -259.669534)
		(end 349.852234 -247.581928)
		(width 0.15494)
		(layer "In15.Cu")
		(net "UART_PEX2_SDB_BUF_RX")
	)
	(segment
		(start 363.523022 -247.524016)
		(end 367.207292 -247.524016)
		(width 0.15494)
		(layer "In15.Cu")
		(net "UART_PEX2_SDB_BUF_RX")
	)
	(segment
		(start 316.8396 -261.3406)
		(end 330.85024 -261.3406)
		(width 0.15494)
		(layer "In15.Cu")
		(net "UART_PEX2_SDB_BUF_RX")
	)
	(segment
		(start 387.705854 -249.488452)
		(end 387.850888 -249.343418)
		(width 0.15494)
		(layer "In15.Cu")
		(net "UART_PEX2_SDB_BUF_RX")
	)
	(segment
		(start 332.521306 -259.669534)
		(end 337.764628 -259.669534)
		(width 0.15494)
		(layer "In15.Cu")
		(net "UART_PEX2_SDB_BUF_RX")
	)
	(segment
		(start 330.85024 -261.3406)
		(end 332.521306 -259.669534)
		(width 0.15494)
		(layer "In15.Cu")
		(net "UART_PEX2_SDB_BUF_RX")
	)
	(segment
		(start 367.207292 -247.524016)
		(end 369.171728 -249.488452)
		(width 0.15494)
		(layer "In15.Cu")
		(net "UART_PEX2_SDB_BUF_RX")
	)
	(segment
		(start 349.852234 -247.581928)
		(end 363.46511 -247.581928)
		(width 0.15494)
		(layer "In15.Cu")
		(net "UART_PEX2_SDB_BUF_RX")
	)
	(segment
		(start 369.171728 -249.488452)
		(end 387.705854 -249.488452)
		(width 0.15494)
		(layer "In15.Cu")
		(net "UART_PEX2_SDB_BUF_RX")
	)
	(segment
		(start 363.46511 -247.581928)
		(end 363.523022 -247.524016)
		(width 0.15494)
		(layer "In15.Cu")
		(net "UART_PEX2_SDB_BUF_RX")
	)
	(segment
		(start 387.850888 -249.343418)
		(end 387.850888 -247.97766)
		(width 0.15494)
		(layer "In15.Cu")
		(net "UART_PEX2_SDB_BUF_RX")
	)
	(segment
		(start 387.850888 -247.97766)
		(end 387.35127 -247.478042)
		(width 0.15494)
		(layer "In15.Cu")
		(net "UART_PEX2_SDB_BUF_RX")
	)
	(segment
		(start 134.13486 -93.087952)
		(end 134.032498 -93.190314)
		(width 0.13208)
		(layer "F.Cu")
		(net "SMB_BIC_I2C9_MUX0_SSD6_SDA")
	)
	(segment
		(start 134.993126 -93.087952)
		(end 134.13486 -93.087952)
		(width 0.13208)
		(layer "F.Cu")
		(net "SMB_BIC_I2C9_MUX0_SSD6_SDA")
	)
	(segment
		(start 135.435594 -92.645484)
		(end 134.993126 -93.087952)
		(width 0.13208)
		(layer "F.Cu")
		(net "SMB_BIC_I2C9_MUX0_SSD6_SDA")
	)
	(segment
		(start 134.032498 -93.190314)
		(end 133.062726 -93.190314)
		(width 0.13208)
		(layer "F.Cu")
		(net "SMB_BIC_I2C9_MUX0_SSD6_SDA")
	)
	(segment
		(start 135.45185 -92.645484)
		(end 135.711692 -92.385642)
		(width 0.13208)
		(layer "F.Cu")
		(net "SMB_BIC_I2C9_MUX0_SSD6_SDA")
	)
	(segment
		(start 135.711692 -92.385642)
		(end 136.045194 -92.385642)
		(width 0.13208)
		(layer "F.Cu")
		(net "SMB_BIC_I2C9_MUX0_SSD6_SDA")
	)
	(segment
		(start 135.435594 -92.645484)
		(end 135.45185 -92.645484)
		(width 0.13208)
		(layer "F.Cu")
		(net "SMB_BIC_I2C9_MUX0_SSD6_SDA")
	)
	(via
		(at 135.435594 -92.645484)
		(size 0.508)
		(drill 0.254)
		(layers "F.Cu" "B.Cu")
		(net "SMB_BIC_I2C9_MUX0_SSD6_SDA")
	)
	(segment
		(start 285.211774 -16.363188)
		(end 285.135574 -16.439388)
		(width 0.13208)
		(layer "F.Cu")
		(net "SMB_ISO_SSD9_SDA")
	)
	(segment
		(start 282.226258 -19.453098)
		(end 282.267914 -19.453098)
		(width 0.13208)
		(layer "F.Cu")
		(net "SMB_ISO_SSD9_SDA")
	)
	(segment
		(start 285.135574 -18.533618)
		(end 284.216094 -19.453098)
		(width 0.13208)
		(layer "F.Cu")
		(net "SMB_ISO_SSD9_SDA")
	)
	(segment
		(start 285.135574 -16.439388)
		(end 285.135574 -18.533618)
		(width 0.13208)
		(layer "F.Cu")
		(net "SMB_ISO_SSD9_SDA")
	)
	(segment
		(start 281.456384 -20.222972)
		(end 282.226258 -19.453098)
		(width 0.13208)
		(layer "F.Cu")
		(net "SMB_ISO_SSD9_SDA")
	)
	(segment
		(start 284.216094 -19.453098)
		(end 282.267914 -19.453098)
		(width 0.13208)
		(layer "F.Cu")
		(net "SMB_ISO_SSD9_SDA")
	)
	(segment
		(start 285.66237 -23.337266)
		(end 285.66237 -23.946866)
		(width 0.13208)
		(layer "F.Cu")
		(net "SMB_ISO_SSD9_SDA")
	)
	(segment
		(start 281.456384 -20.467574)
		(end 281.456384 -20.222972)
		(width 0.13208)
		(layer "F.Cu")
		(net "SMB_ISO_SSD9_SDA")
	)
	(segment
		(start 285.211774 -15.351252)
		(end 285.211774 -16.363188)
		(width 0.13208)
		(layer "F.Cu")
		(net "SMB_ISO_SSD9_SDA")
	)
	(via
		(at 285.66237 -23.946866)
		(size 0.508)
		(drill 0.254)
		(layers "F.Cu" "B.Cu")
		(net "SMB_ISO_SSD9_SDA")
	)
	(via
		(at 285.211774 -15.351252)
		(size 0.508)
		(drill 0.254)
		(layers "F.Cu" "B.Cu")
		(net "SMB_ISO_SSD9_SDA")
	)
	(segment
		(start 285.211774 -15.420594)
		(end 285.211774 -15.351252)
		(width 0.13208)
		(layer "B.Cu")
		(net "SMB_ISO_SSD9_SDA")
	)
	(segment
		(start 287.216088 -17.424908)
		(end 285.211774 -15.420594)
		(width 0.13208)
		(layer "B.Cu")
		(net "SMB_ISO_SSD9_SDA")
	)
	(segment
		(start 285.66237 -23.946866)
		(end 287.216088 -22.393148)
		(width 0.13208)
		(layer "B.Cu")
		(net "SMB_ISO_SSD9_SDA")
	)
	(segment
		(start 287.216088 -22.393148)
		(end 287.216088 -17.424908)
		(width 0.13208)
		(layer "B.Cu")
		(net "SMB_ISO_SSD9_SDA")
	)
	(segment
		(start 57.341262 -390.936734)
		(end 57.132982 -391.145014)
		(width 0.13208)
		(layer "F.Cu")
		(net "GPU_PEX_STRAP0_R")
	)
	(segment
		(start 57.132982 -391.145014)
		(end 56.418226 -391.145014)
		(width 0.13208)
		(layer "F.Cu")
		(net "GPU_PEX_STRAP0_R")
	)
	(segment
		(start 57.341262 -390.47166)
		(end 57.341262 -390.936734)
		(width 0.13208)
		(layer "F.Cu")
		(net "GPU_PEX_STRAP0_R")
	)
	(via
		(at 56.418226 -391.145014)
		(size 0.508)
		(drill 0.254)
		(layers "F.Cu" "B.Cu")
		(net "GPU_PEX_STRAP0_R")
	)
	(segment
		(start 50.217324 -393.165076)
		(end 52.237386 -391.145014)
		(width 0.15494)
		(layer "In9.Cu")
		(net "GPU_PEX_STRAP0_R")
	)
	(segment
		(start 46.609 -412.623)
		(end 47.105824 -413.119824)
		(width 0.15494)
		(layer "In9.Cu")
		(net "GPU_PEX_STRAP0_R")
	)
	(segment
		(start 50.217324 -412.628588)
		(end 50.217324 -393.165076)
		(width 0.15494)
		(layer "In9.Cu")
		(net "GPU_PEX_STRAP0_R")
	)
	(segment
		(start 52.237386 -391.145014)
		(end 56.418226 -391.145014)
		(width 0.15494)
		(layer "In9.Cu")
		(net "GPU_PEX_STRAP0_R")
	)
	(segment
		(start 46.609 -409.28925)
		(end 46.609 -412.623)
		(width 0.15494)
		(layer "In9.Cu")
		(net "GPU_PEX_STRAP0_R")
	)
	(segment
		(start 49.726088 -413.119824)
		(end 50.217324 -412.628588)
		(width 0.15494)
		(layer "In9.Cu")
		(net "GPU_PEX_STRAP0_R")
	)
	(segment
		(start 47.105824 -413.119824)
		(end 49.726088 -413.119824)
		(width 0.15494)
		(layer "In9.Cu")
		(net "GPU_PEX_STRAP0_R")
	)
	(segment
		(start 45.509942 -408.190192)
		(end 46.609 -409.28925)
		(width 0.15494)
		(layer "In9.Cu")
		(net "GPU_PEX_STRAP0_R")
	)
	(segment
		(start 204.93609 -288.830766)
		(end 204.93609 -288.221166)
		(width 0.13208)
		(layer "F.Cu")
		(net "SMB_PEX1_FPGA_SDA")
	)
	(segment
		(start 339.693758 -225.587052)
		(end 339.293962 -225.986848)
		(width 0.13208)
		(layer "F.Cu")
		(net "SMB_PEX1_FPGA_SDA")
	)
	(via
		(at 339.293962 -225.986848)
		(size 0.4572)
		(drill 0.254)
		(layers "F.Cu" "B.Cu")
		(net "SMB_PEX1_FPGA_SDA")
	)
	(via
		(at 206.727298 -212.127084)
		(size 0.508)
		(drill 0.254)
		(layers "F.Cu" "B.Cu")
		(net "SMB_PEX1_FPGA_SDA")
	)
	(via
		(at 204.93609 -288.221166)
		(size 0.508)
		(drill 0.254)
		(layers "F.Cu" "B.Cu")
		(net "SMB_PEX1_FPGA_SDA")
	)
	(segment
		(start 204.93609 -284.426152)
		(end 204.93609 -277.720044)
		(width 0.13208)
		(layer "B.Cu")
		(net "SMB_PEX1_FPGA_SDA")
	)
	(segment
		(start 205.4098 -284.888432)
		(end 205.4098 -284.696916)
		(width 0.13208)
		(layer "B.Cu")
		(net "SMB_PEX1_FPGA_SDA")
	)
	(segment
		(start 205.071472 -284.561534)
		(end 204.93609 -284.426152)
		(width 0.13208)
		(layer "B.Cu")
		(net "SMB_PEX1_FPGA_SDA")
	)
	(segment
		(start 201.03846 -226.207066)
		(end 201.03846 -217.796364)
		(width 0.13208)
		(layer "B.Cu")
		(net "SMB_PEX1_FPGA_SDA")
	)
	(segment
		(start 204.93609 -288.221166)
		(end 204.93609 -285.159196)
		(width 0.13208)
		(layer "B.Cu")
		(net "SMB_PEX1_FPGA_SDA")
	)
	(segment
		(start 201.03846 -217.796364)
		(end 206.70774 -212.127084)
		(width 0.13208)
		(layer "B.Cu")
		(net "SMB_PEX1_FPGA_SDA")
	)
	(segment
		(start 196.925184 -259.283708)
		(end 198.58736 -257.621532)
		(width 0.13208)
		(layer "B.Cu")
		(net "SMB_PEX1_FPGA_SDA")
	)
	(segment
		(start 200.660254 -273.444208)
		(end 200.660254 -272.033238)
		(width 0.13208)
		(layer "B.Cu")
		(net "SMB_PEX1_FPGA_SDA")
	)
	(segment
		(start 197.21322 -250.990608)
		(end 197.21322 -230.032306)
		(width 0.13208)
		(layer "B.Cu")
		(net "SMB_PEX1_FPGA_SDA")
	)
	(segment
		(start 201.458576 -255.235964)
		(end 197.21322 -250.990608)
		(width 0.13208)
		(layer "B.Cu")
		(net "SMB_PEX1_FPGA_SDA")
	)
	(segment
		(start 205.274418 -285.023814)
		(end 205.4098 -284.888432)
		(width 0.13208)
		(layer "B.Cu")
		(net "SMB_PEX1_FPGA_SDA")
	)
	(segment
		(start 199.738234 -257.621532)
		(end 201.458576 -255.90119)
		(width 0.13208)
		(layer "B.Cu")
		(net "SMB_PEX1_FPGA_SDA")
	)
	(segment
		(start 204.93609 -277.720044)
		(end 200.660254 -273.444208)
		(width 0.13208)
		(layer "B.Cu")
		(net "SMB_PEX1_FPGA_SDA")
	)
	(segment
		(start 201.458576 -255.90119)
		(end 201.458576 -255.235964)
		(width 0.13208)
		(layer "B.Cu")
		(net "SMB_PEX1_FPGA_SDA")
	)
	(segment
		(start 198.58736 -257.621532)
		(end 199.738234 -257.621532)
		(width 0.13208)
		(layer "B.Cu")
		(net "SMB_PEX1_FPGA_SDA")
	)
	(segment
		(start 200.660254 -272.033238)
		(end 196.925184 -268.298168)
		(width 0.13208)
		(layer "B.Cu")
		(net "SMB_PEX1_FPGA_SDA")
	)
	(segment
		(start 205.274418 -284.561534)
		(end 205.071472 -284.561534)
		(width 0.13208)
		(layer "B.Cu")
		(net "SMB_PEX1_FPGA_SDA")
	)
	(segment
		(start 197.21322 -230.032306)
		(end 201.03846 -226.207066)
		(width 0.13208)
		(layer "B.Cu")
		(net "SMB_PEX1_FPGA_SDA")
	)
	(segment
		(start 206.70774 -212.127084)
		(end 206.727298 -212.127084)
		(width 0.13208)
		(layer "B.Cu")
		(net "SMB_PEX1_FPGA_SDA")
	)
	(segment
		(start 205.4098 -284.696916)
		(end 205.274418 -284.561534)
		(width 0.13208)
		(layer "B.Cu")
		(net "SMB_PEX1_FPGA_SDA")
	)
	(segment
		(start 196.925184 -268.298168)
		(end 196.925184 -259.283708)
		(width 0.13208)
		(layer "B.Cu")
		(net "SMB_PEX1_FPGA_SDA")
	)
	(segment
		(start 204.93609 -285.159196)
		(end 205.071472 -285.023814)
		(width 0.13208)
		(layer "B.Cu")
		(net "SMB_PEX1_FPGA_SDA")
	)
	(segment
		(start 205.071472 -285.023814)
		(end 205.274418 -285.023814)
		(width 0.13208)
		(layer "B.Cu")
		(net "SMB_PEX1_FPGA_SDA")
	)
	(segment
		(start 259.29717 -225.02114)
		(end 261.64413 -225.02114)
		(width 0.15494)
		(layer "In13.Cu")
		(net "SMB_PEX1_FPGA_SDA")
	)
	(segment
		(start 206.727298 -212.127084)
		(end 207.569816 -212.127084)
		(width 0.15494)
		(layer "In13.Cu")
		(net "SMB_PEX1_FPGA_SDA")
	)
	(segment
		(start 244.291358 -217.686382)
		(end 244.291358 -220.356176)
		(width 0.15494)
		(layer "In13.Cu")
		(net "SMB_PEX1_FPGA_SDA")
	)
	(segment
		(start 225.19386 -209.3087)
		(end 230.197914 -209.3087)
		(width 0.15494)
		(layer "In13.Cu")
		(net "SMB_PEX1_FPGA_SDA")
	)
	(segment
		(start 300.355254 -232.3846)
		(end 302.120554 -232.3846)
		(width 0.15494)
		(layer "In13.Cu")
		(net "SMB_PEX1_FPGA_SDA")
	)
	(segment
		(start 208.000346 -213.248494)
		(end 209.756502 -215.00465)
		(width 0.15494)
		(layer "In13.Cu")
		(net "SMB_PEX1_FPGA_SDA")
	)
	(segment
		(start 338.892388 -227.838)
		(end 338.892388 -226.388422)
		(width 0.0889)
		(layer "In13.Cu")
		(net "SMB_PEX1_FPGA_SDA")
	)
	(segment
		(start 239.733074 -212.4202)
		(end 240.3602 -213.047326)
		(width 0.15494)
		(layer "In13.Cu")
		(net "SMB_PEX1_FPGA_SDA")
	)
	(segment
		(start 333.990696 -230.6066)
		(end 337.997546 -230.6066)
		(width 0.15494)
		(layer "In13.Cu")
		(net "SMB_PEX1_FPGA_SDA")
	)
	(segment
		(start 258.680204 -224.404174)
		(end 259.29717 -225.02114)
		(width 0.15494)
		(layer "In13.Cu")
		(net "SMB_PEX1_FPGA_SDA")
	)
	(segment
		(start 302.120554 -232.3846)
		(end 302.755554 -233.0196)
		(width 0.15494)
		(layer "In13.Cu")
		(net "SMB_PEX1_FPGA_SDA")
	)
	(segment
		(start 272.4658 -227.1776)
		(end 278.3586 -233.0704)
		(width 0.15494)
		(layer "In13.Cu")
		(net "SMB_PEX1_FPGA_SDA")
	)
	(segment
		(start 230.197914 -209.3087)
		(end 232.16362 -210.12277)
		(width 0.15494)
		(layer "In13.Cu")
		(net "SMB_PEX1_FPGA_SDA")
	)
	(segment
		(start 324.568566 -233.270806)
		(end 325.378572 -232.4608)
		(width 0.15494)
		(layer "In13.Cu")
		(net "SMB_PEX1_FPGA_SDA")
	)
	(segment
		(start 338.892388 -229.711758)
		(end 338.892388 -227.838)
		(width 0.15494)
		(layer "In13.Cu")
		(net "SMB_PEX1_FPGA_SDA")
	)
	(segment
		(start 303.8856 -233.0196)
		(end 304.546 -232.3592)
		(width 0.15494)
		(layer "In13.Cu")
		(net "SMB_PEX1_FPGA_SDA")
	)
	(segment
		(start 263.80059 -227.1776)
		(end 272.4658 -227.1776)
		(width 0.15494)
		(layer "In13.Cu")
		(net "SMB_PEX1_FPGA_SDA")
	)
	(segment
		(start 236.631988 -212.4202)
		(end 239.733074 -212.4202)
		(width 0.15494)
		(layer "In13.Cu")
		(net "SMB_PEX1_FPGA_SDA")
	)
	(segment
		(start 207.569816 -212.127084)
		(end 208.000346 -212.557614)
		(width 0.15494)
		(layer "In13.Cu")
		(net "SMB_PEX1_FPGA_SDA")
	)
	(segment
		(start 209.756502 -215.00465)
		(end 211.127594 -215.00465)
		(width 0.15494)
		(layer "In13.Cu")
		(net "SMB_PEX1_FPGA_SDA")
	)
	(segment
		(start 302.755554 -233.0196)
		(end 303.8856 -233.0196)
		(width 0.15494)
		(layer "In13.Cu")
		(net "SMB_PEX1_FPGA_SDA")
	)
	(segment
		(start 222.25 -211.4804)
		(end 222.26016 -211.4804)
		(width 0.15494)
		(layer "In13.Cu")
		(net "SMB_PEX1_FPGA_SDA")
	)
	(segment
		(start 243.393976 -216.789)
		(end 244.291358 -217.686382)
		(width 0.15494)
		(layer "In13.Cu")
		(net "SMB_PEX1_FPGA_SDA")
	)
	(segment
		(start 240.3602 -214.20836)
		(end 242.94084 -216.789)
		(width 0.15494)
		(layer "In13.Cu")
		(net "SMB_PEX1_FPGA_SDA")
	)
	(segment
		(start 222.3389 -211.40166)
		(end 223.1009 -211.40166)
		(width 0.15494)
		(layer "In13.Cu")
		(net "SMB_PEX1_FPGA_SDA")
	)
	(segment
		(start 261.64413 -225.02114)
		(end 263.80059 -227.1776)
		(width 0.15494)
		(layer "In13.Cu")
		(net "SMB_PEX1_FPGA_SDA")
	)
	(segment
		(start 248.339356 -224.404174)
		(end 258.680204 -224.404174)
		(width 0.15494)
		(layer "In13.Cu")
		(net "SMB_PEX1_FPGA_SDA")
	)
	(segment
		(start 324.167246 -233.270806)
		(end 324.568566 -233.270806)
		(width 0.15494)
		(layer "In13.Cu")
		(net "SMB_PEX1_FPGA_SDA")
	)
	(segment
		(start 208.000346 -212.557614)
		(end 208.000346 -213.248494)
		(width 0.15494)
		(layer "In13.Cu")
		(net "SMB_PEX1_FPGA_SDA")
	)
	(segment
		(start 234.334558 -210.12277)
		(end 236.631988 -212.4202)
		(width 0.15494)
		(layer "In13.Cu")
		(net "SMB_PEX1_FPGA_SDA")
	)
	(segment
		(start 223.1009 -211.40166)
		(end 225.19386 -209.3087)
		(width 0.15494)
		(layer "In13.Cu")
		(net "SMB_PEX1_FPGA_SDA")
	)
	(segment
		(start 332.619096 -231.9782)
		(end 333.990696 -230.6066)
		(width 0.15494)
		(layer "In13.Cu")
		(net "SMB_PEX1_FPGA_SDA")
	)
	(segment
		(start 278.3586 -233.0704)
		(end 299.669454 -233.0704)
		(width 0.15494)
		(layer "In13.Cu")
		(net "SMB_PEX1_FPGA_SDA")
	)
	(segment
		(start 211.127594 -215.00465)
		(end 211.361528 -214.770716)
		(width 0.15494)
		(layer "In13.Cu")
		(net "SMB_PEX1_FPGA_SDA")
	)
	(segment
		(start 299.669454 -233.0704)
		(end 300.355254 -232.3846)
		(width 0.15494)
		(layer "In13.Cu")
		(net "SMB_PEX1_FPGA_SDA")
	)
	(segment
		(start 338.892388 -226.388422)
		(end 339.293962 -225.986848)
		(width 0.0889)
		(layer "In13.Cu")
		(net "SMB_PEX1_FPGA_SDA")
	)
	(segment
		(start 232.16362 -210.12277)
		(end 234.334558 -210.12277)
		(width 0.15494)
		(layer "In13.Cu")
		(net "SMB_PEX1_FPGA_SDA")
	)
	(segment
		(start 325.378572 -232.4608)
		(end 327.3552 -232.4608)
		(width 0.15494)
		(layer "In13.Cu")
		(net "SMB_PEX1_FPGA_SDA")
	)
	(segment
		(start 211.361528 -214.770716)
		(end 218.959684 -214.770716)
		(width 0.15494)
		(layer "In13.Cu")
		(net "SMB_PEX1_FPGA_SDA")
	)
	(segment
		(start 322.655946 -232.3592)
		(end 323.036946 -232.7402)
		(width 0.15494)
		(layer "In13.Cu")
		(net "SMB_PEX1_FPGA_SDA")
	)
	(segment
		(start 218.959684 -214.770716)
		(end 222.25 -211.4804)
		(width 0.15494)
		(layer "In13.Cu")
		(net "SMB_PEX1_FPGA_SDA")
	)
	(segment
		(start 327.3552 -232.4608)
		(end 327.8378 -231.9782)
		(width 0.15494)
		(layer "In13.Cu")
		(net "SMB_PEX1_FPGA_SDA")
	)
	(segment
		(start 304.546 -232.3592)
		(end 322.655946 -232.3592)
		(width 0.15494)
		(layer "In13.Cu")
		(net "SMB_PEX1_FPGA_SDA")
	)
	(segment
		(start 242.94084 -216.789)
		(end 243.393976 -216.789)
		(width 0.15494)
		(layer "In13.Cu")
		(net "SMB_PEX1_FPGA_SDA")
	)
	(segment
		(start 240.3602 -213.047326)
		(end 240.3602 -214.20836)
		(width 0.15494)
		(layer "In13.Cu")
		(net "SMB_PEX1_FPGA_SDA")
	)
	(segment
		(start 244.291358 -220.356176)
		(end 248.339356 -224.404174)
		(width 0.15494)
		(layer "In13.Cu")
		(net "SMB_PEX1_FPGA_SDA")
	)
	(segment
		(start 327.8378 -231.9782)
		(end 332.619096 -231.9782)
		(width 0.15494)
		(layer "In13.Cu")
		(net "SMB_PEX1_FPGA_SDA")
	)
	(segment
		(start 323.036946 -232.7402)
		(end 323.635624 -232.7402)
		(width 0.15494)
		(layer "In13.Cu")
		(net "SMB_PEX1_FPGA_SDA")
	)
	(segment
		(start 323.635624 -232.7402)
		(end 324.167246 -233.270806)
		(width 0.15494)
		(layer "In13.Cu")
		(net "SMB_PEX1_FPGA_SDA")
	)
	(segment
		(start 222.26016 -211.4804)
		(end 222.3389 -211.40166)
		(width 0.15494)
		(layer "In13.Cu")
		(net "SMB_PEX1_FPGA_SDA")
	)
	(segment
		(start 337.997546 -230.6066)
		(end 338.892388 -229.711758)
		(width 0.15494)
		(layer "In13.Cu")
		(net "SMB_PEX1_FPGA_SDA")
	)
	(segment
		(start 347.693742 -218.387168)
		(end 348.093538 -217.987372)
		(width 0.13208)
		(layer "F.Cu")
		(net "NIC6_CLK_EN_N")
	)
	(segment
		(start 357.61295 -218.44)
		(end 356.997 -218.44)
		(width 0.13208)
		(layer "F.Cu")
		(net "NIC6_CLK_EN_N")
	)
	(via
		(at 356.997 -218.44)
		(size 0.508)
		(drill 0.254)
		(layers "F.Cu" "B.Cu")
		(net "NIC6_CLK_EN_N")
	)
	(via
		(at 348.093538 -217.987372)
		(size 0.4572)
		(drill 0.254)
		(layers "F.Cu" "B.Cu")
		(net "NIC6_CLK_EN_N")
	)
	(segment
		(start 356.176834 -217.619834)
		(end 356.997 -218.44)
		(width 0.15494)
		(layer "In9.Cu")
		(net "NIC6_CLK_EN_N")
	)
	(segment
		(start 353.698302 -218.3892)
		(end 354.467668 -217.619834)
		(width 0.15494)
		(layer "In9.Cu")
		(net "NIC6_CLK_EN_N")
	)
	(segment
		(start 354.467668 -217.619834)
		(end 356.176834 -217.619834)
		(width 0.15494)
		(layer "In9.Cu")
		(net "NIC6_CLK_EN_N")
	)
	(segment
		(start 348.495366 -218.3892)
		(end 353.698302 -218.3892)
		(width 0.0889)
		(layer "In9.Cu")
		(net "NIC6_CLK_EN_N")
	)
	(segment
		(start 348.093538 -217.987372)
		(end 348.495366 -218.3892)
		(width 0.0889)
		(layer "In9.Cu")
		(net "NIC6_CLK_EN_N")
	)
	(segment
		(start 102.479856 -51.670966)
		(end 103.131366 -51.019456)
		(width 0.13208)
		(layer "F.Cu")
		(net "P12V_SSD3_SS")
	)
	(segment
		(start 103.131366 -51.019456)
		(end 103.867712 -51.019456)
		(width 0.13208)
		(layer "F.Cu")
		(net "P12V_SSD3_SS")
	)
	(segment
		(start 102.330504 -53.144166)
		(end 102.479856 -52.994814)
		(width 0.13208)
		(layer "F.Cu")
		(net "P12V_SSD3_SS")
	)
	(segment
		(start 102.479856 -52.994814)
		(end 102.479856 -51.670966)
		(width 0.13208)
		(layer "F.Cu")
		(net "P12V_SSD3_SS")
	)
	(segment
		(start 102.147116 -53.144166)
		(end 102.330504 -53.144166)
		(width 0.13208)
		(layer "F.Cu")
		(net "P12V_SSD3_SS")
	)
	(via
		(at 103.131366 -51.019456)
		(size 0.508)
		(drill 0.254)
		(layers "F.Cu" "B.Cu")
		(net "P12V_SSD3_SS")
	)
	(segment
		(start 425.056046 -53.96357)
		(end 425.454064 -53.96357)
		(width 0.13208)
		(layer "F.Cu")
		(net "P12V_SSD14_OCP")
	)
	(segment
		(start 424.447208 -54.144164)
		(end 424.875452 -54.144164)
		(width 0.13208)
		(layer "F.Cu")
		(net "P12V_SSD14_OCP")
	)
	(segment
		(start 424.875452 -54.144164)
		(end 425.056046 -53.96357)
		(width 0.13208)
		(layer "F.Cu")
		(net "P12V_SSD14_OCP")
	)
	(segment
		(start 426.167804 -54.067456)
		(end 426.063918 -53.96357)
		(width 0.13208)
		(layer "F.Cu")
		(net "P12V_SSD14_OCP")
	)
	(segment
		(start 426.063918 -53.96357)
		(end 425.454064 -53.96357)
		(width 0.13208)
		(layer "F.Cu")
		(net "P12V_SSD14_OCP")
	)
	(via
		(at 425.454064 -53.96357)
		(size 0.508)
		(drill 0.254)
		(layers "F.Cu" "B.Cu")
		(net "P12V_SSD14_OCP")
	)
	(segment
		(start 135.029448 -90.624152)
		(end 133.763258 -91.890342)
		(width 0.13208)
		(layer "F.Cu")
		(net "SMB_BIC_I2C9_MUX0_SSD5_SDA")
	)
	(segment
		(start 135.613648 -90.099642)
		(end 135.499094 -89.985088)
		(width 0.13208)
		(layer "F.Cu")
		(net "SMB_BIC_I2C9_MUX0_SSD5_SDA")
	)
	(segment
		(start 133.763258 -91.890342)
		(end 133.062726 -91.890342)
		(width 0.13208)
		(layer "F.Cu")
		(net "SMB_BIC_I2C9_MUX0_SSD5_SDA")
	)
	(segment
		(start 135.499094 -89.985088)
		(end 135.029448 -89.985088)
		(width 0.13208)
		(layer "F.Cu")
		(net "SMB_BIC_I2C9_MUX0_SSD5_SDA")
	)
	(segment
		(start 135.029448 -89.985088)
		(end 135.029448 -90.624152)
		(width 0.13208)
		(layer "F.Cu")
		(net "SMB_BIC_I2C9_MUX0_SSD5_SDA")
	)
	(segment
		(start 136.045194 -90.099642)
		(end 135.613648 -90.099642)
		(width 0.13208)
		(layer "F.Cu")
		(net "SMB_BIC_I2C9_MUX0_SSD5_SDA")
	)
	(via
		(at 135.029448 -89.985088)
		(size 0.508)
		(drill 0.254)
		(layers "F.Cu" "B.Cu")
		(net "SMB_BIC_I2C9_MUX0_SSD5_SDA")
	)
	(segment
		(start 55.348124 -363.334808)
		(end 54.994048 -362.980732)
		(width 0.13462)
		(layer "F.Cu")
		(net "USB2_GPU_HMC_DN")
	)
	(segment
		(start 54.994048 -362.980732)
		(end 54.404514 -362.980732)
		(width 0.13462)
		(layer "F.Cu")
		(net "USB2_GPU_HMC_DN")
	)
	(via
		(at 52.84089 -385.19481)
		(size 0.4064)
		(drill 0.2032)
		(layers "F.Cu" "B.Cu")
		(net "USB2_GPU_HMC_DN")
	)
	(via
		(at 55.348124 -363.334808)
		(size 0.508)
		(drill 0.254)
		(layers "F.Cu" "B.Cu")
		(net "USB2_GPU_HMC_DN")
	)
	(segment
		(start 50.29454 -392.387582)
		(end 50.29454 -392.387328)
		(width 0.13462)
		(layer "B.Cu")
		(net "USB2_GPU_HMC_DN")
	)
	(segment
		(start 46.911006 -396.872968)
		(end 46.911006 -395.771116)
		(width 0.13462)
		(layer "B.Cu")
		(net "USB2_GPU_HMC_DN")
	)
	(segment
		(start 52.84089 -385.19481)
		(end 52.84089 -364.361222)
		(width 0.13462)
		(layer "B.Cu")
		(net "USB2_GPU_HMC_DN")
	)
	(segment
		(start 50.29454 -392.387328)
		(end 52.84089 -389.841232)
		(width 0.13462)
		(layer "B.Cu")
		(net "USB2_GPU_HMC_DN")
	)
	(segment
		(start 54.155594 -363.046518)
		(end 55.059834 -363.046518)
		(width 0.13462)
		(layer "B.Cu")
		(net "USB2_GPU_HMC_DN")
	)
	(segment
		(start 45.509942 -397.790162)
		(end 46.00321 -397.296894)
		(width 0.13462)
		(layer "B.Cu")
		(net "USB2_GPU_HMC_DN")
	)
	(segment
		(start 52.84089 -389.841232)
		(end 52.84089 -385.19481)
		(width 0.13462)
		(layer "B.Cu")
		(net "USB2_GPU_HMC_DN")
	)
	(segment
		(start 55.059834 -363.046518)
		(end 55.348124 -363.334808)
		(width 0.13462)
		(layer "B.Cu")
		(net "USB2_GPU_HMC_DN")
	)
	(segment
		(start 52.84089 -364.361222)
		(end 54.155594 -363.046518)
		(width 0.13462)
		(layer "B.Cu")
		(net "USB2_GPU_HMC_DN")
	)
	(segment
		(start 46.48708 -397.296894)
		(end 46.911006 -396.872968)
		(width 0.13462)
		(layer "B.Cu")
		(net "USB2_GPU_HMC_DN")
	)
	(segment
		(start 46.00321 -397.296894)
		(end 46.48708 -397.296894)
		(width 0.13462)
		(layer "B.Cu")
		(net "USB2_GPU_HMC_DN")
	)
	(segment
		(start 46.911006 -395.771116)
		(end 50.29454 -392.387582)
		(width 0.13462)
		(layer "B.Cu")
		(net "USB2_GPU_HMC_DN")
	)
	(segment
		(start 348.493842 -226.387152)
		(end 348.893638 -226.786948)
		(width 0.13208)
		(layer "F.Cu")
		(net "RST_SSD7_PERST_N")
	)
	(via
		(at 348.893638 -226.786948)
		(size 0.4572)
		(drill 0.254)
		(layers "F.Cu" "B.Cu")
		(net "RST_SSD7_PERST_N")
	)
	(via
		(at 349.123 -231.648)
		(size 0.6604)
		(drill 0.3302)
		(layers "F.Cu" "B.Cu")
		(net "RST_SSD7_PERST_N")
	)
	(segment
		(start 349.377 -230.049578)
		(end 348.893638 -228.882194)
		(width 0.13208)
		(layer "B.Cu")
		(net "RST_SSD7_PERST_N")
	)
	(segment
		(start 349.123 -231.648)
		(end 349.377 -231.394)
		(width 0.13208)
		(layer "B.Cu")
		(net "RST_SSD7_PERST_N")
	)
	(segment
		(start 348.893638 -228.882194)
		(end 348.893638 -226.786948)
		(width 0.13208)
		(layer "B.Cu")
		(net "RST_SSD7_PERST_N")
	)
	(segment
		(start 349.377 -231.394)
		(end 349.377 -230.049578)
		(width 0.13208)
		(layer "B.Cu")
		(net "RST_SSD7_PERST_N")
	)
	(segment
		(start 349.123 -232.13695)
		(end 349.123 -231.648)
		(width 0.13208)
		(layer "B.Cu")
		(net "RST_SSD7_PERST_N")
	)
	(segment
		(start 348.107 -233.15295)
		(end 349.123 -232.13695)
		(width 0.13208)
		(layer "B.Cu")
		(net "RST_SSD7_PERST_N")
	)
	(segment
		(start 347.693742 -216.786968)
		(end 348.093538 -216.387172)
		(width 0.13208)
		(layer "F.Cu")
		(net "RST_PEX_NIC2_PERST_R_N")
	)
	(segment
		(start 381.31496 -200.099676)
		(end 381.65405 -199.760586)
		(width 0.13208)
		(layer "F.Cu")
		(net "RST_PEX_NIC2_PERST_R_N")
	)
	(segment
		(start 380.906782 -200.099676)
		(end 381.31496 -200.099676)
		(width 0.13208)
		(layer "F.Cu")
		(net "RST_PEX_NIC2_PERST_R_N")
	)
	(segment
		(start 381.65405 -198.374)
		(end 381.65405 -199.39)
		(width 0.13208)
		(layer "F.Cu")
		(net "RST_PEX_NIC2_PERST_R_N")
	)
	(segment
		(start 381.65405 -199.760586)
		(end 381.65405 -199.39)
		(width 0.13208)
		(layer "F.Cu")
		(net "RST_PEX_NIC2_PERST_R_N")
	)
	(via
		(at 369.610386 -193.983356)
		(size 0.508)
		(drill 0.254)
		(layers "F.Cu" "B.Cu")
		(net "RST_PEX_NIC2_PERST_R_N")
	)
	(via
		(at 348.093538 -216.387172)
		(size 0.4572)
		(drill 0.254)
		(layers "F.Cu" "B.Cu")
		(net "RST_PEX_NIC2_PERST_R_N")
	)
	(via
		(at 380.906782 -200.099676)
		(size 0.508)
		(drill 0.254)
		(layers "F.Cu" "B.Cu")
		(net "RST_PEX_NIC2_PERST_R_N")
	)
	(segment
		(start 355.567488 -207.430624)
		(end 357.697024 -206.548736)
		(width 0.15494)
		(layer "In7.Cu")
		(net "RST_PEX_NIC2_PERST_R_N")
	)
	(segment
		(start 368.173 -196.834506)
		(end 368.502692 -196.504814)
		(width 0.15494)
		(layer "In7.Cu")
		(net "RST_PEX_NIC2_PERST_R_N")
	)
	(segment
		(start 350.788224 -215.987122)
		(end 350.90862 -215.866726)
		(width 0.15494)
		(layer "In7.Cu")
		(net "RST_PEX_NIC2_PERST_R_N")
	)
	(segment
		(start 361.364022 -202.718924)
		(end 362.968286 -202.718924)
		(width 0.15494)
		(layer "In7.Cu")
		(net "RST_PEX_NIC2_PERST_R_N")
	)
	(segment
		(start 353.6188 -209.379312)
		(end 355.567488 -207.430624)
		(width 0.15494)
		(layer "In7.Cu")
		(net "RST_PEX_NIC2_PERST_R_N")
	)
	(segment
		(start 348.093538 -216.387172)
		(end 348.493588 -215.987122)
		(width 0.0889)
		(layer "In7.Cu")
		(net "RST_PEX_NIC2_PERST_R_N")
	)
	(segment
		(start 361.249976 -202.995784)
		(end 361.249976 -202.83297)
		(width 0.15494)
		(layer "In7.Cu")
		(net "RST_PEX_NIC2_PERST_R_N")
	)
	(segment
		(start 362.968286 -202.718924)
		(end 368.173 -197.51421)
		(width 0.15494)
		(layer "In7.Cu")
		(net "RST_PEX_NIC2_PERST_R_N")
	)
	(segment
		(start 357.697024 -206.548736)
		(end 361.249976 -202.995784)
		(width 0.15494)
		(layer "In7.Cu")
		(net "RST_PEX_NIC2_PERST_R_N")
	)
	(segment
		(start 351.721674 -215.866726)
		(end 353.6188 -213.9696)
		(width 0.15494)
		(layer "In7.Cu")
		(net "RST_PEX_NIC2_PERST_R_N")
	)
	(segment
		(start 350.90862 -215.866726)
		(end 351.721674 -215.866726)
		(width 0.15494)
		(layer "In7.Cu")
		(net "RST_PEX_NIC2_PERST_R_N")
	)
	(segment
		(start 368.502692 -195.09105)
		(end 369.610386 -193.983356)
		(width 0.15494)
		(layer "In7.Cu")
		(net "RST_PEX_NIC2_PERST_R_N")
	)
	(segment
		(start 348.493588 -215.987122)
		(end 350.788224 -215.987122)
		(width 0.0889)
		(layer "In7.Cu")
		(net "RST_PEX_NIC2_PERST_R_N")
	)
	(segment
		(start 368.502692 -196.504814)
		(end 368.502692 -195.09105)
		(width 0.15494)
		(layer "In7.Cu")
		(net "RST_PEX_NIC2_PERST_R_N")
	)
	(segment
		(start 361.249976 -202.83297)
		(end 361.364022 -202.718924)
		(width 0.15494)
		(layer "In7.Cu")
		(net "RST_PEX_NIC2_PERST_R_N")
	)
	(segment
		(start 353.6188 -213.9696)
		(end 353.6188 -209.379312)
		(width 0.15494)
		(layer "In7.Cu")
		(net "RST_PEX_NIC2_PERST_R_N")
	)
	(segment
		(start 368.173 -197.51421)
		(end 368.173 -196.834506)
		(width 0.15494)
		(layer "In7.Cu")
		(net "RST_PEX_NIC2_PERST_R_N")
	)
	(segment
		(start 378.179076 -196.907912)
		(end 376.132852 -194.861688)
		(width 0.15494)
		(layer "In13.Cu")
		(net "RST_PEX_NIC2_PERST_R_N")
	)
	(segment
		(start 369.61064 -193.983102)
		(end 369.610386 -193.983356)
		(width 0.15494)
		(layer "In13.Cu")
		(net "RST_PEX_NIC2_PERST_R_N")
	)
	(segment
		(start 380.906782 -200.099676)
		(end 380.083822 -200.099676)
		(width 0.15494)
		(layer "In13.Cu")
		(net "RST_PEX_NIC2_PERST_R_N")
	)
	(segment
		(start 378.179076 -198.19493)
		(end 378.179076 -196.907912)
		(width 0.15494)
		(layer "In13.Cu")
		(net "RST_PEX_NIC2_PERST_R_N")
	)
	(segment
		(start 376.132852 -194.861688)
		(end 370.95049 -194.861688)
		(width 0.15494)
		(layer "In13.Cu")
		(net "RST_PEX_NIC2_PERST_R_N")
	)
	(segment
		(start 370.95049 -194.861688)
		(end 370.071904 -193.983102)
		(width 0.15494)
		(layer "In13.Cu")
		(net "RST_PEX_NIC2_PERST_R_N")
	)
	(segment
		(start 380.083822 -200.099676)
		(end 378.179076 -198.19493)
		(width 0.15494)
		(layer "In13.Cu")
		(net "RST_PEX_NIC2_PERST_R_N")
	)
	(segment
		(start 370.071904 -193.983102)
		(end 369.61064 -193.983102)
		(width 0.15494)
		(layer "In13.Cu")
		(net "RST_PEX_NIC2_PERST_R_N")
	)
	(segment
		(start 218.247214 -53.144166)
		(end 218.430602 -53.144166)
		(width 0.13208)
		(layer "F.Cu")
		(net "P12V_SSD7_SS")
	)
	(segment
		(start 218.579954 -52.994814)
		(end 218.579954 -51.670966)
		(width 0.13208)
		(layer "F.Cu")
		(net "P12V_SSD7_SS")
	)
	(segment
		(start 219.231464 -51.019456)
		(end 219.96781 -51.019456)
		(width 0.13208)
		(layer "F.Cu")
		(net "P12V_SSD7_SS")
	)
	(segment
		(start 218.430602 -53.144166)
		(end 218.579954 -52.994814)
		(width 0.13208)
		(layer "F.Cu")
		(net "P12V_SSD7_SS")
	)
	(segment
		(start 218.579954 -51.670966)
		(end 219.231464 -51.019456)
		(width 0.13208)
		(layer "F.Cu")
		(net "P12V_SSD7_SS")
	)
	(via
		(at 219.231464 -51.019456)
		(size 0.508)
		(drill 0.254)
		(layers "F.Cu" "B.Cu")
		(net "P12V_SSD7_SS")
	)
	(segment
		(start 135.119364 -87.813642)
		(end 133.702552 -89.230454)
		(width 0.13208)
		(layer "F.Cu")
		(net "SMB_BIC_I2C9_MUX0_SSD4_SDA")
	)
	(segment
		(start 133.8326 -89.360502)
		(end 133.8326 -90.46337)
		(width 0.13208)
		(layer "F.Cu")
		(net "SMB_BIC_I2C9_MUX0_SSD4_SDA")
	)
	(segment
		(start 133.8326 -90.46337)
		(end 133.7056 -90.59037)
		(width 0.13208)
		(layer "F.Cu")
		(net "SMB_BIC_I2C9_MUX0_SSD4_SDA")
	)
	(segment
		(start 133.702552 -89.230454)
		(end 133.8326 -89.360502)
		(width 0.13208)
		(layer "F.Cu")
		(net "SMB_BIC_I2C9_MUX0_SSD4_SDA")
	)
	(segment
		(start 133.7056 -90.59037)
		(end 133.062726 -90.59037)
		(width 0.13208)
		(layer "F.Cu")
		(net "SMB_BIC_I2C9_MUX0_SSD4_SDA")
	)
	(segment
		(start 136.045194 -87.813642)
		(end 135.119364 -87.813642)
		(width 0.13208)
		(layer "F.Cu")
		(net "SMB_BIC_I2C9_MUX0_SSD4_SDA")
	)
	(via
		(at 133.702552 -89.230454)
		(size 0.508)
		(drill 0.254)
		(layers "F.Cu" "B.Cu")
		(net "SMB_BIC_I2C9_MUX0_SSD4_SDA")
	)
	(segment
		(start 330.542392 -240.848896)
		(end 330.542392 -241.515392)
		(width 0.13208)
		(layer "F.Cu")
		(net "RST_MB_PERST_1_ISO_N")
	)
	(segment
		(start 332.613 -238.825278)
		(end 333.540608 -237.89767)
		(width 0.13208)
		(layer "F.Cu")
		(net "RST_MB_PERST_1_ISO_N")
	)
	(segment
		(start 333.540608 -237.89767)
		(end 333.540608 -237.271306)
		(width 0.13208)
		(layer "F.Cu")
		(net "RST_MB_PERST_1_ISO_N")
	)
	(segment
		(start 330.63942 -241.61242)
		(end 332.400148 -241.61242)
		(width 0.13208)
		(layer "F.Cu")
		(net "RST_MB_PERST_1_ISO_N")
	)
	(segment
		(start 332.400148 -241.61242)
		(end 332.613 -241.399568)
		(width 0.13208)
		(layer "F.Cu")
		(net "RST_MB_PERST_1_ISO_N")
	)
	(segment
		(start 332.613 -241.399568)
		(end 332.613 -238.825278)
		(width 0.13208)
		(layer "F.Cu")
		(net "RST_MB_PERST_1_ISO_N")
	)
	(segment
		(start 330.542392 -241.515392)
		(end 330.63942 -241.61242)
		(width 0.13208)
		(layer "F.Cu")
		(net "RST_MB_PERST_1_ISO_N")
	)
	(via
		(at 333.540608 -237.89767)
		(size 0.508)
		(drill 0.254)
		(layers "F.Cu" "B.Cu")
		(net "RST_MB_PERST_1_ISO_N")
	)
	(segment
		(start 439.168032 -288.221166)
		(end 439.168032 -288.830766)
		(width 0.13208)
		(layer "F.Cu")
		(net "SMB_PEX3_FPGA_SCL")
	)
	(segment
		(start 340.493858 -226.387152)
		(end 340.094062 -226.786948)
		(width 0.13208)
		(layer "F.Cu")
		(net "SMB_PEX3_FPGA_SCL")
	)
	(via
		(at 365.9378 -249.367802)
		(size 0.508)
		(drill 0.254)
		(layers "F.Cu" "B.Cu")
		(net "SMB_PEX3_FPGA_SCL")
	)
	(via
		(at 439.168032 -288.221166)
		(size 0.508)
		(drill 0.254)
		(layers "F.Cu" "B.Cu")
		(net "SMB_PEX3_FPGA_SCL")
	)
	(via
		(at 340.094062 -226.786948)
		(size 0.4572)
		(drill 0.254)
		(layers "F.Cu" "B.Cu")
		(net "SMB_PEX3_FPGA_SCL")
	)
	(via
		(at 447.091054 -252.08865)
		(size 0.508)
		(drill 0.254)
		(layers "F.Cu" "B.Cu")
		(net "SMB_PEX3_FPGA_SCL")
	)
	(segment
		(start 437.90743 -288.670238)
		(end 437.671972 -288.43478)
		(width 0.13208)
		(layer "B.Cu")
		(net "SMB_PEX3_FPGA_SCL")
	)
	(segment
		(start 437.671972 -285.361634)
		(end 443.025784 -280.007822)
		(width 0.13208)
		(layer "B.Cu")
		(net "SMB_PEX3_FPGA_SCL")
	)
	(segment
		(start 438.71896 -288.670238)
		(end 437.90743 -288.670238)
		(width 0.13208)
		(layer "B.Cu")
		(net "SMB_PEX3_FPGA_SCL")
	)
	(segment
		(start 437.671972 -288.43478)
		(end 437.671972 -285.361634)
		(width 0.13208)
		(layer "B.Cu")
		(net "SMB_PEX3_FPGA_SCL")
	)
	(segment
		(start 439.168032 -288.221166)
		(end 438.71896 -288.670238)
		(width 0.13208)
		(layer "B.Cu")
		(net "SMB_PEX3_FPGA_SCL")
	)
	(segment
		(start 443.025784 -280.007822)
		(end 443.025784 -255.078992)
		(width 0.13208)
		(layer "B.Cu")
		(net "SMB_PEX3_FPGA_SCL")
	)
	(segment
		(start 446.016126 -252.08865)
		(end 447.091054 -252.08865)
		(width 0.13208)
		(layer "B.Cu")
		(net "SMB_PEX3_FPGA_SCL")
	)
	(segment
		(start 443.025784 -255.078992)
		(end 446.016126 -252.08865)
		(width 0.13208)
		(layer "B.Cu")
		(net "SMB_PEX3_FPGA_SCL")
	)
	(segment
		(start 339.49513 -234.733592)
		(end 339.85581 -234.372912)
		(width 0.15494)
		(layer "In5.Cu")
		(net "SMB_PEX3_FPGA_SCL")
	)
	(segment
		(start 364.538006 -245.561104)
		(end 359.621836 -240.644934)
		(width 0.15494)
		(layer "In5.Cu")
		(net "SMB_PEX3_FPGA_SCL")
	)
	(segment
		(start 364.538006 -248.785888)
		(end 364.538006 -245.561104)
		(width 0.15494)
		(layer "In5.Cu")
		(net "SMB_PEX3_FPGA_SCL")
	)
	(segment
		(start 343.52611 -240.644934)
		(end 339.49513 -236.613954)
		(width 0.15494)
		(layer "In5.Cu")
		(net "SMB_PEX3_FPGA_SCL")
	)
	(segment
		(start 339.85581 -234.372912)
		(end 339.85581 -228.34473)
		(width 0.15494)
		(layer "In5.Cu")
		(net "SMB_PEX3_FPGA_SCL")
	)
	(segment
		(start 339.85581 -228.34473)
		(end 340.094062 -228.106478)
		(width 0.15494)
		(layer "In5.Cu")
		(net "SMB_PEX3_FPGA_SCL")
	)
	(segment
		(start 340.094062 -228.106478)
		(end 340.094062 -226.786948)
		(width 0.15494)
		(layer "In5.Cu")
		(net "SMB_PEX3_FPGA_SCL")
	)
	(segment
		(start 339.49513 -236.613954)
		(end 339.49513 -234.733592)
		(width 0.15494)
		(layer "In5.Cu")
		(net "SMB_PEX3_FPGA_SCL")
	)
	(segment
		(start 359.621836 -240.644934)
		(end 343.52611 -240.644934)
		(width 0.15494)
		(layer "In5.Cu")
		(net "SMB_PEX3_FPGA_SCL")
	)
	(segment
		(start 365.9378 -249.367802)
		(end 365.11992 -249.367802)
		(width 0.15494)
		(layer "In5.Cu")
		(net "SMB_PEX3_FPGA_SCL")
	)
	(segment
		(start 365.11992 -249.367802)
		(end 364.538006 -248.785888)
		(width 0.15494)
		(layer "In5.Cu")
		(net "SMB_PEX3_FPGA_SCL")
	)
	(segment
		(start 370.195602 -249.367802)
		(end 365.9378 -249.367802)
		(width 0.15494)
		(layer "In13.Cu")
		(net "SMB_PEX3_FPGA_SCL")
	)
	(segment
		(start 386.838444 -245.81993)
		(end 386.838444 -246.621554)
		(width 0.15494)
		(layer "In13.Cu")
		(net "SMB_PEX3_FPGA_SCL")
	)
	(segment
		(start 447.091054 -252.08865)
		(end 447.091054 -250.673108)
		(width 0.15494)
		(layer "In13.Cu")
		(net "SMB_PEX3_FPGA_SCL")
	)
	(segment
		(start 447.091054 -250.673108)
		(end 443.550802 -247.132856)
		(width 0.15494)
		(layer "In13.Cu")
		(net "SMB_PEX3_FPGA_SCL")
	)
	(segment
		(start 385.528566 -247.931432)
		(end 385.528566 -249.24258)
		(width 0.15494)
		(layer "In13.Cu")
		(net "SMB_PEX3_FPGA_SCL")
	)
	(segment
		(start 386.838444 -246.621554)
		(end 385.528566 -247.931432)
		(width 0.15494)
		(layer "In13.Cu")
		(net "SMB_PEX3_FPGA_SCL")
	)
	(segment
		(start 389.90651 -247.132856)
		(end 388.288784 -245.51513)
		(width 0.15494)
		(layer "In13.Cu")
		(net "SMB_PEX3_FPGA_SCL")
	)
	(segment
		(start 385.528566 -249.24258)
		(end 384.174746 -250.5964)
		(width 0.15494)
		(layer "In13.Cu")
		(net "SMB_PEX3_FPGA_SCL")
	)
	(segment
		(start 384.174746 -250.5964)
		(end 371.4242 -250.5964)
		(width 0.15494)
		(layer "In13.Cu")
		(net "SMB_PEX3_FPGA_SCL")
	)
	(segment
		(start 371.4242 -250.5964)
		(end 370.195602 -249.367802)
		(width 0.15494)
		(layer "In13.Cu")
		(net "SMB_PEX3_FPGA_SCL")
	)
	(segment
		(start 388.288784 -245.51513)
		(end 387.143244 -245.51513)
		(width 0.15494)
		(layer "In13.Cu")
		(net "SMB_PEX3_FPGA_SCL")
	)
	(segment
		(start 443.550802 -247.132856)
		(end 389.90651 -247.132856)
		(width 0.15494)
		(layer "In13.Cu")
		(net "SMB_PEX3_FPGA_SCL")
	)
	(segment
		(start 387.143244 -245.51513)
		(end 386.838444 -245.81993)
		(width 0.15494)
		(layer "In13.Cu")
		(net "SMB_PEX3_FPGA_SCL")
	)
	(segment
		(start 350.093788 -216.786968)
		(end 350.493584 -216.387172)
		(width 0.13208)
		(layer "F.Cu")
		(net "NIC7_MAIN_PWR_EN")
	)
	(via
		(at 418.80409 -99.187)
		(size 0.508)
		(drill 0.254)
		(layers "F.Cu" "B.Cu")
		(net "NIC7_MAIN_PWR_EN")
	)
	(via
		(at 365.892842 -97.217738)
		(size 0.508)
		(drill 0.254)
		(layers "F.Cu" "B.Cu")
		(net "NIC7_MAIN_PWR_EN")
	)
	(via
		(at 350.493584 -216.387172)
		(size 0.4572)
		(drill 0.254)
		(layers "F.Cu" "B.Cu")
		(net "NIC7_MAIN_PWR_EN")
	)
	(segment
		(start 418.80409 -98.552)
		(end 418.80409 -99.187)
		(width 0.13208)
		(layer "B.Cu")
		(net "NIC7_MAIN_PWR_EN")
	)
	(segment
		(start 419.65499 -98.552)
		(end 418.80409 -98.552)
		(width 0.13208)
		(layer "B.Cu")
		(net "NIC7_MAIN_PWR_EN")
	)
	(segment
		(start 349.770954 -158.766256)
		(end 349.770954 -162.605466)
		(width 0.15494)
		(layer "In5.Cu")
		(net "NIC7_MAIN_PWR_EN")
	)
	(segment
		(start 364.33379 -206.134462)
		(end 363.2454 -207.222852)
		(width 0.15494)
		(layer "In5.Cu")
		(net "NIC7_MAIN_PWR_EN")
	)
	(segment
		(start 365.892842 -97.217738)
		(end 362.183426 -100.927154)
		(width 0.15494)
		(layer "In5.Cu")
		(net "NIC7_MAIN_PWR_EN")
	)
	(segment
		(start 351.30105 -215.871806)
		(end 351.00895 -215.871806)
		(width 0.15494)
		(layer "In5.Cu")
		(net "NIC7_MAIN_PWR_EN")
	)
	(segment
		(start 367.511838 -203.611734)
		(end 364.98911 -206.134462)
		(width 0.15494)
		(layer "In5.Cu")
		(net "NIC7_MAIN_PWR_EN")
	)
	(segment
		(start 349.770954 -162.605466)
		(end 350.50476 -163.339272)
		(width 0.15494)
		(layer "In5.Cu")
		(net "NIC7_MAIN_PWR_EN")
	)
	(segment
		(start 361.433364 -173.494954)
		(end 361.433364 -177.166778)
		(width 0.15494)
		(layer "In5.Cu")
		(net "NIC7_MAIN_PWR_EN")
	)
	(segment
		(start 363.785404 -179.518818)
		(end 365.00943 -179.518818)
		(width 0.15494)
		(layer "In5.Cu")
		(net "NIC7_MAIN_PWR_EN")
	)
	(segment
		(start 368.308128 -182.817516)
		(end 368.308128 -193.480182)
		(width 0.15494)
		(layer "In5.Cu")
		(net "NIC7_MAIN_PWR_EN")
	)
	(segment
		(start 353.957636 -213.21522)
		(end 351.30105 -215.871806)
		(width 0.15494)
		(layer "In5.Cu")
		(net "NIC7_MAIN_PWR_EN")
	)
	(segment
		(start 354.67798 -213.21522)
		(end 353.957636 -213.21522)
		(width 0.15494)
		(layer "In5.Cu")
		(net "NIC7_MAIN_PWR_EN")
	)
	(segment
		(start 353.113594 -163.339272)
		(end 353.750118 -163.975796)
		(width 0.15494)
		(layer "In5.Cu")
		(net "NIC7_MAIN_PWR_EN")
	)
	(segment
		(start 353.750118 -165.231318)
		(end 354.61702 -166.09822)
		(width 0.15494)
		(layer "In5.Cu")
		(net "NIC7_MAIN_PWR_EN")
	)
	(segment
		(start 349.801688 -128.620266)
		(end 349.801688 -140.338556)
		(width 0.15494)
		(layer "In5.Cu")
		(net "NIC7_MAIN_PWR_EN")
	)
	(segment
		(start 349.801688 -140.338556)
		(end 350.74606 -141.282928)
		(width 0.15494)
		(layer "In5.Cu")
		(net "NIC7_MAIN_PWR_EN")
	)
	(segment
		(start 358.0257 -211.3915)
		(end 356.5017 -211.3915)
		(width 0.15494)
		(layer "In5.Cu")
		(net "NIC7_MAIN_PWR_EN")
	)
	(segment
		(start 369.987322 -195.159376)
		(end 369.987322 -202.096878)
		(width 0.15494)
		(layer "In5.Cu")
		(net "NIC7_MAIN_PWR_EN")
	)
	(segment
		(start 355.3714 -166.42334)
		(end 355.3714 -167.43299)
		(width 0.15494)
		(layer "In5.Cu")
		(net "NIC7_MAIN_PWR_EN")
	)
	(segment
		(start 360.241342 -210.8073)
		(end 358.6099 -210.8073)
		(width 0.15494)
		(layer "In5.Cu")
		(net "NIC7_MAIN_PWR_EN")
	)
	(segment
		(start 355.3714 -167.43299)
		(end 361.433364 -173.494954)
		(width 0.15494)
		(layer "In5.Cu")
		(net "NIC7_MAIN_PWR_EN")
	)
	(segment
		(start 361.433364 -177.166778)
		(end 363.785404 -179.518818)
		(width 0.15494)
		(layer "In5.Cu")
		(net "NIC7_MAIN_PWR_EN")
	)
	(segment
		(start 350.74606 -141.282928)
		(end 350.74606 -157.79115)
		(width 0.15494)
		(layer "In5.Cu")
		(net "NIC7_MAIN_PWR_EN")
	)
	(segment
		(start 353.735132 -116.901976)
		(end 353.735132 -124.686822)
		(width 0.15494)
		(layer "In5.Cu")
		(net "NIC7_MAIN_PWR_EN")
	)
	(segment
		(start 363.2454 -207.803242)
		(end 360.241342 -210.8073)
		(width 0.15494)
		(layer "In5.Cu")
		(net "NIC7_MAIN_PWR_EN")
	)
	(segment
		(start 353.750118 -163.975796)
		(end 353.750118 -165.231318)
		(width 0.15494)
		(layer "In5.Cu")
		(net "NIC7_MAIN_PWR_EN")
	)
	(segment
		(start 365.00943 -179.518818)
		(end 368.308128 -182.817516)
		(width 0.15494)
		(layer "In5.Cu")
		(net "NIC7_MAIN_PWR_EN")
	)
	(segment
		(start 351.00895 -215.871806)
		(end 350.493584 -216.387172)
		(width 0.15494)
		(layer "In5.Cu")
		(net "NIC7_MAIN_PWR_EN")
	)
	(segment
		(start 368.472466 -203.611734)
		(end 367.511838 -203.611734)
		(width 0.15494)
		(layer "In5.Cu")
		(net "NIC7_MAIN_PWR_EN")
	)
	(segment
		(start 364.98911 -206.134462)
		(end 364.33379 -206.134462)
		(width 0.15494)
		(layer "In5.Cu")
		(net "NIC7_MAIN_PWR_EN")
	)
	(segment
		(start 368.308128 -193.480182)
		(end 369.987322 -195.159376)
		(width 0.15494)
		(layer "In5.Cu")
		(net "NIC7_MAIN_PWR_EN")
	)
	(segment
		(start 350.50476 -163.339272)
		(end 353.113594 -163.339272)
		(width 0.15494)
		(layer "In5.Cu")
		(net "NIC7_MAIN_PWR_EN")
	)
	(segment
		(start 362.183426 -108.453682)
		(end 353.735132 -116.901976)
		(width 0.15494)
		(layer "In5.Cu")
		(net "NIC7_MAIN_PWR_EN")
	)
	(segment
		(start 355.04628 -166.09822)
		(end 355.3714 -166.42334)
		(width 0.15494)
		(layer "In5.Cu")
		(net "NIC7_MAIN_PWR_EN")
	)
	(segment
		(start 353.735132 -124.686822)
		(end 349.801688 -128.620266)
		(width 0.15494)
		(layer "In5.Cu")
		(net "NIC7_MAIN_PWR_EN")
	)
	(segment
		(start 354.61702 -166.09822)
		(end 355.04628 -166.09822)
		(width 0.15494)
		(layer "In5.Cu")
		(net "NIC7_MAIN_PWR_EN")
	)
	(segment
		(start 362.183426 -100.927154)
		(end 362.183426 -108.453682)
		(width 0.15494)
		(layer "In5.Cu")
		(net "NIC7_MAIN_PWR_EN")
	)
	(segment
		(start 369.987322 -202.096878)
		(end 368.472466 -203.611734)
		(width 0.15494)
		(layer "In5.Cu")
		(net "NIC7_MAIN_PWR_EN")
	)
	(segment
		(start 350.74606 -157.79115)
		(end 349.770954 -158.766256)
		(width 0.15494)
		(layer "In5.Cu")
		(net "NIC7_MAIN_PWR_EN")
	)
	(segment
		(start 358.6099 -210.8073)
		(end 358.0257 -211.3915)
		(width 0.15494)
		(layer "In5.Cu")
		(net "NIC7_MAIN_PWR_EN")
	)
	(segment
		(start 356.5017 -211.3915)
		(end 354.67798 -213.21522)
		(width 0.15494)
		(layer "In5.Cu")
		(net "NIC7_MAIN_PWR_EN")
	)
	(segment
		(start 363.2454 -207.222852)
		(end 363.2454 -207.803242)
		(width 0.15494)
		(layer "In5.Cu")
		(net "NIC7_MAIN_PWR_EN")
	)
	(segment
		(start 417.497768 -95.187516)
		(end 416.169602 -93.85935)
		(width 0.15494)
		(layer "In13.Cu")
		(net "NIC7_MAIN_PWR_EN")
	)
	(segment
		(start 399.950178 -91.891104)
		(end 383.553716 -91.891104)
		(width 0.15494)
		(layer "In13.Cu")
		(net "NIC7_MAIN_PWR_EN")
	)
	(segment
		(start 417.497768 -97.880678)
		(end 417.497768 -95.187516)
		(width 0.15494)
		(layer "In13.Cu")
		(net "NIC7_MAIN_PWR_EN")
	)
	(segment
		(start 418.80409 -99.187)
		(end 417.497768 -97.880678)
		(width 0.15494)
		(layer "In13.Cu")
		(net "NIC7_MAIN_PWR_EN")
	)
	(segment
		(start 382.4097 -93.03512)
		(end 370.07546 -93.03512)
		(width 0.15494)
		(layer "In13.Cu")
		(net "NIC7_MAIN_PWR_EN")
	)
	(segment
		(start 370.07546 -93.03512)
		(end 365.892842 -97.217738)
		(width 0.15494)
		(layer "In13.Cu")
		(net "NIC7_MAIN_PWR_EN")
	)
	(segment
		(start 383.553716 -91.891104)
		(end 382.4097 -93.03512)
		(width 0.15494)
		(layer "In13.Cu")
		(net "NIC7_MAIN_PWR_EN")
	)
	(segment
		(start 401.918424 -93.85935)
		(end 399.950178 -91.891104)
		(width 0.15494)
		(layer "In13.Cu")
		(net "NIC7_MAIN_PWR_EN")
	)
	(segment
		(start 416.169602 -93.85935)
		(end 401.918424 -93.85935)
		(width 0.15494)
		(layer "In13.Cu")
		(net "NIC7_MAIN_PWR_EN")
	)
	(segment
		(start 283.801312 -53.051456)
		(end 284.067758 -53.051456)
		(width 0.13208)
		(layer "F.Cu")
		(net "PWRGD_P12V_SSD9")
	)
	(segment
		(start 284.067758 -52.035456)
		(end 284.067758 -53.051456)
		(width 0.13208)
		(layer "F.Cu")
		(net "PWRGD_P12V_SSD9")
	)
	(segment
		(start 283.337254 -53.023008)
		(end 283.337254 -52.587398)
		(width 0.13208)
		(layer "F.Cu")
		(net "PWRGD_P12V_SSD9")
	)
	(segment
		(start 282.347162 -53.644038)
		(end 282.716224 -53.644038)
		(width 0.13208)
		(layer "F.Cu")
		(net "PWRGD_P12V_SSD9")
	)
	(segment
		(start 283.337254 -52.587398)
		(end 283.801312 -53.051456)
		(width 0.13208)
		(layer "F.Cu")
		(net "PWRGD_P12V_SSD9")
	)
	(segment
		(start 282.716224 -53.644038)
		(end 283.337254 -53.023008)
		(width 0.13208)
		(layer "F.Cu")
		(net "PWRGD_P12V_SSD9")
	)
	(via
		(at 283.337254 -52.587398)
		(size 0.508)
		(drill 0.254)
		(layers "F.Cu" "B.Cu")
		(net "PWRGD_P12V_SSD9")
	)
	(segment
		(start 136.045194 -93.528642)
		(end 134.557262 -93.528642)
		(width 0.13208)
		(layer "F.Cu")
		(net "SMB_BIC_I2C9_MUX0_SSD6_SCL")
	)
	(segment
		(start 133.88975 -93.8403)
		(end 133.062726 -93.8403)
		(width 0.13208)
		(layer "F.Cu")
		(net "SMB_BIC_I2C9_MUX0_SSD6_SCL")
	)
	(segment
		(start 134.318248 -93.767656)
		(end 133.962394 -93.767656)
		(width 0.13208)
		(layer "F.Cu")
		(net "SMB_BIC_I2C9_MUX0_SSD6_SCL")
	)
	(segment
		(start 134.557262 -93.528642)
		(end 134.318248 -93.767656)
		(width 0.13208)
		(layer "F.Cu")
		(net "SMB_BIC_I2C9_MUX0_SSD6_SCL")
	)
	(segment
		(start 133.962394 -93.767656)
		(end 133.88975 -93.8403)
		(width 0.13208)
		(layer "F.Cu")
		(net "SMB_BIC_I2C9_MUX0_SSD6_SCL")
	)
	(via
		(at 134.318248 -93.767656)
		(size 0.508)
		(drill 0.254)
		(layers "F.Cu" "B.Cu")
		(net "SMB_BIC_I2C9_MUX0_SSD6_SCL")
	)
	(segment
		(start 332.512162 -230.368856)
		(end 334.89392 -227.987098)
		(width 0.13208)
		(layer "F.Cu")
		(net "RST_MB_PERST_1_ISO_R_N")
	)
	(segment
		(start 332.512162 -232.918)
		(end 332.512162 -230.368856)
		(width 0.13208)
		(layer "F.Cu")
		(net "RST_MB_PERST_1_ISO_R_N")
	)
	(segment
		(start 333.540608 -236.471206)
		(end 332.512162 -236.471206)
		(width 0.13208)
		(layer "F.Cu")
		(net "RST_MB_PERST_1_ISO_R_N")
	)
	(segment
		(start 332.512162 -236.471206)
		(end 332.512162 -232.918)
		(width 0.13208)
		(layer "F.Cu")
		(net "RST_MB_PERST_1_ISO_R_N")
	)
	(via
		(at 332.512162 -232.918)
		(size 0.508)
		(drill 0.254)
		(layers "F.Cu" "B.Cu")
		(net "RST_MB_PERST_1_ISO_R_N")
	)
	(segment
		(start 343.69375 -227.186998)
		(end 344.08999 -227.583238)
		(width 0.13208)
		(layer "F.Cu")
		(net "PWRGD_P3V3_SSD3_R")
	)
	(segment
		(start 78.637638 -35.6616)
		(end 79.20863 -36.232592)
		(width 0.13208)
		(layer "F.Cu")
		(net "PWRGD_P3V3_SSD3_R")
	)
	(segment
		(start 343.916 -229.616)
		(end 343.281 -230.251)
		(width 0.13208)
		(layer "F.Cu")
		(net "PWRGD_P3V3_SSD3_R")
	)
	(segment
		(start 343.916 -229.235)
		(end 343.916 -229.616)
		(width 0.13208)
		(layer "F.Cu")
		(net "PWRGD_P3V3_SSD3_R")
	)
	(segment
		(start 75.170792 -35.876738)
		(end 74.427842 -35.876738)
		(width 0.13208)
		(layer "F.Cu")
		(net "PWRGD_P3V3_SSD3_R")
	)
	(segment
		(start 344.08999 -229.06101)
		(end 343.916 -229.235)
		(width 0.13208)
		(layer "F.Cu")
		(net "PWRGD_P3V3_SSD3_R")
	)
	(segment
		(start 75.881992 -35.876738)
		(end 76.09713 -35.6616)
		(width 0.13208)
		(layer "F.Cu")
		(net "PWRGD_P3V3_SSD3_R")
	)
	(segment
		(start 79.20863 -36.232592)
		(end 79.595218 -36.232592)
		(width 0.13208)
		(layer "F.Cu")
		(net "PWRGD_P3V3_SSD3_R")
	)
	(segment
		(start 344.08999 -227.583238)
		(end 344.08999 -229.06101)
		(width 0.13208)
		(layer "F.Cu")
		(net "PWRGD_P3V3_SSD3_R")
	)
	(segment
		(start 86.610952 -61.386974)
		(end 86.610952 -62.051438)
		(width 0.13208)
		(layer "F.Cu")
		(net "PWRGD_P3V3_SSD3_R")
	)
	(segment
		(start 76.09713 -35.6616)
		(end 78.637638 -35.6616)
		(width 0.13208)
		(layer "F.Cu")
		(net "PWRGD_P3V3_SSD3_R")
	)
	(segment
		(start 75.170792 -35.876738)
		(end 75.881992 -35.876738)
		(width 0.13208)
		(layer "F.Cu")
		(net "PWRGD_P3V3_SSD3_R")
	)
	(via
		(at 75.170792 -35.876738)
		(size 0.508)
		(drill 0.254)
		(layers "F.Cu" "B.Cu")
		(net "PWRGD_P3V3_SSD3_R")
	)
	(via
		(at 343.281 -230.251)
		(size 0.508)
		(drill 0.254)
		(layers "F.Cu" "B.Cu")
		(net "PWRGD_P3V3_SSD3_R")
	)
	(via
		(at 86.610952 -62.051438)
		(size 0.508)
		(drill 0.254)
		(layers "F.Cu" "B.Cu")
		(net "PWRGD_P3V3_SSD3_R")
	)
	(via
		(at 117.704616 -215.10498)
		(size 0.508)
		(drill 0.254)
		(layers "F.Cu" "B.Cu")
		(net "PWRGD_P3V3_SSD3_R")
	)
	(segment
		(start 108.0008 -193.46164)
		(end 105.766616 -191.227456)
		(width 0.15494)
		(layer "In5.Cu")
		(net "PWRGD_P3V3_SSD3_R")
	)
	(segment
		(start 86.58479 -62.0776)
		(end 86.610952 -62.051438)
		(width 0.15494)
		(layer "In5.Cu")
		(net "PWRGD_P3V3_SSD3_R")
	)
	(segment
		(start 75.170792 -35.876738)
		(end 77.456538 -35.876738)
		(width 0.15494)
		(layer "In5.Cu")
		(net "PWRGD_P3V3_SSD3_R")
	)
	(segment
		(start 89.17686 -118.61419)
		(end 88.354408 -117.791738)
		(width 0.15494)
		(layer "In5.Cu")
		(net "PWRGD_P3V3_SSD3_R")
	)
	(segment
		(start 88.2904 -60.881006)
		(end 87.119968 -62.051438)
		(width 0.15494)
		(layer "In5.Cu")
		(net "PWRGD_P3V3_SSD3_R")
	)
	(segment
		(start 89.8652 -85.37194)
		(end 89.8652 -80.462628)
		(width 0.15494)
		(layer "In5.Cu")
		(net "PWRGD_P3V3_SSD3_R")
	)
	(segment
		(start 84.815934 -63.606934)
		(end 84.815934 -62.580266)
		(width 0.15494)
		(layer "In5.Cu")
		(net "PWRGD_P3V3_SSD3_R")
	)
	(segment
		(start 88.354408 -116.192808)
		(end 88.0618 -115.9002)
		(width 0.15494)
		(layer "In5.Cu")
		(net "PWRGD_P3V3_SSD3_R")
	)
	(segment
		(start 109.5756 -200.5584)
		(end 108.7628 -200.5584)
		(width 0.15494)
		(layer "In5.Cu")
		(net "PWRGD_P3V3_SSD3_R")
	)
	(segment
		(start 108.0008 -199.7964)
		(end 108.0008 -193.46164)
		(width 0.15494)
		(layer "In5.Cu")
		(net "PWRGD_P3V3_SSD3_R")
	)
	(segment
		(start 89.8652 -80.462628)
		(end 85.537802 -76.13523)
		(width 0.15494)
		(layer "In5.Cu")
		(net "PWRGD_P3V3_SSD3_R")
	)
	(segment
		(start 92.35186 -133.614922)
		(end 92.35186 -129.81559)
		(width 0.15494)
		(layer "In5.Cu")
		(net "PWRGD_P3V3_SSD3_R")
	)
	(segment
		(start 84.815934 -62.580266)
		(end 85.3186 -62.0776)
		(width 0.15494)
		(layer "In5.Cu")
		(net "PWRGD_P3V3_SSD3_R")
	)
	(segment
		(start 88.354408 -117.791738)
		(end 88.354408 -116.192808)
		(width 0.15494)
		(layer "In5.Cu")
		(net "PWRGD_P3V3_SSD3_R")
	)
	(segment
		(start 108.7628 -200.5584)
		(end 108.0008 -199.7964)
		(width 0.15494)
		(layer "In5.Cu")
		(net "PWRGD_P3V3_SSD3_R")
	)
	(segment
		(start 117.3226 -214.722964)
		(end 117.3226 -208.3054)
		(width 0.15494)
		(layer "In5.Cu")
		(net "PWRGD_P3V3_SSD3_R")
	)
	(segment
		(start 105.766616 -191.227456)
		(end 101.928168 -191.227456)
		(width 0.15494)
		(layer "In5.Cu")
		(net "PWRGD_P3V3_SSD3_R")
	)
	(segment
		(start 100.984304 -190.283592)
		(end 100.984304 -186.09945)
		(width 0.15494)
		(layer "In5.Cu")
		(net "PWRGD_P3V3_SSD3_R")
	)
	(segment
		(start 92.35186 -129.81559)
		(end 89.17686 -126.64059)
		(width 0.15494)
		(layer "In5.Cu")
		(net "PWRGD_P3V3_SSD3_R")
	)
	(segment
		(start 95.70974 -177.11547)
		(end 95.70974 -141.721586)
		(width 0.15494)
		(layer "In5.Cu")
		(net "PWRGD_P3V3_SSD3_R")
	)
	(segment
		(start 82.157316 -109.130084)
		(end 82.820002 -108.467398)
		(width 0.15494)
		(layer "In5.Cu")
		(net "PWRGD_P3V3_SSD3_R")
	)
	(segment
		(start 95.70974 -141.721586)
		(end 92.35186 -133.614922)
		(width 0.15494)
		(layer "In5.Cu")
		(net "PWRGD_P3V3_SSD3_R")
	)
	(segment
		(start 97.203768 -182.318914)
		(end 97.203768 -178.609498)
		(width 0.15494)
		(layer "In5.Cu")
		(net "PWRGD_P3V3_SSD3_R")
	)
	(segment
		(start 97.203768 -178.609498)
		(end 95.70974 -177.11547)
		(width 0.15494)
		(layer "In5.Cu")
		(net "PWRGD_P3V3_SSD3_R")
	)
	(segment
		(start 100.984304 -186.09945)
		(end 97.203768 -182.318914)
		(width 0.15494)
		(layer "In5.Cu")
		(net "PWRGD_P3V3_SSD3_R")
	)
	(segment
		(start 82.820002 -108.467398)
		(end 82.820002 -92.417138)
		(width 0.15494)
		(layer "In5.Cu")
		(net "PWRGD_P3V3_SSD3_R")
	)
	(segment
		(start 82.284316 -114.229642)
		(end 82.157316 -114.102642)
		(width 0.15494)
		(layer "In5.Cu")
		(net "PWRGD_P3V3_SSD3_R")
	)
	(segment
		(start 86.443312 -115.9002)
		(end 84.772754 -114.229642)
		(width 0.15494)
		(layer "In5.Cu")
		(net "PWRGD_P3V3_SSD3_R")
	)
	(segment
		(start 89.17686 -126.64059)
		(end 89.17686 -118.61419)
		(width 0.15494)
		(layer "In5.Cu")
		(net "PWRGD_P3V3_SSD3_R")
	)
	(segment
		(start 88.0618 -115.9002)
		(end 86.443312 -115.9002)
		(width 0.15494)
		(layer "In5.Cu")
		(net "PWRGD_P3V3_SSD3_R")
	)
	(segment
		(start 85.537802 -76.13523)
		(end 85.537802 -64.328802)
		(width 0.15494)
		(layer "In5.Cu")
		(net "PWRGD_P3V3_SSD3_R")
	)
	(segment
		(start 84.772754 -114.229642)
		(end 82.284316 -114.229642)
		(width 0.15494)
		(layer "In5.Cu")
		(net "PWRGD_P3V3_SSD3_R")
	)
	(segment
		(start 85.537802 -64.328802)
		(end 84.815934 -63.606934)
		(width 0.15494)
		(layer "In5.Cu")
		(net "PWRGD_P3V3_SSD3_R")
	)
	(segment
		(start 82.820002 -92.417138)
		(end 89.8652 -85.37194)
		(width 0.15494)
		(layer "In5.Cu")
		(net "PWRGD_P3V3_SSD3_R")
	)
	(segment
		(start 82.157316 -114.102642)
		(end 82.157316 -109.130084)
		(width 0.15494)
		(layer "In5.Cu")
		(net "PWRGD_P3V3_SSD3_R")
	)
	(segment
		(start 101.928168 -191.227456)
		(end 100.984304 -190.283592)
		(width 0.15494)
		(layer "In5.Cu")
		(net "PWRGD_P3V3_SSD3_R")
	)
	(segment
		(start 117.3226 -208.3054)
		(end 109.5756 -200.5584)
		(width 0.15494)
		(layer "In5.Cu")
		(net "PWRGD_P3V3_SSD3_R")
	)
	(segment
		(start 87.119968 -62.051438)
		(end 86.610952 -62.051438)
		(width 0.15494)
		(layer "In5.Cu")
		(net "PWRGD_P3V3_SSD3_R")
	)
	(segment
		(start 88.2904 -46.7106)
		(end 88.2904 -60.881006)
		(width 0.15494)
		(layer "In5.Cu")
		(net "PWRGD_P3V3_SSD3_R")
	)
	(segment
		(start 77.456538 -35.876738)
		(end 88.2904 -46.7106)
		(width 0.15494)
		(layer "In5.Cu")
		(net "PWRGD_P3V3_SSD3_R")
	)
	(segment
		(start 117.704616 -215.10498)
		(end 117.3226 -214.722964)
		(width 0.15494)
		(layer "In5.Cu")
		(net "PWRGD_P3V3_SSD3_R")
	)
	(segment
		(start 85.3186 -62.0776)
		(end 86.58479 -62.0776)
		(width 0.15494)
		(layer "In5.Cu")
		(net "PWRGD_P3V3_SSD3_R")
	)
	(segment
		(start 271.062196 -233.61269)
		(end 300.666404 -233.61269)
		(width 0.15494)
		(layer "In15.Cu")
		(net "PWRGD_P3V3_SSD3_R")
	)
	(segment
		(start 341.215218 -232.316782)
		(end 343.281 -230.251)
		(width 0.15494)
		(layer "In15.Cu")
		(net "PWRGD_P3V3_SSD3_R")
	)
	(segment
		(start 322.21297 -233.776012)
		(end 323.26834 -234.831382)
		(width 0.15494)
		(layer "In15.Cu")
		(net "PWRGD_P3V3_SSD3_R")
	)
	(segment
		(start 261.928102 -227.59162)
		(end 265.041126 -227.59162)
		(width 0.15494)
		(layer "In15.Cu")
		(net "PWRGD_P3V3_SSD3_R")
	)
	(segment
		(start 301.187104 -233.09199)
		(end 301.987204 -233.09199)
		(width 0.15494)
		(layer "In15.Cu")
		(net "PWRGD_P3V3_SSD3_R")
	)
	(segment
		(start 141.555978 -225.24593)
		(end 142.751048 -225.24593)
		(width 0.15494)
		(layer "In15.Cu")
		(net "PWRGD_P3V3_SSD3_R")
	)
	(segment
		(start 326.968612 -233.91241)
		(end 329.617832 -233.91241)
		(width 0.15494)
		(layer "In15.Cu")
		(net "PWRGD_P3V3_SSD3_R")
	)
	(segment
		(start 333.10068 -232.821988)
		(end 336.322162 -232.821988)
		(width 0.15494)
		(layer "In15.Cu")
		(net "PWRGD_P3V3_SSD3_R")
	)
	(segment
		(start 258.50215 -226.619816)
		(end 258.502404 -226.619562)
		(width 0.15494)
		(layer "In15.Cu")
		(net "PWRGD_P3V3_SSD3_R")
	)
	(segment
		(start 162.078416 -228.829616)
		(end 188.770514 -228.829616)
		(width 0.15494)
		(layer "In15.Cu")
		(net "PWRGD_P3V3_SSD3_R")
	)
	(segment
		(start 332.301342 -232.44429)
		(end 332.311502 -232.43413)
		(width 0.15494)
		(layer "In15.Cu")
		(net "PWRGD_P3V3_SSD3_R")
	)
	(segment
		(start 142.751048 -225.24593)
		(end 145.6563 -222.340678)
		(width 0.15494)
		(layer "In15.Cu")
		(net "PWRGD_P3V3_SSD3_R")
	)
	(segment
		(start 336.322162 -232.821988)
		(end 336.827368 -232.316782)
		(width 0.15494)
		(layer "In15.Cu")
		(net "PWRGD_P3V3_SSD3_R")
	)
	(segment
		(start 193.285364 -233.344466)
		(end 211.281772 -233.344466)
		(width 0.15494)
		(layer "In15.Cu")
		(net "PWRGD_P3V3_SSD3_R")
	)
	(segment
		(start 128.465326 -226.49307)
		(end 140.308838 -226.49307)
		(width 0.15494)
		(layer "In15.Cu")
		(net "PWRGD_P3V3_SSD3_R")
	)
	(segment
		(start 246.823738 -226.40798)
		(end 249.362468 -226.40798)
		(width 0.15494)
		(layer "In15.Cu")
		(net "PWRGD_P3V3_SSD3_R")
	)
	(segment
		(start 301.987204 -233.09199)
		(end 302.671226 -233.776012)
		(width 0.15494)
		(layer "In15.Cu")
		(net "PWRGD_P3V3_SSD3_R")
	)
	(segment
		(start 300.666404 -233.61269)
		(end 301.187104 -233.09199)
		(width 0.15494)
		(layer "In15.Cu")
		(net "PWRGD_P3V3_SSD3_R")
	)
	(segment
		(start 302.671226 -233.776012)
		(end 322.21297 -233.776012)
		(width 0.15494)
		(layer "In15.Cu")
		(net "PWRGD_P3V3_SSD3_R")
	)
	(segment
		(start 211.281772 -233.344466)
		(end 211.7598 -232.866438)
		(width 0.15494)
		(layer "In15.Cu")
		(net "PWRGD_P3V3_SSD3_R")
	)
	(segment
		(start 242.395248 -231.84231)
		(end 244.127528 -230.11003)
		(width 0.15494)
		(layer "In15.Cu")
		(net "PWRGD_P3V3_SSD3_R")
	)
	(segment
		(start 155.589478 -222.340678)
		(end 162.078416 -228.829616)
		(width 0.15494)
		(layer "In15.Cu")
		(net "PWRGD_P3V3_SSD3_R")
	)
	(segment
		(start 117.704616 -215.10498)
		(end 117.704616 -215.73236)
		(width 0.15494)
		(layer "In15.Cu")
		(net "PWRGD_P3V3_SSD3_R")
	)
	(segment
		(start 212.33638 -231.42702)
		(end 213.62543 -231.42702)
		(width 0.15494)
		(layer "In15.Cu")
		(net "PWRGD_P3V3_SSD3_R")
	)
	(segment
		(start 145.6563 -222.340678)
		(end 155.589478 -222.340678)
		(width 0.15494)
		(layer "In15.Cu")
		(net "PWRGD_P3V3_SSD3_R")
	)
	(segment
		(start 265.041126 -227.59162)
		(end 271.062196 -233.61269)
		(width 0.15494)
		(layer "In15.Cu")
		(net "PWRGD_P3V3_SSD3_R")
	)
	(segment
		(start 188.770514 -228.829616)
		(end 193.285364 -233.344466)
		(width 0.15494)
		(layer "In15.Cu")
		(net "PWRGD_P3V3_SSD3_R")
	)
	(segment
		(start 140.308838 -226.49307)
		(end 141.555978 -225.24593)
		(width 0.15494)
		(layer "In15.Cu")
		(net "PWRGD_P3V3_SSD3_R")
	)
	(segment
		(start 211.7598 -232.866438)
		(end 211.7598 -232.0036)
		(width 0.15494)
		(layer "In15.Cu")
		(net "PWRGD_P3V3_SSD3_R")
	)
	(segment
		(start 329.617832 -233.91241)
		(end 330.974954 -233.350308)
		(width 0.15494)
		(layer "In15.Cu")
		(net "PWRGD_P3V3_SSD3_R")
	)
	(segment
		(start 254.611124 -226.619816)
		(end 258.50215 -226.619816)
		(width 0.15494)
		(layer "In15.Cu")
		(net "PWRGD_P3V3_SSD3_R")
	)
	(segment
		(start 244.127528 -230.11003)
		(end 244.127528 -229.10419)
		(width 0.15494)
		(layer "In15.Cu")
		(net "PWRGD_P3V3_SSD3_R")
	)
	(segment
		(start 330.974954 -233.350308)
		(end 331.880972 -232.44429)
		(width 0.15494)
		(layer "In15.Cu")
		(net "PWRGD_P3V3_SSD3_R")
	)
	(segment
		(start 323.26834 -234.831382)
		(end 326.04964 -234.831382)
		(width 0.15494)
		(layer "In15.Cu")
		(net "PWRGD_P3V3_SSD3_R")
	)
	(segment
		(start 211.7598 -232.0036)
		(end 212.33638 -231.42702)
		(width 0.15494)
		(layer "In15.Cu")
		(net "PWRGD_P3V3_SSD3_R")
	)
	(segment
		(start 259.579618 -226.619562)
		(end 261.928102 -227.59162)
		(width 0.15494)
		(layer "In15.Cu")
		(net "PWRGD_P3V3_SSD3_R")
	)
	(segment
		(start 254.16002 -227.07092)
		(end 254.611124 -226.619816)
		(width 0.15494)
		(layer "In15.Cu")
		(net "PWRGD_P3V3_SSD3_R")
	)
	(segment
		(start 250.025408 -227.07092)
		(end 254.16002 -227.07092)
		(width 0.15494)
		(layer "In15.Cu")
		(net "PWRGD_P3V3_SSD3_R")
	)
	(segment
		(start 213.62543 -231.42702)
		(end 214.04072 -231.84231)
		(width 0.15494)
		(layer "In15.Cu")
		(net "PWRGD_P3V3_SSD3_R")
	)
	(segment
		(start 244.127528 -229.10419)
		(end 246.823738 -226.40798)
		(width 0.15494)
		(layer "In15.Cu")
		(net "PWRGD_P3V3_SSD3_R")
	)
	(segment
		(start 249.362468 -226.40798)
		(end 250.025408 -227.07092)
		(width 0.15494)
		(layer "In15.Cu")
		(net "PWRGD_P3V3_SSD3_R")
	)
	(segment
		(start 214.04072 -231.84231)
		(end 242.395248 -231.84231)
		(width 0.15494)
		(layer "In15.Cu")
		(net "PWRGD_P3V3_SSD3_R")
	)
	(segment
		(start 332.311502 -232.43413)
		(end 332.712822 -232.43413)
		(width 0.15494)
		(layer "In15.Cu")
		(net "PWRGD_P3V3_SSD3_R")
	)
	(segment
		(start 336.827368 -232.316782)
		(end 341.215218 -232.316782)
		(width 0.15494)
		(layer "In15.Cu")
		(net "PWRGD_P3V3_SSD3_R")
	)
	(segment
		(start 326.04964 -234.831382)
		(end 326.968612 -233.91241)
		(width 0.15494)
		(layer "In15.Cu")
		(net "PWRGD_P3V3_SSD3_R")
	)
	(segment
		(start 258.502404 -226.619562)
		(end 259.579618 -226.619562)
		(width 0.15494)
		(layer "In15.Cu")
		(net "PWRGD_P3V3_SSD3_R")
	)
	(segment
		(start 332.712822 -232.43413)
		(end 333.10068 -232.821988)
		(width 0.15494)
		(layer "In15.Cu")
		(net "PWRGD_P3V3_SSD3_R")
	)
	(segment
		(start 331.880972 -232.44429)
		(end 332.301342 -232.44429)
		(width 0.15494)
		(layer "In15.Cu")
		(net "PWRGD_P3V3_SSD3_R")
	)
	(segment
		(start 117.704616 -215.73236)
		(end 128.465326 -226.49307)
		(width 0.15494)
		(layer "In15.Cu")
		(net "PWRGD_P3V3_SSD3_R")
	)
	(segment
		(start 251.56287 -80.81645)
		(end 252.362208 -80.81645)
		(width 0.13208)
		(layer "F.Cu")
		(net "XTAL_CK440_25M_XOUT")
	)
	(segment
		(start 248.097802 -81.196434)
		(end 248.956322 -80.337914)
		(width 0.13208)
		(layer "F.Cu")
		(net "XTAL_CK440_25M_XOUT")
	)
	(segment
		(start 254.113538 -81.583022)
		(end 253.346966 -80.81645)
		(width 0.13208)
		(layer "F.Cu")
		(net "XTAL_CK440_25M_XOUT")
	)
	(segment
		(start 253.346966 -80.81645)
		(end 252.362208 -80.81645)
		(width 0.13208)
		(layer "F.Cu")
		(net "XTAL_CK440_25M_XOUT")
	)
	(segment
		(start 250.334018 -80.337914)
		(end 250.625864 -80.458818)
		(width 0.13208)
		(layer "F.Cu")
		(net "XTAL_CK440_25M_XOUT")
	)
	(segment
		(start 254.884174 -81.583022)
		(end 254.113538 -81.583022)
		(width 0.13208)
		(layer "F.Cu")
		(net "XTAL_CK440_25M_XOUT")
	)
	(segment
		(start 250.625864 -80.458818)
		(end 250.983496 -80.81645)
		(width 0.13208)
		(layer "F.Cu")
		(net "XTAL_CK440_25M_XOUT")
	)
	(segment
		(start 255.42367 -81.806288)
		(end 254.884174 -81.583022)
		(width 0.13208)
		(layer "F.Cu")
		(net "XTAL_CK440_25M_XOUT")
	)
	(segment
		(start 248.097802 -81.349342)
		(end 248.097802 -81.196434)
		(width 0.13208)
		(layer "F.Cu")
		(net "XTAL_CK440_25M_XOUT")
	)
	(segment
		(start 250.983496 -80.81645)
		(end 251.56287 -80.81645)
		(width 0.13208)
		(layer "F.Cu")
		(net "XTAL_CK440_25M_XOUT")
	)
	(segment
		(start 248.956322 -80.337914)
		(end 250.334018 -80.337914)
		(width 0.13208)
		(layer "F.Cu")
		(net "XTAL_CK440_25M_XOUT")
	)
	(segment
		(start 256.551938 -81.806288)
		(end 255.42367 -81.806288)
		(width 0.0889)
		(layer "F.Cu")
		(net "XTAL_CK440_25M_XOUT")
	)
	(via
		(at 252.362208 -80.81645)
		(size 0.508)
		(drill 0.254)
		(layers "F.Cu" "B.Cu")
		(net "XTAL_CK440_25M_XOUT")
	)
	(segment
		(start 135.142986 -91.327478)
		(end 133.930136 -92.540328)
		(width 0.13208)
		(layer "F.Cu")
		(net "SMB_BIC_I2C9_MUX0_SSD5_SCL")
	)
	(segment
		(start 133.930136 -92.540328)
		(end 133.062726 -92.540328)
		(width 0.13208)
		(layer "F.Cu")
		(net "SMB_BIC_I2C9_MUX0_SSD5_SCL")
	)
	(segment
		(start 135.960358 -91.327478)
		(end 135.295386 -91.327478)
		(width 0.13208)
		(layer "F.Cu")
		(net "SMB_BIC_I2C9_MUX0_SSD5_SCL")
	)
	(segment
		(start 135.295386 -91.327478)
		(end 135.142986 -91.327478)
		(width 0.13208)
		(layer "F.Cu")
		(net "SMB_BIC_I2C9_MUX0_SSD5_SCL")
	)
	(segment
		(start 136.045194 -91.242642)
		(end 135.960358 -91.327478)
		(width 0.13208)
		(layer "F.Cu")
		(net "SMB_BIC_I2C9_MUX0_SSD5_SCL")
	)
	(via
		(at 135.295386 -91.327478)
		(size 0.508)
		(drill 0.254)
		(layers "F.Cu" "B.Cu")
		(net "SMB_BIC_I2C9_MUX0_SSD5_SCL")
	)
	(segment
		(start 206.96809 -288.221166)
		(end 206.96809 -288.830766)
		(width 0.13208)
		(layer "F.Cu")
		(net "SMB_PEX1_FPGA_SCL")
	)
	(segment
		(start 339.693758 -226.387152)
		(end 339.293962 -226.786948)
		(width 0.13208)
		(layer "F.Cu")
		(net "SMB_PEX1_FPGA_SCL")
	)
	(via
		(at 206.96809 -288.221166)
		(size 0.508)
		(drill 0.254)
		(layers "F.Cu" "B.Cu")
		(net "SMB_PEX1_FPGA_SCL")
	)
	(via
		(at 206.831946 -213.582758)
		(size 0.508)
		(drill 0.254)
		(layers "F.Cu" "B.Cu")
		(net "SMB_PEX1_FPGA_SCL")
	)
	(via
		(at 339.293962 -226.786948)
		(size 0.4572)
		(drill 0.254)
		(layers "F.Cu" "B.Cu")
		(net "SMB_PEX1_FPGA_SCL")
	)
	(segment
		(start 201.499216 -218.269058)
		(end 204.936598 -214.831676)
		(width 0.13208)
		(layer "B.Cu")
		(net "SMB_PEX1_FPGA_SCL")
	)
	(segment
		(start 201.919332 -255.044956)
		(end 197.673976 -250.7996)
		(width 0.13208)
		(layer "B.Cu")
		(net "SMB_PEX1_FPGA_SCL")
	)
	(segment
		(start 197.673976 -250.7996)
		(end 197.673976 -230.223314)
		(width 0.13208)
		(layer "B.Cu")
		(net "SMB_PEX1_FPGA_SCL")
	)
	(segment
		(start 211.24799 -268.322552)
		(end 205.179422 -262.253984)
		(width 0.13208)
		(layer "B.Cu")
		(net "SMB_PEX1_FPGA_SCL")
	)
	(segment
		(start 204.936598 -214.831676)
		(end 205.016862 -214.831676)
		(width 0.13208)
		(layer "B.Cu")
		(net "SMB_PEX1_FPGA_SCL")
	)
	(segment
		(start 206.96809 -288.221166)
		(end 206.96809 -284.513782)
		(width 0.13208)
		(layer "B.Cu")
		(net "SMB_PEX1_FPGA_SCL")
	)
	(segment
		(start 205.016862 -214.831676)
		(end 206.26578 -213.582758)
		(width 0.13208)
		(layer "B.Cu")
		(net "SMB_PEX1_FPGA_SCL")
	)
	(segment
		(start 197.673976 -230.223314)
		(end 201.499216 -226.398074)
		(width 0.13208)
		(layer "B.Cu")
		(net "SMB_PEX1_FPGA_SCL")
	)
	(segment
		(start 197.884288 -259.301488)
		(end 199.0344 -258.151376)
		(width 0.13208)
		(layer "B.Cu")
		(net "SMB_PEX1_FPGA_SCL")
	)
	(segment
		(start 201.919332 -256.094484)
		(end 201.919332 -255.044956)
		(width 0.13208)
		(layer "B.Cu")
		(net "SMB_PEX1_FPGA_SCL")
	)
	(segment
		(start 206.26578 -213.582758)
		(end 206.831946 -213.582758)
		(width 0.13208)
		(layer "B.Cu")
		(net "SMB_PEX1_FPGA_SCL")
	)
	(segment
		(start 211.24799 -280.233882)
		(end 211.24799 -268.322552)
		(width 0.13208)
		(layer "B.Cu")
		(net "SMB_PEX1_FPGA_SCL")
	)
	(segment
		(start 201.499216 -226.398074)
		(end 201.499216 -218.269058)
		(width 0.13208)
		(layer "B.Cu")
		(net "SMB_PEX1_FPGA_SCL")
	)
	(segment
		(start 199.0344 -258.151376)
		(end 199.86244 -258.151376)
		(width 0.13208)
		(layer "B.Cu")
		(net "SMB_PEX1_FPGA_SCL")
	)
	(segment
		(start 206.96809 -284.513782)
		(end 211.24799 -280.233882)
		(width 0.13208)
		(layer "B.Cu")
		(net "SMB_PEX1_FPGA_SCL")
	)
	(segment
		(start 197.884288 -261.274814)
		(end 197.884288 -259.301488)
		(width 0.13208)
		(layer "B.Cu")
		(net "SMB_PEX1_FPGA_SCL")
	)
	(segment
		(start 205.179422 -262.253984)
		(end 198.863458 -262.253984)
		(width 0.13208)
		(layer "B.Cu")
		(net "SMB_PEX1_FPGA_SCL")
	)
	(segment
		(start 198.863458 -262.253984)
		(end 197.884288 -261.274814)
		(width 0.13208)
		(layer "B.Cu")
		(net "SMB_PEX1_FPGA_SCL")
	)
	(segment
		(start 199.86244 -258.151376)
		(end 201.919332 -256.094484)
		(width 0.13208)
		(layer "B.Cu")
		(net "SMB_PEX1_FPGA_SCL")
	)
	(segment
		(start 325.773034 -233.610912)
		(end 332.61173 -233.610912)
		(width 0.15494)
		(layer "In13.Cu")
		(net "SMB_PEX1_FPGA_SCL")
	)
	(segment
		(start 240.6142 -215.1126)
		(end 242.677442 -217.175842)
		(width 0.15494)
		(layer "In13.Cu")
		(net "SMB_PEX1_FPGA_SCL")
	)
	(segment
		(start 321.626738 -232.81894)
		(end 322.234306 -232.81894)
		(width 0.15494)
		(layer "In13.Cu")
		(net "SMB_PEX1_FPGA_SCL")
	)
	(segment
		(start 237.55985 -213.434422)
		(end 237.55985 -213.939882)
		(width 0.15494)
		(layer "In13.Cu")
		(net "SMB_PEX1_FPGA_SCL")
	)
	(segment
		(start 300.58741 -232.99039)
		(end 301.927514 -232.99039)
		(width 0.15494)
		(layer "In13.Cu")
		(net "SMB_PEX1_FPGA_SCL")
	)
	(segment
		(start 339.87613 -230.565198)
		(end 339.87613 -227.369116)
		(width 0.15494)
		(layer "In13.Cu")
		(net "SMB_PEX1_FPGA_SCL")
	)
	(segment
		(start 219.49664 -214.89416)
		(end 222.5294 -211.8614)
		(width 0.15494)
		(layer "In13.Cu")
		(net "SMB_PEX1_FPGA_SCL")
	)
	(segment
		(start 211.789518 -215.8746)
		(end 212.275166 -215.8746)
		(width 0.15494)
		(layer "In13.Cu")
		(net "SMB_PEX1_FPGA_SCL")
	)
	(segment
		(start 332.61173 -233.610912)
		(end 335.000092 -231.22255)
		(width 0.15494)
		(layer "In13.Cu")
		(net "SMB_PEX1_FPGA_SCL")
	)
	(segment
		(start 217.675968 -216.23274)
		(end 218.633294 -216.23274)
		(width 0.15494)
		(layer "In13.Cu")
		(net "SMB_PEX1_FPGA_SCL")
	)
	(segment
		(start 212.376766 -215.773)
		(end 217.216228 -215.773)
		(width 0.15494)
		(layer "In13.Cu")
		(net "SMB_PEX1_FPGA_SCL")
	)
	(segment
		(start 207.944212 -213.8426)
		(end 209.566002 -215.46439)
		(width 0.15494)
		(layer "In13.Cu")
		(net "SMB_PEX1_FPGA_SCL")
	)
	(segment
		(start 222.5294 -211.8614)
		(end 223.2914 -211.8614)
		(width 0.15494)
		(layer "In13.Cu")
		(net "SMB_PEX1_FPGA_SCL")
	)
	(segment
		(start 243.75618 -220.977206)
		(end 247.666002 -224.887028)
		(width 0.15494)
		(layer "In13.Cu")
		(net "SMB_PEX1_FPGA_SCL")
	)
	(segment
		(start 339.218778 -231.22255)
		(end 339.87613 -230.565198)
		(width 0.15494)
		(layer "In13.Cu")
		(net "SMB_PEX1_FPGA_SCL")
	)
	(segment
		(start 259.051044 -225.637344)
		(end 261.494016 -225.637344)
		(width 0.15494)
		(layer "In13.Cu")
		(net "SMB_PEX1_FPGA_SCL")
	)
	(segment
		(start 242.677442 -217.637868)
		(end 243.75618 -218.716606)
		(width 0.15494)
		(layer "In13.Cu")
		(net "SMB_PEX1_FPGA_SCL")
	)
	(segment
		(start 218.633294 -216.23274)
		(end 219.49664 -215.369394)
		(width 0.15494)
		(layer "In13.Cu")
		(net "SMB_PEX1_FPGA_SCL")
	)
	(segment
		(start 209.566002 -215.46439)
		(end 211.379308 -215.46439)
		(width 0.15494)
		(layer "In13.Cu")
		(net "SMB_PEX1_FPGA_SCL")
	)
	(segment
		(start 235.38434 -212.447886)
		(end 235.86694 -212.930486)
		(width 0.15494)
		(layer "In13.Cu")
		(net "SMB_PEX1_FPGA_SCL")
	)
	(segment
		(start 238.732568 -215.1126)
		(end 240.6142 -215.1126)
		(width 0.15494)
		(layer "In13.Cu")
		(net "SMB_PEX1_FPGA_SCL")
	)
	(segment
		(start 278.2062 -233.68)
		(end 299.8978 -233.68)
		(width 0.15494)
		(layer "In13.Cu")
		(net "SMB_PEX1_FPGA_SCL")
	)
	(segment
		(start 225.38436 -209.76844)
		(end 230.007922 -209.76844)
		(width 0.15494)
		(layer "In13.Cu")
		(net "SMB_PEX1_FPGA_SCL")
	)
	(segment
		(start 258.300728 -224.887028)
		(end 259.051044 -225.637344)
		(width 0.15494)
		(layer "In13.Cu")
		(net "SMB_PEX1_FPGA_SCL")
	)
	(segment
		(start 325.195946 -234.188)
		(end 325.773034 -233.610912)
		(width 0.15494)
		(layer "In13.Cu")
		(net "SMB_PEX1_FPGA_SCL")
	)
	(segment
		(start 237.55985 -213.939882)
		(end 238.732568 -215.1126)
		(width 0.15494)
		(layer "In13.Cu")
		(net "SMB_PEX1_FPGA_SCL")
	)
	(segment
		(start 261.494016 -225.637344)
		(end 263.593072 -227.7364)
		(width 0.15494)
		(layer "In13.Cu")
		(net "SMB_PEX1_FPGA_SCL")
	)
	(segment
		(start 247.666002 -224.887028)
		(end 258.300728 -224.887028)
		(width 0.15494)
		(layer "In13.Cu")
		(net "SMB_PEX1_FPGA_SCL")
	)
	(segment
		(start 302.515524 -233.5784)
		(end 304.3428 -233.5784)
		(width 0.15494)
		(layer "In13.Cu")
		(net "SMB_PEX1_FPGA_SCL")
	)
	(segment
		(start 243.75618 -218.716606)
		(end 243.75618 -220.977206)
		(width 0.15494)
		(layer "In13.Cu")
		(net "SMB_PEX1_FPGA_SCL")
	)
	(segment
		(start 231.973628 -210.58251)
		(end 234.143804 -210.58251)
		(width 0.15494)
		(layer "In13.Cu")
		(net "SMB_PEX1_FPGA_SCL")
	)
	(segment
		(start 234.143804 -210.58251)
		(end 235.38434 -211.823046)
		(width 0.15494)
		(layer "In13.Cu")
		(net "SMB_PEX1_FPGA_SCL")
	)
	(segment
		(start 237.055914 -212.930486)
		(end 237.55985 -213.434422)
		(width 0.15494)
		(layer "In13.Cu")
		(net "SMB_PEX1_FPGA_SCL")
	)
	(segment
		(start 301.927514 -232.99039)
		(end 302.515524 -233.5784)
		(width 0.15494)
		(layer "In13.Cu")
		(net "SMB_PEX1_FPGA_SCL")
	)
	(segment
		(start 304.3428 -233.5784)
		(end 305.097688 -232.823512)
		(width 0.15494)
		(layer "In13.Cu")
		(net "SMB_PEX1_FPGA_SCL")
	)
	(segment
		(start 263.593072 -227.7364)
		(end 272.2626 -227.7364)
		(width 0.15494)
		(layer "In13.Cu")
		(net "SMB_PEX1_FPGA_SCL")
	)
	(segment
		(start 235.38434 -211.823046)
		(end 235.38434 -212.447886)
		(width 0.15494)
		(layer "In13.Cu")
		(net "SMB_PEX1_FPGA_SCL")
	)
	(segment
		(start 272.2626 -227.7364)
		(end 278.2062 -233.68)
		(width 0.15494)
		(layer "In13.Cu")
		(net "SMB_PEX1_FPGA_SCL")
	)
	(segment
		(start 305.097688 -232.823512)
		(end 321.622166 -232.823512)
		(width 0.15494)
		(layer "In13.Cu")
		(net "SMB_PEX1_FPGA_SCL")
	)
	(segment
		(start 235.86694 -212.930486)
		(end 237.055914 -212.930486)
		(width 0.15494)
		(layer "In13.Cu")
		(net "SMB_PEX1_FPGA_SCL")
	)
	(segment
		(start 223.2914 -211.8614)
		(end 225.38436 -209.76844)
		(width 0.15494)
		(layer "In13.Cu")
		(net "SMB_PEX1_FPGA_SCL")
	)
	(segment
		(start 299.8978 -233.68)
		(end 300.58741 -232.99039)
		(width 0.15494)
		(layer "In13.Cu")
		(net "SMB_PEX1_FPGA_SCL")
	)
	(segment
		(start 219.49664 -215.369394)
		(end 219.49664 -214.89416)
		(width 0.15494)
		(layer "In13.Cu")
		(net "SMB_PEX1_FPGA_SCL")
	)
	(segment
		(start 339.87613 -227.369116)
		(end 339.293962 -226.786948)
		(width 0.15494)
		(layer "In13.Cu")
		(net "SMB_PEX1_FPGA_SCL")
	)
	(segment
		(start 212.275166 -215.8746)
		(end 212.376766 -215.773)
		(width 0.15494)
		(layer "In13.Cu")
		(net "SMB_PEX1_FPGA_SCL")
	)
	(segment
		(start 242.677442 -217.175842)
		(end 242.677442 -217.637868)
		(width 0.15494)
		(layer "In13.Cu")
		(net "SMB_PEX1_FPGA_SCL")
	)
	(segment
		(start 217.216228 -215.773)
		(end 217.675968 -216.23274)
		(width 0.15494)
		(layer "In13.Cu")
		(net "SMB_PEX1_FPGA_SCL")
	)
	(segment
		(start 207.091788 -213.8426)
		(end 207.944212 -213.8426)
		(width 0.15494)
		(layer "In13.Cu")
		(net "SMB_PEX1_FPGA_SCL")
	)
	(segment
		(start 211.379308 -215.46439)
		(end 211.789518 -215.8746)
		(width 0.15494)
		(layer "In13.Cu")
		(net "SMB_PEX1_FPGA_SCL")
	)
	(segment
		(start 335.000092 -231.22255)
		(end 339.218778 -231.22255)
		(width 0.15494)
		(layer "In13.Cu")
		(net "SMB_PEX1_FPGA_SCL")
	)
	(segment
		(start 323.603366 -234.188)
		(end 325.195946 -234.188)
		(width 0.15494)
		(layer "In13.Cu")
		(net "SMB_PEX1_FPGA_SCL")
	)
	(segment
		(start 322.234306 -232.81894)
		(end 323.603366 -234.188)
		(width 0.15494)
		(layer "In13.Cu")
		(net "SMB_PEX1_FPGA_SCL")
	)
	(segment
		(start 321.622166 -232.823512)
		(end 321.626738 -232.81894)
		(width 0.15494)
		(layer "In13.Cu")
		(net "SMB_PEX1_FPGA_SCL")
	)
	(segment
		(start 230.007922 -209.76844)
		(end 231.973628 -210.58251)
		(width 0.15494)
		(layer "In13.Cu")
		(net "SMB_PEX1_FPGA_SCL")
	)
	(segment
		(start 206.831946 -213.582758)
		(end 207.091788 -213.8426)
		(width 0.15494)
		(layer "In13.Cu")
		(net "SMB_PEX1_FPGA_SCL")
	)
	(segment
		(start 452.167752 -52.035456)
		(end 452.167752 -53.051456)
		(width 0.13208)
		(layer "F.Cu")
		(net "PWRGD_P12V_SSD15")
	)
	(segment
		(start 451.437248 -52.587398)
		(end 451.901306 -53.051456)
		(width 0.13208)
		(layer "F.Cu")
		(net "PWRGD_P12V_SSD15")
	)
	(segment
		(start 450.816218 -53.644038)
		(end 451.437248 -53.023008)
		(width 0.13208)
		(layer "F.Cu")
		(net "PWRGD_P12V_SSD15")
	)
	(segment
		(start 450.447156 -53.644038)
		(end 450.816218 -53.644038)
		(width 0.13208)
		(layer "F.Cu")
		(net "PWRGD_P12V_SSD15")
	)
	(segment
		(start 451.437248 -53.023008)
		(end 451.437248 -52.587398)
		(width 0.13208)
		(layer "F.Cu")
		(net "PWRGD_P12V_SSD15")
	)
	(segment
		(start 451.901306 -53.051456)
		(end 452.167752 -53.051456)
		(width 0.13208)
		(layer "F.Cu")
		(net "PWRGD_P12V_SSD15")
	)
	(via
		(at 451.437248 -52.587398)
		(size 0.508)
		(drill 0.254)
		(layers "F.Cu" "B.Cu")
		(net "PWRGD_P12V_SSD15")
	)
	(segment
		(start 124.644658 -97.177606)
		(end 124.07519 -97.177606)
		(width 0.13208)
		(layer "F.Cu")
		(net "SMB_BIC_I2C9_MUX0_SSD0_SDA")
	)
	(segment
		(start 124.68479 -97.17278)
		(end 125.36932 -97.17278)
		(width 0.13208)
		(layer "F.Cu")
		(net "SMB_BIC_I2C9_MUX0_SSD0_SDA")
	)
	(segment
		(start 125.36932 -97.17278)
		(end 126.751588 -95.790512)
		(width 0.13208)
		(layer "F.Cu")
		(net "SMB_BIC_I2C9_MUX0_SSD0_SDA")
	)
	(segment
		(start 124.68479 -97.17278)
		(end 124.649484 -97.17278)
		(width 0.13208)
		(layer "F.Cu")
		(net "SMB_BIC_I2C9_MUX0_SSD0_SDA")
	)
	(segment
		(start 126.751588 -95.790512)
		(end 127.462534 -95.790512)
		(width 0.13208)
		(layer "F.Cu")
		(net "SMB_BIC_I2C9_MUX0_SSD0_SDA")
	)
	(segment
		(start 124.649484 -97.17278)
		(end 124.644658 -97.177606)
		(width 0.13208)
		(layer "F.Cu")
		(net "SMB_BIC_I2C9_MUX0_SSD0_SDA")
	)
	(via
		(at 124.68479 -97.17278)
		(size 0.508)
		(drill 0.254)
		(layers "F.Cu" "B.Cu")
		(net "SMB_BIC_I2C9_MUX0_SSD0_SDA")
	)
	(segment
		(start 330.424028 -237.271306)
		(end 330.424028 -238.034576)
		(width 0.13208)
		(layer "F.Cu")
		(net "RST_MB_PERST_0_ISO_N")
	)
	(segment
		(start 331.125576 -238.034576)
		(end 331.842364 -238.751364)
		(width 0.13208)
		(layer "F.Cu")
		(net "RST_MB_PERST_0_ISO_N")
	)
	(segment
		(start 331.842364 -238.751364)
		(end 331.842364 -240.848896)
		(width 0.13208)
		(layer "F.Cu")
		(net "RST_MB_PERST_0_ISO_N")
	)
	(segment
		(start 330.424028 -238.034576)
		(end 331.125576 -238.034576)
		(width 0.13208)
		(layer "F.Cu")
		(net "RST_MB_PERST_0_ISO_N")
	)
	(via
		(at 330.424028 -238.034576)
		(size 0.508)
		(drill 0.254)
		(layers "F.Cu" "B.Cu")
		(net "RST_MB_PERST_0_ISO_N")
	)
	(segment
		(start 354.838 -178.562)
		(end 355.45395 -178.562)
		(width 0.13208)
		(layer "F.Cu")
		(net "NIC4_PEX_PWR_EN_R")
	)
	(segment
		(start 350.093788 -213.587076)
		(end 350.493584 -213.18728)
		(width 0.13208)
		(layer "F.Cu")
		(net "NIC4_PEX_PWR_EN_R")
	)
	(segment
		(start 354.22205 -178.562)
		(end 354.838 -178.562)
		(width 0.13208)
		(layer "F.Cu")
		(net "NIC4_PEX_PWR_EN_R")
	)
	(segment
		(start 355.45395 -177.546)
		(end 355.45395 -178.562)
		(width 0.13208)
		(layer "F.Cu")
		(net "NIC4_PEX_PWR_EN_R")
	)
	(via
		(at 365.48822 -181.956202)
		(size 0.508)
		(drill 0.254)
		(layers "F.Cu" "B.Cu")
		(net "NIC4_PEX_PWR_EN_R")
	)
	(via
		(at 354.838 -178.562)
		(size 0.508)
		(drill 0.254)
		(layers "F.Cu" "B.Cu")
		(net "NIC4_PEX_PWR_EN_R")
	)
	(via
		(at 350.493584 -213.18728)
		(size 0.4572)
		(drill 0.254)
		(layers "F.Cu" "B.Cu")
		(net "NIC4_PEX_PWR_EN_R")
	)
	(segment
		(start 365.805466 -182.273448)
		(end 365.805466 -196.649594)
		(width 0.15494)
		(layer "In5.Cu")
		(net "NIC4_PEX_PWR_EN_R")
	)
	(segment
		(start 361.79633 -200.65873)
		(end 361.79633 -202.89647)
		(width 0.15494)
		(layer "In5.Cu")
		(net "NIC4_PEX_PWR_EN_R")
	)
	(segment
		(start 355.1174 -209.2452)
		(end 351.724468 -212.638132)
		(width 0.15494)
		(layer "In5.Cu")
		(net "NIC4_PEX_PWR_EN_R")
	)
	(segment
		(start 357.8098 -208.01076)
		(end 357.8098 -208.3054)
		(width 0.15494)
		(layer "In5.Cu")
		(net "NIC4_PEX_PWR_EN_R")
	)
	(segment
		(start 351.042732 -212.638132)
		(end 350.493584 -213.18728)
		(width 0.15494)
		(layer "In5.Cu")
		(net "NIC4_PEX_PWR_EN_R")
	)
	(segment
		(start 365.805466 -196.649594)
		(end 361.79633 -200.65873)
		(width 0.15494)
		(layer "In5.Cu")
		(net "NIC4_PEX_PWR_EN_R")
	)
	(segment
		(start 356.87 -209.2452)
		(end 355.1174 -209.2452)
		(width 0.15494)
		(layer "In5.Cu")
		(net "NIC4_PEX_PWR_EN_R")
	)
	(segment
		(start 351.724468 -212.638132)
		(end 351.042732 -212.638132)
		(width 0.15494)
		(layer "In5.Cu")
		(net "NIC4_PEX_PWR_EN_R")
	)
	(segment
		(start 361.79633 -202.89647)
		(end 360.4006 -204.2922)
		(width 0.15494)
		(layer "In5.Cu")
		(net "NIC4_PEX_PWR_EN_R")
	)
	(segment
		(start 357.8098 -208.3054)
		(end 356.87 -209.2452)
		(width 0.15494)
		(layer "In5.Cu")
		(net "NIC4_PEX_PWR_EN_R")
	)
	(segment
		(start 365.48822 -181.956202)
		(end 365.805466 -182.273448)
		(width 0.15494)
		(layer "In5.Cu")
		(net "NIC4_PEX_PWR_EN_R")
	)
	(segment
		(start 360.4006 -204.2922)
		(end 360.4006 -205.1304)
		(width 0.15494)
		(layer "In5.Cu")
		(net "NIC4_PEX_PWR_EN_R")
	)
	(segment
		(start 360.4006 -205.1304)
		(end 358.4956 -207.0354)
		(width 0.15494)
		(layer "In5.Cu")
		(net "NIC4_PEX_PWR_EN_R")
	)
	(segment
		(start 358.4956 -207.32496)
		(end 357.8098 -208.01076)
		(width 0.15494)
		(layer "In5.Cu")
		(net "NIC4_PEX_PWR_EN_R")
	)
	(segment
		(start 358.4956 -207.0354)
		(end 358.4956 -207.32496)
		(width 0.15494)
		(layer "In5.Cu")
		(net "NIC4_PEX_PWR_EN_R")
	)
	(segment
		(start 365.48822 -180.66766)
		(end 364.298992 -179.478432)
		(width 0.15494)
		(layer "In13.Cu")
		(net "NIC4_PEX_PWR_EN_R")
	)
	(segment
		(start 360.737404 -179.592224)
		(end 357.757476 -179.592224)
		(width 0.15494)
		(layer "In13.Cu")
		(net "NIC4_PEX_PWR_EN_R")
	)
	(segment
		(start 364.298992 -179.478432)
		(end 360.851196 -179.478432)
		(width 0.15494)
		(layer "In13.Cu")
		(net "NIC4_PEX_PWR_EN_R")
	)
	(segment
		(start 365.48822 -181.956202)
		(end 365.48822 -180.66766)
		(width 0.15494)
		(layer "In13.Cu")
		(net "NIC4_PEX_PWR_EN_R")
	)
	(segment
		(start 357.217726 -179.052474)
		(end 355.328474 -179.052474)
		(width 0.15494)
		(layer "In13.Cu")
		(net "NIC4_PEX_PWR_EN_R")
	)
	(segment
		(start 355.328474 -179.052474)
		(end 354.838 -178.562)
		(width 0.15494)
		(layer "In13.Cu")
		(net "NIC4_PEX_PWR_EN_R")
	)
	(segment
		(start 357.757476 -179.592224)
		(end 357.217726 -179.052474)
		(width 0.15494)
		(layer "In13.Cu")
		(net "NIC4_PEX_PWR_EN_R")
	)
	(segment
		(start 360.851196 -179.478432)
		(end 360.737404 -179.592224)
		(width 0.15494)
		(layer "In13.Cu")
		(net "NIC4_PEX_PWR_EN_R")
	)
	(segment
		(start 255.602486 -81.556352)
		(end 255.801876 -81.556352)
		(width 0.13208)
		(layer "F.Cu")
		(net "XTAL_CK440_25M_XIN")
	)
	(segment
		(start 253.429008 -79.921862)
		(end 254.28067 -80.773524)
		(width 0.13208)
		(layer "F.Cu")
		(net "XTAL_CK440_25M_XIN")
	)
	(segment
		(start 254.28067 -80.773524)
		(end 254.682498 -81.175352)
		(width 0.13208)
		(layer "F.Cu")
		(net "XTAL_CK440_25M_XIN")
	)
	(segment
		(start 254.682498 -81.175352)
		(end 255.602486 -81.556352)
		(width 0.13208)
		(layer "F.Cu")
		(net "XTAL_CK440_25M_XIN")
	)
	(via
		(at 254.28067 -80.773524)
		(size 0.508)
		(drill 0.254)
		(layers "F.Cu" "B.Cu")
		(net "XTAL_CK440_25M_XIN")
	)
	(segment
		(start 125.676406 -89.92489)
		(end 125.676406 -90.309446)
		(width 0.13208)
		(layer "F.Cu")
		(net "SMB_BIC_I2C9_MUX0_SSD3_SCL")
	)
	(segment
		(start 124.928122 -89.176606)
		(end 125.676406 -89.92489)
		(width 0.13208)
		(layer "F.Cu")
		(net "SMB_BIC_I2C9_MUX0_SSD3_SCL")
	)
	(segment
		(start 124.928122 -88.59393)
		(end 124.928122 -89.176606)
		(width 0.13208)
		(layer "F.Cu")
		(net "SMB_BIC_I2C9_MUX0_SSD3_SCL")
	)
	(segment
		(start 126.607316 -91.240356)
		(end 127.462534 -91.240356)
		(width 0.13208)
		(layer "F.Cu")
		(net "SMB_BIC_I2C9_MUX0_SSD3_SCL")
	)
	(segment
		(start 124.724922 -88.39073)
		(end 124.928122 -88.59393)
		(width 0.13208)
		(layer "F.Cu")
		(net "SMB_BIC_I2C9_MUX0_SSD3_SCL")
	)
	(segment
		(start 125.676406 -90.309446)
		(end 126.607316 -91.240356)
		(width 0.13208)
		(layer "F.Cu")
		(net "SMB_BIC_I2C9_MUX0_SSD3_SCL")
	)
	(segment
		(start 124.049028 -88.39073)
		(end 124.724922 -88.39073)
		(width 0.13208)
		(layer "F.Cu")
		(net "SMB_BIC_I2C9_MUX0_SSD3_SCL")
	)
	(via
		(at 124.928122 -89.176606)
		(size 0.508)
		(drill 0.254)
		(layers "F.Cu" "B.Cu")
		(net "SMB_BIC_I2C9_MUX0_SSD3_SCL")
	)
	(segment
		(start 331.978 -230.027988)
		(end 333.20863 -228.797358)
		(width 0.13208)
		(layer "F.Cu")
		(net "RST_MB_PERST_0_ISO_R_N")
	)
	(segment
		(start 331.457046 -236.471206)
		(end 331.457046 -235.850684)
		(width 0.13208)
		(layer "F.Cu")
		(net "RST_MB_PERST_0_ISO_R_N")
	)
	(segment
		(start 331.457046 -235.850684)
		(end 331.978 -235.32973)
		(width 0.13208)
		(layer "F.Cu")
		(net "RST_MB_PERST_0_ISO_R_N")
	)
	(segment
		(start 331.978 -235.32973)
		(end 331.978 -230.027988)
		(width 0.13208)
		(layer "F.Cu")
		(net "RST_MB_PERST_0_ISO_R_N")
	)
	(segment
		(start 330.424028 -236.471206)
		(end 331.457046 -236.471206)
		(width 0.13208)
		(layer "F.Cu")
		(net "RST_MB_PERST_0_ISO_R_N")
	)
	(segment
		(start 333.20863 -228.797358)
		(end 333.20863 -228.072188)
		(width 0.13208)
		(layer "F.Cu")
		(net "RST_MB_PERST_0_ISO_R_N")
	)
	(segment
		(start 333.20863 -228.072188)
		(end 334.09382 -227.186998)
		(width 0.13208)
		(layer "F.Cu")
		(net "RST_MB_PERST_0_ISO_R_N")
	)
	(via
		(at 331.457046 -235.850684)
		(size 0.508)
		(drill 0.254)
		(layers "F.Cu" "B.Cu")
		(net "RST_MB_PERST_0_ISO_R_N")
	)
	(segment
		(start 277.819612 -406.291796)
		(end 277.806658 -406.30475)
		(width 0.13208)
		(layer "F.Cu")
		(net "BIC_SYS_READY_R1_N")
	)
	(segment
		(start 278.105616 -406.005792)
		(end 278.105616 -405.474424)
		(width 0.13208)
		(layer "F.Cu")
		(net "BIC_SYS_READY_R1_N")
	)
	(segment
		(start 277.819612 -406.291796)
		(end 278.105616 -406.005792)
		(width 0.13208)
		(layer "F.Cu")
		(net "BIC_SYS_READY_R1_N")
	)
	(segment
		(start 277.806658 -406.30475)
		(end 277.806658 -408.165046)
		(width 0.13208)
		(layer "F.Cu")
		(net "BIC_SYS_READY_R1_N")
	)
	(via
		(at 277.819612 -406.291796)
		(size 0.508)
		(drill 0.254)
		(layers "F.Cu" "B.Cu")
		(net "BIC_SYS_READY_R1_N")
	)
	(segment
		(start 88.835992 -288.830766)
		(end 88.835992 -288.221166)
		(width 0.13208)
		(layer "F.Cu")
		(net "SMB_PEX0_FPGA_SDA")
	)
	(segment
		(start 338.893912 -225.587052)
		(end 338.494116 -225.986848)
		(width 0.13208)
		(layer "F.Cu")
		(net "SMB_PEX0_FPGA_SDA")
	)
	(via
		(at 94.362778 -207.086962)
		(size 0.508)
		(drill 0.254)
		(layers "F.Cu" "B.Cu")
		(net "SMB_PEX0_FPGA_SDA")
	)
	(via
		(at 93.489018 -234.984544)
		(size 0.508)
		(drill 0.254)
		(layers "F.Cu" "B.Cu")
		(net "SMB_PEX0_FPGA_SDA")
	)
	(via
		(at 338.494116 -225.986848)
		(size 0.4572)
		(drill 0.254)
		(layers "F.Cu" "B.Cu")
		(net "SMB_PEX0_FPGA_SDA")
	)
	(via
		(at 88.835992 -288.221166)
		(size 0.508)
		(drill 0.254)
		(layers "F.Cu" "B.Cu")
		(net "SMB_PEX0_FPGA_SDA")
	)
	(segment
		(start 95.577406 -253.756922)
		(end 89.95283 -248.132346)
		(width 0.13208)
		(layer "B.Cu")
		(net "SMB_PEX0_FPGA_SDA")
	)
	(segment
		(start 89.364566 -288.74974)
		(end 91.113356 -288.74974)
		(width 0.13208)
		(layer "B.Cu")
		(net "SMB_PEX0_FPGA_SDA")
	)
	(segment
		(start 88.835992 -288.221166)
		(end 89.364566 -288.74974)
		(width 0.13208)
		(layer "B.Cu")
		(net "SMB_PEX0_FPGA_SDA")
	)
	(segment
		(start 97.398586 -263.880854)
		(end 98.169222 -263.110218)
		(width 0.13208)
		(layer "B.Cu")
		(net "SMB_PEX0_FPGA_SDA")
	)
	(segment
		(start 91.489276 -281.189176)
		(end 91.489276 -281.18943)
		(width 0.13208)
		(layer "B.Cu")
		(net "SMB_PEX0_FPGA_SDA")
	)
	(segment
		(start 96.833436 -253.756922)
		(end 95.577406 -253.756922)
		(width 0.13208)
		(layer "B.Cu")
		(net "SMB_PEX0_FPGA_SDA")
	)
	(segment
		(start 97.398586 -275.28012)
		(end 97.398586 -263.880854)
		(width 0.13208)
		(layer "B.Cu")
		(net "SMB_PEX0_FPGA_SDA")
	)
	(segment
		(start 98.018092 -254.941832)
		(end 96.833436 -253.756922)
		(width 0.13208)
		(layer "B.Cu")
		(net "SMB_PEX0_FPGA_SDA")
	)
	(segment
		(start 89.95283 -248.132346)
		(end 89.95283 -238.520732)
		(width 0.13208)
		(layer "B.Cu")
		(net "SMB_PEX0_FPGA_SDA")
	)
	(segment
		(start 91.36126 -288.501836)
		(end 91.36126 -281.317192)
		(width 0.13208)
		(layer "B.Cu")
		(net "SMB_PEX0_FPGA_SDA")
	)
	(segment
		(start 98.169222 -263.110218)
		(end 98.169222 -255.092708)
		(width 0.13208)
		(layer "B.Cu")
		(net "SMB_PEX0_FPGA_SDA")
	)
	(segment
		(start 98.169222 -255.092708)
		(end 98.018092 -254.941832)
		(width 0.13208)
		(layer "B.Cu")
		(net "SMB_PEX0_FPGA_SDA")
	)
	(segment
		(start 91.489276 -281.18943)
		(end 97.398586 -275.28012)
		(width 0.13208)
		(layer "B.Cu")
		(net "SMB_PEX0_FPGA_SDA")
	)
	(segment
		(start 91.113356 -288.74974)
		(end 91.36126 -288.501836)
		(width 0.13208)
		(layer "B.Cu")
		(net "SMB_PEX0_FPGA_SDA")
	)
	(segment
		(start 91.36126 -281.317192)
		(end 91.489276 -281.189176)
		(width 0.13208)
		(layer "B.Cu")
		(net "SMB_PEX0_FPGA_SDA")
	)
	(segment
		(start 89.95283 -238.520732)
		(end 93.489018 -234.984544)
		(width 0.13208)
		(layer "B.Cu")
		(net "SMB_PEX0_FPGA_SDA")
	)
	(segment
		(start 93.489018 -211.16925)
		(end 93.489018 -234.984544)
		(width 0.15494)
		(layer "In5.Cu")
		(net "SMB_PEX0_FPGA_SDA")
	)
	(segment
		(start 94.362778 -210.29549)
		(end 93.489018 -211.16925)
		(width 0.15494)
		(layer "In5.Cu")
		(net "SMB_PEX0_FPGA_SDA")
	)
	(segment
		(start 94.362778 -207.086962)
		(end 94.362778 -210.29549)
		(width 0.15494)
		(layer "In5.Cu")
		(net "SMB_PEX0_FPGA_SDA")
	)
	(segment
		(start 193.507868 -211.355432)
		(end 191.154812 -213.708488)
		(width 0.15494)
		(layer "In13.Cu")
		(net "SMB_PEX0_FPGA_SDA")
	)
	(segment
		(start 116.66728 -207.59928)
		(end 99.146614 -207.59928)
		(width 0.15494)
		(layer "In13.Cu")
		(net "SMB_PEX0_FPGA_SDA")
	)
	(segment
		(start 240.8428 -213.909656)
		(end 240.8428 -212.863938)
		(width 0.15494)
		(layer "In13.Cu")
		(net "SMB_PEX0_FPGA_SDA")
	)
	(segment
		(start 232.25506 -209.66303)
		(end 230.289354 -208.84896)
		(width 0.15494)
		(layer "In13.Cu")
		(net "SMB_PEX0_FPGA_SDA")
	)
	(segment
		(start 221.632272 -211.447888)
		(end 219.383864 -213.696296)
		(width 0.15494)
		(layer "In13.Cu")
		(net "SMB_PEX0_FPGA_SDA")
	)
	(segment
		(start 245.066312 -218.148916)
		(end 245.066312 -217.786458)
		(width 0.15494)
		(layer "In13.Cu")
		(net "SMB_PEX0_FPGA_SDA")
	)
	(segment
		(start 208.578196 -212.311996)
		(end 207.621632 -211.355432)
		(width 0.15494)
		(layer "In13.Cu")
		(net "SMB_PEX0_FPGA_SDA")
	)
	(segment
		(start 216.401396 -213.706456)
		(end 216.000076 -213.706456)
		(width 0.15494)
		(layer "In13.Cu")
		(net "SMB_PEX0_FPGA_SDA")
	)
	(segment
		(start 338.092542 -226.388422)
		(end 338.092542 -227.655628)
		(width 0.0889)
		(layer "In13.Cu")
		(net "SMB_PEX0_FPGA_SDA")
	)
	(segment
		(start 216.411556 -213.696296)
		(end 216.401396 -213.706456)
		(width 0.15494)
		(layer "In13.Cu")
		(net "SMB_PEX0_FPGA_SDA")
	)
	(segment
		(start 215.278716 -213.696296)
		(end 211.785454 -213.696296)
		(width 0.15494)
		(layer "In13.Cu")
		(net "SMB_PEX0_FPGA_SDA")
	)
	(segment
		(start 215.288876 -213.706456)
		(end 215.278716 -213.696296)
		(width 0.15494)
		(layer "In13.Cu")
		(net "SMB_PEX0_FPGA_SDA")
	)
	(segment
		(start 191.01562 -213.728808)
		(end 150.212806 -213.728808)
		(width 0.15494)
		(layer "In13.Cu")
		(net "SMB_PEX0_FPGA_SDA")
	)
	(segment
		(start 150.212806 -213.728808)
		(end 148.448014 -215.4936)
		(width 0.15494)
		(layer "In13.Cu")
		(net "SMB_PEX0_FPGA_SDA")
	)
	(segment
		(start 322.793614 -231.434132)
		(end 277.509478 -231.434132)
		(width 0.15494)
		(layer "In13.Cu")
		(net "SMB_PEX0_FPGA_SDA")
	)
	(segment
		(start 326.799702 -230.9749)
		(end 326.736202 -230.9114)
		(width 0.15494)
		(layer "In13.Cu")
		(net "SMB_PEX0_FPGA_SDA")
	)
	(segment
		(start 210.93684 -214.54491)
		(end 209.947002 -214.54491)
		(width 0.15494)
		(layer "In13.Cu")
		(net "SMB_PEX0_FPGA_SDA")
	)
	(segment
		(start 191.03594 -213.708488)
		(end 191.01562 -213.728808)
		(width 0.15494)
		(layer "In13.Cu")
		(net "SMB_PEX0_FPGA_SDA")
	)
	(segment
		(start 221.632272 -209.999326)
		(end 221.632272 -211.447888)
		(width 0.15494)
		(layer "In13.Cu")
		(net "SMB_PEX0_FPGA_SDA")
	)
	(segment
		(start 122.821954 -213.690454)
		(end 116.74348 -207.61198)
		(width 0.15494)
		(layer "In13.Cu")
		(net "SMB_PEX0_FPGA_SDA")
	)
	(segment
		(start 262.432546 -223.9264)
		(end 260.035294 -221.529148)
		(width 0.15494)
		(layer "In13.Cu")
		(net "SMB_PEX0_FPGA_SDA")
	)
	(segment
		(start 333.282544 -228.93655)
		(end 331.244194 -230.9749)
		(width 0.15494)
		(layer "In13.Cu")
		(net "SMB_PEX0_FPGA_SDA")
	)
	(segment
		(start 236.779054 -211.9122)
		(end 234.529884 -209.66303)
		(width 0.15494)
		(layer "In13.Cu")
		(net "SMB_PEX0_FPGA_SDA")
	)
	(segment
		(start 331.244194 -230.9749)
		(end 326.799702 -230.9749)
		(width 0.15494)
		(layer "In13.Cu")
		(net "SMB_PEX0_FPGA_SDA")
	)
	(segment
		(start 125.857508 -213.690454)
		(end 122.821954 -213.690454)
		(width 0.15494)
		(layer "In13.Cu")
		(net "SMB_PEX0_FPGA_SDA")
	)
	(segment
		(start 246.8245 -219.907104)
		(end 245.066312 -218.148916)
		(width 0.15494)
		(layer "In13.Cu")
		(net "SMB_PEX0_FPGA_SDA")
	)
	(segment
		(start 98.818954 -207.92694)
		(end 95.202756 -207.92694)
		(width 0.15494)
		(layer "In13.Cu")
		(net "SMB_PEX0_FPGA_SDA")
	)
	(segment
		(start 254.806704 -219.907104)
		(end 246.8245 -219.907104)
		(width 0.15494)
		(layer "In13.Cu")
		(net "SMB_PEX0_FPGA_SDA")
	)
	(segment
		(start 222.911416 -208.84896)
		(end 222.691452 -208.940146)
		(width 0.15494)
		(layer "In13.Cu")
		(net "SMB_PEX0_FPGA_SDA")
	)
	(segment
		(start 240.8428 -212.863938)
		(end 239.891062 -211.9122)
		(width 0.15494)
		(layer "In13.Cu")
		(net "SMB_PEX0_FPGA_SDA")
	)
	(segment
		(start 242.990116 -215.710262)
		(end 242.643406 -215.710262)
		(width 0.15494)
		(layer "In13.Cu")
		(net "SMB_PEX0_FPGA_SDA")
	)
	(segment
		(start 260.035294 -221.529148)
		(end 256.428748 -221.529148)
		(width 0.15494)
		(layer "In13.Cu")
		(net "SMB_PEX0_FPGA_SDA")
	)
	(segment
		(start 215.700356 -213.696296)
		(end 215.690196 -213.706456)
		(width 0.15494)
		(layer "In13.Cu")
		(net "SMB_PEX0_FPGA_SDA")
	)
	(segment
		(start 334.407002 -228.386132)
		(end 333.856584 -228.93655)
		(width 0.15494)
		(layer "In13.Cu")
		(net "SMB_PEX0_FPGA_SDA")
	)
	(segment
		(start 216.000076 -213.706456)
		(end 215.989916 -213.696296)
		(width 0.15494)
		(layer "In13.Cu")
		(net "SMB_PEX0_FPGA_SDA")
	)
	(segment
		(start 239.891062 -211.9122)
		(end 236.779054 -211.9122)
		(width 0.15494)
		(layer "In13.Cu")
		(net "SMB_PEX0_FPGA_SDA")
	)
	(segment
		(start 99.146614 -207.59928)
		(end 98.818954 -207.92694)
		(width 0.15494)
		(layer "In13.Cu")
		(net "SMB_PEX0_FPGA_SDA")
	)
	(segment
		(start 207.621632 -211.355432)
		(end 193.507868 -211.355432)
		(width 0.15494)
		(layer "In13.Cu")
		(net "SMB_PEX0_FPGA_SDA")
	)
	(segment
		(start 134.493 -216.3064)
		(end 128.473454 -216.3064)
		(width 0.15494)
		(layer "In13.Cu")
		(net "SMB_PEX0_FPGA_SDA")
	)
	(segment
		(start 95.202756 -207.92694)
		(end 94.362778 -207.086962)
		(width 0.15494)
		(layer "In13.Cu")
		(net "SMB_PEX0_FPGA_SDA")
	)
	(segment
		(start 326.736202 -230.9114)
		(end 323.316346 -230.9114)
		(width 0.15494)
		(layer "In13.Cu")
		(net "SMB_PEX0_FPGA_SDA")
	)
	(segment
		(start 128.473454 -216.3064)
		(end 125.857508 -213.690454)
		(width 0.15494)
		(layer "In13.Cu")
		(net "SMB_PEX0_FPGA_SDA")
	)
	(segment
		(start 211.785454 -213.696296)
		(end 210.93684 -214.54491)
		(width 0.15494)
		(layer "In13.Cu")
		(net "SMB_PEX0_FPGA_SDA")
	)
	(segment
		(start 277.509478 -231.434132)
		(end 270.001746 -223.9264)
		(width 0.15494)
		(layer "In13.Cu")
		(net "SMB_PEX0_FPGA_SDA")
	)
	(segment
		(start 136.663684 -215.2396)
		(end 135.5598 -215.2396)
		(width 0.15494)
		(layer "In13.Cu")
		(net "SMB_PEX0_FPGA_SDA")
	)
	(segment
		(start 116.67998 -207.61198)
		(end 116.66728 -207.59928)
		(width 0.15494)
		(layer "In13.Cu")
		(net "SMB_PEX0_FPGA_SDA")
	)
	(segment
		(start 116.74348 -207.61198)
		(end 116.67998 -207.61198)
		(width 0.15494)
		(layer "In13.Cu")
		(net "SMB_PEX0_FPGA_SDA")
	)
	(segment
		(start 191.154812 -213.708488)
		(end 191.03594 -213.708488)
		(width 0.15494)
		(layer "In13.Cu")
		(net "SMB_PEX0_FPGA_SDA")
	)
	(segment
		(start 219.383864 -213.696296)
		(end 216.411556 -213.696296)
		(width 0.15494)
		(layer "In13.Cu")
		(net "SMB_PEX0_FPGA_SDA")
	)
	(segment
		(start 270.001746 -223.9264)
		(end 262.432546 -223.9264)
		(width 0.15494)
		(layer "In13.Cu")
		(net "SMB_PEX0_FPGA_SDA")
	)
	(segment
		(start 245.066312 -217.786458)
		(end 242.990116 -215.710262)
		(width 0.15494)
		(layer "In13.Cu")
		(net "SMB_PEX0_FPGA_SDA")
	)
	(segment
		(start 148.448014 -215.4936)
		(end 136.917684 -215.4936)
		(width 0.15494)
		(layer "In13.Cu")
		(net "SMB_PEX0_FPGA_SDA")
	)
	(segment
		(start 333.856584 -228.93655)
		(end 333.282544 -228.93655)
		(width 0.15494)
		(layer "In13.Cu")
		(net "SMB_PEX0_FPGA_SDA")
	)
	(segment
		(start 208.578196 -213.176104)
		(end 208.578196 -212.311996)
		(width 0.15494)
		(layer "In13.Cu")
		(net "SMB_PEX0_FPGA_SDA")
	)
	(segment
		(start 234.529884 -209.66303)
		(end 232.25506 -209.66303)
		(width 0.15494)
		(layer "In13.Cu")
		(net "SMB_PEX0_FPGA_SDA")
	)
	(segment
		(start 222.691452 -208.940146)
		(end 221.632272 -209.999326)
		(width 0.15494)
		(layer "In13.Cu")
		(net "SMB_PEX0_FPGA_SDA")
	)
	(segment
		(start 337.362038 -228.386132)
		(end 334.407002 -228.386132)
		(width 0.15494)
		(layer "In13.Cu")
		(net "SMB_PEX0_FPGA_SDA")
	)
	(segment
		(start 136.917684 -215.4936)
		(end 136.663684 -215.2396)
		(width 0.15494)
		(layer "In13.Cu")
		(net "SMB_PEX0_FPGA_SDA")
	)
	(segment
		(start 230.289354 -208.84896)
		(end 222.911416 -208.84896)
		(width 0.15494)
		(layer "In13.Cu")
		(net "SMB_PEX0_FPGA_SDA")
	)
	(segment
		(start 209.947002 -214.54491)
		(end 208.578196 -213.176104)
		(width 0.15494)
		(layer "In13.Cu")
		(net "SMB_PEX0_FPGA_SDA")
	)
	(segment
		(start 338.494116 -225.986848)
		(end 338.092542 -226.388422)
		(width 0.0889)
		(layer "In13.Cu")
		(net "SMB_PEX0_FPGA_SDA")
	)
	(segment
		(start 215.989916 -213.696296)
		(end 215.700356 -213.696296)
		(width 0.15494)
		(layer "In13.Cu")
		(net "SMB_PEX0_FPGA_SDA")
	)
	(segment
		(start 215.690196 -213.706456)
		(end 215.288876 -213.706456)
		(width 0.15494)
		(layer "In13.Cu")
		(net "SMB_PEX0_FPGA_SDA")
	)
	(segment
		(start 256.428748 -221.529148)
		(end 254.806704 -219.907104)
		(width 0.15494)
		(layer "In13.Cu")
		(net "SMB_PEX0_FPGA_SDA")
	)
	(segment
		(start 242.643406 -215.710262)
		(end 240.8428 -213.909656)
		(width 0.15494)
		(layer "In13.Cu")
		(net "SMB_PEX0_FPGA_SDA")
	)
	(segment
		(start 338.092542 -227.655628)
		(end 337.362038 -228.386132)
		(width 0.15494)
		(layer "In13.Cu")
		(net "SMB_PEX0_FPGA_SDA")
	)
	(segment
		(start 135.5598 -215.2396)
		(end 134.493 -216.3064)
		(width 0.15494)
		(layer "In13.Cu")
		(net "SMB_PEX0_FPGA_SDA")
	)
	(segment
		(start 323.316346 -230.9114)
		(end 322.793614 -231.434132)
		(width 0.15494)
		(layer "In13.Cu")
		(net "SMB_PEX0_FPGA_SDA")
	)
	(segment
		(start 381.470154 -209.06867)
		(end 379.921262 -209.06867)
		(width 0.13208)
		(layer "F.Cu")
		(net "NIC0_PEX_PWR_EN_R")
	)
	(segment
		(start 381.65405 -207.518)
		(end 381.65405 -208.534)
		(width 0.13208)
		(layer "F.Cu")
		(net "NIC0_PEX_PWR_EN_R")
	)
	(segment
		(start 381.65405 -208.534)
		(end 381.65405 -208.884774)
		(width 0.13208)
		(layer "F.Cu")
		(net "NIC0_PEX_PWR_EN_R")
	)
	(segment
		(start 381.65405 -208.884774)
		(end 381.470154 -209.06867)
		(width 0.13208)
		(layer "F.Cu")
		(net "NIC0_PEX_PWR_EN_R")
	)
	(segment
		(start 350.093788 -215.987122)
		(end 350.493584 -215.587326)
		(width 0.13208)
		(layer "F.Cu")
		(net "NIC0_PEX_PWR_EN_R")
	)
	(segment
		(start 381.65405 -206.502)
		(end 381.65405 -207.518)
		(width 0.13208)
		(layer "F.Cu")
		(net "NIC0_PEX_PWR_EN_R")
	)
	(segment
		(start 379.921262 -209.06867)
		(end 379.245368 -208.392776)
		(width 0.13208)
		(layer "F.Cu")
		(net "NIC0_PEX_PWR_EN_R")
	)
	(via
		(at 379.245368 -208.392776)
		(size 0.508)
		(drill 0.254)
		(layers "F.Cu" "B.Cu")
		(net "NIC0_PEX_PWR_EN_R")
	)
	(via
		(at 369.444016 -197.50405)
		(size 0.508)
		(drill 0.254)
		(layers "F.Cu" "B.Cu")
		(net "NIC0_PEX_PWR_EN_R")
	)
	(via
		(at 350.493584 -215.587326)
		(size 0.4572)
		(drill 0.254)
		(layers "F.Cu" "B.Cu")
		(net "NIC0_PEX_PWR_EN_R")
	)
	(segment
		(start 358.5718 -209.804)
		(end 359.6894 -209.804)
		(width 0.15494)
		(layer "In5.Cu")
		(net "NIC0_PEX_PWR_EN_R")
	)
	(segment
		(start 359.6894 -209.804)
		(end 361.9246 -207.5688)
		(width 0.15494)
		(layer "In5.Cu")
		(net "NIC0_PEX_PWR_EN_R")
	)
	(segment
		(start 362.13796 -206.39913)
		(end 362.852208 -206.39913)
		(width 0.15494)
		(layer "In5.Cu")
		(net "NIC0_PEX_PWR_EN_R")
	)
	(segment
		(start 361.9246 -207.5688)
		(end 361.9246 -206.61249)
		(width 0.15494)
		(layer "In5.Cu")
		(net "NIC0_PEX_PWR_EN_R")
	)
	(segment
		(start 369.444016 -198.148702)
		(end 369.444016 -197.50405)
		(width 0.15494)
		(layer "In5.Cu")
		(net "NIC0_PEX_PWR_EN_R")
	)
	(segment
		(start 351.0788 -215.587326)
		(end 353.842066 -212.82406)
		(width 0.15494)
		(layer "In5.Cu")
		(net "NIC0_PEX_PWR_EN_R")
	)
	(segment
		(start 361.9246 -206.61249)
		(end 362.13796 -206.39913)
		(width 0.15494)
		(layer "In5.Cu")
		(net "NIC0_PEX_PWR_EN_R")
	)
	(segment
		(start 365.510572 -202.082146)
		(end 369.444016 -198.148702)
		(width 0.15494)
		(layer "In5.Cu")
		(net "NIC0_PEX_PWR_EN_R")
	)
	(segment
		(start 357.505 -210.8708)
		(end 358.5718 -209.804)
		(width 0.15494)
		(layer "In5.Cu")
		(net "NIC0_PEX_PWR_EN_R")
	)
	(segment
		(start 362.852208 -206.39913)
		(end 365.510572 -203.740766)
		(width 0.15494)
		(layer "In5.Cu")
		(net "NIC0_PEX_PWR_EN_R")
	)
	(segment
		(start 350.493584 -215.587326)
		(end 351.0788 -215.587326)
		(width 0.15494)
		(layer "In5.Cu")
		(net "NIC0_PEX_PWR_EN_R")
	)
	(segment
		(start 356.5144 -210.8708)
		(end 357.505 -210.8708)
		(width 0.15494)
		(layer "In5.Cu")
		(net "NIC0_PEX_PWR_EN_R")
	)
	(segment
		(start 353.842066 -212.82406)
		(end 354.56114 -212.82406)
		(width 0.15494)
		(layer "In5.Cu")
		(net "NIC0_PEX_PWR_EN_R")
	)
	(segment
		(start 365.510572 -203.740766)
		(end 365.510572 -202.082146)
		(width 0.15494)
		(layer "In5.Cu")
		(net "NIC0_PEX_PWR_EN_R")
	)
	(segment
		(start 354.56114 -212.82406)
		(end 356.5144 -210.8708)
		(width 0.15494)
		(layer "In5.Cu")
		(net "NIC0_PEX_PWR_EN_R")
	)
	(segment
		(start 370.376196 -197.50405)
		(end 369.444016 -197.50405)
		(width 0.15494)
		(layer "In13.Cu")
		(net "NIC0_PEX_PWR_EN_R")
	)
	(segment
		(start 379.245368 -208.392776)
		(end 379.245368 -206.373222)
		(width 0.15494)
		(layer "In13.Cu")
		(net "NIC0_PEX_PWR_EN_R")
	)
	(segment
		(start 379.245368 -206.373222)
		(end 370.376196 -197.50405)
		(width 0.15494)
		(layer "In13.Cu")
		(net "NIC0_PEX_PWR_EN_R")
	)
	(segment
		(start 308.67985 -51.670966)
		(end 309.33136 -51.019456)
		(width 0.13208)
		(layer "F.Cu")
		(net "P12V_SSD10_SS")
	)
	(segment
		(start 308.530498 -53.144166)
		(end 308.67985 -52.994814)
		(width 0.13208)
		(layer "F.Cu")
		(net "P12V_SSD10_SS")
	)
	(segment
		(start 308.67985 -52.994814)
		(end 308.67985 -51.670966)
		(width 0.13208)
		(layer "F.Cu")
		(net "P12V_SSD10_SS")
	)
	(segment
		(start 309.33136 -51.019456)
		(end 310.067706 -51.019456)
		(width 0.13208)
		(layer "F.Cu")
		(net "P12V_SSD10_SS")
	)
	(segment
		(start 308.34711 -53.144166)
		(end 308.530498 -53.144166)
		(width 0.13208)
		(layer "F.Cu")
		(net "P12V_SSD10_SS")
	)
	(via
		(at 309.33136 -51.019456)
		(size 0.508)
		(drill 0.254)
		(layers "F.Cu" "B.Cu")
		(net "P12V_SSD10_SS")
	)
	(via
		(at 367.980722 -237.639352)
		(size 0.6604)
		(drill 0.3302)
		(layers "F.Cu" "B.Cu")
		(net "FT4232_SDB_EEPROM_R_SDA")
	)
	(segment
		(start 367.173256 -237.744)
		(end 367.277904 -237.639352)
		(width 0.13208)
		(layer "B.Cu")
		(net "FT4232_SDB_EEPROM_R_SDA")
	)
	(segment
		(start 367.277904 -237.639352)
		(end 367.980722 -237.639352)
		(width 0.13208)
		(layer "B.Cu")
		(net "FT4232_SDB_EEPROM_R_SDA")
	)
	(segment
		(start 367.980722 -237.639352)
		(end 369.521486 -237.639352)
		(width 0.13208)
		(layer "B.Cu")
		(net "FT4232_SDB_EEPROM_R_SDA")
	)
	(segment
		(start 366.66805 -237.744)
		(end 367.173256 -237.744)
		(width 0.13208)
		(layer "B.Cu")
		(net "FT4232_SDB_EEPROM_R_SDA")
	)
	(segment
		(start 366.66805 -236.601)
		(end 366.66805 -237.744)
		(width 0.13208)
		(layer "B.Cu")
		(net "FT4232_SDB_EEPROM_R_SDA")
	)
	(segment
		(start 262.170926 -79.923132)
		(end 261.926832 -80.167226)
		(width 0.13208)
		(layer "F.Cu")
		(net "CLK_GEN_CK440_OE3_N")
	)
	(segment
		(start 261.726172 -78.860904)
		(end 262.170926 -79.305658)
		(width 0.13208)
		(layer "F.Cu")
		(net "CLK_GEN_CK440_OE3_N")
	)
	(segment
		(start 261.726172 -78.300326)
		(end 261.726172 -78.860904)
		(width 0.13208)
		(layer "F.Cu")
		(net "CLK_GEN_CK440_OE3_N")
	)
	(segment
		(start 261.528306 -78.10246)
		(end 261.726172 -78.300326)
		(width 0.13208)
		(layer "F.Cu")
		(net "CLK_GEN_CK440_OE3_N")
	)
	(segment
		(start 261.926832 -80.167226)
		(end 261.926832 -80.431386)
		(width 0.13208)
		(layer "F.Cu")
		(net "CLK_GEN_CK440_OE3_N")
	)
	(segment
		(start 262.170926 -79.305658)
		(end 262.170926 -79.923132)
		(width 0.13208)
		(layer "F.Cu")
		(net "CLK_GEN_CK440_OE3_N")
	)
	(segment
		(start 261.528306 -77.679804)
		(end 261.528306 -78.10246)
		(width 0.13208)
		(layer "F.Cu")
		(net "CLK_GEN_CK440_OE3_N")
	)
	(via
		(at 261.726172 -78.860904)
		(size 0.762)
		(drill 0.381)
		(layers "F.Cu" "B.Cu")
		(net "CLK_GEN_CK440_OE3_N")
	)
	(segment
		(start 125.989842 -92.179902)
		(end 126.350268 -92.540328)
		(width 0.13208)
		(layer "F.Cu")
		(net "SMB_BIC_I2C9_MUX0_SSD2_SCL")
	)
	(segment
		(start 126.350268 -92.540328)
		(end 127.462534 -92.540328)
		(width 0.13208)
		(layer "F.Cu")
		(net "SMB_BIC_I2C9_MUX0_SSD2_SCL")
	)
	(segment
		(start 124.734574 -91.462606)
		(end 124.07519 -91.462606)
		(width 0.13208)
		(layer "F.Cu")
		(net "SMB_BIC_I2C9_MUX0_SSD2_SCL")
	)
	(segment
		(start 125.989842 -92.179902)
		(end 125.45187 -92.179902)
		(width 0.13208)
		(layer "F.Cu")
		(net "SMB_BIC_I2C9_MUX0_SSD2_SCL")
	)
	(segment
		(start 125.45187 -92.179902)
		(end 124.734574 -91.462606)
		(width 0.13208)
		(layer "F.Cu")
		(net "SMB_BIC_I2C9_MUX0_SSD2_SCL")
	)
	(via
		(at 125.989842 -92.179902)
		(size 0.508)
		(drill 0.254)
		(layers "F.Cu" "B.Cu")
		(net "SMB_BIC_I2C9_MUX0_SSD2_SCL")
	)
	(segment
		(start 347.693742 -225.587052)
		(end 348.093538 -225.986848)
		(width 0.13208)
		(layer "F.Cu")
		(net "RST_SSD6_PERST_N")
	)
	(via
		(at 348.093538 -225.986848)
		(size 0.4572)
		(drill 0.254)
		(layers "F.Cu" "B.Cu")
		(net "RST_SSD6_PERST_N")
	)
	(via
		(at 348.6404 -230.240332)
		(size 0.6604)
		(drill 0.3302)
		(layers "F.Cu" "B.Cu")
		(net "RST_SSD6_PERST_N")
	)
	(segment
		(start 348.488 -231.75595)
		(end 348.488 -231.14)
		(width 0.13208)
		(layer "B.Cu")
		(net "RST_SSD6_PERST_N")
	)
	(segment
		(start 348.493588 -229.559104)
		(end 348.6404 -229.705916)
		(width 0.13208)
		(layer "B.Cu")
		(net "RST_SSD6_PERST_N")
	)
	(segment
		(start 348.488 -231.14)
		(end 348.6404 -230.9876)
		(width 0.13208)
		(layer "B.Cu")
		(net "RST_SSD6_PERST_N")
	)
	(segment
		(start 348.6404 -229.705916)
		(end 348.6404 -230.240332)
		(width 0.13208)
		(layer "B.Cu")
		(net "RST_SSD6_PERST_N")
	)
	(segment
		(start 347.091 -233.15295)
		(end 348.488 -231.75595)
		(width 0.13208)
		(layer "B.Cu")
		(net "RST_SSD6_PERST_N")
	)
	(segment
		(start 348.6404 -230.9876)
		(end 348.6404 -230.240332)
		(width 0.13208)
		(layer "B.Cu")
		(net "RST_SSD6_PERST_N")
	)
	(segment
		(start 348.093538 -225.986848)
		(end 348.493588 -226.386898)
		(width 0.0889)
		(layer "B.Cu")
		(net "RST_SSD6_PERST_N")
	)
	(segment
		(start 348.493588 -226.386898)
		(end 348.493588 -227.203)
		(width 0.0889)
		(layer "B.Cu")
		(net "RST_SSD6_PERST_N")
	)
	(segment
		(start 348.493588 -227.203)
		(end 348.493588 -229.559104)
		(width 0.13208)
		(layer "B.Cu")
		(net "RST_SSD6_PERST_N")
	)
	(segment
		(start 189.049914 -291.149786)
		(end 188.574934 -290.674806)
		(width 0.13208)
		(layer "F.Cu")
		(net "UART_PEX1_SDB_BUF_RX")
	)
	(via
		(at 191.900048 -282.599892)
		(size 0.6604)
		(drill 0.3302)
		(layers "F.Cu" "B.Cu")
		(net "UART_PEX1_SDB_BUF_RX")
	)
	(via
		(at 188.574934 -290.674806)
		(size 0.4064)
		(drill 0.2032)
		(layers "F.Cu" "B.Cu")
		(net "UART_PEX1_SDB_BUF_RX")
	)
	(via
		(at 188.571378 -251.066808)
		(size 0.508)
		(drill 0.254)
		(layers "F.Cu" "B.Cu")
		(net "UART_PEX1_SDB_BUF_RX")
	)
	(via
		(at 377.987052 -221.701106)
		(size 0.508)
		(drill 0.254)
		(layers "F.Cu" "B.Cu")
		(net "UART_PEX1_SDB_BUF_RX")
	)
	(segment
		(start 192.3542 -288.4424)
		(end 192.3542 -283.054044)
		(width 0.13208)
		(layer "B.Cu")
		(net "UART_PEX1_SDB_BUF_RX")
	)
	(segment
		(start 188.571378 -252.932184)
		(end 188.571378 -251.066808)
		(width 0.13208)
		(layer "B.Cu")
		(net "UART_PEX1_SDB_BUF_RX")
	)
	(segment
		(start 188.574934 -290.674806)
		(end 189.045088 -290.204652)
		(width 0.13208)
		(layer "B.Cu")
		(net "UART_PEX1_SDB_BUF_RX")
	)
	(segment
		(start 192.3542 -283.054044)
		(end 191.900048 -282.599892)
		(width 0.13208)
		(layer "B.Cu")
		(net "UART_PEX1_SDB_BUF_RX")
	)
	(segment
		(start 192.375028 -282.124912)
		(end 192.375028 -271.69237)
		(width 0.13208)
		(layer "B.Cu")
		(net "UART_PEX1_SDB_BUF_RX")
	)
	(segment
		(start 192.375028 -271.69237)
		(end 188.25972 -267.577062)
		(width 0.13208)
		(layer "B.Cu")
		(net "UART_PEX1_SDB_BUF_RX")
	)
	(segment
		(start 378.964952 -221.066106)
		(end 377.987052 -221.066106)
		(width 0.13208)
		(layer "B.Cu")
		(net "UART_PEX1_SDB_BUF_RX")
	)
	(segment
		(start 188.25972 -253.243842)
		(end 188.571378 -252.932184)
		(width 0.13208)
		(layer "B.Cu")
		(net "UART_PEX1_SDB_BUF_RX")
	)
	(segment
		(start 191.900048 -282.599892)
		(end 192.375028 -282.124912)
		(width 0.13208)
		(layer "B.Cu")
		(net "UART_PEX1_SDB_BUF_RX")
	)
	(segment
		(start 377.987052 -221.066106)
		(end 377.987052 -221.701106)
		(width 0.13208)
		(layer "B.Cu")
		(net "UART_PEX1_SDB_BUF_RX")
	)
	(segment
		(start 189.045088 -290.204652)
		(end 189.045088 -289.47618)
		(width 0.13208)
		(layer "B.Cu")
		(net "UART_PEX1_SDB_BUF_RX")
	)
	(segment
		(start 191.9986 -288.798)
		(end 192.3542 -288.4424)
		(width 0.13208)
		(layer "B.Cu")
		(net "UART_PEX1_SDB_BUF_RX")
	)
	(segment
		(start 189.045088 -289.47618)
		(end 189.723268 -288.798)
		(width 0.13208)
		(layer "B.Cu")
		(net "UART_PEX1_SDB_BUF_RX")
	)
	(segment
		(start 188.25972 -267.577062)
		(end 188.25972 -253.243842)
		(width 0.13208)
		(layer "B.Cu")
		(net "UART_PEX1_SDB_BUF_RX")
	)
	(segment
		(start 189.723268 -288.798)
		(end 191.9986 -288.798)
		(width 0.13208)
		(layer "B.Cu")
		(net "UART_PEX1_SDB_BUF_RX")
	)
	(segment
		(start 350.458278 -245.97614)
		(end 360.325162 -236.109256)
		(width 0.15494)
		(layer "In13.Cu")
		(net "UART_PEX1_SDB_BUF_RX")
	)
	(segment
		(start 270.69415 -254.26289)
		(end 271.04086 -254.6096)
		(width 0.15494)
		(layer "In13.Cu")
		(net "UART_PEX1_SDB_BUF_RX")
	)
	(segment
		(start 367.394744 -236.109256)
		(end 368.3762 -235.1278)
		(width 0.15494)
		(layer "In13.Cu")
		(net "UART_PEX1_SDB_BUF_RX")
	)
	(segment
		(start 252.532642 -252.90272)
		(end 253.892812 -254.26289)
		(width 0.15494)
		(layer "In13.Cu")
		(net "UART_PEX1_SDB_BUF_RX")
	)
	(segment
		(start 377.444 -228.1174)
		(end 377.444 -222.732854)
		(width 0.15494)
		(layer "In13.Cu")
		(net "UART_PEX1_SDB_BUF_RX")
	)
	(segment
		(start 341.63762 -251.27204)
		(end 346.93352 -245.97614)
		(width 0.15494)
		(layer "In13.Cu")
		(net "UART_PEX1_SDB_BUF_RX")
	)
	(segment
		(start 189.575186 -250.063)
		(end 228.308408 -250.063)
		(width 0.15494)
		(layer "In13.Cu")
		(net "UART_PEX1_SDB_BUF_RX")
	)
	(segment
		(start 297.509946 -254.6096)
		(end 300.860968 -257.960622)
		(width 0.15494)
		(layer "In13.Cu")
		(net "UART_PEX1_SDB_BUF_RX")
	)
	(segment
		(start 305.817778 -257.960622)
		(end 308.08549 -255.69291)
		(width 0.15494)
		(layer "In13.Cu")
		(net "UART_PEX1_SDB_BUF_RX")
	)
	(segment
		(start 229.296468 -251.05106)
		(end 232.981246 -251.05106)
		(width 0.15494)
		(layer "In13.Cu")
		(net "UART_PEX1_SDB_BUF_RX")
	)
	(segment
		(start 319.00622 -254.576326)
		(end 338.806028 -254.576326)
		(width 0.15494)
		(layer "In13.Cu")
		(net "UART_PEX1_SDB_BUF_RX")
	)
	(segment
		(start 232.981246 -251.05106)
		(end 234.00385 -252.073664)
		(width 0.15494)
		(layer "In13.Cu")
		(net "UART_PEX1_SDB_BUF_RX")
	)
	(segment
		(start 253.892812 -254.26289)
		(end 270.69415 -254.26289)
		(width 0.15494)
		(layer "In13.Cu")
		(net "UART_PEX1_SDB_BUF_RX")
	)
	(segment
		(start 370.4336 -235.1278)
		(end 377.444 -228.1174)
		(width 0.15494)
		(layer "In13.Cu")
		(net "UART_PEX1_SDB_BUF_RX")
	)
	(segment
		(start 317.889636 -255.69291)
		(end 319.00622 -254.576326)
		(width 0.15494)
		(layer "In13.Cu")
		(net "UART_PEX1_SDB_BUF_RX")
	)
	(segment
		(start 308.08549 -255.69291)
		(end 317.889636 -255.69291)
		(width 0.15494)
		(layer "In13.Cu")
		(net "UART_PEX1_SDB_BUF_RX")
	)
	(segment
		(start 271.04086 -254.6096)
		(end 297.509946 -254.6096)
		(width 0.15494)
		(layer "In13.Cu")
		(net "UART_PEX1_SDB_BUF_RX")
	)
	(segment
		(start 235.139484 -252.073664)
		(end 235.96854 -252.90272)
		(width 0.15494)
		(layer "In13.Cu")
		(net "UART_PEX1_SDB_BUF_RX")
	)
	(segment
		(start 346.93352 -245.97614)
		(end 350.458278 -245.97614)
		(width 0.15494)
		(layer "In13.Cu")
		(net "UART_PEX1_SDB_BUF_RX")
	)
	(segment
		(start 228.308408 -250.063)
		(end 229.296468 -251.05106)
		(width 0.15494)
		(layer "In13.Cu")
		(net "UART_PEX1_SDB_BUF_RX")
	)
	(segment
		(start 377.987052 -222.189802)
		(end 377.987052 -221.701106)
		(width 0.15494)
		(layer "In13.Cu")
		(net "UART_PEX1_SDB_BUF_RX")
	)
	(segment
		(start 235.96854 -252.90272)
		(end 252.532642 -252.90272)
		(width 0.15494)
		(layer "In13.Cu")
		(net "UART_PEX1_SDB_BUF_RX")
	)
	(segment
		(start 234.00385 -252.073664)
		(end 235.139484 -252.073664)
		(width 0.15494)
		(layer "In13.Cu")
		(net "UART_PEX1_SDB_BUF_RX")
	)
	(segment
		(start 188.571378 -251.066808)
		(end 189.575186 -250.063)
		(width 0.15494)
		(layer "In13.Cu")
		(net "UART_PEX1_SDB_BUF_RX")
	)
	(segment
		(start 368.3762 -235.1278)
		(end 370.4336 -235.1278)
		(width 0.15494)
		(layer "In13.Cu")
		(net "UART_PEX1_SDB_BUF_RX")
	)
	(segment
		(start 377.444 -222.732854)
		(end 377.987052 -222.189802)
		(width 0.15494)
		(layer "In13.Cu")
		(net "UART_PEX1_SDB_BUF_RX")
	)
	(segment
		(start 338.806028 -254.576326)
		(end 341.63762 -251.744734)
		(width 0.15494)
		(layer "In13.Cu")
		(net "UART_PEX1_SDB_BUF_RX")
	)
	(segment
		(start 300.860968 -257.960622)
		(end 305.817778 -257.960622)
		(width 0.15494)
		(layer "In13.Cu")
		(net "UART_PEX1_SDB_BUF_RX")
	)
	(segment
		(start 341.63762 -251.744734)
		(end 341.63762 -251.27204)
		(width 0.15494)
		(layer "In13.Cu")
		(net "UART_PEX1_SDB_BUF_RX")
	)
	(segment
		(start 360.325162 -236.109256)
		(end 367.394744 -236.109256)
		(width 0.15494)
		(layer "In13.Cu")
		(net "UART_PEX1_SDB_BUF_RX")
	)
	(via
		(at 374.015 -237.572296)
		(size 0.6604)
		(drill 0.3302)
		(layers "F.Cu" "B.Cu")
		(net "FT4232_SDB_EEPROM_R_SCL")
	)
	(segment
		(start 375.18848 -238.588296)
		(end 375.18848 -237.572296)
		(width 0.13208)
		(layer "B.Cu")
		(net "FT4232_SDB_EEPROM_R_SCL")
	)
	(segment
		(start 372.388638 -237.572296)
		(end 374.015 -237.572296)
		(width 0.13208)
		(layer "B.Cu")
		(net "FT4232_SDB_EEPROM_R_SCL")
	)
	(segment
		(start 372.321582 -237.639352)
		(end 372.388638 -237.572296)
		(width 0.13208)
		(layer "B.Cu")
		(net "FT4232_SDB_EEPROM_R_SCL")
	)
	(segment
		(start 374.015 -237.572296)
		(end 375.18848 -237.572296)
		(width 0.13208)
		(layer "B.Cu")
		(net "FT4232_SDB_EEPROM_R_SCL")
	)
	(segment
		(start 258.176776 -81.181448)
		(end 258.176776 -79.791306)
		(width 0.0889)
		(layer "F.Cu")
		(net "CLK_GEN_CK440_OE6_N")
	)
	(segment
		(start 258.176776 -79.791306)
		(end 257.470656 -79.085186)
		(width 0.13208)
		(layer "F.Cu")
		(net "CLK_GEN_CK440_OE6_N")
	)
	(segment
		(start 258.22529 -78.330552)
		(end 257.470656 -79.085186)
		(width 0.13208)
		(layer "F.Cu")
		(net "CLK_GEN_CK440_OE6_N")
	)
	(segment
		(start 258.22529 -77.679804)
		(end 258.22529 -78.330552)
		(width 0.13208)
		(layer "F.Cu")
		(net "CLK_GEN_CK440_OE6_N")
	)
	(via
		(at 257.470656 -79.085186)
		(size 0.762)
		(drill 0.381)
		(layers "F.Cu" "B.Cu")
		(net "CLK_GEN_CK440_OE6_N")
	)
	(segment
		(start 125.100334 -93.190314)
		(end 127.462534 -93.190314)
		(width 0.13208)
		(layer "F.Cu")
		(net "SMB_BIC_I2C9_MUX0_SSD2_SDA")
	)
	(segment
		(start 124.07519 -92.605606)
		(end 124.515626 -92.605606)
		(width 0.13208)
		(layer "F.Cu")
		(net "SMB_BIC_I2C9_MUX0_SSD2_SDA")
	)
	(segment
		(start 124.515626 -92.605606)
		(end 124.727462 -92.817442)
		(width 0.13208)
		(layer "F.Cu")
		(net "SMB_BIC_I2C9_MUX0_SSD2_SDA")
	)
	(segment
		(start 124.727462 -92.817442)
		(end 125.100334 -93.190314)
		(width 0.13208)
		(layer "F.Cu")
		(net "SMB_BIC_I2C9_MUX0_SSD2_SDA")
	)
	(via
		(at 124.727462 -92.817442)
		(size 0.508)
		(drill 0.254)
		(layers "F.Cu" "B.Cu")
		(net "SMB_BIC_I2C9_MUX0_SSD2_SDA")
	)
	(segment
		(start 276.883622 -413.587438)
		(end 277.806658 -412.664402)
		(width 0.13208)
		(layer "F.Cu")
		(net "RST_MB_BMC_R_N")
	)
	(segment
		(start 276.883622 -413.987234)
		(end 276.883622 -413.587438)
		(width 0.13208)
		(layer "F.Cu")
		(net "RST_MB_BMC_R_N")
	)
	(segment
		(start 277.806658 -412.664402)
		(end 277.806658 -411.86481)
		(width 0.13208)
		(layer "F.Cu")
		(net "RST_MB_BMC_R_N")
	)
	(segment
		(start 276.726396 -414.4899)
		(end 276.726396 -414.14446)
		(width 0.13208)
		(layer "F.Cu")
		(net "RST_MB_BMC_R_N")
	)
	(segment
		(start 276.726396 -414.14446)
		(end 276.883622 -413.987234)
		(width 0.13208)
		(layer "F.Cu")
		(net "RST_MB_BMC_R_N")
	)
	(via
		(at 276.883622 -413.587438)
		(size 0.508)
		(drill 0.254)
		(layers "F.Cu" "B.Cu")
		(net "RST_MB_BMC_R_N")
	)
	(segment
		(start 143.247872 -391.52703)
		(end 142.947644 -391.226802)
		(width 0.13208)
		(layer "F.Cu")
		(net "SMB_MB_BMC_SCL")
	)
	(segment
		(start 142.947644 -391.226802)
		(end 142.947644 -390.571736)
		(width 0.13208)
		(layer "F.Cu")
		(net "SMB_MB_BMC_SCL")
	)
	(via
		(at 143.247872 -391.52703)
		(size 0.508)
		(drill 0.254)
		(layers "F.Cu" "B.Cu")
		(net "SMB_MB_BMC_SCL")
	)
	(segment
		(start 142.474442 -390.7536)
		(end 143.247872 -391.52703)
		(width 0.15494)
		(layer "In9.Cu")
		(net "SMB_MB_BMC_SCL")
	)
	(segment
		(start 137.8966 -406.994106)
		(end 137.8966 -393.2682)
		(width 0.15494)
		(layer "In9.Cu")
		(net "SMB_MB_BMC_SCL")
	)
	(segment
		(start 140.4112 -390.7536)
		(end 142.474442 -390.7536)
		(width 0.15494)
		(layer "In9.Cu")
		(net "SMB_MB_BMC_SCL")
	)
	(segment
		(start 134.031228 -408.7114)
		(end 136.179306 -408.7114)
		(width 0.15494)
		(layer "In9.Cu")
		(net "SMB_MB_BMC_SCL")
	)
	(segment
		(start 137.8966 -393.2682)
		(end 140.4112 -390.7536)
		(width 0.15494)
		(layer "In9.Cu")
		(net "SMB_MB_BMC_SCL")
	)
	(segment
		(start 136.179306 -408.7114)
		(end 137.8966 -406.994106)
		(width 0.15494)
		(layer "In9.Cu")
		(net "SMB_MB_BMC_SCL")
	)
	(segment
		(start 133.51002 -408.190192)
		(end 134.031228 -408.7114)
		(width 0.15494)
		(layer "In9.Cu")
		(net "SMB_MB_BMC_SCL")
	)
	(segment
		(start 379.87859 -211.237576)
		(end 381.31496 -211.237576)
		(width 0.13208)
		(layer "F.Cu")
		(net "RST_PEX_NIC0_PERST_R_N")
	)
	(segment
		(start 378.266198 -209.625184)
		(end 379.87859 -211.237576)
		(width 0.13208)
		(layer "F.Cu")
		(net "RST_PEX_NIC0_PERST_R_N")
	)
	(segment
		(start 377.542044 -209.625184)
		(end 378.266198 -209.625184)
		(width 0.13208)
		(layer "F.Cu")
		(net "RST_PEX_NIC0_PERST_R_N")
	)
	(segment
		(start 381.31496 -211.237576)
		(end 381.65405 -210.898486)
		(width 0.13208)
		(layer "F.Cu")
		(net "RST_PEX_NIC0_PERST_R_N")
	)
	(segment
		(start 381.65405 -210.898486)
		(end 381.65405 -210.566)
		(width 0.13208)
		(layer "F.Cu")
		(net "RST_PEX_NIC0_PERST_R_N")
	)
	(segment
		(start 381.65405 -209.55)
		(end 381.65405 -210.566)
		(width 0.13208)
		(layer "F.Cu")
		(net "RST_PEX_NIC0_PERST_R_N")
	)
	(segment
		(start 348.493842 -217.587068)
		(end 348.893892 -217.187018)
		(width 0.13208)
		(layer "F.Cu")
		(net "RST_PEX_NIC0_PERST_R_N")
	)
	(via
		(at 377.542044 -209.625184)
		(size 0.508)
		(drill 0.254)
		(layers "F.Cu" "B.Cu")
		(net "RST_PEX_NIC0_PERST_R_N")
	)
	(via
		(at 364.543848 -216.926668)
		(size 0.508)
		(drill 0.254)
		(layers "F.Cu" "B.Cu")
		(net "RST_PEX_NIC0_PERST_R_N")
	)
	(via
		(at 348.893892 -217.187018)
		(size 0.4572)
		(drill 0.254)
		(layers "F.Cu" "B.Cu")
		(net "RST_PEX_NIC0_PERST_R_N")
	)
	(segment
		(start 367.23447 -216.926668)
		(end 364.543848 -216.926668)
		(width 0.15494)
		(layer "In7.Cu")
		(net "RST_PEX_NIC0_PERST_R_N")
	)
	(segment
		(start 374.535954 -209.625184)
		(end 367.23447 -216.926668)
		(width 0.15494)
		(layer "In7.Cu")
		(net "RST_PEX_NIC0_PERST_R_N")
	)
	(segment
		(start 377.542044 -209.625184)
		(end 374.535954 -209.625184)
		(width 0.15494)
		(layer "In7.Cu")
		(net "RST_PEX_NIC0_PERST_R_N")
	)
	(segment
		(start 349.291656 -217.584782)
		(end 348.893892 -217.187018)
		(width 0.0889)
		(layer "In13.Cu")
		(net "RST_PEX_NIC0_PERST_R_N")
	)
	(segment
		(start 351.476564 -217.584782)
		(end 349.291656 -217.584782)
		(width 0.0889)
		(layer "In13.Cu")
		(net "RST_PEX_NIC0_PERST_R_N")
	)
	(segment
		(start 364.543848 -216.926668)
		(end 352.134678 -216.926668)
		(width 0.15494)
		(layer "In13.Cu")
		(net "RST_PEX_NIC0_PERST_R_N")
	)
	(segment
		(start 352.134678 -216.926668)
		(end 351.476564 -217.584782)
		(width 0.15494)
		(layer "In13.Cu")
		(net "RST_PEX_NIC0_PERST_R_N")
	)
	(via
		(at 373.888 -236.093)
		(size 0.6604)
		(drill 0.3302)
		(layers "F.Cu" "B.Cu")
		(net "FT4232_SDB_EEPROM_R_CS")
	)
	(segment
		(start 373.888 -236.093)
		(end 374.269 -236.093)
		(width 0.13208)
		(layer "B.Cu")
		(net "FT4232_SDB_EEPROM_R_CS")
	)
	(segment
		(start 373.507 -236.093)
		(end 373.888 -236.093)
		(width 0.13208)
		(layer "B.Cu")
		(net "FT4232_SDB_EEPROM_R_CS")
	)
	(segment
		(start 374.269 -236.093)
		(end 374.732296 -236.556296)
		(width 0.13208)
		(layer "B.Cu")
		(net "FT4232_SDB_EEPROM_R_CS")
	)
	(segment
		(start 374.732296 -236.556296)
		(end 375.18848 -236.556296)
		(width 0.13208)
		(layer "B.Cu")
		(net "FT4232_SDB_EEPROM_R_CS")
	)
	(segment
		(start 372.321582 -236.689392)
		(end 372.910608 -236.689392)
		(width 0.13208)
		(layer "B.Cu")
		(net "FT4232_SDB_EEPROM_R_CS")
	)
	(segment
		(start 372.910608 -236.689392)
		(end 373.507 -236.093)
		(width 0.13208)
		(layer "B.Cu")
		(net "FT4232_SDB_EEPROM_R_CS")
	)
	(segment
		(start 375.18848 -235.540296)
		(end 375.18848 -236.556296)
		(width 0.13208)
		(layer "B.Cu")
		(net "FT4232_SDB_EEPROM_R_CS")
	)
	(segment
		(start 258.78028 -78.140814)
		(end 259.24129 -77.679804)
		(width 0.13208)
		(layer "F.Cu")
		(net "CLK_GEN_CK440_OE5_N")
	)
	(segment
		(start 258.78028 -79.621888)
		(end 258.78028 -79.190088)
		(width 0.13208)
		(layer "F.Cu")
		(net "CLK_GEN_CK440_OE5_N")
	)
	(segment
		(start 258.676902 -79.725266)
		(end 258.78028 -79.621888)
		(width 0.13208)
		(layer "F.Cu")
		(net "CLK_GEN_CK440_OE5_N")
	)
	(segment
		(start 258.676902 -81.181448)
		(end 258.676902 -79.725266)
		(width 0.0889)
		(layer "F.Cu")
		(net "CLK_GEN_CK440_OE5_N")
	)
	(segment
		(start 258.78028 -79.190088)
		(end 258.78028 -78.140814)
		(width 0.13208)
		(layer "F.Cu")
		(net "CLK_GEN_CK440_OE5_N")
	)
	(via
		(at 258.78028 -79.190088)
		(size 0.762)
		(drill 0.381)
		(layers "F.Cu" "B.Cu")
		(net "CLK_GEN_CK440_OE5_N")
	)
	(segment
		(start 29.106622 -306.649374)
		(end 29.445712 -306.988464)
		(width 0.13208)
		(layer "F.Cu")
		(net "PEX0_DFT_IDDT")
	)
	(segment
		(start 29.445712 -306.988464)
		(end 29.884116 -306.988464)
		(width 0.13208)
		(layer "F.Cu")
		(net "PEX0_DFT_IDDT")
	)
	(segment
		(start 29.824934 -305.931062)
		(end 29.106622 -306.649374)
		(width 0.13208)
		(layer "F.Cu")
		(net "PEX0_DFT_IDDT")
	)
	(segment
		(start 29.884116 -306.988464)
		(end 30.107382 -306.765198)
		(width 0.13208)
		(layer "F.Cu")
		(net "PEX0_DFT_IDDT")
	)
	(via
		(at 51.099974 -308.249828)
		(size 0.4064)
		(drill 0.2032)
		(layers "F.Cu" "B.Cu")
		(net "PEX0_DFT_IDDT")
	)
	(via
		(at 30.107382 -306.765198)
		(size 0.508)
		(drill 0.254)
		(layers "F.Cu" "B.Cu")
		(net "PEX0_DFT_IDDT")
	)
	(segment
		(start 47.607474 -306.7558)
		(end 30.11678 -306.7558)
		(width 0.13208)
		(layer "B.Cu")
		(net "PEX0_DFT_IDDT")
	)
	(segment
		(start 30.11678 -306.7558)
		(end 30.107382 -306.765198)
		(width 0.13208)
		(layer "B.Cu")
		(net "PEX0_DFT_IDDT")
	)
	(segment
		(start 47.8282 -307.5432)
		(end 47.8282 -306.976526)
		(width 0.13208)
		(layer "B.Cu")
		(net "PEX0_DFT_IDDT")
	)
	(segment
		(start 51.057556 -308.292246)
		(end 50.4317 -308.292246)
		(width 0.13208)
		(layer "B.Cu")
		(net "PEX0_DFT_IDDT")
	)
	(segment
		(start 49.936654 -307.7972)
		(end 48.0822 -307.7972)
		(width 0.13208)
		(layer "B.Cu")
		(net "PEX0_DFT_IDDT")
	)
	(segment
		(start 47.8282 -306.976526)
		(end 47.607474 -306.7558)
		(width 0.13208)
		(layer "B.Cu")
		(net "PEX0_DFT_IDDT")
	)
	(segment
		(start 50.4317 -308.292246)
		(end 49.936654 -307.7972)
		(width 0.13208)
		(layer "B.Cu")
		(net "PEX0_DFT_IDDT")
	)
	(segment
		(start 48.0822 -307.7972)
		(end 47.8282 -307.5432)
		(width 0.13208)
		(layer "B.Cu")
		(net "PEX0_DFT_IDDT")
	)
	(segment
		(start 51.099974 -308.249828)
		(end 51.057556 -308.292246)
		(width 0.13208)
		(layer "B.Cu")
		(net "PEX0_DFT_IDDT")
	)
	(segment
		(start 124.128784 -96.0882)
		(end 125.352556 -96.0882)
		(width 0.13208)
		(layer "F.Cu")
		(net "SMB_BIC_I2C9_MUX0_SSD0_SCL")
	)
	(segment
		(start 126.247652 -95.140526)
		(end 127.462534 -95.140526)
		(width 0.13208)
		(layer "F.Cu")
		(net "SMB_BIC_I2C9_MUX0_SSD0_SCL")
	)
	(segment
		(start 125.9205 -95.467678)
		(end 126.247652 -95.140526)
		(width 0.13208)
		(layer "F.Cu")
		(net "SMB_BIC_I2C9_MUX0_SSD0_SCL")
	)
	(segment
		(start 125.352556 -96.0882)
		(end 125.547882 -95.892874)
		(width 0.13208)
		(layer "F.Cu")
		(net "SMB_BIC_I2C9_MUX0_SSD0_SCL")
	)
	(segment
		(start 125.547882 -95.892874)
		(end 125.9205 -95.892874)
		(width 0.13208)
		(layer "F.Cu")
		(net "SMB_BIC_I2C9_MUX0_SSD0_SCL")
	)
	(segment
		(start 125.9205 -95.892874)
		(end 125.9205 -95.467678)
		(width 0.13208)
		(layer "F.Cu")
		(net "SMB_BIC_I2C9_MUX0_SSD0_SCL")
	)
	(segment
		(start 124.07519 -96.034606)
		(end 124.128784 -96.0882)
		(width 0.13208)
		(layer "F.Cu")
		(net "SMB_BIC_I2C9_MUX0_SSD0_SCL")
	)
	(via
		(at 125.9205 -95.892874)
		(size 0.508)
		(drill 0.254)
		(layers "F.Cu" "B.Cu")
		(net "SMB_BIC_I2C9_MUX0_SSD0_SCL")
	)
	(segment
		(start 280.176478 -413.8803)
		(end 280.790396 -413.8803)
		(width 0.13208)
		(layer "F.Cu")
		(net "MB_BIC_R_MON")
	)
	(segment
		(start 279.106884 -411.86481)
		(end 279.106884 -412.810706)
		(width 0.13208)
		(layer "F.Cu")
		(net "MB_BIC_R_MON")
	)
	(segment
		(start 279.106884 -412.810706)
		(end 280.176478 -413.8803)
		(width 0.13208)
		(layer "F.Cu")
		(net "MB_BIC_R_MON")
	)
	(segment
		(start 280.790396 -414.4899)
		(end 280.790396 -413.8803)
		(width 0.13208)
		(layer "F.Cu")
		(net "MB_BIC_R_MON")
	)
	(via
		(at 280.790396 -413.8803)
		(size 0.508)
		(drill 0.254)
		(layers "F.Cu" "B.Cu")
		(net "MB_BIC_R_MON")
	)
	(segment
		(start 346.093796 -227.987098)
		(end 346.093796 -228.465634)
		(width 0.13208)
		(layer "F.Cu")
		(net "PWRGD_P12V_SSD5_R")
	)
	(segment
		(start 168.768014 -53.051456)
		(end 169.423334 -53.051456)
		(width 0.13208)
		(layer "F.Cu")
		(net "PWRGD_P12V_SSD5_R")
	)
	(segment
		(start 143.104616 -64.886332)
		(end 143.973804 -65.75552)
		(width 0.13208)
		(layer "F.Cu")
		(net "PWRGD_P12V_SSD5_R")
	)
	(segment
		(start 346.093796 -228.465634)
		(end 346.202 -228.727)
		(width 0.13208)
		(layer "F.Cu")
		(net "PWRGD_P12V_SSD5_R")
	)
	(segment
		(start 143.973804 -65.75552)
		(end 156.828744 -65.75552)
		(width 0.13208)
		(layer "F.Cu")
		(net "PWRGD_P12V_SSD5_R")
	)
	(segment
		(start 143.736568 -61.487812)
		(end 143.104616 -62.119764)
		(width 0.13208)
		(layer "F.Cu")
		(net "PWRGD_P12V_SSD5_R")
	)
	(segment
		(start 145.583656 -61.487812)
		(end 143.736568 -61.487812)
		(width 0.13208)
		(layer "F.Cu")
		(net "PWRGD_P12V_SSD5_R")
	)
	(segment
		(start 143.104616 -62.119764)
		(end 143.104616 -64.886332)
		(width 0.13208)
		(layer "F.Cu")
		(net "PWRGD_P12V_SSD5_R")
	)
	(via
		(at 346.202 -228.727)
		(size 0.508)
		(drill 0.254)
		(layers "F.Cu" "B.Cu")
		(net "PWRGD_P12V_SSD5_R")
	)
	(via
		(at 169.423334 -53.051456)
		(size 0.508)
		(drill 0.254)
		(layers "F.Cu" "B.Cu")
		(net "PWRGD_P12V_SSD5_R")
	)
	(via
		(at 156.828744 -65.75552)
		(size 0.508)
		(drill 0.254)
		(layers "F.Cu" "B.Cu")
		(net "PWRGD_P12V_SSD5_R")
	)
	(via
		(at 182.793894 -229.8446)
		(size 0.508)
		(drill 0.254)
		(layers "F.Cu" "B.Cu")
		(net "PWRGD_P12V_SSD5_R")
	)
	(segment
		(start 168.880282 -54.847236)
		(end 169.15511 -54.572408)
		(width 0.15494)
		(layer "In5.Cu")
		(net "PWRGD_P12V_SSD5_R")
	)
	(segment
		(start 167.467534 -64.617092)
		(end 167.843962 -64.240664)
		(width 0.15494)
		(layer "In5.Cu")
		(net "PWRGD_P12V_SSD5_R")
	)
	(segment
		(start 170.429936 -66.971672)
		(end 169.30116 -65.842896)
		(width 0.15494)
		(layer "In5.Cu")
		(net "PWRGD_P12V_SSD5_R")
	)
	(segment
		(start 160.318196 -65.75552)
		(end 161.456624 -64.617092)
		(width 0.15494)
		(layer "In5.Cu")
		(net "PWRGD_P12V_SSD5_R")
	)
	(segment
		(start 169.30116 -57.020968)
		(end 168.880282 -56.60009)
		(width 0.15494)
		(layer "In5.Cu")
		(net "PWRGD_P12V_SSD5_R")
	)
	(segment
		(start 173.762416 -115.69954)
		(end 172.879512 -114.816636)
		(width 0.15494)
		(layer "In5.Cu")
		(net "PWRGD_P12V_SSD5_R")
	)
	(segment
		(start 167.361362 -57.501028)
		(end 167.361362 -55.113428)
		(width 0.15494)
		(layer "In5.Cu")
		(net "PWRGD_P12V_SSD5_R")
	)
	(segment
		(start 172.879512 -89.285318)
		(end 170.429936 -86.835742)
		(width 0.15494)
		(layer "In5.Cu")
		(net "PWRGD_P12V_SSD5_R")
	)
	(segment
		(start 167.361362 -55.113428)
		(end 169.423334 -53.051456)
		(width 0.15494)
		(layer "In5.Cu")
		(net "PWRGD_P12V_SSD5_R")
	)
	(segment
		(start 182.793894 -229.8446)
		(end 181.306216 -228.356922)
		(width 0.15494)
		(layer "In5.Cu")
		(net "PWRGD_P12V_SSD5_R")
	)
	(segment
		(start 181.306216 -228.356922)
		(end 181.306216 -221.644464)
		(width 0.15494)
		(layer "In5.Cu")
		(net "PWRGD_P12V_SSD5_R")
	)
	(segment
		(start 173.762416 -119.327422)
		(end 173.762416 -115.69954)
		(width 0.15494)
		(layer "In5.Cu")
		(net "PWRGD_P12V_SSD5_R")
	)
	(segment
		(start 172.384974 -136.367774)
		(end 172.802804 -135.949944)
		(width 0.15494)
		(layer "In5.Cu")
		(net "PWRGD_P12V_SSD5_R")
	)
	(segment
		(start 172.802804 -120.287034)
		(end 173.762416 -119.327422)
		(width 0.15494)
		(layer "In5.Cu")
		(net "PWRGD_P12V_SSD5_R")
	)
	(segment
		(start 168.880282 -56.60009)
		(end 168.880282 -54.847236)
		(width 0.15494)
		(layer "In5.Cu")
		(net "PWRGD_P12V_SSD5_R")
	)
	(segment
		(start 169.635932 -54.572408)
		(end 170.049444 -54.158896)
		(width 0.15494)
		(layer "In5.Cu")
		(net "PWRGD_P12V_SSD5_R")
	)
	(segment
		(start 170.049444 -53.677566)
		(end 169.423334 -53.051456)
		(width 0.15494)
		(layer "In5.Cu")
		(net "PWRGD_P12V_SSD5_R")
	)
	(segment
		(start 169.15511 -54.572408)
		(end 169.635932 -54.572408)
		(width 0.15494)
		(layer "In5.Cu")
		(net "PWRGD_P12V_SSD5_R")
	)
	(segment
		(start 170.429936 -86.835742)
		(end 170.429936 -66.971672)
		(width 0.15494)
		(layer "In5.Cu")
		(net "PWRGD_P12V_SSD5_R")
	)
	(segment
		(start 177.242216 -211.833714)
		(end 177.242216 -203.39685)
		(width 0.15494)
		(layer "In5.Cu")
		(net "PWRGD_P12V_SSD5_R")
	)
	(segment
		(start 167.843962 -57.983628)
		(end 167.361362 -57.501028)
		(width 0.15494)
		(layer "In5.Cu")
		(net "PWRGD_P12V_SSD5_R")
	)
	(segment
		(start 172.384974 -180.246274)
		(end 172.384974 -136.367774)
		(width 0.15494)
		(layer "In5.Cu")
		(net "PWRGD_P12V_SSD5_R")
	)
	(segment
		(start 172.802804 -135.949944)
		(end 172.802804 -120.287034)
		(width 0.15494)
		(layer "In5.Cu")
		(net "PWRGD_P12V_SSD5_R")
	)
	(segment
		(start 181.306216 -221.644464)
		(end 177.242216 -211.833714)
		(width 0.15494)
		(layer "In5.Cu")
		(net "PWRGD_P12V_SSD5_R")
	)
	(segment
		(start 169.30116 -65.842896)
		(end 169.30116 -57.020968)
		(width 0.15494)
		(layer "In5.Cu")
		(net "PWRGD_P12V_SSD5_R")
	)
	(segment
		(start 173.681136 -181.542436)
		(end 172.384974 -180.246274)
		(width 0.15494)
		(layer "In5.Cu")
		(net "PWRGD_P12V_SSD5_R")
	)
	(segment
		(start 170.049444 -54.158896)
		(end 170.049444 -53.677566)
		(width 0.15494)
		(layer "In5.Cu")
		(net "PWRGD_P12V_SSD5_R")
	)
	(segment
		(start 156.828744 -65.75552)
		(end 160.318196 -65.75552)
		(width 0.15494)
		(layer "In5.Cu")
		(net "PWRGD_P12V_SSD5_R")
	)
	(segment
		(start 167.843962 -64.240664)
		(end 167.843962 -57.983628)
		(width 0.15494)
		(layer "In5.Cu")
		(net "PWRGD_P12V_SSD5_R")
	)
	(segment
		(start 161.456624 -64.617092)
		(end 167.467534 -64.617092)
		(width 0.15494)
		(layer "In5.Cu")
		(net "PWRGD_P12V_SSD5_R")
	)
	(segment
		(start 177.242216 -203.39685)
		(end 173.681136 -199.83577)
		(width 0.15494)
		(layer "In5.Cu")
		(net "PWRGD_P12V_SSD5_R")
	)
	(segment
		(start 173.681136 -199.83577)
		(end 173.681136 -181.542436)
		(width 0.15494)
		(layer "In5.Cu")
		(net "PWRGD_P12V_SSD5_R")
	)
	(segment
		(start 172.879512 -114.816636)
		(end 172.879512 -89.285318)
		(width 0.15494)
		(layer "In5.Cu")
		(net "PWRGD_P12V_SSD5_R")
	)
	(segment
		(start 188.542422 -229.8446)
		(end 192.758568 -234.060746)
		(width 0.15494)
		(layer "In15.Cu")
		(net "PWRGD_P12V_SSD5_R")
	)
	(segment
		(start 247.121934 -227.12426)
		(end 249.001534 -227.12426)
		(width 0.15494)
		(layer "In15.Cu")
		(net "PWRGD_P12V_SSD5_R")
	)
	(segment
		(start 211.121244 -234.060746)
		(end 211.82584 -234.765342)
		(width 0.15494)
		(layer "In15.Cu")
		(net "PWRGD_P12V_SSD5_R")
	)
	(segment
		(start 213.70417 -234.060746)
		(end 240.28527 -234.060746)
		(width 0.15494)
		(layer "In15.Cu")
		(net "PWRGD_P12V_SSD5_R")
	)
	(segment
		(start 327.265792 -234.62869)
		(end 329.85329 -234.62869)
		(width 0.15494)
		(layer "In15.Cu")
		(net "PWRGD_P12V_SSD5_R")
	)
	(segment
		(start 249.001534 -227.12426)
		(end 251.039884 -229.16261)
		(width 0.15494)
		(layer "In15.Cu")
		(net "PWRGD_P12V_SSD5_R")
	)
	(segment
		(start 333.967328 -233.586528)
		(end 336.571082 -233.586528)
		(width 0.15494)
		(layer "In15.Cu")
		(net "PWRGD_P12V_SSD5_R")
	)
	(segment
		(start 192.758568 -234.060746)
		(end 211.121244 -234.060746)
		(width 0.15494)
		(layer "In15.Cu")
		(net "PWRGD_P12V_SSD5_R")
	)
	(segment
		(start 293.619174 -234.3658)
		(end 294.010588 -234.757214)
		(width 0.15494)
		(layer "In15.Cu")
		(net "PWRGD_P12V_SSD5_R")
	)
	(segment
		(start 258.881118 -228.49078)
		(end 261.823962 -228.49078)
		(width 0.15494)
		(layer "In15.Cu")
		(net "PWRGD_P12V_SSD5_R")
	)
	(segment
		(start 241.787426 -232.55859)
		(end 242.692682 -232.55859)
		(width 0.15494)
		(layer "In15.Cu")
		(net "PWRGD_P12V_SSD5_R")
	)
	(segment
		(start 270.801338 -234.3658)
		(end 293.619174 -234.3658)
		(width 0.15494)
		(layer "In15.Cu")
		(net "PWRGD_P12V_SSD5_R")
	)
	(segment
		(start 182.793894 -229.8446)
		(end 188.542422 -229.8446)
		(width 0.15494)
		(layer "In15.Cu")
		(net "PWRGD_P12V_SSD5_R")
	)
	(segment
		(start 262.006842 -228.3079)
		(end 264.743438 -228.3079)
		(width 0.15494)
		(layer "In15.Cu")
		(net "PWRGD_P12V_SSD5_R")
	)
	(segment
		(start 246.282972 -227.963222)
		(end 247.121934 -227.12426)
		(width 0.15494)
		(layer "In15.Cu")
		(net "PWRGD_P12V_SSD5_R")
	)
	(segment
		(start 336.571082 -233.586528)
		(end 337.124548 -233.033062)
		(width 0.15494)
		(layer "In15.Cu")
		(net "PWRGD_P12V_SSD5_R")
	)
	(segment
		(start 322.180712 -234.757214)
		(end 322.97116 -235.547662)
		(width 0.15494)
		(layer "In15.Cu")
		(net "PWRGD_P12V_SSD5_R")
	)
	(segment
		(start 245.86565 -230.469694)
		(end 246.282972 -230.052372)
		(width 0.15494)
		(layer "In15.Cu")
		(net "PWRGD_P12V_SSD5_R")
	)
	(segment
		(start 240.28527 -234.060746)
		(end 241.787426 -232.55859)
		(width 0.15494)
		(layer "In15.Cu")
		(net "PWRGD_P12V_SSD5_R")
	)
	(segment
		(start 333.671672 -233.882184)
		(end 333.967328 -233.586528)
		(width 0.15494)
		(layer "In15.Cu")
		(net "PWRGD_P12V_SSD5_R")
	)
	(segment
		(start 342.37168 -233.033062)
		(end 346.202 -229.202742)
		(width 0.15494)
		(layer "In15.Cu")
		(net "PWRGD_P12V_SSD5_R")
	)
	(segment
		(start 246.282972 -230.052372)
		(end 246.282972 -227.963222)
		(width 0.15494)
		(layer "In15.Cu")
		(net "PWRGD_P12V_SSD5_R")
	)
	(segment
		(start 331.655674 -233.882184)
		(end 333.671672 -233.882184)
		(width 0.15494)
		(layer "In15.Cu")
		(net "PWRGD_P12V_SSD5_R")
	)
	(segment
		(start 212.999574 -234.765342)
		(end 213.70417 -234.060746)
		(width 0.15494)
		(layer "In15.Cu")
		(net "PWRGD_P12V_SSD5_R")
	)
	(segment
		(start 264.743438 -228.3079)
		(end 270.801338 -234.3658)
		(width 0.15494)
		(layer "In15.Cu")
		(net "PWRGD_P12V_SSD5_R")
	)
	(segment
		(start 329.85329 -234.62869)
		(end 331.655674 -233.882184)
		(width 0.15494)
		(layer "In15.Cu")
		(net "PWRGD_P12V_SSD5_R")
	)
	(segment
		(start 322.97116 -235.547662)
		(end 326.34682 -235.547662)
		(width 0.15494)
		(layer "In15.Cu")
		(net "PWRGD_P12V_SSD5_R")
	)
	(segment
		(start 211.82584 -234.765342)
		(end 212.999574 -234.765342)
		(width 0.15494)
		(layer "In15.Cu")
		(net "PWRGD_P12V_SSD5_R")
	)
	(segment
		(start 244.781578 -230.469694)
		(end 245.86565 -230.469694)
		(width 0.15494)
		(layer "In15.Cu")
		(net "PWRGD_P12V_SSD5_R")
	)
	(segment
		(start 337.124548 -233.033062)
		(end 342.37168 -233.033062)
		(width 0.15494)
		(layer "In15.Cu")
		(net "PWRGD_P12V_SSD5_R")
	)
	(segment
		(start 251.039884 -229.16261)
		(end 252.03277 -229.16261)
		(width 0.15494)
		(layer "In15.Cu")
		(net "PWRGD_P12V_SSD5_R")
	)
	(segment
		(start 261.823962 -228.49078)
		(end 262.006842 -228.3079)
		(width 0.15494)
		(layer "In15.Cu")
		(net "PWRGD_P12V_SSD5_R")
	)
	(segment
		(start 242.692682 -232.55859)
		(end 244.781578 -230.469694)
		(width 0.15494)
		(layer "In15.Cu")
		(net "PWRGD_P12V_SSD5_R")
	)
	(segment
		(start 252.03277 -229.16261)
		(end 253.34214 -227.85324)
		(width 0.15494)
		(layer "In15.Cu")
		(net "PWRGD_P12V_SSD5_R")
	)
	(segment
		(start 346.202 -229.202742)
		(end 346.202 -228.727)
		(width 0.15494)
		(layer "In15.Cu")
		(net "PWRGD_P12V_SSD5_R")
	)
	(segment
		(start 294.010588 -234.757214)
		(end 322.180712 -234.757214)
		(width 0.15494)
		(layer "In15.Cu")
		(net "PWRGD_P12V_SSD5_R")
	)
	(segment
		(start 253.34214 -227.85324)
		(end 258.243578 -227.85324)
		(width 0.15494)
		(layer "In15.Cu")
		(net "PWRGD_P12V_SSD5_R")
	)
	(segment
		(start 258.243578 -227.85324)
		(end 258.881118 -228.49078)
		(width 0.15494)
		(layer "In15.Cu")
		(net "PWRGD_P12V_SSD5_R")
	)
	(segment
		(start 326.34682 -235.547662)
		(end 327.265792 -234.62869)
		(width 0.15494)
		(layer "In15.Cu")
		(net "PWRGD_P12V_SSD5_R")
	)
	(segment
		(start 377.20905 -176.18202)
		(end 377.20905 -177.19802)
		(width 0.13208)
		(layer "F.Cu")
		(net "RST_PEX_NIC3_PERST_R_N")
	)
	(segment
		(start 377.20905 -176.18202)
		(end 377.901454 -175.489616)
		(width 0.13208)
		(layer "F.Cu")
		(net "RST_PEX_NIC3_PERST_R_N")
	)
	(segment
		(start 377.901454 -175.489616)
		(end 377.901454 -171.63288)
		(width 0.13208)
		(layer "F.Cu")
		(net "RST_PEX_NIC3_PERST_R_N")
	)
	(segment
		(start 366.465612 -171.81576)
		(end 365.8743 -171.224448)
		(width 0.13208)
		(layer "F.Cu")
		(net "RST_PEX_NIC3_PERST_R_N")
	)
	(segment
		(start 377.901454 -171.63288)
		(end 376.659394 -170.39082)
		(width 0.13208)
		(layer "F.Cu")
		(net "RST_PEX_NIC3_PERST_R_N")
	)
	(segment
		(start 365.8743 -171.224448)
		(end 362.36021 -171.224448)
		(width 0.13208)
		(layer "F.Cu")
		(net "RST_PEX_NIC3_PERST_R_N")
	)
	(segment
		(start 347.693742 -215.987122)
		(end 348.093538 -215.587326)
		(width 0.13208)
		(layer "F.Cu")
		(net "RST_PEX_NIC3_PERST_R_N")
	)
	(segment
		(start 372.71325 -170.39082)
		(end 371.28831 -171.81576)
		(width 0.13208)
		(layer "F.Cu")
		(net "RST_PEX_NIC3_PERST_R_N")
	)
	(segment
		(start 376.659394 -170.39082)
		(end 372.71325 -170.39082)
		(width 0.13208)
		(layer "F.Cu")
		(net "RST_PEX_NIC3_PERST_R_N")
	)
	(segment
		(start 371.28831 -171.81576)
		(end 366.465612 -171.81576)
		(width 0.13208)
		(layer "F.Cu")
		(net "RST_PEX_NIC3_PERST_R_N")
	)
	(via
		(at 348.093538 -215.587326)
		(size 0.4572)
		(drill 0.254)
		(layers "F.Cu" "B.Cu")
		(net "RST_PEX_NIC3_PERST_R_N")
	)
	(via
		(at 362.36021 -171.224448)
		(size 0.508)
		(drill 0.254)
		(layers "F.Cu" "B.Cu")
		(net "RST_PEX_NIC3_PERST_R_N")
	)
	(segment
		(start 361.72013 -177.430938)
		(end 361.72013 -190.060072)
		(width 0.15494)
		(layer "In9.Cu")
		(net "RST_PEX_NIC3_PERST_R_N")
	)
	(segment
		(start 361.72013 -190.060072)
		(end 360.796078 -190.984124)
		(width 0.15494)
		(layer "In9.Cu")
		(net "RST_PEX_NIC3_PERST_R_N")
	)
	(segment
		(start 356.728014 -205.399132)
		(end 356.728014 -206.432404)
		(width 0.15494)
		(layer "In9.Cu")
		(net "RST_PEX_NIC3_PERST_R_N")
	)
	(segment
		(start 353.176586 -209.983832)
		(end 349.527114 -209.983832)
		(width 0.15494)
		(layer "In9.Cu")
		(net "RST_PEX_NIC3_PERST_R_N")
	)
	(segment
		(start 362.811822 -174.592488)
		(end 362.811822 -176.339246)
		(width 0.15494)
		(layer "In9.Cu")
		(net "RST_PEX_NIC3_PERST_R_N")
	)
	(segment
		(start 362.47197 -171.336208)
		(end 362.47197 -174.252636)
		(width 0.15494)
		(layer "In9.Cu")
		(net "RST_PEX_NIC3_PERST_R_N")
	)
	(segment
		(start 348.491048 -211.019898)
		(end 348.491048 -215.189816)
		(width 0.0889)
		(layer "In9.Cu")
		(net "RST_PEX_NIC3_PERST_R_N")
	)
	(segment
		(start 362.47197 -174.252636)
		(end 362.811822 -174.592488)
		(width 0.15494)
		(layer "In9.Cu")
		(net "RST_PEX_NIC3_PERST_R_N")
	)
	(segment
		(start 362.36021 -171.224448)
		(end 362.47197 -171.336208)
		(width 0.15494)
		(layer "In9.Cu")
		(net "RST_PEX_NIC3_PERST_R_N")
	)
	(segment
		(start 356.728014 -206.432404)
		(end 353.176586 -209.983832)
		(width 0.15494)
		(layer "In9.Cu")
		(net "RST_PEX_NIC3_PERST_R_N")
	)
	(segment
		(start 360.796078 -190.984124)
		(end 360.796078 -201.331068)
		(width 0.15494)
		(layer "In9.Cu")
		(net "RST_PEX_NIC3_PERST_R_N")
	)
	(segment
		(start 349.527114 -209.983832)
		(end 348.491048 -211.019898)
		(width 0.15494)
		(layer "In9.Cu")
		(net "RST_PEX_NIC3_PERST_R_N")
	)
	(segment
		(start 348.491048 -215.189816)
		(end 348.093538 -215.587326)
		(width 0.0889)
		(layer "In9.Cu")
		(net "RST_PEX_NIC3_PERST_R_N")
	)
	(segment
		(start 362.811822 -176.339246)
		(end 361.72013 -177.430938)
		(width 0.15494)
		(layer "In9.Cu")
		(net "RST_PEX_NIC3_PERST_R_N")
	)
	(segment
		(start 360.796078 -201.331068)
		(end 356.728014 -205.399132)
		(width 0.15494)
		(layer "In9.Cu")
		(net "RST_PEX_NIC3_PERST_R_N")
	)
	(segment
		(start 140.58011 -52.994814)
		(end 140.58011 -51.670966)
		(width 0.13208)
		(layer "F.Cu")
		(net "P12V_SSD4_SS")
	)
	(segment
		(start 140.430758 -53.144166)
		(end 140.58011 -52.994814)
		(width 0.13208)
		(layer "F.Cu")
		(net "P12V_SSD4_SS")
	)
	(segment
		(start 140.58011 -51.670966)
		(end 141.23162 -51.019456)
		(width 0.13208)
		(layer "F.Cu")
		(net "P12V_SSD4_SS")
	)
	(segment
		(start 141.23162 -51.019456)
		(end 141.967966 -51.019456)
		(width 0.13208)
		(layer "F.Cu")
		(net "P12V_SSD4_SS")
	)
	(segment
		(start 140.24737 -53.144166)
		(end 140.430758 -53.144166)
		(width 0.13208)
		(layer "F.Cu")
		(net "P12V_SSD4_SS")
	)
	(via
		(at 141.23162 -51.019456)
		(size 0.508)
		(drill 0.254)
		(layers "F.Cu" "B.Cu")
		(net "P12V_SSD4_SS")
	)
	(segment
		(start 335.33715 -52.587398)
		(end 335.801208 -53.051456)
		(width 0.13208)
		(layer "F.Cu")
		(net "PWRGD_P12V_SSD11")
	)
	(segment
		(start 335.801208 -53.051456)
		(end 336.067654 -53.051456)
		(width 0.13208)
		(layer "F.Cu")
		(net "PWRGD_P12V_SSD11")
	)
	(segment
		(start 334.71612 -53.644038)
		(end 335.33715 -53.023008)
		(width 0.13208)
		(layer "F.Cu")
		(net "PWRGD_P12V_SSD11")
	)
	(segment
		(start 334.347058 -53.644038)
		(end 334.71612 -53.644038)
		(width 0.13208)
		(layer "F.Cu")
		(net "PWRGD_P12V_SSD11")
	)
	(segment
		(start 335.33715 -53.023008)
		(end 335.33715 -52.587398)
		(width 0.13208)
		(layer "F.Cu")
		(net "PWRGD_P12V_SSD11")
	)
	(segment
		(start 336.067654 -52.035456)
		(end 336.067654 -53.051456)
		(width 0.13208)
		(layer "F.Cu")
		(net "PWRGD_P12V_SSD11")
	)
	(via
		(at 335.33715 -52.587398)
		(size 0.508)
		(drill 0.254)
		(layers "F.Cu" "B.Cu")
		(net "PWRGD_P12V_SSD11")
	)
	(segment
		(start 72.949816 -291.149786)
		(end 72.474836 -290.674806)
		(width 0.13208)
		(layer "F.Cu")
		(net "UART_PEX0_SDB_BUF_RX")
	)
	(via
		(at 377.987052 -223.098106)
		(size 0.508)
		(drill 0.254)
		(layers "F.Cu" "B.Cu")
		(net "UART_PEX0_SDB_BUF_RX")
	)
	(via
		(at 84.83219 -258.55803)
		(size 0.508)
		(drill 0.254)
		(layers "F.Cu" "B.Cu")
		(net "UART_PEX0_SDB_BUF_RX")
	)
	(via
		(at 72.474836 -290.674806)
		(size 0.4064)
		(drill 0.2032)
		(layers "F.Cu" "B.Cu")
		(net "UART_PEX0_SDB_BUF_RX")
	)
	(segment
		(start 76.27493 -267.11529)
		(end 84.83219 -258.55803)
		(width 0.13208)
		(layer "B.Cu")
		(net "UART_PEX0_SDB_BUF_RX")
	)
	(segment
		(start 75.32497 -283.464)
		(end 75.75677 -283.0322)
		(width 0.13208)
		(layer "B.Cu")
		(net "UART_PEX0_SDB_BUF_RX")
	)
	(segment
		(start 75.94092 -283.0322)
		(end 76.27493 -282.69819)
		(width 0.13208)
		(layer "B.Cu")
		(net "UART_PEX0_SDB_BUF_RX")
	)
	(segment
		(start 76.27493 -282.69819)
		(end 76.27493 -267.11529)
		(width 0.13208)
		(layer "B.Cu")
		(net "UART_PEX0_SDB_BUF_RX")
	)
	(segment
		(start 377.987052 -223.733106)
		(end 377.987052 -223.098106)
		(width 0.13208)
		(layer "B.Cu")
		(net "UART_PEX0_SDB_BUF_RX")
	)
	(segment
		(start 72.94499 -289.47618)
		(end 73.64857 -288.7726)
		(width 0.13208)
		(layer "B.Cu")
		(net "UART_PEX0_SDB_BUF_RX")
	)
	(segment
		(start 72.94499 -290.204652)
		(end 72.94499 -289.47618)
		(width 0.13208)
		(layer "B.Cu")
		(net "UART_PEX0_SDB_BUF_RX")
	)
	(segment
		(start 75.75677 -283.0322)
		(end 75.94092 -283.0322)
		(width 0.13208)
		(layer "B.Cu")
		(net "UART_PEX0_SDB_BUF_RX")
	)
	(segment
		(start 75.32497 -288.441892)
		(end 75.32497 -283.464)
		(width 0.13208)
		(layer "B.Cu")
		(net "UART_PEX0_SDB_BUF_RX")
	)
	(segment
		(start 73.64857 -288.7726)
		(end 74.994262 -288.7726)
		(width 0.13208)
		(layer "B.Cu")
		(net "UART_PEX0_SDB_BUF_RX")
	)
	(segment
		(start 378.964952 -223.733106)
		(end 377.987052 -223.733106)
		(width 0.13208)
		(layer "B.Cu")
		(net "UART_PEX0_SDB_BUF_RX")
	)
	(segment
		(start 72.474836 -290.674806)
		(end 72.94499 -290.204652)
		(width 0.13208)
		(layer "B.Cu")
		(net "UART_PEX0_SDB_BUF_RX")
	)
	(segment
		(start 74.994262 -288.7726)
		(end 75.32497 -288.441892)
		(width 0.13208)
		(layer "B.Cu")
		(net "UART_PEX0_SDB_BUF_RX")
	)
	(segment
		(start 350.648778 -246.43588)
		(end 360.432858 -236.6518)
		(width 0.15494)
		(layer "In13.Cu")
		(net "UART_PEX0_SDB_BUF_RX")
	)
	(segment
		(start 140.453618 -242.310158)
		(end 142.44066 -244.2972)
		(width 0.15494)
		(layer "In13.Cu")
		(net "UART_PEX0_SDB_BUF_RX")
	)
	(segment
		(start 149.09038 -243.019326)
		(end 150.368254 -244.2972)
		(width 0.15494)
		(layer "In13.Cu")
		(net "UART_PEX0_SDB_BUF_RX")
	)
	(segment
		(start 377.987052 -228.234494)
		(end 377.987052 -223.098106)
		(width 0.15494)
		(layer "In13.Cu")
		(net "UART_PEX0_SDB_BUF_RX")
	)
	(segment
		(start 342.09736 -251.935234)
		(end 342.09736 -251.46254)
		(width 0.15494)
		(layer "In13.Cu")
		(net "UART_PEX0_SDB_BUF_RX")
	)
	(segment
		(start 189.799976 -250.52274)
		(end 228.117908 -250.52274)
		(width 0.15494)
		(layer "In13.Cu")
		(net "UART_PEX0_SDB_BUF_RX")
	)
	(segment
		(start 180.6194 -251.7648)
		(end 188.557916 -251.7648)
		(width 0.15494)
		(layer "In13.Cu")
		(net "UART_PEX0_SDB_BUF_RX")
	)
	(segment
		(start 319.25768 -255.036066)
		(end 338.996528 -255.036066)
		(width 0.15494)
		(layer "In13.Cu")
		(net "UART_PEX0_SDB_BUF_RX")
	)
	(segment
		(start 188.557916 -251.7648)
		(end 189.799976 -250.52274)
		(width 0.15494)
		(layer "In13.Cu")
		(net "UART_PEX0_SDB_BUF_RX")
	)
	(segment
		(start 228.117908 -250.52274)
		(end 229.105968 -251.5108)
		(width 0.15494)
		(layer "In13.Cu")
		(net "UART_PEX0_SDB_BUF_RX")
	)
	(segment
		(start 234.642406 -253.36246)
		(end 252.342142 -253.36246)
		(width 0.15494)
		(layer "In13.Cu")
		(net "UART_PEX0_SDB_BUF_RX")
	)
	(segment
		(start 367.6142 -236.6518)
		(end 368.554 -235.712)
		(width 0.15494)
		(layer "In13.Cu")
		(net "UART_PEX0_SDB_BUF_RX")
	)
	(segment
		(start 297.369484 -255.165098)
		(end 300.624748 -258.420362)
		(width 0.15494)
		(layer "In13.Cu")
		(net "UART_PEX0_SDB_BUF_RX")
	)
	(segment
		(start 114.056414 -242.7732)
		(end 134.88416 -242.7732)
		(width 0.15494)
		(layer "In13.Cu")
		(net "UART_PEX0_SDB_BUF_RX")
	)
	(segment
		(start 318.141096 -256.15265)
		(end 319.25768 -255.036066)
		(width 0.15494)
		(layer "In13.Cu")
		(net "UART_PEX0_SDB_BUF_RX")
	)
	(segment
		(start 252.342142 -253.36246)
		(end 253.702312 -254.72263)
		(width 0.15494)
		(layer "In13.Cu")
		(net "UART_PEX0_SDB_BUF_RX")
	)
	(segment
		(start 98.99396 -257.835654)
		(end 114.056414 -242.7732)
		(width 0.15494)
		(layer "In13.Cu")
		(net "UART_PEX0_SDB_BUF_RX")
	)
	(segment
		(start 308.31155 -256.15265)
		(end 318.141096 -256.15265)
		(width 0.15494)
		(layer "In13.Cu")
		(net "UART_PEX0_SDB_BUF_RX")
	)
	(segment
		(start 300.624748 -258.420362)
		(end 306.043838 -258.420362)
		(width 0.15494)
		(layer "In13.Cu")
		(net "UART_PEX0_SDB_BUF_RX")
	)
	(segment
		(start 134.88416 -242.7732)
		(end 135.347202 -242.310158)
		(width 0.15494)
		(layer "In13.Cu")
		(net "UART_PEX0_SDB_BUF_RX")
	)
	(segment
		(start 370.509546 -235.712)
		(end 377.987052 -228.234494)
		(width 0.15494)
		(layer "In13.Cu")
		(net "UART_PEX0_SDB_BUF_RX")
	)
	(segment
		(start 368.554 -235.712)
		(end 370.509546 -235.712)
		(width 0.15494)
		(layer "In13.Cu")
		(net "UART_PEX0_SDB_BUF_RX")
	)
	(segment
		(start 135.347202 -242.310158)
		(end 140.453618 -242.310158)
		(width 0.15494)
		(layer "In13.Cu")
		(net "UART_PEX0_SDB_BUF_RX")
	)
	(segment
		(start 270.50365 -254.72263)
		(end 270.946118 -255.165098)
		(width 0.15494)
		(layer "In13.Cu")
		(net "UART_PEX0_SDB_BUF_RX")
	)
	(segment
		(start 270.946118 -255.165098)
		(end 297.369484 -255.165098)
		(width 0.15494)
		(layer "In13.Cu")
		(net "UART_PEX0_SDB_BUF_RX")
	)
	(segment
		(start 150.368254 -244.2972)
		(end 173.1518 -244.2972)
		(width 0.15494)
		(layer "In13.Cu")
		(net "UART_PEX0_SDB_BUF_RX")
	)
	(segment
		(start 338.996528 -255.036066)
		(end 342.09736 -251.935234)
		(width 0.15494)
		(layer "In13.Cu")
		(net "UART_PEX0_SDB_BUF_RX")
	)
	(segment
		(start 173.1518 -244.2972)
		(end 180.6194 -251.7648)
		(width 0.15494)
		(layer "In13.Cu")
		(net "UART_PEX0_SDB_BUF_RX")
	)
	(segment
		(start 342.09736 -251.46254)
		(end 347.12402 -246.43588)
		(width 0.15494)
		(layer "In13.Cu")
		(net "UART_PEX0_SDB_BUF_RX")
	)
	(segment
		(start 84.83219 -258.55803)
		(end 85.554566 -257.835654)
		(width 0.15494)
		(layer "In13.Cu")
		(net "UART_PEX0_SDB_BUF_RX")
	)
	(segment
		(start 253.702312 -254.72263)
		(end 270.50365 -254.72263)
		(width 0.15494)
		(layer "In13.Cu")
		(net "UART_PEX0_SDB_BUF_RX")
	)
	(segment
		(start 145.161254 -244.2972)
		(end 146.439128 -243.019326)
		(width 0.15494)
		(layer "In13.Cu")
		(net "UART_PEX0_SDB_BUF_RX")
	)
	(segment
		(start 85.554566 -257.835654)
		(end 98.99396 -257.835654)
		(width 0.15494)
		(layer "In13.Cu")
		(net "UART_PEX0_SDB_BUF_RX")
	)
	(segment
		(start 347.12402 -246.43588)
		(end 350.648778 -246.43588)
		(width 0.15494)
		(layer "In13.Cu")
		(net "UART_PEX0_SDB_BUF_RX")
	)
	(segment
		(start 306.043838 -258.420362)
		(end 308.31155 -256.15265)
		(width 0.15494)
		(layer "In13.Cu")
		(net "UART_PEX0_SDB_BUF_RX")
	)
	(segment
		(start 146.439128 -243.019326)
		(end 149.09038 -243.019326)
		(width 0.15494)
		(layer "In13.Cu")
		(net "UART_PEX0_SDB_BUF_RX")
	)
	(segment
		(start 360.432858 -236.6518)
		(end 367.6142 -236.6518)
		(width 0.15494)
		(layer "In13.Cu")
		(net "UART_PEX0_SDB_BUF_RX")
	)
	(segment
		(start 229.105968 -251.5108)
		(end 232.790746 -251.5108)
		(width 0.15494)
		(layer "In13.Cu")
		(net "UART_PEX0_SDB_BUF_RX")
	)
	(segment
		(start 142.44066 -244.2972)
		(end 145.161254 -244.2972)
		(width 0.15494)
		(layer "In13.Cu")
		(net "UART_PEX0_SDB_BUF_RX")
	)
	(segment
		(start 232.790746 -251.5108)
		(end 234.642406 -253.36246)
		(width 0.15494)
		(layer "In13.Cu")
		(net "UART_PEX0_SDB_BUF_RX")
	)
	(via
		(at 367.939574 -234.806744)
		(size 0.6604)
		(drill 0.3302)
		(layers "F.Cu" "B.Cu")
		(net "FT4232_SDB_EEPROM_DO")
	)
	(segment
		(start 365.86795 -235.030772)
		(end 365.86795 -235.458)
		(width 0.13208)
		(layer "B.Cu")
		(net "FT4232_SDB_EEPROM_DO")
	)
	(segment
		(start 369.248182 -235.739432)
		(end 368.315494 -234.806744)
		(width 0.13208)
		(layer "B.Cu")
		(net "FT4232_SDB_EEPROM_DO")
	)
	(segment
		(start 367.939574 -234.806744)
		(end 366.091978 -234.806744)
		(width 0.13208)
		(layer "B.Cu")
		(net "FT4232_SDB_EEPROM_DO")
	)
	(segment
		(start 369.521486 -235.739432)
		(end 369.248182 -235.739432)
		(width 0.13208)
		(layer "B.Cu")
		(net "FT4232_SDB_EEPROM_DO")
	)
	(segment
		(start 366.091978 -234.806744)
		(end 365.86795 -235.030772)
		(width 0.13208)
		(layer "B.Cu")
		(net "FT4232_SDB_EEPROM_DO")
	)
	(segment
		(start 368.315494 -234.806744)
		(end 367.939574 -234.806744)
		(width 0.13208)
		(layer "B.Cu")
		(net "FT4232_SDB_EEPROM_DO")
	)
	(segment
		(start 365.86795 -236.601)
		(end 365.86795 -235.458)
		(width 0.13208)
		(layer "B.Cu")
		(net "FT4232_SDB_EEPROM_DO")
	)
	(segment
		(start 260.540246 -78.06309)
		(end 260.540246 -77.679804)
		(width 0.13208)
		(layer "F.Cu")
		(net "CLK_GEN_CK440_OE4_N")
	)
	(segment
		(start 260.456172 -79.431642)
		(end 260.676898 -79.652368)
		(width 0.13208)
		(layer "F.Cu")
		(net "CLK_GEN_CK440_OE4_N")
	)
	(segment
		(start 260.676898 -80.05318)
		(end 260.676898 -81.181448)
		(width 0.0889)
		(layer "F.Cu")
		(net "CLK_GEN_CK440_OE4_N")
	)
	(segment
		(start 260.676898 -79.652368)
		(end 260.676898 -80.05318)
		(width 0.13208)
		(layer "F.Cu")
		(net "CLK_GEN_CK440_OE4_N")
	)
	(segment
		(start 260.456172 -78.860904)
		(end 260.456172 -79.431642)
		(width 0.13208)
		(layer "F.Cu")
		(net "CLK_GEN_CK440_OE4_N")
	)
	(segment
		(start 260.456172 -78.147164)
		(end 260.540246 -78.06309)
		(width 0.13208)
		(layer "F.Cu")
		(net "CLK_GEN_CK440_OE4_N")
	)
	(segment
		(start 260.456172 -78.860904)
		(end 260.456172 -78.147164)
		(width 0.13208)
		(layer "F.Cu")
		(net "CLK_GEN_CK440_OE4_N")
	)
	(via
		(at 260.456172 -78.860904)
		(size 0.762)
		(drill 0.381)
		(layers "F.Cu" "B.Cu")
		(net "CLK_GEN_CK440_OE4_N")
	)
	(segment
		(start 92.0496 -304.436526)
		(end 92.0496 -305.007518)
		(width 0.13208)
		(layer "F.Cu")
		(net "PEX0_SPARE6")
	)
	(segment
		(start 92.050108 -305.063906)
		(end 92.050108 -305.674522)
		(width 0.13208)
		(layer "F.Cu")
		(net "PEX0_SPARE6")
	)
	(segment
		(start 92.050108 -305.008026)
		(end 92.050108 -305.063906)
		(width 0.13208)
		(layer "F.Cu")
		(net "PEX0_SPARE6")
	)
	(segment
		(start 92.0496 -305.007518)
		(end 92.050108 -305.008026)
		(width 0.13208)
		(layer "F.Cu")
		(net "PEX0_SPARE6")
	)
	(segment
		(start 62.974728 -308.724554)
		(end 62.499748 -309.199788)
		(width 0.13208)
		(layer "F.Cu")
		(net "PEX0_SPARE6")
	)
	(via
		(at 62.974728 -308.724554)
		(size 0.4064)
		(drill 0.2032)
		(layers "F.Cu" "B.Cu")
		(net "PEX0_SPARE6")
	)
	(via
		(at 92.050108 -305.063906)
		(size 0.508)
		(drill 0.254)
		(layers "F.Cu" "B.Cu")
		(net "PEX0_SPARE6")
	)
	(via
		(at 84.07781 -312.999882)
		(size 0.6604)
		(drill 0.3302)
		(layers "F.Cu" "B.Cu")
		(net "PEX0_SPARE6")
	)
	(segment
		(start 65.116202 -312.537602)
		(end 83.61553 -312.537602)
		(width 0.13208)
		(layer "B.Cu")
		(net "PEX0_SPARE6")
	)
	(segment
		(start 91.445842 -305.63185)
		(end 84.07781 -312.999882)
		(width 0.13208)
		(layer "B.Cu")
		(net "PEX0_SPARE6")
	)
	(segment
		(start 64.86017 -309.760366)
		(end 64.86017 -312.28157)
		(width 0.13208)
		(layer "B.Cu")
		(net "PEX0_SPARE6")
	)
	(segment
		(start 64.86017 -312.28157)
		(end 65.116202 -312.537602)
		(width 0.13208)
		(layer "B.Cu")
		(net "PEX0_SPARE6")
	)
	(segment
		(start 91.482164 -305.63185)
		(end 91.445842 -305.63185)
		(width 0.13208)
		(layer "B.Cu")
		(net "PEX0_SPARE6")
	)
	(segment
		(start 83.61553 -312.537602)
		(end 84.07781 -312.999882)
		(width 0.13208)
		(layer "B.Cu")
		(net "PEX0_SPARE6")
	)
	(segment
		(start 92.050108 -305.063906)
		(end 91.482164 -305.63185)
		(width 0.13208)
		(layer "B.Cu")
		(net "PEX0_SPARE6")
	)
	(segment
		(start 64.2874 -309.187596)
		(end 64.86017 -309.760366)
		(width 0.13208)
		(layer "B.Cu")
		(net "PEX0_SPARE6")
	)
	(segment
		(start 63.43777 -309.187596)
		(end 64.2874 -309.187596)
		(width 0.13208)
		(layer "B.Cu")
		(net "PEX0_SPARE6")
	)
	(segment
		(start 62.974728 -308.724554)
		(end 63.43777 -309.187596)
		(width 0.13208)
		(layer "B.Cu")
		(net "PEX0_SPARE6")
	)
	(segment
		(start 126.250192 -93.8403)
		(end 127.462534 -93.8403)
		(width 0.13208)
		(layer "F.Cu")
		(net "SMB_BIC_I2C9_MUX0_SSD1_SCL")
	)
	(segment
		(start 124.166884 -93.8403)
		(end 126.250192 -93.8403)
		(width 0.13208)
		(layer "F.Cu")
		(net "SMB_BIC_I2C9_MUX0_SSD1_SCL")
	)
	(segment
		(start 124.07519 -93.748606)
		(end 124.166884 -93.8403)
		(width 0.13208)
		(layer "F.Cu")
		(net "SMB_BIC_I2C9_MUX0_SSD1_SCL")
	)
	(via
		(at 126.250192 -93.8403)
		(size 0.508)
		(drill 0.254)
		(layers "F.Cu" "B.Cu")
		(net "SMB_BIC_I2C9_MUX0_SSD1_SCL")
	)
	(segment
		(start 343.25052 -232.82148)
		(end 343.027 -233.045)
		(width 0.13208)
		(layer "F.Cu")
		(net "RST_SSD3_PERST_N")
	)
	(segment
		(start 343.25052 -232.451656)
		(end 343.359994 -232.451656)
		(width 0.13208)
		(layer "F.Cu")
		(net "RST_SSD3_PERST_N")
	)
	(segment
		(start 344.45194 -231.35971)
		(end 344.45194 -228.57206)
		(width 0.13208)
		(layer "F.Cu")
		(net "RST_SSD3_PERST_N")
	)
	(segment
		(start 344.45194 -228.57206)
		(end 344.49385 -228.53015)
		(width 0.13208)
		(layer "F.Cu")
		(net "RST_SSD3_PERST_N")
	)
	(segment
		(start 343.359994 -232.451656)
		(end 344.45194 -231.35971)
		(width 0.13208)
		(layer "F.Cu")
		(net "RST_SSD3_PERST_N")
	)
	(segment
		(start 344.49385 -228.53015)
		(end 344.49385 -227.987098)
		(width 0.13208)
		(layer "F.Cu")
		(net "RST_SSD3_PERST_N")
	)
	(segment
		(start 343.25052 -232.451656)
		(end 343.25052 -232.82148)
		(width 0.13208)
		(layer "F.Cu")
		(net "RST_SSD3_PERST_N")
	)
	(segment
		(start 343.027 -233.045)
		(end 343.027 -233.66095)
		(width 0.13208)
		(layer "F.Cu")
		(net "RST_SSD3_PERST_N")
	)
	(via
		(at 343.25052 -232.451656)
		(size 0.762)
		(drill 0.381)
		(layers "F.Cu" "B.Cu")
		(net "RST_SSD3_PERST_N")
	)
	(segment
		(start 355.346 -215.987122)
		(end 355.766878 -216.408)
		(width 0.13208)
		(layer "F.Cu")
		(net "PRSNT_NIC0_FPGA_N")
	)
	(segment
		(start 355.766878 -216.408)
		(end 357.61295 -216.408)
		(width 0.13208)
		(layer "F.Cu")
		(net "PRSNT_NIC0_FPGA_N")
	)
	(segment
		(start 350.893888 -215.987122)
		(end 351.6884 -215.987122)
		(width 0.0889)
		(layer "F.Cu")
		(net "PRSNT_NIC0_FPGA_N")
	)
	(segment
		(start 351.6884 -215.987122)
		(end 354.838 -215.987122)
		(width 0.13208)
		(layer "F.Cu")
		(net "PRSNT_NIC0_FPGA_N")
	)
	(segment
		(start 354.838 -215.987122)
		(end 355.346 -215.987122)
		(width 0.13208)
		(layer "F.Cu")
		(net "PRSNT_NIC0_FPGA_N")
	)
	(via
		(at 354.838 -215.987122)
		(size 0.762)
		(drill 0.381)
		(layers "F.Cu" "B.Cu")
		(net "PRSNT_NIC0_FPGA_N")
	)
	(segment
		(start 218.675458 -54.144164)
		(end 218.856052 -53.96357)
		(width 0.13208)
		(layer "F.Cu")
		(net "P12V_SSD7_OCP")
	)
	(segment
		(start 218.247214 -54.144164)
		(end 218.675458 -54.144164)
		(width 0.13208)
		(layer "F.Cu")
		(net "P12V_SSD7_OCP")
	)
	(segment
		(start 219.863924 -53.96357)
		(end 219.25407 -53.96357)
		(width 0.13208)
		(layer "F.Cu")
		(net "P12V_SSD7_OCP")
	)
	(segment
		(start 219.96781 -54.067456)
		(end 219.863924 -53.96357)
		(width 0.13208)
		(layer "F.Cu")
		(net "P12V_SSD7_OCP")
	)
	(segment
		(start 218.856052 -53.96357)
		(end 219.25407 -53.96357)
		(width 0.13208)
		(layer "F.Cu")
		(net "P12V_SSD7_OCP")
	)
	(via
		(at 219.25407 -53.96357)
		(size 0.508)
		(drill 0.254)
		(layers "F.Cu" "B.Cu")
		(net "P12V_SSD7_OCP")
	)
	(segment
		(start 236.92485 -91.266518)
		(end 236.433614 -91.266518)
		(width 0.254)
		(layer "F.Cu")
		(net "P3V3_PEX_USB_HUB")
	)
	(segment
		(start 234.520994 -89.854024)
		(end 234.520994 -88.889586)
		(width 0.254)
		(layer "F.Cu")
		(net "P3V3_PEX_USB_HUB")
	)
	(segment
		(start 231.212136 -90.766392)
		(end 231.049576 -90.603832)
		(width 0.254)
		(layer "F.Cu")
		(net "P3V3_PEX_USB_HUB")
	)
	(segment
		(start 237.353856 -91.088972)
		(end 236.92485 -91.266518)
		(width 0.254)
		(layer "F.Cu")
		(net "P3V3_PEX_USB_HUB")
	)
	(segment
		(start 232.520998 -94.679008)
		(end 231.975152 -94.679008)
		(width 0.13208)
		(layer "F.Cu")
		(net "P3V3_PEX_USB_HUB")
	)
	(segment
		(start 231.60863 -90.766392)
		(end 231.212136 -90.766392)
		(width 0.254)
		(layer "F.Cu")
		(net "P3V3_PEX_USB_HUB")
	)
	(segment
		(start 231.60863 -91.266518)
		(end 230.79075 -91.266518)
		(width 0.254)
		(layer "F.Cu")
		(net "P3V3_PEX_USB_HUB")
	)
	(segment
		(start 236.433614 -93.76664)
		(end 237.247938 -93.76664)
		(width 0.2032)
		(layer "F.Cu")
		(net "P3V3_PEX_USB_HUB")
	)
	(segment
		(start 231.049576 -90.603832)
		(end 230.764334 -90.603832)
		(width 0.254)
		(layer "F.Cu")
		(net "P3V3_PEX_USB_HUB")
	)
	(via
		(at 237.247938 -93.76664)
		(size 0.508)
		(drill 0.254)
		(layers "F.Cu" "B.Cu")
		(net "P3V3_PEX_USB_HUB")
	)
	(via
		(at 234.520994 -88.889586)
		(size 0.508)
		(drill 0.254)
		(layers "F.Cu" "B.Cu")
		(net "P3V3_PEX_USB_HUB")
	)
	(via
		(at 230.79075 -91.266518)
		(size 0.508)
		(drill 0.254)
		(layers "F.Cu" "B.Cu")
		(net "P3V3_PEX_USB_HUB")
	)
	(via
		(at 230.764334 -90.603832)
		(size 0.508)
		(drill 0.254)
		(layers "F.Cu" "B.Cu")
		(net "P3V3_PEX_USB_HUB")
	)
	(via
		(at 237.353856 -91.088972)
		(size 0.508)
		(drill 0.254)
		(layers "F.Cu" "B.Cu")
		(net "P3V3_PEX_USB_HUB")
	)
	(via
		(at 231.975152 -94.679008)
		(size 0.508)
		(drill 0.254)
		(layers "F.Cu" "B.Cu")
		(net "P3V3_PEX_USB_HUB")
	)
	(segment
		(start 384.855466 -233.957876)
		(end 384.855466 -232.836212)
		(width 0.2794)
		(layer "F.Cu")
		(net "P3V3_SDB_VPLL")
	)
	(via
		(at 385.099306 -233.273346)
		(size 0.6604)
		(drill 0.3302)
		(layers "F.Cu" "B.Cu")
		(net "P3V3_SDB_VPLL")
	)
	(via
		(at 382.562354 -232.594404)
		(size 0.6604)
		(drill 0.3302)
		(layers "F.Cu" "B.Cu")
		(net "P3V3_SDB_VPLL")
	)
	(via
		(at 383.859024 -232.748836)
		(size 0.6604)
		(drill 0.3302)
		(layers "F.Cu" "B.Cu")
		(net "P3V3_SDB_VPLL")
	)
	(via
		(at 384.855466 -233.957876)
		(size 0.508)
		(drill 0.254)
		(layers "F.Cu" "B.Cu")
		(net "P3V3_SDB_VPLL")
	)
	(segment
		(start 60.124848 -308.724808)
		(end 59.649868 -309.199788)
		(width 0.13462)
		(layer "F.Cu")
		(net "PEX0_SPARE5")
	)
	(segment
		(start 90.52179 -311.969404)
		(end 90.215974 -311.663588)
		(width 0.13208)
		(layer "F.Cu")
		(net "PEX0_SPARE5")
	)
	(segment
		(start 92.069666 -311.4802)
		(end 91.580462 -311.969404)
		(width 0.13208)
		(layer "F.Cu")
		(net "PEX0_SPARE5")
	)
	(segment
		(start 91.580462 -311.969404)
		(end 91.509342 -311.969404)
		(width 0.13208)
		(layer "F.Cu")
		(net "PEX0_SPARE5")
	)
	(segment
		(start 91.509342 -311.969404)
		(end 90.52179 -311.969404)
		(width 0.13208)
		(layer "F.Cu")
		(net "PEX0_SPARE5")
	)
	(via
		(at 91.509342 -311.969404)
		(size 0.508)
		(drill 0.254)
		(layers "F.Cu" "B.Cu")
		(net "PEX0_SPARE5")
	)
	(via
		(at 60.124848 -308.724808)
		(size 0.4064)
		(drill 0.2032)
		(layers "F.Cu" "B.Cu")
		(net "PEX0_SPARE5")
	)
	(via
		(at 78.381352 -320.890646)
		(size 0.6604)
		(drill 0.3302)
		(layers "F.Cu" "B.Cu")
		(net "PEX0_SPARE5")
	)
	(segment
		(start 60.124848 -319.76314)
		(end 60.124848 -308.724808)
		(width 0.13208)
		(layer "B.Cu")
		(net "PEX0_SPARE5")
	)
	(segment
		(start 91.509342 -311.969404)
		(end 90.200226 -313.27852)
		(width 0.13208)
		(layer "B.Cu")
		(net "PEX0_SPARE5")
	)
	(segment
		(start 81.935066 -320.890646)
		(end 78.381352 -320.890646)
		(width 0.13208)
		(layer "B.Cu")
		(net "PEX0_SPARE5")
	)
	(segment
		(start 78.381352 -320.890646)
		(end 61.252354 -320.890646)
		(width 0.13208)
		(layer "B.Cu")
		(net "PEX0_SPARE5")
	)
	(segment
		(start 61.252354 -320.890646)
		(end 60.124848 -319.76314)
		(width 0.13208)
		(layer "B.Cu")
		(net "PEX0_SPARE5")
	)
	(segment
		(start 90.200226 -313.27852)
		(end 89.547192 -313.27852)
		(width 0.13208)
		(layer "B.Cu")
		(net "PEX0_SPARE5")
	)
	(segment
		(start 89.547192 -313.27852)
		(end 81.935066 -320.890646)
		(width 0.13208)
		(layer "B.Cu")
		(net "PEX0_SPARE5")
	)
	(segment
		(start 125.362208 -94.49054)
		(end 127.462534 -94.49054)
		(width 0.13208)
		(layer "F.Cu")
		(net "SMB_BIC_I2C9_MUX0_SSD1_SDA")
	)
	(segment
		(start 124.07519 -94.891606)
		(end 124.68479 -94.891606)
		(width 0.13208)
		(layer "F.Cu")
		(net "SMB_BIC_I2C9_MUX0_SSD1_SDA")
	)
	(segment
		(start 124.68479 -94.891606)
		(end 124.961142 -94.891606)
		(width 0.13208)
		(layer "F.Cu")
		(net "SMB_BIC_I2C9_MUX0_SSD1_SDA")
	)
	(segment
		(start 124.961142 -94.891606)
		(end 125.362208 -94.49054)
		(width 0.13208)
		(layer "F.Cu")
		(net "SMB_BIC_I2C9_MUX0_SSD1_SDA")
	)
	(via
		(at 124.68479 -94.891606)
		(size 0.508)
		(drill 0.254)
		(layers "F.Cu" "B.Cu")
		(net "SMB_BIC_I2C9_MUX0_SSD1_SDA")
	)
	(segment
		(start 349.293942 -226.387152)
		(end 349.693738 -226.786948)
		(width 0.13208)
		(layer "F.Cu")
		(net "SSD7_CLK_EN_N")
	)
	(via
		(at 350.52 -231.775)
		(size 0.6604)
		(drill 0.3302)
		(layers "F.Cu" "B.Cu")
		(net "SSD7_CLK_EN_N")
	)
	(via
		(at 349.693738 -226.786948)
		(size 0.4572)
		(drill 0.254)
		(layers "F.Cu" "B.Cu")
		(net "SSD7_CLK_EN_N")
	)
	(segment
		(start 350.139 -233.15295)
		(end 350.52 -232.77195)
		(width 0.13208)
		(layer "B.Cu")
		(net "SSD7_CLK_EN_N")
	)
	(segment
		(start 350.52 -228.27361)
		(end 349.693738 -227.447348)
		(width 0.13208)
		(layer "B.Cu")
		(net "SSD7_CLK_EN_N")
	)
	(segment
		(start 350.52 -232.77195)
		(end 350.52 -231.775)
		(width 0.13208)
		(layer "B.Cu")
		(net "SSD7_CLK_EN_N")
	)
	(segment
		(start 349.693738 -227.447348)
		(end 349.693738 -226.786948)
		(width 0.13208)
		(layer "B.Cu")
		(net "SSD7_CLK_EN_N")
	)
	(segment
		(start 350.52 -231.775)
		(end 350.52 -228.27361)
		(width 0.13208)
		(layer "B.Cu")
		(net "SSD7_CLK_EN_N")
	)
	(segment
		(start 379.298454 -197.335394)
		(end 379.79477 -197.83171)
		(width 0.13208)
		(layer "F.Cu")
		(net "NIC2_PEX_PWR_EN_R")
	)
	(segment
		(start 348.493842 -216.786968)
		(end 348.893638 -216.387172)
		(width 0.13208)
		(layer "F.Cu")
		(net "NIC2_PEX_PWR_EN_R")
	)
	(segment
		(start 381.52705 -197.83171)
		(end 381.65405 -197.70471)
		(width 0.13208)
		(layer "F.Cu")
		(net "NIC2_PEX_PWR_EN_R")
	)
	(segment
		(start 381.65405 -196.342)
		(end 381.65405 -195.326)
		(width 0.13208)
		(layer "F.Cu")
		(net "NIC2_PEX_PWR_EN_R")
	)
	(segment
		(start 381.65405 -197.70471)
		(end 381.65405 -197.358)
		(width 0.13208)
		(layer "F.Cu")
		(net "NIC2_PEX_PWR_EN_R")
	)
	(segment
		(start 381.65405 -196.342)
		(end 381.65405 -197.358)
		(width 0.13208)
		(layer "F.Cu")
		(net "NIC2_PEX_PWR_EN_R")
	)
	(segment
		(start 379.79477 -197.83171)
		(end 381.52705 -197.83171)
		(width 0.13208)
		(layer "F.Cu")
		(net "NIC2_PEX_PWR_EN_R")
	)
	(via
		(at 348.893638 -216.387172)
		(size 0.4572)
		(drill 0.254)
		(layers "F.Cu" "B.Cu")
		(net "NIC2_PEX_PWR_EN_R")
	)
	(via
		(at 379.298454 -197.335394)
		(size 0.508)
		(drill 0.254)
		(layers "F.Cu" "B.Cu")
		(net "NIC2_PEX_PWR_EN_R")
	)
	(via
		(at 369.643914 -192.952624)
		(size 0.508)
		(drill 0.254)
		(layers "F.Cu" "B.Cu")
		(net "NIC2_PEX_PWR_EN_R")
	)
	(segment
		(start 370.160296 -196.5452)
		(end 370.160296 -193.469006)
		(width 0.15494)
		(layer "In7.Cu")
		(net "NIC2_PEX_PWR_EN_R")
	)
	(segment
		(start 370.160296 -193.469006)
		(end 369.643914 -192.952624)
		(width 0.15494)
		(layer "In7.Cu")
		(net "NIC2_PEX_PWR_EN_R")
	)
	(segment
		(start 355.827838 -207.820768)
		(end 356.803198 -207.416908)
		(width 0.15494)
		(layer "In7.Cu")
		(net "NIC2_PEX_PWR_EN_R")
	)
	(segment
		(start 348.893638 -216.387172)
		(end 349.293688 -216.787222)
		(width 0.0889)
		(layer "In7.Cu")
		(net "NIC2_PEX_PWR_EN_R")
	)
	(segment
		(start 351.613978 -216.787222)
		(end 351.616518 -216.784682)
		(width 0.0889)
		(layer "In7.Cu")
		(net "NIC2_PEX_PWR_EN_R")
	)
	(segment
		(start 369.785646 -196.91985)
		(end 370.160296 -196.5452)
		(width 0.15494)
		(layer "In7.Cu")
		(net "NIC2_PEX_PWR_EN_R")
	)
	(segment
		(start 363.04474 -203.29271)
		(end 368.6556 -197.68185)
		(width 0.15494)
		(layer "In7.Cu")
		(net "NIC2_PEX_PWR_EN_R")
	)
	(segment
		(start 368.6556 -197.332346)
		(end 369.068096 -196.91985)
		(width 0.15494)
		(layer "In7.Cu")
		(net "NIC2_PEX_PWR_EN_R")
	)
	(segment
		(start 354.083366 -214.317834)
		(end 354.083366 -209.56524)
		(width 0.15494)
		(layer "In7.Cu")
		(net "NIC2_PEX_PWR_EN_R")
	)
	(segment
		(start 368.6556 -197.68185)
		(end 368.6556 -197.332346)
		(width 0.15494)
		(layer "In7.Cu")
		(net "NIC2_PEX_PWR_EN_R")
	)
	(segment
		(start 357.479092 -207.416908)
		(end 361.60329 -203.29271)
		(width 0.15494)
		(layer "In7.Cu")
		(net "NIC2_PEX_PWR_EN_R")
	)
	(segment
		(start 354.083366 -209.56524)
		(end 355.827838 -207.820768)
		(width 0.15494)
		(layer "In7.Cu")
		(net "NIC2_PEX_PWR_EN_R")
	)
	(segment
		(start 369.068096 -196.91985)
		(end 369.785646 -196.91985)
		(width 0.15494)
		(layer "In7.Cu")
		(net "NIC2_PEX_PWR_EN_R")
	)
	(segment
		(start 349.293688 -216.787222)
		(end 351.613978 -216.787222)
		(width 0.0889)
		(layer "In7.Cu")
		(net "NIC2_PEX_PWR_EN_R")
	)
	(segment
		(start 361.60329 -203.29271)
		(end 363.04474 -203.29271)
		(width 0.15494)
		(layer "In7.Cu")
		(net "NIC2_PEX_PWR_EN_R")
	)
	(segment
		(start 356.803198 -207.416908)
		(end 357.479092 -207.416908)
		(width 0.15494)
		(layer "In7.Cu")
		(net "NIC2_PEX_PWR_EN_R")
	)
	(segment
		(start 351.616518 -216.784682)
		(end 354.083366 -214.317834)
		(width 0.15494)
		(layer "In7.Cu")
		(net "NIC2_PEX_PWR_EN_R")
	)
	(segment
		(start 376.669808 -193.961766)
		(end 371.487446 -193.961766)
		(width 0.15494)
		(layer "In13.Cu")
		(net "NIC2_PEX_PWR_EN_R")
	)
	(segment
		(start 379.298454 -196.590412)
		(end 376.669808 -193.961766)
		(width 0.15494)
		(layer "In13.Cu")
		(net "NIC2_PEX_PWR_EN_R")
	)
	(segment
		(start 370.79047 -193.26479)
		(end 369.95608 -193.26479)
		(width 0.15494)
		(layer "In13.Cu")
		(net "NIC2_PEX_PWR_EN_R")
	)
	(segment
		(start 371.487446 -193.961766)
		(end 370.79047 -193.26479)
		(width 0.15494)
		(layer "In13.Cu")
		(net "NIC2_PEX_PWR_EN_R")
	)
	(segment
		(start 369.95608 -193.26479)
		(end 369.643914 -192.952624)
		(width 0.15494)
		(layer "In13.Cu")
		(net "NIC2_PEX_PWR_EN_R")
	)
	(segment
		(start 379.298454 -197.335394)
		(end 379.298454 -196.590412)
		(width 0.15494)
		(layer "In13.Cu")
		(net "NIC2_PEX_PWR_EN_R")
	)
	(segment
		(start 450.447156 -53.144166)
		(end 450.630544 -53.144166)
		(width 0.13208)
		(layer "F.Cu")
		(net "P12V_SSD15_SS")
	)
	(segment
		(start 450.779896 -52.994814)
		(end 450.779896 -51.670966)
		(width 0.13208)
		(layer "F.Cu")
		(net "P12V_SSD15_SS")
	)
	(segment
		(start 450.779896 -51.670966)
		(end 451.431406 -51.019456)
		(width 0.13208)
		(layer "F.Cu")
		(net "P12V_SSD15_SS")
	)
	(segment
		(start 450.630544 -53.144166)
		(end 450.779896 -52.994814)
		(width 0.13208)
		(layer "F.Cu")
		(net "P12V_SSD15_SS")
	)
	(segment
		(start 451.431406 -51.019456)
		(end 452.167752 -51.019456)
		(width 0.13208)
		(layer "F.Cu")
		(net "P12V_SSD15_SS")
	)
	(via
		(at 451.431406 -51.019456)
		(size 0.508)
		(drill 0.254)
		(layers "F.Cu" "B.Cu")
		(net "P12V_SSD15_SS")
	)
	(segment
		(start 386.19684 -246.059706)
		(end 386.35559 -245.900956)
		(width 0.3048)
		(layer "F.Cu")
		(net "P1V8_SDB_VCORE")
	)
	(segment
		(start 386.045202 -246.211344)
		(end 386.19684 -246.059706)
		(width 0.381)
		(layer "F.Cu")
		(net "P1V8_SDB_VCORE")
	)
	(segment
		(start 386.35559 -233.957876)
		(end 386.35559 -232.836212)
		(width 0.2794)
		(layer "F.Cu")
		(net "P1V8_SDB_VCORE")
	)
	(segment
		(start 386.045202 -247.32996)
		(end 386.045202 -246.211344)
		(width 0.381)
		(layer "F.Cu")
		(net "P1V8_SDB_VCORE")
	)
	(segment
		(start 386.35559 -243.16436)
		(end 386.35559 -244.286024)
		(width 0.2794)
		(layer "F.Cu")
		(net "P1V8_SDB_VCORE")
	)
	(segment
		(start 386.35559 -245.900956)
		(end 386.35559 -244.286024)
		(width 0.3048)
		(layer "F.Cu")
		(net "P1V8_SDB_VCORE")
	)
	(segment
		(start 378.880624 -242.311174)
		(end 380.002288 -242.311174)
		(width 0.2794)
		(layer "F.Cu")
		(net "P1V8_SDB_VCORE")
	)
	(segment
		(start 378.880624 -234.811062)
		(end 377.75896 -234.811062)
		(width 0.2794)
		(layer "F.Cu")
		(net "P1V8_SDB_VCORE")
	)
	(segment
		(start 386.045202 -247.32996)
		(end 386.045202 -248.319798)
		(width 0.381)
		(layer "F.Cu")
		(net "P1V8_SDB_VCORE")
	)
	(via
		(at 386.35559 -243.16436)
		(size 0.508)
		(drill 0.254)
		(layers "F.Cu" "B.Cu")
		(net "P1V8_SDB_VCORE")
	)
	(via
		(at 387.656324 -233.258614)
		(size 0.6604)
		(drill 0.3302)
		(layers "F.Cu" "B.Cu")
		(net "P1V8_SDB_VCORE")
	)
	(via
		(at 378.46 -235.87837)
		(size 0.6604)
		(drill 0.3302)
		(layers "F.Cu" "B.Cu")
		(net "P1V8_SDB_VCORE")
	)
	(via
		(at 386.045202 -248.319798)
		(size 0.508)
		(drill 0.254)
		(layers "F.Cu" "B.Cu")
		(net "P1V8_SDB_VCORE")
	)
	(via
		(at 381.460248 -238.352838)
		(size 0.508)
		(drill 0.254)
		(layers "F.Cu" "B.Cu")
		(net "P1V8_SDB_VCORE")
	)
	(via
		(at 386.35559 -233.957876)
		(size 0.508)
		(drill 0.254)
		(layers "F.Cu" "B.Cu")
		(net "P1V8_SDB_VCORE")
	)
	(via
		(at 377.75896 -234.811062)
		(size 0.508)
		(drill 0.254)
		(layers "F.Cu" "B.Cu")
		(net "P1V8_SDB_VCORE")
	)
	(via
		(at 380.002288 -242.311174)
		(size 0.508)
		(drill 0.254)
		(layers "F.Cu" "B.Cu")
		(net "P1V8_SDB_VCORE")
	)
	(segment
		(start 386.316982 -233.258614)
		(end 387.656324 -233.258614)
		(width 0.13208)
		(layer "B.Cu")
		(net "P1V8_SDB_VCORE")
	)
	(segment
		(start 380.746 -242.08105)
		(end 380.232412 -242.08105)
		(width 0.381)
		(layer "B.Cu")
		(net "P1V8_SDB_VCORE")
	)
	(segment
		(start 378.46 -234.71505)
		(end 378.46 -235.87837)
		(width 0.13208)
		(layer "B.Cu")
		(net "P1V8_SDB_VCORE")
	)
	(segment
		(start 377.854972 -234.71505)
		(end 377.75896 -234.811062)
		(width 0.381)
		(layer "B.Cu")
		(net "P1V8_SDB_VCORE")
	)
	(segment
		(start 386.316982 -233.258614)
		(end 386.316982 -233.919268)
		(width 0.4572)
		(layer "B.Cu")
		(net "P1V8_SDB_VCORE")
	)
	(segment
		(start 386.316982 -233.919268)
		(end 386.35559 -233.957876)
		(width 0.4572)
		(layer "B.Cu")
		(net "P1V8_SDB_VCORE")
	)
	(segment
		(start 378.46 -234.71505)
		(end 377.854972 -234.71505)
		(width 0.381)
		(layer "B.Cu")
		(net "P1V8_SDB_VCORE")
	)
	(segment
		(start 380.232412 -242.08105)
		(end 380.002288 -242.311174)
		(width 0.381)
		(layer "B.Cu")
		(net "P1V8_SDB_VCORE")
	)
	(segment
		(start 89.0016 -305.091846)
		(end 89.0016 -304.436526)
		(width 0.13208)
		(layer "F.Cu")
		(net "PEX0_SPARE4")
	)
	(segment
		(start 89.002108 -305.064922)
		(end 89.002108 -305.092354)
		(width 0.13208)
		(layer "F.Cu")
		(net "PEX0_SPARE4")
	)
	(segment
		(start 89.002108 -305.092354)
		(end 89.0016 -305.091846)
		(width 0.13208)
		(layer "F.Cu")
		(net "PEX0_SPARE4")
	)
	(segment
		(start 60.124848 -307.774848)
		(end 59.649868 -308.249828)
		(width 0.13462)
		(layer "F.Cu")
		(net "PEX0_SPARE4")
	)
	(segment
		(start 89.002108 -305.092354)
		(end 89.002108 -305.674522)
		(width 0.13208)
		(layer "F.Cu")
		(net "PEX0_SPARE4")
	)
	(via
		(at 60.124848 -307.774848)
		(size 0.4064)
		(drill 0.2032)
		(layers "F.Cu" "B.Cu")
		(net "PEX0_SPARE4")
	)
	(via
		(at 89.002108 -305.064922)
		(size 0.508)
		(drill 0.254)
		(layers "F.Cu" "B.Cu")
		(net "PEX0_SPARE4")
	)
	(via
		(at 87.542878 -303.544986)
		(size 0.6604)
		(drill 0.3302)
		(layers "F.Cu" "B.Cu")
		(net "PEX0_SPARE4")
	)
	(segment
		(start 60.58662 -308.23662)
		(end 72.81418 -308.23662)
		(width 0.13208)
		(layer "B.Cu")
		(net "PEX0_SPARE4")
	)
	(segment
		(start 86.555326 -305.519074)
		(end 86.860634 -305.213766)
		(width 0.13208)
		(layer "B.Cu")
		(net "PEX0_SPARE4")
	)
	(segment
		(start 86.860634 -304.22723)
		(end 87.542878 -303.544986)
		(width 0.13208)
		(layer "B.Cu")
		(net "PEX0_SPARE4")
	)
	(segment
		(start 73.1901 -307.8607)
		(end 73.1901 -307.2511)
		(width 0.13208)
		(layer "B.Cu")
		(net "PEX0_SPARE4")
	)
	(segment
		(start 87.651844 -303.43602)
		(end 88.346026 -303.43602)
		(width 0.13208)
		(layer "B.Cu")
		(net "PEX0_SPARE4")
	)
	(segment
		(start 73.633838 -306.807362)
		(end 84.627466 -306.807362)
		(width 0.13208)
		(layer "B.Cu")
		(net "PEX0_SPARE4")
	)
	(segment
		(start 89.002108 -304.092102)
		(end 89.002108 -305.064922)
		(width 0.13208)
		(layer "B.Cu")
		(net "PEX0_SPARE4")
	)
	(segment
		(start 72.81418 -308.23662)
		(end 73.1901 -307.8607)
		(width 0.13208)
		(layer "B.Cu")
		(net "PEX0_SPARE4")
	)
	(segment
		(start 60.124848 -307.774848)
		(end 60.58662 -308.23662)
		(width 0.13208)
		(layer "B.Cu")
		(net "PEX0_SPARE4")
	)
	(segment
		(start 86.860634 -305.213766)
		(end 86.860634 -304.22723)
		(width 0.13208)
		(layer "B.Cu")
		(net "PEX0_SPARE4")
	)
	(segment
		(start 84.627466 -306.807362)
		(end 86.555326 -305.519074)
		(width 0.13208)
		(layer "B.Cu")
		(net "PEX0_SPARE4")
	)
	(segment
		(start 87.542878 -303.544986)
		(end 87.651844 -303.43602)
		(width 0.13208)
		(layer "B.Cu")
		(net "PEX0_SPARE4")
	)
	(segment
		(start 73.1901 -307.2511)
		(end 73.633838 -306.807362)
		(width 0.13208)
		(layer "B.Cu")
		(net "PEX0_SPARE4")
	)
	(segment
		(start 88.346026 -303.43602)
		(end 89.002108 -304.092102)
		(width 0.13208)
		(layer "B.Cu")
		(net "PEX0_SPARE4")
	)
	(segment
		(start 126.459742 -91.890342)
		(end 127.462534 -91.890342)
		(width 0.13208)
		(layer "F.Cu")
		(net "SMB_BIC_I2C9_MUX0_SSD3_SDA")
	)
	(segment
		(start 124.049028 -90.151204)
		(end 124.604018 -90.706194)
		(width 0.13208)
		(layer "F.Cu")
		(net "SMB_BIC_I2C9_MUX0_SSD3_SDA")
	)
	(segment
		(start 124.049028 -89.53373)
		(end 124.049028 -90.151204)
		(width 0.13208)
		(layer "F.Cu")
		(net "SMB_BIC_I2C9_MUX0_SSD3_SDA")
	)
	(segment
		(start 125.275594 -90.706194)
		(end 126.459742 -91.890342)
		(width 0.13208)
		(layer "F.Cu")
		(net "SMB_BIC_I2C9_MUX0_SSD3_SDA")
	)
	(segment
		(start 124.604018 -90.706194)
		(end 125.175518 -90.706194)
		(width 0.13208)
		(layer "F.Cu")
		(net "SMB_BIC_I2C9_MUX0_SSD3_SDA")
	)
	(segment
		(start 125.175518 -90.706194)
		(end 125.275594 -90.706194)
		(width 0.13208)
		(layer "F.Cu")
		(net "SMB_BIC_I2C9_MUX0_SSD3_SDA")
	)
	(via
		(at 125.175518 -90.706194)
		(size 0.508)
		(drill 0.254)
		(layers "F.Cu" "B.Cu")
		(net "SMB_BIC_I2C9_MUX0_SSD3_SDA")
	)
	(segment
		(start 52.66309 -35.687)
		(end 53.208682 -36.232592)
		(width 0.13208)
		(layer "F.Cu")
		(net "PWRGD_P3V3_SSD2_R")
	)
	(segment
		(start 49.170844 -35.876738)
		(end 49.882044 -35.876738)
		(width 0.13208)
		(layer "F.Cu")
		(net "PWRGD_P3V3_SSD2_R")
	)
	(segment
		(start 53.208682 -36.232592)
		(end 53.59527 -36.232592)
		(width 0.13208)
		(layer "F.Cu")
		(net "PWRGD_P3V3_SSD2_R")
	)
	(segment
		(start 60.611004 -61.386974)
		(end 60.611004 -62.051438)
		(width 0.13208)
		(layer "F.Cu")
		(net "PWRGD_P3V3_SSD2_R")
	)
	(segment
		(start 339.693758 -223.187006)
		(end 339.293962 -223.586802)
		(width 0.13208)
		(layer "F.Cu")
		(net "PWRGD_P3V3_SSD2_R")
	)
	(segment
		(start 49.882044 -35.876738)
		(end 50.071782 -35.687)
		(width 0.13208)
		(layer "F.Cu")
		(net "PWRGD_P3V3_SSD2_R")
	)
	(segment
		(start 50.071782 -35.687)
		(end 52.66309 -35.687)
		(width 0.13208)
		(layer "F.Cu")
		(net "PWRGD_P3V3_SSD2_R")
	)
	(segment
		(start 49.170844 -35.876738)
		(end 48.427894 -35.876738)
		(width 0.13208)
		(layer "F.Cu")
		(net "PWRGD_P3V3_SSD2_R")
	)
	(via
		(at 63.120524 -206.258668)
		(size 0.508)
		(drill 0.254)
		(layers "F.Cu" "B.Cu")
		(net "PWRGD_P3V3_SSD2_R")
	)
	(via
		(at 49.170844 -35.876738)
		(size 0.508)
		(drill 0.254)
		(layers "F.Cu" "B.Cu")
		(net "PWRGD_P3V3_SSD2_R")
	)
	(via
		(at 60.611004 -62.051438)
		(size 0.508)
		(drill 0.254)
		(layers "F.Cu" "B.Cu")
		(net "PWRGD_P3V3_SSD2_R")
	)
	(via
		(at 339.293962 -223.586802)
		(size 0.4572)
		(drill 0.254)
		(layers "F.Cu" "B.Cu")
		(net "PWRGD_P3V3_SSD2_R")
	)
	(segment
		(start 52.02809 -35.876738)
		(end 49.170844 -35.876738)
		(width 0.15494)
		(layer "In5.Cu")
		(net "PWRGD_P3V3_SSD2_R")
	)
	(segment
		(start 60.611004 -62.051438)
		(end 61.723778 -62.051438)
		(width 0.15494)
		(layer "In5.Cu")
		(net "PWRGD_P3V3_SSD2_R")
	)
	(segment
		(start 63.120524 -206.258668)
		(end 62.166754 -205.304898)
		(width 0.15494)
		(layer "In5.Cu")
		(net "PWRGD_P3V3_SSD2_R")
	)
	(segment
		(start 57.353708 -67.247262)
		(end 60.611004 -63.989966)
		(width 0.15494)
		(layer "In5.Cu")
		(net "PWRGD_P3V3_SSD2_R")
	)
	(segment
		(start 58.674 -93.942154)
		(end 57.353708 -92.621862)
		(width 0.15494)
		(layer "In5.Cu")
		(net "PWRGD_P3V3_SSD2_R")
	)
	(segment
		(start 62.166754 -205.304898)
		(end 62.166754 -184.561226)
		(width 0.15494)
		(layer "In5.Cu")
		(net "PWRGD_P3V3_SSD2_R")
	)
	(segment
		(start 62.166754 -184.561226)
		(end 57.7596 -180.154072)
		(width 0.15494)
		(layer "In5.Cu")
		(net "PWRGD_P3V3_SSD2_R")
	)
	(segment
		(start 58.674 -154.381454)
		(end 58.674 -93.942154)
		(width 0.15494)
		(layer "In5.Cu")
		(net "PWRGD_P3V3_SSD2_R")
	)
	(segment
		(start 60.611004 -63.989966)
		(end 60.611004 -62.051438)
		(width 0.15494)
		(layer "In5.Cu")
		(net "PWRGD_P3V3_SSD2_R")
	)
	(segment
		(start 62.1157 -61.659516)
		(end 62.1157 -45.964348)
		(width 0.15494)
		(layer "In5.Cu")
		(net "PWRGD_P3V3_SSD2_R")
	)
	(segment
		(start 57.7596 -155.295854)
		(end 58.674 -154.381454)
		(width 0.15494)
		(layer "In5.Cu")
		(net "PWRGD_P3V3_SSD2_R")
	)
	(segment
		(start 61.723778 -62.051438)
		(end 62.1157 -61.659516)
		(width 0.15494)
		(layer "In5.Cu")
		(net "PWRGD_P3V3_SSD2_R")
	)
	(segment
		(start 57.7596 -180.154072)
		(end 57.7596 -155.295854)
		(width 0.15494)
		(layer "In5.Cu")
		(net "PWRGD_P3V3_SSD2_R")
	)
	(segment
		(start 62.1157 -45.964348)
		(end 52.02809 -35.876738)
		(width 0.15494)
		(layer "In5.Cu")
		(net "PWRGD_P3V3_SSD2_R")
	)
	(segment
		(start 57.353708 -92.621862)
		(end 57.353708 -67.247262)
		(width 0.15494)
		(layer "In5.Cu")
		(net "PWRGD_P3V3_SSD2_R")
	)
	(segment
		(start 260.189472 -226.095814)
		(end 259.198618 -225.10496)
		(width 0.15494)
		(layer "In15.Cu")
		(net "PWRGD_P3V3_SSD2_R")
	)
	(segment
		(start 333.567786 -232.09631)
		(end 333.199486 -231.72801)
		(width 0.15494)
		(layer "In15.Cu")
		(net "PWRGD_P3V3_SSD2_R")
	)
	(segment
		(start 332.014322 -231.71785)
		(end 332.004162 -231.72801)
		(width 0.15494)
		(layer "In15.Cu")
		(net "PWRGD_P3V3_SSD2_R")
	)
	(segment
		(start 243.411248 -229.81285)
		(end 242.098068 -231.12603)
		(width 0.15494)
		(layer "In15.Cu")
		(net "PWRGD_P3V3_SSD2_R")
	)
	(segment
		(start 336.696812 -231.361742)
		(end 335.962244 -232.09631)
		(width 0.15494)
		(layer "In15.Cu")
		(net "PWRGD_P3V3_SSD2_R")
	)
	(segment
		(start 271.22882 -232.7656)
		(end 265.33856 -226.87534)
		(width 0.15494)
		(layer "In15.Cu")
		(net "PWRGD_P3V3_SSD2_R")
	)
	(segment
		(start 322.507102 -233.056684)
		(end 321.558412 -233.056684)
		(width 0.15494)
		(layer "In15.Cu")
		(net "PWRGD_P3V3_SSD2_R")
	)
	(segment
		(start 162.43681 -228.0158)
		(end 156.045408 -221.624398)
		(width 0.15494)
		(layer "In15.Cu")
		(net "PWRGD_P3V3_SSD2_R")
	)
	(segment
		(start 117.300502 -213.707472)
		(end 117.300502 -211.226908)
		(width 0.15494)
		(layer "In15.Cu")
		(net "PWRGD_P3V3_SSD2_R")
	)
	(segment
		(start 265.33856 -226.87534)
		(end 262.071358 -226.87534)
		(width 0.15494)
		(layer "In15.Cu")
		(net "PWRGD_P3V3_SSD2_R")
	)
	(segment
		(start 131.22783 -224.489772)
		(end 130.864864 -224.852738)
		(width 0.15494)
		(layer "In15.Cu")
		(net "PWRGD_P3V3_SSD2_R")
	)
	(segment
		(start 209.021172 -230.5177)
		(end 208.023714 -231.515158)
		(width 0.15494)
		(layer "In15.Cu")
		(net "PWRGD_P3V3_SSD2_R")
	)
	(segment
		(start 110.676182 -205.12278)
		(end 102.461822 -205.12278)
		(width 0.15494)
		(layer "In15.Cu")
		(net "PWRGD_P3V3_SSD2_R")
	)
	(segment
		(start 213.72957 -230.5177)
		(end 209.021172 -230.5177)
		(width 0.15494)
		(layer "In15.Cu")
		(net "PWRGD_P3V3_SSD2_R")
	)
	(segment
		(start 292.784784 -231.80294)
		(end 291.822124 -232.7656)
		(width 0.15494)
		(layer "In15.Cu")
		(net "PWRGD_P3V3_SSD2_R")
	)
	(segment
		(start 141.253972 -224.534476)
		(end 137.259314 -224.534476)
		(width 0.15494)
		(layer "In15.Cu")
		(net "PWRGD_P3V3_SSD2_R")
	)
	(segment
		(start 325.24065 -234.115102)
		(end 323.56552 -234.115102)
		(width 0.15494)
		(layer "In15.Cu")
		(net "PWRGD_P3V3_SSD2_R")
	)
	(segment
		(start 320.304668 -231.80294)
		(end 292.784784 -231.80294)
		(width 0.15494)
		(layer "In15.Cu")
		(net "PWRGD_P3V3_SSD2_R")
	)
	(segment
		(start 111.201454 -205.12786)
		(end 110.681262 -205.12786)
		(width 0.15494)
		(layer "In15.Cu")
		(net "PWRGD_P3V3_SSD2_R")
	)
	(segment
		(start 253.862586 -226.35464)
		(end 250.322588 -226.35464)
		(width 0.15494)
		(layer "In15.Cu")
		(net "PWRGD_P3V3_SSD2_R")
	)
	(segment
		(start 327.627742 -231.72801)
		(end 325.24065 -234.115102)
		(width 0.15494)
		(layer "In15.Cu")
		(net "PWRGD_P3V3_SSD2_R")
	)
	(segment
		(start 340.313518 -231.361742)
		(end 336.696812 -231.361742)
		(width 0.15494)
		(layer "In15.Cu")
		(net "PWRGD_P3V3_SSD2_R")
	)
	(segment
		(start 250.322588 -226.35464)
		(end 249.659648 -225.6917)
		(width 0.15494)
		(layer "In15.Cu")
		(net "PWRGD_P3V3_SSD2_R")
	)
	(segment
		(start 243.411248 -228.80701)
		(end 243.411248 -229.81285)
		(width 0.15494)
		(layer "In15.Cu")
		(net "PWRGD_P3V3_SSD2_R")
	)
	(segment
		(start 214.3379 -231.12603)
		(end 213.72957 -230.5177)
		(width 0.15494)
		(layer "In15.Cu")
		(net "PWRGD_P3V3_SSD2_R")
	)
	(segment
		(start 128.445768 -224.852738)
		(end 117.300502 -213.707472)
		(width 0.15494)
		(layer "In15.Cu")
		(net "PWRGD_P3V3_SSD2_R")
	)
	(segment
		(start 249.659648 -225.6917)
		(end 246.526558 -225.6917)
		(width 0.15494)
		(layer "In15.Cu")
		(net "PWRGD_P3V3_SSD2_R")
	)
	(segment
		(start 142.453868 -224.52965)
		(end 141.258798 -224.52965)
		(width 0.15494)
		(layer "In15.Cu")
		(net "PWRGD_P3V3_SSD2_R")
	)
	(segment
		(start 110.681262 -205.12786)
		(end 110.676182 -205.12278)
		(width 0.15494)
		(layer "In15.Cu")
		(net "PWRGD_P3V3_SSD2_R")
	)
	(segment
		(start 333.199486 -231.72801)
		(end 333.020162 -231.72801)
		(width 0.15494)
		(layer "In15.Cu")
		(net "PWRGD_P3V3_SSD2_R")
	)
	(segment
		(start 66.481452 -202.89774)
		(end 63.120524 -206.258668)
		(width 0.15494)
		(layer "In15.Cu")
		(net "PWRGD_P3V3_SSD2_R")
	)
	(segment
		(start 332.004162 -231.72801)
		(end 327.627742 -231.72801)
		(width 0.15494)
		(layer "In15.Cu")
		(net "PWRGD_P3V3_SSD2_R")
	)
	(segment
		(start 130.864864 -224.852738)
		(end 128.445768 -224.852738)
		(width 0.15494)
		(layer "In15.Cu")
		(net "PWRGD_P3V3_SSD2_R")
	)
	(segment
		(start 96.067372 -202.89774)
		(end 66.481452 -202.89774)
		(width 0.15494)
		(layer "In15.Cu")
		(net "PWRGD_P3V3_SSD2_R")
	)
	(segment
		(start 255.112266 -225.10496)
		(end 253.862586 -226.35464)
		(width 0.15494)
		(layer "In15.Cu")
		(net "PWRGD_P3V3_SSD2_R")
	)
	(segment
		(start 323.56552 -234.115102)
		(end 322.507102 -233.056684)
		(width 0.15494)
		(layer "In15.Cu")
		(net "PWRGD_P3V3_SSD2_R")
	)
	(segment
		(start 117.300502 -211.226908)
		(end 111.201454 -205.12786)
		(width 0.15494)
		(layer "In15.Cu")
		(net "PWRGD_P3V3_SSD2_R")
	)
	(segment
		(start 208.023714 -231.515158)
		(end 192.762378 -231.515158)
		(width 0.15494)
		(layer "In15.Cu")
		(net "PWRGD_P3V3_SSD2_R")
	)
	(segment
		(start 102.461822 -205.12278)
		(end 98.032824 -203.288392)
		(width 0.15494)
		(layer "In15.Cu")
		(net "PWRGD_P3V3_SSD2_R")
	)
	(segment
		(start 340.22284 -223.985836)
		(end 340.492588 -224.255584)
		(width 0.0889)
		(layer "In15.Cu")
		(net "PWRGD_P3V3_SSD2_R")
	)
	(segment
		(start 137.259314 -224.534476)
		(end 137.21461 -224.489772)
		(width 0.15494)
		(layer "In15.Cu")
		(net "PWRGD_P3V3_SSD2_R")
	)
	(segment
		(start 242.098068 -231.12603)
		(end 214.3379 -231.12603)
		(width 0.15494)
		(layer "In15.Cu")
		(net "PWRGD_P3V3_SSD2_R")
	)
	(segment
		(start 341.20201 -230.47325)
		(end 340.313518 -231.361742)
		(width 0.15494)
		(layer "In15.Cu")
		(net "PWRGD_P3V3_SSD2_R")
	)
	(segment
		(start 340.492588 -224.255584)
		(end 340.492588 -227.1014)
		(width 0.0889)
		(layer "In15.Cu")
		(net "PWRGD_P3V3_SSD2_R")
	)
	(segment
		(start 321.558412 -233.056684)
		(end 320.304668 -231.80294)
		(width 0.15494)
		(layer "In15.Cu")
		(net "PWRGD_P3V3_SSD2_R")
	)
	(segment
		(start 156.045408 -221.624398)
		(end 145.35912 -221.624398)
		(width 0.15494)
		(layer "In15.Cu")
		(net "PWRGD_P3V3_SSD2_R")
	)
	(segment
		(start 262.071358 -226.87534)
		(end 260.189472 -226.095814)
		(width 0.15494)
		(layer "In15.Cu")
		(net "PWRGD_P3V3_SSD2_R")
	)
	(segment
		(start 192.762378 -231.515158)
		(end 189.26302 -228.0158)
		(width 0.15494)
		(layer "In15.Cu")
		(net "PWRGD_P3V3_SSD2_R")
	)
	(segment
		(start 259.198618 -225.10496)
		(end 255.112266 -225.10496)
		(width 0.15494)
		(layer "In15.Cu")
		(net "PWRGD_P3V3_SSD2_R")
	)
	(segment
		(start 333.010002 -231.71785)
		(end 332.014322 -231.71785)
		(width 0.15494)
		(layer "In15.Cu")
		(net "PWRGD_P3V3_SSD2_R")
	)
	(segment
		(start 341.20201 -227.810822)
		(end 341.20201 -230.47325)
		(width 0.15494)
		(layer "In15.Cu")
		(net "PWRGD_P3V3_SSD2_R")
	)
	(segment
		(start 333.020162 -231.72801)
		(end 333.010002 -231.71785)
		(width 0.15494)
		(layer "In15.Cu")
		(net "PWRGD_P3V3_SSD2_R")
	)
	(segment
		(start 335.962244 -232.09631)
		(end 333.567786 -232.09631)
		(width 0.15494)
		(layer "In15.Cu")
		(net "PWRGD_P3V3_SSD2_R")
	)
	(segment
		(start 339.293962 -223.586802)
		(end 339.692996 -223.985836)
		(width 0.0889)
		(layer "In15.Cu")
		(net "PWRGD_P3V3_SSD2_R")
	)
	(segment
		(start 291.822124 -232.7656)
		(end 271.22882 -232.7656)
		(width 0.15494)
		(layer "In15.Cu")
		(net "PWRGD_P3V3_SSD2_R")
	)
	(segment
		(start 189.26302 -228.0158)
		(end 162.43681 -228.0158)
		(width 0.15494)
		(layer "In15.Cu")
		(net "PWRGD_P3V3_SSD2_R")
	)
	(segment
		(start 98.032824 -203.288392)
		(end 96.067372 -202.89774)
		(width 0.15494)
		(layer "In15.Cu")
		(net "PWRGD_P3V3_SSD2_R")
	)
	(segment
		(start 141.258798 -224.52965)
		(end 141.253972 -224.534476)
		(width 0.15494)
		(layer "In15.Cu")
		(net "PWRGD_P3V3_SSD2_R")
	)
	(segment
		(start 339.692996 -223.985836)
		(end 340.22284 -223.985836)
		(width 0.0889)
		(layer "In15.Cu")
		(net "PWRGD_P3V3_SSD2_R")
	)
	(segment
		(start 340.492588 -227.1014)
		(end 341.20201 -227.810822)
		(width 0.15494)
		(layer "In15.Cu")
		(net "PWRGD_P3V3_SSD2_R")
	)
	(segment
		(start 145.35912 -221.624398)
		(end 142.453868 -224.52965)
		(width 0.15494)
		(layer "In15.Cu")
		(net "PWRGD_P3V3_SSD2_R")
	)
	(segment
		(start 137.21461 -224.489772)
		(end 131.22783 -224.489772)
		(width 0.15494)
		(layer "In15.Cu")
		(net "PWRGD_P3V3_SSD2_R")
	)
	(segment
		(start 246.526558 -225.6917)
		(end 243.411248 -228.80701)
		(width 0.15494)
		(layer "In15.Cu")
		(net "PWRGD_P3V3_SSD2_R")
	)
	(segment
		(start 399.90141 -53.051456)
		(end 400.167856 -53.051456)
		(width 0.13208)
		(layer "F.Cu")
		(net "PWRGD_P12V_SSD13")
	)
	(segment
		(start 400.167856 -52.035456)
		(end 400.167856 -53.051456)
		(width 0.13208)
		(layer "F.Cu")
		(net "PWRGD_P12V_SSD13")
	)
	(segment
		(start 398.44726 -53.644038)
		(end 398.816322 -53.644038)
		(width 0.13208)
		(layer "F.Cu")
		(net "PWRGD_P12V_SSD13")
	)
	(segment
		(start 398.816322 -53.644038)
		(end 399.437352 -53.023008)
		(width 0.13208)
		(layer "F.Cu")
		(net "PWRGD_P12V_SSD13")
	)
	(segment
		(start 399.437352 -52.587398)
		(end 399.90141 -53.051456)
		(width 0.13208)
		(layer "F.Cu")
		(net "PWRGD_P12V_SSD13")
	)
	(segment
		(start 399.437352 -53.023008)
		(end 399.437352 -52.587398)
		(width 0.13208)
		(layer "F.Cu")
		(net "PWRGD_P12V_SSD13")
	)
	(via
		(at 399.437352 -52.587398)
		(size 0.508)
		(drill 0.254)
		(layers "F.Cu" "B.Cu")
		(net "PWRGD_P12V_SSD13")
	)
	(segment
		(start 382.355598 -233.99496)
		(end 382.355598 -232.836212)
		(width 0.13208)
		(layer "F.Cu")
		(net "P3V3_SDB_VPHY")
	)
	(via
		(at 381.105918 -232.458514)
		(size 0.6604)
		(drill 0.3302)
		(layers "F.Cu" "B.Cu")
		(net "P3V3_SDB_VPHY")
	)
	(via
		(at 380.741682 -239.888522)
		(size 0.6604)
		(drill 0.3302)
		(layers "F.Cu" "B.Cu")
		(net "P3V3_SDB_VPHY")
	)
	(via
		(at 382.355598 -233.99496)
		(size 0.508)
		(drill 0.254)
		(layers "F.Cu" "B.Cu")
		(net "P3V3_SDB_VPHY")
	)
	(via
		(at 382.03759 -239.703356)
		(size 0.6604)
		(drill 0.3302)
		(layers "F.Cu" "B.Cu")
		(net "P3V3_SDB_VPHY")
	)
	(segment
		(start 381.727202 -236.40796)
		(end 381.727202 -236.940598)
		(width 0.13208)
		(layer "B.Cu")
		(net "P3V3_SDB_VPHY")
	)
	(segment
		(start 380.741682 -239.888522)
		(end 380.741682 -237.617254)
		(width 0.13208)
		(layer "B.Cu")
		(net "P3V3_SDB_VPHY")
	)
	(segment
		(start 382.43256 -236.691932)
		(end 382.43256 -239.308386)
		(width 0.13208)
		(layer "B.Cu")
		(net "P3V3_SDB_VPHY")
	)
	(segment
		(start 380.741682 -237.617254)
		(end 381.418338 -236.940598)
		(width 0.13208)
		(layer "B.Cu")
		(net "P3V3_SDB_VPHY")
	)
	(segment
		(start 381.418338 -236.940598)
		(end 381.727202 -236.940598)
		(width 0.13208)
		(layer "B.Cu")
		(net "P3V3_SDB_VPHY")
	)
	(segment
		(start 382.43256 -239.308386)
		(end 382.03759 -239.703356)
		(width 0.13208)
		(layer "B.Cu")
		(net "P3V3_SDB_VPHY")
	)
	(segment
		(start 90.018108 -305.065938)
		(end 90.018108 -305.674522)
		(width 0.13208)
		(layer "F.Cu")
		(net "PEX0_SPARE3")
	)
	(segment
		(start 90.017092 -305.064922)
		(end 90.018108 -305.065938)
		(width 0.13208)
		(layer "F.Cu")
		(net "PEX0_SPARE3")
	)
	(segment
		(start 90.0176 -304.436526)
		(end 90.0176 -305.064414)
		(width 0.13208)
		(layer "F.Cu")
		(net "PEX0_SPARE3")
	)
	(segment
		(start 66.299842 -309.199788)
		(end 66.774822 -308.724808)
		(width 0.13208)
		(layer "F.Cu")
		(net "PEX0_SPARE3")
	)
	(segment
		(start 90.0176 -305.064414)
		(end 90.017092 -305.064922)
		(width 0.13208)
		(layer "F.Cu")
		(net "PEX0_SPARE3")
	)
	(via
		(at 90.017092 -305.064922)
		(size 0.508)
		(drill 0.254)
		(layers "F.Cu" "B.Cu")
		(net "PEX0_SPARE3")
	)
	(via
		(at 84.13496 -310.149748)
		(size 0.6604)
		(drill 0.3302)
		(layers "F.Cu" "B.Cu")
		(net "PEX0_SPARE3")
	)
	(via
		(at 66.774822 -308.724808)
		(size 0.4064)
		(drill 0.2032)
		(layers "F.Cu" "B.Cu")
		(net "PEX0_SPARE3")
	)
	(segment
		(start 66.774822 -310.53024)
		(end 66.902076 -310.657494)
		(width 0.13208)
		(layer "B.Cu")
		(net "PEX0_SPARE3")
	)
	(segment
		(start 78.194916 -310.437022)
		(end 78.194916 -309.890414)
		(width 0.13208)
		(layer "B.Cu")
		(net "PEX0_SPARE3")
	)
	(segment
		(start 66.902076 -310.657494)
		(end 77.974444 -310.657494)
		(width 0.13208)
		(layer "B.Cu")
		(net "PEX0_SPARE3")
	)
	(segment
		(start 85.402166 -310.149748)
		(end 84.13496 -310.149748)
		(width 0.13208)
		(layer "B.Cu")
		(net "PEX0_SPARE3")
	)
	(segment
		(start 78.194916 -309.890414)
		(end 78.400402 -309.684928)
		(width 0.13208)
		(layer "B.Cu")
		(net "PEX0_SPARE3")
	)
	(segment
		(start 83.67014 -309.684928)
		(end 84.13496 -310.149748)
		(width 0.13208)
		(layer "B.Cu")
		(net "PEX0_SPARE3")
	)
	(segment
		(start 77.974444 -310.657494)
		(end 78.194916 -310.437022)
		(width 0.13208)
		(layer "B.Cu")
		(net "PEX0_SPARE3")
	)
	(segment
		(start 90.017092 -305.534822)
		(end 85.402166 -310.149748)
		(width 0.13208)
		(layer "B.Cu")
		(net "PEX0_SPARE3")
	)
	(segment
		(start 90.017092 -305.064922)
		(end 90.017092 -305.534822)
		(width 0.13208)
		(layer "B.Cu")
		(net "PEX0_SPARE3")
	)
	(segment
		(start 66.774822 -308.724808)
		(end 66.774822 -310.53024)
		(width 0.13208)
		(layer "B.Cu")
		(net "PEX0_SPARE3")
	)
	(segment
		(start 78.400402 -309.684928)
		(end 83.67014 -309.684928)
		(width 0.13208)
		(layer "B.Cu")
		(net "PEX0_SPARE3")
	)
	(segment
		(start 79.220568 -21.855684)
		(end 79.462376 -22.097492)
		(width 0.13208)
		(layer "F.Cu")
		(net "SMB_BIC_I2C9_MUX0_SSD2_R_SDA")
	)
	(segment
		(start 119.299736 -93.1164)
		(end 121.433336 -93.1164)
		(width 0.13208)
		(layer "F.Cu")
		(net "SMB_BIC_I2C9_MUX0_SSD2_R_SDA")
	)
	(segment
		(start 78.93558 -21.570696)
		(end 78.93558 -20.789392)
		(width 0.13208)
		(layer "F.Cu")
		(net "SMB_BIC_I2C9_MUX0_SSD2_R_SDA")
	)
	(segment
		(start 79.462376 -22.097492)
		(end 79.462376 -22.537166)
		(width 0.13208)
		(layer "F.Cu")
		(net "SMB_BIC_I2C9_MUX0_SSD2_R_SDA")
	)
	(segment
		(start 121.53519 -93.014546)
		(end 121.53519 -92.605606)
		(width 0.13208)
		(layer "F.Cu")
		(net "SMB_BIC_I2C9_MUX0_SSD2_R_SDA")
	)
	(segment
		(start 123.27509 -92.605606)
		(end 121.53519 -92.605606)
		(width 0.13208)
		(layer "F.Cu")
		(net "SMB_BIC_I2C9_MUX0_SSD2_R_SDA")
	)
	(segment
		(start 119.26062 -93.155516)
		(end 119.299736 -93.1164)
		(width 0.13208)
		(layer "F.Cu")
		(net "SMB_BIC_I2C9_MUX0_SSD2_R_SDA")
	)
	(segment
		(start 79.220568 -21.855684)
		(end 78.93558 -21.570696)
		(width 0.13208)
		(layer "F.Cu")
		(net "SMB_BIC_I2C9_MUX0_SSD2_R_SDA")
	)
	(segment
		(start 121.433336 -93.1164)
		(end 121.53519 -93.014546)
		(width 0.13208)
		(layer "F.Cu")
		(net "SMB_BIC_I2C9_MUX0_SSD2_R_SDA")
	)
	(via
		(at 119.26062 -93.155516)
		(size 0.508)
		(drill 0.254)
		(layers "F.Cu" "B.Cu")
		(net "SMB_BIC_I2C9_MUX0_SSD2_R_SDA")
	)
	(via
		(at 79.220568 -21.855684)
		(size 0.508)
		(drill 0.254)
		(layers "F.Cu" "B.Cu")
		(net "SMB_BIC_I2C9_MUX0_SSD2_R_SDA")
	)
	(segment
		(start 119.098822 -90.34526)
		(end 119.098822 -83.386422)
		(width 0.15494)
		(layer "In5.Cu")
		(net "SMB_BIC_I2C9_MUX0_SSD2_R_SDA")
	)
	(segment
		(start 77.342746 -21.2852)
		(end 78.650084 -21.2852)
		(width 0.15494)
		(layer "In5.Cu")
		(net "SMB_BIC_I2C9_MUX0_SSD2_R_SDA")
	)
	(segment
		(start 77.851 -34.137854)
		(end 77.851 -28.346146)
		(width 0.15494)
		(layer "In5.Cu")
		(net "SMB_BIC_I2C9_MUX0_SSD2_R_SDA")
	)
	(segment
		(start 118.21922 -91.224862)
		(end 119.098822 -90.34526)
		(width 0.15494)
		(layer "In5.Cu")
		(net "SMB_BIC_I2C9_MUX0_SSD2_R_SDA")
	)
	(segment
		(start 105.908856 -80.453992)
		(end 104.960928 -79.506064)
		(width 0.15494)
		(layer "In5.Cu")
		(net "SMB_BIC_I2C9_MUX0_SSD2_R_SDA")
	)
	(segment
		(start 76.2762 -22.351746)
		(end 77.342746 -21.2852)
		(width 0.15494)
		(layer "In5.Cu")
		(net "SMB_BIC_I2C9_MUX0_SSD2_R_SDA")
	)
	(segment
		(start 116.166392 -80.453992)
		(end 105.908856 -80.453992)
		(width 0.15494)
		(layer "In5.Cu")
		(net "SMB_BIC_I2C9_MUX0_SSD2_R_SDA")
	)
	(segment
		(start 119.26062 -92.859098)
		(end 118.21922 -91.817698)
		(width 0.15494)
		(layer "In5.Cu")
		(net "SMB_BIC_I2C9_MUX0_SSD2_R_SDA")
	)
	(segment
		(start 89.76614 -77.067156)
		(end 89.76614 -46.052994)
		(width 0.15494)
		(layer "In5.Cu")
		(net "SMB_BIC_I2C9_MUX0_SSD2_R_SDA")
	)
	(segment
		(start 119.098822 -83.386422)
		(end 116.166392 -80.453992)
		(width 0.15494)
		(layer "In5.Cu")
		(net "SMB_BIC_I2C9_MUX0_SSD2_R_SDA")
	)
	(segment
		(start 89.76614 -46.052994)
		(end 77.851 -34.137854)
		(width 0.15494)
		(layer "In5.Cu")
		(net "SMB_BIC_I2C9_MUX0_SSD2_R_SDA")
	)
	(segment
		(start 78.650084 -21.2852)
		(end 79.220568 -21.855684)
		(width 0.15494)
		(layer "In5.Cu")
		(net "SMB_BIC_I2C9_MUX0_SSD2_R_SDA")
	)
	(segment
		(start 77.851 -28.346146)
		(end 76.2762 -26.771346)
		(width 0.15494)
		(layer "In5.Cu")
		(net "SMB_BIC_I2C9_MUX0_SSD2_R_SDA")
	)
	(segment
		(start 76.2762 -26.771346)
		(end 76.2762 -22.351746)
		(width 0.15494)
		(layer "In5.Cu")
		(net "SMB_BIC_I2C9_MUX0_SSD2_R_SDA")
	)
	(segment
		(start 104.960928 -79.506064)
		(end 92.205048 -79.506064)
		(width 0.15494)
		(layer "In5.Cu")
		(net "SMB_BIC_I2C9_MUX0_SSD2_R_SDA")
	)
	(segment
		(start 92.205048 -79.506064)
		(end 89.76614 -77.067156)
		(width 0.15494)
		(layer "In5.Cu")
		(net "SMB_BIC_I2C9_MUX0_SSD2_R_SDA")
	)
	(segment
		(start 118.21922 -91.817698)
		(end 118.21922 -91.224862)
		(width 0.15494)
		(layer "In5.Cu")
		(net "SMB_BIC_I2C9_MUX0_SSD2_R_SDA")
	)
	(segment
		(start 119.26062 -93.155516)
		(end 119.26062 -92.859098)
		(width 0.15494)
		(layer "In5.Cu")
		(net "SMB_BIC_I2C9_MUX0_SSD2_R_SDA")
	)
	(segment
		(start 342.093804 -227.186998)
		(end 342.490044 -227.583238)
		(width 0.13208)
		(layer "F.Cu")
		(net "SSD1_PWR_EN")
	)
	(segment
		(start 342.138 -230.886)
		(end 341.503 -231.521)
		(width 0.13208)
		(layer "F.Cu")
		(net "SSD1_PWR_EN")
	)
	(segment
		(start 341.503 -231.521)
		(end 340.995 -232.029)
		(width 0.13208)
		(layer "F.Cu")
		(net "SSD1_PWR_EN")
	)
	(segment
		(start 342.490044 -228.28377)
		(end 342.287352 -228.486462)
		(width 0.13208)
		(layer "F.Cu")
		(net "SSD1_PWR_EN")
	)
	(segment
		(start 342.490044 -227.583238)
		(end 342.490044 -228.28377)
		(width 0.13208)
		(layer "F.Cu")
		(net "SSD1_PWR_EN")
	)
	(segment
		(start 342.138 -230.505)
		(end 342.138 -230.886)
		(width 0.13208)
		(layer "F.Cu")
		(net "SSD1_PWR_EN")
	)
	(segment
		(start 342.287352 -230.355648)
		(end 342.138 -230.505)
		(width 0.13208)
		(layer "F.Cu")
		(net "SSD1_PWR_EN")
	)
	(segment
		(start 340.995 -232.029)
		(end 340.995 -233.66095)
		(width 0.13208)
		(layer "F.Cu")
		(net "SSD1_PWR_EN")
	)
	(segment
		(start 342.287352 -228.486462)
		(end 342.287352 -230.355648)
		(width 0.13208)
		(layer "F.Cu")
		(net "SSD1_PWR_EN")
	)
	(via
		(at 341.503 -231.521)
		(size 0.762)
		(drill 0.381)
		(layers "F.Cu" "B.Cu")
		(net "SSD1_PWR_EN")
	)
	(segment
		(start 419.589458 -234.744006)
		(end 419.589458 -230.956866)
		(width 0.13208)
		(layer "F.Cu")
		(net "UART_PEX3_SDB_R_RX")
	)
	(segment
		(start 442.4172 -233.1466)
		(end 441.59424 -232.32364)
		(width 0.13208)
		(layer "F.Cu")
		(net "UART_PEX3_SDB_R_RX")
	)
	(segment
		(start 419.15207 -235.181394)
		(end 419.589458 -234.744006)
		(width 0.13208)
		(layer "F.Cu")
		(net "UART_PEX3_SDB_R_RX")
	)
	(segment
		(start 441.59424 -232.32364)
		(end 441.59424 -229.09022)
		(width 0.13208)
		(layer "F.Cu")
		(net "UART_PEX3_SDB_R_RX")
	)
	(segment
		(start 441.59424 -229.09022)
		(end 442.775594 -227.908866)
		(width 0.13208)
		(layer "F.Cu")
		(net "UART_PEX3_SDB_R_RX")
	)
	(segment
		(start 442.775594 -227.908866)
		(end 444.522098 -227.908866)
		(width 0.13208)
		(layer "F.Cu")
		(net "UART_PEX3_SDB_R_RX")
	)
	(via
		(at 385.191 -240.665)
		(size 0.508)
		(drill 0.254)
		(layers "F.Cu" "B.Cu")
		(net "UART_PEX3_SDB_R_RX")
	)
	(via
		(at 419.15207 -235.181394)
		(size 0.508)
		(drill 0.254)
		(layers "F.Cu" "B.Cu")
		(net "UART_PEX3_SDB_R_RX")
	)
	(via
		(at 442.4172 -233.1466)
		(size 0.508)
		(drill 0.254)
		(layers "F.Cu" "B.Cu")
		(net "UART_PEX3_SDB_R_RX")
	)
	(segment
		(start 385.84505 -240.01095)
		(end 385.84505 -239.522)
		(width 0.13208)
		(layer "B.Cu")
		(net "UART_PEX3_SDB_R_RX")
	)
	(segment
		(start 386.192014 -242.205002)
		(end 386.192014 -241.951256)
		(width 0.13208)
		(layer "B.Cu")
		(net "UART_PEX3_SDB_R_RX")
	)
	(segment
		(start 385.996434 -241.479324)
		(end 385.990084 -241.464084)
		(width 0.13208)
		(layer "B.Cu")
		(net "UART_PEX3_SDB_R_RX")
	)
	(segment
		(start 386.185156 -241.935)
		(end 385.996434 -241.479324)
		(width 0.13208)
		(layer "B.Cu")
		(net "UART_PEX3_SDB_R_RX")
	)
	(segment
		(start 386.192014 -241.951256)
		(end 386.185156 -241.935)
		(width 0.13208)
		(layer "B.Cu")
		(net "UART_PEX3_SDB_R_RX")
	)
	(segment
		(start 385.990084 -241.464084)
		(end 385.191 -240.665)
		(width 0.13208)
		(layer "B.Cu")
		(net "UART_PEX3_SDB_R_RX")
	)
	(segment
		(start 385.191 -240.665)
		(end 385.84505 -240.01095)
		(width 0.13208)
		(layer "B.Cu")
		(net "UART_PEX3_SDB_R_RX")
	)
	(segment
		(start 415.7472 -238.7346)
		(end 388.934706 -238.7346)
		(width 0.15494)
		(layer "In13.Cu")
		(net "UART_PEX3_SDB_R_RX")
	)
	(segment
		(start 419.15207 -236.77753)
		(end 418.2872 -237.6424)
		(width 0.15494)
		(layer "In13.Cu")
		(net "UART_PEX3_SDB_R_RX")
	)
	(segment
		(start 418.2872 -237.6424)
		(end 416.8394 -237.6424)
		(width 0.15494)
		(layer "In13.Cu")
		(net "UART_PEX3_SDB_R_RX")
	)
	(segment
		(start 385.98094 -239.11306)
		(end 385.191 -239.903)
		(width 0.15494)
		(layer "In13.Cu")
		(net "UART_PEX3_SDB_R_RX")
	)
	(segment
		(start 419.15207 -235.181394)
		(end 419.15207 -236.77753)
		(width 0.15494)
		(layer "In13.Cu")
		(net "UART_PEX3_SDB_R_RX")
	)
	(segment
		(start 388.934706 -238.7346)
		(end 388.556246 -239.11306)
		(width 0.15494)
		(layer "In13.Cu")
		(net "UART_PEX3_SDB_R_RX")
	)
	(segment
		(start 416.8394 -237.6424)
		(end 415.7472 -238.7346)
		(width 0.15494)
		(layer "In13.Cu")
		(net "UART_PEX3_SDB_R_RX")
	)
	(segment
		(start 388.556246 -239.11306)
		(end 385.98094 -239.11306)
		(width 0.15494)
		(layer "In13.Cu")
		(net "UART_PEX3_SDB_R_RX")
	)
	(segment
		(start 385.191 -239.903)
		(end 385.191 -240.665)
		(width 0.15494)
		(layer "In13.Cu")
		(net "UART_PEX3_SDB_R_RX")
	)
	(segment
		(start 442.4172 -233.1466)
		(end 441.285884 -232.015284)
		(width 0.15494)
		(layer "In15.Cu")
		(net "UART_PEX3_SDB_R_RX")
	)
	(segment
		(start 441.285884 -232.015284)
		(end 422.31818 -232.015284)
		(width 0.15494)
		(layer "In15.Cu")
		(net "UART_PEX3_SDB_R_RX")
	)
	(segment
		(start 422.31818 -232.015284)
		(end 419.15207 -235.181394)
		(width 0.15494)
		(layer "In15.Cu")
		(net "UART_PEX3_SDB_R_RX")
	)
	(segment
		(start 377.374404 -235.311188)
		(end 378.880624 -235.311188)
		(width 0.13208)
		(layer "F.Cu")
		(net "FT4232_SDB_EEPROM_CS")
	)
	(segment
		(start 377.145296 -235.540296)
		(end 377.374404 -235.311188)
		(width 0.13208)
		(layer "F.Cu")
		(net "FT4232_SDB_EEPROM_CS")
	)
	(via
		(at 377.145296 -235.540296)
		(size 0.508)
		(drill 0.254)
		(layers "F.Cu" "B.Cu")
		(net "FT4232_SDB_EEPROM_CS")
	)
	(segment
		(start 375.98858 -235.540296)
		(end 377.145296 -235.540296)
		(width 0.13208)
		(layer "B.Cu")
		(net "FT4232_SDB_EEPROM_CS")
	)
	(segment
		(start 89.39276 -309.85333)
		(end 89.914222 -309.331868)
		(width 0.13208)
		(layer "F.Cu")
		(net "PEX0_SPARE2")
	)
	(segment
		(start 89.019634 -310.226456)
		(end 89.39276 -309.85333)
		(width 0.13208)
		(layer "F.Cu")
		(net "PEX0_SPARE2")
	)
	(segment
		(start 89.914222 -309.331868)
		(end 89.914222 -309.324756)
		(width 0.13208)
		(layer "F.Cu")
		(net "PEX0_SPARE2")
	)
	(segment
		(start 88.778842 -310.226456)
		(end 89.019634 -310.226456)
		(width 0.13208)
		(layer "F.Cu")
		(net "PEX0_SPARE2")
	)
	(via
		(at 89.39276 -309.85333)
		(size 0.508)
		(drill 0.254)
		(layers "F.Cu" "B.Cu")
		(net "PEX0_SPARE2")
	)
	(via
		(at 61.549788 -309.199788)
		(size 0.4064)
		(drill 0.2032)
		(layers "F.Cu" "B.Cu")
		(net "PEX0_SPARE2")
	)
	(via
		(at 85.822536 -313.423554)
		(size 0.6604)
		(drill 0.3302)
		(layers "F.Cu" "B.Cu")
		(net "PEX0_SPARE2")
	)
	(segment
		(start 62.304168 -309.199788)
		(end 62.970156 -309.865776)
		(width 0.13208)
		(layer "B.Cu")
		(net "PEX0_SPARE2")
	)
	(segment
		(start 62.970156 -309.865776)
		(end 62.970156 -314.330334)
		(width 0.13208)
		(layer "B.Cu")
		(net "PEX0_SPARE2")
	)
	(segment
		(start 61.549788 -309.199788)
		(end 62.304168 -309.199788)
		(width 0.13208)
		(layer "B.Cu")
		(net "PEX0_SPARE2")
	)
	(segment
		(start 85.822536 -313.423554)
		(end 89.39276 -309.85333)
		(width 0.13208)
		(layer "B.Cu")
		(net "PEX0_SPARE2")
	)
	(segment
		(start 62.970156 -314.330334)
		(end 63.097156 -314.457334)
		(width 0.13208)
		(layer "B.Cu")
		(net "PEX0_SPARE2")
	)
	(segment
		(start 63.097156 -314.457334)
		(end 84.788756 -314.457334)
		(width 0.13208)
		(layer "B.Cu")
		(net "PEX0_SPARE2")
	)
	(segment
		(start 84.788756 -314.457334)
		(end 85.822536 -313.423554)
		(width 0.13208)
		(layer "B.Cu")
		(net "PEX0_SPARE2")
	)
	(segment
		(start 2.906268 -33.710626)
		(end 2.906268 -34.348928)
		(width 0.13208)
		(layer "F.Cu")
		(net "SMB_BIC_I2C9_MUX0_SSD0_R_SCL")
	)
	(segment
		(start 2.873756 -32.724344)
		(end 2.873756 -33.678114)
		(width 0.13208)
		(layer "F.Cu")
		(net "SMB_BIC_I2C9_MUX0_SSD0_R_SCL")
	)
	(segment
		(start 2.873756 -33.678114)
		(end 2.906268 -33.710626)
		(width 0.13208)
		(layer "F.Cu")
		(net "SMB_BIC_I2C9_MUX0_SSD0_R_SCL")
	)
	(segment
		(start 122.357896 -96.034606)
		(end 123.27509 -96.034606)
		(width 0.13208)
		(layer "F.Cu")
		(net "SMB_BIC_I2C9_MUX0_SSD0_R_SCL")
	)
	(segment
		(start 121.53519 -96.034606)
		(end 122.357896 -96.034606)
		(width 0.13208)
		(layer "F.Cu")
		(net "SMB_BIC_I2C9_MUX0_SSD0_R_SCL")
	)
	(segment
		(start 2.906268 -34.348928)
		(end 3.047746 -34.490406)
		(width 0.13208)
		(layer "F.Cu")
		(net "SMB_BIC_I2C9_MUX0_SSD0_R_SCL")
	)
	(via
		(at 32.037274 -91.315794)
		(size 0.508)
		(drill 0.254)
		(layers "F.Cu" "B.Cu")
		(net "SMB_BIC_I2C9_MUX0_SSD0_R_SCL")
	)
	(via
		(at 122.357896 -96.034606)
		(size 0.508)
		(drill 0.254)
		(layers "F.Cu" "B.Cu")
		(net "SMB_BIC_I2C9_MUX0_SSD0_R_SCL")
	)
	(via
		(at 2.906268 -33.710626)
		(size 0.508)
		(drill 0.254)
		(layers "F.Cu" "B.Cu")
		(net "SMB_BIC_I2C9_MUX0_SSD0_R_SCL")
	)
	(segment
		(start 17.018508 -28.906724)
		(end 15.944088 -28.906724)
		(width 0.15494)
		(layer "In5.Cu")
		(net "SMB_BIC_I2C9_MUX0_SSD0_R_SCL")
	)
	(segment
		(start 18.442432 -27.4828)
		(end 17.018508 -28.906724)
		(width 0.15494)
		(layer "In5.Cu")
		(net "SMB_BIC_I2C9_MUX0_SSD0_R_SCL")
	)
	(segment
		(start 12.685014 -33.40735)
		(end 10.158476 -35.933888)
		(width 0.15494)
		(layer "In5.Cu")
		(net "SMB_BIC_I2C9_MUX0_SSD0_R_SCL")
	)
	(segment
		(start 36.22294 -87.94496)
		(end 36.22294 -46.875954)
		(width 0.15494)
		(layer "In5.Cu")
		(net "SMB_BIC_I2C9_MUX0_SSD0_R_SCL")
	)
	(segment
		(start 15.944088 -28.906724)
		(end 12.685014 -32.165798)
		(width 0.15494)
		(layer "In5.Cu")
		(net "SMB_BIC_I2C9_MUX0_SSD0_R_SCL")
	)
	(segment
		(start 32.852106 -91.315794)
		(end 36.22294 -87.94496)
		(width 0.15494)
		(layer "In5.Cu")
		(net "SMB_BIC_I2C9_MUX0_SSD0_R_SCL")
	)
	(segment
		(start 32.037274 -91.315794)
		(end 32.852106 -91.315794)
		(width 0.15494)
		(layer "In5.Cu")
		(net "SMB_BIC_I2C9_MUX0_SSD0_R_SCL")
	)
	(segment
		(start 36.22294 -46.875954)
		(end 23.325836 -33.97885)
		(width 0.15494)
		(layer "In5.Cu")
		(net "SMB_BIC_I2C9_MUX0_SSD0_R_SCL")
	)
	(segment
		(start 21.55444 -27.4828)
		(end 18.442432 -27.4828)
		(width 0.15494)
		(layer "In5.Cu")
		(net "SMB_BIC_I2C9_MUX0_SSD0_R_SCL")
	)
	(segment
		(start 12.685014 -32.165798)
		(end 12.685014 -33.40735)
		(width 0.15494)
		(layer "In5.Cu")
		(net "SMB_BIC_I2C9_MUX0_SSD0_R_SCL")
	)
	(segment
		(start 23.325836 -29.254196)
		(end 21.55444 -27.4828)
		(width 0.15494)
		(layer "In5.Cu")
		(net "SMB_BIC_I2C9_MUX0_SSD0_R_SCL")
	)
	(segment
		(start 10.158476 -35.933888)
		(end 5.950458 -35.933888)
		(width 0.15494)
		(layer "In5.Cu")
		(net "SMB_BIC_I2C9_MUX0_SSD0_R_SCL")
	)
	(segment
		(start 2.9337 -33.710626)
		(end 2.906268 -33.710626)
		(width 0.15494)
		(layer "In5.Cu")
		(net "SMB_BIC_I2C9_MUX0_SSD0_R_SCL")
	)
	(segment
		(start 23.325836 -33.97885)
		(end 23.325836 -29.254196)
		(width 0.15494)
		(layer "In5.Cu")
		(net "SMB_BIC_I2C9_MUX0_SSD0_R_SCL")
	)
	(segment
		(start 5.950458 -35.933888)
		(end 5.243576 -35.227006)
		(width 0.15494)
		(layer "In5.Cu")
		(net "SMB_BIC_I2C9_MUX0_SSD0_R_SCL")
	)
	(segment
		(start 4.45008 -35.227006)
		(end 2.9337 -33.710626)
		(width 0.15494)
		(layer "In5.Cu")
		(net "SMB_BIC_I2C9_MUX0_SSD0_R_SCL")
	)
	(segment
		(start 5.243576 -35.227006)
		(end 4.45008 -35.227006)
		(width 0.15494)
		(layer "In5.Cu")
		(net "SMB_BIC_I2C9_MUX0_SSD0_R_SCL")
	)
	(segment
		(start 121.874026 -95.550736)
		(end 122.357896 -96.034606)
		(width 0.15494)
		(layer "In15.Cu")
		(net "SMB_BIC_I2C9_MUX0_SSD0_R_SCL")
	)
	(segment
		(start 101.161088 -91.50858)
		(end 104.384348 -94.73184)
		(width 0.15494)
		(layer "In15.Cu")
		(net "SMB_BIC_I2C9_MUX0_SSD0_R_SCL")
	)
	(segment
		(start 77.031342 -94.872556)
		(end 85.142324 -94.872556)
		(width 0.15494)
		(layer "In15.Cu")
		(net "SMB_BIC_I2C9_MUX0_SSD0_R_SCL")
	)
	(segment
		(start 88.5063 -91.50858)
		(end 101.161088 -91.50858)
		(width 0.15494)
		(layer "In15.Cu")
		(net "SMB_BIC_I2C9_MUX0_SSD0_R_SCL")
	)
	(segment
		(start 85.142324 -94.872556)
		(end 88.5063 -91.50858)
		(width 0.15494)
		(layer "In15.Cu")
		(net "SMB_BIC_I2C9_MUX0_SSD0_R_SCL")
	)
	(segment
		(start 108.611924 -94.73184)
		(end 111.570008 -97.689924)
		(width 0.15494)
		(layer "In15.Cu")
		(net "SMB_BIC_I2C9_MUX0_SSD0_R_SCL")
	)
	(segment
		(start 104.384348 -94.73184)
		(end 108.611924 -94.73184)
		(width 0.15494)
		(layer "In15.Cu")
		(net "SMB_BIC_I2C9_MUX0_SSD0_R_SCL")
	)
	(segment
		(start 114.570256 -97.689924)
		(end 116.709444 -95.550736)
		(width 0.15494)
		(layer "In15.Cu")
		(net "SMB_BIC_I2C9_MUX0_SSD0_R_SCL")
	)
	(segment
		(start 58.44921 -91.783408)
		(end 73.942194 -91.783408)
		(width 0.15494)
		(layer "In15.Cu")
		(net "SMB_BIC_I2C9_MUX0_SSD0_R_SCL")
	)
	(segment
		(start 116.709444 -95.550736)
		(end 121.874026 -95.550736)
		(width 0.15494)
		(layer "In15.Cu")
		(net "SMB_BIC_I2C9_MUX0_SSD0_R_SCL")
	)
	(segment
		(start 111.570008 -97.689924)
		(end 114.570256 -97.689924)
		(width 0.15494)
		(layer "In15.Cu")
		(net "SMB_BIC_I2C9_MUX0_SSD0_R_SCL")
	)
	(segment
		(start 32.037274 -91.315794)
		(end 57.981596 -91.315794)
		(width 0.15494)
		(layer "In15.Cu")
		(net "SMB_BIC_I2C9_MUX0_SSD0_R_SCL")
	)
	(segment
		(start 73.942194 -91.783408)
		(end 77.031342 -94.872556)
		(width 0.15494)
		(layer "In15.Cu")
		(net "SMB_BIC_I2C9_MUX0_SSD0_R_SCL")
	)
	(segment
		(start 57.981596 -91.315794)
		(end 58.44921 -91.783408)
		(width 0.15494)
		(layer "In15.Cu")
		(net "SMB_BIC_I2C9_MUX0_SSD0_R_SCL")
	)
	(segment
		(start 27.004518 -64.886332)
		(end 27.873706 -65.75552)
		(width 0.13208)
		(layer "F.Cu")
		(net "PWRGD_P12V_SSD1_R")
	)
	(segment
		(start 27.873706 -65.75552)
		(end 40.728646 -65.75552)
		(width 0.13208)
		(layer "F.Cu")
		(net "PWRGD_P12V_SSD1_R")
	)
	(segment
		(start 342.093804 -223.187006)
		(end 341.694008 -223.586802)
		(width 0.13208)
		(layer "F.Cu")
		(net "PWRGD_P12V_SSD1_R")
	)
	(segment
		(start 27.63647 -61.487812)
		(end 27.004518 -62.119764)
		(width 0.13208)
		(layer "F.Cu")
		(net "PWRGD_P12V_SSD1_R")
	)
	(segment
		(start 29.483558 -61.487812)
		(end 27.63647 -61.487812)
		(width 0.13208)
		(layer "F.Cu")
		(net "PWRGD_P12V_SSD1_R")
	)
	(segment
		(start 27.004518 -62.119764)
		(end 27.004518 -64.886332)
		(width 0.13208)
		(layer "F.Cu")
		(net "PWRGD_P12V_SSD1_R")
	)
	(segment
		(start 52.667916 -53.051456)
		(end 53.323236 -53.051456)
		(width 0.13208)
		(layer "F.Cu")
		(net "PWRGD_P12V_SSD1_R")
	)
	(via
		(at 53.323236 -53.051456)
		(size 0.508)
		(drill 0.254)
		(layers "F.Cu" "B.Cu")
		(net "PWRGD_P12V_SSD1_R")
	)
	(via
		(at 40.728646 -65.75552)
		(size 0.508)
		(drill 0.254)
		(layers "F.Cu" "B.Cu")
		(net "PWRGD_P12V_SSD1_R")
	)
	(via
		(at 61.265816 -206.969614)
		(size 0.508)
		(drill 0.254)
		(layers "F.Cu" "B.Cu")
		(net "PWRGD_P12V_SSD1_R")
	)
	(via
		(at 341.694008 -223.586802)
		(size 0.4572)
		(drill 0.254)
		(layers "F.Cu" "B.Cu")
		(net "PWRGD_P12V_SSD1_R")
	)
	(segment
		(start 57.404508 -107.511596)
		(end 58.263028 -108.370116)
		(width 0.15494)
		(layer "In5.Cu")
		(net "PWRGD_P12V_SSD1_R")
	)
	(segment
		(start 55.884064 -65.807844)
		(end 56.9468 -66.87058)
		(width 0.15494)
		(layer "In5.Cu")
		(net "PWRGD_P12V_SSD1_R")
	)
	(segment
		(start 51.367436 -64.617092)
		(end 51.743864 -64.240664)
		(width 0.15494)
		(layer "In5.Cu")
		(net "PWRGD_P12V_SSD1_R")
	)
	(segment
		(start 57.3532 -154.86253)
		(end 57.3532 -180.543454)
		(width 0.15494)
		(layer "In5.Cu")
		(net "PWRGD_P12V_SSD1_R")
	)
	(segment
		(start 45.314362 -64.617092)
		(end 51.367436 -64.617092)
		(width 0.15494)
		(layer "In5.Cu")
		(net "PWRGD_P12V_SSD1_R")
	)
	(segment
		(start 51.743864 -57.983628)
		(end 51.261264 -57.501028)
		(width 0.15494)
		(layer "In5.Cu")
		(net "PWRGD_P12V_SSD1_R")
	)
	(segment
		(start 51.261264 -55.113428)
		(end 53.323236 -53.051456)
		(width 0.15494)
		(layer "In5.Cu")
		(net "PWRGD_P12V_SSD1_R")
	)
	(segment
		(start 51.261264 -57.501028)
		(end 51.261264 -55.113428)
		(width 0.15494)
		(layer "In5.Cu")
		(net "PWRGD_P12V_SSD1_R")
	)
	(segment
		(start 58.263028 -153.952702)
		(end 57.3532 -154.86253)
		(width 0.15494)
		(layer "In5.Cu")
		(net "PWRGD_P12V_SSD1_R")
	)
	(segment
		(start 54.32806 -65.807844)
		(end 55.884064 -65.807844)
		(width 0.15494)
		(layer "In5.Cu")
		(net "PWRGD_P12V_SSD1_R")
	)
	(segment
		(start 52.703984 -57.716166)
		(end 52.992274 -58.004456)
		(width 0.15494)
		(layer "In5.Cu")
		(net "PWRGD_P12V_SSD1_R")
	)
	(segment
		(start 53.34508 -55.818024)
		(end 53.131466 -55.818024)
		(width 0.15494)
		(layer "In5.Cu")
		(net "PWRGD_P12V_SSD1_R")
	)
	(segment
		(start 58.263028 -108.370116)
		(end 58.263028 -153.952702)
		(width 0.15494)
		(layer "In5.Cu")
		(net "PWRGD_P12V_SSD1_R")
	)
	(segment
		(start 54.131972 -55.031132)
		(end 53.34508 -55.818024)
		(width 0.15494)
		(layer "In5.Cu")
		(net "PWRGD_P12V_SSD1_R")
	)
	(segment
		(start 53.131466 -55.818024)
		(end 52.703984 -56.245506)
		(width 0.15494)
		(layer "In5.Cu")
		(net "PWRGD_P12V_SSD1_R")
	)
	(segment
		(start 56.9468 -96.1898)
		(end 57.404508 -96.647508)
		(width 0.15494)
		(layer "In5.Cu")
		(net "PWRGD_P12V_SSD1_R")
	)
	(segment
		(start 57.3532 -180.543454)
		(end 61.265816 -184.45607)
		(width 0.15494)
		(layer "In5.Cu")
		(net "PWRGD_P12V_SSD1_R")
	)
	(segment
		(start 61.265816 -184.45607)
		(end 61.265816 -206.969614)
		(width 0.15494)
		(layer "In5.Cu")
		(net "PWRGD_P12V_SSD1_R")
	)
	(segment
		(start 40.728646 -65.75552)
		(end 44.175934 -65.75552)
		(width 0.15494)
		(layer "In5.Cu")
		(net "PWRGD_P12V_SSD1_R")
	)
	(segment
		(start 53.323236 -53.051456)
		(end 54.131972 -53.860192)
		(width 0.15494)
		(layer "In5.Cu")
		(net "PWRGD_P12V_SSD1_R")
	)
	(segment
		(start 52.992274 -58.004456)
		(end 52.992274 -64.472058)
		(width 0.15494)
		(layer "In5.Cu")
		(net "PWRGD_P12V_SSD1_R")
	)
	(segment
		(start 57.404508 -96.647508)
		(end 57.404508 -107.511596)
		(width 0.15494)
		(layer "In5.Cu")
		(net "PWRGD_P12V_SSD1_R")
	)
	(segment
		(start 54.131972 -53.860192)
		(end 54.131972 -55.031132)
		(width 0.15494)
		(layer "In5.Cu")
		(net "PWRGD_P12V_SSD1_R")
	)
	(segment
		(start 52.703984 -56.245506)
		(end 52.703984 -57.716166)
		(width 0.15494)
		(layer "In5.Cu")
		(net "PWRGD_P12V_SSD1_R")
	)
	(segment
		(start 52.992274 -64.472058)
		(end 54.32806 -65.807844)
		(width 0.15494)
		(layer "In5.Cu")
		(net "PWRGD_P12V_SSD1_R")
	)
	(segment
		(start 51.743864 -64.240664)
		(end 51.743864 -57.983628)
		(width 0.15494)
		(layer "In5.Cu")
		(net "PWRGD_P12V_SSD1_R")
	)
	(segment
		(start 56.9468 -66.87058)
		(end 56.9468 -96.1898)
		(width 0.15494)
		(layer "In5.Cu")
		(net "PWRGD_P12V_SSD1_R")
	)
	(segment
		(start 44.175934 -65.75552)
		(end 45.314362 -64.617092)
		(width 0.15494)
		(layer "In5.Cu")
		(net "PWRGD_P12V_SSD1_R")
	)
	(segment
		(start 142.070074 -217.135456)
		(end 142.039594 -217.165936)
		(width 0.15494)
		(layer "In13.Cu")
		(net "PWRGD_P12V_SSD1_R")
	)
	(segment
		(start 342.4936 -227.295456)
		(end 341.694008 -228.095048)
		(width 0.15494)
		(layer "In13.Cu")
		(net "PWRGD_P12V_SSD1_R")
	)
	(segment
		(start 236.044486 -214.5665)
		(end 236.044486 -214.327486)
		(width 0.15494)
		(layer "In13.Cu")
		(net "PWRGD_P12V_SSD1_R")
	)
	(segment
		(start 220.813884 -215.15197)
		(end 220.813884 -216.988136)
		(width 0.15494)
		(layer "In13.Cu")
		(net "PWRGD_P12V_SSD1_R")
	)
	(segment
		(start 326.042782 -234.498134)
		(end 325.535036 -235.00588)
		(width 0.15494)
		(layer "In13.Cu")
		(net "PWRGD_P12V_SSD1_R")
	)
	(segment
		(start 250.034552 -226.947476)
		(end 249.486928 -226.399852)
		(width 0.15494)
		(layer "In13.Cu")
		(net "PWRGD_P12V_SSD1_R")
	)
	(segment
		(start 116.40439 -208.42986)
		(end 116.278406 -208.42986)
		(width 0.15494)
		(layer "In13.Cu")
		(net "PWRGD_P12V_SSD1_R")
	)
	(segment
		(start 234.5436 -212.1662)
		(end 233.8578 -211.4804)
		(width 0.15494)
		(layer "In13.Cu")
		(net "PWRGD_P12V_SSD1_R")
	)
	(segment
		(start 277.625302 -234.7214)
		(end 272.663666 -229.759764)
		(width 0.15494)
		(layer "In13.Cu")
		(net "PWRGD_P12V_SSD1_R")
	)
	(segment
		(start 150.932896 -214.95766)
		(end 150.803356 -214.95766)
		(width 0.15494)
		(layer "In13.Cu")
		(net "PWRGD_P12V_SSD1_R")
	)
	(segment
		(start 225.475292 -212.339682)
		(end 224.68967 -213.125304)
		(width 0.15494)
		(layer "In13.Cu")
		(net "PWRGD_P12V_SSD1_R")
	)
	(segment
		(start 241.18443 -221.553024)
		(end 240.843308 -221.211902)
		(width 0.15494)
		(layer "In13.Cu")
		(net "PWRGD_P12V_SSD1_R")
	)
	(segment
		(start 325.535036 -235.00588)
		(end 323.264276 -235.00588)
		(width 0.15494)
		(layer "In13.Cu")
		(net "PWRGD_P12V_SSD1_R")
	)
	(segment
		(start 126.032514 -217.135456)
		(end 124.273818 -215.37676)
		(width 0.15494)
		(layer "In13.Cu")
		(net "PWRGD_P12V_SSD1_R")
	)
	(segment
		(start 116.278406 -208.42986)
		(end 116.265706 -208.41716)
		(width 0.15494)
		(layer "In13.Cu")
		(net "PWRGD_P12V_SSD1_R")
	)
	(segment
		(start 148.37664 -217.135456)
		(end 142.070074 -217.135456)
		(width 0.15494)
		(layer "In13.Cu")
		(net "PWRGD_P12V_SSD1_R")
	)
	(segment
		(start 339.716618 -232.214928)
		(end 335.359248 -232.214928)
		(width 0.15494)
		(layer "In13.Cu")
		(net "PWRGD_P12V_SSD1_R")
	)
	(segment
		(start 141.310614 -217.135456)
		(end 126.032514 -217.135456)
		(width 0.15494)
		(layer "In13.Cu")
		(net "PWRGD_P12V_SSD1_R")
	)
	(segment
		(start 259.484368 -229.759764)
		(end 256.67208 -226.947476)
		(width 0.15494)
		(layer "In13.Cu")
		(net "PWRGD_P12V_SSD1_R")
	)
	(segment
		(start 240.843308 -221.211902)
		(end 240.843308 -219.365322)
		(width 0.15494)
		(layer "In13.Cu")
		(net "PWRGD_P12V_SSD1_R")
	)
	(segment
		(start 249.486928 -226.399852)
		(end 247.22709 -226.399852)
		(width 0.15494)
		(layer "In13.Cu")
		(net "PWRGD_P12V_SSD1_R")
	)
	(segment
		(start 341.694008 -223.586802)
		(end 342.4936 -224.386394)
		(width 0.15494)
		(layer "In13.Cu")
		(net "PWRGD_P12V_SSD1_R")
	)
	(segment
		(start 341.694008 -228.095048)
		(end 341.694008 -230.237538)
		(width 0.15494)
		(layer "In13.Cu")
		(net "PWRGD_P12V_SSD1_R")
	)
	(segment
		(start 205.74254 -214.886794)
		(end 151.003762 -214.886794)
		(width 0.15494)
		(layer "In13.Cu")
		(net "PWRGD_P12V_SSD1_R")
	)
	(segment
		(start 99.034346 -208.8896)
		(end 76.865734 -208.8896)
		(width 0.15494)
		(layer "In13.Cu")
		(net "PWRGD_P12V_SSD1_R")
	)
	(segment
		(start 225.922332 -211.3788)
		(end 225.795332 -211.5058)
		(width 0.15494)
		(layer "In13.Cu")
		(net "PWRGD_P12V_SSD1_R")
	)
	(segment
		(start 211.124546 -217.9066)
		(end 210.29676 -217.078814)
		(width 0.15494)
		(layer "In13.Cu")
		(net "PWRGD_P12V_SSD1_R")
	)
	(segment
		(start 272.663666 -229.759764)
		(end 259.484368 -229.759764)
		(width 0.15494)
		(layer "In13.Cu")
		(net "PWRGD_P12V_SSD1_R")
	)
	(segment
		(start 150.803356 -214.95766)
		(end 150.724616 -215.0364)
		(width 0.15494)
		(layer "In13.Cu")
		(net "PWRGD_P12V_SSD1_R")
	)
	(segment
		(start 74.945748 -206.969614)
		(end 61.265816 -206.969614)
		(width 0.15494)
		(layer "In13.Cu")
		(net "PWRGD_P12V_SSD1_R")
	)
	(segment
		(start 76.865734 -208.8896)
		(end 74.945748 -206.969614)
		(width 0.15494)
		(layer "In13.Cu")
		(net "PWRGD_P12V_SSD1_R")
	)
	(segment
		(start 322.979796 -234.7214)
		(end 277.625302 -234.7214)
		(width 0.15494)
		(layer "In13.Cu")
		(net "PWRGD_P12V_SSD1_R")
	)
	(segment
		(start 233.8578 -211.4804)
		(end 231.4448 -211.4804)
		(width 0.15494)
		(layer "In13.Cu")
		(net "PWRGD_P12V_SSD1_R")
	)
	(segment
		(start 151.003762 -214.886794)
		(end 150.932896 -214.95766)
		(width 0.15494)
		(layer "In13.Cu")
		(net "PWRGD_P12V_SSD1_R")
	)
	(segment
		(start 229.9716 -211.9122)
		(end 229.4382 -211.3788)
		(width 0.15494)
		(layer "In13.Cu")
		(net "PWRGD_P12V_SSD1_R")
	)
	(segment
		(start 212.68436 -217.9066)
		(end 211.124546 -217.9066)
		(width 0.15494)
		(layer "In13.Cu")
		(net "PWRGD_P12V_SSD1_R")
	)
	(segment
		(start 150.475696 -215.0364)
		(end 148.37664 -217.135456)
		(width 0.15494)
		(layer "In13.Cu")
		(net "PWRGD_P12V_SSD1_R")
	)
	(segment
		(start 231.013 -211.9122)
		(end 229.9716 -211.9122)
		(width 0.15494)
		(layer "In13.Cu")
		(net "PWRGD_P12V_SSD1_R")
	)
	(segment
		(start 225.475292 -212.309964)
		(end 225.475292 -212.339682)
		(width 0.15494)
		(layer "In13.Cu")
		(net "PWRGD_P12V_SSD1_R")
	)
	(segment
		(start 247.22709 -226.399852)
		(end 242.380262 -221.553024)
		(width 0.15494)
		(layer "In13.Cu")
		(net "PWRGD_P12V_SSD1_R")
	)
	(segment
		(start 236.044486 -214.327486)
		(end 234.5436 -212.8266)
		(width 0.15494)
		(layer "In13.Cu")
		(net "PWRGD_P12V_SSD1_R")
	)
	(segment
		(start 124.273818 -215.37676)
		(end 123.35129 -215.37676)
		(width 0.15494)
		(layer "In13.Cu")
		(net "PWRGD_P12V_SSD1_R")
	)
	(segment
		(start 123.35129 -215.37676)
		(end 116.40439 -208.42986)
		(width 0.15494)
		(layer "In13.Cu")
		(net "PWRGD_P12V_SSD1_R")
	)
	(segment
		(start 217.1446 -218.313)
		(end 215.9762 -218.313)
		(width 0.15494)
		(layer "In13.Cu")
		(net "PWRGD_P12V_SSD1_R")
	)
	(segment
		(start 225.795332 -211.989924)
		(end 225.475292 -212.309964)
		(width 0.15494)
		(layer "In13.Cu")
		(net "PWRGD_P12V_SSD1_R")
	)
	(segment
		(start 342.4936 -224.386394)
		(end 342.4936 -227.295456)
		(width 0.15494)
		(layer "In13.Cu")
		(net "PWRGD_P12V_SSD1_R")
	)
	(segment
		(start 116.265706 -208.41716)
		(end 99.506786 -208.41716)
		(width 0.15494)
		(layer "In13.Cu")
		(net "PWRGD_P12V_SSD1_R")
	)
	(segment
		(start 256.67208 -226.947476)
		(end 250.034552 -226.947476)
		(width 0.15494)
		(layer "In13.Cu")
		(net "PWRGD_P12V_SSD1_R")
	)
	(segment
		(start 210.29676 -217.078814)
		(end 207.93456 -217.078814)
		(width 0.15494)
		(layer "In13.Cu")
		(net "PWRGD_P12V_SSD1_R")
	)
	(segment
		(start 212.81136 -217.7796)
		(end 212.68436 -217.9066)
		(width 0.15494)
		(layer "In13.Cu")
		(net "PWRGD_P12V_SSD1_R")
	)
	(segment
		(start 217.678 -217.7796)
		(end 217.1446 -218.313)
		(width 0.15494)
		(layer "In13.Cu")
		(net "PWRGD_P12V_SSD1_R")
	)
	(segment
		(start 215.4428 -217.7796)
		(end 212.81136 -217.7796)
		(width 0.15494)
		(layer "In13.Cu")
		(net "PWRGD_P12V_SSD1_R")
	)
	(segment
		(start 341.694008 -230.237538)
		(end 339.716618 -232.214928)
		(width 0.15494)
		(layer "In13.Cu")
		(net "PWRGD_P12V_SSD1_R")
	)
	(segment
		(start 240.843308 -219.365322)
		(end 236.044486 -214.5665)
		(width 0.15494)
		(layer "In13.Cu")
		(net "PWRGD_P12V_SSD1_R")
	)
	(segment
		(start 225.795332 -211.5058)
		(end 225.795332 -211.989924)
		(width 0.15494)
		(layer "In13.Cu")
		(net "PWRGD_P12V_SSD1_R")
	)
	(segment
		(start 229.4382 -211.3788)
		(end 225.922332 -211.3788)
		(width 0.15494)
		(layer "In13.Cu")
		(net "PWRGD_P12V_SSD1_R")
	)
	(segment
		(start 215.9762 -218.313)
		(end 215.4428 -217.7796)
		(width 0.15494)
		(layer "In13.Cu")
		(net "PWRGD_P12V_SSD1_R")
	)
	(segment
		(start 323.264276 -235.00588)
		(end 322.979796 -234.7214)
		(width 0.15494)
		(layer "In13.Cu")
		(net "PWRGD_P12V_SSD1_R")
	)
	(segment
		(start 207.93456 -217.078814)
		(end 205.74254 -214.886794)
		(width 0.15494)
		(layer "In13.Cu")
		(net "PWRGD_P12V_SSD1_R")
	)
	(segment
		(start 141.341094 -217.165936)
		(end 141.310614 -217.135456)
		(width 0.15494)
		(layer "In13.Cu")
		(net "PWRGD_P12V_SSD1_R")
	)
	(segment
		(start 222.84055 -213.125304)
		(end 220.813884 -215.15197)
		(width 0.15494)
		(layer "In13.Cu")
		(net "PWRGD_P12V_SSD1_R")
	)
	(segment
		(start 231.4448 -211.4804)
		(end 231.013 -211.9122)
		(width 0.15494)
		(layer "In13.Cu")
		(net "PWRGD_P12V_SSD1_R")
	)
	(segment
		(start 150.724616 -215.0364)
		(end 150.475696 -215.0364)
		(width 0.15494)
		(layer "In13.Cu")
		(net "PWRGD_P12V_SSD1_R")
	)
	(segment
		(start 242.380262 -221.553024)
		(end 241.18443 -221.553024)
		(width 0.15494)
		(layer "In13.Cu")
		(net "PWRGD_P12V_SSD1_R")
	)
	(segment
		(start 333.076042 -234.498134)
		(end 326.042782 -234.498134)
		(width 0.15494)
		(layer "In13.Cu")
		(net "PWRGD_P12V_SSD1_R")
	)
	(segment
		(start 224.68967 -213.125304)
		(end 222.84055 -213.125304)
		(width 0.15494)
		(layer "In13.Cu")
		(net "PWRGD_P12V_SSD1_R")
	)
	(segment
		(start 99.506786 -208.41716)
		(end 99.034346 -208.8896)
		(width 0.15494)
		(layer "In13.Cu")
		(net "PWRGD_P12V_SSD1_R")
	)
	(segment
		(start 335.359248 -232.214928)
		(end 333.076042 -234.498134)
		(width 0.15494)
		(layer "In13.Cu")
		(net "PWRGD_P12V_SSD1_R")
	)
	(segment
		(start 220.02242 -217.7796)
		(end 217.678 -217.7796)
		(width 0.15494)
		(layer "In13.Cu")
		(net "PWRGD_P12V_SSD1_R")
	)
	(segment
		(start 142.039594 -217.165936)
		(end 141.341094 -217.165936)
		(width 0.15494)
		(layer "In13.Cu")
		(net "PWRGD_P12V_SSD1_R")
	)
	(segment
		(start 220.813884 -216.988136)
		(end 220.02242 -217.7796)
		(width 0.15494)
		(layer "In13.Cu")
		(net "PWRGD_P12V_SSD1_R")
	)
	(segment
		(start 234.5436 -212.8266)
		(end 234.5436 -212.1662)
		(width 0.15494)
		(layer "In13.Cu")
		(net "PWRGD_P12V_SSD1_R")
	)
	(segment
		(start 350.893888 -216.786968)
		(end 351.293684 -216.387172)
		(width 0.13208)
		(layer "F.Cu")
		(net "PWRGD_NIC7_PWR_GOOD_R")
	)
	(via
		(at 418.00399 -96.901)
		(size 0.508)
		(drill 0.254)
		(layers "F.Cu" "B.Cu")
		(net "PWRGD_NIC7_PWR_GOOD_R")
	)
	(via
		(at 366.428782 -94.361508)
		(size 0.508)
		(drill 0.254)
		(layers "F.Cu" "B.Cu")
		(net "PWRGD_NIC7_PWR_GOOD_R")
	)
	(via
		(at 351.293684 -216.387172)
		(size 0.4572)
		(drill 0.254)
		(layers "F.Cu" "B.Cu")
		(net "PWRGD_NIC7_PWR_GOOD_R")
	)
	(segment
		(start 418.00399 -97.663)
		(end 418.00399 -96.901)
		(width 0.13208)
		(layer "B.Cu")
		(net "PWRGD_NIC7_PWR_GOOD_R")
	)
	(segment
		(start 350.728788 -128.199896)
		(end 350.728788 -140.068554)
		(width 0.15494)
		(layer "In5.Cu")
		(net "PWRGD_NIC7_PWR_GOOD_R")
	)
	(segment
		(start 364.694978 -207.40497)
		(end 364.150402 -207.40497)
		(width 0.15494)
		(layer "In5.Cu")
		(net "PWRGD_NIC7_PWR_GOOD_R")
	)
	(segment
		(start 366.428782 -97.558352)
		(end 362.719366 -101.267768)
		(width 0.15494)
		(layer "In5.Cu")
		(net "PWRGD_NIC7_PWR_GOOD_R")
	)
	(segment
		(start 355.93147 -165.650418)
		(end 355.93147 -167.41013)
		(width 0.15494)
		(layer "In5.Cu")
		(net "PWRGD_NIC7_PWR_GOOD_R")
	)
	(segment
		(start 352.048064 -159.787336)
		(end 352.733864 -160.473136)
		(width 0.15494)
		(layer "In5.Cu")
		(net "PWRGD_NIC7_PWR_GOOD_R")
	)
	(segment
		(start 355.93147 -167.41013)
		(end 356.887526 -168.366186)
		(width 0.15494)
		(layer "In5.Cu")
		(net "PWRGD_NIC7_PWR_GOOD_R")
	)
	(segment
		(start 352.733864 -160.473136)
		(end 352.733864 -162.452812)
		(width 0.15494)
		(layer "In5.Cu")
		(net "PWRGD_NIC7_PWR_GOOD_R")
	)
	(segment
		(start 354.093272 -117.055138)
		(end 354.093272 -124.835412)
		(width 0.15494)
		(layer "In5.Cu")
		(net "PWRGD_NIC7_PWR_GOOD_R")
	)
	(segment
		(start 362.719366 -108.429044)
		(end 354.093272 -117.055138)
		(width 0.15494)
		(layer "In5.Cu")
		(net "PWRGD_NIC7_PWR_GOOD_R")
	)
	(segment
		(start 352.733864 -162.452812)
		(end 355.93147 -165.650418)
		(width 0.15494)
		(layer "In5.Cu")
		(net "PWRGD_NIC7_PWR_GOOD_R")
	)
	(segment
		(start 356.887526 -168.366186)
		(end 358.584754 -168.366186)
		(width 0.15494)
		(layer "In5.Cu")
		(net "PWRGD_NIC7_PWR_GOOD_R")
	)
	(segment
		(start 365.68888 -178.619658)
		(end 365.68888 -179.57673)
		(width 0.15494)
		(layer "In5.Cu")
		(net "PWRGD_NIC7_PWR_GOOD_R")
	)
	(segment
		(start 363.561122 -176.926748)
		(end 364.913926 -178.279552)
		(width 0.15494)
		(layer "In5.Cu")
		(net "PWRGD_NIC7_PWR_GOOD_R")
	)
	(segment
		(start 350.728788 -140.068554)
		(end 350.98736 -140.327126)
		(width 0.15494)
		(layer "In5.Cu")
		(net "PWRGD_NIC7_PWR_GOOD_R")
	)
	(segment
		(start 351.637346 -140.327126)
		(end 352.048064 -140.737844)
		(width 0.15494)
		(layer "In5.Cu")
		(net "PWRGD_NIC7_PWR_GOOD_R")
	)
	(segment
		(start 364.150402 -207.40497)
		(end 359.739692 -211.81568)
		(width 0.15494)
		(layer "In5.Cu")
		(net "PWRGD_NIC7_PWR_GOOD_R")
	)
	(segment
		(start 362.719366 -101.267768)
		(end 362.719366 -108.429044)
		(width 0.15494)
		(layer "In5.Cu")
		(net "PWRGD_NIC7_PWR_GOOD_R")
	)
	(segment
		(start 363.561122 -173.342554)
		(end 363.561122 -176.926748)
		(width 0.15494)
		(layer "In5.Cu")
		(net "PWRGD_NIC7_PWR_GOOD_R")
	)
	(segment
		(start 359.739692 -211.81568)
		(end 356.73792 -211.81568)
		(width 0.15494)
		(layer "In5.Cu")
		(net "PWRGD_NIC7_PWR_GOOD_R")
	)
	(segment
		(start 354.880672 -213.672928)
		(end 354.007928 -213.672928)
		(width 0.15494)
		(layer "In5.Cu")
		(net "PWRGD_NIC7_PWR_GOOD_R")
	)
	(segment
		(start 364.913926 -178.279552)
		(end 365.348774 -178.279552)
		(width 0.15494)
		(layer "In5.Cu")
		(net "PWRGD_NIC7_PWR_GOOD_R")
	)
	(segment
		(start 352.048064 -140.737844)
		(end 352.048064 -159.787336)
		(width 0.15494)
		(layer "In5.Cu")
		(net "PWRGD_NIC7_PWR_GOOD_R")
	)
	(segment
		(start 366.428782 -94.361508)
		(end 366.428782 -97.558352)
		(width 0.15494)
		(layer "In5.Cu")
		(net "PWRGD_NIC7_PWR_GOOD_R")
	)
	(segment
		(start 370.345462 -203.156566)
		(end 368.708432 -204.793596)
		(width 0.15494)
		(layer "In5.Cu")
		(net "PWRGD_NIC7_PWR_GOOD_R")
	)
	(segment
		(start 365.68888 -179.57673)
		(end 368.666268 -182.554118)
		(width 0.15494)
		(layer "In5.Cu")
		(net "PWRGD_NIC7_PWR_GOOD_R")
	)
	(segment
		(start 365.348774 -178.279552)
		(end 365.68888 -178.619658)
		(width 0.15494)
		(layer "In5.Cu")
		(net "PWRGD_NIC7_PWR_GOOD_R")
	)
	(segment
		(start 368.708432 -204.793596)
		(end 367.306352 -204.793596)
		(width 0.15494)
		(layer "In5.Cu")
		(net "PWRGD_NIC7_PWR_GOOD_R")
	)
	(segment
		(start 350.98736 -140.327126)
		(end 351.637346 -140.327126)
		(width 0.15494)
		(layer "In5.Cu")
		(net "PWRGD_NIC7_PWR_GOOD_R")
	)
	(segment
		(start 368.666268 -182.554118)
		(end 368.666268 -191.277494)
		(width 0.15494)
		(layer "In5.Cu")
		(net "PWRGD_NIC7_PWR_GOOD_R")
	)
	(segment
		(start 358.584754 -168.366186)
		(end 363.561122 -173.342554)
		(width 0.15494)
		(layer "In5.Cu")
		(net "PWRGD_NIC7_PWR_GOOD_R")
	)
	(segment
		(start 368.666268 -191.277494)
		(end 370.345462 -192.956688)
		(width 0.15494)
		(layer "In5.Cu")
		(net "PWRGD_NIC7_PWR_GOOD_R")
	)
	(segment
		(start 356.73792 -211.81568)
		(end 354.880672 -213.672928)
		(width 0.15494)
		(layer "In5.Cu")
		(net "PWRGD_NIC7_PWR_GOOD_R")
	)
	(segment
		(start 367.306352 -204.793596)
		(end 364.694978 -207.40497)
		(width 0.15494)
		(layer "In5.Cu")
		(net "PWRGD_NIC7_PWR_GOOD_R")
	)
	(segment
		(start 354.093272 -124.835412)
		(end 350.728788 -128.199896)
		(width 0.15494)
		(layer "In5.Cu")
		(net "PWRGD_NIC7_PWR_GOOD_R")
	)
	(segment
		(start 354.007928 -213.672928)
		(end 351.293684 -216.387172)
		(width 0.15494)
		(layer "In5.Cu")
		(net "PWRGD_NIC7_PWR_GOOD_R")
	)
	(segment
		(start 370.345462 -192.956688)
		(end 370.345462 -203.156566)
		(width 0.15494)
		(layer "In5.Cu")
		(net "PWRGD_NIC7_PWR_GOOD_R")
	)
	(segment
		(start 402.270976 -93.411548)
		(end 400.18462 -91.325192)
		(width 0.15494)
		(layer "In13.Cu")
		(net "PWRGD_NIC7_PWR_GOOD_R")
	)
	(segment
		(start 418.00399 -96.901)
		(end 418.00399 -94.973648)
		(width 0.15494)
		(layer "In13.Cu")
		(net "PWRGD_NIC7_PWR_GOOD_R")
	)
	(segment
		(start 382.24968 -92.573602)
		(end 370.011198 -92.573602)
		(width 0.15494)
		(layer "In13.Cu")
		(net "PWRGD_NIC7_PWR_GOOD_R")
	)
	(segment
		(start 416.44189 -93.411548)
		(end 402.270976 -93.411548)
		(width 0.15494)
		(layer "In13.Cu")
		(net "PWRGD_NIC7_PWR_GOOD_R")
	)
	(segment
		(start 368.223292 -94.361508)
		(end 366.428782 -94.361508)
		(width 0.15494)
		(layer "In13.Cu")
		(net "PWRGD_NIC7_PWR_GOOD_R")
	)
	(segment
		(start 370.011198 -92.573602)
		(end 368.223292 -94.361508)
		(width 0.15494)
		(layer "In13.Cu")
		(net "PWRGD_NIC7_PWR_GOOD_R")
	)
	(segment
		(start 400.18462 -91.325192)
		(end 383.49809 -91.325192)
		(width 0.15494)
		(layer "In13.Cu")
		(net "PWRGD_NIC7_PWR_GOOD_R")
	)
	(segment
		(start 418.00399 -94.973648)
		(end 416.44189 -93.411548)
		(width 0.15494)
		(layer "In13.Cu")
		(net "PWRGD_NIC7_PWR_GOOD_R")
	)
	(segment
		(start 383.49809 -91.325192)
		(end 382.24968 -92.573602)
		(width 0.15494)
		(layer "In13.Cu")
		(net "PWRGD_NIC7_PWR_GOOD_R")
	)
	(segment
		(start 334.679798 -52.994814)
		(end 334.679798 -51.670966)
		(width 0.13208)
		(layer "F.Cu")
		(net "P12V_SSD11_SS")
	)
	(segment
		(start 335.331308 -51.019456)
		(end 336.067654 -51.019456)
		(width 0.13208)
		(layer "F.Cu")
		(net "P12V_SSD11_SS")
	)
	(segment
		(start 334.347058 -53.144166)
		(end 334.530446 -53.144166)
		(width 0.13208)
		(layer "F.Cu")
		(net "P12V_SSD11_SS")
	)
	(segment
		(start 334.530446 -53.144166)
		(end 334.679798 -52.994814)
		(width 0.13208)
		(layer "F.Cu")
		(net "P12V_SSD11_SS")
	)
	(segment
		(start 334.679798 -51.670966)
		(end 335.331308 -51.019456)
		(width 0.13208)
		(layer "F.Cu")
		(net "P12V_SSD11_SS")
	)
	(via
		(at 335.331308 -51.019456)
		(size 0.508)
		(drill 0.254)
		(layers "F.Cu" "B.Cu")
		(net "P12V_SSD11_SS")
	)
	(segment
		(start 418.690298 -240.170716)
		(end 419.339522 -240.170716)
		(width 0.13208)
		(layer "F.Cu")
		(net "UART_PEX2_SDB_R_RX")
	)
	(segment
		(start 444.508128 -223.316546)
		(end 443.711838 -223.316546)
		(width 0.13208)
		(layer "F.Cu")
		(net "UART_PEX2_SDB_R_RX")
	)
	(segment
		(start 419.339522 -240.170716)
		(end 419.489636 -240.020602)
		(width 0.13208)
		(layer "F.Cu")
		(net "UART_PEX2_SDB_R_RX")
	)
	(segment
		(start 419.489636 -240.020602)
		(end 419.489636 -239.302544)
		(width 0.13208)
		(layer "F.Cu")
		(net "UART_PEX2_SDB_R_RX")
	)
	(via
		(at 388.239 -240.693448)
		(size 0.508)
		(drill 0.254)
		(layers "F.Cu" "B.Cu")
		(net "UART_PEX2_SDB_R_RX")
	)
	(via
		(at 418.690298 -240.170716)
		(size 0.508)
		(drill 0.254)
		(layers "F.Cu" "B.Cu")
		(net "UART_PEX2_SDB_R_RX")
	)
	(via
		(at 443.711838 -223.316546)
		(size 0.508)
		(drill 0.254)
		(layers "F.Cu" "B.Cu")
		(net "UART_PEX2_SDB_R_RX")
	)
	(segment
		(start 388.239 -240.693448)
		(end 388.239 -240.13795)
		(width 0.13208)
		(layer "B.Cu")
		(net "UART_PEX2_SDB_R_RX")
	)
	(segment
		(start 388.239 -240.13795)
		(end 387.62305 -239.522)
		(width 0.13208)
		(layer "B.Cu")
		(net "UART_PEX2_SDB_R_RX")
	)
	(segment
		(start 387.491986 -241.793014)
		(end 387.842506 -241.442494)
		(width 0.13208)
		(layer "B.Cu")
		(net "UART_PEX2_SDB_R_RX")
	)
	(segment
		(start 387.842506 -241.442494)
		(end 387.842506 -241.089942)
		(width 0.13208)
		(layer "B.Cu")
		(net "UART_PEX2_SDB_R_RX")
	)
	(segment
		(start 387.842506 -241.089942)
		(end 388.239 -240.693448)
		(width 0.13208)
		(layer "B.Cu")
		(net "UART_PEX2_SDB_R_RX")
	)
	(segment
		(start 387.491986 -242.205002)
		(end 387.491986 -241.793014)
		(width 0.13208)
		(layer "B.Cu")
		(net "UART_PEX2_SDB_R_RX")
	)
	(segment
		(start 389.111998 -240.693448)
		(end 388.239 -240.693448)
		(width 0.15494)
		(layer "In13.Cu")
		(net "UART_PEX2_SDB_R_RX")
	)
	(segment
		(start 389.63473 -240.170716)
		(end 389.111998 -240.693448)
		(width 0.15494)
		(layer "In13.Cu")
		(net "UART_PEX2_SDB_R_RX")
	)
	(segment
		(start 418.690298 -240.170716)
		(end 389.63473 -240.170716)
		(width 0.15494)
		(layer "In13.Cu")
		(net "UART_PEX2_SDB_R_RX")
	)
	(segment
		(start 418.690298 -240.170716)
		(end 439.099198 -240.170716)
		(width 0.15494)
		(layer "In15.Cu")
		(net "UART_PEX2_SDB_R_RX")
	)
	(segment
		(start 443.019688 -225.0948)
		(end 443.019688 -224.008696)
		(width 0.15494)
		(layer "In15.Cu")
		(net "UART_PEX2_SDB_R_RX")
	)
	(segment
		(start 445.288924 -227.364036)
		(end 443.019688 -225.0948)
		(width 0.15494)
		(layer "In15.Cu")
		(net "UART_PEX2_SDB_R_RX")
	)
	(segment
		(start 439.099198 -240.170716)
		(end 445.288924 -233.98099)
		(width 0.15494)
		(layer "In15.Cu")
		(net "UART_PEX2_SDB_R_RX")
	)
	(segment
		(start 445.288924 -233.98099)
		(end 445.288924 -227.364036)
		(width 0.15494)
		(layer "In15.Cu")
		(net "UART_PEX2_SDB_R_RX")
	)
	(segment
		(start 443.019688 -224.008696)
		(end 443.711838 -223.316546)
		(width 0.15494)
		(layer "In15.Cu")
		(net "UART_PEX2_SDB_R_RX")
	)
	(segment
		(start 380.843282 -229.16896)
		(end 380.843282 -229.802182)
		(width 0.13208)
		(layer "F.Cu")
		(net "OSC_SDB_IN")
	)
	(segment
		(start 381.548132 -228.46411)
		(end 380.843282 -229.16896)
		(width 0.13208)
		(layer "F.Cu")
		(net "OSC_SDB_IN")
	)
	(segment
		(start 380.843282 -229.802182)
		(end 381.090932 -230.049832)
		(width 0.13208)
		(layer "F.Cu")
		(net "OSC_SDB_IN")
	)
	(segment
		(start 381.3556 -231.991408)
		(end 381.090932 -231.72674)
		(width 0.13208)
		(layer "F.Cu")
		(net "OSC_SDB_IN")
	)
	(segment
		(start 381.090932 -231.72674)
		(end 381.090932 -230.43896)
		(width 0.13208)
		(layer "F.Cu")
		(net "OSC_SDB_IN")
	)
	(segment
		(start 382.646428 -228.095048)
		(end 382.277366 -228.46411)
		(width 0.13208)
		(layer "F.Cu")
		(net "OSC_SDB_IN")
	)
	(segment
		(start 381.3556 -232.836212)
		(end 381.3556 -231.991408)
		(width 0.13208)
		(layer "F.Cu")
		(net "OSC_SDB_IN")
	)
	(segment
		(start 381.686562 -225.585782)
		(end 381.852678 -225.585782)
		(width 0.13208)
		(layer "F.Cu")
		(net "OSC_SDB_IN")
	)
	(segment
		(start 381.852678 -225.585782)
		(end 382.646428 -226.379532)
		(width 0.13208)
		(layer "F.Cu")
		(net "OSC_SDB_IN")
	)
	(segment
		(start 382.277366 -228.46411)
		(end 381.548132 -228.46411)
		(width 0.13208)
		(layer "F.Cu")
		(net "OSC_SDB_IN")
	)
	(segment
		(start 381.548132 -228.46411)
		(end 381.548132 -228.467666)
		(width 0.13208)
		(layer "F.Cu")
		(net "OSC_SDB_IN")
	)
	(segment
		(start 381.090932 -230.049832)
		(end 381.090932 -230.43896)
		(width 0.13208)
		(layer "F.Cu")
		(net "OSC_SDB_IN")
	)
	(segment
		(start 382.646428 -226.379532)
		(end 382.646428 -228.095048)
		(width 0.13208)
		(layer "F.Cu")
		(net "OSC_SDB_IN")
	)
	(via
		(at 381.548132 -228.467666)
		(size 0.508)
		(drill 0.254)
		(layers "F.Cu" "B.Cu")
		(net "OSC_SDB_IN")
	)
	(segment
		(start 91.025472 -305.064922)
		(end 91.034108 -305.073558)
		(width 0.13208)
		(layer "F.Cu")
		(net "PEX0_SPARE1")
	)
	(segment
		(start 91.0336 -305.056794)
		(end 91.025472 -305.064922)
		(width 0.13208)
		(layer "F.Cu")
		(net "PEX0_SPARE1")
	)
	(segment
		(start 91.0336 -304.436526)
		(end 91.0336 -305.056794)
		(width 0.13208)
		(layer "F.Cu")
		(net "PEX0_SPARE1")
	)
	(segment
		(start 64.399922 -309.199788)
		(end 64.874902 -308.724808)
		(width 0.13208)
		(layer "F.Cu")
		(net "PEX0_SPARE1")
	)
	(segment
		(start 91.034108 -305.073558)
		(end 91.034108 -305.674522)
		(width 0.13208)
		(layer "F.Cu")
		(net "PEX0_SPARE1")
	)
	(via
		(at 91.025472 -305.064922)
		(size 0.508)
		(drill 0.254)
		(layers "F.Cu" "B.Cu")
		(net "PEX0_SPARE1")
	)
	(via
		(at 64.874902 -308.724808)
		(size 0.4064)
		(drill 0.2032)
		(layers "F.Cu" "B.Cu")
		(net "PEX0_SPARE1")
	)
	(via
		(at 85.064346 -311.026048)
		(size 0.6604)
		(drill 0.3302)
		(layers "F.Cu" "B.Cu")
		(net "PEX0_SPARE1")
	)
	(segment
		(start 65.7606 -311.285636)
		(end 66.0146 -311.539636)
		(width 0.13208)
		(layer "B.Cu")
		(net "PEX0_SPARE1")
	)
	(segment
		(start 64.874902 -308.724808)
		(end 65.7606 -309.610506)
		(width 0.13208)
		(layer "B.Cu")
		(net "PEX0_SPARE1")
	)
	(segment
		(start 65.7606 -309.610506)
		(end 65.7606 -311.285636)
		(width 0.13208)
		(layer "B.Cu")
		(net "PEX0_SPARE1")
	)
	(segment
		(start 85.064346 -311.026048)
		(end 91.025472 -305.064922)
		(width 0.13208)
		(layer "B.Cu")
		(net "PEX0_SPARE1")
	)
	(segment
		(start 66.0146 -311.539636)
		(end 84.550758 -311.539636)
		(width 0.13208)
		(layer "B.Cu")
		(net "PEX0_SPARE1")
	)
	(segment
		(start 84.550758 -311.539636)
		(end 85.064346 -311.026048)
		(width 0.13208)
		(layer "B.Cu")
		(net "PEX0_SPARE1")
	)
	(segment
		(start 282.842462 -141.964918)
		(end 284.187138 -141.964918)
		(width 0.13208)
		(layer "F.Cu")
		(net "SMB_NIC4_LS_SDA")
	)
	(segment
		(start 284.852364 -141.964918)
		(end 285.212282 -141.605)
		(width 0.13208)
		(layer "F.Cu")
		(net "SMB_NIC4_LS_SDA")
	)
	(segment
		(start 285.212282 -141.605)
		(end 287.349692 -141.605)
		(width 0.13208)
		(layer "F.Cu")
		(net "SMB_NIC4_LS_SDA")
	)
	(segment
		(start 287.349692 -141.605)
		(end 287.679892 -141.9352)
		(width 0.13208)
		(layer "F.Cu")
		(net "SMB_NIC4_LS_SDA")
	)
	(segment
		(start 284.187138 -141.964918)
		(end 284.852364 -141.964918)
		(width 0.13208)
		(layer "F.Cu")
		(net "SMB_NIC4_LS_SDA")
	)
	(via
		(at 254.40767 -159.41167)
		(size 0.508)
		(drill 0.254)
		(layers "F.Cu" "B.Cu")
		(net "SMB_NIC4_LS_SDA")
	)
	(via
		(at 215.773 -207.645)
		(size 0.508)
		(drill 0.254)
		(layers "F.Cu" "B.Cu")
		(net "SMB_NIC4_LS_SDA")
	)
	(via
		(at 217.2462 -164.292026)
		(size 0.508)
		(drill 0.254)
		(layers "F.Cu" "B.Cu")
		(net "SMB_NIC4_LS_SDA")
	)
	(via
		(at 284.187138 -141.964918)
		(size 0.508)
		(drill 0.254)
		(layers "F.Cu" "B.Cu")
		(net "SMB_NIC4_LS_SDA")
	)
	(segment
		(start 214.64905 -207.645)
		(end 214.503 -207.49895)
		(width 0.13208)
		(layer "B.Cu")
		(net "SMB_NIC4_LS_SDA")
	)
	(segment
		(start 214.503 -207.49895)
		(end 213.106 -207.49895)
		(width 0.13208)
		(layer "B.Cu")
		(net "SMB_NIC4_LS_SDA")
	)
	(segment
		(start 215.773 -207.645)
		(end 214.64905 -207.645)
		(width 0.13208)
		(layer "B.Cu")
		(net "SMB_NIC4_LS_SDA")
	)
	(segment
		(start 215.773 -207.645)
		(end 215.392 -207.645)
		(width 0.15494)
		(layer "In7.Cu")
		(net "SMB_NIC4_LS_SDA")
	)
	(segment
		(start 217.47226 -184.5945)
		(end 216.3318 -183.45404)
		(width 0.15494)
		(layer "In7.Cu")
		(net "SMB_NIC4_LS_SDA")
	)
	(segment
		(start 219.129356 -189.531244)
		(end 219.129356 -187.013596)
		(width 0.15494)
		(layer "In7.Cu")
		(net "SMB_NIC4_LS_SDA")
	)
	(segment
		(start 217.47226 -185.3565)
		(end 217.47226 -184.5945)
		(width 0.15494)
		(layer "In7.Cu")
		(net "SMB_NIC4_LS_SDA")
	)
	(segment
		(start 215.392 -207.645)
		(end 215.257634 -207.510634)
		(width 0.15494)
		(layer "In7.Cu")
		(net "SMB_NIC4_LS_SDA")
	)
	(segment
		(start 217.603324 -165.154356)
		(end 217.2462 -164.292026)
		(width 0.15494)
		(layer "In7.Cu")
		(net "SMB_NIC4_LS_SDA")
	)
	(segment
		(start 215.88857 -169.418508)
		(end 217.603324 -167.703754)
		(width 0.15494)
		(layer "In7.Cu")
		(net "SMB_NIC4_LS_SDA")
	)
	(segment
		(start 215.88857 -174.48657)
		(end 215.88857 -169.418508)
		(width 0.15494)
		(layer "In7.Cu")
		(net "SMB_NIC4_LS_SDA")
	)
	(segment
		(start 217.66022 -198.7169)
		(end 217.66022 -191.00038)
		(width 0.15494)
		(layer "In7.Cu")
		(net "SMB_NIC4_LS_SDA")
	)
	(segment
		(start 216.249758 -200.127362)
		(end 217.66022 -198.7169)
		(width 0.15494)
		(layer "In7.Cu")
		(net "SMB_NIC4_LS_SDA")
	)
	(segment
		(start 216.408 -203.4286)
		(end 216.408 -201.49312)
		(width 0.15494)
		(layer "In7.Cu")
		(net "SMB_NIC4_LS_SDA")
	)
	(segment
		(start 215.257634 -204.578966)
		(end 216.408 -203.4286)
		(width 0.15494)
		(layer "In7.Cu")
		(net "SMB_NIC4_LS_SDA")
	)
	(segment
		(start 217.66022 -191.00038)
		(end 219.129356 -189.531244)
		(width 0.15494)
		(layer "In7.Cu")
		(net "SMB_NIC4_LS_SDA")
	)
	(segment
		(start 219.129356 -187.013596)
		(end 217.47226 -185.3565)
		(width 0.15494)
		(layer "In7.Cu")
		(net "SMB_NIC4_LS_SDA")
	)
	(segment
		(start 216.3318 -174.9298)
		(end 215.88857 -174.48657)
		(width 0.15494)
		(layer "In7.Cu")
		(net "SMB_NIC4_LS_SDA")
	)
	(segment
		(start 216.3318 -183.45404)
		(end 216.3318 -174.9298)
		(width 0.15494)
		(layer "In7.Cu")
		(net "SMB_NIC4_LS_SDA")
	)
	(segment
		(start 216.408 -201.49312)
		(end 216.249758 -201.334878)
		(width 0.15494)
		(layer "In7.Cu")
		(net "SMB_NIC4_LS_SDA")
	)
	(segment
		(start 216.249758 -201.334878)
		(end 216.249758 -200.127362)
		(width 0.15494)
		(layer "In7.Cu")
		(net "SMB_NIC4_LS_SDA")
	)
	(segment
		(start 215.257634 -207.510634)
		(end 215.257634 -204.578966)
		(width 0.15494)
		(layer "In7.Cu")
		(net "SMB_NIC4_LS_SDA")
	)
	(segment
		(start 217.603324 -167.703754)
		(end 217.603324 -165.154356)
		(width 0.15494)
		(layer "In7.Cu")
		(net "SMB_NIC4_LS_SDA")
	)
	(segment
		(start 217.2462 -164.292026)
		(end 217.2462 -163.804854)
		(width 0.15494)
		(layer "In13.Cu")
		(net "SMB_NIC4_LS_SDA")
	)
	(segment
		(start 253.365 -164.338)
		(end 254.40767 -163.29533)
		(width 0.15494)
		(layer "In13.Cu")
		(net "SMB_NIC4_LS_SDA")
	)
	(segment
		(start 254.40767 -163.29533)
		(end 254.40767 -159.41167)
		(width 0.15494)
		(layer "In13.Cu")
		(net "SMB_NIC4_LS_SDA")
	)
	(segment
		(start 220.1926 -164.338)
		(end 253.365 -164.338)
		(width 0.15494)
		(layer "In13.Cu")
		(net "SMB_NIC4_LS_SDA")
	)
	(segment
		(start 217.417904 -163.63315)
		(end 219.48775 -163.63315)
		(width 0.15494)
		(layer "In13.Cu")
		(net "SMB_NIC4_LS_SDA")
	)
	(segment
		(start 219.48775 -163.63315)
		(end 220.1926 -164.338)
		(width 0.15494)
		(layer "In13.Cu")
		(net "SMB_NIC4_LS_SDA")
	)
	(segment
		(start 217.2462 -163.804854)
		(end 217.417904 -163.63315)
		(width 0.15494)
		(layer "In13.Cu")
		(net "SMB_NIC4_LS_SDA")
	)
	(segment
		(start 271.008856 -140.267944)
		(end 271.008856 -144.281398)
		(width 0.15494)
		(layer "In15.Cu")
		(net "SMB_NIC4_LS_SDA")
	)
	(segment
		(start 281.2796 -137.0584)
		(end 280.2636 -136.0424)
		(width 0.15494)
		(layer "In15.Cu")
		(net "SMB_NIC4_LS_SDA")
	)
	(segment
		(start 281.2796 -141.122146)
		(end 281.2796 -137.0584)
		(width 0.15494)
		(layer "In15.Cu")
		(net "SMB_NIC4_LS_SDA")
	)
	(segment
		(start 280.2636 -136.0424)
		(end 275.2344 -136.0424)
		(width 0.15494)
		(layer "In15.Cu")
		(net "SMB_NIC4_LS_SDA")
	)
	(segment
		(start 282.122372 -141.964918)
		(end 281.2796 -141.122146)
		(width 0.15494)
		(layer "In15.Cu")
		(net "SMB_NIC4_LS_SDA")
	)
	(segment
		(start 256.819654 -158.4706)
		(end 255.1176 -158.4706)
		(width 0.15494)
		(layer "In15.Cu")
		(net "SMB_NIC4_LS_SDA")
	)
	(segment
		(start 255.1176 -158.4706)
		(end 254.40767 -159.18053)
		(width 0.15494)
		(layer "In15.Cu")
		(net "SMB_NIC4_LS_SDA")
	)
	(segment
		(start 284.187138 -141.964918)
		(end 282.122372 -141.964918)
		(width 0.15494)
		(layer "In15.Cu")
		(net "SMB_NIC4_LS_SDA")
	)
	(segment
		(start 271.008856 -144.281398)
		(end 256.819654 -158.4706)
		(width 0.15494)
		(layer "In15.Cu")
		(net "SMB_NIC4_LS_SDA")
	)
	(segment
		(start 254.40767 -159.18053)
		(end 254.40767 -159.41167)
		(width 0.15494)
		(layer "In15.Cu")
		(net "SMB_NIC4_LS_SDA")
	)
	(segment
		(start 275.2344 -136.0424)
		(end 271.008856 -140.267944)
		(width 0.15494)
		(layer "In15.Cu")
		(net "SMB_NIC4_LS_SDA")
	)
	(segment
		(start 122.124724 -86.977474)
		(end 123.934474 -86.977474)
		(width 0.13208)
		(layer "F.Cu")
		(net "SMB_BIC_I2C9_MUX0_SSD3_R_SCL")
	)
	(segment
		(start 130.751326 -80.160622)
		(end 130.751326 -79.490062)
		(width 0.13208)
		(layer "F.Cu")
		(net "SMB_BIC_I2C9_MUX0_SSD3_R_SCL")
	)
	(segment
		(start 105.131616 -8.272526)
		(end 104.775762 -7.916672)
		(width 0.13208)
		(layer "F.Cu")
		(net "SMB_BIC_I2C9_MUX0_SSD3_R_SCL")
	)
	(segment
		(start 121.509028 -87.59317)
		(end 122.124724 -86.977474)
		(width 0.13208)
		(layer "F.Cu")
		(net "SMB_BIC_I2C9_MUX0_SSD3_R_SCL")
	)
	(segment
		(start 123.934474 -86.977474)
		(end 130.751326 -80.160622)
		(width 0.13208)
		(layer "F.Cu")
		(net "SMB_BIC_I2C9_MUX0_SSD3_R_SCL")
	)
	(segment
		(start 123.248928 -88.39073)
		(end 121.509028 -88.39073)
		(width 0.13208)
		(layer "F.Cu")
		(net "SMB_BIC_I2C9_MUX0_SSD3_R_SCL")
	)
	(segment
		(start 105.703624 -7.931658)
		(end 105.472484 -7.931658)
		(width 0.13208)
		(layer "F.Cu")
		(net "SMB_BIC_I2C9_MUX0_SSD3_R_SCL")
	)
	(segment
		(start 105.472484 -7.931658)
		(end 105.131616 -8.272526)
		(width 0.13208)
		(layer "F.Cu")
		(net "SMB_BIC_I2C9_MUX0_SSD3_R_SCL")
	)
	(segment
		(start 121.509028 -88.39073)
		(end 121.509028 -87.59317)
		(width 0.13208)
		(layer "F.Cu")
		(net "SMB_BIC_I2C9_MUX0_SSD3_R_SCL")
	)
	(segment
		(start 105.8926 -7.742682)
		(end 105.703624 -7.931658)
		(width 0.13208)
		(layer "F.Cu")
		(net "SMB_BIC_I2C9_MUX0_SSD3_R_SCL")
	)
	(segment
		(start 104.775762 -7.916672)
		(end 104.126538 -7.916672)
		(width 0.13208)
		(layer "F.Cu")
		(net "SMB_BIC_I2C9_MUX0_SSD3_R_SCL")
	)
	(via
		(at 130.751326 -79.490062)
		(size 0.508)
		(drill 0.254)
		(layers "F.Cu" "B.Cu")
		(net "SMB_BIC_I2C9_MUX0_SSD3_R_SCL")
	)
	(via
		(at 105.131616 -8.272526)
		(size 0.508)
		(drill 0.254)
		(layers "F.Cu" "B.Cu")
		(net "SMB_BIC_I2C9_MUX0_SSD3_R_SCL")
	)
	(segment
		(start 105.11282 -12.36218)
		(end 104.56291 -12.91209)
		(width 0.15494)
		(layer "In5.Cu")
		(net "SMB_BIC_I2C9_MUX0_SSD3_R_SCL")
	)
	(segment
		(start 102.8446 -35.42284)
		(end 108.96346 -41.5417)
		(width 0.15494)
		(layer "In5.Cu")
		(net "SMB_BIC_I2C9_MUX0_SSD3_R_SCL")
	)
	(segment
		(start 104.241092 -31.42996)
		(end 102.8446 -32.826452)
		(width 0.15494)
		(layer "In5.Cu")
		(net "SMB_BIC_I2C9_MUX0_SSD3_R_SCL")
	)
	(segment
		(start 128.38303 -76.572872)
		(end 128.38303 -76.763372)
		(width 0.15494)
		(layer "In5.Cu")
		(net "SMB_BIC_I2C9_MUX0_SSD3_R_SCL")
	)
	(segment
		(start 118.521734 -63.505334)
		(end 119.71147 -64.69507)
		(width 0.15494)
		(layer "In5.Cu")
		(net "SMB_BIC_I2C9_MUX0_SSD3_R_SCL")
	)
	(segment
		(start 126.665482 -74.855324)
		(end 127.110998 -75.30084)
		(width 0.15494)
		(layer "In5.Cu")
		(net "SMB_BIC_I2C9_MUX0_SSD3_R_SCL")
	)
	(segment
		(start 108.96346 -53.0733)
		(end 118.521734 -62.631574)
		(width 0.15494)
		(layer "In5.Cu")
		(net "SMB_BIC_I2C9_MUX0_SSD3_R_SCL")
	)
	(segment
		(start 126.636272 -75.966066)
		(end 126.636272 -76.156566)
		(width 0.15494)
		(layer "In5.Cu")
		(net "SMB_BIC_I2C9_MUX0_SSD3_R_SCL")
	)
	(segment
		(start 127.110998 -75.30084)
		(end 127.110998 -75.49134)
		(width 0.15494)
		(layer "In5.Cu")
		(net "SMB_BIC_I2C9_MUX0_SSD3_R_SCL")
	)
	(segment
		(start 125.809756 -75.33005)
		(end 126.000256 -75.33005)
		(width 0.15494)
		(layer "In5.Cu")
		(net "SMB_BIC_I2C9_MUX0_SSD3_R_SCL")
	)
	(segment
		(start 125.168152 -69.267578)
		(end 125.168152 -74.688446)
		(width 0.15494)
		(layer "In5.Cu")
		(net "SMB_BIC_I2C9_MUX0_SSD3_R_SCL")
	)
	(segment
		(start 127.937514 -76.127356)
		(end 128.38303 -76.572872)
		(width 0.15494)
		(layer "In5.Cu")
		(net "SMB_BIC_I2C9_MUX0_SSD3_R_SCL")
	)
	(segment
		(start 108.96346 -41.5417)
		(end 108.96346 -53.0733)
		(width 0.15494)
		(layer "In5.Cu")
		(net "SMB_BIC_I2C9_MUX0_SSD3_R_SCL")
	)
	(segment
		(start 126.636272 -76.156566)
		(end 127.081788 -76.602082)
		(width 0.15494)
		(layer "In5.Cu")
		(net "SMB_BIC_I2C9_MUX0_SSD3_R_SCL")
	)
	(segment
		(start 129.982468 -78.406244)
		(end 130.751326 -79.175102)
		(width 0.15494)
		(layer "In5.Cu")
		(net "SMB_BIC_I2C9_MUX0_SSD3_R_SCL")
	)
	(segment
		(start 128.38303 -76.763372)
		(end 127.908304 -77.238098)
		(width 0.15494)
		(layer "In5.Cu")
		(net "SMB_BIC_I2C9_MUX0_SSD3_R_SCL")
	)
	(segment
		(start 102.7176 -26.513282)
		(end 104.241092 -28.036774)
		(width 0.15494)
		(layer "In5.Cu")
		(net "SMB_BIC_I2C9_MUX0_SSD3_R_SCL")
	)
	(segment
		(start 127.908304 -77.238098)
		(end 127.908304 -77.428598)
		(width 0.15494)
		(layer "In5.Cu")
		(net "SMB_BIC_I2C9_MUX0_SSD3_R_SCL")
	)
	(segment
		(start 127.081788 -76.602082)
		(end 127.272288 -76.602082)
		(width 0.15494)
		(layer "In5.Cu")
		(net "SMB_BIC_I2C9_MUX0_SSD3_R_SCL")
	)
	(segment
		(start 125.168152 -74.688446)
		(end 125.809756 -75.33005)
		(width 0.15494)
		(layer "In5.Cu")
		(net "SMB_BIC_I2C9_MUX0_SSD3_R_SCL")
	)
	(segment
		(start 126.000256 -75.33005)
		(end 126.474982 -74.855324)
		(width 0.15494)
		(layer "In5.Cu")
		(net "SMB_BIC_I2C9_MUX0_SSD3_R_SCL")
	)
	(segment
		(start 128.88595 -78.406244)
		(end 129.982468 -78.406244)
		(width 0.15494)
		(layer "In5.Cu")
		(net "SMB_BIC_I2C9_MUX0_SSD3_R_SCL")
	)
	(segment
		(start 127.110998 -75.49134)
		(end 126.636272 -75.966066)
		(width 0.15494)
		(layer "In5.Cu")
		(net "SMB_BIC_I2C9_MUX0_SSD3_R_SCL")
	)
	(segment
		(start 118.521734 -62.631574)
		(end 118.521734 -63.505334)
		(width 0.15494)
		(layer "In5.Cu")
		(net "SMB_BIC_I2C9_MUX0_SSD3_R_SCL")
	)
	(segment
		(start 127.272288 -76.602082)
		(end 127.747014 -76.127356)
		(width 0.15494)
		(layer "In5.Cu")
		(net "SMB_BIC_I2C9_MUX0_SSD3_R_SCL")
	)
	(segment
		(start 102.8446 -32.826452)
		(end 102.8446 -35.42284)
		(width 0.15494)
		(layer "In5.Cu")
		(net "SMB_BIC_I2C9_MUX0_SSD3_R_SCL")
	)
	(segment
		(start 126.474982 -74.855324)
		(end 126.665482 -74.855324)
		(width 0.15494)
		(layer "In5.Cu")
		(net "SMB_BIC_I2C9_MUX0_SSD3_R_SCL")
	)
	(segment
		(start 120.595644 -64.69507)
		(end 125.168152 -69.267578)
		(width 0.15494)
		(layer "In5.Cu")
		(net "SMB_BIC_I2C9_MUX0_SSD3_R_SCL")
	)
	(segment
		(start 130.751326 -79.175102)
		(end 130.751326 -79.490062)
		(width 0.15494)
		(layer "In5.Cu")
		(net "SMB_BIC_I2C9_MUX0_SSD3_R_SCL")
	)
	(segment
		(start 105.131616 -8.272526)
		(end 105.11282 -8.272526)
		(width 0.15494)
		(layer "In5.Cu")
		(net "SMB_BIC_I2C9_MUX0_SSD3_R_SCL")
	)
	(segment
		(start 104.241092 -28.036774)
		(end 104.241092 -31.42996)
		(width 0.15494)
		(layer "In5.Cu")
		(net "SMB_BIC_I2C9_MUX0_SSD3_R_SCL")
	)
	(segment
		(start 105.11282 -8.272526)
		(end 105.11282 -12.36218)
		(width 0.15494)
		(layer "In5.Cu")
		(net "SMB_BIC_I2C9_MUX0_SSD3_R_SCL")
	)
	(segment
		(start 104.56291 -19.28368)
		(end 102.7176 -21.12899)
		(width 0.15494)
		(layer "In5.Cu")
		(net "SMB_BIC_I2C9_MUX0_SSD3_R_SCL")
	)
	(segment
		(start 104.56291 -12.91209)
		(end 104.56291 -19.28368)
		(width 0.15494)
		(layer "In5.Cu")
		(net "SMB_BIC_I2C9_MUX0_SSD3_R_SCL")
	)
	(segment
		(start 102.7176 -21.12899)
		(end 102.7176 -26.513282)
		(width 0.15494)
		(layer "In5.Cu")
		(net "SMB_BIC_I2C9_MUX0_SSD3_R_SCL")
	)
	(segment
		(start 119.71147 -64.69507)
		(end 120.595644 -64.69507)
		(width 0.15494)
		(layer "In5.Cu")
		(net "SMB_BIC_I2C9_MUX0_SSD3_R_SCL")
	)
	(segment
		(start 127.908304 -77.428598)
		(end 128.88595 -78.406244)
		(width 0.15494)
		(layer "In5.Cu")
		(net "SMB_BIC_I2C9_MUX0_SSD3_R_SCL")
	)
	(segment
		(start 127.747014 -76.127356)
		(end 127.937514 -76.127356)
		(width 0.15494)
		(layer "In5.Cu")
		(net "SMB_BIC_I2C9_MUX0_SSD3_R_SCL")
	)
	(segment
		(start 91.883992 -288.830766)
		(end 91.883992 -288.253424)
		(width 0.13208)
		(layer "F.Cu")
		(net "SMB_PEX0_FPGA_SCL")
	)
	(segment
		(start 91.883992 -288.253424)
		(end 91.851734 -288.221166)
		(width 0.13208)
		(layer "F.Cu")
		(net "SMB_PEX0_FPGA_SCL")
	)
	(segment
		(start 338.093812 -226.387152)
		(end 337.694016 -226.786948)
		(width 0.13208)
		(layer "F.Cu")
		(net "SMB_PEX0_FPGA_SCL")
	)
	(via
		(at 91.851734 -288.221166)
		(size 0.508)
		(drill 0.254)
		(layers "F.Cu" "B.Cu")
		(net "SMB_PEX0_FPGA_SCL")
	)
	(via
		(at 92.885514 -207.042258)
		(size 0.508)
		(drill 0.254)
		(layers "F.Cu" "B.Cu")
		(net "SMB_PEX0_FPGA_SCL")
	)
	(via
		(at 337.694016 -226.786948)
		(size 0.4572)
		(drill 0.254)
		(layers "F.Cu" "B.Cu")
		(net "SMB_PEX0_FPGA_SCL")
	)
	(via
		(at 93.631004 -236.561884)
		(size 0.508)
		(drill 0.254)
		(layers "F.Cu" "B.Cu")
		(net "SMB_PEX0_FPGA_SCL")
	)
	(segment
		(start 97.015554 -253.317502)
		(end 95.759524 -253.317502)
		(width 0.13208)
		(layer "B.Cu")
		(net "SMB_PEX0_FPGA_SCL")
	)
	(segment
		(start 90.39225 -239.208564)
		(end 93.03893 -236.561884)
		(width 0.13208)
		(layer "B.Cu")
		(net "SMB_PEX0_FPGA_SCL")
	)
	(segment
		(start 98.608642 -263.292336)
		(end 98.608642 -254.91059)
		(width 0.13208)
		(layer "B.Cu")
		(net "SMB_PEX0_FPGA_SCL")
	)
	(segment
		(start 95.759524 -253.317502)
		(end 90.39225 -247.950228)
		(width 0.13208)
		(layer "B.Cu")
		(net "SMB_PEX0_FPGA_SCL")
	)
	(segment
		(start 91.851734 -281.551888)
		(end 97.838006 -275.565616)
		(width 0.13208)
		(layer "B.Cu")
		(net "SMB_PEX0_FPGA_SCL")
	)
	(segment
		(start 98.608642 -254.91059)
		(end 97.015554 -253.317502)
		(width 0.13208)
		(layer "B.Cu")
		(net "SMB_PEX0_FPGA_SCL")
	)
	(segment
		(start 93.03893 -236.561884)
		(end 93.631004 -236.561884)
		(width 0.13208)
		(layer "B.Cu")
		(net "SMB_PEX0_FPGA_SCL")
	)
	(segment
		(start 97.838006 -264.062972)
		(end 98.608642 -263.292336)
		(width 0.13208)
		(layer "B.Cu")
		(net "SMB_PEX0_FPGA_SCL")
	)
	(segment
		(start 97.838006 -275.565616)
		(end 97.838006 -264.062972)
		(width 0.13208)
		(layer "B.Cu")
		(net "SMB_PEX0_FPGA_SCL")
	)
	(segment
		(start 91.851734 -288.221166)
		(end 91.851734 -281.551888)
		(width 0.13208)
		(layer "B.Cu")
		(net "SMB_PEX0_FPGA_SCL")
	)
	(segment
		(start 90.39225 -247.950228)
		(end 90.39225 -239.208564)
		(width 0.13208)
		(layer "B.Cu")
		(net "SMB_PEX0_FPGA_SCL")
	)
	(segment
		(start 92.557346 -210.965796)
		(end 92.557346 -235.488226)
		(width 0.15494)
		(layer "In5.Cu")
		(net "SMB_PEX0_FPGA_SCL")
	)
	(segment
		(start 92.885514 -210.637628)
		(end 92.557346 -210.965796)
		(width 0.15494)
		(layer "In5.Cu")
		(net "SMB_PEX0_FPGA_SCL")
	)
	(segment
		(start 92.885514 -207.042258)
		(end 92.885514 -210.637628)
		(width 0.15494)
		(layer "In5.Cu")
		(net "SMB_PEX0_FPGA_SCL")
	)
	(segment
		(start 92.557346 -235.488226)
		(end 93.631004 -236.561884)
		(width 0.15494)
		(layer "In5.Cu")
		(net "SMB_PEX0_FPGA_SCL")
	)
	(segment
		(start 310.12511 -230.974392)
		(end 311.631076 -229.468426)
		(width 0.15494)
		(layer "In13.Cu")
		(net "SMB_PEX0_FPGA_SCL")
	)
	(segment
		(start 139.023344 -213.52637)
		(end 139.023344 -213.511892)
		(width 0.15494)
		(layer "In13.Cu")
		(net "SMB_PEX0_FPGA_SCL")
	)
	(segment
		(start 326.990202 -230.51516)
		(end 331.053694 -230.51516)
		(width 0.15494)
		(layer "In13.Cu")
		(net "SMB_PEX0_FPGA_SCL")
	)
	(segment
		(start 247.463564 -219.447364)
		(end 255.083564 -219.447364)
		(width 0.15494)
		(layer "In13.Cu")
		(net "SMB_PEX0_FPGA_SCL")
	)
	(segment
		(start 256.662936 -221.026736)
		(end 260.193536 -221.026736)
		(width 0.15494)
		(layer "In13.Cu")
		(net "SMB_PEX0_FPGA_SCL")
	)
	(segment
		(start 222.819468 -208.38922)
		(end 230.517954 -208.38922)
		(width 0.15494)
		(layer "In13.Cu")
		(net "SMB_PEX0_FPGA_SCL")
	)
	(segment
		(start 140.637514 -214.1728)
		(end 143.079724 -214.1728)
		(width 0.15494)
		(layer "In13.Cu")
		(net "SMB_PEX0_FPGA_SCL")
	)
	(segment
		(start 211.7852 -213.1568)
		(end 213.791546 -213.1568)
		(width 0.15494)
		(layer "In13.Cu")
		(net "SMB_PEX0_FPGA_SCL")
	)
	(segment
		(start 232.484422 -209.20329)
		(end 235.670344 -209.20329)
		(width 0.15494)
		(layer "In13.Cu")
		(net "SMB_PEX0_FPGA_SCL")
	)
	(segment
		(start 190.82512 -213.269068)
		(end 193.743834 -210.350354)
		(width 0.15494)
		(layer "In13.Cu")
		(net "SMB_PEX0_FPGA_SCL")
	)
	(segment
		(start 230.517954 -208.38922)
		(end 232.484422 -209.20329)
		(width 0.15494)
		(layer "In13.Cu")
		(net "SMB_PEX0_FPGA_SCL")
	)
	(segment
		(start 241.51336 -212.092286)
		(end 241.51336 -213.894162)
		(width 0.15494)
		(layer "In13.Cu")
		(net "SMB_PEX0_FPGA_SCL")
	)
	(segment
		(start 143.079724 -214.1728)
		(end 143.983456 -213.269068)
		(width 0.15494)
		(layer "In13.Cu")
		(net "SMB_PEX0_FPGA_SCL")
	)
	(segment
		(start 139.306554 -213.228682)
		(end 139.707874 -213.228682)
		(width 0.15494)
		(layer "In13.Cu")
		(net "SMB_PEX0_FPGA_SCL")
	)
	(segment
		(start 123.012454 -213.230714)
		(end 126.84506 -213.230714)
		(width 0.15494)
		(layer "In13.Cu")
		(net "SMB_PEX0_FPGA_SCL")
	)
	(segment
		(start 116.93398 -207.15224)
		(end 123.012454 -213.230714)
		(width 0.15494)
		(layer "In13.Cu")
		(net "SMB_PEX0_FPGA_SCL")
	)
	(segment
		(start 216.465404 -211.696554)
		(end 217.49385 -212.725)
		(width 0.15494)
		(layer "In13.Cu")
		(net "SMB_PEX0_FPGA_SCL")
	)
	(segment
		(start 207.429608 -210.350354)
		(end 208.553304 -211.47405)
		(width 0.15494)
		(layer "In13.Cu")
		(net "SMB_PEX0_FPGA_SCL")
	)
	(segment
		(start 255.083564 -219.447364)
		(end 256.662936 -221.026736)
		(width 0.15494)
		(layer "In13.Cu")
		(net "SMB_PEX0_FPGA_SCL")
	)
	(segment
		(start 116.85778 -207.13954)
		(end 116.87048 -207.15224)
		(width 0.15494)
		(layer "In13.Cu")
		(net "SMB_PEX0_FPGA_SCL")
	)
	(segment
		(start 336.820764 -227.6602)
		(end 337.694016 -226.786948)
		(width 0.15494)
		(layer "In13.Cu")
		(net "SMB_PEX0_FPGA_SCL")
	)
	(segment
		(start 133.223 -213.5886)
		(end 138.961114 -213.5886)
		(width 0.15494)
		(layer "In13.Cu")
		(net "SMB_PEX0_FPGA_SCL")
	)
	(segment
		(start 128.015746 -214.4014)
		(end 132.4102 -214.4014)
		(width 0.15494)
		(layer "In13.Cu")
		(net "SMB_PEX0_FPGA_SCL")
	)
	(segment
		(start 98.628454 -207.4672)
		(end 98.956114 -207.13954)
		(width 0.15494)
		(layer "In13.Cu")
		(net "SMB_PEX0_FPGA_SCL")
	)
	(segment
		(start 332.1812 -227.9904)
		(end 332.5114 -227.6602)
		(width 0.15494)
		(layer "In13.Cu")
		(net "SMB_PEX0_FPGA_SCL")
	)
	(segment
		(start 210.540854 -212.4202)
		(end 211.0486 -212.4202)
		(width 0.15494)
		(layer "In13.Cu")
		(net "SMB_PEX0_FPGA_SCL")
	)
	(segment
		(start 139.991084 -213.511892)
		(end 139.991084 -213.52637)
		(width 0.15494)
		(layer "In13.Cu")
		(net "SMB_PEX0_FPGA_SCL")
	)
	(segment
		(start 323.77888 -229.468426)
		(end 324.249288 -229.938834)
		(width 0.15494)
		(layer "In13.Cu")
		(net "SMB_PEX0_FPGA_SCL")
	)
	(segment
		(start 331.053694 -230.51516)
		(end 332.1812 -229.387654)
		(width 0.15494)
		(layer "In13.Cu")
		(net "SMB_PEX0_FPGA_SCL")
	)
	(segment
		(start 217.49385 -212.725)
		(end 219.6592 -212.725)
		(width 0.15494)
		(layer "In13.Cu")
		(net "SMB_PEX0_FPGA_SCL")
	)
	(segment
		(start 243.205 -215.1888)
		(end 247.463564 -219.447364)
		(width 0.15494)
		(layer "In13.Cu")
		(net "SMB_PEX0_FPGA_SCL")
	)
	(segment
		(start 220.93301 -210.048348)
		(end 222.431102 -208.550256)
		(width 0.15494)
		(layer "In13.Cu")
		(net "SMB_PEX0_FPGA_SCL")
	)
	(segment
		(start 235.670344 -209.20329)
		(end 236.568234 -210.10118)
		(width 0.15494)
		(layer "In13.Cu")
		(net "SMB_PEX0_FPGA_SCL")
	)
	(segment
		(start 332.1812 -229.387654)
		(end 332.1812 -227.9904)
		(width 0.15494)
		(layer "In13.Cu")
		(net "SMB_PEX0_FPGA_SCL")
	)
	(segment
		(start 211.0486 -212.4202)
		(end 211.7852 -213.1568)
		(width 0.15494)
		(layer "In13.Cu")
		(net "SMB_PEX0_FPGA_SCL")
	)
	(segment
		(start 98.956114 -207.13954)
		(end 116.85778 -207.13954)
		(width 0.15494)
		(layer "In13.Cu")
		(net "SMB_PEX0_FPGA_SCL")
	)
	(segment
		(start 219.6592 -212.725)
		(end 220.93301 -211.45119)
		(width 0.15494)
		(layer "In13.Cu")
		(net "SMB_PEX0_FPGA_SCL")
	)
	(segment
		(start 139.023344 -213.511892)
		(end 139.306554 -213.228682)
		(width 0.15494)
		(layer "In13.Cu")
		(net "SMB_PEX0_FPGA_SCL")
	)
	(segment
		(start 326.413876 -229.938834)
		(end 326.990202 -230.51516)
		(width 0.15494)
		(layer "In13.Cu")
		(net "SMB_PEX0_FPGA_SCL")
	)
	(segment
		(start 94.7166 -206.375)
		(end 95.8088 -207.4672)
		(width 0.15494)
		(layer "In13.Cu")
		(net "SMB_PEX0_FPGA_SCL")
	)
	(segment
		(start 332.5114 -227.6602)
		(end 336.820764 -227.6602)
		(width 0.15494)
		(layer "In13.Cu")
		(net "SMB_PEX0_FPGA_SCL")
	)
	(segment
		(start 222.431102 -208.550256)
		(end 222.819468 -208.38922)
		(width 0.15494)
		(layer "In13.Cu")
		(net "SMB_PEX0_FPGA_SCL")
	)
	(segment
		(start 208.553304 -211.47405)
		(end 209.594704 -211.47405)
		(width 0.15494)
		(layer "In13.Cu")
		(net "SMB_PEX0_FPGA_SCL")
	)
	(segment
		(start 132.4102 -214.4014)
		(end 133.223 -213.5886)
		(width 0.15494)
		(layer "In13.Cu")
		(net "SMB_PEX0_FPGA_SCL")
	)
	(segment
		(start 143.983456 -213.269068)
		(end 190.82512 -213.269068)
		(width 0.15494)
		(layer "In13.Cu")
		(net "SMB_PEX0_FPGA_SCL")
	)
	(segment
		(start 116.87048 -207.15224)
		(end 116.93398 -207.15224)
		(width 0.15494)
		(layer "In13.Cu")
		(net "SMB_PEX0_FPGA_SCL")
	)
	(segment
		(start 209.594704 -211.47405)
		(end 210.540854 -212.4202)
		(width 0.15494)
		(layer "In13.Cu")
		(net "SMB_PEX0_FPGA_SCL")
	)
	(segment
		(start 236.568234 -210.10118)
		(end 239.522254 -210.10118)
		(width 0.15494)
		(layer "In13.Cu")
		(net "SMB_PEX0_FPGA_SCL")
	)
	(segment
		(start 277.761192 -230.974392)
		(end 310.12511 -230.974392)
		(width 0.15494)
		(layer "In13.Cu")
		(net "SMB_PEX0_FPGA_SCL")
	)
	(segment
		(start 269.621 -222.8342)
		(end 277.761192 -230.974392)
		(width 0.15494)
		(layer "In13.Cu")
		(net "SMB_PEX0_FPGA_SCL")
	)
	(segment
		(start 242.807998 -215.1888)
		(end 243.205 -215.1888)
		(width 0.15494)
		(layer "In13.Cu")
		(net "SMB_PEX0_FPGA_SCL")
	)
	(segment
		(start 239.522254 -210.10118)
		(end 241.51336 -212.092286)
		(width 0.15494)
		(layer "In13.Cu")
		(net "SMB_PEX0_FPGA_SCL")
	)
	(segment
		(start 241.51336 -213.894162)
		(end 242.807998 -215.1888)
		(width 0.15494)
		(layer "In13.Cu")
		(net "SMB_PEX0_FPGA_SCL")
	)
	(segment
		(start 260.193536 -221.026736)
		(end 262.001 -222.8342)
		(width 0.15494)
		(layer "In13.Cu")
		(net "SMB_PEX0_FPGA_SCL")
	)
	(segment
		(start 138.961114 -213.5886)
		(end 139.023344 -213.52637)
		(width 0.15494)
		(layer "In13.Cu")
		(net "SMB_PEX0_FPGA_SCL")
	)
	(segment
		(start 93.552772 -206.375)
		(end 94.7166 -206.375)
		(width 0.15494)
		(layer "In13.Cu")
		(net "SMB_PEX0_FPGA_SCL")
	)
	(segment
		(start 126.84506 -213.230714)
		(end 128.015746 -214.4014)
		(width 0.15494)
		(layer "In13.Cu")
		(net "SMB_PEX0_FPGA_SCL")
	)
	(segment
		(start 215.251792 -211.696554)
		(end 216.465404 -211.696554)
		(width 0.15494)
		(layer "In13.Cu")
		(net "SMB_PEX0_FPGA_SCL")
	)
	(segment
		(start 220.93301 -211.45119)
		(end 220.93301 -210.048348)
		(width 0.15494)
		(layer "In13.Cu")
		(net "SMB_PEX0_FPGA_SCL")
	)
	(segment
		(start 139.707874 -213.228682)
		(end 139.991084 -213.511892)
		(width 0.15494)
		(layer "In13.Cu")
		(net "SMB_PEX0_FPGA_SCL")
	)
	(segment
		(start 92.885514 -207.042258)
		(end 93.552772 -206.375)
		(width 0.15494)
		(layer "In13.Cu")
		(net "SMB_PEX0_FPGA_SCL")
	)
	(segment
		(start 193.743834 -210.350354)
		(end 207.429608 -210.350354)
		(width 0.15494)
		(layer "In13.Cu")
		(net "SMB_PEX0_FPGA_SCL")
	)
	(segment
		(start 324.249288 -229.938834)
		(end 326.413876 -229.938834)
		(width 0.15494)
		(layer "In13.Cu")
		(net "SMB_PEX0_FPGA_SCL")
	)
	(segment
		(start 213.791546 -213.1568)
		(end 215.251792 -211.696554)
		(width 0.15494)
		(layer "In13.Cu")
		(net "SMB_PEX0_FPGA_SCL")
	)
	(segment
		(start 311.631076 -229.468426)
		(end 323.77888 -229.468426)
		(width 0.15494)
		(layer "In13.Cu")
		(net "SMB_PEX0_FPGA_SCL")
	)
	(segment
		(start 95.8088 -207.4672)
		(end 98.628454 -207.4672)
		(width 0.15494)
		(layer "In13.Cu")
		(net "SMB_PEX0_FPGA_SCL")
	)
	(segment
		(start 262.001 -222.8342)
		(end 269.621 -222.8342)
		(width 0.15494)
		(layer "In13.Cu")
		(net "SMB_PEX0_FPGA_SCL")
	)
	(segment
		(start 139.991084 -213.52637)
		(end 140.637514 -214.1728)
		(width 0.15494)
		(layer "In13.Cu")
		(net "SMB_PEX0_FPGA_SCL")
	)
	(segment
		(start 357.61295 -219.456)
		(end 356.108 -219.456)
		(width 0.13208)
		(layer "F.Cu")
		(net "RST_NIC6_PERST_N")
	)
	(segment
		(start 346.893896 -218.387168)
		(end 347.293692 -217.987372)
		(width 0.13208)
		(layer "F.Cu")
		(net "RST_NIC6_PERST_N")
	)
	(via
		(at 356.108 -219.456)
		(size 0.508)
		(drill 0.254)
		(layers "F.Cu" "B.Cu")
		(net "RST_NIC6_PERST_N")
	)
	(via
		(at 347.293692 -217.987372)
		(size 0.4572)
		(drill 0.254)
		(layers "F.Cu" "B.Cu")
		(net "RST_NIC6_PERST_N")
	)
	(segment
		(start 355.161342 -218.509342)
		(end 354.38588 -218.509342)
		(width 0.15494)
		(layer "In9.Cu")
		(net "RST_NIC6_PERST_N")
	)
	(segment
		(start 356.108 -219.456)
		(end 355.161342 -218.509342)
		(width 0.15494)
		(layer "In9.Cu")
		(net "RST_NIC6_PERST_N")
	)
	(segment
		(start 354.38588 -218.509342)
		(end 353.56546 -219.329762)
		(width 0.15494)
		(layer "In9.Cu")
		(net "RST_NIC6_PERST_N")
	)
	(segment
		(start 347.691202 -219.014802)
		(end 347.691202 -218.384882)
		(width 0.0889)
		(layer "In9.Cu")
		(net "RST_NIC6_PERST_N")
	)
	(segment
		(start 353.56546 -219.329762)
		(end 348.006162 -219.329762)
		(width 0.15494)
		(layer "In9.Cu")
		(net "RST_NIC6_PERST_N")
	)
	(segment
		(start 348.006162 -219.329762)
		(end 347.691202 -219.014802)
		(width 0.15494)
		(layer "In9.Cu")
		(net "RST_NIC6_PERST_N")
	)
	(segment
		(start 347.691202 -218.384882)
		(end 347.293692 -217.987372)
		(width 0.0889)
		(layer "In9.Cu")
		(net "RST_NIC6_PERST_N")
	)
	(segment
		(start 372.6307 -53.144166)
		(end 372.780052 -52.994814)
		(width 0.13208)
		(layer "F.Cu")
		(net "P12V_SSD12_SS")
	)
	(segment
		(start 372.780052 -52.994814)
		(end 372.780052 -51.670966)
		(width 0.13208)
		(layer "F.Cu")
		(net "P12V_SSD12_SS")
	)
	(segment
		(start 373.431562 -51.019456)
		(end 374.167908 -51.019456)
		(width 0.13208)
		(layer "F.Cu")
		(net "P12V_SSD12_SS")
	)
	(segment
		(start 372.780052 -51.670966)
		(end 373.431562 -51.019456)
		(width 0.13208)
		(layer "F.Cu")
		(net "P12V_SSD12_SS")
	)
	(segment
		(start 372.447312 -53.144166)
		(end 372.6307 -53.144166)
		(width 0.13208)
		(layer "F.Cu")
		(net "P12V_SSD12_SS")
	)
	(via
		(at 373.431562 -51.019456)
		(size 0.508)
		(drill 0.254)
		(layers "F.Cu" "B.Cu")
		(net "P12V_SSD12_SS")
	)
	(segment
		(start 381.855472 -232.030016)
		(end 381.855472 -232.836212)
		(width 0.13208)
		(layer "F.Cu")
		(net "OSC_SDB_OUT")
	)
	(segment
		(start 384.274314 -229.16896)
		(end 384.564128 -228.879146)
		(width 0.13208)
		(layer "F.Cu")
		(net "OSC_SDB_OUT")
	)
	(segment
		(start 384.564128 -227.897944)
		(end 383.951734 -227.28555)
		(width 0.13208)
		(layer "F.Cu")
		(net "OSC_SDB_OUT")
	)
	(segment
		(start 384.564128 -228.879146)
		(end 384.564128 -227.897944)
		(width 0.13208)
		(layer "F.Cu")
		(net "OSC_SDB_OUT")
	)
	(segment
		(start 383.951734 -227.28555)
		(end 383.88671 -227.28555)
		(width 0.13208)
		(layer "F.Cu")
		(net "OSC_SDB_OUT")
	)
	(segment
		(start 382.068832 -229.41661)
		(end 382.316482 -229.16896)
		(width 0.13208)
		(layer "F.Cu")
		(net "OSC_SDB_OUT")
	)
	(segment
		(start 382.068832 -230.43896)
		(end 382.068832 -229.41661)
		(width 0.13208)
		(layer "F.Cu")
		(net "OSC_SDB_OUT")
	)
	(segment
		(start 382.068832 -230.43896)
		(end 382.068832 -231.07396)
		(width 0.13208)
		(layer "F.Cu")
		(net "OSC_SDB_OUT")
	)
	(segment
		(start 382.068832 -231.816656)
		(end 381.855472 -232.030016)
		(width 0.13208)
		(layer "F.Cu")
		(net "OSC_SDB_OUT")
	)
	(segment
		(start 382.316482 -229.16896)
		(end 384.274314 -229.16896)
		(width 0.13208)
		(layer "F.Cu")
		(net "OSC_SDB_OUT")
	)
	(segment
		(start 382.068832 -231.07396)
		(end 382.068832 -231.816656)
		(width 0.13208)
		(layer "F.Cu")
		(net "OSC_SDB_OUT")
	)
	(via
		(at 382.068832 -231.07396)
		(size 0.508)
		(drill 0.254)
		(layers "F.Cu" "B.Cu")
		(net "OSC_SDB_OUT")
	)
	(segment
		(start 90.22461 -310.68518)
		(end 90.632788 -310.277002)
		(width 0.13208)
		(layer "F.Cu")
		(net "PEX0_SPARE0")
	)
	(segment
		(start 89.964768 -310.945022)
		(end 90.22461 -310.68518)
		(width 0.13208)
		(layer "F.Cu")
		(net "PEX0_SPARE0")
	)
	(segment
		(start 89.497408 -310.945022)
		(end 89.964768 -310.945022)
		(width 0.13208)
		(layer "F.Cu")
		(net "PEX0_SPARE0")
	)
	(segment
		(start 90.632788 -310.277002)
		(end 90.632788 -310.043322)
		(width 0.13208)
		(layer "F.Cu")
		(net "PEX0_SPARE0")
	)
	(segment
		(start 61.074808 -308.724808)
		(end 60.599828 -308.249828)
		(width 0.13208)
		(layer "F.Cu")
		(net "PEX0_SPARE0")
	)
	(via
		(at 87.16645 -314.33389)
		(size 0.6604)
		(drill 0.3302)
		(layers "F.Cu" "B.Cu")
		(net "PEX0_SPARE0")
	)
	(via
		(at 61.074808 -308.724808)
		(size 0.4064)
		(drill 0.2032)
		(layers "F.Cu" "B.Cu")
		(net "PEX0_SPARE0")
	)
	(via
		(at 90.22461 -310.68518)
		(size 0.508)
		(drill 0.254)
		(layers "F.Cu" "B.Cu")
		(net "PEX0_SPARE0")
	)
	(segment
		(start 62.164722 -315.379862)
		(end 86.120478 -315.379862)
		(width 0.13208)
		(layer "B.Cu")
		(net "PEX0_SPARE0")
	)
	(segment
		(start 62.037722 -315.252862)
		(end 62.164722 -315.379862)
		(width 0.13208)
		(layer "B.Cu")
		(net "PEX0_SPARE0")
	)
	(segment
		(start 61.526674 -309.740046)
		(end 61.797184 -309.740046)
		(width 0.13208)
		(layer "B.Cu")
		(net "PEX0_SPARE0")
	)
	(segment
		(start 86.120478 -315.379862)
		(end 87.16645 -314.33389)
		(width 0.13208)
		(layer "B.Cu")
		(net "PEX0_SPARE0")
	)
	(segment
		(start 62.037722 -309.980584)
		(end 62.037722 -315.252862)
		(width 0.13208)
		(layer "B.Cu")
		(net "PEX0_SPARE0")
	)
	(segment
		(start 90.22461 -311.27573)
		(end 87.16645 -314.33389)
		(width 0.13208)
		(layer "B.Cu")
		(net "PEX0_SPARE0")
	)
	(segment
		(start 61.074808 -309.28818)
		(end 61.526674 -309.740046)
		(width 0.13208)
		(layer "B.Cu")
		(net "PEX0_SPARE0")
	)
	(segment
		(start 61.074808 -308.724808)
		(end 61.074808 -309.28818)
		(width 0.13208)
		(layer "B.Cu")
		(net "PEX0_SPARE0")
	)
	(segment
		(start 61.797184 -309.740046)
		(end 62.037722 -309.980584)
		(width 0.13208)
		(layer "B.Cu")
		(net "PEX0_SPARE0")
	)
	(segment
		(start 90.22461 -310.68518)
		(end 90.22461 -311.27573)
		(width 0.13208)
		(layer "B.Cu")
		(net "PEX0_SPARE0")
	)
	(segment
		(start 52.317904 -21.775674)
		(end 52.285392 -21.743162)
		(width 0.13208)
		(layer "F.Cu")
		(net "SMB_BIC_I2C9_MUX0_SSD1_R_SCL")
	)
	(segment
		(start 122.357896 -93.748606)
		(end 121.53519 -93.748606)
		(width 0.13208)
		(layer "F.Cu")
		(net "SMB_BIC_I2C9_MUX0_SSD1_R_SCL")
	)
	(segment
		(start 123.27509 -93.748606)
		(end 122.357896 -93.748606)
		(width 0.13208)
		(layer "F.Cu")
		(net "SMB_BIC_I2C9_MUX0_SSD1_R_SCL")
	)
	(segment
		(start 52.459382 -22.555454)
		(end 52.317904 -22.413976)
		(width 0.13208)
		(layer "F.Cu")
		(net "SMB_BIC_I2C9_MUX0_SSD1_R_SCL")
	)
	(segment
		(start 52.285392 -21.743162)
		(end 52.285392 -20.789392)
		(width 0.13208)
		(layer "F.Cu")
		(net "SMB_BIC_I2C9_MUX0_SSD1_R_SCL")
	)
	(segment
		(start 52.317904 -22.413976)
		(end 52.317904 -21.775674)
		(width 0.13208)
		(layer "F.Cu")
		(net "SMB_BIC_I2C9_MUX0_SSD1_R_SCL")
	)
	(via
		(at 122.357896 -93.748606)
		(size 0.508)
		(drill 0.254)
		(layers "F.Cu" "B.Cu")
		(net "SMB_BIC_I2C9_MUX0_SSD1_R_SCL")
	)
	(via
		(at 52.317904 -21.775674)
		(size 0.508)
		(drill 0.254)
		(layers "F.Cu" "B.Cu")
		(net "SMB_BIC_I2C9_MUX0_SSD1_R_SCL")
	)
	(via
		(at 60.011056 -86.993476)
		(size 0.508)
		(drill 0.254)
		(layers "F.Cu" "B.Cu")
		(net "SMB_BIC_I2C9_MUX0_SSD1_R_SCL")
	)
	(segment
		(start 60.775088 -86.229444)
		(end 60.775088 -66.732658)
		(width 0.15494)
		(layer "In5.Cu")
		(net "SMB_BIC_I2C9_MUX0_SSD1_R_SCL")
	)
	(segment
		(start 51.813714 -21.775674)
		(end 52.317904 -21.775674)
		(width 0.15494)
		(layer "In5.Cu")
		(net "SMB_BIC_I2C9_MUX0_SSD1_R_SCL")
	)
	(segment
		(start 63.85306 -45.243496)
		(end 52.326794 -33.71723)
		(width 0.15494)
		(layer "In5.Cu")
		(net "SMB_BIC_I2C9_MUX0_SSD1_R_SCL")
	)
	(segment
		(start 50.740056 -26.520648)
		(end 50.740056 -22.849332)
		(width 0.15494)
		(layer "In5.Cu")
		(net "SMB_BIC_I2C9_MUX0_SSD1_R_SCL")
	)
	(segment
		(start 52.326794 -33.71723)
		(end 52.326794 -28.107386)
		(width 0.15494)
		(layer "In5.Cu")
		(net "SMB_BIC_I2C9_MUX0_SSD1_R_SCL")
	)
	(segment
		(start 52.326794 -28.107386)
		(end 50.740056 -26.520648)
		(width 0.15494)
		(layer "In5.Cu")
		(net "SMB_BIC_I2C9_MUX0_SSD1_R_SCL")
	)
	(segment
		(start 50.740056 -22.849332)
		(end 51.813714 -21.775674)
		(width 0.15494)
		(layer "In5.Cu")
		(net "SMB_BIC_I2C9_MUX0_SSD1_R_SCL")
	)
	(segment
		(start 60.011056 -86.993476)
		(end 60.775088 -86.229444)
		(width 0.15494)
		(layer "In5.Cu")
		(net "SMB_BIC_I2C9_MUX0_SSD1_R_SCL")
	)
	(segment
		(start 60.775088 -66.732658)
		(end 63.85306 -63.654686)
		(width 0.15494)
		(layer "In5.Cu")
		(net "SMB_BIC_I2C9_MUX0_SSD1_R_SCL")
	)
	(segment
		(start 63.85306 -63.654686)
		(end 63.85306 -45.243496)
		(width 0.15494)
		(layer "In5.Cu")
		(net "SMB_BIC_I2C9_MUX0_SSD1_R_SCL")
	)
	(segment
		(start 120.660922 -92.051632)
		(end 122.357896 -93.748606)
		(width 0.15494)
		(layer "In15.Cu")
		(net "SMB_BIC_I2C9_MUX0_SSD1_R_SCL")
	)
	(segment
		(start 98.74885 -88.798654)
		(end 103.5558 -88.798654)
		(width 0.15494)
		(layer "In15.Cu")
		(net "SMB_BIC_I2C9_MUX0_SSD1_R_SCL")
	)
	(segment
		(start 79.134462 -92.215716)
		(end 83.559904 -92.215716)
		(width 0.15494)
		(layer "In15.Cu")
		(net "SMB_BIC_I2C9_MUX0_SSD1_R_SCL")
	)
	(segment
		(start 103.5558 -88.798654)
		(end 104.206548 -89.449402)
		(width 0.15494)
		(layer "In15.Cu")
		(net "SMB_BIC_I2C9_MUX0_SSD1_R_SCL")
	)
	(segment
		(start 60.011056 -86.993476)
		(end 73.912222 -86.993476)
		(width 0.15494)
		(layer "In15.Cu")
		(net "SMB_BIC_I2C9_MUX0_SSD1_R_SCL")
	)
	(segment
		(start 73.912222 -86.993476)
		(end 79.134462 -92.215716)
		(width 0.15494)
		(layer "In15.Cu")
		(net "SMB_BIC_I2C9_MUX0_SSD1_R_SCL")
	)
	(segment
		(start 83.559904 -92.215716)
		(end 87.371936 -88.403684)
		(width 0.15494)
		(layer "In15.Cu")
		(net "SMB_BIC_I2C9_MUX0_SSD1_R_SCL")
	)
	(segment
		(start 104.206548 -89.449402)
		(end 105.973372 -89.449402)
		(width 0.15494)
		(layer "In15.Cu")
		(net "SMB_BIC_I2C9_MUX0_SSD1_R_SCL")
	)
	(segment
		(start 98.35388 -88.403684)
		(end 98.74885 -88.798654)
		(width 0.15494)
		(layer "In15.Cu")
		(net "SMB_BIC_I2C9_MUX0_SSD1_R_SCL")
	)
	(segment
		(start 105.973372 -89.449402)
		(end 108.347764 -91.823794)
		(width 0.15494)
		(layer "In15.Cu")
		(net "SMB_BIC_I2C9_MUX0_SSD1_R_SCL")
	)
	(segment
		(start 115.728496 -91.823794)
		(end 115.956334 -92.051632)
		(width 0.15494)
		(layer "In15.Cu")
		(net "SMB_BIC_I2C9_MUX0_SSD1_R_SCL")
	)
	(segment
		(start 108.347764 -91.823794)
		(end 115.728496 -91.823794)
		(width 0.15494)
		(layer "In15.Cu")
		(net "SMB_BIC_I2C9_MUX0_SSD1_R_SCL")
	)
	(segment
		(start 87.371936 -88.403684)
		(end 98.35388 -88.403684)
		(width 0.15494)
		(layer "In15.Cu")
		(net "SMB_BIC_I2C9_MUX0_SSD1_R_SCL")
	)
	(segment
		(start 115.956334 -92.051632)
		(end 120.660922 -92.051632)
		(width 0.15494)
		(layer "In15.Cu")
		(net "SMB_BIC_I2C9_MUX0_SSD1_R_SCL")
	)
	(segment
		(start 282.224226 -18.437098)
		(end 282.267914 -18.437098)
		(width 0.13208)
		(layer "F.Cu")
		(net "SMB_ISO_SSD9_SCL")
	)
	(segment
		(start 284.485334 -15.370302)
		(end 284.485334 -16.439388)
		(width 0.13208)
		(layer "F.Cu")
		(net "SMB_ISO_SSD9_SCL")
	)
	(segment
		(start 283.954982 -18.990818)
		(end 282.821634 -18.990818)
		(width 0.13208)
		(layer "F.Cu")
		(net "SMB_ISO_SSD9_SCL")
	)
	(segment
		(start 284.659324 -23.355554)
		(end 284.659324 -23.965154)
		(width 0.13208)
		(layer "F.Cu")
		(net "SMB_ISO_SSD9_SCL")
	)
	(segment
		(start 282.821634 -18.990818)
		(end 282.267914 -18.437098)
		(width 0.13208)
		(layer "F.Cu")
		(net "SMB_ISO_SSD9_SCL")
	)
	(segment
		(start 284.485334 -18.460466)
		(end 283.954982 -18.990818)
		(width 0.13208)
		(layer "F.Cu")
		(net "SMB_ISO_SSD9_SCL")
	)
	(segment
		(start 281.456384 -17.419574)
		(end 281.456384 -17.669256)
		(width 0.13208)
		(layer "F.Cu")
		(net "SMB_ISO_SSD9_SCL")
	)
	(segment
		(start 284.485334 -16.439388)
		(end 284.485334 -18.460466)
		(width 0.13208)
		(layer "F.Cu")
		(net "SMB_ISO_SSD9_SCL")
	)
	(segment
		(start 281.456384 -17.669256)
		(end 282.224226 -18.437098)
		(width 0.13208)
		(layer "F.Cu")
		(net "SMB_ISO_SSD9_SCL")
	)
	(via
		(at 284.485334 -15.370302)
		(size 0.508)
		(drill 0.254)
		(layers "F.Cu" "B.Cu")
		(net "SMB_ISO_SSD9_SCL")
	)
	(via
		(at 284.659324 -23.965154)
		(size 0.508)
		(drill 0.254)
		(layers "F.Cu" "B.Cu")
		(net "SMB_ISO_SSD9_SCL")
	)
	(segment
		(start 285.905702 -22.718776)
		(end 285.905702 -16.79067)
		(width 0.13208)
		(layer "B.Cu")
		(net "SMB_ISO_SSD9_SCL")
	)
	(segment
		(start 284.659324 -23.965154)
		(end 285.905702 -22.718776)
		(width 0.13208)
		(layer "B.Cu")
		(net "SMB_ISO_SSD9_SCL")
	)
	(segment
		(start 285.905702 -16.79067)
		(end 284.485334 -15.370302)
		(width 0.13208)
		(layer "B.Cu")
		(net "SMB_ISO_SSD9_SCL")
	)
	(segment
		(start 342.893904 -223.187006)
		(end 343.2937 -223.586802)
		(width 0.13208)
		(layer "F.Cu")
		(net "SMB_FPGA_ALERT_N")
	)
	(segment
		(start 345.934792 -240.291112)
		(end 345.934792 -239.675162)
		(width 0.13208)
		(layer "F.Cu")
		(net "SMB_FPGA_ALERT_N")
	)
	(via
		(at 345.934792 -239.675162)
		(size 0.508)
		(drill 0.254)
		(layers "F.Cu" "B.Cu")
		(net "SMB_FPGA_ALERT_N")
	)
	(via
		(at 343.2937 -223.586802)
		(size 0.4572)
		(drill 0.254)
		(layers "F.Cu" "B.Cu")
		(net "SMB_FPGA_ALERT_N")
	)
	(segment
		(start 343.2937 -223.604582)
		(end 343.2937 -223.586802)
		(width 0.15494)
		(layer "In7.Cu")
		(net "SMB_FPGA_ALERT_N")
	)
	(segment
		(start 344.264488 -238.141764)
		(end 344.556334 -237.849918)
		(width 0.15494)
		(layer "In7.Cu")
		(net "SMB_FPGA_ALERT_N")
	)
	(segment
		(start 344.556334 -237.849918)
		(end 344.556334 -233.960924)
		(width 0.15494)
		(layer "In7.Cu")
		(net "SMB_FPGA_ALERT_N")
	)
	(segment
		(start 345.934792 -239.675162)
		(end 345.076526 -239.675162)
		(width 0.15494)
		(layer "In7.Cu")
		(net "SMB_FPGA_ALERT_N")
	)
	(segment
		(start 344.556334 -233.960924)
		(end 342.776048 -232.180638)
		(width 0.15494)
		(layer "In7.Cu")
		(net "SMB_FPGA_ALERT_N")
	)
	(segment
		(start 342.776048 -232.180638)
		(end 342.776048 -224.122234)
		(width 0.15494)
		(layer "In7.Cu")
		(net "SMB_FPGA_ALERT_N")
	)
	(segment
		(start 342.776048 -224.122234)
		(end 343.2937 -223.604582)
		(width 0.15494)
		(layer "In7.Cu")
		(net "SMB_FPGA_ALERT_N")
	)
	(segment
		(start 344.264488 -238.863124)
		(end 344.264488 -238.141764)
		(width 0.15494)
		(layer "In7.Cu")
		(net "SMB_FPGA_ALERT_N")
	)
	(segment
		(start 345.076526 -239.675162)
		(end 344.264488 -238.863124)
		(width 0.15494)
		(layer "In7.Cu")
		(net "SMB_FPGA_ALERT_N")
	)
	(segment
		(start 354.838 -167.64)
		(end 354.22205 -167.64)
		(width 0.13208)
		(layer "F.Cu")
		(net "RST_PEX_NIC5_PERST_R_N")
	)
	(segment
		(start 355.45395 -167.64)
		(end 354.838 -167.64)
		(width 0.13208)
		(layer "F.Cu")
		(net "RST_PEX_NIC5_PERST_R_N")
	)
	(segment
		(start 348.493842 -214.387176)
		(end 348.893638 -213.98738)
		(width 0.13208)
		(layer "F.Cu")
		(net "RST_PEX_NIC5_PERST_R_N")
	)
	(via
		(at 348.893638 -213.98738)
		(size 0.4572)
		(drill 0.254)
		(layers "F.Cu" "B.Cu")
		(net "RST_PEX_NIC5_PERST_R_N")
	)
	(via
		(at 354.838 -167.64)
		(size 0.508)
		(drill 0.254)
		(layers "F.Cu" "B.Cu")
		(net "RST_PEX_NIC5_PERST_R_N")
	)
	(via
		(at 368.043714 -176.375568)
		(size 0.508)
		(drill 0.254)
		(layers "F.Cu" "B.Cu")
		(net "RST_PEX_NIC5_PERST_R_N")
	)
	(segment
		(start 354.27666 -206.770732)
		(end 354.27666 -205.791054)
		(width 0.15494)
		(layer "In7.Cu")
		(net "RST_PEX_NIC5_PERST_R_N")
	)
	(segment
		(start 348.493588 -213.58733)
		(end 348.493588 -212.897212)
		(width 0.0889)
		(layer "In7.Cu")
		(net "RST_PEX_NIC5_PERST_R_N")
	)
	(segment
		(start 348.603824 -212.786976)
		(end 349.924624 -212.786976)
		(width 0.0889)
		(layer "In7.Cu")
		(net "RST_PEX_NIC5_PERST_R_N")
	)
	(segment
		(start 349.924624 -212.786976)
		(end 350.0374 -212.6742)
		(width 0.0889)
		(layer "In7.Cu")
		(net "RST_PEX_NIC5_PERST_R_N")
	)
	(segment
		(start 366.10671 -195.690744)
		(end 366.10671 -178.312572)
		(width 0.15494)
		(layer "In7.Cu")
		(net "RST_PEX_NIC5_PERST_R_N")
	)
	(segment
		(start 350.0374 -212.6742)
		(end 350.2406 -212.471)
		(width 0.15494)
		(layer "In7.Cu")
		(net "RST_PEX_NIC5_PERST_R_N")
	)
	(segment
		(start 350.951546 -212.471)
		(end 351.79 -211.632546)
		(width 0.15494)
		(layer "In7.Cu")
		(net "RST_PEX_NIC5_PERST_R_N")
	)
	(segment
		(start 355.7524 -204.315314)
		(end 355.7524 -203.149454)
		(width 0.15494)
		(layer "In7.Cu")
		(net "RST_PEX_NIC5_PERST_R_N")
	)
	(segment
		(start 363.833918 -197.963536)
		(end 366.10671 -195.690744)
		(width 0.15494)
		(layer "In7.Cu")
		(net "RST_PEX_NIC5_PERST_R_N")
	)
	(segment
		(start 366.10671 -178.312572)
		(end 368.043714 -176.375568)
		(width 0.15494)
		(layer "In7.Cu")
		(net "RST_PEX_NIC5_PERST_R_N")
	)
	(segment
		(start 350.2406 -212.471)
		(end 350.951546 -212.471)
		(width 0.15494)
		(layer "In7.Cu")
		(net "RST_PEX_NIC5_PERST_R_N")
	)
	(segment
		(start 351.79 -209.257392)
		(end 354.27666 -206.770732)
		(width 0.15494)
		(layer "In7.Cu")
		(net "RST_PEX_NIC5_PERST_R_N")
	)
	(segment
		(start 348.893638 -213.98738)
		(end 348.493588 -213.58733)
		(width 0.0889)
		(layer "In7.Cu")
		(net "RST_PEX_NIC5_PERST_R_N")
	)
	(segment
		(start 348.493588 -212.897212)
		(end 348.603824 -212.786976)
		(width 0.0889)
		(layer "In7.Cu")
		(net "RST_PEX_NIC5_PERST_R_N")
	)
	(segment
		(start 351.79 -211.632546)
		(end 351.79 -209.257392)
		(width 0.15494)
		(layer "In7.Cu")
		(net "RST_PEX_NIC5_PERST_R_N")
	)
	(segment
		(start 354.27666 -205.791054)
		(end 355.7524 -204.315314)
		(width 0.15494)
		(layer "In7.Cu")
		(net "RST_PEX_NIC5_PERST_R_N")
	)
	(segment
		(start 355.7524 -203.149454)
		(end 360.938318 -197.963536)
		(width 0.15494)
		(layer "In7.Cu")
		(net "RST_PEX_NIC5_PERST_R_N")
	)
	(segment
		(start 360.938318 -197.963536)
		(end 363.833918 -197.963536)
		(width 0.15494)
		(layer "In7.Cu")
		(net "RST_PEX_NIC5_PERST_R_N")
	)
	(segment
		(start 357.88473 -170.68673)
		(end 354.838 -167.64)
		(width 0.15494)
		(layer "In13.Cu")
		(net "RST_PEX_NIC5_PERST_R_N")
	)
	(segment
		(start 361.278678 -172.988478)
		(end 358.97693 -170.68673)
		(width 0.15494)
		(layer "In13.Cu")
		(net "RST_PEX_NIC5_PERST_R_N")
	)
	(segment
		(start 364.675166 -175.697896)
		(end 364.318804 -175.341534)
		(width 0.15494)
		(layer "In13.Cu")
		(net "RST_PEX_NIC5_PERST_R_N")
	)
	(segment
		(start 368.043714 -176.375568)
		(end 367.366042 -175.697896)
		(width 0.15494)
		(layer "In13.Cu")
		(net "RST_PEX_NIC5_PERST_R_N")
	)
	(segment
		(start 363.615732 -175.341534)
		(end 362.882942 -176.074324)
		(width 0.15494)
		(layer "In13.Cu")
		(net "RST_PEX_NIC5_PERST_R_N")
	)
	(segment
		(start 367.366042 -175.697896)
		(end 364.675166 -175.697896)
		(width 0.15494)
		(layer "In13.Cu")
		(net "RST_PEX_NIC5_PERST_R_N")
	)
	(segment
		(start 358.97693 -170.68673)
		(end 357.88473 -170.68673)
		(width 0.15494)
		(layer "In13.Cu")
		(net "RST_PEX_NIC5_PERST_R_N")
	)
	(segment
		(start 362.015024 -176.074324)
		(end 361.278678 -175.337978)
		(width 0.15494)
		(layer "In13.Cu")
		(net "RST_PEX_NIC5_PERST_R_N")
	)
	(segment
		(start 364.318804 -175.341534)
		(end 363.615732 -175.341534)
		(width 0.15494)
		(layer "In13.Cu")
		(net "RST_PEX_NIC5_PERST_R_N")
	)
	(segment
		(start 362.882942 -176.074324)
		(end 362.015024 -176.074324)
		(width 0.15494)
		(layer "In13.Cu")
		(net "RST_PEX_NIC5_PERST_R_N")
	)
	(segment
		(start 361.278678 -175.337978)
		(end 361.278678 -172.988478)
		(width 0.15494)
		(layer "In13.Cu")
		(net "RST_PEX_NIC5_PERST_R_N")
	)
	(segment
		(start 377.85294 -235.81106)
		(end 378.880624 -235.81106)
		(width 0.13208)
		(layer "F.Cu")
		(net "FT4232_SDB_EEPROM_SCL")
	)
	(segment
		(start 377.317 -236.347)
		(end 377.85294 -235.81106)
		(width 0.13208)
		(layer "F.Cu")
		(net "FT4232_SDB_EEPROM_SCL")
	)
	(segment
		(start 377.317 -236.855)
		(end 377.317 -236.347)
		(width 0.13208)
		(layer "F.Cu")
		(net "FT4232_SDB_EEPROM_SCL")
	)
	(via
		(at 377.317 -236.855)
		(size 0.508)
		(drill 0.254)
		(layers "F.Cu" "B.Cu")
		(net "FT4232_SDB_EEPROM_SCL")
	)
	(segment
		(start 377.317 -236.855)
		(end 376.599704 -237.572296)
		(width 0.13208)
		(layer "B.Cu")
		(net "FT4232_SDB_EEPROM_SCL")
	)
	(segment
		(start 376.599704 -237.572296)
		(end 375.98858 -237.572296)
		(width 0.13208)
		(layer "B.Cu")
		(net "FT4232_SDB_EEPROM_SCL")
	)
	(segment
		(start 287.679892 -142.9512)
		(end 285.239206 -142.9512)
		(width 0.13208)
		(layer "F.Cu")
		(net "SMB_NIC4_LS_SCL")
	)
	(segment
		(start 285.239206 -142.9512)
		(end 284.888686 -142.60068)
		(width 0.13208)
		(layer "F.Cu")
		(net "SMB_NIC4_LS_SCL")
	)
	(segment
		(start 283.824934 -142.60068)
		(end 283.789374 -142.56512)
		(width 0.13208)
		(layer "F.Cu")
		(net "SMB_NIC4_LS_SCL")
	)
	(segment
		(start 283.789374 -142.56512)
		(end 282.842462 -142.56512)
		(width 0.13208)
		(layer "F.Cu")
		(net "SMB_NIC4_LS_SCL")
	)
	(segment
		(start 284.187138 -142.60068)
		(end 283.824934 -142.60068)
		(width 0.13208)
		(layer "F.Cu")
		(net "SMB_NIC4_LS_SCL")
	)
	(segment
		(start 284.888686 -142.60068)
		(end 284.187138 -142.60068)
		(width 0.13208)
		(layer "F.Cu")
		(net "SMB_NIC4_LS_SCL")
	)
	(via
		(at 215.773 -206.375)
		(size 0.508)
		(drill 0.254)
		(layers "F.Cu" "B.Cu")
		(net "SMB_NIC4_LS_SCL")
	)
	(via
		(at 284.187138 -142.60068)
		(size 0.508)
		(drill 0.254)
		(layers "F.Cu" "B.Cu")
		(net "SMB_NIC4_LS_SCL")
	)
	(via
		(at 254.9906 -159.6898)
		(size 0.508)
		(drill 0.254)
		(layers "F.Cu" "B.Cu")
		(net "SMB_NIC4_LS_SCL")
	)
	(via
		(at 218.862402 -164.249862)
		(size 0.508)
		(drill 0.254)
		(layers "F.Cu" "B.Cu")
		(net "SMB_NIC4_LS_SCL")
	)
	(segment
		(start 215.011 -206.375)
		(end 214.503 -206.883)
		(width 0.13208)
		(layer "B.Cu")
		(net "SMB_NIC4_LS_SCL")
	)
	(segment
		(start 213.46795 -206.883)
		(end 213.106 -206.52105)
		(width 0.13208)
		(layer "B.Cu")
		(net "SMB_NIC4_LS_SCL")
	)
	(segment
		(start 214.503 -206.883)
		(end 213.46795 -206.883)
		(width 0.13208)
		(layer "B.Cu")
		(net "SMB_NIC4_LS_SCL")
	)
	(segment
		(start 215.773 -206.375)
		(end 215.011 -206.375)
		(width 0.13208)
		(layer "B.Cu")
		(net "SMB_NIC4_LS_SCL")
	)
	(segment
		(start 217.4494 -182.122318)
		(end 217.4494 -181.92115)
		(width 0.15494)
		(layer "In7.Cu")
		(net "SMB_NIC4_LS_SCL")
	)
	(segment
		(start 215.773 -204.8256)
		(end 217.297 -203.3016)
		(width 0.15494)
		(layer "In7.Cu")
		(net "SMB_NIC4_LS_SCL")
	)
	(segment
		(start 215.773 -206.375)
		(end 215.773 -204.8256)
		(width 0.15494)
		(layer "In7.Cu")
		(net "SMB_NIC4_LS_SCL")
	)
	(segment
		(start 216.850214 -183.322214)
		(end 216.850214 -182.40629)
		(width 0.15494)
		(layer "In7.Cu")
		(net "SMB_NIC4_LS_SCL")
	)
	(segment
		(start 216.9922 -180.323744)
		(end 217.307414 -180.323744)
		(width 0.15494)
		(layer "In7.Cu")
		(net "SMB_NIC4_LS_SCL")
	)
	(segment
		(start 217.307414 -181.294024)
		(end 217.4494 -181.152038)
		(width 0.15494)
		(layer "In7.Cu")
		(net "SMB_NIC4_LS_SCL")
	)
	(segment
		(start 217.307414 -179.838604)
		(end 216.9922 -179.838604)
		(width 0.15494)
		(layer "In7.Cu")
		(net "SMB_NIC4_LS_SCL")
	)
	(segment
		(start 217.307414 -179.353464)
		(end 217.4494 -179.211478)
		(width 0.15494)
		(layer "In7.Cu")
		(net "SMB_NIC4_LS_SCL")
	)
	(segment
		(start 217.4494 -181.92115)
		(end 217.307414 -181.779164)
		(width 0.15494)
		(layer "In7.Cu")
		(net "SMB_NIC4_LS_SCL")
	)
	(segment
		(start 216.9922 -181.294024)
		(end 217.307414 -181.294024)
		(width 0.15494)
		(layer "In7.Cu")
		(net "SMB_NIC4_LS_SCL")
	)
	(segment
		(start 217.4494 -179.98059)
		(end 217.307414 -179.838604)
		(width 0.15494)
		(layer "In7.Cu")
		(net "SMB_NIC4_LS_SCL")
	)
	(segment
		(start 216.850214 -177.756058)
		(end 216.850214 -174.584614)
		(width 0.15494)
		(layer "In7.Cu")
		(net "SMB_NIC4_LS_SCL")
	)
	(segment
		(start 216.850214 -178.52517)
		(end 216.9922 -178.383184)
		(width 0.15494)
		(layer "In7.Cu")
		(net "SMB_NIC4_LS_SCL")
	)
	(segment
		(start 217.297 -203.3016)
		(end 217.297 -200.178416)
		(width 0.15494)
		(layer "In7.Cu")
		(net "SMB_NIC4_LS_SCL")
	)
	(segment
		(start 216.850214 -181.43601)
		(end 216.9922 -181.294024)
		(width 0.15494)
		(layer "In7.Cu")
		(net "SMB_NIC4_LS_SCL")
	)
	(segment
		(start 216.850214 -179.696618)
		(end 216.850214 -179.49545)
		(width 0.15494)
		(layer "In7.Cu")
		(net "SMB_NIC4_LS_SCL")
	)
	(segment
		(start 217.4494 -180.181758)
		(end 217.4494 -179.98059)
		(width 0.15494)
		(layer "In7.Cu")
		(net "SMB_NIC4_LS_SCL")
	)
	(segment
		(start 216.9922 -179.838604)
		(end 216.850214 -179.696618)
		(width 0.15494)
		(layer "In7.Cu")
		(net "SMB_NIC4_LS_SCL")
	)
	(segment
		(start 217.4494 -178.04003)
		(end 217.307414 -177.898044)
		(width 0.15494)
		(layer "In7.Cu")
		(net "SMB_NIC4_LS_SCL")
	)
	(segment
		(start 217.4494 -181.152038)
		(end 217.4494 -180.95087)
		(width 0.15494)
		(layer "In7.Cu")
		(net "SMB_NIC4_LS_SCL")
	)
	(segment
		(start 216.9922 -179.353464)
		(end 217.307414 -179.353464)
		(width 0.15494)
		(layer "In7.Cu")
		(net "SMB_NIC4_LS_SCL")
	)
	(segment
		(start 217.307414 -177.898044)
		(end 216.9922 -177.898044)
		(width 0.15494)
		(layer "In7.Cu")
		(net "SMB_NIC4_LS_SCL")
	)
	(segment
		(start 216.9922 -178.383184)
		(end 217.307414 -178.383184)
		(width 0.15494)
		(layer "In7.Cu")
		(net "SMB_NIC4_LS_SCL")
	)
	(segment
		(start 217.307414 -178.868324)
		(end 216.9922 -178.868324)
		(width 0.15494)
		(layer "In7.Cu")
		(net "SMB_NIC4_LS_SCL")
	)
	(segment
		(start 217.307414 -181.779164)
		(end 216.9922 -181.779164)
		(width 0.15494)
		(layer "In7.Cu")
		(net "SMB_NIC4_LS_SCL")
	)
	(segment
		(start 218.719908 -190.829438)
		(end 219.589096 -189.96025)
		(width 0.15494)
		(layer "In7.Cu")
		(net "SMB_NIC4_LS_SCL")
	)
	(segment
		(start 217.932 -184.404)
		(end 216.850214 -183.322214)
		(width 0.15494)
		(layer "In7.Cu")
		(net "SMB_NIC4_LS_SCL")
	)
	(segment
		(start 219.589096 -186.823096)
		(end 217.932 -185.166)
		(width 0.15494)
		(layer "In7.Cu")
		(net "SMB_NIC4_LS_SCL")
	)
	(segment
		(start 217.307414 -182.264304)
		(end 217.4494 -182.122318)
		(width 0.15494)
		(layer "In7.Cu")
		(net "SMB_NIC4_LS_SCL")
	)
	(segment
		(start 216.850214 -179.49545)
		(end 216.9922 -179.353464)
		(width 0.15494)
		(layer "In7.Cu")
		(net "SMB_NIC4_LS_SCL")
	)
	(segment
		(start 217.307414 -178.383184)
		(end 217.4494 -178.241198)
		(width 0.15494)
		(layer "In7.Cu")
		(net "SMB_NIC4_LS_SCL")
	)
	(segment
		(start 216.9922 -177.898044)
		(end 216.850214 -177.756058)
		(width 0.15494)
		(layer "In7.Cu")
		(net "SMB_NIC4_LS_SCL")
	)
	(segment
		(start 217.4494 -179.211478)
		(end 217.4494 -179.01031)
		(width 0.15494)
		(layer "In7.Cu")
		(net "SMB_NIC4_LS_SCL")
	)
	(segment
		(start 217.307414 -180.808884)
		(end 216.9922 -180.808884)
		(width 0.15494)
		(layer "In7.Cu")
		(net "SMB_NIC4_LS_SCL")
	)
	(segment
		(start 216.850214 -181.637178)
		(end 216.850214 -181.43601)
		(width 0.15494)
		(layer "In7.Cu")
		(net "SMB_NIC4_LS_SCL")
	)
	(segment
		(start 217.932 -185.166)
		(end 217.932 -184.404)
		(width 0.15494)
		(layer "In7.Cu")
		(net "SMB_NIC4_LS_SCL")
	)
	(segment
		(start 218.2368 -195.8594)
		(end 218.2368 -195.199)
		(width 0.15494)
		(layer "In7.Cu")
		(net "SMB_NIC4_LS_SCL")
	)
	(segment
		(start 217.297 -200.178416)
		(end 218.694 -198.781416)
		(width 0.15494)
		(layer "In7.Cu")
		(net "SMB_NIC4_LS_SCL")
	)
	(segment
		(start 218.719908 -194.715892)
		(end 218.719908 -190.829438)
		(width 0.15494)
		(layer "In7.Cu")
		(net "SMB_NIC4_LS_SCL")
	)
	(segment
		(start 218.694 -196.3166)
		(end 218.2368 -195.8594)
		(width 0.15494)
		(layer "In7.Cu")
		(net "SMB_NIC4_LS_SCL")
	)
	(segment
		(start 216.850214 -174.584614)
		(end 216.429082 -174.163482)
		(width 0.15494)
		(layer "In7.Cu")
		(net "SMB_NIC4_LS_SCL")
	)
	(segment
		(start 216.850214 -182.40629)
		(end 216.9922 -182.264304)
		(width 0.15494)
		(layer "In7.Cu")
		(net "SMB_NIC4_LS_SCL")
	)
	(segment
		(start 217.307414 -180.323744)
		(end 217.4494 -180.181758)
		(width 0.15494)
		(layer "In7.Cu")
		(net "SMB_NIC4_LS_SCL")
	)
	(segment
		(start 216.9922 -181.779164)
		(end 216.850214 -181.637178)
		(width 0.15494)
		(layer "In7.Cu")
		(net "SMB_NIC4_LS_SCL")
	)
	(segment
		(start 216.9922 -182.264304)
		(end 217.307414 -182.264304)
		(width 0.15494)
		(layer "In7.Cu")
		(net "SMB_NIC4_LS_SCL")
	)
	(segment
		(start 216.850214 -180.666898)
		(end 216.850214 -180.46573)
		(width 0.15494)
		(layer "In7.Cu")
		(net "SMB_NIC4_LS_SCL")
	)
	(segment
		(start 216.850214 -178.726338)
		(end 216.850214 -178.52517)
		(width 0.15494)
		(layer "In7.Cu")
		(net "SMB_NIC4_LS_SCL")
	)
	(segment
		(start 218.059254 -165.05301)
		(end 218.862402 -164.249862)
		(width 0.15494)
		(layer "In7.Cu")
		(net "SMB_NIC4_LS_SCL")
	)
	(segment
		(start 217.4494 -178.241198)
		(end 217.4494 -178.04003)
		(width 0.15494)
		(layer "In7.Cu")
		(net "SMB_NIC4_LS_SCL")
	)
	(segment
		(start 216.850214 -180.46573)
		(end 216.9922 -180.323744)
		(width 0.15494)
		(layer "In7.Cu")
		(net "SMB_NIC4_LS_SCL")
	)
	(segment
		(start 216.9922 -178.868324)
		(end 216.850214 -178.726338)
		(width 0.15494)
		(layer "In7.Cu")
		(net "SMB_NIC4_LS_SCL")
	)
	(segment
		(start 218.2368 -195.199)
		(end 218.719908 -194.715892)
		(width 0.15494)
		(layer "In7.Cu")
		(net "SMB_NIC4_LS_SCL")
	)
	(segment
		(start 218.694 -198.781416)
		(end 218.694 -196.3166)
		(width 0.15494)
		(layer "In7.Cu")
		(net "SMB_NIC4_LS_SCL")
	)
	(segment
		(start 219.589096 -189.96025)
		(end 219.589096 -186.823096)
		(width 0.15494)
		(layer "In7.Cu")
		(net "SMB_NIC4_LS_SCL")
	)
	(segment
		(start 216.429082 -174.163482)
		(end 216.429082 -169.528236)
		(width 0.15494)
		(layer "In7.Cu")
		(net "SMB_NIC4_LS_SCL")
	)
	(segment
		(start 216.429082 -169.528236)
		(end 218.063064 -167.894254)
		(width 0.15494)
		(layer "In7.Cu")
		(net "SMB_NIC4_LS_SCL")
	)
	(segment
		(start 217.4494 -179.01031)
		(end 217.307414 -178.868324)
		(width 0.15494)
		(layer "In7.Cu")
		(net "SMB_NIC4_LS_SCL")
	)
	(segment
		(start 217.4494 -180.95087)
		(end 217.307414 -180.808884)
		(width 0.15494)
		(layer "In7.Cu")
		(net "SMB_NIC4_LS_SCL")
	)
	(segment
		(start 216.9922 -180.808884)
		(end 216.850214 -180.666898)
		(width 0.15494)
		(layer "In7.Cu")
		(net "SMB_NIC4_LS_SCL")
	)
	(segment
		(start 218.063064 -167.894254)
		(end 218.063064 -165.062916)
		(width 0.15494)
		(layer "In7.Cu")
		(net "SMB_NIC4_LS_SCL")
	)
	(segment
		(start 218.063064 -165.062916)
		(end 218.059254 -165.05301)
		(width 0.15494)
		(layer "In7.Cu")
		(net "SMB_NIC4_LS_SCL")
	)
	(segment
		(start 254.9906 -159.6898)
		(end 254.9398 -159.7406)
		(width 0.15494)
		(layer "In13.Cu")
		(net "SMB_NIC4_LS_SCL")
	)
	(segment
		(start 254.9398 -163.576254)
		(end 253.670054 -164.846)
		(width 0.15494)
		(layer "In13.Cu")
		(net "SMB_NIC4_LS_SCL")
	)
	(segment
		(start 219.45854 -164.846)
		(end 218.862402 -164.249862)
		(width 0.15494)
		(layer "In13.Cu")
		(net "SMB_NIC4_LS_SCL")
	)
	(segment
		(start 254.9398 -159.7406)
		(end 254.9398 -163.576254)
		(width 0.15494)
		(layer "In13.Cu")
		(net "SMB_NIC4_LS_SCL")
	)
	(segment
		(start 253.670054 -164.846)
		(end 219.45854 -164.846)
		(width 0.15494)
		(layer "In13.Cu")
		(net "SMB_NIC4_LS_SCL")
	)
	(segment
		(start 280.810208 -137.263632)
		(end 280.112724 -136.566148)
		(width 0.15494)
		(layer "In15.Cu")
		(net "SMB_NIC4_LS_SCL")
	)
	(segment
		(start 281.922982 -142.5194)
		(end 280.810208 -141.406626)
		(width 0.15494)
		(layer "In15.Cu")
		(net "SMB_NIC4_LS_SCL")
	)
	(segment
		(start 257.0988 -158.9532)
		(end 255.809496 -158.9532)
		(width 0.15494)
		(layer "In15.Cu")
		(net "SMB_NIC4_LS_SCL")
	)
	(segment
		(start 280.112724 -136.566148)
		(end 275.41982 -136.566148)
		(width 0.15494)
		(layer "In15.Cu")
		(net "SMB_NIC4_LS_SCL")
	)
	(segment
		(start 255.809496 -158.9532)
		(end 255.669034 -159.011366)
		(width 0.15494)
		(layer "In15.Cu")
		(net "SMB_NIC4_LS_SCL")
	)
	(segment
		(start 280.810208 -141.406626)
		(end 280.810208 -137.263632)
		(width 0.15494)
		(layer "In15.Cu")
		(net "SMB_NIC4_LS_SCL")
	)
	(segment
		(start 275.41982 -136.566148)
		(end 271.4752 -140.510768)
		(width 0.15494)
		(layer "In15.Cu")
		(net "SMB_NIC4_LS_SCL")
	)
	(segment
		(start 284.187138 -142.60068)
		(end 284.105858 -142.5194)
		(width 0.15494)
		(layer "In15.Cu")
		(net "SMB_NIC4_LS_SCL")
	)
	(segment
		(start 271.4752 -144.5768)
		(end 257.0988 -158.9532)
		(width 0.15494)
		(layer "In15.Cu")
		(net "SMB_NIC4_LS_SCL")
	)
	(segment
		(start 284.105858 -142.5194)
		(end 281.922982 -142.5194)
		(width 0.15494)
		(layer "In15.Cu")
		(net "SMB_NIC4_LS_SCL")
	)
	(segment
		(start 255.669034 -159.011366)
		(end 254.9906 -159.6898)
		(width 0.15494)
		(layer "In15.Cu")
		(net "SMB_NIC4_LS_SCL")
	)
	(segment
		(start 271.4752 -140.510768)
		(end 271.4752 -144.5768)
		(width 0.15494)
		(layer "In15.Cu")
		(net "SMB_NIC4_LS_SCL")
	)
	(segment
		(start 78.317852 -21.775674)
		(end 78.28534 -21.743162)
		(width 0.13208)
		(layer "F.Cu")
		(net "SMB_BIC_I2C9_MUX0_SSD2_R_SCL")
	)
	(segment
		(start 118.70309 -91.425776)
		(end 119.399812 -90.729054)
		(width 0.13208)
		(layer "F.Cu")
		(net "SMB_BIC_I2C9_MUX0_SSD2_R_SCL")
	)
	(segment
		(start 78.317852 -22.413976)
		(end 78.317852 -21.775674)
		(width 0.13208)
		(layer "F.Cu")
		(net "SMB_BIC_I2C9_MUX0_SSD2_R_SCL")
	)
	(segment
		(start 121.53519 -91.112086)
		(end 121.53519 -91.462606)
		(width 0.13208)
		(layer "F.Cu")
		(net "SMB_BIC_I2C9_MUX0_SSD2_R_SCL")
	)
	(segment
		(start 119.399812 -90.729054)
		(end 121.152158 -90.729054)
		(width 0.13208)
		(layer "F.Cu")
		(net "SMB_BIC_I2C9_MUX0_SSD2_R_SCL")
	)
	(segment
		(start 121.152158 -90.729054)
		(end 121.53519 -91.112086)
		(width 0.13208)
		(layer "F.Cu")
		(net "SMB_BIC_I2C9_MUX0_SSD2_R_SCL")
	)
	(segment
		(start 123.27509 -91.462606)
		(end 121.53519 -91.462606)
		(width 0.13208)
		(layer "F.Cu")
		(net "SMB_BIC_I2C9_MUX0_SSD2_R_SCL")
	)
	(segment
		(start 78.45933 -22.555454)
		(end 78.317852 -22.413976)
		(width 0.13208)
		(layer "F.Cu")
		(net "SMB_BIC_I2C9_MUX0_SSD2_R_SCL")
	)
	(segment
		(start 78.28534 -21.743162)
		(end 78.28534 -20.789392)
		(width 0.13208)
		(layer "F.Cu")
		(net "SMB_BIC_I2C9_MUX0_SSD2_R_SCL")
	)
	(via
		(at 118.70309 -91.425776)
		(size 0.508)
		(drill 0.254)
		(layers "F.Cu" "B.Cu")
		(net "SMB_BIC_I2C9_MUX0_SSD2_R_SCL")
	)
	(via
		(at 78.317852 -21.775674)
		(size 0.508)
		(drill 0.254)
		(layers "F.Cu" "B.Cu")
		(net "SMB_BIC_I2C9_MUX0_SSD2_R_SCL")
	)
	(segment
		(start 118.70309 -91.425776)
		(end 119.558562 -90.570304)
		(width 0.15494)
		(layer "In5.Cu")
		(net "SMB_BIC_I2C9_MUX0_SSD2_R_SCL")
	)
	(segment
		(start 90.333068 -45.59554)
		(end 78.326742 -33.589214)
		(width 0.15494)
		(layer "In5.Cu")
		(net "SMB_BIC_I2C9_MUX0_SSD2_R_SCL")
	)
	(segment
		(start 93.735144 -79.046324)
		(end 90.333068 -75.644248)
		(width 0.15494)
		(layer "In5.Cu")
		(net "SMB_BIC_I2C9_MUX0_SSD2_R_SCL")
	)
	(segment
		(start 119.558562 -83.109816)
		(end 116.442998 -79.994252)
		(width 0.15494)
		(layer "In5.Cu")
		(net "SMB_BIC_I2C9_MUX0_SSD2_R_SCL")
	)
	(segment
		(start 116.442998 -79.994252)
		(end 106.099356 -79.994252)
		(width 0.15494)
		(layer "In5.Cu")
		(net "SMB_BIC_I2C9_MUX0_SSD2_R_SCL")
	)
	(segment
		(start 78.326742 -28.107386)
		(end 76.740004 -26.520648)
		(width 0.15494)
		(layer "In5.Cu")
		(net "SMB_BIC_I2C9_MUX0_SSD2_R_SCL")
	)
	(segment
		(start 119.558562 -90.570304)
		(end 119.558562 -83.109816)
		(width 0.15494)
		(layer "In5.Cu")
		(net "SMB_BIC_I2C9_MUX0_SSD2_R_SCL")
	)
	(segment
		(start 77.716126 -21.775674)
		(end 78.317852 -21.775674)
		(width 0.15494)
		(layer "In5.Cu")
		(net "SMB_BIC_I2C9_MUX0_SSD2_R_SCL")
	)
	(segment
		(start 76.740004 -26.520648)
		(end 76.740004 -22.751796)
		(width 0.15494)
		(layer "In5.Cu")
		(net "SMB_BIC_I2C9_MUX0_SSD2_R_SCL")
	)
	(segment
		(start 105.151428 -79.046324)
		(end 93.735144 -79.046324)
		(width 0.15494)
		(layer "In5.Cu")
		(net "SMB_BIC_I2C9_MUX0_SSD2_R_SCL")
	)
	(segment
		(start 78.326742 -33.589214)
		(end 78.326742 -28.107386)
		(width 0.15494)
		(layer "In5.Cu")
		(net "SMB_BIC_I2C9_MUX0_SSD2_R_SCL")
	)
	(segment
		(start 106.099356 -79.994252)
		(end 105.151428 -79.046324)
		(width 0.15494)
		(layer "In5.Cu")
		(net "SMB_BIC_I2C9_MUX0_SSD2_R_SCL")
	)
	(segment
		(start 90.333068 -75.644248)
		(end 90.333068 -45.59554)
		(width 0.15494)
		(layer "In5.Cu")
		(net "SMB_BIC_I2C9_MUX0_SSD2_R_SCL")
	)
	(segment
		(start 76.740004 -22.751796)
		(end 77.716126 -21.775674)
		(width 0.15494)
		(layer "In5.Cu")
		(net "SMB_BIC_I2C9_MUX0_SSD2_R_SCL")
	)
	(segment
		(start 169.736516 -61.487812)
		(end 169.104564 -62.119764)
		(width 0.13208)
		(layer "F.Cu")
		(net "PWRGD_P12V_SSD6_R")
	)
	(segment
		(start 194.767962 -53.051456)
		(end 195.423282 -53.051456)
		(width 0.13208)
		(layer "F.Cu")
		(net "PWRGD_P12V_SSD6_R")
	)
	(segment
		(start 169.104564 -64.886332)
		(end 169.973752 -65.75552)
		(width 0.13208)
		(layer "F.Cu")
		(net "PWRGD_P12V_SSD6_R")
	)
	(segment
		(start 171.583604 -61.487812)
		(end 169.736516 -61.487812)
		(width 0.13208)
		(layer "F.Cu")
		(net "PWRGD_P12V_SSD6_R")
	)
	(segment
		(start 169.104564 -62.119764)
		(end 169.104564 -64.886332)
		(width 0.13208)
		(layer "F.Cu")
		(net "PWRGD_P12V_SSD6_R")
	)
	(segment
		(start 169.973752 -65.75552)
		(end 182.828692 -65.75552)
		(width 0.13208)
		(layer "F.Cu")
		(net "PWRGD_P12V_SSD6_R")
	)
	(segment
		(start 346.893896 -225.587052)
		(end 347.293692 -225.986848)
		(width 0.13208)
		(layer "F.Cu")
		(net "PWRGD_P12V_SSD6_R")
	)
	(via
		(at 182.828692 -65.75552)
		(size 0.508)
		(drill 0.254)
		(layers "F.Cu" "B.Cu")
		(net "PWRGD_P12V_SSD6_R")
	)
	(via
		(at 185.126884 -240.876074)
		(size 0.508)
		(drill 0.254)
		(layers "F.Cu" "B.Cu")
		(net "PWRGD_P12V_SSD6_R")
	)
	(via
		(at 195.423282 -53.051456)
		(size 0.508)
		(drill 0.254)
		(layers "F.Cu" "B.Cu")
		(net "PWRGD_P12V_SSD6_R")
	)
	(via
		(at 347.293692 -225.986848)
		(size 0.4572)
		(drill 0.254)
		(layers "F.Cu" "B.Cu")
		(net "PWRGD_P12V_SSD6_R")
	)
	(segment
		(start 186.318144 -65.75552)
		(end 187.551822 -64.521842)
		(width 0.15494)
		(layer "In5.Cu")
		(net "PWRGD_P12V_SSD6_R")
	)
	(segment
		(start 194.30238 -69.044566)
		(end 195.05676 -68.290186)
		(width 0.15494)
		(layer "In5.Cu")
		(net "PWRGD_P12V_SSD6_R")
	)
	(segment
		(start 184.4548 -220.551502)
		(end 180.320696 -210.571334)
		(width 0.15494)
		(layer "In5.Cu")
		(net "PWRGD_P12V_SSD6_R")
	)
	(segment
		(start 193.467228 -57.606946)
		(end 193.36131 -57.501028)
		(width 0.15494)
		(layer "In5.Cu")
		(net "PWRGD_P12V_SSD6_R")
	)
	(segment
		(start 185.647584 -229.107238)
		(end 183.882538 -227.342192)
		(width 0.15494)
		(layer "In5.Cu")
		(net "PWRGD_P12V_SSD6_R")
	)
	(segment
		(start 180.320696 -202.167236)
		(end 179.2986 -201.14514)
		(width 0.15494)
		(layer "In5.Cu")
		(net "PWRGD_P12V_SSD6_R")
	)
	(segment
		(start 179.2986 -201.14514)
		(end 179.2986 -199.031606)
		(width 0.15494)
		(layer "In5.Cu")
		(net "PWRGD_P12V_SSD6_R")
	)
	(segment
		(start 183.261 -81.7118)
		(end 188.79693 -81.7118)
		(width 0.15494)
		(layer "In5.Cu")
		(net "PWRGD_P12V_SSD6_R")
	)
	(segment
		(start 183.882538 -227.342192)
		(end 183.874918 -227.342192)
		(width 0.15494)
		(layer "In5.Cu")
		(net "PWRGD_P12V_SSD6_R")
	)
	(segment
		(start 194.30238 -76.20635)
		(end 194.30238 -69.044566)
		(width 0.15494)
		(layer "In5.Cu")
		(net "PWRGD_P12V_SSD6_R")
	)
	(segment
		(start 185.126884 -239.635538)
		(end 185.647584 -239.114838)
		(width 0.15494)
		(layer "In5.Cu")
		(net "PWRGD_P12V_SSD6_R")
	)
	(segment
		(start 180.320696 -210.571334)
		(end 180.320696 -202.167236)
		(width 0.15494)
		(layer "In5.Cu")
		(net "PWRGD_P12V_SSD6_R")
	)
	(segment
		(start 193.467228 -64.090296)
		(end 193.467228 -57.606946)
		(width 0.15494)
		(layer "In5.Cu")
		(net "PWRGD_P12V_SSD6_R")
	)
	(segment
		(start 183.874918 -227.342192)
		(end 183.591708 -227.058982)
		(width 0.15494)
		(layer "In5.Cu")
		(net "PWRGD_P12V_SSD6_R")
	)
	(segment
		(start 179.2986 -199.031606)
		(end 179.7558 -198.574406)
		(width 0.15494)
		(layer "In5.Cu")
		(net "PWRGD_P12V_SSD6_R")
	)
	(segment
		(start 184.4548 -221.690184)
		(end 184.4548 -220.551502)
		(width 0.15494)
		(layer "In5.Cu")
		(net "PWRGD_P12V_SSD6_R")
	)
	(segment
		(start 185.647584 -239.114838)
		(end 185.647584 -229.107238)
		(width 0.15494)
		(layer "In5.Cu")
		(net "PWRGD_P12V_SSD6_R")
	)
	(segment
		(start 193.36131 -57.501028)
		(end 193.36131 -55.113428)
		(width 0.15494)
		(layer "In5.Cu")
		(net "PWRGD_P12V_SSD6_R")
	)
	(segment
		(start 188.79693 -81.7118)
		(end 194.30238 -76.20635)
		(width 0.15494)
		(layer "In5.Cu")
		(net "PWRGD_P12V_SSD6_R")
	)
	(segment
		(start 195.05676 -57.571894)
		(end 196.221858 -56.406796)
		(width 0.15494)
		(layer "In5.Cu")
		(net "PWRGD_P12V_SSD6_R")
	)
	(segment
		(start 176.465738 -88.507062)
		(end 183.261 -81.7118)
		(width 0.15494)
		(layer "In5.Cu")
		(net "PWRGD_P12V_SSD6_R")
	)
	(segment
		(start 193.035682 -64.521842)
		(end 193.467228 -64.090296)
		(width 0.15494)
		(layer "In5.Cu")
		(net "PWRGD_P12V_SSD6_R")
	)
	(segment
		(start 179.7558 -198.574406)
		(end 179.7558 -183.769)
		(width 0.15494)
		(layer "In5.Cu")
		(net "PWRGD_P12V_SSD6_R")
	)
	(segment
		(start 179.7558 -183.769)
		(end 176.465738 -180.478938)
		(width 0.15494)
		(layer "In5.Cu")
		(net "PWRGD_P12V_SSD6_R")
	)
	(segment
		(start 195.05676 -68.290186)
		(end 195.05676 -57.571894)
		(width 0.15494)
		(layer "In5.Cu")
		(net "PWRGD_P12V_SSD6_R")
	)
	(segment
		(start 183.591708 -227.058982)
		(end 183.591708 -227.051362)
		(width 0.15494)
		(layer "In5.Cu")
		(net "PWRGD_P12V_SSD6_R")
	)
	(segment
		(start 187.551822 -64.521842)
		(end 193.035682 -64.521842)
		(width 0.15494)
		(layer "In5.Cu")
		(net "PWRGD_P12V_SSD6_R")
	)
	(segment
		(start 183.503316 -222.641668)
		(end 184.4548 -221.690184)
		(width 0.15494)
		(layer "In5.Cu")
		(net "PWRGD_P12V_SSD6_R")
	)
	(segment
		(start 196.221858 -56.406796)
		(end 196.221858 -53.850032)
		(width 0.15494)
		(layer "In5.Cu")
		(net "PWRGD_P12V_SSD6_R")
	)
	(segment
		(start 183.503316 -226.96297)
		(end 183.503316 -222.641668)
		(width 0.15494)
		(layer "In5.Cu")
		(net "PWRGD_P12V_SSD6_R")
	)
	(segment
		(start 185.126884 -240.876074)
		(end 185.126884 -239.635538)
		(width 0.15494)
		(layer "In5.Cu")
		(net "PWRGD_P12V_SSD6_R")
	)
	(segment
		(start 182.828692 -65.75552)
		(end 186.318144 -65.75552)
		(width 0.15494)
		(layer "In5.Cu")
		(net "PWRGD_P12V_SSD6_R")
	)
	(segment
		(start 176.465738 -180.478938)
		(end 176.465738 -88.507062)
		(width 0.15494)
		(layer "In5.Cu")
		(net "PWRGD_P12V_SSD6_R")
	)
	(segment
		(start 183.591708 -227.051362)
		(end 183.503316 -226.96297)
		(width 0.15494)
		(layer "In5.Cu")
		(net "PWRGD_P12V_SSD6_R")
	)
	(segment
		(start 193.36131 -55.113428)
		(end 195.423282 -53.051456)
		(width 0.15494)
		(layer "In5.Cu")
		(net "PWRGD_P12V_SSD6_R")
	)
	(segment
		(start 196.221858 -53.850032)
		(end 195.423282 -53.051456)
		(width 0.15494)
		(layer "In5.Cu")
		(net "PWRGD_P12V_SSD6_R")
	)
	(segment
		(start 214.818468 -238.84509)
		(end 214.370158 -239.2934)
		(width 0.15494)
		(layer "In13.Cu")
		(net "PWRGD_P12V_SSD6_R")
	)
	(segment
		(start 348.107 -232.216198)
		(end 345.54287 -234.780328)
		(width 0.15494)
		(layer "In13.Cu")
		(net "PWRGD_P12V_SSD6_R")
	)
	(segment
		(start 344.535252 -236.068108)
		(end 344.535252 -236.718348)
		(width 0.15494)
		(layer "In13.Cu")
		(net "PWRGD_P12V_SSD6_R")
	)
	(segment
		(start 275.894546 -240.4618)
		(end 274.875244 -239.442498)
		(width 0.15494)
		(layer "In13.Cu")
		(net "PWRGD_P12V_SSD6_R")
	)
	(segment
		(start 347.696028 -227.3554)
		(end 347.696028 -228.617526)
		(width 0.15494)
		(layer "In13.Cu")
		(net "PWRGD_P12V_SSD6_R")
	)
	(segment
		(start 345.195652 -235.721144)
		(end 344.882216 -235.721144)
		(width 0.15494)
		(layer "In13.Cu")
		(net "PWRGD_P12V_SSD6_R")
	)
	(segment
		(start 185.287158 -240.7158)
		(end 185.126884 -240.876074)
		(width 0.15494)
		(layer "In13.Cu")
		(net "PWRGD_P12V_SSD6_R")
	)
	(segment
		(start 329.4126 -241.0968)
		(end 328.73696 -241.77244)
		(width 0.15494)
		(layer "In13.Cu")
		(net "PWRGD_P12V_SSD6_R")
	)
	(segment
		(start 338.7344 -241.0968)
		(end 329.4126 -241.0968)
		(width 0.15494)
		(layer "In13.Cu")
		(net "PWRGD_P12V_SSD6_R")
	)
	(segment
		(start 347.696028 -226.389184)
		(end 347.696028 -227.3554)
		(width 0.0889)
		(layer "In13.Cu")
		(net "PWRGD_P12V_SSD6_R")
	)
	(segment
		(start 344.882216 -235.721144)
		(end 344.535252 -236.068108)
		(width 0.15494)
		(layer "In13.Cu")
		(net "PWRGD_P12V_SSD6_R")
	)
	(segment
		(start 221.072964 -238.84509)
		(end 214.818468 -238.84509)
		(width 0.15494)
		(layer "In13.Cu")
		(net "PWRGD_P12V_SSD6_R")
	)
	(segment
		(start 207.53451 -239.2934)
		(end 206.11211 -240.7158)
		(width 0.15494)
		(layer "In13.Cu")
		(net "PWRGD_P12V_SSD6_R")
	)
	(segment
		(start 206.11211 -240.7158)
		(end 185.287158 -240.7158)
		(width 0.15494)
		(layer "In13.Cu")
		(net "PWRGD_P12V_SSD6_R")
	)
	(segment
		(start 274.875244 -239.442498)
		(end 241.779298 -239.442498)
		(width 0.15494)
		(layer "In13.Cu")
		(net "PWRGD_P12V_SSD6_R")
	)
	(segment
		(start 348.107 -229.028498)
		(end 348.107 -232.216198)
		(width 0.15494)
		(layer "In13.Cu")
		(net "PWRGD_P12V_SSD6_R")
	)
	(segment
		(start 306.898294 -241.77244)
		(end 305.587654 -240.4618)
		(width 0.15494)
		(layer "In13.Cu")
		(net "PWRGD_P12V_SSD6_R")
	)
	(segment
		(start 214.370158 -239.2934)
		(end 207.53451 -239.2934)
		(width 0.15494)
		(layer "In13.Cu")
		(net "PWRGD_P12V_SSD6_R")
	)
	(segment
		(start 345.54287 -234.780328)
		(end 345.54287 -235.373926)
		(width 0.15494)
		(layer "In13.Cu")
		(net "PWRGD_P12V_SSD6_R")
	)
	(segment
		(start 344.316304 -236.937296)
		(end 342.893904 -236.937296)
		(width 0.15494)
		(layer "In13.Cu")
		(net "PWRGD_P12V_SSD6_R")
	)
	(segment
		(start 347.293692 -225.986848)
		(end 347.696028 -226.389184)
		(width 0.0889)
		(layer "In13.Cu")
		(net "PWRGD_P12V_SSD6_R")
	)
	(segment
		(start 221.843854 -238.0742)
		(end 221.072964 -238.84509)
		(width 0.15494)
		(layer "In13.Cu")
		(net "PWRGD_P12V_SSD6_R")
	)
	(segment
		(start 347.696028 -228.617526)
		(end 348.107 -229.028498)
		(width 0.15494)
		(layer "In13.Cu")
		(net "PWRGD_P12V_SSD6_R")
	)
	(segment
		(start 240.411 -238.0742)
		(end 221.843854 -238.0742)
		(width 0.15494)
		(layer "In13.Cu")
		(net "PWRGD_P12V_SSD6_R")
	)
	(segment
		(start 305.587654 -240.4618)
		(end 275.894546 -240.4618)
		(width 0.15494)
		(layer "In13.Cu")
		(net "PWRGD_P12V_SSD6_R")
	)
	(segment
		(start 241.779298 -239.442498)
		(end 240.411 -238.0742)
		(width 0.15494)
		(layer "In13.Cu")
		(net "PWRGD_P12V_SSD6_R")
	)
	(segment
		(start 344.535252 -236.718348)
		(end 344.316304 -236.937296)
		(width 0.15494)
		(layer "In13.Cu")
		(net "PWRGD_P12V_SSD6_R")
	)
	(segment
		(start 328.73696 -241.77244)
		(end 306.898294 -241.77244)
		(width 0.15494)
		(layer "In13.Cu")
		(net "PWRGD_P12V_SSD6_R")
	)
	(segment
		(start 342.893904 -236.937296)
		(end 338.7344 -241.0968)
		(width 0.15494)
		(layer "In13.Cu")
		(net "PWRGD_P12V_SSD6_R")
	)
	(segment
		(start 345.54287 -235.373926)
		(end 345.195652 -235.721144)
		(width 0.15494)
		(layer "In13.Cu")
		(net "PWRGD_P12V_SSD6_R")
	)
	(segment
		(start 358.369362 -118.743476)
		(end 358.369362 -119.486426)
		(width 0.13208)
		(layer "F.Cu")
		(net "PWRGD_P3V3_NIC6_R")
	)
	(segment
		(start 358.01046 -124.963428)
		(end 357.35514 -124.963428)
		(width 0.13208)
		(layer "F.Cu")
		(net "PWRGD_P3V3_NIC6_R")
	)
	(segment
		(start 349.293942 -219.187014)
		(end 349.693738 -218.787218)
		(width 0.13208)
		(layer "F.Cu")
		(net "PWRGD_P3V3_NIC6_R")
	)
	(via
		(at 358.369362 -119.486426)
		(size 0.508)
		(drill 0.254)
		(layers "F.Cu" "B.Cu")
		(net "PWRGD_P3V3_NIC6_R")
	)
	(via
		(at 349.693738 -218.787218)
		(size 0.4572)
		(drill 0.254)
		(layers "F.Cu" "B.Cu")
		(net "PWRGD_P3V3_NIC6_R")
	)
	(via
		(at 357.35514 -124.963428)
		(size 0.508)
		(drill 0.254)
		(layers "F.Cu" "B.Cu")
		(net "PWRGD_P3V3_NIC6_R")
	)
	(segment
		(start 349.693738 -218.787218)
		(end 350.491298 -219.584778)
		(width 0.15494)
		(layer "In5.Cu")
		(net "PWRGD_P3V3_NIC6_R")
	)
	(segment
		(start 355.700076 -138.466322)
		(end 355.088952 -137.855198)
		(width 0.15494)
		(layer "In5.Cu")
		(net "PWRGD_P3V3_NIC6_R")
	)
	(segment
		(start 354.13696 -137.855198)
		(end 353.981512 -137.69975)
		(width 0.15494)
		(layer "In5.Cu")
		(net "PWRGD_P3V3_NIC6_R")
	)
	(segment
		(start 354.395024 -219.584778)
		(end 354.476304 -219.666058)
		(width 0.15494)
		(layer "In5.Cu")
		(net "PWRGD_P3V3_NIC6_R")
	)
	(segment
		(start 353.981512 -137.69975)
		(end 353.981512 -130.874008)
		(width 0.15494)
		(layer "In5.Cu")
		(net "PWRGD_P3V3_NIC6_R")
	)
	(segment
		(start 361.06989 -218.948)
		(end 364.0836 -215.93429)
		(width 0.15494)
		(layer "In5.Cu")
		(net "PWRGD_P3V3_NIC6_R")
	)
	(segment
		(start 372.852442 -191.916558)
		(end 371.955314 -191.01943)
		(width 0.15494)
		(layer "In5.Cu")
		(net "PWRGD_P3V3_NIC6_R")
	)
	(segment
		(start 372.852442 -208.29905)
		(end 372.852442 -191.916558)
		(width 0.15494)
		(layer "In5.Cu")
		(net "PWRGD_P3V3_NIC6_R")
	)
	(segment
		(start 371.955314 -180.971952)
		(end 371.352064 -180.368702)
		(width 0.15494)
		(layer "In5.Cu")
		(net "PWRGD_P3V3_NIC6_R")
	)
	(segment
		(start 354.571046 -127.747522)
		(end 357.35514 -124.963428)
		(width 0.15494)
		(layer "In5.Cu")
		(net "PWRGD_P3V3_NIC6_R")
	)
	(segment
		(start 371.352064 -171.970954)
		(end 364.787434 -165.406324)
		(width 0.15494)
		(layer "In5.Cu")
		(net "PWRGD_P3V3_NIC6_R")
	)
	(segment
		(start 354.720398 -144.051528)
		(end 355.700076 -143.07185)
		(width 0.15494)
		(layer "In5.Cu")
		(net "PWRGD_P3V3_NIC6_R")
	)
	(segment
		(start 372.801388 -208.350104)
		(end 372.852442 -208.29905)
		(width 0.15494)
		(layer "In5.Cu")
		(net "PWRGD_P3V3_NIC6_R")
	)
	(segment
		(start 364.0836 -215.93429)
		(end 367.385346 -215.93429)
		(width 0.15494)
		(layer "In5.Cu")
		(net "PWRGD_P3V3_NIC6_R")
	)
	(segment
		(start 372.801388 -210.518248)
		(end 372.801388 -208.350104)
		(width 0.15494)
		(layer "In5.Cu")
		(net "PWRGD_P3V3_NIC6_R")
	)
	(segment
		(start 371.955314 -191.01943)
		(end 371.955314 -180.971952)
		(width 0.15494)
		(layer "In5.Cu")
		(net "PWRGD_P3V3_NIC6_R")
	)
	(segment
		(start 354.476304 -219.666058)
		(end 355.10089 -219.666058)
		(width 0.15494)
		(layer "In5.Cu")
		(net "PWRGD_P3V3_NIC6_R")
	)
	(segment
		(start 353.981512 -130.874008)
		(end 354.571046 -130.284474)
		(width 0.15494)
		(layer "In5.Cu")
		(net "PWRGD_P3V3_NIC6_R")
	)
	(segment
		(start 354.720398 -160.923732)
		(end 354.720398 -144.051528)
		(width 0.15494)
		(layer "In5.Cu")
		(net "PWRGD_P3V3_NIC6_R")
	)
	(segment
		(start 354.571046 -130.284474)
		(end 354.571046 -127.747522)
		(width 0.15494)
		(layer "In5.Cu")
		(net "PWRGD_P3V3_NIC6_R")
	)
	(segment
		(start 355.088952 -137.855198)
		(end 354.13696 -137.855198)
		(width 0.15494)
		(layer "In5.Cu")
		(net "PWRGD_P3V3_NIC6_R")
	)
	(segment
		(start 359.20299 -165.406324)
		(end 354.720398 -160.923732)
		(width 0.15494)
		(layer "In5.Cu")
		(net "PWRGD_P3V3_NIC6_R")
	)
	(segment
		(start 355.10089 -219.666058)
		(end 355.818948 -218.948)
		(width 0.15494)
		(layer "In5.Cu")
		(net "PWRGD_P3V3_NIC6_R")
	)
	(segment
		(start 350.491298 -219.584778)
		(end 354.395024 -219.584778)
		(width 0.15494)
		(layer "In5.Cu")
		(net "PWRGD_P3V3_NIC6_R")
	)
	(segment
		(start 371.352064 -180.368702)
		(end 371.352064 -171.970954)
		(width 0.15494)
		(layer "In5.Cu")
		(net "PWRGD_P3V3_NIC6_R")
	)
	(segment
		(start 364.787434 -165.406324)
		(end 359.20299 -165.406324)
		(width 0.15494)
		(layer "In5.Cu")
		(net "PWRGD_P3V3_NIC6_R")
	)
	(segment
		(start 355.700076 -143.07185)
		(end 355.700076 -138.466322)
		(width 0.15494)
		(layer "In5.Cu")
		(net "PWRGD_P3V3_NIC6_R")
	)
	(segment
		(start 367.385346 -215.93429)
		(end 372.801388 -210.518248)
		(width 0.15494)
		(layer "In5.Cu")
		(net "PWRGD_P3V3_NIC6_R")
	)
	(segment
		(start 355.818948 -218.948)
		(end 361.06989 -218.948)
		(width 0.15494)
		(layer "In5.Cu")
		(net "PWRGD_P3V3_NIC6_R")
	)
	(segment
		(start 357.35514 -124.963428)
		(end 357.884476 -124.434092)
		(width 0.15494)
		(layer "In7.Cu")
		(net "PWRGD_P3V3_NIC6_R")
	)
	(segment
		(start 358.369362 -120.756426)
		(end 358.369362 -119.486426)
		(width 0.15494)
		(layer "In7.Cu")
		(net "PWRGD_P3V3_NIC6_R")
	)
	(segment
		(start 357.884476 -121.241312)
		(end 358.369362 -120.756426)
		(width 0.15494)
		(layer "In7.Cu")
		(net "PWRGD_P3V3_NIC6_R")
	)
	(segment
		(start 357.884476 -124.434092)
		(end 357.884476 -121.241312)
		(width 0.15494)
		(layer "In7.Cu")
		(net "PWRGD_P3V3_NIC6_R")
	)
	(segment
		(start 393.989306 -242.039648)
		(end 393.995402 -242.033552)
		(width 0.13208)
		(layer "F.Cu")
		(net "UART_PEX1_SDB_R_RX")
	)
	(segment
		(start 387.148578 -226.877372)
		(end 387.148578 -222.79229)
		(width 0.13208)
		(layer "F.Cu")
		(net "UART_PEX1_SDB_R_RX")
	)
	(segment
		(start 386.296408 -221.94012)
		(end 385.686808 -221.94012)
		(width 0.13208)
		(layer "F.Cu")
		(net "UART_PEX1_SDB_R_RX")
	)
	(segment
		(start 456.53071 -235.593382)
		(end 456.532996 -235.591096)
		(width 0.13208)
		(layer "F.Cu")
		(net "UART_PEX1_SDB_R_RX")
	)
	(segment
		(start 387.148578 -222.79229)
		(end 386.296408 -221.94012)
		(width 0.13208)
		(layer "F.Cu")
		(net "UART_PEX1_SDB_R_RX")
	)
	(segment
		(start 393.995402 -231.538018)
		(end 394.531088 -231.002332)
		(width 0.13208)
		(layer "F.Cu")
		(net "UART_PEX1_SDB_R_RX")
	)
	(segment
		(start 394.531088 -231.002332)
		(end 394.531088 -229.16007)
		(width 0.13208)
		(layer "F.Cu")
		(net "UART_PEX1_SDB_R_RX")
	)
	(segment
		(start 394.531088 -229.16007)
		(end 393.6365 -228.265482)
		(width 0.13208)
		(layer "F.Cu")
		(net "UART_PEX1_SDB_R_RX")
	)
	(segment
		(start 393.989306 -242.9764)
		(end 393.989306 -242.039648)
		(width 0.13208)
		(layer "F.Cu")
		(net "UART_PEX1_SDB_R_RX")
	)
	(segment
		(start 393.995402 -242.033552)
		(end 393.995402 -231.538018)
		(width 0.13208)
		(layer "F.Cu")
		(net "UART_PEX1_SDB_R_RX")
	)
	(segment
		(start 388.536688 -228.265482)
		(end 387.148578 -226.877372)
		(width 0.13208)
		(layer "F.Cu")
		(net "UART_PEX1_SDB_R_RX")
	)
	(segment
		(start 393.6365 -228.265482)
		(end 388.536688 -228.265482)
		(width 0.13208)
		(layer "F.Cu")
		(net "UART_PEX1_SDB_R_RX")
	)
	(segment
		(start 456.53071 -236.413294)
		(end 456.53071 -235.593382)
		(width 0.13208)
		(layer "F.Cu")
		(net "UART_PEX1_SDB_R_RX")
	)
	(via
		(at 388.366 -224.537524)
		(size 0.6604)
		(drill 0.3302)
		(layers "F.Cu" "B.Cu")
		(net "UART_PEX1_SDB_R_RX")
	)
	(via
		(at 456.53071 -236.413294)
		(size 0.508)
		(drill 0.254)
		(layers "F.Cu" "B.Cu")
		(net "UART_PEX1_SDB_R_RX")
	)
	(via
		(at 393.995402 -242.033552)
		(size 0.508)
		(drill 0.254)
		(layers "F.Cu" "B.Cu")
		(net "UART_PEX1_SDB_R_RX")
	)
	(via
		(at 385.686808 -221.94012)
		(size 0.508)
		(drill 0.254)
		(layers "F.Cu" "B.Cu")
		(net "UART_PEX1_SDB_R_RX")
	)
	(segment
		(start 385.686808 -221.94012)
		(end 384.683 -221.94012)
		(width 0.13208)
		(layer "B.Cu")
		(net "UART_PEX1_SDB_R_RX")
	)
	(segment
		(start 386.138674 -221.94012)
		(end 385.686808 -221.94012)
		(width 0.13208)
		(layer "B.Cu")
		(net "UART_PEX1_SDB_R_RX")
	)
	(segment
		(start 388.366 -224.167446)
		(end 386.138674 -221.94012)
		(width 0.13208)
		(layer "B.Cu")
		(net "UART_PEX1_SDB_R_RX")
	)
	(segment
		(start 388.366 -226.80295)
		(end 388.366 -224.537524)
		(width 0.13208)
		(layer "B.Cu")
		(net "UART_PEX1_SDB_R_RX")
	)
	(segment
		(start 388.366 -224.537524)
		(end 388.366 -224.167446)
		(width 0.13208)
		(layer "B.Cu")
		(net "UART_PEX1_SDB_R_RX")
	)
	(segment
		(start 415.31032 -243.409724)
		(end 416.103308 -242.616736)
		(width 0.15494)
		(layer "In15.Cu")
		(net "UART_PEX1_SDB_R_RX")
	)
	(segment
		(start 395.588236 -242.53698)
		(end 396.46098 -243.409724)
		(width 0.15494)
		(layer "In15.Cu")
		(net "UART_PEX1_SDB_R_RX")
	)
	(segment
		(start 416.103308 -242.616736)
		(end 440.368944 -242.616736)
		(width 0.15494)
		(layer "In15.Cu")
		(net "UART_PEX1_SDB_R_RX")
	)
	(segment
		(start 396.46098 -243.409724)
		(end 415.31032 -243.409724)
		(width 0.15494)
		(layer "In15.Cu")
		(net "UART_PEX1_SDB_R_RX")
	)
	(segment
		(start 454.14057 -238.803434)
		(end 456.53071 -236.413294)
		(width 0.15494)
		(layer "In15.Cu")
		(net "UART_PEX1_SDB_R_RX")
	)
	(segment
		(start 440.368944 -242.616736)
		(end 444.182246 -238.803434)
		(width 0.15494)
		(layer "In15.Cu")
		(net "UART_PEX1_SDB_R_RX")
	)
	(segment
		(start 393.995402 -242.033552)
		(end 394.49883 -242.53698)
		(width 0.15494)
		(layer "In15.Cu")
		(net "UART_PEX1_SDB_R_RX")
	)
	(segment
		(start 394.49883 -242.53698)
		(end 395.588236 -242.53698)
		(width 0.15494)
		(layer "In15.Cu")
		(net "UART_PEX1_SDB_R_RX")
	)
	(segment
		(start 444.182246 -238.803434)
		(end 454.14057 -238.803434)
		(width 0.15494)
		(layer "In15.Cu")
		(net "UART_PEX1_SDB_R_RX")
	)
	(segment
		(start 364.612428 -236.008926)
		(end 364.612428 -237.735364)
		(width 0.13208)
		(layer "F.Cu")
		(net "FT4232_SDB_EEPROM_SDA")
	)
	(segment
		(start 371.48008 -234.34675)
		(end 366.274604 -234.34675)
		(width 0.13208)
		(layer "F.Cu")
		(net "FT4232_SDB_EEPROM_SDA")
	)
	(segment
		(start 374.43918 -235.661708)
		(end 372.795038 -235.661708)
		(width 0.13208)
		(layer "F.Cu")
		(net "FT4232_SDB_EEPROM_SDA")
	)
	(segment
		(start 377.555252 -237.378748)
		(end 376.15622 -237.378748)
		(width 0.13208)
		(layer "F.Cu")
		(net "FT4232_SDB_EEPROM_SDA")
	)
	(segment
		(start 372.795038 -235.661708)
		(end 371.48008 -234.34675)
		(width 0.13208)
		(layer "F.Cu")
		(net "FT4232_SDB_EEPROM_SDA")
	)
	(segment
		(start 377.825 -236.601)
		(end 377.825 -237.109)
		(width 0.13208)
		(layer "F.Cu")
		(net "FT4232_SDB_EEPROM_SDA")
	)
	(segment
		(start 366.274604 -234.34675)
		(end 364.612428 -236.008926)
		(width 0.13208)
		(layer "F.Cu")
		(net "FT4232_SDB_EEPROM_SDA")
	)
	(segment
		(start 378.880624 -236.311186)
		(end 378.114814 -236.311186)
		(width 0.13208)
		(layer "F.Cu")
		(net "FT4232_SDB_EEPROM_SDA")
	)
	(segment
		(start 378.114814 -236.311186)
		(end 377.825 -236.601)
		(width 0.13208)
		(layer "F.Cu")
		(net "FT4232_SDB_EEPROM_SDA")
	)
	(segment
		(start 376.15622 -237.378748)
		(end 374.43918 -235.661708)
		(width 0.13208)
		(layer "F.Cu")
		(net "FT4232_SDB_EEPROM_SDA")
	)
	(segment
		(start 377.825 -237.109)
		(end 377.555252 -237.378748)
		(width 0.13208)
		(layer "F.Cu")
		(net "FT4232_SDB_EEPROM_SDA")
	)
	(segment
		(start 364.612428 -237.735364)
		(end 364.621064 -237.744)
		(width 0.13208)
		(layer "F.Cu")
		(net "FT4232_SDB_EEPROM_SDA")
	)
	(via
		(at 364.621064 -237.744)
		(size 0.508)
		(drill 0.254)
		(layers "F.Cu" "B.Cu")
		(net "FT4232_SDB_EEPROM_SDA")
	)
	(segment
		(start 365.86795 -237.744)
		(end 364.621064 -237.744)
		(width 0.13208)
		(layer "B.Cu")
		(net "FT4232_SDB_EEPROM_SDA")
	)
	(segment
		(start 53.462428 -22.537166)
		(end 53.462428 -22.097492)
		(width 0.13208)
		(layer "F.Cu")
		(net "SMB_BIC_I2C9_MUX0_SSD1_R_SDA")
	)
	(segment
		(start 123.27509 -94.891606)
		(end 122.357896 -94.891606)
		(width 0.13208)
		(layer "F.Cu")
		(net "SMB_BIC_I2C9_MUX0_SSD1_R_SDA")
	)
	(segment
		(start 53.462428 -22.097492)
		(end 53.22062 -21.855684)
		(width 0.13208)
		(layer "F.Cu")
		(net "SMB_BIC_I2C9_MUX0_SSD1_R_SDA")
	)
	(segment
		(start 52.935632 -21.570696)
		(end 52.935632 -20.789392)
		(width 0.13208)
		(layer "F.Cu")
		(net "SMB_BIC_I2C9_MUX0_SSD1_R_SDA")
	)
	(segment
		(start 122.357896 -94.891606)
		(end 121.53519 -94.891606)
		(width 0.13208)
		(layer "F.Cu")
		(net "SMB_BIC_I2C9_MUX0_SSD1_R_SDA")
	)
	(segment
		(start 53.22062 -21.855684)
		(end 52.935632 -21.570696)
		(width 0.13208)
		(layer "F.Cu")
		(net "SMB_BIC_I2C9_MUX0_SSD1_R_SDA")
	)
	(via
		(at 53.22062 -21.855684)
		(size 0.508)
		(drill 0.254)
		(layers "F.Cu" "B.Cu")
		(net "SMB_BIC_I2C9_MUX0_SSD1_R_SDA")
	)
	(via
		(at 122.357896 -94.891606)
		(size 0.508)
		(drill 0.254)
		(layers "F.Cu" "B.Cu")
		(net "SMB_BIC_I2C9_MUX0_SSD1_R_SDA")
	)
	(via
		(at 59.686444 -85.384894)
		(size 0.508)
		(drill 0.254)
		(layers "F.Cu" "B.Cu")
		(net "SMB_BIC_I2C9_MUX0_SSD1_R_SDA")
	)
	(segment
		(start 63.39332 -63.40348)
		(end 63.39332 -45.43425)
		(width 0.15494)
		(layer "In5.Cu")
		(net "SMB_BIC_I2C9_MUX0_SSD1_R_SDA")
	)
	(segment
		(start 59.686444 -85.384894)
		(end 60.287154 -84.784184)
		(width 0.15494)
		(layer "In5.Cu")
		(net "SMB_BIC_I2C9_MUX0_SSD1_R_SDA")
	)
	(segment
		(start 51.780694 -21.1582)
		(end 52.523136 -21.1582)
		(width 0.15494)
		(layer "In5.Cu")
		(net "SMB_BIC_I2C9_MUX0_SSD1_R_SDA")
	)
	(segment
		(start 50.280316 -22.658578)
		(end 51.780694 -21.1582)
		(width 0.15494)
		(layer "In5.Cu")
		(net "SMB_BIC_I2C9_MUX0_SSD1_R_SDA")
	)
	(segment
		(start 60.287154 -84.784184)
		(end 60.287154 -66.509646)
		(width 0.15494)
		(layer "In5.Cu")
		(net "SMB_BIC_I2C9_MUX0_SSD1_R_SDA")
	)
	(segment
		(start 50.280316 -26.711402)
		(end 50.280316 -22.658578)
		(width 0.15494)
		(layer "In5.Cu")
		(net "SMB_BIC_I2C9_MUX0_SSD1_R_SDA")
	)
	(segment
		(start 52.523136 -21.1582)
		(end 53.22062 -21.855684)
		(width 0.15494)
		(layer "In5.Cu")
		(net "SMB_BIC_I2C9_MUX0_SSD1_R_SDA")
	)
	(segment
		(start 60.287154 -66.509646)
		(end 63.39332 -63.40348)
		(width 0.15494)
		(layer "In5.Cu")
		(net "SMB_BIC_I2C9_MUX0_SSD1_R_SDA")
	)
	(segment
		(start 51.867054 -28.29814)
		(end 50.280316 -26.711402)
		(width 0.15494)
		(layer "In5.Cu")
		(net "SMB_BIC_I2C9_MUX0_SSD1_R_SDA")
	)
	(segment
		(start 63.39332 -45.43425)
		(end 51.867054 -33.907984)
		(width 0.15494)
		(layer "In5.Cu")
		(net "SMB_BIC_I2C9_MUX0_SSD1_R_SDA")
	)
	(segment
		(start 51.867054 -33.907984)
		(end 51.867054 -28.29814)
		(width 0.15494)
		(layer "In5.Cu")
		(net "SMB_BIC_I2C9_MUX0_SSD1_R_SDA")
	)
	(segment
		(start 59.8424 -87.757)
		(end 73.779126 -87.757)
		(width 0.15494)
		(layer "In15.Cu")
		(net "SMB_BIC_I2C9_MUX0_SSD1_R_SDA")
	)
	(segment
		(start 119.977662 -92.511372)
		(end 122.357896 -94.891606)
		(width 0.15494)
		(layer "In15.Cu")
		(net "SMB_BIC_I2C9_MUX0_SSD1_R_SDA")
	)
	(segment
		(start 59.257184 -85.814154)
		(end 59.257184 -87.171784)
		(width 0.15494)
		(layer "In15.Cu")
		(net "SMB_BIC_I2C9_MUX0_SSD1_R_SDA")
	)
	(segment
		(start 78.697582 -92.675456)
		(end 83.750404 -92.675456)
		(width 0.15494)
		(layer "In15.Cu")
		(net "SMB_BIC_I2C9_MUX0_SSD1_R_SDA")
	)
	(segment
		(start 59.257184 -87.171784)
		(end 59.8424 -87.757)
		(width 0.15494)
		(layer "In15.Cu")
		(net "SMB_BIC_I2C9_MUX0_SSD1_R_SDA")
	)
	(segment
		(start 101.584252 -90.184478)
		(end 102.551992 -90.184478)
		(width 0.15494)
		(layer "In15.Cu")
		(net "SMB_BIC_I2C9_MUX0_SSD1_R_SDA")
	)
	(segment
		(start 115.537996 -92.283534)
		(end 115.765834 -92.511372)
		(width 0.15494)
		(layer "In15.Cu")
		(net "SMB_BIC_I2C9_MUX0_SSD1_R_SDA")
	)
	(segment
		(start 102.551992 -90.184478)
		(end 104.651048 -92.283534)
		(width 0.15494)
		(layer "In15.Cu")
		(net "SMB_BIC_I2C9_MUX0_SSD1_R_SDA")
	)
	(segment
		(start 87.562436 -88.863424)
		(end 93.983302 -88.863424)
		(width 0.15494)
		(layer "In15.Cu")
		(net "SMB_BIC_I2C9_MUX0_SSD1_R_SDA")
	)
	(segment
		(start 100.658168 -89.258394)
		(end 101.584252 -90.184478)
		(width 0.15494)
		(layer "In15.Cu")
		(net "SMB_BIC_I2C9_MUX0_SSD1_R_SDA")
	)
	(segment
		(start 59.686444 -85.384894)
		(end 59.257184 -85.814154)
		(width 0.15494)
		(layer "In15.Cu")
		(net "SMB_BIC_I2C9_MUX0_SSD1_R_SDA")
	)
	(segment
		(start 104.651048 -92.283534)
		(end 115.537996 -92.283534)
		(width 0.15494)
		(layer "In15.Cu")
		(net "SMB_BIC_I2C9_MUX0_SSD1_R_SDA")
	)
	(segment
		(start 94.378272 -89.258394)
		(end 100.658168 -89.258394)
		(width 0.15494)
		(layer "In15.Cu")
		(net "SMB_BIC_I2C9_MUX0_SSD1_R_SDA")
	)
	(segment
		(start 115.765834 -92.511372)
		(end 119.977662 -92.511372)
		(width 0.15494)
		(layer "In15.Cu")
		(net "SMB_BIC_I2C9_MUX0_SSD1_R_SDA")
	)
	(segment
		(start 73.779126 -87.757)
		(end 78.697582 -92.675456)
		(width 0.15494)
		(layer "In15.Cu")
		(net "SMB_BIC_I2C9_MUX0_SSD1_R_SDA")
	)
	(segment
		(start 93.983302 -88.863424)
		(end 94.378272 -89.258394)
		(width 0.15494)
		(layer "In15.Cu")
		(net "SMB_BIC_I2C9_MUX0_SSD1_R_SDA")
	)
	(segment
		(start 83.750404 -92.675456)
		(end 87.562436 -88.863424)
		(width 0.15494)
		(layer "In15.Cu")
		(net "SMB_BIC_I2C9_MUX0_SSD1_R_SDA")
	)
	(segment
		(start 345.29395 -227.186998)
		(end 345.69019 -227.583238)
		(width 0.13208)
		(layer "F.Cu")
		(net "RST_SSD4_PERST_N")
	)
	(segment
		(start 346.06992 -230.25608)
		(end 346.583 -230.76916)
		(width 0.13208)
		(layer "F.Cu")
		(net "RST_SSD4_PERST_N")
	)
	(segment
		(start 345.69019 -228.98735)
		(end 346.06992 -229.36708)
		(width 0.13208)
		(layer "F.Cu")
		(net "RST_SSD4_PERST_N")
	)
	(segment
		(start 345.69019 -227.583238)
		(end 345.69019 -228.98735)
		(width 0.13208)
		(layer "F.Cu")
		(net "RST_SSD4_PERST_N")
	)
	(segment
		(start 346.06992 -229.36708)
		(end 346.06992 -230.25608)
		(width 0.13208)
		(layer "F.Cu")
		(net "RST_SSD4_PERST_N")
	)
	(segment
		(start 346.075 -232.9942)
		(end 346.583 -232.4862)
		(width 0.13208)
		(layer "F.Cu")
		(net "RST_SSD4_PERST_N")
	)
	(segment
		(start 346.075 -233.66095)
		(end 346.075 -232.9942)
		(width 0.13208)
		(layer "F.Cu")
		(net "RST_SSD4_PERST_N")
	)
	(segment
		(start 346.583 -230.76916)
		(end 346.583 -232.4862)
		(width 0.13208)
		(layer "F.Cu")
		(net "RST_SSD4_PERST_N")
	)
	(via
		(at 346.583 -232.4862)
		(size 0.762)
		(drill 0.381)
		(layers "F.Cu" "B.Cu")
		(net "RST_SSD4_PERST_N")
	)
	(segment
		(start 354.707444 -217.220038)
		(end 354.911406 -217.424)
		(width 0.13208)
		(layer "F.Cu")
		(net "RST_NIC7_PERST_N")
	)
	(segment
		(start 354.911406 -217.424)
		(end 356.235 -217.424)
		(width 0.13208)
		(layer "F.Cu")
		(net "RST_NIC7_PERST_N")
	)
	(segment
		(start 350.893888 -217.587068)
		(end 351.260918 -217.220038)
		(width 0.13208)
		(layer "F.Cu")
		(net "RST_NIC7_PERST_N")
	)
	(segment
		(start 356.235 -217.424)
		(end 357.61295 -217.424)
		(width 0.13208)
		(layer "F.Cu")
		(net "RST_NIC7_PERST_N")
	)
	(segment
		(start 351.260918 -217.220038)
		(end 354.707444 -217.220038)
		(width 0.13208)
		(layer "F.Cu")
		(net "RST_NIC7_PERST_N")
	)
	(via
		(at 356.235 -217.424)
		(size 0.762)
		(drill 0.381)
		(layers "F.Cu" "B.Cu")
		(net "RST_NIC7_PERST_N")
	)
	(segment
		(start 418.440108 -223.89084)
		(end 419.45306 -222.877888)
		(width 0.13208)
		(layer "F.Cu")
		(net "UART_PEX0_SDB_R_RX")
	)
	(segment
		(start 454.542398 -235.623608)
		(end 454.542398 -236.346492)
		(width 0.13208)
		(layer "F.Cu")
		(net "UART_PEX0_SDB_R_RX")
	)
	(segment
		(start 419.45306 -222.877888)
		(end 419.45306 -221.32163)
		(width 0.13208)
		(layer "F.Cu")
		(net "UART_PEX0_SDB_R_RX")
	)
	(via
		(at 385.703318 -223.240092)
		(size 0.508)
		(drill 0.254)
		(layers "F.Cu" "B.Cu")
		(net "UART_PEX0_SDB_R_RX")
	)
	(via
		(at 454.542398 -236.346492)
		(size 0.508)
		(drill 0.254)
		(layers "F.Cu" "B.Cu")
		(net "UART_PEX0_SDB_R_RX")
	)
	(via
		(at 418.440108 -223.89084)
		(size 0.508)
		(drill 0.254)
		(layers "F.Cu" "B.Cu")
		(net "UART_PEX0_SDB_R_RX")
	)
	(segment
		(start 385.703318 -223.240092)
		(end 384.683 -223.240092)
		(width 0.13208)
		(layer "B.Cu")
		(net "UART_PEX0_SDB_R_RX")
	)
	(segment
		(start 387.35 -226.80295)
		(end 387.35 -224.886774)
		(width 0.13208)
		(layer "B.Cu")
		(net "UART_PEX0_SDB_R_RX")
	)
	(segment
		(start 387.35 -224.886774)
		(end 385.703318 -223.240092)
		(width 0.13208)
		(layer "B.Cu")
		(net "UART_PEX0_SDB_R_RX")
	)
	(segment
		(start 430.737518 -236.18825)
		(end 443.80785 -236.18825)
		(width 0.15494)
		(layer "In13.Cu")
		(net "UART_PEX0_SDB_R_RX")
	)
	(segment
		(start 418.440108 -223.89084)
		(end 430.737518 -236.18825)
		(width 0.15494)
		(layer "In13.Cu")
		(net "UART_PEX0_SDB_R_RX")
	)
	(segment
		(start 452.8058 -233.7308)
		(end 453.77862 -233.7308)
		(width 0.15494)
		(layer "In13.Cu")
		(net "UART_PEX0_SDB_R_RX")
	)
	(segment
		(start 385.703318 -223.240092)
		(end 417.78936 -223.240092)
		(width 0.15494)
		(layer "In13.Cu")
		(net "UART_PEX0_SDB_R_RX")
	)
	(segment
		(start 417.78936 -223.240092)
		(end 418.440108 -223.89084)
		(width 0.15494)
		(layer "In13.Cu")
		(net "UART_PEX0_SDB_R_RX")
	)
	(segment
		(start 451.08622 -237.43158)
		(end 452.0946 -236.4232)
		(width 0.15494)
		(layer "In13.Cu")
		(net "UART_PEX0_SDB_R_RX")
	)
	(segment
		(start 453.77862 -233.7308)
		(end 456.028552 -235.980732)
		(width 0.15494)
		(layer "In13.Cu")
		(net "UART_PEX0_SDB_R_RX")
	)
	(segment
		(start 443.80785 -236.18825)
		(end 445.05118 -237.43158)
		(width 0.15494)
		(layer "In13.Cu")
		(net "UART_PEX0_SDB_R_RX")
	)
	(segment
		(start 456.028552 -235.980732)
		(end 456.028552 -236.561122)
		(width 0.15494)
		(layer "In13.Cu")
		(net "UART_PEX0_SDB_R_RX")
	)
	(segment
		(start 445.05118 -237.43158)
		(end 451.08622 -237.43158)
		(width 0.15494)
		(layer "In13.Cu")
		(net "UART_PEX0_SDB_R_RX")
	)
	(segment
		(start 452.0946 -236.4232)
		(end 452.0946 -234.442)
		(width 0.15494)
		(layer "In13.Cu")
		(net "UART_PEX0_SDB_R_RX")
	)
	(segment
		(start 455.006964 -236.811058)
		(end 454.542398 -236.346492)
		(width 0.15494)
		(layer "In13.Cu")
		(net "UART_PEX0_SDB_R_RX")
	)
	(segment
		(start 456.028552 -236.561122)
		(end 455.778616 -236.811058)
		(width 0.15494)
		(layer "In13.Cu")
		(net "UART_PEX0_SDB_R_RX")
	)
	(segment
		(start 452.0946 -234.442)
		(end 452.8058 -233.7308)
		(width 0.15494)
		(layer "In13.Cu")
		(net "UART_PEX0_SDB_R_RX")
	)
	(segment
		(start 455.778616 -236.811058)
		(end 455.006964 -236.811058)
		(width 0.15494)
		(layer "In13.Cu")
		(net "UART_PEX0_SDB_R_RX")
	)
	(segment
		(start 89.19591 -308.606444)
		(end 89.19591 -308.696106)
		(width 0.13208)
		(layer "F.Cu")
		(net "PEX0_SPARE7")
	)
	(segment
		(start 88.716104 -309.175912)
		(end 88.383618 -309.508398)
		(width 0.13208)
		(layer "F.Cu")
		(net "PEX0_SPARE7")
	)
	(segment
		(start 89.19591 -308.696106)
		(end 88.716104 -309.175912)
		(width 0.13208)
		(layer "F.Cu")
		(net "PEX0_SPARE7")
	)
	(segment
		(start 88.383618 -309.508398)
		(end 88.060276 -309.508398)
		(width 0.13208)
		(layer "F.Cu")
		(net "PEX0_SPARE7")
	)
	(segment
		(start 62.024768 -308.724808)
		(end 61.549788 -308.249828)
		(width 0.13208)
		(layer "F.Cu")
		(net "PEX0_SPARE7")
	)
	(via
		(at 87.707978 -310.184038)
		(size 0.6604)
		(drill 0.3302)
		(layers "F.Cu" "B.Cu")
		(net "PEX0_SPARE7")
	)
	(via
		(at 62.024768 -308.724808)
		(size 0.4064)
		(drill 0.2032)
		(layers "F.Cu" "B.Cu")
		(net "PEX0_SPARE7")
	)
	(via
		(at 88.716104 -309.175912)
		(size 0.508)
		(drill 0.254)
		(layers "F.Cu" "B.Cu")
		(net "PEX0_SPARE7")
	)
	(segment
		(start 62.320932 -308.724808)
		(end 63.175896 -309.579772)
		(width 0.13208)
		(layer "B.Cu")
		(net "PEX0_SPARE7")
	)
	(segment
		(start 64.03975 -313.54522)
		(end 84.346796 -313.54522)
		(width 0.13208)
		(layer "B.Cu")
		(net "PEX0_SPARE7")
	)
	(segment
		(start 63.91275 -313.41822)
		(end 64.03975 -313.54522)
		(width 0.13208)
		(layer "B.Cu")
		(net "PEX0_SPARE7")
	)
	(segment
		(start 63.91275 -309.90032)
		(end 63.91275 -313.41822)
		(width 0.13208)
		(layer "B.Cu")
		(net "PEX0_SPARE7")
	)
	(segment
		(start 63.175896 -309.579772)
		(end 63.592202 -309.579772)
		(width 0.13208)
		(layer "B.Cu")
		(net "PEX0_SPARE7")
	)
	(segment
		(start 63.592202 -309.579772)
		(end 63.91275 -309.90032)
		(width 0.13208)
		(layer "B.Cu")
		(net "PEX0_SPARE7")
	)
	(segment
		(start 87.707978 -310.184038)
		(end 88.716104 -309.175912)
		(width 0.13208)
		(layer "B.Cu")
		(net "PEX0_SPARE7")
	)
	(segment
		(start 84.346796 -313.54522)
		(end 87.707978 -310.184038)
		(width 0.13208)
		(layer "B.Cu")
		(net "PEX0_SPARE7")
	)
	(segment
		(start 62.024768 -308.724808)
		(end 62.320932 -308.724808)
		(width 0.13208)
		(layer "B.Cu")
		(net "PEX0_SPARE7")
	)
	(segment
		(start 4.050792 -34.032444)
		(end 4.050792 -34.472118)
		(width 0.13208)
		(layer "F.Cu")
		(net "SMB_BIC_I2C9_MUX0_SSD0_R_SDA")
	)
	(segment
		(start 3.523996 -33.505648)
		(end 3.808984 -33.790636)
		(width 0.13208)
		(layer "F.Cu")
		(net "SMB_BIC_I2C9_MUX0_SSD0_R_SDA")
	)
	(segment
		(start 3.523996 -32.724344)
		(end 3.523996 -33.505648)
		(width 0.13208)
		(layer "F.Cu")
		(net "SMB_BIC_I2C9_MUX0_SSD0_R_SDA")
	)
	(segment
		(start 122.357896 -97.177606)
		(end 121.53519 -97.177606)
		(width 0.13208)
		(layer "F.Cu")
		(net "SMB_BIC_I2C9_MUX0_SSD0_R_SDA")
	)
	(segment
		(start 3.808984 -33.790636)
		(end 4.050792 -34.032444)
		(width 0.13208)
		(layer "F.Cu")
		(net "SMB_BIC_I2C9_MUX0_SSD0_R_SDA")
	)
	(segment
		(start 123.27509 -97.177606)
		(end 122.357896 -97.177606)
		(width 0.13208)
		(layer "F.Cu")
		(net "SMB_BIC_I2C9_MUX0_SSD0_R_SDA")
	)
	(via
		(at 122.357896 -97.177606)
		(size 0.508)
		(drill 0.254)
		(layers "F.Cu" "B.Cu")
		(net "SMB_BIC_I2C9_MUX0_SSD0_R_SDA")
	)
	(via
		(at 31.941262 -92.927424)
		(size 0.508)
		(drill 0.254)
		(layers "F.Cu" "B.Cu")
		(net "SMB_BIC_I2C9_MUX0_SSD0_R_SDA")
	)
	(via
		(at 3.808984 -33.790636)
		(size 0.508)
		(drill 0.254)
		(layers "F.Cu" "B.Cu")
		(net "SMB_BIC_I2C9_MUX0_SSD0_R_SDA")
	)
	(segment
		(start 10.879328 -32.644588)
		(end 8.049768 -35.474148)
		(width 0.15494)
		(layer "In5.Cu")
		(net "SMB_BIC_I2C9_MUX0_SSD0_R_SDA")
	)
	(segment
		(start 14.080236 -28.40101)
		(end 12.100052 -30.381194)
		(width 0.15494)
		(layer "In5.Cu")
		(net "SMB_BIC_I2C9_MUX0_SSD0_R_SDA")
	)
	(segment
		(start 10.879328 -30.855158)
		(end 10.879328 -32.644588)
		(width 0.15494)
		(layer "In5.Cu")
		(net "SMB_BIC_I2C9_MUX0_SSD0_R_SDA")
	)
	(segment
		(start 21.646134 -26.924)
		(end 18.3134 -26.924)
		(width 0.15494)
		(layer "In5.Cu")
		(net "SMB_BIC_I2C9_MUX0_SSD0_R_SDA")
	)
	(segment
		(start 4.697222 -34.678874)
		(end 3.808984 -33.790636)
		(width 0.15494)
		(layer "In5.Cu")
		(net "SMB_BIC_I2C9_MUX0_SSD0_R_SDA")
	)
	(segment
		(start 6.277356 -35.474148)
		(end 5.482082 -34.678874)
		(width 0.15494)
		(layer "In5.Cu")
		(net "SMB_BIC_I2C9_MUX0_SSD0_R_SDA")
	)
	(segment
		(start 18.3134 -26.924)
		(end 16.83639 -28.40101)
		(width 0.15494)
		(layer "In5.Cu")
		(net "SMB_BIC_I2C9_MUX0_SSD0_R_SDA")
	)
	(segment
		(start 23.892256 -29.170122)
		(end 21.646134 -26.924)
		(width 0.15494)
		(layer "In5.Cu")
		(net "SMB_BIC_I2C9_MUX0_SSD0_R_SDA")
	)
	(segment
		(start 16.83639 -28.40101)
		(end 14.080236 -28.40101)
		(width 0.15494)
		(layer "In5.Cu")
		(net "SMB_BIC_I2C9_MUX0_SSD0_R_SDA")
	)
	(segment
		(start 36.68268 -46.6852)
		(end 23.892256 -33.894776)
		(width 0.15494)
		(layer "In5.Cu")
		(net "SMB_BIC_I2C9_MUX0_SSD0_R_SDA")
	)
	(segment
		(start 11.353292 -30.381194)
		(end 10.879328 -30.855158)
		(width 0.15494)
		(layer "In5.Cu")
		(net "SMB_BIC_I2C9_MUX0_SSD0_R_SDA")
	)
	(segment
		(start 36.68268 -88.186006)
		(end 36.68268 -46.6852)
		(width 0.15494)
		(layer "In5.Cu")
		(net "SMB_BIC_I2C9_MUX0_SSD0_R_SDA")
	)
	(segment
		(start 5.482082 -34.678874)
		(end 4.697222 -34.678874)
		(width 0.15494)
		(layer "In5.Cu")
		(net "SMB_BIC_I2C9_MUX0_SSD0_R_SDA")
	)
	(segment
		(start 23.892256 -33.894776)
		(end 23.892256 -29.170122)
		(width 0.15494)
		(layer "In5.Cu")
		(net "SMB_BIC_I2C9_MUX0_SSD0_R_SDA")
	)
	(segment
		(start 12.100052 -30.381194)
		(end 11.353292 -30.381194)
		(width 0.15494)
		(layer "In5.Cu")
		(net "SMB_BIC_I2C9_MUX0_SSD0_R_SDA")
	)
	(segment
		(start 8.049768 -35.474148)
		(end 6.277356 -35.474148)
		(width 0.15494)
		(layer "In5.Cu")
		(net "SMB_BIC_I2C9_MUX0_SSD0_R_SDA")
	)
	(segment
		(start 31.941262 -92.927424)
		(end 36.68268 -88.186006)
		(width 0.15494)
		(layer "In5.Cu")
		(net "SMB_BIC_I2C9_MUX0_SSD0_R_SDA")
	)
	(segment
		(start 122.357896 -97.177606)
		(end 121.80189 -96.6216)
		(width 0.15494)
		(layer "In15.Cu")
		(net "SMB_BIC_I2C9_MUX0_SSD0_R_SDA")
	)
	(segment
		(start 88.6968 -91.96832)
		(end 85.332824 -95.332296)
		(width 0.15494)
		(layer "In15.Cu")
		(net "SMB_BIC_I2C9_MUX0_SSD0_R_SDA")
	)
	(segment
		(start 121.80189 -96.6216)
		(end 116.332254 -96.6216)
		(width 0.15494)
		(layer "In15.Cu")
		(net "SMB_BIC_I2C9_MUX0_SSD0_R_SDA")
	)
	(segment
		(start 114.782854 -98.171)
		(end 111.400844 -98.171)
		(width 0.15494)
		(layer "In15.Cu")
		(net "SMB_BIC_I2C9_MUX0_SSD0_R_SDA")
	)
	(segment
		(start 73.751694 -92.243148)
		(end 58.25871 -92.243148)
		(width 0.15494)
		(layer "In15.Cu")
		(net "SMB_BIC_I2C9_MUX0_SSD0_R_SDA")
	)
	(segment
		(start 111.400844 -98.171)
		(end 108.421424 -95.19158)
		(width 0.15494)
		(layer "In15.Cu")
		(net "SMB_BIC_I2C9_MUX0_SSD0_R_SDA")
	)
	(segment
		(start 104.193848 -95.19158)
		(end 100.970588 -91.96832)
		(width 0.15494)
		(layer "In15.Cu")
		(net "SMB_BIC_I2C9_MUX0_SSD0_R_SDA")
	)
	(segment
		(start 57.791096 -91.775534)
		(end 33.093152 -91.775534)
		(width 0.15494)
		(layer "In15.Cu")
		(net "SMB_BIC_I2C9_MUX0_SSD0_R_SDA")
	)
	(segment
		(start 33.093152 -91.775534)
		(end 31.941262 -92.927424)
		(width 0.15494)
		(layer "In15.Cu")
		(net "SMB_BIC_I2C9_MUX0_SSD0_R_SDA")
	)
	(segment
		(start 108.421424 -95.19158)
		(end 104.193848 -95.19158)
		(width 0.15494)
		(layer "In15.Cu")
		(net "SMB_BIC_I2C9_MUX0_SSD0_R_SDA")
	)
	(segment
		(start 58.25871 -92.243148)
		(end 57.791096 -91.775534)
		(width 0.15494)
		(layer "In15.Cu")
		(net "SMB_BIC_I2C9_MUX0_SSD0_R_SDA")
	)
	(segment
		(start 76.840842 -95.332296)
		(end 73.751694 -92.243148)
		(width 0.15494)
		(layer "In15.Cu")
		(net "SMB_BIC_I2C9_MUX0_SSD0_R_SDA")
	)
	(segment
		(start 116.332254 -96.6216)
		(end 114.782854 -98.171)
		(width 0.15494)
		(layer "In15.Cu")
		(net "SMB_BIC_I2C9_MUX0_SSD0_R_SDA")
	)
	(segment
		(start 85.332824 -95.332296)
		(end 76.840842 -95.332296)
		(width 0.15494)
		(layer "In15.Cu")
		(net "SMB_BIC_I2C9_MUX0_SSD0_R_SDA")
	)
	(segment
		(start 100.970588 -91.96832)
		(end 88.6968 -91.96832)
		(width 0.15494)
		(layer "In15.Cu")
		(net "SMB_BIC_I2C9_MUX0_SSD0_R_SDA")
	)
	(segment
		(start 338.893912 -230.181912)
		(end 337.947 -231.128824)
		(width 0.13208)
		(layer "F.Cu")
		(net "FM_SOL_UART_CH_SEL_R")
	)
	(segment
		(start 337.947 -231.128824)
		(end 337.947 -232.4862)
		(width 0.13208)
		(layer "F.Cu")
		(net "FM_SOL_UART_CH_SEL_R")
	)
	(segment
		(start 337.947 -232.4862)
		(end 337.947 -233.66095)
		(width 0.13208)
		(layer "F.Cu")
		(net "FM_SOL_UART_CH_SEL_R")
	)
	(segment
		(start 338.893912 -227.987098)
		(end 338.893912 -230.181912)
		(width 0.13208)
		(layer "F.Cu")
		(net "FM_SOL_UART_CH_SEL_R")
	)
	(via
		(at 337.947 -232.4862)
		(size 0.762)
		(drill 0.381)
		(layers "F.Cu" "B.Cu")
		(net "FM_SOL_UART_CH_SEL_R")
	)
	(segment
		(start 348.493842 -215.187022)
		(end 348.893638 -214.787226)
		(width 0.13208)
		(layer "F.Cu")
		(net "RST_PEX_NIC4_PERST_R_N")
	)
	(segment
		(start 354.838 -179.578)
		(end 355.45395 -179.578)
		(width 0.13208)
		(layer "F.Cu")
		(net "RST_PEX_NIC4_PERST_R_N")
	)
	(segment
		(start 354.22205 -179.578)
		(end 354.838 -179.578)
		(width 0.13208)
		(layer "F.Cu")
		(net "RST_PEX_NIC4_PERST_R_N")
	)
	(via
		(at 354.838 -179.578)
		(size 0.508)
		(drill 0.254)
		(layers "F.Cu" "B.Cu")
		(net "RST_PEX_NIC4_PERST_R_N")
	)
	(via
		(at 367.420652 -182.765192)
		(size 0.508)
		(drill 0.254)
		(layers "F.Cu" "B.Cu")
		(net "RST_PEX_NIC4_PERST_R_N")
	)
	(via
		(at 348.893638 -214.787226)
		(size 0.4572)
		(drill 0.254)
		(layers "F.Cu" "B.Cu")
		(net "RST_PEX_NIC4_PERST_R_N")
	)
	(segment
		(start 366.6236 -195.910454)
		(end 366.6236 -183.562244)
		(width 0.15494)
		(layer "In7.Cu")
		(net "RST_PEX_NIC4_PERST_R_N")
	)
	(segment
		(start 366.6236 -183.562244)
		(end 367.420652 -182.765192)
		(width 0.15494)
		(layer "In7.Cu")
		(net "RST_PEX_NIC4_PERST_R_N")
	)
	(segment
		(start 354.7364 -206.961232)
		(end 354.7364 -205.981808)
		(width 0.15494)
		(layer "In7.Cu")
		(net "RST_PEX_NIC4_PERST_R_N")
	)
	(segment
		(start 352.427286 -209.270346)
		(end 354.7364 -206.961232)
		(width 0.15494)
		(layer "In7.Cu")
		(net "RST_PEX_NIC4_PERST_R_N")
	)
	(segment
		(start 354.7364 -205.981808)
		(end 357.670608 -203.0476)
		(width 0.15494)
		(layer "In7.Cu")
		(net "RST_PEX_NIC4_PERST_R_N")
	)
	(segment
		(start 358.6988 -203.0476)
		(end 363.323124 -198.423276)
		(width 0.15494)
		(layer "In7.Cu")
		(net "RST_PEX_NIC4_PERST_R_N")
	)
	(segment
		(start 351.57537 -214.38743)
		(end 352.427286 -213.535514)
		(width 0.15494)
		(layer "In7.Cu")
		(net "RST_PEX_NIC4_PERST_R_N")
	)
	(segment
		(start 349.293434 -214.38743)
		(end 351.57537 -214.38743)
		(width 0.0889)
		(layer "In7.Cu")
		(net "RST_PEX_NIC4_PERST_R_N")
	)
	(segment
		(start 348.893638 -214.787226)
		(end 349.293434 -214.38743)
		(width 0.0889)
		(layer "In7.Cu")
		(net "RST_PEX_NIC4_PERST_R_N")
	)
	(segment
		(start 352.427286 -213.535514)
		(end 352.427286 -209.270346)
		(width 0.15494)
		(layer "In7.Cu")
		(net "RST_PEX_NIC4_PERST_R_N")
	)
	(segment
		(start 363.323124 -198.423276)
		(end 364.110778 -198.423276)
		(width 0.15494)
		(layer "In7.Cu")
		(net "RST_PEX_NIC4_PERST_R_N")
	)
	(segment
		(start 364.110778 -198.423276)
		(end 366.6236 -195.910454)
		(width 0.15494)
		(layer "In7.Cu")
		(net "RST_PEX_NIC4_PERST_R_N")
	)
	(segment
		(start 357.670608 -203.0476)
		(end 358.6988 -203.0476)
		(width 0.15494)
		(layer "In7.Cu")
		(net "RST_PEX_NIC4_PERST_R_N")
	)
	(segment
		(start 364.53191 -181.829202)
		(end 363.662722 -181.829202)
		(width 0.15494)
		(layer "In13.Cu")
		(net "RST_PEX_NIC4_PERST_R_N")
	)
	(segment
		(start 367.420652 -182.765192)
		(end 365.4679 -182.765192)
		(width 0.15494)
		(layer "In13.Cu")
		(net "RST_PEX_NIC4_PERST_R_N")
	)
	(segment
		(start 362.41101 -180.57749)
		(end 355.83749 -180.57749)
		(width 0.15494)
		(layer "In13.Cu")
		(net "RST_PEX_NIC4_PERST_R_N")
	)
	(segment
		(start 365.4679 -182.765192)
		(end 364.53191 -181.829202)
		(width 0.15494)
		(layer "In13.Cu")
		(net "RST_PEX_NIC4_PERST_R_N")
	)
	(segment
		(start 363.662722 -181.829202)
		(end 362.41101 -180.57749)
		(width 0.15494)
		(layer "In13.Cu")
		(net "RST_PEX_NIC4_PERST_R_N")
	)
	(segment
		(start 355.83749 -180.57749)
		(end 354.838 -179.578)
		(width 0.15494)
		(layer "In13.Cu")
		(net "RST_PEX_NIC4_PERST_R_N")
	)
	(segment
		(start 390.054846 -26.58999)
		(end 389.56488 -26.58999)
		(width 0.13462)
		(layer "F.Cu")
		(net "CLK_100M_DB800ZL_SSD13_R_DN")
	)
	(segment
		(start 346.0369 -87.84336)
		(end 346.33789 -88.14435)
		(width 0.13462)
		(layer "F.Cu")
		(net "CLK_100M_DB800ZL_SSD13_R_DN")
	)
	(segment
		(start 345.339416 -87.84336)
		(end 346.0369 -87.84336)
		(width 0.13462)
		(layer "F.Cu")
		(net "CLK_100M_DB800ZL_SSD13_R_DN")
	)
	(segment
		(start 345.013026 -88.16975)
		(end 345.339416 -87.84336)
		(width 0.13462)
		(layer "F.Cu")
		(net "CLK_100M_DB800ZL_SSD13_R_DN")
	)
	(segment
		(start 390.216136 -26.75128)
		(end 390.054846 -26.58999)
		(width 0.13462)
		(layer "F.Cu")
		(net "CLK_100M_DB800ZL_SSD13_R_DN")
	)
	(segment
		(start 391.281412 -26.479246)
		(end 391.009378 -26.75128)
		(width 0.13462)
		(layer "F.Cu")
		(net "CLK_100M_DB800ZL_SSD13_R_DN")
	)
	(segment
		(start 391.009378 -26.75128)
		(end 390.216136 -26.75128)
		(width 0.13462)
		(layer "F.Cu")
		(net "CLK_100M_DB800ZL_SSD13_R_DN")
	)
	(via
		(at 346.33789 -88.14435)
		(size 0.508)
		(drill 0.254)
		(layers "F.Cu" "B.Cu")
		(net "CLK_100M_DB800ZL_SSD13_R_DN")
	)
	(via
		(at 391.281412 -26.479246)
		(size 0.508)
		(drill 0.254)
		(layers "F.Cu" "B.Cu")
		(net "CLK_100M_DB800ZL_SSD13_R_DN")
	)
	(segment
		(start 392.22934 -36.77666)
		(end 392.22934 -27.076654)
		(width 0.1651)
		(layer "In13.Cu")
		(net "CLK_100M_DB800ZL_SSD13_R_DN")
	)
	(segment
		(start 375.30024 -75.54214)
		(end 386.2324 -64.60998)
		(width 0.1651)
		(layer "In13.Cu")
		(net "CLK_100M_DB800ZL_SSD13_R_DN")
	)
	(segment
		(start 386.2324 -43.914314)
		(end 387.03885 -41.96715)
		(width 0.1651)
		(layer "In13.Cu")
		(net "CLK_100M_DB800ZL_SSD13_R_DN")
	)
	(segment
		(start 387.03885 -41.96715)
		(end 392.22934 -36.77666)
		(width 0.1651)
		(layer "In13.Cu")
		(net "CLK_100M_DB800ZL_SSD13_R_DN")
	)
	(segment
		(start 392.22934 -27.076654)
		(end 391.922762 -26.770076)
		(width 0.1651)
		(layer "In13.Cu")
		(net "CLK_100M_DB800ZL_SSD13_R_DN")
	)
	(segment
		(start 350.89084 -79.60614)
		(end 361.02544 -79.60614)
		(width 0.1651)
		(layer "In13.Cu")
		(net "CLK_100M_DB800ZL_SSD13_R_DN")
	)
	(segment
		(start 346.33789 -88.14435)
		(end 346.62872 -87.85352)
		(width 0.1651)
		(layer "In13.Cu")
		(net "CLK_100M_DB800ZL_SSD13_R_DN")
	)
	(segment
		(start 386.2324 -64.60998)
		(end 386.2324 -43.914314)
		(width 0.1651)
		(layer "In13.Cu")
		(net "CLK_100M_DB800ZL_SSD13_R_DN")
	)
	(segment
		(start 346.62872 -87.85352)
		(end 348.02826 -87.85352)
		(width 0.1651)
		(layer "In13.Cu")
		(net "CLK_100M_DB800ZL_SSD13_R_DN")
	)
	(segment
		(start 349.50654 -86.37524)
		(end 349.50654 -80.99044)
		(width 0.1651)
		(layer "In13.Cu")
		(net "CLK_100M_DB800ZL_SSD13_R_DN")
	)
	(segment
		(start 361.02544 -79.60614)
		(end 365.08944 -75.54214)
		(width 0.1651)
		(layer "In13.Cu")
		(net "CLK_100M_DB800ZL_SSD13_R_DN")
	)
	(segment
		(start 349.50654 -80.99044)
		(end 350.89084 -79.60614)
		(width 0.1651)
		(layer "In13.Cu")
		(net "CLK_100M_DB800ZL_SSD13_R_DN")
	)
	(segment
		(start 391.922762 -26.770076)
		(end 391.572242 -26.770076)
		(width 0.1651)
		(layer "In13.Cu")
		(net "CLK_100M_DB800ZL_SSD13_R_DN")
	)
	(segment
		(start 348.02826 -87.85352)
		(end 349.50654 -86.37524)
		(width 0.1651)
		(layer "In13.Cu")
		(net "CLK_100M_DB800ZL_SSD13_R_DN")
	)
	(segment
		(start 391.572242 -26.770076)
		(end 391.281412 -26.479246)
		(width 0.1651)
		(layer "In13.Cu")
		(net "CLK_100M_DB800ZL_SSD13_R_DN")
	)
	(segment
		(start 365.08944 -75.54214)
		(end 375.30024 -75.54214)
		(width 0.1651)
		(layer "In13.Cu")
		(net "CLK_100M_DB800ZL_SSD13_R_DN")
	)
	(segment
		(start 21.53412 -260.027674)
		(end 22.473666 -260.027674)
		(width 0.13208)
		(layer "F.Cu")
		(net "PEX0_SYS_ERR_N")
	)
	(segment
		(start 21.371814 -259.865368)
		(end 21.53412 -260.027674)
		(width 0.13208)
		(layer "F.Cu")
		(net "PEX0_SYS_ERR_N")
	)
	(segment
		(start 21.371814 -259.346192)
		(end 21.371814 -259.865368)
		(width 0.13208)
		(layer "F.Cu")
		(net "PEX0_SYS_ERR_N")
	)
	(segment
		(start 64.399922 -283.549852)
		(end 64.874902 -284.024832)
		(width 0.13208)
		(layer "F.Cu")
		(net "PEX0_SYS_ERR_N")
	)
	(via
		(at 64.874902 -284.024832)
		(size 0.4064)
		(drill 0.2032)
		(layers "F.Cu" "B.Cu")
		(net "PEX0_SYS_ERR_N")
	)
	(via
		(at 22.473666 -260.027674)
		(size 0.508)
		(drill 0.254)
		(layers "F.Cu" "B.Cu")
		(net "PEX0_SYS_ERR_N")
	)
	(segment
		(start 56.799988 -284.092904)
		(end 56.799988 -282.391612)
		(width 0.13208)
		(layer "B.Cu")
		(net "PEX0_SYS_ERR_N")
	)
	(segment
		(start 32.6644 -262.7122)
		(end 29.264356 -259.312156)
		(width 0.13208)
		(layer "B.Cu")
		(net "PEX0_SYS_ERR_N")
	)
	(segment
		(start 59.9948 -285.3944)
		(end 59.7408 -285.1404)
		(width 0.13208)
		(layer "B.Cu")
		(net "PEX0_SYS_ERR_N")
	)
	(segment
		(start 64.874902 -284.024832)
		(end 64.46266 -283.61259)
		(width 0.13208)
		(layer "B.Cu")
		(net "PEX0_SYS_ERR_N")
	)
	(segment
		(start 59.7408 -285.1404)
		(end 59.7408 -284.8102)
		(width 0.13208)
		(layer "B.Cu")
		(net "PEX0_SYS_ERR_N")
	)
	(segment
		(start 57.275222 -281.916378)
		(end 57.275222 -271.128998)
		(width 0.13208)
		(layer "B.Cu")
		(net "PEX0_SYS_ERR_N")
	)
	(segment
		(start 25.480264 -257.723386)
		(end 23.26132 -257.723386)
		(width 0.13208)
		(layer "B.Cu")
		(net "PEX0_SYS_ERR_N")
	)
	(segment
		(start 57.237884 -284.5308)
		(end 56.799988 -284.092904)
		(width 0.13208)
		(layer "B.Cu")
		(net "PEX0_SYS_ERR_N")
	)
	(segment
		(start 59.4614 -284.5308)
		(end 57.237884 -284.5308)
		(width 0.13208)
		(layer "B.Cu")
		(net "PEX0_SYS_ERR_N")
	)
	(segment
		(start 29.264356 -259.312156)
		(end 27.069034 -259.312156)
		(width 0.13208)
		(layer "B.Cu")
		(net "PEX0_SYS_ERR_N")
	)
	(segment
		(start 64.46266 -283.61259)
		(end 62.754764 -283.61259)
		(width 0.13208)
		(layer "B.Cu")
		(net "PEX0_SYS_ERR_N")
	)
	(segment
		(start 62.53988 -285.095442)
		(end 62.240922 -285.3944)
		(width 0.13208)
		(layer "B.Cu")
		(net "PEX0_SYS_ERR_N")
	)
	(segment
		(start 62.53988 -283.827474)
		(end 62.53988 -285.095442)
		(width 0.13208)
		(layer "B.Cu")
		(net "PEX0_SYS_ERR_N")
	)
	(segment
		(start 57.275222 -271.128998)
		(end 48.858424 -262.7122)
		(width 0.13208)
		(layer "B.Cu")
		(net "PEX0_SYS_ERR_N")
	)
	(segment
		(start 22.473666 -258.51104)
		(end 22.473666 -260.027674)
		(width 0.13208)
		(layer "B.Cu")
		(net "PEX0_SYS_ERR_N")
	)
	(segment
		(start 48.858424 -262.7122)
		(end 32.6644 -262.7122)
		(width 0.13208)
		(layer "B.Cu")
		(net "PEX0_SYS_ERR_N")
	)
	(segment
		(start 56.799988 -282.391612)
		(end 57.275222 -281.916378)
		(width 0.13208)
		(layer "B.Cu")
		(net "PEX0_SYS_ERR_N")
	)
	(segment
		(start 23.26132 -257.723386)
		(end 22.473666 -258.51104)
		(width 0.13208)
		(layer "B.Cu")
		(net "PEX0_SYS_ERR_N")
	)
	(segment
		(start 62.754764 -283.61259)
		(end 62.53988 -283.827474)
		(width 0.13208)
		(layer "B.Cu")
		(net "PEX0_SYS_ERR_N")
	)
	(segment
		(start 27.069034 -259.312156)
		(end 25.480264 -257.723386)
		(width 0.13208)
		(layer "B.Cu")
		(net "PEX0_SYS_ERR_N")
	)
	(segment
		(start 59.7408 -284.8102)
		(end 59.4614 -284.5308)
		(width 0.13208)
		(layer "B.Cu")
		(net "PEX0_SYS_ERR_N")
	)
	(segment
		(start 62.240922 -285.3944)
		(end 59.9948 -285.3944)
		(width 0.13208)
		(layer "B.Cu")
		(net "PEX0_SYS_ERR_N")
	)
	(segment
		(start 121.509028 -89.944194)
		(end 121.283222 -90.17)
		(width 0.13208)
		(layer "F.Cu")
		(net "SMB_BIC_I2C9_MUX0_SSD3_R_SDA")
	)
	(segment
		(start 119.888254 -90.17)
		(end 119.5578 -89.839546)
		(width 0.13208)
		(layer "F.Cu")
		(net "SMB_BIC_I2C9_MUX0_SSD3_R_SDA")
	)
	(segment
		(start 105.434638 -6.739636)
		(end 105.874312 -6.739636)
		(width 0.13208)
		(layer "F.Cu")
		(net "SMB_BIC_I2C9_MUX0_SSD3_R_SDA")
	)
	(segment
		(start 119.5578 -86.89594)
		(end 120.04294 -86.4108)
		(width 0.13208)
		(layer "F.Cu")
		(net "SMB_BIC_I2C9_MUX0_SSD3_R_SDA")
	)
	(segment
		(start 105.19283 -6.981444)
		(end 105.434638 -6.739636)
		(width 0.13208)
		(layer "F.Cu")
		(net "SMB_BIC_I2C9_MUX0_SSD3_R_SDA")
	)
	(segment
		(start 121.509028 -89.53373)
		(end 123.248928 -89.53373)
		(width 0.13208)
		(layer "F.Cu")
		(net "SMB_BIC_I2C9_MUX0_SSD3_R_SDA")
	)
	(segment
		(start 104.907842 -7.266432)
		(end 105.19283 -6.981444)
		(width 0.13208)
		(layer "F.Cu")
		(net "SMB_BIC_I2C9_MUX0_SSD3_R_SDA")
	)
	(segment
		(start 120.04294 -86.4108)
		(end 123.603004 -86.4108)
		(width 0.13208)
		(layer "F.Cu")
		(net "SMB_BIC_I2C9_MUX0_SSD3_R_SDA")
	)
	(segment
		(start 104.126538 -7.266432)
		(end 104.907842 -7.266432)
		(width 0.13208)
		(layer "F.Cu")
		(net "SMB_BIC_I2C9_MUX0_SSD3_R_SDA")
	)
	(segment
		(start 129.99466 -80.019144)
		(end 129.99466 -79.706216)
		(width 0.13208)
		(layer "F.Cu")
		(net "SMB_BIC_I2C9_MUX0_SSD3_R_SDA")
	)
	(segment
		(start 121.283222 -90.17)
		(end 119.888254 -90.17)
		(width 0.13208)
		(layer "F.Cu")
		(net "SMB_BIC_I2C9_MUX0_SSD3_R_SDA")
	)
	(segment
		(start 121.509028 -89.53373)
		(end 121.509028 -89.944194)
		(width 0.13208)
		(layer "F.Cu")
		(net "SMB_BIC_I2C9_MUX0_SSD3_R_SDA")
	)
	(segment
		(start 123.603004 -86.4108)
		(end 129.99466 -80.019144)
		(width 0.13208)
		(layer "F.Cu")
		(net "SMB_BIC_I2C9_MUX0_SSD3_R_SDA")
	)
	(segment
		(start 119.5578 -89.839546)
		(end 119.5578 -86.89594)
		(width 0.13208)
		(layer "F.Cu")
		(net "SMB_BIC_I2C9_MUX0_SSD3_R_SDA")
	)
	(via
		(at 105.19283 -6.981444)
		(size 0.508)
		(drill 0.254)
		(layers "F.Cu" "B.Cu")
		(net "SMB_BIC_I2C9_MUX0_SSD3_R_SDA")
	)
	(via
		(at 129.99466 -79.706216)
		(size 0.508)
		(drill 0.254)
		(layers "F.Cu" "B.Cu")
		(net "SMB_BIC_I2C9_MUX0_SSD3_R_SDA")
	)
	(segment
		(start 102.221538 -26.961338)
		(end 103.251 -27.9908)
		(width 0.15494)
		(layer "In5.Cu")
		(net "SMB_BIC_I2C9_MUX0_SSD3_R_SDA")
	)
	(segment
		(start 102.221538 -20.802346)
		(end 102.221538 -26.961338)
		(width 0.15494)
		(layer "In5.Cu")
		(net "SMB_BIC_I2C9_MUX0_SSD3_R_SDA")
	)
	(segment
		(start 129.535428 -79.706216)
		(end 129.99466 -79.706216)
		(width 0.15494)
		(layer "In5.Cu")
		(net "SMB_BIC_I2C9_MUX0_SSD3_R_SDA")
	)
	(segment
		(start 115.822222 -60.582302)
		(end 115.822222 -63.040768)
		(width 0.15494)
		(layer "In5.Cu")
		(net "SMB_BIC_I2C9_MUX0_SSD3_R_SDA")
	)
	(segment
		(start 104.63911 -11.919712)
		(end 103.9876 -12.571222)
		(width 0.15494)
		(layer "In5.Cu")
		(net "SMB_BIC_I2C9_MUX0_SSD3_R_SDA")
	)
	(segment
		(start 108.50372 -53.2638)
		(end 115.822222 -60.582302)
		(width 0.15494)
		(layer "In5.Cu")
		(net "SMB_BIC_I2C9_MUX0_SSD3_R_SDA")
	)
	(segment
		(start 124.708412 -69.458078)
		(end 124.708412 -74.8792)
		(width 0.15494)
		(layer "In5.Cu")
		(net "SMB_BIC_I2C9_MUX0_SSD3_R_SDA")
	)
	(segment
		(start 103.251 -29.21)
		(end 102.338378 -30.122622)
		(width 0.15494)
		(layer "In5.Cu")
		(net "SMB_BIC_I2C9_MUX0_SSD3_R_SDA")
	)
	(segment
		(start 118.067582 -65.286128)
		(end 120.536462 -65.286128)
		(width 0.15494)
		(layer "In5.Cu")
		(net "SMB_BIC_I2C9_MUX0_SSD3_R_SDA")
	)
	(segment
		(start 103.251 -27.9908)
		(end 103.251 -29.21)
		(width 0.15494)
		(layer "In5.Cu")
		(net "SMB_BIC_I2C9_MUX0_SSD3_R_SDA")
	)
	(segment
		(start 120.536462 -65.286128)
		(end 124.708412 -69.458078)
		(width 0.15494)
		(layer "In5.Cu")
		(net "SMB_BIC_I2C9_MUX0_SSD3_R_SDA")
	)
	(segment
		(start 103.9876 -19.036284)
		(end 102.221538 -20.802346)
		(width 0.15494)
		(layer "In5.Cu")
		(net "SMB_BIC_I2C9_MUX0_SSD3_R_SDA")
	)
	(segment
		(start 102.338378 -35.566858)
		(end 108.50372 -41.7322)
		(width 0.15494)
		(layer "In5.Cu")
		(net "SMB_BIC_I2C9_MUX0_SSD3_R_SDA")
	)
	(segment
		(start 108.50372 -41.7322)
		(end 108.50372 -53.2638)
		(width 0.15494)
		(layer "In5.Cu")
		(net "SMB_BIC_I2C9_MUX0_SSD3_R_SDA")
	)
	(segment
		(start 124.708412 -74.8792)
		(end 129.535428 -79.706216)
		(width 0.15494)
		(layer "In5.Cu")
		(net "SMB_BIC_I2C9_MUX0_SSD3_R_SDA")
	)
	(segment
		(start 104.63911 -7.535164)
		(end 104.63911 -11.919712)
		(width 0.15494)
		(layer "In5.Cu")
		(net "SMB_BIC_I2C9_MUX0_SSD3_R_SDA")
	)
	(segment
		(start 103.9876 -12.571222)
		(end 103.9876 -19.036284)
		(width 0.15494)
		(layer "In5.Cu")
		(net "SMB_BIC_I2C9_MUX0_SSD3_R_SDA")
	)
	(segment
		(start 105.19283 -6.981444)
		(end 104.63911 -7.535164)
		(width 0.15494)
		(layer "In5.Cu")
		(net "SMB_BIC_I2C9_MUX0_SSD3_R_SDA")
	)
	(segment
		(start 102.338378 -30.122622)
		(end 102.338378 -35.566858)
		(width 0.15494)
		(layer "In5.Cu")
		(net "SMB_BIC_I2C9_MUX0_SSD3_R_SDA")
	)
	(segment
		(start 115.822222 -63.040768)
		(end 118.067582 -65.286128)
		(width 0.15494)
		(layer "In5.Cu")
		(net "SMB_BIC_I2C9_MUX0_SSD3_R_SDA")
	)
	(segment
		(start 344.49385 -223.987106)
		(end 344.893646 -224.386902)
		(width 0.13208)
		(layer "F.Cu")
		(net "SSD4_PWR_EN")
	)
	(segment
		(start 348.982792 -240.291112)
		(end 348.982792 -238.786162)
		(width 0.13208)
		(layer "F.Cu")
		(net "SSD4_PWR_EN")
	)
	(via
		(at 348.982792 -238.786162)
		(size 0.508)
		(drill 0.254)
		(layers "F.Cu" "B.Cu")
		(net "SSD4_PWR_EN")
	)
	(via
		(at 344.893646 -224.386902)
		(size 0.4572)
		(drill 0.254)
		(layers "F.Cu" "B.Cu")
		(net "SSD4_PWR_EN")
	)
	(segment
		(start 348.982792 -237.922562)
		(end 348.982792 -238.786162)
		(width 0.15494)
		(layer "In5.Cu")
		(net "SSD4_PWR_EN")
	)
	(segment
		(start 347.611192 -230.955088)
		(end 347.611192 -236.550962)
		(width 0.15494)
		(layer "In5.Cu")
		(net "SSD4_PWR_EN")
	)
	(segment
		(start 345.29522 -227.05314)
		(end 345.29522 -228.639116)
		(width 0.15494)
		(layer "In5.Cu")
		(net "SSD4_PWR_EN")
	)
	(segment
		(start 345.29522 -224.788476)
		(end 345.29522 -227.05314)
		(width 0.0889)
		(layer "In5.Cu")
		(net "SSD4_PWR_EN")
	)
	(segment
		(start 347.611192 -236.550962)
		(end 348.982792 -237.922562)
		(width 0.15494)
		(layer "In5.Cu")
		(net "SSD4_PWR_EN")
	)
	(segment
		(start 344.893646 -224.386902)
		(end 345.29522 -224.788476)
		(width 0.0889)
		(layer "In5.Cu")
		(net "SSD4_PWR_EN")
	)
	(segment
		(start 345.29522 -228.639116)
		(end 347.611192 -230.955088)
		(width 0.15494)
		(layer "In5.Cu")
		(net "SSD4_PWR_EN")
	)
	(segment
		(start 227.750116 -230.594408)
		(end 227.743512 -230.601012)
		(width 0.13208)
		(layer "F.Cu")
		(net "NIC3_MAIN_PWR_BIC_EN")
	)
	(segment
		(start 227.750116 -229.566978)
		(end 227.715064 -229.531926)
		(width 0.13208)
		(layer "F.Cu")
		(net "NIC3_MAIN_PWR_BIC_EN")
	)
	(segment
		(start 227.715064 -227.1014)
		(end 228.267768 -226.548696)
		(width 0.13208)
		(layer "F.Cu")
		(net "NIC3_MAIN_PWR_BIC_EN")
	)
	(segment
		(start 227.743512 -230.601012)
		(end 227.743512 -231.016556)
		(width 0.13208)
		(layer "F.Cu")
		(net "NIC3_MAIN_PWR_BIC_EN")
	)
	(segment
		(start 227.750116 -229.566978)
		(end 227.750116 -230.594408)
		(width 0.13208)
		(layer "F.Cu")
		(net "NIC3_MAIN_PWR_BIC_EN")
	)
	(segment
		(start 227.715064 -229.531926)
		(end 227.715064 -227.1014)
		(width 0.13208)
		(layer "F.Cu")
		(net "NIC3_MAIN_PWR_BIC_EN")
	)
	(segment
		(start 228.267768 -226.548696)
		(end 228.267768 -224.704148)
		(width 0.13208)
		(layer "F.Cu")
		(net "NIC3_MAIN_PWR_BIC_EN")
	)
	(via
		(at 227.750116 -229.566978)
		(size 0.762)
		(drill 0.381)
		(layers "F.Cu" "B.Cu")
		(net "NIC3_MAIN_PWR_BIC_EN")
	)
	(segment
		(start 256.347214 -54.144164)
		(end 256.775458 -54.144164)
		(width 0.13208)
		(layer "F.Cu")
		(net "P12V_SSD8_OCP")
	)
	(segment
		(start 256.956052 -53.96357)
		(end 257.35407 -53.96357)
		(width 0.13208)
		(layer "F.Cu")
		(net "P12V_SSD8_OCP")
	)
	(segment
		(start 257.963924 -53.96357)
		(end 257.35407 -53.96357)
		(width 0.13208)
		(layer "F.Cu")
		(net "P12V_SSD8_OCP")
	)
	(segment
		(start 258.06781 -54.067456)
		(end 257.963924 -53.96357)
		(width 0.13208)
		(layer "F.Cu")
		(net "P12V_SSD8_OCP")
	)
	(segment
		(start 256.775458 -54.144164)
		(end 256.956052 -53.96357)
		(width 0.13208)
		(layer "F.Cu")
		(net "P12V_SSD8_OCP")
	)
	(via
		(at 257.35407 -53.96357)
		(size 0.508)
		(drill 0.254)
		(layers "F.Cu" "B.Cu")
		(net "P12V_SSD8_OCP")
	)
	(segment
		(start 390.068562 -27.189938)
		(end 389.56488 -27.189938)
		(width 0.13462)
		(layer "F.Cu")
		(net "CLK_100M_DB800ZL_SSD13_R_DP")
	)
	(segment
		(start 391.281412 -27.342846)
		(end 390.964166 -27.0256)
		(width 0.13462)
		(layer "F.Cu")
		(net "CLK_100M_DB800ZL_SSD13_R_DP")
	)
	(segment
		(start 346.0496 -87.56904)
		(end 346.33789 -87.28075)
		(width 0.13462)
		(layer "F.Cu")
		(net "CLK_100M_DB800ZL_SSD13_R_DP")
	)
	(segment
		(start 345.326716 -87.56904)
		(end 346.0496 -87.56904)
		(width 0.13462)
		(layer "F.Cu")
		(net "CLK_100M_DB800ZL_SSD13_R_DP")
	)
	(segment
		(start 345.013026 -87.25535)
		(end 345.326716 -87.56904)
		(width 0.13462)
		(layer "F.Cu")
		(net "CLK_100M_DB800ZL_SSD13_R_DP")
	)
	(segment
		(start 390.2329 -27.0256)
		(end 390.068562 -27.189938)
		(width 0.13462)
		(layer "F.Cu")
		(net "CLK_100M_DB800ZL_SSD13_R_DP")
	)
	(segment
		(start 390.964166 -27.0256)
		(end 390.2329 -27.0256)
		(width 0.13462)
		(layer "F.Cu")
		(net "CLK_100M_DB800ZL_SSD13_R_DP")
	)
	(via
		(at 346.33789 -87.28075)
		(size 0.508)
		(drill 0.254)
		(layers "F.Cu" "B.Cu")
		(net "CLK_100M_DB800ZL_SSD13_R_DP")
	)
	(via
		(at 391.281412 -27.342846)
		(size 0.508)
		(drill 0.254)
		(layers "F.Cu" "B.Cu")
		(net "CLK_100M_DB800ZL_SSD13_R_DP")
	)
	(segment
		(start 391.43559 -37.009832)
		(end 391.08507 -37.360352)
		(width 0.1651)
		(layer "In13.Cu")
		(net "CLK_100M_DB800ZL_SSD13_R_DP")
	)
	(segment
		(start 391.9474 -33.289494)
		(end 391.9474 -33.784794)
		(width 0.1651)
		(layer "In13.Cu")
		(net "CLK_100M_DB800ZL_SSD13_R_DP")
	)
	(segment
		(start 349.2246 -86.2584)
		(end 347.91142 -87.57158)
		(width 0.1651)
		(layer "In13.Cu")
		(net "CLK_100M_DB800ZL_SSD13_R_DP")
	)
	(segment
		(start 391.9474 -30.127194)
		(end 391.8331 -30.241494)
		(width 0.1651)
		(layer "In13.Cu")
		(net "CLK_100M_DB800ZL_SSD13_R_DP")
	)
	(segment
		(start 390.735058 -37.872162)
		(end 390.57326 -37.872162)
		(width 0.1651)
		(layer "In13.Cu")
		(net "CLK_100M_DB800ZL_SSD13_R_DP")
	)
	(segment
		(start 391.9474 -28.907994)
		(end 391.8331 -29.022294)
		(width 0.1651)
		(layer "In13.Cu")
		(net "CLK_100M_DB800ZL_SSD13_R_DP")
	)
	(segment
		(start 391.9474 -32.070294)
		(end 391.9474 -32.565594)
		(width 0.1651)
		(layer "In13.Cu")
		(net "CLK_100M_DB800ZL_SSD13_R_DP")
	)
	(segment
		(start 391.8331 -29.517594)
		(end 391.9474 -29.631894)
		(width 0.1651)
		(layer "In13.Cu")
		(net "CLK_100M_DB800ZL_SSD13_R_DP")
	)
	(segment
		(start 386.799836 -41.807384)
		(end 385.95046 -43.85818)
		(width 0.1651)
		(layer "In13.Cu")
		(net "CLK_100M_DB800ZL_SSD13_R_DP")
	)
	(segment
		(start 391.8331 -33.899094)
		(end 391.8331 -34.394394)
		(width 0.1651)
		(layer "In13.Cu")
		(net "CLK_100M_DB800ZL_SSD13_R_DP")
	)
	(segment
		(start 391.8331 -30.736794)
		(end 391.9474 -30.851094)
		(width 0.1651)
		(layer "In13.Cu")
		(net "CLK_100M_DB800ZL_SSD13_R_DP")
	)
	(segment
		(start 391.9474 -35.003994)
		(end 391.8331 -35.118294)
		(width 0.1651)
		(layer "In13.Cu")
		(net "CLK_100M_DB800ZL_SSD13_R_DP")
	)
	(segment
		(start 350.774 -79.3242)
		(end 349.2246 -80.8736)
		(width 0.1651)
		(layer "In13.Cu")
		(net "CLK_100M_DB800ZL_SSD13_R_DP")
	)
	(segment
		(start 391.597388 -37.009832)
		(end 391.43559 -37.009832)
		(width 0.1651)
		(layer "In13.Cu")
		(net "CLK_100M_DB800ZL_SSD13_R_DP")
	)
	(segment
		(start 347.91142 -87.57158)
		(end 346.62872 -87.57158)
		(width 0.1651)
		(layer "In13.Cu")
		(net "CLK_100M_DB800ZL_SSD13_R_DP")
	)
	(segment
		(start 391.9474 -29.631894)
		(end 391.9474 -30.127194)
		(width 0.1651)
		(layer "In13.Cu")
		(net "CLK_100M_DB800ZL_SSD13_R_DP")
	)
	(segment
		(start 391.8331 -35.118294)
		(end 391.8331 -35.613594)
		(width 0.1651)
		(layer "In13.Cu")
		(net "CLK_100M_DB800ZL_SSD13_R_DP")
	)
	(segment
		(start 391.9474 -31.346394)
		(end 391.8331 -31.460694)
		(width 0.1651)
		(layer "In13.Cu")
		(net "CLK_100M_DB800ZL_SSD13_R_DP")
	)
	(segment
		(start 391.8331 -27.803094)
		(end 391.8331 -28.298394)
		(width 0.1651)
		(layer "In13.Cu")
		(net "CLK_100M_DB800ZL_SSD13_R_DP")
	)
	(segment
		(start 391.8331 -31.955994)
		(end 391.9474 -32.070294)
		(width 0.1651)
		(layer "In13.Cu")
		(net "CLK_100M_DB800ZL_SSD13_R_DP")
	)
	(segment
		(start 391.08507 -37.52215)
		(end 390.735058 -37.872162)
		(width 0.1651)
		(layer "In13.Cu")
		(net "CLK_100M_DB800ZL_SSD13_R_DP")
	)
	(segment
		(start 390.22274 -38.222682)
		(end 390.22274 -38.38448)
		(width 0.1651)
		(layer "In13.Cu")
		(net "CLK_100M_DB800ZL_SSD13_R_DP")
	)
	(segment
		(start 391.8331 -28.298394)
		(end 391.9474 -28.412694)
		(width 0.1651)
		(layer "In13.Cu")
		(net "CLK_100M_DB800ZL_SSD13_R_DP")
	)
	(segment
		(start 391.9474 -34.508694)
		(end 391.9474 -35.003994)
		(width 0.1651)
		(layer "In13.Cu")
		(net "CLK_100M_DB800ZL_SSD13_R_DP")
	)
	(segment
		(start 391.9474 -30.851094)
		(end 391.9474 -31.346394)
		(width 0.1651)
		(layer "In13.Cu")
		(net "CLK_100M_DB800ZL_SSD13_R_DP")
	)
	(segment
		(start 391.9474 -27.193494)
		(end 391.9474 -27.688794)
		(width 0.1651)
		(layer "In13.Cu")
		(net "CLK_100M_DB800ZL_SSD13_R_DP")
	)
	(segment
		(start 391.8331 -34.394394)
		(end 391.9474 -34.508694)
		(width 0.1651)
		(layer "In13.Cu")
		(net "CLK_100M_DB800ZL_SSD13_R_DP")
	)
	(segment
		(start 360.9086 -79.3242)
		(end 350.774 -79.3242)
		(width 0.1651)
		(layer "In13.Cu")
		(net "CLK_100M_DB800ZL_SSD13_R_DP")
	)
	(segment
		(start 375.1834 -75.2602)
		(end 364.9726 -75.2602)
		(width 0.1651)
		(layer "In13.Cu")
		(net "CLK_100M_DB800ZL_SSD13_R_DP")
	)
	(segment
		(start 390.22274 -38.38448)
		(end 386.799836 -41.807384)
		(width 0.1651)
		(layer "In13.Cu")
		(net "CLK_100M_DB800ZL_SSD13_R_DP")
	)
	(segment
		(start 391.9474 -27.688794)
		(end 391.8331 -27.803094)
		(width 0.1651)
		(layer "In13.Cu")
		(net "CLK_100M_DB800ZL_SSD13_R_DP")
	)
	(segment
		(start 390.57326 -37.872162)
		(end 390.22274 -38.222682)
		(width 0.1651)
		(layer "In13.Cu")
		(net "CLK_100M_DB800ZL_SSD13_R_DP")
	)
	(segment
		(start 391.8331 -35.613594)
		(end 391.9474 -35.727894)
		(width 0.1651)
		(layer "In13.Cu")
		(net "CLK_100M_DB800ZL_SSD13_R_DP")
	)
	(segment
		(start 391.9474 -35.727894)
		(end 391.9474 -36.65982)
		(width 0.1651)
		(layer "In13.Cu")
		(net "CLK_100M_DB800ZL_SSD13_R_DP")
	)
	(segment
		(start 385.95046 -64.49314)
		(end 375.1834 -75.2602)
		(width 0.1651)
		(layer "In13.Cu")
		(net "CLK_100M_DB800ZL_SSD13_R_DP")
	)
	(segment
		(start 391.8331 -29.022294)
		(end 391.8331 -29.517594)
		(width 0.1651)
		(layer "In13.Cu")
		(net "CLK_100M_DB800ZL_SSD13_R_DP")
	)
	(segment
		(start 391.8331 -32.679894)
		(end 391.8331 -33.175194)
		(width 0.1651)
		(layer "In13.Cu")
		(net "CLK_100M_DB800ZL_SSD13_R_DP")
	)
	(segment
		(start 391.572242 -27.052016)
		(end 391.805922 -27.052016)
		(width 0.1651)
		(layer "In13.Cu")
		(net "CLK_100M_DB800ZL_SSD13_R_DP")
	)
	(segment
		(start 391.9474 -32.565594)
		(end 391.8331 -32.679894)
		(width 0.1651)
		(layer "In13.Cu")
		(net "CLK_100M_DB800ZL_SSD13_R_DP")
	)
	(segment
		(start 391.9474 -33.784794)
		(end 391.8331 -33.899094)
		(width 0.1651)
		(layer "In13.Cu")
		(net "CLK_100M_DB800ZL_SSD13_R_DP")
	)
	(segment
		(start 391.8331 -31.460694)
		(end 391.8331 -31.955994)
		(width 0.1651)
		(layer "In13.Cu")
		(net "CLK_100M_DB800ZL_SSD13_R_DP")
	)
	(segment
		(start 391.9474 -28.412694)
		(end 391.9474 -28.907994)
		(width 0.1651)
		(layer "In13.Cu")
		(net "CLK_100M_DB800ZL_SSD13_R_DP")
	)
	(segment
		(start 391.9474 -36.65982)
		(end 391.597388 -37.009832)
		(width 0.1651)
		(layer "In13.Cu")
		(net "CLK_100M_DB800ZL_SSD13_R_DP")
	)
	(segment
		(start 391.805922 -27.052016)
		(end 391.9474 -27.193494)
		(width 0.1651)
		(layer "In13.Cu")
		(net "CLK_100M_DB800ZL_SSD13_R_DP")
	)
	(segment
		(start 391.281412 -27.342846)
		(end 391.572242 -27.052016)
		(width 0.1651)
		(layer "In13.Cu")
		(net "CLK_100M_DB800ZL_SSD13_R_DP")
	)
	(segment
		(start 364.9726 -75.2602)
		(end 360.9086 -79.3242)
		(width 0.1651)
		(layer "In13.Cu")
		(net "CLK_100M_DB800ZL_SSD13_R_DP")
	)
	(segment
		(start 346.62872 -87.57158)
		(end 346.33789 -87.28075)
		(width 0.1651)
		(layer "In13.Cu")
		(net "CLK_100M_DB800ZL_SSD13_R_DP")
	)
	(segment
		(start 391.08507 -37.360352)
		(end 391.08507 -37.52215)
		(width 0.1651)
		(layer "In13.Cu")
		(net "CLK_100M_DB800ZL_SSD13_R_DP")
	)
	(segment
		(start 385.95046 -43.85818)
		(end 385.95046 -64.49314)
		(width 0.1651)
		(layer "In13.Cu")
		(net "CLK_100M_DB800ZL_SSD13_R_DP")
	)
	(segment
		(start 391.8331 -33.175194)
		(end 391.9474 -33.289494)
		(width 0.1651)
		(layer "In13.Cu")
		(net "CLK_100M_DB800ZL_SSD13_R_DP")
	)
	(segment
		(start 349.2246 -80.8736)
		(end 349.2246 -86.2584)
		(width 0.1651)
		(layer "In13.Cu")
		(net "CLK_100M_DB800ZL_SSD13_R_DP")
	)
	(segment
		(start 391.8331 -30.241494)
		(end 391.8331 -30.736794)
		(width 0.1651)
		(layer "In13.Cu")
		(net "CLK_100M_DB800ZL_SSD13_R_DP")
	)
	(segment
		(start 255.801876 -83.556348)
		(end 254.501396 -83.556348)
		(width 0.13208)
		(layer "F.Cu")
		(net "TP_CLK_PFT_IN_DN")
	)
	(segment
		(start 251.8029 -87.340948)
		(end 251.36602 -87.340948)
		(width 0.13208)
		(layer "F.Cu")
		(net "TP_CLK_PFT_IN_DN")
	)
	(segment
		(start 254.009906 -85.133942)
		(end 251.8029 -87.340948)
		(width 0.13208)
		(layer "F.Cu")
		(net "TP_CLK_PFT_IN_DN")
	)
	(segment
		(start 254.009906 -84.047838)
		(end 254.009906 -85.133942)
		(width 0.13208)
		(layer "F.Cu")
		(net "TP_CLK_PFT_IN_DN")
	)
	(segment
		(start 254.501396 -83.556348)
		(end 254.009906 -84.047838)
		(width 0.13208)
		(layer "F.Cu")
		(net "TP_CLK_PFT_IN_DN")
	)
	(via
		(at 251.36602 -87.340948)
		(size 0.508)
		(drill 0.254)
		(layers "F.Cu" "B.Cu")
		(net "TP_CLK_PFT_IN_DN")
	)
	(segment
		(start 364.304072 -81.498694)
		(end 365.014256 -81.498694)
		(width 0.13208)
		(layer "F.Cu")
		(net "SMB_BIC_I2C9_MUX1_SSD12_SDA")
	)
	(segment
		(start 362.30814 -82.914998)
		(end 362.887768 -82.914998)
		(width 0.13208)
		(layer "F.Cu")
		(net "SMB_BIC_I2C9_MUX1_SSD12_SDA")
	)
	(segment
		(start 365.014256 -81.498694)
		(end 366.555528 -81.498694)
		(width 0.13208)
		(layer "F.Cu")
		(net "SMB_BIC_I2C9_MUX1_SSD12_SDA")
	)
	(segment
		(start 362.887768 -82.914998)
		(end 364.304072 -81.498694)
		(width 0.13208)
		(layer "F.Cu")
		(net "SMB_BIC_I2C9_MUX1_SSD12_SDA")
	)
	(via
		(at 365.014256 -81.498694)
		(size 0.508)
		(drill 0.254)
		(layers "F.Cu" "B.Cu")
		(net "SMB_BIC_I2C9_MUX1_SSD12_SDA")
	)
	(segment
		(start 340.493858 -225.587052)
		(end 340.093808 -225.987102)
		(width 0.13208)
		(layer "F.Cu")
		(net "SMB_PEX3_FPGA_SDA")
	)
	(segment
		(start 437.136032 -288.830766)
		(end 437.136032 -288.221166)
		(width 0.13208)
		(layer "F.Cu")
		(net "SMB_PEX3_FPGA_SDA")
	)
	(via
		(at 437.136032 -288.221166)
		(size 0.508)
		(drill 0.254)
		(layers "F.Cu" "B.Cu")
		(net "SMB_PEX3_FPGA_SDA")
	)
	(via
		(at 447.671444 -251.52604)
		(size 0.508)
		(drill 0.254)
		(layers "F.Cu" "B.Cu")
		(net "SMB_PEX3_FPGA_SDA")
	)
	(via
		(at 366.036352 -248.007886)
		(size 0.508)
		(drill 0.254)
		(layers "F.Cu" "B.Cu")
		(net "SMB_PEX3_FPGA_SDA")
	)
	(via
		(at 340.093808 -225.987102)
		(size 0.4572)
		(drill 0.254)
		(layers "F.Cu" "B.Cu")
		(net "SMB_PEX3_FPGA_SDA")
	)
	(segment
		(start 432.500786 -264.967974)
		(end 432.500786 -273.316192)
		(width 0.13208)
		(layer "B.Cu")
		(net "SMB_PEX3_FPGA_SDA")
	)
	(segment
		(start 437.136032 -277.951438)
		(end 437.136032 -288.221166)
		(width 0.13208)
		(layer "B.Cu")
		(net "SMB_PEX3_FPGA_SDA")
	)
	(segment
		(start 445.94272 -251.52604)
		(end 432.500786 -264.967974)
		(width 0.13208)
		(layer "B.Cu")
		(net "SMB_PEX3_FPGA_SDA")
	)
	(segment
		(start 432.500786 -273.316192)
		(end 437.136032 -277.951438)
		(width 0.13208)
		(layer "B.Cu")
		(net "SMB_PEX3_FPGA_SDA")
	)
	(segment
		(start 447.671444 -251.52604)
		(end 445.94272 -251.52604)
		(width 0.13208)
		(layer "B.Cu")
		(net "SMB_PEX3_FPGA_SDA")
	)
	(segment
		(start 340.495128 -227.762562)
		(end 340.495128 -226.91217)
		(width 0.15494)
		(layer "In5.Cu")
		(net "SMB_PEX3_FPGA_SDA")
	)
	(segment
		(start 364.997746 -245.370604)
		(end 359.804462 -240.17732)
		(width 0.15494)
		(layer "In5.Cu")
		(net "SMB_PEX3_FPGA_SDA")
	)
	(segment
		(start 364.997746 -246.96928)
		(end 364.997746 -245.370604)
		(width 0.15494)
		(layer "In5.Cu")
		(net "SMB_PEX3_FPGA_SDA")
	)
	(segment
		(start 340.495128 -226.91217)
		(end 340.495128 -226.388422)
		(width 0.0889)
		(layer "In5.Cu")
		(net "SMB_PEX3_FPGA_SDA")
	)
	(segment
		(start 343.708736 -240.17732)
		(end 340.51113 -236.979714)
		(width 0.15494)
		(layer "In5.Cu")
		(net "SMB_PEX3_FPGA_SDA")
	)
	(segment
		(start 340.51113 -234.73156)
		(end 340.84387 -234.39882)
		(width 0.15494)
		(layer "In5.Cu")
		(net "SMB_PEX3_FPGA_SDA")
	)
	(segment
		(start 366.036352 -248.007886)
		(end 364.997746 -246.96928)
		(width 0.15494)
		(layer "In5.Cu")
		(net "SMB_PEX3_FPGA_SDA")
	)
	(segment
		(start 340.84387 -234.39882)
		(end 340.84387 -228.111304)
		(width 0.15494)
		(layer "In5.Cu")
		(net "SMB_PEX3_FPGA_SDA")
	)
	(segment
		(start 340.84387 -228.111304)
		(end 340.495128 -227.762562)
		(width 0.15494)
		(layer "In5.Cu")
		(net "SMB_PEX3_FPGA_SDA")
	)
	(segment
		(start 359.804462 -240.17732)
		(end 343.708736 -240.17732)
		(width 0.15494)
		(layer "In5.Cu")
		(net "SMB_PEX3_FPGA_SDA")
	)
	(segment
		(start 340.51113 -236.979714)
		(end 340.51113 -234.73156)
		(width 0.15494)
		(layer "In5.Cu")
		(net "SMB_PEX3_FPGA_SDA")
	)
	(segment
		(start 340.495128 -226.388422)
		(end 340.093808 -225.987102)
		(width 0.0889)
		(layer "In5.Cu")
		(net "SMB_PEX3_FPGA_SDA")
	)
	(segment
		(start 383.664714 -250.1138)
		(end 371.6782 -250.1138)
		(width 0.15494)
		(layer "In13.Cu")
		(net "SMB_PEX3_FPGA_SDA")
	)
	(segment
		(start 385.06019 -248.718324)
		(end 383.664714 -250.1138)
		(width 0.15494)
		(layer "In13.Cu")
		(net "SMB_PEX3_FPGA_SDA")
	)
	(segment
		(start 371.6782 -250.1138)
		(end 370.2812 -248.7168)
		(width 0.15494)
		(layer "In13.Cu")
		(net "SMB_PEX3_FPGA_SDA")
	)
	(segment
		(start 388.64159 -245.05539)
		(end 386.924804 -245.05539)
		(width 0.15494)
		(layer "In13.Cu")
		(net "SMB_PEX3_FPGA_SDA")
	)
	(segment
		(start 444.124334 -246.639588)
		(end 395.408404 -246.639588)
		(width 0.15494)
		(layer "In13.Cu")
		(net "SMB_PEX3_FPGA_SDA")
	)
	(segment
		(start 395.408404 -246.639588)
		(end 394.621258 -245.852442)
		(width 0.15494)
		(layer "In13.Cu")
		(net "SMB_PEX3_FPGA_SDA")
	)
	(segment
		(start 394.621258 -245.852442)
		(end 389.438642 -245.852442)
		(width 0.15494)
		(layer "In13.Cu")
		(net "SMB_PEX3_FPGA_SDA")
	)
	(segment
		(start 386.364988 -245.615206)
		(end 386.364988 -246.374412)
		(width 0.15494)
		(layer "In13.Cu")
		(net "SMB_PEX3_FPGA_SDA")
	)
	(segment
		(start 366.745266 -248.7168)
		(end 366.036352 -248.007886)
		(width 0.15494)
		(layer "In13.Cu")
		(net "SMB_PEX3_FPGA_SDA")
	)
	(segment
		(start 386.924804 -245.05539)
		(end 386.364988 -245.615206)
		(width 0.15494)
		(layer "In13.Cu")
		(net "SMB_PEX3_FPGA_SDA")
	)
	(segment
		(start 370.2812 -248.7168)
		(end 366.745266 -248.7168)
		(width 0.15494)
		(layer "In13.Cu")
		(net "SMB_PEX3_FPGA_SDA")
	)
	(segment
		(start 386.364988 -246.374412)
		(end 385.06019 -247.67921)
		(width 0.15494)
		(layer "In13.Cu")
		(net "SMB_PEX3_FPGA_SDA")
	)
	(segment
		(start 385.06019 -247.67921)
		(end 385.06019 -248.718324)
		(width 0.15494)
		(layer "In13.Cu")
		(net "SMB_PEX3_FPGA_SDA")
	)
	(segment
		(start 447.671444 -251.52604)
		(end 447.671444 -250.186698)
		(width 0.15494)
		(layer "In13.Cu")
		(net "SMB_PEX3_FPGA_SDA")
	)
	(segment
		(start 447.671444 -250.186698)
		(end 444.124334 -246.639588)
		(width 0.15494)
		(layer "In13.Cu")
		(net "SMB_PEX3_FPGA_SDA")
	)
	(segment
		(start 389.438642 -245.852442)
		(end 388.64159 -245.05539)
		(width 0.15494)
		(layer "In13.Cu")
		(net "SMB_PEX3_FPGA_SDA")
	)
	(segment
		(start 386.50799 -163.061396)
		(end 386.50799 -163.470082)
		(width 0.13208)
		(layer "F.Cu")
		(net "PWRGD_NIC6_PWR_GOOD_R")
	)
	(segment
		(start 346.093796 -219.187014)
		(end 346.493592 -218.787218)
		(width 0.13208)
		(layer "F.Cu")
		(net "PWRGD_NIC6_PWR_GOOD_R")
	)
	(segment
		(start 386.50799 -163.470082)
		(end 387.1468 -164.108892)
		(width 0.13208)
		(layer "F.Cu")
		(net "PWRGD_NIC6_PWR_GOOD_R")
	)
	(via
		(at 364.116366 -167.783256)
		(size 0.508)
		(drill 0.254)
		(layers "F.Cu" "B.Cu")
		(net "PWRGD_NIC6_PWR_GOOD_R")
	)
	(via
		(at 346.493592 -218.787218)
		(size 0.4572)
		(drill 0.254)
		(layers "F.Cu" "B.Cu")
		(net "PWRGD_NIC6_PWR_GOOD_R")
	)
	(via
		(at 387.1468 -164.108892)
		(size 0.508)
		(drill 0.254)
		(layers "F.Cu" "B.Cu")
		(net "PWRGD_NIC6_PWR_GOOD_R")
	)
	(segment
		(start 370.937536 -192.723516)
		(end 370.152422 -191.938402)
		(width 0.15494)
		(layer "In7.Cu")
		(net "PWRGD_NIC6_PWR_GOOD_R")
	)
	(segment
		(start 356.5779 -210.53552)
		(end 356.5779 -209.3595)
		(width 0.15494)
		(layer "In7.Cu")
		(net "PWRGD_NIC6_PWR_GOOD_R")
	)
	(segment
		(start 361.594654 -204.9272)
		(end 361.597194 -204.92466)
		(width 0.15494)
		(layer "In7.Cu")
		(net "PWRGD_NIC6_PWR_GOOD_R")
	)
	(segment
		(start 370.937536 -197.463664)
		(end 370.937536 -192.723516)
		(width 0.15494)
		(layer "In7.Cu")
		(net "PWRGD_NIC6_PWR_GOOD_R")
	)
	(segment
		(start 361.432856 -204.9272)
		(end 361.594654 -204.9272)
		(width 0.15494)
		(layer "In7.Cu")
		(net "PWRGD_NIC6_PWR_GOOD_R")
	)
	(segment
		(start 355.5746 -211.53882)
		(end 356.5779 -210.53552)
		(width 0.15494)
		(layer "In7.Cu")
		(net "PWRGD_NIC6_PWR_GOOD_R")
	)
	(segment
		(start 360.543856 -205.8162)
		(end 361.432856 -204.9272)
		(width 0.15494)
		(layer "In7.Cu")
		(net "PWRGD_NIC6_PWR_GOOD_R")
	)
	(segment
		(start 351.456244 -218.387168)
		(end 351.7392 -218.104212)
		(width 0.0889)
		(layer "In7.Cu")
		(net "PWRGD_NIC6_PWR_GOOD_R")
	)
	(segment
		(start 355.019356 -214.325708)
		(end 355.5746 -213.770464)
		(width 0.15494)
		(layer "In7.Cu")
		(net "PWRGD_NIC6_PWR_GOOD_R")
	)
	(segment
		(start 346.893642 -218.387168)
		(end 351.456244 -218.387168)
		(width 0.0889)
		(layer "In7.Cu")
		(net "PWRGD_NIC6_PWR_GOOD_R")
	)
	(segment
		(start 361.597194 -204.92466)
		(end 362.71454 -204.92466)
		(width 0.15494)
		(layer "In7.Cu")
		(net "PWRGD_NIC6_PWR_GOOD_R")
	)
	(segment
		(start 346.493592 -218.787218)
		(end 346.893642 -218.387168)
		(width 0.0889)
		(layer "In7.Cu")
		(net "PWRGD_NIC6_PWR_GOOD_R")
	)
	(segment
		(start 364.116366 -170.085512)
		(end 364.116366 -167.783256)
		(width 0.15494)
		(layer "In7.Cu")
		(net "PWRGD_NIC6_PWR_GOOD_R")
	)
	(segment
		(start 355.5746 -213.770464)
		(end 355.5746 -211.53882)
		(width 0.15494)
		(layer "In7.Cu")
		(net "PWRGD_NIC6_PWR_GOOD_R")
	)
	(segment
		(start 362.71454 -204.92466)
		(end 368.8842 -198.755)
		(width 0.15494)
		(layer "In7.Cu")
		(net "PWRGD_NIC6_PWR_GOOD_R")
	)
	(segment
		(start 370.152422 -176.121568)
		(end 364.116366 -170.085512)
		(width 0.15494)
		(layer "In7.Cu")
		(net "PWRGD_NIC6_PWR_GOOD_R")
	)
	(segment
		(start 356.5779 -209.3595)
		(end 360.1212 -205.8162)
		(width 0.15494)
		(layer "In7.Cu")
		(net "PWRGD_NIC6_PWR_GOOD_R")
	)
	(segment
		(start 369.6462 -198.755)
		(end 370.937536 -197.463664)
		(width 0.15494)
		(layer "In7.Cu")
		(net "PWRGD_NIC6_PWR_GOOD_R")
	)
	(segment
		(start 355.019356 -214.824056)
		(end 355.019356 -214.325708)
		(width 0.15494)
		(layer "In7.Cu")
		(net "PWRGD_NIC6_PWR_GOOD_R")
	)
	(segment
		(start 368.8842 -198.755)
		(end 369.6462 -198.755)
		(width 0.15494)
		(layer "In7.Cu")
		(net "PWRGD_NIC6_PWR_GOOD_R")
	)
	(segment
		(start 370.152422 -191.938402)
		(end 370.152422 -176.121568)
		(width 0.15494)
		(layer "In7.Cu")
		(net "PWRGD_NIC6_PWR_GOOD_R")
	)
	(segment
		(start 351.7392 -218.104212)
		(end 355.019356 -214.824056)
		(width 0.15494)
		(layer "In7.Cu")
		(net "PWRGD_NIC6_PWR_GOOD_R")
	)
	(segment
		(start 360.1212 -205.8162)
		(end 360.543856 -205.8162)
		(width 0.15494)
		(layer "In7.Cu")
		(net "PWRGD_NIC6_PWR_GOOD_R")
	)
	(segment
		(start 377.575064 -164.108892)
		(end 373.9007 -167.783256)
		(width 0.15494)
		(layer "In13.Cu")
		(net "PWRGD_NIC6_PWR_GOOD_R")
	)
	(segment
		(start 387.1468 -164.108892)
		(end 377.575064 -164.108892)
		(width 0.15494)
		(layer "In13.Cu")
		(net "PWRGD_NIC6_PWR_GOOD_R")
	)
	(segment
		(start 373.9007 -167.783256)
		(end 364.116366 -167.783256)
		(width 0.15494)
		(layer "In13.Cu")
		(net "PWRGD_NIC6_PWR_GOOD_R")
	)
	(segment
		(start 248.112534 -27.04592)
		(end 247.968516 -27.189938)
		(width 0.13462)
		(layer "F.Cu")
		(net "CLK_100M_DB800ZL_SSD8_R_DP")
	)
	(segment
		(start 247.968516 -27.189938)
		(end 247.464834 -27.189938)
		(width 0.13462)
		(layer "F.Cu")
		(net "CLK_100M_DB800ZL_SSD8_R_DP")
	)
	(segment
		(start 249.181366 -27.342846)
		(end 248.88444 -27.04592)
		(width 0.13462)
		(layer "F.Cu")
		(net "CLK_100M_DB800ZL_SSD8_R_DP")
	)
	(segment
		(start 335.153 -79.89316)
		(end 335.153 -79.1718)
		(width 0.13462)
		(layer "F.Cu")
		(net "CLK_100M_DB800ZL_SSD8_R_DP")
	)
	(segment
		(start 248.88444 -27.04592)
		(end 248.112534 -27.04592)
		(width 0.13462)
		(layer "F.Cu")
		(net "CLK_100M_DB800ZL_SSD8_R_DP")
	)
	(segment
		(start 335.153 -79.1718)
		(end 334.863948 -78.882748)
		(width 0.13462)
		(layer "F.Cu")
		(net "CLK_100M_DB800ZL_SSD8_R_DP")
	)
	(segment
		(start 334.838548 -80.207612)
		(end 335.153 -79.89316)
		(width 0.13462)
		(layer "F.Cu")
		(net "CLK_100M_DB800ZL_SSD8_R_DP")
	)
	(via
		(at 334.863948 -78.882748)
		(size 0.508)
		(drill 0.254)
		(layers "F.Cu" "B.Cu")
		(net "CLK_100M_DB800ZL_SSD8_R_DP")
	)
	(via
		(at 249.181366 -27.342846)
		(size 0.508)
		(drill 0.254)
		(layers "F.Cu" "B.Cu")
		(net "CLK_100M_DB800ZL_SSD8_R_DP")
	)
	(segment
		(start 258.487672 -36.04387)
		(end 258.487672 -35.882072)
		(width 0.1651)
		(layer "In13.Cu")
		(net "CLK_100M_DB800ZL_SSD8_R_DP")
	)
	(segment
		(start 335.154778 -77.573378)
		(end 334.8736 -77.2922)
		(width 0.1651)
		(layer "In13.Cu")
		(net "CLK_100M_DB800ZL_SSD8_R_DP")
	)
	(segment
		(start 256.413 -33.8074)
		(end 256.413 -30.7848)
		(width 0.1651)
		(layer "In13.Cu")
		(net "CLK_100M_DB800ZL_SSD8_R_DP")
	)
	(segment
		(start 251.1044 -27.432)
		(end 250.724416 -27.052016)
		(width 0.1651)
		(layer "In13.Cu")
		(net "CLK_100M_DB800ZL_SSD8_R_DP")
	)
	(segment
		(start 323.2658 -77.2922)
		(end 314.359544 -68.385944)
		(width 0.1651)
		(layer "In13.Cu")
		(net "CLK_100M_DB800ZL_SSD8_R_DP")
	)
	(segment
		(start 258.838192 -36.39439)
		(end 258.487672 -36.04387)
		(width 0.1651)
		(layer "In13.Cu")
		(net "CLK_100M_DB800ZL_SSD8_R_DP")
	)
	(segment
		(start 334.863948 -78.882748)
		(end 335.154778 -78.591918)
		(width 0.1651)
		(layer "In13.Cu")
		(net "CLK_100M_DB800ZL_SSD8_R_DP")
	)
	(segment
		(start 314.359544 -68.385944)
		(end 309.677308 -66.4464)
		(width 0.1651)
		(layer "In13.Cu")
		(net "CLK_100M_DB800ZL_SSD8_R_DP")
	)
	(segment
		(start 259.86232 -37.25672)
		(end 259.700522 -37.25672)
		(width 0.1651)
		(layer "In13.Cu")
		(net "CLK_100M_DB800ZL_SSD8_R_DP")
	)
	(segment
		(start 257.625342 -35.019742)
		(end 257.27533 -34.66973)
		(width 0.1651)
		(layer "In13.Cu")
		(net "CLK_100M_DB800ZL_SSD8_R_DP")
	)
	(segment
		(start 258.13766 -35.53206)
		(end 257.975862 -35.53206)
		(width 0.1651)
		(layer "In13.Cu")
		(net "CLK_100M_DB800ZL_SSD8_R_DP")
	)
	(segment
		(start 260.212332 -37.606732)
		(end 259.86232 -37.25672)
		(width 0.1651)
		(layer "In13.Cu")
		(net "CLK_100M_DB800ZL_SSD8_R_DP")
	)
	(segment
		(start 260.72465 -38.11905)
		(end 260.562852 -38.11905)
		(width 0.1651)
		(layer "In13.Cu")
		(net "CLK_100M_DB800ZL_SSD8_R_DP")
	)
	(segment
		(start 256.763012 -34.157412)
		(end 256.413 -33.8074)
		(width 0.1651)
		(layer "In13.Cu")
		(net "CLK_100M_DB800ZL_SSD8_R_DP")
	)
	(segment
		(start 258.487672 -35.882072)
		(end 258.13766 -35.53206)
		(width 0.1651)
		(layer "In13.Cu")
		(net "CLK_100M_DB800ZL_SSD8_R_DP")
	)
	(segment
		(start 252.349 -27.432)
		(end 251.1044 -27.432)
		(width 0.1651)
		(layer "In13.Cu")
		(net "CLK_100M_DB800ZL_SSD8_R_DP")
	)
	(segment
		(start 335.154778 -78.591918)
		(end 335.154778 -77.573378)
		(width 0.1651)
		(layer "In13.Cu")
		(net "CLK_100M_DB800ZL_SSD8_R_DP")
	)
	(segment
		(start 259.350002 -36.9062)
		(end 259.350002 -36.744402)
		(width 0.1651)
		(layer "In13.Cu")
		(net "CLK_100M_DB800ZL_SSD8_R_DP")
	)
	(segment
		(start 269.9766 -47.371)
		(end 260.72465 -38.11905)
		(width 0.1651)
		(layer "In13.Cu")
		(net "CLK_100M_DB800ZL_SSD8_R_DP")
	)
	(segment
		(start 256.763012 -34.31921)
		(end 256.763012 -34.157412)
		(width 0.1651)
		(layer "In13.Cu")
		(net "CLK_100M_DB800ZL_SSD8_R_DP")
	)
	(segment
		(start 334.8736 -77.2922)
		(end 323.2658 -77.2922)
		(width 0.1651)
		(layer "In13.Cu")
		(net "CLK_100M_DB800ZL_SSD8_R_DP")
	)
	(segment
		(start 253.5936 -27.9654)
		(end 252.8824 -27.9654)
		(width 0.1651)
		(layer "In13.Cu")
		(net "CLK_100M_DB800ZL_SSD8_R_DP")
	)
	(segment
		(start 276.6822 -66.4464)
		(end 269.9766 -59.7408)
		(width 0.1651)
		(layer "In13.Cu")
		(net "CLK_100M_DB800ZL_SSD8_R_DP")
	)
	(segment
		(start 259.350002 -36.744402)
		(end 258.99999 -36.39439)
		(width 0.1651)
		(layer "In13.Cu")
		(net "CLK_100M_DB800ZL_SSD8_R_DP")
	)
	(segment
		(start 309.677308 -66.4464)
		(end 276.6822 -66.4464)
		(width 0.1651)
		(layer "In13.Cu")
		(net "CLK_100M_DB800ZL_SSD8_R_DP")
	)
	(segment
		(start 252.8824 -27.9654)
		(end 252.349 -27.432)
		(width 0.1651)
		(layer "In13.Cu")
		(net "CLK_100M_DB800ZL_SSD8_R_DP")
	)
	(segment
		(start 258.99999 -36.39439)
		(end 258.838192 -36.39439)
		(width 0.1651)
		(layer "In13.Cu")
		(net "CLK_100M_DB800ZL_SSD8_R_DP")
	)
	(segment
		(start 269.9766 -59.7408)
		(end 269.9766 -47.371)
		(width 0.1651)
		(layer "In13.Cu")
		(net "CLK_100M_DB800ZL_SSD8_R_DP")
	)
	(segment
		(start 260.562852 -38.11905)
		(end 260.212332 -37.76853)
		(width 0.1651)
		(layer "In13.Cu")
		(net "CLK_100M_DB800ZL_SSD8_R_DP")
	)
	(segment
		(start 257.975862 -35.53206)
		(end 257.625342 -35.18154)
		(width 0.1651)
		(layer "In13.Cu")
		(net "CLK_100M_DB800ZL_SSD8_R_DP")
	)
	(segment
		(start 260.212332 -37.76853)
		(end 260.212332 -37.606732)
		(width 0.1651)
		(layer "In13.Cu")
		(net "CLK_100M_DB800ZL_SSD8_R_DP")
	)
	(segment
		(start 259.700522 -37.25672)
		(end 259.350002 -36.9062)
		(width 0.1651)
		(layer "In13.Cu")
		(net "CLK_100M_DB800ZL_SSD8_R_DP")
	)
	(segment
		(start 257.113532 -34.66973)
		(end 256.763012 -34.31921)
		(width 0.1651)
		(layer "In13.Cu")
		(net "CLK_100M_DB800ZL_SSD8_R_DP")
	)
	(segment
		(start 250.724416 -27.052016)
		(end 249.472196 -27.052016)
		(width 0.1651)
		(layer "In13.Cu")
		(net "CLK_100M_DB800ZL_SSD8_R_DP")
	)
	(segment
		(start 256.413 -30.7848)
		(end 253.5936 -27.9654)
		(width 0.1651)
		(layer "In13.Cu")
		(net "CLK_100M_DB800ZL_SSD8_R_DP")
	)
	(segment
		(start 257.625342 -35.18154)
		(end 257.625342 -35.019742)
		(width 0.1651)
		(layer "In13.Cu")
		(net "CLK_100M_DB800ZL_SSD8_R_DP")
	)
	(segment
		(start 257.27533 -34.66973)
		(end 257.113532 -34.66973)
		(width 0.1651)
		(layer "In13.Cu")
		(net "CLK_100M_DB800ZL_SSD8_R_DP")
	)
	(segment
		(start 249.472196 -27.052016)
		(end 249.181366 -27.342846)
		(width 0.1651)
		(layer "In13.Cu")
		(net "CLK_100M_DB800ZL_SSD8_R_DP")
	)
	(segment
		(start 255.582674 -84.056474)
		(end 255.498092 -83.971892)
		(width 0.13208)
		(layer "F.Cu")
		(net "TP_CLK_PFT_IN_DP")
	)
	(segment
		(start 254.458724 -83.971892)
		(end 254.283972 -84.146644)
		(width 0.13208)
		(layer "F.Cu")
		(net "TP_CLK_PFT_IN_DP")
	)
	(segment
		(start 255.498092 -83.971892)
		(end 254.458724 -83.971892)
		(width 0.13208)
		(layer "F.Cu")
		(net "TP_CLK_PFT_IN_DP")
	)
	(segment
		(start 254.283972 -84.146644)
		(end 254.283972 -85.600286)
		(width 0.13208)
		(layer "F.Cu")
		(net "TP_CLK_PFT_IN_DP")
	)
	(segment
		(start 254.283972 -85.600286)
		(end 251.112274 -88.771984)
		(width 0.13208)
		(layer "F.Cu")
		(net "TP_CLK_PFT_IN_DP")
	)
	(segment
		(start 255.801876 -84.056474)
		(end 255.582674 -84.056474)
		(width 0.13208)
		(layer "F.Cu")
		(net "TP_CLK_PFT_IN_DP")
	)
	(via
		(at 251.112274 -88.771984)
		(size 0.508)
		(drill 0.254)
		(layers "F.Cu" "B.Cu")
		(net "TP_CLK_PFT_IN_DP")
	)
	(segment
		(start 362.30814 -84.864956)
		(end 364.245652 -84.864956)
		(width 0.13208)
		(layer "F.Cu")
		(net "SMB_BIC_I2C9_MUX1_SSD13_SCL")
	)
	(segment
		(start 364.245652 -84.864956)
		(end 366.49279 -84.864956)
		(width 0.13208)
		(layer "F.Cu")
		(net "SMB_BIC_I2C9_MUX1_SSD13_SCL")
	)
	(segment
		(start 366.49279 -84.864956)
		(end 366.555528 -84.927694)
		(width 0.13208)
		(layer "F.Cu")
		(net "SMB_BIC_I2C9_MUX1_SSD13_SCL")
	)
	(via
		(at 364.245652 -84.864956)
		(size 0.508)
		(drill 0.254)
		(layers "F.Cu" "B.Cu")
		(net "SMB_BIC_I2C9_MUX1_SSD13_SCL")
	)
	(segment
		(start 349.25 -230.504746)
		(end 349.25 -231.521)
		(width 0.13208)
		(layer "F.Cu")
		(net "SSD6_CLK_EN_N")
	)
	(segment
		(start 349.25 -231.521)
		(end 349.25 -232.537)
		(width 0.13208)
		(layer "F.Cu")
		(net "SSD6_CLK_EN_N")
	)
	(segment
		(start 348.493842 -229.748588)
		(end 349.25 -230.504746)
		(width 0.13208)
		(layer "F.Cu")
		(net "SSD6_CLK_EN_N")
	)
	(segment
		(start 348.493842 -227.987098)
		(end 348.493842 -229.748588)
		(width 0.13208)
		(layer "F.Cu")
		(net "SSD6_CLK_EN_N")
	)
	(segment
		(start 349.123 -232.664)
		(end 349.123 -233.66095)
		(width 0.13208)
		(layer "F.Cu")
		(net "SSD6_CLK_EN_N")
	)
	(segment
		(start 349.25 -232.537)
		(end 349.123 -232.664)
		(width 0.13208)
		(layer "F.Cu")
		(net "SSD6_CLK_EN_N")
	)
	(via
		(at 349.25 -231.521)
		(size 0.762)
		(drill 0.381)
		(layers "F.Cu" "B.Cu")
		(net "SSD6_CLK_EN_N")
	)
	(segment
		(start 346.093796 -217.587068)
		(end 346.493592 -217.187272)
		(width 0.13208)
		(layer "F.Cu")
		(net "PRSNT_NIC1_FPGA_N")
	)
	(segment
		(start 357.61295 -215.392)
		(end 356.108 -215.392)
		(width 0.13208)
		(layer "F.Cu")
		(net "PRSNT_NIC1_FPGA_N")
	)
	(via
		(at 346.493592 -217.187272)
		(size 0.4572)
		(drill 0.254)
		(layers "F.Cu" "B.Cu")
		(net "PRSNT_NIC1_FPGA_N")
	)
	(via
		(at 356.108 -215.392)
		(size 0.508)
		(drill 0.254)
		(layers "F.Cu" "B.Cu")
		(net "PRSNT_NIC1_FPGA_N")
	)
	(segment
		(start 351.358454 -217.27795)
		(end 353.07905 -217.27795)
		(width 0.15494)
		(layer "In9.Cu")
		(net "PRSNT_NIC1_FPGA_N")
	)
	(segment
		(start 346.493592 -217.187272)
		(end 346.896182 -217.589862)
		(width 0.0889)
		(layer "In9.Cu")
		(net "PRSNT_NIC1_FPGA_N")
	)
	(segment
		(start 346.896182 -217.589862)
		(end 351.046542 -217.589862)
		(width 0.0889)
		(layer "In9.Cu")
		(net "PRSNT_NIC1_FPGA_N")
	)
	(segment
		(start 351.046542 -217.589862)
		(end 351.358454 -217.27795)
		(width 0.15494)
		(layer "In9.Cu")
		(net "PRSNT_NIC1_FPGA_N")
	)
	(segment
		(start 353.07905 -217.27795)
		(end 354.965 -215.392)
		(width 0.15494)
		(layer "In9.Cu")
		(net "PRSNT_NIC1_FPGA_N")
	)
	(segment
		(start 354.965 -215.392)
		(end 356.108 -215.392)
		(width 0.15494)
		(layer "In9.Cu")
		(net "PRSNT_NIC1_FPGA_N")
	)
	(segment
		(start 273.968464 -27.189938)
		(end 273.464782 -27.189938)
		(width 0.13462)
		(layer "F.Cu")
		(net "CLK_100M_DB800ZL_SSD9_R_DP")
	)
	(segment
		(start 337.1596 -79.886556)
		(end 337.1596 -78.416404)
		(width 0.13462)
		(layer "F.Cu")
		(net "CLK_100M_DB800ZL_SSD9_R_DP")
	)
	(segment
		(start 337.1596 -78.416404)
		(end 336.863944 -78.120748)
		(width 0.13462)
		(layer "F.Cu")
		(net "CLK_100M_DB800ZL_SSD9_R_DP")
	)
	(segment
		(start 274.884388 -27.04592)
		(end 274.112482 -27.04592)
		(width 0.13462)
		(layer "F.Cu")
		(net "CLK_100M_DB800ZL_SSD9_R_DP")
	)
	(segment
		(start 336.838544 -80.207612)
		(end 337.1596 -79.886556)
		(width 0.13462)
		(layer "F.Cu")
		(net "CLK_100M_DB800ZL_SSD9_R_DP")
	)
	(segment
		(start 275.181314 -27.342846)
		(end 274.884388 -27.04592)
		(width 0.13462)
		(layer "F.Cu")
		(net "CLK_100M_DB800ZL_SSD9_R_DP")
	)
	(segment
		(start 274.112482 -27.04592)
		(end 273.968464 -27.189938)
		(width 0.13462)
		(layer "F.Cu")
		(net "CLK_100M_DB800ZL_SSD9_R_DP")
	)
	(via
		(at 275.181314 -27.342846)
		(size 0.508)
		(drill 0.254)
		(layers "F.Cu" "B.Cu")
		(net "CLK_100M_DB800ZL_SSD9_R_DP")
	)
	(via
		(at 336.863944 -78.120748)
		(size 0.508)
		(drill 0.254)
		(layers "F.Cu" "B.Cu")
		(net "CLK_100M_DB800ZL_SSD9_R_DP")
	)
	(segment
		(start 286.195262 -36.87826)
		(end 286.195262 -36.716462)
		(width 0.1651)
		(layer "In13.Cu")
		(net "CLK_100M_DB800ZL_SSD9_R_DP")
	)
	(segment
		(start 283.608272 -34.29127)
		(end 283.608272 -34.129472)
		(width 0.1651)
		(layer "In13.Cu")
		(net "CLK_100M_DB800ZL_SSD9_R_DP")
	)
	(segment
		(start 283.25826 -31.15564)
		(end 280.06802 -27.9654)
		(width 0.1651)
		(layer "In13.Cu")
		(net "CLK_100M_DB800ZL_SSD9_R_DP")
	)
	(segment
		(start 284.470602 -35.1536)
		(end 284.470602 -34.991802)
		(width 0.1651)
		(layer "In13.Cu")
		(net "CLK_100M_DB800ZL_SSD9_R_DP")
	)
	(segment
		(start 324.49262 -76.1492)
		(end 315.916056 -67.572636)
		(width 0.1651)
		(layer "In13.Cu")
		(net "CLK_100M_DB800ZL_SSD9_R_DP")
	)
	(segment
		(start 279.019 -27.9654)
		(end 278.4094 -27.3558)
		(width 0.1651)
		(layer "In13.Cu")
		(net "CLK_100M_DB800ZL_SSD9_R_DP")
	)
	(segment
		(start 337.154774 -76.804774)
		(end 336.4992 -76.1492)
		(width 0.1651)
		(layer "In13.Cu")
		(net "CLK_100M_DB800ZL_SSD9_R_DP")
	)
	(segment
		(start 285.683452 -36.36645)
		(end 285.332932 -36.01593)
		(width 0.1651)
		(layer "In13.Cu")
		(net "CLK_100M_DB800ZL_SSD9_R_DP")
	)
	(segment
		(start 280.06802 -27.9654)
		(end 279.019 -27.9654)
		(width 0.1651)
		(layer "In13.Cu")
		(net "CLK_100M_DB800ZL_SSD9_R_DP")
	)
	(segment
		(start 284.98292 -35.50412)
		(end 284.821122 -35.50412)
		(width 0.1651)
		(layer "In13.Cu")
		(net "CLK_100M_DB800ZL_SSD9_R_DP")
	)
	(segment
		(start 285.84525 -36.36645)
		(end 285.683452 -36.36645)
		(width 0.1651)
		(layer "In13.Cu")
		(net "CLK_100M_DB800ZL_SSD9_R_DP")
	)
	(segment
		(start 336.863944 -78.120748)
		(end 337.154774 -77.829918)
		(width 0.1651)
		(layer "In13.Cu")
		(net "CLK_100M_DB800ZL_SSD9_R_DP")
	)
	(segment
		(start 337.154774 -77.829918)
		(end 337.154774 -76.804774)
		(width 0.1651)
		(layer "In13.Cu")
		(net "CLK_100M_DB800ZL_SSD9_R_DP")
	)
	(segment
		(start 275.472144 -27.052016)
		(end 275.181314 -27.342846)
		(width 0.1651)
		(layer "In13.Cu")
		(net "CLK_100M_DB800ZL_SSD9_R_DP")
	)
	(segment
		(start 284.470602 -34.991802)
		(end 284.12059 -34.64179)
		(width 0.1651)
		(layer "In13.Cu")
		(net "CLK_100M_DB800ZL_SSD9_R_DP")
	)
	(segment
		(start 295.9608 -58.97118)
		(end 295.9608 -46.482)
		(width 0.1651)
		(layer "In13.Cu")
		(net "CLK_100M_DB800ZL_SSD9_R_DP")
	)
	(segment
		(start 276.9616 -27.3558)
		(end 276.657816 -27.052016)
		(width 0.1651)
		(layer "In13.Cu")
		(net "CLK_100M_DB800ZL_SSD9_R_DP")
	)
	(segment
		(start 286.195262 -36.716462)
		(end 285.84525 -36.36645)
		(width 0.1651)
		(layer "In13.Cu")
		(net "CLK_100M_DB800ZL_SSD9_R_DP")
	)
	(segment
		(start 295.9608 -46.482)
		(end 286.70758 -37.22878)
		(width 0.1651)
		(layer "In13.Cu")
		(net "CLK_100M_DB800ZL_SSD9_R_DP")
	)
	(segment
		(start 315.916056 -67.572636)
		(end 307.923438 -64.262)
		(width 0.1651)
		(layer "In13.Cu")
		(net "CLK_100M_DB800ZL_SSD9_R_DP")
	)
	(segment
		(start 285.332932 -36.01593)
		(end 285.332932 -35.854132)
		(width 0.1651)
		(layer "In13.Cu")
		(net "CLK_100M_DB800ZL_SSD9_R_DP")
	)
	(segment
		(start 284.12059 -34.64179)
		(end 283.958792 -34.64179)
		(width 0.1651)
		(layer "In13.Cu")
		(net "CLK_100M_DB800ZL_SSD9_R_DP")
	)
	(segment
		(start 301.25162 -64.262)
		(end 295.9608 -58.97118)
		(width 0.1651)
		(layer "In13.Cu")
		(net "CLK_100M_DB800ZL_SSD9_R_DP")
	)
	(segment
		(start 285.332932 -35.854132)
		(end 284.98292 -35.50412)
		(width 0.1651)
		(layer "In13.Cu")
		(net "CLK_100M_DB800ZL_SSD9_R_DP")
	)
	(segment
		(start 286.70758 -37.22878)
		(end 286.545782 -37.22878)
		(width 0.1651)
		(layer "In13.Cu")
		(net "CLK_100M_DB800ZL_SSD9_R_DP")
	)
	(segment
		(start 283.25826 -33.77946)
		(end 283.25826 -31.15564)
		(width 0.1651)
		(layer "In13.Cu")
		(net "CLK_100M_DB800ZL_SSD9_R_DP")
	)
	(segment
		(start 336.4992 -76.1492)
		(end 324.49262 -76.1492)
		(width 0.1651)
		(layer "In13.Cu")
		(net "CLK_100M_DB800ZL_SSD9_R_DP")
	)
	(segment
		(start 284.821122 -35.50412)
		(end 284.470602 -35.1536)
		(width 0.1651)
		(layer "In13.Cu")
		(net "CLK_100M_DB800ZL_SSD9_R_DP")
	)
	(segment
		(start 283.958792 -34.64179)
		(end 283.608272 -34.29127)
		(width 0.1651)
		(layer "In13.Cu")
		(net "CLK_100M_DB800ZL_SSD9_R_DP")
	)
	(segment
		(start 278.4094 -27.3558)
		(end 276.9616 -27.3558)
		(width 0.1651)
		(layer "In13.Cu")
		(net "CLK_100M_DB800ZL_SSD9_R_DP")
	)
	(segment
		(start 307.923438 -64.262)
		(end 301.25162 -64.262)
		(width 0.1651)
		(layer "In13.Cu")
		(net "CLK_100M_DB800ZL_SSD9_R_DP")
	)
	(segment
		(start 276.657816 -27.052016)
		(end 275.472144 -27.052016)
		(width 0.1651)
		(layer "In13.Cu")
		(net "CLK_100M_DB800ZL_SSD9_R_DP")
	)
	(segment
		(start 283.608272 -34.129472)
		(end 283.25826 -33.77946)
		(width 0.1651)
		(layer "In13.Cu")
		(net "CLK_100M_DB800ZL_SSD9_R_DP")
	)
	(segment
		(start 286.545782 -37.22878)
		(end 286.195262 -36.87826)
		(width 0.1651)
		(layer "In13.Cu")
		(net "CLK_100M_DB800ZL_SSD9_R_DP")
	)
	(segment
		(start 218.186 -205.74)
		(end 218.80195 -205.74)
		(width 0.13208)
		(layer "F.Cu")
		(net "SMB_NIC4_LS_EN")
	)
	(segment
		(start 217.637106 -206.288894)
		(end 218.186 -205.74)
		(width 0.13208)
		(layer "F.Cu")
		(net "SMB_NIC4_LS_EN")
	)
	(segment
		(start 216.991946 -206.288894)
		(end 217.637106 -206.288894)
		(width 0.13208)
		(layer "F.Cu")
		(net "SMB_NIC4_LS_EN")
	)
	(via
		(at 218.186 -205.74)
		(size 0.508)
		(drill 0.254)
		(layers "F.Cu" "B.Cu")
		(net "SMB_NIC4_LS_EN")
	)
	(segment
		(start 362.30814 -84.21497)
		(end 363.732064 -84.21497)
		(width 0.13208)
		(layer "F.Cu")
		(net "SMB_BIC_I2C9_MUX1_SSD13_SDA")
	)
	(segment
		(start 365.462566 -83.784694)
		(end 366.555528 -83.784694)
		(width 0.13208)
		(layer "F.Cu")
		(net "SMB_BIC_I2C9_MUX1_SSD13_SDA")
	)
	(segment
		(start 364.16234 -83.784694)
		(end 365.462566 -83.784694)
		(width 0.13208)
		(layer "F.Cu")
		(net "SMB_BIC_I2C9_MUX1_SSD13_SDA")
	)
	(segment
		(start 363.732064 -84.21497)
		(end 364.16234 -83.784694)
		(width 0.13208)
		(layer "F.Cu")
		(net "SMB_BIC_I2C9_MUX1_SSD13_SDA")
	)
	(via
		(at 365.462566 -83.784694)
		(size 0.508)
		(drill 0.254)
		(layers "F.Cu" "B.Cu")
		(net "SMB_BIC_I2C9_MUX1_SSD13_SDA")
	)
	(segment
		(start 339.344 -228.727)
		(end 339.344 -228.336856)
		(width 0.13208)
		(layer "F.Cu")
		(net "SMB_PEX2_FPGA_SDA")
	)
	(segment
		(start 322.051934 -288.221166)
		(end 322.051934 -288.830766)
		(width 0.13208)
		(layer "F.Cu")
		(net "SMB_PEX2_FPGA_SDA")
	)
	(segment
		(start 339.344 -228.336856)
		(end 339.693758 -227.987098)
		(width 0.13208)
		(layer "F.Cu")
		(net "SMB_PEX2_FPGA_SDA")
	)
	(via
		(at 331.82179 -263.308084)
		(size 0.508)
		(drill 0.254)
		(layers "F.Cu" "B.Cu")
		(net "SMB_PEX2_FPGA_SDA")
	)
	(via
		(at 322.051934 -288.221166)
		(size 0.508)
		(drill 0.254)
		(layers "F.Cu" "B.Cu")
		(net "SMB_PEX2_FPGA_SDA")
	)
	(via
		(at 339.344 -228.727)
		(size 0.508)
		(drill 0.254)
		(layers "F.Cu" "B.Cu")
		(net "SMB_PEX2_FPGA_SDA")
	)
	(segment
		(start 322.051934 -278.583136)
		(end 322.051934 -288.221166)
		(width 0.13208)
		(layer "B.Cu")
		(net "SMB_PEX2_FPGA_SDA")
	)
	(segment
		(start 327.723246 -267.484352)
		(end 327.723246 -272.911824)
		(width 0.13208)
		(layer "B.Cu")
		(net "SMB_PEX2_FPGA_SDA")
	)
	(segment
		(start 331.82179 -263.385808)
		(end 327.723246 -267.484352)
		(width 0.13208)
		(layer "B.Cu")
		(net "SMB_PEX2_FPGA_SDA")
	)
	(segment
		(start 331.82179 -263.308084)
		(end 331.82179 -263.385808)
		(width 0.13208)
		(layer "B.Cu")
		(net "SMB_PEX2_FPGA_SDA")
	)
	(segment
		(start 327.723246 -272.911824)
		(end 322.051934 -278.583136)
		(width 0.13208)
		(layer "B.Cu")
		(net "SMB_PEX2_FPGA_SDA")
	)
	(segment
		(start 333.531972 -261.623556)
		(end 333.506318 -261.623556)
		(width 0.15494)
		(layer "In9.Cu")
		(net "SMB_PEX2_FPGA_SDA")
	)
	(segment
		(start 326.517 -252.501654)
		(end 333.658972 -259.643626)
		(width 0.15494)
		(layer "In9.Cu")
		(net "SMB_PEX2_FPGA_SDA")
	)
	(segment
		(start 330.554838 -233.5276)
		(end 329.692 -234.390438)
		(width 0.15494)
		(layer "In9.Cu")
		(net "SMB_PEX2_FPGA_SDA")
	)
	(segment
		(start 333.658972 -261.496556)
		(end 333.531972 -261.623556)
		(width 0.15494)
		(layer "In9.Cu")
		(net "SMB_PEX2_FPGA_SDA")
	)
	(segment
		(start 326.9234 -240.7412)
		(end 326.517 -241.1476)
		(width 0.15494)
		(layer "In9.Cu")
		(net "SMB_PEX2_FPGA_SDA")
	)
	(segment
		(start 333.658972 -259.643626)
		(end 333.658972 -261.496556)
		(width 0.15494)
		(layer "In9.Cu")
		(net "SMB_PEX2_FPGA_SDA")
	)
	(segment
		(start 339.344 -228.727)
		(end 338.755482 -229.315518)
		(width 0.15494)
		(layer "In9.Cu")
		(net "SMB_PEX2_FPGA_SDA")
	)
	(segment
		(start 329.692 -234.390438)
		(end 329.692 -235.762546)
		(width 0.15494)
		(layer "In9.Cu")
		(net "SMB_PEX2_FPGA_SDA")
	)
	(segment
		(start 326.9234 -238.531146)
		(end 326.9234 -240.7412)
		(width 0.15494)
		(layer "In9.Cu")
		(net "SMB_PEX2_FPGA_SDA")
	)
	(segment
		(start 335.0514 -233.5276)
		(end 330.554838 -233.5276)
		(width 0.15494)
		(layer "In9.Cu")
		(net "SMB_PEX2_FPGA_SDA")
	)
	(segment
		(start 326.517 -241.1476)
		(end 326.517 -252.501654)
		(width 0.15494)
		(layer "In9.Cu")
		(net "SMB_PEX2_FPGA_SDA")
	)
	(segment
		(start 333.506318 -261.623556)
		(end 331.82179 -263.308084)
		(width 0.15494)
		(layer "In9.Cu")
		(net "SMB_PEX2_FPGA_SDA")
	)
	(segment
		(start 338.755482 -229.315518)
		(end 338.755482 -229.823518)
		(width 0.15494)
		(layer "In9.Cu")
		(net "SMB_PEX2_FPGA_SDA")
	)
	(segment
		(start 329.692 -235.762546)
		(end 326.9234 -238.531146)
		(width 0.15494)
		(layer "In9.Cu")
		(net "SMB_PEX2_FPGA_SDA")
	)
	(segment
		(start 338.755482 -229.823518)
		(end 335.0514 -233.5276)
		(width 0.15494)
		(layer "In9.Cu")
		(net "SMB_PEX2_FPGA_SDA")
	)
	(segment
		(start 450.8754 -54.144164)
		(end 451.055994 -53.96357)
		(width 0.13208)
		(layer "F.Cu")
		(net "P12V_SSD15_OCP")
	)
	(segment
		(start 450.447156 -54.144164)
		(end 450.8754 -54.144164)
		(width 0.13208)
		(layer "F.Cu")
		(net "P12V_SSD15_OCP")
	)
	(segment
		(start 452.063866 -53.96357)
		(end 451.454012 -53.96357)
		(width 0.13208)
		(layer "F.Cu")
		(net "P12V_SSD15_OCP")
	)
	(segment
		(start 452.167752 -54.067456)
		(end 452.063866 -53.96357)
		(width 0.13208)
		(layer "F.Cu")
		(net "P12V_SSD15_OCP")
	)
	(segment
		(start 451.055994 -53.96357)
		(end 451.454012 -53.96357)
		(width 0.13208)
		(layer "F.Cu")
		(net "P12V_SSD15_OCP")
	)
	(via
		(at 451.454012 -53.96357)
		(size 0.508)
		(drill 0.254)
		(layers "F.Cu" "B.Cu")
		(net "P12V_SSD15_OCP")
	)
	(segment
		(start 383.355596 -233.991404)
		(end 383.355596 -232.836212)
		(width 0.13208)
		(layer "F.Cu")
		(net "FT4232_SDB_REF")
	)
	(via
		(at 383.355596 -233.991404)
		(size 0.508)
		(drill 0.254)
		(layers "F.Cu" "B.Cu")
		(net "FT4232_SDB_REF")
	)
	(segment
		(start 383.667 -235.18495)
		(end 383.667 -234.302808)
		(width 0.13208)
		(layer "B.Cu")
		(net "FT4232_SDB_REF")
	)
	(segment
		(start 383.667 -234.302808)
		(end 383.355596 -233.991404)
		(width 0.13208)
		(layer "B.Cu")
		(net "FT4232_SDB_REF")
	)
	(via
		(at 426.94987 -290.199826)
		(size 0.6604)
		(drill 0.3302)
		(layers "F.Cu" "B.Cu")
		(net "UART_PEX3_CLI_R_TX")
	)
	(via
		(at 125.9078 -215.744806)
		(size 0.508)
		(drill 0.254)
		(layers "F.Cu" "B.Cu")
		(net "UART_PEX3_CLI_R_TX")
	)
	(via
		(at 264.773156 -203.566522)
		(size 0.508)
		(drill 0.254)
		(layers "F.Cu" "B.Cu")
		(net "UART_PEX3_CLI_R_TX")
	)
	(via
		(at 444.325756 -250.927616)
		(size 0.508)
		(drill 0.254)
		(layers "F.Cu" "B.Cu")
		(net "UART_PEX3_CLI_R_TX")
	)
	(via
		(at 272.67535 -257.156712)
		(size 0.508)
		(drill 0.254)
		(layers "F.Cu" "B.Cu")
		(net "UART_PEX3_CLI_R_TX")
	)
	(segment
		(start 426.703236 -291.224716)
		(end 426.94987 -290.978082)
		(width 0.13208)
		(layer "B.Cu")
		(net "UART_PEX3_CLI_R_TX")
	)
	(segment
		(start 424.02379 -291.224716)
		(end 426.703236 -291.224716)
		(width 0.13208)
		(layer "B.Cu")
		(net "UART_PEX3_CLI_R_TX")
	)
	(segment
		(start 426.94987 -289.300666)
		(end 426.47997 -288.830766)
		(width 0.13208)
		(layer "B.Cu")
		(net "UART_PEX3_CLI_R_TX")
	)
	(segment
		(start 426.94987 -290.978082)
		(end 426.94987 -290.199826)
		(width 0.13208)
		(layer "B.Cu")
		(net "UART_PEX3_CLI_R_TX")
	)
	(segment
		(start 426.47997 -268.773402)
		(end 444.325756 -250.927616)
		(width 0.13208)
		(layer "B.Cu")
		(net "UART_PEX3_CLI_R_TX")
	)
	(segment
		(start 126.986538 -215.744806)
		(end 125.9078 -215.744806)
		(width 0.13208)
		(layer "B.Cu")
		(net "UART_PEX3_CLI_R_TX")
	)
	(segment
		(start 426.47997 -288.830766)
		(end 426.47997 -268.773402)
		(width 0.13208)
		(layer "B.Cu")
		(net "UART_PEX3_CLI_R_TX")
	)
	(segment
		(start 426.94987 -290.199826)
		(end 426.94987 -289.300666)
		(width 0.13208)
		(layer "B.Cu")
		(net "UART_PEX3_CLI_R_TX")
	)
	(segment
		(start 273.592036 -255.608328)
		(end 272.67535 -256.525014)
		(width 0.15494)
		(layer "In5.Cu")
		(net "UART_PEX3_CLI_R_TX")
	)
	(segment
		(start 264.773156 -203.566522)
		(end 264.773156 -204.962506)
		(width 0.15494)
		(layer "In5.Cu")
		(net "UART_PEX3_CLI_R_TX")
	)
	(segment
		(start 268.238224 -243.58473)
		(end 273.592036 -248.938542)
		(width 0.15494)
		(layer "In5.Cu")
		(net "UART_PEX3_CLI_R_TX")
	)
	(segment
		(start 269.461742 -228.327712)
		(end 268.238224 -229.55123)
		(width 0.15494)
		(layer "In5.Cu")
		(net "UART_PEX3_CLI_R_TX")
	)
	(segment
		(start 269.461742 -209.651092)
		(end 269.461742 -228.327712)
		(width 0.15494)
		(layer "In5.Cu")
		(net "UART_PEX3_CLI_R_TX")
	)
	(segment
		(start 272.67535 -256.525014)
		(end 272.67535 -257.156712)
		(width 0.15494)
		(layer "In5.Cu")
		(net "UART_PEX3_CLI_R_TX")
	)
	(segment
		(start 273.592036 -248.938542)
		(end 273.592036 -255.608328)
		(width 0.15494)
		(layer "In5.Cu")
		(net "UART_PEX3_CLI_R_TX")
	)
	(segment
		(start 268.238224 -229.55123)
		(end 268.238224 -243.58473)
		(width 0.15494)
		(layer "In5.Cu")
		(net "UART_PEX3_CLI_R_TX")
	)
	(segment
		(start 264.773156 -204.962506)
		(end 269.461742 -209.651092)
		(width 0.15494)
		(layer "In5.Cu")
		(net "UART_PEX3_CLI_R_TX")
	)
	(segment
		(start 260.179058 -205.618842)
		(end 259.190236 -204.63002)
		(width 0.15494)
		(layer "In15.Cu")
		(net "UART_PEX3_CLI_R_TX")
	)
	(segment
		(start 246.386096 -202.707748)
		(end 246.268748 -202.5904)
		(width 0.15494)
		(layer "In15.Cu")
		(net "UART_PEX3_CLI_R_TX")
	)
	(segment
		(start 330.491338 -258.290314)
		(end 337.118706 -258.290314)
		(width 0.15494)
		(layer "In15.Cu")
		(net "UART_PEX3_CLI_R_TX")
	)
	(segment
		(start 239.806988 -209.4992)
		(end 238.581946 -209.4992)
		(width 0.15494)
		(layer "In15.Cu")
		(net "UART_PEX3_CLI_R_TX")
	)
	(segment
		(start 392.098022 -245.85803)
		(end 440.522868 -245.85803)
		(width 0.15494)
		(layer "In15.Cu")
		(net "UART_PEX3_CLI_R_TX")
	)
	(segment
		(start 257.182112 -204.727048)
		(end 256.542794 -204.727048)
		(width 0.15494)
		(layer "In15.Cu")
		(net "UART_PEX3_CLI_R_TX")
	)
	(segment
		(start 373.782082 -244.827552)
		(end 377.009152 -244.827552)
		(width 0.15494)
		(layer "In15.Cu")
		(net "UART_PEX3_CLI_R_TX")
	)
	(segment
		(start 367.994438 -244.906292)
		(end 370.3066 -242.59413)
		(width 0.15494)
		(layer "In15.Cu")
		(net "UART_PEX3_CLI_R_TX")
	)
	(segment
		(start 274.674584 -257.733038)
		(end 302.731932 -257.733038)
		(width 0.15494)
		(layer "In15.Cu")
		(net "UART_PEX3_CLI_R_TX")
	)
	(segment
		(start 264.773156 -203.566522)
		(end 264.773156 -204.223874)
		(width 0.15494)
		(layer "In15.Cu")
		(net "UART_PEX3_CLI_R_TX")
	)
	(segment
		(start 222.23222 -211.77758)
		(end 217.294968 -211.77758)
		(width 0.15494)
		(layer "In15.Cu")
		(net "UART_PEX3_CLI_R_TX")
	)
	(segment
		(start 245.243858 -203.040742)
		(end 245.243858 -204.23251)
		(width 0.15494)
		(layer "In15.Cu")
		(net "UART_PEX3_CLI_R_TX")
	)
	(segment
		(start 337.118706 -258.290314)
		(end 350.764094 -244.644926)
		(width 0.15494)
		(layer "In15.Cu")
		(net "UART_PEX3_CLI_R_TX")
	)
	(segment
		(start 246.652034 -205.640686)
		(end 246.652034 -208.176876)
		(width 0.15494)
		(layer "In15.Cu")
		(net "UART_PEX3_CLI_R_TX")
	)
	(segment
		(start 264.773156 -204.223874)
		(end 263.378188 -205.618842)
		(width 0.15494)
		(layer "In15.Cu")
		(net "UART_PEX3_CLI_R_TX")
	)
	(segment
		(start 242.00485 -209.37855)
		(end 241.21491 -210.16849)
		(width 0.15494)
		(layer "In15.Cu")
		(net "UART_PEX3_CLI_R_TX")
	)
	(segment
		(start 222.82531 -211.398358)
		(end 222.611442 -211.398358)
		(width 0.15494)
		(layer "In15.Cu")
		(net "UART_PEX3_CLI_R_TX")
	)
	(segment
		(start 370.3066 -242.59413)
		(end 371.54866 -242.59413)
		(width 0.15494)
		(layer "In15.Cu")
		(net "UART_PEX3_CLI_R_TX")
	)
	(segment
		(start 444.496444 -249.831606)
		(end 444.496444 -250.232926)
		(width 0.15494)
		(layer "In15.Cu")
		(net "UART_PEX3_CLI_R_TX")
	)
	(segment
		(start 371.54866 -242.59413)
		(end 373.782082 -244.827552)
		(width 0.15494)
		(layer "In15.Cu")
		(net "UART_PEX3_CLI_R_TX")
	)
	(segment
		(start 257.27914 -204.63002)
		(end 257.182112 -204.727048)
		(width 0.15494)
		(layer "In15.Cu")
		(net "UART_PEX3_CLI_R_TX")
	)
	(segment
		(start 238.581946 -209.4992)
		(end 238.098076 -209.01533)
		(width 0.15494)
		(layer "In15.Cu")
		(net "UART_PEX3_CLI_R_TX")
	)
	(segment
		(start 315.28258 -258.423664)
		(end 315.529976 -258.67106)
		(width 0.15494)
		(layer "In15.Cu")
		(net "UART_PEX3_CLI_R_TX")
	)
	(segment
		(start 377.009152 -244.827552)
		(end 378.088906 -245.907306)
		(width 0.15494)
		(layer "In15.Cu")
		(net "UART_PEX3_CLI_R_TX")
	)
	(segment
		(start 140.380466 -216.9668)
		(end 139.849606 -217.49766)
		(width 0.15494)
		(layer "In15.Cu")
		(net "UART_PEX3_CLI_R_TX")
	)
	(segment
		(start 272.67535 -257.156712)
		(end 273.063462 -256.7686)
		(width 0.15494)
		(layer "In15.Cu")
		(net "UART_PEX3_CLI_R_TX")
	)
	(segment
		(start 247.974866 -204.2922)
		(end 246.390414 -202.707748)
		(width 0.15494)
		(layer "In15.Cu")
		(net "UART_PEX3_CLI_R_TX")
	)
	(segment
		(start 252.8824 -204.2414)
		(end 252.1712 -203.5302)
		(width 0.15494)
		(layer "In15.Cu")
		(net "UART_PEX3_CLI_R_TX")
	)
	(segment
		(start 256.057146 -204.2414)
		(end 252.8824 -204.2414)
		(width 0.15494)
		(layer "In15.Cu")
		(net "UART_PEX3_CLI_R_TX")
	)
	(segment
		(start 240.476278 -210.16849)
		(end 239.806988 -209.4992)
		(width 0.15494)
		(layer "In15.Cu")
		(net "UART_PEX3_CLI_R_TX")
	)
	(segment
		(start 382.782572 -245.907306)
		(end 384.460496 -244.229382)
		(width 0.15494)
		(layer "In15.Cu")
		(net "UART_PEX3_CLI_R_TX")
	)
	(segment
		(start 215.62314 -210.105752)
		(end 205.222094 -210.105752)
		(width 0.15494)
		(layer "In15.Cu")
		(net "UART_PEX3_CLI_R_TX")
	)
	(segment
		(start 252.1712 -203.5302)
		(end 249.8344 -203.5302)
		(width 0.15494)
		(layer "In15.Cu")
		(net "UART_PEX3_CLI_R_TX")
	)
	(segment
		(start 330.110592 -258.67106)
		(end 330.491338 -258.290314)
		(width 0.15494)
		(layer "In15.Cu")
		(net "UART_PEX3_CLI_R_TX")
	)
	(segment
		(start 378.088906 -245.907306)
		(end 382.782572 -245.907306)
		(width 0.15494)
		(layer "In15.Cu")
		(net "UART_PEX3_CLI_R_TX")
	)
	(segment
		(start 205.222094 -210.105752)
		(end 205.195678 -210.131914)
		(width 0.15494)
		(layer "In15.Cu")
		(net "UART_PEX3_CLI_R_TX")
	)
	(segment
		(start 225.208338 -209.01533)
		(end 222.82531 -211.398358)
		(width 0.15494)
		(layer "In15.Cu")
		(net "UART_PEX3_CLI_R_TX")
	)
	(segment
		(start 205.195678 -210.131914)
		(end 194.408298 -220.919294)
		(width 0.15494)
		(layer "In15.Cu")
		(net "UART_PEX3_CLI_R_TX")
	)
	(segment
		(start 245.6942 -202.5904)
		(end 245.243858 -203.040742)
		(width 0.15494)
		(layer "In15.Cu")
		(net "UART_PEX3_CLI_R_TX")
	)
	(segment
		(start 256.542794 -204.727048)
		(end 256.057146 -204.2414)
		(width 0.15494)
		(layer "In15.Cu")
		(net "UART_PEX3_CLI_R_TX")
	)
	(segment
		(start 444.496444 -250.232926)
		(end 444.325756 -250.403614)
		(width 0.15494)
		(layer "In15.Cu")
		(net "UART_PEX3_CLI_R_TX")
	)
	(segment
		(start 302.731932 -257.733038)
		(end 303.422558 -258.423664)
		(width 0.15494)
		(layer "In15.Cu")
		(net "UART_PEX3_CLI_R_TX")
	)
	(segment
		(start 444.325756 -250.403614)
		(end 444.325756 -250.927616)
		(width 0.15494)
		(layer "In15.Cu")
		(net "UART_PEX3_CLI_R_TX")
	)
	(segment
		(start 181.6608 -216.9668)
		(end 140.380466 -216.9668)
		(width 0.15494)
		(layer "In15.Cu")
		(net "UART_PEX3_CLI_R_TX")
	)
	(segment
		(start 303.422558 -258.423664)
		(end 315.28258 -258.423664)
		(width 0.15494)
		(layer "In15.Cu")
		(net "UART_PEX3_CLI_R_TX")
	)
	(segment
		(start 246.390414 -202.707748)
		(end 246.386096 -202.707748)
		(width 0.15494)
		(layer "In15.Cu")
		(net "UART_PEX3_CLI_R_TX")
	)
	(segment
		(start 249.8344 -203.5302)
		(end 249.0724 -204.2922)
		(width 0.15494)
		(layer "In15.Cu")
		(net "UART_PEX3_CLI_R_TX")
	)
	(segment
		(start 246.652034 -208.176876)
		(end 245.45036 -209.37855)
		(width 0.15494)
		(layer "In15.Cu")
		(net "UART_PEX3_CLI_R_TX")
	)
	(segment
		(start 245.45036 -209.37855)
		(end 242.00485 -209.37855)
		(width 0.15494)
		(layer "In15.Cu")
		(net "UART_PEX3_CLI_R_TX")
	)
	(segment
		(start 350.764094 -244.644926)
		(end 363.513878 -244.644926)
		(width 0.15494)
		(layer "In15.Cu")
		(net "UART_PEX3_CLI_R_TX")
	)
	(segment
		(start 259.190236 -204.63002)
		(end 257.27914 -204.63002)
		(width 0.15494)
		(layer "In15.Cu")
		(net "UART_PEX3_CLI_R_TX")
	)
	(segment
		(start 273.063462 -256.7686)
		(end 273.710146 -256.7686)
		(width 0.15494)
		(layer "In15.Cu")
		(net "UART_PEX3_CLI_R_TX")
	)
	(segment
		(start 273.710146 -256.7686)
		(end 274.674584 -257.733038)
		(width 0.15494)
		(layer "In15.Cu")
		(net "UART_PEX3_CLI_R_TX")
	)
	(segment
		(start 440.522868 -245.85803)
		(end 444.496444 -249.831606)
		(width 0.15494)
		(layer "In15.Cu")
		(net "UART_PEX3_CLI_R_TX")
	)
	(segment
		(start 238.098076 -209.01533)
		(end 225.208338 -209.01533)
		(width 0.15494)
		(layer "In15.Cu")
		(net "UART_PEX3_CLI_R_TX")
	)
	(segment
		(start 194.408298 -220.919294)
		(end 185.613294 -220.919294)
		(width 0.15494)
		(layer "In15.Cu")
		(net "UART_PEX3_CLI_R_TX")
	)
	(segment
		(start 246.268748 -202.5904)
		(end 245.6942 -202.5904)
		(width 0.15494)
		(layer "In15.Cu")
		(net "UART_PEX3_CLI_R_TX")
	)
	(segment
		(start 384.460496 -244.229382)
		(end 390.469374 -244.229382)
		(width 0.15494)
		(layer "In15.Cu")
		(net "UART_PEX3_CLI_R_TX")
	)
	(segment
		(start 363.513878 -244.644926)
		(end 363.775244 -244.906292)
		(width 0.15494)
		(layer "In15.Cu")
		(net "UART_PEX3_CLI_R_TX")
	)
	(segment
		(start 390.469374 -244.229382)
		(end 392.098022 -245.85803)
		(width 0.15494)
		(layer "In15.Cu")
		(net "UART_PEX3_CLI_R_TX")
	)
	(segment
		(start 222.611442 -211.398358)
		(end 222.23222 -211.77758)
		(width 0.15494)
		(layer "In15.Cu")
		(net "UART_PEX3_CLI_R_TX")
	)
	(segment
		(start 128.993646 -215.744806)
		(end 125.9078 -215.744806)
		(width 0.15494)
		(layer "In15.Cu")
		(net "UART_PEX3_CLI_R_TX")
	)
	(segment
		(start 185.613294 -220.919294)
		(end 181.6608 -216.9668)
		(width 0.15494)
		(layer "In15.Cu")
		(net "UART_PEX3_CLI_R_TX")
	)
	(segment
		(start 363.775244 -244.906292)
		(end 367.994438 -244.906292)
		(width 0.15494)
		(layer "In15.Cu")
		(net "UART_PEX3_CLI_R_TX")
	)
	(segment
		(start 245.243858 -204.23251)
		(end 246.652034 -205.640686)
		(width 0.15494)
		(layer "In15.Cu")
		(net "UART_PEX3_CLI_R_TX")
	)
	(segment
		(start 130.7465 -217.49766)
		(end 128.993646 -215.744806)
		(width 0.15494)
		(layer "In15.Cu")
		(net "UART_PEX3_CLI_R_TX")
	)
	(segment
		(start 241.21491 -210.16849)
		(end 240.476278 -210.16849)
		(width 0.15494)
		(layer "In15.Cu")
		(net "UART_PEX3_CLI_R_TX")
	)
	(segment
		(start 263.378188 -205.618842)
		(end 260.179058 -205.618842)
		(width 0.15494)
		(layer "In15.Cu")
		(net "UART_PEX3_CLI_R_TX")
	)
	(segment
		(start 217.294968 -211.77758)
		(end 215.62314 -210.105752)
		(width 0.15494)
		(layer "In15.Cu")
		(net "UART_PEX3_CLI_R_TX")
	)
	(segment
		(start 315.529976 -258.67106)
		(end 330.110592 -258.67106)
		(width 0.15494)
		(layer "In15.Cu")
		(net "UART_PEX3_CLI_R_TX")
	)
	(segment
		(start 249.0724 -204.2922)
		(end 247.974866 -204.2922)
		(width 0.15494)
		(layer "In15.Cu")
		(net "UART_PEX3_CLI_R_TX")
	)
	(segment
		(start 139.849606 -217.49766)
		(end 130.7465 -217.49766)
		(width 0.15494)
		(layer "In15.Cu")
		(net "UART_PEX3_CLI_R_TX")
	)
	(segment
		(start 326.884284 -27.04592)
		(end 326.112378 -27.04592)
		(width 0.13462)
		(layer "F.Cu")
		(net "CLK_100M_DB800ZL_SSD11_R_DP")
	)
	(segment
		(start 345.013026 -83.255358)
		(end 345.328748 -83.57108)
		(width 0.13462)
		(layer "F.Cu")
		(net "CLK_100M_DB800ZL_SSD11_R_DP")
	)
	(segment
		(start 346.047568 -83.57108)
		(end 346.33789 -83.280758)
		(width 0.13462)
		(layer "F.Cu")
		(net "CLK_100M_DB800ZL_SSD11_R_DP")
	)
	(segment
		(start 325.96836 -27.189938)
		(end 325.464678 -27.189938)
		(width 0.13462)
		(layer "F.Cu")
		(net "CLK_100M_DB800ZL_SSD11_R_DP")
	)
	(segment
		(start 326.112378 -27.04592)
		(end 325.96836 -27.189938)
		(width 0.13462)
		(layer "F.Cu")
		(net "CLK_100M_DB800ZL_SSD11_R_DP")
	)
	(segment
		(start 327.18121 -27.342846)
		(end 326.884284 -27.04592)
		(width 0.13462)
		(layer "F.Cu")
		(net "CLK_100M_DB800ZL_SSD11_R_DP")
	)
	(segment
		(start 345.328748 -83.57108)
		(end 346.047568 -83.57108)
		(width 0.13462)
		(layer "F.Cu")
		(net "CLK_100M_DB800ZL_SSD11_R_DP")
	)
	(via
		(at 346.33789 -83.280758)
		(size 0.508)
		(drill 0.254)
		(layers "F.Cu" "B.Cu")
		(net "CLK_100M_DB800ZL_SSD11_R_DP")
	)
	(via
		(at 327.18121 -27.342846)
		(size 0.508)
		(drill 0.254)
		(layers "F.Cu" "B.Cu")
		(net "CLK_100M_DB800ZL_SSD11_R_DP")
	)
	(segment
		(start 332.818232 -28.42641)
		(end 332.818232 -28.264612)
		(width 0.1651)
		(layer "In13.Cu")
		(net "CLK_100M_DB800ZL_SSD11_R_DP")
	)
	(segment
		(start 335.91754 -31.36392)
		(end 335.755742 -31.36392)
		(width 0.1651)
		(layer "In13.Cu")
		(net "CLK_100M_DB800ZL_SSD11_R_DP")
	)
	(segment
		(start 336.267552 -31.713932)
		(end 335.91754 -31.36392)
		(width 0.1651)
		(layer "In13.Cu")
		(net "CLK_100M_DB800ZL_SSD11_R_DP")
	)
	(segment
		(start 334.893412 -30.50159)
		(end 334.542892 -30.15107)
		(width 0.1651)
		(layer "In13.Cu")
		(net "CLK_100M_DB800ZL_SSD11_R_DP")
	)
	(segment
		(start 333.168752 -28.77693)
		(end 332.818232 -28.42641)
		(width 0.1651)
		(layer "In13.Cu")
		(net "CLK_100M_DB800ZL_SSD11_R_DP")
	)
	(segment
		(start 332.818232 -28.264612)
		(end 332.46822 -27.9146)
		(width 0.1651)
		(layer "In13.Cu")
		(net "CLK_100M_DB800ZL_SSD11_R_DP")
	)
	(segment
		(start 338.854542 -34.300922)
		(end 338.50453 -33.95091)
		(width 0.1651)
		(layer "In13.Cu")
		(net "CLK_100M_DB800ZL_SSD11_R_DP")
	)
	(segment
		(start 344.1192 -43.1546)
		(end 341.122 -40.1574)
		(width 0.1651)
		(layer "In13.Cu")
		(net "CLK_100M_DB800ZL_SSD11_R_DP")
	)
	(segment
		(start 346.8624 -83.571588)
		(end 347.0656 -83.368388)
		(width 0.1651)
		(layer "In13.Cu")
		(net "CLK_100M_DB800ZL_SSD11_R_DP")
	)
	(segment
		(start 329.34402 -27.3558)
		(end 329.040236 -27.052016)
		(width 0.1651)
		(layer "In13.Cu")
		(net "CLK_100M_DB800ZL_SSD11_R_DP")
	)
	(segment
		(start 332.46822 -27.9146)
		(end 331.97292 -27.9146)
		(width 0.1651)
		(layer "In13.Cu")
		(net "CLK_100M_DB800ZL_SSD11_R_DP")
	)
	(segment
		(start 331.36332 -28.0289)
		(end 331.24902 -27.9146)
		(width 0.1651)
		(layer "In13.Cu")
		(net "CLK_100M_DB800ZL_SSD11_R_DP")
	)
	(segment
		(start 337.129882 -32.73806)
		(end 337.129882 -32.576262)
		(width 0.1651)
		(layer "In13.Cu")
		(net "CLK_100M_DB800ZL_SSD11_R_DP")
	)
	(segment
		(start 333.680562 -29.28874)
		(end 333.680562 -29.126942)
		(width 0.1651)
		(layer "In13.Cu")
		(net "CLK_100M_DB800ZL_SSD11_R_DP")
	)
	(segment
		(start 334.19288 -29.63926)
		(end 334.031082 -29.63926)
		(width 0.1651)
		(layer "In13.Cu")
		(net "CLK_100M_DB800ZL_SSD11_R_DP")
	)
	(segment
		(start 336.77987 -32.22625)
		(end 336.618072 -32.22625)
		(width 0.1651)
		(layer "In13.Cu")
		(net "CLK_100M_DB800ZL_SSD11_R_DP")
	)
	(segment
		(start 331.85862 -28.0289)
		(end 331.36332 -28.0289)
		(width 0.1651)
		(layer "In13.Cu")
		(net "CLK_100M_DB800ZL_SSD11_R_DP")
	)
	(segment
		(start 346.33789 -83.280758)
		(end 346.62872 -83.571588)
		(width 0.1651)
		(layer "In13.Cu")
		(net "CLK_100M_DB800ZL_SSD11_R_DP")
	)
	(segment
		(start 338.342732 -33.95091)
		(end 337.992212 -33.60039)
		(width 0.1651)
		(layer "In13.Cu")
		(net "CLK_100M_DB800ZL_SSD11_R_DP")
	)
	(segment
		(start 338.50453 -33.95091)
		(end 338.342732 -33.95091)
		(width 0.1651)
		(layer "In13.Cu")
		(net "CLK_100M_DB800ZL_SSD11_R_DP")
	)
	(segment
		(start 339.36686 -34.81324)
		(end 339.205062 -34.81324)
		(width 0.1651)
		(layer "In13.Cu")
		(net "CLK_100M_DB800ZL_SSD11_R_DP")
	)
	(segment
		(start 339.881972 -35.328352)
		(end 339.36686 -34.81324)
		(width 0.1651)
		(layer "In13.Cu")
		(net "CLK_100M_DB800ZL_SSD11_R_DP")
	)
	(segment
		(start 336.618072 -32.22625)
		(end 336.267552 -31.87573)
		(width 0.1651)
		(layer "In13.Cu")
		(net "CLK_100M_DB800ZL_SSD11_R_DP")
	)
	(segment
		(start 337.992212 -33.60039)
		(end 337.992212 -33.438592)
		(width 0.1651)
		(layer "In13.Cu")
		(net "CLK_100M_DB800ZL_SSD11_R_DP")
	)
	(segment
		(start 333.33055 -28.77693)
		(end 333.168752 -28.77693)
		(width 0.1651)
		(layer "In13.Cu")
		(net "CLK_100M_DB800ZL_SSD11_R_DP")
	)
	(segment
		(start 341.122 -37.184076)
		(end 340.55939 -36.342066)
		(width 0.1651)
		(layer "In13.Cu")
		(net "CLK_100M_DB800ZL_SSD11_R_DP")
	)
	(segment
		(start 340.125558 -35.898582)
		(end 340.157054 -35.740086)
		(width 0.1651)
		(layer "In13.Cu")
		(net "CLK_100M_DB800ZL_SSD11_R_DP")
	)
	(segment
		(start 341.122 -40.1574)
		(end 341.122 -37.184076)
		(width 0.1651)
		(layer "In13.Cu")
		(net "CLK_100M_DB800ZL_SSD11_R_DP")
	)
	(segment
		(start 337.129882 -32.576262)
		(end 336.77987 -32.22625)
		(width 0.1651)
		(layer "In13.Cu")
		(net "CLK_100M_DB800ZL_SSD11_R_DP")
	)
	(segment
		(start 346.62872 -83.571588)
		(end 346.8624 -83.571588)
		(width 0.1651)
		(layer "In13.Cu")
		(net "CLK_100M_DB800ZL_SSD11_R_DP")
	)
	(segment
		(start 337.480402 -33.08858)
		(end 337.129882 -32.73806)
		(width 0.1651)
		(layer "In13.Cu")
		(net "CLK_100M_DB800ZL_SSD11_R_DP")
	)
	(segment
		(start 329.040236 -27.052016)
		(end 327.47204 -27.052016)
		(width 0.1651)
		(layer "In13.Cu")
		(net "CLK_100M_DB800ZL_SSD11_R_DP")
	)
	(segment
		(start 333.680562 -29.126942)
		(end 333.33055 -28.77693)
		(width 0.1651)
		(layer "In13.Cu")
		(net "CLK_100M_DB800ZL_SSD11_R_DP")
	)
	(segment
		(start 335.405222 -31.0134)
		(end 335.405222 -30.851602)
		(width 0.1651)
		(layer "In13.Cu")
		(net "CLK_100M_DB800ZL_SSD11_R_DP")
	)
	(segment
		(start 330.7334 -27.9146)
		(end 330.1746 -27.3558)
		(width 0.1651)
		(layer "In13.Cu")
		(net "CLK_100M_DB800ZL_SSD11_R_DP")
	)
	(segment
		(start 340.55939 -36.342066)
		(end 340.400894 -36.31057)
		(width 0.1651)
		(layer "In13.Cu")
		(net "CLK_100M_DB800ZL_SSD11_R_DP")
	)
	(segment
		(start 330.1746 -27.3558)
		(end 329.34402 -27.3558)
		(width 0.1651)
		(layer "In13.Cu")
		(net "CLK_100M_DB800ZL_SSD11_R_DP")
	)
	(segment
		(start 335.755742 -31.36392)
		(end 335.405222 -31.0134)
		(width 0.1651)
		(layer "In13.Cu")
		(net "CLK_100M_DB800ZL_SSD11_R_DP")
	)
	(segment
		(start 335.05521 -30.50159)
		(end 334.893412 -30.50159)
		(width 0.1651)
		(layer "In13.Cu")
		(net "CLK_100M_DB800ZL_SSD11_R_DP")
	)
	(segment
		(start 334.542892 -30.15107)
		(end 334.542892 -29.989272)
		(width 0.1651)
		(layer "In13.Cu")
		(net "CLK_100M_DB800ZL_SSD11_R_DP")
	)
	(segment
		(start 337.6422 -33.08858)
		(end 337.480402 -33.08858)
		(width 0.1651)
		(layer "In13.Cu")
		(net "CLK_100M_DB800ZL_SSD11_R_DP")
	)
	(segment
		(start 327.47204 -27.052016)
		(end 327.18121 -27.342846)
		(width 0.1651)
		(layer "In13.Cu")
		(net "CLK_100M_DB800ZL_SSD11_R_DP")
	)
	(segment
		(start 336.267552 -31.87573)
		(end 336.267552 -31.713932)
		(width 0.1651)
		(layer "In13.Cu")
		(net "CLK_100M_DB800ZL_SSD11_R_DP")
	)
	(segment
		(start 334.542892 -29.989272)
		(end 334.19288 -29.63926)
		(width 0.1651)
		(layer "In13.Cu")
		(net "CLK_100M_DB800ZL_SSD11_R_DP")
	)
	(segment
		(start 335.405222 -30.851602)
		(end 335.05521 -30.50159)
		(width 0.1651)
		(layer "In13.Cu")
		(net "CLK_100M_DB800ZL_SSD11_R_DP")
	)
	(segment
		(start 347.0656 -83.0072)
		(end 344.1192 -80.0608)
		(width 0.1651)
		(layer "In13.Cu")
		(net "CLK_100M_DB800ZL_SSD11_R_DP")
	)
	(segment
		(start 340.157054 -35.740086)
		(end 339.881972 -35.328352)
		(width 0.1651)
		(layer "In13.Cu")
		(net "CLK_100M_DB800ZL_SSD11_R_DP")
	)
	(segment
		(start 338.854542 -34.46272)
		(end 338.854542 -34.300922)
		(width 0.1651)
		(layer "In13.Cu")
		(net "CLK_100M_DB800ZL_SSD11_R_DP")
	)
	(segment
		(start 340.400894 -36.31057)
		(end 340.125558 -35.898582)
		(width 0.1651)
		(layer "In13.Cu")
		(net "CLK_100M_DB800ZL_SSD11_R_DP")
	)
	(segment
		(start 337.992212 -33.438592)
		(end 337.6422 -33.08858)
		(width 0.1651)
		(layer "In13.Cu")
		(net "CLK_100M_DB800ZL_SSD11_R_DP")
	)
	(segment
		(start 347.0656 -83.368388)
		(end 347.0656 -83.0072)
		(width 0.1651)
		(layer "In13.Cu")
		(net "CLK_100M_DB800ZL_SSD11_R_DP")
	)
	(segment
		(start 331.24902 -27.9146)
		(end 330.7334 -27.9146)
		(width 0.1651)
		(layer "In13.Cu")
		(net "CLK_100M_DB800ZL_SSD11_R_DP")
	)
	(segment
		(start 339.205062 -34.81324)
		(end 338.854542 -34.46272)
		(width 0.1651)
		(layer "In13.Cu")
		(net "CLK_100M_DB800ZL_SSD11_R_DP")
	)
	(segment
		(start 344.1192 -80.0608)
		(end 344.1192 -43.1546)
		(width 0.1651)
		(layer "In13.Cu")
		(net "CLK_100M_DB800ZL_SSD11_R_DP")
	)
	(segment
		(start 331.97292 -27.9146)
		(end 331.85862 -28.0289)
		(width 0.1651)
		(layer "In13.Cu")
		(net "CLK_100M_DB800ZL_SSD11_R_DP")
	)
	(segment
		(start 334.031082 -29.63926)
		(end 333.680562 -29.28874)
		(width 0.1651)
		(layer "In13.Cu")
		(net "CLK_100M_DB800ZL_SSD11_R_DP")
	)
	(segment
		(start 364.697772 -89.499694)
		(end 366.555528 -89.499694)
		(width 0.13208)
		(layer "F.Cu")
		(net "SMB_BIC_I2C9_MUX1_SSD15_SCL")
	)
	(segment
		(start 363.885734 -88.35136)
		(end 364.123478 -88.9254)
		(width 0.13208)
		(layer "F.Cu")
		(net "SMB_BIC_I2C9_MUX1_SSD15_SCL")
	)
	(segment
		(start 363.385608 -87.465154)
		(end 363.885734 -87.96528)
		(width 0.13208)
		(layer "F.Cu")
		(net "SMB_BIC_I2C9_MUX1_SSD15_SCL")
	)
	(segment
		(start 363.885734 -87.96528)
		(end 363.885734 -88.35136)
		(width 0.13208)
		(layer "F.Cu")
		(net "SMB_BIC_I2C9_MUX1_SSD15_SCL")
	)
	(segment
		(start 364.123478 -88.9254)
		(end 364.697772 -89.499694)
		(width 0.13208)
		(layer "F.Cu")
		(net "SMB_BIC_I2C9_MUX1_SSD15_SCL")
	)
	(segment
		(start 362.30814 -87.465154)
		(end 363.385608 -87.465154)
		(width 0.13208)
		(layer "F.Cu")
		(net "SMB_BIC_I2C9_MUX1_SSD15_SCL")
	)
	(via
		(at 364.697772 -89.499694)
		(size 0.508)
		(drill 0.254)
		(layers "F.Cu" "B.Cu")
		(net "SMB_BIC_I2C9_MUX1_SSD15_SCL")
	)
	(segment
		(start 339.979 -232.4862)
		(end 339.979 -232.029)
		(width 0.13208)
		(layer "F.Cu")
		(net "SSD1_PWRDIS")
	)
	(segment
		(start 339.979 -232.029)
		(end 341.8586 -230.1494)
		(width 0.13208)
		(layer "F.Cu")
		(net "SSD1_PWRDIS")
	)
	(segment
		(start 341.8586 -230.1494)
		(end 341.8586 -228.38537)
		(width 0.13208)
		(layer "F.Cu")
		(net "SSD1_PWRDIS")
	)
	(segment
		(start 342.093804 -228.150166)
		(end 342.093804 -227.987098)
		(width 0.13208)
		(layer "F.Cu")
		(net "SSD1_PWRDIS")
	)
	(segment
		(start 339.979 -233.66095)
		(end 339.979 -232.4862)
		(width 0.13208)
		(layer "F.Cu")
		(net "SSD1_PWRDIS")
	)
	(segment
		(start 341.8586 -228.38537)
		(end 342.093804 -228.150166)
		(width 0.13208)
		(layer "F.Cu")
		(net "SSD1_PWRDIS")
	)
	(via
		(at 339.979 -232.4862)
		(size 0.762)
		(drill 0.381)
		(layers "F.Cu" "B.Cu")
		(net "SSD1_PWRDIS")
	)
	(segment
		(start 350.093788 -212.786976)
		(end 350.497394 -212.38337)
		(width 0.13208)
		(layer "F.Cu")
		(net "PRSNT_NIC5_FPGA_N")
	)
	(segment
		(start 356.761796 -210.693)
		(end 357.23195 -210.693)
		(width 0.13208)
		(layer "F.Cu")
		(net "PRSNT_NIC5_FPGA_N")
	)
	(segment
		(start 351.49663 -212.38337)
		(end 351.7646 -212.1154)
		(width 0.13208)
		(layer "F.Cu")
		(net "PRSNT_NIC5_FPGA_N")
	)
	(segment
		(start 356.002082 -211.452714)
		(end 356.761796 -210.693)
		(width 0.13208)
		(layer "F.Cu")
		(net "PRSNT_NIC5_FPGA_N")
	)
	(segment
		(start 350.497394 -212.38337)
		(end 351.49663 -212.38337)
		(width 0.13208)
		(layer "F.Cu")
		(net "PRSNT_NIC5_FPGA_N")
	)
	(segment
		(start 355.339396 -212.1154)
		(end 356.002082 -211.452714)
		(width 0.13208)
		(layer "F.Cu")
		(net "PRSNT_NIC5_FPGA_N")
	)
	(segment
		(start 357.23195 -210.693)
		(end 357.61295 -210.312)
		(width 0.13208)
		(layer "F.Cu")
		(net "PRSNT_NIC5_FPGA_N")
	)
	(segment
		(start 351.7646 -212.1154)
		(end 355.339396 -212.1154)
		(width 0.13208)
		(layer "F.Cu")
		(net "PRSNT_NIC5_FPGA_N")
	)
	(via
		(at 356.002082 -211.452714)
		(size 0.762)
		(drill 0.381)
		(layers "F.Cu" "B.Cu")
		(net "PRSNT_NIC5_FPGA_N")
	)
	(segment
		(start 424.81627 -53.644038)
		(end 425.4373 -53.023008)
		(width 0.13208)
		(layer "F.Cu")
		(net "PWRGD_P12V_SSD14")
	)
	(segment
		(start 424.447208 -53.644038)
		(end 424.81627 -53.644038)
		(width 0.13208)
		(layer "F.Cu")
		(net "PWRGD_P12V_SSD14")
	)
	(segment
		(start 425.901358 -53.051456)
		(end 426.167804 -53.051456)
		(width 0.13208)
		(layer "F.Cu")
		(net "PWRGD_P12V_SSD14")
	)
	(segment
		(start 426.167804 -52.035456)
		(end 426.167804 -53.051456)
		(width 0.13208)
		(layer "F.Cu")
		(net "PWRGD_P12V_SSD14")
	)
	(segment
		(start 425.4373 -52.587398)
		(end 425.901358 -53.051456)
		(width 0.13208)
		(layer "F.Cu")
		(net "PWRGD_P12V_SSD14")
	)
	(segment
		(start 425.4373 -53.023008)
		(end 425.4373 -52.587398)
		(width 0.13208)
		(layer "F.Cu")
		(net "PWRGD_P12V_SSD14")
	)
	(via
		(at 425.4373 -52.587398)
		(size 0.508)
		(drill 0.254)
		(layers "F.Cu" "B.Cu")
		(net "PWRGD_P12V_SSD14")
	)
	(segment
		(start 387.35381 -230.2764)
		(end 387.35381 -231.025954)
		(width 0.13208)
		(layer "F.Cu")
		(net "RST_FT4232_SDB_R_N")
	)
	(segment
		(start 387.355588 -231.027732)
		(end 387.355588 -232.836212)
		(width 0.13208)
		(layer "F.Cu")
		(net "RST_FT4232_SDB_R_N")
	)
	(segment
		(start 387.35381 -231.025954)
		(end 387.355588 -231.027732)
		(width 0.13208)
		(layer "F.Cu")
		(net "RST_FT4232_SDB_R_N")
	)
	(via
		(at 387.355588 -231.027732)
		(size 0.508)
		(drill 0.254)
		(layers "F.Cu" "B.Cu")
		(net "RST_FT4232_SDB_R_N")
	)
	(segment
		(start 420.299896 -292.099746)
		(end 420.774876 -291.624766)
		(width 0.13208)
		(layer "F.Cu")
		(net "UART_PEX3_CLI_TX")
	)
	(via
		(at 420.774876 -291.624766)
		(size 0.4064)
		(drill 0.2032)
		(layers "F.Cu" "B.Cu")
		(net "UART_PEX3_CLI_TX")
	)
	(via
		(at 421.249856 -292.099746)
		(size 0.6604)
		(drill 0.3302)
		(layers "F.Cu" "B.Cu")
		(net "UART_PEX3_CLI_TX")
	)
	(segment
		(start 423.140886 -292.024816)
		(end 424.02379 -292.024816)
		(width 0.13208)
		(layer "B.Cu")
		(net "UART_PEX3_CLI_TX")
	)
	(segment
		(start 421.249856 -292.099746)
		(end 423.065956 -292.099746)
		(width 0.13208)
		(layer "B.Cu")
		(net "UART_PEX3_CLI_TX")
	)
	(segment
		(start 420.774876 -291.624766)
		(end 421.249856 -292.099746)
		(width 0.13208)
		(layer "B.Cu")
		(net "UART_PEX3_CLI_TX")
	)
	(segment
		(start 423.065956 -292.099746)
		(end 423.140886 -292.024816)
		(width 0.13208)
		(layer "B.Cu")
		(net "UART_PEX3_CLI_TX")
	)
	(segment
		(start 274.88896 -26.7716)
		(end 274.136358 -26.7716)
		(width 0.13462)
		(layer "F.Cu")
		(net "CLK_100M_DB800ZL_SSD9_R_DN")
	)
	(segment
		(start 275.181314 -26.479246)
		(end 274.88896 -26.7716)
		(width 0.13462)
		(layer "F.Cu")
		(net "CLK_100M_DB800ZL_SSD9_R_DN")
	)
	(segment
		(start 273.954748 -26.58999)
		(end 273.464782 -26.58999)
		(width 0.13462)
		(layer "F.Cu")
		(net "CLK_100M_DB800ZL_SSD9_R_DN")
	)
	(segment
		(start 274.136358 -26.7716)
		(end 273.954748 -26.58999)
		(width 0.13462)
		(layer "F.Cu")
		(net "CLK_100M_DB800ZL_SSD9_R_DN")
	)
	(segment
		(start 337.752944 -80.207612)
		(end 337.43392 -79.888588)
		(width 0.13462)
		(layer "F.Cu")
		(net "CLK_100M_DB800ZL_SSD9_R_DN")
	)
	(segment
		(start 337.43392 -79.888588)
		(end 337.43392 -78.414372)
		(width 0.13462)
		(layer "F.Cu")
		(net "CLK_100M_DB800ZL_SSD9_R_DN")
	)
	(segment
		(start 337.43392 -78.414372)
		(end 337.727544 -78.120748)
		(width 0.13462)
		(layer "F.Cu")
		(net "CLK_100M_DB800ZL_SSD9_R_DN")
	)
	(via
		(at 275.181314 -26.479246)
		(size 0.508)
		(drill 0.254)
		(layers "F.Cu" "B.Cu")
		(net "CLK_100M_DB800ZL_SSD9_R_DN")
	)
	(via
		(at 337.727544 -78.120748)
		(size 0.508)
		(drill 0.254)
		(layers "F.Cu" "B.Cu")
		(net "CLK_100M_DB800ZL_SSD9_R_DN")
	)
	(segment
		(start 278.52624 -27.07386)
		(end 277.07844 -27.07386)
		(width 0.1651)
		(layer "In13.Cu")
		(net "CLK_100M_DB800ZL_SSD9_R_DN")
	)
	(segment
		(start 337.727544 -78.120748)
		(end 337.436714 -77.829918)
		(width 0.1651)
		(layer "In13.Cu")
		(net "CLK_100M_DB800ZL_SSD9_R_DN")
	)
	(segment
		(start 337.436714 -77.829918)
		(end 337.436714 -76.687934)
		(width 0.1651)
		(layer "In13.Cu")
		(net "CLK_100M_DB800ZL_SSD9_R_DN")
	)
	(segment
		(start 337.436714 -76.687934)
		(end 336.61604 -75.86726)
		(width 0.1651)
		(layer "In13.Cu")
		(net "CLK_100M_DB800ZL_SSD9_R_DN")
	)
	(segment
		(start 307.979572 -63.98006)
		(end 301.36846 -63.98006)
		(width 0.1651)
		(layer "In13.Cu")
		(net "CLK_100M_DB800ZL_SSD9_R_DN")
	)
	(segment
		(start 283.5402 -31.0388)
		(end 280.18486 -27.68346)
		(width 0.1651)
		(layer "In13.Cu")
		(net "CLK_100M_DB800ZL_SSD9_R_DN")
	)
	(segment
		(start 280.18486 -27.68346)
		(end 279.13584 -27.68346)
		(width 0.1651)
		(layer "In13.Cu")
		(net "CLK_100M_DB800ZL_SSD9_R_DN")
	)
	(segment
		(start 275.472144 -26.770076)
		(end 275.181314 -26.479246)
		(width 0.1651)
		(layer "In13.Cu")
		(net "CLK_100M_DB800ZL_SSD9_R_DN")
	)
	(segment
		(start 296.24274 -58.85434)
		(end 296.24274 -46.36516)
		(width 0.1651)
		(layer "In13.Cu")
		(net "CLK_100M_DB800ZL_SSD9_R_DN")
	)
	(segment
		(start 301.36846 -63.98006)
		(end 296.24274 -58.85434)
		(width 0.1651)
		(layer "In13.Cu")
		(net "CLK_100M_DB800ZL_SSD9_R_DN")
	)
	(segment
		(start 336.61604 -75.86726)
		(end 324.60946 -75.86726)
		(width 0.1651)
		(layer "In13.Cu")
		(net "CLK_100M_DB800ZL_SSD9_R_DN")
	)
	(segment
		(start 283.5402 -33.66262)
		(end 283.5402 -31.0388)
		(width 0.1651)
		(layer "In13.Cu")
		(net "CLK_100M_DB800ZL_SSD9_R_DN")
	)
	(segment
		(start 277.07844 -27.07386)
		(end 276.774656 -26.770076)
		(width 0.1651)
		(layer "In13.Cu")
		(net "CLK_100M_DB800ZL_SSD9_R_DN")
	)
	(segment
		(start 324.60946 -75.86726)
		(end 316.075822 -67.333622)
		(width 0.1651)
		(layer "In13.Cu")
		(net "CLK_100M_DB800ZL_SSD9_R_DN")
	)
	(segment
		(start 276.774656 -26.770076)
		(end 275.472144 -26.770076)
		(width 0.1651)
		(layer "In13.Cu")
		(net "CLK_100M_DB800ZL_SSD9_R_DN")
	)
	(segment
		(start 316.075822 -67.333622)
		(end 307.979572 -63.98006)
		(width 0.1651)
		(layer "In13.Cu")
		(net "CLK_100M_DB800ZL_SSD9_R_DN")
	)
	(segment
		(start 279.13584 -27.68346)
		(end 278.52624 -27.07386)
		(width 0.1651)
		(layer "In13.Cu")
		(net "CLK_100M_DB800ZL_SSD9_R_DN")
	)
	(segment
		(start 296.24274 -46.36516)
		(end 283.5402 -33.66262)
		(width 0.1651)
		(layer "In13.Cu")
		(net "CLK_100M_DB800ZL_SSD9_R_DN")
	)
	(segment
		(start 21.01342 -257.102102)
		(end 21.508466 -257.102102)
		(width 0.13208)
		(layer "F.Cu")
		(net "PEX0_SYS_ERR_R_N")
	)
	(segment
		(start 22.353778 -258.349496)
		(end 22.353778 -257.474212)
		(width 0.13208)
		(layer "F.Cu")
		(net "PEX0_SYS_ERR_R_N")
	)
	(segment
		(start 20.852892 -255.399032)
		(end 20.852892 -256.941574)
		(width 0.13208)
		(layer "F.Cu")
		(net "PEX0_SYS_ERR_R_N")
	)
	(segment
		(start 22.171914 -258.53136)
		(end 22.353778 -258.349496)
		(width 0.13208)
		(layer "F.Cu")
		(net "PEX0_SYS_ERR_R_N")
	)
	(segment
		(start 21.981668 -257.102102)
		(end 21.508466 -257.102102)
		(width 0.13208)
		(layer "F.Cu")
		(net "PEX0_SYS_ERR_R_N")
	)
	(segment
		(start 22.353778 -257.474212)
		(end 21.981668 -257.102102)
		(width 0.13208)
		(layer "F.Cu")
		(net "PEX0_SYS_ERR_R_N")
	)
	(segment
		(start 20.852892 -256.941574)
		(end 21.01342 -257.102102)
		(width 0.13208)
		(layer "F.Cu")
		(net "PEX0_SYS_ERR_R_N")
	)
	(segment
		(start 21.09851 -255.153414)
		(end 20.852892 -255.399032)
		(width 0.13208)
		(layer "F.Cu")
		(net "PEX0_SYS_ERR_R_N")
	)
	(segment
		(start 21.513546 -255.153414)
		(end 21.09851 -255.153414)
		(width 0.13208)
		(layer "F.Cu")
		(net "PEX0_SYS_ERR_R_N")
	)
	(segment
		(start 22.171914 -259.346192)
		(end 22.171914 -258.53136)
		(width 0.13208)
		(layer "F.Cu")
		(net "PEX0_SYS_ERR_R_N")
	)
	(via
		(at 22.353778 -257.474212)
		(size 0.508)
		(drill 0.254)
		(layers "F.Cu" "B.Cu")
		(net "PEX0_SYS_ERR_R_N")
	)
	(segment
		(start 287.099756 -308.249828)
		(end 286.624776 -307.774848)
		(width 0.13208)
		(layer "F.Cu")
		(net "TP_PEX2_TMS")
	)
	(via
		(at 286.624776 -307.774848)
		(size 0.4064)
		(drill 0.2032)
		(layers "F.Cu" "B.Cu")
		(net "TP_PEX2_TMS")
	)
	(via
		(at 286.149796 -307.299868)
		(size 0.6604)
		(drill 0.3302)
		(layers "F.Cu" "B.Cu")
		(net "TP_PEX2_TMS")
	)
	(segment
		(start 286.624776 -307.774848)
		(end 286.149796 -307.299868)
		(width 0.13208)
		(layer "B.Cu")
		(net "TP_PEX2_TMS")
	)
	(segment
		(start 362.30814 -83.564984)
		(end 363.354874 -83.564984)
		(width 0.13208)
		(layer "F.Cu")
		(net "SMB_BIC_I2C9_MUX1_SSD12_SCL")
	)
	(segment
		(start 363.354874 -83.564984)
		(end 364.278164 -82.641694)
		(width 0.13208)
		(layer "F.Cu")
		(net "SMB_BIC_I2C9_MUX1_SSD12_SCL")
	)
	(segment
		(start 364.278164 -82.641694)
		(end 366.555528 -82.641694)
		(width 0.13208)
		(layer "F.Cu")
		(net "SMB_BIC_I2C9_MUX1_SSD12_SCL")
	)
	(via
		(at 364.278164 -82.641694)
		(size 0.508)
		(drill 0.254)
		(layers "F.Cu" "B.Cu")
		(net "SMB_BIC_I2C9_MUX1_SSD12_SCL")
	)
	(segment
		(start 26.663142 -35.687)
		(end 27.208734 -36.232592)
		(width 0.13208)
		(layer "F.Cu")
		(net "PWRGD_P3V3_SSD1_R")
	)
	(segment
		(start 23.170896 -35.876738)
		(end 22.427946 -35.876738)
		(width 0.13208)
		(layer "F.Cu")
		(net "PWRGD_P3V3_SSD1_R")
	)
	(segment
		(start 23.170896 -35.876738)
		(end 23.882096 -35.876738)
		(width 0.13208)
		(layer "F.Cu")
		(net "PWRGD_P3V3_SSD1_R")
	)
	(segment
		(start 35.216084 -61.386974)
		(end 35.220656 -61.391546)
		(width 0.13208)
		(layer "F.Cu")
		(net "PWRGD_P3V3_SSD1_R")
	)
	(segment
		(start 342.093804 -223.987106)
		(end 341.694008 -224.386902)
		(width 0.13208)
		(layer "F.Cu")
		(net "PWRGD_P3V3_SSD1_R")
	)
	(segment
		(start 34.611056 -61.386974)
		(end 35.216084 -61.386974)
		(width 0.13208)
		(layer "F.Cu")
		(net "PWRGD_P3V3_SSD1_R")
	)
	(segment
		(start 24.071834 -35.687)
		(end 26.663142 -35.687)
		(width 0.13208)
		(layer "F.Cu")
		(net "PWRGD_P3V3_SSD1_R")
	)
	(segment
		(start 23.882096 -35.876738)
		(end 24.071834 -35.687)
		(width 0.13208)
		(layer "F.Cu")
		(net "PWRGD_P3V3_SSD1_R")
	)
	(segment
		(start 27.208734 -36.232592)
		(end 27.595322 -36.232592)
		(width 0.13208)
		(layer "F.Cu")
		(net "PWRGD_P3V3_SSD1_R")
	)
	(via
		(at 23.170896 -35.876738)
		(size 0.508)
		(drill 0.254)
		(layers "F.Cu" "B.Cu")
		(net "PWRGD_P3V3_SSD1_R")
	)
	(via
		(at 341.694008 -224.386902)
		(size 0.4572)
		(drill 0.254)
		(layers "F.Cu" "B.Cu")
		(net "PWRGD_P3V3_SSD1_R")
	)
	(via
		(at 35.220656 -61.391546)
		(size 0.508)
		(drill 0.254)
		(layers "F.Cu" "B.Cu")
		(net "PWRGD_P3V3_SSD1_R")
	)
	(via
		(at 31.927292 -217.80881)
		(size 0.508)
		(drill 0.254)
		(layers "F.Cu" "B.Cu")
		(net "PWRGD_P3V3_SSD1_R")
	)
	(segment
		(start 24.573484 -35.876738)
		(end 35.7632 -47.066454)
		(width 0.15494)
		(layer "In5.Cu")
		(net "PWRGD_P3V3_SSD1_R")
	)
	(segment
		(start 26.199084 -166.860982)
		(end 26.199084 -192.594484)
		(width 0.15494)
		(layer "In5.Cu")
		(net "PWRGD_P3V3_SSD1_R")
	)
	(segment
		(start 31.40202 -204.631036)
		(end 31.40202 -217.283538)
		(width 0.15494)
		(layer "In5.Cu")
		(net "PWRGD_P3V3_SSD1_R")
	)
	(segment
		(start 30.574488 -203.803504)
		(end 31.40202 -204.631036)
		(width 0.15494)
		(layer "In5.Cu")
		(net "PWRGD_P3V3_SSD1_R")
	)
	(segment
		(start 28.702 -93.93555)
		(end 28.702 -97.45726)
		(width 0.15494)
		(layer "In5.Cu")
		(net "PWRGD_P3V3_SSD1_R")
	)
	(segment
		(start 35.220656 -61.391546)
		(end 35.220656 -87.416894)
		(width 0.15494)
		(layer "In5.Cu")
		(net "PWRGD_P3V3_SSD1_R")
	)
	(segment
		(start 31.40202 -217.283538)
		(end 31.927292 -217.80881)
		(width 0.15494)
		(layer "In5.Cu")
		(net "PWRGD_P3V3_SSD1_R")
	)
	(segment
		(start 35.7632 -47.066454)
		(end 35.7632 -60.849002)
		(width 0.15494)
		(layer "In5.Cu")
		(net "PWRGD_P3V3_SSD1_R")
	)
	(segment
		(start 25.763728 -100.395532)
		(end 25.763728 -165.80993)
		(width 0.15494)
		(layer "In5.Cu")
		(net "PWRGD_P3V3_SSD1_R")
	)
	(segment
		(start 30.574488 -196.969888)
		(end 30.574488 -203.803504)
		(width 0.15494)
		(layer "In5.Cu")
		(net "PWRGD_P3V3_SSD1_R")
	)
	(segment
		(start 26.199084 -192.594484)
		(end 30.574488 -196.969888)
		(width 0.15494)
		(layer "In5.Cu")
		(net "PWRGD_P3V3_SSD1_R")
	)
	(segment
		(start 35.220656 -87.416894)
		(end 28.702 -93.93555)
		(width 0.15494)
		(layer "In5.Cu")
		(net "PWRGD_P3V3_SSD1_R")
	)
	(segment
		(start 23.170896 -35.876738)
		(end 24.573484 -35.876738)
		(width 0.15494)
		(layer "In5.Cu")
		(net "PWRGD_P3V3_SSD1_R")
	)
	(segment
		(start 35.7632 -60.849002)
		(end 35.220656 -61.391546)
		(width 0.15494)
		(layer "In5.Cu")
		(net "PWRGD_P3V3_SSD1_R")
	)
	(segment
		(start 28.702 -97.45726)
		(end 25.763728 -100.395532)
		(width 0.15494)
		(layer "In5.Cu")
		(net "PWRGD_P3V3_SSD1_R")
	)
	(segment
		(start 25.763728 -165.80993)
		(end 26.199084 -166.860982)
		(width 0.15494)
		(layer "In5.Cu")
		(net "PWRGD_P3V3_SSD1_R")
	)
	(segment
		(start 63.321184 -205.774798)
		(end 63.331344 -205.784958)
		(width 0.15494)
		(layer "In13.Cu")
		(net "PWRGD_P3V3_SSD1_R")
	)
	(segment
		(start 240.65357 -218.6686)
		(end 241.1222 -218.6686)
		(width 0.15494)
		(layer "In13.Cu")
		(net "PWRGD_P3V3_SSD1_R")
	)
	(segment
		(start 231.37622 -211.04225)
		(end 233.953304 -211.04225)
		(width 0.15494)
		(layer "In13.Cu")
		(net "PWRGD_P3V3_SSD1_R")
	)
	(segment
		(start 225.221546 -210.9978)
		(end 229.666546 -210.9978)
		(width 0.15494)
		(layer "In13.Cu")
		(net "PWRGD_P3V3_SSD1_R")
	)
	(segment
		(start 219.312998 -217.3478)
		(end 220.37294 -216.287858)
		(width 0.15494)
		(layer "In13.Cu")
		(net "PWRGD_P3V3_SSD1_R")
	)
	(segment
		(start 191.20612 -214.188548)
		(end 191.221868 -214.1728)
		(width 0.15494)
		(layer "In13.Cu")
		(net "PWRGD_P3V3_SSD1_R")
	)
	(segment
		(start 342.218518 -224.911412)
		(end 341.694008 -224.386902)
		(width 0.15494)
		(layer "In13.Cu")
		(net "PWRGD_P3V3_SSD1_R")
	)
	(segment
		(start 63.331344 -205.784958)
		(end 74.38263 -205.784958)
		(width 0.15494)
		(layer "In13.Cu")
		(net "PWRGD_P3V3_SSD1_R")
	)
	(segment
		(start 141.891004 -216.807796)
		(end 141.921484 -216.777316)
		(width 0.15494)
		(layer "In13.Cu")
		(net "PWRGD_P3V3_SSD1_R")
	)
	(segment
		(start 323.412866 -234.64774)
		(end 325.386446 -234.64774)
		(width 0.15494)
		(layer "In13.Cu")
		(net "PWRGD_P3V3_SSD1_R")
	)
	(segment
		(start 62.909704 -205.784958)
		(end 62.919864 -205.774798)
		(width 0.15494)
		(layer "In13.Cu")
		(net "PWRGD_P3V3_SSD1_R")
	)
	(segment
		(start 236.511846 -214.526876)
		(end 240.65357 -218.6686)
		(width 0.15494)
		(layer "In13.Cu")
		(net "PWRGD_P3V3_SSD1_R")
	)
	(segment
		(start 212.04301 -216.789)
		(end 215.478868 -216.789)
		(width 0.15494)
		(layer "In13.Cu")
		(net "PWRGD_P3V3_SSD1_R")
	)
	(segment
		(start 259.14223 -226.619816)
		(end 259.142484 -226.619562)
		(width 0.15494)
		(layer "In13.Cu")
		(net "PWRGD_P3V3_SSD1_R")
	)
	(segment
		(start 94.956376 -208.3308)
		(end 95.012256 -208.38668)
		(width 0.15494)
		(layer "In13.Cu")
		(net "PWRGD_P3V3_SSD1_R")
	)
	(segment
		(start 250.287282 -226.4156)
		(end 257.861816 -226.4156)
		(width 0.15494)
		(layer "In13.Cu")
		(net "PWRGD_P3V3_SSD1_R")
	)
	(segment
		(start 342.218518 -226.868736)
		(end 342.218518 -224.911412)
		(width 0.15494)
		(layer "In13.Cu")
		(net "PWRGD_P3V3_SSD1_R")
	)
	(segment
		(start 332.849474 -234.139994)
		(end 335.307178 -231.68229)
		(width 0.15494)
		(layer "In13.Cu")
		(net "PWRGD_P3V3_SSD1_R")
	)
	(segment
		(start 99.337114 -208.05902)
		(end 116.414296 -208.05902)
		(width 0.15494)
		(layer "In13.Cu")
		(net "PWRGD_P3V3_SSD1_R")
	)
	(segment
		(start 325.386446 -234.64774)
		(end 325.894192 -234.139994)
		(width 0.15494)
		(layer "In13.Cu")
		(net "PWRGD_P3V3_SSD1_R")
	)
	(segment
		(start 302.576484 -234.2896)
		(end 323.054726 -234.2896)
		(width 0.15494)
		(layer "In13.Cu")
		(net "PWRGD_P3V3_SSD1_R")
	)
	(segment
		(start 211.17814 -215.92413)
		(end 212.04301 -216.789)
		(width 0.15494)
		(layer "In13.Cu")
		(net "PWRGD_P3V3_SSD1_R")
	)
	(segment
		(start 220.37294 -216.287858)
		(end 220.37294 -214.907114)
		(width 0.15494)
		(layer "In13.Cu")
		(net "PWRGD_P3V3_SSD1_R")
	)
	(segment
		(start 141.921484 -216.777316)
		(end 148.113242 -216.777316)
		(width 0.15494)
		(layer "In13.Cu")
		(net "PWRGD_P3V3_SSD1_R")
	)
	(segment
		(start 335.307178 -231.68229)
		(end 339.409278 -231.68229)
		(width 0.15494)
		(layer "In13.Cu")
		(net "PWRGD_P3V3_SSD1_R")
	)
	(segment
		(start 278.020272 -234.222798)
		(end 300.091602 -234.222798)
		(width 0.15494)
		(layer "In13.Cu")
		(net "PWRGD_P3V3_SSD1_R")
	)
	(segment
		(start 242.142264 -220.675454)
		(end 247.053608 -225.586798)
		(width 0.15494)
		(layer "In13.Cu")
		(net "PWRGD_P3V3_SSD1_R")
	)
	(segment
		(start 247.053608 -225.586798)
		(end 249.45848 -225.586798)
		(width 0.15494)
		(layer "In13.Cu")
		(net "PWRGD_P3V3_SSD1_R")
	)
	(segment
		(start 99.009454 -208.38668)
		(end 99.337114 -208.05902)
		(width 0.15494)
		(layer "In13.Cu")
		(net "PWRGD_P3V3_SSD1_R")
	)
	(segment
		(start 62.919864 -205.774798)
		(end 63.321184 -205.774798)
		(width 0.15494)
		(layer "In13.Cu")
		(net "PWRGD_P3V3_SSD1_R")
	)
	(segment
		(start 259.733034 -226.619816)
		(end 260.337046 -226.619816)
		(width 0.15494)
		(layer "In13.Cu")
		(net "PWRGD_P3V3_SSD1_R")
	)
	(segment
		(start 215.711024 -217.42273)
		(end 215.994234 -217.70594)
		(width 0.15494)
		(layer "In13.Cu")
		(net "PWRGD_P3V3_SSD1_R")
	)
	(segment
		(start 209.277966 -216.070434)
		(end 209.42427 -215.92413)
		(width 0.15494)
		(layer "In13.Cu")
		(net "PWRGD_P3V3_SSD1_R")
	)
	(segment
		(start 126.181104 -216.777316)
		(end 141.459204 -216.777316)
		(width 0.15494)
		(layer "In13.Cu")
		(net "PWRGD_P3V3_SSD1_R")
	)
	(segment
		(start 300.86427 -233.45013)
		(end 301.737014 -233.45013)
		(width 0.15494)
		(layer "In13.Cu")
		(net "PWRGD_P3V3_SSD1_R")
	)
	(segment
		(start 150.70201 -214.188548)
		(end 191.20612 -214.188548)
		(width 0.15494)
		(layer "In13.Cu")
		(net "PWRGD_P3V3_SSD1_R")
	)
	(segment
		(start 236.511846 -214.159846)
		(end 236.511846 -214.526876)
		(width 0.15494)
		(layer "In13.Cu")
		(net "PWRGD_P3V3_SSD1_R")
	)
	(segment
		(start 215.478868 -216.789)
		(end 215.711024 -217.021156)
		(width 0.15494)
		(layer "In13.Cu")
		(net "PWRGD_P3V3_SSD1_R")
	)
	(segment
		(start 76.928472 -208.3308)
		(end 94.956376 -208.3308)
		(width 0.15494)
		(layer "In13.Cu")
		(net "PWRGD_P3V3_SSD1_R")
	)
	(segment
		(start 148.113242 -216.777316)
		(end 150.70201 -214.188548)
		(width 0.15494)
		(layer "In13.Cu")
		(net "PWRGD_P3V3_SSD1_R")
	)
	(segment
		(start 220.37294 -214.907114)
		(end 222.51289 -212.767164)
		(width 0.15494)
		(layer "In13.Cu")
		(net "PWRGD_P3V3_SSD1_R")
	)
	(segment
		(start 249.45848 -225.586798)
		(end 250.287282 -226.4156)
		(width 0.15494)
		(layer "In13.Cu")
		(net "PWRGD_P3V3_SSD1_R")
	)
	(segment
		(start 341.17153 -227.915724)
		(end 342.218518 -226.868736)
		(width 0.15494)
		(layer "In13.Cu")
		(net "PWRGD_P3V3_SSD1_R")
	)
	(segment
		(start 224.3836 -211.835746)
		(end 225.221546 -210.9978)
		(width 0.15494)
		(layer "In13.Cu")
		(net "PWRGD_P3V3_SSD1_R")
	)
	(segment
		(start 216.753694 -217.3478)
		(end 219.312998 -217.3478)
		(width 0.15494)
		(layer "In13.Cu")
		(net "PWRGD_P3V3_SSD1_R")
	)
	(segment
		(start 116.426996 -208.07172)
		(end 116.55298 -208.07172)
		(width 0.15494)
		(layer "In13.Cu")
		(net "PWRGD_P3V3_SSD1_R")
	)
	(segment
		(start 141.459204 -216.777316)
		(end 141.489684 -216.807796)
		(width 0.15494)
		(layer "In13.Cu")
		(net "PWRGD_P3V3_SSD1_R")
	)
	(segment
		(start 262.08863 -228.3714)
		(end 272.168874 -228.3714)
		(width 0.15494)
		(layer "In13.Cu")
		(net "PWRGD_P3V3_SSD1_R")
	)
	(segment
		(start 234.9246 -212.5726)
		(end 236.511846 -214.159846)
		(width 0.15494)
		(layer "In13.Cu")
		(net "PWRGD_P3V3_SSD1_R")
	)
	(segment
		(start 191.221868 -214.1728)
		(end 205.5876 -214.1728)
		(width 0.15494)
		(layer "In13.Cu")
		(net "PWRGD_P3V3_SSD1_R")
	)
	(segment
		(start 215.711024 -217.021156)
		(end 215.711024 -217.42273)
		(width 0.15494)
		(layer "In13.Cu")
		(net "PWRGD_P3V3_SSD1_R")
	)
	(segment
		(start 95.012256 -208.38668)
		(end 99.009454 -208.38668)
		(width 0.15494)
		(layer "In13.Cu")
		(net "PWRGD_P3V3_SSD1_R")
	)
	(segment
		(start 141.489684 -216.807796)
		(end 141.891004 -216.807796)
		(width 0.15494)
		(layer "In13.Cu")
		(net "PWRGD_P3V3_SSD1_R")
	)
	(segment
		(start 272.168874 -228.3714)
		(end 278.020272 -234.222798)
		(width 0.15494)
		(layer "In13.Cu")
		(net "PWRGD_P3V3_SSD1_R")
	)
	(segment
		(start 300.091602 -234.222798)
		(end 300.86427 -233.45013)
		(width 0.15494)
		(layer "In13.Cu")
		(net "PWRGD_P3V3_SSD1_R")
	)
	(segment
		(start 323.054726 -234.2896)
		(end 323.412866 -234.64774)
		(width 0.15494)
		(layer "In13.Cu")
		(net "PWRGD_P3V3_SSD1_R")
	)
	(segment
		(start 207.485234 -216.070434)
		(end 209.277966 -216.070434)
		(width 0.15494)
		(layer "In13.Cu")
		(net "PWRGD_P3V3_SSD1_R")
	)
	(segment
		(start 216.395554 -217.70594)
		(end 216.753694 -217.3478)
		(width 0.15494)
		(layer "In13.Cu")
		(net "PWRGD_P3V3_SSD1_R")
	)
	(segment
		(start 124.422408 -215.01862)
		(end 126.181104 -216.777316)
		(width 0.15494)
		(layer "In13.Cu")
		(net "PWRGD_P3V3_SSD1_R")
	)
	(segment
		(start 116.414296 -208.05902)
		(end 116.426996 -208.07172)
		(width 0.15494)
		(layer "In13.Cu")
		(net "PWRGD_P3V3_SSD1_R")
	)
	(segment
		(start 224.163636 -212.767164)
		(end 224.3836 -212.5472)
		(width 0.15494)
		(layer "In13.Cu")
		(net "PWRGD_P3V3_SSD1_R")
	)
	(segment
		(start 260.337046 -226.619816)
		(end 262.08863 -228.3714)
		(width 0.15494)
		(layer "In13.Cu")
		(net "PWRGD_P3V3_SSD1_R")
	)
	(segment
		(start 233.953304 -211.04225)
		(end 234.9246 -212.013546)
		(width 0.15494)
		(layer "In13.Cu")
		(net "PWRGD_P3V3_SSD1_R")
	)
	(segment
		(start 32.430212 -217.30589)
		(end 60.244736 -205.784958)
		(width 0.15494)
		(layer "In13.Cu")
		(net "PWRGD_P3V3_SSD1_R")
	)
	(segment
		(start 258.066032 -226.619816)
		(end 259.14223 -226.619816)
		(width 0.15494)
		(layer "In13.Cu")
		(net "PWRGD_P3V3_SSD1_R")
	)
	(segment
		(start 339.409786 -231.681782)
		(end 339.538818 -231.681782)
		(width 0.15494)
		(layer "In13.Cu")
		(net "PWRGD_P3V3_SSD1_R")
	)
	(segment
		(start 257.861816 -226.4156)
		(end 258.066032 -226.619816)
		(width 0.15494)
		(layer "In13.Cu")
		(net "PWRGD_P3V3_SSD1_R")
	)
	(segment
		(start 339.409278 -231.68229)
		(end 339.409786 -231.681782)
		(width 0.15494)
		(layer "In13.Cu")
		(net "PWRGD_P3V3_SSD1_R")
	)
	(segment
		(start 209.42427 -215.92413)
		(end 211.17814 -215.92413)
		(width 0.15494)
		(layer "In13.Cu")
		(net "PWRGD_P3V3_SSD1_R")
	)
	(segment
		(start 301.737014 -233.45013)
		(end 302.576484 -234.2896)
		(width 0.15494)
		(layer "In13.Cu")
		(net "PWRGD_P3V3_SSD1_R")
	)
	(segment
		(start 205.5876 -214.1728)
		(end 207.485234 -216.070434)
		(width 0.15494)
		(layer "In13.Cu")
		(net "PWRGD_P3V3_SSD1_R")
	)
	(segment
		(start 230.88727 -211.5312)
		(end 231.37622 -211.04225)
		(width 0.15494)
		(layer "In13.Cu")
		(net "PWRGD_P3V3_SSD1_R")
	)
	(segment
		(start 116.55298 -208.07172)
		(end 123.49988 -215.01862)
		(width 0.15494)
		(layer "In13.Cu")
		(net "PWRGD_P3V3_SSD1_R")
	)
	(segment
		(start 234.9246 -212.013546)
		(end 234.9246 -212.5726)
		(width 0.15494)
		(layer "In13.Cu")
		(net "PWRGD_P3V3_SSD1_R")
	)
	(segment
		(start 31.927292 -217.80881)
		(end 32.430212 -217.30589)
		(width 0.15494)
		(layer "In13.Cu")
		(net "PWRGD_P3V3_SSD1_R")
	)
	(segment
		(start 259.73278 -226.619562)
		(end 259.733034 -226.619816)
		(width 0.15494)
		(layer "In13.Cu")
		(net "PWRGD_P3V3_SSD1_R")
	)
	(segment
		(start 339.538818 -231.681782)
		(end 341.17153 -230.04907)
		(width 0.15494)
		(layer "In13.Cu")
		(net "PWRGD_P3V3_SSD1_R")
	)
	(segment
		(start 259.142484 -226.619562)
		(end 259.73278 -226.619562)
		(width 0.15494)
		(layer "In13.Cu")
		(net "PWRGD_P3V3_SSD1_R")
	)
	(segment
		(start 74.38263 -205.784958)
		(end 76.928472 -208.3308)
		(width 0.15494)
		(layer "In13.Cu")
		(net "PWRGD_P3V3_SSD1_R")
	)
	(segment
		(start 341.17153 -230.04907)
		(end 341.17153 -227.915724)
		(width 0.15494)
		(layer "In13.Cu")
		(net "PWRGD_P3V3_SSD1_R")
	)
	(segment
		(start 325.894192 -234.139994)
		(end 332.849474 -234.139994)
		(width 0.15494)
		(layer "In13.Cu")
		(net "PWRGD_P3V3_SSD1_R")
	)
	(segment
		(start 215.994234 -217.70594)
		(end 216.395554 -217.70594)
		(width 0.15494)
		(layer "In13.Cu")
		(net "PWRGD_P3V3_SSD1_R")
	)
	(segment
		(start 123.49988 -215.01862)
		(end 124.422408 -215.01862)
		(width 0.15494)
		(layer "In13.Cu")
		(net "PWRGD_P3V3_SSD1_R")
	)
	(segment
		(start 222.51289 -212.767164)
		(end 224.163636 -212.767164)
		(width 0.15494)
		(layer "In13.Cu")
		(net "PWRGD_P3V3_SSD1_R")
	)
	(segment
		(start 229.666546 -210.9978)
		(end 230.199946 -211.5312)
		(width 0.15494)
		(layer "In13.Cu")
		(net "PWRGD_P3V3_SSD1_R")
	)
	(segment
		(start 241.1222 -218.6686)
		(end 242.142264 -219.688664)
		(width 0.15494)
		(layer "In13.Cu")
		(net "PWRGD_P3V3_SSD1_R")
	)
	(segment
		(start 242.142264 -219.688664)
		(end 242.142264 -220.675454)
		(width 0.15494)
		(layer "In13.Cu")
		(net "PWRGD_P3V3_SSD1_R")
	)
	(segment
		(start 224.3836 -212.5472)
		(end 224.3836 -211.835746)
		(width 0.15494)
		(layer "In13.Cu")
		(net "PWRGD_P3V3_SSD1_R")
	)
	(segment
		(start 230.199946 -211.5312)
		(end 230.88727 -211.5312)
		(width 0.15494)
		(layer "In13.Cu")
		(net "PWRGD_P3V3_SSD1_R")
	)
	(segment
		(start 60.244736 -205.784958)
		(end 62.909704 -205.784958)
		(width 0.15494)
		(layer "In13.Cu")
		(net "PWRGD_P3V3_SSD1_R")
	)
	(segment
		(start 227.867718 -224.304098)
		(end 228.267768 -223.904048)
		(width 0.13208)
		(layer "F.Cu")
		(net "NIC4_MAIN_PWR_BIC_EN")
	)
	(segment
		(start 227.115116 -227.142548)
		(end 227.867718 -226.389946)
		(width 0.13208)
		(layer "F.Cu")
		(net "NIC4_MAIN_PWR_BIC_EN")
	)
	(segment
		(start 227.115116 -227.695252)
		(end 227.115116 -227.142548)
		(width 0.13208)
		(layer "F.Cu")
		(net "NIC4_MAIN_PWR_BIC_EN")
	)
	(segment
		(start 226.727512 -230.601012)
		(end 226.727512 -231.016556)
		(width 0.13208)
		(layer "F.Cu")
		(net "NIC4_MAIN_PWR_BIC_EN")
	)
	(segment
		(start 227.115116 -227.695252)
		(end 227.115116 -230.213408)
		(width 0.13208)
		(layer "F.Cu")
		(net "NIC4_MAIN_PWR_BIC_EN")
	)
	(segment
		(start 227.115116 -230.213408)
		(end 226.727512 -230.601012)
		(width 0.13208)
		(layer "F.Cu")
		(net "NIC4_MAIN_PWR_BIC_EN")
	)
	(segment
		(start 227.867718 -226.389946)
		(end 227.867718 -224.304098)
		(width 0.13208)
		(layer "F.Cu")
		(net "NIC4_MAIN_PWR_BIC_EN")
	)
	(via
		(at 227.115116 -227.695252)
		(size 0.762)
		(drill 0.381)
		(layers "F.Cu" "B.Cu")
		(net "NIC4_MAIN_PWR_BIC_EN")
	)
	(segment
		(start 326.136254 -26.7716)
		(end 325.954644 -26.58999)
		(width 0.13462)
		(layer "F.Cu")
		(net "CLK_100M_DB800ZL_SSD11_R_DN")
	)
	(segment
		(start 325.954644 -26.58999)
		(end 325.464678 -26.58999)
		(width 0.13462)
		(layer "F.Cu")
		(net "CLK_100M_DB800ZL_SSD11_R_DN")
	)
	(segment
		(start 327.18121 -26.479246)
		(end 326.888856 -26.7716)
		(width 0.13462)
		(layer "F.Cu")
		(net "CLK_100M_DB800ZL_SSD11_R_DN")
	)
	(segment
		(start 345.013026 -84.169758)
		(end 345.337384 -83.8454)
		(width 0.13462)
		(layer "F.Cu")
		(net "CLK_100M_DB800ZL_SSD11_R_DN")
	)
	(segment
		(start 345.337384 -83.8454)
		(end 346.038932 -83.8454)
		(width 0.13462)
		(layer "F.Cu")
		(net "CLK_100M_DB800ZL_SSD11_R_DN")
	)
	(segment
		(start 346.038932 -83.8454)
		(end 346.33789 -84.144358)
		(width 0.13462)
		(layer "F.Cu")
		(net "CLK_100M_DB800ZL_SSD11_R_DN")
	)
	(segment
		(start 326.888856 -26.7716)
		(end 326.136254 -26.7716)
		(width 0.13462)
		(layer "F.Cu")
		(net "CLK_100M_DB800ZL_SSD11_R_DN")
	)
	(via
		(at 327.18121 -26.479246)
		(size 0.508)
		(drill 0.254)
		(layers "F.Cu" "B.Cu")
		(net "CLK_100M_DB800ZL_SSD11_R_DN")
	)
	(via
		(at 346.33789 -84.144358)
		(size 0.508)
		(drill 0.254)
		(layers "F.Cu" "B.Cu")
		(net "CLK_100M_DB800ZL_SSD11_R_DN")
	)
	(segment
		(start 332.58506 -27.63266)
		(end 330.85024 -27.63266)
		(width 0.1651)
		(layer "In13.Cu")
		(net "CLK_100M_DB800ZL_SSD11_R_DN")
	)
	(segment
		(start 330.85024 -27.63266)
		(end 330.29144 -27.07386)
		(width 0.1651)
		(layer "In13.Cu")
		(net "CLK_100M_DB800ZL_SSD11_R_DN")
	)
	(segment
		(start 340.10092 -35.14852)
		(end 332.58506 -27.63266)
		(width 0.1651)
		(layer "In13.Cu")
		(net "CLK_100M_DB800ZL_SSD11_R_DN")
	)
	(segment
		(start 346.97924 -83.853528)
		(end 347.34754 -83.485228)
		(width 0.1651)
		(layer "In13.Cu")
		(net "CLK_100M_DB800ZL_SSD11_R_DN")
	)
	(segment
		(start 341.40394 -37.098478)
		(end 340.10092 -35.14852)
		(width 0.1651)
		(layer "In13.Cu")
		(net "CLK_100M_DB800ZL_SSD11_R_DN")
	)
	(segment
		(start 344.40114 -79.94396)
		(end 344.40114 -43.03776)
		(width 0.1651)
		(layer "In13.Cu")
		(net "CLK_100M_DB800ZL_SSD11_R_DN")
	)
	(segment
		(start 344.40114 -43.03776)
		(end 341.40394 -40.04056)
		(width 0.1651)
		(layer "In13.Cu")
		(net "CLK_100M_DB800ZL_SSD11_R_DN")
	)
	(segment
		(start 346.33789 -84.144358)
		(end 346.62872 -83.853528)
		(width 0.1651)
		(layer "In13.Cu")
		(net "CLK_100M_DB800ZL_SSD11_R_DN")
	)
	(segment
		(start 347.34754 -82.89036)
		(end 344.40114 -79.94396)
		(width 0.1651)
		(layer "In13.Cu")
		(net "CLK_100M_DB800ZL_SSD11_R_DN")
	)
	(segment
		(start 347.34754 -83.485228)
		(end 347.34754 -82.89036)
		(width 0.1651)
		(layer "In13.Cu")
		(net "CLK_100M_DB800ZL_SSD11_R_DN")
	)
	(segment
		(start 330.29144 -27.07386)
		(end 329.46086 -27.07386)
		(width 0.1651)
		(layer "In13.Cu")
		(net "CLK_100M_DB800ZL_SSD11_R_DN")
	)
	(segment
		(start 327.47204 -26.770076)
		(end 327.18121 -26.479246)
		(width 0.1651)
		(layer "In13.Cu")
		(net "CLK_100M_DB800ZL_SSD11_R_DN")
	)
	(segment
		(start 346.62872 -83.853528)
		(end 346.97924 -83.853528)
		(width 0.1651)
		(layer "In13.Cu")
		(net "CLK_100M_DB800ZL_SSD11_R_DN")
	)
	(segment
		(start 329.157076 -26.770076)
		(end 327.47204 -26.770076)
		(width 0.1651)
		(layer "In13.Cu")
		(net "CLK_100M_DB800ZL_SSD11_R_DN")
	)
	(segment
		(start 341.40394 -40.04056)
		(end 341.40394 -37.098478)
		(width 0.1651)
		(layer "In13.Cu")
		(net "CLK_100M_DB800ZL_SSD11_R_DN")
	)
	(segment
		(start 329.46086 -27.07386)
		(end 329.157076 -26.770076)
		(width 0.1651)
		(layer "In13.Cu")
		(net "CLK_100M_DB800ZL_SSD11_R_DN")
	)
	(segment
		(start 321.219576 -310.226456)
		(end 321.592702 -309.85333)
		(width 0.13208)
		(layer "F.Cu")
		(net "PEX2_SPARE2")
	)
	(segment
		(start 321.592702 -309.85333)
		(end 322.114164 -309.331868)
		(width 0.13208)
		(layer "F.Cu")
		(net "PEX2_SPARE2")
	)
	(segment
		(start 320.978784 -310.226456)
		(end 321.219576 -310.226456)
		(width 0.13208)
		(layer "F.Cu")
		(net "PEX2_SPARE2")
	)
	(segment
		(start 322.114164 -309.331868)
		(end 322.114164 -309.324756)
		(width 0.13208)
		(layer "F.Cu")
		(net "PEX2_SPARE2")
	)
	(via
		(at 318.022478 -313.423554)
		(size 0.6604)
		(drill 0.3302)
		(layers "F.Cu" "B.Cu")
		(net "PEX2_SPARE2")
	)
	(via
		(at 293.74973 -309.199788)
		(size 0.4064)
		(drill 0.2032)
		(layers "F.Cu" "B.Cu")
		(net "PEX2_SPARE2")
	)
	(via
		(at 321.592702 -309.85333)
		(size 0.508)
		(drill 0.254)
		(layers "F.Cu" "B.Cu")
		(net "PEX2_SPARE2")
	)
	(segment
		(start 294.50411 -309.199788)
		(end 295.170098 -309.865776)
		(width 0.13208)
		(layer "B.Cu")
		(net "PEX2_SPARE2")
	)
	(segment
		(start 316.988698 -314.457334)
		(end 318.022478 -313.423554)
		(width 0.13208)
		(layer "B.Cu")
		(net "PEX2_SPARE2")
	)
	(segment
		(start 293.74973 -309.199788)
		(end 294.50411 -309.199788)
		(width 0.13208)
		(layer "B.Cu")
		(net "PEX2_SPARE2")
	)
	(segment
		(start 295.170098 -314.330334)
		(end 295.297098 -314.457334)
		(width 0.13208)
		(layer "B.Cu")
		(net "PEX2_SPARE2")
	)
	(segment
		(start 295.297098 -314.457334)
		(end 316.988698 -314.457334)
		(width 0.13208)
		(layer "B.Cu")
		(net "PEX2_SPARE2")
	)
	(segment
		(start 295.170098 -309.865776)
		(end 295.170098 -314.330334)
		(width 0.13208)
		(layer "B.Cu")
		(net "PEX2_SPARE2")
	)
	(segment
		(start 318.022478 -313.423554)
		(end 321.592702 -309.85333)
		(width 0.13208)
		(layer "B.Cu")
		(net "PEX2_SPARE2")
	)
	(segment
		(start 362.30814 -86.815168)
		(end 364.051342 -86.815168)
		(width 0.13208)
		(layer "F.Cu")
		(net "SMB_BIC_I2C9_MUX1_SSD15_SDA")
	)
	(segment
		(start 366.127792 -88.356694)
		(end 366.555528 -88.356694)
		(width 0.13208)
		(layer "F.Cu")
		(net "SMB_BIC_I2C9_MUX1_SSD15_SDA")
	)
	(segment
		(start 364.051342 -86.815168)
		(end 365.331756 -88.095582)
		(width 0.13208)
		(layer "F.Cu")
		(net "SMB_BIC_I2C9_MUX1_SSD15_SDA")
	)
	(segment
		(start 365.86668 -88.095582)
		(end 366.127792 -88.356694)
		(width 0.13208)
		(layer "F.Cu")
		(net "SMB_BIC_I2C9_MUX1_SSD15_SDA")
	)
	(segment
		(start 365.331756 -88.095582)
		(end 365.86668 -88.095582)
		(width 0.13208)
		(layer "F.Cu")
		(net "SMB_BIC_I2C9_MUX1_SSD15_SDA")
	)
	(via
		(at 365.86668 -88.095582)
		(size 0.508)
		(drill 0.254)
		(layers "F.Cu" "B.Cu")
		(net "SMB_BIC_I2C9_MUX1_SSD15_SDA")
	)
	(segment
		(start 347.693742 -229.006146)
		(end 347.693742 -227.987098)
		(width 0.13208)
		(layer "F.Cu")
		(net "PWRGD_P3V3_SSD6_R")
	)
	(segment
		(start 168.712388 -35.6362)
		(end 166.22268 -35.6362)
		(width 0.13208)
		(layer "F.Cu")
		(net "PWRGD_P3V3_SSD6_R")
	)
	(segment
		(start 165.982142 -35.876738)
		(end 165.270942 -35.876738)
		(width 0.13208)
		(layer "F.Cu")
		(net "PWRGD_P3V3_SSD6_R")
	)
	(segment
		(start 169.30878 -36.232592)
		(end 168.712388 -35.6362)
		(width 0.13208)
		(layer "F.Cu")
		(net "PWRGD_P3V3_SSD6_R")
	)
	(segment
		(start 166.22268 -35.6362)
		(end 165.982142 -35.876738)
		(width 0.13208)
		(layer "F.Cu")
		(net "PWRGD_P3V3_SSD6_R")
	)
	(segment
		(start 347.218 -229.743)
		(end 347.509084 -229.451916)
		(width 0.13208)
		(layer "F.Cu")
		(net "PWRGD_P3V3_SSD6_R")
	)
	(segment
		(start 176.711102 -61.386974)
		(end 176.711102 -62.051438)
		(width 0.13208)
		(layer "F.Cu")
		(net "PWRGD_P3V3_SSD6_R")
	)
	(segment
		(start 169.695368 -36.232592)
		(end 169.30878 -36.232592)
		(width 0.13208)
		(layer "F.Cu")
		(net "PWRGD_P3V3_SSD6_R")
	)
	(segment
		(start 164.527992 -35.876738)
		(end 165.270942 -35.876738)
		(width 0.13208)
		(layer "F.Cu")
		(net "PWRGD_P3V3_SSD6_R")
	)
	(segment
		(start 347.509084 -229.451916)
		(end 347.693742 -229.006146)
		(width 0.13208)
		(layer "F.Cu")
		(net "PWRGD_P3V3_SSD6_R")
	)
	(via
		(at 347.218 -229.743)
		(size 0.508)
		(drill 0.254)
		(layers "F.Cu" "B.Cu")
		(net "PWRGD_P3V3_SSD6_R")
	)
	(via
		(at 165.270942 -35.876738)
		(size 0.508)
		(drill 0.254)
		(layers "F.Cu" "B.Cu")
		(net "PWRGD_P3V3_SSD6_R")
	)
	(via
		(at 183.4896 -239.395)
		(size 0.508)
		(drill 0.254)
		(layers "F.Cu" "B.Cu")
		(net "PWRGD_P3V3_SSD6_R")
	)
	(via
		(at 176.711102 -62.051438)
		(size 0.508)
		(drill 0.254)
		(layers "F.Cu" "B.Cu")
		(net "PWRGD_P3V3_SSD6_R")
	)
	(segment
		(start 177.927 -61.344556)
		(end 177.220118 -62.051438)
		(width 0.15494)
		(layer "In5.Cu")
		(net "PWRGD_P3V3_SSD6_R")
	)
	(segment
		(start 174.120556 -199.653652)
		(end 174.120556 -108.25607)
		(width 0.15494)
		(layer "In5.Cu")
		(net "PWRGD_P3V3_SSD6_R")
	)
	(segment
		(start 171.776136 -87.674958)
		(end 171.776136 -84.35594)
		(width 0.15494)
		(layer "In5.Cu")
		(net "PWRGD_P3V3_SSD6_R")
	)
	(segment
		(start 173.237652 -89.136474)
		(end 171.776136 -87.674958)
		(width 0.15494)
		(layer "In5.Cu")
		(net "PWRGD_P3V3_SSD6_R")
	)
	(segment
		(start 183.277764 -229.225094)
		(end 181.806596 -227.753926)
		(width 0.15494)
		(layer "In5.Cu")
		(net "PWRGD_P3V3_SSD6_R")
	)
	(segment
		(start 177.681636 -203.214732)
		(end 174.120556 -199.653652)
		(width 0.15494)
		(layer "In5.Cu")
		(net "PWRGD_P3V3_SSD6_R")
	)
	(segment
		(start 181.664356 -227.51161)
		(end 181.664356 -221.381066)
		(width 0.15494)
		(layer "In5.Cu")
		(net "PWRGD_P3V3_SSD6_R")
	)
	(segment
		(start 181.806596 -227.753926)
		(end 181.806596 -227.65385)
		(width 0.15494)
		(layer "In5.Cu")
		(net "PWRGD_P3V3_SSD6_R")
	)
	(segment
		(start 173.237652 -107.373166)
		(end 173.237652 -89.136474)
		(width 0.15494)
		(layer "In5.Cu")
		(net "PWRGD_P3V3_SSD6_R")
	)
	(segment
		(start 165.270942 -35.876738)
		(end 168.164256 -35.876738)
		(width 0.15494)
		(layer "In5.Cu")
		(net "PWRGD_P3V3_SSD6_R")
	)
	(segment
		(start 183.104536 -234.373166)
		(end 183.277764 -234.199938)
		(width 0.15494)
		(layer "In5.Cu")
		(net "PWRGD_P3V3_SSD6_R")
	)
	(segment
		(start 183.4896 -239.395)
		(end 183.4896 -236.067854)
		(width 0.15494)
		(layer "In5.Cu")
		(net "PWRGD_P3V3_SSD6_R")
	)
	(segment
		(start 183.104536 -235.68279)
		(end 183.104536 -234.373166)
		(width 0.15494)
		(layer "In5.Cu")
		(net "PWRGD_P3V3_SSD6_R")
	)
	(segment
		(start 176.711102 -79.420974)
		(end 176.711102 -62.051438)
		(width 0.15494)
		(layer "In5.Cu")
		(net "PWRGD_P3V3_SSD6_R")
	)
	(segment
		(start 177.681636 -211.765642)
		(end 177.681636 -203.214732)
		(width 0.15494)
		(layer "In5.Cu")
		(net "PWRGD_P3V3_SSD6_R")
	)
	(segment
		(start 183.277764 -234.199938)
		(end 183.277764 -229.225094)
		(width 0.15494)
		(layer "In5.Cu")
		(net "PWRGD_P3V3_SSD6_R")
	)
	(segment
		(start 171.776136 -84.35594)
		(end 176.711102 -79.420974)
		(width 0.15494)
		(layer "In5.Cu")
		(net "PWRGD_P3V3_SSD6_R")
	)
	(segment
		(start 181.664356 -221.381066)
		(end 177.681636 -211.765642)
		(width 0.15494)
		(layer "In5.Cu")
		(net "PWRGD_P3V3_SSD6_R")
	)
	(segment
		(start 177.927 -45.639482)
		(end 177.927 -61.344556)
		(width 0.15494)
		(layer "In5.Cu")
		(net "PWRGD_P3V3_SSD6_R")
	)
	(segment
		(start 168.164256 -35.876738)
		(end 177.927 -45.639482)
		(width 0.15494)
		(layer "In5.Cu")
		(net "PWRGD_P3V3_SSD6_R")
	)
	(segment
		(start 181.806596 -227.65385)
		(end 181.664356 -227.51161)
		(width 0.15494)
		(layer "In5.Cu")
		(net "PWRGD_P3V3_SSD6_R")
	)
	(segment
		(start 174.120556 -108.25607)
		(end 173.237652 -107.373166)
		(width 0.15494)
		(layer "In5.Cu")
		(net "PWRGD_P3V3_SSD6_R")
	)
	(segment
		(start 177.220118 -62.051438)
		(end 176.711102 -62.051438)
		(width 0.15494)
		(layer "In5.Cu")
		(net "PWRGD_P3V3_SSD6_R")
	)
	(segment
		(start 183.4896 -236.067854)
		(end 183.104536 -235.68279)
		(width 0.15494)
		(layer "In5.Cu")
		(net "PWRGD_P3V3_SSD6_R")
	)
	(segment
		(start 256.362962 -238.2012)
		(end 257.251962 -237.3122)
		(width 0.15494)
		(layer "In13.Cu")
		(net "PWRGD_P3V3_SSD6_R")
	)
	(segment
		(start 306.689506 -240.2586)
		(end 337.134454 -240.2586)
		(width 0.15494)
		(layer "In13.Cu")
		(net "PWRGD_P3V3_SSD6_R")
	)
	(segment
		(start 246.898922 -236.796326)
		(end 247.386856 -236.99851)
		(width 0.15494)
		(layer "In13.Cu")
		(net "PWRGD_P3V3_SSD6_R")
	)
	(segment
		(start 340.385654 -237.0074)
		(end 341.122254 -237.0074)
		(width 0.15494)
		(layer "In13.Cu")
		(net "PWRGD_P3V3_SSD6_R")
	)
	(segment
		(start 341.644732 -235.773468)
		(end 342.127332 -235.773468)
		(width 0.15494)
		(layer "In13.Cu")
		(net "PWRGD_P3V3_SSD6_R")
	)
	(segment
		(start 347.218 -231.461564)
		(end 347.218 -229.743)
		(width 0.15494)
		(layer "In13.Cu")
		(net "PWRGD_P3V3_SSD6_R")
	)
	(segment
		(start 259.968746 -237.3122)
		(end 261.32917 -235.951776)
		(width 0.15494)
		(layer "In13.Cu")
		(net "PWRGD_P3V3_SSD6_R")
	)
	(segment
		(start 306.105306 -239.6744)
		(end 306.689506 -240.2586)
		(width 0.15494)
		(layer "In13.Cu")
		(net "PWRGD_P3V3_SSD6_R")
	)
	(segment
		(start 341.488268 -236.641386)
		(end 341.488268 -235.929932)
		(width 0.15494)
		(layer "In13.Cu")
		(net "PWRGD_P3V3_SSD6_R")
	)
	(segment
		(start 248.589546 -238.2012)
		(end 256.362962 -238.2012)
		(width 0.15494)
		(layer "In13.Cu")
		(net "PWRGD_P3V3_SSD6_R")
	)
	(segment
		(start 206.069946 -238.8108)
		(end 207.417162 -237.463584)
		(width 0.15494)
		(layer "In13.Cu")
		(net "PWRGD_P3V3_SSD6_R")
	)
	(segment
		(start 207.417162 -237.463584)
		(end 210.410298 -237.463584)
		(width 0.15494)
		(layer "In13.Cu")
		(net "PWRGD_P3V3_SSD6_R")
	)
	(segment
		(start 344.273378 -234.406186)
		(end 347.218 -231.461564)
		(width 0.15494)
		(layer "In13.Cu")
		(net "PWRGD_P3V3_SSD6_R")
	)
	(segment
		(start 211.679282 -236.1946)
		(end 230.359712 -236.1946)
		(width 0.15494)
		(layer "In13.Cu")
		(net "PWRGD_P3V3_SSD6_R")
	)
	(segment
		(start 341.122254 -237.0074)
		(end 341.488268 -236.641386)
		(width 0.15494)
		(layer "In13.Cu")
		(net "PWRGD_P3V3_SSD6_R")
	)
	(segment
		(start 265.020552 -235.951776)
		(end 267.23721 -238.168434)
		(width 0.15494)
		(layer "In13.Cu")
		(net "PWRGD_P3V3_SSD6_R")
	)
	(segment
		(start 184.5818 -239.8268)
		(end 185.5978 -238.8108)
		(width 0.15494)
		(layer "In13.Cu")
		(net "PWRGD_P3V3_SSD6_R")
	)
	(segment
		(start 342.50503 -235.39577)
		(end 342.50503 -234.813856)
		(width 0.15494)
		(layer "In13.Cu")
		(net "PWRGD_P3V3_SSD6_R")
	)
	(segment
		(start 230.359712 -236.1946)
		(end 230.961438 -236.796326)
		(width 0.15494)
		(layer "In13.Cu")
		(net "PWRGD_P3V3_SSD6_R")
	)
	(segment
		(start 337.134454 -240.2586)
		(end 340.385654 -237.0074)
		(width 0.15494)
		(layer "In13.Cu")
		(net "PWRGD_P3V3_SSD6_R")
	)
	(segment
		(start 342.9127 -234.406186)
		(end 344.273378 -234.406186)
		(width 0.15494)
		(layer "In13.Cu")
		(net "PWRGD_P3V3_SSD6_R")
	)
	(segment
		(start 183.4896 -239.66297)
		(end 183.65343 -239.8268)
		(width 0.15494)
		(layer "In13.Cu")
		(net "PWRGD_P3V3_SSD6_R")
	)
	(segment
		(start 276.6314 -239.6744)
		(end 306.105306 -239.6744)
		(width 0.15494)
		(layer "In13.Cu")
		(net "PWRGD_P3V3_SSD6_R")
	)
	(segment
		(start 267.23721 -238.168434)
		(end 275.125434 -238.168434)
		(width 0.15494)
		(layer "In13.Cu")
		(net "PWRGD_P3V3_SSD6_R")
	)
	(segment
		(start 230.961438 -236.796326)
		(end 246.898922 -236.796326)
		(width 0.15494)
		(layer "In13.Cu")
		(net "PWRGD_P3V3_SSD6_R")
	)
	(segment
		(start 183.65343 -239.8268)
		(end 184.5818 -239.8268)
		(width 0.15494)
		(layer "In13.Cu")
		(net "PWRGD_P3V3_SSD6_R")
	)
	(segment
		(start 247.386856 -236.99851)
		(end 248.589546 -238.2012)
		(width 0.15494)
		(layer "In13.Cu")
		(net "PWRGD_P3V3_SSD6_R")
	)
	(segment
		(start 261.32917 -235.951776)
		(end 265.020552 -235.951776)
		(width 0.15494)
		(layer "In13.Cu")
		(net "PWRGD_P3V3_SSD6_R")
	)
	(segment
		(start 275.125434 -238.168434)
		(end 276.6314 -239.6744)
		(width 0.15494)
		(layer "In13.Cu")
		(net "PWRGD_P3V3_SSD6_R")
	)
	(segment
		(start 257.251962 -237.3122)
		(end 259.968746 -237.3122)
		(width 0.15494)
		(layer "In13.Cu")
		(net "PWRGD_P3V3_SSD6_R")
	)
	(segment
		(start 342.127332 -235.773468)
		(end 342.50503 -235.39577)
		(width 0.15494)
		(layer "In13.Cu")
		(net "PWRGD_P3V3_SSD6_R")
	)
	(segment
		(start 342.50503 -234.813856)
		(end 342.9127 -234.406186)
		(width 0.15494)
		(layer "In13.Cu")
		(net "PWRGD_P3V3_SSD6_R")
	)
	(segment
		(start 341.488268 -235.929932)
		(end 341.644732 -235.773468)
		(width 0.15494)
		(layer "In13.Cu")
		(net "PWRGD_P3V3_SSD6_R")
	)
	(segment
		(start 185.5978 -238.8108)
		(end 206.069946 -238.8108)
		(width 0.15494)
		(layer "In13.Cu")
		(net "PWRGD_P3V3_SSD6_R")
	)
	(segment
		(start 183.4896 -239.395)
		(end 183.4896 -239.66297)
		(width 0.15494)
		(layer "In13.Cu")
		(net "PWRGD_P3V3_SSD6_R")
	)
	(segment
		(start 210.410298 -237.463584)
		(end 211.679282 -236.1946)
		(width 0.15494)
		(layer "In13.Cu")
		(net "PWRGD_P3V3_SSD6_R")
	)
	(segment
		(start 424.630596 -53.144166)
		(end 424.779948 -52.994814)
		(width 0.13208)
		(layer "F.Cu")
		(net "P12V_SSD14_SS")
	)
	(segment
		(start 425.431458 -51.019456)
		(end 426.167804 -51.019456)
		(width 0.13208)
		(layer "F.Cu")
		(net "P12V_SSD14_SS")
	)
	(segment
		(start 424.447208 -53.144166)
		(end 424.630596 -53.144166)
		(width 0.13208)
		(layer "F.Cu")
		(net "P12V_SSD14_SS")
	)
	(segment
		(start 424.779948 -51.670966)
		(end 425.431458 -51.019456)
		(width 0.13208)
		(layer "F.Cu")
		(net "P12V_SSD14_SS")
	)
	(segment
		(start 424.779948 -52.994814)
		(end 424.779948 -51.670966)
		(width 0.13208)
		(layer "F.Cu")
		(net "P12V_SSD14_SS")
	)
	(via
		(at 425.431458 -51.019456)
		(size 0.508)
		(drill 0.254)
		(layers "F.Cu" "B.Cu")
		(net "P12V_SSD14_SS")
	)
	(segment
		(start 442.232796 -27.0256)
		(end 442.068458 -27.189938)
		(width 0.13462)
		(layer "F.Cu")
		(net "CLK_100M_DB800ZL_SSD15_R_DP")
	)
	(segment
		(start 339.44052 -94.557088)
		(end 339.727286 -94.843854)
		(width 0.13462)
		(layer "F.Cu")
		(net "CLK_100M_DB800ZL_SSD15_R_DP")
	)
	(segment
		(start 443.281308 -27.342846)
		(end 442.964062 -27.0256)
		(width 0.13462)
		(layer "F.Cu")
		(net "CLK_100M_DB800ZL_SSD15_R_DP")
	)
	(segment
		(start 339.752686 -93.51899)
		(end 339.44052 -93.831156)
		(width 0.13462)
		(layer "F.Cu")
		(net "CLK_100M_DB800ZL_SSD15_R_DP")
	)
	(segment
		(start 442.068458 -27.189938)
		(end 441.564776 -27.189938)
		(width 0.13462)
		(layer "F.Cu")
		(net "CLK_100M_DB800ZL_SSD15_R_DP")
	)
	(segment
		(start 339.44052 -93.831156)
		(end 339.44052 -94.557088)
		(width 0.13462)
		(layer "F.Cu")
		(net "CLK_100M_DB800ZL_SSD15_R_DP")
	)
	(segment
		(start 442.964062 -27.0256)
		(end 442.232796 -27.0256)
		(width 0.13462)
		(layer "F.Cu")
		(net "CLK_100M_DB800ZL_SSD15_R_DP")
	)
	(via
		(at 339.727286 -94.843854)
		(size 0.508)
		(drill 0.254)
		(layers "F.Cu" "B.Cu")
		(net "CLK_100M_DB800ZL_SSD15_R_DP")
	)
	(via
		(at 443.281308 -27.342846)
		(size 0.508)
		(drill 0.254)
		(layers "F.Cu" "B.Cu")
		(net "CLK_100M_DB800ZL_SSD15_R_DP")
	)
	(segment
		(start 439.511948 -41.199054)
		(end 439.511948 -41.360852)
		(width 0.1651)
		(layer "In13.Cu")
		(net "CLK_100M_DB800ZL_SSD15_R_DP")
	)
	(segment
		(start 440.374278 -40.498522)
		(end 440.024266 -40.848534)
		(width 0.1651)
		(layer "In13.Cu")
		(net "CLK_100M_DB800ZL_SSD15_R_DP")
	)
	(segment
		(start 442.961268 -37.911532)
		(end 442.611256 -38.261544)
		(width 0.1651)
		(layer "In13.Cu")
		(net "CLK_100M_DB800ZL_SSD15_R_DP")
	)
	(segment
		(start 443.9158 -30.836616)
		(end 443.9158 -31.331916)
		(width 0.1651)
		(layer "In13.Cu")
		(net "CLK_100M_DB800ZL_SSD15_R_DP")
	)
	(segment
		(start 443.281308 -27.342846)
		(end 443.572138 -27.052016)
		(width 0.1651)
		(layer "In13.Cu")
		(net "CLK_100M_DB800ZL_SSD15_R_DP")
	)
	(segment
		(start 443.8015 -27.788616)
		(end 443.8015 -28.283916)
		(width 0.1651)
		(layer "In13.Cu")
		(net "CLK_100M_DB800ZL_SSD15_R_DP")
	)
	(segment
		(start 443.311788 -37.399468)
		(end 442.961268 -37.749988)
		(width 0.1651)
		(layer "In13.Cu")
		(net "CLK_100M_DB800ZL_SSD15_R_DP")
	)
	(segment
		(start 437.55056 -62.3951)
		(end 437.66486 -62.5094)
		(width 0.1651)
		(layer "In13.Cu")
		(net "CLK_100M_DB800ZL_SSD15_R_DP")
	)
	(segment
		(start 362.247688 -85.011768)
		(end 361.897168 -85.362288)
		(width 0.1651)
		(layer "In13.Cu")
		(net "CLK_100M_DB800ZL_SSD15_R_DP")
	)
	(segment
		(start 437.66486 -61.2902)
		(end 437.66486 -61.7855)
		(width 0.1651)
		(layer "In13.Cu")
		(net "CLK_100M_DB800ZL_SSD15_R_DP")
	)
	(segment
		(start 437.55056 -61.1759)
		(end 437.66486 -61.2902)
		(width 0.1651)
		(layer "In13.Cu")
		(net "CLK_100M_DB800ZL_SSD15_R_DP")
	)
	(segment
		(start 441.748926 -39.123874)
		(end 441.587128 -39.123874)
		(width 0.1651)
		(layer "In13.Cu")
		(net "CLK_100M_DB800ZL_SSD15_R_DP")
	)
	(segment
		(start 436.859172 -64.65062)
		(end 436.669688 -65.108328)
		(width 0.1651)
		(layer "In13.Cu")
		(net "CLK_100M_DB800ZL_SSD15_R_DP")
	)
	(segment
		(start 440.024266 -40.848534)
		(end 439.862468 -40.848534)
		(width 0.1651)
		(layer "In13.Cu")
		(net "CLK_100M_DB800ZL_SSD15_R_DP")
	)
	(segment
		(start 437.66486 -60.5663)
		(end 437.55056 -60.6806)
		(width 0.1651)
		(layer "In13.Cu")
		(net "CLK_100M_DB800ZL_SSD15_R_DP")
	)
	(segment
		(start 443.7888 -27.052016)
		(end 443.9158 -27.179016)
		(width 0.1651)
		(layer "In13.Cu")
		(net "CLK_100M_DB800ZL_SSD15_R_DP")
	)
	(segment
		(start 441.236608 -39.636192)
		(end 440.886596 -39.986204)
		(width 0.1651)
		(layer "In13.Cu")
		(net "CLK_100M_DB800ZL_SSD15_R_DP")
	)
	(segment
		(start 443.9158 -28.398216)
		(end 443.9158 -28.893516)
		(width 0.1651)
		(layer "In13.Cu")
		(net "CLK_100M_DB800ZL_SSD15_R_DP")
	)
	(segment
		(start 440.374278 -40.336724)
		(end 440.374278 -40.498522)
		(width 0.1651)
		(layer "In13.Cu")
		(net "CLK_100M_DB800ZL_SSD15_R_DP")
	)
	(segment
		(start 443.9158 -29.617416)
		(end 443.9158 -30.112716)
		(width 0.1651)
		(layer "In13.Cu")
		(net "CLK_100M_DB800ZL_SSD15_R_DP")
	)
	(segment
		(start 361.897168 -85.523832)
		(end 351.8408 -95.5802)
		(width 0.1651)
		(layer "In13.Cu")
		(net "CLK_100M_DB800ZL_SSD15_R_DP")
	)
	(segment
		(start 443.572138 -27.052016)
		(end 443.7888 -27.052016)
		(width 0.1651)
		(layer "In13.Cu")
		(net "CLK_100M_DB800ZL_SSD15_R_DP")
	)
	(segment
		(start 443.9158 -36.957)
		(end 443.473332 -37.399468)
		(width 0.1651)
		(layer "In13.Cu")
		(net "CLK_100M_DB800ZL_SSD15_R_DP")
	)
	(segment
		(start 443.8015 -30.722316)
		(end 443.9158 -30.836616)
		(width 0.1651)
		(layer "In13.Cu")
		(net "CLK_100M_DB800ZL_SSD15_R_DP")
	)
	(segment
		(start 351.8408 -95.5802)
		(end 339.648292 -95.5802)
		(width 0.1651)
		(layer "In13.Cu")
		(net "CLK_100M_DB800ZL_SSD15_R_DP")
	)
	(segment
		(start 443.8015 -29.503116)
		(end 443.9158 -29.617416)
		(width 0.1651)
		(layer "In13.Cu")
		(net "CLK_100M_DB800ZL_SSD15_R_DP")
	)
	(segment
		(start 441.236608 -39.474394)
		(end 441.236608 -39.636192)
		(width 0.1651)
		(layer "In13.Cu")
		(net "CLK_100M_DB800ZL_SSD15_R_DP")
	)
	(segment
		(start 443.473332 -37.399468)
		(end 443.311788 -37.399468)
		(width 0.1651)
		(layer "In13.Cu")
		(net "CLK_100M_DB800ZL_SSD15_R_DP")
	)
	(segment
		(start 437.55056 -61.8998)
		(end 437.55056 -62.3951)
		(width 0.1651)
		(layer "In13.Cu")
		(net "CLK_100M_DB800ZL_SSD15_R_DP")
	)
	(segment
		(start 436.669688 -65.108328)
		(end 436.731664 -65.25768)
		(width 0.1651)
		(layer "In13.Cu")
		(net "CLK_100M_DB800ZL_SSD15_R_DP")
	)
	(segment
		(start 437.008778 -64.588644)
		(end 436.859172 -64.65062)
		(width 0.1651)
		(layer "In13.Cu")
		(net "CLK_100M_DB800ZL_SSD15_R_DP")
	)
	(segment
		(start 443.8015 -30.227016)
		(end 443.8015 -30.722316)
		(width 0.1651)
		(layer "In13.Cu")
		(net "CLK_100M_DB800ZL_SSD15_R_DP")
	)
	(segment
		(start 435.023768 -67.379088)
		(end 435.023768 -67.540632)
		(width 0.1651)
		(layer "In13.Cu")
		(net "CLK_100M_DB800ZL_SSD15_R_DP")
	)
	(segment
		(start 435.535832 -67.028568)
		(end 435.374288 -67.028568)
		(width 0.1651)
		(layer "In13.Cu")
		(net "CLK_100M_DB800ZL_SSD15_R_DP")
	)
	(segment
		(start 442.449458 -38.261544)
		(end 442.098938 -38.612064)
		(width 0.1651)
		(layer "In13.Cu")
		(net "CLK_100M_DB800ZL_SSD15_R_DP")
	)
	(segment
		(start 366.0902 -80.8228)
		(end 366.0902 -81.7626)
		(width 0.1651)
		(layer "In13.Cu")
		(net "CLK_100M_DB800ZL_SSD15_R_DP")
	)
	(segment
		(start 439.511948 -41.360852)
		(end 437.66486 -43.20794)
		(width 0.1651)
		(layer "In13.Cu")
		(net "CLK_100M_DB800ZL_SSD15_R_DP")
	)
	(segment
		(start 443.9158 -32.055816)
		(end 443.9158 -36.957)
		(width 0.1651)
		(layer "In13.Cu")
		(net "CLK_100M_DB800ZL_SSD15_R_DP")
	)
	(segment
		(start 443.8015 -29.007816)
		(end 443.8015 -29.503116)
		(width 0.1651)
		(layer "In13.Cu")
		(net "CLK_100M_DB800ZL_SSD15_R_DP")
	)
	(segment
		(start 437.66486 -43.20794)
		(end 437.66486 -60.5663)
		(width 0.1651)
		(layer "In13.Cu")
		(net "CLK_100M_DB800ZL_SSD15_R_DP")
	)
	(segment
		(start 443.9158 -28.893516)
		(end 443.8015 -29.007816)
		(width 0.1651)
		(layer "In13.Cu")
		(net "CLK_100M_DB800ZL_SSD15_R_DP")
	)
	(segment
		(start 339.648292 -95.5802)
		(end 339.436456 -95.368364)
		(width 0.1651)
		(layer "In13.Cu")
		(net "CLK_100M_DB800ZL_SSD15_R_DP")
	)
	(segment
		(start 443.9158 -31.331916)
		(end 443.8015 -31.446216)
		(width 0.1651)
		(layer "In13.Cu")
		(net "CLK_100M_DB800ZL_SSD15_R_DP")
	)
	(segment
		(start 437.66486 -61.7855)
		(end 437.55056 -61.8998)
		(width 0.1651)
		(layer "In13.Cu")
		(net "CLK_100M_DB800ZL_SSD15_R_DP")
	)
	(segment
		(start 443.8015 -31.446216)
		(end 443.8015 -31.941516)
		(width 0.1651)
		(layer "In13.Cu")
		(net "CLK_100M_DB800ZL_SSD15_R_DP")
	)
	(segment
		(start 440.886596 -39.986204)
		(end 440.724798 -39.986204)
		(width 0.1651)
		(layer "In13.Cu")
		(net "CLK_100M_DB800ZL_SSD15_R_DP")
	)
	(segment
		(start 339.436456 -95.368364)
		(end 339.436456 -95.134684)
		(width 0.1651)
		(layer "In13.Cu")
		(net "CLK_100M_DB800ZL_SSD15_R_DP")
	)
	(segment
		(start 436.32501 -66.23939)
		(end 435.535832 -67.028568)
		(width 0.1651)
		(layer "In13.Cu")
		(net "CLK_100M_DB800ZL_SSD15_R_DP")
	)
	(segment
		(start 437.55056 -60.6806)
		(end 437.55056 -61.1759)
		(width 0.1651)
		(layer "In13.Cu")
		(net "CLK_100M_DB800ZL_SSD15_R_DP")
	)
	(segment
		(start 443.8015 -28.283916)
		(end 443.9158 -28.398216)
		(width 0.1651)
		(layer "In13.Cu")
		(net "CLK_100M_DB800ZL_SSD15_R_DP")
	)
	(segment
		(start 443.9158 -30.112716)
		(end 443.8015 -30.227016)
		(width 0.1651)
		(layer "In13.Cu")
		(net "CLK_100M_DB800ZL_SSD15_R_DP")
	)
	(segment
		(start 435.023768 -67.540632)
		(end 423.5196 -79.0448)
		(width 0.1651)
		(layer "In13.Cu")
		(net "CLK_100M_DB800ZL_SSD15_R_DP")
	)
	(segment
		(start 437.32577 -63.52413)
		(end 437.136286 -63.981838)
		(width 0.1651)
		(layer "In13.Cu")
		(net "CLK_100M_DB800ZL_SSD15_R_DP")
	)
	(segment
		(start 437.66486 -62.5094)
		(end 437.66486 -63.0047)
		(width 0.1651)
		(layer "In13.Cu")
		(net "CLK_100M_DB800ZL_SSD15_R_DP")
	)
	(segment
		(start 435.374288 -67.028568)
		(end 435.023768 -67.379088)
		(width 0.1651)
		(layer "In13.Cu")
		(net "CLK_100M_DB800ZL_SSD15_R_DP")
	)
	(segment
		(start 437.136286 -63.981838)
		(end 437.198262 -64.13119)
		(width 0.1651)
		(layer "In13.Cu")
		(net "CLK_100M_DB800ZL_SSD15_R_DP")
	)
	(segment
		(start 439.862468 -40.848534)
		(end 439.511948 -41.199054)
		(width 0.1651)
		(layer "In13.Cu")
		(net "CLK_100M_DB800ZL_SSD15_R_DP")
	)
	(segment
		(start 437.475376 -63.462154)
		(end 437.32577 -63.52413)
		(width 0.1651)
		(layer "In13.Cu")
		(net "CLK_100M_DB800ZL_SSD15_R_DP")
	)
	(segment
		(start 442.961268 -37.749988)
		(end 442.961268 -37.911532)
		(width 0.1651)
		(layer "In13.Cu")
		(net "CLK_100M_DB800ZL_SSD15_R_DP")
	)
	(segment
		(start 443.9158 -27.179016)
		(end 443.9158 -27.674316)
		(width 0.1651)
		(layer "In13.Cu")
		(net "CLK_100M_DB800ZL_SSD15_R_DP")
	)
	(segment
		(start 441.587128 -39.123874)
		(end 441.236608 -39.474394)
		(width 0.1651)
		(layer "In13.Cu")
		(net "CLK_100M_DB800ZL_SSD15_R_DP")
	)
	(segment
		(start 361.897168 -85.362288)
		(end 361.897168 -85.523832)
		(width 0.1651)
		(layer "In13.Cu")
		(net "CLK_100M_DB800ZL_SSD15_R_DP")
	)
	(segment
		(start 443.8015 -31.941516)
		(end 443.9158 -32.055816)
		(width 0.1651)
		(layer "In13.Cu")
		(net "CLK_100M_DB800ZL_SSD15_R_DP")
	)
	(segment
		(start 423.5196 -79.0448)
		(end 367.8682 -79.0448)
		(width 0.1651)
		(layer "In13.Cu")
		(net "CLK_100M_DB800ZL_SSD15_R_DP")
	)
	(segment
		(start 442.611256 -38.261544)
		(end 442.449458 -38.261544)
		(width 0.1651)
		(layer "In13.Cu")
		(net "CLK_100M_DB800ZL_SSD15_R_DP")
	)
	(segment
		(start 442.098938 -38.773862)
		(end 441.748926 -39.123874)
		(width 0.1651)
		(layer "In13.Cu")
		(net "CLK_100M_DB800ZL_SSD15_R_DP")
	)
	(segment
		(start 339.436456 -95.134684)
		(end 339.727286 -94.843854)
		(width 0.1651)
		(layer "In13.Cu")
		(net "CLK_100M_DB800ZL_SSD15_R_DP")
	)
	(segment
		(start 440.724798 -39.986204)
		(end 440.374278 -40.336724)
		(width 0.1651)
		(layer "In13.Cu")
		(net "CLK_100M_DB800ZL_SSD15_R_DP")
	)
	(segment
		(start 366.0902 -81.7626)
		(end 364.0074 -83.8454)
		(width 0.1651)
		(layer "In13.Cu")
		(net "CLK_100M_DB800ZL_SSD15_R_DP")
	)
	(segment
		(start 364.0074 -83.8454)
		(end 363.5756 -83.8454)
		(width 0.1651)
		(layer "In13.Cu")
		(net "CLK_100M_DB800ZL_SSD15_R_DP")
	)
	(segment
		(start 362.409232 -85.011768)
		(end 362.247688 -85.011768)
		(width 0.1651)
		(layer "In13.Cu")
		(net "CLK_100M_DB800ZL_SSD15_R_DP")
	)
	(segment
		(start 436.731664 -65.25768)
		(end 436.32501 -66.23939)
		(width 0.1651)
		(layer "In13.Cu")
		(net "CLK_100M_DB800ZL_SSD15_R_DP")
	)
	(segment
		(start 437.66486 -63.0047)
		(end 437.475376 -63.462154)
		(width 0.1651)
		(layer "In13.Cu")
		(net "CLK_100M_DB800ZL_SSD15_R_DP")
	)
	(segment
		(start 442.098938 -38.612064)
		(end 442.098938 -38.773862)
		(width 0.1651)
		(layer "In13.Cu")
		(net "CLK_100M_DB800ZL_SSD15_R_DP")
	)
	(segment
		(start 443.9158 -27.674316)
		(end 443.8015 -27.788616)
		(width 0.1651)
		(layer "In13.Cu")
		(net "CLK_100M_DB800ZL_SSD15_R_DP")
	)
	(segment
		(start 437.198262 -64.13119)
		(end 437.008778 -64.588644)
		(width 0.1651)
		(layer "In13.Cu")
		(net "CLK_100M_DB800ZL_SSD15_R_DP")
	)
	(segment
		(start 367.8682 -79.0448)
		(end 366.0902 -80.8228)
		(width 0.1651)
		(layer "In13.Cu")
		(net "CLK_100M_DB800ZL_SSD15_R_DP")
	)
	(segment
		(start 363.5756 -83.8454)
		(end 362.409232 -85.011768)
		(width 0.1651)
		(layer "In13.Cu")
		(net "CLK_100M_DB800ZL_SSD15_R_DP")
	)
	(segment
		(start 322.83273 -310.043322)
		(end 322.83273 -310.277002)
		(width 0.13208)
		(layer "F.Cu")
		(net "PEX2_SPARE0")
	)
	(segment
		(start 293.27475 -308.724808)
		(end 292.79977 -308.249828)
		(width 0.13208)
		(layer "F.Cu")
		(net "PEX2_SPARE0")
	)
	(segment
		(start 322.424552 -310.68518)
		(end 322.16471 -310.945022)
		(width 0.13208)
		(layer "F.Cu")
		(net "PEX2_SPARE0")
	)
	(segment
		(start 322.83273 -310.277002)
		(end 322.424552 -310.68518)
		(width 0.13208)
		(layer "F.Cu")
		(net "PEX2_SPARE0")
	)
	(segment
		(start 322.16471 -310.945022)
		(end 321.69735 -310.945022)
		(width 0.13208)
		(layer "F.Cu")
		(net "PEX2_SPARE0")
	)
	(via
		(at 293.27475 -308.724808)
		(size 0.4064)
		(drill 0.2032)
		(layers "F.Cu" "B.Cu")
		(net "PEX2_SPARE0")
	)
	(via
		(at 322.424552 -310.68518)
		(size 0.508)
		(drill 0.254)
		(layers "F.Cu" "B.Cu")
		(net "PEX2_SPARE0")
	)
	(via
		(at 319.366392 -314.33389)
		(size 0.6604)
		(drill 0.3302)
		(layers "F.Cu" "B.Cu")
		(net "PEX2_SPARE0")
	)
	(segment
		(start 294.237664 -315.252862)
		(end 294.364664 -315.379862)
		(width 0.13208)
		(layer "B.Cu")
		(net "PEX2_SPARE0")
	)
	(segment
		(start 294.237664 -309.980584)
		(end 294.237664 -315.252862)
		(width 0.13208)
		(layer "B.Cu")
		(net "PEX2_SPARE0")
	)
	(segment
		(start 293.997126 -309.740046)
		(end 294.237664 -309.980584)
		(width 0.13208)
		(layer "B.Cu")
		(net "PEX2_SPARE0")
	)
	(segment
		(start 322.424552 -311.27573)
		(end 322.424552 -310.68518)
		(width 0.13208)
		(layer "B.Cu")
		(net "PEX2_SPARE0")
	)
	(segment
		(start 294.364664 -315.379862)
		(end 318.32042 -315.379862)
		(width 0.13208)
		(layer "B.Cu")
		(net "PEX2_SPARE0")
	)
	(segment
		(start 293.726616 -309.740046)
		(end 293.997126 -309.740046)
		(width 0.13208)
		(layer "B.Cu")
		(net "PEX2_SPARE0")
	)
	(segment
		(start 319.366392 -314.33389)
		(end 322.424552 -311.27573)
		(width 0.13208)
		(layer "B.Cu")
		(net "PEX2_SPARE0")
	)
	(segment
		(start 318.32042 -315.379862)
		(end 319.366392 -314.33389)
		(width 0.13208)
		(layer "B.Cu")
		(net "PEX2_SPARE0")
	)
	(segment
		(start 293.27475 -309.28818)
		(end 293.726616 -309.740046)
		(width 0.13208)
		(layer "B.Cu")
		(net "PEX2_SPARE0")
	)
	(segment
		(start 293.27475 -308.724808)
		(end 293.27475 -309.28818)
		(width 0.13208)
		(layer "B.Cu")
		(net "PEX2_SPARE0")
	)
	(segment
		(start 365.686848 -85.514942)
		(end 366.2426 -86.070694)
		(width 0.13208)
		(layer "F.Cu")
		(net "SMB_BIC_I2C9_MUX1_SSD14_SDA")
	)
	(segment
		(start 366.2426 -86.070694)
		(end 366.555528 -86.070694)
		(width 0.13208)
		(layer "F.Cu")
		(net "SMB_BIC_I2C9_MUX1_SSD14_SDA")
	)
	(segment
		(start 362.30814 -85.514942)
		(end 365.686848 -85.514942)
		(width 0.13208)
		(layer "F.Cu")
		(net "SMB_BIC_I2C9_MUX1_SSD14_SDA")
	)
	(via
		(at 365.686848 -85.514942)
		(size 0.508)
		(drill 0.254)
		(layers "F.Cu" "B.Cu")
		(net "SMB_BIC_I2C9_MUX1_SSD14_SDA")
	)
	(segment
		(start 346.093796 -225.587052)
		(end 346.493592 -225.986848)
		(width 0.13208)
		(layer "F.Cu")
		(net "SSD5_PWRDIS")
	)
	(via
		(at 346.493592 -225.986848)
		(size 0.4572)
		(drill 0.254)
		(layers "F.Cu" "B.Cu")
		(net "SSD5_PWRDIS")
	)
	(via
		(at 345.694 -229.616)
		(size 0.6604)
		(drill 0.3302)
		(layers "F.Cu" "B.Cu")
		(net "SSD5_PWRDIS")
	)
	(segment
		(start 346.091764 -228.075236)
		(end 345.694 -228.473)
		(width 0.13208)
		(layer "B.Cu")
		(net "SSD5_PWRDIS")
	)
	(segment
		(start 345.694 -231.013)
		(end 345.694 -229.616)
		(width 0.13208)
		(layer "B.Cu")
		(net "SSD5_PWRDIS")
	)
	(segment
		(start 344.043 -232.664)
		(end 345.694 -231.013)
		(width 0.13208)
		(layer "B.Cu")
		(net "SSD5_PWRDIS")
	)
	(segment
		(start 345.694 -228.473)
		(end 345.694 -229.616)
		(width 0.13208)
		(layer "B.Cu")
		(net "SSD5_PWRDIS")
	)
	(segment
		(start 344.043 -233.15295)
		(end 344.043 -232.664)
		(width 0.13208)
		(layer "B.Cu")
		(net "SSD5_PWRDIS")
	)
	(segment
		(start 346.091764 -226.388676)
		(end 346.091764 -228.075236)
		(width 0.0889)
		(layer "B.Cu")
		(net "SSD5_PWRDIS")
	)
	(segment
		(start 346.493592 -225.986848)
		(end 346.091764 -226.388676)
		(width 0.0889)
		(layer "B.Cu")
		(net "SSD5_PWRDIS")
	)
	(segment
		(start 357.097076 -211.328)
		(end 357.61295 -211.328)
		(width 0.13208)
		(layer "F.Cu")
		(net "PRSNT_NIC4_FPGA_N")
	)
	(segment
		(start 354.583492 -212.786976)
		(end 355.6381 -212.786976)
		(width 0.13208)
		(layer "F.Cu")
		(net "PRSNT_NIC4_FPGA_N")
	)
	(segment
		(start 351.6884 -212.786976)
		(end 354.583492 -212.786976)
		(width 0.13208)
		(layer "F.Cu")
		(net "PRSNT_NIC4_FPGA_N")
	)
	(segment
		(start 350.893888 -212.786976)
		(end 351.6884 -212.786976)
		(width 0.0889)
		(layer "F.Cu")
		(net "PRSNT_NIC4_FPGA_N")
	)
	(segment
		(start 355.6381 -212.786976)
		(end 357.097076 -211.328)
		(width 0.13208)
		(layer "F.Cu")
		(net "PRSNT_NIC4_FPGA_N")
	)
	(via
		(at 354.583492 -212.786976)
		(size 0.762)
		(drill 0.381)
		(layers "F.Cu" "B.Cu")
		(net "PRSNT_NIC4_FPGA_N")
	)
	(segment
		(start 398.44726 -53.144166)
		(end 398.630648 -53.144166)
		(width 0.13208)
		(layer "F.Cu")
		(net "P12V_SSD13_SS")
	)
	(segment
		(start 398.78 -52.994814)
		(end 398.78 -51.670966)
		(width 0.13208)
		(layer "F.Cu")
		(net "P12V_SSD13_SS")
	)
	(segment
		(start 398.630648 -53.144166)
		(end 398.78 -52.994814)
		(width 0.13208)
		(layer "F.Cu")
		(net "P12V_SSD13_SS")
	)
	(segment
		(start 399.43151 -51.019456)
		(end 400.167856 -51.019456)
		(width 0.13208)
		(layer "F.Cu")
		(net "P12V_SSD13_SS")
	)
	(segment
		(start 398.78 -51.670966)
		(end 399.43151 -51.019456)
		(width 0.13208)
		(layer "F.Cu")
		(net "P12V_SSD13_SS")
	)
	(via
		(at 399.43151 -51.019456)
		(size 0.508)
		(drill 0.254)
		(layers "F.Cu" "B.Cu")
		(net "P12V_SSD13_SS")
	)
	(segment
		(start 416.06851 -27.189938)
		(end 415.564828 -27.189938)
		(width 0.13462)
		(layer "F.Cu")
		(net "CLK_100M_DB800ZL_SSD14_R_DP")
	)
	(segment
		(start 346.794836 -89.5858)
		(end 347.09989 -89.280746)
		(width 0.13462)
		(layer "F.Cu")
		(net "CLK_100M_DB800ZL_SSD14_R_DP")
	)
	(segment
		(start 417.28136 -27.342846)
		(end 416.964114 -27.0256)
		(width 0.13462)
		(layer "F.Cu")
		(net "CLK_100M_DB800ZL_SSD14_R_DP")
	)
	(segment
		(start 416.964114 -27.0256)
		(end 416.232848 -27.0256)
		(width 0.13462)
		(layer "F.Cu")
		(net "CLK_100M_DB800ZL_SSD14_R_DP")
	)
	(segment
		(start 416.232848 -27.0256)
		(end 416.06851 -27.189938)
		(width 0.13462)
		(layer "F.Cu")
		(net "CLK_100M_DB800ZL_SSD14_R_DP")
	)
	(segment
		(start 345.34348 -89.5858)
		(end 346.794836 -89.5858)
		(width 0.13462)
		(layer "F.Cu")
		(net "CLK_100M_DB800ZL_SSD14_R_DP")
	)
	(segment
		(start 345.013026 -89.255346)
		(end 345.34348 -89.5858)
		(width 0.13462)
		(layer "F.Cu")
		(net "CLK_100M_DB800ZL_SSD14_R_DP")
	)
	(via
		(at 347.09989 -89.280746)
		(size 0.508)
		(drill 0.254)
		(layers "F.Cu" "B.Cu")
		(net "CLK_100M_DB800ZL_SSD14_R_DP")
	)
	(via
		(at 417.28136 -27.342846)
		(size 0.508)
		(drill 0.254)
		(layers "F.Cu" "B.Cu")
		(net "CLK_100M_DB800ZL_SSD14_R_DP")
	)
	(segment
		(start 417.9062 -28.398216)
		(end 417.9062 -28.893516)
		(width 0.1651)
		(layer "In13.Cu")
		(net "CLK_100M_DB800ZL_SSD14_R_DP")
	)
	(segment
		(start 417.7919 -30.722316)
		(end 417.9062 -30.836616)
		(width 0.1651)
		(layer "In13.Cu")
		(net "CLK_100M_DB800ZL_SSD14_R_DP")
	)
	(segment
		(start 417.9062 -33.275016)
		(end 417.9062 -33.770316)
		(width 0.1651)
		(layer "In13.Cu")
		(net "CLK_100M_DB800ZL_SSD14_R_DP")
	)
	(segment
		(start 412.01086 -42.59834)
		(end 412.01086 -60.738766)
		(width 0.1651)
		(layer "In13.Cu")
		(net "CLK_100M_DB800ZL_SSD14_R_DP")
	)
	(segment
		(start 416.53206 -37.915342)
		(end 416.18154 -38.265862)
		(width 0.1651)
		(layer "In13.Cu")
		(net "CLK_100M_DB800ZL_SSD14_R_DP")
	)
	(segment
		(start 417.7792 -27.052016)
		(end 417.9062 -27.179016)
		(width 0.1651)
		(layer "In13.Cu")
		(net "CLK_100M_DB800ZL_SSD14_R_DP")
	)
	(segment
		(start 417.57219 -27.052016)
		(end 417.7792 -27.052016)
		(width 0.1651)
		(layer "In13.Cu")
		(net "CLK_100M_DB800ZL_SSD14_R_DP")
	)
	(segment
		(start 416.693858 -37.915342)
		(end 416.53206 -37.915342)
		(width 0.1651)
		(layer "In13.Cu")
		(net "CLK_100M_DB800ZL_SSD14_R_DP")
	)
	(segment
		(start 417.7919 -32.665416)
		(end 417.7919 -33.160716)
		(width 0.1651)
		(layer "In13.Cu")
		(net "CLK_100M_DB800ZL_SSD14_R_DP")
	)
	(segment
		(start 417.9062 -29.617416)
		(end 417.9062 -30.112716)
		(width 0.1651)
		(layer "In13.Cu")
		(net "CLK_100M_DB800ZL_SSD14_R_DP")
	)
	(segment
		(start 365.8108 -76.327)
		(end 361.9246 -80.2132)
		(width 0.1651)
		(layer "In13.Cu")
		(net "CLK_100M_DB800ZL_SSD14_R_DP")
	)
	(segment
		(start 417.556188 -37.053012)
		(end 417.39439 -37.053012)
		(width 0.1651)
		(layer "In13.Cu")
		(net "CLK_100M_DB800ZL_SSD14_R_DP")
	)
	(segment
		(start 417.39439 -37.053012)
		(end 417.04387 -37.403532)
		(width 0.1651)
		(layer "In13.Cu")
		(net "CLK_100M_DB800ZL_SSD14_R_DP")
	)
	(segment
		(start 350.4692 -87.376)
		(end 348.273624 -89.571576)
		(width 0.1651)
		(layer "In13.Cu")
		(net "CLK_100M_DB800ZL_SSD14_R_DP")
	)
	(segment
		(start 417.9062 -30.836616)
		(end 417.9062 -31.331916)
		(width 0.1651)
		(layer "In13.Cu")
		(net "CLK_100M_DB800ZL_SSD14_R_DP")
	)
	(segment
		(start 347.39072 -89.571576)
		(end 347.09989 -89.280746)
		(width 0.1651)
		(layer "In13.Cu")
		(net "CLK_100M_DB800ZL_SSD14_R_DP")
	)
	(segment
		(start 417.9062 -27.179016)
		(end 417.9062 -27.674316)
		(width 0.1651)
		(layer "In13.Cu")
		(net "CLK_100M_DB800ZL_SSD14_R_DP")
	)
	(segment
		(start 417.9062 -32.551116)
		(end 417.7919 -32.665416)
		(width 0.1651)
		(layer "In13.Cu")
		(net "CLK_100M_DB800ZL_SSD14_R_DP")
	)
	(segment
		(start 416.18154 -38.265862)
		(end 416.18154 -38.42766)
		(width 0.1651)
		(layer "In13.Cu")
		(net "CLK_100M_DB800ZL_SSD14_R_DP")
	)
	(segment
		(start 417.9062 -36.703)
		(end 417.556188 -37.053012)
		(width 0.1651)
		(layer "In13.Cu")
		(net "CLK_100M_DB800ZL_SSD14_R_DP")
	)
	(segment
		(start 417.9062 -27.674316)
		(end 417.7919 -27.788616)
		(width 0.1651)
		(layer "In13.Cu")
		(net "CLK_100M_DB800ZL_SSD14_R_DP")
	)
	(segment
		(start 417.7919 -34.379916)
		(end 417.9062 -34.494216)
		(width 0.1651)
		(layer "In13.Cu")
		(net "CLK_100M_DB800ZL_SSD14_R_DP")
	)
	(segment
		(start 417.9062 -32.055816)
		(end 417.9062 -32.551116)
		(width 0.1651)
		(layer "In13.Cu")
		(net "CLK_100M_DB800ZL_SSD14_R_DP")
	)
	(segment
		(start 417.7919 -30.227016)
		(end 417.7919 -30.722316)
		(width 0.1651)
		(layer "In13.Cu")
		(net "CLK_100M_DB800ZL_SSD14_R_DP")
	)
	(segment
		(start 417.04387 -37.403532)
		(end 417.04387 -37.56533)
		(width 0.1651)
		(layer "In13.Cu")
		(net "CLK_100M_DB800ZL_SSD14_R_DP")
	)
	(segment
		(start 417.7919 -28.283916)
		(end 417.9062 -28.398216)
		(width 0.1651)
		(layer "In13.Cu")
		(net "CLK_100M_DB800ZL_SSD14_R_DP")
	)
	(segment
		(start 417.7919 -33.160716)
		(end 417.9062 -33.275016)
		(width 0.1651)
		(layer "In13.Cu")
		(net "CLK_100M_DB800ZL_SSD14_R_DP")
	)
	(segment
		(start 417.9062 -31.331916)
		(end 417.7919 -31.446216)
		(width 0.1651)
		(layer "In13.Cu")
		(net "CLK_100M_DB800ZL_SSD14_R_DP")
	)
	(segment
		(start 416.18154 -38.42766)
		(end 412.01086 -42.59834)
		(width 0.1651)
		(layer "In13.Cu")
		(net "CLK_100M_DB800ZL_SSD14_R_DP")
	)
	(segment
		(start 417.9062 -33.770316)
		(end 417.7919 -33.884616)
		(width 0.1651)
		(layer "In13.Cu")
		(net "CLK_100M_DB800ZL_SSD14_R_DP")
	)
	(segment
		(start 417.7919 -27.788616)
		(end 417.7919 -28.283916)
		(width 0.1651)
		(layer "In13.Cu")
		(net "CLK_100M_DB800ZL_SSD14_R_DP")
	)
	(segment
		(start 417.9062 -34.989516)
		(end 417.7919 -35.103816)
		(width 0.1651)
		(layer "In13.Cu")
		(net "CLK_100M_DB800ZL_SSD14_R_DP")
	)
	(segment
		(start 417.9062 -35.713416)
		(end 417.9062 -36.703)
		(width 0.1651)
		(layer "In13.Cu")
		(net "CLK_100M_DB800ZL_SSD14_R_DP")
	)
	(segment
		(start 417.7919 -35.599116)
		(end 417.9062 -35.713416)
		(width 0.1651)
		(layer "In13.Cu")
		(net "CLK_100M_DB800ZL_SSD14_R_DP")
	)
	(segment
		(start 417.9062 -34.494216)
		(end 417.9062 -34.989516)
		(width 0.1651)
		(layer "In13.Cu")
		(net "CLK_100M_DB800ZL_SSD14_R_DP")
	)
	(segment
		(start 410.056584 -65.456816)
		(end 399.1864 -76.327)
		(width 0.1651)
		(layer "In13.Cu")
		(net "CLK_100M_DB800ZL_SSD14_R_DP")
	)
	(segment
		(start 399.1864 -76.327)
		(end 365.8108 -76.327)
		(width 0.1651)
		(layer "In13.Cu")
		(net "CLK_100M_DB800ZL_SSD14_R_DP")
	)
	(segment
		(start 417.9062 -30.112716)
		(end 417.7919 -30.227016)
		(width 0.1651)
		(layer "In13.Cu")
		(net "CLK_100M_DB800ZL_SSD14_R_DP")
	)
	(segment
		(start 417.7919 -31.446216)
		(end 417.7919 -31.941516)
		(width 0.1651)
		(layer "In13.Cu")
		(net "CLK_100M_DB800ZL_SSD14_R_DP")
	)
	(segment
		(start 361.9246 -80.2132)
		(end 351.3836 -80.2132)
		(width 0.1651)
		(layer "In13.Cu")
		(net "CLK_100M_DB800ZL_SSD14_R_DP")
	)
	(segment
		(start 417.7919 -31.941516)
		(end 417.9062 -32.055816)
		(width 0.1651)
		(layer "In13.Cu")
		(net "CLK_100M_DB800ZL_SSD14_R_DP")
	)
	(segment
		(start 351.3836 -80.2132)
		(end 350.4692 -81.1276)
		(width 0.1651)
		(layer "In13.Cu")
		(net "CLK_100M_DB800ZL_SSD14_R_DP")
	)
	(segment
		(start 350.4692 -81.1276)
		(end 350.4692 -87.376)
		(width 0.1651)
		(layer "In13.Cu")
		(net "CLK_100M_DB800ZL_SSD14_R_DP")
	)
	(segment
		(start 417.7919 -29.007816)
		(end 417.7919 -29.503116)
		(width 0.1651)
		(layer "In13.Cu")
		(net "CLK_100M_DB800ZL_SSD14_R_DP")
	)
	(segment
		(start 417.7919 -33.884616)
		(end 417.7919 -34.379916)
		(width 0.1651)
		(layer "In13.Cu")
		(net "CLK_100M_DB800ZL_SSD14_R_DP")
	)
	(segment
		(start 417.28136 -27.342846)
		(end 417.57219 -27.052016)
		(width 0.1651)
		(layer "In13.Cu")
		(net "CLK_100M_DB800ZL_SSD14_R_DP")
	)
	(segment
		(start 417.04387 -37.56533)
		(end 416.693858 -37.915342)
		(width 0.1651)
		(layer "In13.Cu")
		(net "CLK_100M_DB800ZL_SSD14_R_DP")
	)
	(segment
		(start 412.01086 -60.738766)
		(end 410.056584 -65.456816)
		(width 0.1651)
		(layer "In13.Cu")
		(net "CLK_100M_DB800ZL_SSD14_R_DP")
	)
	(segment
		(start 417.7919 -29.503116)
		(end 417.9062 -29.617416)
		(width 0.1651)
		(layer "In13.Cu")
		(net "CLK_100M_DB800ZL_SSD14_R_DP")
	)
	(segment
		(start 417.9062 -28.893516)
		(end 417.7919 -29.007816)
		(width 0.1651)
		(layer "In13.Cu")
		(net "CLK_100M_DB800ZL_SSD14_R_DP")
	)
	(segment
		(start 348.273624 -89.571576)
		(end 347.39072 -89.571576)
		(width 0.1651)
		(layer "In13.Cu")
		(net "CLK_100M_DB800ZL_SSD14_R_DP")
	)
	(segment
		(start 417.7919 -35.103816)
		(end 417.7919 -35.599116)
		(width 0.1651)
		(layer "In13.Cu")
		(net "CLK_100M_DB800ZL_SSD14_R_DP")
	)
	(segment
		(start 321.395852 -308.606444)
		(end 321.395852 -308.696106)
		(width 0.13208)
		(layer "F.Cu")
		(net "PEX2_SPARE7")
	)
	(segment
		(start 320.916046 -309.175912)
		(end 320.58356 -309.508398)
		(width 0.13208)
		(layer "F.Cu")
		(net "PEX2_SPARE7")
	)
	(segment
		(start 294.22471 -308.724808)
		(end 293.74973 -308.249828)
		(width 0.13208)
		(layer "F.Cu")
		(net "PEX2_SPARE7")
	)
	(segment
		(start 321.395852 -308.696106)
		(end 320.916046 -309.175912)
		(width 0.13208)
		(layer "F.Cu")
		(net "PEX2_SPARE7")
	)
	(segment
		(start 320.58356 -309.508398)
		(end 320.260218 -309.508398)
		(width 0.13208)
		(layer "F.Cu")
		(net "PEX2_SPARE7")
	)
	(via
		(at 319.90792 -310.184038)
		(size 0.6604)
		(drill 0.3302)
		(layers "F.Cu" "B.Cu")
		(net "PEX2_SPARE7")
	)
	(via
		(at 294.22471 -308.724808)
		(size 0.4064)
		(drill 0.2032)
		(layers "F.Cu" "B.Cu")
		(net "PEX2_SPARE7")
	)
	(via
		(at 320.916046 -309.175912)
		(size 0.508)
		(drill 0.254)
		(layers "F.Cu" "B.Cu")
		(net "PEX2_SPARE7")
	)
	(segment
		(start 296.239692 -313.54522)
		(end 316.546738 -313.54522)
		(width 0.13208)
		(layer "B.Cu")
		(net "PEX2_SPARE7")
	)
	(segment
		(start 295.792144 -309.579772)
		(end 296.112692 -309.90032)
		(width 0.13208)
		(layer "B.Cu")
		(net "PEX2_SPARE7")
	)
	(segment
		(start 295.375838 -309.579772)
		(end 295.792144 -309.579772)
		(width 0.13208)
		(layer "B.Cu")
		(net "PEX2_SPARE7")
	)
	(segment
		(start 319.90792 -310.184038)
		(end 320.916046 -309.175912)
		(width 0.13208)
		(layer "B.Cu")
		(net "PEX2_SPARE7")
	)
	(segment
		(start 316.546738 -313.54522)
		(end 319.90792 -310.184038)
		(width 0.13208)
		(layer "B.Cu")
		(net "PEX2_SPARE7")
	)
	(segment
		(start 294.22471 -308.724808)
		(end 294.520874 -308.724808)
		(width 0.13208)
		(layer "B.Cu")
		(net "PEX2_SPARE7")
	)
	(segment
		(start 296.112692 -313.41822)
		(end 296.239692 -313.54522)
		(width 0.13208)
		(layer "B.Cu")
		(net "PEX2_SPARE7")
	)
	(segment
		(start 294.520874 -308.724808)
		(end 295.375838 -309.579772)
		(width 0.13208)
		(layer "B.Cu")
		(net "PEX2_SPARE7")
	)
	(segment
		(start 296.112692 -309.90032)
		(end 296.112692 -313.41822)
		(width 0.13208)
		(layer "B.Cu")
		(net "PEX2_SPARE7")
	)
	(segment
		(start 362.30814 -86.164928)
		(end 364.277656 -86.164928)
		(width 0.13208)
		(layer "F.Cu")
		(net "SMB_BIC_I2C9_MUX1_SSD14_SCL")
	)
	(segment
		(start 364.277656 -86.164928)
		(end 365.326422 -87.213694)
		(width 0.13208)
		(layer "F.Cu")
		(net "SMB_BIC_I2C9_MUX1_SSD14_SCL")
	)
	(segment
		(start 365.326422 -87.213694)
		(end 366.555528 -87.213694)
		(width 0.13208)
		(layer "F.Cu")
		(net "SMB_BIC_I2C9_MUX1_SSD14_SCL")
	)
	(via
		(at 364.277656 -86.164928)
		(size 0.508)
		(drill 0.254)
		(layers "F.Cu" "B.Cu")
		(net "SMB_BIC_I2C9_MUX1_SSD14_SCL")
	)
	(segment
		(start 117.73662 -61.487812)
		(end 117.3226 -61.901832)
		(width 0.13208)
		(layer "F.Cu")
		(net "PWRGD_P12V_SSD4_R")
	)
	(segment
		(start 117.599206 -64.64046)
		(end 119.741696 -64.64046)
		(width 0.13208)
		(layer "F.Cu")
		(net "PWRGD_P12V_SSD4_R")
	)
	(segment
		(start 120.051322 -64.950086)
		(end 121.348754 -64.950086)
		(width 0.13208)
		(layer "F.Cu")
		(net "PWRGD_P12V_SSD4_R")
	)
	(segment
		(start 119.583708 -61.487812)
		(end 117.73662 -61.487812)
		(width 0.13208)
		(layer "F.Cu")
		(net "PWRGD_P12V_SSD4_R")
	)
	(segment
		(start 122.154188 -65.75552)
		(end 130.828796 -65.75552)
		(width 0.13208)
		(layer "F.Cu")
		(net "PWRGD_P12V_SSD4_R")
	)
	(segment
		(start 142.768066 -53.051456)
		(end 143.423386 -53.051456)
		(width 0.13208)
		(layer "F.Cu")
		(net "PWRGD_P12V_SSD4_R")
	)
	(segment
		(start 119.741696 -64.64046)
		(end 120.051322 -64.950086)
		(width 0.13208)
		(layer "F.Cu")
		(net "PWRGD_P12V_SSD4_R")
	)
	(segment
		(start 344.49385 -225.587052)
		(end 344.8939 -225.987102)
		(width 0.13208)
		(layer "F.Cu")
		(net "PWRGD_P12V_SSD4_R")
	)
	(segment
		(start 121.348754 -64.950086)
		(end 122.154188 -65.75552)
		(width 0.13208)
		(layer "F.Cu")
		(net "PWRGD_P12V_SSD4_R")
	)
	(segment
		(start 117.3226 -61.901832)
		(end 117.3226 -64.363854)
		(width 0.13208)
		(layer "F.Cu")
		(net "PWRGD_P12V_SSD4_R")
	)
	(segment
		(start 117.3226 -64.363854)
		(end 117.599206 -64.64046)
		(width 0.13208)
		(layer "F.Cu")
		(net "PWRGD_P12V_SSD4_R")
	)
	(via
		(at 143.423386 -53.051456)
		(size 0.508)
		(drill 0.254)
		(layers "F.Cu" "B.Cu")
		(net "PWRGD_P12V_SSD4_R")
	)
	(via
		(at 130.828796 -65.75552)
		(size 0.508)
		(drill 0.254)
		(layers "F.Cu" "B.Cu")
		(net "PWRGD_P12V_SSD4_R")
	)
	(via
		(at 344.8939 -225.987102)
		(size 0.4572)
		(drill 0.254)
		(layers "F.Cu" "B.Cu")
		(net "PWRGD_P12V_SSD4_R")
	)
	(via
		(at 150.437088 -222.824548)
		(size 0.508)
		(drill 0.254)
		(layers "F.Cu" "B.Cu")
		(net "PWRGD_P12V_SSD4_R")
	)
	(segment
		(start 141.404086 -163.235894)
		(end 141.404086 -111.046768)
		(width 0.15494)
		(layer "In5.Cu")
		(net "PWRGD_P12V_SSD4_R")
	)
	(segment
		(start 142.53591 -172.07611)
		(end 142.53591 -164.367718)
		(width 0.15494)
		(layer "In5.Cu")
		(net "PWRGD_P12V_SSD4_R")
	)
	(segment
		(start 141.361414 -55.113428)
		(end 143.423386 -53.051456)
		(width 0.15494)
		(layer "In5.Cu")
		(net "PWRGD_P12V_SSD4_R")
	)
	(segment
		(start 150.719282 -222.542354)
		(end 150.719282 -195.28409)
		(width 0.15494)
		(layer "In5.Cu")
		(net "PWRGD_P12V_SSD4_R")
	)
	(segment
		(start 150.719282 -195.28409)
		(end 149.452584 -192.22593)
		(width 0.15494)
		(layer "In5.Cu")
		(net "PWRGD_P12V_SSD4_R")
	)
	(segment
		(start 135.456676 -64.617092)
		(end 141.467586 -64.617092)
		(width 0.15494)
		(layer "In5.Cu")
		(net "PWRGD_P12V_SSD4_R")
	)
	(segment
		(start 142.53591 -164.367718)
		(end 141.404086 -163.235894)
		(width 0.15494)
		(layer "In5.Cu")
		(net "PWRGD_P12V_SSD4_R")
	)
	(segment
		(start 144.221962 -53.850032)
		(end 143.423386 -53.051456)
		(width 0.15494)
		(layer "In5.Cu")
		(net "PWRGD_P12V_SSD4_R")
	)
	(segment
		(start 130.828796 -65.75552)
		(end 134.318248 -65.75552)
		(width 0.15494)
		(layer "In5.Cu")
		(net "PWRGD_P12V_SSD4_R")
	)
	(segment
		(start 141.844014 -64.240664)
		(end 141.844014 -57.983628)
		(width 0.15494)
		(layer "In5.Cu")
		(net "PWRGD_P12V_SSD4_R")
	)
	(segment
		(start 144.221962 -61.783214)
		(end 144.221962 -53.850032)
		(width 0.15494)
		(layer "In5.Cu")
		(net "PWRGD_P12V_SSD4_R")
	)
	(segment
		(start 141.9606 -82.2579)
		(end 143.311372 -80.907128)
		(width 0.15494)
		(layer "In5.Cu")
		(net "PWRGD_P12V_SSD4_R")
	)
	(segment
		(start 141.844014 -57.983628)
		(end 141.361414 -57.501028)
		(width 0.15494)
		(layer "In5.Cu")
		(net "PWRGD_P12V_SSD4_R")
	)
	(segment
		(start 141.361414 -57.501028)
		(end 141.361414 -55.113428)
		(width 0.15494)
		(layer "In5.Cu")
		(net "PWRGD_P12V_SSD4_R")
	)
	(segment
		(start 143.311372 -80.907128)
		(end 143.311372 -62.693804)
		(width 0.15494)
		(layer "In5.Cu")
		(net "PWRGD_P12V_SSD4_R")
	)
	(segment
		(start 150.437088 -222.824548)
		(end 150.719282 -222.542354)
		(width 0.15494)
		(layer "In5.Cu")
		(net "PWRGD_P12V_SSD4_R")
	)
	(segment
		(start 141.9606 -110.490254)
		(end 141.9606 -82.2579)
		(width 0.15494)
		(layer "In5.Cu")
		(net "PWRGD_P12V_SSD4_R")
	)
	(segment
		(start 143.862806 -186.636152)
		(end 143.862806 -173.403006)
		(width 0.15494)
		(layer "In5.Cu")
		(net "PWRGD_P12V_SSD4_R")
	)
	(segment
		(start 141.467586 -64.617092)
		(end 141.844014 -64.240664)
		(width 0.15494)
		(layer "In5.Cu")
		(net "PWRGD_P12V_SSD4_R")
	)
	(segment
		(start 149.452584 -192.22593)
		(end 143.862806 -186.636152)
		(width 0.15494)
		(layer "In5.Cu")
		(net "PWRGD_P12V_SSD4_R")
	)
	(segment
		(start 134.318248 -65.75552)
		(end 135.456676 -64.617092)
		(width 0.15494)
		(layer "In5.Cu")
		(net "PWRGD_P12V_SSD4_R")
	)
	(segment
		(start 141.404086 -111.046768)
		(end 141.9606 -110.490254)
		(width 0.15494)
		(layer "In5.Cu")
		(net "PWRGD_P12V_SSD4_R")
	)
	(segment
		(start 143.862806 -173.403006)
		(end 142.53591 -172.07611)
		(width 0.15494)
		(layer "In5.Cu")
		(net "PWRGD_P12V_SSD4_R")
	)
	(segment
		(start 143.311372 -62.693804)
		(end 144.221962 -61.783214)
		(width 0.15494)
		(layer "In5.Cu")
		(net "PWRGD_P12V_SSD4_R")
	)
	(segment
		(start 161.929826 -229.187756)
		(end 188.507116 -229.187756)
		(width 0.15494)
		(layer "In15.Cu")
		(net "PWRGD_P12V_SSD4_R")
	)
	(segment
		(start 249.150124 -226.76612)
		(end 251.188474 -228.80447)
		(width 0.15494)
		(layer "In15.Cu")
		(net "PWRGD_P12V_SSD4_R")
	)
	(segment
		(start 300.814994 -233.97083)
		(end 301.335694 -233.45013)
		(width 0.15494)
		(layer "In15.Cu")
		(net "PWRGD_P12V_SSD4_R")
	)
	(segment
		(start 336.975958 -232.674922)
		(end 342.22309 -232.674922)
		(width 0.15494)
		(layer "In15.Cu")
		(net "PWRGD_P12V_SSD4_R")
	)
	(segment
		(start 241.638836 -232.20045)
		(end 242.544092 -232.20045)
		(width 0.15494)
		(layer "In15.Cu")
		(net "PWRGD_P12V_SSD4_R")
	)
	(segment
		(start 333.818738 -233.228388)
		(end 336.422492 -233.228388)
		(width 0.15494)
		(layer "In15.Cu")
		(net "PWRGD_P12V_SSD4_R")
	)
	(segment
		(start 155.566618 -222.824548)
		(end 161.929826 -229.187756)
		(width 0.15494)
		(layer "In15.Cu")
		(net "PWRGD_P12V_SSD4_R")
	)
	(segment
		(start 261.675372 -228.13264)
		(end 261.858252 -227.94976)
		(width 0.15494)
		(layer "In15.Cu")
		(net "PWRGD_P12V_SSD4_R")
	)
	(segment
		(start 344.491056 -226.389946)
		(end 344.8939 -225.987102)
		(width 0.0889)
		(layer "In15.Cu")
		(net "PWRGD_P12V_SSD4_R")
	)
	(segment
		(start 240.13668 -233.702606)
		(end 241.638836 -232.20045)
		(width 0.15494)
		(layer "In15.Cu")
		(net "PWRGD_P12V_SSD4_R")
	)
	(segment
		(start 333.523082 -233.524044)
		(end 333.818738 -233.228388)
		(width 0.15494)
		(layer "In15.Cu")
		(net "PWRGD_P12V_SSD4_R")
	)
	(segment
		(start 264.892282 -227.94976)
		(end 270.913352 -233.97083)
		(width 0.15494)
		(layer "In15.Cu")
		(net "PWRGD_P12V_SSD4_R")
	)
	(segment
		(start 244.485668 -230.258874)
		(end 244.485668 -229.253034)
		(width 0.15494)
		(layer "In15.Cu")
		(net "PWRGD_P12V_SSD4_R")
	)
	(segment
		(start 150.437088 -222.824548)
		(end 155.566618 -222.824548)
		(width 0.15494)
		(layer "In15.Cu")
		(net "PWRGD_P12V_SSD4_R")
	)
	(segment
		(start 301.838614 -233.45013)
		(end 302.522636 -234.134152)
		(width 0.15494)
		(layer "In15.Cu")
		(net "PWRGD_P12V_SSD4_R")
	)
	(segment
		(start 323.11975 -235.189522)
		(end 326.19823 -235.189522)
		(width 0.15494)
		(layer "In15.Cu")
		(net "PWRGD_P12V_SSD4_R")
	)
	(segment
		(start 251.188474 -228.80447)
		(end 251.88418 -228.80447)
		(width 0.15494)
		(layer "In15.Cu")
		(net "PWRGD_P12V_SSD4_R")
	)
	(segment
		(start 302.522636 -234.134152)
		(end 322.06438 -234.134152)
		(width 0.15494)
		(layer "In15.Cu")
		(net "PWRGD_P12V_SSD4_R")
	)
	(segment
		(start 344.491056 -227.466144)
		(end 344.491056 -226.389946)
		(width 0.0889)
		(layer "In15.Cu")
		(net "PWRGD_P12V_SSD4_R")
	)
	(segment
		(start 258.592828 -227.4951)
		(end 259.230368 -228.13264)
		(width 0.15494)
		(layer "In15.Cu")
		(net "PWRGD_P12V_SSD4_R")
	)
	(segment
		(start 336.422492 -233.228388)
		(end 336.975958 -232.674922)
		(width 0.15494)
		(layer "In15.Cu")
		(net "PWRGD_P12V_SSD4_R")
	)
	(segment
		(start 331.556106 -233.524044)
		(end 333.523082 -233.524044)
		(width 0.15494)
		(layer "In15.Cu")
		(net "PWRGD_P12V_SSD4_R")
	)
	(segment
		(start 188.507116 -229.187756)
		(end 193.021966 -233.702606)
		(width 0.15494)
		(layer "In15.Cu")
		(net "PWRGD_P12V_SSD4_R")
	)
	(segment
		(start 344.491056 -230.406956)
		(end 344.491056 -227.466144)
		(width 0.15494)
		(layer "In15.Cu")
		(net "PWRGD_P12V_SSD4_R")
	)
	(segment
		(start 259.230368 -228.13264)
		(end 261.675372 -228.13264)
		(width 0.15494)
		(layer "In15.Cu")
		(net "PWRGD_P12V_SSD4_R")
	)
	(segment
		(start 322.06438 -234.134152)
		(end 323.11975 -235.189522)
		(width 0.15494)
		(layer "In15.Cu")
		(net "PWRGD_P12V_SSD4_R")
	)
	(segment
		(start 246.972582 -226.76612)
		(end 249.150124 -226.76612)
		(width 0.15494)
		(layer "In15.Cu")
		(net "PWRGD_P12V_SSD4_R")
	)
	(segment
		(start 244.485668 -229.253034)
		(end 246.972582 -226.76612)
		(width 0.15494)
		(layer "In15.Cu")
		(net "PWRGD_P12V_SSD4_R")
	)
	(segment
		(start 270.913352 -233.97083)
		(end 300.814994 -233.97083)
		(width 0.15494)
		(layer "In15.Cu")
		(net "PWRGD_P12V_SSD4_R")
	)
	(segment
		(start 342.22309 -232.674922)
		(end 344.491056 -230.406956)
		(width 0.15494)
		(layer "In15.Cu")
		(net "PWRGD_P12V_SSD4_R")
	)
	(segment
		(start 327.117202 -234.27055)
		(end 329.753468 -234.27055)
		(width 0.15494)
		(layer "In15.Cu")
		(net "PWRGD_P12V_SSD4_R")
	)
	(segment
		(start 193.021966 -233.702606)
		(end 240.13668 -233.702606)
		(width 0.15494)
		(layer "In15.Cu")
		(net "PWRGD_P12V_SSD4_R")
	)
	(segment
		(start 301.335694 -233.45013)
		(end 301.838614 -233.45013)
		(width 0.15494)
		(layer "In15.Cu")
		(net "PWRGD_P12V_SSD4_R")
	)
	(segment
		(start 329.753468 -234.27055)
		(end 331.556106 -233.524044)
		(width 0.15494)
		(layer "In15.Cu")
		(net "PWRGD_P12V_SSD4_R")
	)
	(segment
		(start 326.19823 -235.189522)
		(end 327.117202 -234.27055)
		(width 0.15494)
		(layer "In15.Cu")
		(net "PWRGD_P12V_SSD4_R")
	)
	(segment
		(start 261.858252 -227.94976)
		(end 264.892282 -227.94976)
		(width 0.15494)
		(layer "In15.Cu")
		(net "PWRGD_P12V_SSD4_R")
	)
	(segment
		(start 251.88418 -228.80447)
		(end 253.19355 -227.4951)
		(width 0.15494)
		(layer "In15.Cu")
		(net "PWRGD_P12V_SSD4_R")
	)
	(segment
		(start 242.544092 -232.20045)
		(end 244.485668 -230.258874)
		(width 0.15494)
		(layer "In15.Cu")
		(net "PWRGD_P12V_SSD4_R")
	)
	(segment
		(start 253.19355 -227.4951)
		(end 258.592828 -227.4951)
		(width 0.15494)
		(layer "In15.Cu")
		(net "PWRGD_P12V_SSD4_R")
	)
	(segment
		(start 373.901462 -53.051456)
		(end 374.167908 -53.051456)
		(width 0.13208)
		(layer "F.Cu")
		(net "PWRGD_P12V_SSD12")
	)
	(segment
		(start 372.447312 -53.644038)
		(end 372.816374 -53.644038)
		(width 0.13208)
		(layer "F.Cu")
		(net "PWRGD_P12V_SSD12")
	)
	(segment
		(start 373.437404 -52.587398)
		(end 373.901462 -53.051456)
		(width 0.13208)
		(layer "F.Cu")
		(net "PWRGD_P12V_SSD12")
	)
	(segment
		(start 372.816374 -53.644038)
		(end 373.437404 -53.023008)
		(width 0.13208)
		(layer "F.Cu")
		(net "PWRGD_P12V_SSD12")
	)
	(segment
		(start 374.167908 -52.035456)
		(end 374.167908 -53.051456)
		(width 0.13208)
		(layer "F.Cu")
		(net "PWRGD_P12V_SSD12")
	)
	(segment
		(start 373.437404 -53.023008)
		(end 373.437404 -52.587398)
		(width 0.13208)
		(layer "F.Cu")
		(net "PWRGD_P12V_SSD12")
	)
	(via
		(at 373.437404 -52.587398)
		(size 0.508)
		(drill 0.254)
		(layers "F.Cu" "B.Cu")
		(net "PWRGD_P12V_SSD12")
	)
	(via
		(at 125.84938 -214.444834)
		(size 0.508)
		(drill 0.254)
		(layers "F.Cu" "B.Cu")
		(net "UART_PEX2_CLI_R_TX")
	)
	(via
		(at 310.849772 -290.199826)
		(size 0.6604)
		(drill 0.3302)
		(layers "F.Cu" "B.Cu")
		(net "UART_PEX2_CLI_R_TX")
	)
	(via
		(at 269.417292 -236.631226)
		(size 0.508)
		(drill 0.254)
		(layers "F.Cu" "B.Cu")
		(net "UART_PEX2_CLI_R_TX")
	)
	(via
		(at 265.92022 -202.325478)
		(size 0.508)
		(drill 0.254)
		(layers "F.Cu" "B.Cu")
		(net "UART_PEX2_CLI_R_TX")
	)
	(segment
		(start 310.379872 -281.0002)
		(end 310.379872 -270.670528)
		(width 0.13208)
		(layer "B.Cu")
		(net "UART_PEX2_CLI_R_TX")
	)
	(segment
		(start 310.981344 -281.1272)
		(end 310.506872 -281.1272)
		(width 0.13208)
		(layer "B.Cu")
		(net "UART_PEX2_CLI_R_TX")
	)
	(segment
		(start 285.204154 -250.255532)
		(end 285.199328 -250.250706)
		(width 0.13208)
		(layer "B.Cu")
		(net "UART_PEX2_CLI_R_TX")
	)
	(segment
		(start 310.603138 -291.224716)
		(end 307.923692 -291.224716)
		(width 0.13208)
		(layer "B.Cu")
		(net "UART_PEX2_CLI_R_TX")
	)
	(segment
		(start 311.349644 -281.4955)
		(end 310.981344 -281.1272)
		(width 0.13208)
		(layer "B.Cu")
		(net "UART_PEX2_CLI_R_TX")
	)
	(segment
		(start 318.320166 -260.04393)
		(end 295.104566 -260.04393)
		(width 0.13208)
		(layer "B.Cu")
		(net "UART_PEX2_CLI_R_TX")
	)
	(segment
		(start 310.849772 -290.199826)
		(end 310.849772 -290.978082)
		(width 0.13208)
		(layer "B.Cu")
		(net "UART_PEX2_CLI_R_TX")
	)
	(segment
		(start 283.036772 -250.250706)
		(end 269.417292 -236.631226)
		(width 0.13208)
		(layer "B.Cu")
		(net "UART_PEX2_CLI_R_TX")
	)
	(segment
		(start 310.506872 -281.1272)
		(end 310.379872 -281.0002)
		(width 0.13208)
		(layer "B.Cu")
		(net "UART_PEX2_CLI_R_TX")
	)
	(segment
		(start 295.104566 -260.04393)
		(end 285.316168 -250.255532)
		(width 0.13208)
		(layer "B.Cu")
		(net "UART_PEX2_CLI_R_TX")
	)
	(segment
		(start 318.62395 -262.42645)
		(end 318.62395 -260.347714)
		(width 0.13208)
		(layer "B.Cu")
		(net "UART_PEX2_CLI_R_TX")
	)
	(segment
		(start 311.349644 -288.797746)
		(end 311.349644 -281.4955)
		(width 0.13208)
		(layer "B.Cu")
		(net "UART_PEX2_CLI_R_TX")
	)
	(segment
		(start 285.316168 -250.255532)
		(end 285.204154 -250.255532)
		(width 0.13208)
		(layer "B.Cu")
		(net "UART_PEX2_CLI_R_TX")
	)
	(segment
		(start 318.62395 -260.347714)
		(end 318.320166 -260.04393)
		(width 0.13208)
		(layer "B.Cu")
		(net "UART_PEX2_CLI_R_TX")
	)
	(segment
		(start 310.849772 -290.199826)
		(end 310.849772 -289.297618)
		(width 0.13208)
		(layer "B.Cu")
		(net "UART_PEX2_CLI_R_TX")
	)
	(segment
		(start 126.986538 -214.444834)
		(end 125.84938 -214.444834)
		(width 0.13208)
		(layer "B.Cu")
		(net "UART_PEX2_CLI_R_TX")
	)
	(segment
		(start 285.199328 -250.250706)
		(end 283.036772 -250.250706)
		(width 0.13208)
		(layer "B.Cu")
		(net "UART_PEX2_CLI_R_TX")
	)
	(segment
		(start 310.849772 -290.978082)
		(end 310.603138 -291.224716)
		(width 0.13208)
		(layer "B.Cu")
		(net "UART_PEX2_CLI_R_TX")
	)
	(segment
		(start 310.379872 -270.670528)
		(end 318.62395 -262.42645)
		(width 0.13208)
		(layer "B.Cu")
		(net "UART_PEX2_CLI_R_TX")
	)
	(segment
		(start 310.849772 -289.297618)
		(end 311.349644 -288.797746)
		(width 0.13208)
		(layer "B.Cu")
		(net "UART_PEX2_CLI_R_TX")
	)
	(segment
		(start 269.417292 -235.483908)
		(end 269.417292 -236.631226)
		(width 0.15494)
		(layer "In5.Cu")
		(net "UART_PEX2_CLI_R_TX")
	)
	(segment
		(start 269.921482 -234.979718)
		(end 269.417292 -235.483908)
		(width 0.15494)
		(layer "In5.Cu")
		(net "UART_PEX2_CLI_R_TX")
	)
	(segment
		(start 265.92022 -202.325478)
		(end 269.921482 -206.32674)
		(width 0.15494)
		(layer "In5.Cu")
		(net "UART_PEX2_CLI_R_TX")
	)
	(segment
		(start 269.921482 -206.32674)
		(end 269.921482 -234.979718)
		(width 0.15494)
		(layer "In5.Cu")
		(net "UART_PEX2_CLI_R_TX")
	)
	(segment
		(start 246.4562 -202.1078)
		(end 247.3452 -202.9968)
		(width 0.15494)
		(layer "In15.Cu")
		(net "UART_PEX2_CLI_R_TX")
	)
	(segment
		(start 128.350518 -214.444834)
		(end 130.943604 -217.03792)
		(width 0.15494)
		(layer "In15.Cu")
		(net "UART_PEX2_CLI_R_TX")
	)
	(segment
		(start 212.370416 -208.913984)
		(end 212.771736 -208.913984)
		(width 0.15494)
		(layer "In15.Cu")
		(net "UART_PEX2_CLI_R_TX")
	)
	(segment
		(start 125.84938 -214.444834)
		(end 128.350518 -214.444834)
		(width 0.15494)
		(layer "In15.Cu")
		(net "UART_PEX2_CLI_R_TX")
	)
	(segment
		(start 205.865222 -208.81213)
		(end 207.567276 -208.81213)
		(width 0.15494)
		(layer "In15.Cu")
		(net "UART_PEX2_CLI_R_TX")
	)
	(segment
		(start 194.357752 -220.3196)
		(end 205.865222 -208.81213)
		(width 0.15494)
		(layer "In15.Cu")
		(net "UART_PEX2_CLI_R_TX")
	)
	(segment
		(start 245.465854 -202.1078)
		(end 246.4562 -202.1078)
		(width 0.15494)
		(layer "In15.Cu")
		(net "UART_PEX2_CLI_R_TX")
	)
	(segment
		(start 216.053924 -208.71561)
		(end 218.99499 -208.71561)
		(width 0.15494)
		(layer "In15.Cu")
		(net "UART_PEX2_CLI_R_TX")
	)
	(segment
		(start 207.567276 -208.81213)
		(end 208.355946 -209.6008)
		(width 0.15494)
		(layer "In15.Cu")
		(net "UART_PEX2_CLI_R_TX")
	)
	(segment
		(start 185.851292 -220.3196)
		(end 194.357752 -220.3196)
		(width 0.15494)
		(layer "In15.Cu")
		(net "UART_PEX2_CLI_R_TX")
	)
	(segment
		(start 244.7798 -202.793854)
		(end 245.465854 -202.1078)
		(width 0.15494)
		(layer "In15.Cu")
		(net "UART_PEX2_CLI_R_TX")
	)
	(segment
		(start 256.387346 -203.708)
		(end 256.791206 -203.30414)
		(width 0.15494)
		(layer "In15.Cu")
		(net "UART_PEX2_CLI_R_TX")
	)
	(segment
		(start 244.321584 -204.064362)
		(end 244.7798 -203.606146)
		(width 0.15494)
		(layer "In15.Cu")
		(net "UART_PEX2_CLI_R_TX")
	)
	(segment
		(start 259.89534 -202.9968)
		(end 265.248898 -202.9968)
		(width 0.15494)
		(layer "In15.Cu")
		(net "UART_PEX2_CLI_R_TX")
	)
	(segment
		(start 219.15501 -208.55559)
		(end 238.482886 -208.55559)
		(width 0.15494)
		(layer "In15.Cu")
		(net "UART_PEX2_CLI_R_TX")
	)
	(segment
		(start 140.924026 -215.773)
		(end 144.182592 -215.773)
		(width 0.15494)
		(layer "In15.Cu")
		(net "UART_PEX2_CLI_R_TX")
	)
	(segment
		(start 212.771736 -208.913984)
		(end 213.228174 -209.370422)
		(width 0.15494)
		(layer "In15.Cu")
		(net "UART_PEX2_CLI_R_TX")
	)
	(segment
		(start 247.3452 -202.9968)
		(end 248.74855 -202.9968)
		(width 0.15494)
		(layer "In15.Cu")
		(net "UART_PEX2_CLI_R_TX")
	)
	(segment
		(start 238.482886 -208.55559)
		(end 238.918496 -208.9912)
		(width 0.15494)
		(layer "In15.Cu")
		(net "UART_PEX2_CLI_R_TX")
	)
	(segment
		(start 265.248898 -202.9968)
		(end 265.92022 -202.325478)
		(width 0.15494)
		(layer "In15.Cu")
		(net "UART_PEX2_CLI_R_TX")
	)
	(segment
		(start 256.791206 -203.30414)
		(end 259.588 -203.30414)
		(width 0.15494)
		(layer "In15.Cu")
		(net "UART_PEX2_CLI_R_TX")
	)
	(segment
		(start 248.74855 -202.9968)
		(end 248.80824 -203.05649)
		(width 0.15494)
		(layer "In15.Cu")
		(net "UART_PEX2_CLI_R_TX")
	)
	(segment
		(start 259.588 -203.30414)
		(end 259.89534 -202.9968)
		(width 0.15494)
		(layer "In15.Cu")
		(net "UART_PEX2_CLI_R_TX")
	)
	(segment
		(start 211.6836 -209.6008)
		(end 212.370416 -208.913984)
		(width 0.15494)
		(layer "In15.Cu")
		(net "UART_PEX2_CLI_R_TX")
	)
	(segment
		(start 215.248236 -208.685638)
		(end 216.023952 -208.685638)
		(width 0.15494)
		(layer "In15.Cu")
		(net "UART_PEX2_CLI_R_TX")
	)
	(segment
		(start 248.80824 -203.05649)
		(end 252.99289 -203.05649)
		(width 0.15494)
		(layer "In15.Cu")
		(net "UART_PEX2_CLI_R_TX")
	)
	(segment
		(start 244.321584 -206.095854)
		(end 244.321584 -204.064362)
		(width 0.15494)
		(layer "In15.Cu")
		(net "UART_PEX2_CLI_R_TX")
	)
	(segment
		(start 130.943604 -217.03792)
		(end 139.659106 -217.03792)
		(width 0.15494)
		(layer "In15.Cu")
		(net "UART_PEX2_CLI_R_TX")
	)
	(segment
		(start 244.7798 -203.606146)
		(end 244.7798 -202.793854)
		(width 0.15494)
		(layer "In15.Cu")
		(net "UART_PEX2_CLI_R_TX")
	)
	(segment
		(start 181.533292 -216.0016)
		(end 185.851292 -220.3196)
		(width 0.15494)
		(layer "In15.Cu")
		(net "UART_PEX2_CLI_R_TX")
	)
	(segment
		(start 144.411192 -216.0016)
		(end 181.533292 -216.0016)
		(width 0.15494)
		(layer "In15.Cu")
		(net "UART_PEX2_CLI_R_TX")
	)
	(segment
		(start 216.023952 -208.685638)
		(end 216.053924 -208.71561)
		(width 0.15494)
		(layer "In15.Cu")
		(net "UART_PEX2_CLI_R_TX")
	)
	(segment
		(start 238.918496 -208.9912)
		(end 241.426238 -208.9912)
		(width 0.15494)
		(layer "In15.Cu")
		(net "UART_PEX2_CLI_R_TX")
	)
	(segment
		(start 213.228174 -209.370422)
		(end 214.563452 -209.370422)
		(width 0.15494)
		(layer "In15.Cu")
		(net "UART_PEX2_CLI_R_TX")
	)
	(segment
		(start 241.426238 -208.9912)
		(end 244.321584 -206.095854)
		(width 0.15494)
		(layer "In15.Cu")
		(net "UART_PEX2_CLI_R_TX")
	)
	(segment
		(start 208.355946 -209.6008)
		(end 211.6836 -209.6008)
		(width 0.15494)
		(layer "In15.Cu")
		(net "UART_PEX2_CLI_R_TX")
	)
	(segment
		(start 252.99289 -203.05649)
		(end 253.6444 -203.708)
		(width 0.15494)
		(layer "In15.Cu")
		(net "UART_PEX2_CLI_R_TX")
	)
	(segment
		(start 144.182592 -215.773)
		(end 144.411192 -216.0016)
		(width 0.15494)
		(layer "In15.Cu")
		(net "UART_PEX2_CLI_R_TX")
	)
	(segment
		(start 139.659106 -217.03792)
		(end 140.924026 -215.773)
		(width 0.15494)
		(layer "In15.Cu")
		(net "UART_PEX2_CLI_R_TX")
	)
	(segment
		(start 253.6444 -203.708)
		(end 256.387346 -203.708)
		(width 0.15494)
		(layer "In15.Cu")
		(net "UART_PEX2_CLI_R_TX")
	)
	(segment
		(start 218.99499 -208.71561)
		(end 219.15501 -208.55559)
		(width 0.15494)
		(layer "In15.Cu")
		(net "UART_PEX2_CLI_R_TX")
	)
	(segment
		(start 214.563452 -209.370422)
		(end 215.248236 -208.685638)
		(width 0.15494)
		(layer "In15.Cu")
		(net "UART_PEX2_CLI_R_TX")
	)
	(segment
		(start 301.181262 -26.479246)
		(end 300.888908 -26.7716)
		(width 0.13462)
		(layer "F.Cu")
		(net "CLK_100M_DB800ZL_SSD10_R_DN")
	)
	(segment
		(start 300.888908 -26.7716)
		(end 300.136306 -26.7716)
		(width 0.13462)
		(layer "F.Cu")
		(net "CLK_100M_DB800ZL_SSD10_R_DN")
	)
	(segment
		(start 300.136306 -26.7716)
		(end 299.954696 -26.58999)
		(width 0.13462)
		(layer "F.Cu")
		(net "CLK_100M_DB800ZL_SSD10_R_DN")
	)
	(segment
		(start 339.75294 -80.207612)
		(end 339.44052 -79.895192)
		(width 0.13462)
		(layer "F.Cu")
		(net "CLK_100M_DB800ZL_SSD10_R_DN")
	)
	(segment
		(start 339.44052 -79.895192)
		(end 339.44052 -79.169768)
		(width 0.13462)
		(layer "F.Cu")
		(net "CLK_100M_DB800ZL_SSD10_R_DN")
	)
	(segment
		(start 339.44052 -79.169768)
		(end 339.72754 -78.882748)
		(width 0.13462)
		(layer "F.Cu")
		(net "CLK_100M_DB800ZL_SSD10_R_DN")
	)
	(segment
		(start 299.954696 -26.58999)
		(end 299.46473 -26.58999)
		(width 0.13462)
		(layer "F.Cu")
		(net "CLK_100M_DB800ZL_SSD10_R_DN")
	)
	(via
		(at 339.72754 -78.882748)
		(size 0.508)
		(drill 0.254)
		(layers "F.Cu" "B.Cu")
		(net "CLK_100M_DB800ZL_SSD10_R_DN")
	)
	(via
		(at 301.181262 -26.479246)
		(size 0.508)
		(drill 0.254)
		(layers "F.Cu" "B.Cu")
		(net "CLK_100M_DB800ZL_SSD10_R_DN")
	)
	(segment
		(start 319.66662 -47.78502)
		(end 309.4736 -37.592)
		(width 0.1651)
		(layer "In13.Cu")
		(net "CLK_100M_DB800ZL_SSD10_R_DN")
	)
	(segment
		(start 309.4736 -30.5816)
		(end 307.0098 -28.1178)
		(width 0.1651)
		(layer "In13.Cu")
		(net "CLK_100M_DB800ZL_SSD10_R_DN")
	)
	(segment
		(start 335.534 -63.9572)
		(end 325.1962 -63.9572)
		(width 0.1651)
		(layer "In13.Cu")
		(net "CLK_100M_DB800ZL_SSD10_R_DN")
	)
	(segment
		(start 304.28184 -27.07386)
		(end 303.46904 -27.07386)
		(width 0.1651)
		(layer "In13.Cu")
		(net "CLK_100M_DB800ZL_SSD10_R_DN")
	)
	(segment
		(start 325.1962 -63.9572)
		(end 322.0466 -60.8076)
		(width 0.1651)
		(layer "In13.Cu")
		(net "CLK_100M_DB800ZL_SSD10_R_DN")
	)
	(segment
		(start 339.43671 -67.85991)
		(end 335.534 -63.9572)
		(width 0.1651)
		(layer "In13.Cu")
		(net "CLK_100M_DB800ZL_SSD10_R_DN")
	)
	(segment
		(start 303.165256 -26.770076)
		(end 301.472092 -26.770076)
		(width 0.1651)
		(layer "In13.Cu")
		(net "CLK_100M_DB800ZL_SSD10_R_DN")
	)
	(segment
		(start 339.72754 -78.882748)
		(end 339.43671 -78.591918)
		(width 0.1651)
		(layer "In13.Cu")
		(net "CLK_100M_DB800ZL_SSD10_R_DN")
	)
	(segment
		(start 339.43671 -78.591918)
		(end 339.43671 -67.85991)
		(width 0.1651)
		(layer "In13.Cu")
		(net "CLK_100M_DB800ZL_SSD10_R_DN")
	)
	(segment
		(start 322.0466 -60.8076)
		(end 322.0466 -51.346862)
		(width 0.1651)
		(layer "In13.Cu")
		(net "CLK_100M_DB800ZL_SSD10_R_DN")
	)
	(segment
		(start 322.0466 -51.346862)
		(end 319.66662 -47.78502)
		(width 0.1651)
		(layer "In13.Cu")
		(net "CLK_100M_DB800ZL_SSD10_R_DN")
	)
	(segment
		(start 307.0098 -28.1178)
		(end 305.32578 -28.1178)
		(width 0.1651)
		(layer "In13.Cu")
		(net "CLK_100M_DB800ZL_SSD10_R_DN")
	)
	(segment
		(start 305.32578 -28.1178)
		(end 304.28184 -27.07386)
		(width 0.1651)
		(layer "In13.Cu")
		(net "CLK_100M_DB800ZL_SSD10_R_DN")
	)
	(segment
		(start 301.472092 -26.770076)
		(end 301.181262 -26.479246)
		(width 0.1651)
		(layer "In13.Cu")
		(net "CLK_100M_DB800ZL_SSD10_R_DN")
	)
	(segment
		(start 309.4736 -37.592)
		(end 309.4736 -30.5816)
		(width 0.1651)
		(layer "In13.Cu")
		(net "CLK_100M_DB800ZL_SSD10_R_DN")
	)
	(segment
		(start 303.46904 -27.07386)
		(end 303.165256 -26.770076)
		(width 0.1651)
		(layer "In13.Cu")
		(net "CLK_100M_DB800ZL_SSD10_R_DN")
	)
	(segment
		(start 323.709284 -311.969404)
		(end 323.709284 -312.131456)
		(width 0.13208)
		(layer "F.Cu")
		(net "PEX2_SPARE5")
	)
	(segment
		(start 323.062346 -312.6105)
		(end 322.415916 -311.96407)
		(width 0.13208)
		(layer "F.Cu")
		(net "PEX2_SPARE5")
	)
	(segment
		(start 292.32479 -308.724808)
		(end 291.84981 -309.199788)
		(width 0.13462)
		(layer "F.Cu")
		(net "PEX2_SPARE5")
	)
	(segment
		(start 323.177154 -312.6105)
		(end 323.062346 -312.6105)
		(width 0.13208)
		(layer "F.Cu")
		(net "PEX2_SPARE5")
	)
	(segment
		(start 323.23024 -312.6105)
		(end 323.177154 -312.6105)
		(width 0.13208)
		(layer "F.Cu")
		(net "PEX2_SPARE5")
	)
	(segment
		(start 323.709284 -312.131456)
		(end 323.23024 -312.6105)
		(width 0.13208)
		(layer "F.Cu")
		(net "PEX2_SPARE5")
	)
	(segment
		(start 323.709284 -311.969404)
		(end 323.780404 -311.969404)
		(width 0.13208)
		(layer "F.Cu")
		(net "PEX2_SPARE5")
	)
	(segment
		(start 322.415916 -311.96407)
		(end 322.415916 -311.663588)
		(width 0.13208)
		(layer "F.Cu")
		(net "PEX2_SPARE5")
	)
	(segment
		(start 323.780404 -311.969404)
		(end 324.269608 -311.4802)
		(width 0.13208)
		(layer "F.Cu")
		(net "PEX2_SPARE5")
	)
	(via
		(at 292.32479 -308.724808)
		(size 0.4064)
		(drill 0.2032)
		(layers "F.Cu" "B.Cu")
		(net "PEX2_SPARE5")
	)
	(via
		(at 323.709284 -311.969404)
		(size 0.508)
		(drill 0.254)
		(layers "F.Cu" "B.Cu")
		(net "PEX2_SPARE5")
	)
	(via
		(at 323.177154 -312.6105)
		(size 0.762)
		(drill 0.381)
		(layers "F.Cu" "B.Cu")
		(net "PEX2_SPARE5")
	)
	(segment
		(start 321.747134 -313.27852)
		(end 322.400168 -313.27852)
		(width 0.13208)
		(layer "B.Cu")
		(net "PEX2_SPARE5")
	)
	(segment
		(start 314.135008 -320.890646)
		(end 321.747134 -313.27852)
		(width 0.13208)
		(layer "B.Cu")
		(net "PEX2_SPARE5")
	)
	(segment
		(start 292.32479 -308.724808)
		(end 292.32479 -320.605404)
		(width 0.13208)
		(layer "B.Cu")
		(net "PEX2_SPARE5")
	)
	(segment
		(start 322.400168 -313.27852)
		(end 323.709284 -311.969404)
		(width 0.13208)
		(layer "B.Cu")
		(net "PEX2_SPARE5")
	)
	(segment
		(start 292.32479 -320.605404)
		(end 292.610032 -320.890646)
		(width 0.13208)
		(layer "B.Cu")
		(net "PEX2_SPARE5")
	)
	(segment
		(start 292.610032 -320.890646)
		(end 314.135008 -320.890646)
		(width 0.13208)
		(layer "B.Cu")
		(net "PEX2_SPARE5")
	)
	(segment
		(start 367.437924 -86.50605)
		(end 367.355628 -86.423754)
		(width 0.13208)
		(layer "F.Cu")
		(net "SMB_BIC_I2C9_MUX1_SSD14_R_SDA")
	)
	(segment
		(start 368.354356 -86.070694)
		(end 367.919 -86.50605)
		(width 0.13208)
		(layer "F.Cu")
		(net "SMB_BIC_I2C9_MUX1_SSD14_R_SDA")
	)
	(segment
		(start 427.762416 -22.097492)
		(end 427.520608 -21.855684)
		(width 0.13208)
		(layer "F.Cu")
		(net "SMB_BIC_I2C9_MUX1_SSD14_R_SDA")
	)
	(segment
		(start 427.23562 -21.570696)
		(end 427.23562 -20.789392)
		(width 0.13208)
		(layer "F.Cu")
		(net "SMB_BIC_I2C9_MUX1_SSD14_R_SDA")
	)
	(segment
		(start 427.520608 -21.855684)
		(end 427.23562 -21.570696)
		(width 0.13208)
		(layer "F.Cu")
		(net "SMB_BIC_I2C9_MUX1_SSD14_R_SDA")
	)
	(segment
		(start 367.919 -86.50605)
		(end 367.437924 -86.50605)
		(width 0.13208)
		(layer "F.Cu")
		(net "SMB_BIC_I2C9_MUX1_SSD14_R_SDA")
	)
	(segment
		(start 427.762416 -22.537166)
		(end 427.762416 -22.097492)
		(width 0.13208)
		(layer "F.Cu")
		(net "SMB_BIC_I2C9_MUX1_SSD14_R_SDA")
	)
	(segment
		(start 369.095528 -86.070694)
		(end 368.354356 -86.070694)
		(width 0.13208)
		(layer "F.Cu")
		(net "SMB_BIC_I2C9_MUX1_SSD14_R_SDA")
	)
	(segment
		(start 367.355628 -86.423754)
		(end 367.355628 -86.070694)
		(width 0.13208)
		(layer "F.Cu")
		(net "SMB_BIC_I2C9_MUX1_SSD14_R_SDA")
	)
	(via
		(at 367.919 -86.50605)
		(size 0.508)
		(drill 0.254)
		(layers "F.Cu" "B.Cu")
		(net "SMB_BIC_I2C9_MUX1_SSD14_R_SDA")
	)
	(via
		(at 427.520608 -21.855684)
		(size 0.508)
		(drill 0.254)
		(layers "F.Cu" "B.Cu")
		(net "SMB_BIC_I2C9_MUX1_SSD14_R_SDA")
	)
	(via
		(at 432.716686 -72.97928)
		(size 0.508)
		(drill 0.254)
		(layers "F.Cu" "B.Cu")
		(net "SMB_BIC_I2C9_MUX1_SSD14_R_SDA")
	)
	(segment
		(start 424.556936 -27.244548)
		(end 424.556936 -22.049994)
		(width 0.15494)
		(layer "In5.Cu")
		(net "SMB_BIC_I2C9_MUX1_SSD14_R_SDA")
	)
	(segment
		(start 437.509666 -45.416724)
		(end 424.617896 -32.524954)
		(width 0.15494)
		(layer "In5.Cu")
		(net "SMB_BIC_I2C9_MUX1_SSD14_R_SDA")
	)
	(segment
		(start 424.617896 -32.524954)
		(end 424.617896 -30.088586)
		(width 0.15494)
		(layer "In5.Cu")
		(net "SMB_BIC_I2C9_MUX1_SSD14_R_SDA")
	)
	(segment
		(start 425.315126 -21.291804)
		(end 426.956728 -21.291804)
		(width 0.15494)
		(layer "In5.Cu")
		(net "SMB_BIC_I2C9_MUX1_SSD14_R_SDA")
	)
	(segment
		(start 424.617896 -30.088586)
		(end 425.378626 -29.327856)
		(width 0.15494)
		(layer "In5.Cu")
		(net "SMB_BIC_I2C9_MUX1_SSD14_R_SDA")
	)
	(segment
		(start 425.378626 -29.327856)
		(end 425.378626 -28.066238)
		(width 0.15494)
		(layer "In5.Cu")
		(net "SMB_BIC_I2C9_MUX1_SSD14_R_SDA")
	)
	(segment
		(start 432.716686 -72.97928)
		(end 437.509666 -68.1863)
		(width 0.15494)
		(layer "In5.Cu")
		(net "SMB_BIC_I2C9_MUX1_SSD14_R_SDA")
	)
	(segment
		(start 424.556936 -22.049994)
		(end 425.315126 -21.291804)
		(width 0.15494)
		(layer "In5.Cu")
		(net "SMB_BIC_I2C9_MUX1_SSD14_R_SDA")
	)
	(segment
		(start 437.509666 -68.1863)
		(end 437.509666 -45.416724)
		(width 0.15494)
		(layer "In5.Cu")
		(net "SMB_BIC_I2C9_MUX1_SSD14_R_SDA")
	)
	(segment
		(start 425.378626 -28.066238)
		(end 424.556936 -27.244548)
		(width 0.15494)
		(layer "In5.Cu")
		(net "SMB_BIC_I2C9_MUX1_SSD14_R_SDA")
	)
	(segment
		(start 426.956728 -21.291804)
		(end 427.520608 -21.855684)
		(width 0.15494)
		(layer "In5.Cu")
		(net "SMB_BIC_I2C9_MUX1_SSD14_R_SDA")
	)
	(segment
		(start 369.826794 -85.447886)
		(end 370.927376 -85.447886)
		(width 0.15494)
		(layer "In15.Cu")
		(net "SMB_BIC_I2C9_MUX1_SSD14_R_SDA")
	)
	(segment
		(start 375.664222 -78.258924)
		(end 424.485562 -78.258924)
		(width 0.15494)
		(layer "In15.Cu")
		(net "SMB_BIC_I2C9_MUX1_SSD14_R_SDA")
	)
	(segment
		(start 430.960276 -74.116438)
		(end 432.097434 -72.97928)
		(width 0.15494)
		(layer "In15.Cu")
		(net "SMB_BIC_I2C9_MUX1_SSD14_R_SDA")
	)
	(segment
		(start 369.203986 -86.070694)
		(end 369.826794 -85.447886)
		(width 0.15494)
		(layer "In15.Cu")
		(net "SMB_BIC_I2C9_MUX1_SSD14_R_SDA")
	)
	(segment
		(start 424.485562 -78.258924)
		(end 428.628048 -74.116438)
		(width 0.15494)
		(layer "In15.Cu")
		(net "SMB_BIC_I2C9_MUX1_SSD14_R_SDA")
	)
	(segment
		(start 372.289324 -84.085938)
		(end 372.289324 -81.633822)
		(width 0.15494)
		(layer "In15.Cu")
		(net "SMB_BIC_I2C9_MUX1_SSD14_R_SDA")
	)
	(segment
		(start 368.354356 -86.070694)
		(end 369.203986 -86.070694)
		(width 0.15494)
		(layer "In15.Cu")
		(net "SMB_BIC_I2C9_MUX1_SSD14_R_SDA")
	)
	(segment
		(start 367.919 -86.50605)
		(end 368.354356 -86.070694)
		(width 0.15494)
		(layer "In15.Cu")
		(net "SMB_BIC_I2C9_MUX1_SSD14_R_SDA")
	)
	(segment
		(start 428.628048 -74.116438)
		(end 430.960276 -74.116438)
		(width 0.15494)
		(layer "In15.Cu")
		(net "SMB_BIC_I2C9_MUX1_SSD14_R_SDA")
	)
	(segment
		(start 372.289324 -81.633822)
		(end 375.664222 -78.258924)
		(width 0.15494)
		(layer "In15.Cu")
		(net "SMB_BIC_I2C9_MUX1_SSD14_R_SDA")
	)
	(segment
		(start 370.927376 -85.447886)
		(end 372.289324 -84.085938)
		(width 0.15494)
		(layer "In15.Cu")
		(net "SMB_BIC_I2C9_MUX1_SSD14_R_SDA")
	)
	(segment
		(start 432.097434 -72.97928)
		(end 432.716686 -72.97928)
		(width 0.15494)
		(layer "In15.Cu")
		(net "SMB_BIC_I2C9_MUX1_SSD14_R_SDA")
	)
	(segment
		(start 344.918792 -240.291112)
		(end 344.918792 -238.465868)
		(width 0.13208)
		(layer "F.Cu")
		(net "SSD0_PWRDIS")
	)
	(segment
		(start 341.293958 -223.987106)
		(end 340.894162 -224.386902)
		(width 0.13208)
		(layer "F.Cu")
		(net "SSD0_PWRDIS")
	)
	(via
		(at 340.894162 -224.386902)
		(size 0.4572)
		(drill 0.254)
		(layers "F.Cu" "B.Cu")
		(net "SSD0_PWRDIS")
	)
	(via
		(at 344.918792 -238.465868)
		(size 0.508)
		(drill 0.254)
		(layers "F.Cu" "B.Cu")
		(net "SSD0_PWRDIS")
	)
	(segment
		(start 341.97798 -224.788476)
		(end 341.810086 -224.788476)
		(width 0.15494)
		(layer "In5.Cu")
		(net "SSD0_PWRDIS")
	)
	(segment
		(start 341.810086 -224.788476)
		(end 341.295736 -224.788476)
		(width 0.0889)
		(layer "In5.Cu")
		(net "SSD0_PWRDIS")
	)
	(segment
		(start 343.546684 -232.928414)
		(end 342.436958 -231.818688)
		(width 0.15494)
		(layer "In5.Cu")
		(net "SSD0_PWRDIS")
	)
	(segment
		(start 342.436958 -225.247454)
		(end 341.97798 -224.788476)
		(width 0.15494)
		(layer "In5.Cu")
		(net "SSD0_PWRDIS")
	)
	(segment
		(start 343.546684 -237.09376)
		(end 343.546684 -232.928414)
		(width 0.15494)
		(layer "In5.Cu")
		(net "SSD0_PWRDIS")
	)
	(segment
		(start 342.436958 -231.818688)
		(end 342.436958 -225.247454)
		(width 0.15494)
		(layer "In5.Cu")
		(net "SSD0_PWRDIS")
	)
	(segment
		(start 344.918792 -238.465868)
		(end 343.546684 -237.09376)
		(width 0.15494)
		(layer "In5.Cu")
		(net "SSD0_PWRDIS")
	)
	(segment
		(start 341.295736 -224.788476)
		(end 340.894162 -224.386902)
		(width 0.0889)
		(layer "In5.Cu")
		(net "SSD0_PWRDIS")
	)
	(segment
		(start 355.45395 -166.624)
		(end 354.838 -166.624)
		(width 0.13208)
		(layer "F.Cu")
		(net "NIC5_PEX_PWR_EN_R")
	)
	(segment
		(start 355.45395 -165.608)
		(end 355.45395 -166.624)
		(width 0.13208)
		(layer "F.Cu")
		(net "NIC5_PEX_PWR_EN_R")
	)
	(segment
		(start 346.893896 -215.187022)
		(end 347.293692 -214.787226)
		(width 0.13208)
		(layer "F.Cu")
		(net "NIC5_PEX_PWR_EN_R")
	)
	(segment
		(start 354.838 -166.624)
		(end 354.22205 -166.624)
		(width 0.13208)
		(layer "F.Cu")
		(net "NIC5_PEX_PWR_EN_R")
	)
	(via
		(at 354.838 -166.624)
		(size 0.508)
		(drill 0.254)
		(layers "F.Cu" "B.Cu")
		(net "NIC5_PEX_PWR_EN_R")
	)
	(via
		(at 347.293692 -214.787226)
		(size 0.4572)
		(drill 0.254)
		(layers "F.Cu" "B.Cu")
		(net "NIC5_PEX_PWR_EN_R")
	)
	(via
		(at 362.180886 -175.54448)
		(size 0.508)
		(drill 0.254)
		(layers "F.Cu" "B.Cu")
		(net "NIC5_PEX_PWR_EN_R")
	)
	(segment
		(start 362.180886 -175.54448)
		(end 361.157774 -176.567592)
		(width 0.15494)
		(layer "In9.Cu")
		(net "NIC5_PEX_PWR_EN_R")
	)
	(segment
		(start 356.123494 -202.582526)
		(end 356.123494 -203.03363)
		(width 0.15494)
		(layer "In9.Cu")
		(net "NIC5_PEX_PWR_EN_R")
	)
	(segment
		(start 355.71049 -203.446634)
		(end 355.71049 -206.479394)
		(width 0.15494)
		(layer "In9.Cu")
		(net "NIC5_PEX_PWR_EN_R")
	)
	(segment
		(start 361.157774 -176.567592)
		(end 361.157774 -189.917578)
		(width 0.15494)
		(layer "In9.Cu")
		(net "NIC5_PEX_PWR_EN_R")
	)
	(segment
		(start 359.619804 -191.455548)
		(end 359.619804 -199.086216)
		(width 0.15494)
		(layer "In9.Cu")
		(net "NIC5_PEX_PWR_EN_R")
	)
	(segment
		(start 352.738436 -209.451448)
		(end 348.662752 -209.451448)
		(width 0.15494)
		(layer "In9.Cu")
		(net "NIC5_PEX_PWR_EN_R")
	)
	(segment
		(start 355.71049 -206.479394)
		(end 352.738436 -209.451448)
		(width 0.15494)
		(layer "In9.Cu")
		(net "NIC5_PEX_PWR_EN_R")
	)
	(segment
		(start 361.157774 -189.917578)
		(end 359.619804 -191.455548)
		(width 0.15494)
		(layer "In9.Cu")
		(net "NIC5_PEX_PWR_EN_R")
	)
	(segment
		(start 356.123494 -203.03363)
		(end 355.71049 -203.446634)
		(width 0.15494)
		(layer "In9.Cu")
		(net "NIC5_PEX_PWR_EN_R")
	)
	(segment
		(start 359.619804 -199.086216)
		(end 356.123494 -202.582526)
		(width 0.15494)
		(layer "In9.Cu")
		(net "NIC5_PEX_PWR_EN_R")
	)
	(segment
		(start 348.662752 -209.451448)
		(end 347.696028 -210.418172)
		(width 0.15494)
		(layer "In9.Cu")
		(net "NIC5_PEX_PWR_EN_R")
	)
	(segment
		(start 347.696028 -210.418172)
		(end 347.696028 -214.38489)
		(width 0.0889)
		(layer "In9.Cu")
		(net "NIC5_PEX_PWR_EN_R")
	)
	(segment
		(start 347.696028 -214.38489)
		(end 347.293692 -214.787226)
		(width 0.0889)
		(layer "In9.Cu")
		(net "NIC5_PEX_PWR_EN_R")
	)
	(segment
		(start 354.838 -166.948104)
		(end 354.838 -166.624)
		(width 0.15494)
		(layer "In13.Cu")
		(net "NIC5_PEX_PWR_EN_R")
	)
	(segment
		(start 356.571296 -168.6814)
		(end 354.838 -166.948104)
		(width 0.15494)
		(layer "In13.Cu")
		(net "NIC5_PEX_PWR_EN_R")
	)
	(segment
		(start 357.784654 -168.6814)
		(end 356.571296 -168.6814)
		(width 0.15494)
		(layer "In13.Cu")
		(net "NIC5_PEX_PWR_EN_R")
	)
	(segment
		(start 362.180886 -173.077632)
		(end 357.784654 -168.6814)
		(width 0.15494)
		(layer "In13.Cu")
		(net "NIC5_PEX_PWR_EN_R")
	)
	(segment
		(start 362.180886 -175.54448)
		(end 362.180886 -173.077632)
		(width 0.15494)
		(layer "In13.Cu")
		(net "NIC5_PEX_PWR_EN_R")
	)
	(segment
		(start 377.2662 -245.9482)
		(end 377.2662 -241.528346)
		(width 0.13208)
		(layer "F.Cu")
		(net "UART_PEX3_SDB_BUF_TX")
	)
	(segment
		(start 377.2662 -241.528346)
		(end 377.983496 -240.81105)
		(width 0.13208)
		(layer "F.Cu")
		(net "UART_PEX3_SDB_BUF_TX")
	)
	(segment
		(start 378.333 -247.015)
		(end 377.2662 -245.9482)
		(width 0.13208)
		(layer "F.Cu")
		(net "UART_PEX3_SDB_BUF_TX")
	)
	(segment
		(start 377.983496 -240.81105)
		(end 378.880624 -240.81105)
		(width 0.13208)
		(layer "F.Cu")
		(net "UART_PEX3_SDB_BUF_TX")
	)
	(via
		(at 378.333 -247.015)
		(size 0.508)
		(drill 0.254)
		(layers "F.Cu" "B.Cu")
		(net "UART_PEX3_SDB_BUF_TX")
	)
	(segment
		(start 378.388372 -248.203974)
		(end 378.388372 -247.070372)
		(width 0.13208)
		(layer "B.Cu")
		(net "UART_PEX3_SDB_BUF_TX")
	)
	(segment
		(start 379.366272 -248.203974)
		(end 378.388372 -248.203974)
		(width 0.13208)
		(layer "B.Cu")
		(net "UART_PEX3_SDB_BUF_TX")
	)
	(segment
		(start 378.388372 -247.070372)
		(end 378.333 -247.015)
		(width 0.13208)
		(layer "B.Cu")
		(net "UART_PEX3_SDB_BUF_TX")
	)
	(segment
		(start 304.199798 -292.099746)
		(end 304.674778 -291.624766)
		(width 0.13208)
		(layer "F.Cu")
		(net "UART_PEX2_CLI_TX")
	)
	(via
		(at 304.674778 -291.624766)
		(size 0.4064)
		(drill 0.2032)
		(layers "F.Cu" "B.Cu")
		(net "UART_PEX2_CLI_TX")
	)
	(via
		(at 305.149758 -292.099746)
		(size 0.6604)
		(drill 0.3302)
		(layers "F.Cu" "B.Cu")
		(net "UART_PEX2_CLI_TX")
	)
	(segment
		(start 307.040788 -292.024816)
		(end 307.923692 -292.024816)
		(width 0.13208)
		(layer "B.Cu")
		(net "UART_PEX2_CLI_TX")
	)
	(segment
		(start 305.149758 -292.099746)
		(end 306.965858 -292.099746)
		(width 0.13208)
		(layer "B.Cu")
		(net "UART_PEX2_CLI_TX")
	)
	(segment
		(start 304.674778 -291.624766)
		(end 305.149758 -292.099746)
		(width 0.13208)
		(layer "B.Cu")
		(net "UART_PEX2_CLI_TX")
	)
	(segment
		(start 306.965858 -292.099746)
		(end 307.040788 -292.024816)
		(width 0.13208)
		(layer "B.Cu")
		(net "UART_PEX2_CLI_TX")
	)
	(segment
		(start 346.807536 -85.852)
		(end 347.09989 -86.144354)
		(width 0.13462)
		(layer "F.Cu")
		(net "CLK_100M_DB800ZL_SSD12_R_DN")
	)
	(segment
		(start 364.216188 -26.75128)
		(end 364.054898 -26.58999)
		(width 0.13462)
		(layer "F.Cu")
		(net "CLK_100M_DB800ZL_SSD12_R_DN")
	)
	(segment
		(start 345.33078 -85.852)
		(end 346.807536 -85.852)
		(width 0.13462)
		(layer "F.Cu")
		(net "CLK_100M_DB800ZL_SSD12_R_DN")
	)
	(segment
		(start 365.00943 -26.75128)
		(end 364.216188 -26.75128)
		(width 0.13462)
		(layer "F.Cu")
		(net "CLK_100M_DB800ZL_SSD12_R_DN")
	)
	(segment
		(start 364.054898 -26.58999)
		(end 363.564932 -26.58999)
		(width 0.13462)
		(layer "F.Cu")
		(net "CLK_100M_DB800ZL_SSD12_R_DN")
	)
	(segment
		(start 365.281464 -26.479246)
		(end 365.00943 -26.75128)
		(width 0.13462)
		(layer "F.Cu")
		(net "CLK_100M_DB800ZL_SSD12_R_DN")
	)
	(segment
		(start 345.013026 -86.169754)
		(end 345.33078 -85.852)
		(width 0.13462)
		(layer "F.Cu")
		(net "CLK_100M_DB800ZL_SSD12_R_DN")
	)
	(via
		(at 365.281464 -26.479246)
		(size 0.508)
		(drill 0.254)
		(layers "F.Cu" "B.Cu")
		(net "CLK_100M_DB800ZL_SSD12_R_DN")
	)
	(via
		(at 347.09989 -86.144354)
		(size 0.508)
		(drill 0.254)
		(layers "F.Cu" "B.Cu")
		(net "CLK_100M_DB800ZL_SSD12_R_DN")
	)
	(segment
		(start 353.02444 -78.56474)
		(end 360.93654 -70.65264)
		(width 0.1651)
		(layer "In13.Cu")
		(net "CLK_100M_DB800ZL_SSD12_R_DN")
	)
	(segment
		(start 365.572294 -26.770076)
		(end 365.281464 -26.479246)
		(width 0.1651)
		(layer "In13.Cu")
		(net "CLK_100M_DB800ZL_SSD12_R_DN")
	)
	(segment
		(start 347.74124 -85.853524)
		(end 348.31274 -85.282024)
		(width 0.1651)
		(layer "In13.Cu")
		(net "CLK_100M_DB800ZL_SSD12_R_DN")
	)
	(segment
		(start 348.31274 -80.50784)
		(end 350.25584 -78.56474)
		(width 0.1651)
		(layer "In13.Cu")
		(net "CLK_100M_DB800ZL_SSD12_R_DN")
	)
	(segment
		(start 360.93654 -42.05224)
		(end 366.268 -36.72078)
		(width 0.1651)
		(layer "In13.Cu")
		(net "CLK_100M_DB800ZL_SSD12_R_DN")
	)
	(segment
		(start 366.268 -36.72078)
		(end 366.268 -27.127454)
		(width 0.1651)
		(layer "In13.Cu")
		(net "CLK_100M_DB800ZL_SSD12_R_DN")
	)
	(segment
		(start 366.268 -27.127454)
		(end 365.910622 -26.770076)
		(width 0.1651)
		(layer "In13.Cu")
		(net "CLK_100M_DB800ZL_SSD12_R_DN")
	)
	(segment
		(start 360.93654 -70.65264)
		(end 360.93654 -42.05224)
		(width 0.1651)
		(layer "In13.Cu")
		(net "CLK_100M_DB800ZL_SSD12_R_DN")
	)
	(segment
		(start 350.25584 -78.56474)
		(end 353.02444 -78.56474)
		(width 0.1651)
		(layer "In13.Cu")
		(net "CLK_100M_DB800ZL_SSD12_R_DN")
	)
	(segment
		(start 365.910622 -26.770076)
		(end 365.572294 -26.770076)
		(width 0.1651)
		(layer "In13.Cu")
		(net "CLK_100M_DB800ZL_SSD12_R_DN")
	)
	(segment
		(start 347.09989 -86.144354)
		(end 347.39072 -85.853524)
		(width 0.1651)
		(layer "In13.Cu")
		(net "CLK_100M_DB800ZL_SSD12_R_DN")
	)
	(segment
		(start 348.31274 -85.282024)
		(end 348.31274 -80.50784)
		(width 0.1651)
		(layer "In13.Cu")
		(net "CLK_100M_DB800ZL_SSD12_R_DN")
	)
	(segment
		(start 347.39072 -85.853524)
		(end 347.74124 -85.853524)
		(width 0.1651)
		(layer "In13.Cu")
		(net "CLK_100M_DB800ZL_SSD12_R_DN")
	)
	(segment
		(start 287.099756 -309.199788)
		(end 287.574736 -308.724808)
		(width 0.13208)
		(layer "F.Cu")
		(net "PU_PEX2_TR_TCK")
	)
	(segment
		(start 262.863076 -312.557922)
		(end 260.023864 -312.557922)
		(width 0.13208)
		(layer "F.Cu")
		(net "PU_PEX2_TR_TCK")
	)
	(segment
		(start 260.023864 -312.557922)
		(end 259.022596 -311.556654)
		(width 0.13208)
		(layer "F.Cu")
		(net "PU_PEX2_TR_TCK")
	)
	(segment
		(start 266.62888 -313.669934)
		(end 265.54811 -313.669934)
		(width 0.13208)
		(layer "F.Cu")
		(net "PU_PEX2_TR_TCK")
	)
	(segment
		(start 265.54811 -313.669934)
		(end 262.863076 -312.557922)
		(width 0.13208)
		(layer "F.Cu")
		(net "PU_PEX2_TR_TCK")
	)
	(via
		(at 266.62888 -313.669934)
		(size 0.508)
		(drill 0.254)
		(layers "F.Cu" "B.Cu")
		(net "PU_PEX2_TR_TCK")
	)
	(via
		(at 287.574736 -308.724808)
		(size 0.4064)
		(drill 0.2032)
		(layers "F.Cu" "B.Cu")
		(net "PU_PEX2_TR_TCK")
	)
	(segment
		(start 266.62888 -314.381134)
		(end 267.588746 -315.341)
		(width 0.13208)
		(layer "B.Cu")
		(net "PU_PEX2_TR_TCK")
	)
	(segment
		(start 287.574736 -315.014864)
		(end 287.574736 -308.724808)
		(width 0.13208)
		(layer "B.Cu")
		(net "PU_PEX2_TR_TCK")
	)
	(segment
		(start 287.2486 -315.341)
		(end 287.574736 -315.014864)
		(width 0.13208)
		(layer "B.Cu")
		(net "PU_PEX2_TR_TCK")
	)
	(segment
		(start 266.62888 -313.669934)
		(end 266.62888 -314.381134)
		(width 0.13208)
		(layer "B.Cu")
		(net "PU_PEX2_TR_TCK")
	)
	(segment
		(start 267.588746 -315.341)
		(end 287.2486 -315.341)
		(width 0.13208)
		(layer "B.Cu")
		(net "PU_PEX2_TR_TCK")
	)
	(segment
		(start 452.61784 -21.775674)
		(end 452.585328 -21.743162)
		(width 0.13208)
		(layer "F.Cu")
		(net "SMB_BIC_I2C9_MUX1_SSD15_R_SCL")
	)
	(segment
		(start 367.355628 -89.499694)
		(end 368.06124 -89.499694)
		(width 0.13208)
		(layer "F.Cu")
		(net "SMB_BIC_I2C9_MUX1_SSD15_R_SCL")
	)
	(segment
		(start 368.06124 -89.499694)
		(end 369.095528 -89.499694)
		(width 0.13208)
		(layer "F.Cu")
		(net "SMB_BIC_I2C9_MUX1_SSD15_R_SCL")
	)
	(segment
		(start 452.585328 -21.743162)
		(end 452.585328 -20.789392)
		(width 0.13208)
		(layer "F.Cu")
		(net "SMB_BIC_I2C9_MUX1_SSD15_R_SCL")
	)
	(segment
		(start 452.759318 -22.555454)
		(end 452.61784 -22.413976)
		(width 0.13208)
		(layer "F.Cu")
		(net "SMB_BIC_I2C9_MUX1_SSD15_R_SCL")
	)
	(segment
		(start 452.61784 -22.413976)
		(end 452.61784 -21.775674)
		(width 0.13208)
		(layer "F.Cu")
		(net "SMB_BIC_I2C9_MUX1_SSD15_R_SCL")
	)
	(via
		(at 452.61784 -21.775674)
		(size 0.508)
		(drill 0.254)
		(layers "F.Cu" "B.Cu")
		(net "SMB_BIC_I2C9_MUX1_SSD15_R_SCL")
	)
	(via
		(at 368.06124 -89.499694)
		(size 0.508)
		(drill 0.254)
		(layers "F.Cu" "B.Cu")
		(net "SMB_BIC_I2C9_MUX1_SSD15_R_SCL")
	)
	(via
		(at 458.519784 -76.441808)
		(size 0.508)
		(drill 0.254)
		(layers "F.Cu" "B.Cu")
		(net "SMB_BIC_I2C9_MUX1_SSD15_R_SCL")
	)
	(segment
		(start 452.14286 -29.99359)
		(end 451.077584 -31.058866)
		(width 0.15494)
		(layer "In5.Cu")
		(net "SMB_BIC_I2C9_MUX1_SSD15_R_SCL")
	)
	(segment
		(start 451.077584 -31.058866)
		(end 451.077584 -32.219646)
		(width 0.15494)
		(layer "In5.Cu")
		(net "SMB_BIC_I2C9_MUX1_SSD15_R_SCL")
	)
	(segment
		(start 451.57771 -21.775674)
		(end 451.006464 -22.34692)
		(width 0.15494)
		(layer "In5.Cu")
		(net "SMB_BIC_I2C9_MUX1_SSD15_R_SCL")
	)
	(segment
		(start 451.006464 -26.787094)
		(end 452.14286 -27.92349)
		(width 0.15494)
		(layer "In5.Cu")
		(net "SMB_BIC_I2C9_MUX1_SSD15_R_SCL")
	)
	(segment
		(start 451.006464 -22.34692)
		(end 451.006464 -26.787094)
		(width 0.15494)
		(layer "In5.Cu")
		(net "SMB_BIC_I2C9_MUX1_SSD15_R_SCL")
	)
	(segment
		(start 452.61784 -21.775674)
		(end 451.57771 -21.775674)
		(width 0.15494)
		(layer "In5.Cu")
		(net "SMB_BIC_I2C9_MUX1_SSD15_R_SCL")
	)
	(segment
		(start 456.96251 -38.104572)
		(end 456.96251 -71.788782)
		(width 0.15494)
		(layer "In5.Cu")
		(net "SMB_BIC_I2C9_MUX1_SSD15_R_SCL")
	)
	(segment
		(start 458.952092 -73.778364)
		(end 458.952092 -76.0095)
		(width 0.15494)
		(layer "In5.Cu")
		(net "SMB_BIC_I2C9_MUX1_SSD15_R_SCL")
	)
	(segment
		(start 458.952092 -76.0095)
		(end 458.519784 -76.441808)
		(width 0.15494)
		(layer "In5.Cu")
		(net "SMB_BIC_I2C9_MUX1_SSD15_R_SCL")
	)
	(segment
		(start 451.077584 -32.219646)
		(end 456.96251 -38.104572)
		(width 0.15494)
		(layer "In5.Cu")
		(net "SMB_BIC_I2C9_MUX1_SSD15_R_SCL")
	)
	(segment
		(start 452.14286 -27.92349)
		(end 452.14286 -29.99359)
		(width 0.15494)
		(layer "In5.Cu")
		(net "SMB_BIC_I2C9_MUX1_SSD15_R_SCL")
	)
	(segment
		(start 456.96251 -71.788782)
		(end 458.952092 -73.778364)
		(width 0.15494)
		(layer "In5.Cu")
		(net "SMB_BIC_I2C9_MUX1_SSD15_R_SCL")
	)
	(segment
		(start 429.28921 -75.879198)
		(end 457.957174 -75.879198)
		(width 0.15494)
		(layer "In15.Cu")
		(net "SMB_BIC_I2C9_MUX1_SSD15_R_SCL")
	)
	(segment
		(start 370.84635 -88.957912)
		(end 373.776494 -86.027768)
		(width 0.15494)
		(layer "In15.Cu")
		(net "SMB_BIC_I2C9_MUX1_SSD15_R_SCL")
	)
	(segment
		(start 369.710208 -89.499694)
		(end 370.25199 -88.957912)
		(width 0.15494)
		(layer "In15.Cu")
		(net "SMB_BIC_I2C9_MUX1_SSD15_R_SCL")
	)
	(segment
		(start 373.776494 -82.097372)
		(end 376.028204 -79.845662)
		(width 0.15494)
		(layer "In15.Cu")
		(net "SMB_BIC_I2C9_MUX1_SSD15_R_SCL")
	)
	(segment
		(start 457.957174 -75.879198)
		(end 458.519784 -76.441808)
		(width 0.15494)
		(layer "In15.Cu")
		(net "SMB_BIC_I2C9_MUX1_SSD15_R_SCL")
	)
	(segment
		(start 420.142924 -79.845662)
		(end 420.804086 -80.506824)
		(width 0.15494)
		(layer "In15.Cu")
		(net "SMB_BIC_I2C9_MUX1_SSD15_R_SCL")
	)
	(segment
		(start 370.25199 -88.957912)
		(end 370.84635 -88.957912)
		(width 0.15494)
		(layer "In15.Cu")
		(net "SMB_BIC_I2C9_MUX1_SSD15_R_SCL")
	)
	(segment
		(start 422.144952 -79.972154)
		(end 425.196254 -79.972154)
		(width 0.15494)
		(layer "In15.Cu")
		(net "SMB_BIC_I2C9_MUX1_SSD15_R_SCL")
	)
	(segment
		(start 421.610282 -80.506824)
		(end 422.144952 -79.972154)
		(width 0.15494)
		(layer "In15.Cu")
		(net "SMB_BIC_I2C9_MUX1_SSD15_R_SCL")
	)
	(segment
		(start 420.804086 -80.506824)
		(end 421.610282 -80.506824)
		(width 0.15494)
		(layer "In15.Cu")
		(net "SMB_BIC_I2C9_MUX1_SSD15_R_SCL")
	)
	(segment
		(start 376.028204 -79.845662)
		(end 420.142924 -79.845662)
		(width 0.15494)
		(layer "In15.Cu")
		(net "SMB_BIC_I2C9_MUX1_SSD15_R_SCL")
	)
	(segment
		(start 368.06124 -89.499694)
		(end 369.710208 -89.499694)
		(width 0.15494)
		(layer "In15.Cu")
		(net "SMB_BIC_I2C9_MUX1_SSD15_R_SCL")
	)
	(segment
		(start 425.196254 -79.972154)
		(end 429.28921 -75.879198)
		(width 0.15494)
		(layer "In15.Cu")
		(net "SMB_BIC_I2C9_MUX1_SSD15_R_SCL")
	)
	(segment
		(start 373.776494 -86.027768)
		(end 373.776494 -82.097372)
		(width 0.15494)
		(layer "In15.Cu")
		(net "SMB_BIC_I2C9_MUX1_SSD15_R_SCL")
	)
	(segment
		(start 343.69375 -228.37775)
		(end 343.789 -228.473)
		(width 0.13208)
		(layer "F.Cu")
		(net "PWRGD_P12V_SSD3_R")
	)
	(segment
		(start 79.636366 -61.487812)
		(end 79.004414 -62.119764)
		(width 0.13208)
		(layer "F.Cu")
		(net "PWRGD_P12V_SSD3_R")
	)
	(segment
		(start 79.004414 -62.119764)
		(end 79.004414 -64.886332)
		(width 0.13208)
		(layer "F.Cu")
		(net "PWRGD_P12V_SSD3_R")
	)
	(segment
		(start 79.873602 -65.75552)
		(end 92.728542 -65.75552)
		(width 0.13208)
		(layer "F.Cu")
		(net "PWRGD_P12V_SSD3_R")
	)
	(segment
		(start 343.789 -228.854)
		(end 343.281 -229.362)
		(width 0.13208)
		(layer "F.Cu")
		(net "PWRGD_P12V_SSD3_R")
	)
	(segment
		(start 343.789 -228.473)
		(end 343.789 -228.854)
		(width 0.13208)
		(layer "F.Cu")
		(net "PWRGD_P12V_SSD3_R")
	)
	(segment
		(start 79.004414 -64.886332)
		(end 79.873602 -65.75552)
		(width 0.13208)
		(layer "F.Cu")
		(net "PWRGD_P12V_SSD3_R")
	)
	(segment
		(start 104.667812 -53.051456)
		(end 105.323132 -53.051456)
		(width 0.13208)
		(layer "F.Cu")
		(net "PWRGD_P12V_SSD3_R")
	)
	(segment
		(start 343.69375 -227.987098)
		(end 343.69375 -228.37775)
		(width 0.13208)
		(layer "F.Cu")
		(net "PWRGD_P12V_SSD3_R")
	)
	(segment
		(start 81.483454 -61.487812)
		(end 79.636366 -61.487812)
		(width 0.13208)
		(layer "F.Cu")
		(net "PWRGD_P12V_SSD3_R")
	)
	(via
		(at 121.303796 -218.64701)
		(size 0.508)
		(drill 0.254)
		(layers "F.Cu" "B.Cu")
		(net "PWRGD_P12V_SSD3_R")
	)
	(via
		(at 105.323132 -53.051456)
		(size 0.508)
		(drill 0.254)
		(layers "F.Cu" "B.Cu")
		(net "PWRGD_P12V_SSD3_R")
	)
	(via
		(at 92.728542 -65.75552)
		(size 0.508)
		(drill 0.254)
		(layers "F.Cu" "B.Cu")
		(net "PWRGD_P12V_SSD3_R")
	)
	(via
		(at 343.281 -229.362)
		(size 0.508)
		(drill 0.254)
		(layers "F.Cu" "B.Cu")
		(net "PWRGD_P12V_SSD3_R")
	)
	(segment
		(start 121.81332 -117.16766)
		(end 123.319032 -118.673372)
		(width 0.15494)
		(layer "In5.Cu")
		(net "PWRGD_P12V_SSD3_R")
	)
	(segment
		(start 109.834934 -74.196956)
		(end 114.37493 -78.736952)
		(width 0.15494)
		(layer "In5.Cu")
		(net "PWRGD_P12V_SSD3_R")
	)
	(segment
		(start 114.37493 -78.736952)
		(end 117.61216 -78.736952)
		(width 0.15494)
		(layer "In5.Cu")
		(net "PWRGD_P12V_SSD3_R")
	)
	(segment
		(start 121.81332 -104.861614)
		(end 121.81332 -117.16766)
		(width 0.15494)
		(layer "In5.Cu")
		(net "PWRGD_P12V_SSD3_R")
	)
	(segment
		(start 121.9708 -126.958598)
		(end 121.9708 -138.591036)
		(width 0.15494)
		(layer "In5.Cu")
		(net "PWRGD_P12V_SSD3_R")
	)
	(segment
		(start 105.34142 -58.357008)
		(end 105.34142 -66.228722)
		(width 0.15494)
		(layer "In5.Cu")
		(net "PWRGD_P12V_SSD3_R")
	)
	(segment
		(start 109.834934 -70.722236)
		(end 109.834934 -74.196956)
		(width 0.15494)
		(layer "In5.Cu")
		(net "PWRGD_P12V_SSD3_R")
	)
	(segment
		(start 123.319032 -125.610366)
		(end 121.9708 -126.958598)
		(width 0.15494)
		(layer "In5.Cu")
		(net "PWRGD_P12V_SSD3_R")
	)
	(segment
		(start 96.217994 -65.75552)
		(end 97.356422 -64.617092)
		(width 0.15494)
		(layer "In5.Cu")
		(net "PWRGD_P12V_SSD3_R")
	)
	(segment
		(start 123.319032 -118.673372)
		(end 123.319032 -125.610366)
		(width 0.15494)
		(layer "In5.Cu")
		(net "PWRGD_P12V_SSD3_R")
	)
	(segment
		(start 121.295922 -218.639136)
		(end 121.303796 -218.64701)
		(width 0.15494)
		(layer "In5.Cu")
		(net "PWRGD_P12V_SSD3_R")
	)
	(segment
		(start 121.295922 -204.179678)
		(end 121.295922 -218.639136)
		(width 0.15494)
		(layer "In5.Cu")
		(net "PWRGD_P12V_SSD3_R")
	)
	(segment
		(start 103.732076 -53.493924)
		(end 104.174544 -53.051456)
		(width 0.15494)
		(layer "In5.Cu")
		(net "PWRGD_P12V_SSD3_R")
	)
	(segment
		(start 104.174544 -53.051456)
		(end 105.323132 -53.051456)
		(width 0.15494)
		(layer "In5.Cu")
		(net "PWRGD_P12V_SSD3_R")
	)
	(segment
		(start 92.728542 -65.75552)
		(end 96.217994 -65.75552)
		(width 0.15494)
		(layer "In5.Cu")
		(net "PWRGD_P12V_SSD3_R")
	)
	(segment
		(start 124.035566 -102.639368)
		(end 121.81332 -104.861614)
		(width 0.15494)
		(layer "In5.Cu")
		(net "PWRGD_P12V_SSD3_R")
	)
	(segment
		(start 121.73204 -139.167616)
		(end 121.73204 -181.32044)
		(width 0.15494)
		(layer "In5.Cu")
		(net "PWRGD_P12V_SSD3_R")
	)
	(segment
		(start 103.732076 -64.252348)
		(end 103.732076 -53.493924)
		(width 0.15494)
		(layer "In5.Cu")
		(net "PWRGD_P12V_SSD3_R")
	)
	(segment
		(start 121.9708 -138.591036)
		(end 121.73204 -139.167616)
		(width 0.15494)
		(layer "In5.Cu")
		(net "PWRGD_P12V_SSD3_R")
	)
	(segment
		(start 103.367332 -64.617092)
		(end 103.732076 -64.252348)
		(width 0.15494)
		(layer "In5.Cu")
		(net "PWRGD_P12V_SSD3_R")
	)
	(segment
		(start 97.356422 -64.617092)
		(end 103.367332 -64.617092)
		(width 0.15494)
		(layer "In5.Cu")
		(net "PWRGD_P12V_SSD3_R")
	)
	(segment
		(start 105.323132 -53.051456)
		(end 104.7496 -53.624988)
		(width 0.15494)
		(layer "In5.Cu")
		(net "PWRGD_P12V_SSD3_R")
	)
	(segment
		(start 105.34142 -66.228722)
		(end 109.834934 -70.722236)
		(width 0.15494)
		(layer "In5.Cu")
		(net "PWRGD_P12V_SSD3_R")
	)
	(segment
		(start 117.61216 -78.736952)
		(end 124.035566 -85.160358)
		(width 0.15494)
		(layer "In5.Cu")
		(net "PWRGD_P12V_SSD3_R")
	)
	(segment
		(start 125.6538 -185.2422)
		(end 125.6538 -199.8218)
		(width 0.15494)
		(layer "In5.Cu")
		(net "PWRGD_P12V_SSD3_R")
	)
	(segment
		(start 104.7496 -57.765188)
		(end 105.34142 -58.357008)
		(width 0.15494)
		(layer "In5.Cu")
		(net "PWRGD_P12V_SSD3_R")
	)
	(segment
		(start 124.035566 -85.160358)
		(end 124.035566 -102.639368)
		(width 0.15494)
		(layer "In5.Cu")
		(net "PWRGD_P12V_SSD3_R")
	)
	(segment
		(start 121.73204 -181.32044)
		(end 125.6538 -185.2422)
		(width 0.15494)
		(layer "In5.Cu")
		(net "PWRGD_P12V_SSD3_R")
	)
	(segment
		(start 104.7496 -53.624988)
		(end 104.7496 -57.765188)
		(width 0.15494)
		(layer "In5.Cu")
		(net "PWRGD_P12V_SSD3_R")
	)
	(segment
		(start 125.6538 -199.8218)
		(end 121.295922 -204.179678)
		(width 0.15494)
		(layer "In5.Cu")
		(net "PWRGD_P12V_SSD3_R")
	)
	(segment
		(start 214.18931 -231.48417)
		(end 213.58098 -230.87584)
		(width 0.15494)
		(layer "In15.Cu")
		(net "PWRGD_P12V_SSD3_R")
	)
	(segment
		(start 323.41693 -234.473242)
		(end 322.36156 -233.417872)
		(width 0.15494)
		(layer "In15.Cu")
		(net "PWRGD_P12V_SSD3_R")
	)
	(segment
		(start 137.06602 -224.847912)
		(end 131.37642 -224.847912)
		(width 0.15494)
		(layer "In15.Cu")
		(net "PWRGD_P12V_SSD3_R")
	)
	(segment
		(start 162.261804 -228.390196)
		(end 155.854146 -221.982538)
		(width 0.15494)
		(layer "In15.Cu")
		(net "PWRGD_P12V_SSD3_R")
	)
	(segment
		(start 336.916776 -231.806496)
		(end 336.76463 -231.958642)
		(width 0.15494)
		(layer "In15.Cu")
		(net "PWRGD_P12V_SSD3_R")
	)
	(segment
		(start 255.260856 -225.4631)
		(end 254.011176 -226.71278)
		(width 0.15494)
		(layer "In15.Cu")
		(net "PWRGD_P12V_SSD3_R")
	)
	(segment
		(start 192.435734 -231.873298)
		(end 188.952632 -228.390196)
		(width 0.15494)
		(layer "In15.Cu")
		(net "PWRGD_P12V_SSD3_R")
	)
	(segment
		(start 254.011176 -226.71278)
		(end 250.173998 -226.71278)
		(width 0.15494)
		(layer "In15.Cu")
		(net "PWRGD_P12V_SSD3_R")
	)
	(segment
		(start 327.477882 -232.3846)
		(end 325.38924 -234.473242)
		(width 0.15494)
		(layer "In15.Cu")
		(net "PWRGD_P12V_SSD3_R")
	)
	(segment
		(start 131.37642 -224.847912)
		(end 130.089402 -226.13493)
		(width 0.15494)
		(layer "In15.Cu")
		(net "PWRGD_P12V_SSD3_R")
	)
	(segment
		(start 300.517814 -233.25455)
		(end 271.21104 -233.25455)
		(width 0.15494)
		(layer "In15.Cu")
		(net "PWRGD_P12V_SSD3_R")
	)
	(segment
		(start 302.135794 -232.73385)
		(end 301.038514 -232.73385)
		(width 0.15494)
		(layer "In15.Cu")
		(net "PWRGD_P12V_SSD3_R")
	)
	(segment
		(start 249.511058 -226.04984)
		(end 246.675148 -226.04984)
		(width 0.15494)
		(layer "In15.Cu")
		(net "PWRGD_P12V_SSD3_R")
	)
	(segment
		(start 188.952632 -228.390196)
		(end 162.261804 -228.390196)
		(width 0.15494)
		(layer "In15.Cu")
		(net "PWRGD_P12V_SSD3_R")
	)
	(segment
		(start 301.038514 -232.73385)
		(end 300.517814 -233.25455)
		(width 0.15494)
		(layer "In15.Cu")
		(net "PWRGD_P12V_SSD3_R")
	)
	(segment
		(start 243.769388 -229.96144)
		(end 242.246658 -231.48417)
		(width 0.15494)
		(layer "In15.Cu")
		(net "PWRGD_P12V_SSD3_R")
	)
	(segment
		(start 242.246658 -231.48417)
		(end 214.18931 -231.48417)
		(width 0.15494)
		(layer "In15.Cu")
		(net "PWRGD_P12V_SSD3_R")
	)
	(segment
		(start 330.869798 -232.08615)
		(end 330.571348 -232.3846)
		(width 0.15494)
		(layer "In15.Cu")
		(net "PWRGD_P12V_SSD3_R")
	)
	(segment
		(start 246.675148 -226.04984)
		(end 243.769388 -228.9556)
		(width 0.15494)
		(layer "In15.Cu")
		(net "PWRGD_P12V_SSD3_R")
	)
	(segment
		(start 250.173998 -226.71278)
		(end 249.511058 -226.04984)
		(width 0.15494)
		(layer "In15.Cu")
		(net "PWRGD_P12V_SSD3_R")
	)
	(segment
		(start 336.76463 -231.958642)
		(end 336.678778 -231.958642)
		(width 0.15494)
		(layer "In15.Cu")
		(net "PWRGD_P12V_SSD3_R")
	)
	(segment
		(start 271.21104 -233.25455)
		(end 265.18997 -227.23348)
		(width 0.15494)
		(layer "In15.Cu")
		(net "PWRGD_P12V_SSD3_R")
	)
	(segment
		(start 261.999984 -227.23348)
		(end 259.986272 -226.399344)
		(width 0.15494)
		(layer "In15.Cu")
		(net "PWRGD_P12V_SSD3_R")
	)
	(segment
		(start 243.769388 -228.9556)
		(end 243.769388 -229.96144)
		(width 0.15494)
		(layer "In15.Cu")
		(net "PWRGD_P12V_SSD3_R")
	)
	(segment
		(start 130.089402 -226.13493)
		(end 128.791716 -226.13493)
		(width 0.15494)
		(layer "In15.Cu")
		(net "PWRGD_P12V_SSD3_R")
	)
	(segment
		(start 322.36156 -233.417872)
		(end 302.819816 -233.417872)
		(width 0.15494)
		(layer "In15.Cu")
		(net "PWRGD_P12V_SSD3_R")
	)
	(segment
		(start 145.50771 -221.982538)
		(end 142.602458 -224.88779)
		(width 0.15494)
		(layer "In15.Cu")
		(net "PWRGD_P12V_SSD3_R")
	)
	(segment
		(start 209.169762 -230.87584)
		(end 208.172304 -231.873298)
		(width 0.15494)
		(layer "In15.Cu")
		(net "PWRGD_P12V_SSD3_R")
	)
	(segment
		(start 330.571348 -232.3846)
		(end 327.477882 -232.3846)
		(width 0.15494)
		(layer "In15.Cu")
		(net "PWRGD_P12V_SSD3_R")
	)
	(segment
		(start 302.819816 -233.417872)
		(end 302.135794 -232.73385)
		(width 0.15494)
		(layer "In15.Cu")
		(net "PWRGD_P12V_SSD3_R")
	)
	(segment
		(start 259.050028 -225.4631)
		(end 255.260856 -225.4631)
		(width 0.15494)
		(layer "In15.Cu")
		(net "PWRGD_P12V_SSD3_R")
	)
	(segment
		(start 343.281 -229.362)
		(end 340.836504 -231.806496)
		(width 0.15494)
		(layer "In15.Cu")
		(net "PWRGD_P12V_SSD3_R")
	)
	(segment
		(start 137.110724 -224.892616)
		(end 137.06602 -224.847912)
		(width 0.15494)
		(layer "In15.Cu")
		(net "PWRGD_P12V_SSD3_R")
	)
	(segment
		(start 128.791716 -226.13493)
		(end 121.303796 -218.64701)
		(width 0.15494)
		(layer "In15.Cu")
		(net "PWRGD_P12V_SSD3_R")
	)
	(segment
		(start 340.836504 -231.806496)
		(end 336.916776 -231.806496)
		(width 0.15494)
		(layer "In15.Cu")
		(net "PWRGD_P12V_SSD3_R")
	)
	(segment
		(start 325.38924 -234.473242)
		(end 323.41693 -234.473242)
		(width 0.15494)
		(layer "In15.Cu")
		(net "PWRGD_P12V_SSD3_R")
	)
	(segment
		(start 142.602458 -224.88779)
		(end 141.407388 -224.88779)
		(width 0.15494)
		(layer "In15.Cu")
		(net "PWRGD_P12V_SSD3_R")
	)
	(segment
		(start 332.861412 -232.07599)
		(end 332.162912 -232.07599)
		(width 0.15494)
		(layer "In15.Cu")
		(net "PWRGD_P12V_SSD3_R")
	)
	(segment
		(start 141.407388 -224.88779)
		(end 141.402562 -224.892616)
		(width 0.15494)
		(layer "In15.Cu")
		(net "PWRGD_P12V_SSD3_R")
	)
	(segment
		(start 208.172304 -231.873298)
		(end 192.435734 -231.873298)
		(width 0.15494)
		(layer "In15.Cu")
		(net "PWRGD_P12V_SSD3_R")
	)
	(segment
		(start 141.402562 -224.892616)
		(end 137.110724 -224.892616)
		(width 0.15494)
		(layer "In15.Cu")
		(net "PWRGD_P12V_SSD3_R")
	)
	(segment
		(start 265.18997 -227.23348)
		(end 261.999984 -227.23348)
		(width 0.15494)
		(layer "In15.Cu")
		(net "PWRGD_P12V_SSD3_R")
	)
	(segment
		(start 332.162912 -232.07599)
		(end 332.152752 -232.08615)
		(width 0.15494)
		(layer "In15.Cu")
		(net "PWRGD_P12V_SSD3_R")
	)
	(segment
		(start 213.58098 -230.87584)
		(end 209.169762 -230.87584)
		(width 0.15494)
		(layer "In15.Cu")
		(net "PWRGD_P12V_SSD3_R")
	)
	(segment
		(start 259.986272 -226.399344)
		(end 259.050028 -225.4631)
		(width 0.15494)
		(layer "In15.Cu")
		(net "PWRGD_P12V_SSD3_R")
	)
	(segment
		(start 332.152752 -232.08615)
		(end 330.869798 -232.08615)
		(width 0.15494)
		(layer "In15.Cu")
		(net "PWRGD_P12V_SSD3_R")
	)
	(segment
		(start 336.173572 -232.463848)
		(end 333.24927 -232.463848)
		(width 0.15494)
		(layer "In15.Cu")
		(net "PWRGD_P12V_SSD3_R")
	)
	(segment
		(start 333.24927 -232.463848)
		(end 332.861412 -232.07599)
		(width 0.15494)
		(layer "In15.Cu")
		(net "PWRGD_P12V_SSD3_R")
	)
	(segment
		(start 155.854146 -221.982538)
		(end 145.50771 -221.982538)
		(width 0.15494)
		(layer "In15.Cu")
		(net "PWRGD_P12V_SSD3_R")
	)
	(segment
		(start 336.678778 -231.958642)
		(end 336.173572 -232.463848)
		(width 0.15494)
		(layer "In15.Cu")
		(net "PWRGD_P12V_SSD3_R")
	)
	(segment
		(start 348.493842 -218.387168)
		(end 348.893638 -217.987372)
		(width 0.13208)
		(layer "F.Cu")
		(net "NIC7_AUX_PWR_EN")
	)
	(via
		(at 418.491416 -118.711218)
		(size 0.508)
		(drill 0.254)
		(layers "F.Cu" "B.Cu")
		(net "NIC7_AUX_PWR_EN")
	)
	(via
		(at 348.893638 -217.987372)
		(size 0.4572)
		(drill 0.254)
		(layers "F.Cu" "B.Cu")
		(net "NIC7_AUX_PWR_EN")
	)
	(via
		(at 351.369122 -129.089912)
		(size 0.508)
		(drill 0.254)
		(layers "F.Cu" "B.Cu")
		(net "NIC7_AUX_PWR_EN")
	)
	(segment
		(start 419.18636 -117.66169)
		(end 419.18636 -118.7069)
		(width 0.13208)
		(layer "B.Cu")
		(net "NIC7_AUX_PWR_EN")
	)
	(segment
		(start 419.190678 -118.711218)
		(end 418.491416 -118.711218)
		(width 0.13208)
		(layer "B.Cu")
		(net "NIC7_AUX_PWR_EN")
	)
	(segment
		(start 419.18636 -118.7069)
		(end 419.190678 -118.711218)
		(width 0.13208)
		(layer "B.Cu")
		(net "NIC7_AUX_PWR_EN")
	)
	(segment
		(start 354.5332 -214.187786)
		(end 355.1174 -213.603586)
		(width 0.15494)
		(layer "In7.Cu")
		(net "NIC7_AUX_PWR_EN")
	)
	(segment
		(start 370.518436 -192.906142)
		(end 369.713002 -192.100708)
		(width 0.15494)
		(layer "In7.Cu")
		(net "NIC7_AUX_PWR_EN")
	)
	(segment
		(start 369.713002 -192.100708)
		(end 369.713002 -176.368202)
		(width 0.15494)
		(layer "In7.Cu")
		(net "NIC7_AUX_PWR_EN")
	)
	(segment
		(start 351.280476 -217.44432)
		(end 351.76968 -217.44432)
		(width 0.15494)
		(layer "In7.Cu")
		(net "NIC7_AUX_PWR_EN")
	)
	(segment
		(start 348.893638 -217.987372)
		(end 349.292418 -217.588592)
		(width 0.0889)
		(layer "In7.Cu")
		(net "NIC7_AUX_PWR_EN")
	)
	(segment
		(start 351.0026 -164.973)
		(end 348.848426 -162.818826)
		(width 0.15494)
		(layer "In7.Cu")
		(net "NIC7_AUX_PWR_EN")
	)
	(segment
		(start 361.061254 -204.3684)
		(end 362.60024 -204.3684)
		(width 0.15494)
		(layer "In7.Cu")
		(net "NIC7_AUX_PWR_EN")
	)
	(segment
		(start 357.654606 -207.775048)
		(end 361.061254 -204.3684)
		(width 0.15494)
		(layer "In7.Cu")
		(net "NIC7_AUX_PWR_EN")
	)
	(segment
		(start 355.273356 -170.412156)
		(end 351.0026 -166.1414)
		(width 0.15494)
		(layer "In7.Cu")
		(net "NIC7_AUX_PWR_EN")
	)
	(segment
		(start 348.848426 -162.818826)
		(end 348.848426 -131.610608)
		(width 0.15494)
		(layer "In7.Cu")
		(net "NIC7_AUX_PWR_EN")
	)
	(segment
		(start 351.76968 -217.44432)
		(end 354.5332 -214.6808)
		(width 0.15494)
		(layer "In7.Cu")
		(net "NIC7_AUX_PWR_EN")
	)
	(segment
		(start 354.5332 -214.6808)
		(end 354.5332 -214.187786)
		(width 0.15494)
		(layer "In7.Cu")
		(net "NIC7_AUX_PWR_EN")
	)
	(segment
		(start 355.1174 -213.603586)
		(end 355.1174 -209.979006)
		(width 0.15494)
		(layer "In7.Cu")
		(net "NIC7_AUX_PWR_EN")
	)
	(segment
		(start 356.875842 -207.775048)
		(end 357.654606 -207.775048)
		(width 0.15494)
		(layer "In7.Cu")
		(net "NIC7_AUX_PWR_EN")
	)
	(segment
		(start 362.60024 -204.3684)
		(end 362.64977 -204.31887)
		(width 0.15494)
		(layer "In7.Cu")
		(net "NIC7_AUX_PWR_EN")
	)
	(segment
		(start 356.443026 -208.65338)
		(end 356.443026 -208.021174)
		(width 0.15494)
		(layer "In7.Cu")
		(net "NIC7_AUX_PWR_EN")
	)
	(segment
		(start 356.443026 -208.021174)
		(end 356.557326 -207.906874)
		(width 0.15494)
		(layer "In7.Cu")
		(net "NIC7_AUX_PWR_EN")
	)
	(segment
		(start 355.1174 -209.979006)
		(end 356.443026 -208.65338)
		(width 0.15494)
		(layer "In7.Cu")
		(net "NIC7_AUX_PWR_EN")
	)
	(segment
		(start 362.64977 -204.31887)
		(end 362.65866 -204.31887)
		(width 0.15494)
		(layer "In7.Cu")
		(net "NIC7_AUX_PWR_EN")
	)
	(segment
		(start 369.713002 -176.368202)
		(end 363.756956 -170.412156)
		(width 0.15494)
		(layer "In7.Cu")
		(net "NIC7_AUX_PWR_EN")
	)
	(segment
		(start 363.756956 -170.412156)
		(end 355.273356 -170.412156)
		(width 0.15494)
		(layer "In7.Cu")
		(net "NIC7_AUX_PWR_EN")
	)
	(segment
		(start 370.518436 -197.146418)
		(end 370.518436 -192.906142)
		(width 0.15494)
		(layer "In7.Cu")
		(net "NIC7_AUX_PWR_EN")
	)
	(segment
		(start 349.292418 -217.588592)
		(end 351.136204 -217.588592)
		(width 0.0889)
		(layer "In7.Cu")
		(net "NIC7_AUX_PWR_EN")
	)
	(segment
		(start 356.557326 -207.906874)
		(end 356.875842 -207.775048)
		(width 0.15494)
		(layer "In7.Cu")
		(net "NIC7_AUX_PWR_EN")
	)
	(segment
		(start 351.0026 -166.1414)
		(end 351.0026 -164.973)
		(width 0.15494)
		(layer "In7.Cu")
		(net "NIC7_AUX_PWR_EN")
	)
	(segment
		(start 368.613182 -198.364348)
		(end 369.300506 -198.364348)
		(width 0.15494)
		(layer "In7.Cu")
		(net "NIC7_AUX_PWR_EN")
	)
	(segment
		(start 348.848426 -131.610608)
		(end 351.369122 -129.089912)
		(width 0.15494)
		(layer "In7.Cu")
		(net "NIC7_AUX_PWR_EN")
	)
	(segment
		(start 369.300506 -198.364348)
		(end 370.518436 -197.146418)
		(width 0.15494)
		(layer "In7.Cu")
		(net "NIC7_AUX_PWR_EN")
	)
	(segment
		(start 351.136204 -217.588592)
		(end 351.280476 -217.44432)
		(width 0.0889)
		(layer "In7.Cu")
		(net "NIC7_AUX_PWR_EN")
	)
	(segment
		(start 362.65866 -204.31887)
		(end 368.613182 -198.364348)
		(width 0.15494)
		(layer "In7.Cu")
		(net "NIC7_AUX_PWR_EN")
	)
	(segment
		(start 357.375968 -128.373124)
		(end 357.985568 -128.982724)
		(width 0.15494)
		(layer "In13.Cu")
		(net "NIC7_AUX_PWR_EN")
	)
	(segment
		(start 416.430968 -126.569978)
		(end 418.491416 -124.50953)
		(width 0.15494)
		(layer "In13.Cu")
		(net "NIC7_AUX_PWR_EN")
	)
	(segment
		(start 351.369122 -129.089912)
		(end 352.08591 -128.373124)
		(width 0.15494)
		(layer "In13.Cu")
		(net "NIC7_AUX_PWR_EN")
	)
	(segment
		(start 384.118866 -125.909832)
		(end 384.779012 -126.569978)
		(width 0.15494)
		(layer "In13.Cu")
		(net "NIC7_AUX_PWR_EN")
	)
	(segment
		(start 384.779012 -126.569978)
		(end 393.761214 -126.569978)
		(width 0.15494)
		(layer "In13.Cu")
		(net "NIC7_AUX_PWR_EN")
	)
	(segment
		(start 393.761214 -126.569978)
		(end 394.457682 -125.87351)
		(width 0.15494)
		(layer "In13.Cu")
		(net "NIC7_AUX_PWR_EN")
	)
	(segment
		(start 357.985568 -128.982724)
		(end 367.179352 -128.982724)
		(width 0.15494)
		(layer "In13.Cu")
		(net "NIC7_AUX_PWR_EN")
	)
	(segment
		(start 418.491416 -124.50953)
		(end 418.491416 -118.711218)
		(width 0.15494)
		(layer "In13.Cu")
		(net "NIC7_AUX_PWR_EN")
	)
	(segment
		(start 367.179352 -128.982724)
		(end 370.252244 -125.909832)
		(width 0.15494)
		(layer "In13.Cu")
		(net "NIC7_AUX_PWR_EN")
	)
	(segment
		(start 394.457682 -125.87351)
		(end 396.188184 -125.87351)
		(width 0.15494)
		(layer "In13.Cu")
		(net "NIC7_AUX_PWR_EN")
	)
	(segment
		(start 352.08591 -128.373124)
		(end 357.375968 -128.373124)
		(width 0.15494)
		(layer "In13.Cu")
		(net "NIC7_AUX_PWR_EN")
	)
	(segment
		(start 396.188184 -125.87351)
		(end 396.884652 -126.569978)
		(width 0.15494)
		(layer "In13.Cu")
		(net "NIC7_AUX_PWR_EN")
	)
	(segment
		(start 370.252244 -125.909832)
		(end 384.118866 -125.909832)
		(width 0.15494)
		(layer "In13.Cu")
		(net "NIC7_AUX_PWR_EN")
	)
	(segment
		(start 396.884652 -126.569978)
		(end 416.430968 -126.569978)
		(width 0.15494)
		(layer "In13.Cu")
		(net "NIC7_AUX_PWR_EN")
	)
	(segment
		(start 364.068614 -27.189938)
		(end 363.564932 -27.189938)
		(width 0.13462)
		(layer "F.Cu")
		(net "CLK_100M_DB800ZL_SSD12_R_DP")
	)
	(segment
		(start 345.335352 -85.57768)
		(end 346.802964 -85.57768)
		(width 0.13462)
		(layer "F.Cu")
		(net "CLK_100M_DB800ZL_SSD12_R_DP")
	)
	(segment
		(start 346.802964 -85.57768)
		(end 347.09989 -85.280754)
		(width 0.13462)
		(layer "F.Cu")
		(net "CLK_100M_DB800ZL_SSD12_R_DP")
	)
	(segment
		(start 345.013026 -85.255354)
		(end 345.335352 -85.57768)
		(width 0.13462)
		(layer "F.Cu")
		(net "CLK_100M_DB800ZL_SSD12_R_DP")
	)
	(segment
		(start 364.232952 -27.0256)
		(end 364.068614 -27.189938)
		(width 0.13462)
		(layer "F.Cu")
		(net "CLK_100M_DB800ZL_SSD12_R_DP")
	)
	(segment
		(start 365.281464 -27.342846)
		(end 364.964218 -27.0256)
		(width 0.13462)
		(layer "F.Cu")
		(net "CLK_100M_DB800ZL_SSD12_R_DP")
	)
	(segment
		(start 364.964218 -27.0256)
		(end 364.232952 -27.0256)
		(width 0.13462)
		(layer "F.Cu")
		(net "CLK_100M_DB800ZL_SSD12_R_DP")
	)
	(via
		(at 347.09989 -85.280754)
		(size 0.508)
		(drill 0.254)
		(layers "F.Cu" "B.Cu")
		(net "CLK_100M_DB800ZL_SSD12_R_DP")
	)
	(via
		(at 365.281464 -27.342846)
		(size 0.508)
		(drill 0.254)
		(layers "F.Cu" "B.Cu")
		(net "CLK_100M_DB800ZL_SSD12_R_DP")
	)
	(segment
		(start 348.0308 -85.165184)
		(end 347.6244 -85.571584)
		(width 0.1651)
		(layer "In13.Cu")
		(net "CLK_100M_DB800ZL_SSD12_R_DP")
	)
	(segment
		(start 365.98606 -27.739594)
		(end 365.87176 -27.853894)
		(width 0.1651)
		(layer "In13.Cu")
		(net "CLK_100M_DB800ZL_SSD12_R_DP")
	)
	(segment
		(start 365.87176 -32.006794)
		(end 365.98606 -32.121094)
		(width 0.1651)
		(layer "In13.Cu")
		(net "CLK_100M_DB800ZL_SSD12_R_DP")
	)
	(segment
		(start 347.6244 -85.571584)
		(end 347.39072 -85.571584)
		(width 0.1651)
		(layer "In13.Cu")
		(net "CLK_100M_DB800ZL_SSD12_R_DP")
	)
	(segment
		(start 365.87176 -29.568394)
		(end 365.98606 -29.682694)
		(width 0.1651)
		(layer "In13.Cu")
		(net "CLK_100M_DB800ZL_SSD12_R_DP")
	)
	(segment
		(start 364.773718 -37.816282)
		(end 364.61192 -37.816282)
		(width 0.1651)
		(layer "In13.Cu")
		(net "CLK_100M_DB800ZL_SSD12_R_DP")
	)
	(segment
		(start 365.98606 -30.901894)
		(end 365.98606 -31.397194)
		(width 0.1651)
		(layer "In13.Cu")
		(net "CLK_100M_DB800ZL_SSD12_R_DP")
	)
	(segment
		(start 365.98606 -34.559494)
		(end 365.98606 -35.054794)
		(width 0.1651)
		(layer "In13.Cu")
		(net "CLK_100M_DB800ZL_SSD12_R_DP")
	)
	(segment
		(start 365.98606 -35.778694)
		(end 365.98606 -36.60394)
		(width 0.1651)
		(layer "In13.Cu")
		(net "CLK_100M_DB800ZL_SSD12_R_DP")
	)
	(segment
		(start 365.87176 -35.169094)
		(end 365.87176 -35.664394)
		(width 0.1651)
		(layer "In13.Cu")
		(net "CLK_100M_DB800ZL_SSD12_R_DP")
	)
	(segment
		(start 365.12373 -37.46627)
		(end 364.773718 -37.816282)
		(width 0.1651)
		(layer "In13.Cu")
		(net "CLK_100M_DB800ZL_SSD12_R_DP")
	)
	(segment
		(start 365.636048 -36.953952)
		(end 365.47425 -36.953952)
		(width 0.1651)
		(layer "In13.Cu")
		(net "CLK_100M_DB800ZL_SSD12_R_DP")
	)
	(segment
		(start 365.87176 -34.445194)
		(end 365.98606 -34.559494)
		(width 0.1651)
		(layer "In13.Cu")
		(net "CLK_100M_DB800ZL_SSD12_R_DP")
	)
	(segment
		(start 365.98606 -28.463494)
		(end 365.98606 -28.958794)
		(width 0.1651)
		(layer "In13.Cu")
		(net "CLK_100M_DB800ZL_SSD12_R_DP")
	)
	(segment
		(start 360.6546 -41.9354)
		(end 360.6546 -70.5358)
		(width 0.1651)
		(layer "In13.Cu")
		(net "CLK_100M_DB800ZL_SSD12_R_DP")
	)
	(segment
		(start 365.98606 -33.835594)
		(end 365.87176 -33.949894)
		(width 0.1651)
		(layer "In13.Cu")
		(net "CLK_100M_DB800ZL_SSD12_R_DP")
	)
	(segment
		(start 365.98606 -28.958794)
		(end 365.87176 -29.073094)
		(width 0.1651)
		(layer "In13.Cu")
		(net "CLK_100M_DB800ZL_SSD12_R_DP")
	)
	(segment
		(start 365.47425 -36.953952)
		(end 365.12373 -37.304472)
		(width 0.1651)
		(layer "In13.Cu")
		(net "CLK_100M_DB800ZL_SSD12_R_DP")
	)
	(segment
		(start 365.98606 -29.682694)
		(end 365.98606 -30.177994)
		(width 0.1651)
		(layer "In13.Cu")
		(net "CLK_100M_DB800ZL_SSD12_R_DP")
	)
	(segment
		(start 350.139 -78.2828)
		(end 348.0308 -80.391)
		(width 0.1651)
		(layer "In13.Cu")
		(net "CLK_100M_DB800ZL_SSD12_R_DP")
	)
	(segment
		(start 352.9076 -78.2828)
		(end 350.139 -78.2828)
		(width 0.1651)
		(layer "In13.Cu")
		(net "CLK_100M_DB800ZL_SSD12_R_DP")
	)
	(segment
		(start 365.793782 -27.052016)
		(end 365.98606 -27.244294)
		(width 0.1651)
		(layer "In13.Cu")
		(net "CLK_100M_DB800ZL_SSD12_R_DP")
	)
	(segment
		(start 365.12373 -37.304472)
		(end 365.12373 -37.46627)
		(width 0.1651)
		(layer "In13.Cu")
		(net "CLK_100M_DB800ZL_SSD12_R_DP")
	)
	(segment
		(start 365.87176 -28.349194)
		(end 365.98606 -28.463494)
		(width 0.1651)
		(layer "In13.Cu")
		(net "CLK_100M_DB800ZL_SSD12_R_DP")
	)
	(segment
		(start 365.87176 -30.292294)
		(end 365.87176 -30.787594)
		(width 0.1651)
		(layer "In13.Cu")
		(net "CLK_100M_DB800ZL_SSD12_R_DP")
	)
	(segment
		(start 364.61192 -37.816282)
		(end 364.2614 -38.166802)
		(width 0.1651)
		(layer "In13.Cu")
		(net "CLK_100M_DB800ZL_SSD12_R_DP")
	)
	(segment
		(start 365.87176 -33.949894)
		(end 365.87176 -34.445194)
		(width 0.1651)
		(layer "In13.Cu")
		(net "CLK_100M_DB800ZL_SSD12_R_DP")
	)
	(segment
		(start 348.0308 -80.391)
		(end 348.0308 -85.165184)
		(width 0.1651)
		(layer "In13.Cu")
		(net "CLK_100M_DB800ZL_SSD12_R_DP")
	)
	(segment
		(start 365.98606 -35.054794)
		(end 365.87176 -35.169094)
		(width 0.1651)
		(layer "In13.Cu")
		(net "CLK_100M_DB800ZL_SSD12_R_DP")
	)
	(segment
		(start 365.98606 -32.121094)
		(end 365.98606 -32.616394)
		(width 0.1651)
		(layer "In13.Cu")
		(net "CLK_100M_DB800ZL_SSD12_R_DP")
	)
	(segment
		(start 365.87176 -33.225994)
		(end 365.98606 -33.340294)
		(width 0.1651)
		(layer "In13.Cu")
		(net "CLK_100M_DB800ZL_SSD12_R_DP")
	)
	(segment
		(start 365.87176 -29.073094)
		(end 365.87176 -29.568394)
		(width 0.1651)
		(layer "In13.Cu")
		(net "CLK_100M_DB800ZL_SSD12_R_DP")
	)
	(segment
		(start 365.281464 -27.342846)
		(end 365.572294 -27.052016)
		(width 0.1651)
		(layer "In13.Cu")
		(net "CLK_100M_DB800ZL_SSD12_R_DP")
	)
	(segment
		(start 365.87176 -31.511494)
		(end 365.87176 -32.006794)
		(width 0.1651)
		(layer "In13.Cu")
		(net "CLK_100M_DB800ZL_SSD12_R_DP")
	)
	(segment
		(start 365.98606 -33.340294)
		(end 365.98606 -33.835594)
		(width 0.1651)
		(layer "In13.Cu")
		(net "CLK_100M_DB800ZL_SSD12_R_DP")
	)
	(segment
		(start 364.2614 -38.3286)
		(end 360.6546 -41.9354)
		(width 0.1651)
		(layer "In13.Cu")
		(net "CLK_100M_DB800ZL_SSD12_R_DP")
	)
	(segment
		(start 365.87176 -32.730694)
		(end 365.87176 -33.225994)
		(width 0.1651)
		(layer "In13.Cu")
		(net "CLK_100M_DB800ZL_SSD12_R_DP")
	)
	(segment
		(start 365.98606 -30.177994)
		(end 365.87176 -30.292294)
		(width 0.1651)
		(layer "In13.Cu")
		(net "CLK_100M_DB800ZL_SSD12_R_DP")
	)
	(segment
		(start 365.87176 -35.664394)
		(end 365.98606 -35.778694)
		(width 0.1651)
		(layer "In13.Cu")
		(net "CLK_100M_DB800ZL_SSD12_R_DP")
	)
	(segment
		(start 365.87176 -27.853894)
		(end 365.87176 -28.349194)
		(width 0.1651)
		(layer "In13.Cu")
		(net "CLK_100M_DB800ZL_SSD12_R_DP")
	)
	(segment
		(start 365.98606 -32.616394)
		(end 365.87176 -32.730694)
		(width 0.1651)
		(layer "In13.Cu")
		(net "CLK_100M_DB800ZL_SSD12_R_DP")
	)
	(segment
		(start 365.98606 -36.60394)
		(end 365.636048 -36.953952)
		(width 0.1651)
		(layer "In13.Cu")
		(net "CLK_100M_DB800ZL_SSD12_R_DP")
	)
	(segment
		(start 360.6546 -70.5358)
		(end 352.9076 -78.2828)
		(width 0.1651)
		(layer "In13.Cu")
		(net "CLK_100M_DB800ZL_SSD12_R_DP")
	)
	(segment
		(start 347.39072 -85.571584)
		(end 347.09989 -85.280754)
		(width 0.1651)
		(layer "In13.Cu")
		(net "CLK_100M_DB800ZL_SSD12_R_DP")
	)
	(segment
		(start 365.572294 -27.052016)
		(end 365.793782 -27.052016)
		(width 0.1651)
		(layer "In13.Cu")
		(net "CLK_100M_DB800ZL_SSD12_R_DP")
	)
	(segment
		(start 364.2614 -38.166802)
		(end 364.2614 -38.3286)
		(width 0.1651)
		(layer "In13.Cu")
		(net "CLK_100M_DB800ZL_SSD12_R_DP")
	)
	(segment
		(start 365.87176 -30.787594)
		(end 365.98606 -30.901894)
		(width 0.1651)
		(layer "In13.Cu")
		(net "CLK_100M_DB800ZL_SSD12_R_DP")
	)
	(segment
		(start 365.98606 -31.397194)
		(end 365.87176 -31.511494)
		(width 0.1651)
		(layer "In13.Cu")
		(net "CLK_100M_DB800ZL_SSD12_R_DP")
	)
	(segment
		(start 365.98606 -27.244294)
		(end 365.98606 -27.739594)
		(width 0.1651)
		(layer "In13.Cu")
		(net "CLK_100M_DB800ZL_SSD12_R_DP")
	)
	(segment
		(start 324.249542 -305.007518)
		(end 324.25005 -305.008026)
		(width 0.13208)
		(layer "F.Cu")
		(net "PEX2_SPARE6")
	)
	(segment
		(start 324.249542 -304.436526)
		(end 324.249542 -305.007518)
		(width 0.13208)
		(layer "F.Cu")
		(net "PEX2_SPARE6")
	)
	(segment
		(start 324.25005 -305.008026)
		(end 324.25005 -305.063906)
		(width 0.13208)
		(layer "F.Cu")
		(net "PEX2_SPARE6")
	)
	(segment
		(start 324.25005 -305.063906)
		(end 324.25005 -305.674522)
		(width 0.13208)
		(layer "F.Cu")
		(net "PEX2_SPARE6")
	)
	(segment
		(start 295.17467 -308.724554)
		(end 294.69969 -309.199788)
		(width 0.13208)
		(layer "F.Cu")
		(net "PEX2_SPARE6")
	)
	(via
		(at 295.17467 -308.724554)
		(size 0.4064)
		(drill 0.2032)
		(layers "F.Cu" "B.Cu")
		(net "PEX2_SPARE6")
	)
	(via
		(at 324.25005 -305.063906)
		(size 0.508)
		(drill 0.254)
		(layers "F.Cu" "B.Cu")
		(net "PEX2_SPARE6")
	)
	(via
		(at 316.277752 -312.999882)
		(size 0.6604)
		(drill 0.3302)
		(layers "F.Cu" "B.Cu")
		(net "PEX2_SPARE6")
	)
	(segment
		(start 297.316144 -312.537602)
		(end 315.815472 -312.537602)
		(width 0.13208)
		(layer "B.Cu")
		(net "PEX2_SPARE6")
	)
	(segment
		(start 323.682106 -305.63185)
		(end 324.25005 -305.063906)
		(width 0.13208)
		(layer "B.Cu")
		(net "PEX2_SPARE6")
	)
	(segment
		(start 323.645784 -305.63185)
		(end 323.682106 -305.63185)
		(width 0.13208)
		(layer "B.Cu")
		(net "PEX2_SPARE6")
	)
	(segment
		(start 297.060112 -309.760366)
		(end 297.060112 -312.28157)
		(width 0.13208)
		(layer "B.Cu")
		(net "PEX2_SPARE6")
	)
	(segment
		(start 296.487342 -309.187596)
		(end 297.060112 -309.760366)
		(width 0.13208)
		(layer "B.Cu")
		(net "PEX2_SPARE6")
	)
	(segment
		(start 297.060112 -312.28157)
		(end 297.316144 -312.537602)
		(width 0.13208)
		(layer "B.Cu")
		(net "PEX2_SPARE6")
	)
	(segment
		(start 316.277752 -312.999882)
		(end 323.645784 -305.63185)
		(width 0.13208)
		(layer "B.Cu")
		(net "PEX2_SPARE6")
	)
	(segment
		(start 315.815472 -312.537602)
		(end 316.277752 -312.999882)
		(width 0.13208)
		(layer "B.Cu")
		(net "PEX2_SPARE6")
	)
	(segment
		(start 295.637712 -309.187596)
		(end 296.487342 -309.187596)
		(width 0.13208)
		(layer "B.Cu")
		(net "PEX2_SPARE6")
	)
	(segment
		(start 295.17467 -308.724554)
		(end 295.637712 -309.187596)
		(width 0.13208)
		(layer "B.Cu")
		(net "PEX2_SPARE6")
	)
	(segment
		(start 375.235724 -21.570696)
		(end 375.235724 -20.789392)
		(width 0.13208)
		(layer "F.Cu")
		(net "SMB_BIC_I2C9_MUX1_SSD12_R_SDA")
	)
	(segment
		(start 375.520712 -21.855684)
		(end 375.235724 -21.570696)
		(width 0.13208)
		(layer "F.Cu")
		(net "SMB_BIC_I2C9_MUX1_SSD12_R_SDA")
	)
	(segment
		(start 375.76252 -22.097492)
		(end 375.520712 -21.855684)
		(width 0.13208)
		(layer "F.Cu")
		(net "SMB_BIC_I2C9_MUX1_SSD12_R_SDA")
	)
	(segment
		(start 367.355628 -81.498694)
		(end 368.06124 -81.498694)
		(width 0.13208)
		(layer "F.Cu")
		(net "SMB_BIC_I2C9_MUX1_SSD12_R_SDA")
	)
	(segment
		(start 368.06124 -81.498694)
		(end 369.095528 -81.498694)
		(width 0.13208)
		(layer "F.Cu")
		(net "SMB_BIC_I2C9_MUX1_SSD12_R_SDA")
	)
	(segment
		(start 375.76252 -22.537166)
		(end 375.76252 -22.097492)
		(width 0.13208)
		(layer "F.Cu")
		(net "SMB_BIC_I2C9_MUX1_SSD12_R_SDA")
	)
	(via
		(at 368.06124 -81.498694)
		(size 0.508)
		(drill 0.254)
		(layers "F.Cu" "B.Cu")
		(net "SMB_BIC_I2C9_MUX1_SSD12_R_SDA")
	)
	(via
		(at 381.986536 -75.069446)
		(size 0.508)
		(drill 0.254)
		(layers "F.Cu" "B.Cu")
		(net "SMB_BIC_I2C9_MUX1_SSD12_R_SDA")
	)
	(via
		(at 375.520712 -21.855684)
		(size 0.508)
		(drill 0.254)
		(layers "F.Cu" "B.Cu")
		(net "SMB_BIC_I2C9_MUX1_SSD12_R_SDA")
	)
	(segment
		(start 381.986536 -67.779646)
		(end 385.46913 -64.297052)
		(width 0.15494)
		(layer "In5.Cu")
		(net "SMB_BIC_I2C9_MUX1_SSD12_R_SDA")
	)
	(segment
		(start 373.31523 -21.291804)
		(end 374.956832 -21.291804)
		(width 0.15494)
		(layer "In5.Cu")
		(net "SMB_BIC_I2C9_MUX1_SSD12_R_SDA")
	)
	(segment
		(start 372.55704 -22.049994)
		(end 373.31523 -21.291804)
		(width 0.15494)
		(layer "In5.Cu")
		(net "SMB_BIC_I2C9_MUX1_SSD12_R_SDA")
	)
	(segment
		(start 372.59768 -30.149546)
		(end 373.380762 -29.366464)
		(width 0.15494)
		(layer "In5.Cu")
		(net "SMB_BIC_I2C9_MUX1_SSD12_R_SDA")
	)
	(segment
		(start 385.46913 -45.376084)
		(end 372.59768 -32.504634)
		(width 0.15494)
		(layer "In5.Cu")
		(net "SMB_BIC_I2C9_MUX1_SSD12_R_SDA")
	)
	(segment
		(start 372.59768 -32.504634)
		(end 372.59768 -30.149546)
		(width 0.15494)
		(layer "In5.Cu")
		(net "SMB_BIC_I2C9_MUX1_SSD12_R_SDA")
	)
	(segment
		(start 374.956832 -21.291804)
		(end 375.520712 -21.855684)
		(width 0.15494)
		(layer "In5.Cu")
		(net "SMB_BIC_I2C9_MUX1_SSD12_R_SDA")
	)
	(segment
		(start 381.986536 -75.069446)
		(end 381.986536 -67.779646)
		(width 0.15494)
		(layer "In5.Cu")
		(net "SMB_BIC_I2C9_MUX1_SSD12_R_SDA")
	)
	(segment
		(start 373.380762 -29.366464)
		(end 373.380762 -28.04414)
		(width 0.15494)
		(layer "In5.Cu")
		(net "SMB_BIC_I2C9_MUX1_SSD12_R_SDA")
	)
	(segment
		(start 372.55704 -27.220418)
		(end 372.55704 -22.049994)
		(width 0.15494)
		(layer "In5.Cu")
		(net "SMB_BIC_I2C9_MUX1_SSD12_R_SDA")
	)
	(segment
		(start 385.46913 -64.297052)
		(end 385.46913 -45.376084)
		(width 0.15494)
		(layer "In5.Cu")
		(net "SMB_BIC_I2C9_MUX1_SSD12_R_SDA")
	)
	(segment
		(start 373.380762 -28.04414)
		(end 372.55704 -27.220418)
		(width 0.15494)
		(layer "In5.Cu")
		(net "SMB_BIC_I2C9_MUX1_SSD12_R_SDA")
	)
	(segment
		(start 368.602006 -81.498694)
		(end 373.72544 -76.37526)
		(width 0.15494)
		(layer "In15.Cu")
		(net "SMB_BIC_I2C9_MUX1_SSD12_R_SDA")
	)
	(segment
		(start 376.238008 -76.37526)
		(end 378.006356 -74.606912)
		(width 0.15494)
		(layer "In15.Cu")
		(net "SMB_BIC_I2C9_MUX1_SSD12_R_SDA")
	)
	(segment
		(start 378.006356 -74.606912)
		(end 381.524002 -74.606912)
		(width 0.15494)
		(layer "In15.Cu")
		(net "SMB_BIC_I2C9_MUX1_SSD12_R_SDA")
	)
	(segment
		(start 381.524002 -74.606912)
		(end 381.986536 -75.069446)
		(width 0.15494)
		(layer "In15.Cu")
		(net "SMB_BIC_I2C9_MUX1_SSD12_R_SDA")
	)
	(segment
		(start 368.06124 -81.498694)
		(end 368.602006 -81.498694)
		(width 0.15494)
		(layer "In15.Cu")
		(net "SMB_BIC_I2C9_MUX1_SSD12_R_SDA")
	)
	(segment
		(start 373.72544 -76.37526)
		(end 376.238008 -76.37526)
		(width 0.15494)
		(layer "In15.Cu")
		(net "SMB_BIC_I2C9_MUX1_SSD12_R_SDA")
	)
	(segment
		(start 53.004466 -62.119764)
		(end 53.004466 -64.886332)
		(width 0.13208)
		(layer "F.Cu")
		(net "PWRGD_P12V_SSD2_R")
	)
	(segment
		(start 55.483506 -61.487812)
		(end 53.636418 -61.487812)
		(width 0.13208)
		(layer "F.Cu")
		(net "PWRGD_P12V_SSD2_R")
	)
	(segment
		(start 53.004466 -64.886332)
		(end 53.873654 -65.75552)
		(width 0.13208)
		(layer "F.Cu")
		(net "PWRGD_P12V_SSD2_R")
	)
	(segment
		(start 339.693758 -223.987106)
		(end 339.293962 -224.386902)
		(width 0.13208)
		(layer "F.Cu")
		(net "PWRGD_P12V_SSD2_R")
	)
	(segment
		(start 53.636418 -61.487812)
		(end 53.004466 -62.119764)
		(width 0.13208)
		(layer "F.Cu")
		(net "PWRGD_P12V_SSD2_R")
	)
	(segment
		(start 78.667864 -53.051456)
		(end 79.323184 -53.051456)
		(width 0.13208)
		(layer "F.Cu")
		(net "PWRGD_P12V_SSD2_R")
	)
	(segment
		(start 53.873654 -65.75552)
		(end 66.728594 -65.75552)
		(width 0.13208)
		(layer "F.Cu")
		(net "PWRGD_P12V_SSD2_R")
	)
	(via
		(at 343.96299 -230.250492)
		(size 0.508)
		(drill 0.254)
		(layers "F.Cu" "B.Cu")
		(net "PWRGD_P12V_SSD2_R")
	)
	(via
		(at 79.323184 -53.051456)
		(size 0.508)
		(drill 0.254)
		(layers "F.Cu" "B.Cu")
		(net "PWRGD_P12V_SSD2_R")
	)
	(via
		(at 66.728594 -65.75552)
		(size 0.508)
		(drill 0.254)
		(layers "F.Cu" "B.Cu")
		(net "PWRGD_P12V_SSD2_R")
	)
	(via
		(at 339.293962 -224.386902)
		(size 0.4572)
		(drill 0.254)
		(layers "F.Cu" "B.Cu")
		(net "PWRGD_P12V_SSD2_R")
	)
	(via
		(at 69.620384 -208.46415)
		(size 0.508)
		(drill 0.254)
		(layers "F.Cu" "B.Cu")
		(net "PWRGD_P12V_SSD2_R")
	)
	(segment
		(start 341.99703 -223.186752)
		(end 341.919306 -223.186752)
		(width 0.15494)
		(layer "In5.Cu")
		(net "PWRGD_P12V_SSD2_R")
	)
	(segment
		(start 343.962736 -230.250492)
		(end 343.789254 -230.07701)
		(width 0.15494)
		(layer "In5.Cu")
		(net "PWRGD_P12V_SSD2_R")
	)
	(segment
		(start 70.218046 -65.75552)
		(end 71.356474 -64.617092)
		(width 0.15494)
		(layer "In5.Cu")
		(net "PWRGD_P12V_SSD2_R")
	)
	(segment
		(start 79.91729 -62.09411)
		(end 79.91729 -53.631338)
		(width 0.15494)
		(layer "In5.Cu")
		(net "PWRGD_P12V_SSD2_R")
	)
	(segment
		(start 60.9092 -93.862144)
		(end 80.3402 -74.431144)
		(width 0.15494)
		(layer "In5.Cu")
		(net "PWRGD_P12V_SSD2_R")
	)
	(segment
		(start 79.337408 -53.051456)
		(end 79.323184 -53.051456)
		(width 0.15494)
		(layer "In5.Cu")
		(net "PWRGD_P12V_SSD2_R")
	)
	(segment
		(start 342.857836 -225.081592)
		(end 342.163654 -224.38741)
		(width 0.15494)
		(layer "In5.Cu")
		(net "PWRGD_P12V_SSD2_R")
	)
	(segment
		(start 69.620384 -206.582772)
		(end 65.320164 -202.282552)
		(width 0.15494)
		(layer "In5.Cu")
		(net "PWRGD_P12V_SSD2_R")
	)
	(segment
		(start 77.251306 -56.855106)
		(end 77.251306 -55.10911)
		(width 0.15494)
		(layer "In5.Cu")
		(net "PWRGD_P12V_SSD2_R")
	)
	(segment
		(start 77.743812 -57.347612)
		(end 77.251306 -56.855106)
		(width 0.15494)
		(layer "In5.Cu")
		(net "PWRGD_P12V_SSD2_R")
	)
	(segment
		(start 80.3402 -74.431144)
		(end 80.3402 -62.51702)
		(width 0.15494)
		(layer "In5.Cu")
		(net "PWRGD_P12V_SSD2_R")
	)
	(segment
		(start 342.857836 -227.291646)
		(end 342.857836 -225.081592)
		(width 0.15494)
		(layer "In5.Cu")
		(net "PWRGD_P12V_SSD2_R")
	)
	(segment
		(start 59.809126 -177.908204)
		(end 59.809126 -156.432504)
		(width 0.15494)
		(layer "In5.Cu")
		(net "PWRGD_P12V_SSD2_R")
	)
	(segment
		(start 339.69325 -223.387412)
		(end 339.69325 -223.987614)
		(width 0.0889)
		(layer "In5.Cu")
		(net "PWRGD_P12V_SSD2_R")
	)
	(segment
		(start 77.251306 -55.10911)
		(end 79.30896 -53.051456)
		(width 0.15494)
		(layer "In5.Cu")
		(net "PWRGD_P12V_SSD2_R")
	)
	(segment
		(start 59.809126 -156.432504)
		(end 60.9092 -155.33243)
		(width 0.15494)
		(layer "In5.Cu")
		(net "PWRGD_P12V_SSD2_R")
	)
	(segment
		(start 77.367384 -64.617092)
		(end 77.743812 -64.240664)
		(width 0.15494)
		(layer "In5.Cu")
		(net "PWRGD_P12V_SSD2_R")
	)
	(segment
		(start 339.69325 -223.987614)
		(end 339.293962 -224.386902)
		(width 0.0889)
		(layer "In5.Cu")
		(net "PWRGD_P12V_SSD2_R")
	)
	(segment
		(start 343.96299 -230.250492)
		(end 343.962736 -230.250492)
		(width 0.15494)
		(layer "In5.Cu")
		(net "PWRGD_P12V_SSD2_R")
	)
	(segment
		(start 342.163654 -224.38741)
		(end 342.163654 -223.353376)
		(width 0.15494)
		(layer "In5.Cu")
		(net "PWRGD_P12V_SSD2_R")
	)
	(segment
		(start 80.3402 -62.51702)
		(end 79.91729 -62.09411)
		(width 0.15494)
		(layer "In5.Cu")
		(net "PWRGD_P12V_SSD2_R")
	)
	(segment
		(start 66.728594 -65.75552)
		(end 70.218046 -65.75552)
		(width 0.15494)
		(layer "In5.Cu")
		(net "PWRGD_P12V_SSD2_R")
	)
	(segment
		(start 71.356474 -64.617092)
		(end 77.367384 -64.617092)
		(width 0.15494)
		(layer "In5.Cu")
		(net "PWRGD_P12V_SSD2_R")
	)
	(segment
		(start 79.91729 -53.631338)
		(end 79.337408 -53.051456)
		(width 0.15494)
		(layer "In5.Cu")
		(net "PWRGD_P12V_SSD2_R")
	)
	(segment
		(start 342.163654 -223.353376)
		(end 341.99703 -223.186752)
		(width 0.15494)
		(layer "In5.Cu")
		(net "PWRGD_P12V_SSD2_R")
	)
	(segment
		(start 69.620384 -208.46415)
		(end 69.620384 -206.582772)
		(width 0.15494)
		(layer "In5.Cu")
		(net "PWRGD_P12V_SSD2_R")
	)
	(segment
		(start 339.89391 -223.186752)
		(end 339.69325 -223.387412)
		(width 0.0889)
		(layer "In5.Cu")
		(net "PWRGD_P12V_SSD2_R")
	)
	(segment
		(start 65.320164 -202.282552)
		(end 65.320164 -183.419242)
		(width 0.15494)
		(layer "In5.Cu")
		(net "PWRGD_P12V_SSD2_R")
	)
	(segment
		(start 60.9092 -155.33243)
		(end 60.9092 -93.862144)
		(width 0.15494)
		(layer "In5.Cu")
		(net "PWRGD_P12V_SSD2_R")
	)
	(segment
		(start 65.320164 -183.419242)
		(end 59.809126 -177.908204)
		(width 0.15494)
		(layer "In5.Cu")
		(net "PWRGD_P12V_SSD2_R")
	)
	(segment
		(start 343.789254 -230.07701)
		(end 343.789254 -228.223064)
		(width 0.15494)
		(layer "In5.Cu")
		(net "PWRGD_P12V_SSD2_R")
	)
	(segment
		(start 341.919306 -223.186752)
		(end 339.89391 -223.186752)
		(width 0.0889)
		(layer "In5.Cu")
		(net "PWRGD_P12V_SSD2_R")
	)
	(segment
		(start 79.30896 -53.051456)
		(end 79.323184 -53.051456)
		(width 0.15494)
		(layer "In5.Cu")
		(net "PWRGD_P12V_SSD2_R")
	)
	(segment
		(start 343.789254 -228.223064)
		(end 342.857836 -227.291646)
		(width 0.15494)
		(layer "In5.Cu")
		(net "PWRGD_P12V_SSD2_R")
	)
	(segment
		(start 77.743812 -64.240664)
		(end 77.743812 -57.347612)
		(width 0.15494)
		(layer "In5.Cu")
		(net "PWRGD_P12V_SSD2_R")
	)
	(segment
		(start 323.115686 -235.36402)
		(end 322.890388 -235.138722)
		(width 0.15494)
		(layer "In13.Cu")
		(net "PWRGD_P12V_SSD2_R")
	)
	(segment
		(start 343.96299 -230.250492)
		(end 343.96299 -230.63581)
		(width 0.15494)
		(layer "In13.Cu")
		(net "PWRGD_P12V_SSD2_R")
	)
	(segment
		(start 218.616784 -220.539056)
		(end 217.792046 -220.539056)
		(width 0.15494)
		(layer "In13.Cu")
		(net "PWRGD_P12V_SSD2_R")
	)
	(segment
		(start 209.7913 -217.436954)
		(end 206.57693 -217.436954)
		(width 0.15494)
		(layer "In13.Cu")
		(net "PWRGD_P12V_SSD2_R")
	)
	(segment
		(start 231.696514 -211.88934)
		(end 231.368854 -212.217)
		(width 0.15494)
		(layer "In13.Cu")
		(net "PWRGD_P12V_SSD2_R")
	)
	(segment
		(start 259.1435 -230.199184)
		(end 257.333496 -228.38918)
		(width 0.15494)
		(layer "In13.Cu")
		(net "PWRGD_P12V_SSD2_R")
	)
	(segment
		(start 272.481548 -230.199184)
		(end 259.1435 -230.199184)
		(width 0.15494)
		(layer "In13.Cu")
		(net "PWRGD_P12V_SSD2_R")
	)
	(segment
		(start 249.484642 -227.208588)
		(end 247.292622 -227.208588)
		(width 0.15494)
		(layer "In13.Cu")
		(net "PWRGD_P12V_SSD2_R")
	)
	(segment
		(start 343.580974 -231.017826)
		(end 341.472774 -231.017826)
		(width 0.15494)
		(layer "In13.Cu")
		(net "PWRGD_P12V_SSD2_R")
	)
	(segment
		(start 326.191372 -234.856274)
		(end 325.683626 -235.36402)
		(width 0.15494)
		(layer "In13.Cu")
		(net "PWRGD_P12V_SSD2_R")
	)
	(segment
		(start 148.69287 -217.574876)
		(end 125.957076 -217.574876)
		(width 0.15494)
		(layer "In13.Cu")
		(net "PWRGD_P12V_SSD2_R")
	)
	(segment
		(start 234.1118 -212.37194)
		(end 233.6292 -211.88934)
		(width 0.15494)
		(layer "In13.Cu")
		(net "PWRGD_P12V_SSD2_R")
	)
	(segment
		(start 221.408752 -217.747088)
		(end 218.616784 -220.539056)
		(width 0.15494)
		(layer "In13.Cu")
		(net "PWRGD_P12V_SSD2_R")
	)
	(segment
		(start 116.2558 -208.788)
		(end 99.7458 -208.788)
		(width 0.15494)
		(layer "In13.Cu")
		(net "PWRGD_P12V_SSD2_R")
	)
	(segment
		(start 151.152352 -215.244934)
		(end 151.081486 -215.3158)
		(width 0.15494)
		(layer "In13.Cu")
		(net "PWRGD_P12V_SSD2_R")
	)
	(segment
		(start 151.081486 -215.3158)
		(end 150.951946 -215.3158)
		(width 0.15494)
		(layer "In13.Cu")
		(net "PWRGD_P12V_SSD2_R")
	)
	(segment
		(start 341.472774 -231.017826)
		(end 339.704934 -232.785666)
		(width 0.15494)
		(layer "In13.Cu")
		(net "PWRGD_P12V_SSD2_R")
	)
	(segment
		(start 257.333496 -228.38918)
		(end 252.371098 -228.38918)
		(width 0.15494)
		(layer "In13.Cu")
		(net "PWRGD_P12V_SSD2_R")
	)
	(segment
		(start 221.408752 -215.522302)
		(end 221.408752 -217.747088)
		(width 0.15494)
		(layer "In13.Cu")
		(net "PWRGD_P12V_SSD2_R")
	)
	(segment
		(start 335.30921 -232.785666)
		(end 333.055722 -235.039154)
		(width 0.15494)
		(layer "In13.Cu")
		(net "PWRGD_P12V_SSD2_R")
	)
	(segment
		(start 251.174504 -228.89845)
		(end 249.484642 -227.208588)
		(width 0.15494)
		(layer "In13.Cu")
		(net "PWRGD_P12V_SSD2_R")
	)
	(segment
		(start 235.682282 -214.711026)
		(end 235.682282 -214.473282)
		(width 0.15494)
		(layer "In13.Cu")
		(net "PWRGD_P12V_SSD2_R")
	)
	(segment
		(start 343.96299 -230.63581)
		(end 343.580974 -231.017826)
		(width 0.15494)
		(layer "In13.Cu")
		(net "PWRGD_P12V_SSD2_R")
	)
	(segment
		(start 332.494382 -234.856274)
		(end 326.191372 -234.856274)
		(width 0.15494)
		(layer "In13.Cu")
		(net "PWRGD_P12V_SSD2_R")
	)
	(segment
		(start 277.421086 -235.138722)
		(end 272.481548 -230.199184)
		(width 0.15494)
		(layer "In13.Cu")
		(net "PWRGD_P12V_SSD2_R")
	)
	(segment
		(start 150.951946 -215.3158)
		(end 148.69287 -217.574876)
		(width 0.15494)
		(layer "In13.Cu")
		(net "PWRGD_P12V_SSD2_R")
	)
	(segment
		(start 216.686638 -218.821)
		(end 212.73643 -218.821)
		(width 0.15494)
		(layer "In13.Cu")
		(net "PWRGD_P12V_SSD2_R")
	)
	(segment
		(start 223.444054 -213.487)
		(end 221.408752 -215.522302)
		(width 0.15494)
		(layer "In13.Cu")
		(net "PWRGD_P12V_SSD2_R")
	)
	(segment
		(start 252.371098 -228.38918)
		(end 251.861828 -228.89845)
		(width 0.15494)
		(layer "In13.Cu")
		(net "PWRGD_P12V_SSD2_R")
	)
	(segment
		(start 234.1118 -212.9028)
		(end 234.1118 -212.37194)
		(width 0.15494)
		(layer "In13.Cu")
		(net "PWRGD_P12V_SSD2_R")
	)
	(segment
		(start 123.2027 -215.7349)
		(end 116.2558 -208.788)
		(width 0.15494)
		(layer "In13.Cu")
		(net "PWRGD_P12V_SSD2_R")
	)
	(segment
		(start 212.251798 -218.336368)
		(end 210.690714 -218.336368)
		(width 0.15494)
		(layer "In13.Cu")
		(net "PWRGD_P12V_SSD2_R")
	)
	(segment
		(start 235.682282 -214.473282)
		(end 234.1118 -212.9028)
		(width 0.15494)
		(layer "In13.Cu")
		(net "PWRGD_P12V_SSD2_R")
	)
	(segment
		(start 76.451714 -209.34426)
		(end 75.570334 -208.46415)
		(width 0.15494)
		(layer "In13.Cu")
		(net "PWRGD_P12V_SSD2_R")
	)
	(segment
		(start 332.677262 -235.039154)
		(end 332.494382 -234.856274)
		(width 0.15494)
		(layer "In13.Cu")
		(net "PWRGD_P12V_SSD2_R")
	)
	(segment
		(start 124.1171 -215.7349)
		(end 123.2027 -215.7349)
		(width 0.15494)
		(layer "In13.Cu")
		(net "PWRGD_P12V_SSD2_R")
	)
	(segment
		(start 333.055722 -235.039154)
		(end 332.677262 -235.039154)
		(width 0.15494)
		(layer "In13.Cu")
		(net "PWRGD_P12V_SSD2_R")
	)
	(segment
		(start 224.7646 -213.487)
		(end 223.444054 -213.487)
		(width 0.15494)
		(layer "In13.Cu")
		(net "PWRGD_P12V_SSD2_R")
	)
	(segment
		(start 210.690714 -218.336368)
		(end 209.7913 -217.436954)
		(width 0.15494)
		(layer "In13.Cu")
		(net "PWRGD_P12V_SSD2_R")
	)
	(segment
		(start 322.890388 -235.138722)
		(end 277.421086 -235.138722)
		(width 0.15494)
		(layer "In13.Cu")
		(net "PWRGD_P12V_SSD2_R")
	)
	(segment
		(start 204.38491 -215.244934)
		(end 151.152352 -215.244934)
		(width 0.15494)
		(layer "In13.Cu")
		(net "PWRGD_P12V_SSD2_R")
	)
	(segment
		(start 212.73643 -218.821)
		(end 212.251798 -218.336368)
		(width 0.15494)
		(layer "In13.Cu")
		(net "PWRGD_P12V_SSD2_R")
	)
	(segment
		(start 217.22461 -219.358972)
		(end 216.686638 -218.821)
		(width 0.15494)
		(layer "In13.Cu")
		(net "PWRGD_P12V_SSD2_R")
	)
	(segment
		(start 325.683626 -235.36402)
		(end 323.115686 -235.36402)
		(width 0.15494)
		(layer "In13.Cu")
		(net "PWRGD_P12V_SSD2_R")
	)
	(segment
		(start 240.15065 -222.821754)
		(end 240.15065 -219.179394)
		(width 0.15494)
		(layer "In13.Cu")
		(net "PWRGD_P12V_SSD2_R")
	)
	(segment
		(start 217.792046 -220.539056)
		(end 217.22461 -219.97162)
		(width 0.15494)
		(layer "In13.Cu")
		(net "PWRGD_P12V_SSD2_R")
	)
	(segment
		(start 125.957076 -217.574876)
		(end 124.1171 -215.7349)
		(width 0.15494)
		(layer "In13.Cu")
		(net "PWRGD_P12V_SSD2_R")
	)
	(segment
		(start 229.616254 -212.217)
		(end 229.159054 -211.7598)
		(width 0.15494)
		(layer "In13.Cu")
		(net "PWRGD_P12V_SSD2_R")
	)
	(segment
		(start 233.6292 -211.88934)
		(end 231.696514 -211.88934)
		(width 0.15494)
		(layer "In13.Cu")
		(net "PWRGD_P12V_SSD2_R")
	)
	(segment
		(start 339.704934 -232.785666)
		(end 335.30921 -232.785666)
		(width 0.15494)
		(layer "In13.Cu")
		(net "PWRGD_P12V_SSD2_R")
	)
	(segment
		(start 99.7458 -208.788)
		(end 99.18954 -209.34426)
		(width 0.15494)
		(layer "In13.Cu")
		(net "PWRGD_P12V_SSD2_R")
	)
	(segment
		(start 99.18954 -209.34426)
		(end 76.451714 -209.34426)
		(width 0.15494)
		(layer "In13.Cu")
		(net "PWRGD_P12V_SSD2_R")
	)
	(segment
		(start 240.15065 -219.179394)
		(end 235.682282 -214.711026)
		(width 0.15494)
		(layer "In13.Cu")
		(net "PWRGD_P12V_SSD2_R")
	)
	(segment
		(start 75.570334 -208.46415)
		(end 69.620384 -208.46415)
		(width 0.15494)
		(layer "In13.Cu")
		(net "PWRGD_P12V_SSD2_R")
	)
	(segment
		(start 226.4918 -211.7598)
		(end 224.7646 -213.487)
		(width 0.15494)
		(layer "In13.Cu")
		(net "PWRGD_P12V_SSD2_R")
	)
	(segment
		(start 231.368854 -212.217)
		(end 229.616254 -212.217)
		(width 0.15494)
		(layer "In13.Cu")
		(net "PWRGD_P12V_SSD2_R")
	)
	(segment
		(start 244.582442 -224.498408)
		(end 241.827304 -224.498408)
		(width 0.15494)
		(layer "In13.Cu")
		(net "PWRGD_P12V_SSD2_R")
	)
	(segment
		(start 206.57693 -217.436954)
		(end 204.38491 -215.244934)
		(width 0.15494)
		(layer "In13.Cu")
		(net "PWRGD_P12V_SSD2_R")
	)
	(segment
		(start 251.861828 -228.89845)
		(end 251.174504 -228.89845)
		(width 0.15494)
		(layer "In13.Cu")
		(net "PWRGD_P12V_SSD2_R")
	)
	(segment
		(start 217.22461 -219.97162)
		(end 217.22461 -219.358972)
		(width 0.15494)
		(layer "In13.Cu")
		(net "PWRGD_P12V_SSD2_R")
	)
	(segment
		(start 229.159054 -211.7598)
		(end 226.4918 -211.7598)
		(width 0.15494)
		(layer "In13.Cu")
		(net "PWRGD_P12V_SSD2_R")
	)
	(segment
		(start 247.292622 -227.208588)
		(end 244.582442 -224.498408)
		(width 0.15494)
		(layer "In13.Cu")
		(net "PWRGD_P12V_SSD2_R")
	)
	(segment
		(start 241.827304 -224.498408)
		(end 240.15065 -222.821754)
		(width 0.15494)
		(layer "In13.Cu")
		(net "PWRGD_P12V_SSD2_R")
	)
	(segment
		(start 386.50799 -160.841436)
		(end 386.50799 -160.380934)
		(width 0.13208)
		(layer "F.Cu")
		(net "NIC6_MAIN_PWR_EN")
	)
	(segment
		(start 386.50799 -159.4104)
		(end 386.50799 -160.380934)
		(width 0.13208)
		(layer "F.Cu")
		(net "NIC6_MAIN_PWR_EN")
	)
	(segment
		(start 386.265166 -161.08426)
		(end 386.50799 -160.841436)
		(width 0.13208)
		(layer "F.Cu")
		(net "NIC6_MAIN_PWR_EN")
	)
	(segment
		(start 346.093796 -218.387168)
		(end 346.493592 -217.987372)
		(width 0.13208)
		(layer "F.Cu")
		(net "NIC6_MAIN_PWR_EN")
	)
	(via
		(at 346.493592 -217.987372)
		(size 0.4572)
		(drill 0.254)
		(layers "F.Cu" "B.Cu")
		(net "NIC6_MAIN_PWR_EN")
	)
	(via
		(at 363.342174 -167.170862)
		(size 0.508)
		(drill 0.254)
		(layers "F.Cu" "B.Cu")
		(net "NIC6_MAIN_PWR_EN")
	)
	(via
		(at 386.265166 -161.08426)
		(size 0.508)
		(drill 0.254)
		(layers "F.Cu" "B.Cu")
		(net "NIC6_MAIN_PWR_EN")
	)
	(segment
		(start 354.736146 -202.42149)
		(end 358.8512 -198.306436)
		(width 0.15494)
		(layer "In9.Cu")
		(net "NIC6_MAIN_PWR_EN")
	)
	(segment
		(start 347.853254 -208.788)
		(end 352.5012 -208.788)
		(width 0.15494)
		(layer "In9.Cu")
		(net "NIC6_MAIN_PWR_EN")
	)
	(segment
		(start 354.568252 -204.47508)
		(end 354.736146 -204.307186)
		(width 0.15494)
		(layer "In9.Cu")
		(net "NIC6_MAIN_PWR_EN")
	)
	(segment
		(start 360.68 -169.833036)
		(end 363.342174 -167.170862)
		(width 0.15494)
		(layer "In9.Cu")
		(net "NIC6_MAIN_PWR_EN")
	)
	(segment
		(start 346.096082 -217.589862)
		(end 346.096082 -210.545172)
		(width 0.0889)
		(layer "In9.Cu")
		(net "NIC6_MAIN_PWR_EN")
	)
	(segment
		(start 354.568252 -206.720948)
		(end 354.568252 -204.47508)
		(width 0.15494)
		(layer "In9.Cu")
		(net "NIC6_MAIN_PWR_EN")
	)
	(segment
		(start 360.68 -189.6364)
		(end 360.68 -169.833036)
		(width 0.15494)
		(layer "In9.Cu")
		(net "NIC6_MAIN_PWR_EN")
	)
	(segment
		(start 358.8512 -194.226942)
		(end 359.179876 -193.898266)
		(width 0.15494)
		(layer "In9.Cu")
		(net "NIC6_MAIN_PWR_EN")
	)
	(segment
		(start 359.179876 -191.136524)
		(end 360.68 -189.6364)
		(width 0.15494)
		(layer "In9.Cu")
		(net "NIC6_MAIN_PWR_EN")
	)
	(segment
		(start 358.8512 -198.306436)
		(end 358.8512 -194.226942)
		(width 0.15494)
		(layer "In9.Cu")
		(net "NIC6_MAIN_PWR_EN")
	)
	(segment
		(start 352.5012 -208.788)
		(end 354.568252 -206.720948)
		(width 0.15494)
		(layer "In9.Cu")
		(net "NIC6_MAIN_PWR_EN")
	)
	(segment
		(start 346.493592 -217.987372)
		(end 346.096082 -217.589862)
		(width 0.0889)
		(layer "In9.Cu")
		(net "NIC6_MAIN_PWR_EN")
	)
	(segment
		(start 359.179876 -193.898266)
		(end 359.179876 -191.136524)
		(width 0.15494)
		(layer "In9.Cu")
		(net "NIC6_MAIN_PWR_EN")
	)
	(segment
		(start 346.096082 -210.545172)
		(end 347.853254 -208.788)
		(width 0.15494)
		(layer "In9.Cu")
		(net "NIC6_MAIN_PWR_EN")
	)
	(segment
		(start 354.736146 -204.307186)
		(end 354.736146 -202.42149)
		(width 0.15494)
		(layer "In9.Cu")
		(net "NIC6_MAIN_PWR_EN")
	)
	(segment
		(start 372.892828 -167.170862)
		(end 363.342174 -167.170862)
		(width 0.15494)
		(layer "In13.Cu")
		(net "NIC6_MAIN_PWR_EN")
	)
	(segment
		(start 386.265166 -161.08426)
		(end 378.97943 -161.08426)
		(width 0.15494)
		(layer "In13.Cu")
		(net "NIC6_MAIN_PWR_EN")
	)
	(segment
		(start 378.97943 -161.08426)
		(end 372.892828 -167.170862)
		(width 0.15494)
		(layer "In13.Cu")
		(net "NIC6_MAIN_PWR_EN")
	)
	(segment
		(start 256.530602 -53.144166)
		(end 256.679954 -52.994814)
		(width 0.13208)
		(layer "F.Cu")
		(net "P12V_SSD8_SS")
	)
	(segment
		(start 256.679954 -51.670966)
		(end 257.331464 -51.019456)
		(width 0.13208)
		(layer "F.Cu")
		(net "P12V_SSD8_SS")
	)
	(segment
		(start 257.331464 -51.019456)
		(end 258.06781 -51.019456)
		(width 0.13208)
		(layer "F.Cu")
		(net "P12V_SSD8_SS")
	)
	(segment
		(start 256.347214 -53.144166)
		(end 256.530602 -53.144166)
		(width 0.13208)
		(layer "F.Cu")
		(net "P12V_SSD8_SS")
	)
	(segment
		(start 256.679954 -52.994814)
		(end 256.679954 -51.670966)
		(width 0.13208)
		(layer "F.Cu")
		(net "P12V_SSD8_SS")
	)
	(via
		(at 257.331464 -51.019456)
		(size 0.508)
		(drill 0.254)
		(layers "F.Cu" "B.Cu")
		(net "P12V_SSD8_SS")
	)
	(segment
		(start 384.117088 -245.421912)
		(end 382.524 -247.015)
		(width 0.13208)
		(layer "F.Cu")
		(net "UART_PEX2_SDB_BUF_TX")
	)
	(segment
		(start 385.355592 -244.286024)
		(end 385.355592 -245.326408)
		(width 0.13208)
		(layer "F.Cu")
		(net "UART_PEX2_SDB_BUF_TX")
	)
	(segment
		(start 385.355592 -245.326408)
		(end 385.260088 -245.421912)
		(width 0.13208)
		(layer "F.Cu")
		(net "UART_PEX2_SDB_BUF_TX")
	)
	(segment
		(start 385.260088 -245.421912)
		(end 384.117088 -245.421912)
		(width 0.13208)
		(layer "F.Cu")
		(net "UART_PEX2_SDB_BUF_TX")
	)
	(segment
		(start 382.524 -247.015)
		(end 379.857 -247.015)
		(width 0.13208)
		(layer "F.Cu")
		(net "UART_PEX2_SDB_BUF_TX")
	)
	(via
		(at 379.857 -247.015)
		(size 0.508)
		(drill 0.254)
		(layers "F.Cu" "B.Cu")
		(net "UART_PEX2_SDB_BUF_TX")
	)
	(segment
		(start 379.45695 -246.61495)
		(end 379.857 -247.015)
		(width 0.13208)
		(layer "B.Cu")
		(net "UART_PEX2_SDB_BUF_TX")
	)
	(segment
		(start 378.47905 -245.872)
		(end 379.45695 -245.872)
		(width 0.13208)
		(layer "B.Cu")
		(net "UART_PEX2_SDB_BUF_TX")
	)
	(segment
		(start 379.45695 -245.872)
		(end 379.45695 -246.61495)
		(width 0.13208)
		(layer "B.Cu")
		(net "UART_PEX2_SDB_BUF_TX")
	)
	(segment
		(start 335.42732 -79.881984)
		(end 335.42732 -79.182976)
		(width 0.13462)
		(layer "F.Cu")
		(net "CLK_100M_DB800ZL_SSD8_R_DN")
	)
	(segment
		(start 248.13641 -26.7716)
		(end 247.9548 -26.58999)
		(width 0.13462)
		(layer "F.Cu")
		(net "CLK_100M_DB800ZL_SSD8_R_DN")
	)
	(segment
		(start 247.9548 -26.58999)
		(end 247.464834 -26.58999)
		(width 0.13462)
		(layer "F.Cu")
		(net "CLK_100M_DB800ZL_SSD8_R_DN")
	)
	(segment
		(start 248.889012 -26.7716)
		(end 248.13641 -26.7716)
		(width 0.13462)
		(layer "F.Cu")
		(net "CLK_100M_DB800ZL_SSD8_R_DN")
	)
	(segment
		(start 335.752948 -80.207612)
		(end 335.42732 -79.881984)
		(width 0.13462)
		(layer "F.Cu")
		(net "CLK_100M_DB800ZL_SSD8_R_DN")
	)
	(segment
		(start 249.181366 -26.479246)
		(end 248.889012 -26.7716)
		(width 0.13462)
		(layer "F.Cu")
		(net "CLK_100M_DB800ZL_SSD8_R_DN")
	)
	(segment
		(start 335.42732 -79.182976)
		(end 335.727548 -78.882748)
		(width 0.13462)
		(layer "F.Cu")
		(net "CLK_100M_DB800ZL_SSD8_R_DN")
	)
	(via
		(at 335.727548 -78.882748)
		(size 0.508)
		(drill 0.254)
		(layers "F.Cu" "B.Cu")
		(net "CLK_100M_DB800ZL_SSD8_R_DN")
	)
	(via
		(at 249.181366 -26.479246)
		(size 0.508)
		(drill 0.254)
		(layers "F.Cu" "B.Cu")
		(net "CLK_100M_DB800ZL_SSD8_R_DN")
	)
	(segment
		(start 250.841256 -26.770076)
		(end 251.22124 -27.15006)
		(width 0.1651)
		(layer "In13.Cu")
		(net "CLK_100M_DB800ZL_SSD8_R_DN")
	)
	(segment
		(start 270.25854 -59.62396)
		(end 276.79904 -66.16446)
		(width 0.1651)
		(layer "In13.Cu")
		(net "CLK_100M_DB800ZL_SSD8_R_DN")
	)
	(segment
		(start 252.99924 -27.68346)
		(end 253.71044 -27.68346)
		(width 0.1651)
		(layer "In13.Cu")
		(net "CLK_100M_DB800ZL_SSD8_R_DN")
	)
	(segment
		(start 253.71044 -27.68346)
		(end 256.69494 -30.66796)
		(width 0.1651)
		(layer "In13.Cu")
		(net "CLK_100M_DB800ZL_SSD8_R_DN")
	)
	(segment
		(start 323.38264 -77.01026)
		(end 334.99044 -77.01026)
		(width 0.1651)
		(layer "In13.Cu")
		(net "CLK_100M_DB800ZL_SSD8_R_DN")
	)
	(segment
		(start 249.472196 -26.770076)
		(end 250.841256 -26.770076)
		(width 0.1651)
		(layer "In13.Cu")
		(net "CLK_100M_DB800ZL_SSD8_R_DN")
	)
	(segment
		(start 335.436718 -77.456538)
		(end 335.436718 -78.591918)
		(width 0.1651)
		(layer "In13.Cu")
		(net "CLK_100M_DB800ZL_SSD8_R_DN")
	)
	(segment
		(start 314.51931 -68.14693)
		(end 323.38264 -77.01026)
		(width 0.1651)
		(layer "In13.Cu")
		(net "CLK_100M_DB800ZL_SSD8_R_DN")
	)
	(segment
		(start 252.46584 -27.15006)
		(end 252.99924 -27.68346)
		(width 0.1651)
		(layer "In13.Cu")
		(net "CLK_100M_DB800ZL_SSD8_R_DN")
	)
	(segment
		(start 256.69494 -33.69056)
		(end 270.25854 -47.25416)
		(width 0.1651)
		(layer "In13.Cu")
		(net "CLK_100M_DB800ZL_SSD8_R_DN")
	)
	(segment
		(start 270.25854 -47.25416)
		(end 270.25854 -59.62396)
		(width 0.1651)
		(layer "In13.Cu")
		(net "CLK_100M_DB800ZL_SSD8_R_DN")
	)
	(segment
		(start 335.436718 -78.591918)
		(end 335.727548 -78.882748)
		(width 0.1651)
		(layer "In13.Cu")
		(net "CLK_100M_DB800ZL_SSD8_R_DN")
	)
	(segment
		(start 334.99044 -77.01026)
		(end 335.436718 -77.456538)
		(width 0.1651)
		(layer "In13.Cu")
		(net "CLK_100M_DB800ZL_SSD8_R_DN")
	)
	(segment
		(start 276.79904 -66.16446)
		(end 309.733442 -66.16446)
		(width 0.1651)
		(layer "In13.Cu")
		(net "CLK_100M_DB800ZL_SSD8_R_DN")
	)
	(segment
		(start 249.181366 -26.479246)
		(end 249.472196 -26.770076)
		(width 0.1651)
		(layer "In13.Cu")
		(net "CLK_100M_DB800ZL_SSD8_R_DN")
	)
	(segment
		(start 309.733442 -66.16446)
		(end 314.51931 -68.14693)
		(width 0.1651)
		(layer "In13.Cu")
		(net "CLK_100M_DB800ZL_SSD8_R_DN")
	)
	(segment
		(start 256.69494 -30.66796)
		(end 256.69494 -33.69056)
		(width 0.1651)
		(layer "In13.Cu")
		(net "CLK_100M_DB800ZL_SSD8_R_DN")
	)
	(segment
		(start 251.22124 -27.15006)
		(end 252.46584 -27.15006)
		(width 0.1651)
		(layer "In13.Cu")
		(net "CLK_100M_DB800ZL_SSD8_R_DN")
	)
	(segment
		(start 264.191242 -311.613296)
		(end 263.0678 -311.613296)
		(width 0.13208)
		(layer "F.Cu")
		(net "PU_PEX2_PAD_TRI_L")
	)
	(segment
		(start 263.0678 -311.613296)
		(end 262.744712 -311.290208)
		(width 0.13208)
		(layer "F.Cu")
		(net "PU_PEX2_PAD_TRI_L")
	)
	(segment
		(start 266.64158 -312.268108)
		(end 264.846054 -312.268108)
		(width 0.13208)
		(layer "F.Cu")
		(net "PU_PEX2_PAD_TRI_L")
	)
	(segment
		(start 264.846054 -312.268108)
		(end 264.191242 -311.613296)
		(width 0.13208)
		(layer "F.Cu")
		(net "PU_PEX2_PAD_TRI_L")
	)
	(via
		(at 266.64158 -312.268108)
		(size 0.508)
		(drill 0.254)
		(layers "F.Cu" "B.Cu")
		(net "PU_PEX2_PAD_TRI_L")
	)
	(via
		(at 283.299916 -309.199788)
		(size 0.4064)
		(drill 0.2032)
		(layers "F.Cu" "B.Cu")
		(net "PU_PEX2_PAD_TRI_L")
	)
	(segment
		(start 266.895072 -312.5216)
		(end 282.4226 -312.5216)
		(width 0.13208)
		(layer "B.Cu")
		(net "PU_PEX2_PAD_TRI_L")
	)
	(segment
		(start 282.8544 -309.645304)
		(end 283.299916 -309.199788)
		(width 0.13208)
		(layer "B.Cu")
		(net "PU_PEX2_PAD_TRI_L")
	)
	(segment
		(start 282.4226 -312.5216)
		(end 282.8544 -312.0898)
		(width 0.13208)
		(layer "B.Cu")
		(net "PU_PEX2_PAD_TRI_L")
	)
	(segment
		(start 266.64158 -312.268108)
		(end 266.895072 -312.5216)
		(width 0.13208)
		(layer "B.Cu")
		(net "PU_PEX2_PAD_TRI_L")
	)
	(segment
		(start 282.8544 -312.0898)
		(end 282.8544 -309.645304)
		(width 0.13208)
		(layer "B.Cu")
		(net "PU_PEX2_PAD_TRI_L")
	)
	(segment
		(start 374.617996 -22.413976)
		(end 374.617996 -21.775674)
		(width 0.13208)
		(layer "F.Cu")
		(net "SMB_BIC_I2C9_MUX1_SSD12_R_SCL")
	)
	(segment
		(start 368.30889 -82.641694)
		(end 369.095528 -82.641694)
		(width 0.13208)
		(layer "F.Cu")
		(net "SMB_BIC_I2C9_MUX1_SSD12_R_SCL")
	)
	(segment
		(start 374.759474 -22.555454)
		(end 374.617996 -22.413976)
		(width 0.13208)
		(layer "F.Cu")
		(net "SMB_BIC_I2C9_MUX1_SSD12_R_SCL")
	)
	(segment
		(start 368.032792 -82.917792)
		(end 368.30889 -82.641694)
		(width 0.13208)
		(layer "F.Cu")
		(net "SMB_BIC_I2C9_MUX1_SSD12_R_SCL")
	)
	(segment
		(start 367.355628 -82.641694)
		(end 367.756694 -82.641694)
		(width 0.13208)
		(layer "F.Cu")
		(net "SMB_BIC_I2C9_MUX1_SSD12_R_SCL")
	)
	(segment
		(start 374.617996 -21.775674)
		(end 374.585484 -21.743162)
		(width 0.13208)
		(layer "F.Cu")
		(net "SMB_BIC_I2C9_MUX1_SSD12_R_SCL")
	)
	(segment
		(start 367.756694 -82.641694)
		(end 368.032792 -82.917792)
		(width 0.13208)
		(layer "F.Cu")
		(net "SMB_BIC_I2C9_MUX1_SSD12_R_SCL")
	)
	(segment
		(start 374.585484 -21.743162)
		(end 374.585484 -20.789392)
		(width 0.13208)
		(layer "F.Cu")
		(net "SMB_BIC_I2C9_MUX1_SSD12_R_SCL")
	)
	(via
		(at 368.032792 -82.917792)
		(size 0.508)
		(drill 0.254)
		(layers "F.Cu" "B.Cu")
		(net "SMB_BIC_I2C9_MUX1_SSD12_R_SCL")
	)
	(via
		(at 380.351284 -75.152758)
		(size 0.508)
		(drill 0.254)
		(layers "F.Cu" "B.Cu")
		(net "SMB_BIC_I2C9_MUX1_SSD12_R_SCL")
	)
	(via
		(at 374.617996 -21.775674)
		(size 0.508)
		(drill 0.254)
		(layers "F.Cu" "B.Cu")
		(net "SMB_BIC_I2C9_MUX1_SSD12_R_SCL")
	)
	(segment
		(start 374.142508 -28.155646)
		(end 373.01678 -27.029918)
		(width 0.15494)
		(layer "In5.Cu")
		(net "SMB_BIC_I2C9_MUX1_SSD12_R_SCL")
	)
	(segment
		(start 374.142508 -29.984446)
		(end 374.142508 -28.155646)
		(width 0.15494)
		(layer "In5.Cu")
		(net "SMB_BIC_I2C9_MUX1_SSD12_R_SCL")
	)
	(segment
		(start 385.92887 -64.544448)
		(end 385.92887 -45.185584)
		(width 0.15494)
		(layer "In5.Cu")
		(net "SMB_BIC_I2C9_MUX1_SSD12_R_SCL")
	)
	(segment
		(start 373.084598 -31.042356)
		(end 374.142508 -29.984446)
		(width 0.15494)
		(layer "In5.Cu")
		(net "SMB_BIC_I2C9_MUX1_SSD12_R_SCL")
	)
	(segment
		(start 382.525778 -75.60437)
		(end 382.525778 -67.94754)
		(width 0.15494)
		(layer "In5.Cu")
		(net "SMB_BIC_I2C9_MUX1_SSD12_R_SCL")
	)
	(segment
		(start 373.01678 -22.33676)
		(end 373.577866 -21.775674)
		(width 0.15494)
		(layer "In5.Cu")
		(net "SMB_BIC_I2C9_MUX1_SSD12_R_SCL")
	)
	(segment
		(start 380.351284 -75.152758)
		(end 380.351284 -75.482958)
		(width 0.15494)
		(layer "In5.Cu")
		(net "SMB_BIC_I2C9_MUX1_SSD12_R_SCL")
	)
	(segment
		(start 382.21031 -75.919838)
		(end 382.525778 -75.60437)
		(width 0.15494)
		(layer "In5.Cu")
		(net "SMB_BIC_I2C9_MUX1_SSD12_R_SCL")
	)
	(segment
		(start 373.01678 -27.029918)
		(end 373.01678 -22.33676)
		(width 0.15494)
		(layer "In5.Cu")
		(net "SMB_BIC_I2C9_MUX1_SSD12_R_SCL")
	)
	(segment
		(start 373.577866 -21.775674)
		(end 374.617996 -21.775674)
		(width 0.15494)
		(layer "In5.Cu")
		(net "SMB_BIC_I2C9_MUX1_SSD12_R_SCL")
	)
	(segment
		(start 385.92887 -45.185584)
		(end 373.084598 -32.341312)
		(width 0.15494)
		(layer "In5.Cu")
		(net "SMB_BIC_I2C9_MUX1_SSD12_R_SCL")
	)
	(segment
		(start 380.788164 -75.919838)
		(end 382.21031 -75.919838)
		(width 0.15494)
		(layer "In5.Cu")
		(net "SMB_BIC_I2C9_MUX1_SSD12_R_SCL")
	)
	(segment
		(start 382.525778 -67.94754)
		(end 385.92887 -64.544448)
		(width 0.15494)
		(layer "In5.Cu")
		(net "SMB_BIC_I2C9_MUX1_SSD12_R_SCL")
	)
	(segment
		(start 380.351284 -75.482958)
		(end 380.788164 -75.919838)
		(width 0.15494)
		(layer "In5.Cu")
		(net "SMB_BIC_I2C9_MUX1_SSD12_R_SCL")
	)
	(segment
		(start 373.084598 -32.341312)
		(end 373.084598 -31.042356)
		(width 0.15494)
		(layer "In5.Cu")
		(net "SMB_BIC_I2C9_MUX1_SSD12_R_SCL")
	)
	(segment
		(start 376.436128 -76.837794)
		(end 374.567196 -76.837794)
		(width 0.15494)
		(layer "In15.Cu")
		(net "SMB_BIC_I2C9_MUX1_SSD12_R_SCL")
	)
	(segment
		(start 374.567196 -76.837794)
		(end 368.763296 -82.641694)
		(width 0.15494)
		(layer "In15.Cu")
		(net "SMB_BIC_I2C9_MUX1_SSD12_R_SCL")
	)
	(segment
		(start 368.30889 -82.641694)
		(end 368.032792 -82.917792)
		(width 0.15494)
		(layer "In15.Cu")
		(net "SMB_BIC_I2C9_MUX1_SSD12_R_SCL")
	)
	(segment
		(start 378.121164 -75.152758)
		(end 376.436128 -76.837794)
		(width 0.15494)
		(layer "In15.Cu")
		(net "SMB_BIC_I2C9_MUX1_SSD12_R_SCL")
	)
	(segment
		(start 368.763296 -82.641694)
		(end 368.30889 -82.641694)
		(width 0.15494)
		(layer "In15.Cu")
		(net "SMB_BIC_I2C9_MUX1_SSD12_R_SCL")
	)
	(segment
		(start 380.351284 -75.152758)
		(end 378.121164 -75.152758)
		(width 0.15494)
		(layer "In15.Cu")
		(net "SMB_BIC_I2C9_MUX1_SSD12_R_SCL")
	)
	(segment
		(start 349.293942 -217.587068)
		(end 349.693738 -217.187272)
		(width 0.13208)
		(layer "F.Cu")
		(net "NIC7_CLK_EN_N")
	)
	(segment
		(start 357.61295 -214.376)
		(end 356.997 -214.376)
		(width 0.13208)
		(layer "F.Cu")
		(net "NIC7_CLK_EN_N")
	)
	(via
		(at 349.693738 -217.187272)
		(size 0.4572)
		(drill 0.254)
		(layers "F.Cu" "B.Cu")
		(net "NIC7_CLK_EN_N")
	)
	(via
		(at 356.997 -214.376)
		(size 0.508)
		(drill 0.254)
		(layers "F.Cu" "B.Cu")
		(net "NIC7_CLK_EN_N")
	)
	(segment
		(start 356.743 -214.122)
		(end 356.997 -214.376)
		(width 0.15494)
		(layer "In9.Cu")
		(net "NIC7_CLK_EN_N")
	)
	(segment
		(start 352.551238 -216.789762)
		(end 355.219 -214.122)
		(width 0.15494)
		(layer "In9.Cu")
		(net "NIC7_CLK_EN_N")
	)
	(segment
		(start 355.219 -214.122)
		(end 356.743 -214.122)
		(width 0.15494)
		(layer "In9.Cu")
		(net "NIC7_CLK_EN_N")
	)
	(segment
		(start 349.693738 -217.187272)
		(end 350.091248 -216.789762)
		(width 0.0889)
		(layer "In9.Cu")
		(net "NIC7_CLK_EN_N")
	)
	(segment
		(start 350.091248 -216.789762)
		(end 352.551238 -216.789762)
		(width 0.0889)
		(layer "In9.Cu")
		(net "NIC7_CLK_EN_N")
	)
	(segment
		(start 309.96382 -53.96357)
		(end 309.353966 -53.96357)
		(width 0.13208)
		(layer "F.Cu")
		(net "P12V_SSD10_OCP")
	)
	(segment
		(start 308.34711 -54.144164)
		(end 308.775354 -54.144164)
		(width 0.13208)
		(layer "F.Cu")
		(net "P12V_SSD10_OCP")
	)
	(segment
		(start 310.067706 -54.067456)
		(end 309.96382 -53.96357)
		(width 0.13208)
		(layer "F.Cu")
		(net "P12V_SSD10_OCP")
	)
	(segment
		(start 308.775354 -54.144164)
		(end 308.955948 -53.96357)
		(width 0.13208)
		(layer "F.Cu")
		(net "P12V_SSD10_OCP")
	)
	(segment
		(start 308.955948 -53.96357)
		(end 309.353966 -53.96357)
		(width 0.13208)
		(layer "F.Cu")
		(net "P12V_SSD10_OCP")
	)
	(via
		(at 309.353966 -53.96357)
		(size 0.508)
		(drill 0.254)
		(layers "F.Cu" "B.Cu")
		(net "P12V_SSD10_OCP")
	)
	(segment
		(start 132.117084 -209.167222)
		(end 132.216906 -209.0674)
		(width 0.13208)
		(layer "F.Cu")
		(net "UART_PEX3_CLI_BUF_TX")
	)
	(segment
		(start 133.284214 -214.667846)
		(end 133.284214 -211.873846)
		(width 0.13208)
		(layer "F.Cu")
		(net "UART_PEX3_CLI_BUF_TX")
	)
	(segment
		(start 132.692902 -208.9912)
		(end 133.220206 -208.463896)
		(width 0.13208)
		(layer "F.Cu")
		(net "UART_PEX3_CLI_BUF_TX")
	)
	(segment
		(start 132.117084 -210.706716)
		(end 132.117084 -209.167222)
		(width 0.13208)
		(layer "F.Cu")
		(net "UART_PEX3_CLI_BUF_TX")
	)
	(segment
		(start 133.220206 -208.463896)
		(end 133.831838 -208.463896)
		(width 0.13208)
		(layer "F.Cu")
		(net "UART_PEX3_CLI_BUF_TX")
	)
	(segment
		(start 133.284214 -211.873846)
		(end 132.117084 -210.706716)
		(width 0.13208)
		(layer "F.Cu")
		(net "UART_PEX3_CLI_BUF_TX")
	)
	(segment
		(start 132.4864 -208.9912)
		(end 132.692902 -208.9912)
		(width 0.13208)
		(layer "F.Cu")
		(net "UART_PEX3_CLI_BUF_TX")
	)
	(segment
		(start 132.216906 -209.0674)
		(end 132.4102 -209.0674)
		(width 0.13208)
		(layer "F.Cu")
		(net "UART_PEX3_CLI_BUF_TX")
	)
	(segment
		(start 132.4102 -209.0674)
		(end 132.4864 -208.9912)
		(width 0.13208)
		(layer "F.Cu")
		(net "UART_PEX3_CLI_BUF_TX")
	)
	(via
		(at 133.284214 -214.667846)
		(size 0.508)
		(drill 0.254)
		(layers "F.Cu" "B.Cu")
		(net "UART_PEX3_CLI_BUF_TX")
	)
	(segment
		(start 133.339586 -214.723218)
		(end 133.284214 -214.667846)
		(width 0.13208)
		(layer "B.Cu")
		(net "UART_PEX3_CLI_BUF_TX")
	)
	(segment
		(start 134.317486 -215.85682)
		(end 133.339586 -215.85682)
		(width 0.13208)
		(layer "B.Cu")
		(net "UART_PEX3_CLI_BUF_TX")
	)
	(segment
		(start 133.339586 -215.85682)
		(end 133.339586 -214.723218)
		(width 0.13208)
		(layer "B.Cu")
		(net "UART_PEX3_CLI_BUF_TX")
	)
	(segment
		(start 345.013026 -90.169746)
		(end 345.322652 -89.86012)
		(width 0.13462)
		(layer "F.Cu")
		(net "CLK_100M_DB800ZL_SSD14_R_DN")
	)
	(segment
		(start 416.216084 -26.75128)
		(end 416.054794 -26.58999)
		(width 0.13462)
		(layer "F.Cu")
		(net "CLK_100M_DB800ZL_SSD14_R_DN")
	)
	(segment
		(start 417.28136 -26.479246)
		(end 417.009326 -26.75128)
		(width 0.13462)
		(layer "F.Cu")
		(net "CLK_100M_DB800ZL_SSD14_R_DN")
	)
	(segment
		(start 345.322652 -89.86012)
		(end 346.815664 -89.86012)
		(width 0.13462)
		(layer "F.Cu")
		(net "CLK_100M_DB800ZL_SSD14_R_DN")
	)
	(segment
		(start 416.054794 -26.58999)
		(end 415.564828 -26.58999)
		(width 0.13462)
		(layer "F.Cu")
		(net "CLK_100M_DB800ZL_SSD14_R_DN")
	)
	(segment
		(start 417.009326 -26.75128)
		(end 416.216084 -26.75128)
		(width 0.13462)
		(layer "F.Cu")
		(net "CLK_100M_DB800ZL_SSD14_R_DN")
	)
	(segment
		(start 346.815664 -89.86012)
		(end 347.09989 -90.144346)
		(width 0.13462)
		(layer "F.Cu")
		(net "CLK_100M_DB800ZL_SSD14_R_DN")
	)
	(via
		(at 347.09989 -90.144346)
		(size 0.508)
		(drill 0.254)
		(layers "F.Cu" "B.Cu")
		(net "CLK_100M_DB800ZL_SSD14_R_DN")
	)
	(via
		(at 417.28136 -26.479246)
		(size 0.508)
		(drill 0.254)
		(layers "F.Cu" "B.Cu")
		(net "CLK_100M_DB800ZL_SSD14_R_DN")
	)
	(segment
		(start 418.18814 -36.81984)
		(end 418.18814 -27.062176)
		(width 0.1651)
		(layer "In13.Cu")
		(net "CLK_100M_DB800ZL_SSD14_R_DN")
	)
	(segment
		(start 417.89604 -26.770076)
		(end 417.57219 -26.770076)
		(width 0.1651)
		(layer "In13.Cu")
		(net "CLK_100M_DB800ZL_SSD14_R_DN")
	)
	(segment
		(start 350.75114 -87.49284)
		(end 350.75114 -81.24444)
		(width 0.1651)
		(layer "In13.Cu")
		(net "CLK_100M_DB800ZL_SSD14_R_DN")
	)
	(segment
		(start 418.18814 -27.062176)
		(end 417.89604 -26.770076)
		(width 0.1651)
		(layer "In13.Cu")
		(net "CLK_100M_DB800ZL_SSD14_R_DN")
	)
	(segment
		(start 351.50044 -80.49514)
		(end 362.04144 -80.49514)
		(width 0.1651)
		(layer "In13.Cu")
		(net "CLK_100M_DB800ZL_SSD14_R_DN")
	)
	(segment
		(start 350.75114 -81.24444)
		(end 351.50044 -80.49514)
		(width 0.1651)
		(layer "In13.Cu")
		(net "CLK_100M_DB800ZL_SSD14_R_DN")
	)
	(segment
		(start 410.295598 -65.616582)
		(end 412.2928 -60.7949)
		(width 0.1651)
		(layer "In13.Cu")
		(net "CLK_100M_DB800ZL_SSD14_R_DN")
	)
	(segment
		(start 347.39072 -89.853516)
		(end 348.390464 -89.853516)
		(width 0.1651)
		(layer "In13.Cu")
		(net "CLK_100M_DB800ZL_SSD14_R_DN")
	)
	(segment
		(start 365.92764 -76.60894)
		(end 399.30324 -76.60894)
		(width 0.1651)
		(layer "In13.Cu")
		(net "CLK_100M_DB800ZL_SSD14_R_DN")
	)
	(segment
		(start 362.04144 -80.49514)
		(end 365.92764 -76.60894)
		(width 0.1651)
		(layer "In13.Cu")
		(net "CLK_100M_DB800ZL_SSD14_R_DN")
	)
	(segment
		(start 412.2928 -60.7949)
		(end 412.2928 -42.71518)
		(width 0.1651)
		(layer "In13.Cu")
		(net "CLK_100M_DB800ZL_SSD14_R_DN")
	)
	(segment
		(start 347.09989 -90.144346)
		(end 347.39072 -89.853516)
		(width 0.1651)
		(layer "In13.Cu")
		(net "CLK_100M_DB800ZL_SSD14_R_DN")
	)
	(segment
		(start 412.2928 -42.71518)
		(end 418.18814 -36.81984)
		(width 0.1651)
		(layer "In13.Cu")
		(net "CLK_100M_DB800ZL_SSD14_R_DN")
	)
	(segment
		(start 399.30324 -76.60894)
		(end 410.295598 -65.616582)
		(width 0.1651)
		(layer "In13.Cu")
		(net "CLK_100M_DB800ZL_SSD14_R_DN")
	)
	(segment
		(start 417.57219 -26.770076)
		(end 417.28136 -26.479246)
		(width 0.1651)
		(layer "In13.Cu")
		(net "CLK_100M_DB800ZL_SSD14_R_DN")
	)
	(segment
		(start 348.390464 -89.853516)
		(end 350.75114 -87.49284)
		(width 0.1651)
		(layer "In13.Cu")
		(net "CLK_100M_DB800ZL_SSD14_R_DN")
	)
	(segment
		(start 286.149796 -309.199788)
		(end 286.624776 -308.724808)
		(width 0.127)
		(layer "F.Cu")
		(net "TP_PEX2_TDO")
	)
	(via
		(at 286.149796 -309.199788)
		(size 0.6604)
		(drill 0.3302)
		(layers "F.Cu" "B.Cu")
		(net "TP_PEX2_TDO")
	)
	(via
		(at 286.624776 -308.724808)
		(size 0.4064)
		(drill 0.2032)
		(layers "F.Cu" "B.Cu")
		(net "TP_PEX2_TDO")
	)
	(segment
		(start 286.149796 -309.199788)
		(end 286.624776 -308.724808)
		(width 0.13208)
		(layer "B.Cu")
		(net "TP_PEX2_TDO")
	)
	(segment
		(start 367.609882 -84.927694)
		(end 367.978436 -84.55914)
		(width 0.13208)
		(layer "F.Cu")
		(net "SMB_BIC_I2C9_MUX1_SSD13_R_SCL")
	)
	(segment
		(start 367.978436 -84.55914)
		(end 368.34699 -84.927694)
		(width 0.13208)
		(layer "F.Cu")
		(net "SMB_BIC_I2C9_MUX1_SSD13_R_SCL")
	)
	(segment
		(start 400.617944 -21.775674)
		(end 400.585432 -21.743162)
		(width 0.13208)
		(layer "F.Cu")
		(net "SMB_BIC_I2C9_MUX1_SSD13_R_SCL")
	)
	(segment
		(start 367.355628 -84.927694)
		(end 367.609882 -84.927694)
		(width 0.13208)
		(layer "F.Cu")
		(net "SMB_BIC_I2C9_MUX1_SSD13_R_SCL")
	)
	(segment
		(start 368.34699 -84.927694)
		(end 369.095528 -84.927694)
		(width 0.13208)
		(layer "F.Cu")
		(net "SMB_BIC_I2C9_MUX1_SSD13_R_SCL")
	)
	(segment
		(start 400.585432 -21.743162)
		(end 400.585432 -20.789392)
		(width 0.13208)
		(layer "F.Cu")
		(net "SMB_BIC_I2C9_MUX1_SSD13_R_SCL")
	)
	(segment
		(start 400.617944 -22.413976)
		(end 400.617944 -21.775674)
		(width 0.13208)
		(layer "F.Cu")
		(net "SMB_BIC_I2C9_MUX1_SSD13_R_SCL")
	)
	(segment
		(start 400.759422 -22.555454)
		(end 400.617944 -22.413976)
		(width 0.13208)
		(layer "F.Cu")
		(net "SMB_BIC_I2C9_MUX1_SSD13_R_SCL")
	)
	(via
		(at 400.617944 -21.775674)
		(size 0.508)
		(drill 0.254)
		(layers "F.Cu" "B.Cu")
		(net "SMB_BIC_I2C9_MUX1_SSD13_R_SCL")
	)
	(via
		(at 405.434038 -74.543158)
		(size 0.508)
		(drill 0.254)
		(layers "F.Cu" "B.Cu")
		(net "SMB_BIC_I2C9_MUX1_SSD13_R_SCL")
	)
	(via
		(at 367.978436 -84.55914)
		(size 0.508)
		(drill 0.254)
		(layers "F.Cu" "B.Cu")
		(net "SMB_BIC_I2C9_MUX1_SSD13_R_SCL")
	)
	(segment
		(start 400.16176 -30.061916)
		(end 400.16176 -28.18765)
		(width 0.15494)
		(layer "In5.Cu")
		(net "SMB_BIC_I2C9_MUX1_SSD13_R_SCL")
	)
	(segment
		(start 399.037048 -22.31644)
		(end 399.577814 -21.775674)
		(width 0.15494)
		(layer "In5.Cu")
		(net "SMB_BIC_I2C9_MUX1_SSD13_R_SCL")
	)
	(segment
		(start 406.246584 -74.259948)
		(end 406.246584 -69.679058)
		(width 0.15494)
		(layer "In5.Cu")
		(net "SMB_BIC_I2C9_MUX1_SSD13_R_SCL")
	)
	(segment
		(start 405.434038 -74.543158)
		(end 405.963374 -74.543158)
		(width 0.15494)
		(layer "In5.Cu")
		(net "SMB_BIC_I2C9_MUX1_SSD13_R_SCL")
	)
	(segment
		(start 406.246584 -69.679058)
		(end 411.969458 -63.956184)
		(width 0.15494)
		(layer "In5.Cu")
		(net "SMB_BIC_I2C9_MUX1_SSD13_R_SCL")
	)
	(segment
		(start 400.16176 -28.18765)
		(end 399.037048 -27.062938)
		(width 0.15494)
		(layer "In5.Cu")
		(net "SMB_BIC_I2C9_MUX1_SSD13_R_SCL")
	)
	(segment
		(start 399.577814 -21.775674)
		(end 400.617944 -21.775674)
		(width 0.15494)
		(layer "In5.Cu")
		(net "SMB_BIC_I2C9_MUX1_SSD13_R_SCL")
	)
	(segment
		(start 399.064226 -32.193992)
		(end 399.064226 -31.15945)
		(width 0.15494)
		(layer "In5.Cu")
		(net "SMB_BIC_I2C9_MUX1_SSD13_R_SCL")
	)
	(segment
		(start 399.064226 -31.15945)
		(end 400.16176 -30.061916)
		(width 0.15494)
		(layer "In5.Cu")
		(net "SMB_BIC_I2C9_MUX1_SSD13_R_SCL")
	)
	(segment
		(start 411.969458 -63.956184)
		(end 411.969458 -45.099224)
		(width 0.15494)
		(layer "In5.Cu")
		(net "SMB_BIC_I2C9_MUX1_SSD13_R_SCL")
	)
	(segment
		(start 405.963374 -74.543158)
		(end 406.246584 -74.259948)
		(width 0.15494)
		(layer "In5.Cu")
		(net "SMB_BIC_I2C9_MUX1_SSD13_R_SCL")
	)
	(segment
		(start 411.969458 -45.099224)
		(end 399.064226 -32.193992)
		(width 0.15494)
		(layer "In5.Cu")
		(net "SMB_BIC_I2C9_MUX1_SSD13_R_SCL")
	)
	(segment
		(start 399.037048 -27.062938)
		(end 399.037048 -22.31644)
		(width 0.15494)
		(layer "In5.Cu")
		(net "SMB_BIC_I2C9_MUX1_SSD13_R_SCL")
	)
	(segment
		(start 368.311176 -84.89188)
		(end 369.568476 -84.89188)
		(width 0.15494)
		(layer "In15.Cu")
		(net "SMB_BIC_I2C9_MUX1_SSD13_R_SCL")
	)
	(segment
		(start 371.793516 -83.36153)
		(end 371.793516 -81.47939)
		(width 0.15494)
		(layer "In15.Cu")
		(net "SMB_BIC_I2C9_MUX1_SSD13_R_SCL")
	)
	(segment
		(start 370.850922 -84.304124)
		(end 371.793516 -83.36153)
		(width 0.15494)
		(layer "In15.Cu")
		(net "SMB_BIC_I2C9_MUX1_SSD13_R_SCL")
	)
	(segment
		(start 371.793516 -81.47939)
		(end 375.487692 -77.785214)
		(width 0.15494)
		(layer "In15.Cu")
		(net "SMB_BIC_I2C9_MUX1_SSD13_R_SCL")
	)
	(segment
		(start 403.07641 -76.900786)
		(end 405.434038 -74.543158)
		(width 0.15494)
		(layer "In15.Cu")
		(net "SMB_BIC_I2C9_MUX1_SSD13_R_SCL")
	)
	(segment
		(start 391.236708 -76.900786)
		(end 403.07641 -76.900786)
		(width 0.15494)
		(layer "In15.Cu")
		(net "SMB_BIC_I2C9_MUX1_SSD13_R_SCL")
	)
	(segment
		(start 390.35228 -77.785214)
		(end 391.236708 -76.900786)
		(width 0.15494)
		(layer "In15.Cu")
		(net "SMB_BIC_I2C9_MUX1_SSD13_R_SCL")
	)
	(segment
		(start 369.568476 -84.89188)
		(end 370.156232 -84.304124)
		(width 0.15494)
		(layer "In15.Cu")
		(net "SMB_BIC_I2C9_MUX1_SSD13_R_SCL")
	)
	(segment
		(start 370.156232 -84.304124)
		(end 370.850922 -84.304124)
		(width 0.15494)
		(layer "In15.Cu")
		(net "SMB_BIC_I2C9_MUX1_SSD13_R_SCL")
	)
	(segment
		(start 375.487692 -77.785214)
		(end 390.35228 -77.785214)
		(width 0.15494)
		(layer "In15.Cu")
		(net "SMB_BIC_I2C9_MUX1_SSD13_R_SCL")
	)
	(segment
		(start 367.978436 -84.55914)
		(end 368.311176 -84.89188)
		(width 0.15494)
		(layer "In15.Cu")
		(net "SMB_BIC_I2C9_MUX1_SSD13_R_SCL")
	)
	(segment
		(start 340.493858 -223.187006)
		(end 340.094062 -223.586802)
		(width 0.13208)
		(layer "F.Cu")
		(net "SSD0_PWR_EN")
	)
	(segment
		(start 341.870792 -240.291112)
		(end 341.870792 -239.675162)
		(width 0.13208)
		(layer "F.Cu")
		(net "SSD0_PWR_EN")
	)
	(via
		(at 340.094062 -223.586802)
		(size 0.4572)
		(drill 0.254)
		(layers "F.Cu" "B.Cu")
		(net "SSD0_PWR_EN")
	)
	(via
		(at 341.870792 -239.675162)
		(size 0.508)
		(drill 0.254)
		(layers "F.Cu" "B.Cu")
		(net "SSD0_PWR_EN")
	)
	(segment
		(start 340.301326 -225.586798)
		(end 339.920072 -225.586798)
		(width 0.0889)
		(layer "In5.Cu")
		(net "SSD0_PWR_EN")
	)
	(segment
		(start 340.301326 -223.586802)
		(end 340.492842 -223.778318)
		(width 0.0889)
		(layer "In5.Cu")
		(net "SSD0_PWR_EN")
	)
	(segment
		(start 337.11515 -236.87405)
		(end 337.11515 -237.516924)
		(width 0.15494)
		(layer "In5.Cu")
		(net "SSD0_PWR_EN")
	)
	(segment
		(start 338.774532 -234.268772)
		(end 338.431378 -234.611926)
		(width 0.15494)
		(layer "In5.Cu")
		(net "SSD0_PWR_EN")
	)
	(segment
		(start 338.431378 -234.611926)
		(end 338.431378 -235.557822)
		(width 0.15494)
		(layer "In5.Cu")
		(net "SSD0_PWR_EN")
	)
	(segment
		(start 337.11515 -237.516924)
		(end 337.327494 -237.729268)
		(width 0.15494)
		(layer "In5.Cu")
		(net "SSD0_PWR_EN")
	)
	(segment
		(start 339.01126 -228.070918)
		(end 338.774532 -228.307646)
		(width 0.15494)
		(layer "In5.Cu")
		(net "SSD0_PWR_EN")
	)
	(segment
		(start 340.492842 -225.395282)
		(end 340.301326 -225.586798)
		(width 0.0889)
		(layer "In5.Cu")
		(net "SSD0_PWR_EN")
	)
	(segment
		(start 339.428328 -228.070918)
		(end 339.01126 -228.070918)
		(width 0.15494)
		(layer "In5.Cu")
		(net "SSD0_PWR_EN")
	)
	(segment
		(start 337.327494 -237.729268)
		(end 339.924898 -237.729268)
		(width 0.15494)
		(layer "In5.Cu")
		(net "SSD0_PWR_EN")
	)
	(segment
		(start 339.924898 -237.729268)
		(end 341.870792 -239.675162)
		(width 0.15494)
		(layer "In5.Cu")
		(net "SSD0_PWR_EN")
	)
	(segment
		(start 340.492842 -223.778318)
		(end 340.492842 -225.395282)
		(width 0.0889)
		(layer "In5.Cu")
		(net "SSD0_PWR_EN")
	)
	(segment
		(start 338.774532 -228.307646)
		(end 338.774532 -234.268772)
		(width 0.15494)
		(layer "In5.Cu")
		(net "SSD0_PWR_EN")
	)
	(segment
		(start 339.706712 -225.800158)
		(end 339.706712 -226.973638)
		(width 0.0889)
		(layer "In5.Cu")
		(net "SSD0_PWR_EN")
	)
	(segment
		(start 339.706712 -226.973638)
		(end 339.706712 -227.792534)
		(width 0.15494)
		(layer "In5.Cu")
		(net "SSD0_PWR_EN")
	)
	(segment
		(start 339.706712 -227.792534)
		(end 339.428328 -228.070918)
		(width 0.15494)
		(layer "In5.Cu")
		(net "SSD0_PWR_EN")
	)
	(segment
		(start 339.920072 -225.586798)
		(end 339.706712 -225.800158)
		(width 0.0889)
		(layer "In5.Cu")
		(net "SSD0_PWR_EN")
	)
	(segment
		(start 338.431378 -235.557822)
		(end 337.11515 -236.87405)
		(width 0.15494)
		(layer "In5.Cu")
		(net "SSD0_PWR_EN")
	)
	(segment
		(start 340.094062 -223.586802)
		(end 340.301326 -223.586802)
		(width 0.0889)
		(layer "In5.Cu")
		(net "SSD0_PWR_EN")
	)
	(segment
		(start 348.493842 -219.187014)
		(end 348.893638 -218.787218)
		(width 0.13208)
		(layer "F.Cu")
		(net "NIC6_AUX_PWR_EN")
	)
	(via
		(at 367.366042 -170.988482)
		(size 0.508)
		(drill 0.254)
		(layers "F.Cu" "B.Cu")
		(net "NIC6_AUX_PWR_EN")
	)
	(via
		(at 398.636236 -171.986194)
		(size 0.508)
		(drill 0.254)
		(layers "F.Cu" "B.Cu")
		(net "NIC6_AUX_PWR_EN")
	)
	(via
		(at 348.893638 -218.787218)
		(size 0.4572)
		(drill 0.254)
		(layers "F.Cu" "B.Cu")
		(net "NIC6_AUX_PWR_EN")
	)
	(via
		(at 398.8308 -139.96416)
		(size 0.6604)
		(drill 0.3302)
		(layers "F.Cu" "B.Cu")
		(net "NIC6_AUX_PWR_EN")
	)
	(via
		(at 399.22577 -146.795998)
		(size 0.508)
		(drill 0.254)
		(layers "F.Cu" "B.Cu")
		(net "NIC6_AUX_PWR_EN")
	)
	(segment
		(start 398.8308 -139.96416)
		(end 398.544034 -139.677394)
		(width 0.13208)
		(layer "B.Cu")
		(net "NIC6_AUX_PWR_EN")
	)
	(segment
		(start 399.22577 -146.795998)
		(end 399.22577 -140.35913)
		(width 0.13208)
		(layer "B.Cu")
		(net "NIC6_AUX_PWR_EN")
	)
	(segment
		(start 399.22577 -140.35913)
		(end 398.8308 -139.96416)
		(width 0.13208)
		(layer "B.Cu")
		(net "NIC6_AUX_PWR_EN")
	)
	(segment
		(start 398.544034 -139.677394)
		(end 398.544034 -138.421618)
		(width 0.13208)
		(layer "B.Cu")
		(net "NIC6_AUX_PWR_EN")
	)
	(segment
		(start 397.566134 -138.421618)
		(end 398.544034 -138.421618)
		(width 0.13208)
		(layer "B.Cu")
		(net "NIC6_AUX_PWR_EN")
	)
	(segment
		(start 364.8202 -212.50529)
		(end 362.82249 -214.503)
		(width 0.15494)
		(layer "In5.Cu")
		(net "NIC6_AUX_PWR_EN")
	)
	(segment
		(start 356.631748 -216.84234)
		(end 355.140768 -216.84234)
		(width 0.15494)
		(layer "In5.Cu")
		(net "NIC6_AUX_PWR_EN")
	)
	(segment
		(start 365.021114 -212.50529)
		(end 364.8202 -212.50529)
		(width 0.15494)
		(layer "In5.Cu")
		(net "NIC6_AUX_PWR_EN")
	)
	(segment
		(start 361.4674 -214.503)
		(end 360.0704 -215.9)
		(width 0.15494)
		(layer "In5.Cu")
		(net "NIC6_AUX_PWR_EN")
	)
	(segment
		(start 371.778022 -205.183994)
		(end 365.537496 -211.42452)
		(width 0.15494)
		(layer "In5.Cu")
		(net "NIC6_AUX_PWR_EN")
	)
	(segment
		(start 353.5934 -218.389708)
		(end 351.55632 -218.389708)
		(width 0.15494)
		(layer "In5.Cu")
		(net "NIC6_AUX_PWR_EN")
	)
	(segment
		(start 370.098828 -180.700172)
		(end 370.098828 -190.683134)
		(width 0.15494)
		(layer "In5.Cu")
		(net "NIC6_AUX_PWR_EN")
	)
	(segment
		(start 371.778022 -192.362328)
		(end 371.778022 -205.183994)
		(width 0.15494)
		(layer "In5.Cu")
		(net "NIC6_AUX_PWR_EN")
	)
	(segment
		(start 360.0704 -215.9)
		(end 357.574088 -215.9)
		(width 0.15494)
		(layer "In5.Cu")
		(net "NIC6_AUX_PWR_EN")
	)
	(segment
		(start 367.366042 -170.988482)
		(end 367.366042 -177.967386)
		(width 0.15494)
		(layer "In5.Cu")
		(net "NIC6_AUX_PWR_EN")
	)
	(segment
		(start 351.55632 -218.389708)
		(end 349.291148 -218.389708)
		(width 0.0889)
		(layer "In5.Cu")
		(net "NIC6_AUX_PWR_EN")
	)
	(segment
		(start 365.537496 -211.988908)
		(end 365.021114 -212.50529)
		(width 0.15494)
		(layer "In5.Cu")
		(net "NIC6_AUX_PWR_EN")
	)
	(segment
		(start 357.574088 -215.9)
		(end 356.631748 -216.84234)
		(width 0.15494)
		(layer "In5.Cu")
		(net "NIC6_AUX_PWR_EN")
	)
	(segment
		(start 362.82249 -214.503)
		(end 361.4674 -214.503)
		(width 0.15494)
		(layer "In5.Cu")
		(net "NIC6_AUX_PWR_EN")
	)
	(segment
		(start 349.291148 -218.389708)
		(end 348.893638 -218.787218)
		(width 0.0889)
		(layer "In5.Cu")
		(net "NIC6_AUX_PWR_EN")
	)
	(segment
		(start 367.366042 -177.967386)
		(end 370.098828 -180.700172)
		(width 0.15494)
		(layer "In5.Cu")
		(net "NIC6_AUX_PWR_EN")
	)
	(segment
		(start 370.098828 -190.683134)
		(end 371.778022 -192.362328)
		(width 0.15494)
		(layer "In5.Cu")
		(net "NIC6_AUX_PWR_EN")
	)
	(segment
		(start 365.537496 -211.42452)
		(end 365.537496 -211.988908)
		(width 0.15494)
		(layer "In5.Cu")
		(net "NIC6_AUX_PWR_EN")
	)
	(segment
		(start 355.140768 -216.84234)
		(end 353.5934 -218.389708)
		(width 0.15494)
		(layer "In5.Cu")
		(net "NIC6_AUX_PWR_EN")
	)
	(segment
		(start 402.366226 -169.642028)
		(end 400.02206 -171.986194)
		(width 0.15494)
		(layer "In9.Cu")
		(net "NIC6_AUX_PWR_EN")
	)
	(segment
		(start 398.794986 -160.833054)
		(end 402.366226 -164.404294)
		(width 0.15494)
		(layer "In9.Cu")
		(net "NIC6_AUX_PWR_EN")
	)
	(segment
		(start 400.02206 -171.986194)
		(end 398.636236 -171.986194)
		(width 0.15494)
		(layer "In9.Cu")
		(net "NIC6_AUX_PWR_EN")
	)
	(segment
		(start 399.22577 -146.795998)
		(end 398.794986 -147.226782)
		(width 0.15494)
		(layer "In9.Cu")
		(net "NIC6_AUX_PWR_EN")
	)
	(segment
		(start 398.794986 -147.226782)
		(end 398.794986 -160.833054)
		(width 0.15494)
		(layer "In9.Cu")
		(net "NIC6_AUX_PWR_EN")
	)
	(segment
		(start 402.366226 -164.404294)
		(end 402.366226 -169.642028)
		(width 0.15494)
		(layer "In9.Cu")
		(net "NIC6_AUX_PWR_EN")
	)
	(segment
		(start 374.339866 -171.536868)
		(end 374.033034 -171.8437)
		(width 0.15494)
		(layer "In15.Cu")
		(net "NIC6_AUX_PWR_EN")
	)
	(segment
		(start 368.22126 -171.8437)
		(end 367.366042 -170.988482)
		(width 0.15494)
		(layer "In15.Cu")
		(net "NIC6_AUX_PWR_EN")
	)
	(segment
		(start 398.636236 -171.986194)
		(end 398.18691 -171.536868)
		(width 0.15494)
		(layer "In15.Cu")
		(net "NIC6_AUX_PWR_EN")
	)
	(segment
		(start 398.18691 -171.536868)
		(end 374.339866 -171.536868)
		(width 0.15494)
		(layer "In15.Cu")
		(net "NIC6_AUX_PWR_EN")
	)
	(segment
		(start 374.033034 -171.8437)
		(end 368.22126 -171.8437)
		(width 0.15494)
		(layer "In15.Cu")
		(net "NIC6_AUX_PWR_EN")
	)
	(segment
		(start 282.347162 -53.144166)
		(end 282.53055 -53.144166)
		(width 0.13208)
		(layer "F.Cu")
		(net "P12V_SSD9_SS")
	)
	(segment
		(start 283.331412 -51.019456)
		(end 284.067758 -51.019456)
		(width 0.13208)
		(layer "F.Cu")
		(net "P12V_SSD9_SS")
	)
	(segment
		(start 282.53055 -53.144166)
		(end 282.679902 -52.994814)
		(width 0.13208)
		(layer "F.Cu")
		(net "P12V_SSD9_SS")
	)
	(segment
		(start 282.679902 -52.994814)
		(end 282.679902 -51.670966)
		(width 0.13208)
		(layer "F.Cu")
		(net "P12V_SSD9_SS")
	)
	(segment
		(start 282.679902 -51.670966)
		(end 283.331412 -51.019456)
		(width 0.13208)
		(layer "F.Cu")
		(net "P12V_SSD9_SS")
	)
	(via
		(at 283.331412 -51.019456)
		(size 0.508)
		(drill 0.254)
		(layers "F.Cu" "B.Cu")
		(net "P12V_SSD9_SS")
	)
	(segment
		(start 383.413 -239.811052)
		(end 390.330436 -239.811052)
		(width 0.13208)
		(layer "F.Cu")
		(net "UART_PEX1_SDB_BUF_TX")
	)
	(via
		(at 383.413 -239.811052)
		(size 0.508)
		(drill 0.254)
		(layers "F.Cu" "B.Cu")
		(net "UART_PEX1_SDB_BUF_TX")
	)
	(segment
		(start 380.746 -245.364)
		(end 379.58395 -245.364)
		(width 0.13208)
		(layer "B.Cu")
		(net "UART_PEX1_SDB_BUF_TX")
	)
	(segment
		(start 380.873 -245.237)
		(end 380.746 -245.364)
		(width 0.13208)
		(layer "B.Cu")
		(net "UART_PEX1_SDB_BUF_TX")
	)
	(segment
		(start 383.413 -239.811052)
		(end 382.651 -240.573052)
		(width 0.13208)
		(layer "B.Cu")
		(net "UART_PEX1_SDB_BUF_TX")
	)
	(segment
		(start 382.651 -240.573052)
		(end 382.651 -242.189)
		(width 0.13208)
		(layer "B.Cu")
		(net "UART_PEX1_SDB_BUF_TX")
	)
	(segment
		(start 380.873 -243.967)
		(end 380.873 -245.237)
		(width 0.13208)
		(layer "B.Cu")
		(net "UART_PEX1_SDB_BUF_TX")
	)
	(segment
		(start 379.58395 -245.364)
		(end 379.45695 -245.237)
		(width 0.13208)
		(layer "B.Cu")
		(net "UART_PEX1_SDB_BUF_TX")
	)
	(segment
		(start 378.47905 -244.729)
		(end 379.45695 -244.729)
		(width 0.13208)
		(layer "B.Cu")
		(net "UART_PEX1_SDB_BUF_TX")
	)
	(segment
		(start 379.45695 -245.237)
		(end 379.45695 -244.729)
		(width 0.13208)
		(layer "B.Cu")
		(net "UART_PEX1_SDB_BUF_TX")
	)
	(segment
		(start 382.651 -242.189)
		(end 380.873 -243.967)
		(width 0.13208)
		(layer "B.Cu")
		(net "UART_PEX1_SDB_BUF_TX")
	)
	(segment
		(start 338.83854 -80.207612)
		(end 339.1662 -79.879952)
		(width 0.13462)
		(layer "F.Cu")
		(net "CLK_100M_DB800ZL_SSD10_R_DP")
	)
	(segment
		(start 301.181262 -27.342846)
		(end 300.884336 -27.04592)
		(width 0.13462)
		(layer "F.Cu")
		(net "CLK_100M_DB800ZL_SSD10_R_DP")
	)
	(segment
		(start 339.1662 -79.185008)
		(end 338.86394 -78.882748)
		(width 0.13462)
		(layer "F.Cu")
		(net "CLK_100M_DB800ZL_SSD10_R_DP")
	)
	(segment
		(start 300.884336 -27.04592)
		(end 300.11243 -27.04592)
		(width 0.13462)
		(layer "F.Cu")
		(net "CLK_100M_DB800ZL_SSD10_R_DP")
	)
	(segment
		(start 300.11243 -27.04592)
		(end 299.968412 -27.189938)
		(width 0.13462)
		(layer "F.Cu")
		(net "CLK_100M_DB800ZL_SSD10_R_DP")
	)
	(segment
		(start 339.1662 -79.879952)
		(end 339.1662 -79.185008)
		(width 0.13462)
		(layer "F.Cu")
		(net "CLK_100M_DB800ZL_SSD10_R_DP")
	)
	(segment
		(start 299.968412 -27.189938)
		(end 299.46473 -27.189938)
		(width 0.13462)
		(layer "F.Cu")
		(net "CLK_100M_DB800ZL_SSD10_R_DP")
	)
	(via
		(at 338.86394 -78.882748)
		(size 0.508)
		(drill 0.254)
		(layers "F.Cu" "B.Cu")
		(net "CLK_100M_DB800ZL_SSD10_R_DP")
	)
	(via
		(at 301.181262 -27.342846)
		(size 0.508)
		(drill 0.254)
		(layers "F.Cu" "B.Cu")
		(net "CLK_100M_DB800ZL_SSD10_R_DP")
	)
	(segment
		(start 339.15477 -78.591918)
		(end 339.15477 -67.97675)
		(width 0.1651)
		(layer "In13.Cu")
		(net "CLK_100M_DB800ZL_SSD10_R_DP")
	)
	(segment
		(start 309.07736 -31.30804)
		(end 309.19166 -31.19374)
		(width 0.1651)
		(layer "In13.Cu")
		(net "CLK_100M_DB800ZL_SSD10_R_DP")
	)
	(segment
		(start 309.07736 -32.52724)
		(end 309.19166 -32.41294)
		(width 0.1651)
		(layer "In13.Cu")
		(net "CLK_100M_DB800ZL_SSD10_R_DP")
	)
	(segment
		(start 305.20894 -28.39974)
		(end 304.165 -27.3558)
		(width 0.1651)
		(layer "In13.Cu")
		(net "CLK_100M_DB800ZL_SSD10_R_DP")
	)
	(segment
		(start 309.07736 -34.96564)
		(end 309.19166 -34.85134)
		(width 0.1651)
		(layer "In13.Cu")
		(net "CLK_100M_DB800ZL_SSD10_R_DP")
	)
	(segment
		(start 303.3522 -27.3558)
		(end 303.048416 -27.052016)
		(width 0.1651)
		(layer "In13.Cu")
		(net "CLK_100M_DB800ZL_SSD10_R_DP")
	)
	(segment
		(start 304.165 -27.3558)
		(end 303.3522 -27.3558)
		(width 0.1651)
		(layer "In13.Cu")
		(net "CLK_100M_DB800ZL_SSD10_R_DP")
	)
	(segment
		(start 309.19166 -35.57524)
		(end 309.07736 -35.46094)
		(width 0.1651)
		(layer "In13.Cu")
		(net "CLK_100M_DB800ZL_SSD10_R_DP")
	)
	(segment
		(start 309.19166 -37.70884)
		(end 309.19166 -35.57524)
		(width 0.1651)
		(layer "In13.Cu")
		(net "CLK_100M_DB800ZL_SSD10_R_DP")
	)
	(segment
		(start 325.07936 -64.23914)
		(end 321.76466 -60.92444)
		(width 0.1651)
		(layer "In13.Cu")
		(net "CLK_100M_DB800ZL_SSD10_R_DP")
	)
	(segment
		(start 309.07736 -33.02254)
		(end 309.07736 -32.52724)
		(width 0.1651)
		(layer "In13.Cu")
		(net "CLK_100M_DB800ZL_SSD10_R_DP")
	)
	(segment
		(start 309.19166 -34.35604)
		(end 309.07736 -34.24174)
		(width 0.1651)
		(layer "In13.Cu")
		(net "CLK_100M_DB800ZL_SSD10_R_DP")
	)
	(segment
		(start 309.19166 -33.63214)
		(end 309.19166 -33.13684)
		(width 0.1651)
		(layer "In13.Cu")
		(net "CLK_100M_DB800ZL_SSD10_R_DP")
	)
	(segment
		(start 306.89296 -28.39974)
		(end 305.20894 -28.39974)
		(width 0.1651)
		(layer "In13.Cu")
		(net "CLK_100M_DB800ZL_SSD10_R_DP")
	)
	(segment
		(start 319.447672 -47.964852)
		(end 309.19166 -37.70884)
		(width 0.1651)
		(layer "In13.Cu")
		(net "CLK_100M_DB800ZL_SSD10_R_DP")
	)
	(segment
		(start 309.19166 -34.85134)
		(end 309.19166 -34.35604)
		(width 0.1651)
		(layer "In13.Cu")
		(net "CLK_100M_DB800ZL_SSD10_R_DP")
	)
	(segment
		(start 335.41716 -64.23914)
		(end 325.07936 -64.23914)
		(width 0.1651)
		(layer "In13.Cu")
		(net "CLK_100M_DB800ZL_SSD10_R_DP")
	)
	(segment
		(start 309.19166 -33.13684)
		(end 309.07736 -33.02254)
		(width 0.1651)
		(layer "In13.Cu")
		(net "CLK_100M_DB800ZL_SSD10_R_DP")
	)
	(segment
		(start 309.19166 -31.91764)
		(end 309.07736 -31.80334)
		(width 0.1651)
		(layer "In13.Cu")
		(net "CLK_100M_DB800ZL_SSD10_R_DP")
	)
	(segment
		(start 309.07736 -35.46094)
		(end 309.07736 -34.96564)
		(width 0.1651)
		(layer "In13.Cu")
		(net "CLK_100M_DB800ZL_SSD10_R_DP")
	)
	(segment
		(start 321.76466 -60.92444)
		(end 321.76466 -51.43246)
		(width 0.1651)
		(layer "In13.Cu")
		(net "CLK_100M_DB800ZL_SSD10_R_DP")
	)
	(segment
		(start 301.472092 -27.052016)
		(end 301.181262 -27.342846)
		(width 0.1651)
		(layer "In13.Cu")
		(net "CLK_100M_DB800ZL_SSD10_R_DP")
	)
	(segment
		(start 309.19166 -32.41294)
		(end 309.19166 -31.91764)
		(width 0.1651)
		(layer "In13.Cu")
		(net "CLK_100M_DB800ZL_SSD10_R_DP")
	)
	(segment
		(start 309.07736 -31.80334)
		(end 309.07736 -31.30804)
		(width 0.1651)
		(layer "In13.Cu")
		(net "CLK_100M_DB800ZL_SSD10_R_DP")
	)
	(segment
		(start 338.86394 -78.882748)
		(end 339.15477 -78.591918)
		(width 0.1651)
		(layer "In13.Cu")
		(net "CLK_100M_DB800ZL_SSD10_R_DP")
	)
	(segment
		(start 309.19166 -30.69844)
		(end 306.89296 -28.39974)
		(width 0.1651)
		(layer "In13.Cu")
		(net "CLK_100M_DB800ZL_SSD10_R_DP")
	)
	(segment
		(start 339.15477 -67.97675)
		(end 335.41716 -64.23914)
		(width 0.1651)
		(layer "In13.Cu")
		(net "CLK_100M_DB800ZL_SSD10_R_DP")
	)
	(segment
		(start 309.07736 -34.24174)
		(end 309.07736 -33.74644)
		(width 0.1651)
		(layer "In13.Cu")
		(net "CLK_100M_DB800ZL_SSD10_R_DP")
	)
	(segment
		(start 309.07736 -33.74644)
		(end 309.19166 -33.63214)
		(width 0.1651)
		(layer "In13.Cu")
		(net "CLK_100M_DB800ZL_SSD10_R_DP")
	)
	(segment
		(start 321.76466 -51.43246)
		(end 319.447672 -47.964852)
		(width 0.1651)
		(layer "In13.Cu")
		(net "CLK_100M_DB800ZL_SSD10_R_DP")
	)
	(segment
		(start 303.048416 -27.052016)
		(end 301.472092 -27.052016)
		(width 0.1651)
		(layer "In13.Cu")
		(net "CLK_100M_DB800ZL_SSD10_R_DP")
	)
	(segment
		(start 309.19166 -31.19374)
		(end 309.19166 -30.69844)
		(width 0.1651)
		(layer "In13.Cu")
		(net "CLK_100M_DB800ZL_SSD10_R_DP")
	)
	(segment
		(start 296.599864 -283.549852)
		(end 297.074844 -284.024832)
		(width 0.13208)
		(layer "F.Cu")
		(net "PEX2_SYS_ERR_N")
	)
	(segment
		(start 254.481838 -260.219444)
		(end 254.673608 -260.027674)
		(width 0.13208)
		(layer "F.Cu")
		(net "PEX2_SYS_ERR_N")
	)
	(segment
		(start 254.062992 -260.219444)
		(end 254.481838 -260.219444)
		(width 0.13208)
		(layer "F.Cu")
		(net "PEX2_SYS_ERR_N")
	)
	(via
		(at 254.673608 -260.027674)
		(size 0.508)
		(drill 0.254)
		(layers "F.Cu" "B.Cu")
		(net "PEX2_SYS_ERR_N")
	)
	(via
		(at 297.074844 -284.024832)
		(size 0.4064)
		(drill 0.2032)
		(layers "F.Cu" "B.Cu")
		(net "PEX2_SYS_ERR_N")
	)
	(segment
		(start 288.99993 -282.547568)
		(end 288.99993 -284.092904)
		(width 0.13208)
		(layer "B.Cu")
		(net "PEX2_SYS_ERR_N")
	)
	(segment
		(start 288.99993 -284.092904)
		(end 289.412426 -284.5054)
		(width 0.13208)
		(layer "B.Cu")
		(net "PEX2_SYS_ERR_N")
	)
	(segment
		(start 289.475164 -282.072334)
		(end 288.99993 -282.547568)
		(width 0.13208)
		(layer "B.Cu")
		(net "PEX2_SYS_ERR_N")
	)
	(segment
		(start 291.61359 -284.5054)
		(end 291.9222 -284.81401)
		(width 0.13208)
		(layer "B.Cu")
		(net "PEX2_SYS_ERR_N")
	)
	(segment
		(start 289.412426 -284.5054)
		(end 291.61359 -284.5054)
		(width 0.13208)
		(layer "B.Cu")
		(net "PEX2_SYS_ERR_N")
	)
	(segment
		(start 294.954706 -283.61259)
		(end 296.662602 -283.61259)
		(width 0.13208)
		(layer "B.Cu")
		(net "PEX2_SYS_ERR_N")
	)
	(segment
		(start 294.739822 -285.095442)
		(end 294.739822 -283.827474)
		(width 0.13208)
		(layer "B.Cu")
		(net "PEX2_SYS_ERR_N")
	)
	(segment
		(start 279.293828 -260.947662)
		(end 289.475164 -271.149826)
		(width 0.13208)
		(layer "B.Cu")
		(net "PEX2_SYS_ERR_N")
	)
	(segment
		(start 294.440864 -285.3944)
		(end 294.739822 -285.095442)
		(width 0.13208)
		(layer "B.Cu")
		(net "PEX2_SYS_ERR_N")
	)
	(segment
		(start 291.9222 -285.1404)
		(end 292.1762 -285.3944)
		(width 0.13208)
		(layer "B.Cu")
		(net "PEX2_SYS_ERR_N")
	)
	(segment
		(start 291.9222 -284.81401)
		(end 291.9222 -285.1404)
		(width 0.13208)
		(layer "B.Cu")
		(net "PEX2_SYS_ERR_N")
	)
	(segment
		(start 289.475164 -271.149826)
		(end 289.475164 -282.072334)
		(width 0.13208)
		(layer "B.Cu")
		(net "PEX2_SYS_ERR_N")
	)
	(segment
		(start 255.593596 -260.947662)
		(end 279.293828 -260.947662)
		(width 0.13208)
		(layer "B.Cu")
		(net "PEX2_SYS_ERR_N")
	)
	(segment
		(start 292.1762 -285.3944)
		(end 294.440864 -285.3944)
		(width 0.13208)
		(layer "B.Cu")
		(net "PEX2_SYS_ERR_N")
	)
	(segment
		(start 294.739822 -283.827474)
		(end 294.954706 -283.61259)
		(width 0.13208)
		(layer "B.Cu")
		(net "PEX2_SYS_ERR_N")
	)
	(segment
		(start 296.662602 -283.61259)
		(end 297.074844 -284.024832)
		(width 0.13208)
		(layer "B.Cu")
		(net "PEX2_SYS_ERR_N")
	)
	(segment
		(start 254.673608 -260.027674)
		(end 255.593596 -260.947662)
		(width 0.13208)
		(layer "B.Cu")
		(net "PEX2_SYS_ERR_N")
	)
	(segment
		(start 426.617892 -21.775674)
		(end 426.58538 -21.743162)
		(width 0.13208)
		(layer "F.Cu")
		(net "SMB_BIC_I2C9_MUX1_SSD14_R_SCL")
	)
	(segment
		(start 368.000788 -87.352632)
		(end 368.000788 -87.712296)
		(width 0.13208)
		(layer "F.Cu")
		(net "SMB_BIC_I2C9_MUX1_SSD14_R_SCL")
	)
	(segment
		(start 368.000788 -87.712296)
		(end 368.49939 -87.213694)
		(width 0.13208)
		(layer "F.Cu")
		(net "SMB_BIC_I2C9_MUX1_SSD14_R_SCL")
	)
	(segment
		(start 368.49939 -87.213694)
		(end 369.095528 -87.213694)
		(width 0.13208)
		(layer "F.Cu")
		(net "SMB_BIC_I2C9_MUX1_SSD14_R_SCL")
	)
	(segment
		(start 367.355628 -87.213694)
		(end 367.86185 -87.213694)
		(width 0.13208)
		(layer "F.Cu")
		(net "SMB_BIC_I2C9_MUX1_SSD14_R_SCL")
	)
	(segment
		(start 426.58538 -21.743162)
		(end 426.58538 -20.789392)
		(width 0.13208)
		(layer "F.Cu")
		(net "SMB_BIC_I2C9_MUX1_SSD14_R_SCL")
	)
	(segment
		(start 426.75937 -22.555454)
		(end 426.617892 -22.413976)
		(width 0.13208)
		(layer "F.Cu")
		(net "SMB_BIC_I2C9_MUX1_SSD14_R_SCL")
	)
	(segment
		(start 426.617892 -22.413976)
		(end 426.617892 -21.775674)
		(width 0.13208)
		(layer "F.Cu")
		(net "SMB_BIC_I2C9_MUX1_SSD14_R_SCL")
	)
	(segment
		(start 367.86185 -87.213694)
		(end 368.000788 -87.352632)
		(width 0.13208)
		(layer "F.Cu")
		(net "SMB_BIC_I2C9_MUX1_SSD14_R_SCL")
	)
	(via
		(at 368.000788 -87.712296)
		(size 0.508)
		(drill 0.254)
		(layers "F.Cu" "B.Cu")
		(net "SMB_BIC_I2C9_MUX1_SSD14_R_SCL")
	)
	(via
		(at 431.856642 -74.203814)
		(size 0.508)
		(drill 0.254)
		(layers "F.Cu" "B.Cu")
		(net "SMB_BIC_I2C9_MUX1_SSD14_R_SCL")
	)
	(via
		(at 426.617892 -21.775674)
		(size 0.508)
		(drill 0.254)
		(layers "F.Cu" "B.Cu")
		(net "SMB_BIC_I2C9_MUX1_SSD14_R_SCL")
	)
	(segment
		(start 425.077636 -31.066232)
		(end 425.077636 -32.334454)
		(width 0.15494)
		(layer "In5.Cu")
		(net "SMB_BIC_I2C9_MUX1_SSD14_R_SCL")
	)
	(segment
		(start 426.617892 -21.775674)
		(end 425.577762 -21.775674)
		(width 0.15494)
		(layer "In5.Cu")
		(net "SMB_BIC_I2C9_MUX1_SSD14_R_SCL")
	)
	(segment
		(start 432.335178 -74.203814)
		(end 431.856642 -74.203814)
		(width 0.15494)
		(layer "In5.Cu")
		(net "SMB_BIC_I2C9_MUX1_SSD14_R_SCL")
	)
	(segment
		(start 425.577762 -21.775674)
		(end 425.016676 -22.33676)
		(width 0.15494)
		(layer "In5.Cu")
		(net "SMB_BIC_I2C9_MUX1_SSD14_R_SCL")
	)
	(segment
		(start 437.969406 -45.226224)
		(end 437.969406 -68.569586)
		(width 0.15494)
		(layer "In5.Cu")
		(net "SMB_BIC_I2C9_MUX1_SSD14_R_SCL")
	)
	(segment
		(start 425.077636 -32.334454)
		(end 437.969406 -45.226224)
		(width 0.15494)
		(layer "In5.Cu")
		(net "SMB_BIC_I2C9_MUX1_SSD14_R_SCL")
	)
	(segment
		(start 426.14723 -28.184602)
		(end 426.14723 -29.996638)
		(width 0.15494)
		(layer "In5.Cu")
		(net "SMB_BIC_I2C9_MUX1_SSD14_R_SCL")
	)
	(segment
		(start 425.016676 -27.054048)
		(end 426.14723 -28.184602)
		(width 0.15494)
		(layer "In5.Cu")
		(net "SMB_BIC_I2C9_MUX1_SSD14_R_SCL")
	)
	(segment
		(start 425.016676 -22.33676)
		(end 425.016676 -27.054048)
		(width 0.15494)
		(layer "In5.Cu")
		(net "SMB_BIC_I2C9_MUX1_SSD14_R_SCL")
	)
	(segment
		(start 426.14723 -29.996638)
		(end 425.077636 -31.066232)
		(width 0.15494)
		(layer "In5.Cu")
		(net "SMB_BIC_I2C9_MUX1_SSD14_R_SCL")
	)
	(segment
		(start 437.969406 -68.569586)
		(end 432.335178 -74.203814)
		(width 0.15494)
		(layer "In5.Cu")
		(net "SMB_BIC_I2C9_MUX1_SSD14_R_SCL")
	)
	(segment
		(start 368.000788 -87.712296)
		(end 368.49939 -87.213694)
		(width 0.15494)
		(layer "In15.Cu")
		(net "SMB_BIC_I2C9_MUX1_SSD14_R_SCL")
	)
	(segment
		(start 424.67276 -78.732888)
		(end 428.78248 -74.623168)
		(width 0.15494)
		(layer "In15.Cu")
		(net "SMB_BIC_I2C9_MUX1_SSD14_R_SCL")
	)
	(segment
		(start 370.927376 -86.590886)
		(end 372.80088 -84.717382)
		(width 0.15494)
		(layer "In15.Cu")
		(net "SMB_BIC_I2C9_MUX1_SSD14_R_SCL")
	)
	(segment
		(start 431.437288 -74.623168)
		(end 431.856642 -74.203814)
		(width 0.15494)
		(layer "In15.Cu")
		(net "SMB_BIC_I2C9_MUX1_SSD14_R_SCL")
	)
	(segment
		(start 372.80088 -81.772506)
		(end 375.840498 -78.732888)
		(width 0.15494)
		(layer "In15.Cu")
		(net "SMB_BIC_I2C9_MUX1_SSD14_R_SCL")
	)
	(segment
		(start 375.840498 -78.732888)
		(end 424.67276 -78.732888)
		(width 0.15494)
		(layer "In15.Cu")
		(net "SMB_BIC_I2C9_MUX1_SSD14_R_SCL")
	)
	(segment
		(start 369.677442 -87.213694)
		(end 370.30025 -86.590886)
		(width 0.15494)
		(layer "In15.Cu")
		(net "SMB_BIC_I2C9_MUX1_SSD14_R_SCL")
	)
	(segment
		(start 370.30025 -86.590886)
		(end 370.927376 -86.590886)
		(width 0.15494)
		(layer "In15.Cu")
		(net "SMB_BIC_I2C9_MUX1_SSD14_R_SCL")
	)
	(segment
		(start 372.80088 -84.717382)
		(end 372.80088 -81.772506)
		(width 0.15494)
		(layer "In15.Cu")
		(net "SMB_BIC_I2C9_MUX1_SSD14_R_SCL")
	)
	(segment
		(start 368.49939 -87.213694)
		(end 369.677442 -87.213694)
		(width 0.15494)
		(layer "In15.Cu")
		(net "SMB_BIC_I2C9_MUX1_SSD14_R_SCL")
	)
	(segment
		(start 428.78248 -74.623168)
		(end 431.437288 -74.623168)
		(width 0.15494)
		(layer "In15.Cu")
		(net "SMB_BIC_I2C9_MUX1_SSD14_R_SCL")
	)
	(segment
		(start 348.493842 -227.186998)
		(end 348.890082 -227.583238)
		(width 0.13208)
		(layer "F.Cu")
		(net "SSD6_PWR_EN")
	)
	(segment
		(start 348.890082 -227.583238)
		(end 348.890082 -229.509828)
		(width 0.13208)
		(layer "F.Cu")
		(net "SSD6_PWR_EN")
	)
	(segment
		(start 348.890082 -229.509828)
		(end 350.139 -230.758746)
		(width 0.13208)
		(layer "F.Cu")
		(net "SSD6_PWR_EN")
	)
	(segment
		(start 350.139 -230.758746)
		(end 350.139 -232.4862)
		(width 0.13208)
		(layer "F.Cu")
		(net "SSD6_PWR_EN")
	)
	(segment
		(start 350.139 -233.66095)
		(end 350.139 -232.4862)
		(width 0.13208)
		(layer "F.Cu")
		(net "SSD6_PWR_EN")
	)
	(via
		(at 350.139 -232.4862)
		(size 0.762)
		(drill 0.381)
		(layers "F.Cu" "B.Cu")
		(net "SSD6_PWR_EN")
	)
	(segment
		(start 228.267768 -223.104202)
		(end 227.867972 -223.503998)
		(width 0.13208)
		(layer "F.Cu")
		(net "NIC5_MAIN_PWR_BIC_EN")
	)
	(via
		(at 231.466644 -228.501448)
		(size 0.6604)
		(drill 0.3302)
		(layers "F.Cu" "B.Cu")
		(net "NIC5_MAIN_PWR_BIC_EN")
	)
	(via
		(at 227.867972 -223.503998)
		(size 0.4572)
		(drill 0.254)
		(layers "F.Cu" "B.Cu")
		(net "NIC5_MAIN_PWR_BIC_EN")
	)
	(segment
		(start 231.466644 -228.03612)
		(end 231.311704 -227.88118)
		(width 0.13208)
		(layer "B.Cu")
		(net "NIC5_MAIN_PWR_BIC_EN")
	)
	(segment
		(start 231.311704 -227.88118)
		(end 228.197664 -227.88118)
		(width 0.13208)
		(layer "B.Cu")
		(net "NIC5_MAIN_PWR_BIC_EN")
	)
	(segment
		(start 231.466644 -230.825548)
		(end 231.466644 -228.501448)
		(width 0.13208)
		(layer "B.Cu")
		(net "NIC5_MAIN_PWR_BIC_EN")
	)
	(segment
		(start 228.197664 -227.88118)
		(end 227.867972 -227.551488)
		(width 0.13208)
		(layer "B.Cu")
		(net "NIC5_MAIN_PWR_BIC_EN")
	)
	(segment
		(start 231.466644 -228.501448)
		(end 231.466644 -228.03612)
		(width 0.13208)
		(layer "B.Cu")
		(net "NIC5_MAIN_PWR_BIC_EN")
	)
	(segment
		(start 227.867972 -227.551488)
		(end 227.867972 -223.503998)
		(width 0.13208)
		(layer "B.Cu")
		(net "NIC5_MAIN_PWR_BIC_EN")
	)
	(segment
		(start 400.06397 -53.96357)
		(end 399.454116 -53.96357)
		(width 0.13208)
		(layer "F.Cu")
		(net "P12V_SSD13_OCP")
	)
	(segment
		(start 398.875504 -54.144164)
		(end 399.056098 -53.96357)
		(width 0.13208)
		(layer "F.Cu")
		(net "P12V_SSD13_OCP")
	)
	(segment
		(start 398.44726 -54.144164)
		(end 398.875504 -54.144164)
		(width 0.13208)
		(layer "F.Cu")
		(net "P12V_SSD13_OCP")
	)
	(segment
		(start 399.056098 -53.96357)
		(end 399.454116 -53.96357)
		(width 0.13208)
		(layer "F.Cu")
		(net "P12V_SSD13_OCP")
	)
	(segment
		(start 400.167856 -54.067456)
		(end 400.06397 -53.96357)
		(width 0.13208)
		(layer "F.Cu")
		(net "P12V_SSD13_OCP")
	)
	(via
		(at 399.454116 -53.96357)
		(size 0.508)
		(drill 0.254)
		(layers "F.Cu" "B.Cu")
		(net "P12V_SSD13_OCP")
	)
	(segment
		(start 442.054742 -26.58999)
		(end 441.564776 -26.58999)
		(width 0.13462)
		(layer "F.Cu")
		(net "CLK_100M_DB800ZL_SSD15_R_DN")
	)
	(segment
		(start 443.009274 -26.75128)
		(end 442.216032 -26.75128)
		(width 0.13462)
		(layer "F.Cu")
		(net "CLK_100M_DB800ZL_SSD15_R_DN")
	)
	(segment
		(start 442.216032 -26.75128)
		(end 442.054742 -26.58999)
		(width 0.13462)
		(layer "F.Cu")
		(net "CLK_100M_DB800ZL_SSD15_R_DN")
	)
	(segment
		(start 338.838286 -93.51899)
		(end 339.1662 -93.846904)
		(width 0.13462)
		(layer "F.Cu")
		(net "CLK_100M_DB800ZL_SSD15_R_DN")
	)
	(segment
		(start 339.1662 -94.54134)
		(end 338.863686 -94.843854)
		(width 0.13462)
		(layer "F.Cu")
		(net "CLK_100M_DB800ZL_SSD15_R_DN")
	)
	(segment
		(start 443.281308 -26.479246)
		(end 443.009274 -26.75128)
		(width 0.13462)
		(layer "F.Cu")
		(net "CLK_100M_DB800ZL_SSD15_R_DN")
	)
	(segment
		(start 339.1662 -93.846904)
		(end 339.1662 -94.54134)
		(width 0.13462)
		(layer "F.Cu")
		(net "CLK_100M_DB800ZL_SSD15_R_DN")
	)
	(via
		(at 338.863686 -94.843854)
		(size 0.508)
		(drill 0.254)
		(layers "F.Cu" "B.Cu")
		(net "CLK_100M_DB800ZL_SSD15_R_DN")
	)
	(via
		(at 443.281308 -26.479246)
		(size 0.508)
		(drill 0.254)
		(layers "F.Cu" "B.Cu")
		(net "CLK_100M_DB800ZL_SSD15_R_DN")
	)
	(segment
		(start 423.63644 -79.32674)
		(end 436.564024 -66.399156)
		(width 0.1651)
		(layer "In13.Cu")
		(net "CLK_100M_DB800ZL_SSD15_R_DN")
	)
	(segment
		(start 366.37214 -80.93964)
		(end 367.98504 -79.32674)
		(width 0.1651)
		(layer "In13.Cu")
		(net "CLK_100M_DB800ZL_SSD15_R_DN")
	)
	(segment
		(start 436.564024 -66.399156)
		(end 437.9468 -63.060834)
		(width 0.1651)
		(layer "In13.Cu")
		(net "CLK_100M_DB800ZL_SSD15_R_DN")
	)
	(segment
		(start 437.9468 -63.060834)
		(end 437.9468 -43.32478)
		(width 0.1651)
		(layer "In13.Cu")
		(net "CLK_100M_DB800ZL_SSD15_R_DN")
	)
	(segment
		(start 444.19774 -27.062176)
		(end 443.90564 -26.770076)
		(width 0.1651)
		(layer "In13.Cu")
		(net "CLK_100M_DB800ZL_SSD15_R_DN")
	)
	(segment
		(start 339.531452 -95.86214)
		(end 351.95764 -95.86214)
		(width 0.1651)
		(layer "In13.Cu")
		(net "CLK_100M_DB800ZL_SSD15_R_DN")
	)
	(segment
		(start 363.69244 -84.12734)
		(end 364.12424 -84.12734)
		(width 0.1651)
		(layer "In13.Cu")
		(net "CLK_100M_DB800ZL_SSD15_R_DN")
	)
	(segment
		(start 339.154516 -95.134684)
		(end 339.154516 -95.485204)
		(width 0.1651)
		(layer "In13.Cu")
		(net "CLK_100M_DB800ZL_SSD15_R_DN")
	)
	(segment
		(start 339.154516 -95.485204)
		(end 339.531452 -95.86214)
		(width 0.1651)
		(layer "In13.Cu")
		(net "CLK_100M_DB800ZL_SSD15_R_DN")
	)
	(segment
		(start 367.98504 -79.32674)
		(end 423.63644 -79.32674)
		(width 0.1651)
		(layer "In13.Cu")
		(net "CLK_100M_DB800ZL_SSD15_R_DN")
	)
	(segment
		(start 366.37214 -81.87944)
		(end 366.37214 -80.93964)
		(width 0.1651)
		(layer "In13.Cu")
		(net "CLK_100M_DB800ZL_SSD15_R_DN")
	)
	(segment
		(start 364.12424 -84.12734)
		(end 366.37214 -81.87944)
		(width 0.1651)
		(layer "In13.Cu")
		(net "CLK_100M_DB800ZL_SSD15_R_DN")
	)
	(segment
		(start 338.863686 -94.843854)
		(end 339.154516 -95.134684)
		(width 0.1651)
		(layer "In13.Cu")
		(net "CLK_100M_DB800ZL_SSD15_R_DN")
	)
	(segment
		(start 444.19774 -37.07384)
		(end 444.19774 -27.062176)
		(width 0.1651)
		(layer "In13.Cu")
		(net "CLK_100M_DB800ZL_SSD15_R_DN")
	)
	(segment
		(start 351.95764 -95.86214)
		(end 363.69244 -84.12734)
		(width 0.1651)
		(layer "In13.Cu")
		(net "CLK_100M_DB800ZL_SSD15_R_DN")
	)
	(segment
		(start 443.572138 -26.770076)
		(end 443.281308 -26.479246)
		(width 0.1651)
		(layer "In13.Cu")
		(net "CLK_100M_DB800ZL_SSD15_R_DN")
	)
	(segment
		(start 437.9468 -43.32478)
		(end 444.19774 -37.07384)
		(width 0.1651)
		(layer "In13.Cu")
		(net "CLK_100M_DB800ZL_SSD15_R_DN")
	)
	(segment
		(start 443.90564 -26.770076)
		(end 443.572138 -26.770076)
		(width 0.1651)
		(layer "In13.Cu")
		(net "CLK_100M_DB800ZL_SSD15_R_DN")
	)
	(segment
		(start 266.780772 -311.015888)
		(end 264.899902 -309.135018)
		(width 0.13208)
		(layer "F.Cu")
		(net "PU_PEX2_ATPG_MODE_L")
	)
	(segment
		(start 266.85367 -311.015888)
		(end 266.780772 -311.015888)
		(width 0.13208)
		(layer "F.Cu")
		(net "PU_PEX2_ATPG_MODE_L")
	)
	(via
		(at 266.85367 -311.015888)
		(size 0.508)
		(drill 0.254)
		(layers "F.Cu" "B.Cu")
		(net "PU_PEX2_ATPG_MODE_L")
	)
	(via
		(at 267.79093 -311.015888)
		(size 0.6604)
		(drill 0.3302)
		(layers "F.Cu" "B.Cu")
		(net "PU_PEX2_ATPG_MODE_L")
	)
	(via
		(at 282.349702 -309.199788)
		(size 0.4064)
		(drill 0.2032)
		(layers "F.Cu" "B.Cu")
		(net "PU_PEX2_ATPG_MODE_L")
	)
	(segment
		(start 268.241018 -310.5658)
		(end 281.812746 -310.5658)
		(width 0.13208)
		(layer "B.Cu")
		(net "PU_PEX2_ATPG_MODE_L")
	)
	(segment
		(start 281.94 -310.438546)
		(end 281.94 -309.60949)
		(width 0.13208)
		(layer "B.Cu")
		(net "PU_PEX2_ATPG_MODE_L")
	)
	(segment
		(start 281.812746 -310.5658)
		(end 281.94 -310.438546)
		(width 0.13208)
		(layer "B.Cu")
		(net "PU_PEX2_ATPG_MODE_L")
	)
	(segment
		(start 266.85367 -311.015888)
		(end 267.79093 -311.015888)
		(width 0.13208)
		(layer "B.Cu")
		(net "PU_PEX2_ATPG_MODE_L")
	)
	(segment
		(start 281.94 -309.60949)
		(end 282.349702 -309.199788)
		(width 0.13208)
		(layer "B.Cu")
		(net "PU_PEX2_ATPG_MODE_L")
	)
	(segment
		(start 267.79093 -311.015888)
		(end 268.241018 -310.5658)
		(width 0.13208)
		(layer "B.Cu")
		(net "PU_PEX2_ATPG_MODE_L")
	)
	(segment
		(start 367.355628 -83.784694)
		(end 368.06124 -83.784694)
		(width 0.13208)
		(layer "F.Cu")
		(net "SMB_BIC_I2C9_MUX1_SSD13_R_SDA")
	)
	(segment
		(start 401.762468 -22.537166)
		(end 401.762468 -22.097492)
		(width 0.13208)
		(layer "F.Cu")
		(net "SMB_BIC_I2C9_MUX1_SSD13_R_SDA")
	)
	(segment
		(start 368.06124 -83.784694)
		(end 369.095528 -83.784694)
		(width 0.13208)
		(layer "F.Cu")
		(net "SMB_BIC_I2C9_MUX1_SSD13_R_SDA")
	)
	(segment
		(start 401.235672 -21.570696)
		(end 401.235672 -20.789392)
		(width 0.13208)
		(layer "F.Cu")
		(net "SMB_BIC_I2C9_MUX1_SSD13_R_SDA")
	)
	(segment
		(start 401.52066 -21.855684)
		(end 401.235672 -21.570696)
		(width 0.13208)
		(layer "F.Cu")
		(net "SMB_BIC_I2C9_MUX1_SSD13_R_SDA")
	)
	(segment
		(start 401.762468 -22.097492)
		(end 401.52066 -21.855684)
		(width 0.13208)
		(layer "F.Cu")
		(net "SMB_BIC_I2C9_MUX1_SSD13_R_SDA")
	)
	(via
		(at 368.06124 -83.784694)
		(size 0.508)
		(drill 0.254)
		(layers "F.Cu" "B.Cu")
		(net "SMB_BIC_I2C9_MUX1_SSD13_R_SDA")
	)
	(via
		(at 401.52066 -21.855684)
		(size 0.508)
		(drill 0.254)
		(layers "F.Cu" "B.Cu")
		(net "SMB_BIC_I2C9_MUX1_SSD13_R_SDA")
	)
	(via
		(at 405.559514 -72.998838)
		(size 0.508)
		(drill 0.254)
		(layers "F.Cu" "B.Cu")
		(net "SMB_BIC_I2C9_MUX1_SSD13_R_SDA")
	)
	(segment
		(start 400.95678 -21.291804)
		(end 401.52066 -21.855684)
		(width 0.15494)
		(layer "In5.Cu")
		(net "SMB_BIC_I2C9_MUX1_SSD13_R_SDA")
	)
	(segment
		(start 399.42135 -29.287724)
		(end 399.42135 -28.09748)
		(width 0.15494)
		(layer "In5.Cu")
		(net "SMB_BIC_I2C9_MUX1_SSD13_R_SDA")
	)
	(segment
		(start 398.577308 -27.253438)
		(end 398.577308 -22.029674)
		(width 0.15494)
		(layer "In5.Cu")
		(net "SMB_BIC_I2C9_MUX1_SSD13_R_SDA")
	)
	(segment
		(start 399.315178 -21.291804)
		(end 400.95678 -21.291804)
		(width 0.15494)
		(layer "In5.Cu")
		(net "SMB_BIC_I2C9_MUX1_SSD13_R_SDA")
	)
	(segment
		(start 398.577308 -22.029674)
		(end 399.315178 -21.291804)
		(width 0.15494)
		(layer "In5.Cu")
		(net "SMB_BIC_I2C9_MUX1_SSD13_R_SDA")
	)
	(segment
		(start 398.604486 -30.104588)
		(end 399.42135 -29.287724)
		(width 0.15494)
		(layer "In5.Cu")
		(net "SMB_BIC_I2C9_MUX1_SSD13_R_SDA")
	)
	(segment
		(start 399.42135 -28.09748)
		(end 398.577308 -27.253438)
		(width 0.15494)
		(layer "In5.Cu")
		(net "SMB_BIC_I2C9_MUX1_SSD13_R_SDA")
	)
	(segment
		(start 405.559514 -72.998838)
		(end 405.559514 -69.715888)
		(width 0.15494)
		(layer "In5.Cu")
		(net "SMB_BIC_I2C9_MUX1_SSD13_R_SDA")
	)
	(segment
		(start 411.509718 -45.289724)
		(end 398.604486 -32.384492)
		(width 0.15494)
		(layer "In5.Cu")
		(net "SMB_BIC_I2C9_MUX1_SSD13_R_SDA")
	)
	(segment
		(start 411.509718 -63.765684)
		(end 411.509718 -45.289724)
		(width 0.15494)
		(layer "In5.Cu")
		(net "SMB_BIC_I2C9_MUX1_SSD13_R_SDA")
	)
	(segment
		(start 398.604486 -32.384492)
		(end 398.604486 -30.104588)
		(width 0.15494)
		(layer "In5.Cu")
		(net "SMB_BIC_I2C9_MUX1_SSD13_R_SDA")
	)
	(segment
		(start 405.559514 -69.715888)
		(end 411.509718 -63.765684)
		(width 0.15494)
		(layer "In5.Cu")
		(net "SMB_BIC_I2C9_MUX1_SSD13_R_SDA")
	)
	(segment
		(start 375.041922 -77.300582)
		(end 390.186672 -77.300582)
		(width 0.15494)
		(layer "In15.Cu")
		(net "SMB_BIC_I2C9_MUX1_SSD13_R_SDA")
	)
	(segment
		(start 371.265704 -81.0768)
		(end 375.041922 -77.300582)
		(width 0.15494)
		(layer "In15.Cu")
		(net "SMB_BIC_I2C9_MUX1_SSD13_R_SDA")
	)
	(segment
		(start 390.186672 -77.300582)
		(end 391.046208 -76.441046)
		(width 0.15494)
		(layer "In15.Cu")
		(net "SMB_BIC_I2C9_MUX1_SSD13_R_SDA")
	)
	(segment
		(start 391.046208 -76.441046)
		(end 402.117306 -76.441046)
		(width 0.15494)
		(layer "In15.Cu")
		(net "SMB_BIC_I2C9_MUX1_SSD13_R_SDA")
	)
	(segment
		(start 369.682776 -83.161124)
		(end 370.850922 -83.161124)
		(width 0.15494)
		(layer "In15.Cu")
		(net "SMB_BIC_I2C9_MUX1_SSD13_R_SDA")
	)
	(segment
		(start 368.06124 -83.784694)
		(end 369.059206 -83.784694)
		(width 0.15494)
		(layer "In15.Cu")
		(net "SMB_BIC_I2C9_MUX1_SSD13_R_SDA")
	)
	(segment
		(start 369.059206 -83.784694)
		(end 369.682776 -83.161124)
		(width 0.15494)
		(layer "In15.Cu")
		(net "SMB_BIC_I2C9_MUX1_SSD13_R_SDA")
	)
	(segment
		(start 402.117306 -76.441046)
		(end 405.559514 -72.998838)
		(width 0.15494)
		(layer "In15.Cu")
		(net "SMB_BIC_I2C9_MUX1_SSD13_R_SDA")
	)
	(segment
		(start 370.850922 -83.161124)
		(end 371.265704 -82.746342)
		(width 0.15494)
		(layer "In15.Cu")
		(net "SMB_BIC_I2C9_MUX1_SSD13_R_SDA")
	)
	(segment
		(start 371.265704 -82.746342)
		(end 371.265704 -81.0768)
		(width 0.15494)
		(layer "In15.Cu")
		(net "SMB_BIC_I2C9_MUX1_SSD13_R_SDA")
	)
	(segment
		(start 347.693742 -226.387152)
		(end 348.093538 -226.786948)
		(width 0.13208)
		(layer "F.Cu")
		(net "SSD6_PWRDIS")
	)
	(via
		(at 348.093538 -226.786948)
		(size 0.4572)
		(drill 0.254)
		(layers "F.Cu" "B.Cu")
		(net "SSD6_PWRDIS")
	)
	(via
		(at 347.51137 -231.71658)
		(size 0.6604)
		(drill 0.3302)
		(layers "F.Cu" "B.Cu")
		(net "SSD6_PWRDIS")
	)
	(segment
		(start 347.8022 -231.42575)
		(end 347.8022 -228.905054)
		(width 0.13208)
		(layer "B.Cu")
		(net "SSD6_PWRDIS")
	)
	(segment
		(start 347.8022 -228.905054)
		(end 348.093538 -228.613716)
		(width 0.13208)
		(layer "B.Cu")
		(net "SSD6_PWRDIS")
	)
	(segment
		(start 348.093538 -228.613716)
		(end 348.093538 -226.786948)
		(width 0.13208)
		(layer "B.Cu")
		(net "SSD6_PWRDIS")
	)
	(segment
		(start 347.51137 -231.71658)
		(end 347.8022 -231.42575)
		(width 0.13208)
		(layer "B.Cu")
		(net "SSD6_PWRDIS")
	)
	(segment
		(start 346.075 -233.15295)
		(end 347.51137 -231.71658)
		(width 0.13208)
		(layer "B.Cu")
		(net "SSD6_PWRDIS")
	)
	(segment
		(start 349.293942 -216.786968)
		(end 349.693738 -216.387172)
		(width 0.13208)
		(layer "F.Cu")
		(net "PRSNT_NIC2_FPGA_N")
	)
	(segment
		(start 357.61295 -213.36)
		(end 356.108 -213.36)
		(width 0.13208)
		(layer "F.Cu")
		(net "PRSNT_NIC2_FPGA_N")
	)
	(via
		(at 356.108 -213.36)
		(size 0.508)
		(drill 0.254)
		(layers "F.Cu" "B.Cu")
		(net "PRSNT_NIC2_FPGA_N")
	)
	(via
		(at 349.693738 -216.387172)
		(size 0.4572)
		(drill 0.254)
		(layers "F.Cu" "B.Cu")
		(net "PRSNT_NIC2_FPGA_N")
	)
	(segment
		(start 352.086164 -215.984836)
		(end 354.711 -213.36)
		(width 0.15494)
		(layer "In9.Cu")
		(net "PRSNT_NIC2_FPGA_N")
	)
	(segment
		(start 354.711 -213.36)
		(end 356.108 -213.36)
		(width 0.15494)
		(layer "In9.Cu")
		(net "PRSNT_NIC2_FPGA_N")
	)
	(segment
		(start 349.693738 -216.387172)
		(end 350.096074 -215.984836)
		(width 0.0889)
		(layer "In9.Cu")
		(net "PRSNT_NIC2_FPGA_N")
	)
	(segment
		(start 350.096074 -215.984836)
		(end 352.086164 -215.984836)
		(width 0.0889)
		(layer "In9.Cu")
		(net "PRSNT_NIC2_FPGA_N")
	)
	(segment
		(start 384.302 -237.998)
		(end 387.488938 -234.811062)
		(width 0.13208)
		(layer "F.Cu")
		(net "UART_PEX0_SDB_BUF_TX")
	)
	(segment
		(start 387.488938 -234.811062)
		(end 390.330436 -234.811062)
		(width 0.13208)
		(layer "F.Cu")
		(net "UART_PEX0_SDB_BUF_TX")
	)
	(segment
		(start 383.413 -237.998)
		(end 384.302 -237.998)
		(width 0.13208)
		(layer "F.Cu")
		(net "UART_PEX0_SDB_BUF_TX")
	)
	(via
		(at 383.413 -237.998)
		(size 0.508)
		(drill 0.254)
		(layers "F.Cu" "B.Cu")
		(net "UART_PEX0_SDB_BUF_TX")
	)
	(segment
		(start 382.839976 -238.571024)
		(end 383.413 -237.998)
		(width 0.13208)
		(layer "B.Cu")
		(net "UART_PEX0_SDB_BUF_TX")
	)
	(segment
		(start 381.254 -242.824)
		(end 381.762 -242.316)
		(width 0.13208)
		(layer "B.Cu")
		(net "UART_PEX0_SDB_BUF_TX")
	)
	(segment
		(start 379.447552 -242.979448)
		(end 379.603 -242.824)
		(width 0.13208)
		(layer "B.Cu")
		(net "UART_PEX0_SDB_BUF_TX")
	)
	(segment
		(start 381.762 -242.316)
		(end 381.762 -240.867438)
		(width 0.13208)
		(layer "B.Cu")
		(net "UART_PEX0_SDB_BUF_TX")
	)
	(segment
		(start 379.447552 -243.428012)
		(end 379.447552 -242.979448)
		(width 0.13208)
		(layer "B.Cu")
		(net "UART_PEX0_SDB_BUF_TX")
	)
	(segment
		(start 378.469652 -243.428012)
		(end 379.447552 -243.428012)
		(width 0.13208)
		(layer "B.Cu")
		(net "UART_PEX0_SDB_BUF_TX")
	)
	(segment
		(start 381.762 -240.867438)
		(end 382.839976 -239.789462)
		(width 0.13208)
		(layer "B.Cu")
		(net "UART_PEX0_SDB_BUF_TX")
	)
	(segment
		(start 382.839976 -239.789462)
		(end 382.839976 -238.571024)
		(width 0.13208)
		(layer "B.Cu")
		(net "UART_PEX0_SDB_BUF_TX")
	)
	(segment
		(start 379.603 -242.824)
		(end 381.254 -242.824)
		(width 0.13208)
		(layer "B.Cu")
		(net "UART_PEX0_SDB_BUF_TX")
	)
	(segment
		(start 136.652 -215.3412)
		(end 135.481568 -215.3412)
		(width 0.13208)
		(layer "F.Cu")
		(net "UART_PEX2_CLI_BUF_TX")
	)
	(segment
		(start 140.306806 -211.93887)
		(end 140.306806 -212.6996)
		(width 0.13208)
		(layer "F.Cu")
		(net "UART_PEX2_CLI_BUF_TX")
	)
	(segment
		(start 138.4808 -212.8266)
		(end 137.1346 -214.1728)
		(width 0.13208)
		(layer "F.Cu")
		(net "UART_PEX2_CLI_BUF_TX")
	)
	(segment
		(start 137.1346 -214.8586)
		(end 136.652 -215.3412)
		(width 0.13208)
		(layer "F.Cu")
		(net "UART_PEX2_CLI_BUF_TX")
	)
	(segment
		(start 140.306806 -212.6996)
		(end 140.179806 -212.8266)
		(width 0.13208)
		(layer "F.Cu")
		(net "UART_PEX2_CLI_BUF_TX")
	)
	(segment
		(start 135.481568 -215.3412)
		(end 134.808214 -214.667846)
		(width 0.13208)
		(layer "F.Cu")
		(net "UART_PEX2_CLI_BUF_TX")
	)
	(segment
		(start 140.179806 -212.8266)
		(end 138.4808 -212.8266)
		(width 0.13208)
		(layer "F.Cu")
		(net "UART_PEX2_CLI_BUF_TX")
	)
	(segment
		(start 137.1346 -214.1728)
		(end 137.1346 -214.8586)
		(width 0.13208)
		(layer "F.Cu")
		(net "UART_PEX2_CLI_BUF_TX")
	)
	(via
		(at 134.808214 -214.667846)
		(size 0.508)
		(drill 0.254)
		(layers "F.Cu" "B.Cu")
		(net "UART_PEX2_CLI_BUF_TX")
	)
	(segment
		(start 134.408164 -213.524846)
		(end 134.408164 -214.267796)
		(width 0.13208)
		(layer "B.Cu")
		(net "UART_PEX2_CLI_BUF_TX")
	)
	(segment
		(start 134.408164 -214.267796)
		(end 134.808214 -214.667846)
		(width 0.13208)
		(layer "B.Cu")
		(net "UART_PEX2_CLI_BUF_TX")
	)
	(segment
		(start 133.430264 -213.524846)
		(end 134.408164 -213.524846)
		(width 0.13208)
		(layer "B.Cu")
		(net "UART_PEX2_CLI_BUF_TX")
	)
	(segment
		(start 321.20205 -305.092354)
		(end 321.201542 -305.091846)
		(width 0.13208)
		(layer "F.Cu")
		(net "PEX2_SPARE4")
	)
	(segment
		(start 321.20205 -305.092354)
		(end 321.20205 -305.674522)
		(width 0.13208)
		(layer "F.Cu")
		(net "PEX2_SPARE4")
	)
	(segment
		(start 292.32479 -307.774848)
		(end 291.84981 -308.249828)
		(width 0.13462)
		(layer "F.Cu")
		(net "PEX2_SPARE4")
	)
	(segment
		(start 321.20205 -305.064922)
		(end 321.20205 -305.092354)
		(width 0.13208)
		(layer "F.Cu")
		(net "PEX2_SPARE4")
	)
	(segment
		(start 321.201542 -305.091846)
		(end 321.201542 -304.436526)
		(width 0.13208)
		(layer "F.Cu")
		(net "PEX2_SPARE4")
	)
	(via
		(at 292.32479 -307.774848)
		(size 0.4064)
		(drill 0.2032)
		(layers "F.Cu" "B.Cu")
		(net "PEX2_SPARE4")
	)
	(via
		(at 320.654934 -303.544986)
		(size 0.6604)
		(drill 0.3302)
		(layers "F.Cu" "B.Cu")
		(net "PEX2_SPARE4")
	)
	(via
		(at 321.20205 -305.064922)
		(size 0.508)
		(drill 0.254)
		(layers "F.Cu" "B.Cu")
		(net "PEX2_SPARE4")
	)
	(segment
		(start 319.05956 -304.859182)
		(end 317.083186 -306.835556)
		(width 0.13208)
		(layer "B.Cu")
		(net "PEX2_SPARE4")
	)
	(segment
		(start 320.654934 -303.544986)
		(end 320.322956 -303.544986)
		(width 0.13208)
		(layer "B.Cu")
		(net "PEX2_SPARE4")
	)
	(segment
		(start 304.199036 -307.967126)
		(end 303.929542 -308.23662)
		(width 0.13208)
		(layer "B.Cu")
		(net "PEX2_SPARE4")
	)
	(segment
		(start 303.929542 -308.23662)
		(end 292.786562 -308.23662)
		(width 0.13208)
		(layer "B.Cu")
		(net "PEX2_SPARE4")
	)
	(segment
		(start 304.199036 -307.527706)
		(end 304.199036 -307.967126)
		(width 0.13208)
		(layer "B.Cu")
		(net "PEX2_SPARE4")
	)
	(segment
		(start 319.675764 -304.859182)
		(end 319.05956 -304.859182)
		(width 0.13208)
		(layer "B.Cu")
		(net "PEX2_SPARE4")
	)
	(segment
		(start 321.20205 -304.092102)
		(end 320.654934 -303.544986)
		(width 0.13208)
		(layer "B.Cu")
		(net "PEX2_SPARE4")
	)
	(segment
		(start 319.989454 -303.878488)
		(end 319.989454 -304.545492)
		(width 0.13208)
		(layer "B.Cu")
		(net "PEX2_SPARE4")
	)
	(segment
		(start 319.989454 -304.545492)
		(end 319.675764 -304.859182)
		(width 0.13208)
		(layer "B.Cu")
		(net "PEX2_SPARE4")
	)
	(segment
		(start 317.083186 -306.835556)
		(end 305.707034 -306.835556)
		(width 0.13208)
		(layer "B.Cu")
		(net "PEX2_SPARE4")
	)
	(segment
		(start 320.322956 -303.544986)
		(end 319.989454 -303.878488)
		(width 0.13208)
		(layer "B.Cu")
		(net "PEX2_SPARE4")
	)
	(segment
		(start 305.25339 -307.2892)
		(end 304.437542 -307.2892)
		(width 0.13208)
		(layer "B.Cu")
		(net "PEX2_SPARE4")
	)
	(segment
		(start 321.20205 -305.064922)
		(end 321.20205 -304.092102)
		(width 0.13208)
		(layer "B.Cu")
		(net "PEX2_SPARE4")
	)
	(segment
		(start 304.437542 -307.2892)
		(end 304.199036 -307.527706)
		(width 0.13208)
		(layer "B.Cu")
		(net "PEX2_SPARE4")
	)
	(segment
		(start 292.786562 -308.23662)
		(end 292.32479 -307.774848)
		(width 0.13208)
		(layer "B.Cu")
		(net "PEX2_SPARE4")
	)
	(segment
		(start 305.707034 -306.835556)
		(end 305.25339 -307.2892)
		(width 0.13208)
		(layer "B.Cu")
		(net "PEX2_SPARE4")
	)
	(segment
		(start 453.762364 -21.824442)
		(end 453.762364 -22.537166)
		(width 0.13208)
		(layer "F.Cu")
		(net "SMB_BIC_I2C9_MUX1_SSD15_R_SDA")
	)
	(segment
		(start 453.235568 -21.648674)
		(end 453.411336 -21.824442)
		(width 0.13208)
		(layer "F.Cu")
		(net "SMB_BIC_I2C9_MUX1_SSD15_R_SDA")
	)
	(segment
		(start 367.355628 -88.356694)
		(end 367.355628 -88.658954)
		(width 0.13208)
		(layer "F.Cu")
		(net "SMB_BIC_I2C9_MUX1_SSD15_R_SDA")
	)
	(segment
		(start 368.338608 -88.356694)
		(end 369.095528 -88.356694)
		(width 0.13208)
		(layer "F.Cu")
		(net "SMB_BIC_I2C9_MUX1_SSD15_R_SDA")
	)
	(segment
		(start 453.411336 -21.824442)
		(end 453.762364 -21.824442)
		(width 0.13208)
		(layer "F.Cu")
		(net "SMB_BIC_I2C9_MUX1_SSD15_R_SDA")
	)
	(segment
		(start 367.937288 -88.758014)
		(end 368.338608 -88.356694)
		(width 0.13208)
		(layer "F.Cu")
		(net "SMB_BIC_I2C9_MUX1_SSD15_R_SDA")
	)
	(segment
		(start 367.355628 -88.658954)
		(end 367.454688 -88.758014)
		(width 0.13208)
		(layer "F.Cu")
		(net "SMB_BIC_I2C9_MUX1_SSD15_R_SDA")
	)
	(segment
		(start 367.454688 -88.758014)
		(end 367.937288 -88.758014)
		(width 0.13208)
		(layer "F.Cu")
		(net "SMB_BIC_I2C9_MUX1_SSD15_R_SDA")
	)
	(segment
		(start 453.235568 -20.789392)
		(end 453.235568 -21.648674)
		(width 0.13208)
		(layer "F.Cu")
		(net "SMB_BIC_I2C9_MUX1_SSD15_R_SDA")
	)
	(via
		(at 367.937288 -88.758014)
		(size 0.508)
		(drill 0.254)
		(layers "F.Cu" "B.Cu")
		(net "SMB_BIC_I2C9_MUX1_SSD15_R_SDA")
	)
	(via
		(at 453.762364 -21.824442)
		(size 0.508)
		(drill 0.254)
		(layers "F.Cu" "B.Cu")
		(net "SMB_BIC_I2C9_MUX1_SSD15_R_SDA")
	)
	(via
		(at 458.408532 -74.784966)
		(size 0.508)
		(drill 0.254)
		(layers "F.Cu" "B.Cu")
		(net "SMB_BIC_I2C9_MUX1_SSD15_R_SDA")
	)
	(segment
		(start 458.408532 -74.126598)
		(end 458.408532 -74.784966)
		(width 0.15494)
		(layer "In5.Cu")
		(net "SMB_BIC_I2C9_MUX1_SSD15_R_SDA")
	)
	(segment
		(start 453.762364 -21.824442)
		(end 453.480932 -21.824442)
		(width 0.15494)
		(layer "In5.Cu")
		(net "SMB_BIC_I2C9_MUX1_SSD15_R_SDA")
	)
	(segment
		(start 450.546724 -26.977594)
		(end 451.485508 -27.916378)
		(width 0.15494)
		(layer "In5.Cu")
		(net "SMB_BIC_I2C9_MUX1_SSD15_R_SDA")
	)
	(segment
		(start 450.546724 -22.15642)
		(end 450.546724 -26.977594)
		(width 0.15494)
		(layer "In5.Cu")
		(net "SMB_BIC_I2C9_MUX1_SSD15_R_SDA")
	)
	(segment
		(start 456.50277 -72.220836)
		(end 458.408532 -74.126598)
		(width 0.15494)
		(layer "In5.Cu")
		(net "SMB_BIC_I2C9_MUX1_SSD15_R_SDA")
	)
	(segment
		(start 451.485508 -27.916378)
		(end 451.485508 -29.266134)
		(width 0.15494)
		(layer "In5.Cu")
		(net "SMB_BIC_I2C9_MUX1_SSD15_R_SDA")
	)
	(segment
		(start 450.617844 -30.133798)
		(end 450.617844 -32.410146)
		(width 0.15494)
		(layer "In5.Cu")
		(net "SMB_BIC_I2C9_MUX1_SSD15_R_SDA")
	)
	(segment
		(start 451.485508 -29.266134)
		(end 450.617844 -30.133798)
		(width 0.15494)
		(layer "In5.Cu")
		(net "SMB_BIC_I2C9_MUX1_SSD15_R_SDA")
	)
	(segment
		(start 452.948294 -21.291804)
		(end 451.41134 -21.291804)
		(width 0.15494)
		(layer "In5.Cu")
		(net "SMB_BIC_I2C9_MUX1_SSD15_R_SDA")
	)
	(segment
		(start 450.617844 -32.410146)
		(end 456.50277 -38.295072)
		(width 0.15494)
		(layer "In5.Cu")
		(net "SMB_BIC_I2C9_MUX1_SSD15_R_SDA")
	)
	(segment
		(start 456.50277 -38.295072)
		(end 456.50277 -72.220836)
		(width 0.15494)
		(layer "In5.Cu")
		(net "SMB_BIC_I2C9_MUX1_SSD15_R_SDA")
	)
	(segment
		(start 451.41134 -21.291804)
		(end 450.546724 -22.15642)
		(width 0.15494)
		(layer "In5.Cu")
		(net "SMB_BIC_I2C9_MUX1_SSD15_R_SDA")
	)
	(segment
		(start 453.480932 -21.824442)
		(end 452.948294 -21.291804)
		(width 0.15494)
		(layer "In5.Cu")
		(net "SMB_BIC_I2C9_MUX1_SSD15_R_SDA")
	)
	(segment
		(start 367.937288 -88.758014)
		(end 368.338608 -88.356694)
		(width 0.15494)
		(layer "In15.Cu")
		(net "SMB_BIC_I2C9_MUX1_SSD15_R_SDA")
	)
	(segment
		(start 368.338608 -88.356694)
		(end 369.236752 -88.356694)
		(width 0.15494)
		(layer "In15.Cu")
		(net "SMB_BIC_I2C9_MUX1_SSD15_R_SDA")
	)
	(segment
		(start 369.778534 -87.814912)
		(end 370.84635 -87.814912)
		(width 0.15494)
		(layer "In15.Cu")
		(net "SMB_BIC_I2C9_MUX1_SSD15_R_SDA")
	)
	(segment
		(start 373.264684 -81.958942)
		(end 376.017028 -79.206598)
		(width 0.15494)
		(layer "In15.Cu")
		(net "SMB_BIC_I2C9_MUX1_SSD15_R_SDA")
	)
	(segment
		(start 370.84635 -87.814912)
		(end 373.264684 -85.396578)
		(width 0.15494)
		(layer "In15.Cu")
		(net "SMB_BIC_I2C9_MUX1_SSD15_R_SDA")
	)
	(segment
		(start 457.820268 -75.37323)
		(end 458.408532 -74.784966)
		(width 0.15494)
		(layer "In15.Cu")
		(net "SMB_BIC_I2C9_MUX1_SSD15_R_SDA")
	)
	(segment
		(start 425.1071 -79.206598)
		(end 428.940468 -75.37323)
		(width 0.15494)
		(layer "In15.Cu")
		(net "SMB_BIC_I2C9_MUX1_SSD15_R_SDA")
	)
	(segment
		(start 428.940468 -75.37323)
		(end 457.820268 -75.37323)
		(width 0.15494)
		(layer "In15.Cu")
		(net "SMB_BIC_I2C9_MUX1_SSD15_R_SDA")
	)
	(segment
		(start 373.264684 -85.396578)
		(end 373.264684 -81.958942)
		(width 0.15494)
		(layer "In15.Cu")
		(net "SMB_BIC_I2C9_MUX1_SSD15_R_SDA")
	)
	(segment
		(start 376.017028 -79.206598)
		(end 425.1071 -79.206598)
		(width 0.15494)
		(layer "In15.Cu")
		(net "SMB_BIC_I2C9_MUX1_SSD15_R_SDA")
	)
	(segment
		(start 369.236752 -88.356694)
		(end 369.778534 -87.814912)
		(width 0.15494)
		(layer "In15.Cu")
		(net "SMB_BIC_I2C9_MUX1_SSD15_R_SDA")
	)
	(segment
		(start 231.87152 -212.40369)
		(end 231.87152 -213.100412)
		(width 0.13208)
		(layer "F.Cu")
		(net "SPI_BIC1_CS1_N")
	)
	(segment
		(start 230.991664 -207.42021)
		(end 230.991664 -208.053686)
		(width 0.13208)
		(layer "F.Cu")
		(net "SPI_BIC1_CS1_N")
	)
	(segment
		(start 230.991664 -208.053686)
		(end 230.728012 -208.317338)
		(width 0.13208)
		(layer "F.Cu")
		(net "SPI_BIC1_CS1_N")
	)
	(segment
		(start 231.648 -210.54822)
		(end 231.648 -212.18017)
		(width 0.13208)
		(layer "F.Cu")
		(net "SPI_BIC1_CS1_N")
	)
	(segment
		(start 231.87152 -213.100412)
		(end 231.46766 -213.504272)
		(width 0.13208)
		(layer "F.Cu")
		(net "SPI_BIC1_CS1_N")
	)
	(segment
		(start 230.728012 -209.628232)
		(end 231.648 -210.54822)
		(width 0.13208)
		(layer "F.Cu")
		(net "SPI_BIC1_CS1_N")
	)
	(segment
		(start 231.648 -212.18017)
		(end 231.87152 -212.40369)
		(width 0.13208)
		(layer "F.Cu")
		(net "SPI_BIC1_CS1_N")
	)
	(segment
		(start 230.728012 -208.317338)
		(end 230.728012 -209.628232)
		(width 0.13208)
		(layer "F.Cu")
		(net "SPI_BIC1_CS1_N")
	)
	(via
		(at 230.728012 -209.628232)
		(size 0.762)
		(drill 0.381)
		(layers "F.Cu" "B.Cu")
		(net "SPI_BIC1_CS1_N")
	)
	(segment
		(start 377.33605 -187.833)
		(end 378.137674 -187.833)
		(width 0.13208)
		(layer "F.Cu")
		(net "RST_PEX_NIC1_PERST_R_N")
	)
	(segment
		(start 377.33605 -188.849)
		(end 377.33605 -187.833)
		(width 0.13208)
		(layer "F.Cu")
		(net "RST_PEX_NIC1_PERST_R_N")
	)
	(segment
		(start 350.093788 -215.187022)
		(end 350.493584 -214.787226)
		(width 0.13208)
		(layer "F.Cu")
		(net "RST_PEX_NIC1_PERST_R_N")
	)
	(via
		(at 378.137674 -187.833)
		(size 0.508)
		(drill 0.254)
		(layers "F.Cu" "B.Cu")
		(net "RST_PEX_NIC1_PERST_R_N")
	)
	(via
		(at 350.493584 -214.787226)
		(size 0.4572)
		(drill 0.254)
		(layers "F.Cu" "B.Cu")
		(net "RST_PEX_NIC1_PERST_R_N")
	)
	(via
		(at 367.466118 -186.826144)
		(size 0.508)
		(drill 0.254)
		(layers "F.Cu" "B.Cu")
		(net "RST_PEX_NIC1_PERST_R_N")
	)
	(segment
		(start 350.901 -214.37981)
		(end 350.493584 -214.787226)
		(width 0.0889)
		(layer "In5.Cu")
		(net "RST_PEX_NIC1_PERST_R_N")
	)
	(segment
		(start 358.394 -208.0768)
		(end 358.394 -208.3816)
		(width 0.15494)
		(layer "In5.Cu")
		(net "RST_PEX_NIC1_PERST_R_N")
	)
	(segment
		(start 358.775 -207.6958)
		(end 358.394 -208.0768)
		(width 0.15494)
		(layer "In5.Cu")
		(net "RST_PEX_NIC1_PERST_R_N")
	)
	(segment
		(start 355.40442 -209.70494)
		(end 351.51949 -213.58987)
		(width 0.15494)
		(layer "In5.Cu")
		(net "RST_PEX_NIC1_PERST_R_N")
	)
	(segment
		(start 360.934 -206.9338)
		(end 360.172 -207.6958)
		(width 0.15494)
		(layer "In5.Cu")
		(net "RST_PEX_NIC1_PERST_R_N")
	)
	(segment
		(start 360.934 -204.672692)
		(end 360.934 -206.9338)
		(width 0.15494)
		(layer "In5.Cu")
		(net "RST_PEX_NIC1_PERST_R_N")
	)
	(segment
		(start 360.172 -207.6958)
		(end 358.775 -207.6958)
		(width 0.15494)
		(layer "In5.Cu")
		(net "RST_PEX_NIC1_PERST_R_N")
	)
	(segment
		(start 351.51949 -213.58987)
		(end 351.02673 -213.58987)
		(width 0.0889)
		(layer "In5.Cu")
		(net "RST_PEX_NIC1_PERST_R_N")
	)
	(segment
		(start 351.02673 -213.58987)
		(end 350.901 -213.7156)
		(width 0.0889)
		(layer "In5.Cu")
		(net "RST_PEX_NIC1_PERST_R_N")
	)
	(segment
		(start 366.425988 -187.866274)
		(end 366.425988 -199.180704)
		(width 0.15494)
		(layer "In5.Cu")
		(net "RST_PEX_NIC1_PERST_R_N")
	)
	(segment
		(start 366.425988 -199.180704)
		(end 360.934 -204.672692)
		(width 0.15494)
		(layer "In5.Cu")
		(net "RST_PEX_NIC1_PERST_R_N")
	)
	(segment
		(start 357.07066 -209.70494)
		(end 355.40442 -209.70494)
		(width 0.15494)
		(layer "In5.Cu")
		(net "RST_PEX_NIC1_PERST_R_N")
	)
	(segment
		(start 358.394 -208.3816)
		(end 357.07066 -209.70494)
		(width 0.15494)
		(layer "In5.Cu")
		(net "RST_PEX_NIC1_PERST_R_N")
	)
	(segment
		(start 350.901 -213.7156)
		(end 350.901 -214.37981)
		(width 0.0889)
		(layer "In5.Cu")
		(net "RST_PEX_NIC1_PERST_R_N")
	)
	(segment
		(start 367.466118 -186.826144)
		(end 366.425988 -187.866274)
		(width 0.15494)
		(layer "In5.Cu")
		(net "RST_PEX_NIC1_PERST_R_N")
	)
	(segment
		(start 374.623838 -187.325)
		(end 374.124982 -186.826144)
		(width 0.15494)
		(layer "In13.Cu")
		(net "RST_PEX_NIC1_PERST_R_N")
	)
	(segment
		(start 378.137674 -187.833)
		(end 377.629674 -187.325)
		(width 0.15494)
		(layer "In13.Cu")
		(net "RST_PEX_NIC1_PERST_R_N")
	)
	(segment
		(start 377.629674 -187.325)
		(end 374.623838 -187.325)
		(width 0.15494)
		(layer "In13.Cu")
		(net "RST_PEX_NIC1_PERST_R_N")
	)
	(segment
		(start 374.124982 -186.826144)
		(end 367.466118 -186.826144)
		(width 0.15494)
		(layer "In13.Cu")
		(net "RST_PEX_NIC1_PERST_R_N")
	)
	(segment
		(start 309.80126 -53.051456)
		(end 310.067706 -53.051456)
		(width 0.13208)
		(layer "F.Cu")
		(net "PWRGD_P12V_SSD10")
	)
	(segment
		(start 309.337202 -52.587398)
		(end 309.80126 -53.051456)
		(width 0.13208)
		(layer "F.Cu")
		(net "PWRGD_P12V_SSD10")
	)
	(segment
		(start 309.337202 -53.023008)
		(end 309.337202 -52.587398)
		(width 0.13208)
		(layer "F.Cu")
		(net "PWRGD_P12V_SSD10")
	)
	(segment
		(start 310.067706 -52.035456)
		(end 310.067706 -53.051456)
		(width 0.13208)
		(layer "F.Cu")
		(net "PWRGD_P12V_SSD10")
	)
	(segment
		(start 308.34711 -53.644038)
		(end 308.716172 -53.644038)
		(width 0.13208)
		(layer "F.Cu")
		(net "PWRGD_P12V_SSD10")
	)
	(segment
		(start 308.716172 -53.644038)
		(end 309.337202 -53.023008)
		(width 0.13208)
		(layer "F.Cu")
		(net "PWRGD_P12V_SSD10")
	)
	(via
		(at 309.337202 -52.587398)
		(size 0.508)
		(drill 0.254)
		(layers "F.Cu" "B.Cu")
		(net "PWRGD_P12V_SSD10")
	)
	(segment
		(start 298.499784 -309.199788)
		(end 298.974764 -308.724808)
		(width 0.13208)
		(layer "F.Cu")
		(net "PEX2_SPARE3")
	)
	(segment
		(start 322.21805 -305.065938)
		(end 322.21805 -305.674522)
		(width 0.13208)
		(layer "F.Cu")
		(net "PEX2_SPARE3")
	)
	(segment
		(start 322.217542 -305.064414)
		(end 322.217034 -305.064922)
		(width 0.13208)
		(layer "F.Cu")
		(net "PEX2_SPARE3")
	)
	(segment
		(start 322.217034 -305.064922)
		(end 322.21805 -305.065938)
		(width 0.13208)
		(layer "F.Cu")
		(net "PEX2_SPARE3")
	)
	(segment
		(start 322.217542 -304.436526)
		(end 322.217542 -305.064414)
		(width 0.13208)
		(layer "F.Cu")
		(net "PEX2_SPARE3")
	)
	(via
		(at 298.974764 -308.724808)
		(size 0.4064)
		(drill 0.2032)
		(layers "F.Cu" "B.Cu")
		(net "PEX2_SPARE3")
	)
	(via
		(at 316.334902 -310.149748)
		(size 0.6604)
		(drill 0.3302)
		(layers "F.Cu" "B.Cu")
		(net "PEX2_SPARE3")
	)
	(via
		(at 322.217034 -305.064922)
		(size 0.508)
		(drill 0.254)
		(layers "F.Cu" "B.Cu")
		(net "PEX2_SPARE3")
	)
	(segment
		(start 299.329094 -310.657494)
		(end 310.174386 -310.657494)
		(width 0.13208)
		(layer "B.Cu")
		(net "PEX2_SPARE3")
	)
	(segment
		(start 310.394858 -309.890414)
		(end 310.600344 -309.684928)
		(width 0.13208)
		(layer "B.Cu")
		(net "PEX2_SPARE3")
	)
	(segment
		(start 298.974764 -310.303164)
		(end 299.329094 -310.657494)
		(width 0.13208)
		(layer "B.Cu")
		(net "PEX2_SPARE3")
	)
	(segment
		(start 298.974764 -308.724808)
		(end 298.974764 -310.303164)
		(width 0.13208)
		(layer "B.Cu")
		(net "PEX2_SPARE3")
	)
	(segment
		(start 315.870082 -309.684928)
		(end 316.334902 -310.149748)
		(width 0.13208)
		(layer "B.Cu")
		(net "PEX2_SPARE3")
	)
	(segment
		(start 322.217034 -305.534822)
		(end 322.217034 -305.064922)
		(width 0.13208)
		(layer "B.Cu")
		(net "PEX2_SPARE3")
	)
	(segment
		(start 310.174386 -310.657494)
		(end 310.394858 -310.437022)
		(width 0.13208)
		(layer "B.Cu")
		(net "PEX2_SPARE3")
	)
	(segment
		(start 316.334902 -310.149748)
		(end 317.602108 -310.149748)
		(width 0.13208)
		(layer "B.Cu")
		(net "PEX2_SPARE3")
	)
	(segment
		(start 310.394858 -310.437022)
		(end 310.394858 -309.890414)
		(width 0.13208)
		(layer "B.Cu")
		(net "PEX2_SPARE3")
	)
	(segment
		(start 317.602108 -310.149748)
		(end 322.217034 -305.534822)
		(width 0.13208)
		(layer "B.Cu")
		(net "PEX2_SPARE3")
	)
	(segment
		(start 310.600344 -309.684928)
		(end 315.870082 -309.684928)
		(width 0.13208)
		(layer "B.Cu")
		(net "PEX2_SPARE3")
	)
	(segment
		(start 355.424994 -84.864956)
		(end 354.514404 -83.954366)
		(width 0.13208)
		(layer "F.Cu")
		(net "SMB_BIC_I2C9_MUX1_SSD10_SCL")
	)
	(segment
		(start 354.514404 -83.954366)
		(end 353.487736 -83.954366)
		(width 0.13208)
		(layer "F.Cu")
		(net "SMB_BIC_I2C9_MUX1_SSD10_SCL")
	)
	(segment
		(start 356.707948 -84.864956)
		(end 355.424994 -84.864956)
		(width 0.13208)
		(layer "F.Cu")
		(net "SMB_BIC_I2C9_MUX1_SSD10_SCL")
	)
	(segment
		(start 353.487736 -83.954366)
		(end 353.320604 -83.787234)
		(width 0.13208)
		(layer "F.Cu")
		(net "SMB_BIC_I2C9_MUX1_SSD10_SCL")
	)
	(via
		(at 354.514404 -83.954366)
		(size 0.508)
		(drill 0.254)
		(layers "F.Cu" "B.Cu")
		(net "SMB_BIC_I2C9_MUX1_SSD10_SCL")
	)
	(segment
		(start 347.472 -232.791)
		(end 347.472 -231.521)
		(width 0.13208)
		(layer "F.Cu")
		(net "RST_SSD5_PERST_N")
	)
	(segment
		(start 347.091 -233.66095)
		(end 347.091 -233.172)
		(width 0.13208)
		(layer "F.Cu")
		(net "RST_SSD5_PERST_N")
	)
	(segment
		(start 347.472 -230.93807)
		(end 346.71 -230.17607)
		(width 0.13208)
		(layer "F.Cu")
		(net "RST_SSD5_PERST_N")
	)
	(segment
		(start 347.472 -231.521)
		(end 347.472 -230.93807)
		(width 0.13208)
		(layer "F.Cu")
		(net "RST_SSD5_PERST_N")
	)
	(segment
		(start 346.71 -228.170994)
		(end 346.893896 -227.987098)
		(width 0.13208)
		(layer "F.Cu")
		(net "RST_SSD5_PERST_N")
	)
	(segment
		(start 346.71 -230.17607)
		(end 346.71 -228.170994)
		(width 0.13208)
		(layer "F.Cu")
		(net "RST_SSD5_PERST_N")
	)
	(segment
		(start 347.091 -233.172)
		(end 347.472 -232.791)
		(width 0.13208)
		(layer "F.Cu")
		(net "RST_SSD5_PERST_N")
	)
	(via
		(at 347.472 -231.521)
		(size 0.762)
		(drill 0.381)
		(layers "F.Cu" "B.Cu")
		(net "RST_SSD5_PERST_N")
	)
	(segment
		(start 382.524 -242.316)
		(end 383.413 -241.427)
		(width 0.13208)
		(layer "F.Cu")
		(net "UART_PEX3_SDB_RX")
	)
	(segment
		(start 380.855474 -244.286024)
		(end 380.855474 -243.476526)
		(width 0.13208)
		(layer "F.Cu")
		(net "UART_PEX3_SDB_RX")
	)
	(segment
		(start 382.016 -242.316)
		(end 382.524 -242.316)
		(width 0.13208)
		(layer "F.Cu")
		(net "UART_PEX3_SDB_RX")
	)
	(segment
		(start 380.855474 -243.476526)
		(end 382.016 -242.316)
		(width 0.13208)
		(layer "F.Cu")
		(net "UART_PEX3_SDB_RX")
	)
	(via
		(at 383.413 -241.427)
		(size 0.508)
		(drill 0.254)
		(layers "F.Cu" "B.Cu")
		(net "UART_PEX3_SDB_RX")
	)
	(segment
		(start 384.175 -240.665)
		(end 383.413 -241.427)
		(width 0.13208)
		(layer "B.Cu")
		(net "UART_PEX3_SDB_RX")
	)
	(segment
		(start 384.683 -239.522)
		(end 384.175 -240.03)
		(width 0.13208)
		(layer "B.Cu")
		(net "UART_PEX3_SDB_RX")
	)
	(segment
		(start 385.04495 -239.522)
		(end 384.683 -239.522)
		(width 0.13208)
		(layer "B.Cu")
		(net "UART_PEX3_SDB_RX")
	)
	(segment
		(start 384.175 -240.03)
		(end 384.175 -240.665)
		(width 0.13208)
		(layer "B.Cu")
		(net "UART_PEX3_SDB_RX")
	)
	(via
		(at 140.388594 -213.39048)
		(size 0.6604)
		(drill 0.3302)
		(layers "F.Cu" "B.Cu")
		(net "UART_PEX3_CLI_BUF_R_RX")
	)
	(segment
		(start 141.143228 -212.635846)
		(end 141.143228 -211.857844)
		(width 0.13208)
		(layer "B.Cu")
		(net "UART_PEX3_CLI_BUF_R_RX")
	)
	(segment
		(start 140.37691 -213.402164)
		(end 140.388594 -213.39048)
		(width 0.13208)
		(layer "B.Cu")
		(net "UART_PEX3_CLI_BUF_R_RX")
	)
	(segment
		(start 140.388594 -213.39048)
		(end 141.143228 -212.635846)
		(width 0.13208)
		(layer "B.Cu")
		(net "UART_PEX3_CLI_BUF_R_RX")
	)
	(segment
		(start 140.37691 -214.564722)
		(end 140.37691 -213.402164)
		(width 0.13208)
		(layer "B.Cu")
		(net "UART_PEX3_CLI_BUF_R_RX")
	)
	(segment
		(start 261.77494 -307.11775)
		(end 261.306564 -306.649374)
		(width 0.13208)
		(layer "F.Cu")
		(net "PEX2_DFT_IDDT")
	)
	(segment
		(start 262.040624 -307.11775)
		(end 261.77494 -307.11775)
		(width 0.13208)
		(layer "F.Cu")
		(net "PEX2_DFT_IDDT")
	)
	(segment
		(start 262.024876 -305.931062)
		(end 261.306564 -306.649374)
		(width 0.13208)
		(layer "F.Cu")
		(net "PEX2_DFT_IDDT")
	)
	(segment
		(start 283.299916 -308.249828)
		(end 282.824936 -307.774848)
		(width 0.13208)
		(layer "F.Cu")
		(net "PEX2_DFT_IDDT")
	)
	(segment
		(start 262.339074 -306.8193)
		(end 262.040624 -307.11775)
		(width 0.13208)
		(layer "F.Cu")
		(net "PEX2_DFT_IDDT")
	)
	(via
		(at 262.339074 -306.8193)
		(size 0.508)
		(drill 0.254)
		(layers "F.Cu" "B.Cu")
		(net "PEX2_DFT_IDDT")
	)
	(via
		(at 282.824936 -307.774848)
		(size 0.4064)
		(drill 0.2032)
		(layers "F.Cu" "B.Cu")
		(net "PEX2_DFT_IDDT")
	)
	(segment
		(start 264.231374 -304.927)
		(end 277.850346 -304.927)
		(width 0.13208)
		(layer "B.Cu")
		(net "PEX2_DFT_IDDT")
	)
	(segment
		(start 280.799032 -307.265832)
		(end 282.31592 -307.265832)
		(width 0.13208)
		(layer "B.Cu")
		(net "PEX2_DFT_IDDT")
	)
	(segment
		(start 280.154126 -305.376326)
		(end 280.456132 -305.678332)
		(width 0.13208)
		(layer "B.Cu")
		(net "PEX2_DFT_IDDT")
	)
	(segment
		(start 280.456132 -306.922932)
		(end 280.799032 -307.265832)
		(width 0.13208)
		(layer "B.Cu")
		(net "PEX2_DFT_IDDT")
	)
	(segment
		(start 278.299672 -305.376326)
		(end 280.154126 -305.376326)
		(width 0.13208)
		(layer "B.Cu")
		(net "PEX2_DFT_IDDT")
	)
	(segment
		(start 282.31592 -307.265832)
		(end 282.824936 -307.774848)
		(width 0.13208)
		(layer "B.Cu")
		(net "PEX2_DFT_IDDT")
	)
	(segment
		(start 262.339074 -306.8193)
		(end 264.231374 -304.927)
		(width 0.13208)
		(layer "B.Cu")
		(net "PEX2_DFT_IDDT")
	)
	(segment
		(start 277.850346 -304.927)
		(end 278.299672 -305.376326)
		(width 0.13208)
		(layer "B.Cu")
		(net "PEX2_DFT_IDDT")
	)
	(segment
		(start 280.456132 -305.678332)
		(end 280.456132 -306.922932)
		(width 0.13208)
		(layer "B.Cu")
		(net "PEX2_DFT_IDDT")
	)
	(segment
		(start 353.868736 -87.764366)
		(end 353.320604 -87.216234)
		(width 0.13208)
		(layer "F.Cu")
		(net "SMB_BIC_I2C9_MUX1_SSD9_SDA")
	)
	(segment
		(start 355.463602 -86.815168)
		(end 354.514404 -87.764366)
		(width 0.13208)
		(layer "F.Cu")
		(net "SMB_BIC_I2C9_MUX1_SSD9_SDA")
	)
	(segment
		(start 356.707948 -86.815168)
		(end 355.463602 -86.815168)
		(width 0.13208)
		(layer "F.Cu")
		(net "SMB_BIC_I2C9_MUX1_SSD9_SDA")
	)
	(segment
		(start 354.514404 -87.764366)
		(end 353.868736 -87.764366)
		(width 0.13208)
		(layer "F.Cu")
		(net "SMB_BIC_I2C9_MUX1_SSD9_SDA")
	)
	(via
		(at 354.514404 -87.764366)
		(size 0.508)
		(drill 0.254)
		(layers "F.Cu" "B.Cu")
		(net "SMB_BIC_I2C9_MUX1_SSD9_SDA")
	)
	(segment
		(start 337.293966 -225.587052)
		(end 336.89417 -225.986848)
		(width 0.13208)
		(layer "F.Cu")
		(net "RST_SSD2_PERST_N")
	)
	(segment
		(start 346.950792 -240.291112)
		(end 346.950792 -238.62665)
		(width 0.13208)
		(layer "F.Cu")
		(net "RST_SSD2_PERST_N")
	)
	(via
		(at 346.950792 -238.62665)
		(size 0.508)
		(drill 0.254)
		(layers "F.Cu" "B.Cu")
		(net "RST_SSD2_PERST_N")
	)
	(via
		(at 336.89417 -225.986848)
		(size 0.4572)
		(drill 0.254)
		(layers "F.Cu" "B.Cu")
		(net "RST_SSD2_PERST_N")
	)
	(segment
		(start 337.063334 -237.052866)
		(end 337.063334 -238.362998)
		(width 0.15494)
		(layer "In7.Cu")
		(net "RST_SSD2_PERST_N")
	)
	(segment
		(start 339.691726 -241.6302)
		(end 346.473018 -241.6302)
		(width 0.15494)
		(layer "In7.Cu")
		(net "RST_SSD2_PERST_N")
	)
	(segment
		(start 337.439 -234.76839)
		(end 337.439 -236.6772)
		(width 0.15494)
		(layer "In7.Cu")
		(net "RST_SSD2_PERST_N")
	)
	(segment
		(start 338.305902 -239.605566)
		(end 338.305902 -240.244376)
		(width 0.15494)
		(layer "In7.Cu")
		(net "RST_SSD2_PERST_N")
	)
	(segment
		(start 337.293966 -227.076)
		(end 337.293966 -227.37191)
		(width 0.15494)
		(layer "In7.Cu")
		(net "RST_SSD2_PERST_N")
	)
	(segment
		(start 337.063334 -238.362998)
		(end 338.305902 -239.605566)
		(width 0.15494)
		(layer "In7.Cu")
		(net "RST_SSD2_PERST_N")
	)
	(segment
		(start 347.472 -239.191292)
		(end 346.950792 -238.670084)
		(width 0.15494)
		(layer "In7.Cu")
		(net "RST_SSD2_PERST_N")
	)
	(segment
		(start 336.89417 -225.986848)
		(end 337.293966 -226.386644)
		(width 0.0889)
		(layer "In7.Cu")
		(net "RST_SSD2_PERST_N")
	)
	(segment
		(start 337.154774 -227.511102)
		(end 337.154774 -229.31628)
		(width 0.15494)
		(layer "In7.Cu")
		(net "RST_SSD2_PERST_N")
	)
	(segment
		(start 337.439 -236.6772)
		(end 337.063334 -237.052866)
		(width 0.15494)
		(layer "In7.Cu")
		(net "RST_SSD2_PERST_N")
	)
	(segment
		(start 336.851498 -234.180888)
		(end 337.439 -234.76839)
		(width 0.15494)
		(layer "In7.Cu")
		(net "RST_SSD2_PERST_N")
	)
	(segment
		(start 346.950792 -238.670084)
		(end 346.950792 -238.62665)
		(width 0.15494)
		(layer "In7.Cu")
		(net "RST_SSD2_PERST_N")
	)
	(segment
		(start 337.293966 -227.37191)
		(end 337.154774 -227.511102)
		(width 0.15494)
		(layer "In7.Cu")
		(net "RST_SSD2_PERST_N")
	)
	(segment
		(start 338.305902 -240.244376)
		(end 339.691726 -241.6302)
		(width 0.15494)
		(layer "In7.Cu")
		(net "RST_SSD2_PERST_N")
	)
	(segment
		(start 346.473018 -241.6302)
		(end 347.472 -240.631218)
		(width 0.15494)
		(layer "In7.Cu")
		(net "RST_SSD2_PERST_N")
	)
	(segment
		(start 337.154774 -229.31628)
		(end 336.851498 -229.619556)
		(width 0.15494)
		(layer "In7.Cu")
		(net "RST_SSD2_PERST_N")
	)
	(segment
		(start 336.851498 -229.619556)
		(end 336.851498 -234.180888)
		(width 0.15494)
		(layer "In7.Cu")
		(net "RST_SSD2_PERST_N")
	)
	(segment
		(start 337.293966 -226.386644)
		(end 337.293966 -227.076)
		(width 0.0889)
		(layer "In7.Cu")
		(net "RST_SSD2_PERST_N")
	)
	(segment
		(start 347.472 -240.631218)
		(end 347.472 -239.191292)
		(width 0.15494)
		(layer "In7.Cu")
		(net "RST_SSD2_PERST_N")
	)
	(segment
		(start 349.293942 -218.387168)
		(end 349.693738 -217.987372)
		(width 0.13208)
		(layer "F.Cu")
		(net "PWRGD_P3V3_NIC7_R")
	)
	(segment
		(start 448.286124 -120.493028)
		(end 449.002912 -119.77624)
		(width 0.13208)
		(layer "F.Cu")
		(net "PWRGD_P3V3_NIC7_R")
	)
	(segment
		(start 448.286124 -120.493028)
		(end 447.675762 -120.493028)
		(width 0.13208)
		(layer "F.Cu")
		(net "PWRGD_P3V3_NIC7_R")
	)
	(segment
		(start 449.002912 -119.77624)
		(end 449.830444 -119.77624)
		(width 0.13208)
		(layer "F.Cu")
		(net "PWRGD_P3V3_NIC7_R")
	)
	(via
		(at 354.087176 -129.79146)
		(size 0.508)
		(drill 0.254)
		(layers "F.Cu" "B.Cu")
		(net "PWRGD_P3V3_NIC7_R")
	)
	(via
		(at 349.693738 -217.987372)
		(size 0.4572)
		(drill 0.254)
		(layers "F.Cu" "B.Cu")
		(net "PWRGD_P3V3_NIC7_R")
	)
	(via
		(at 449.61429 -124.640594)
		(size 0.508)
		(drill 0.254)
		(layers "F.Cu" "B.Cu")
		(net "PWRGD_P3V3_NIC7_R")
	)
	(via
		(at 448.286124 -120.493028)
		(size 0.508)
		(drill 0.254)
		(layers "F.Cu" "B.Cu")
		(net "PWRGD_P3V3_NIC7_R")
	)
	(segment
		(start 450.723 -123.531884)
		(end 449.61429 -124.640594)
		(width 0.13208)
		(layer "B.Cu")
		(net "PWRGD_P3V3_NIC7_R")
	)
	(segment
		(start 450.335396 -120.1928)
		(end 450.723 -120.580404)
		(width 0.13208)
		(layer "B.Cu")
		(net "PWRGD_P3V3_NIC7_R")
	)
	(segment
		(start 450.723 -120.580404)
		(end 450.723 -123.531884)
		(width 0.13208)
		(layer "B.Cu")
		(net "PWRGD_P3V3_NIC7_R")
	)
	(segment
		(start 448.286124 -120.493028)
		(end 448.586352 -120.1928)
		(width 0.13208)
		(layer "B.Cu")
		(net "PWRGD_P3V3_NIC7_R")
	)
	(segment
		(start 448.586352 -120.1928)
		(end 450.335396 -120.1928)
		(width 0.13208)
		(layer "B.Cu")
		(net "PWRGD_P3V3_NIC7_R")
	)
	(segment
		(start 364.11916 -210.46313)
		(end 364.40745 -210.46313)
		(width 0.15494)
		(layer "In5.Cu")
		(net "PWRGD_P3V3_NIC7_R")
	)
	(segment
		(start 357.222298 -215.193118)
		(end 357.222298 -215.014302)
		(width 0.15494)
		(layer "In5.Cu")
		(net "PWRGD_P3V3_NIC7_R")
	)
	(segment
		(start 353.492054 -160.217866)
		(end 352.764344 -159.490156)
		(width 0.15494)
		(layer "In5.Cu")
		(net "PWRGD_P3V3_NIC7_R")
	)
	(segment
		(start 353.1997 -216.938352)
		(end 354.02774 -216.110312)
		(width 0.15494)
		(layer "In5.Cu")
		(net "PWRGD_P3V3_NIC7_R")
	)
	(segment
		(start 363.1819 -212.4837)
		(end 363.347 -212.3186)
		(width 0.15494)
		(layer "In5.Cu")
		(net "PWRGD_P3V3_NIC7_R")
	)
	(segment
		(start 364.40745 -210.46313)
		(end 365.24311 -209.62747)
		(width 0.15494)
		(layer "In5.Cu")
		(net "PWRGD_P3V3_NIC7_R")
	)
	(segment
		(start 363.347 -211.23529)
		(end 364.11916 -210.46313)
		(width 0.15494)
		(layer "In5.Cu")
		(net "PWRGD_P3V3_NIC7_R")
	)
	(segment
		(start 366.554766 -173.714156)
		(end 360.316018 -167.475408)
		(width 0.15494)
		(layer "In5.Cu")
		(net "PWRGD_P3V3_NIC7_R")
	)
	(segment
		(start 353.492054 -161.416238)
		(end 353.492054 -160.217866)
		(width 0.15494)
		(layer "In5.Cu")
		(net "PWRGD_P3V3_NIC7_R")
	)
	(segment
		(start 371.061742 -203.585826)
		(end 371.061742 -192.659508)
		(width 0.15494)
		(layer "In5.Cu")
		(net "PWRGD_P3V3_NIC7_R")
	)
	(segment
		(start 361.1245 -212.4837)
		(end 363.1819 -212.4837)
		(width 0.15494)
		(layer "In5.Cu")
		(net "PWRGD_P3V3_NIC7_R")
	)
	(segment
		(start 359.7402 -213.868)
		(end 361.1245 -212.4837)
		(width 0.15494)
		(layer "In5.Cu")
		(net "PWRGD_P3V3_NIC7_R")
	)
	(segment
		(start 351.737676 -217.50528)
		(end 352.304604 -216.938352)
		(width 0.15494)
		(layer "In5.Cu")
		(net "PWRGD_P3V3_NIC7_R")
	)
	(segment
		(start 354.02774 -216.110312)
		(end 356.305104 -216.110312)
		(width 0.15494)
		(layer "In5.Cu")
		(net "PWRGD_P3V3_NIC7_R")
	)
	(segment
		(start 363.347 -212.3186)
		(end 363.347 -211.23529)
		(width 0.15494)
		(layer "In5.Cu")
		(net "PWRGD_P3V3_NIC7_R")
	)
	(segment
		(start 351.01022 -217.50528)
		(end 351.737676 -217.50528)
		(width 0.15494)
		(layer "In5.Cu")
		(net "PWRGD_P3V3_NIC7_R")
	)
	(segment
		(start 359.551224 -167.475408)
		(end 353.492054 -161.416238)
		(width 0.15494)
		(layer "In5.Cu")
		(net "PWRGD_P3V3_NIC7_R")
	)
	(segment
		(start 356.305104 -216.110312)
		(end 357.222298 -215.193118)
		(width 0.15494)
		(layer "In5.Cu")
		(net "PWRGD_P3V3_NIC7_R")
	)
	(segment
		(start 352.304604 -216.938352)
		(end 353.1997 -216.938352)
		(width 0.15494)
		(layer "In5.Cu")
		(net "PWRGD_P3V3_NIC7_R")
	)
	(segment
		(start 369.382548 -181.222904)
		(end 366.554766 -178.395122)
		(width 0.15494)
		(layer "In5.Cu")
		(net "PWRGD_P3V3_NIC7_R")
	)
	(segment
		(start 349.693738 -217.987372)
		(end 350.08185 -217.59926)
		(width 0.0889)
		(layer "In5.Cu")
		(net "PWRGD_P3V3_NIC7_R")
	)
	(segment
		(start 352.764344 -159.490156)
		(end 352.764344 -131.114292)
		(width 0.15494)
		(layer "In5.Cu")
		(net "PWRGD_P3V3_NIC7_R")
	)
	(segment
		(start 365.24311 -209.404458)
		(end 371.061742 -203.585826)
		(width 0.15494)
		(layer "In5.Cu")
		(net "PWRGD_P3V3_NIC7_R")
	)
	(segment
		(start 369.382548 -190.980314)
		(end 369.382548 -181.222904)
		(width 0.15494)
		(layer "In5.Cu")
		(net "PWRGD_P3V3_NIC7_R")
	)
	(segment
		(start 357.222298 -215.014302)
		(end 358.3686 -213.868)
		(width 0.15494)
		(layer "In5.Cu")
		(net "PWRGD_P3V3_NIC7_R")
	)
	(segment
		(start 371.061742 -192.659508)
		(end 369.382548 -190.980314)
		(width 0.15494)
		(layer "In5.Cu")
		(net "PWRGD_P3V3_NIC7_R")
	)
	(segment
		(start 366.554766 -178.395122)
		(end 366.554766 -173.714156)
		(width 0.15494)
		(layer "In5.Cu")
		(net "PWRGD_P3V3_NIC7_R")
	)
	(segment
		(start 358.3686 -213.868)
		(end 359.7402 -213.868)
		(width 0.15494)
		(layer "In5.Cu")
		(net "PWRGD_P3V3_NIC7_R")
	)
	(segment
		(start 350.91624 -217.59926)
		(end 351.01022 -217.50528)
		(width 0.15494)
		(layer "In5.Cu")
		(net "PWRGD_P3V3_NIC7_R")
	)
	(segment
		(start 350.08185 -217.59926)
		(end 350.91624 -217.59926)
		(width 0.0889)
		(layer "In5.Cu")
		(net "PWRGD_P3V3_NIC7_R")
	)
	(segment
		(start 365.24311 -209.62747)
		(end 365.24311 -209.404458)
		(width 0.15494)
		(layer "In5.Cu")
		(net "PWRGD_P3V3_NIC7_R")
	)
	(segment
		(start 352.764344 -131.114292)
		(end 354.087176 -129.79146)
		(width 0.15494)
		(layer "In5.Cu")
		(net "PWRGD_P3V3_NIC7_R")
	)
	(segment
		(start 360.316018 -167.475408)
		(end 359.551224 -167.475408)
		(width 0.15494)
		(layer "In5.Cu")
		(net "PWRGD_P3V3_NIC7_R")
	)
	(segment
		(start 416.15233 -127.738632)
		(end 400.482308 -127.738632)
		(width 0.15494)
		(layer "In13.Cu")
		(net "PWRGD_P3V3_NIC7_R")
	)
	(segment
		(start 400.482308 -127.738632)
		(end 397.60398 -130.61696)
		(width 0.15494)
		(layer "In13.Cu")
		(net "PWRGD_P3V3_NIC7_R")
	)
	(segment
		(start 421.328088 -128.946656)
		(end 417.360354 -128.946656)
		(width 0.15494)
		(layer "In13.Cu")
		(net "PWRGD_P3V3_NIC7_R")
	)
	(segment
		(start 384.066542 -127.738632)
		(end 383.70637 -128.098804)
		(width 0.15494)
		(layer "In13.Cu")
		(net "PWRGD_P3V3_NIC7_R")
	)
	(segment
		(start 384.585718 -127.738632)
		(end 384.066542 -127.738632)
		(width 0.15494)
		(layer "In13.Cu")
		(net "PWRGD_P3V3_NIC7_R")
	)
	(segment
		(start 367.861342 -129.79146)
		(end 354.087176 -129.79146)
		(width 0.15494)
		(layer "In13.Cu")
		(net "PWRGD_P3V3_NIC7_R")
	)
	(segment
		(start 417.360354 -128.946656)
		(end 416.15233 -127.738632)
		(width 0.15494)
		(layer "In13.Cu")
		(net "PWRGD_P3V3_NIC7_R")
	)
	(segment
		(start 383.70637 -128.098804)
		(end 369.553998 -128.098804)
		(width 0.15494)
		(layer "In13.Cu")
		(net "PWRGD_P3V3_NIC7_R")
	)
	(segment
		(start 369.553998 -128.098804)
		(end 367.861342 -129.79146)
		(width 0.15494)
		(layer "In13.Cu")
		(net "PWRGD_P3V3_NIC7_R")
	)
	(segment
		(start 397.60398 -130.61696)
		(end 387.464046 -130.61696)
		(width 0.15494)
		(layer "In13.Cu")
		(net "PWRGD_P3V3_NIC7_R")
	)
	(segment
		(start 446.120012 -128.134872)
		(end 422.139872 -128.134872)
		(width 0.15494)
		(layer "In13.Cu")
		(net "PWRGD_P3V3_NIC7_R")
	)
	(segment
		(start 422.139872 -128.134872)
		(end 421.328088 -128.946656)
		(width 0.15494)
		(layer "In13.Cu")
		(net "PWRGD_P3V3_NIC7_R")
	)
	(segment
		(start 449.61429 -124.640594)
		(end 446.120012 -128.134872)
		(width 0.15494)
		(layer "In13.Cu")
		(net "PWRGD_P3V3_NIC7_R")
	)
	(segment
		(start 387.464046 -130.61696)
		(end 384.585718 -127.738632)
		(width 0.15494)
		(layer "In13.Cu")
		(net "PWRGD_P3V3_NIC7_R")
	)
	(segment
		(start 420.299896 -291.149786)
		(end 419.824916 -290.674806)
		(width 0.13208)
		(layer "F.Cu")
		(net "UART_PEX3_CLI_BUF_RX")
	)
	(via
		(at 422.199816 -282.599892)
		(size 0.6604)
		(drill 0.3302)
		(layers "F.Cu" "B.Cu")
		(net "UART_PEX3_CLI_BUF_RX")
	)
	(via
		(at 419.824916 -290.674806)
		(size 0.4064)
		(drill 0.2032)
		(layers "F.Cu" "B.Cu")
		(net "UART_PEX3_CLI_BUF_RX")
	)
	(via
		(at 419.847776 -252.424184)
		(size 0.508)
		(drill 0.254)
		(layers "F.Cu" "B.Cu")
		(net "UART_PEX3_CLI_BUF_RX")
	)
	(via
		(at 273.5072 -257.2766)
		(size 0.508)
		(drill 0.254)
		(layers "F.Cu" "B.Cu")
		(net "UART_PEX3_CLI_BUF_RX")
	)
	(via
		(at 139.36091 -216.001346)
		(size 0.508)
		(drill 0.254)
		(layers "F.Cu" "B.Cu")
		(net "UART_PEX3_CLI_BUF_RX")
	)
	(via
		(at 265.701272 -201.356468)
		(size 0.508)
		(drill 0.254)
		(layers "F.Cu" "B.Cu")
		(net "UART_PEX3_CLI_BUF_RX")
	)
	(segment
		(start 422.720262 -282.079446)
		(end 422.199816 -282.599892)
		(width 0.13208)
		(layer "B.Cu")
		(net "UART_PEX3_CLI_BUF_RX")
	)
	(segment
		(start 420.248842 -290.25088)
		(end 419.824916 -290.674806)
		(width 0.13208)
		(layer "B.Cu")
		(net "UART_PEX3_CLI_BUF_RX")
	)
	(segment
		(start 420.42588 -288.359088)
		(end 420.248842 -288.536126)
		(width 0.13208)
		(layer "B.Cu")
		(net "UART_PEX3_CLI_BUF_RX")
	)
	(segment
		(start 421.75938 -287.891474)
		(end 421.291766 -288.359088)
		(width 0.13208)
		(layer "B.Cu")
		(net "UART_PEX3_CLI_BUF_RX")
	)
	(segment
		(start 422.23182 -287.891474)
		(end 421.75938 -287.891474)
		(width 0.13208)
		(layer "B.Cu")
		(net "UART_PEX3_CLI_BUF_RX")
	)
	(segment
		(start 139.36091 -215.364822)
		(end 139.36091 -216.001346)
		(width 0.13208)
		(layer "B.Cu")
		(net "UART_PEX3_CLI_BUF_RX")
	)
	(segment
		(start 422.199816 -282.599892)
		(end 422.6052 -283.005276)
		(width 0.13208)
		(layer "B.Cu")
		(net "UART_PEX3_CLI_BUF_RX")
	)
	(segment
		(start 419.847776 -252.424184)
		(end 422.720262 -255.29667)
		(width 0.13208)
		(layer "B.Cu")
		(net "UART_PEX3_CLI_BUF_RX")
	)
	(segment
		(start 422.6052 -283.005276)
		(end 422.6052 -287.518094)
		(width 0.13208)
		(layer "B.Cu")
		(net "UART_PEX3_CLI_BUF_RX")
	)
	(segment
		(start 140.37691 -215.364822)
		(end 139.36091 -215.364822)
		(width 0.13208)
		(layer "B.Cu")
		(net "UART_PEX3_CLI_BUF_RX")
	)
	(segment
		(start 420.248842 -288.536126)
		(end 420.248842 -290.25088)
		(width 0.13208)
		(layer "B.Cu")
		(net "UART_PEX3_CLI_BUF_RX")
	)
	(segment
		(start 422.6052 -287.518094)
		(end 422.23182 -287.891474)
		(width 0.13208)
		(layer "B.Cu")
		(net "UART_PEX3_CLI_BUF_RX")
	)
	(segment
		(start 421.291766 -288.359088)
		(end 420.42588 -288.359088)
		(width 0.13208)
		(layer "B.Cu")
		(net "UART_PEX3_CLI_BUF_RX")
	)
	(segment
		(start 422.720262 -255.29667)
		(end 422.720262 -282.079446)
		(width 0.13208)
		(layer "B.Cu")
		(net "UART_PEX3_CLI_BUF_RX")
	)
	(segment
		(start 274.073874 -256.10947)
		(end 273.5072 -256.676144)
		(width 0.15494)
		(layer "In5.Cu")
		(net "UART_PEX3_CLI_BUF_RX")
	)
	(segment
		(start 270.381222 -205.362302)
		(end 270.381222 -245.077234)
		(width 0.15494)
		(layer "In5.Cu")
		(net "UART_PEX3_CLI_BUF_RX")
	)
	(segment
		(start 266.375388 -201.356468)
		(end 270.381222 -205.362302)
		(width 0.15494)
		(layer "In5.Cu")
		(net "UART_PEX3_CLI_BUF_RX")
	)
	(segment
		(start 273.5072 -256.676144)
		(end 273.5072 -257.2766)
		(width 0.15494)
		(layer "In5.Cu")
		(net "UART_PEX3_CLI_BUF_RX")
	)
	(segment
		(start 274.073874 -248.769886)
		(end 274.073874 -256.10947)
		(width 0.15494)
		(layer "In5.Cu")
		(net "UART_PEX3_CLI_BUF_RX")
	)
	(segment
		(start 265.701272 -201.356468)
		(end 266.375388 -201.356468)
		(width 0.15494)
		(layer "In5.Cu")
		(net "UART_PEX3_CLI_BUF_RX")
	)
	(segment
		(start 270.381222 -245.077234)
		(end 274.073874 -248.769886)
		(width 0.15494)
		(layer "In5.Cu")
		(net "UART_PEX3_CLI_BUF_RX")
	)
	(segment
		(start 371.395752 -244.431058)
		(end 371.736112 -244.771418)
		(width 0.15494)
		(layer "In15.Cu")
		(net "UART_PEX3_CLI_BUF_RX")
	)
	(segment
		(start 217.400886 -205.639416)
		(end 217.400886 -205.124304)
		(width 0.15494)
		(layer "In15.Cu")
		(net "UART_PEX3_CLI_BUF_RX")
	)
	(segment
		(start 249.68327 -201.67727)
		(end 249.174 -201.168)
		(width 0.15494)
		(layer "In15.Cu")
		(net "UART_PEX3_CLI_BUF_RX")
	)
	(segment
		(start 242.443 -205.5114)
		(end 242.202716 -205.751684)
		(width 0.15494)
		(layer "In15.Cu")
		(net "UART_PEX3_CLI_BUF_RX")
	)
	(segment
		(start 371.736112 -246.863616)
		(end 373.20347 -248.330974)
		(width 0.15494)
		(layer "In15.Cu")
		(net "UART_PEX3_CLI_BUF_RX")
	)
	(segment
		(start 244.8052 -200.4314)
		(end 242.443 -202.7936)
		(width 0.15494)
		(layer "In15.Cu")
		(net "UART_PEX3_CLI_BUF_RX")
	)
	(segment
		(start 228.577648 -206.248)
		(end 218.00947 -206.248)
		(width 0.15494)
		(layer "In15.Cu")
		(net "UART_PEX3_CLI_BUF_RX")
	)
	(segment
		(start 212.417406 -206.25816)
		(end 205.76286 -206.25816)
		(width 0.15494)
		(layer "In15.Cu")
		(net "UART_PEX3_CLI_BUF_RX")
	)
	(segment
		(start 265.701272 -201.356468)
		(end 264.649204 -200.3044)
		(width 0.15494)
		(layer "In15.Cu")
		(net "UART_PEX3_CLI_BUF_RX")
	)
	(segment
		(start 233.849418 -206.545434)
		(end 233.319066 -207.075786)
		(width 0.15494)
		(layer "In15.Cu")
		(net "UART_PEX3_CLI_BUF_RX")
	)
	(segment
		(start 264.649204 -200.3044)
		(end 256.779776 -200.3044)
		(width 0.15494)
		(layer "In15.Cu")
		(net "UART_PEX3_CLI_BUF_RX")
	)
	(segment
		(start 256.779776 -200.3044)
		(end 256.373376 -200.7108)
		(width 0.15494)
		(layer "In15.Cu")
		(net "UART_PEX3_CLI_BUF_RX")
	)
	(segment
		(start 385.153916 -248.330974)
		(end 386.733542 -246.751348)
		(width 0.15494)
		(layer "In15.Cu")
		(net "UART_PEX3_CLI_BUF_RX")
	)
	(segment
		(start 419.483286 -251.4092)
		(end 419.483286 -252.059694)
		(width 0.15494)
		(layer "In15.Cu")
		(net "UART_PEX3_CLI_BUF_RX")
	)
	(segment
		(start 369.380008 -244.431058)
		(end 371.395752 -244.431058)
		(width 0.15494)
		(layer "In15.Cu")
		(net "UART_PEX3_CLI_BUF_RX")
	)
	(segment
		(start 305.827684 -259.06857)
		(end 315.277246 -259.06857)
		(width 0.15494)
		(layer "In15.Cu")
		(net "UART_PEX3_CLI_BUF_RX")
	)
	(segment
		(start 350.137222 -245.922038)
		(end 363.778546 -245.922038)
		(width 0.15494)
		(layer "In15.Cu")
		(net "UART_PEX3_CLI_BUF_RX")
	)
	(segment
		(start 371.736112 -244.771418)
		(end 371.736112 -246.863616)
		(width 0.15494)
		(layer "In15.Cu")
		(net "UART_PEX3_CLI_BUF_RX")
	)
	(segment
		(start 247.650254 -201.168)
		(end 246.913654 -200.4314)
		(width 0.15494)
		(layer "In15.Cu")
		(net "UART_PEX3_CLI_BUF_RX")
	)
	(segment
		(start 242.443 -202.7936)
		(end 242.443 -205.5114)
		(width 0.15494)
		(layer "In15.Cu")
		(net "UART_PEX3_CLI_BUF_RX")
	)
	(segment
		(start 194.126612 -217.894408)
		(end 185.37682 -217.894408)
		(width 0.15494)
		(layer "In15.Cu")
		(net "UART_PEX3_CLI_BUF_RX")
	)
	(segment
		(start 246.913654 -200.4314)
		(end 244.8052 -200.4314)
		(width 0.15494)
		(layer "In15.Cu")
		(net "UART_PEX3_CLI_BUF_RX")
	)
	(segment
		(start 217.400886 -205.124304)
		(end 217.01125 -204.734668)
		(width 0.15494)
		(layer "In15.Cu")
		(net "UART_PEX3_CLI_BUF_RX")
	)
	(segment
		(start 242.202716 -205.751684)
		(end 241.48288 -205.751684)
		(width 0.15494)
		(layer "In15.Cu")
		(net "UART_PEX3_CLI_BUF_RX")
	)
	(segment
		(start 218.00947 -206.248)
		(end 217.400886 -205.639416)
		(width 0.15494)
		(layer "In15.Cu")
		(net "UART_PEX3_CLI_BUF_RX")
	)
	(segment
		(start 273.5072 -257.2766)
		(end 275.7424 -259.5118)
		(width 0.15494)
		(layer "In15.Cu")
		(net "UART_PEX3_CLI_BUF_RX")
	)
	(segment
		(start 256.373376 -201.61377)
		(end 255.904746 -202.0824)
		(width 0.15494)
		(layer "In15.Cu")
		(net "UART_PEX3_CLI_BUF_RX")
	)
	(segment
		(start 387.306566 -245.32717)
		(end 388.72033 -245.32717)
		(width 0.15494)
		(layer "In15.Cu")
		(net "UART_PEX3_CLI_BUF_RX")
	)
	(segment
		(start 240.68913 -206.545434)
		(end 233.849418 -206.545434)
		(width 0.15494)
		(layer "In15.Cu")
		(net "UART_PEX3_CLI_BUF_RX")
	)
	(segment
		(start 185.37682 -217.894408)
		(end 181.788562 -214.30615)
		(width 0.15494)
		(layer "In15.Cu")
		(net "UART_PEX3_CLI_BUF_RX")
	)
	(segment
		(start 213.940898 -204.734668)
		(end 212.417406 -206.25816)
		(width 0.15494)
		(layer "In15.Cu")
		(net "UART_PEX3_CLI_BUF_RX")
	)
	(segment
		(start 144.20088 -213.989666)
		(end 139.927838 -213.989666)
		(width 0.15494)
		(layer "In15.Cu")
		(net "UART_PEX3_CLI_BUF_RX")
	)
	(segment
		(start 144.718532 -213.472014)
		(end 144.20088 -213.989666)
		(width 0.15494)
		(layer "In15.Cu")
		(net "UART_PEX3_CLI_BUF_RX")
	)
	(segment
		(start 419.483286 -252.059694)
		(end 419.847776 -252.424184)
		(width 0.15494)
		(layer "In15.Cu")
		(net "UART_PEX3_CLI_BUF_RX")
	)
	(segment
		(start 330.301092 -259.1308)
		(end 330.681838 -258.750054)
		(width 0.15494)
		(layer "In15.Cu")
		(net "UART_PEX3_CLI_BUF_RX")
	)
	(segment
		(start 386.733542 -246.751348)
		(end 386.733542 -245.900194)
		(width 0.15494)
		(layer "In15.Cu")
		(net "UART_PEX3_CLI_BUF_RX")
	)
	(segment
		(start 373.20347 -248.330974)
		(end 385.153916 -248.330974)
		(width 0.15494)
		(layer "In15.Cu")
		(net "UART_PEX3_CLI_BUF_RX")
	)
	(segment
		(start 139.36091 -214.556594)
		(end 139.36091 -216.001346)
		(width 0.15494)
		(layer "In15.Cu")
		(net "UART_PEX3_CLI_BUF_RX")
	)
	(segment
		(start 388.72033 -245.32717)
		(end 391.396982 -248.003822)
		(width 0.15494)
		(layer "In15.Cu")
		(net "UART_PEX3_CLI_BUF_RX")
	)
	(segment
		(start 419.950392 -250.942094)
		(end 419.483286 -251.4092)
		(width 0.15494)
		(layer "In15.Cu")
		(net "UART_PEX3_CLI_BUF_RX")
	)
	(segment
		(start 315.277246 -259.06857)
		(end 315.339476 -259.1308)
		(width 0.15494)
		(layer "In15.Cu")
		(net "UART_PEX3_CLI_BUF_RX")
	)
	(segment
		(start 363.778546 -245.922038)
		(end 364.070138 -245.630446)
		(width 0.15494)
		(layer "In15.Cu")
		(net "UART_PEX3_CLI_BUF_RX")
	)
	(segment
		(start 386.733542 -245.900194)
		(end 387.306566 -245.32717)
		(width 0.15494)
		(layer "In15.Cu")
		(net "UART_PEX3_CLI_BUF_RX")
	)
	(segment
		(start 419.950392 -249.10415)
		(end 419.950392 -250.942094)
		(width 0.15494)
		(layer "In15.Cu")
		(net "UART_PEX3_CLI_BUF_RX")
	)
	(segment
		(start 205.76286 -206.25816)
		(end 194.126612 -217.894408)
		(width 0.15494)
		(layer "In15.Cu")
		(net "UART_PEX3_CLI_BUF_RX")
	)
	(segment
		(start 146.36623 -214.30615)
		(end 145.532094 -213.472014)
		(width 0.15494)
		(layer "In15.Cu")
		(net "UART_PEX3_CLI_BUF_RX")
	)
	(segment
		(start 241.48288 -205.751684)
		(end 240.68913 -206.545434)
		(width 0.15494)
		(layer "In15.Cu")
		(net "UART_PEX3_CLI_BUF_RX")
	)
	(segment
		(start 255.904746 -202.0824)
		(end 254.530098 -202.0824)
		(width 0.15494)
		(layer "In15.Cu")
		(net "UART_PEX3_CLI_BUF_RX")
	)
	(segment
		(start 418.850064 -248.003822)
		(end 419.950392 -249.10415)
		(width 0.15494)
		(layer "In15.Cu")
		(net "UART_PEX3_CLI_BUF_RX")
	)
	(segment
		(start 391.396982 -248.003822)
		(end 418.850064 -248.003822)
		(width 0.15494)
		(layer "In15.Cu")
		(net "UART_PEX3_CLI_BUF_RX")
	)
	(segment
		(start 249.174 -201.168)
		(end 247.650254 -201.168)
		(width 0.15494)
		(layer "In15.Cu")
		(net "UART_PEX3_CLI_BUF_RX")
	)
	(segment
		(start 256.373376 -200.7108)
		(end 256.373376 -201.61377)
		(width 0.15494)
		(layer "In15.Cu")
		(net "UART_PEX3_CLI_BUF_RX")
	)
	(segment
		(start 254.124968 -201.67727)
		(end 249.68327 -201.67727)
		(width 0.15494)
		(layer "In15.Cu")
		(net "UART_PEX3_CLI_BUF_RX")
	)
	(segment
		(start 305.384454 -259.5118)
		(end 305.827684 -259.06857)
		(width 0.15494)
		(layer "In15.Cu")
		(net "UART_PEX3_CLI_BUF_RX")
	)
	(segment
		(start 233.319066 -207.075786)
		(end 229.405434 -207.075786)
		(width 0.15494)
		(layer "In15.Cu")
		(net "UART_PEX3_CLI_BUF_RX")
	)
	(segment
		(start 368.18062 -245.630446)
		(end 369.380008 -244.431058)
		(width 0.15494)
		(layer "In15.Cu")
		(net "UART_PEX3_CLI_BUF_RX")
	)
	(segment
		(start 254.530098 -202.0824)
		(end 254.124968 -201.67727)
		(width 0.15494)
		(layer "In15.Cu")
		(net "UART_PEX3_CLI_BUF_RX")
	)
	(segment
		(start 337.309206 -258.750054)
		(end 350.137222 -245.922038)
		(width 0.15494)
		(layer "In15.Cu")
		(net "UART_PEX3_CLI_BUF_RX")
	)
	(segment
		(start 145.532094 -213.472014)
		(end 144.718532 -213.472014)
		(width 0.15494)
		(layer "In15.Cu")
		(net "UART_PEX3_CLI_BUF_RX")
	)
	(segment
		(start 181.788562 -214.30615)
		(end 146.36623 -214.30615)
		(width 0.15494)
		(layer "In15.Cu")
		(net "UART_PEX3_CLI_BUF_RX")
	)
	(segment
		(start 315.339476 -259.1308)
		(end 330.301092 -259.1308)
		(width 0.15494)
		(layer "In15.Cu")
		(net "UART_PEX3_CLI_BUF_RX")
	)
	(segment
		(start 139.927838 -213.989666)
		(end 139.36091 -214.556594)
		(width 0.15494)
		(layer "In15.Cu")
		(net "UART_PEX3_CLI_BUF_RX")
	)
	(segment
		(start 229.405434 -207.075786)
		(end 228.577648 -206.248)
		(width 0.15494)
		(layer "In15.Cu")
		(net "UART_PEX3_CLI_BUF_RX")
	)
	(segment
		(start 330.681838 -258.750054)
		(end 337.309206 -258.750054)
		(width 0.15494)
		(layer "In15.Cu")
		(net "UART_PEX3_CLI_BUF_RX")
	)
	(segment
		(start 275.7424 -259.5118)
		(end 305.384454 -259.5118)
		(width 0.15494)
		(layer "In15.Cu")
		(net "UART_PEX3_CLI_BUF_RX")
	)
	(segment
		(start 217.01125 -204.734668)
		(end 213.940898 -204.734668)
		(width 0.15494)
		(layer "In15.Cu")
		(net "UART_PEX3_CLI_BUF_RX")
	)
	(segment
		(start 364.070138 -245.630446)
		(end 368.18062 -245.630446)
		(width 0.15494)
		(layer "In15.Cu")
		(net "UART_PEX3_CLI_BUF_RX")
	)
	(segment
		(start 323.233542 -304.436526)
		(end 323.233542 -305.056794)
		(width 0.13208)
		(layer "F.Cu")
		(net "PEX2_SPARE1")
	)
	(segment
		(start 296.599864 -309.199788)
		(end 297.074844 -308.724808)
		(width 0.13208)
		(layer "F.Cu")
		(net "PEX2_SPARE1")
	)
	(segment
		(start 323.23405 -305.073558)
		(end 323.23405 -305.674522)
		(width 0.13208)
		(layer "F.Cu")
		(net "PEX2_SPARE1")
	)
	(segment
		(start 323.225414 -305.064922)
		(end 323.23405 -305.073558)
		(width 0.13208)
		(layer "F.Cu")
		(net "PEX2_SPARE1")
	)
	(segment
		(start 323.233542 -305.056794)
		(end 323.225414 -305.064922)
		(width 0.13208)
		(layer "F.Cu")
		(net "PEX2_SPARE1")
	)
	(via
		(at 317.264288 -311.026048)
		(size 0.6604)
		(drill 0.3302)
		(layers "F.Cu" "B.Cu")
		(net "PEX2_SPARE1")
	)
	(via
		(at 323.225414 -305.064922)
		(size 0.508)
		(drill 0.254)
		(layers "F.Cu" "B.Cu")
		(net "PEX2_SPARE1")
	)
	(via
		(at 297.074844 -308.724808)
		(size 0.4064)
		(drill 0.2032)
		(layers "F.Cu" "B.Cu")
		(net "PEX2_SPARE1")
	)
	(segment
		(start 297.074844 -308.724808)
		(end 297.960542 -309.610506)
		(width 0.13208)
		(layer "B.Cu")
		(net "PEX2_SPARE1")
	)
	(segment
		(start 316.7507 -311.539636)
		(end 317.264288 -311.026048)
		(width 0.13208)
		(layer "B.Cu")
		(net "PEX2_SPARE1")
	)
	(segment
		(start 298.214542 -311.539636)
		(end 316.7507 -311.539636)
		(width 0.13208)
		(layer "B.Cu")
		(net "PEX2_SPARE1")
	)
	(segment
		(start 317.264288 -311.026048)
		(end 323.225414 -305.064922)
		(width 0.13208)
		(layer "B.Cu")
		(net "PEX2_SPARE1")
	)
	(segment
		(start 297.960542 -309.610506)
		(end 297.960542 -311.285636)
		(width 0.13208)
		(layer "B.Cu")
		(net "PEX2_SPARE1")
	)
	(segment
		(start 297.960542 -311.285636)
		(end 298.214542 -311.539636)
		(width 0.13208)
		(layer "B.Cu")
		(net "PEX2_SPARE1")
	)
	(segment
		(start 353.320604 -82.644234)
		(end 354.43414 -82.644234)
		(width 0.13208)
		(layer "F.Cu")
		(net "SMB_BIC_I2C9_MUX1_SSD11_SDA")
	)
	(segment
		(start 355.572568 -84.21497)
		(end 356.707948 -84.21497)
		(width 0.13208)
		(layer "F.Cu")
		(net "SMB_BIC_I2C9_MUX1_SSD11_SDA")
	)
	(segment
		(start 354.474272 -82.684366)
		(end 355.09327 -83.303364)
		(width 0.13208)
		(layer "F.Cu")
		(net "SMB_BIC_I2C9_MUX1_SSD11_SDA")
	)
	(segment
		(start 355.09327 -83.735672)
		(end 355.572568 -84.21497)
		(width 0.13208)
		(layer "F.Cu")
		(net "SMB_BIC_I2C9_MUX1_SSD11_SDA")
	)
	(segment
		(start 354.43414 -82.644234)
		(end 354.474272 -82.684366)
		(width 0.13208)
		(layer "F.Cu")
		(net "SMB_BIC_I2C9_MUX1_SSD11_SDA")
	)
	(segment
		(start 355.09327 -83.303364)
		(end 355.09327 -83.735672)
		(width 0.13208)
		(layer "F.Cu")
		(net "SMB_BIC_I2C9_MUX1_SSD11_SDA")
	)
	(via
		(at 354.474272 -82.684366)
		(size 0.508)
		(drill 0.254)
		(layers "F.Cu" "B.Cu")
		(net "SMB_BIC_I2C9_MUX1_SSD11_SDA")
	)
	(segment
		(start 195.736464 -61.487812)
		(end 195.104512 -62.119764)
		(width 0.13208)
		(layer "F.Cu")
		(net "PWRGD_P12V_SSD7_R")
	)
	(segment
		(start 345.29395 -223.987106)
		(end 345.693746 -224.386902)
		(width 0.13208)
		(layer "F.Cu")
		(net "PWRGD_P12V_SSD7_R")
	)
	(segment
		(start 195.9737 -65.75552)
		(end 208.82864 -65.75552)
		(width 0.13208)
		(layer "F.Cu")
		(net "PWRGD_P12V_SSD7_R")
	)
	(segment
		(start 221.42323 -53.051456)
		(end 220.76791 -53.051456)
		(width 0.13208)
		(layer "F.Cu")
		(net "PWRGD_P12V_SSD7_R")
	)
	(segment
		(start 195.104512 -62.119764)
		(end 195.104512 -64.886332)
		(width 0.13208)
		(layer "F.Cu")
		(net "PWRGD_P12V_SSD7_R")
	)
	(segment
		(start 195.104512 -64.886332)
		(end 195.9737 -65.75552)
		(width 0.13208)
		(layer "F.Cu")
		(net "PWRGD_P12V_SSD7_R")
	)
	(segment
		(start 197.583552 -61.487812)
		(end 195.736464 -61.487812)
		(width 0.13208)
		(layer "F.Cu")
		(net "PWRGD_P12V_SSD7_R")
	)
	(via
		(at 221.42323 -53.051456)
		(size 0.508)
		(drill 0.254)
		(layers "F.Cu" "B.Cu")
		(net "PWRGD_P12V_SSD7_R")
	)
	(via
		(at 345.693746 -224.386902)
		(size 0.4572)
		(drill 0.254)
		(layers "F.Cu" "B.Cu")
		(net "PWRGD_P12V_SSD7_R")
	)
	(via
		(at 221.706948 -169.382186)
		(size 0.508)
		(drill 0.254)
		(layers "F.Cu" "B.Cu")
		(net "PWRGD_P12V_SSD7_R")
	)
	(via
		(at 208.82864 -65.75552)
		(size 0.508)
		(drill 0.254)
		(layers "F.Cu" "B.Cu")
		(net "PWRGD_P12V_SSD7_R")
	)
	(segment
		(start 220.979492 -64.897254)
		(end 220.40469 -65.472056)
		(width 0.15494)
		(layer "In5.Cu")
		(net "PWRGD_P12V_SSD7_R")
	)
	(segment
		(start 211.9376 -138.93673)
		(end 211.9376 -161.347912)
		(width 0.15494)
		(layer "In5.Cu")
		(net "PWRGD_P12V_SSD7_R")
	)
	(segment
		(start 219.971874 -169.382186)
		(end 221.706948 -169.382186)
		(width 0.15494)
		(layer "In5.Cu")
		(net "PWRGD_P12V_SSD7_R")
	)
	(segment
		(start 221.529656 -57.426606)
		(end 221.529656 -62.75197)
		(width 0.15494)
		(layer "In5.Cu")
		(net "PWRGD_P12V_SSD7_R")
	)
	(segment
		(start 219.46743 -64.617092)
		(end 219.843858 -64.240664)
		(width 0.15494)
		(layer "In5.Cu")
		(net "PWRGD_P12V_SSD7_R")
	)
	(segment
		(start 214.8332 -94.494858)
		(end 214.8332 -100.592636)
		(width 0.15494)
		(layer "In5.Cu")
		(net "PWRGD_P12V_SSD7_R")
	)
	(segment
		(start 221.71152 -55.705248)
		(end 221.1451 -55.705248)
		(width 0.15494)
		(layer "In5.Cu")
		(net "PWRGD_P12V_SSD7_R")
	)
	(segment
		(start 212.997542 -107.511088)
		(end 219.7862 -114.299746)
		(width 0.15494)
		(layer "In5.Cu")
		(net "PWRGD_P12V_SSD7_R")
	)
	(segment
		(start 220.40469 -75.530964)
		(end 218.04757 -77.888084)
		(width 0.15494)
		(layer "In5.Cu")
		(net "PWRGD_P12V_SSD7_R")
	)
	(segment
		(start 221.42323 -53.051456)
		(end 221.975172 -53.603398)
		(width 0.15494)
		(layer "In5.Cu")
		(net "PWRGD_P12V_SSD7_R")
	)
	(segment
		(start 219.843858 -57.983628)
		(end 219.361258 -57.501028)
		(width 0.15494)
		(layer "In5.Cu")
		(net "PWRGD_P12V_SSD7_R")
	)
	(segment
		(start 214.8332 -100.592636)
		(end 212.997542 -105.024174)
		(width 0.15494)
		(layer "In5.Cu")
		(net "PWRGD_P12V_SSD7_R")
	)
	(segment
		(start 212.29828 -65.75552)
		(end 213.436708 -64.617092)
		(width 0.15494)
		(layer "In5.Cu")
		(net "PWRGD_P12V_SSD7_R")
	)
	(segment
		(start 212.997542 -105.024174)
		(end 212.997542 -107.511088)
		(width 0.15494)
		(layer "In5.Cu")
		(net "PWRGD_P12V_SSD7_R")
	)
	(segment
		(start 221.1451 -55.705248)
		(end 220.838522 -56.011826)
		(width 0.15494)
		(layer "In5.Cu")
		(net "PWRGD_P12V_SSD7_R")
	)
	(segment
		(start 220.838522 -56.735472)
		(end 221.529656 -57.426606)
		(width 0.15494)
		(layer "In5.Cu")
		(net "PWRGD_P12V_SSD7_R")
	)
	(segment
		(start 220.838522 -56.011826)
		(end 220.838522 -56.735472)
		(width 0.15494)
		(layer "In5.Cu")
		(net "PWRGD_P12V_SSD7_R")
	)
	(segment
		(start 218.04757 -91.280488)
		(end 214.8332 -94.494858)
		(width 0.15494)
		(layer "In5.Cu")
		(net "PWRGD_P12V_SSD7_R")
	)
	(segment
		(start 219.7862 -131.08813)
		(end 211.9376 -138.93673)
		(width 0.15494)
		(layer "In5.Cu")
		(net "PWRGD_P12V_SSD7_R")
	)
	(segment
		(start 219.361258 -57.501028)
		(end 219.361258 -55.113428)
		(width 0.15494)
		(layer "In5.Cu")
		(net "PWRGD_P12V_SSD7_R")
	)
	(segment
		(start 221.975172 -53.603398)
		(end 221.975172 -55.441596)
		(width 0.15494)
		(layer "In5.Cu")
		(net "PWRGD_P12V_SSD7_R")
	)
	(segment
		(start 219.843858 -64.240664)
		(end 219.843858 -57.983628)
		(width 0.15494)
		(layer "In5.Cu")
		(net "PWRGD_P12V_SSD7_R")
	)
	(segment
		(start 211.9376 -161.347912)
		(end 219.971874 -169.382186)
		(width 0.15494)
		(layer "In5.Cu")
		(net "PWRGD_P12V_SSD7_R")
	)
	(segment
		(start 208.82864 -65.75552)
		(end 212.29828 -65.75552)
		(width 0.15494)
		(layer "In5.Cu")
		(net "PWRGD_P12V_SSD7_R")
	)
	(segment
		(start 220.40469 -65.472056)
		(end 220.40469 -75.530964)
		(width 0.15494)
		(layer "In5.Cu")
		(net "PWRGD_P12V_SSD7_R")
	)
	(segment
		(start 219.361258 -55.113428)
		(end 221.42323 -53.051456)
		(width 0.15494)
		(layer "In5.Cu")
		(net "PWRGD_P12V_SSD7_R")
	)
	(segment
		(start 221.975172 -55.441596)
		(end 221.71152 -55.705248)
		(width 0.15494)
		(layer "In5.Cu")
		(net "PWRGD_P12V_SSD7_R")
	)
	(segment
		(start 220.979492 -63.302134)
		(end 220.979492 -64.897254)
		(width 0.15494)
		(layer "In5.Cu")
		(net "PWRGD_P12V_SSD7_R")
	)
	(segment
		(start 219.7862 -114.299746)
		(end 219.7862 -131.08813)
		(width 0.15494)
		(layer "In5.Cu")
		(net "PWRGD_P12V_SSD7_R")
	)
	(segment
		(start 213.436708 -64.617092)
		(end 219.46743 -64.617092)
		(width 0.15494)
		(layer "In5.Cu")
		(net "PWRGD_P12V_SSD7_R")
	)
	(segment
		(start 221.529656 -62.75197)
		(end 220.979492 -63.302134)
		(width 0.15494)
		(layer "In5.Cu")
		(net "PWRGD_P12V_SSD7_R")
	)
	(segment
		(start 218.04757 -77.888084)
		(end 218.04757 -91.280488)
		(width 0.15494)
		(layer "In5.Cu")
		(net "PWRGD_P12V_SSD7_R")
	)
	(segment
		(start 375.332752 -228.108256)
		(end 375.332752 -217.038682)
		(width 0.15494)
		(layer "In15.Cu")
		(net "PWRGD_P12V_SSD7_R")
	)
	(segment
		(start 347.161612 -224.784666)
		(end 348.2213 -224.784666)
		(width 0.0889)
		(layer "In15.Cu")
		(net "PWRGD_P12V_SSD7_R")
	)
	(segment
		(start 376.31878 -192.91173)
		(end 376.31878 -190.391542)
		(width 0.15494)
		(layer "In15.Cu")
		(net "PWRGD_P12V_SSD7_R")
	)
	(segment
		(start 371.389656 -183.069738)
		(end 371.389656 -178.139598)
		(width 0.15494)
		(layer "In15.Cu")
		(net "PWRGD_P12V_SSD7_R")
	)
	(segment
		(start 332.932532 -168.439592)
		(end 287.236662 -168.439592)
		(width 0.15494)
		(layer "In15.Cu")
		(net "PWRGD_P12V_SSD7_R")
	)
	(segment
		(start 376.31878 -190.391542)
		(end 374.70461 -188.777372)
		(width 0.15494)
		(layer "In15.Cu")
		(net "PWRGD_P12V_SSD7_R")
	)
	(segment
		(start 357.75138 -171.77385)
		(end 356.94366 -170.96613)
		(width 0.15494)
		(layer "In15.Cu")
		(net "PWRGD_P12V_SSD7_R")
	)
	(segment
		(start 348.333314 -172.06087)
		(end 344.957146 -168.684702)
		(width 0.15494)
		(layer "In15.Cu")
		(net "PWRGD_P12V_SSD7_R")
	)
	(segment
		(start 353.236276 -230.528876)
		(end 356.722934 -234.015534)
		(width 0.15494)
		(layer "In15.Cu")
		(net "PWRGD_P12V_SSD7_R")
	)
	(segment
		(start 285.295594 -170.38066)
		(end 257.215132 -170.38066)
		(width 0.15494)
		(layer "In15.Cu")
		(net "PWRGD_P12V_SSD7_R")
	)
	(segment
		(start 346.894912 -224.517966)
		(end 347.161612 -224.784666)
		(width 0.0889)
		(layer "In15.Cu")
		(net "PWRGD_P12V_SSD7_R")
	)
	(segment
		(start 374.70461 -186.384692)
		(end 371.389656 -183.069738)
		(width 0.15494)
		(layer "In15.Cu")
		(net "PWRGD_P12V_SSD7_R")
	)
	(segment
		(start 369.425474 -234.015534)
		(end 375.332752 -228.108256)
		(width 0.15494)
		(layer "In15.Cu")
		(net "PWRGD_P12V_SSD7_R")
	)
	(segment
		(start 352.013012 -230.528876)
		(end 353.236276 -230.528876)
		(width 0.15494)
		(layer "In15.Cu")
		(net "PWRGD_P12V_SSD7_R")
	)
	(segment
		(start 348.2213 -224.784666)
		(end 348.492826 -225.056192)
		(width 0.0889)
		(layer "In15.Cu")
		(net "PWRGD_P12V_SSD7_R")
	)
	(segment
		(start 237.13186 -170.449748)
		(end 222.77451 -170.449748)
		(width 0.15494)
		(layer "In15.Cu")
		(net "PWRGD_P12V_SSD7_R")
	)
	(segment
		(start 356.94366 -170.96613)
		(end 353.833176 -170.96613)
		(width 0.15494)
		(layer "In15.Cu")
		(net "PWRGD_P12V_SSD7_R")
	)
	(segment
		(start 356.722934 -234.015534)
		(end 369.425474 -234.015534)
		(width 0.15494)
		(layer "In15.Cu")
		(net "PWRGD_P12V_SSD7_R")
	)
	(segment
		(start 257.215132 -170.38066)
		(end 254.896112 -172.69968)
		(width 0.15494)
		(layer "In15.Cu")
		(net "PWRGD_P12V_SSD7_R")
	)
	(segment
		(start 336.905854 -168.684702)
		(end 336.416142 -168.19499)
		(width 0.15494)
		(layer "In15.Cu")
		(net "PWRGD_P12V_SSD7_R")
	)
	(segment
		(start 352.738436 -172.06087)
		(end 348.333314 -172.06087)
		(width 0.15494)
		(layer "In15.Cu")
		(net "PWRGD_P12V_SSD7_R")
	)
	(segment
		(start 222.77451 -170.449748)
		(end 221.706948 -169.382186)
		(width 0.15494)
		(layer "In15.Cu")
		(net "PWRGD_P12V_SSD7_R")
	)
	(segment
		(start 287.236662 -168.439592)
		(end 285.295594 -170.38066)
		(width 0.15494)
		(layer "In15.Cu")
		(net "PWRGD_P12V_SSD7_R")
	)
	(segment
		(start 353.833176 -170.96613)
		(end 352.738436 -172.06087)
		(width 0.15494)
		(layer "In15.Cu")
		(net "PWRGD_P12V_SSD7_R")
	)
	(segment
		(start 333.177134 -168.19499)
		(end 332.932532 -168.439592)
		(width 0.15494)
		(layer "In15.Cu")
		(net "PWRGD_P12V_SSD7_R")
	)
	(segment
		(start 348.492826 -225.056192)
		(end 348.492826 -227.00869)
		(width 0.0889)
		(layer "In15.Cu")
		(net "PWRGD_P12V_SSD7_R")
	)
	(segment
		(start 344.957146 -168.684702)
		(end 336.905854 -168.684702)
		(width 0.15494)
		(layer "In15.Cu")
		(net "PWRGD_P12V_SSD7_R")
	)
	(segment
		(start 345.693746 -224.386902)
		(end 346.068396 -224.012252)
		(width 0.0889)
		(layer "In15.Cu")
		(net "PWRGD_P12V_SSD7_R")
	)
	(segment
		(start 374.70461 -188.777372)
		(end 374.70461 -186.384692)
		(width 0.15494)
		(layer "In15.Cu")
		(net "PWRGD_P12V_SSD7_R")
	)
	(segment
		(start 346.648786 -224.012252)
		(end 346.894912 -224.258378)
		(width 0.0889)
		(layer "In15.Cu")
		(net "PWRGD_P12V_SSD7_R")
	)
	(segment
		(start 348.492826 -227.00869)
		(end 352.013012 -230.528876)
		(width 0.15494)
		(layer "In15.Cu")
		(net "PWRGD_P12V_SSD7_R")
	)
	(segment
		(start 374.233948 -215.939878)
		(end 374.233948 -194.996562)
		(width 0.15494)
		(layer "In15.Cu")
		(net "PWRGD_P12V_SSD7_R")
	)
	(segment
		(start 346.894912 -224.258378)
		(end 346.894912 -224.517966)
		(width 0.0889)
		(layer "In15.Cu")
		(net "PWRGD_P12V_SSD7_R")
	)
	(segment
		(start 375.332752 -217.038682)
		(end 374.233948 -215.939878)
		(width 0.15494)
		(layer "In15.Cu")
		(net "PWRGD_P12V_SSD7_R")
	)
	(segment
		(start 336.416142 -168.19499)
		(end 333.177134 -168.19499)
		(width 0.15494)
		(layer "In15.Cu")
		(net "PWRGD_P12V_SSD7_R")
	)
	(segment
		(start 371.389656 -178.139598)
		(end 365.023908 -171.77385)
		(width 0.15494)
		(layer "In15.Cu")
		(net "PWRGD_P12V_SSD7_R")
	)
	(segment
		(start 346.068396 -224.012252)
		(end 346.648786 -224.012252)
		(width 0.0889)
		(layer "In15.Cu")
		(net "PWRGD_P12V_SSD7_R")
	)
	(segment
		(start 374.233948 -194.996562)
		(end 376.31878 -192.91173)
		(width 0.15494)
		(layer "In15.Cu")
		(net "PWRGD_P12V_SSD7_R")
	)
	(segment
		(start 365.023908 -171.77385)
		(end 357.75138 -171.77385)
		(width 0.15494)
		(layer "In15.Cu")
		(net "PWRGD_P12V_SSD7_R")
	)
	(segment
		(start 239.381792 -172.69968)
		(end 237.13186 -170.449748)
		(width 0.15494)
		(layer "In15.Cu")
		(net "PWRGD_P12V_SSD7_R")
	)
	(segment
		(start 254.896112 -172.69968)
		(end 239.381792 -172.69968)
		(width 0.15494)
		(layer "In15.Cu")
		(net "PWRGD_P12V_SSD7_R")
	)
	(segment
		(start 229.467664 -226.893882)
		(end 229.467664 -223.504252)
		(width 0.13208)
		(layer "F.Cu")
		(net "NIC1_MAIN_PWR_BIC_EN")
	)
	(segment
		(start 229.655116 -227.081334)
		(end 229.467664 -226.893882)
		(width 0.13208)
		(layer "F.Cu")
		(net "NIC1_MAIN_PWR_BIC_EN")
	)
	(segment
		(start 229.467664 -223.504252)
		(end 229.067614 -223.104202)
		(width 0.13208)
		(layer "F.Cu")
		(net "NIC1_MAIN_PWR_BIC_EN")
	)
	(segment
		(start 229.655116 -230.220266)
		(end 229.655116 -227.695252)
		(width 0.13208)
		(layer "F.Cu")
		(net "NIC1_MAIN_PWR_BIC_EN")
	)
	(segment
		(start 230.4542 -231.01935)
		(end 229.655116 -230.220266)
		(width 0.13208)
		(layer "F.Cu")
		(net "NIC1_MAIN_PWR_BIC_EN")
	)
	(segment
		(start 229.655116 -227.695252)
		(end 229.655116 -227.081334)
		(width 0.13208)
		(layer "F.Cu")
		(net "NIC1_MAIN_PWR_BIC_EN")
	)
	(via
		(at 229.655116 -227.695252)
		(size 0.762)
		(drill 0.381)
		(layers "F.Cu" "B.Cu")
		(net "NIC1_MAIN_PWR_BIC_EN")
	)
	(segment
		(start 385.855464 -241.270536)
		(end 386.461 -240.665)
		(width 0.13208)
		(layer "F.Cu")
		(net "UART_PEX2_SDB_RX")
	)
	(segment
		(start 385.855464 -244.286024)
		(end 385.855464 -241.270536)
		(width 0.13208)
		(layer "F.Cu")
		(net "UART_PEX2_SDB_RX")
	)
	(via
		(at 386.461 -240.665)
		(size 0.508)
		(drill 0.254)
		(layers "F.Cu" "B.Cu")
		(net "UART_PEX2_SDB_RX")
	)
	(segment
		(start 386.461 -240.665)
		(end 386.82295 -240.30305)
		(width 0.13208)
		(layer "B.Cu")
		(net "UART_PEX2_SDB_RX")
	)
	(segment
		(start 386.82295 -240.30305)
		(end 386.82295 -239.522)
		(width 0.13208)
		(layer "B.Cu")
		(net "UART_PEX2_SDB_RX")
	)
	(segment
		(start 282.349702 -308.249828)
		(end 281.874722 -308.724808)
		(width 0.13208)
		(layer "F.Cu")
		(net "TP_PEX2_TCK")
	)
	(via
		(at 281.399742 -309.199788)
		(size 0.6604)
		(drill 0.3302)
		(layers "F.Cu" "B.Cu")
		(net "TP_PEX2_TCK")
	)
	(via
		(at 281.874722 -308.724808)
		(size 0.4064)
		(drill 0.2032)
		(layers "F.Cu" "B.Cu")
		(net "TP_PEX2_TCK")
	)
	(segment
		(start 281.399742 -309.199788)
		(end 281.874722 -308.724808)
		(width 0.13208)
		(layer "B.Cu")
		(net "TP_PEX2_TCK")
	)
	(segment
		(start 354.514404 -90.304366)
		(end 354.227384 -90.017346)
		(width 0.13208)
		(layer "F.Cu")
		(net "SMB_BIC_I2C9_MUX1_SSD8_SDA")
	)
	(segment
		(start 355.56444 -88.528906)
		(end 355.56444 -89.189306)
		(width 0.13208)
		(layer "F.Cu")
		(net "SMB_BIC_I2C9_MUX1_SSD8_SDA")
	)
	(segment
		(start 354.227384 -90.017346)
		(end 353.835716 -90.017346)
		(width 0.13208)
		(layer "F.Cu")
		(net "SMB_BIC_I2C9_MUX1_SSD8_SDA")
	)
	(segment
		(start 355.56444 -89.189306)
		(end 354.514404 -90.239342)
		(width 0.13208)
		(layer "F.Cu")
		(net "SMB_BIC_I2C9_MUX1_SSD8_SDA")
	)
	(segment
		(start 353.835716 -90.017346)
		(end 353.320604 -89.502234)
		(width 0.13208)
		(layer "F.Cu")
		(net "SMB_BIC_I2C9_MUX1_SSD8_SDA")
	)
	(segment
		(start 355.978206 -88.11514)
		(end 355.56444 -88.528906)
		(width 0.13208)
		(layer "F.Cu")
		(net "SMB_BIC_I2C9_MUX1_SSD8_SDA")
	)
	(segment
		(start 356.707948 -88.11514)
		(end 355.978206 -88.11514)
		(width 0.13208)
		(layer "F.Cu")
		(net "SMB_BIC_I2C9_MUX1_SSD8_SDA")
	)
	(segment
		(start 354.514404 -90.239342)
		(end 354.514404 -90.304366)
		(width 0.13208)
		(layer "F.Cu")
		(net "SMB_BIC_I2C9_MUX1_SSD8_SDA")
	)
	(via
		(at 354.514404 -90.304366)
		(size 0.508)
		(drill 0.254)
		(layers "F.Cu" "B.Cu")
		(net "SMB_BIC_I2C9_MUX1_SSD8_SDA")
	)
	(segment
		(start 348.361 -230.123746)
		(end 348.361 -232.4862)
		(width 0.13208)
		(layer "F.Cu")
		(net "SSD5_CLK_EN_N")
	)
	(segment
		(start 347.693742 -227.186998)
		(end 348.089982 -227.583238)
		(width 0.13208)
		(layer "F.Cu")
		(net "SSD5_CLK_EN_N")
	)
	(segment
		(start 348.361 -233.035602)
		(end 348.361 -232.4862)
		(width 0.13208)
		(layer "F.Cu")
		(net "SSD5_CLK_EN_N")
	)
	(segment
		(start 348.089982 -227.583238)
		(end 348.089982 -229.852728)
		(width 0.13208)
		(layer "F.Cu")
		(net "SSD5_CLK_EN_N")
	)
	(segment
		(start 348.089982 -229.852728)
		(end 348.361 -230.123746)
		(width 0.13208)
		(layer "F.Cu")
		(net "SSD5_CLK_EN_N")
	)
	(segment
		(start 348.107 -233.66095)
		(end 348.107 -233.289602)
		(width 0.13208)
		(layer "F.Cu")
		(net "SSD5_CLK_EN_N")
	)
	(segment
		(start 348.107 -233.289602)
		(end 348.361 -233.035602)
		(width 0.13208)
		(layer "F.Cu")
		(net "SSD5_CLK_EN_N")
	)
	(via
		(at 348.361 -232.4862)
		(size 0.762)
		(drill 0.381)
		(layers "F.Cu" "B.Cu")
		(net "SSD5_CLK_EN_N")
	)
	(segment
		(start 377.33605 -185.801)
		(end 377.33605 -186.817)
		(width 0.13208)
		(layer "F.Cu")
		(net "NIC1_PEX_PWR_EN_R")
	)
	(segment
		(start 377.33605 -185.801)
		(end 377.952 -185.801)
		(width 0.13208)
		(layer "F.Cu")
		(net "NIC1_PEX_PWR_EN_R")
	)
	(segment
		(start 350.893888 -215.187022)
		(end 351.293684 -214.787226)
		(width 0.13208)
		(layer "F.Cu")
		(net "NIC1_PEX_PWR_EN_R")
	)
	(segment
		(start 377.33605 -184.785)
		(end 377.33605 -185.801)
		(width 0.13208)
		(layer "F.Cu")
		(net "NIC1_PEX_PWR_EN_R")
	)
	(via
		(at 377.952 -185.801)
		(size 0.508)
		(drill 0.254)
		(layers "F.Cu" "B.Cu")
		(net "NIC1_PEX_PWR_EN_R")
	)
	(via
		(at 351.293684 -214.787226)
		(size 0.4572)
		(drill 0.254)
		(layers "F.Cu" "B.Cu")
		(net "NIC1_PEX_PWR_EN_R")
	)
	(via
		(at 367.50244 -185.60669)
		(size 0.508)
		(drill 0.254)
		(layers "F.Cu" "B.Cu")
		(net "NIC1_PEX_PWR_EN_R")
	)
	(segment
		(start 368.095276 -198.89597)
		(end 368.095276 -193.89598)
		(width 0.15494)
		(layer "In5.Cu")
		(net "NIC1_PEX_PWR_EN_R")
	)
	(segment
		(start 367.949988 -186.054238)
		(end 367.50244 -185.60669)
		(width 0.15494)
		(layer "In5.Cu")
		(net "NIC1_PEX_PWR_EN_R")
	)
	(segment
		(start 353.64293 -212.43798)
		(end 354.42398 -212.43798)
		(width 0.15494)
		(layer "In5.Cu")
		(net "NIC1_PEX_PWR_EN_R")
	)
	(segment
		(start 361.4928 -207.264)
		(end 361.4928 -205.9686)
		(width 0.15494)
		(layer "In5.Cu")
		(net "NIC1_PEX_PWR_EN_R")
	)
	(segment
		(start 368.095276 -193.89598)
		(end 367.949988 -193.750692)
		(width 0.15494)
		(layer "In5.Cu")
		(net "NIC1_PEX_PWR_EN_R")
	)
	(segment
		(start 356.60076 -210.2612)
		(end 357.251 -210.2612)
		(width 0.15494)
		(layer "In5.Cu")
		(net "NIC1_PEX_PWR_EN_R")
	)
	(segment
		(start 354.42398 -212.43798)
		(end 356.60076 -210.2612)
		(width 0.15494)
		(layer "In5.Cu")
		(net "NIC1_PEX_PWR_EN_R")
	)
	(segment
		(start 367.949988 -193.750692)
		(end 367.949988 -186.054238)
		(width 0.15494)
		(layer "In5.Cu")
		(net "NIC1_PEX_PWR_EN_R")
	)
	(segment
		(start 362.331 -205.1304)
		(end 362.9406 -205.1304)
		(width 0.15494)
		(layer "In5.Cu")
		(net "NIC1_PEX_PWR_EN_R")
	)
	(segment
		(start 362.9406 -205.1304)
		(end 363.7788 -204.2922)
		(width 0.15494)
		(layer "In5.Cu")
		(net "NIC1_PEX_PWR_EN_R")
	)
	(segment
		(start 351.293684 -214.787226)
		(end 353.64293 -212.43798)
		(width 0.15494)
		(layer "In5.Cu")
		(net "NIC1_PEX_PWR_EN_R")
	)
	(segment
		(start 360.045 -208.7118)
		(end 361.4928 -207.264)
		(width 0.15494)
		(layer "In5.Cu")
		(net "NIC1_PEX_PWR_EN_R")
	)
	(segment
		(start 358.8004 -208.7118)
		(end 360.045 -208.7118)
		(width 0.15494)
		(layer "In5.Cu")
		(net "NIC1_PEX_PWR_EN_R")
	)
	(segment
		(start 357.251 -210.2612)
		(end 358.8004 -208.7118)
		(width 0.15494)
		(layer "In5.Cu")
		(net "NIC1_PEX_PWR_EN_R")
	)
	(segment
		(start 363.7788 -203.212446)
		(end 368.095276 -198.89597)
		(width 0.15494)
		(layer "In5.Cu")
		(net "NIC1_PEX_PWR_EN_R")
	)
	(segment
		(start 363.7788 -204.2922)
		(end 363.7788 -203.212446)
		(width 0.15494)
		(layer "In5.Cu")
		(net "NIC1_PEX_PWR_EN_R")
	)
	(segment
		(start 361.4928 -205.9686)
		(end 362.331 -205.1304)
		(width 0.15494)
		(layer "In5.Cu")
		(net "NIC1_PEX_PWR_EN_R")
	)
	(segment
		(start 377.952 -185.801)
		(end 377.448826 -186.304174)
		(width 0.15494)
		(layer "In13.Cu")
		(net "NIC1_PEX_PWR_EN_R")
	)
	(segment
		(start 377.448826 -186.304174)
		(end 368.199924 -186.304174)
		(width 0.15494)
		(layer "In13.Cu")
		(net "NIC1_PEX_PWR_EN_R")
	)
	(segment
		(start 368.199924 -186.304174)
		(end 367.50244 -185.60669)
		(width 0.15494)
		(layer "In13.Cu")
		(net "NIC1_PEX_PWR_EN_R")
	)
	(via
		(at 143.354552 -213.334346)
		(size 0.6604)
		(drill 0.3302)
		(layers "F.Cu" "B.Cu")
		(net "UART_PEX2_CLI_BUF_R_RX")
	)
	(segment
		(start 143.227552 -212.74151)
		(end 143.354552 -212.86851)
		(width 0.13208)
		(layer "B.Cu")
		(net "UART_PEX2_CLI_BUF_R_RX")
	)
	(segment
		(start 143.354552 -212.86851)
		(end 143.354552 -213.334346)
		(width 0.13208)
		(layer "B.Cu")
		(net "UART_PEX2_CLI_BUF_R_RX")
	)
	(segment
		(start 142.4432 -212.523832)
		(end 142.660878 -212.74151)
		(width 0.13208)
		(layer "B.Cu")
		(net "UART_PEX2_CLI_BUF_R_RX")
	)
	(segment
		(start 143.354552 -213.334346)
		(end 143.354552 -214.011256)
		(width 0.13208)
		(layer "B.Cu")
		(net "UART_PEX2_CLI_BUF_R_RX")
	)
	(segment
		(start 142.4432 -211.857844)
		(end 142.4432 -212.523832)
		(width 0.13208)
		(layer "B.Cu")
		(net "UART_PEX2_CLI_BUF_R_RX")
	)
	(segment
		(start 143.354552 -214.011256)
		(end 142.806674 -214.559134)
		(width 0.13208)
		(layer "B.Cu")
		(net "UART_PEX2_CLI_BUF_R_RX")
	)
	(segment
		(start 142.660878 -212.74151)
		(end 143.227552 -212.74151)
		(width 0.13208)
		(layer "B.Cu")
		(net "UART_PEX2_CLI_BUF_R_RX")
	)
	(segment
		(start 284.249876 -309.199788)
		(end 283.774896 -308.724808)
		(width 0.127)
		(layer "F.Cu")
		(net "TP_PEX2_TDI")
	)
	(via
		(at 283.774896 -308.724808)
		(size 0.4064)
		(drill 0.2032)
		(layers "F.Cu" "B.Cu")
		(net "TP_PEX2_TDI")
	)
	(via
		(at 284.249876 -309.199788)
		(size 0.6604)
		(drill 0.3302)
		(layers "F.Cu" "B.Cu")
		(net "TP_PEX2_TDI")
	)
	(segment
		(start 284.249876 -309.199788)
		(end 283.774896 -308.724808)
		(width 0.13208)
		(layer "B.Cu")
		(net "TP_PEX2_TDI")
	)
	(segment
		(start 354.093272 -86.073234)
		(end 354.514404 -86.494366)
		(width 0.13208)
		(layer "F.Cu")
		(net "SMB_BIC_I2C9_MUX1_SSD9_SCL")
	)
	(segment
		(start 354.514404 -86.494366)
		(end 354.843842 -86.164928)
		(width 0.13208)
		(layer "F.Cu")
		(net "SMB_BIC_I2C9_MUX1_SSD9_SCL")
	)
	(segment
		(start 353.320604 -86.073234)
		(end 354.093272 -86.073234)
		(width 0.13208)
		(layer "F.Cu")
		(net "SMB_BIC_I2C9_MUX1_SSD9_SCL")
	)
	(segment
		(start 354.843842 -86.164928)
		(end 356.707948 -86.164928)
		(width 0.13208)
		(layer "F.Cu")
		(net "SMB_BIC_I2C9_MUX1_SSD9_SCL")
	)
	(via
		(at 354.514404 -86.494366)
		(size 0.508)
		(drill 0.254)
		(layers "F.Cu" "B.Cu")
		(net "SMB_BIC_I2C9_MUX1_SSD9_SCL")
	)
	(segment
		(start 280.137616 -404.674324)
		(end 281.15387 -403.65807)
		(width 0.13208)
		(layer "F.Cu")
		(net "MB_BIC_MON_BUF_R")
	)
	(segment
		(start 281.15387 -398.949926)
		(end 280.137616 -397.933672)
		(width 0.13208)
		(layer "F.Cu")
		(net "MB_BIC_MON_BUF_R")
	)
	(segment
		(start 281.15387 -403.65807)
		(end 281.15387 -398.949926)
		(width 0.13208)
		(layer "F.Cu")
		(net "MB_BIC_MON_BUF_R")
	)
	(via
		(at 143.6116 -389.9154)
		(size 0.508)
		(drill 0.254)
		(layers "F.Cu" "B.Cu")
		(net "MB_BIC_MON_BUF_R")
	)
	(via
		(at 280.137616 -397.933672)
		(size 0.508)
		(drill 0.254)
		(layers "F.Cu" "B.Cu")
		(net "MB_BIC_MON_BUF_R")
	)
	(segment
		(start 182.348632 -392.617198)
		(end 182.348632 -415.307526)
		(width 0.13208)
		(layer "B.Cu")
		(net "MB_BIC_MON_BUF_R")
	)
	(segment
		(start 152.7302 -387.223)
		(end 176.954434 -387.223)
		(width 0.13208)
		(layer "B.Cu")
		(net "MB_BIC_MON_BUF_R")
	)
	(segment
		(start 264.994136 -386.92582)
		(end 270.520414 -386.92582)
		(width 0.13208)
		(layer "B.Cu")
		(net "MB_BIC_MON_BUF_R")
	)
	(segment
		(start 245.499128 -399.60042)
		(end 245.499128 -392.033506)
		(width 0.13208)
		(layer "B.Cu")
		(net "MB_BIC_MON_BUF_R")
	)
	(segment
		(start 148.7678 -390.1694)
		(end 149.1234 -389.8138)
		(width 0.13208)
		(layer "B.Cu")
		(net "MB_BIC_MON_BUF_R")
	)
	(segment
		(start 143.8656 -390.1694)
		(end 148.7678 -390.1694)
		(width 0.13208)
		(layer "B.Cu")
		(net "MB_BIC_MON_BUF_R")
	)
	(segment
		(start 143.6116 -389.9154)
		(end 143.8656 -390.1694)
		(width 0.13208)
		(layer "B.Cu")
		(net "MB_BIC_MON_BUF_R")
	)
	(segment
		(start 176.954434 -387.223)
		(end 182.348632 -392.617198)
		(width 0.13208)
		(layer "B.Cu")
		(net "MB_BIC_MON_BUF_R")
	)
	(segment
		(start 275.75129 -392.156696)
		(end 275.75129 -396.25905)
		(width 0.13208)
		(layer "B.Cu")
		(net "MB_BIC_MON_BUF_R")
	)
	(segment
		(start 182.348632 -415.307526)
		(end 184.130442 -417.089336)
		(width 0.13208)
		(layer "B.Cu")
		(net "MB_BIC_MON_BUF_R")
	)
	(segment
		(start 148.7424 -388.6962)
		(end 148.7424 -387.985)
		(width 0.13208)
		(layer "B.Cu")
		(net "MB_BIC_MON_BUF_R")
	)
	(segment
		(start 152.2984 -387.6548)
		(end 152.7302 -387.223)
		(width 0.13208)
		(layer "B.Cu")
		(net "MB_BIC_MON_BUF_R")
	)
	(segment
		(start 149.1234 -389.0772)
		(end 148.7424 -388.6962)
		(width 0.13208)
		(layer "B.Cu")
		(net "MB_BIC_MON_BUF_R")
	)
	(segment
		(start 148.7424 -387.985)
		(end 149.0726 -387.6548)
		(width 0.13208)
		(layer "B.Cu")
		(net "MB_BIC_MON_BUF_R")
	)
	(segment
		(start 149.0726 -387.6548)
		(end 152.2984 -387.6548)
		(width 0.13208)
		(layer "B.Cu")
		(net "MB_BIC_MON_BUF_R")
	)
	(segment
		(start 277.425912 -397.933672)
		(end 280.137616 -397.933672)
		(width 0.13208)
		(layer "B.Cu")
		(net "MB_BIC_MON_BUF_R")
	)
	(segment
		(start 270.520414 -386.92582)
		(end 275.75129 -392.156696)
		(width 0.13208)
		(layer "B.Cu")
		(net "MB_BIC_MON_BUF_R")
	)
	(segment
		(start 275.75129 -396.25905)
		(end 277.425912 -397.933672)
		(width 0.13208)
		(layer "B.Cu")
		(net "MB_BIC_MON_BUF_R")
	)
	(segment
		(start 238.773462 -414.185608)
		(end 238.773462 -403.133306)
		(width 0.13208)
		(layer "B.Cu")
		(net "MB_BIC_MON_BUF_R")
	)
	(segment
		(start 200.40727 -417.089336)
		(end 201.746866 -415.74974)
		(width 0.13208)
		(layer "B.Cu")
		(net "MB_BIC_MON_BUF_R")
	)
	(segment
		(start 149.1234 -389.8138)
		(end 149.1234 -389.0772)
		(width 0.13208)
		(layer "B.Cu")
		(net "MB_BIC_MON_BUF_R")
	)
	(segment
		(start 245.499128 -392.033506)
		(end 246.008144 -391.52449)
		(width 0.13208)
		(layer "B.Cu")
		(net "MB_BIC_MON_BUF_R")
	)
	(segment
		(start 184.130442 -417.089336)
		(end 200.40727 -417.089336)
		(width 0.13208)
		(layer "B.Cu")
		(net "MB_BIC_MON_BUF_R")
	)
	(segment
		(start 243.7003 -401.399248)
		(end 245.499128 -399.60042)
		(width 0.13208)
		(layer "B.Cu")
		(net "MB_BIC_MON_BUF_R")
	)
	(segment
		(start 238.773462 -403.133306)
		(end 240.50752 -401.399248)
		(width 0.13208)
		(layer "B.Cu")
		(net "MB_BIC_MON_BUF_R")
	)
	(segment
		(start 260.395466 -391.52449)
		(end 264.994136 -386.92582)
		(width 0.13208)
		(layer "B.Cu")
		(net "MB_BIC_MON_BUF_R")
	)
	(segment
		(start 240.50752 -401.399248)
		(end 243.7003 -401.399248)
		(width 0.13208)
		(layer "B.Cu")
		(net "MB_BIC_MON_BUF_R")
	)
	(segment
		(start 237.20933 -415.74974)
		(end 238.773462 -414.185608)
		(width 0.13208)
		(layer "B.Cu")
		(net "MB_BIC_MON_BUF_R")
	)
	(segment
		(start 201.746866 -415.74974)
		(end 237.20933 -415.74974)
		(width 0.13208)
		(layer "B.Cu")
		(net "MB_BIC_MON_BUF_R")
	)
	(segment
		(start 246.008144 -391.52449)
		(end 260.395466 -391.52449)
		(width 0.13208)
		(layer "B.Cu")
		(net "MB_BIC_MON_BUF_R")
	)
	(segment
		(start 143.597884 -389.901684)
		(end 139.993116 -389.901684)
		(width 0.15494)
		(layer "In9.Cu")
		(net "MB_BIC_MON_BUF_R")
	)
	(segment
		(start 139.993116 -389.901684)
		(end 136.9568 -392.938)
		(width 0.15494)
		(layer "In9.Cu")
		(net "MB_BIC_MON_BUF_R")
	)
	(segment
		(start 136.9568 -392.938)
		(end 136.9568 -403.885146)
		(width 0.15494)
		(layer "In9.Cu")
		(net "MB_BIC_MON_BUF_R")
	)
	(segment
		(start 134.019798 -404.7998)
		(end 133.51002 -404.290022)
		(width 0.15494)
		(layer "In9.Cu")
		(net "MB_BIC_MON_BUF_R")
	)
	(segment
		(start 136.042146 -404.7998)
		(end 134.019798 -404.7998)
		(width 0.15494)
		(layer "In9.Cu")
		(net "MB_BIC_MON_BUF_R")
	)
	(segment
		(start 136.9568 -403.885146)
		(end 136.042146 -404.7998)
		(width 0.15494)
		(layer "In9.Cu")
		(net "MB_BIC_MON_BUF_R")
	)
	(segment
		(start 143.6116 -389.9154)
		(end 143.597884 -389.901684)
		(width 0.15494)
		(layer "In9.Cu")
		(net "MB_BIC_MON_BUF_R")
	)
	(segment
		(start 342.093804 -224.786952)
		(end 341.694008 -225.186748)
		(width 0.13208)
		(layer "F.Cu")
		(net "RST_SSD1_PERST_N")
	)
	(segment
		(start 343.902792 -240.291112)
		(end 343.902792 -239.675162)
		(width 0.13208)
		(layer "F.Cu")
		(net "RST_SSD1_PERST_N")
	)
	(via
		(at 341.694008 -225.186748)
		(size 0.4572)
		(drill 0.254)
		(layers "F.Cu" "B.Cu")
		(net "RST_SSD1_PERST_N")
	)
	(via
		(at 343.902792 -239.675162)
		(size 0.508)
		(drill 0.254)
		(layers "F.Cu" "B.Cu")
		(net "RST_SSD1_PERST_N")
	)
	(segment
		(start 342.118696 -228.941884)
		(end 342.118696 -225.611436)
		(width 0.15494)
		(layer "In5.Cu")
		(net "RST_SSD1_PERST_N")
	)
	(segment
		(start 341.97036 -232.964482)
		(end 341.97036 -229.09022)
		(width 0.15494)
		(layer "In5.Cu")
		(net "RST_SSD1_PERST_N")
	)
	(segment
		(start 341.97036 -229.09022)
		(end 342.118696 -228.941884)
		(width 0.15494)
		(layer "In5.Cu")
		(net "RST_SSD1_PERST_N")
	)
	(segment
		(start 343.902792 -238.195866)
		(end 342.523572 -236.816646)
		(width 0.15494)
		(layer "In5.Cu")
		(net "RST_SSD1_PERST_N")
	)
	(segment
		(start 343.902792 -239.675162)
		(end 343.902792 -238.195866)
		(width 0.15494)
		(layer "In5.Cu")
		(net "RST_SSD1_PERST_N")
	)
	(segment
		(start 342.523572 -236.816646)
		(end 342.523572 -233.517694)
		(width 0.15494)
		(layer "In5.Cu")
		(net "RST_SSD1_PERST_N")
	)
	(segment
		(start 342.118696 -225.611436)
		(end 341.694008 -225.186748)
		(width 0.15494)
		(layer "In5.Cu")
		(net "RST_SSD1_PERST_N")
	)
	(segment
		(start 342.523572 -233.517694)
		(end 341.97036 -232.964482)
		(width 0.15494)
		(layer "In5.Cu")
		(net "RST_SSD1_PERST_N")
	)
	(segment
		(start 260.67512 -63.086234)
		(end 259.969508 -63.086234)
		(width 0.4572)
		(layer "F.Cu")
		(net "P12V_SSD9_R")
	)
	(segment
		(start 278.725376 -42.849038)
		(end 279.473914 -42.849038)
		(width 0.381)
		(layer "F.Cu")
		(net "P12V_SSD9_R")
	)
	(via
		(at 276.552914 -68.586604)
		(size 0.508)
		(drill 0.254)
		(layers "F.Cu" "B.Cu")
		(net "P12V_SSD9_R")
	)
	(via
		(at 275.917914 -68.586604)
		(size 0.508)
		(drill 0.254)
		(layers "F.Cu" "B.Cu")
		(net "P12V_SSD9_R")
	)
	(via
		(at 259.969508 -63.086234)
		(size 0.508)
		(drill 0.254)
		(layers "F.Cu" "B.Cu")
		(net "P12V_SSD9_R")
	)
	(via
		(at 278.652478 -54.135528)
		(size 0.508)
		(drill 0.254)
		(layers "F.Cu" "B.Cu")
		(net "P12V_SSD9_R")
	)
	(via
		(at 275.792184 -53.77053)
		(size 0.508)
		(drill 0.254)
		(layers "F.Cu" "B.Cu")
		(net "P12V_SSD9_R")
	)
	(via
		(at 277.711916 -54.320186)
		(size 0.508)
		(drill 0.254)
		(layers "F.Cu" "B.Cu")
		(net "P12V_SSD9_R")
	)
	(via
		(at 275.792184 -53.00853)
		(size 0.508)
		(drill 0.254)
		(layers "F.Cu" "B.Cu")
		(net "P12V_SSD9_R")
	)
	(via
		(at 273.582638 -67.10172)
		(size 0.508)
		(drill 0.254)
		(layers "F.Cu" "B.Cu")
		(net "P12V_SSD9_R")
	)
	(via
		(at 276.427184 -53.77053)
		(size 0.508)
		(drill 0.254)
		(layers "F.Cu" "B.Cu")
		(net "P12V_SSD9_R")
	)
	(via
		(at 277.449534 -46.066964)
		(size 0.508)
		(drill 0.254)
		(layers "F.Cu" "B.Cu")
		(net "P12V_SSD9_R")
	)
	(via
		(at 277.35149 -46.739048)
		(size 0.508)
		(drill 0.254)
		(layers "F.Cu" "B.Cu")
		(net "P12V_SSD9_R")
	)
	(via
		(at 275.206714 -67.951604)
		(size 0.508)
		(drill 0.254)
		(layers "F.Cu" "B.Cu")
		(net "P12V_SSD9_R")
	)
	(via
		(at 274.757896 -54.791102)
		(size 0.508)
		(drill 0.254)
		(layers "F.Cu" "B.Cu")
		(net "P12V_SSD9_R")
	)
	(via
		(at 277.711916 -53.685186)
		(size 0.508)
		(drill 0.254)
		(layers "F.Cu" "B.Cu")
		(net "P12V_SSD9_R")
	)
	(via
		(at 278.652478 -54.770528)
		(size 0.508)
		(drill 0.254)
		(layers "F.Cu" "B.Cu")
		(net "P12V_SSD9_R")
	)
	(via
		(at 276.63394 -46.082204)
		(size 0.508)
		(drill 0.254)
		(layers "F.Cu" "B.Cu")
		(net "P12V_SSD9_R")
	)
	(via
		(at 276.552914 -67.951604)
		(size 0.508)
		(drill 0.254)
		(layers "F.Cu" "B.Cu")
		(net "P12V_SSD9_R")
	)
	(via
		(at 272.947638 -67.10172)
		(size 0.508)
		(drill 0.254)
		(layers "F.Cu" "B.Cu")
		(net "P12V_SSD9_R")
	)
	(via
		(at 275.917914 -67.951604)
		(size 0.508)
		(drill 0.254)
		(layers "F.Cu" "B.Cu")
		(net "P12V_SSD9_R")
	)
	(via
		(at 275.206714 -68.586604)
		(size 0.508)
		(drill 0.254)
		(layers "F.Cu" "B.Cu")
		(net "P12V_SSD9_R")
	)
	(via
		(at 279.473914 -42.849038)
		(size 0.508)
		(drill 0.254)
		(layers "F.Cu" "B.Cu")
		(net "P12V_SSD9_R")
	)
	(via
		(at 274.757896 -52.886102)
		(size 0.508)
		(drill 0.254)
		(layers "F.Cu" "B.Cu")
		(net "P12V_SSD9_R")
	)
	(via
		(at 274.757896 -54.156102)
		(size 0.508)
		(drill 0.254)
		(layers "F.Cu" "B.Cu")
		(net "P12V_SSD9_R")
	)
	(via
		(at 272.102072 -54.731412)
		(size 0.508)
		(drill 0.254)
		(layers "F.Cu" "B.Cu")
		(net "P12V_SSD9_R")
	)
	(via
		(at 272.102072 -53.461412)
		(size 0.508)
		(drill 0.254)
		(layers "F.Cu" "B.Cu")
		(net "P12V_SSD9_R")
	)
	(via
		(at 272.102072 -52.826412)
		(size 0.508)
		(drill 0.254)
		(layers "F.Cu" "B.Cu")
		(net "P12V_SSD9_R")
	)
	(via
		(at 278.159464 -45.976286)
		(size 0.508)
		(drill 0.254)
		(layers "F.Cu" "B.Cu")
		(net "P12V_SSD9_R")
	)
	(via
		(at 272.102072 -54.096412)
		(size 0.508)
		(drill 0.254)
		(layers "F.Cu" "B.Cu")
		(net "P12V_SSD9_R")
	)
	(via
		(at 276.503384 -53.00853)
		(size 0.508)
		(drill 0.254)
		(layers "F.Cu" "B.Cu")
		(net "P12V_SSD9_R")
	)
	(via
		(at 274.757896 -53.521102)
		(size 0.508)
		(drill 0.254)
		(layers "F.Cu" "B.Cu")
		(net "P12V_SSD9_R")
	)
	(via
		(at 276.686772 -46.792134)
		(size 0.508)
		(drill 0.254)
		(layers "F.Cu" "B.Cu")
		(net "P12V_SSD9_R")
	)
	(segment
		(start 392.249406 -238.432594)
		(end 391.37082 -239.31118)
		(width 0.13208)
		(layer "F.Cu")
		(net "UART_PEX1_SDB_RX")
	)
	(segment
		(start 392.249406 -230.22941)
		(end 392.249406 -238.432594)
		(width 0.13208)
		(layer "F.Cu")
		(net "UART_PEX1_SDB_RX")
	)
	(segment
		(start 391.37082 -239.31118)
		(end 390.330436 -239.31118)
		(width 0.13208)
		(layer "F.Cu")
		(net "UART_PEX1_SDB_RX")
	)
	(segment
		(start 393.101576 -229.37724)
		(end 392.249406 -230.22941)
		(width 0.13208)
		(layer "F.Cu")
		(net "UART_PEX1_SDB_RX")
	)
	(via
		(at 393.101576 -229.37724)
		(size 0.508)
		(drill 0.254)
		(layers "F.Cu" "B.Cu")
		(net "UART_PEX1_SDB_RX")
	)
	(segment
		(start 391.018522 -230.255572)
		(end 388.366 -227.60305)
		(width 0.13208)
		(layer "B.Cu")
		(net "UART_PEX1_SDB_RX")
	)
	(segment
		(start 393.101576 -229.37724)
		(end 392.223244 -230.255572)
		(width 0.13208)
		(layer "B.Cu")
		(net "UART_PEX1_SDB_RX")
	)
	(segment
		(start 392.223244 -230.255572)
		(end 391.018522 -230.255572)
		(width 0.13208)
		(layer "B.Cu")
		(net "UART_PEX1_SDB_RX")
	)
	(segment
		(start 304.199798 -291.149786)
		(end 303.724818 -290.674806)
		(width 0.13208)
		(layer "F.Cu")
		(net "UART_PEX2_CLI_BUF_RX")
	)
	(via
		(at 145.408904 -214.76589)
		(size 0.508)
		(drill 0.254)
		(layers "F.Cu" "B.Cu")
		(net "UART_PEX2_CLI_BUF_RX")
	)
	(via
		(at 258.678426 -233.06405)
		(size 0.508)
		(drill 0.254)
		(layers "F.Cu" "B.Cu")
		(net "UART_PEX2_CLI_BUF_RX")
	)
	(via
		(at 303.724818 -290.674806)
		(size 0.4064)
		(drill 0.2032)
		(layers "F.Cu" "B.Cu")
		(net "UART_PEX2_CLI_BUF_RX")
	)
	(via
		(at 257.572256 -201.58964)
		(size 0.508)
		(drill 0.254)
		(layers "F.Cu" "B.Cu")
		(net "UART_PEX2_CLI_BUF_RX")
	)
	(via
		(at 306.099718 -282.599892)
		(size 0.6604)
		(drill 0.3302)
		(layers "F.Cu" "B.Cu")
		(net "UART_PEX2_CLI_BUF_RX")
	)
	(segment
		(start 306.099718 -282.599892)
		(end 306.620164 -282.079446)
		(width 0.13208)
		(layer "B.Cu")
		(net "UART_PEX2_CLI_BUF_RX")
	)
	(segment
		(start 306.620164 -282.079446)
		(end 306.620164 -272.069814)
		(width 0.13208)
		(layer "B.Cu")
		(net "UART_PEX2_CLI_BUF_RX")
	)
	(segment
		(start 303.724818 -290.674806)
		(end 304.148744 -290.25088)
		(width 0.13208)
		(layer "B.Cu")
		(net "UART_PEX2_CLI_BUF_RX")
	)
	(segment
		(start 305.634644 -287.8582)
		(end 306.493164 -287.8582)
		(width 0.13208)
		(layer "B.Cu")
		(net "UART_PEX2_CLI_BUF_RX")
	)
	(segment
		(start 304.148744 -288.536126)
		(end 304.325782 -288.359088)
		(width 0.13208)
		(layer "B.Cu")
		(net "UART_PEX2_CLI_BUF_RX")
	)
	(segment
		(start 305.133756 -288.359088)
		(end 305.634644 -287.8582)
		(width 0.13208)
		(layer "B.Cu")
		(net "UART_PEX2_CLI_BUF_RX")
	)
	(segment
		(start 306.620164 -272.069814)
		(end 285.166562 -250.616212)
		(width 0.13208)
		(layer "B.Cu")
		(net "UART_PEX2_CLI_BUF_RX")
	)
	(segment
		(start 145.408904 -214.76589)
		(end 144.81556 -215.359234)
		(width 0.13208)
		(layer "B.Cu")
		(net "UART_PEX2_CLI_BUF_RX")
	)
	(segment
		(start 285.166562 -250.616212)
		(end 280.421334 -250.616212)
		(width 0.13208)
		(layer "B.Cu")
		(net "UART_PEX2_CLI_BUF_RX")
	)
	(segment
		(start 306.493164 -287.8582)
		(end 306.620164 -287.7312)
		(width 0.13208)
		(layer "B.Cu")
		(net "UART_PEX2_CLI_BUF_RX")
	)
	(segment
		(start 304.325782 -288.359088)
		(end 305.133756 -288.359088)
		(width 0.13208)
		(layer "B.Cu")
		(net "UART_PEX2_CLI_BUF_RX")
	)
	(segment
		(start 306.620164 -287.7312)
		(end 306.620164 -283.120338)
		(width 0.13208)
		(layer "B.Cu")
		(net "UART_PEX2_CLI_BUF_RX")
	)
	(segment
		(start 260.155436 -234.54106)
		(end 258.678426 -233.06405)
		(width 0.13208)
		(layer "B.Cu")
		(net "UART_PEX2_CLI_BUF_RX")
	)
	(segment
		(start 304.148744 -290.25088)
		(end 304.148744 -288.536126)
		(width 0.13208)
		(layer "B.Cu")
		(net "UART_PEX2_CLI_BUF_RX")
	)
	(segment
		(start 306.620164 -283.120338)
		(end 306.099718 -282.599892)
		(width 0.13208)
		(layer "B.Cu")
		(net "UART_PEX2_CLI_BUF_RX")
	)
	(segment
		(start 144.81556 -215.359234)
		(end 143.822674 -215.359234)
		(width 0.13208)
		(layer "B.Cu")
		(net "UART_PEX2_CLI_BUF_RX")
	)
	(segment
		(start 264.346182 -234.54106)
		(end 260.155436 -234.54106)
		(width 0.13208)
		(layer "B.Cu")
		(net "UART_PEX2_CLI_BUF_RX")
	)
	(segment
		(start 280.421334 -250.616212)
		(end 264.346182 -234.54106)
		(width 0.13208)
		(layer "B.Cu")
		(net "UART_PEX2_CLI_BUF_RX")
	)
	(segment
		(start 142.806674 -215.359234)
		(end 143.822674 -215.359234)
		(width 0.13208)
		(layer "B.Cu")
		(net "UART_PEX2_CLI_BUF_RX")
	)
	(segment
		(start 267.81506 -227.33254)
		(end 267.81506 -225.080576)
		(width 0.15494)
		(layer "In5.Cu")
		(net "UART_PEX2_CLI_BUF_RX")
	)
	(segment
		(start 266.217654 -220.472)
		(end 263.1186 -220.472)
		(width 0.15494)
		(layer "In5.Cu")
		(net "UART_PEX2_CLI_BUF_RX")
	)
	(segment
		(start 259.564632 -201.716894)
		(end 258.908296 -201.060558)
		(width 0.15494)
		(layer "In5.Cu")
		(net "UART_PEX2_CLI_BUF_RX")
	)
	(segment
		(start 260.985 -211.480146)
		(end 260.0706 -210.565746)
		(width 0.15494)
		(layer "In5.Cu")
		(net "UART_PEX2_CLI_BUF_RX")
	)
	(segment
		(start 258.908296 -201.060558)
		(end 258.101338 -201.060558)
		(width 0.15494)
		(layer "In5.Cu")
		(net "UART_PEX2_CLI_BUF_RX")
	)
	(segment
		(start 260.0706 -205.9178)
		(end 259.564632 -205.411832)
		(width 0.15494)
		(layer "In5.Cu")
		(net "UART_PEX2_CLI_BUF_RX")
	)
	(segment
		(start 268.42847 -224.467166)
		(end 268.42847 -222.682816)
		(width 0.15494)
		(layer "In5.Cu")
		(net "UART_PEX2_CLI_BUF_RX")
	)
	(segment
		(start 268.42847 -222.682816)
		(end 266.217654 -220.472)
		(width 0.15494)
		(layer "In5.Cu")
		(net "UART_PEX2_CLI_BUF_RX")
	)
	(segment
		(start 260.0706 -210.565746)
		(end 260.0706 -205.9178)
		(width 0.15494)
		(layer "In5.Cu")
		(net "UART_PEX2_CLI_BUF_RX")
	)
	(segment
		(start 263.1186 -220.472)
		(end 260.985 -218.3384)
		(width 0.15494)
		(layer "In5.Cu")
		(net "UART_PEX2_CLI_BUF_RX")
	)
	(segment
		(start 259.564632 -205.411832)
		(end 259.564632 -201.716894)
		(width 0.15494)
		(layer "In5.Cu")
		(net "UART_PEX2_CLI_BUF_RX")
	)
	(segment
		(start 267.81506 -225.080576)
		(end 268.42847 -224.467166)
		(width 0.15494)
		(layer "In5.Cu")
		(net "UART_PEX2_CLI_BUF_RX")
	)
	(segment
		(start 260.985 -218.3384)
		(end 260.985 -211.480146)
		(width 0.15494)
		(layer "In5.Cu")
		(net "UART_PEX2_CLI_BUF_RX")
	)
	(segment
		(start 258.678426 -233.06405)
		(end 263.211056 -228.53142)
		(width 0.15494)
		(layer "In5.Cu")
		(net "UART_PEX2_CLI_BUF_RX")
	)
	(segment
		(start 263.211056 -228.53142)
		(end 266.61618 -228.53142)
		(width 0.15494)
		(layer "In5.Cu")
		(net "UART_PEX2_CLI_BUF_RX")
	)
	(segment
		(start 266.61618 -228.53142)
		(end 267.81506 -227.33254)
		(width 0.15494)
		(layer "In5.Cu")
		(net "UART_PEX2_CLI_BUF_RX")
	)
	(segment
		(start 258.101338 -201.060558)
		(end 257.572256 -201.58964)
		(width 0.15494)
		(layer "In5.Cu")
		(net "UART_PEX2_CLI_BUF_RX")
	)
	(segment
		(start 248.6914 -202.2602)
		(end 247.2944 -202.2602)
		(width 0.15494)
		(layer "In15.Cu")
		(net "UART_PEX2_CLI_BUF_RX")
	)
	(segment
		(start 242.156488 -207.4926)
		(end 238.760508 -207.4926)
		(width 0.15494)
		(layer "In15.Cu")
		(net "UART_PEX2_CLI_BUF_RX")
	)
	(segment
		(start 245.3132 -201.5998)
		(end 244.2972 -202.6158)
		(width 0.15494)
		(layer "In15.Cu")
		(net "UART_PEX2_CLI_BUF_RX")
	)
	(segment
		(start 246.634 -201.5998)
		(end 245.3132 -201.5998)
		(width 0.15494)
		(layer "In15.Cu")
		(net "UART_PEX2_CLI_BUF_RX")
	)
	(segment
		(start 253.44755 -202.59675)
		(end 249.02795 -202.59675)
		(width 0.15494)
		(layer "In15.Cu")
		(net "UART_PEX2_CLI_BUF_RX")
	)
	(segment
		(start 218.96451 -208.09585)
		(end 218.80449 -208.25587)
		(width 0.15494)
		(layer "In15.Cu")
		(net "UART_PEX2_CLI_BUF_RX")
	)
	(segment
		(start 256.232914 -203.202032)
		(end 254.052832 -203.202032)
		(width 0.15494)
		(layer "In15.Cu")
		(net "UART_PEX2_CLI_BUF_RX")
	)
	(segment
		(start 243.811298 -203.838302)
		(end 243.811298 -205.83779)
		(width 0.15494)
		(layer "In15.Cu")
		(net "UART_PEX2_CLI_BUF_RX")
	)
	(segment
		(start 238.760508 -207.4926)
		(end 238.157258 -208.09585)
		(width 0.15494)
		(layer "In15.Cu")
		(net "UART_PEX2_CLI_BUF_RX")
	)
	(segment
		(start 194.317112 -218.354148)
		(end 185.18632 -218.354148)
		(width 0.15494)
		(layer "In15.Cu")
		(net "UART_PEX2_CLI_BUF_RX")
	)
	(segment
		(start 216.244424 -208.25587)
		(end 216.214452 -208.225898)
		(width 0.15494)
		(layer "In15.Cu")
		(net "UART_PEX2_CLI_BUF_RX")
	)
	(segment
		(start 207.202278 -208.225898)
		(end 206.704946 -207.728566)
		(width 0.15494)
		(layer "In15.Cu")
		(net "UART_PEX2_CLI_BUF_RX")
	)
	(segment
		(start 206.704946 -207.728566)
		(end 204.942694 -207.728566)
		(width 0.15494)
		(layer "In15.Cu")
		(net "UART_PEX2_CLI_BUF_RX")
	)
	(segment
		(start 243.811298 -205.83779)
		(end 242.156488 -207.4926)
		(width 0.15494)
		(layer "In15.Cu")
		(net "UART_PEX2_CLI_BUF_RX")
	)
	(segment
		(start 247.2944 -202.2602)
		(end 246.634 -201.5998)
		(width 0.15494)
		(layer "In15.Cu")
		(net "UART_PEX2_CLI_BUF_RX")
	)
	(segment
		(start 257.572256 -201.58964)
		(end 257.572256 -201.86269)
		(width 0.15494)
		(layer "In15.Cu")
		(net "UART_PEX2_CLI_BUF_RX")
	)
	(segment
		(start 254.052832 -203.202032)
		(end 253.44755 -202.59675)
		(width 0.15494)
		(layer "In15.Cu")
		(net "UART_PEX2_CLI_BUF_RX")
	)
	(segment
		(start 204.942694 -207.728566)
		(end 194.317112 -218.354148)
		(width 0.15494)
		(layer "In15.Cu")
		(net "UART_PEX2_CLI_BUF_RX")
	)
	(segment
		(start 244.2972 -203.3524)
		(end 243.811298 -203.838302)
		(width 0.15494)
		(layer "In15.Cu")
		(net "UART_PEX2_CLI_BUF_RX")
	)
	(segment
		(start 181.598062 -214.76589)
		(end 145.408904 -214.76589)
		(width 0.15494)
		(layer "In15.Cu")
		(net "UART_PEX2_CLI_BUF_RX")
	)
	(segment
		(start 238.157258 -208.09585)
		(end 218.96451 -208.09585)
		(width 0.15494)
		(layer "In15.Cu")
		(net "UART_PEX2_CLI_BUF_RX")
	)
	(segment
		(start 257.572256 -201.86269)
		(end 256.232914 -203.202032)
		(width 0.15494)
		(layer "In15.Cu")
		(net "UART_PEX2_CLI_BUF_RX")
	)
	(segment
		(start 249.02795 -202.59675)
		(end 248.6914 -202.2602)
		(width 0.15494)
		(layer "In15.Cu")
		(net "UART_PEX2_CLI_BUF_RX")
	)
	(segment
		(start 244.2972 -202.6158)
		(end 244.2972 -203.3524)
		(width 0.15494)
		(layer "In15.Cu")
		(net "UART_PEX2_CLI_BUF_RX")
	)
	(segment
		(start 216.214452 -208.225898)
		(end 207.202278 -208.225898)
		(width 0.15494)
		(layer "In15.Cu")
		(net "UART_PEX2_CLI_BUF_RX")
	)
	(segment
		(start 218.80449 -208.25587)
		(end 216.244424 -208.25587)
		(width 0.15494)
		(layer "In15.Cu")
		(net "UART_PEX2_CLI_BUF_RX")
	)
	(segment
		(start 185.18632 -218.354148)
		(end 181.598062 -214.76589)
		(width 0.15494)
		(layer "In15.Cu")
		(net "UART_PEX2_CLI_BUF_RX")
	)
	(segment
		(start 284.724856 -307.774848)
		(end 285.199836 -308.249828)
		(width 0.13208)
		(layer "F.Cu")
		(net "TP_PEX2_TRST_L")
	)
	(via
		(at 287.099756 -308.249828)
		(size 0.6604)
		(drill 0.3302)
		(layers "F.Cu" "B.Cu")
		(net "TP_PEX2_TRST_L")
	)
	(via
		(at 284.724856 -307.774848)
		(size 0.4064)
		(drill 0.2032)
		(layers "F.Cu" "B.Cu")
		(net "TP_PEX2_TRST_L")
	)
	(segment
		(start 284.724856 -307.774848)
		(end 285.199836 -308.249828)
		(width 0.13208)
		(layer "B.Cu")
		(net "TP_PEX2_TRST_L")
	)
	(segment
		(start 288.804604 -308.324758)
		(end 289.08375 -308.324758)
		(width 0.13208)
		(layer "B.Cu")
		(net "TP_PEX2_TRST_L")
	)
	(segment
		(start 288.729674 -308.249828)
		(end 288.804604 -308.324758)
		(width 0.13208)
		(layer "B.Cu")
		(net "TP_PEX2_TRST_L")
	)
	(segment
		(start 285.199836 -308.249828)
		(end 287.099756 -308.249828)
		(width 0.13208)
		(layer "B.Cu")
		(net "TP_PEX2_TRST_L")
	)
	(segment
		(start 287.099756 -308.249828)
		(end 288.729674 -308.249828)
		(width 0.13208)
		(layer "B.Cu")
		(net "TP_PEX2_TRST_L")
	)
	(segment
		(start 356.707948 -85.514942)
		(end 354.80498 -85.514942)
		(width 0.13208)
		(layer "F.Cu")
		(net "SMB_BIC_I2C9_MUX1_SSD10_SDA")
	)
	(segment
		(start 354.514404 -85.224366)
		(end 354.220272 -84.930234)
		(width 0.13208)
		(layer "F.Cu")
		(net "SMB_BIC_I2C9_MUX1_SSD10_SDA")
	)
	(segment
		(start 354.220272 -84.930234)
		(end 353.320604 -84.930234)
		(width 0.13208)
		(layer "F.Cu")
		(net "SMB_BIC_I2C9_MUX1_SSD10_SDA")
	)
	(segment
		(start 354.516944 -85.224366)
		(end 354.514404 -85.224366)
		(width 0.13208)
		(layer "F.Cu")
		(net "SMB_BIC_I2C9_MUX1_SSD10_SDA")
	)
	(segment
		(start 354.516944 -85.226906)
		(end 354.516944 -85.224366)
		(width 0.13208)
		(layer "F.Cu")
		(net "SMB_BIC_I2C9_MUX1_SSD10_SDA")
	)
	(segment
		(start 354.80498 -85.514942)
		(end 354.516944 -85.226906)
		(width 0.13208)
		(layer "F.Cu")
		(net "SMB_BIC_I2C9_MUX1_SSD10_SDA")
	)
	(via
		(at 354.516944 -85.224366)
		(size 0.508)
		(drill 0.254)
		(layers "F.Cu" "B.Cu")
		(net "SMB_BIC_I2C9_MUX1_SSD10_SDA")
	)
	(segment
		(start 336.890106 -227.583238)
		(end 336.890106 -229.021894)
		(width 0.13208)
		(layer "F.Cu")
		(net "SSD2_PWR_EN")
	)
	(segment
		(start 336.493866 -227.186998)
		(end 336.890106 -227.583238)
		(width 0.13208)
		(layer "F.Cu")
		(net "SSD2_PWR_EN")
	)
	(segment
		(start 335.407 -230.505)
		(end 334.899 -230.505)
		(width 0.13208)
		(layer "F.Cu")
		(net "SSD2_PWR_EN")
	)
	(segment
		(start 334.899 -230.505)
		(end 333.883 -231.521)
		(width 0.13208)
		(layer "F.Cu")
		(net "SSD2_PWR_EN")
	)
	(segment
		(start 333.883 -231.521)
		(end 333.883 -233.66095)
		(width 0.13208)
		(layer "F.Cu")
		(net "SSD2_PWR_EN")
	)
	(segment
		(start 336.890106 -229.021894)
		(end 335.407 -230.505)
		(width 0.13208)
		(layer "F.Cu")
		(net "SSD2_PWR_EN")
	)
	(via
		(at 333.883 -231.521)
		(size 0.508)
		(drill 0.254)
		(layers "F.Cu" "B.Cu")
		(net "SSD2_PWR_EN")
	)
	(segment
		(start 372.875556 -54.144164)
		(end 373.05615 -53.96357)
		(width 0.13208)
		(layer "F.Cu")
		(net "P12V_SSD12_OCP")
	)
	(segment
		(start 373.05615 -53.96357)
		(end 373.454168 -53.96357)
		(width 0.13208)
		(layer "F.Cu")
		(net "P12V_SSD12_OCP")
	)
	(segment
		(start 374.064022 -53.96357)
		(end 373.454168 -53.96357)
		(width 0.13208)
		(layer "F.Cu")
		(net "P12V_SSD12_OCP")
	)
	(segment
		(start 372.447312 -54.144164)
		(end 372.875556 -54.144164)
		(width 0.13208)
		(layer "F.Cu")
		(net "P12V_SSD12_OCP")
	)
	(segment
		(start 374.167908 -54.067456)
		(end 374.064022 -53.96357)
		(width 0.13208)
		(layer "F.Cu")
		(net "P12V_SSD12_OCP")
	)
	(via
		(at 373.454168 -53.96357)
		(size 0.508)
		(drill 0.254)
		(layers "F.Cu" "B.Cu")
		(net "P12V_SSD12_OCP")
	)
	(segment
		(start 214.193374 -118.207028)
		(end 214.675466 -118.207028)
		(width 0.13208)
		(layer "F.Cu")
		(net "PWRGD_P3V3_NIC3")
	)
	(segment
		(start 213.449154 -119.271796)
		(end 214.100664 -118.620286)
		(width 0.13208)
		(layer "F.Cu")
		(net "PWRGD_P3V3_NIC3")
	)
	(segment
		(start 214.100664 -118.620286)
		(end 214.100664 -118.299738)
		(width 0.13208)
		(layer "F.Cu")
		(net "PWRGD_P3V3_NIC3")
	)
	(segment
		(start 214.100664 -118.299738)
		(end 214.193374 -118.207028)
		(width 0.13208)
		(layer "F.Cu")
		(net "PWRGD_P3V3_NIC3")
	)
	(segment
		(start 212.871304 -119.271796)
		(end 213.449154 -119.271796)
		(width 0.13208)
		(layer "F.Cu")
		(net "PWRGD_P3V3_NIC3")
	)
	(segment
		(start 214.675466 -119.223028)
		(end 214.675466 -118.207028)
		(width 0.13208)
		(layer "F.Cu")
		(net "PWRGD_P3V3_NIC3")
	)
	(via
		(at 214.100664 -118.620286)
		(size 0.508)
		(drill 0.254)
		(layers "F.Cu" "B.Cu")
		(net "PWRGD_P3V3_NIC3")
	)
	(segment
		(start 356.707948 -87.465154)
		(end 355.855016 -87.465154)
		(width 0.13208)
		(layer "F.Cu")
		(net "SMB_BIC_I2C9_MUX1_SSD8_SCL")
	)
	(segment
		(start 355.855016 -87.465154)
		(end 354.873306 -88.446864)
		(width 0.13208)
		(layer "F.Cu")
		(net "SMB_BIC_I2C9_MUX1_SSD8_SCL")
	)
	(segment
		(start 354.514404 -89.034366)
		(end 353.995736 -89.034366)
		(width 0.13208)
		(layer "F.Cu")
		(net "SMB_BIC_I2C9_MUX1_SSD8_SCL")
	)
	(segment
		(start 354.873306 -88.675464)
		(end 354.514404 -89.034366)
		(width 0.13208)
		(layer "F.Cu")
		(net "SMB_BIC_I2C9_MUX1_SSD8_SCL")
	)
	(segment
		(start 353.995736 -89.034366)
		(end 353.320604 -88.359234)
		(width 0.13208)
		(layer "F.Cu")
		(net "SMB_BIC_I2C9_MUX1_SSD8_SCL")
	)
	(segment
		(start 354.873306 -88.446864)
		(end 354.873306 -88.675464)
		(width 0.13208)
		(layer "F.Cu")
		(net "SMB_BIC_I2C9_MUX1_SSD8_SCL")
	)
	(via
		(at 354.514404 -89.034366)
		(size 0.508)
		(drill 0.254)
		(layers "F.Cu" "B.Cu")
		(net "SMB_BIC_I2C9_MUX1_SSD8_SCL")
	)
	(segment
		(start 276.515068 -407.372058)
		(end 276.849586 -407.372058)
		(width 0.13208)
		(layer "F.Cu")
		(net "RST_MB_BMC_BUF_N")
	)
	(segment
		(start 277.156672 -407.679144)
		(end 277.156672 -408.165046)
		(width 0.13208)
		(layer "F.Cu")
		(net "RST_MB_BMC_BUF_N")
	)
	(segment
		(start 276.388068 -407.499058)
		(end 276.515068 -407.372058)
		(width 0.13208)
		(layer "F.Cu")
		(net "RST_MB_BMC_BUF_N")
	)
	(segment
		(start 276.357334 -408.165046)
		(end 276.388068 -408.134312)
		(width 0.13208)
		(layer "F.Cu")
		(net "RST_MB_BMC_BUF_N")
	)
	(segment
		(start 276.849586 -407.372058)
		(end 277.156672 -407.679144)
		(width 0.13208)
		(layer "F.Cu")
		(net "RST_MB_BMC_BUF_N")
	)
	(segment
		(start 275.26869 -408.120342)
		(end 275.313394 -408.165046)
		(width 0.13208)
		(layer "F.Cu")
		(net "RST_MB_BMC_BUF_N")
	)
	(segment
		(start 275.313394 -408.165046)
		(end 276.357334 -408.165046)
		(width 0.13208)
		(layer "F.Cu")
		(net "RST_MB_BMC_BUF_N")
	)
	(segment
		(start 275.26869 -409.335986)
		(end 275.26869 -408.120342)
		(width 0.13208)
		(layer "F.Cu")
		(net "RST_MB_BMC_BUF_N")
	)
	(segment
		(start 276.388068 -408.134312)
		(end 276.388068 -407.499058)
		(width 0.13208)
		(layer "F.Cu")
		(net "RST_MB_BMC_BUF_N")
	)
	(via
		(at 276.357334 -408.165046)
		(size 0.508)
		(drill 0.254)
		(layers "F.Cu" "B.Cu")
		(net "RST_MB_BMC_BUF_N")
	)
	(segment
		(start 393.800584 -230.744014)
		(end 393.800584 -229.284784)
		(width 0.13208)
		(layer "F.Cu")
		(net "UART_PEX0_SDB_RX")
	)
	(segment
		(start 389.949944 -228.80955)
		(end 388.355586 -230.403908)
		(width 0.13208)
		(layer "F.Cu")
		(net "UART_PEX0_SDB_RX")
	)
	(segment
		(start 393.32535 -228.80955)
		(end 389.949944 -228.80955)
		(width 0.13208)
		(layer "F.Cu")
		(net "UART_PEX0_SDB_RX")
	)
	(segment
		(start 393.21232 -231.332278)
		(end 393.800584 -230.744014)
		(width 0.13208)
		(layer "F.Cu")
		(net "UART_PEX0_SDB_RX")
	)
	(segment
		(start 393.800584 -229.284784)
		(end 393.32535 -228.80955)
		(width 0.13208)
		(layer "F.Cu")
		(net "UART_PEX0_SDB_RX")
	)
	(segment
		(start 388.355586 -230.403908)
		(end 388.355586 -232.836212)
		(width 0.13208)
		(layer "F.Cu")
		(net "UART_PEX0_SDB_RX")
	)
	(via
		(at 393.21232 -231.332278)
		(size 0.508)
		(drill 0.254)
		(layers "F.Cu" "B.Cu")
		(net "UART_PEX0_SDB_RX")
	)
	(segment
		(start 390.450324 -230.703374)
		(end 387.35 -227.60305)
		(width 0.13208)
		(layer "B.Cu")
		(net "UART_PEX0_SDB_RX")
	)
	(segment
		(start 393.21232 -231.332278)
		(end 392.583416 -230.703374)
		(width 0.13208)
		(layer "B.Cu")
		(net "UART_PEX0_SDB_RX")
	)
	(segment
		(start 392.583416 -230.703374)
		(end 390.450324 -230.703374)
		(width 0.13208)
		(layer "B.Cu")
		(net "UART_PEX0_SDB_RX")
	)
	(segment
		(start 135.0137 -214.185754)
		(end 134.9629 -214.185754)
		(width 0.13208)
		(layer "F.Cu")
		(net "UART_PEX3_CLI_R_RX")
	)
	(segment
		(start 94.08541 -194.591432)
		(end 94.130368 -194.591432)
		(width 0.13208)
		(layer "F.Cu")
		(net "UART_PEX3_CLI_R_RX")
	)
	(segment
		(start 134.9629 -214.185754)
		(end 134.394194 -213.617048)
		(width 0.13208)
		(layer "F.Cu")
		(net "UART_PEX3_CLI_R_RX")
	)
	(segment
		(start 135.457946 -214.63)
		(end 135.0137 -214.185754)
		(width 0.13208)
		(layer "F.Cu")
		(net "UART_PEX3_CLI_R_RX")
	)
	(segment
		(start 136.4742 -214.0966)
		(end 135.9408 -214.63)
		(width 0.13208)
		(layer "F.Cu")
		(net "UART_PEX3_CLI_R_RX")
	)
	(segment
		(start 135.9408 -214.63)
		(end 135.457946 -214.63)
		(width 0.13208)
		(layer "F.Cu")
		(net "UART_PEX3_CLI_R_RX")
	)
	(segment
		(start 94.130368 -194.591432)
		(end 94.5388 -194.183)
		(width 0.13208)
		(layer "F.Cu")
		(net "UART_PEX3_CLI_R_RX")
	)
	(segment
		(start 70.602094 -216.6874)
		(end 68.5038 -216.6874)
		(width 0.13208)
		(layer "F.Cu")
		(net "UART_PEX3_CLI_R_RX")
	)
	(segment
		(start 71.247 -217.332306)
		(end 70.602094 -216.6874)
		(width 0.13208)
		(layer "F.Cu")
		(net "UART_PEX3_CLI_R_RX")
	)
	(segment
		(start 134.394194 -213.617048)
		(end 134.394194 -213.5378)
		(width 0.13208)
		(layer "F.Cu")
		(net "UART_PEX3_CLI_R_RX")
	)
	(segment
		(start 94.5388 -194.183)
		(end 95.074994 -194.183)
		(width 0.13208)
		(layer "F.Cu")
		(net "UART_PEX3_CLI_R_RX")
	)
	(via
		(at 136.4742 -214.0966)
		(size 0.508)
		(drill 0.254)
		(layers "F.Cu" "B.Cu")
		(net "UART_PEX3_CLI_R_RX")
	)
	(via
		(at 68.5038 -216.6874)
		(size 0.508)
		(drill 0.254)
		(layers "F.Cu" "B.Cu")
		(net "UART_PEX3_CLI_R_RX")
	)
	(via
		(at 91.108784 -196.978016)
		(size 0.6604)
		(drill 0.3302)
		(layers "F.Cu" "B.Cu")
		(net "UART_PEX3_CLI_R_RX")
	)
	(via
		(at 94.08541 -194.591432)
		(size 0.508)
		(drill 0.254)
		(layers "F.Cu" "B.Cu")
		(net "UART_PEX3_CLI_R_RX")
	)
	(segment
		(start 91.108784 -196.978016)
		(end 71.3994 -216.6874)
		(width 0.13208)
		(layer "B.Cu")
		(net "UART_PEX3_CLI_R_RX")
	)
	(segment
		(start 137.3124 -214.0966)
		(end 141.143228 -210.265772)
		(width 0.13208)
		(layer "B.Cu")
		(net "UART_PEX3_CLI_R_RX")
	)
	(segment
		(start 93.531182 -195.14566)
		(end 94.08541 -194.591432)
		(width 0.13208)
		(layer "B.Cu")
		(net "UART_PEX3_CLI_R_RX")
	)
	(segment
		(start 91.108784 -196.978016)
		(end 92.94114 -195.14566)
		(width 0.13208)
		(layer "B.Cu")
		(net "UART_PEX3_CLI_R_RX")
	)
	(segment
		(start 71.3994 -216.6874)
		(end 68.5038 -216.6874)
		(width 0.13208)
		(layer "B.Cu")
		(net "UART_PEX3_CLI_R_RX")
	)
	(segment
		(start 141.143228 -210.265772)
		(end 141.143228 -209.857848)
		(width 0.13208)
		(layer "B.Cu")
		(net "UART_PEX3_CLI_R_RX")
	)
	(segment
		(start 92.94114 -195.14566)
		(end 93.531182 -195.14566)
		(width 0.13208)
		(layer "B.Cu")
		(net "UART_PEX3_CLI_R_RX")
	)
	(segment
		(start 136.4742 -214.0966)
		(end 137.3124 -214.0966)
		(width 0.13208)
		(layer "B.Cu")
		(net "UART_PEX3_CLI_R_RX")
	)
	(segment
		(start 94.08541 -194.993768)
		(end 95.001842 -195.9102)
		(width 0.15494)
		(layer "In9.Cu")
		(net "UART_PEX3_CLI_R_RX")
	)
	(segment
		(start 110.236 -196.7484)
		(end 123.4948 -210.0072)
		(width 0.15494)
		(layer "In9.Cu")
		(net "UART_PEX3_CLI_R_RX")
	)
	(segment
		(start 130.5814 -210.0072)
		(end 133.5278 -212.9536)
		(width 0.15494)
		(layer "In9.Cu")
		(net "UART_PEX3_CLI_R_RX")
	)
	(segment
		(start 95.001842 -195.9102)
		(end 99.101148 -195.9102)
		(width 0.15494)
		(layer "In9.Cu")
		(net "UART_PEX3_CLI_R_RX")
	)
	(segment
		(start 133.5278 -212.9536)
		(end 135.3312 -212.9536)
		(width 0.15494)
		(layer "In9.Cu")
		(net "UART_PEX3_CLI_R_RX")
	)
	(segment
		(start 135.3312 -212.9536)
		(end 136.4742 -214.0966)
		(width 0.15494)
		(layer "In9.Cu")
		(net "UART_PEX3_CLI_R_RX")
	)
	(segment
		(start 99.101148 -195.9102)
		(end 99.939348 -196.7484)
		(width 0.15494)
		(layer "In9.Cu")
		(net "UART_PEX3_CLI_R_RX")
	)
	(segment
		(start 94.08541 -194.591432)
		(end 94.08541 -194.993768)
		(width 0.15494)
		(layer "In9.Cu")
		(net "UART_PEX3_CLI_R_RX")
	)
	(segment
		(start 99.939348 -196.7484)
		(end 110.236 -196.7484)
		(width 0.15494)
		(layer "In9.Cu")
		(net "UART_PEX3_CLI_R_RX")
	)
	(segment
		(start 123.4948 -210.0072)
		(end 130.5814 -210.0072)
		(width 0.15494)
		(layer "In9.Cu")
		(net "UART_PEX3_CLI_R_RX")
	)
	(segment
		(start 253.713488 -255.153414)
		(end 253.337568 -255.153414)
		(width 0.13208)
		(layer "F.Cu")
		(net "PEX2_SYS_ERR_R_N")
	)
	(segment
		(start 254.062992 -259.419344)
		(end 254.55372 -258.928616)
		(width 0.13208)
		(layer "F.Cu")
		(net "PEX2_SYS_ERR_R_N")
	)
	(segment
		(start 253.337568 -255.153414)
		(end 253.210568 -255.280414)
		(width 0.13208)
		(layer "F.Cu")
		(net "PEX2_SYS_ERR_R_N")
	)
	(segment
		(start 253.210568 -256.975102)
		(end 253.337568 -257.102102)
		(width 0.13208)
		(layer "F.Cu")
		(net "PEX2_SYS_ERR_R_N")
	)
	(segment
		(start 254.18161 -257.102102)
		(end 253.708408 -257.102102)
		(width 0.13208)
		(layer "F.Cu")
		(net "PEX2_SYS_ERR_R_N")
	)
	(segment
		(start 253.210568 -255.280414)
		(end 253.210568 -256.975102)
		(width 0.13208)
		(layer "F.Cu")
		(net "PEX2_SYS_ERR_R_N")
	)
	(segment
		(start 253.337568 -257.102102)
		(end 253.708408 -257.102102)
		(width 0.13208)
		(layer "F.Cu")
		(net "PEX2_SYS_ERR_R_N")
	)
	(segment
		(start 254.55372 -258.928616)
		(end 254.55372 -257.474212)
		(width 0.13208)
		(layer "F.Cu")
		(net "PEX2_SYS_ERR_R_N")
	)
	(segment
		(start 254.55372 -257.474212)
		(end 254.18161 -257.102102)
		(width 0.13208)
		(layer "F.Cu")
		(net "PEX2_SYS_ERR_R_N")
	)
	(via
		(at 254.55372 -257.474212)
		(size 0.508)
		(drill 0.254)
		(layers "F.Cu" "B.Cu")
		(net "PEX2_SYS_ERR_R_N")
	)
	(segment
		(start 421.249856 -299.699934)
		(end 420.774876 -299.224954)
		(width 0.254)
		(layer "F.Cu")
		(net "PEX3_ADCTEMP_VINP1")
	)
	(via
		(at 423.59834 -299.330618)
		(size 0.6604)
		(drill 0.3302)
		(layers "F.Cu" "B.Cu")
		(net "PEX3_ADCTEMP_VINP1")
	)
	(via
		(at 420.774876 -299.224954)
		(size 0.4064)
		(drill 0.2032)
		(layers "F.Cu" "B.Cu")
		(net "PEX3_ADCTEMP_VINP1")
	)
	(segment
		(start 422.326816 -299.62475)
		(end 423.304208 -299.62475)
		(width 0.13208)
		(layer "B.Cu")
		(net "PEX3_ADCTEMP_VINP1")
	)
	(segment
		(start 422.239186 -299.71238)
		(end 422.326816 -299.62475)
		(width 0.254)
		(layer "B.Cu")
		(net "PEX3_ADCTEMP_VINP1")
	)
	(segment
		(start 420.774876 -299.224954)
		(end 421.262302 -299.71238)
		(width 0.254)
		(layer "B.Cu")
		(net "PEX3_ADCTEMP_VINP1")
	)
	(segment
		(start 421.262302 -299.71238)
		(end 422.239186 -299.71238)
		(width 0.254)
		(layer "B.Cu")
		(net "PEX3_ADCTEMP_VINP1")
	)
	(segment
		(start 423.304208 -299.62475)
		(end 423.59834 -299.330618)
		(width 0.13208)
		(layer "B.Cu")
		(net "PEX3_ADCTEMP_VINP1")
	)
	(segment
		(start 353.8728 -81.501234)
		(end 353.320604 -81.501234)
		(width 0.13208)
		(layer "F.Cu")
		(net "SMB_BIC_I2C9_MUX1_SSD11_SCL")
	)
	(segment
		(start 355.80955 -83.564984)
		(end 355.610668 -83.366102)
		(width 0.13208)
		(layer "F.Cu")
		(net "SMB_BIC_I2C9_MUX1_SSD11_SCL")
	)
	(segment
		(start 356.707948 -83.564984)
		(end 355.80955 -83.564984)
		(width 0.13208)
		(layer "F.Cu")
		(net "SMB_BIC_I2C9_MUX1_SSD11_SCL")
	)
	(segment
		(start 354.514404 -81.414366)
		(end 353.959668 -81.414366)
		(width 0.13208)
		(layer "F.Cu")
		(net "SMB_BIC_I2C9_MUX1_SSD11_SCL")
	)
	(segment
		(start 355.610668 -83.366102)
		(end 355.610668 -82.51063)
		(width 0.13208)
		(layer "F.Cu")
		(net "SMB_BIC_I2C9_MUX1_SSD11_SCL")
	)
	(segment
		(start 353.959668 -81.414366)
		(end 353.8728 -81.501234)
		(width 0.13208)
		(layer "F.Cu")
		(net "SMB_BIC_I2C9_MUX1_SSD11_SCL")
	)
	(segment
		(start 355.610668 -82.51063)
		(end 354.514404 -81.414366)
		(width 0.13208)
		(layer "F.Cu")
		(net "SMB_BIC_I2C9_MUX1_SSD11_SCL")
	)
	(via
		(at 354.514404 -81.414366)
		(size 0.508)
		(drill 0.254)
		(layers "F.Cu" "B.Cu")
		(net "SMB_BIC_I2C9_MUX1_SSD11_SCL")
	)
	(segment
		(start 257.801364 -53.051456)
		(end 258.06781 -53.051456)
		(width 0.13208)
		(layer "F.Cu")
		(net "PWRGD_P12V_SSD8")
	)
	(segment
		(start 258.06781 -52.035456)
		(end 258.06781 -53.051456)
		(width 0.13208)
		(layer "F.Cu")
		(net "PWRGD_P12V_SSD8")
	)
	(segment
		(start 256.716276 -53.644038)
		(end 257.337306 -53.023008)
		(width 0.13208)
		(layer "F.Cu")
		(net "PWRGD_P12V_SSD8")
	)
	(segment
		(start 256.347214 -53.644038)
		(end 256.716276 -53.644038)
		(width 0.13208)
		(layer "F.Cu")
		(net "PWRGD_P12V_SSD8")
	)
	(segment
		(start 257.337306 -53.023008)
		(end 257.337306 -52.587398)
		(width 0.13208)
		(layer "F.Cu")
		(net "PWRGD_P12V_SSD8")
	)
	(segment
		(start 257.337306 -52.587398)
		(end 257.801364 -53.051456)
		(width 0.13208)
		(layer "F.Cu")
		(net "PWRGD_P12V_SSD8")
	)
	(via
		(at 257.337306 -52.587398)
		(size 0.508)
		(drill 0.254)
		(layers "F.Cu" "B.Cu")
		(net "PWRGD_P12V_SSD8")
	)
	(segment
		(start 135.806688 -211.129372)
		(end 135.806688 -211.93887)
		(width 0.13208)
		(layer "F.Cu")
		(net "UART_PEX3_CLI_RX")
	)
	(segment
		(start 135.194294 -213.11616)
		(end 135.194294 -213.5378)
		(width 0.13208)
		(layer "F.Cu")
		(net "UART_PEX3_CLI_RX")
	)
	(segment
		(start 135.806688 -211.93887)
		(end 135.806688 -212.503766)
		(width 0.13208)
		(layer "F.Cu")
		(net "UART_PEX3_CLI_RX")
	)
	(segment
		(start 135.806688 -212.503766)
		(end 135.194294 -213.11616)
		(width 0.13208)
		(layer "F.Cu")
		(net "UART_PEX3_CLI_RX")
	)
	(segment
		(start 138.364214 -209.079846)
		(end 137.856214 -209.079846)
		(width 0.13208)
		(layer "F.Cu")
		(net "UART_PEX3_CLI_RX")
	)
	(segment
		(start 137.856214 -209.079846)
		(end 135.806688 -211.129372)
		(width 0.13208)
		(layer "F.Cu")
		(net "UART_PEX3_CLI_RX")
	)
	(via
		(at 138.364214 -209.079846)
		(size 0.508)
		(drill 0.254)
		(layers "F.Cu" "B.Cu")
		(net "UART_PEX3_CLI_RX")
	)
	(via
		(at 101.207824 -337.937856)
		(size 0.6604)
		(drill 0.3302)
		(layers "F.Cu" "B.Cu")
		(net "P3V3_CLK_BUFFER_9ZXL0451E_VZX3P3")
	)
	(via
		(at 112.849152 -333.855314)
		(size 0.508)
		(drill 0.254)
		(layers "F.Cu" "B.Cu")
		(net "P3V3_CLK_BUFFER_9ZXL0451E_VZX3P3")
	)
	(via
		(at 101.856794 -332.043532)
		(size 0.508)
		(drill 0.254)
		(layers "F.Cu" "B.Cu")
		(net "P3V3_CLK_BUFFER_9ZXL0451E_VZX3P3")
	)
	(via
		(at 102.564692 -331.688186)
		(size 0.6604)
		(drill 0.3302)
		(layers "F.Cu" "B.Cu")
		(net "P3V3_CLK_BUFFER_9ZXL0451E_VZX3P3")
	)
	(via
		(at 105.035604 -327.390252)
		(size 0.508)
		(drill 0.254)
		(layers "F.Cu" "B.Cu")
		(net "P3V3_CLK_BUFFER_9ZXL0451E_VZX3P3")
	)
	(via
		(at 103.572818 -328.218292)
		(size 0.508)
		(drill 0.254)
		(layers "F.Cu" "B.Cu")
		(net "P3V3_CLK_BUFFER_9ZXL0451E_VZX3P3")
	)
	(via
		(at 102.849934 -335.742026)
		(size 0.508)
		(drill 0.254)
		(layers "F.Cu" "B.Cu")
		(net "P3V3_CLK_BUFFER_9ZXL0451E_VZX3P3")
	)
	(via
		(at 102.353618 -335.23301)
		(size 0.508)
		(drill 0.254)
		(layers "F.Cu" "B.Cu")
		(net "P3V3_CLK_BUFFER_9ZXL0451E_VZX3P3")
	)
	(via
		(at 106.674158 -327.366122)
		(size 0.508)
		(drill 0.254)
		(layers "F.Cu" "B.Cu")
		(net "P3V3_CLK_BUFFER_9ZXL0451E_VZX3P3")
	)
	(via
		(at 113.880646 -333.855314)
		(size 0.6604)
		(drill 0.3302)
		(layers "F.Cu" "B.Cu")
		(net "P3V3_CLK_BUFFER_9ZXL0451E_VZX3P3")
	)
	(via
		(at 103.94188 -334.141064)
		(size 0.508)
		(drill 0.254)
		(layers "F.Cu" "B.Cu")
		(net "P3V3_CLK_BUFFER_9ZXL0451E_VZX3P3")
	)
	(via
		(at 106.56443 -334.701388)
		(size 0.508)
		(drill 0.254)
		(layers "F.Cu" "B.Cu")
		(net "P3V3_CLK_BUFFER_9ZXL0451E_VZX3P3")
	)
	(via
		(at 103.831898 -335.73593)
		(size 0.508)
		(drill 0.254)
		(layers "F.Cu" "B.Cu")
		(net "P3V3_CLK_BUFFER_9ZXL0451E_VZX3P3")
	)
	(segment
		(start 112.013492 -333.855314)
		(end 112.849152 -333.855314)
		(width 0.381)
		(layer "B.Cu")
		(net "P3V3_CLK_BUFFER_9ZXL0451E_VZX3P3")
	)
	(segment
		(start 104.359964 -327.390252)
		(end 103.707692 -327.390252)
		(width 0.508)
		(layer "B.Cu")
		(net "P3V3_CLK_BUFFER_9ZXL0451E_VZX3P3")
	)
	(segment
		(start 103.572818 -327.525126)
		(end 103.572818 -328.218292)
		(width 0.508)
		(layer "B.Cu")
		(net "P3V3_CLK_BUFFER_9ZXL0451E_VZX3P3")
	)
	(segment
		(start 107.297728 -327.366122)
		(end 107.297728 -327.891902)
		(width 0.254)
		(layer "B.Cu")
		(net "P3V3_CLK_BUFFER_9ZXL0451E_VZX3P3")
	)
	(segment
		(start 104.359964 -328.452734)
		(end 104.359964 -327.390252)
		(width 0.508)
		(layer "B.Cu")
		(net "P3V3_CLK_BUFFER_9ZXL0451E_VZX3P3")
	)
	(segment
		(start 104.359964 -328.971148)
		(end 104.359964 -328.452734)
		(width 0.254)
		(layer "B.Cu")
		(net "P3V3_CLK_BUFFER_9ZXL0451E_VZX3P3")
	)
	(segment
		(start 106.674158 -327.366122)
		(end 107.297728 -327.366122)
		(width 0.3048)
		(layer "B.Cu")
		(net "P3V3_CLK_BUFFER_9ZXL0451E_VZX3P3")
	)
	(segment
		(start 105.035604 -327.390252)
		(end 104.359964 -327.390252)
		(width 0.508)
		(layer "B.Cu")
		(net "P3V3_CLK_BUFFER_9ZXL0451E_VZX3P3")
	)
	(segment
		(start 102.564692 -331.688186)
		(end 102.21214 -331.688186)
		(width 0.508)
		(layer "B.Cu")
		(net "P3V3_CLK_BUFFER_9ZXL0451E_VZX3P3")
	)
	(segment
		(start 107.297728 -327.891902)
		(end 106.56443 -328.6252)
		(width 0.254)
		(layer "B.Cu")
		(net "P3V3_CLK_BUFFER_9ZXL0451E_VZX3P3")
	)
	(segment
		(start 112.849152 -333.855314)
		(end 113.880646 -333.855314)
		(width 0.13208)
		(layer "B.Cu")
		(net "P3V3_CLK_BUFFER_9ZXL0451E_VZX3P3")
	)
	(segment
		(start 102.21214 -331.688186)
		(end 101.856794 -332.043532)
		(width 0.508)
		(layer "B.Cu")
		(net "P3V3_CLK_BUFFER_9ZXL0451E_VZX3P3")
	)
	(segment
		(start 101.112066 -332.038452)
		(end 101.851714 -332.038452)
		(width 0.508)
		(layer "B.Cu")
		(net "P3V3_CLK_BUFFER_9ZXL0451E_VZX3P3")
	)
	(segment
		(start 104.564434 -329.175618)
		(end 104.359964 -328.971148)
		(width 0.254)
		(layer "B.Cu")
		(net "P3V3_CLK_BUFFER_9ZXL0451E_VZX3P3")
	)
	(segment
		(start 106.56443 -328.6252)
		(end 106.56443 -329.175618)
		(width 0.254)
		(layer "B.Cu")
		(net "P3V3_CLK_BUFFER_9ZXL0451E_VZX3P3")
	)
	(segment
		(start 101.207824 -336.53095)
		(end 101.207824 -337.937856)
		(width 0.13208)
		(layer "B.Cu")
		(net "P3V3_CLK_BUFFER_9ZXL0451E_VZX3P3")
	)
	(segment
		(start 103.939594 -331.800454)
		(end 102.67696 -331.800454)
		(width 0.254)
		(layer "B.Cu")
		(net "P3V3_CLK_BUFFER_9ZXL0451E_VZX3P3")
	)
	(segment
		(start 101.851714 -332.038452)
		(end 101.856794 -332.043532)
		(width 0.508)
		(layer "B.Cu")
		(net "P3V3_CLK_BUFFER_9ZXL0451E_VZX3P3")
	)
	(segment
		(start 106.56443 -333.925418)
		(end 106.56443 -334.701388)
		(width 0.254)
		(layer "B.Cu")
		(net "P3V3_CLK_BUFFER_9ZXL0451E_VZX3P3")
	)
	(segment
		(start 102.67696 -331.800454)
		(end 102.564692 -331.688186)
		(width 0.254)
		(layer "B.Cu")
		(net "P3V3_CLK_BUFFER_9ZXL0451E_VZX3P3")
	)
	(segment
		(start 103.707692 -327.390252)
		(end 103.572818 -327.525126)
		(width 0.508)
		(layer "B.Cu")
		(net "P3V3_CLK_BUFFER_9ZXL0451E_VZX3P3")
	)
	(segment
		(start 259.590286 -251.956824)
		(end 259.590286 -251.158502)
		(width 0.13208)
		(layer "F.Cu")
		(net "PEX2_MODE_SEL5")
	)
	(segment
		(start 291.84981 -282.599892)
		(end 292.32479 -283.074872)
		(width 0.1651)
		(layer "F.Cu")
		(net "PEX2_MODE_SEL5")
	)
	(segment
		(start 259.590286 -251.158502)
		(end 259.590286 -250.470924)
		(width 0.13208)
		(layer "F.Cu")
		(net "PEX2_MODE_SEL5")
	)
	(via
		(at 292.32479 -283.074872)
		(size 0.4064)
		(drill 0.2032)
		(layers "F.Cu" "B.Cu")
		(net "PEX2_MODE_SEL5")
	)
	(via
		(at 259.590286 -251.158502)
		(size 0.508)
		(drill 0.254)
		(layers "F.Cu" "B.Cu")
		(net "PEX2_MODE_SEL5")
	)
	(via
		(at 289.138868 -268.21765)
		(size 0.6604)
		(drill 0.3302)
		(layers "F.Cu" "B.Cu")
		(net "PEX2_MODE_SEL5")
	)
	(segment
		(start 259.590286 -251.158502)
		(end 259.097526 -251.651262)
		(width 0.13208)
		(layer "B.Cu")
		(net "PEX2_MODE_SEL5")
	)
	(segment
		(start 265.081512 -257.321558)
		(end 266.107418 -258.347464)
		(width 0.13208)
		(layer "B.Cu")
		(net "PEX2_MODE_SEL5")
	)
	(segment
		(start 292.32479 -271.403572)
		(end 292.32479 -283.074872)
		(width 0.13208)
		(layer "B.Cu")
		(net "PEX2_MODE_SEL5")
	)
	(segment
		(start 259.494274 -254.395478)
		(end 260.408928 -254.395478)
		(width 0.13208)
		(layer "B.Cu")
		(net "PEX2_MODE_SEL5")
	)
	(segment
		(start 259.097526 -253.99873)
		(end 259.494274 -254.395478)
		(width 0.13208)
		(layer "B.Cu")
		(net "PEX2_MODE_SEL5")
	)
	(segment
		(start 279.268682 -258.347464)
		(end 289.138868 -268.21765)
		(width 0.13208)
		(layer "B.Cu")
		(net "PEX2_MODE_SEL5")
	)
	(segment
		(start 262.132318 -257.098292)
		(end 262.355584 -257.321558)
		(width 0.13208)
		(layer "B.Cu")
		(net "PEX2_MODE_SEL5")
	)
	(segment
		(start 289.138868 -268.21765)
		(end 292.32479 -271.403572)
		(width 0.13208)
		(layer "B.Cu")
		(net "PEX2_MODE_SEL5")
	)
	(segment
		(start 262.355584 -257.321558)
		(end 265.081512 -257.321558)
		(width 0.13208)
		(layer "B.Cu")
		(net "PEX2_MODE_SEL5")
	)
	(segment
		(start 266.107418 -258.347464)
		(end 279.268682 -258.347464)
		(width 0.13208)
		(layer "B.Cu")
		(net "PEX2_MODE_SEL5")
	)
	(segment
		(start 260.408928 -254.395478)
		(end 262.132318 -256.118868)
		(width 0.13208)
		(layer "B.Cu")
		(net "PEX2_MODE_SEL5")
	)
	(segment
		(start 259.097526 -251.651262)
		(end 259.097526 -253.99873)
		(width 0.13208)
		(layer "B.Cu")
		(net "PEX2_MODE_SEL5")
	)
	(segment
		(start 262.132318 -256.118868)
		(end 262.132318 -257.098292)
		(width 0.13208)
		(layer "B.Cu")
		(net "PEX2_MODE_SEL5")
	)
	(segment
		(start 421.249856 -300.649894)
		(end 421.724836 -300.174914)
		(width 0.254)
		(layer "F.Cu")
		(net "PEX3_ADCTEMP_VINP0")
	)
	(via
		(at 423.487088 -301.120556)
		(size 0.6604)
		(drill 0.3302)
		(layers "F.Cu" "B.Cu")
		(net "PEX3_ADCTEMP_VINP0")
	)
	(via
		(at 421.724836 -300.174914)
		(size 0.4064)
		(drill 0.2032)
		(layers "F.Cu" "B.Cu")
		(net "PEX3_ADCTEMP_VINP0")
	)
	(segment
		(start 422.274746 -300.724824)
		(end 422.326816 -300.724824)
		(width 0.254)
		(layer "B.Cu")
		(net "PEX3_ADCTEMP_VINP0")
	)
	(segment
		(start 423.091356 -300.724824)
		(end 422.326816 -300.724824)
		(width 0.13208)
		(layer "B.Cu")
		(net "PEX3_ADCTEMP_VINP0")
	)
	(segment
		(start 421.724836 -300.174914)
		(end 422.274746 -300.724824)
		(width 0.254)
		(layer "B.Cu")
		(net "PEX3_ADCTEMP_VINP0")
	)
	(segment
		(start 423.487088 -301.120556)
		(end 423.091356 -300.724824)
		(width 0.13208)
		(layer "B.Cu")
		(net "PEX3_ADCTEMP_VINP0")
	)
	(segment
		(start 259.135626 -21.570696)
		(end 259.135626 -20.789392)
		(width 0.13208)
		(layer "F.Cu")
		(net "SMB_BIC_I2C9_MUX1_SSD8_R_SDA")
	)
	(segment
		(start 350.780604 -89.502234)
		(end 351.60331 -89.502234)
		(width 0.13208)
		(layer "F.Cu")
		(net "SMB_BIC_I2C9_MUX1_SSD8_R_SDA")
	)
	(segment
		(start 351.60331 -89.502234)
		(end 352.520504 -89.502234)
		(width 0.13208)
		(layer "F.Cu")
		(net "SMB_BIC_I2C9_MUX1_SSD8_R_SDA")
	)
	(segment
		(start 259.662422 -22.097492)
		(end 259.420614 -21.855684)
		(width 0.13208)
		(layer "F.Cu")
		(net "SMB_BIC_I2C9_MUX1_SSD8_R_SDA")
	)
	(segment
		(start 259.662422 -22.537166)
		(end 259.662422 -22.097492)
		(width 0.13208)
		(layer "F.Cu")
		(net "SMB_BIC_I2C9_MUX1_SSD8_R_SDA")
	)
	(segment
		(start 259.420614 -21.855684)
		(end 259.135626 -21.570696)
		(width 0.13208)
		(layer "F.Cu")
		(net "SMB_BIC_I2C9_MUX1_SSD8_R_SDA")
	)
	(via
		(at 259.420614 -21.855684)
		(size 0.508)
		(drill 0.254)
		(layers "F.Cu" "B.Cu")
		(net "SMB_BIC_I2C9_MUX1_SSD8_R_SDA")
	)
	(via
		(at 351.60331 -89.502234)
		(size 0.508)
		(drill 0.254)
		(layers "F.Cu" "B.Cu")
		(net "SMB_BIC_I2C9_MUX1_SSD8_R_SDA")
	)
	(via
		(at 267.156184 -71.11111)
		(size 0.508)
		(drill 0.254)
		(layers "F.Cu" "B.Cu")
		(net "SMB_BIC_I2C9_MUX1_SSD8_R_SDA")
	)
	(segment
		(start 289.774122 -84.085176)
		(end 299.918882 -84.085176)
		(width 0.13208)
		(layer "B.Cu")
		(net "SMB_BIC_I2C9_MUX1_SSD8_R_SDA")
	)
	(segment
		(start 350.684592 -91.9734)
		(end 350.684592 -90.420952)
		(width 0.13208)
		(layer "B.Cu")
		(net "SMB_BIC_I2C9_MUX1_SSD8_R_SDA")
	)
	(segment
		(start 276.769068 -77.164184)
		(end 280.655522 -81.050638)
		(width 0.13208)
		(layer "B.Cu")
		(net "SMB_BIC_I2C9_MUX1_SSD8_R_SDA")
	)
	(segment
		(start 349.960438 -92.697554)
		(end 350.684592 -91.9734)
		(width 0.13208)
		(layer "B.Cu")
		(net "SMB_BIC_I2C9_MUX1_SSD8_R_SDA")
	)
	(segment
		(start 306.914042 -83.5406)
		(end 312.374788 -83.5406)
		(width 0.13208)
		(layer "B.Cu")
		(net "SMB_BIC_I2C9_MUX1_SSD8_R_SDA")
	)
	(segment
		(start 286.739584 -81.050638)
		(end 289.774122 -84.085176)
		(width 0.13208)
		(layer "B.Cu")
		(net "SMB_BIC_I2C9_MUX1_SSD8_R_SDA")
	)
	(segment
		(start 334.607408 -92.697554)
		(end 349.960438 -92.697554)
		(width 0.13208)
		(layer "B.Cu")
		(net "SMB_BIC_I2C9_MUX1_SSD8_R_SDA")
	)
	(segment
		(start 272.389854 -75.4634)
		(end 274.3454 -75.4634)
		(width 0.13208)
		(layer "B.Cu")
		(net "SMB_BIC_I2C9_MUX1_SSD8_R_SDA")
	)
	(segment
		(start 317.403988 -88.5698)
		(end 326.3646 -88.5698)
		(width 0.13208)
		(layer "B.Cu")
		(net "SMB_BIC_I2C9_MUX1_SSD8_R_SDA")
	)
	(segment
		(start 280.655522 -81.050638)
		(end 286.739584 -81.050638)
		(width 0.13208)
		(layer "B.Cu")
		(net "SMB_BIC_I2C9_MUX1_SSD8_R_SDA")
	)
	(segment
		(start 326.3646 -88.5698)
		(end 327.2028 -89.408)
		(width 0.13208)
		(layer "B.Cu")
		(net "SMB_BIC_I2C9_MUX1_SSD8_R_SDA")
	)
	(segment
		(start 268.4526 -71.526146)
		(end 272.389854 -75.4634)
		(width 0.13208)
		(layer "B.Cu")
		(net "SMB_BIC_I2C9_MUX1_SSD8_R_SDA")
	)
	(segment
		(start 299.918882 -84.085176)
		(end 300.184058 -83.82)
		(width 0.13208)
		(layer "B.Cu")
		(net "SMB_BIC_I2C9_MUX1_SSD8_R_SDA")
	)
	(segment
		(start 327.2028 -89.408)
		(end 329.1078 -89.408)
		(width 0.13208)
		(layer "B.Cu")
		(net "SMB_BIC_I2C9_MUX1_SSD8_R_SDA")
	)
	(segment
		(start 350.684592 -90.420952)
		(end 351.60331 -89.502234)
		(width 0.13208)
		(layer "B.Cu")
		(net "SMB_BIC_I2C9_MUX1_SSD8_R_SDA")
	)
	(segment
		(start 300.184058 -83.82)
		(end 306.634642 -83.82)
		(width 0.13208)
		(layer "B.Cu")
		(net "SMB_BIC_I2C9_MUX1_SSD8_R_SDA")
	)
	(segment
		(start 267.57122 -71.526146)
		(end 268.4526 -71.526146)
		(width 0.13208)
		(layer "B.Cu")
		(net "SMB_BIC_I2C9_MUX1_SSD8_R_SDA")
	)
	(segment
		(start 306.634642 -83.82)
		(end 306.914042 -83.5406)
		(width 0.13208)
		(layer "B.Cu")
		(net "SMB_BIC_I2C9_MUX1_SSD8_R_SDA")
	)
	(segment
		(start 329.8444 -88.6714)
		(end 330.581254 -88.6714)
		(width 0.13208)
		(layer "B.Cu")
		(net "SMB_BIC_I2C9_MUX1_SSD8_R_SDA")
	)
	(segment
		(start 274.3454 -75.4634)
		(end 276.046184 -77.164184)
		(width 0.13208)
		(layer "B.Cu")
		(net "SMB_BIC_I2C9_MUX1_SSD8_R_SDA")
	)
	(segment
		(start 267.156184 -71.11111)
		(end 267.57122 -71.526146)
		(width 0.13208)
		(layer "B.Cu")
		(net "SMB_BIC_I2C9_MUX1_SSD8_R_SDA")
	)
	(segment
		(start 312.374788 -83.5406)
		(end 317.403988 -88.5698)
		(width 0.13208)
		(layer "B.Cu")
		(net "SMB_BIC_I2C9_MUX1_SSD8_R_SDA")
	)
	(segment
		(start 276.046184 -77.164184)
		(end 276.769068 -77.164184)
		(width 0.13208)
		(layer "B.Cu")
		(net "SMB_BIC_I2C9_MUX1_SSD8_R_SDA")
	)
	(segment
		(start 329.1078 -89.408)
		(end 329.8444 -88.6714)
		(width 0.13208)
		(layer "B.Cu")
		(net "SMB_BIC_I2C9_MUX1_SSD8_R_SDA")
	)
	(segment
		(start 330.581254 -88.6714)
		(end 334.607408 -92.697554)
		(width 0.13208)
		(layer "B.Cu")
		(net "SMB_BIC_I2C9_MUX1_SSD8_R_SDA")
	)
	(segment
		(start 256.456942 -27.223466)
		(end 256.456942 -22.049994)
		(width 0.15494)
		(layer "In5.Cu")
		(net "SMB_BIC_I2C9_MUX1_SSD8_R_SDA")
	)
	(segment
		(start 267.156184 -71.11111)
		(end 269.389352 -68.877942)
		(width 0.15494)
		(layer "In5.Cu")
		(net "SMB_BIC_I2C9_MUX1_SSD8_R_SDA")
	)
	(segment
		(start 256.50444 -32.511492)
		(end 256.50444 -30.054042)
		(width 0.15494)
		(layer "In5.Cu")
		(net "SMB_BIC_I2C9_MUX1_SSD8_R_SDA")
	)
	(segment
		(start 256.50444 -30.054042)
		(end 257.331718 -29.226764)
		(width 0.15494)
		(layer "In5.Cu")
		(net "SMB_BIC_I2C9_MUX1_SSD8_R_SDA")
	)
	(segment
		(start 269.389352 -45.396404)
		(end 256.50444 -32.511492)
		(width 0.15494)
		(layer "In5.Cu")
		(net "SMB_BIC_I2C9_MUX1_SSD8_R_SDA")
	)
	(segment
		(start 257.331718 -28.098242)
		(end 256.456942 -27.223466)
		(width 0.15494)
		(layer "In5.Cu")
		(net "SMB_BIC_I2C9_MUX1_SSD8_R_SDA")
	)
	(segment
		(start 258.840732 -21.275802)
		(end 259.420614 -21.855684)
		(width 0.15494)
		(layer "In5.Cu")
		(net "SMB_BIC_I2C9_MUX1_SSD8_R_SDA")
	)
	(segment
		(start 256.456942 -22.049994)
		(end 257.231134 -21.275802)
		(width 0.15494)
		(layer "In5.Cu")
		(net "SMB_BIC_I2C9_MUX1_SSD8_R_SDA")
	)
	(segment
		(start 257.231134 -21.275802)
		(end 258.840732 -21.275802)
		(width 0.15494)
		(layer "In5.Cu")
		(net "SMB_BIC_I2C9_MUX1_SSD8_R_SDA")
	)
	(segment
		(start 257.331718 -29.226764)
		(end 257.331718 -28.098242)
		(width 0.15494)
		(layer "In5.Cu")
		(net "SMB_BIC_I2C9_MUX1_SSD8_R_SDA")
	)
	(segment
		(start 269.389352 -68.877942)
		(end 269.389352 -45.396404)
		(width 0.15494)
		(layer "In5.Cu")
		(net "SMB_BIC_I2C9_MUX1_SSD8_R_SDA")
	)
	(segment
		(start 279.121616 -406.943052)
		(end 278.671528 -406.943052)
		(width 0.13208)
		(layer "F.Cu")
		(net "MB_BIC_MON_BUF")
	)
	(segment
		(start 278.456898 -407.157682)
		(end 278.456898 -408.165046)
		(width 0.13208)
		(layer "F.Cu")
		(net "MB_BIC_MON_BUF")
	)
	(segment
		(start 280.137616 -405.474424)
		(end 279.121616 -405.474424)
		(width 0.13208)
		(layer "F.Cu")
		(net "MB_BIC_MON_BUF")
	)
	(segment
		(start 278.671528 -406.943052)
		(end 278.456898 -407.157682)
		(width 0.13208)
		(layer "F.Cu")
		(net "MB_BIC_MON_BUF")
	)
	(segment
		(start 279.121616 -405.474424)
		(end 279.121616 -406.943052)
		(width 0.13208)
		(layer "F.Cu")
		(net "MB_BIC_MON_BUF")
	)
	(via
		(at 279.121616 -406.943052)
		(size 0.508)
		(drill 0.254)
		(layers "F.Cu" "B.Cu")
		(net "MB_BIC_MON_BUF")
	)
	(segment
		(start 342.093804 -225.587052)
		(end 341.694008 -225.986848)
		(width 0.13208)
		(layer "F.Cu")
		(net "SSD1_CLK_EN_N")
	)
	(via
		(at 341.694008 -225.986848)
		(size 0.4572)
		(drill 0.254)
		(layers "F.Cu" "B.Cu")
		(net "SSD1_CLK_EN_N")
	)
	(via
		(at 339.979 -231.902)
		(size 0.6604)
		(drill 0.3302)
		(layers "F.Cu" "B.Cu")
		(net "SSD1_CLK_EN_N")
	)
	(segment
		(start 339.979 -233.15295)
		(end 339.979 -231.902)
		(width 0.13208)
		(layer "B.Cu")
		(net "SSD1_CLK_EN_N")
	)
	(segment
		(start 340.464902 -231.372918)
		(end 340.464902 -231.416098)
		(width 0.13208)
		(layer "B.Cu")
		(net "SSD1_CLK_EN_N")
	)
	(segment
		(start 341.293196 -227.450396)
		(end 341.5284 -227.6856)
		(width 0.13208)
		(layer "B.Cu")
		(net "SSD1_CLK_EN_N")
	)
	(segment
		(start 341.694008 -225.986848)
		(end 341.293196 -226.38766)
		(width 0.0889)
		(layer "B.Cu")
		(net "SSD1_CLK_EN_N")
	)
	(segment
		(start 341.5284 -230.30942)
		(end 340.464902 -231.372918)
		(width 0.13208)
		(layer "B.Cu")
		(net "SSD1_CLK_EN_N")
	)
	(segment
		(start 341.293196 -226.38766)
		(end 341.293196 -227.450396)
		(width 0.0889)
		(layer "B.Cu")
		(net "SSD1_CLK_EN_N")
	)
	(segment
		(start 340.464902 -231.416098)
		(end 339.979 -231.902)
		(width 0.13208)
		(layer "B.Cu")
		(net "SSD1_CLK_EN_N")
	)
	(segment
		(start 341.5284 -227.6856)
		(end 341.5284 -230.30942)
		(width 0.13208)
		(layer "B.Cu")
		(net "SSD1_CLK_EN_N")
	)
	(via
		(at 108.37291 -336.632042)
		(size 0.508)
		(drill 0.254)
		(layers "F.Cu" "B.Cu")
		(net "P3V3_CLK_BUFFER_9ZXL0451E_VZX3P3A")
	)
	(via
		(at 109.10062 -336.562954)
		(size 0.508)
		(drill 0.254)
		(layers "F.Cu" "B.Cu")
		(net "P3V3_CLK_BUFFER_9ZXL0451E_VZX3P3A")
	)
	(via
		(at 107.35691 -336.632042)
		(size 0.508)
		(drill 0.254)
		(layers "F.Cu" "B.Cu")
		(net "P3V3_CLK_BUFFER_9ZXL0451E_VZX3P3A")
	)
	(via
		(at 109.694218 -334.186784)
		(size 0.508)
		(drill 0.254)
		(layers "F.Cu" "B.Cu")
		(net "P3V3_CLK_BUFFER_9ZXL0451E_VZX3P3A")
	)
	(via
		(at 106.914188 -335.433416)
		(size 0.6604)
		(drill 0.3302)
		(layers "F.Cu" "B.Cu")
		(net "P3V3_CLK_BUFFER_9ZXL0451E_VZX3P3A")
	)
	(segment
		(start 107.564428 -333.925418)
		(end 107.564428 -334.612488)
		(width 0.254)
		(layer "B.Cu")
		(net "P3V3_CLK_BUFFER_9ZXL0451E_VZX3P3A")
	)
	(segment
		(start 110.552992 -333.842614)
		(end 110.552992 -332.70571)
		(width 0.254)
		(layer "B.Cu")
		(net "P3V3_CLK_BUFFER_9ZXL0451E_VZX3P3A")
	)
	(segment
		(start 110.540292 -333.855314)
		(end 110.552992 -333.842614)
		(width 0.254)
		(layer "B.Cu")
		(net "P3V3_CLK_BUFFER_9ZXL0451E_VZX3P3A")
	)
	(segment
		(start 108.248196 -338.164424)
		(end 108.950506 -337.462114)
		(width 0.508)
		(layer "B.Cu")
		(net "P3V3_CLK_BUFFER_9ZXL0451E_VZX3P3A")
	)
	(segment
		(start 108.13415 -338.164424)
		(end 107.883706 -337.91398)
		(width 0.508)
		(layer "B.Cu")
		(net "P3V3_CLK_BUFFER_9ZXL0451E_VZX3P3A")
	)
	(segment
		(start 107.883706 -335.616042)
		(end 108.046012 -335.453736)
		(width 0.508)
		(layer "B.Cu")
		(net "P3V3_CLK_BUFFER_9ZXL0451E_VZX3P3A")
	)
	(segment
		(start 110.540292 -333.855314)
		(end 110.208822 -334.186784)
		(width 0.381)
		(layer "B.Cu")
		(net "P3V3_CLK_BUFFER_9ZXL0451E_VZX3P3A")
	)
	(segment
		(start 110.552992 -332.70571)
		(end 110.45825 -332.800452)
		(width 0.254)
		(layer "B.Cu")
		(net "P3V3_CLK_BUFFER_9ZXL0451E_VZX3P3A")
	)
	(segment
		(start 108.13415 -338.164424)
		(end 108.248196 -338.164424)
		(width 0.508)
		(layer "B.Cu")
		(net "P3V3_CLK_BUFFER_9ZXL0451E_VZX3P3A")
	)
	(segment
		(start 107.564428 -334.612488)
		(end 108.046012 -335.094072)
		(width 0.254)
		(layer "B.Cu")
		(net "P3V3_CLK_BUFFER_9ZXL0451E_VZX3P3A")
	)
	(segment
		(start 108.046012 -335.094072)
		(end 108.046012 -335.453736)
		(width 0.254)
		(layer "B.Cu")
		(net "P3V3_CLK_BUFFER_9ZXL0451E_VZX3P3A")
	)
	(segment
		(start 110.208822 -334.186784)
		(end 109.694218 -334.186784)
		(width 0.381)
		(layer "B.Cu")
		(net "P3V3_CLK_BUFFER_9ZXL0451E_VZX3P3A")
	)
	(segment
		(start 108.950506 -337.278218)
		(end 108.950506 -337.462114)
		(width 0.508)
		(layer "B.Cu")
		(net "P3V3_CLK_BUFFER_9ZXL0451E_VZX3P3A")
	)
	(segment
		(start 109.10062 -337.128104)
		(end 108.950506 -337.278218)
		(width 0.508)
		(layer "B.Cu")
		(net "P3V3_CLK_BUFFER_9ZXL0451E_VZX3P3A")
	)
	(segment
		(start 109.10062 -336.562954)
		(end 109.10062 -337.128104)
		(width 0.508)
		(layer "B.Cu")
		(net "P3V3_CLK_BUFFER_9ZXL0451E_VZX3P3A")
	)
	(segment
		(start 110.45825 -332.800452)
		(end 108.689394 -332.800452)
		(width 0.254)
		(layer "B.Cu")
		(net "P3V3_CLK_BUFFER_9ZXL0451E_VZX3P3A")
	)
	(segment
		(start 360.82986 -233.260392)
		(end 360.82986 -230.29291)
		(width 0.13208)
		(layer "F.Cu")
		(net "PEX2_MODE_SEL1")
	)
	(segment
		(start 380.72949 -217.985086)
		(end 381.089662 -218.345258)
		(width 0.13208)
		(layer "F.Cu")
		(net "PEX2_MODE_SEL1")
	)
	(segment
		(start 360.966766 -227.762562)
		(end 360.966766 -220.537532)
		(width 0.13208)
		(layer "F.Cu")
		(net "PEX2_MODE_SEL1")
	)
	(segment
		(start 361.998768 -219.50553)
		(end 365.788956 -219.50553)
		(width 0.13208)
		(layer "F.Cu")
		(net "PEX2_MODE_SEL1")
	)
	(segment
		(start 272.798286 -251.956824)
		(end 272.798286 -251.158502)
		(width 0.13208)
		(layer "F.Cu")
		(net "PEX2_MODE_SEL1")
	)
	(segment
		(start 314.83935 -265.76909)
		(end 319.187068 -261.421372)
		(width 0.13208)
		(layer "F.Cu")
		(net "PEX2_MODE_SEL1")
	)
	(segment
		(start 332.66888 -261.421372)
		(end 360.82986 -233.260392)
		(width 0.13208)
		(layer "F.Cu")
		(net "PEX2_MODE_SEL1")
	)
	(segment
		(start 410.637482 -189.846458)
		(end 410.637482 -189.107318)
		(width 0.13208)
		(layer "F.Cu")
		(net "PEX2_MODE_SEL1")
	)
	(segment
		(start 360.966766 -220.537532)
		(end 361.998768 -219.50553)
		(width 0.13208)
		(layer "F.Cu")
		(net "PEX2_MODE_SEL1")
	)
	(segment
		(start 304.199798 -282.599892)
		(end 304.674778 -283.074872)
		(width 0.13208)
		(layer "F.Cu")
		(net "PEX2_MODE_SEL1")
	)
	(segment
		(start 319.187068 -261.421372)
		(end 332.66888 -261.421372)
		(width 0.13208)
		(layer "F.Cu")
		(net "PEX2_MODE_SEL1")
	)
	(segment
		(start 360.82986 -230.29291)
		(end 360.455464 -229.918514)
		(width 0.13208)
		(layer "F.Cu")
		(net "PEX2_MODE_SEL1")
	)
	(segment
		(start 381.089662 -218.345258)
		(end 381.089662 -218.40317)
		(width 0.13208)
		(layer "F.Cu")
		(net "PEX2_MODE_SEL1")
	)
	(segment
		(start 292.806628 -265.76909)
		(end 314.83935 -265.76909)
		(width 0.13208)
		(layer "F.Cu")
		(net "PEX2_MODE_SEL1")
	)
	(segment
		(start 272.798286 -250.470924)
		(end 277.508462 -250.470924)
		(width 0.13208)
		(layer "F.Cu")
		(net "PEX2_MODE_SEL1")
	)
	(segment
		(start 365.788956 -219.50553)
		(end 367.3094 -217.985086)
		(width 0.13208)
		(layer "F.Cu")
		(net "PEX2_MODE_SEL1")
	)
	(segment
		(start 367.3094 -217.985086)
		(end 380.72949 -217.985086)
		(width 0.13208)
		(layer "F.Cu")
		(net "PEX2_MODE_SEL1")
	)
	(segment
		(start 272.798286 -251.158502)
		(end 272.798286 -250.470924)
		(width 0.13208)
		(layer "F.Cu")
		(net "PEX2_MODE_SEL1")
	)
	(segment
		(start 360.455464 -228.273864)
		(end 360.966766 -227.762562)
		(width 0.13208)
		(layer "F.Cu")
		(net "PEX2_MODE_SEL1")
	)
	(segment
		(start 277.508462 -250.470924)
		(end 292.806628 -265.76909)
		(width 0.13208)
		(layer "F.Cu")
		(net "PEX2_MODE_SEL1")
	)
	(segment
		(start 360.455464 -229.918514)
		(end 360.455464 -228.273864)
		(width 0.13208)
		(layer "F.Cu")
		(net "PEX2_MODE_SEL1")
	)
	(via
		(at 272.798286 -251.158502)
		(size 0.508)
		(drill 0.254)
		(layers "F.Cu" "B.Cu")
		(net "PEX2_MODE_SEL1")
	)
	(via
		(at 410.637482 -189.107318)
		(size 0.508)
		(drill 0.254)
		(layers "F.Cu" "B.Cu")
		(net "PEX2_MODE_SEL1")
	)
	(via
		(at 304.674778 -283.074872)
		(size 0.4064)
		(drill 0.2032)
		(layers "F.Cu" "B.Cu")
		(net "PEX2_MODE_SEL1")
	)
	(via
		(at 381.089662 -218.40317)
		(size 0.508)
		(drill 0.254)
		(layers "F.Cu" "B.Cu")
		(net "PEX2_MODE_SEL1")
	)
	(segment
		(start 410.455872 -195.245228)
		(end 410.455872 -189.288928)
		(width 0.13208)
		(layer "B.Cu")
		(net "PEX2_MODE_SEL1")
	)
	(segment
		(start 305.627532 -271.937226)
		(end 284.848808 -251.158502)
		(width 0.13208)
		(layer "B.Cu")
		(net "PEX2_MODE_SEL1")
	)
	(segment
		(start 305.627532 -282.122118)
		(end 305.627532 -271.937226)
		(width 0.13208)
		(layer "B.Cu")
		(net "PEX2_MODE_SEL1")
	)
	(segment
		(start 408.866594 -200.999598)
		(end 408.866594 -197.830186)
		(width 0.13208)
		(layer "B.Cu")
		(net "PEX2_MODE_SEL1")
	)
	(segment
		(start 381.089662 -218.39428)
		(end 384.737102 -214.74684)
		(width 0.13208)
		(layer "B.Cu")
		(net "PEX2_MODE_SEL1")
	)
	(segment
		(start 381.089662 -218.40317)
		(end 381.089662 -218.39428)
		(width 0.13208)
		(layer "B.Cu")
		(net "PEX2_MODE_SEL1")
	)
	(segment
		(start 384.737102 -214.74684)
		(end 384.737102 -210.797394)
		(width 0.13208)
		(layer "B.Cu")
		(net "PEX2_MODE_SEL1")
	)
	(segment
		(start 409.560776 -197.136004)
		(end 409.560776 -196.140324)
		(width 0.13208)
		(layer "B.Cu")
		(net "PEX2_MODE_SEL1")
	)
	(segment
		(start 407.423366 -202.442826)
		(end 408.866594 -200.999598)
		(width 0.13208)
		(layer "B.Cu")
		(net "PEX2_MODE_SEL1")
	)
	(segment
		(start 409.560776 -196.140324)
		(end 410.455872 -195.245228)
		(width 0.13208)
		(layer "B.Cu")
		(net "PEX2_MODE_SEL1")
	)
	(segment
		(start 393.09167 -202.442826)
		(end 407.423366 -202.442826)
		(width 0.13208)
		(layer "B.Cu")
		(net "PEX2_MODE_SEL1")
	)
	(segment
		(start 410.455872 -189.288928)
		(end 410.637482 -189.107318)
		(width 0.13208)
		(layer "B.Cu")
		(net "PEX2_MODE_SEL1")
	)
	(segment
		(start 304.674778 -283.074872)
		(end 305.627532 -282.122118)
		(width 0.13208)
		(layer "B.Cu")
		(net "PEX2_MODE_SEL1")
	)
	(segment
		(start 384.737102 -210.797394)
		(end 393.09167 -202.442826)
		(width 0.13208)
		(layer "B.Cu")
		(net "PEX2_MODE_SEL1")
	)
	(segment
		(start 408.866594 -197.830186)
		(end 409.560776 -197.136004)
		(width 0.13208)
		(layer "B.Cu")
		(net "PEX2_MODE_SEL1")
	)
	(segment
		(start 284.848808 -251.158502)
		(end 272.798286 -251.158502)
		(width 0.13208)
		(layer "B.Cu")
		(net "PEX2_MODE_SEL1")
	)
	(segment
		(start 311.662318 -22.097492)
		(end 311.42051 -21.855684)
		(width 0.13208)
		(layer "F.Cu")
		(net "SMB_BIC_I2C9_MUX1_SSD10_R_SDA")
	)
	(segment
		(start 311.135522 -21.570696)
		(end 311.135522 -20.789392)
		(width 0.13208)
		(layer "F.Cu")
		(net "SMB_BIC_I2C9_MUX1_SSD10_R_SDA")
	)
	(segment
		(start 311.662318 -22.537166)
		(end 311.662318 -22.097492)
		(width 0.13208)
		(layer "F.Cu")
		(net "SMB_BIC_I2C9_MUX1_SSD10_R_SDA")
	)
	(segment
		(start 351.60331 -84.930234)
		(end 352.520504 -84.930234)
		(width 0.13208)
		(layer "F.Cu")
		(net "SMB_BIC_I2C9_MUX1_SSD10_R_SDA")
	)
	(segment
		(start 311.42051 -21.855684)
		(end 311.135522 -21.570696)
		(width 0.13208)
		(layer "F.Cu")
		(net "SMB_BIC_I2C9_MUX1_SSD10_R_SDA")
	)
	(segment
		(start 350.780604 -84.930234)
		(end 351.60331 -84.930234)
		(width 0.13208)
		(layer "F.Cu")
		(net "SMB_BIC_I2C9_MUX1_SSD10_R_SDA")
	)
	(via
		(at 311.42051 -21.855684)
		(size 0.508)
		(drill 0.254)
		(layers "F.Cu" "B.Cu")
		(net "SMB_BIC_I2C9_MUX1_SSD10_R_SDA")
	)
	(via
		(at 320.71691 -76.89342)
		(size 0.508)
		(drill 0.254)
		(layers "F.Cu" "B.Cu")
		(net "SMB_BIC_I2C9_MUX1_SSD10_R_SDA")
	)
	(via
		(at 351.60331 -84.930234)
		(size 0.508)
		(drill 0.254)
		(layers "F.Cu" "B.Cu")
		(net "SMB_BIC_I2C9_MUX1_SSD10_R_SDA")
	)
	(segment
		(start 308.504336 -32.433514)
		(end 321.348608 -45.277786)
		(width 0.15494)
		(layer "In5.Cu")
		(net "SMB_BIC_I2C9_MUX1_SSD10_R_SDA")
	)
	(segment
		(start 308.456838 -22.049994)
		(end 308.456838 -27.204924)
		(width 0.15494)
		(layer "In5.Cu")
		(net "SMB_BIC_I2C9_MUX1_SSD10_R_SDA")
	)
	(segment
		(start 308.504336 -30.094428)
		(end 308.504336 -32.433514)
		(width 0.15494)
		(layer "In5.Cu")
		(net "SMB_BIC_I2C9_MUX1_SSD10_R_SDA")
	)
	(segment
		(start 321.348608 -45.277786)
		(end 321.348608 -72.25284)
		(width 0.15494)
		(layer "In5.Cu")
		(net "SMB_BIC_I2C9_MUX1_SSD10_R_SDA")
	)
	(segment
		(start 310.840374 -21.275548)
		(end 309.231284 -21.275548)
		(width 0.15494)
		(layer "In5.Cu")
		(net "SMB_BIC_I2C9_MUX1_SSD10_R_SDA")
	)
	(segment
		(start 320.528442 -76.261722)
		(end 320.71691 -76.45019)
		(width 0.15494)
		(layer "In5.Cu")
		(net "SMB_BIC_I2C9_MUX1_SSD10_R_SDA")
	)
	(segment
		(start 309.231284 -21.275548)
		(end 308.456838 -22.049994)
		(width 0.15494)
		(layer "In5.Cu")
		(net "SMB_BIC_I2C9_MUX1_SSD10_R_SDA")
	)
	(segment
		(start 320.71691 -76.45019)
		(end 320.71691 -76.89342)
		(width 0.15494)
		(layer "In5.Cu")
		(net "SMB_BIC_I2C9_MUX1_SSD10_R_SDA")
	)
	(segment
		(start 321.348608 -72.25284)
		(end 320.528442 -73.073006)
		(width 0.15494)
		(layer "In5.Cu")
		(net "SMB_BIC_I2C9_MUX1_SSD10_R_SDA")
	)
	(segment
		(start 308.456838 -27.204924)
		(end 309.320946 -28.069032)
		(width 0.15494)
		(layer "In5.Cu")
		(net "SMB_BIC_I2C9_MUX1_SSD10_R_SDA")
	)
	(segment
		(start 320.528442 -73.073006)
		(end 320.528442 -76.261722)
		(width 0.15494)
		(layer "In5.Cu")
		(net "SMB_BIC_I2C9_MUX1_SSD10_R_SDA")
	)
	(segment
		(start 309.320946 -28.069032)
		(end 309.320946 -29.277818)
		(width 0.15494)
		(layer "In5.Cu")
		(net "SMB_BIC_I2C9_MUX1_SSD10_R_SDA")
	)
	(segment
		(start 309.320946 -29.277818)
		(end 308.504336 -30.094428)
		(width 0.15494)
		(layer "In5.Cu")
		(net "SMB_BIC_I2C9_MUX1_SSD10_R_SDA")
	)
	(segment
		(start 311.42051 -21.855684)
		(end 310.840374 -21.275548)
		(width 0.15494)
		(layer "In5.Cu")
		(net "SMB_BIC_I2C9_MUX1_SSD10_R_SDA")
	)
	(segment
		(start 351.60331 -84.930234)
		(end 350.893634 -84.930234)
		(width 0.15494)
		(layer "In15.Cu")
		(net "SMB_BIC_I2C9_MUX1_SSD10_R_SDA")
	)
	(segment
		(start 321.97929 -78.1558)
		(end 320.71691 -76.89342)
		(width 0.15494)
		(layer "In15.Cu")
		(net "SMB_BIC_I2C9_MUX1_SSD10_R_SDA")
	)
	(segment
		(start 335.8896 -78.1558)
		(end 321.97929 -78.1558)
		(width 0.15494)
		(layer "In15.Cu")
		(net "SMB_BIC_I2C9_MUX1_SSD10_R_SDA")
	)
	(segment
		(start 343.4334 -77.47)
		(end 336.5754 -77.47)
		(width 0.15494)
		(layer "In15.Cu")
		(net "SMB_BIC_I2C9_MUX1_SSD10_R_SDA")
	)
	(segment
		(start 350.893634 -84.930234)
		(end 343.4334 -77.47)
		(width 0.15494)
		(layer "In15.Cu")
		(net "SMB_BIC_I2C9_MUX1_SSD10_R_SDA")
	)
	(segment
		(start 336.5754 -77.47)
		(end 335.8896 -78.1558)
		(width 0.15494)
		(layer "In15.Cu")
		(net "SMB_BIC_I2C9_MUX1_SSD10_R_SDA")
	)
	(segment
		(start 281.621738 -417.008564)
		(end 279.235916 -417.008564)
		(width 0.13208)
		(layer "F.Cu")
		(net "MB_BIC_READY_BUF_R_N")
	)
	(segment
		(start 279.235916 -417.008564)
		(end 278.758396 -416.531044)
		(width 0.13208)
		(layer "F.Cu")
		(net "MB_BIC_READY_BUF_R_N")
	)
	(segment
		(start 270.808704 -359.365042)
		(end 278.872442 -359.365042)
		(width 0.13208)
		(layer "F.Cu")
		(net "MB_BIC_READY_BUF_R_N")
	)
	(segment
		(start 282.634944 -363.127544)
		(end 282.634944 -415.995358)
		(width 0.13208)
		(layer "F.Cu")
		(net "MB_BIC_READY_BUF_R_N")
	)
	(segment
		(start 278.758396 -416.531044)
		(end 278.758396 -415.989262)
		(width 0.13208)
		(layer "F.Cu")
		(net "MB_BIC_READY_BUF_R_N")
	)
	(segment
		(start 278.872442 -359.365042)
		(end 282.634944 -363.127544)
		(width 0.13208)
		(layer "F.Cu")
		(net "MB_BIC_READY_BUF_R_N")
	)
	(segment
		(start 266.571222 -343.076276)
		(end 266.571222 -355.12756)
		(width 0.13208)
		(layer "F.Cu")
		(net "MB_BIC_READY_BUF_R_N")
	)
	(segment
		(start 282.634944 -415.995358)
		(end 281.621738 -417.008564)
		(width 0.13208)
		(layer "F.Cu")
		(net "MB_BIC_READY_BUF_R_N")
	)
	(segment
		(start 278.758396 -415.29)
		(end 278.758396 -415.989262)
		(width 0.13208)
		(layer "F.Cu")
		(net "MB_BIC_READY_BUF_R_N")
	)
	(segment
		(start 266.571222 -355.12756)
		(end 270.808704 -359.365042)
		(width 0.13208)
		(layer "F.Cu")
		(net "MB_BIC_READY_BUF_R_N")
	)
	(via
		(at 364.7186 -340.5632)
		(size 0.508)
		(drill 0.254)
		(layers "F.Cu" "B.Cu")
		(net "MB_BIC_READY_BUF_R_N")
	)
	(via
		(at 266.571222 -343.076276)
		(size 0.508)
		(drill 0.254)
		(layers "F.Cu" "B.Cu")
		(net "MB_BIC_READY_BUF_R_N")
	)
	(via
		(at 278.758396 -415.989262)
		(size 0.508)
		(drill 0.254)
		(layers "F.Cu" "B.Cu")
		(net "MB_BIC_READY_BUF_R_N")
	)
	(segment
		(start 266.116054 -341.578946)
		(end 266.9032 -340.7918)
		(width 0.13208)
		(layer "B.Cu")
		(net "MB_BIC_READY_BUF_R_N")
	)
	(segment
		(start 266.9032 -340.7918)
		(end 347.01353 -340.7918)
		(width 0.13208)
		(layer "B.Cu")
		(net "MB_BIC_READY_BUF_R_N")
	)
	(segment
		(start 266.116054 -342.621108)
		(end 266.116054 -341.578946)
		(width 0.13208)
		(layer "B.Cu")
		(net "MB_BIC_READY_BUF_R_N")
	)
	(segment
		(start 266.571222 -343.076276)
		(end 266.116054 -342.621108)
		(width 0.13208)
		(layer "B.Cu")
		(net "MB_BIC_READY_BUF_R_N")
	)
	(segment
		(start 347.01353 -340.7918)
		(end 348.71533 -342.4936)
		(width 0.13208)
		(layer "B.Cu")
		(net "MB_BIC_READY_BUF_R_N")
	)
	(segment
		(start 348.71533 -342.4936)
		(end 363.6772 -342.4936)
		(width 0.13208)
		(layer "B.Cu")
		(net "MB_BIC_READY_BUF_R_N")
	)
	(segment
		(start 364.7186 -341.4522)
		(end 364.7186 -340.5632)
		(width 0.13208)
		(layer "B.Cu")
		(net "MB_BIC_READY_BUF_R_N")
	)
	(segment
		(start 363.6772 -342.4936)
		(end 364.7186 -341.4522)
		(width 0.13208)
		(layer "B.Cu")
		(net "MB_BIC_READY_BUF_R_N")
	)
	(segment
		(start 364.7186 -359.8164)
		(end 364.7186 -340.5632)
		(width 0.15494)
		(layer "In9.Cu")
		(net "MB_BIC_READY_BUF_R_N")
	)
	(segment
		(start 379.205236 -367.2586)
		(end 374.171718 -362.225082)
		(width 0.15494)
		(layer "In9.Cu")
		(net "MB_BIC_READY_BUF_R_N")
	)
	(segment
		(start 374.171718 -362.225082)
		(end 367.127282 -362.225082)
		(width 0.15494)
		(layer "In9.Cu")
		(net "MB_BIC_READY_BUF_R_N")
	)
	(segment
		(start 382.089914 -368.990118)
		(end 380.358396 -367.2586)
		(width 0.15494)
		(layer "In9.Cu")
		(net "MB_BIC_READY_BUF_R_N")
	)
	(segment
		(start 367.127282 -362.225082)
		(end 364.7186 -359.8164)
		(width 0.15494)
		(layer "In9.Cu")
		(net "MB_BIC_READY_BUF_R_N")
	)
	(segment
		(start 380.358396 -367.2586)
		(end 379.205236 -367.2586)
		(width 0.15494)
		(layer "In9.Cu")
		(net "MB_BIC_READY_BUF_R_N")
	)
	(segment
		(start 346.893896 -226.387152)
		(end 347.293692 -226.786948)
		(width 0.13208)
		(layer "F.Cu")
		(net "SSD5_PWR_EN")
	)
	(via
		(at 347.293692 -226.786948)
		(size 0.4572)
		(drill 0.254)
		(layers "F.Cu" "B.Cu")
		(net "SSD5_PWR_EN")
	)
	(via
		(at 346.07754 -231.77246)
		(size 0.6604)
		(drill 0.3302)
		(layers "F.Cu" "B.Cu")
		(net "SSD5_PWR_EN")
	)
	(segment
		(start 346.6846 -228.395784)
		(end 347.345 -227.735384)
		(width 0.13208)
		(layer "B.Cu")
		(net "SSD5_PWR_EN")
	)
	(segment
		(start 347.345 -226.838256)
		(end 347.293692 -226.786948)
		(width 0.13208)
		(layer "B.Cu")
		(net "SSD5_PWR_EN")
	)
	(segment
		(start 345.059 -233.15295)
		(end 345.059 -232.791)
		(width 0.13208)
		(layer "B.Cu")
		(net "SSD5_PWR_EN")
	)
	(segment
		(start 345.059 -232.791)
		(end 346.07754 -231.77246)
		(width 0.13208)
		(layer "B.Cu")
		(net "SSD5_PWR_EN")
	)
	(segment
		(start 346.07754 -231.77246)
		(end 346.6846 -231.1654)
		(width 0.13208)
		(layer "B.Cu")
		(net "SSD5_PWR_EN")
	)
	(segment
		(start 346.6846 -231.1654)
		(end 346.6846 -228.395784)
		(width 0.13208)
		(layer "B.Cu")
		(net "SSD5_PWR_EN")
	)
	(segment
		(start 347.345 -227.735384)
		(end 347.345 -226.838256)
		(width 0.13208)
		(layer "B.Cu")
		(net "SSD5_PWR_EN")
	)
	(segment
		(start 96.835976 -120.041924)
		(end 96.926654 -119.951246)
		(width 0.13208)
		(layer "F.Cu")
		(net "P3V3_NIC1_SS")
	)
	(segment
		(start 96.926654 -119.405654)
		(end 97.864422 -118.467886)
		(width 0.13208)
		(layer "F.Cu")
		(net "P3V3_NIC1_SS")
	)
	(segment
		(start 97.864422 -118.467886)
		(end 98.575622 -118.467886)
		(width 0.13208)
		(layer "F.Cu")
		(net "P3V3_NIC1_SS")
	)
	(segment
		(start 96.926654 -119.951246)
		(end 96.926654 -119.405654)
		(width 0.13208)
		(layer "F.Cu")
		(net "P3V3_NIC1_SS")
	)
	(segment
		(start 96.77146 -120.041924)
		(end 96.835976 -120.041924)
		(width 0.13208)
		(layer "F.Cu")
		(net "P3V3_NIC1_SS")
	)
	(via
		(at 97.864422 -118.467886)
		(size 0.508)
		(drill 0.254)
		(layers "F.Cu" "B.Cu")
		(net "P3V3_NIC1_SS")
	)
	(segment
		(start 94.8436 -189.3062)
		(end 94.5896 -189.5602)
		(width 0.13208)
		(layer "F.Cu")
		(net "UART_PEX2_CLI_R_RX")
	)
	(segment
		(start 145.6182 -210.7184)
		(end 145.6182 -212.2932)
		(width 0.13208)
		(layer "F.Cu")
		(net "UART_PEX2_CLI_R_RX")
	)
	(segment
		(start 138.5316 -216.9668)
		(end 137.7696 -216.2048)
		(width 0.13208)
		(layer "F.Cu")
		(net "UART_PEX2_CLI_R_RX")
	)
	(segment
		(start 63.6778 -207.654906)
		(end 63.6778 -208.2546)
		(width 0.13208)
		(layer "F.Cu")
		(net "UART_PEX2_CLI_R_RX")
	)
	(segment
		(start 145.6182 -212.2932)
		(end 144.018 -213.8934)
		(width 0.13208)
		(layer "F.Cu")
		(net "UART_PEX2_CLI_R_RX")
	)
	(segment
		(start 137.7696 -216.2048)
		(end 137.7696 -215.363806)
		(width 0.13208)
		(layer "F.Cu")
		(net "UART_PEX2_CLI_R_RX")
	)
	(segment
		(start 144.018 -213.8934)
		(end 144.018 -215.8238)
		(width 0.13208)
		(layer "F.Cu")
		(net "UART_PEX2_CLI_R_RX")
	)
	(segment
		(start 142.875 -216.9668)
		(end 138.5316 -216.9668)
		(width 0.13208)
		(layer "F.Cu")
		(net "UART_PEX2_CLI_R_RX")
	)
	(segment
		(start 63.363094 -207.3402)
		(end 63.6778 -207.654906)
		(width 0.13208)
		(layer "F.Cu")
		(net "UART_PEX2_CLI_R_RX")
	)
	(segment
		(start 144.018 -215.8238)
		(end 142.875 -216.9668)
		(width 0.13208)
		(layer "F.Cu")
		(net "UART_PEX2_CLI_R_RX")
	)
	(segment
		(start 95.506794 -189.3062)
		(end 94.8436 -189.3062)
		(width 0.13208)
		(layer "F.Cu")
		(net "UART_PEX2_CLI_R_RX")
	)
	(via
		(at 63.6778 -208.2546)
		(size 0.508)
		(drill 0.254)
		(layers "F.Cu" "B.Cu")
		(net "UART_PEX2_CLI_R_RX")
	)
	(via
		(at 94.5896 -189.5602)
		(size 0.508)
		(drill 0.254)
		(layers "F.Cu" "B.Cu")
		(net "UART_PEX2_CLI_R_RX")
	)
	(via
		(at 145.6182 -210.7184)
		(size 0.508)
		(drill 0.254)
		(layers "F.Cu" "B.Cu")
		(net "UART_PEX2_CLI_R_RX")
	)
	(via
		(at 142.8496 -208.0006)
		(size 0.508)
		(drill 0.254)
		(layers "F.Cu" "B.Cu")
		(net "UART_PEX2_CLI_R_RX")
	)
	(via
		(at 87.503 -189.5602)
		(size 0.6604)
		(drill 0.3302)
		(layers "F.Cu" "B.Cu")
		(net "UART_PEX2_CLI_R_RX")
	)
	(segment
		(start 84.455 -189.5602)
		(end 67.0052 -207.01)
		(width 0.13208)
		(layer "B.Cu")
		(net "UART_PEX2_CLI_R_RX")
	)
	(segment
		(start 143.51 -208.1784)
		(end 143.51 -210.5152)
		(width 0.13208)
		(layer "B.Cu")
		(net "UART_PEX2_CLI_R_RX")
	)
	(segment
		(start 94.5896 -189.5602)
		(end 87.503 -189.5602)
		(width 0.13208)
		(layer "B.Cu")
		(net "UART_PEX2_CLI_R_RX")
	)
	(segment
		(start 145.3896 -210.947)
		(end 145.6182 -210.7184)
		(width 0.13208)
		(layer "B.Cu")
		(net "UART_PEX2_CLI_R_RX")
	)
	(segment
		(start 143.9418 -210.947)
		(end 145.3896 -210.947)
		(width 0.13208)
		(layer "B.Cu")
		(net "UART_PEX2_CLI_R_RX")
	)
	(segment
		(start 143.51 -210.5152)
		(end 143.9418 -210.947)
		(width 0.13208)
		(layer "B.Cu")
		(net "UART_PEX2_CLI_R_RX")
	)
	(segment
		(start 143.3322 -208.0006)
		(end 143.51 -208.1784)
		(width 0.13208)
		(layer "B.Cu")
		(net "UART_PEX2_CLI_R_RX")
	)
	(segment
		(start 142.8496 -208.0006)
		(end 143.3322 -208.0006)
		(width 0.13208)
		(layer "B.Cu")
		(net "UART_PEX2_CLI_R_RX")
	)
	(segment
		(start 87.503 -189.5602)
		(end 84.455 -189.5602)
		(width 0.13208)
		(layer "B.Cu")
		(net "UART_PEX2_CLI_R_RX")
	)
	(segment
		(start 67.0052 -207.01)
		(end 64.9224 -207.01)
		(width 0.13208)
		(layer "B.Cu")
		(net "UART_PEX2_CLI_R_RX")
	)
	(segment
		(start 142.8496 -209.0674)
		(end 142.4432 -209.4738)
		(width 0.13208)
		(layer "B.Cu")
		(net "UART_PEX2_CLI_R_RX")
	)
	(segment
		(start 142.4432 -209.4738)
		(end 142.4432 -209.857848)
		(width 0.13208)
		(layer "B.Cu")
		(net "UART_PEX2_CLI_R_RX")
	)
	(segment
		(start 142.8496 -208.0006)
		(end 142.8496 -209.0674)
		(width 0.13208)
		(layer "B.Cu")
		(net "UART_PEX2_CLI_R_RX")
	)
	(segment
		(start 64.9224 -207.01)
		(end 63.6778 -208.2546)
		(width 0.13208)
		(layer "B.Cu")
		(net "UART_PEX2_CLI_R_RX")
	)
	(segment
		(start 97.7646 -191.008)
		(end 96.3168 -189.5602)
		(width 0.15494)
		(layer "In15.Cu")
		(net "UART_PEX2_CLI_R_RX")
	)
	(segment
		(start 115.697 -200.787)
		(end 110.7948 -195.8848)
		(width 0.15494)
		(layer "In15.Cu")
		(net "UART_PEX2_CLI_R_RX")
	)
	(segment
		(start 109.1184 -191.008)
		(end 97.7646 -191.008)
		(width 0.15494)
		(layer "In15.Cu")
		(net "UART_PEX2_CLI_R_RX")
	)
	(segment
		(start 110.7948 -195.8848)
		(end 110.7948 -192.6844)
		(width 0.15494)
		(layer "In15.Cu")
		(net "UART_PEX2_CLI_R_RX")
	)
	(segment
		(start 122.790458 -203.654914)
		(end 119.922544 -200.787)
		(width 0.15494)
		(layer "In15.Cu")
		(net "UART_PEX2_CLI_R_RX")
	)
	(segment
		(start 141.510766 -206.661766)
		(end 137.946638 -206.661766)
		(width 0.15494)
		(layer "In15.Cu")
		(net "UART_PEX2_CLI_R_RX")
	)
	(segment
		(start 119.922544 -200.787)
		(end 115.697 -200.787)
		(width 0.15494)
		(layer "In15.Cu")
		(net "UART_PEX2_CLI_R_RX")
	)
	(segment
		(start 110.7948 -192.6844)
		(end 109.1184 -191.008)
		(width 0.15494)
		(layer "In15.Cu")
		(net "UART_PEX2_CLI_R_RX")
	)
	(segment
		(start 134.939786 -203.654914)
		(end 122.790458 -203.654914)
		(width 0.15494)
		(layer "In15.Cu")
		(net "UART_PEX2_CLI_R_RX")
	)
	(segment
		(start 137.946638 -206.661766)
		(end 134.939786 -203.654914)
		(width 0.15494)
		(layer "In15.Cu")
		(net "UART_PEX2_CLI_R_RX")
	)
	(segment
		(start 142.8496 -208.0006)
		(end 141.510766 -206.661766)
		(width 0.15494)
		(layer "In15.Cu")
		(net "UART_PEX2_CLI_R_RX")
	)
	(segment
		(start 96.3168 -189.5602)
		(end 94.5896 -189.5602)
		(width 0.15494)
		(layer "In15.Cu")
		(net "UART_PEX2_CLI_R_RX")
	)
	(segment
		(start 262.638286 -251.956824)
		(end 262.638286 -251.158502)
		(width 0.13208)
		(layer "F.Cu")
		(net "PEX2_MODE_SEL0")
	)
	(segment
		(start 293.74973 -282.599892)
		(end 294.22471 -283.074872)
		(width 0.1651)
		(layer "F.Cu")
		(net "PEX2_MODE_SEL0")
	)
	(segment
		(start 262.638286 -251.158502)
		(end 262.638286 -250.470924)
		(width 0.13208)
		(layer "F.Cu")
		(net "PEX2_MODE_SEL0")
	)
	(via
		(at 294.22471 -283.074872)
		(size 0.4064)
		(drill 0.2032)
		(layers "F.Cu" "B.Cu")
		(net "PEX2_MODE_SEL0")
	)
	(via
		(at 262.638286 -251.158502)
		(size 0.508)
		(drill 0.254)
		(layers "F.Cu" "B.Cu")
		(net "PEX2_MODE_SEL0")
	)
	(segment
		(start 262.638286 -251.158502)
		(end 262.098536 -251.698252)
		(width 0.13208)
		(layer "B.Cu")
		(net "PEX2_MODE_SEL0")
	)
	(segment
		(start 263.160002 -254.736092)
		(end 264.018776 -254.736092)
		(width 0.13208)
		(layer "B.Cu")
		(net "PEX2_MODE_SEL0")
	)
	(segment
		(start 267.603732 -255.77292)
		(end 268.156182 -256.32537)
		(width 0.13208)
		(layer "B.Cu")
		(net "PEX2_MODE_SEL0")
	)
	(segment
		(start 262.098536 -253.674626)
		(end 263.160002 -254.736092)
		(width 0.13208)
		(layer "B.Cu")
		(net "PEX2_MODE_SEL0")
	)
	(segment
		(start 264.050526 -254.761492)
		(end 265.061954 -255.77292)
		(width 0.13208)
		(layer "B.Cu")
		(net "PEX2_MODE_SEL0")
	)
	(segment
		(start 268.156182 -256.32537)
		(end 279.539446 -256.32537)
		(width 0.13208)
		(layer "B.Cu")
		(net "PEX2_MODE_SEL0")
	)
	(segment
		(start 295.170352 -282.12923)
		(end 294.22471 -283.074872)
		(width 0.13208)
		(layer "B.Cu")
		(net "PEX2_MODE_SEL0")
	)
	(segment
		(start 279.539446 -256.32537)
		(end 291.591238 -268.377162)
		(width 0.13208)
		(layer "B.Cu")
		(net "PEX2_MODE_SEL0")
	)
	(segment
		(start 291.608764 -268.377162)
		(end 295.170352 -271.93875)
		(width 0.13208)
		(layer "B.Cu")
		(net "PEX2_MODE_SEL0")
	)
	(segment
		(start 291.591238 -268.377162)
		(end 291.608764 -268.377162)
		(width 0.13208)
		(layer "B.Cu")
		(net "PEX2_MODE_SEL0")
	)
	(segment
		(start 265.061954 -255.77292)
		(end 267.603732 -255.77292)
		(width 0.13208)
		(layer "B.Cu")
		(net "PEX2_MODE_SEL0")
	)
	(segment
		(start 262.098536 -251.698252)
		(end 262.098536 -253.674626)
		(width 0.13208)
		(layer "B.Cu")
		(net "PEX2_MODE_SEL0")
	)
	(segment
		(start 264.044176 -254.761492)
		(end 264.050526 -254.761492)
		(width 0.13208)
		(layer "B.Cu")
		(net "PEX2_MODE_SEL0")
	)
	(segment
		(start 264.018776 -254.736092)
		(end 264.044176 -254.761492)
		(width 0.13208)
		(layer "B.Cu")
		(net "PEX2_MODE_SEL0")
	)
	(segment
		(start 295.170352 -271.93875)
		(end 295.170352 -282.12923)
		(width 0.13208)
		(layer "B.Cu")
		(net "PEX2_MODE_SEL0")
	)
	(segment
		(start 285.420562 -21.855684)
		(end 285.135574 -21.570696)
		(width 0.13208)
		(layer "F.Cu")
		(net "SMB_BIC_I2C9_MUX1_SSD9_R_SDA")
	)
	(segment
		(start 351.759266 -87.062564)
		(end 351.443036 -87.062564)
		(width 0.13208)
		(layer "F.Cu")
		(net "SMB_BIC_I2C9_MUX1_SSD9_R_SDA")
	)
	(segment
		(start 351.912936 -87.216234)
		(end 351.759266 -87.062564)
		(width 0.13208)
		(layer "F.Cu")
		(net "SMB_BIC_I2C9_MUX1_SSD9_R_SDA")
	)
	(segment
		(start 285.135574 -21.570696)
		(end 285.135574 -20.789392)
		(width 0.13208)
		(layer "F.Cu")
		(net "SMB_BIC_I2C9_MUX1_SSD9_R_SDA")
	)
	(segment
		(start 352.520504 -87.216234)
		(end 351.912936 -87.216234)
		(width 0.13208)
		(layer "F.Cu")
		(net "SMB_BIC_I2C9_MUX1_SSD9_R_SDA")
	)
	(segment
		(start 285.66237 -22.097492)
		(end 285.420562 -21.855684)
		(width 0.13208)
		(layer "F.Cu")
		(net "SMB_BIC_I2C9_MUX1_SSD9_R_SDA")
	)
	(segment
		(start 285.66237 -22.537166)
		(end 285.66237 -22.097492)
		(width 0.13208)
		(layer "F.Cu")
		(net "SMB_BIC_I2C9_MUX1_SSD9_R_SDA")
	)
	(segment
		(start 350.934274 -87.062564)
		(end 350.780604 -87.216234)
		(width 0.13208)
		(layer "F.Cu")
		(net "SMB_BIC_I2C9_MUX1_SSD9_R_SDA")
	)
	(segment
		(start 351.443036 -87.062564)
		(end 350.934274 -87.062564)
		(width 0.13208)
		(layer "F.Cu")
		(net "SMB_BIC_I2C9_MUX1_SSD9_R_SDA")
	)
	(via
		(at 285.420562 -21.855684)
		(size 0.508)
		(drill 0.254)
		(layers "F.Cu" "B.Cu")
		(net "SMB_BIC_I2C9_MUX1_SSD9_R_SDA")
	)
	(via
		(at 351.443036 -87.062564)
		(size 0.508)
		(drill 0.254)
		(layers "F.Cu" "B.Cu")
		(net "SMB_BIC_I2C9_MUX1_SSD9_R_SDA")
	)
	(via
		(at 299.694854 -77.816964)
		(size 0.508)
		(drill 0.254)
		(layers "F.Cu" "B.Cu")
		(net "SMB_BIC_I2C9_MUX1_SSD9_R_SDA")
	)
	(segment
		(start 295.32834 -45.335444)
		(end 282.504388 -32.511492)
		(width 0.15494)
		(layer "In5.Cu")
		(net "SMB_BIC_I2C9_MUX1_SSD9_R_SDA")
	)
	(segment
		(start 295.32834 -76.013056)
		(end 295.32834 -45.335444)
		(width 0.15494)
		(layer "In5.Cu")
		(net "SMB_BIC_I2C9_MUX1_SSD9_R_SDA")
	)
	(segment
		(start 297.668696 -78.353412)
		(end 295.32834 -76.013056)
		(width 0.15494)
		(layer "In5.Cu")
		(net "SMB_BIC_I2C9_MUX1_SSD9_R_SDA")
	)
	(segment
		(start 299.694854 -77.816964)
		(end 299.158406 -78.353412)
		(width 0.15494)
		(layer "In5.Cu")
		(net "SMB_BIC_I2C9_MUX1_SSD9_R_SDA")
	)
	(segment
		(start 283.22397 -21.282914)
		(end 284.847792 -21.282914)
		(width 0.15494)
		(layer "In5.Cu")
		(net "SMB_BIC_I2C9_MUX1_SSD9_R_SDA")
	)
	(segment
		(start 299.158406 -78.353412)
		(end 297.668696 -78.353412)
		(width 0.15494)
		(layer "In5.Cu")
		(net "SMB_BIC_I2C9_MUX1_SSD9_R_SDA")
	)
	(segment
		(start 284.847792 -21.282914)
		(end 285.420562 -21.855684)
		(width 0.15494)
		(layer "In5.Cu")
		(net "SMB_BIC_I2C9_MUX1_SSD9_R_SDA")
	)
	(segment
		(start 283.290772 -29.287216)
		(end 283.290772 -28.070556)
		(width 0.15494)
		(layer "In5.Cu")
		(net "SMB_BIC_I2C9_MUX1_SSD9_R_SDA")
	)
	(segment
		(start 282.504388 -32.511492)
		(end 282.504388 -30.0736)
		(width 0.15494)
		(layer "In5.Cu")
		(net "SMB_BIC_I2C9_MUX1_SSD9_R_SDA")
	)
	(segment
		(start 283.290772 -28.070556)
		(end 282.45689 -27.236674)
		(width 0.15494)
		(layer "In5.Cu")
		(net "SMB_BIC_I2C9_MUX1_SSD9_R_SDA")
	)
	(segment
		(start 282.45689 -22.049994)
		(end 283.22397 -21.282914)
		(width 0.15494)
		(layer "In5.Cu")
		(net "SMB_BIC_I2C9_MUX1_SSD9_R_SDA")
	)
	(segment
		(start 282.504388 -30.0736)
		(end 283.290772 -29.287216)
		(width 0.15494)
		(layer "In5.Cu")
		(net "SMB_BIC_I2C9_MUX1_SSD9_R_SDA")
	)
	(segment
		(start 282.45689 -27.236674)
		(end 282.45689 -22.049994)
		(width 0.15494)
		(layer "In5.Cu")
		(net "SMB_BIC_I2C9_MUX1_SSD9_R_SDA")
	)
	(segment
		(start 345.2368 -80.5942)
		(end 350.948244 -86.305644)
		(width 0.15494)
		(layer "In15.Cu")
		(net "SMB_BIC_I2C9_MUX1_SSD9_R_SDA")
	)
	(segment
		(start 311.2516 -77.5716)
		(end 312.612024 -76.211176)
		(width 0.15494)
		(layer "In15.Cu")
		(net "SMB_BIC_I2C9_MUX1_SSD9_R_SDA")
	)
	(segment
		(start 350.948244 -86.567772)
		(end 351.443036 -87.062564)
		(width 0.15494)
		(layer "In15.Cu")
		(net "SMB_BIC_I2C9_MUX1_SSD9_R_SDA")
	)
	(segment
		(start 320.676778 -79.099156)
		(end 332.43901 -79.099156)
		(width 0.15494)
		(layer "In15.Cu")
		(net "SMB_BIC_I2C9_MUX1_SSD9_R_SDA")
	)
	(segment
		(start 334.728566 -80.5942)
		(end 345.2368 -80.5942)
		(width 0.15494)
		(layer "In15.Cu")
		(net "SMB_BIC_I2C9_MUX1_SSD9_R_SDA")
	)
	(segment
		(start 333.371698 -80.031844)
		(end 334.728566 -80.5942)
		(width 0.15494)
		(layer "In15.Cu")
		(net "SMB_BIC_I2C9_MUX1_SSD9_R_SDA")
	)
	(segment
		(start 350.948244 -86.305644)
		(end 350.948244 -86.567772)
		(width 0.15494)
		(layer "In15.Cu")
		(net "SMB_BIC_I2C9_MUX1_SSD9_R_SDA")
	)
	(segment
		(start 317.788798 -76.211176)
		(end 320.676778 -79.099156)
		(width 0.15494)
		(layer "In15.Cu")
		(net "SMB_BIC_I2C9_MUX1_SSD9_R_SDA")
	)
	(segment
		(start 299.694854 -77.816964)
		(end 299.940218 -77.5716)
		(width 0.15494)
		(layer "In15.Cu")
		(net "SMB_BIC_I2C9_MUX1_SSD9_R_SDA")
	)
	(segment
		(start 312.612024 -76.211176)
		(end 317.788798 -76.211176)
		(width 0.15494)
		(layer "In15.Cu")
		(net "SMB_BIC_I2C9_MUX1_SSD9_R_SDA")
	)
	(segment
		(start 299.940218 -77.5716)
		(end 311.2516 -77.5716)
		(width 0.15494)
		(layer "In15.Cu")
		(net "SMB_BIC_I2C9_MUX1_SSD9_R_SDA")
	)
	(segment
		(start 332.43901 -79.099156)
		(end 333.371698 -80.031844)
		(width 0.15494)
		(layer "In15.Cu")
		(net "SMB_BIC_I2C9_MUX1_SSD9_R_SDA")
	)
	(segment
		(start 278.758396 -414.128204)
		(end 278.623014 -413.992822)
		(width 0.13208)
		(layer "F.Cu")
		(net "MB_BIC_READY_BUF_N")
	)
	(segment
		(start 278.623014 -413.992822)
		(end 278.623014 -413.48787)
		(width 0.13208)
		(layer "F.Cu")
		(net "MB_BIC_READY_BUF_N")
	)
	(segment
		(start 278.623014 -412.881064)
		(end 278.623014 -413.48787)
		(width 0.13208)
		(layer "F.Cu")
		(net "MB_BIC_READY_BUF_N")
	)
	(segment
		(start 278.456898 -412.714948)
		(end 278.623014 -412.881064)
		(width 0.13208)
		(layer "F.Cu")
		(net "MB_BIC_READY_BUF_N")
	)
	(segment
		(start 278.758396 -414.4899)
		(end 278.758396 -414.128204)
		(width 0.13208)
		(layer "F.Cu")
		(net "MB_BIC_READY_BUF_N")
	)
	(segment
		(start 278.456898 -411.86481)
		(end 278.456898 -412.714948)
		(width 0.13208)
		(layer "F.Cu")
		(net "MB_BIC_READY_BUF_N")
	)
	(segment
		(start 277.742396 -414.4899)
		(end 278.758396 -414.4899)
		(width 0.13208)
		(layer "F.Cu")
		(net "MB_BIC_READY_BUF_N")
	)
	(via
		(at 278.623014 -413.48787)
		(size 0.508)
		(drill 0.254)
		(layers "F.Cu" "B.Cu")
		(net "MB_BIC_READY_BUF_N")
	)
	(segment
		(start 339.852 -229.397052)
		(end 339.368384 -229.880668)
		(width 0.13208)
		(layer "F.Cu")
		(net "SMB_PEX2_FPGA_SCL")
	)
	(segment
		(start 339.852 -228.473)
		(end 339.852 -229.397052)
		(width 0.13208)
		(layer "F.Cu")
		(net "SMB_PEX2_FPGA_SCL")
	)
	(segment
		(start 340.089998 -228.235002)
		(end 339.852 -228.473)
		(width 0.13208)
		(layer "F.Cu")
		(net "SMB_PEX2_FPGA_SCL")
	)
	(segment
		(start 340.089998 -227.583238)
		(end 340.089998 -228.235002)
		(width 0.13208)
		(layer "F.Cu")
		(net "SMB_PEX2_FPGA_SCL")
	)
	(segment
		(start 323.067934 -288.221166)
		(end 323.067934 -288.830766)
		(width 0.13208)
		(layer "F.Cu")
		(net "SMB_PEX2_FPGA_SCL")
	)
	(segment
		(start 339.693758 -227.186998)
		(end 340.089998 -227.583238)
		(width 0.13208)
		(layer "F.Cu")
		(net "SMB_PEX2_FPGA_SCL")
	)
	(via
		(at 333.469742 -263.281922)
		(size 0.508)
		(drill 0.254)
		(layers "F.Cu" "B.Cu")
		(net "SMB_PEX2_FPGA_SCL")
	)
	(via
		(at 323.067934 -288.221166)
		(size 0.508)
		(drill 0.254)
		(layers "F.Cu" "B.Cu")
		(net "SMB_PEX2_FPGA_SCL")
	)
	(via
		(at 339.368384 -229.880668)
		(size 0.508)
		(drill 0.254)
		(layers "F.Cu" "B.Cu")
		(net "SMB_PEX2_FPGA_SCL")
	)
	(segment
		(start 323.067934 -278.185118)
		(end 328.160126 -273.092926)
		(width 0.13208)
		(layer "B.Cu")
		(net "SMB_PEX2_FPGA_SCL")
	)
	(segment
		(start 323.067934 -288.221166)
		(end 323.067934 -278.185118)
		(width 0.13208)
		(layer "B.Cu")
		(net "SMB_PEX2_FPGA_SCL")
	)
	(segment
		(start 328.160126 -267.665454)
		(end 330.665836 -265.159744)
		(width 0.13208)
		(layer "B.Cu")
		(net "SMB_PEX2_FPGA_SCL")
	)
	(segment
		(start 331.716634 -265.159744)
		(end 333.469742 -263.406636)
		(width 0.13208)
		(layer "B.Cu")
		(net "SMB_PEX2_FPGA_SCL")
	)
	(segment
		(start 330.665836 -265.159744)
		(end 331.716634 -265.159744)
		(width 0.13208)
		(layer "B.Cu")
		(net "SMB_PEX2_FPGA_SCL")
	)
	(segment
		(start 333.469742 -263.406636)
		(end 333.469742 -263.281922)
		(width 0.13208)
		(layer "B.Cu")
		(net "SMB_PEX2_FPGA_SCL")
	)
	(segment
		(start 328.160126 -273.092926)
		(end 328.160126 -267.665454)
		(width 0.13208)
		(layer "B.Cu")
		(net "SMB_PEX2_FPGA_SCL")
	)
	(segment
		(start 327.66 -246.26062)
		(end 327.66 -252.80874)
		(width 0.15494)
		(layer "In9.Cu")
		(net "SMB_PEX2_FPGA_SCL")
	)
	(segment
		(start 327.66 -252.80874)
		(end 334.293972 -259.442712)
		(width 0.15494)
		(layer "In9.Cu")
		(net "SMB_PEX2_FPGA_SCL")
	)
	(segment
		(start 330.2508 -235.035852)
		(end 330.2508 -235.8644)
		(width 0.15494)
		(layer "In9.Cu")
		(net "SMB_PEX2_FPGA_SCL")
	)
	(segment
		(start 328.041 -238.0742)
		(end 328.041 -242.144804)
		(width 0.15494)
		(layer "In9.Cu")
		(net "SMB_PEX2_FPGA_SCL")
	)
	(segment
		(start 330.2508 -235.8644)
		(end 328.041 -238.0742)
		(width 0.15494)
		(layer "In9.Cu")
		(net "SMB_PEX2_FPGA_SCL")
	)
	(segment
		(start 334.293972 -262.457692)
		(end 333.469742 -263.281922)
		(width 0.15494)
		(layer "In9.Cu")
		(net "SMB_PEX2_FPGA_SCL")
	)
	(segment
		(start 339.368384 -229.880668)
		(end 335.195418 -234.053634)
		(width 0.15494)
		(layer "In9.Cu")
		(net "SMB_PEX2_FPGA_SCL")
	)
	(segment
		(start 335.195418 -234.053634)
		(end 331.233018 -234.053634)
		(width 0.15494)
		(layer "In9.Cu")
		(net "SMB_PEX2_FPGA_SCL")
	)
	(segment
		(start 334.293972 -259.442712)
		(end 334.293972 -262.457692)
		(width 0.15494)
		(layer "In9.Cu")
		(net "SMB_PEX2_FPGA_SCL")
	)
	(segment
		(start 327.34758 -242.838224)
		(end 327.34758 -245.9482)
		(width 0.15494)
		(layer "In9.Cu")
		(net "SMB_PEX2_FPGA_SCL")
	)
	(segment
		(start 328.041 -242.144804)
		(end 327.34758 -242.838224)
		(width 0.15494)
		(layer "In9.Cu")
		(net "SMB_PEX2_FPGA_SCL")
	)
	(segment
		(start 327.34758 -245.9482)
		(end 327.66 -246.26062)
		(width 0.15494)
		(layer "In9.Cu")
		(net "SMB_PEX2_FPGA_SCL")
	)
	(segment
		(start 331.233018 -234.053634)
		(end 330.2508 -235.035852)
		(width 0.15494)
		(layer "In9.Cu")
		(net "SMB_PEX2_FPGA_SCL")
	)
	(segment
		(start 359.286048 -125.979428)
		(end 358.81056 -125.979428)
		(width 0.13208)
		(layer "F.Cu")
		(net "PWRGD_P3V3_NIC6")
	)
	(segment
		(start 358.81056 -124.963428)
		(end 358.81056 -125.979428)
		(width 0.13208)
		(layer "F.Cu")
		(net "PWRGD_P3V3_NIC6")
	)
	(segment
		(start 359.768902 -125.894846)
		(end 359.37063 -125.894846)
		(width 0.13208)
		(layer "F.Cu")
		(net "PWRGD_P3V3_NIC6")
	)
	(segment
		(start 360.531156 -125.894846)
		(end 359.768902 -125.894846)
		(width 0.13208)
		(layer "F.Cu")
		(net "PWRGD_P3V3_NIC6")
	)
	(segment
		(start 359.37063 -125.894846)
		(end 359.286048 -125.979428)
		(width 0.13208)
		(layer "F.Cu")
		(net "PWRGD_P3V3_NIC6")
	)
	(via
		(at 359.768902 -125.894846)
		(size 0.508)
		(drill 0.254)
		(layers "F.Cu" "B.Cu")
		(net "PWRGD_P3V3_NIC6")
	)
	(segment
		(start 140.4366 -213.2076)
		(end 140.806678 -212.837522)
		(width 0.13208)
		(layer "F.Cu")
		(net "UART_PEX2_CLI_RX")
	)
	(segment
		(start 140.806678 -211.93887)
		(end 140.806678 -208.923382)
		(width 0.13208)
		(layer "F.Cu")
		(net "UART_PEX2_CLI_RX")
	)
	(segment
		(start 138.7094 -213.2076)
		(end 140.4366 -213.2076)
		(width 0.13208)
		(layer "F.Cu")
		(net "UART_PEX2_CLI_RX")
	)
	(segment
		(start 137.7696 -214.563706)
		(end 137.7696 -214.1474)
		(width 0.13208)
		(layer "F.Cu")
		(net "UART_PEX2_CLI_RX")
	)
	(segment
		(start 140.806678 -212.837522)
		(end 140.806678 -211.93887)
		(width 0.13208)
		(layer "F.Cu")
		(net "UART_PEX2_CLI_RX")
	)
	(segment
		(start 137.7696 -214.1474)
		(end 138.7094 -213.2076)
		(width 0.13208)
		(layer "F.Cu")
		(net "UART_PEX2_CLI_RX")
	)
	(segment
		(start 140.806678 -208.923382)
		(end 141.412214 -208.317846)
		(width 0.13208)
		(layer "F.Cu")
		(net "UART_PEX2_CLI_RX")
	)
	(via
		(at 141.412214 -208.317846)
		(size 0.508)
		(drill 0.254)
		(layers "F.Cu" "B.Cu")
		(net "UART_PEX2_CLI_RX")
	)
	(segment
		(start 270.766286 -251.205238)
		(end 270.70939 -251.148342)
		(width 0.13208)
		(layer "F.Cu")
		(net "PEX2_DBG_MODE4")
	)
	(segment
		(start 300.399704 -282.599892)
		(end 300.874684 -283.074872)
		(width 0.13208)
		(layer "F.Cu")
		(net "PEX2_DBG_MODE4")
	)
	(segment
		(start 270.766286 -251.956824)
		(end 270.766286 -251.205238)
		(width 0.13208)
		(layer "F.Cu")
		(net "PEX2_DBG_MODE4")
	)
	(segment
		(start 270.766286 -251.091446)
		(end 270.70939 -251.148342)
		(width 0.13208)
		(layer "F.Cu")
		(net "PEX2_DBG_MODE4")
	)
	(segment
		(start 270.70939 -251.148342)
		(end 270.719042 -251.148342)
		(width 0.13208)
		(layer "F.Cu")
		(net "PEX2_DBG_MODE4")
	)
	(segment
		(start 270.766286 -250.470924)
		(end 270.766286 -251.091446)
		(width 0.13208)
		(layer "F.Cu")
		(net "PEX2_DBG_MODE4")
	)
	(via
		(at 300.874684 -283.074872)
		(size 0.4064)
		(drill 0.2032)
		(layers "F.Cu" "B.Cu")
		(net "PEX2_DBG_MODE4")
	)
	(via
		(at 270.719042 -251.148342)
		(size 0.508)
		(drill 0.254)
		(layers "F.Cu" "B.Cu")
		(net "PEX2_DBG_MODE4")
	)
	(segment
		(start 302.779938 -281.74696)
		(end 301.935896 -282.591002)
		(width 0.13208)
		(layer "B.Cu")
		(net "PEX2_DBG_MODE4")
	)
	(segment
		(start 270.691102 -254.04953)
		(end 284.659832 -254.04953)
		(width 0.13208)
		(layer "B.Cu")
		(net "PEX2_DBG_MODE4")
	)
	(segment
		(start 301.935896 -282.591002)
		(end 301.608998 -282.591002)
		(width 0.13208)
		(layer "B.Cu")
		(net "PEX2_DBG_MODE4")
	)
	(segment
		(start 301.608998 -282.591002)
		(end 301.125128 -283.074872)
		(width 0.13208)
		(layer "B.Cu")
		(net "PEX2_DBG_MODE4")
	)
	(segment
		(start 270.293846 -253.652274)
		(end 270.691102 -254.04953)
		(width 0.13208)
		(layer "B.Cu")
		(net "PEX2_DBG_MODE4")
	)
	(segment
		(start 284.659832 -254.04953)
		(end 302.779938 -272.169636)
		(width 0.13208)
		(layer "B.Cu")
		(net "PEX2_DBG_MODE4")
	)
	(segment
		(start 302.779938 -272.169636)
		(end 302.779938 -281.74696)
		(width 0.13208)
		(layer "B.Cu")
		(net "PEX2_DBG_MODE4")
	)
	(segment
		(start 301.125128 -283.074872)
		(end 300.874684 -283.074872)
		(width 0.13208)
		(layer "B.Cu")
		(net "PEX2_DBG_MODE4")
	)
	(segment
		(start 270.293846 -251.573538)
		(end 270.293846 -253.652274)
		(width 0.13208)
		(layer "B.Cu")
		(net "PEX2_DBG_MODE4")
	)
	(segment
		(start 270.719042 -251.148342)
		(end 270.293846 -251.573538)
		(width 0.13208)
		(layer "B.Cu")
		(net "PEX2_DBG_MODE4")
	)
	(segment
		(start 350.780604 -82.644234)
		(end 351.60331 -82.644234)
		(width 0.13208)
		(layer "F.Cu")
		(net "SMB_BIC_I2C9_MUX1_SSD11_R_SDA")
	)
	(segment
		(start 337.595718 -6.739636)
		(end 338.074254 -6.739636)
		(width 0.13208)
		(layer "F.Cu")
		(net "SMB_BIC_I2C9_MUX1_SSD11_R_SDA")
	)
	(segment
		(start 336.32648 -7.266432)
		(end 337.068922 -7.266432)
		(width 0.13208)
		(layer "F.Cu")
		(net "SMB_BIC_I2C9_MUX1_SSD11_R_SDA")
	)
	(segment
		(start 337.392772 -6.942582)
		(end 337.595718 -6.739636)
		(width 0.13208)
		(layer "F.Cu")
		(net "SMB_BIC_I2C9_MUX1_SSD11_R_SDA")
	)
	(segment
		(start 351.60331 -82.644234)
		(end 352.520504 -82.644234)
		(width 0.13208)
		(layer "F.Cu")
		(net "SMB_BIC_I2C9_MUX1_SSD11_R_SDA")
	)
	(segment
		(start 337.068922 -7.266432)
		(end 337.392772 -6.942582)
		(width 0.13208)
		(layer "F.Cu")
		(net "SMB_BIC_I2C9_MUX1_SSD11_R_SDA")
	)
	(via
		(at 337.392772 -6.942582)
		(size 0.508)
		(drill 0.254)
		(layers "F.Cu" "B.Cu")
		(net "SMB_BIC_I2C9_MUX1_SSD11_R_SDA")
	)
	(via
		(at 351.60331 -82.644234)
		(size 0.508)
		(drill 0.254)
		(layers "F.Cu" "B.Cu")
		(net "SMB_BIC_I2C9_MUX1_SSD11_R_SDA")
	)
	(segment
		(start 341.871808 -69.893434)
		(end 339.97646 -67.998086)
		(width 0.15494)
		(layer "In5.Cu")
		(net "SMB_BIC_I2C9_MUX1_SSD11_R_SDA")
	)
	(segment
		(start 334.456786 -27.252168)
		(end 334.456786 -14.189964)
		(width 0.15494)
		(layer "In5.Cu")
		(net "SMB_BIC_I2C9_MUX1_SSD11_R_SDA")
	)
	(segment
		(start 336.798158 -7.537196)
		(end 337.392772 -6.942582)
		(width 0.15494)
		(layer "In5.Cu")
		(net "SMB_BIC_I2C9_MUX1_SSD11_R_SDA")
	)
	(segment
		(start 347.97238 -81.740756)
		(end 341.871808 -75.640184)
		(width 0.15494)
		(layer "In5.Cu")
		(net "SMB_BIC_I2C9_MUX1_SSD11_R_SDA")
	)
	(segment
		(start 339.97646 -41.253156)
		(end 334.477106 -35.753802)
		(width 0.15494)
		(layer "In5.Cu")
		(net "SMB_BIC_I2C9_MUX1_SSD11_R_SDA")
	)
	(segment
		(start 336.798158 -11.848592)
		(end 336.798158 -7.537196)
		(width 0.15494)
		(layer "In5.Cu")
		(net "SMB_BIC_I2C9_MUX1_SSD11_R_SDA")
	)
	(segment
		(start 335.285588 -29.346906)
		(end 335.285588 -28.08097)
		(width 0.15494)
		(layer "In5.Cu")
		(net "SMB_BIC_I2C9_MUX1_SSD11_R_SDA")
	)
	(segment
		(start 334.477106 -30.155388)
		(end 335.285588 -29.346906)
		(width 0.15494)
		(layer "In5.Cu")
		(net "SMB_BIC_I2C9_MUX1_SSD11_R_SDA")
	)
	(segment
		(start 351.60331 -82.644234)
		(end 350.699832 -81.740756)
		(width 0.15494)
		(layer "In5.Cu")
		(net "SMB_BIC_I2C9_MUX1_SSD11_R_SDA")
	)
	(segment
		(start 339.97646 -67.998086)
		(end 339.97646 -41.253156)
		(width 0.15494)
		(layer "In5.Cu")
		(net "SMB_BIC_I2C9_MUX1_SSD11_R_SDA")
	)
	(segment
		(start 334.477106 -35.753802)
		(end 334.477106 -30.155388)
		(width 0.15494)
		(layer "In5.Cu")
		(net "SMB_BIC_I2C9_MUX1_SSD11_R_SDA")
	)
	(segment
		(start 334.456786 -14.189964)
		(end 336.798158 -11.848592)
		(width 0.15494)
		(layer "In5.Cu")
		(net "SMB_BIC_I2C9_MUX1_SSD11_R_SDA")
	)
	(segment
		(start 335.285588 -28.08097)
		(end 334.456786 -27.252168)
		(width 0.15494)
		(layer "In5.Cu")
		(net "SMB_BIC_I2C9_MUX1_SSD11_R_SDA")
	)
	(segment
		(start 341.871808 -75.640184)
		(end 341.871808 -69.893434)
		(width 0.15494)
		(layer "In5.Cu")
		(net "SMB_BIC_I2C9_MUX1_SSD11_R_SDA")
	)
	(segment
		(start 350.699832 -81.740756)
		(end 347.97238 -81.740756)
		(width 0.15494)
		(layer "In5.Cu")
		(net "SMB_BIC_I2C9_MUX1_SSD11_R_SDA")
	)
	(segment
		(start 352.756978 -229.947978)
		(end 355.854 -233.045)
		(width 0.13208)
		(layer "F.Cu")
		(net "SSD7_PWRDIS")
	)
	(segment
		(start 355.854 -233.045)
		(end 355.854 -233.66095)
		(width 0.13208)
		(layer "F.Cu")
		(net "SSD7_PWRDIS")
	)
	(segment
		(start 350.928686 -228.984048)
		(end 351.46615 -228.984048)
		(width 0.13208)
		(layer "F.Cu")
		(net "SSD7_PWRDIS")
	)
	(segment
		(start 350.490028 -228.54539)
		(end 350.928686 -228.984048)
		(width 0.13208)
		(layer "F.Cu")
		(net "SSD7_PWRDIS")
	)
	(segment
		(start 350.490028 -227.583238)
		(end 350.490028 -228.54539)
		(width 0.13208)
		(layer "F.Cu")
		(net "SSD7_PWRDIS")
	)
	(segment
		(start 351.46615 -228.984048)
		(end 352.43008 -229.947978)
		(width 0.13208)
		(layer "F.Cu")
		(net "SSD7_PWRDIS")
	)
	(segment
		(start 350.093788 -227.186998)
		(end 350.490028 -227.583238)
		(width 0.13208)
		(layer "F.Cu")
		(net "SSD7_PWRDIS")
	)
	(segment
		(start 352.43008 -229.947978)
		(end 352.756978 -229.947978)
		(width 0.13208)
		(layer "F.Cu")
		(net "SSD7_PWRDIS")
	)
	(via
		(at 352.43008 -229.947978)
		(size 0.508)
		(drill 0.254)
		(layers "F.Cu" "B.Cu")
		(net "SSD7_PWRDIS")
	)
	(segment
		(start 263.463278 -310.571896)
		(end 263.46277 -310.571896)
		(width 0.13208)
		(layer "F.Cu")
		(net "PEX2_DBG_MODE0")
	)
	(segment
		(start 264.22985 -310.892698)
		(end 263.78408 -310.892698)
		(width 0.13208)
		(layer "F.Cu")
		(net "PEX2_DBG_MODE0")
	)
	(segment
		(start 279.499822 -309.199788)
		(end 279.024842 -308.724808)
		(width 0.13208)
		(layer "F.Cu")
		(net "PEX2_DBG_MODE0")
	)
	(segment
		(start 265.071352 -311.7342)
		(end 264.22985 -310.892698)
		(width 0.13208)
		(layer "F.Cu")
		(net "PEX2_DBG_MODE0")
	)
	(segment
		(start 263.78408 -310.892698)
		(end 263.463278 -310.571896)
		(width 0.13208)
		(layer "F.Cu")
		(net "PEX2_DBG_MODE0")
	)
	(segment
		(start 263.463278 -310.571896)
		(end 264.18159 -309.853584)
		(width 0.13208)
		(layer "F.Cu")
		(net "PEX2_DBG_MODE0")
	)
	(via
		(at 279.024842 -308.724808)
		(size 0.4064)
		(drill 0.2032)
		(layers "F.Cu" "B.Cu")
		(net "PEX2_DBG_MODE0")
	)
	(via
		(at 266.745212 -308.593236)
		(size 0.6604)
		(drill 0.3302)
		(layers "F.Cu" "B.Cu")
		(net "PEX2_DBG_MODE0")
	)
	(via
		(at 265.071352 -311.7342)
		(size 0.508)
		(drill 0.254)
		(layers "F.Cu" "B.Cu")
		(net "PEX2_DBG_MODE0")
	)
	(segment
		(start 265.071352 -310.267096)
		(end 266.745212 -308.593236)
		(width 0.13208)
		(layer "B.Cu")
		(net "PEX2_DBG_MODE0")
	)
	(segment
		(start 266.876784 -308.724808)
		(end 266.745212 -308.593236)
		(width 0.13208)
		(layer "B.Cu")
		(net "PEX2_DBG_MODE0")
	)
	(segment
		(start 265.071352 -311.7342)
		(end 265.071352 -310.267096)
		(width 0.13208)
		(layer "B.Cu")
		(net "PEX2_DBG_MODE0")
	)
	(segment
		(start 279.024842 -308.724808)
		(end 266.876784 -308.724808)
		(width 0.13208)
		(layer "B.Cu")
		(net "PEX2_DBG_MODE0")
	)
	(segment
		(start 310.517794 -21.775674)
		(end 310.485282 -21.743162)
		(width 0.13208)
		(layer "F.Cu")
		(net "SMB_BIC_I2C9_MUX1_SSD10_R_SCL")
	)
	(segment
		(start 351.60331 -83.787234)
		(end 352.520504 -83.787234)
		(width 0.13208)
		(layer "F.Cu")
		(net "SMB_BIC_I2C9_MUX1_SSD10_R_SCL")
	)
	(segment
		(start 350.780604 -83.787234)
		(end 351.60331 -83.787234)
		(width 0.13208)
		(layer "F.Cu")
		(net "SMB_BIC_I2C9_MUX1_SSD10_R_SCL")
	)
	(segment
		(start 310.517794 -22.413976)
		(end 310.517794 -21.775674)
		(width 0.13208)
		(layer "F.Cu")
		(net "SMB_BIC_I2C9_MUX1_SSD10_R_SCL")
	)
	(segment
		(start 310.485282 -21.743162)
		(end 310.485282 -20.789392)
		(width 0.13208)
		(layer "F.Cu")
		(net "SMB_BIC_I2C9_MUX1_SSD10_R_SCL")
	)
	(segment
		(start 310.659272 -22.555454)
		(end 310.517794 -22.413976)
		(width 0.13208)
		(layer "F.Cu")
		(net "SMB_BIC_I2C9_MUX1_SSD10_R_SCL")
	)
	(via
		(at 321.808348 -76.750418)
		(size 0.508)
		(drill 0.254)
		(layers "F.Cu" "B.Cu")
		(net "SMB_BIC_I2C9_MUX1_SSD10_R_SCL")
	)
	(via
		(at 351.60331 -83.787234)
		(size 0.508)
		(drill 0.254)
		(layers "F.Cu" "B.Cu")
		(net "SMB_BIC_I2C9_MUX1_SSD10_R_SCL")
	)
	(via
		(at 310.517794 -21.775674)
		(size 0.508)
		(drill 0.254)
		(layers "F.Cu" "B.Cu")
		(net "SMB_BIC_I2C9_MUX1_SSD10_R_SCL")
	)
	(segment
		(start 308.964076 -32.243014)
		(end 321.808348 -45.087286)
		(width 0.15494)
		(layer "In5.Cu")
		(net "SMB_BIC_I2C9_MUX1_SSD10_R_SCL")
	)
	(segment
		(start 310.517794 -21.775674)
		(end 309.477664 -21.775674)
		(width 0.15494)
		(layer "In5.Cu")
		(net "SMB_BIC_I2C9_MUX1_SSD10_R_SCL")
	)
	(segment
		(start 309.477664 -21.775674)
		(end 308.916578 -22.33676)
		(width 0.15494)
		(layer "In5.Cu")
		(net "SMB_BIC_I2C9_MUX1_SSD10_R_SCL")
	)
	(segment
		(start 308.964076 -31.095188)
		(end 308.964076 -32.243014)
		(width 0.15494)
		(layer "In5.Cu")
		(net "SMB_BIC_I2C9_MUX1_SSD10_R_SCL")
	)
	(segment
		(start 310.06923 -29.990034)
		(end 308.964076 -31.095188)
		(width 0.15494)
		(layer "In5.Cu")
		(net "SMB_BIC_I2C9_MUX1_SSD10_R_SCL")
	)
	(segment
		(start 308.916578 -27.014424)
		(end 310.06923 -28.167076)
		(width 0.15494)
		(layer "In5.Cu")
		(net "SMB_BIC_I2C9_MUX1_SSD10_R_SCL")
	)
	(segment
		(start 308.916578 -22.33676)
		(end 308.916578 -27.014424)
		(width 0.15494)
		(layer "In5.Cu")
		(net "SMB_BIC_I2C9_MUX1_SSD10_R_SCL")
	)
	(segment
		(start 321.808348 -45.087286)
		(end 321.808348 -76.750418)
		(width 0.15494)
		(layer "In5.Cu")
		(net "SMB_BIC_I2C9_MUX1_SSD10_R_SCL")
	)
	(segment
		(start 310.06923 -28.167076)
		(end 310.06923 -29.990034)
		(width 0.15494)
		(layer "In5.Cu")
		(net "SMB_BIC_I2C9_MUX1_SSD10_R_SCL")
	)
	(segment
		(start 336.372454 -76.9874)
		(end 335.686654 -77.6732)
		(width 0.15494)
		(layer "In15.Cu")
		(net "SMB_BIC_I2C9_MUX1_SSD10_R_SCL")
	)
	(segment
		(start 322.73113 -77.6732)
		(end 321.808348 -76.750418)
		(width 0.15494)
		(layer "In15.Cu")
		(net "SMB_BIC_I2C9_MUX1_SSD10_R_SCL")
	)
	(segment
		(start 351.60331 -83.787234)
		(end 350.41078 -83.787234)
		(width 0.15494)
		(layer "In15.Cu")
		(net "SMB_BIC_I2C9_MUX1_SSD10_R_SCL")
	)
	(segment
		(start 343.610946 -76.9874)
		(end 336.372454 -76.9874)
		(width 0.15494)
		(layer "In15.Cu")
		(net "SMB_BIC_I2C9_MUX1_SSD10_R_SCL")
	)
	(segment
		(start 350.41078 -83.787234)
		(end 343.610946 -76.9874)
		(width 0.15494)
		(layer "In15.Cu")
		(net "SMB_BIC_I2C9_MUX1_SSD10_R_SCL")
	)
	(segment
		(start 335.686654 -77.6732)
		(end 322.73113 -77.6732)
		(width 0.15494)
		(layer "In15.Cu")
		(net "SMB_BIC_I2C9_MUX1_SSD10_R_SCL")
	)
	(segment
		(start 57.776872 -378.572268)
		(end 57.359804 -378.1552)
		(width 0.13208)
		(layer "F.Cu")
		(net "GPU_BASE_ID1_R")
	)
	(segment
		(start 57.359804 -378.1552)
		(end 56.362346 -378.1552)
		(width 0.13208)
		(layer "F.Cu")
		(net "GPU_BASE_ID1_R")
	)
	(via
		(at 56.362346 -378.1552)
		(size 0.508)
		(drill 0.254)
		(layers "F.Cu" "B.Cu")
		(net "GPU_BASE_ID1_R")
	)
	(segment
		(start 51.39182 -373.742966)
		(end 51.39182 -369.922044)
		(width 0.15494)
		(layer "In9.Cu")
		(net "GPU_BASE_ID1_R")
	)
	(segment
		(start 55.804054 -378.1552)
		(end 51.39182 -373.742966)
		(width 0.15494)
		(layer "In9.Cu")
		(net "GPU_BASE_ID1_R")
	)
	(segment
		(start 51.39182 -369.922044)
		(end 49.871376 -368.4016)
		(width 0.15494)
		(layer "In9.Cu")
		(net "GPU_BASE_ID1_R")
	)
	(segment
		(start 43.898566 -368.4016)
		(end 43.310048 -368.990118)
		(width 0.15494)
		(layer "In9.Cu")
		(net "GPU_BASE_ID1_R")
	)
	(segment
		(start 49.871376 -368.4016)
		(end 43.898566 -368.4016)
		(width 0.15494)
		(layer "In9.Cu")
		(net "GPU_BASE_ID1_R")
	)
	(segment
		(start 56.362346 -378.1552)
		(end 55.804054 -378.1552)
		(width 0.15494)
		(layer "In9.Cu")
		(net "GPU_BASE_ID1_R")
	)
	(segment
		(start 265.843258 -343.205308)
		(end 265.843258 -355.022912)
		(width 0.13208)
		(layer "F.Cu")
		(net "RST_MB_BMC_BUF_R_N")
	)
	(segment
		(start 265.843258 -355.022912)
		(end 270.611346 -359.791)
		(width 0.13208)
		(layer "F.Cu")
		(net "RST_MB_BMC_BUF_R_N")
	)
	(segment
		(start 280.55697 -410.136086)
		(end 279.894284 -410.136086)
		(width 0.13208)
		(layer "F.Cu")
		(net "RST_MB_BMC_BUF_R_N")
	)
	(segment
		(start 279.894284 -410.136086)
		(end 275.26869 -410.136086)
		(width 0.13208)
		(layer "F.Cu")
		(net "RST_MB_BMC_BUF_R_N")
	)
	(segment
		(start 265.70305 -343.0651)
		(end 265.843258 -343.205308)
		(width 0.13208)
		(layer "F.Cu")
		(net "RST_MB_BMC_BUF_R_N")
	)
	(segment
		(start 282.147772 -408.545284)
		(end 280.55697 -410.136086)
		(width 0.13208)
		(layer "F.Cu")
		(net "RST_MB_BMC_BUF_R_N")
	)
	(segment
		(start 282.147772 -363.224572)
		(end 282.147772 -408.545284)
		(width 0.13208)
		(layer "F.Cu")
		(net "RST_MB_BMC_BUF_R_N")
	)
	(segment
		(start 270.611346 -359.791)
		(end 278.7142 -359.791)
		(width 0.13208)
		(layer "F.Cu")
		(net "RST_MB_BMC_BUF_R_N")
	)
	(segment
		(start 278.7142 -359.791)
		(end 282.147772 -363.224572)
		(width 0.13208)
		(layer "F.Cu")
		(net "RST_MB_BMC_BUF_R_N")
	)
	(via
		(at 366.0648 -340.0298)
		(size 0.508)
		(drill 0.254)
		(layers "F.Cu" "B.Cu")
		(net "RST_MB_BMC_BUF_R_N")
	)
	(via
		(at 265.70305 -343.0651)
		(size 0.508)
		(drill 0.254)
		(layers "F.Cu" "B.Cu")
		(net "RST_MB_BMC_BUF_R_N")
	)
	(via
		(at 279.894284 -410.136086)
		(size 0.508)
		(drill 0.254)
		(layers "F.Cu" "B.Cu")
		(net "RST_MB_BMC_BUF_R_N")
	)
	(segment
		(start 265.70305 -341.28075)
		(end 266.6238 -340.36)
		(width 0.13208)
		(layer "B.Cu")
		(net "RST_MB_BMC_BUF_R_N")
	)
	(segment
		(start 266.6238 -340.36)
		(end 347.1926 -340.36)
		(width 0.13208)
		(layer "B.Cu")
		(net "RST_MB_BMC_BUF_R_N")
	)
	(segment
		(start 347.1926 -340.36)
		(end 348.8944 -342.0618)
		(width 0.13208)
		(layer "B.Cu")
		(net "RST_MB_BMC_BUF_R_N")
	)
	(segment
		(start 362.0516 -342.0618)
		(end 364.0836 -340.0298)
		(width 0.13208)
		(layer "B.Cu")
		(net "RST_MB_BMC_BUF_R_N")
	)
	(segment
		(start 364.0836 -340.0298)
		(end 366.0648 -340.0298)
		(width 0.13208)
		(layer "B.Cu")
		(net "RST_MB_BMC_BUF_R_N")
	)
	(segment
		(start 348.8944 -342.0618)
		(end 362.0516 -342.0618)
		(width 0.13208)
		(layer "B.Cu")
		(net "RST_MB_BMC_BUF_R_N")
	)
	(segment
		(start 265.70305 -343.0651)
		(end 265.70305 -341.28075)
		(width 0.13208)
		(layer "B.Cu")
		(net "RST_MB_BMC_BUF_R_N")
	)
	(segment
		(start 366.0648 -352.22434)
		(end 379.44806 -365.6076)
		(width 0.15494)
		(layer "In9.Cu")
		(net "RST_MB_BMC_BUF_R_N")
	)
	(segment
		(start 379.44806 -365.6076)
		(end 387.50748 -365.6076)
		(width 0.15494)
		(layer "In9.Cu")
		(net "RST_MB_BMC_BUF_R_N")
	)
	(segment
		(start 387.50748 -365.6076)
		(end 390.889998 -368.990118)
		(width 0.15494)
		(layer "In9.Cu")
		(net "RST_MB_BMC_BUF_R_N")
	)
	(segment
		(start 366.0648 -340.0298)
		(end 366.0648 -352.22434)
		(width 0.15494)
		(layer "In9.Cu")
		(net "RST_MB_BMC_BUF_R_N")
	)
	(via
		(at 194.749928 -290.199826)
		(size 0.6604)
		(drill 0.3302)
		(layers "F.Cu" "B.Cu")
		(net "UART_PEX1_CLI_R_TX")
	)
	(via
		(at 186.944 -219.523564)
		(size 0.508)
		(drill 0.254)
		(layers "F.Cu" "B.Cu")
		(net "UART_PEX1_CLI_R_TX")
	)
	(via
		(at 125.748542 -212.238844)
		(size 0.508)
		(drill 0.254)
		(layers "F.Cu" "B.Cu")
		(net "UART_PEX1_CLI_R_TX")
	)
	(segment
		(start 194.749928 -289.297618)
		(end 194.749928 -290.199826)
		(width 0.13208)
		(layer "B.Cu")
		(net "UART_PEX1_CLI_R_TX")
	)
	(segment
		(start 194.503294 -291.224716)
		(end 191.823848 -291.224716)
		(width 0.13208)
		(layer "B.Cu")
		(net "UART_PEX1_CLI_R_TX")
	)
	(segment
		(start 194.280028 -281.0002)
		(end 194.407028 -281.1272)
		(width 0.13208)
		(layer "B.Cu")
		(net "UART_PEX1_CLI_R_TX")
	)
	(segment
		(start 194.407028 -281.1272)
		(end 194.8815 -281.1272)
		(width 0.13208)
		(layer "B.Cu")
		(net "UART_PEX1_CLI_R_TX")
	)
	(segment
		(start 194.280028 -226.859592)
		(end 194.280028 -281.0002)
		(width 0.13208)
		(layer "B.Cu")
		(net "UART_PEX1_CLI_R_TX")
	)
	(segment
		(start 127.321818 -212.238844)
		(end 125.748542 -212.238844)
		(width 0.13208)
		(layer "B.Cu")
		(net "UART_PEX1_CLI_R_TX")
	)
	(segment
		(start 186.944 -219.523564)
		(end 194.280028 -226.859592)
		(width 0.13208)
		(layer "B.Cu")
		(net "UART_PEX1_CLI_R_TX")
	)
	(segment
		(start 195.2498 -288.797746)
		(end 194.749928 -289.297618)
		(width 0.13208)
		(layer "B.Cu")
		(net "UART_PEX1_CLI_R_TX")
	)
	(segment
		(start 194.749928 -290.978082)
		(end 194.503294 -291.224716)
		(width 0.13208)
		(layer "B.Cu")
		(net "UART_PEX1_CLI_R_TX")
	)
	(segment
		(start 194.8815 -281.1272)
		(end 195.2498 -281.4955)
		(width 0.13208)
		(layer "B.Cu")
		(net "UART_PEX1_CLI_R_TX")
	)
	(segment
		(start 194.749928 -290.199826)
		(end 194.749928 -290.978082)
		(width 0.13208)
		(layer "B.Cu")
		(net "UART_PEX1_CLI_R_TX")
	)
	(segment
		(start 195.2498 -281.4955)
		(end 195.2498 -288.797746)
		(width 0.13208)
		(layer "B.Cu")
		(net "UART_PEX1_CLI_R_TX")
	)
	(segment
		(start 128.749298 -212.238844)
		(end 125.748542 -212.238844)
		(width 0.15494)
		(layer "In15.Cu")
		(net "UART_PEX1_CLI_R_TX")
	)
	(segment
		(start 143.535146 -214.475314)
		(end 140.101066 -214.475314)
		(width 0.15494)
		(layer "In15.Cu")
		(net "UART_PEX1_CLI_R_TX")
	)
	(segment
		(start 186.944 -219.523564)
		(end 185.705496 -219.523564)
		(width 0.15494)
		(layer "In15.Cu")
		(net "UART_PEX1_CLI_R_TX")
	)
	(segment
		(start 140.101066 -214.475314)
		(end 139.84478 -214.7316)
		(width 0.15494)
		(layer "In15.Cu")
		(net "UART_PEX1_CLI_R_TX")
	)
	(segment
		(start 139.84478 -216.202006)
		(end 139.468606 -216.57818)
		(width 0.15494)
		(layer "In15.Cu")
		(net "UART_PEX1_CLI_R_TX")
	)
	(segment
		(start 181.6862 -215.504268)
		(end 144.5641 -215.504268)
		(width 0.15494)
		(layer "In15.Cu")
		(net "UART_PEX1_CLI_R_TX")
	)
	(segment
		(start 139.468606 -216.57818)
		(end 133.088634 -216.57818)
		(width 0.15494)
		(layer "In15.Cu")
		(net "UART_PEX1_CLI_R_TX")
	)
	(segment
		(start 144.5641 -215.504268)
		(end 143.535146 -214.475314)
		(width 0.15494)
		(layer "In15.Cu")
		(net "UART_PEX1_CLI_R_TX")
	)
	(segment
		(start 133.088634 -216.57818)
		(end 128.749298 -212.238844)
		(width 0.15494)
		(layer "In15.Cu")
		(net "UART_PEX1_CLI_R_TX")
	)
	(segment
		(start 185.705496 -219.523564)
		(end 181.6862 -215.504268)
		(width 0.15494)
		(layer "In15.Cu")
		(net "UART_PEX1_CLI_R_TX")
	)
	(segment
		(start 139.84478 -214.7316)
		(end 139.84478 -216.202006)
		(width 0.15494)
		(layer "In15.Cu")
		(net "UART_PEX1_CLI_R_TX")
	)
	(segment
		(start 264.539984 -79.017876)
		(end 264.539984 -77.679804)
		(width 0.13208)
		(layer "F.Cu")
		(net "CLK_BUFFER_9ZXL0851E_8_15_OE2_N")
	)
	(segment
		(start 263.85266 -80.92948)
		(end 263.85266 -80.39989)
		(width 0.13208)
		(layer "F.Cu")
		(net "CLK_BUFFER_9ZXL0851E_8_15_OE2_N")
	)
	(segment
		(start 263.72566 -81.05648)
		(end 263.85266 -80.92948)
		(width 0.13208)
		(layer "F.Cu")
		(net "CLK_BUFFER_9ZXL0851E_8_15_OE2_N")
	)
	(segment
		(start 265.5951 -77.679804)
		(end 264.539984 -77.679804)
		(width 0.13208)
		(layer "F.Cu")
		(net "CLK_BUFFER_9ZXL0851E_8_15_OE2_N")
	)
	(segment
		(start 264.539984 -79.712566)
		(end 264.539984 -79.017876)
		(width 0.13208)
		(layer "F.Cu")
		(net "CLK_BUFFER_9ZXL0851E_8_15_OE2_N")
	)
	(segment
		(start 263.551924 -81.05648)
		(end 263.72566 -81.05648)
		(width 0.13208)
		(layer "F.Cu")
		(net "CLK_BUFFER_9ZXL0851E_8_15_OE2_N")
	)
	(segment
		(start 263.85266 -80.39989)
		(end 264.539984 -79.712566)
		(width 0.13208)
		(layer "F.Cu")
		(net "CLK_BUFFER_9ZXL0851E_8_15_OE2_N")
	)
	(via
		(at 264.539984 -79.017876)
		(size 0.762)
		(drill 0.381)
		(layers "F.Cu" "B.Cu")
		(net "CLK_BUFFER_9ZXL0851E_8_15_OE2_N")
	)
	(segment
		(start 264.670286 -251.158502)
		(end 264.670286 -251.956824)
		(width 0.13208)
		(layer "F.Cu")
		(net "PEX2_MODE_SEL8")
	)
	(segment
		(start 264.670286 -250.470924)
		(end 264.670286 -251.158502)
		(width 0.13208)
		(layer "F.Cu")
		(net "PEX2_MODE_SEL8")
	)
	(segment
		(start 295.649904 -282.599892)
		(end 296.124884 -283.074872)
		(width 0.1651)
		(layer "F.Cu")
		(net "PEX2_MODE_SEL8")
	)
	(via
		(at 264.670286 -251.158502)
		(size 0.508)
		(drill 0.254)
		(layers "F.Cu" "B.Cu")
		(net "PEX2_MODE_SEL8")
	)
	(via
		(at 296.124884 -283.074872)
		(size 0.4064)
		(drill 0.2032)
		(layers "F.Cu" "B.Cu")
		(net "PEX2_MODE_SEL8")
	)
	(segment
		(start 293.08425 -268.092936)
		(end 293.09314 -268.092936)
		(width 0.13208)
		(layer "B.Cu")
		(net "PEX2_MODE_SEL8")
	)
	(segment
		(start 293.09314 -268.092936)
		(end 297.034966 -272.034762)
		(width 0.13208)
		(layer "B.Cu")
		(net "PEX2_MODE_SEL8")
	)
	(segment
		(start 267.839444 -255.20396)
		(end 268.391894 -255.75641)
		(width 0.13208)
		(layer "B.Cu")
		(net "PEX2_MODE_SEL8")
	)
	(segment
		(start 280.747724 -255.75641)
		(end 293.08425 -268.092936)
		(width 0.13208)
		(layer "B.Cu")
		(net "PEX2_MODE_SEL8")
	)
	(segment
		(start 265.49731 -255.20396)
		(end 267.839444 -255.20396)
		(width 0.13208)
		(layer "B.Cu")
		(net "PEX2_MODE_SEL8")
	)
	(segment
		(start 297.034966 -272.034762)
		(end 297.034966 -282.16479)
		(width 0.13208)
		(layer "B.Cu")
		(net "PEX2_MODE_SEL8")
	)
	(segment
		(start 268.391894 -255.75641)
		(end 280.747724 -255.75641)
		(width 0.13208)
		(layer "B.Cu")
		(net "PEX2_MODE_SEL8")
	)
	(segment
		(start 264.19683 -253.90348)
		(end 265.49731 -255.20396)
		(width 0.13208)
		(layer "B.Cu")
		(net "PEX2_MODE_SEL8")
	)
	(segment
		(start 297.034966 -282.16479)
		(end 296.124884 -283.074872)
		(width 0.13208)
		(layer "B.Cu")
		(net "PEX2_MODE_SEL8")
	)
	(segment
		(start 264.19683 -251.631958)
		(end 264.19683 -253.90348)
		(width 0.13208)
		(layer "B.Cu")
		(net "PEX2_MODE_SEL8")
	)
	(segment
		(start 264.670286 -251.158502)
		(end 264.19683 -251.631958)
		(width 0.13208)
		(layer "B.Cu")
		(net "PEX2_MODE_SEL8")
	)
	(segment
		(start 284.517846 -22.413976)
		(end 284.659324 -22.555454)
		(width 0.13208)
		(layer "F.Cu")
		(net "SMB_BIC_I2C9_MUX1_SSD9_R_SCL")
	)
	(segment
		(start 351.151952 -86.073234)
		(end 350.780604 -86.073234)
		(width 0.13208)
		(layer "F.Cu")
		(net "SMB_BIC_I2C9_MUX1_SSD9_R_SCL")
	)
	(segment
		(start 352.520504 -86.073234)
		(end 351.691956 -86.073234)
		(width 0.13208)
		(layer "F.Cu")
		(net "SMB_BIC_I2C9_MUX1_SSD9_R_SCL")
	)
	(segment
		(start 284.517846 -21.775674)
		(end 284.517846 -22.413976)
		(width 0.13208)
		(layer "F.Cu")
		(net "SMB_BIC_I2C9_MUX1_SSD9_R_SCL")
	)
	(segment
		(start 351.421954 -85.803232)
		(end 351.151952 -86.073234)
		(width 0.13208)
		(layer "F.Cu")
		(net "SMB_BIC_I2C9_MUX1_SSD9_R_SCL")
	)
	(segment
		(start 351.691956 -86.073234)
		(end 351.421954 -85.803232)
		(width 0.13208)
		(layer "F.Cu")
		(net "SMB_BIC_I2C9_MUX1_SSD9_R_SCL")
	)
	(segment
		(start 284.485334 -21.743162)
		(end 284.485334 -20.789392)
		(width 0.13208)
		(layer "F.Cu")
		(net "SMB_BIC_I2C9_MUX1_SSD9_R_SCL")
	)
	(segment
		(start 284.517846 -21.775674)
		(end 284.485334 -21.743162)
		(width 0.13208)
		(layer "F.Cu")
		(net "SMB_BIC_I2C9_MUX1_SSD9_R_SCL")
	)
	(via
		(at 298.083986 -77.456792)
		(size 0.508)
		(drill 0.254)
		(layers "F.Cu" "B.Cu")
		(net "SMB_BIC_I2C9_MUX1_SSD9_R_SCL")
	)
	(via
		(at 284.517846 -21.775674)
		(size 0.508)
		(drill 0.254)
		(layers "F.Cu" "B.Cu")
		(net "SMB_BIC_I2C9_MUX1_SSD9_R_SCL")
	)
	(via
		(at 351.421954 -85.803232)
		(size 0.508)
		(drill 0.254)
		(layers "F.Cu" "B.Cu")
		(net "SMB_BIC_I2C9_MUX1_SSD9_R_SCL")
	)
	(segment
		(start 282.964128 -32.320992)
		(end 295.78808 -45.144944)
		(width 0.15494)
		(layer "In5.Cu")
		(net "SMB_BIC_I2C9_MUX1_SSD9_R_SCL")
	)
	(segment
		(start 284.517846 -21.775674)
		(end 283.477716 -21.775674)
		(width 0.15494)
		(layer "In5.Cu")
		(net "SMB_BIC_I2C9_MUX1_SSD9_R_SCL")
	)
	(segment
		(start 295.78808 -75.822556)
		(end 297.422316 -77.456792)
		(width 0.15494)
		(layer "In5.Cu")
		(net "SMB_BIC_I2C9_MUX1_SSD9_R_SCL")
	)
	(segment
		(start 282.91663 -22.33676)
		(end 282.91663 -27.046174)
		(width 0.15494)
		(layer "In5.Cu")
		(net "SMB_BIC_I2C9_MUX1_SSD9_R_SCL")
	)
	(segment
		(start 295.78808 -45.144944)
		(end 295.78808 -75.822556)
		(width 0.15494)
		(layer "In5.Cu")
		(net "SMB_BIC_I2C9_MUX1_SSD9_R_SCL")
	)
	(segment
		(start 284.048962 -30.003242)
		(end 282.964128 -31.088076)
		(width 0.15494)
		(layer "In5.Cu")
		(net "SMB_BIC_I2C9_MUX1_SSD9_R_SCL")
	)
	(segment
		(start 284.048962 -28.178506)
		(end 284.048962 -30.003242)
		(width 0.15494)
		(layer "In5.Cu")
		(net "SMB_BIC_I2C9_MUX1_SSD9_R_SCL")
	)
	(segment
		(start 282.964128 -31.088076)
		(end 282.964128 -32.320992)
		(width 0.15494)
		(layer "In5.Cu")
		(net "SMB_BIC_I2C9_MUX1_SSD9_R_SCL")
	)
	(segment
		(start 282.91663 -27.046174)
		(end 284.048962 -28.178506)
		(width 0.15494)
		(layer "In5.Cu")
		(net "SMB_BIC_I2C9_MUX1_SSD9_R_SCL")
	)
	(segment
		(start 283.477716 -21.775674)
		(end 282.91663 -22.33676)
		(width 0.15494)
		(layer "In5.Cu")
		(net "SMB_BIC_I2C9_MUX1_SSD9_R_SCL")
	)
	(segment
		(start 297.422316 -77.456792)
		(end 298.083986 -77.456792)
		(width 0.15494)
		(layer "In5.Cu")
		(net "SMB_BIC_I2C9_MUX1_SSD9_R_SCL")
	)
	(segment
		(start 321.131438 -77.978)
		(end 321.791838 -78.6384)
		(width 0.15494)
		(layer "In15.Cu")
		(net "SMB_BIC_I2C9_MUX1_SSD9_R_SCL")
	)
	(segment
		(start 320.345054 -77.978)
		(end 321.131438 -77.978)
		(width 0.15494)
		(layer "In15.Cu")
		(net "SMB_BIC_I2C9_MUX1_SSD9_R_SCL")
	)
	(segment
		(start 351.105978 -85.803232)
		(end 351.421954 -85.803232)
		(width 0.15494)
		(layer "In15.Cu")
		(net "SMB_BIC_I2C9_MUX1_SSD9_R_SCL")
	)
	(segment
		(start 312.340498 -75.746356)
		(end 318.11341 -75.746356)
		(width 0.15494)
		(layer "In15.Cu")
		(net "SMB_BIC_I2C9_MUX1_SSD9_R_SCL")
	)
	(segment
		(start 345.388946 -80.0862)
		(end 351.105978 -85.803232)
		(width 0.15494)
		(layer "In15.Cu")
		(net "SMB_BIC_I2C9_MUX1_SSD9_R_SCL")
	)
	(segment
		(start 321.791838 -78.6384)
		(end 332.688946 -78.6384)
		(width 0.15494)
		(layer "In15.Cu")
		(net "SMB_BIC_I2C9_MUX1_SSD9_R_SCL")
	)
	(segment
		(start 332.688946 -78.6384)
		(end 333.70774 -79.657194)
		(width 0.15494)
		(layer "In15.Cu")
		(net "SMB_BIC_I2C9_MUX1_SSD9_R_SCL")
	)
	(segment
		(start 298.578778 -76.962)
		(end 311.124854 -76.962)
		(width 0.15494)
		(layer "In15.Cu")
		(net "SMB_BIC_I2C9_MUX1_SSD9_R_SCL")
	)
	(segment
		(start 333.70774 -79.657194)
		(end 334.74406 -80.0862)
		(width 0.15494)
		(layer "In15.Cu")
		(net "SMB_BIC_I2C9_MUX1_SSD9_R_SCL")
	)
	(segment
		(start 334.74406 -80.0862)
		(end 345.388946 -80.0862)
		(width 0.15494)
		(layer "In15.Cu")
		(net "SMB_BIC_I2C9_MUX1_SSD9_R_SCL")
	)
	(segment
		(start 311.124854 -76.962)
		(end 312.340498 -75.746356)
		(width 0.15494)
		(layer "In15.Cu")
		(net "SMB_BIC_I2C9_MUX1_SSD9_R_SCL")
	)
	(segment
		(start 318.11341 -75.746356)
		(end 320.345054 -77.978)
		(width 0.15494)
		(layer "In15.Cu")
		(net "SMB_BIC_I2C9_MUX1_SSD9_R_SCL")
	)
	(segment
		(start 298.083986 -77.456792)
		(end 298.578778 -76.962)
		(width 0.15494)
		(layer "In15.Cu")
		(net "SMB_BIC_I2C9_MUX1_SSD9_R_SCL")
	)
	(segment
		(start 188.099954 -292.099746)
		(end 188.574934 -291.624766)
		(width 0.13208)
		(layer "F.Cu")
		(net "UART_PEX1_CLI_TX")
	)
	(via
		(at 188.574934 -291.624766)
		(size 0.4064)
		(drill 0.2032)
		(layers "F.Cu" "B.Cu")
		(net "UART_PEX1_CLI_TX")
	)
	(via
		(at 189.049914 -292.099746)
		(size 0.6604)
		(drill 0.3302)
		(layers "F.Cu" "B.Cu")
		(net "UART_PEX1_CLI_TX")
	)
	(segment
		(start 190.940944 -292.024816)
		(end 190.866014 -292.099746)
		(width 0.13208)
		(layer "B.Cu")
		(net "UART_PEX1_CLI_TX")
	)
	(segment
		(start 190.866014 -292.099746)
		(end 189.049914 -292.099746)
		(width 0.13208)
		(layer "B.Cu")
		(net "UART_PEX1_CLI_TX")
	)
	(segment
		(start 189.049914 -292.099746)
		(end 188.574934 -291.624766)
		(width 0.13208)
		(layer "B.Cu")
		(net "UART_PEX1_CLI_TX")
	)
	(segment
		(start 191.823848 -292.024816)
		(end 190.940944 -292.024816)
		(width 0.13208)
		(layer "B.Cu")
		(net "UART_PEX1_CLI_TX")
	)
	(segment
		(start 263.740392 -81.556352)
		(end 265.403838 -79.892906)
		(width 0.13208)
		(layer "F.Cu")
		(net "CLK_BUFFER_9ZXL0851E_0_7_OE1_N")
	)
	(segment
		(start 266.860528 -79.892906)
		(end 268.1351 -79.892906)
		(width 0.13208)
		(layer "F.Cu")
		(net "CLK_BUFFER_9ZXL0851E_0_7_OE1_N")
	)
	(segment
		(start 265.403838 -79.892906)
		(end 266.860528 -79.892906)
		(width 0.13208)
		(layer "F.Cu")
		(net "CLK_BUFFER_9ZXL0851E_0_7_OE1_N")
	)
	(segment
		(start 268.1351 -78.885796)
		(end 268.1351 -79.892906)
		(width 0.13208)
		(layer "F.Cu")
		(net "CLK_BUFFER_9ZXL0851E_0_7_OE1_N")
	)
	(segment
		(start 263.551924 -81.556352)
		(end 263.740392 -81.556352)
		(width 0.13208)
		(layer "F.Cu")
		(net "CLK_BUFFER_9ZXL0851E_0_7_OE1_N")
	)
	(via
		(at 266.860528 -79.892906)
		(size 0.762)
		(drill 0.381)
		(layers "F.Cu" "B.Cu")
		(net "CLK_BUFFER_9ZXL0851E_0_7_OE1_N")
	)
	(segment
		(start 268.734286 -251.956824)
		(end 268.734286 -251.158502)
		(width 0.13208)
		(layer "F.Cu")
		(net "PEX2_MODE_SEL6")
	)
	(segment
		(start 268.734286 -251.158502)
		(end 268.734286 -250.470924)
		(width 0.13208)
		(layer "F.Cu")
		(net "PEX2_MODE_SEL6")
	)
	(segment
		(start 297.549824 -283.549852)
		(end 298.024804 -284.024832)
		(width 0.13208)
		(layer "F.Cu")
		(net "PEX2_MODE_SEL6")
	)
	(via
		(at 298.024804 -284.024832)
		(size 0.4064)
		(drill 0.2032)
		(layers "F.Cu" "B.Cu")
		(net "PEX2_MODE_SEL6")
	)
	(via
		(at 268.734286 -251.158502)
		(size 0.508)
		(drill 0.254)
		(layers "F.Cu" "B.Cu")
		(net "PEX2_MODE_SEL6")
	)
	(segment
		(start 299.202856 -283.497528)
		(end 299.467778 -283.232606)
		(width 0.13208)
		(layer "B.Cu")
		(net "PEX2_MODE_SEL6")
	)
	(segment
		(start 299.682916 -282.635198)
		(end 300.065186 -282.635198)
		(width 0.13208)
		(layer "B.Cu")
		(net "PEX2_MODE_SEL6")
	)
	(segment
		(start 299.477684 -270.959072)
		(end 299.468794 -270.959072)
		(width 0.13208)
		(layer "B.Cu")
		(net "PEX2_MODE_SEL6")
	)
	(segment
		(start 299.467778 -283.232606)
		(end 299.467778 -282.850336)
		(width 0.13208)
		(layer "B.Cu")
		(net "PEX2_MODE_SEL6")
	)
	(segment
		(start 300.83506 -281.865324)
		(end 300.83506 -272.316448)
		(width 0.13208)
		(layer "B.Cu")
		(net "PEX2_MODE_SEL6")
	)
	(segment
		(start 299.467778 -282.850336)
		(end 299.682916 -282.635198)
		(width 0.13208)
		(layer "B.Cu")
		(net "PEX2_MODE_SEL6")
	)
	(segment
		(start 268.261846 -251.630942)
		(end 268.734286 -251.158502)
		(width 0.13208)
		(layer "B.Cu")
		(net "PEX2_MODE_SEL6")
	)
	(segment
		(start 283.128212 -254.61849)
		(end 269.228062 -254.61849)
		(width 0.13208)
		(layer "B.Cu")
		(net "PEX2_MODE_SEL6")
	)
	(segment
		(start 299.468794 -270.959072)
		(end 283.128212 -254.61849)
		(width 0.13208)
		(layer "B.Cu")
		(net "PEX2_MODE_SEL6")
	)
	(segment
		(start 268.261846 -253.652274)
		(end 268.261846 -251.630942)
		(width 0.13208)
		(layer "B.Cu")
		(net "PEX2_MODE_SEL6")
	)
	(segment
		(start 298.024804 -284.024832)
		(end 298.552108 -283.497528)
		(width 0.13208)
		(layer "B.Cu")
		(net "PEX2_MODE_SEL6")
	)
	(segment
		(start 269.228062 -254.61849)
		(end 268.261846 -253.652274)
		(width 0.13208)
		(layer "B.Cu")
		(net "PEX2_MODE_SEL6")
	)
	(segment
		(start 298.552108 -283.497528)
		(end 299.202856 -283.497528)
		(width 0.13208)
		(layer "B.Cu")
		(net "PEX2_MODE_SEL6")
	)
	(segment
		(start 300.065186 -282.635198)
		(end 300.83506 -281.865324)
		(width 0.13208)
		(layer "B.Cu")
		(net "PEX2_MODE_SEL6")
	)
	(segment
		(start 300.83506 -272.316448)
		(end 299.477684 -270.959072)
		(width 0.13208)
		(layer "B.Cu")
		(net "PEX2_MODE_SEL6")
	)
	(segment
		(start 337.312762 -8.230362)
		(end 336.999072 -7.916672)
		(width 0.13208)
		(layer "F.Cu")
		(net "SMB_BIC_I2C9_MUX1_SSD11_R_SCL")
	)
	(segment
		(start 337.658964 -7.88416)
		(end 337.312762 -8.230362)
		(width 0.13208)
		(layer "F.Cu")
		(net "SMB_BIC_I2C9_MUX1_SSD11_R_SCL")
	)
	(segment
		(start 338.092542 -7.742682)
		(end 337.951064 -7.88416)
		(width 0.13208)
		(layer "F.Cu")
		(net "SMB_BIC_I2C9_MUX1_SSD11_R_SCL")
	)
	(segment
		(start 336.999072 -7.916672)
		(end 336.32648 -7.916672)
		(width 0.13208)
		(layer "F.Cu")
		(net "SMB_BIC_I2C9_MUX1_SSD11_R_SCL")
	)
	(segment
		(start 337.951064 -7.88416)
		(end 337.658964 -7.88416)
		(width 0.13208)
		(layer "F.Cu")
		(net "SMB_BIC_I2C9_MUX1_SSD11_R_SCL")
	)
	(segment
		(start 350.780604 -81.501234)
		(end 351.60331 -81.501234)
		(width 0.13208)
		(layer "F.Cu")
		(net "SMB_BIC_I2C9_MUX1_SSD11_R_SCL")
	)
	(segment
		(start 351.60331 -81.501234)
		(end 352.520504 -81.501234)
		(width 0.13208)
		(layer "F.Cu")
		(net "SMB_BIC_I2C9_MUX1_SSD11_R_SCL")
	)
	(via
		(at 351.60331 -81.501234)
		(size 0.508)
		(drill 0.254)
		(layers "F.Cu" "B.Cu")
		(net "SMB_BIC_I2C9_MUX1_SSD11_R_SCL")
	)
	(via
		(at 337.312762 -8.230362)
		(size 0.508)
		(drill 0.254)
		(layers "F.Cu" "B.Cu")
		(net "SMB_BIC_I2C9_MUX1_SSD11_R_SCL")
	)
	(segment
		(start 342.40724 -75.525376)
		(end 342.40724 -69.642736)
		(width 0.15494)
		(layer "In5.Cu")
		(net "SMB_BIC_I2C9_MUX1_SSD11_R_SCL")
	)
	(segment
		(start 340.4362 -67.671696)
		(end 340.4362 -41.062656)
		(width 0.15494)
		(layer "In5.Cu")
		(net "SMB_BIC_I2C9_MUX1_SSD11_R_SCL")
	)
	(segment
		(start 351.383092 -81.281016)
		(end 348.16288 -81.281016)
		(width 0.15494)
		(layer "In5.Cu")
		(net "SMB_BIC_I2C9_MUX1_SSD11_R_SCL")
	)
	(segment
		(start 351.60331 -81.501234)
		(end 351.383092 -81.281016)
		(width 0.15494)
		(layer "In5.Cu")
		(net "SMB_BIC_I2C9_MUX1_SSD11_R_SCL")
	)
	(segment
		(start 340.4362 -41.062656)
		(end 334.936846 -35.563302)
		(width 0.15494)
		(layer "In5.Cu")
		(net "SMB_BIC_I2C9_MUX1_SSD11_R_SCL")
	)
	(segment
		(start 334.936846 -31.094172)
		(end 336.046572 -29.984446)
		(width 0.15494)
		(layer "In5.Cu")
		(net "SMB_BIC_I2C9_MUX1_SSD11_R_SCL")
	)
	(segment
		(start 348.16288 -81.281016)
		(end 342.40724 -75.525376)
		(width 0.15494)
		(layer "In5.Cu")
		(net "SMB_BIC_I2C9_MUX1_SSD11_R_SCL")
	)
	(segment
		(start 337.312762 -11.984228)
		(end 337.312762 -8.230362)
		(width 0.15494)
		(layer "In5.Cu")
		(net "SMB_BIC_I2C9_MUX1_SSD11_R_SCL")
	)
	(segment
		(start 334.936846 -35.563302)
		(end 334.936846 -31.094172)
		(width 0.15494)
		(layer "In5.Cu")
		(net "SMB_BIC_I2C9_MUX1_SSD11_R_SCL")
	)
	(segment
		(start 336.046572 -28.191714)
		(end 334.916526 -27.061668)
		(width 0.15494)
		(layer "In5.Cu")
		(net "SMB_BIC_I2C9_MUX1_SSD11_R_SCL")
	)
	(segment
		(start 334.916526 -27.061668)
		(end 334.916526 -14.380464)
		(width 0.15494)
		(layer "In5.Cu")
		(net "SMB_BIC_I2C9_MUX1_SSD11_R_SCL")
	)
	(segment
		(start 336.046572 -29.984446)
		(end 336.046572 -28.191714)
		(width 0.15494)
		(layer "In5.Cu")
		(net "SMB_BIC_I2C9_MUX1_SSD11_R_SCL")
	)
	(segment
		(start 342.40724 -69.642736)
		(end 340.4362 -67.671696)
		(width 0.15494)
		(layer "In5.Cu")
		(net "SMB_BIC_I2C9_MUX1_SSD11_R_SCL")
	)
	(segment
		(start 334.916526 -14.380464)
		(end 337.312762 -11.984228)
		(width 0.15494)
		(layer "In5.Cu")
		(net "SMB_BIC_I2C9_MUX1_SSD11_R_SCL")
	)
	(segment
		(start 337.690206 -227.583238)
		(end 337.690206 -228.475794)
		(width 0.13208)
		(layer "F.Cu")
		(net "SYS_PWR_READY_N")
	)
	(segment
		(start 336.931 -230.378)
		(end 336.931 -231.521)
		(width 0.13208)
		(layer "F.Cu")
		(net "SYS_PWR_READY_N")
	)
	(segment
		(start 337.566 -229.743)
		(end 336.931 -230.378)
		(width 0.13208)
		(layer "F.Cu")
		(net "SYS_PWR_READY_N")
	)
	(segment
		(start 337.690206 -228.475794)
		(end 337.566 -228.6)
		(width 0.13208)
		(layer "F.Cu")
		(net "SYS_PWR_READY_N")
	)
	(segment
		(start 336.931 -231.521)
		(end 336.931 -233.66095)
		(width 0.13208)
		(layer "F.Cu")
		(net "SYS_PWR_READY_N")
	)
	(segment
		(start 337.293966 -227.186998)
		(end 337.690206 -227.583238)
		(width 0.13208)
		(layer "F.Cu")
		(net "SYS_PWR_READY_N")
	)
	(segment
		(start 337.566 -228.6)
		(end 337.566 -229.743)
		(width 0.13208)
		(layer "F.Cu")
		(net "SYS_PWR_READY_N")
	)
	(via
		(at 336.931 -231.521)
		(size 0.762)
		(drill 0.381)
		(layers "F.Cu" "B.Cu")
		(net "SYS_PWR_READY_N")
	)
	(segment
		(start 199.165972 -77.889608)
		(end 199.266302 -77.989938)
		(width 0.4572)
		(layer "F.Cu")
		(net "P3V3_NIC3")
	)
	(segment
		(start 219.425266 -123.774962)
		(end 218.812872 -123.774962)
		(width 0.4572)
		(layer "F.Cu")
		(net "P3V3_NIC3")
	)
	(segment
		(start 174.69485 -100.766372)
		(end 174.079662 -100.766372)
		(width 0.4064)
		(layer "F.Cu")
		(net "P3V3_NIC3")
	)
	(segment
		(start 178.908456 -157.680152)
		(end 178.908456 -157.045152)
		(width 0.4064)
		(layer "F.Cu")
		(net "P3V3_NIC3")
	)
	(segment
		(start 199.266302 -77.989938)
		(end 199.266302 -79.463646)
		(width 0.4572)
		(layer "F.Cu")
		(net "P3V3_NIC3")
	)
	(segment
		(start 195.414646 -79.18196)
		(end 196.073014 -79.18196)
		(width 0.4572)
		(layer "F.Cu")
		(net "P3V3_NIC3")
	)
	(segment
		(start 215.475566 -118.207028)
		(end 216.089992 -118.207028)
		(width 0.4064)
		(layer "F.Cu")
		(net "P3V3_NIC3")
	)
	(segment
		(start 199.165972 -77.206348)
		(end 199.165972 -77.889608)
		(width 0.4572)
		(layer "F.Cu")
		(net "P3V3_NIC3")
	)
	(segment
		(start 180.177694 -113.251742)
		(end 180.788056 -113.251742)
		(width 0.4572)
		(layer "F.Cu")
		(net "P3V3_NIC3")
	)
	(via
		(at 209.180176 -120.665494)
		(size 0.508)
		(drill 0.254)
		(layers "F.Cu" "B.Cu")
		(net "P3V3_NIC3")
	)
	(via
		(at 194.651376 -95.989648)
		(size 0.508)
		(drill 0.254)
		(layers "F.Cu" "B.Cu")
		(net "P3V3_NIC3")
	)
	(via
		(at 185.93689 -112.421924)
		(size 0.508)
		(drill 0.254)
		(layers "F.Cu" "B.Cu")
		(net "P3V3_NIC3")
	)
	(via
		(at 205.932024 -119.017034)
		(size 0.508)
		(drill 0.254)
		(layers "F.Cu" "B.Cu")
		(net "P3V3_NIC3")
	)
	(via
		(at 208.48574 -119.695722)
		(size 0.508)
		(drill 0.254)
		(layers "F.Cu" "B.Cu")
		(net "P3V3_NIC3")
	)
	(via
		(at 209.180176 -120.030494)
		(size 0.508)
		(drill 0.254)
		(layers "F.Cu" "B.Cu")
		(net "P3V3_NIC3")
	)
	(via
		(at 192.461134 -156.836872)
		(size 0.6604)
		(drill 0.3302)
		(layers "F.Cu" "B.Cu")
		(net "P3V3_NIC3")
	)
	(via
		(at 207.98536 -115.83924)
		(size 0.508)
		(drill 0.254)
		(layers "F.Cu" "B.Cu")
		(net "P3V3_NIC3")
	)
	(via
		(at 206.90332 -119.076724)
		(size 0.508)
		(drill 0.254)
		(layers "F.Cu" "B.Cu")
		(net "P3V3_NIC3")
	)
	(via
		(at 199.165972 -77.206348)
		(size 0.508)
		(drill 0.254)
		(layers "F.Cu" "B.Cu")
		(net "P3V3_NIC3")
	)
	(via
		(at 178.908456 -157.045152)
		(size 0.508)
		(drill 0.254)
		(layers "F.Cu" "B.Cu")
		(net "P3V3_NIC3")
	)
	(via
		(at 205.932024 -119.652034)
		(size 0.508)
		(drill 0.254)
		(layers "F.Cu" "B.Cu")
		(net "P3V3_NIC3")
	)
	(via
		(at 205.932024 -120.287034)
		(size 0.508)
		(drill 0.254)
		(layers "F.Cu" "B.Cu")
		(net "P3V3_NIC3")
	)
	(via
		(at 194.651376 -97.005648)
		(size 0.508)
		(drill 0.254)
		(layers "F.Cu" "B.Cu")
		(net "P3V3_NIC3")
	)
	(via
		(at 205.932024 -120.922034)
		(size 0.508)
		(drill 0.254)
		(layers "F.Cu" "B.Cu")
		(net "P3V3_NIC3")
	)
	(via
		(at 207.61452 -119.076724)
		(size 0.508)
		(drill 0.254)
		(layers "F.Cu" "B.Cu")
		(net "P3V3_NIC3")
	)
	(via
		(at 190.599822 -114.725958)
		(size 0.508)
		(drill 0.254)
		(layers "F.Cu" "B.Cu")
		(net "P3V3_NIC3")
	)
	(via
		(at 194.651376 -101.069648)
		(size 0.508)
		(drill 0.254)
		(layers "F.Cu" "B.Cu")
		(net "P3V3_NIC3")
	)
	(via
		(at 194.33667 -145.49882)
		(size 0.6604)
		(drill 0.3302)
		(layers "F.Cu" "B.Cu")
		(net "P3V3_NIC3")
	)
	(via
		(at 190.599822 -115.360958)
		(size 0.508)
		(drill 0.254)
		(layers "F.Cu" "B.Cu")
		(net "P3V3_NIC3")
	)
	(via
		(at 218.812872 -123.774962)
		(size 0.508)
		(drill 0.254)
		(layers "F.Cu" "B.Cu")
		(net "P3V3_NIC3")
	)
	(via
		(at 191.234822 -115.360958)
		(size 0.508)
		(drill 0.254)
		(layers "F.Cu" "B.Cu")
		(net "P3V3_NIC3")
	)
	(via
		(at 191.234822 -114.725958)
		(size 0.508)
		(drill 0.254)
		(layers "F.Cu" "B.Cu")
		(net "P3V3_NIC3")
	)
	(via
		(at 185.915808 -113.437924)
		(size 0.508)
		(drill 0.254)
		(layers "F.Cu" "B.Cu")
		(net "P3V3_NIC3")
	)
	(via
		(at 196.073014 -79.18196)
		(size 0.508)
		(drill 0.254)
		(layers "F.Cu" "B.Cu")
		(net "P3V3_NIC3")
	)
	(via
		(at 207.22336 -115.83924)
		(size 0.508)
		(drill 0.254)
		(layers "F.Cu" "B.Cu")
		(net "P3V3_NIC3")
	)
	(via
		(at 206.966312 -119.901462)
		(size 0.508)
		(drill 0.254)
		(layers "F.Cu" "B.Cu")
		(net "P3V3_NIC3")
	)
	(via
		(at 194.33667 -152.536398)
		(size 0.6604)
		(drill 0.3302)
		(layers "F.Cu" "B.Cu")
		(net "P3V3_NIC3")
	)
	(via
		(at 216.089992 -118.207028)
		(size 0.508)
		(drill 0.254)
		(layers "F.Cu" "B.Cu")
		(net "P3V3_NIC3")
	)
	(via
		(at 174.079662 -100.766372)
		(size 0.508)
		(drill 0.254)
		(layers "F.Cu" "B.Cu")
		(net "P3V3_NIC3")
	)
	(via
		(at 207.601312 -119.901462)
		(size 0.508)
		(drill 0.254)
		(layers "F.Cu" "B.Cu")
		(net "P3V3_NIC3")
	)
	(via
		(at 208.48574 -120.330722)
		(size 0.508)
		(drill 0.254)
		(layers "F.Cu" "B.Cu")
		(net "P3V3_NIC3")
	)
	(via
		(at 180.788056 -113.251742)
		(size 0.508)
		(drill 0.254)
		(layers "F.Cu" "B.Cu")
		(net "P3V3_NIC3")
	)
	(segment
		(start 192.461134 -156.836872)
		(end 191.34328 -157.954726)
		(width 0.508)
		(layer "B.Cu")
		(net "P3V3_NIC3")
	)
	(segment
		(start 194.33667 -129.973832)
		(end 195.94576 -128.364742)
		(width 0.508)
		(layer "B.Cu")
		(net "P3V3_NIC3")
	)
	(segment
		(start 179.81803 -157.954726)
		(end 178.908456 -157.045152)
		(width 0.508)
		(layer "B.Cu")
		(net "P3V3_NIC3")
	)
	(segment
		(start 185.172096 -113.437924)
		(end 185.915808 -113.437924)
		(width 0.4572)
		(layer "B.Cu")
		(net "P3V3_NIC3")
	)
	(segment
		(start 185.172096 -112.421924)
		(end 185.93689 -112.421924)
		(width 0.4572)
		(layer "B.Cu")
		(net "P3V3_NIC3")
	)
	(segment
		(start 202.506072 -121.95556)
		(end 204.898498 -121.95556)
		(width 0.508)
		(layer "B.Cu")
		(net "P3V3_NIC3")
	)
	(segment
		(start 194.041776 -95.989648)
		(end 194.651376 -95.989648)
		(width 0.4572)
		(layer "B.Cu")
		(net "P3V3_NIC3")
	)
	(segment
		(start 194.041776 -97.005648)
		(end 194.651376 -97.005648)
		(width 0.4572)
		(layer "B.Cu")
		(net "P3V3_NIC3")
	)
	(segment
		(start 194.33667 -154.961336)
		(end 192.461134 -156.836872)
		(width 0.508)
		(layer "B.Cu")
		(net "P3V3_NIC3")
	)
	(segment
		(start 191.34328 -157.954726)
		(end 179.81803 -157.954726)
		(width 0.508)
		(layer "B.Cu")
		(net "P3V3_NIC3")
	)
	(segment
		(start 194.33667 -152.536398)
		(end 194.33667 -154.961336)
		(width 0.508)
		(layer "B.Cu")
		(net "P3V3_NIC3")
	)
	(segment
		(start 202.037442 -125.75921)
		(end 202.037442 -122.42419)
		(width 0.508)
		(layer "B.Cu")
		(net "P3V3_NIC3")
	)
	(segment
		(start 194.33667 -145.49882)
		(end 194.33667 -129.973832)
		(width 0.508)
		(layer "B.Cu")
		(net "P3V3_NIC3")
	)
	(segment
		(start 194.33667 -145.49882)
		(end 194.33667 -152.536398)
		(width 0.508)
		(layer "B.Cu")
		(net "P3V3_NIC3")
	)
	(segment
		(start 194.041776 -101.069648)
		(end 194.651376 -101.069648)
		(width 0.4572)
		(layer "B.Cu")
		(net "P3V3_NIC3")
	)
	(segment
		(start 202.037442 -122.42419)
		(end 202.506072 -121.95556)
		(width 0.508)
		(layer "B.Cu")
		(net "P3V3_NIC3")
	)
	(segment
		(start 204.898498 -121.95556)
		(end 205.932024 -120.922034)
		(width 0.508)
		(layer "B.Cu")
		(net "P3V3_NIC3")
	)
	(segment
		(start 199.43191 -128.364742)
		(end 202.037442 -125.75921)
		(width 0.508)
		(layer "B.Cu")
		(net "P3V3_NIC3")
	)
	(segment
		(start 195.94576 -128.364742)
		(end 199.43191 -128.364742)
		(width 0.508)
		(layer "B.Cu")
		(net "P3V3_NIC3")
	)
	(segment
		(start 344.212926 -88.16975)
		(end 343.894664 -87.851488)
		(width 0.13462)
		(layer "F.Cu")
		(net "CLK_100M_DB800ZL_SSD13_DN")
	)
	(segment
		(start 342.948514 -87.851488)
		(end 342.601804 -87.707978)
		(width 0.13462)
		(layer "F.Cu")
		(net "CLK_100M_DB800ZL_SSD13_DN")
	)
	(segment
		(start 342.601804 -87.707978)
		(end 341.52967 -87.707978)
		(width 0.13462)
		(layer "F.Cu")
		(net "CLK_100M_DB800ZL_SSD13_DN")
	)
	(segment
		(start 343.894664 -87.851488)
		(end 342.948514 -87.851488)
		(width 0.13462)
		(layer "F.Cu")
		(net "CLK_100M_DB800ZL_SSD13_DN")
	)
	(segment
		(start 341.52967 -87.707978)
		(end 341.473282 -87.764366)
		(width 0.13462)
		(layer "F.Cu")
		(net "CLK_100M_DB800ZL_SSD13_DN")
	)
	(segment
		(start 341.473282 -87.764366)
		(end 341.045546 -87.764366)
		(width 0.13462)
		(layer "F.Cu")
		(net "CLK_100M_DB800ZL_SSD13_DN")
	)
	(segment
		(start 298.499784 -283.549852)
		(end 298.974764 -284.024832)
		(width 0.13208)
		(layer "F.Cu")
		(net "PEX2_MODE_SEL10")
	)
	(segment
		(start 269.750286 -251.956824)
		(end 269.750286 -251.158502)
		(width 0.13208)
		(layer "F.Cu")
		(net "PEX2_MODE_SEL10")
	)
	(segment
		(start 269.750286 -251.158502)
		(end 269.750286 -250.470924)
		(width 0.13208)
		(layer "F.Cu")
		(net "PEX2_MODE_SEL10")
	)
	(via
		(at 269.750286 -251.158502)
		(size 0.508)
		(drill 0.254)
		(layers "F.Cu" "B.Cu")
		(net "PEX2_MODE_SEL10")
	)
	(via
		(at 299.696124 -270.410432)
		(size 0.6604)
		(drill 0.3302)
		(layers "F.Cu" "B.Cu")
		(net "PEX2_MODE_SEL10")
	)
	(via
		(at 298.974764 -284.024832)
		(size 0.4064)
		(drill 0.2032)
		(layers "F.Cu" "B.Cu")
		(net "PEX2_MODE_SEL10")
	)
	(segment
		(start 269.959582 -254.33401)
		(end 283.619702 -254.33401)
		(width 0.13208)
		(layer "B.Cu")
		(net "PEX2_MODE_SEL10")
	)
	(segment
		(start 301.842678 -281.798268)
		(end 301.842678 -271.845278)
		(width 0.13208)
		(layer "B.Cu")
		(net "PEX2_MODE_SEL10")
	)
	(segment
		(start 300.407832 -270.410432)
		(end 299.696124 -270.410432)
		(width 0.13208)
		(layer "B.Cu")
		(net "PEX2_MODE_SEL10")
	)
	(segment
		(start 300.258226 -283.553408)
		(end 300.40453 -283.407104)
		(width 0.13208)
		(layer "B.Cu")
		(net "PEX2_MODE_SEL10")
	)
	(segment
		(start 283.619702 -254.33401)
		(end 299.696124 -270.410432)
		(width 0.13208)
		(layer "B.Cu")
		(net "PEX2_MODE_SEL10")
	)
	(segment
		(start 299.748956 -283.553408)
		(end 300.258226 -283.553408)
		(width 0.13208)
		(layer "B.Cu")
		(net "PEX2_MODE_SEL10")
	)
	(segment
		(start 301.03953 -282.601416)
		(end 301.842678 -281.798268)
		(width 0.13208)
		(layer "B.Cu")
		(net "PEX2_MODE_SEL10")
	)
	(segment
		(start 269.277846 -251.630942)
		(end 269.277846 -253.652274)
		(width 0.13208)
		(layer "B.Cu")
		(net "PEX2_MODE_SEL10")
	)
	(segment
		(start 269.750286 -251.158502)
		(end 269.277846 -251.630942)
		(width 0.13208)
		(layer "B.Cu")
		(net "PEX2_MODE_SEL10")
	)
	(segment
		(start 300.631352 -282.601416)
		(end 301.03953 -282.601416)
		(width 0.13208)
		(layer "B.Cu")
		(net "PEX2_MODE_SEL10")
	)
	(segment
		(start 299.277532 -284.024832)
		(end 299.748956 -283.553408)
		(width 0.13208)
		(layer "B.Cu")
		(net "PEX2_MODE_SEL10")
	)
	(segment
		(start 300.40453 -282.828238)
		(end 300.631352 -282.601416)
		(width 0.13208)
		(layer "B.Cu")
		(net "PEX2_MODE_SEL10")
	)
	(segment
		(start 301.842678 -271.845278)
		(end 300.407832 -270.410432)
		(width 0.13208)
		(layer "B.Cu")
		(net "PEX2_MODE_SEL10")
	)
	(segment
		(start 298.974764 -284.024832)
		(end 299.277532 -284.024832)
		(width 0.13208)
		(layer "B.Cu")
		(net "PEX2_MODE_SEL10")
	)
	(segment
		(start 300.40453 -283.407104)
		(end 300.40453 -282.828238)
		(width 0.13208)
		(layer "B.Cu")
		(net "PEX2_MODE_SEL10")
	)
	(segment
		(start 269.277846 -253.652274)
		(end 269.959582 -254.33401)
		(width 0.13208)
		(layer "B.Cu")
		(net "PEX2_MODE_SEL10")
	)
	(segment
		(start 351.890838 -88.521794)
		(end 352.053398 -88.359234)
		(width 0.13208)
		(layer "F.Cu")
		(net "SMB_BIC_I2C9_MUX1_SSD8_R_SCL")
	)
	(segment
		(start 258.485386 -21.743162)
		(end 258.485386 -20.789392)
		(width 0.13208)
		(layer "F.Cu")
		(net "SMB_BIC_I2C9_MUX1_SSD8_R_SCL")
	)
	(segment
		(start 350.884998 -88.756998)
		(end 351.41027 -88.756998)
		(width 0.13208)
		(layer "F.Cu")
		(net "SMB_BIC_I2C9_MUX1_SSD8_R_SCL")
	)
	(segment
		(start 350.780604 -88.359234)
		(end 350.780604 -88.652604)
		(width 0.13208)
		(layer "F.Cu")
		(net "SMB_BIC_I2C9_MUX1_SSD8_R_SCL")
	)
	(segment
		(start 258.517898 -22.413976)
		(end 258.517898 -21.775674)
		(width 0.13208)
		(layer "F.Cu")
		(net "SMB_BIC_I2C9_MUX1_SSD8_R_SCL")
	)
	(segment
		(start 350.780604 -88.652604)
		(end 350.884998 -88.756998)
		(width 0.13208)
		(layer "F.Cu")
		(net "SMB_BIC_I2C9_MUX1_SSD8_R_SCL")
	)
	(segment
		(start 351.471484 -88.695784)
		(end 351.890838 -88.521794)
		(width 0.13208)
		(layer "F.Cu")
		(net "SMB_BIC_I2C9_MUX1_SSD8_R_SCL")
	)
	(segment
		(start 351.41027 -88.756998)
		(end 351.471484 -88.695784)
		(width 0.13208)
		(layer "F.Cu")
		(net "SMB_BIC_I2C9_MUX1_SSD8_R_SCL")
	)
	(segment
		(start 258.517898 -21.775674)
		(end 258.485386 -21.743162)
		(width 0.13208)
		(layer "F.Cu")
		(net "SMB_BIC_I2C9_MUX1_SSD8_R_SCL")
	)
	(segment
		(start 258.659376 -22.555454)
		(end 258.517898 -22.413976)
		(width 0.13208)
		(layer "F.Cu")
		(net "SMB_BIC_I2C9_MUX1_SSD8_R_SCL")
	)
	(segment
		(start 352.053398 -88.359234)
		(end 352.520504 -88.359234)
		(width 0.13208)
		(layer "F.Cu")
		(net "SMB_BIC_I2C9_MUX1_SSD8_R_SCL")
	)
	(via
		(at 258.517898 -21.775674)
		(size 0.508)
		(drill 0.254)
		(layers "F.Cu" "B.Cu")
		(net "SMB_BIC_I2C9_MUX1_SSD8_R_SCL")
	)
	(via
		(at 351.41027 -88.756998)
		(size 0.508)
		(drill 0.254)
		(layers "F.Cu" "B.Cu")
		(net "SMB_BIC_I2C9_MUX1_SSD8_R_SCL")
	)
	(via
		(at 265.522456 -71.09333)
		(size 0.508)
		(drill 0.254)
		(layers "F.Cu" "B.Cu")
		(net "SMB_BIC_I2C9_MUX1_SSD8_R_SCL")
	)
	(segment
		(start 312.547 -83.0326)
		(end 306.388262 -83.0326)
		(width 0.13208)
		(layer "B.Cu")
		(net "SMB_BIC_I2C9_MUX1_SSD8_R_SCL")
	)
	(segment
		(start 287.325054 -80.5688)
		(end 280.812748 -80.5688)
		(width 0.13208)
		(layer "B.Cu")
		(net "SMB_BIC_I2C9_MUX1_SSD8_R_SCL")
	)
	(segment
		(start 266.029186 -70.5866)
		(end 265.522456 -71.09333)
		(width 0.13208)
		(layer "B.Cu")
		(net "SMB_BIC_I2C9_MUX1_SSD8_R_SCL")
	)
	(segment
		(start 290.336224 -83.57997)
		(end 287.325054 -80.5688)
		(width 0.13208)
		(layer "B.Cu")
		(net "SMB_BIC_I2C9_MUX1_SSD8_R_SCL")
	)
	(segment
		(start 306.083462 -83.3374)
		(end 300.043342 -83.3374)
		(width 0.13208)
		(layer "B.Cu")
		(net "SMB_BIC_I2C9_MUX1_SSD8_R_SCL")
	)
	(segment
		(start 276.127972 -76.439776)
		(end 273.805396 -74.1172)
		(width 0.13208)
		(layer "B.Cu")
		(net "SMB_BIC_I2C9_MUX1_SSD8_R_SCL")
	)
	(segment
		(start 317.5508 -88.0364)
		(end 312.547 -83.0326)
		(width 0.13208)
		(layer "B.Cu")
		(net "SMB_BIC_I2C9_MUX1_SSD8_R_SCL")
	)
	(segment
		(start 276.683724 -76.439776)
		(end 276.127972 -76.439776)
		(width 0.13208)
		(layer "B.Cu")
		(net "SMB_BIC_I2C9_MUX1_SSD8_R_SCL")
	)
	(segment
		(start 299.800772 -83.57997)
		(end 290.336224 -83.57997)
		(width 0.13208)
		(layer "B.Cu")
		(net "SMB_BIC_I2C9_MUX1_SSD8_R_SCL")
	)
	(segment
		(start 330.786994 -88.0364)
		(end 317.5508 -88.0364)
		(width 0.13208)
		(layer "B.Cu")
		(net "SMB_BIC_I2C9_MUX1_SSD8_R_SCL")
	)
	(segment
		(start 349.496126 -92.260674)
		(end 335.011268 -92.260674)
		(width 0.13208)
		(layer "B.Cu")
		(net "SMB_BIC_I2C9_MUX1_SSD8_R_SCL")
	)
	(segment
		(start 335.011268 -92.260674)
		(end 330.786994 -88.0364)
		(width 0.13208)
		(layer "B.Cu")
		(net "SMB_BIC_I2C9_MUX1_SSD8_R_SCL")
	)
	(segment
		(start 272.09369 -74.1172)
		(end 268.56309 -70.5866)
		(width 0.13208)
		(layer "B.Cu")
		(net "SMB_BIC_I2C9_MUX1_SSD8_R_SCL")
	)
	(segment
		(start 350.109282 -90.057986)
		(end 350.109282 -91.647518)
		(width 0.13208)
		(layer "B.Cu")
		(net "SMB_BIC_I2C9_MUX1_SSD8_R_SCL")
	)
	(segment
		(start 351.41027 -88.756998)
		(end 350.109282 -90.057986)
		(width 0.13208)
		(layer "B.Cu")
		(net "SMB_BIC_I2C9_MUX1_SSD8_R_SCL")
	)
	(segment
		(start 268.56309 -70.5866)
		(end 266.029186 -70.5866)
		(width 0.13208)
		(layer "B.Cu")
		(net "SMB_BIC_I2C9_MUX1_SSD8_R_SCL")
	)
	(segment
		(start 273.805396 -74.1172)
		(end 272.09369 -74.1172)
		(width 0.13208)
		(layer "B.Cu")
		(net "SMB_BIC_I2C9_MUX1_SSD8_R_SCL")
	)
	(segment
		(start 350.109282 -91.647518)
		(end 349.496126 -92.260674)
		(width 0.13208)
		(layer "B.Cu")
		(net "SMB_BIC_I2C9_MUX1_SSD8_R_SCL")
	)
	(segment
		(start 280.812748 -80.5688)
		(end 276.683724 -76.439776)
		(width 0.13208)
		(layer "B.Cu")
		(net "SMB_BIC_I2C9_MUX1_SSD8_R_SCL")
	)
	(segment
		(start 306.388262 -83.0326)
		(end 306.083462 -83.3374)
		(width 0.13208)
		(layer "B.Cu")
		(net "SMB_BIC_I2C9_MUX1_SSD8_R_SCL")
	)
	(segment
		(start 300.043342 -83.3374)
		(end 299.800772 -83.57997)
		(width 0.13208)
		(layer "B.Cu")
		(net "SMB_BIC_I2C9_MUX1_SSD8_R_SCL")
	)
	(segment
		(start 266.22756 -71.798434)
		(end 267.181076 -71.798434)
		(width 0.15494)
		(layer "In5.Cu")
		(net "SMB_BIC_I2C9_MUX1_SSD8_R_SCL")
	)
	(segment
		(start 269.849092 -69.130418)
		(end 269.849092 -45.205904)
		(width 0.15494)
		(layer "In5.Cu")
		(net "SMB_BIC_I2C9_MUX1_SSD8_R_SCL")
	)
	(segment
		(start 267.181076 -71.798434)
		(end 269.849092 -69.130418)
		(width 0.15494)
		(layer "In5.Cu")
		(net "SMB_BIC_I2C9_MUX1_SSD8_R_SCL")
	)
	(segment
		(start 256.96418 -32.320992)
		(end 256.96418 -31.095696)
		(width 0.15494)
		(layer "In5.Cu")
		(net "SMB_BIC_I2C9_MUX1_SSD8_R_SCL")
	)
	(segment
		(start 256.916682 -27.032966)
		(end 256.916682 -22.33676)
		(width 0.15494)
		(layer "In5.Cu")
		(net "SMB_BIC_I2C9_MUX1_SSD8_R_SCL")
	)
	(segment
		(start 256.96418 -31.095696)
		(end 258.041648 -30.018228)
		(width 0.15494)
		(layer "In5.Cu")
		(net "SMB_BIC_I2C9_MUX1_SSD8_R_SCL")
	)
	(segment
		(start 265.522456 -71.09333)
		(end 266.22756 -71.798434)
		(width 0.15494)
		(layer "In5.Cu")
		(net "SMB_BIC_I2C9_MUX1_SSD8_R_SCL")
	)
	(segment
		(start 258.041648 -30.018228)
		(end 258.041648 -28.157932)
		(width 0.15494)
		(layer "In5.Cu")
		(net "SMB_BIC_I2C9_MUX1_SSD8_R_SCL")
	)
	(segment
		(start 257.477768 -21.775674)
		(end 258.517898 -21.775674)
		(width 0.15494)
		(layer "In5.Cu")
		(net "SMB_BIC_I2C9_MUX1_SSD8_R_SCL")
	)
	(segment
		(start 269.849092 -45.205904)
		(end 256.96418 -32.320992)
		(width 0.15494)
		(layer "In5.Cu")
		(net "SMB_BIC_I2C9_MUX1_SSD8_R_SCL")
	)
	(segment
		(start 258.041648 -28.157932)
		(end 256.916682 -27.032966)
		(width 0.15494)
		(layer "In5.Cu")
		(net "SMB_BIC_I2C9_MUX1_SSD8_R_SCL")
	)
	(segment
		(start 256.916682 -22.33676)
		(end 257.477768 -21.775674)
		(width 0.15494)
		(layer "In5.Cu")
		(net "SMB_BIC_I2C9_MUX1_SSD8_R_SCL")
	)
	(segment
		(start 55.36819 -376.69597)
		(end 56.155336 -376.69597)
		(width 0.13208)
		(layer "F.Cu")
		(net "GPU_BASE_PWR_GD")
	)
	(segment
		(start 56.508142 -376.69597)
		(end 57.36844 -377.556268)
		(width 0.13208)
		(layer "F.Cu")
		(net "GPU_BASE_PWR_GD")
	)
	(segment
		(start 56.155336 -376.69597)
		(end 56.508142 -376.69597)
		(width 0.13208)
		(layer "F.Cu")
		(net "GPU_BASE_PWR_GD")
	)
	(segment
		(start 57.36844 -377.556268)
		(end 57.776872 -377.556268)
		(width 0.13208)
		(layer "F.Cu")
		(net "GPU_BASE_PWR_GD")
	)
	(via
		(at 55.36819 -376.69597)
		(size 0.508)
		(drill 0.254)
		(layers "F.Cu" "B.Cu")
		(net "GPU_BASE_PWR_GD")
	)
	(segment
		(start 51.872388 -373.620792)
		(end 51.872388 -369.670838)
		(width 0.15494)
		(layer "In9.Cu")
		(net "GPU_BASE_PWR_GD")
	)
	(segment
		(start 55.080916 -376.82932)
		(end 51.872388 -373.620792)
		(width 0.15494)
		(layer "In9.Cu")
		(net "GPU_BASE_PWR_GD")
	)
	(segment
		(start 51.872388 -369.670838)
		(end 50.14595 -367.9444)
		(width 0.15494)
		(layer "In9.Cu")
		(net "GPU_BASE_PWR_GD")
	)
	(segment
		(start 39.955724 -367.9444)
		(end 38.910006 -368.990118)
		(width 0.15494)
		(layer "In9.Cu")
		(net "GPU_BASE_PWR_GD")
	)
	(segment
		(start 50.14595 -367.9444)
		(end 39.955724 -367.9444)
		(width 0.15494)
		(layer "In9.Cu")
		(net "GPU_BASE_PWR_GD")
	)
	(segment
		(start 55.36819 -376.69597)
		(end 55.23484 -376.82932)
		(width 0.15494)
		(layer "In9.Cu")
		(net "GPU_BASE_PWR_GD")
	)
	(segment
		(start 55.23484 -376.82932)
		(end 55.080916 -376.82932)
		(width 0.15494)
		(layer "In9.Cu")
		(net "GPU_BASE_PWR_GD")
	)
	(segment
		(start 345.29395 -226.387152)
		(end 345.693746 -226.786948)
		(width 0.13208)
		(layer "F.Cu")
		(net "SSD4_CLK_EN_N")
	)
	(via
		(at 345.693746 -226.786948)
		(size 0.4572)
		(drill 0.254)
		(layers "F.Cu" "B.Cu")
		(net "SSD4_CLK_EN_N")
	)
	(via
		(at 344.459814 -231.231186)
		(size 0.6604)
		(drill 0.3302)
		(layers "F.Cu" "B.Cu")
		(net "SSD4_CLK_EN_N")
	)
	(segment
		(start 344.459814 -231.231186)
		(end 344.932 -230.759)
		(width 0.13208)
		(layer "B.Cu")
		(net "SSD4_CLK_EN_N")
	)
	(segment
		(start 343.027 -232.664)
		(end 344.459814 -231.231186)
		(width 0.13208)
		(layer "B.Cu")
		(net "SSD4_CLK_EN_N")
	)
	(segment
		(start 343.027 -233.15295)
		(end 343.027 -232.664)
		(width 0.13208)
		(layer "B.Cu")
		(net "SSD4_CLK_EN_N")
	)
	(segment
		(start 344.932 -230.759)
		(end 344.932 -227.548694)
		(width 0.13208)
		(layer "B.Cu")
		(net "SSD4_CLK_EN_N")
	)
	(segment
		(start 344.932 -227.548694)
		(end 345.693746 -226.786948)
		(width 0.13208)
		(layer "B.Cu")
		(net "SSD4_CLK_EN_N")
	)
	(segment
		(start 96.59112 -255.542034)
		(end 97.006156 -255.542034)
		(width 0.13208)
		(layer "F.Cu")
		(net "UART_PEX0_CLI_R_TX")
	)
	(segment
		(start 97.006156 -255.542034)
		(end 97.504758 -255.043432)
		(width 0.13208)
		(layer "F.Cu")
		(net "UART_PEX0_CLI_R_TX")
	)
	(segment
		(start 97.504758 -255.043432)
		(end 106.725466 -255.043432)
		(width 0.13208)
		(layer "F.Cu")
		(net "UART_PEX0_CLI_R_TX")
	)
	(segment
		(start 106.725466 -255.043432)
		(end 113.569496 -248.199402)
		(width 0.13208)
		(layer "F.Cu")
		(net "UART_PEX0_CLI_R_TX")
	)
	(segment
		(start 113.569496 -248.199402)
		(end 124.247402 -248.199402)
		(width 0.13208)
		(layer "F.Cu")
		(net "UART_PEX0_CLI_R_TX")
	)
	(via
		(at 125.647958 -210.938872)
		(size 0.508)
		(drill 0.254)
		(layers "F.Cu" "B.Cu")
		(net "UART_PEX0_CLI_R_TX")
	)
	(via
		(at 96.59112 -255.542034)
		(size 0.508)
		(drill 0.254)
		(layers "F.Cu" "B.Cu")
		(net "UART_PEX0_CLI_R_TX")
	)
	(via
		(at 124.247402 -248.199402)
		(size 0.508)
		(drill 0.254)
		(layers "F.Cu" "B.Cu")
		(net "UART_PEX0_CLI_R_TX")
	)
	(via
		(at 78.64983 -290.199826)
		(size 0.6604)
		(drill 0.3302)
		(layers "F.Cu" "B.Cu")
		(net "UART_PEX0_CLI_R_TX")
	)
	(segment
		(start 91.179396 -254.98679)
		(end 78.17993 -267.986256)
		(width 0.13208)
		(layer "B.Cu")
		(net "UART_PEX0_CLI_R_TX")
	)
	(segment
		(start 78.17993 -267.986256)
		(end 78.17993 -288.830766)
		(width 0.13208)
		(layer "B.Cu")
		(net "UART_PEX0_CLI_R_TX")
	)
	(segment
		(start 78.64983 -289.300666)
		(end 78.64983 -290.199826)
		(width 0.13208)
		(layer "B.Cu")
		(net "UART_PEX0_CLI_R_TX")
	)
	(segment
		(start 78.403196 -291.224716)
		(end 75.72375 -291.224716)
		(width 0.13208)
		(layer "B.Cu")
		(net "UART_PEX0_CLI_R_TX")
	)
	(segment
		(start 95.720916 -254.98679)
		(end 91.179396 -254.98679)
		(width 0.13208)
		(layer "B.Cu")
		(net "UART_PEX0_CLI_R_TX")
	)
	(segment
		(start 78.64983 -290.978082)
		(end 78.403196 -291.224716)
		(width 0.13208)
		(layer "B.Cu")
		(net "UART_PEX0_CLI_R_TX")
	)
	(segment
		(start 78.64983 -290.199826)
		(end 78.64983 -290.978082)
		(width 0.13208)
		(layer "B.Cu")
		(net "UART_PEX0_CLI_R_TX")
	)
	(segment
		(start 127.321818 -210.938872)
		(end 125.647958 -210.938872)
		(width 0.13208)
		(layer "B.Cu")
		(net "UART_PEX0_CLI_R_TX")
	)
	(segment
		(start 78.17993 -288.830766)
		(end 78.64983 -289.300666)
		(width 0.13208)
		(layer "B.Cu")
		(net "UART_PEX0_CLI_R_TX")
	)
	(segment
		(start 96.59112 -255.542034)
		(end 96.27616 -255.542034)
		(width 0.13208)
		(layer "B.Cu")
		(net "UART_PEX0_CLI_R_TX")
	)
	(segment
		(start 96.27616 -255.542034)
		(end 95.720916 -254.98679)
		(width 0.13208)
		(layer "B.Cu")
		(net "UART_PEX0_CLI_R_TX")
	)
	(segment
		(start 124.634244 -211.348066)
		(end 125.238764 -211.348066)
		(width 0.15494)
		(layer "In5.Cu")
		(net "UART_PEX0_CLI_R_TX")
	)
	(segment
		(start 125.238764 -211.348066)
		(end 125.647958 -210.938872)
		(width 0.15494)
		(layer "In5.Cu")
		(net "UART_PEX0_CLI_R_TX")
	)
	(segment
		(start 124.247402 -248.199402)
		(end 124.247402 -241.383058)
		(width 0.15494)
		(layer "In5.Cu")
		(net "UART_PEX0_CLI_R_TX")
	)
	(segment
		(start 124.247402 -241.383058)
		(end 126.0856 -239.54486)
		(width 0.15494)
		(layer "In5.Cu")
		(net "UART_PEX0_CLI_R_TX")
	)
	(segment
		(start 126.0856 -217.576146)
		(end 124.14377 -215.634316)
		(width 0.15494)
		(layer "In5.Cu")
		(net "UART_PEX0_CLI_R_TX")
	)
	(segment
		(start 126.0856 -239.54486)
		(end 126.0856 -217.576146)
		(width 0.15494)
		(layer "In5.Cu")
		(net "UART_PEX0_CLI_R_TX")
	)
	(segment
		(start 124.14377 -215.634316)
		(end 124.14377 -211.83854)
		(width 0.15494)
		(layer "In5.Cu")
		(net "UART_PEX0_CLI_R_TX")
	)
	(segment
		(start 124.14377 -211.83854)
		(end 124.634244 -211.348066)
		(width 0.15494)
		(layer "In5.Cu")
		(net "UART_PEX0_CLI_R_TX")
	)
	(segment
		(start 339.1662 -83.317334)
		(end 339.095588 -83.387946)
		(width 0.13462)
		(layer "F.Cu")
		(net "CLK_100M_DB800ZL_SSD10_DP")
	)
	(segment
		(start 339.095588 -83.387946)
		(end 339.095588 -83.814412)
		(width 0.13462)
		(layer "F.Cu")
		(net "CLK_100M_DB800ZL_SSD10_DP")
	)
	(segment
		(start 339.1662 -81.335372)
		(end 339.1662 -83.317334)
		(width 0.13462)
		(layer "F.Cu")
		(net "CLK_100M_DB800ZL_SSD10_DP")
	)
	(segment
		(start 338.83854 -81.007712)
		(end 339.1662 -81.335372)
		(width 0.13462)
		(layer "F.Cu")
		(net "CLK_100M_DB800ZL_SSD10_DP")
	)
	(segment
		(start 135.116062 -97.558098)
		(end 135.116062 -97.980246)
		(width 0.13208)
		(layer "F.Cu")
		(net "SMB_BIC_I2C9_SSD_MUX0_SCL")
	)
	(segment
		(start 135.580374 -97.980246)
		(end 135.70077 -98.100642)
		(width 0.13208)
		(layer "F.Cu")
		(net "SMB_BIC_I2C9_SSD_MUX0_SCL")
	)
	(segment
		(start 135.70077 -98.100642)
		(end 136.045194 -98.100642)
		(width 0.13208)
		(layer "F.Cu")
		(net "SMB_BIC_I2C9_SSD_MUX0_SCL")
	)
	(segment
		(start 133.998462 -96.440498)
		(end 135.116062 -97.558098)
		(width 0.13208)
		(layer "F.Cu")
		(net "SMB_BIC_I2C9_SSD_MUX0_SCL")
	)
	(segment
		(start 135.116062 -97.980246)
		(end 135.580374 -97.980246)
		(width 0.13208)
		(layer "F.Cu")
		(net "SMB_BIC_I2C9_SSD_MUX0_SCL")
	)
	(segment
		(start 133.062726 -96.440498)
		(end 133.998462 -96.440498)
		(width 0.13208)
		(layer "F.Cu")
		(net "SMB_BIC_I2C9_SSD_MUX0_SCL")
	)
	(via
		(at 135.116062 -97.980246)
		(size 0.508)
		(drill 0.254)
		(layers "F.Cu" "B.Cu")
		(net "SMB_BIC_I2C9_SSD_MUX0_SCL")
	)
	(segment
		(start 343.69375 -226.387152)
		(end 344.093546 -226.786948)
		(width 0.13208)
		(layer "F.Cu")
		(net "SSD3_PWR_EN")
	)
	(via
		(at 341.249 -231.394)
		(size 0.6604)
		(drill 0.3302)
		(layers "F.Cu" "B.Cu")
		(net "SSD3_PWR_EN")
	)
	(via
		(at 344.093546 -226.786948)
		(size 0.4572)
		(drill 0.254)
		(layers "F.Cu" "B.Cu")
		(net "SSD3_PWR_EN")
	)
	(segment
		(start 340.995 -231.648)
		(end 340.995 -233.15295)
		(width 0.13208)
		(layer "B.Cu")
		(net "SSD3_PWR_EN")
	)
	(segment
		(start 344.093546 -227.11537)
		(end 342.62949 -228.579426)
		(width 0.13208)
		(layer "B.Cu")
		(net "SSD3_PWR_EN")
	)
	(segment
		(start 341.249 -231.394)
		(end 340.995 -231.648)
		(width 0.13208)
		(layer "B.Cu")
		(net "SSD3_PWR_EN")
	)
	(segment
		(start 342.62949 -228.579426)
		(end 342.62949 -230.01351)
		(width 0.13208)
		(layer "B.Cu")
		(net "SSD3_PWR_EN")
	)
	(segment
		(start 344.093546 -226.786948)
		(end 344.093546 -227.11537)
		(width 0.13208)
		(layer "B.Cu")
		(net "SSD3_PWR_EN")
	)
	(segment
		(start 342.62949 -230.01351)
		(end 341.249 -231.394)
		(width 0.13208)
		(layer "B.Cu")
		(net "SSD3_PWR_EN")
	)
	(segment
		(start 409.793948 -166.070534)
		(end 409.793948 -166.705534)
		(width 0.4064)
		(layer "F.Cu")
		(net "P3V3_NIC6")
	)
	(segment
		(start 405.2062 -141.9352)
		(end 404.58009 -141.9352)
		(width 0.4064)
		(layer "F.Cu")
		(net "P3V3_NIC6")
	)
	(segment
		(start 409.916122 -170.157902)
		(end 410.53004 -170.77182)
		(width 0.4572)
		(layer "F.Cu")
		(net "P3V3_NIC6")
	)
	(segment
		(start 386.50799 -158.3944)
		(end 385.87299 -158.3944)
		(width 0.4064)
		(layer "F.Cu")
		(net "P3V3_NIC6")
	)
	(segment
		(start 358.01046 -125.979428)
		(end 357.35514 -125.979428)
		(width 0.4064)
		(layer "F.Cu")
		(net "P3V3_NIC6")
	)
	(segment
		(start 386.50799 -153.3144)
		(end 385.87299 -153.3144)
		(width 0.4064)
		(layer "F.Cu")
		(net "P3V3_NIC6")
	)
	(segment
		(start 404.58009 -142.9512)
		(end 405.222456 -142.9512)
		(width 0.4064)
		(layer "F.Cu")
		(net "P3V3_NIC6")
	)
	(segment
		(start 405.96439 -141.6558)
		(end 405.4856 -141.6558)
		(width 0.4572)
		(layer "F.Cu")
		(net "P3V3_NIC6")
	)
	(segment
		(start 410.53004 -171.661328)
		(end 410.53004 -172.329348)
		(width 0.4572)
		(layer "F.Cu")
		(net "P3V3_NIC6")
	)
	(segment
		(start 386.50799 -157.3784)
		(end 385.87299 -157.3784)
		(width 0.4064)
		(layer "F.Cu")
		(net "P3V3_NIC6")
	)
	(segment
		(start 217.764106 -199.095106)
		(end 216.991946 -199.095106)
		(width 0.3556)
		(layer "F.Cu")
		(net "P3V3_NIC6")
	)
	(segment
		(start 219.60205 -196.596)
		(end 220.218 -196.596)
		(width 0.381)
		(layer "F.Cu")
		(net "P3V3_NIC6")
	)
	(segment
		(start 218.313 -199.644)
		(end 217.764106 -199.095106)
		(width 0.3556)
		(layer "F.Cu")
		(net "P3V3_NIC6")
	)
	(segment
		(start 405.4856 -141.6558)
		(end 405.2062 -141.9352)
		(width 0.4572)
		(layer "F.Cu")
		(net "P3V3_NIC6")
	)
	(segment
		(start 411.4673 -171.675806)
		(end 411.4673 -172.343826)
		(width 0.254)
		(layer "F.Cu")
		(net "P3V3_NIC6")
	)
	(segment
		(start 218.80195 -200.279)
		(end 218.80195 -199.644)
		(width 0.4572)
		(layer "F.Cu")
		(net "P3V3_NIC6")
	)
	(segment
		(start 410.53004 -170.77182)
		(end 410.53004 -171.661328)
		(width 0.4572)
		(layer "F.Cu")
		(net "P3V3_NIC6")
	)
	(segment
		(start 219.60205 -197.612)
		(end 219.60205 -196.596)
		(width 0.381)
		(layer "F.Cu")
		(net "P3V3_NIC6")
	)
	(segment
		(start 360.401362 -118.743476)
		(end 360.401362 -119.35587)
		(width 0.4572)
		(layer "F.Cu")
		(net "P3V3_NIC6")
	)
	(segment
		(start 219.60205 -198.628)
		(end 219.60205 -197.612)
		(width 0.381)
		(layer "F.Cu")
		(net "P3V3_NIC6")
	)
	(segment
		(start 218.80195 -199.644)
		(end 218.313 -199.644)
		(width 0.3556)
		(layer "F.Cu")
		(net "P3V3_NIC6")
	)
	(via
		(at 385.87299 -158.3944)
		(size 0.508)
		(drill 0.254)
		(layers "F.Cu" "B.Cu")
		(net "P3V3_NIC6")
	)
	(via
		(at 378.154946 -139.171172)
		(size 0.6604)
		(drill 0.3302)
		(layers "F.Cu" "B.Cu")
		(net "P3V3_NIC6")
	)
	(via
		(at 360.401362 -119.35587)
		(size 0.508)
		(drill 0.254)
		(layers "F.Cu" "B.Cu")
		(net "P3V3_NIC6")
	)
	(via
		(at 368.120422 -126.017782)
		(size 0.508)
		(drill 0.254)
		(layers "F.Cu" "B.Cu")
		(net "P3V3_NIC6")
	)
	(via
		(at 383.969514 -138.88847)
		(size 0.6604)
		(drill 0.3302)
		(layers "F.Cu" "B.Cu")
		(net "P3V3_NIC6")
	)
	(via
		(at 405.222456 -142.9512)
		(size 0.508)
		(drill 0.254)
		(layers "F.Cu" "B.Cu")
		(net "P3V3_NIC6")
	)
	(via
		(at 365.85906 -117.259608)
		(size 0.508)
		(drill 0.254)
		(layers "F.Cu" "B.Cu")
		(net "P3V3_NIC6")
	)
	(via
		(at 367.086134 -126.530354)
		(size 0.508)
		(drill 0.254)
		(layers "F.Cu" "B.Cu")
		(net "P3V3_NIC6")
	)
	(via
		(at 366.49406 -117.259608)
		(size 0.508)
		(drill 0.254)
		(layers "F.Cu" "B.Cu")
		(net "P3V3_NIC6")
	)
	(via
		(at 409.793948 -166.705534)
		(size 0.508)
		(drill 0.254)
		(layers "F.Cu" "B.Cu")
		(net "P3V3_NIC6")
	)
	(via
		(at 396.84579 -155.0416)
		(size 0.508)
		(drill 0.254)
		(layers "F.Cu" "B.Cu")
		(net "P3V3_NIC6")
	)
	(via
		(at 220.218 -196.596)
		(size 0.508)
		(drill 0.254)
		(layers "F.Cu" "B.Cu")
		(net "P3V3_NIC6")
	)
	(via
		(at 367.086134 -125.768354)
		(size 0.508)
		(drill 0.254)
		(layers "F.Cu" "B.Cu")
		(net "P3V3_NIC6")
	)
	(via
		(at 392.90625 -140.565378)
		(size 0.508)
		(drill 0.254)
		(layers "F.Cu" "B.Cu")
		(net "P3V3_NIC6")
	)
	(via
		(at 392.90625 -139.930378)
		(size 0.508)
		(drill 0.254)
		(layers "F.Cu" "B.Cu")
		(net "P3V3_NIC6")
	)
	(via
		(at 366.49406 -116.624608)
		(size 0.508)
		(drill 0.254)
		(layers "F.Cu" "B.Cu")
		(net "P3V3_NIC6")
	)
	(via
		(at 366.451134 -125.768354)
		(size 0.508)
		(drill 0.254)
		(layers "F.Cu" "B.Cu")
		(net "P3V3_NIC6")
	)
	(via
		(at 368.120422 -125.382782)
		(size 0.508)
		(drill 0.254)
		(layers "F.Cu" "B.Cu")
		(net "P3V3_NIC6")
	)
	(via
		(at 365.166402 -125.853698)
		(size 0.508)
		(drill 0.254)
		(layers "F.Cu" "B.Cu")
		(net "P3V3_NIC6")
	)
	(via
		(at 364.22584 -125.403356)
		(size 0.508)
		(drill 0.254)
		(layers "F.Cu" "B.Cu")
		(net "P3V3_NIC6")
	)
	(via
		(at 365.85906 -116.624608)
		(size 0.508)
		(drill 0.254)
		(layers "F.Cu" "B.Cu")
		(net "P3V3_NIC6")
	)
	(via
		(at 357.35514 -125.979428)
		(size 0.508)
		(drill 0.254)
		(layers "F.Cu" "B.Cu")
		(net "P3V3_NIC6")
	)
	(via
		(at 410.53004 -172.329348)
		(size 0.508)
		(drill 0.254)
		(layers "F.Cu" "B.Cu")
		(net "P3V3_NIC6")
	)
	(via
		(at 405.2062 -141.9352)
		(size 0.508)
		(drill 0.254)
		(layers "F.Cu" "B.Cu")
		(net "P3V3_NIC6")
	)
	(via
		(at 392.27125 -140.565378)
		(size 0.508)
		(drill 0.254)
		(layers "F.Cu" "B.Cu")
		(net "P3V3_NIC6")
	)
	(via
		(at 365.166402 -125.218698)
		(size 0.508)
		(drill 0.254)
		(layers "F.Cu" "B.Cu")
		(net "P3V3_NIC6")
	)
	(via
		(at 365.85906 -115.989608)
		(size 0.508)
		(drill 0.254)
		(layers "F.Cu" "B.Cu")
		(net "P3V3_NIC6")
	)
	(via
		(at 225.121216 -169.3291)
		(size 0.508)
		(drill 0.254)
		(layers "F.Cu" "B.Cu")
		(net "P3V3_NIC6")
	)
	(via
		(at 411.4673 -172.343826)
		(size 0.508)
		(drill 0.254)
		(layers "F.Cu" "B.Cu")
		(net "P3V3_NIC6")
	)
	(via
		(at 218.80195 -200.279)
		(size 0.508)
		(drill 0.254)
		(layers "F.Cu" "B.Cu")
		(net "P3V3_NIC6")
	)
	(via
		(at 368.120422 -126.652782)
		(size 0.508)
		(drill 0.254)
		(layers "F.Cu" "B.Cu")
		(net "P3V3_NIC6")
	)
	(via
		(at 364.22584 -124.768356)
		(size 0.508)
		(drill 0.254)
		(layers "F.Cu" "B.Cu")
		(net "P3V3_NIC6")
	)
	(via
		(at 392.27125 -139.930378)
		(size 0.508)
		(drill 0.254)
		(layers "F.Cu" "B.Cu")
		(net "P3V3_NIC6")
	)
	(via
		(at 397.42618 -165.130988)
		(size 0.508)
		(drill 0.254)
		(layers "F.Cu" "B.Cu")
		(net "P3V3_NIC6")
	)
	(via
		(at 385.87299 -157.3784)
		(size 0.508)
		(drill 0.254)
		(layers "F.Cu" "B.Cu")
		(net "P3V3_NIC6")
	)
	(via
		(at 385.87299 -153.3144)
		(size 0.508)
		(drill 0.254)
		(layers "F.Cu" "B.Cu")
		(net "P3V3_NIC6")
	)
	(via
		(at 366.49406 -115.989608)
		(size 0.508)
		(drill 0.254)
		(layers "F.Cu" "B.Cu")
		(net "P3V3_NIC6")
	)
	(via
		(at 366.374934 -126.530354)
		(size 0.508)
		(drill 0.254)
		(layers "F.Cu" "B.Cu")
		(net "P3V3_NIC6")
	)
	(via
		(at 368.120422 -124.747782)
		(size 0.508)
		(drill 0.254)
		(layers "F.Cu" "B.Cu")
		(net "P3V3_NIC6")
	)
	(via
		(at 389.37565 -138.699748)
		(size 0.6604)
		(drill 0.3302)
		(layers "F.Cu" "B.Cu")
		(net "P3V3_NIC6")
	)
	(segment
		(start 397.45539 -155.0416)
		(end 396.84579 -155.0416)
		(width 0.4572)
		(layer "B.Cu")
		(net "P3V3_NIC6")
	)
	(segment
		(start 398.078706 -156.274516)
		(end 396.84579 -155.0416)
		(width 0.508)
		(layer "In5.Cu")
		(net "P3V3_NIC6")
	)
	(segment
		(start 399.129504 -158.811468)
		(end 398.078706 -156.274516)
		(width 0.508)
		(layer "In5.Cu")
		(net "P3V3_NIC6")
	)
	(segment
		(start 397.42618 -165.130988)
		(end 398.266158 -164.29101)
		(width 0.508)
		(layer "In5.Cu")
		(net "P3V3_NIC6")
	)
	(segment
		(start 399.129504 -162.20694)
		(end 399.129504 -158.811468)
		(width 0.508)
		(layer "In5.Cu")
		(net "P3V3_NIC6")
	)
	(segment
		(start 398.266158 -164.29101)
		(end 399.129504 -162.20694)
		(width 0.508)
		(layer "In5.Cu")
		(net "P3V3_NIC6")
	)
	(segment
		(start 220.455744 -196.358256)
		(end 220.455744 -194.530472)
		(width 0.508)
		(layer "In9.Cu")
		(net "P3V3_NIC6")
	)
	(segment
		(start 226.573334 -172.174154)
		(end 225.121216 -170.722036)
		(width 0.508)
		(layer "In9.Cu")
		(net "P3V3_NIC6")
	)
	(segment
		(start 225.121216 -170.722036)
		(end 225.121216 -169.3291)
		(width 0.508)
		(layer "In9.Cu")
		(net "P3V3_NIC6")
	)
	(segment
		(start 220.646752 -187.741306)
		(end 224.217484 -184.170574)
		(width 0.508)
		(layer "In9.Cu")
		(net "P3V3_NIC6")
	)
	(segment
		(start 219.79128 -193.866008)
		(end 219.79128 -192.105534)
		(width 0.508)
		(layer "In9.Cu")
		(net "P3V3_NIC6")
	)
	(segment
		(start 220.646752 -191.250062)
		(end 220.646752 -187.741306)
		(width 0.508)
		(layer "In9.Cu")
		(net "P3V3_NIC6")
	)
	(segment
		(start 218.80195 -199.517)
		(end 218.80195 -200.279)
		(width 0.508)
		(layer "In9.Cu")
		(net "P3V3_NIC6")
	)
	(segment
		(start 226.573334 -177.132488)
		(end 226.573334 -172.174154)
		(width 0.508)
		(layer "In9.Cu")
		(net "P3V3_NIC6")
	)
	(segment
		(start 224.217484 -184.170574)
		(end 224.217484 -181.443122)
		(width 0.508)
		(layer "In9.Cu")
		(net "P3V3_NIC6")
	)
	(segment
		(start 219.837 -196.977)
		(end 219.837 -198.48195)
		(width 0.508)
		(layer "In9.Cu")
		(net "P3V3_NIC6")
	)
	(segment
		(start 224.535238 -179.170584)
		(end 226.573334 -177.132488)
		(width 0.508)
		(layer "In9.Cu")
		(net "P3V3_NIC6")
	)
	(segment
		(start 224.217484 -181.443122)
		(end 224.535238 -181.125368)
		(width 0.508)
		(layer "In9.Cu")
		(net "P3V3_NIC6")
	)
	(segment
		(start 220.455744 -194.530472)
		(end 219.79128 -193.866008)
		(width 0.508)
		(layer "In9.Cu")
		(net "P3V3_NIC6")
	)
	(segment
		(start 220.218 -196.596)
		(end 219.837 -196.977)
		(width 0.508)
		(layer "In9.Cu")
		(net "P3V3_NIC6")
	)
	(segment
		(start 219.837 -198.48195)
		(end 218.80195 -199.517)
		(width 0.508)
		(layer "In9.Cu")
		(net "P3V3_NIC6")
	)
	(segment
		(start 219.79128 -192.105534)
		(end 220.646752 -191.250062)
		(width 0.508)
		(layer "In9.Cu")
		(net "P3V3_NIC6")
	)
	(segment
		(start 220.218 -196.596)
		(end 220.455744 -196.358256)
		(width 0.508)
		(layer "In9.Cu")
		(net "P3V3_NIC6")
	)
	(segment
		(start 224.535238 -181.125368)
		(end 224.535238 -179.170584)
		(width 0.508)
		(layer "In9.Cu")
		(net "P3V3_NIC6")
	)
	(segment
		(start 316.500764 -163.479988)
		(end 305.22037 -174.760382)
		(width 0.15494)
		(layer "In13.Cu")
		(net "P3V3_NIC6")
	)
	(segment
		(start 397.42618 -165.130988)
		(end 396.398242 -164.10305)
		(width 0.15494)
		(layer "In13.Cu")
		(net "P3V3_NIC6")
	)
	(segment
		(start 348.352364 -159.38754)
		(end 344.762074 -159.38754)
		(width 0.15494)
		(layer "In13.Cu")
		(net "P3V3_NIC6")
	)
	(segment
		(start 336.063082 -162.515804)
		(end 336.063082 -162.83686)
		(width 0.15494)
		(layer "In13.Cu")
		(net "P3V3_NIC6")
	)
	(segment
		(start 305.22037 -174.760382)
		(end 292.472364 -174.760382)
		(width 0.15494)
		(layer "In13.Cu")
		(net "P3V3_NIC6")
	)
	(segment
		(start 338.634324 -159.944562)
		(end 336.063082 -162.515804)
		(width 0.15494)
		(layer "In13.Cu")
		(net "P3V3_NIC6")
	)
	(segment
		(start 230.568754 -168.579038)
		(end 228.773228 -170.374564)
		(width 0.15494)
		(layer "In13.Cu")
		(net "P3V3_NIC6")
	)
	(segment
		(start 362.49356 -164.970968)
		(end 359.15981 -161.637218)
		(width 0.15494)
		(layer "In13.Cu")
		(net "P3V3_NIC6")
	)
	(segment
		(start 396.398242 -164.10305)
		(end 391.18159 -164.10305)
		(width 0.15494)
		(layer "In13.Cu")
		(net "P3V3_NIC6")
	)
	(segment
		(start 343.40927 -160.740344)
		(end 341.608156 -160.740344)
		(width 0.15494)
		(layer "In13.Cu")
		(net "P3V3_NIC6")
	)
	(segment
		(start 226.16668 -170.374564)
		(end 225.121216 -169.3291)
		(width 0.15494)
		(layer "In13.Cu")
		(net "P3V3_NIC6")
	)
	(segment
		(start 368.831368 -164.970968)
		(end 362.49356 -164.970968)
		(width 0.15494)
		(layer "In13.Cu")
		(net "P3V3_NIC6")
	)
	(segment
		(start 335.419954 -163.479988)
		(end 316.500764 -163.479988)
		(width 0.15494)
		(layer "In13.Cu")
		(net "P3V3_NIC6")
	)
	(segment
		(start 269.900908 -162.558476)
		(end 263.880346 -168.579038)
		(width 0.15494)
		(layer "In13.Cu")
		(net "P3V3_NIC6")
	)
	(segment
		(start 387.420104 -160.341564)
		(end 373.460772 -160.341564)
		(width 0.15494)
		(layer "In13.Cu")
		(net "P3V3_NIC6")
	)
	(segment
		(start 354.296472 -161.637218)
		(end 351.11436 -158.455106)
		(width 0.15494)
		(layer "In13.Cu")
		(net "P3V3_NIC6")
	)
	(segment
		(start 373.460772 -160.341564)
		(end 368.831368 -164.970968)
		(width 0.15494)
		(layer "In13.Cu")
		(net "P3V3_NIC6")
	)
	(segment
		(start 341.608156 -160.740344)
		(end 340.812374 -159.944562)
		(width 0.15494)
		(layer "In13.Cu")
		(net "P3V3_NIC6")
	)
	(segment
		(start 359.15981 -161.637218)
		(end 354.296472 -161.637218)
		(width 0.15494)
		(layer "In13.Cu")
		(net "P3V3_NIC6")
	)
	(segment
		(start 228.773228 -170.374564)
		(end 226.16668 -170.374564)
		(width 0.15494)
		(layer "In13.Cu")
		(net "P3V3_NIC6")
	)
	(segment
		(start 391.18159 -164.10305)
		(end 387.420104 -160.341564)
		(width 0.15494)
		(layer "In13.Cu")
		(net "P3V3_NIC6")
	)
	(segment
		(start 349.284798 -158.455106)
		(end 348.352364 -159.38754)
		(width 0.15494)
		(layer "In13.Cu")
		(net "P3V3_NIC6")
	)
	(segment
		(start 263.880346 -168.579038)
		(end 230.568754 -168.579038)
		(width 0.15494)
		(layer "In13.Cu")
		(net "P3V3_NIC6")
	)
	(segment
		(start 292.472364 -174.760382)
		(end 288.497772 -170.78579)
		(width 0.15494)
		(layer "In13.Cu")
		(net "P3V3_NIC6")
	)
	(segment
		(start 344.762074 -159.38754)
		(end 343.40927 -160.740344)
		(width 0.15494)
		(layer "In13.Cu")
		(net "P3V3_NIC6")
	)
	(segment
		(start 336.063082 -162.83686)
		(end 335.419954 -163.479988)
		(width 0.15494)
		(layer "In13.Cu")
		(net "P3V3_NIC6")
	)
	(segment
		(start 340.812374 -159.944562)
		(end 338.634324 -159.944562)
		(width 0.15494)
		(layer "In13.Cu")
		(net "P3V3_NIC6")
	)
	(segment
		(start 280.18486 -170.78579)
		(end 271.957546 -162.558476)
		(width 0.15494)
		(layer "In13.Cu")
		(net "P3V3_NIC6")
	)
	(segment
		(start 351.11436 -158.455106)
		(end 349.284798 -158.455106)
		(width 0.15494)
		(layer "In13.Cu")
		(net "P3V3_NIC6")
	)
	(segment
		(start 288.497772 -170.78579)
		(end 280.18486 -170.78579)
		(width 0.15494)
		(layer "In13.Cu")
		(net "P3V3_NIC6")
	)
	(segment
		(start 271.957546 -162.558476)
		(end 269.900908 -162.558476)
		(width 0.15494)
		(layer "In13.Cu")
		(net "P3V3_NIC6")
	)
	(segment
		(start 71.999856 -292.099746)
		(end 72.474836 -291.624766)
		(width 0.13208)
		(layer "F.Cu")
		(net "UART_PEX0_CLI_TX")
	)
	(via
		(at 72.474836 -291.624766)
		(size 0.4064)
		(drill 0.2032)
		(layers "F.Cu" "B.Cu")
		(net "UART_PEX0_CLI_TX")
	)
	(via
		(at 72.949816 -292.099746)
		(size 0.6604)
		(drill 0.3302)
		(layers "F.Cu" "B.Cu")
		(net "UART_PEX0_CLI_TX")
	)
	(segment
		(start 72.474836 -291.624766)
		(end 72.949816 -292.099746)
		(width 0.13208)
		(layer "B.Cu")
		(net "UART_PEX0_CLI_TX")
	)
	(segment
		(start 72.949816 -292.099746)
		(end 74.765916 -292.099746)
		(width 0.13208)
		(layer "B.Cu")
		(net "UART_PEX0_CLI_TX")
	)
	(segment
		(start 74.765916 -292.099746)
		(end 74.840846 -292.024816)
		(width 0.13208)
		(layer "B.Cu")
		(net "UART_PEX0_CLI_TX")
	)
	(segment
		(start 74.840846 -292.024816)
		(end 75.72375 -292.024816)
		(width 0.13208)
		(layer "B.Cu")
		(net "UART_PEX0_CLI_TX")
	)
	(segment
		(start 344.212926 -84.169758)
		(end 343.886536 -83.843368)
		(width 0.13462)
		(layer "F.Cu")
		(net "CLK_100M_DB800ZL_SSD11_DN")
	)
	(segment
		(start 341.473282 -84.96427)
		(end 341.045546 -84.96427)
		(width 0.13462)
		(layer "F.Cu")
		(net "CLK_100M_DB800ZL_SSD11_DN")
	)
	(segment
		(start 343.054686 -83.843368)
		(end 342.002872 -84.895182)
		(width 0.13462)
		(layer "F.Cu")
		(net "CLK_100M_DB800ZL_SSD11_DN")
	)
	(segment
		(start 343.886536 -83.843368)
		(end 343.054686 -83.843368)
		(width 0.13462)
		(layer "F.Cu")
		(net "CLK_100M_DB800ZL_SSD11_DN")
	)
	(segment
		(start 342.002872 -84.895182)
		(end 341.54237 -84.895182)
		(width 0.13462)
		(layer "F.Cu")
		(net "CLK_100M_DB800ZL_SSD11_DN")
	)
	(segment
		(start 341.54237 -84.895182)
		(end 341.473282 -84.96427)
		(width 0.13462)
		(layer "F.Cu")
		(net "CLK_100M_DB800ZL_SSD11_DN")
	)
	(segment
		(start 261.622286 -251.158502)
		(end 261.622286 -250.470924)
		(width 0.13208)
		(layer "F.Cu")
		(net "PEX2_MODE_SEL3")
	)
	(segment
		(start 293.74973 -283.549852)
		(end 294.22471 -284.024832)
		(width 0.1651)
		(layer "F.Cu")
		(net "PEX2_MODE_SEL3")
	)
	(segment
		(start 261.622286 -251.956824)
		(end 261.622286 -251.158502)
		(width 0.13208)
		(layer "F.Cu")
		(net "PEX2_MODE_SEL3")
	)
	(via
		(at 291.381434 -268.925802)
		(size 0.6604)
		(drill 0.3302)
		(layers "F.Cu" "B.Cu")
		(net "PEX2_MODE_SEL3")
	)
	(via
		(at 294.22471 -284.024832)
		(size 0.4064)
		(drill 0.2032)
		(layers "F.Cu" "B.Cu")
		(net "PEX2_MODE_SEL3")
	)
	(via
		(at 261.622286 -251.158502)
		(size 0.508)
		(drill 0.254)
		(layers "F.Cu" "B.Cu")
		(net "PEX2_MODE_SEL3")
	)
	(segment
		(start 261.112254 -251.668534)
		(end 261.112254 -253.614682)
		(width 0.13208)
		(layer "B.Cu")
		(net "PEX2_MODE_SEL3")
	)
	(segment
		(start 294.25773 -282.31846)
		(end 293.74973 -282.82646)
		(width 0.13208)
		(layer "B.Cu")
		(net "PEX2_MODE_SEL3")
	)
	(segment
		(start 280.214832 -257.7592)
		(end 291.381434 -268.925802)
		(width 0.13208)
		(layer "B.Cu")
		(net "PEX2_MODE_SEL3")
	)
	(segment
		(start 263.90092 -255.020572)
		(end 266.639548 -257.7592)
		(width 0.13208)
		(layer "B.Cu")
		(net "PEX2_MODE_SEL3")
	)
	(segment
		(start 261.622286 -251.158502)
		(end 261.112254 -251.668534)
		(width 0.13208)
		(layer "B.Cu")
		(net "PEX2_MODE_SEL3")
	)
	(segment
		(start 293.74973 -282.82646)
		(end 293.74973 -283.549852)
		(width 0.13208)
		(layer "B.Cu")
		(net "PEX2_MODE_SEL3")
	)
	(segment
		(start 266.639548 -257.7592)
		(end 280.214832 -257.7592)
		(width 0.13208)
		(layer "B.Cu")
		(net "PEX2_MODE_SEL3")
	)
	(segment
		(start 294.25773 -271.802098)
		(end 294.25773 -282.31846)
		(width 0.13208)
		(layer "B.Cu")
		(net "PEX2_MODE_SEL3")
	)
	(segment
		(start 262.518144 -255.020572)
		(end 263.90092 -255.020572)
		(width 0.13208)
		(layer "B.Cu")
		(net "PEX2_MODE_SEL3")
	)
	(segment
		(start 293.74973 -283.549852)
		(end 294.22471 -284.024832)
		(width 0.13208)
		(layer "B.Cu")
		(net "PEX2_MODE_SEL3")
	)
	(segment
		(start 261.112254 -253.614682)
		(end 262.518144 -255.020572)
		(width 0.13208)
		(layer "B.Cu")
		(net "PEX2_MODE_SEL3")
	)
	(segment
		(start 291.381434 -268.925802)
		(end 294.25773 -271.802098)
		(width 0.13208)
		(layer "B.Cu")
		(net "PEX2_MODE_SEL3")
	)
	(segment
		(start 305.149758 -300.649894)
		(end 305.624738 -300.174914)
		(width 0.254)
		(layer "F.Cu")
		(net "PEX2_ADCTEMP_VINP0")
	)
	(via
		(at 305.624738 -300.174914)
		(size 0.4064)
		(drill 0.2032)
		(layers "F.Cu" "B.Cu")
		(net "PEX2_ADCTEMP_VINP0")
	)
	(via
		(at 307.38699 -301.120556)
		(size 0.6604)
		(drill 0.3302)
		(layers "F.Cu" "B.Cu")
		(net "PEX2_ADCTEMP_VINP0")
	)
	(segment
		(start 306.174648 -300.724824)
		(end 306.226718 -300.724824)
		(width 0.254)
		(layer "B.Cu")
		(net "PEX2_ADCTEMP_VINP0")
	)
	(segment
		(start 307.38699 -301.120556)
		(end 306.991258 -300.724824)
		(width 0.13208)
		(layer "B.Cu")
		(net "PEX2_ADCTEMP_VINP0")
	)
	(segment
		(start 306.991258 -300.724824)
		(end 306.226718 -300.724824)
		(width 0.13208)
		(layer "B.Cu")
		(net "PEX2_ADCTEMP_VINP0")
	)
	(segment
		(start 305.624738 -300.174914)
		(end 306.174648 -300.724824)
		(width 0.254)
		(layer "B.Cu")
		(net "PEX2_ADCTEMP_VINP0")
	)
	(segment
		(start 133.062726 -97.090484)
		(end 133.989064 -97.090484)
		(width 0.13208)
		(layer "F.Cu")
		(net "SMB_BIC_I2C9_SSD_MUX0_SDA")
	)
	(segment
		(start 134.535418 -98.349054)
		(end 135.430006 -99.243642)
		(width 0.13208)
		(layer "F.Cu")
		(net "SMB_BIC_I2C9_SSD_MUX0_SDA")
	)
	(segment
		(start 135.430006 -99.243642)
		(end 136.045194 -99.243642)
		(width 0.13208)
		(layer "F.Cu")
		(net "SMB_BIC_I2C9_SSD_MUX0_SDA")
	)
	(segment
		(start 134.535418 -97.636838)
		(end 134.535418 -98.349054)
		(width 0.13208)
		(layer "F.Cu")
		(net "SMB_BIC_I2C9_SSD_MUX0_SDA")
	)
	(segment
		(start 133.989064 -97.090484)
		(end 134.535418 -97.636838)
		(width 0.13208)
		(layer "F.Cu")
		(net "SMB_BIC_I2C9_SSD_MUX0_SDA")
	)
	(via
		(at 135.430006 -99.243642)
		(size 0.508)
		(drill 0.254)
		(layers "F.Cu" "B.Cu")
		(net "SMB_BIC_I2C9_SSD_MUX0_SDA")
	)
	(segment
		(start 341.690198 -227.583238)
		(end 341.690198 -228.179376)
		(width 0.13208)
		(layer "F.Cu")
		(net "SSD0_CLK_EN_N")
	)
	(segment
		(start 341.293958 -227.186998)
		(end 341.690198 -227.583238)
		(width 0.13208)
		(layer "F.Cu")
		(net "SSD0_CLK_EN_N")
	)
	(segment
		(start 341.690198 -228.179376)
		(end 341.565992 -228.303582)
		(width 0.13208)
		(layer "F.Cu")
		(net "SSD0_CLK_EN_N")
	)
	(segment
		(start 341.565992 -228.303582)
		(end 341.565992 -229.807008)
		(width 0.13208)
		(layer "F.Cu")
		(net "SSD0_CLK_EN_N")
	)
	(segment
		(start 338.963 -233.66095)
		(end 338.963 -231.557322)
		(width 0.13208)
		(layer "F.Cu")
		(net "SSD0_CLK_EN_N")
	)
	(segment
		(start 341.565992 -229.807008)
		(end 339.815678 -231.557322)
		(width 0.13208)
		(layer "F.Cu")
		(net "SSD0_CLK_EN_N")
	)
	(segment
		(start 339.815678 -231.557322)
		(end 338.963 -231.557322)
		(width 0.13208)
		(layer "F.Cu")
		(net "SSD0_CLK_EN_N")
	)
	(via
		(at 338.963 -231.557322)
		(size 0.762)
		(drill 0.381)
		(layers "F.Cu" "B.Cu")
		(net "SSD0_CLK_EN_N")
	)
	(segment
		(start 337.095592 -83.387946)
		(end 337.095592 -83.814412)
		(width 0.13462)
		(layer "F.Cu")
		(net "CLK_100M_DB800ZL_SSD9_DP")
	)
	(segment
		(start 336.838544 -81.007712)
		(end 337.16468 -81.333848)
		(width 0.13462)
		(layer "F.Cu")
		(net "CLK_100M_DB800ZL_SSD9_DP")
	)
	(segment
		(start 337.16468 -83.318858)
		(end 337.095592 -83.387946)
		(width 0.13462)
		(layer "F.Cu")
		(net "CLK_100M_DB800ZL_SSD9_DP")
	)
	(segment
		(start 337.16468 -81.333848)
		(end 337.16468 -83.318858)
		(width 0.13462)
		(layer "F.Cu")
		(net "CLK_100M_DB800ZL_SSD9_DP")
	)
	(segment
		(start 266.702286 -251.158502)
		(end 266.702286 -250.470924)
		(width 0.13208)
		(layer "F.Cu")
		(net "PEX2_MODE_SEL11")
	)
	(segment
		(start 266.702286 -251.956824)
		(end 266.702286 -251.158502)
		(width 0.13208)
		(layer "F.Cu")
		(net "PEX2_MODE_SEL11")
	)
	(segment
		(start 297.549824 -282.599892)
		(end 298.024804 -283.074872)
		(width 0.13208)
		(layer "F.Cu")
		(net "PEX2_MODE_SEL11")
	)
	(via
		(at 298.024804 -283.074872)
		(size 0.4064)
		(drill 0.2032)
		(layers "F.Cu" "B.Cu")
		(net "PEX2_MODE_SEL11")
	)
	(via
		(at 266.702286 -251.158502)
		(size 0.508)
		(drill 0.254)
		(layers "F.Cu" "B.Cu")
		(net "PEX2_MODE_SEL11")
	)
	(segment
		(start 266.159234 -254.275336)
		(end 266.159234 -251.701554)
		(width 0.13208)
		(layer "B.Cu")
		(net "PEX2_MODE_SEL11")
	)
	(segment
		(start 298.975018 -272.170144)
		(end 295.523412 -268.718538)
		(width 0.13208)
		(layer "B.Cu")
		(net "PEX2_MODE_SEL11")
	)
	(segment
		(start 298.024804 -283.074872)
		(end 298.975018 -282.124658)
		(width 0.13208)
		(layer "B.Cu")
		(net "PEX2_MODE_SEL11")
	)
	(segment
		(start 268.263878 -254.635)
		(end 266.518898 -254.635)
		(width 0.13208)
		(layer "B.Cu")
		(net "PEX2_MODE_SEL11")
	)
	(segment
		(start 281.983434 -255.18745)
		(end 268.816328 -255.18745)
		(width 0.13208)
		(layer "B.Cu")
		(net "PEX2_MODE_SEL11")
	)
	(segment
		(start 266.159234 -251.701554)
		(end 266.702286 -251.158502)
		(width 0.13208)
		(layer "B.Cu")
		(net "PEX2_MODE_SEL11")
	)
	(segment
		(start 266.518898 -254.635)
		(end 266.159234 -254.275336)
		(width 0.13208)
		(layer "B.Cu")
		(net "PEX2_MODE_SEL11")
	)
	(segment
		(start 298.975018 -282.124658)
		(end 298.975018 -272.170144)
		(width 0.13208)
		(layer "B.Cu")
		(net "PEX2_MODE_SEL11")
	)
	(segment
		(start 268.816328 -255.18745)
		(end 268.263878 -254.635)
		(width 0.13208)
		(layer "B.Cu")
		(net "PEX2_MODE_SEL11")
	)
	(segment
		(start 295.523412 -268.718538)
		(end 295.514522 -268.718538)
		(width 0.13208)
		(layer "B.Cu")
		(net "PEX2_MODE_SEL11")
	)
	(segment
		(start 295.514522 -268.718538)
		(end 281.983434 -255.18745)
		(width 0.13208)
		(layer "B.Cu")
		(net "PEX2_MODE_SEL11")
	)
	(segment
		(start 305.149758 -299.699934)
		(end 304.674778 -299.224954)
		(width 0.254)
		(layer "F.Cu")
		(net "PEX2_ADCTEMP_VINP1")
	)
	(via
		(at 307.498242 -299.330618)
		(size 0.6604)
		(drill 0.3302)
		(layers "F.Cu" "B.Cu")
		(net "PEX2_ADCTEMP_VINP1")
	)
	(via
		(at 304.674778 -299.224954)
		(size 0.4064)
		(drill 0.2032)
		(layers "F.Cu" "B.Cu")
		(net "PEX2_ADCTEMP_VINP1")
	)
	(segment
		(start 306.226718 -299.62475)
		(end 307.20411 -299.62475)
		(width 0.13208)
		(layer "B.Cu")
		(net "PEX2_ADCTEMP_VINP1")
	)
	(segment
		(start 304.674778 -299.224954)
		(end 305.162204 -299.71238)
		(width 0.254)
		(layer "B.Cu")
		(net "PEX2_ADCTEMP_VINP1")
	)
	(segment
		(start 305.162204 -299.71238)
		(end 306.139088 -299.71238)
		(width 0.254)
		(layer "B.Cu")
		(net "PEX2_ADCTEMP_VINP1")
	)
	(segment
		(start 306.139088 -299.71238)
		(end 306.226718 -299.62475)
		(width 0.254)
		(layer "B.Cu")
		(net "PEX2_ADCTEMP_VINP1")
	)
	(segment
		(start 307.20411 -299.62475)
		(end 307.498242 -299.330618)
		(width 0.13208)
		(layer "B.Cu")
		(net "PEX2_ADCTEMP_VINP1")
	)
	(segment
		(start 361.248452 -88.765126)
		(end 362.30814 -88.765126)
		(width 0.13208)
		(layer "F.Cu")
		(net "SMB_BIC_I2C9_SSD_MUX1_SCL")
	)
	(segment
		(start 140.605002 -97.786698)
		(end 140.291058 -98.100642)
		(width 0.13208)
		(layer "F.Cu")
		(net "SMB_BIC_I2C9_SSD_MUX1_SCL")
	)
	(segment
		(start 140.291058 -98.100642)
		(end 139.385294 -98.100642)
		(width 0.13208)
		(layer "F.Cu")
		(net "SMB_BIC_I2C9_SSD_MUX1_SCL")
	)
	(segment
		(start 359.78338 -96.874838)
		(end 360.343958 -96.31426)
		(width 0.13208)
		(layer "F.Cu")
		(net "SMB_BIC_I2C9_SSD_MUX1_SCL")
	)
	(segment
		(start 360.343958 -89.66962)
		(end 361.248452 -88.765126)
		(width 0.13208)
		(layer "F.Cu")
		(net "SMB_BIC_I2C9_SSD_MUX1_SCL")
	)
	(segment
		(start 360.343958 -96.31426)
		(end 360.343958 -89.66962)
		(width 0.13208)
		(layer "F.Cu")
		(net "SMB_BIC_I2C9_SSD_MUX1_SCL")
	)
	(via
		(at 140.605002 -97.786698)
		(size 0.508)
		(drill 0.254)
		(layers "F.Cu" "B.Cu")
		(net "SMB_BIC_I2C9_SSD_MUX1_SCL")
	)
	(via
		(at 359.78338 -96.874838)
		(size 0.508)
		(drill 0.254)
		(layers "F.Cu" "B.Cu")
		(net "SMB_BIC_I2C9_SSD_MUX1_SCL")
	)
	(segment
		(start 334.264 -93.446854)
		(end 333.33436 -92.517214)
		(width 0.15494)
		(layer "In15.Cu")
		(net "SMB_BIC_I2C9_SSD_MUX1_SCL")
	)
	(segment
		(start 266.090654 -91.3384)
		(end 256.1844 -91.3384)
		(width 0.15494)
		(layer "In15.Cu")
		(net "SMB_BIC_I2C9_SSD_MUX1_SCL")
	)
	(segment
		(start 310.8452 -90.424)
		(end 271.8308 -90.424)
		(width 0.15494)
		(layer "In15.Cu")
		(net "SMB_BIC_I2C9_SSD_MUX1_SCL")
	)
	(segment
		(start 226.820222 -95.8088)
		(end 223.891094 -92.879672)
		(width 0.15494)
		(layer "In15.Cu")
		(net "SMB_BIC_I2C9_SSD_MUX1_SCL")
	)
	(segment
		(start 256.1844 -91.3384)
		(end 255.524 -91.9988)
		(width 0.15494)
		(layer "In15.Cu")
		(net "SMB_BIC_I2C9_SSD_MUX1_SCL")
	)
	(segment
		(start 255.524 -91.9988)
		(end 248.316496 -91.9988)
		(width 0.15494)
		(layer "In15.Cu")
		(net "SMB_BIC_I2C9_SSD_MUX1_SCL")
	)
	(segment
		(start 235.365036 -94.68231)
		(end 233.135932 -94.68231)
		(width 0.15494)
		(layer "In15.Cu")
		(net "SMB_BIC_I2C9_SSD_MUX1_SCL")
	)
	(segment
		(start 270.8656 -89.4588)
		(end 267.970254 -89.4588)
		(width 0.15494)
		(layer "In15.Cu")
		(net "SMB_BIC_I2C9_SSD_MUX1_SCL")
	)
	(segment
		(start 267.970254 -89.4588)
		(end 266.090654 -91.3384)
		(width 0.15494)
		(layer "In15.Cu")
		(net "SMB_BIC_I2C9_SSD_MUX1_SCL")
	)
	(segment
		(start 192.633854 -87.2998)
		(end 155.194 -87.2998)
		(width 0.15494)
		(layer "In15.Cu")
		(net "SMB_BIC_I2C9_SSD_MUX1_SCL")
	)
	(segment
		(start 155.194 -87.2998)
		(end 143.4592 -99.0346)
		(width 0.15494)
		(layer "In15.Cu")
		(net "SMB_BIC_I2C9_SSD_MUX1_SCL")
	)
	(segment
		(start 345.15679 -97.6122)
		(end 343.09939 -95.5548)
		(width 0.15494)
		(layer "In15.Cu")
		(net "SMB_BIC_I2C9_SSD_MUX1_SCL")
	)
	(segment
		(start 336.092546 -95.5548)
		(end 334.264 -93.726254)
		(width 0.15494)
		(layer "In15.Cu")
		(net "SMB_BIC_I2C9_SSD_MUX1_SCL")
	)
	(segment
		(start 223.891094 -92.879672)
		(end 223.891094 -90.017346)
		(width 0.15494)
		(layer "In15.Cu")
		(net "SMB_BIC_I2C9_SSD_MUX1_SCL")
	)
	(segment
		(start 315.5442 -91.44)
		(end 311.8612 -91.44)
		(width 0.15494)
		(layer "In15.Cu")
		(net "SMB_BIC_I2C9_SSD_MUX1_SCL")
	)
	(segment
		(start 233.135932 -94.68231)
		(end 231.674162 -96.14408)
		(width 0.15494)
		(layer "In15.Cu")
		(net "SMB_BIC_I2C9_SSD_MUX1_SCL")
	)
	(segment
		(start 316.484 -90.5002)
		(end 315.5442 -91.44)
		(width 0.15494)
		(layer "In15.Cu")
		(net "SMB_BIC_I2C9_SSD_MUX1_SCL")
	)
	(segment
		(start 333.33436 -92.517214)
		(end 331.91704 -92.517214)
		(width 0.15494)
		(layer "In15.Cu")
		(net "SMB_BIC_I2C9_SSD_MUX1_SCL")
	)
	(segment
		(start 331.91704 -92.517214)
		(end 331.470254 -92.964)
		(width 0.15494)
		(layer "In15.Cu")
		(net "SMB_BIC_I2C9_SSD_MUX1_SCL")
	)
	(segment
		(start 236.690408 -94.15653)
		(end 235.890816 -94.15653)
		(width 0.15494)
		(layer "In15.Cu")
		(net "SMB_BIC_I2C9_SSD_MUX1_SCL")
	)
	(segment
		(start 222.799148 -88.9254)
		(end 205.5368 -88.9254)
		(width 0.15494)
		(layer "In15.Cu")
		(net "SMB_BIC_I2C9_SSD_MUX1_SCL")
	)
	(segment
		(start 229.530402 -96.14408)
		(end 229.195122 -95.8088)
		(width 0.15494)
		(layer "In15.Cu")
		(net "SMB_BIC_I2C9_SSD_MUX1_SCL")
	)
	(segment
		(start 193.675254 -86.2584)
		(end 192.633854 -87.2998)
		(width 0.15494)
		(layer "In15.Cu")
		(net "SMB_BIC_I2C9_SSD_MUX1_SCL")
	)
	(segment
		(start 205.5368 -88.9254)
		(end 202.8698 -86.2584)
		(width 0.15494)
		(layer "In15.Cu")
		(net "SMB_BIC_I2C9_SSD_MUX1_SCL")
	)
	(segment
		(start 237.501938 -94.96806)
		(end 236.690408 -94.15653)
		(width 0.15494)
		(layer "In15.Cu")
		(net "SMB_BIC_I2C9_SSD_MUX1_SCL")
	)
	(segment
		(start 359.78338 -96.874838)
		(end 359.046018 -97.6122)
		(width 0.15494)
		(layer "In15.Cu")
		(net "SMB_BIC_I2C9_SSD_MUX1_SCL")
	)
	(segment
		(start 359.046018 -97.6122)
		(end 345.15679 -97.6122)
		(width 0.15494)
		(layer "In15.Cu")
		(net "SMB_BIC_I2C9_SSD_MUX1_SCL")
	)
	(segment
		(start 323.723 -90.5002)
		(end 316.484 -90.5002)
		(width 0.15494)
		(layer "In15.Cu")
		(net "SMB_BIC_I2C9_SSD_MUX1_SCL")
	)
	(segment
		(start 245.347236 -94.96806)
		(end 237.501938 -94.96806)
		(width 0.15494)
		(layer "In15.Cu")
		(net "SMB_BIC_I2C9_SSD_MUX1_SCL")
	)
	(segment
		(start 326.1868 -92.964)
		(end 323.723 -90.5002)
		(width 0.15494)
		(layer "In15.Cu")
		(net "SMB_BIC_I2C9_SSD_MUX1_SCL")
	)
	(segment
		(start 229.195122 -95.8088)
		(end 226.820222 -95.8088)
		(width 0.15494)
		(layer "In15.Cu")
		(net "SMB_BIC_I2C9_SSD_MUX1_SCL")
	)
	(segment
		(start 235.890816 -94.15653)
		(end 235.365036 -94.68231)
		(width 0.15494)
		(layer "In15.Cu")
		(net "SMB_BIC_I2C9_SSD_MUX1_SCL")
	)
	(segment
		(start 231.674162 -96.14408)
		(end 229.530402 -96.14408)
		(width 0.15494)
		(layer "In15.Cu")
		(net "SMB_BIC_I2C9_SSD_MUX1_SCL")
	)
	(segment
		(start 202.8698 -86.2584)
		(end 193.675254 -86.2584)
		(width 0.15494)
		(layer "In15.Cu")
		(net "SMB_BIC_I2C9_SSD_MUX1_SCL")
	)
	(segment
		(start 334.264 -93.726254)
		(end 334.264 -93.446854)
		(width 0.15494)
		(layer "In15.Cu")
		(net "SMB_BIC_I2C9_SSD_MUX1_SCL")
	)
	(segment
		(start 311.8612 -91.44)
		(end 310.8452 -90.424)
		(width 0.15494)
		(layer "In15.Cu")
		(net "SMB_BIC_I2C9_SSD_MUX1_SCL")
	)
	(segment
		(start 271.8308 -90.424)
		(end 270.8656 -89.4588)
		(width 0.15494)
		(layer "In15.Cu")
		(net "SMB_BIC_I2C9_SSD_MUX1_SCL")
	)
	(segment
		(start 141.852904 -99.0346)
		(end 140.605002 -97.786698)
		(width 0.15494)
		(layer "In15.Cu")
		(net "SMB_BIC_I2C9_SSD_MUX1_SCL")
	)
	(segment
		(start 143.4592 -99.0346)
		(end 141.852904 -99.0346)
		(width 0.15494)
		(layer "In15.Cu")
		(net "SMB_BIC_I2C9_SSD_MUX1_SCL")
	)
	(segment
		(start 343.09939 -95.5548)
		(end 336.092546 -95.5548)
		(width 0.15494)
		(layer "In15.Cu")
		(net "SMB_BIC_I2C9_SSD_MUX1_SCL")
	)
	(segment
		(start 223.891094 -90.017346)
		(end 222.799148 -88.9254)
		(width 0.15494)
		(layer "In15.Cu")
		(net "SMB_BIC_I2C9_SSD_MUX1_SCL")
	)
	(segment
		(start 248.316496 -91.9988)
		(end 245.347236 -94.96806)
		(width 0.15494)
		(layer "In15.Cu")
		(net "SMB_BIC_I2C9_SSD_MUX1_SCL")
	)
	(segment
		(start 331.470254 -92.964)
		(end 326.1868 -92.964)
		(width 0.15494)
		(layer "In15.Cu")
		(net "SMB_BIC_I2C9_SSD_MUX1_SCL")
	)
	(segment
		(start 330.008992 -207.141318)
		(end 330.74356 -206.40675)
		(width 0.13208)
		(layer "F.Cu")
		(net "CLK_25M_FPGA")
	)
	(segment
		(start 331.574648 -205.20152)
		(end 331.528928 -205.20152)
		(width 0.13208)
		(layer "F.Cu")
		(net "CLK_25M_FPGA")
	)
	(segment
		(start 329.922886 -207.141318)
		(end 330.008992 -207.141318)
		(width 0.13208)
		(layer "F.Cu")
		(net "CLK_25M_FPGA")
	)
	(segment
		(start 330.74356 -205.986888)
		(end 330.74356 -206.40675)
		(width 0.13208)
		(layer "F.Cu")
		(net "CLK_25M_FPGA")
	)
	(segment
		(start 331.528928 -205.20152)
		(end 330.74356 -205.986888)
		(width 0.13208)
		(layer "F.Cu")
		(net "CLK_25M_FPGA")
	)
	(via
		(at 330.74356 -206.40675)
		(size 0.508)
		(drill 0.254)
		(layers "F.Cu" "B.Cu")
		(net "CLK_25M_FPGA")
	)
	(segment
		(start 173.006004 -141.9352)
		(end 173.285404 -141.6558)
		(width 0.4572)
		(layer "F.Cu")
		(net "P3V3_NIC2")
	)
	(segment
		(start 172.379894 -141.9352)
		(end 173.006004 -141.9352)
		(width 0.4064)
		(layer "F.Cu")
		(net "P3V3_NIC2")
	)
	(segment
		(start 128.201166 -118.743476)
		(end 128.201166 -119.35587)
		(width 0.4572)
		(layer "F.Cu")
		(net "P3V3_NIC2")
	)
	(segment
		(start 154.307794 -157.3784)
		(end 153.672794 -157.3784)
		(width 0.4064)
		(layer "F.Cu")
		(net "P3V3_NIC2")
	)
	(segment
		(start 125.810264 -125.979428)
		(end 125.154944 -125.979428)
		(width 0.4064)
		(layer "F.Cu")
		(net "P3V3_NIC2")
	)
	(segment
		(start 173.285404 -141.6558)
		(end 173.764194 -141.6558)
		(width 0.4572)
		(layer "F.Cu")
		(net "P3V3_NIC2")
	)
	(segment
		(start 178.329844 -171.661328)
		(end 178.329844 -172.329348)
		(width 0.4572)
		(layer "F.Cu")
		(net "P3V3_NIC2")
	)
	(segment
		(start 177.593752 -166.070534)
		(end 177.593752 -166.705534)
		(width 0.4064)
		(layer "F.Cu")
		(net "P3V3_NIC2")
	)
	(segment
		(start 172.379894 -142.9512)
		(end 173.02226 -142.9512)
		(width 0.4064)
		(layer "F.Cu")
		(net "P3V3_NIC2")
	)
	(segment
		(start 154.307794 -158.3944)
		(end 153.672794 -158.3944)
		(width 0.4064)
		(layer "F.Cu")
		(net "P3V3_NIC2")
	)
	(segment
		(start 179.267104 -171.675806)
		(end 179.267104 -172.343826)
		(width 0.4572)
		(layer "F.Cu")
		(net "P3V3_NIC2")
	)
	(segment
		(start 177.715926 -170.157902)
		(end 178.329844 -170.77182)
		(width 0.4572)
		(layer "F.Cu")
		(net "P3V3_NIC2")
	)
	(segment
		(start 178.329844 -170.77182)
		(end 178.329844 -171.661328)
		(width 0.4572)
		(layer "F.Cu")
		(net "P3V3_NIC2")
	)
	(segment
		(start 154.307794 -153.3144)
		(end 153.672794 -153.3144)
		(width 0.4064)
		(layer "F.Cu")
		(net "P3V3_NIC2")
	)
	(via
		(at 132.966206 -125.218698)
		(size 0.508)
		(drill 0.254)
		(layers "F.Cu" "B.Cu")
		(net "P3V3_NIC2")
	)
	(via
		(at 132.025644 -125.403356)
		(size 0.508)
		(drill 0.254)
		(layers "F.Cu" "B.Cu")
		(net "P3V3_NIC2")
	)
	(via
		(at 125.154944 -125.979428)
		(size 0.508)
		(drill 0.254)
		(layers "F.Cu" "B.Cu")
		(net "P3V3_NIC2")
	)
	(via
		(at 134.293864 -117.259608)
		(size 0.508)
		(drill 0.254)
		(layers "F.Cu" "B.Cu")
		(net "P3V3_NIC2")
	)
	(via
		(at 151.769318 -138.88847)
		(size 0.6604)
		(drill 0.3302)
		(layers "F.Cu" "B.Cu")
		(net "P3V3_NIC2")
	)
	(via
		(at 179.267104 -172.343826)
		(size 0.508)
		(drill 0.254)
		(layers "F.Cu" "B.Cu")
		(net "P3V3_NIC2")
	)
	(via
		(at 177.593752 -166.705534)
		(size 0.508)
		(drill 0.254)
		(layers "F.Cu" "B.Cu")
		(net "P3V3_NIC2")
	)
	(via
		(at 134.174738 -126.530354)
		(size 0.508)
		(drill 0.254)
		(layers "F.Cu" "B.Cu")
		(net "P3V3_NIC2")
	)
	(via
		(at 132.966206 -125.853698)
		(size 0.508)
		(drill 0.254)
		(layers "F.Cu" "B.Cu")
		(net "P3V3_NIC2")
	)
	(via
		(at 134.293864 -116.624608)
		(size 0.508)
		(drill 0.254)
		(layers "F.Cu" "B.Cu")
		(net "P3V3_NIC2")
	)
	(via
		(at 173.02226 -142.9512)
		(size 0.508)
		(drill 0.254)
		(layers "F.Cu" "B.Cu")
		(net "P3V3_NIC2")
	)
	(via
		(at 134.885938 -125.768354)
		(size 0.508)
		(drill 0.254)
		(layers "F.Cu" "B.Cu")
		(net "P3V3_NIC2")
	)
	(via
		(at 133.658864 -117.259608)
		(size 0.508)
		(drill 0.254)
		(layers "F.Cu" "B.Cu")
		(net "P3V3_NIC2")
	)
	(via
		(at 153.672794 -153.3144)
		(size 0.508)
		(drill 0.254)
		(layers "F.Cu" "B.Cu")
		(net "P3V3_NIC2")
	)
	(via
		(at 160.706054 -139.930378)
		(size 0.508)
		(drill 0.254)
		(layers "F.Cu" "B.Cu")
		(net "P3V3_NIC2")
	)
	(via
		(at 160.706054 -140.565378)
		(size 0.508)
		(drill 0.254)
		(layers "F.Cu" "B.Cu")
		(net "P3V3_NIC2")
	)
	(via
		(at 133.658864 -115.989608)
		(size 0.508)
		(drill 0.254)
		(layers "F.Cu" "B.Cu")
		(net "P3V3_NIC2")
	)
	(via
		(at 134.250938 -125.768354)
		(size 0.508)
		(drill 0.254)
		(layers "F.Cu" "B.Cu")
		(net "P3V3_NIC2")
	)
	(via
		(at 157.175454 -138.699748)
		(size 0.6604)
		(drill 0.3302)
		(layers "F.Cu" "B.Cu")
		(net "P3V3_NIC2")
	)
	(via
		(at 160.071054 -139.930378)
		(size 0.508)
		(drill 0.254)
		(layers "F.Cu" "B.Cu")
		(net "P3V3_NIC2")
	)
	(via
		(at 134.293864 -115.989608)
		(size 0.508)
		(drill 0.254)
		(layers "F.Cu" "B.Cu")
		(net "P3V3_NIC2")
	)
	(via
		(at 135.920226 -126.652782)
		(size 0.508)
		(drill 0.254)
		(layers "F.Cu" "B.Cu")
		(net "P3V3_NIC2")
	)
	(via
		(at 128.201166 -119.35587)
		(size 0.508)
		(drill 0.254)
		(layers "F.Cu" "B.Cu")
		(net "P3V3_NIC2")
	)
	(via
		(at 160.071054 -140.565378)
		(size 0.508)
		(drill 0.254)
		(layers "F.Cu" "B.Cu")
		(net "P3V3_NIC2")
	)
	(via
		(at 153.672794 -158.3944)
		(size 0.508)
		(drill 0.254)
		(layers "F.Cu" "B.Cu")
		(net "P3V3_NIC2")
	)
	(via
		(at 178.329844 -172.329348)
		(size 0.508)
		(drill 0.254)
		(layers "F.Cu" "B.Cu")
		(net "P3V3_NIC2")
	)
	(via
		(at 153.672794 -157.3784)
		(size 0.508)
		(drill 0.254)
		(layers "F.Cu" "B.Cu")
		(net "P3V3_NIC2")
	)
	(via
		(at 173.006004 -141.9352)
		(size 0.508)
		(drill 0.254)
		(layers "F.Cu" "B.Cu")
		(net "P3V3_NIC2")
	)
	(via
		(at 135.920226 -124.747782)
		(size 0.508)
		(drill 0.254)
		(layers "F.Cu" "B.Cu")
		(net "P3V3_NIC2")
	)
	(via
		(at 164.645594 -155.0416)
		(size 0.508)
		(drill 0.254)
		(layers "F.Cu" "B.Cu")
		(net "P3V3_NIC2")
	)
	(via
		(at 135.920226 -126.017782)
		(size 0.508)
		(drill 0.254)
		(layers "F.Cu" "B.Cu")
		(net "P3V3_NIC2")
	)
	(via
		(at 135.920226 -125.382782)
		(size 0.508)
		(drill 0.254)
		(layers "F.Cu" "B.Cu")
		(net "P3V3_NIC2")
	)
	(via
		(at 132.025644 -124.768356)
		(size 0.508)
		(drill 0.254)
		(layers "F.Cu" "B.Cu")
		(net "P3V3_NIC2")
	)
	(via
		(at 145.95475 -139.171172)
		(size 0.6604)
		(drill 0.3302)
		(layers "F.Cu" "B.Cu")
		(net "P3V3_NIC2")
	)
	(via
		(at 133.658864 -116.624608)
		(size 0.508)
		(drill 0.254)
		(layers "F.Cu" "B.Cu")
		(net "P3V3_NIC2")
	)
	(via
		(at 134.885938 -126.530354)
		(size 0.508)
		(drill 0.254)
		(layers "F.Cu" "B.Cu")
		(net "P3V3_NIC2")
	)
	(segment
		(start 165.255194 -155.0416)
		(end 164.645594 -155.0416)
		(width 0.4572)
		(layer "B.Cu")
		(net "P3V3_NIC2")
	)
	(segment
		(start 335.152238 -81.94675)
		(end 335.952084 -82.746596)
		(width 0.13462)
		(layer "F.Cu")
		(net "CLK_100M_DB800ZL_SSD8_DP")
	)
	(segment
		(start 335.952084 -83.331304)
		(end 335.895696 -83.387692)
		(width 0.13462)
		(layer "F.Cu")
		(net "CLK_100M_DB800ZL_SSD8_DP")
	)
	(segment
		(start 335.152238 -81.321402)
		(end 335.152238 -81.94675)
		(width 0.13462)
		(layer "F.Cu")
		(net "CLK_100M_DB800ZL_SSD8_DP")
	)
	(segment
		(start 334.838548 -81.007712)
		(end 335.152238 -81.321402)
		(width 0.13462)
		(layer "F.Cu")
		(net "CLK_100M_DB800ZL_SSD8_DP")
	)
	(segment
		(start 335.952084 -82.746596)
		(end 335.952084 -83.331304)
		(width 0.13462)
		(layer "F.Cu")
		(net "CLK_100M_DB800ZL_SSD8_DP")
	)
	(segment
		(start 335.895696 -83.387692)
		(end 335.895696 -83.814412)
		(width 0.13462)
		(layer "F.Cu")
		(net "CLK_100M_DB800ZL_SSD8_DP")
	)
	(segment
		(start 256.542286 -251.956824)
		(end 256.542286 -251.287026)
		(width 0.13208)
		(layer "F.Cu")
		(net "PEX2_MODE_SEL9")
	)
	(segment
		(start 294.699944 -283.549852)
		(end 295.174924 -284.024832)
		(width 0.13208)
		(layer "F.Cu")
		(net "PEX2_MODE_SEL9")
	)
	(segment
		(start 256.542286 -251.060966)
		(end 256.542286 -250.470924)
		(width 0.13208)
		(layer "F.Cu")
		(net "PEX2_MODE_SEL9")
	)
	(segment
		(start 256.429256 -251.173996)
		(end 256.542286 -251.060966)
		(width 0.13208)
		(layer "F.Cu")
		(net "PEX2_MODE_SEL9")
	)
	(segment
		(start 294.69969 -283.549852)
		(end 294.699944 -283.549852)
		(width 0.13208)
		(layer "F.Cu")
		(net "PEX2_MODE_SEL9")
	)
	(segment
		(start 256.542286 -251.287026)
		(end 256.429256 -251.173996)
		(width 0.13208)
		(layer "F.Cu")
		(net "PEX2_MODE_SEL9")
	)
	(via
		(at 295.174924 -284.024832)
		(size 0.4064)
		(drill 0.2032)
		(layers "F.Cu" "B.Cu")
		(net "PEX2_MODE_SEL9")
	)
	(via
		(at 256.429256 -251.173996)
		(size 0.508)
		(drill 0.254)
		(layers "F.Cu" "B.Cu")
		(net "PEX2_MODE_SEL9")
	)
	(segment
		(start 285.010352 -252.054614)
		(end 304.705258 -271.74952)
		(width 0.13208)
		(layer "B.Cu")
		(net "PEX2_MODE_SEL9")
	)
	(segment
		(start 256.429256 -250.689364)
		(end 256.931414 -250.187206)
		(width 0.13208)
		(layer "B.Cu")
		(net "PEX2_MODE_SEL9")
	)
	(segment
		(start 256.429256 -251.173996)
		(end 256.429256 -250.689364)
		(width 0.13208)
		(layer "B.Cu")
		(net "PEX2_MODE_SEL9")
	)
	(segment
		(start 303.916588 -282.672536)
		(end 303.497234 -282.672536)
		(width 0.13208)
		(layer "B.Cu")
		(net "PEX2_MODE_SEL9")
	)
	(segment
		(start 256.931414 -250.187206)
		(end 270.69669 -250.187206)
		(width 0.13208)
		(layer "B.Cu")
		(net "PEX2_MODE_SEL9")
	)
	(segment
		(start 303.186846 -285.128208)
		(end 302.920654 -285.3944)
		(width 0.13208)
		(layer "B.Cu")
		(net "PEX2_MODE_SEL9")
	)
	(segment
		(start 295.63314 -285.11754)
		(end 295.63314 -284.483048)
		(width 0.13208)
		(layer "B.Cu")
		(net "PEX2_MODE_SEL9")
	)
	(segment
		(start 271.273524 -251.48286)
		(end 271.845278 -252.054614)
		(width 0.13208)
		(layer "B.Cu")
		(net "PEX2_MODE_SEL9")
	)
	(segment
		(start 304.705258 -281.883866)
		(end 303.916588 -282.672536)
		(width 0.13208)
		(layer "B.Cu")
		(net "PEX2_MODE_SEL9")
	)
	(segment
		(start 303.186846 -282.982924)
		(end 303.186846 -285.128208)
		(width 0.13208)
		(layer "B.Cu")
		(net "PEX2_MODE_SEL9")
	)
	(segment
		(start 295.63314 -284.483048)
		(end 295.174924 -284.024832)
		(width 0.13208)
		(layer "B.Cu")
		(net "PEX2_MODE_SEL9")
	)
	(segment
		(start 271.845278 -252.054614)
		(end 285.010352 -252.054614)
		(width 0.13208)
		(layer "B.Cu")
		(net "PEX2_MODE_SEL9")
	)
	(segment
		(start 270.69669 -250.187206)
		(end 271.273524 -250.76404)
		(width 0.13208)
		(layer "B.Cu")
		(net "PEX2_MODE_SEL9")
	)
	(segment
		(start 303.497234 -282.672536)
		(end 303.186846 -282.982924)
		(width 0.13208)
		(layer "B.Cu")
		(net "PEX2_MODE_SEL9")
	)
	(segment
		(start 304.705258 -271.74952)
		(end 304.705258 -281.883866)
		(width 0.13208)
		(layer "B.Cu")
		(net "PEX2_MODE_SEL9")
	)
	(segment
		(start 295.91 -285.3944)
		(end 295.63314 -285.11754)
		(width 0.13208)
		(layer "B.Cu")
		(net "PEX2_MODE_SEL9")
	)
	(segment
		(start 302.920654 -285.3944)
		(end 295.91 -285.3944)
		(width 0.13208)
		(layer "B.Cu")
		(net "PEX2_MODE_SEL9")
	)
	(segment
		(start 271.273524 -250.76404)
		(end 271.273524 -251.48286)
		(width 0.13208)
		(layer "B.Cu")
		(net "PEX2_MODE_SEL9")
	)
	(segment
		(start 212.541104 -211.647786)
		(end 212.541104 -211.166456)
		(width 0.13208)
		(layer "F.Cu")
		(net "RST_BIC_I2C9_SSD_MUX1_R_N")
	)
	(segment
		(start 357.848916 -96.826578)
		(end 357.848916 -88.884506)
		(width 0.13208)
		(layer "F.Cu")
		(net "RST_BIC_I2C9_SSD_MUX1_R_N")
	)
	(segment
		(start 212.541104 -211.166456)
		(end 212.557106 -211.150454)
		(width 0.13208)
		(layer "F.Cu")
		(net "RST_BIC_I2C9_SSD_MUX1_R_N")
	)
	(segment
		(start 357.729536 -88.765126)
		(end 356.707948 -88.765126)
		(width 0.13208)
		(layer "F.Cu")
		(net "RST_BIC_I2C9_SSD_MUX1_R_N")
	)
	(segment
		(start 212.62721 -211.855558)
		(end 212.541104 -211.647786)
		(width 0.13208)
		(layer "F.Cu")
		(net "RST_BIC_I2C9_SSD_MUX1_R_N")
	)
	(segment
		(start 212.82914 -212.057488)
		(end 212.62721 -211.855558)
		(width 0.13208)
		(layer "F.Cu")
		(net "RST_BIC_I2C9_SSD_MUX1_R_N")
	)
	(segment
		(start 213.503256 -212.057488)
		(end 212.82914 -212.057488)
		(width 0.13208)
		(layer "F.Cu")
		(net "RST_BIC_I2C9_SSD_MUX1_R_N")
	)
	(segment
		(start 357.848916 -88.884506)
		(end 357.729536 -88.765126)
		(width 0.13208)
		(layer "F.Cu")
		(net "RST_BIC_I2C9_SSD_MUX1_R_N")
	)
	(segment
		(start 214.054436 -212.206586)
		(end 213.652354 -212.206586)
		(width 0.13208)
		(layer "F.Cu")
		(net "RST_BIC_I2C9_SSD_MUX1_R_N")
	)
	(segment
		(start 213.652354 -212.206586)
		(end 213.503256 -212.057488)
		(width 0.13208)
		(layer "F.Cu")
		(net "RST_BIC_I2C9_SSD_MUX1_R_N")
	)
	(via
		(at 228.227382 -84.962492)
		(size 0.508)
		(drill 0.254)
		(layers "F.Cu" "B.Cu")
		(net "RST_BIC_I2C9_SSD_MUX1_R_N")
	)
	(via
		(at 357.848916 -96.826578)
		(size 0.508)
		(drill 0.254)
		(layers "F.Cu" "B.Cu")
		(net "RST_BIC_I2C9_SSD_MUX1_R_N")
	)
	(via
		(at 212.557106 -211.150454)
		(size 0.508)
		(drill 0.254)
		(layers "F.Cu" "B.Cu")
		(net "RST_BIC_I2C9_SSD_MUX1_R_N")
	)
	(segment
		(start 217.856816 -162.049714)
		(end 211.0232 -168.88333)
		(width 0.15494)
		(layer "In7.Cu")
		(net "RST_BIC_I2C9_SSD_MUX1_R_N")
	)
	(segment
		(start 210.236562 -104.982264)
		(end 210.236562 -116.079016)
		(width 0.15494)
		(layer "In7.Cu")
		(net "RST_BIC_I2C9_SSD_MUX1_R_N")
	)
	(segment
		(start 213.806786 -100.74656)
		(end 210.236308 -104.317038)
		(width 0.15494)
		(layer "In7.Cu")
		(net "RST_BIC_I2C9_SSD_MUX1_R_N")
	)
	(segment
		(start 212.77326 -202.89266)
		(end 212.77326 -206.920846)
		(width 0.15494)
		(layer "In7.Cu")
		(net "RST_BIC_I2C9_SSD_MUX1_R_N")
	)
	(segment
		(start 211.963 -186.730132)
		(end 211.963 -191.947292)
		(width 0.15494)
		(layer "In7.Cu")
		(net "RST_BIC_I2C9_SSD_MUX1_R_N")
	)
	(segment
		(start 213.806786 -90.868754)
		(end 213.806786 -100.74656)
		(width 0.15494)
		(layer "In7.Cu")
		(net "RST_BIC_I2C9_SSD_MUX1_R_N")
	)
	(segment
		(start 212.77326 -206.920846)
		(end 213.054946 -207.202532)
		(width 0.15494)
		(layer "In7.Cu")
		(net "RST_BIC_I2C9_SSD_MUX1_R_N")
	)
	(segment
		(start 209.83829 -200.38187)
		(end 210.26247 -200.38187)
		(width 0.15494)
		(layer "In7.Cu")
		(net "RST_BIC_I2C9_SSD_MUX1_R_N")
	)
	(segment
		(start 211.0232 -168.898062)
		(end 211.02066 -168.900602)
		(width 0.15494)
		(layer "In7.Cu")
		(net "RST_BIC_I2C9_SSD_MUX1_R_N")
	)
	(segment
		(start 207.75422 -196.156072)
		(end 207.75422 -198.69658)
		(width 0.15494)
		(layer "In7.Cu")
		(net "RST_BIC_I2C9_SSD_MUX1_R_N")
	)
	(segment
		(start 213.863428 -153.49982)
		(end 217.856816 -157.493208)
		(width 0.15494)
		(layer "In7.Cu")
		(net "RST_BIC_I2C9_SSD_MUX1_R_N")
	)
	(segment
		(start 209.36204 -200.3044)
		(end 209.76082 -200.3044)
		(width 0.15494)
		(layer "In7.Cu")
		(net "RST_BIC_I2C9_SSD_MUX1_R_N")
	)
	(segment
		(start 210.26247 -200.38187)
		(end 212.77326 -202.89266)
		(width 0.15494)
		(layer "In7.Cu")
		(net "RST_BIC_I2C9_SSD_MUX1_R_N")
	)
	(segment
		(start 213.863428 -133.050534)
		(end 213.863428 -153.49982)
		(width 0.15494)
		(layer "In7.Cu")
		(net "RST_BIC_I2C9_SSD_MUX1_R_N")
	)
	(segment
		(start 210.236562 -116.079016)
		(end 210.5152 -116.357654)
		(width 0.15494)
		(layer "In7.Cu")
		(net "RST_BIC_I2C9_SSD_MUX1_R_N")
	)
	(segment
		(start 209.2452 -121.3104)
		(end 208.7626 -121.3104)
		(width 0.15494)
		(layer "In7.Cu")
		(net "RST_BIC_I2C9_SSD_MUX1_R_N")
	)
	(segment
		(start 227.51034 -85.679534)
		(end 225.89744 -85.679534)
		(width 0.15494)
		(layer "In7.Cu")
		(net "RST_BIC_I2C9_SSD_MUX1_R_N")
	)
	(segment
		(start 208.2038 -123.3424)
		(end 209.4484 -124.587)
		(width 0.15494)
		(layer "In7.Cu")
		(net "RST_BIC_I2C9_SSD_MUX1_R_N")
	)
	(segment
		(start 210.236308 -104.98201)
		(end 210.236562 -104.982264)
		(width 0.15494)
		(layer "In7.Cu")
		(net "RST_BIC_I2C9_SSD_MUX1_R_N")
	)
	(segment
		(start 208.7626 -121.3104)
		(end 208.2038 -121.8692)
		(width 0.15494)
		(layer "In7.Cu")
		(net "RST_BIC_I2C9_SSD_MUX1_R_N")
	)
	(segment
		(start 211.963 -191.947292)
		(end 207.75422 -196.156072)
		(width 0.15494)
		(layer "In7.Cu")
		(net "RST_BIC_I2C9_SSD_MUX1_R_N")
	)
	(segment
		(start 211.0232 -170.675554)
		(end 211.384642 -171.036996)
		(width 0.15494)
		(layer "In7.Cu")
		(net "RST_BIC_I2C9_SSD_MUX1_R_N")
	)
	(segment
		(start 210.236308 -104.317038)
		(end 210.236308 -104.98201)
		(width 0.15494)
		(layer "In7.Cu")
		(net "RST_BIC_I2C9_SSD_MUX1_R_N")
	)
	(segment
		(start 210.5152 -120.0404)
		(end 209.2452 -121.3104)
		(width 0.15494)
		(layer "In7.Cu")
		(net "RST_BIC_I2C9_SSD_MUX1_R_N")
	)
	(segment
		(start 217.856816 -157.493208)
		(end 217.856816 -162.049714)
		(width 0.15494)
		(layer "In7.Cu")
		(net "RST_BIC_I2C9_SSD_MUX1_R_N")
	)
	(segment
		(start 222.093536 -89.456514)
		(end 214.416894 -89.456514)
		(width 0.15494)
		(layer "In7.Cu")
		(net "RST_BIC_I2C9_SSD_MUX1_R_N")
	)
	(segment
		(start 213.79688 -90.076528)
		(end 213.79688 -90.858848)
		(width 0.15494)
		(layer "In7.Cu")
		(net "RST_BIC_I2C9_SSD_MUX1_R_N")
	)
	(segment
		(start 211.384642 -171.036996)
		(end 211.384642 -183.165242)
		(width 0.15494)
		(layer "In7.Cu")
		(net "RST_BIC_I2C9_SSD_MUX1_R_N")
	)
	(segment
		(start 209.76082 -200.3044)
		(end 209.83829 -200.38187)
		(width 0.15494)
		(layer "In7.Cu")
		(net "RST_BIC_I2C9_SSD_MUX1_R_N")
	)
	(segment
		(start 207.75422 -198.69658)
		(end 209.36204 -200.3044)
		(width 0.15494)
		(layer "In7.Cu")
		(net "RST_BIC_I2C9_SSD_MUX1_R_N")
	)
	(segment
		(start 222.113856 -89.436194)
		(end 222.093536 -89.456514)
		(width 0.15494)
		(layer "In7.Cu")
		(net "RST_BIC_I2C9_SSD_MUX1_R_N")
	)
	(segment
		(start 212.557106 -210.362038)
		(end 212.557106 -211.150454)
		(width 0.15494)
		(layer "In7.Cu")
		(net "RST_BIC_I2C9_SSD_MUX1_R_N")
	)
	(segment
		(start 210.5152 -116.357654)
		(end 210.5152 -120.0404)
		(width 0.15494)
		(layer "In7.Cu")
		(net "RST_BIC_I2C9_SSD_MUX1_R_N")
	)
	(segment
		(start 211.0232 -170.321986)
		(end 211.0232 -170.675554)
		(width 0.15494)
		(layer "In7.Cu")
		(net "RST_BIC_I2C9_SSD_MUX1_R_N")
	)
	(segment
		(start 211.02066 -170.319446)
		(end 211.0232 -170.321986)
		(width 0.15494)
		(layer "In7.Cu")
		(net "RST_BIC_I2C9_SSD_MUX1_R_N")
	)
	(segment
		(start 228.227382 -84.962492)
		(end 227.51034 -85.679534)
		(width 0.15494)
		(layer "In7.Cu")
		(net "RST_BIC_I2C9_SSD_MUX1_R_N")
	)
	(segment
		(start 222.14078 -89.436194)
		(end 222.113856 -89.436194)
		(width 0.15494)
		(layer "In7.Cu")
		(net "RST_BIC_I2C9_SSD_MUX1_R_N")
	)
	(segment
		(start 211.0232 -168.88333)
		(end 211.0232 -168.898062)
		(width 0.15494)
		(layer "In7.Cu")
		(net "RST_BIC_I2C9_SSD_MUX1_R_N")
	)
	(segment
		(start 211.384642 -183.165242)
		(end 212.388958 -184.169558)
		(width 0.15494)
		(layer "In7.Cu")
		(net "RST_BIC_I2C9_SSD_MUX1_R_N")
	)
	(segment
		(start 212.388958 -184.169558)
		(end 212.388958 -186.304174)
		(width 0.15494)
		(layer "In7.Cu")
		(net "RST_BIC_I2C9_SSD_MUX1_R_N")
	)
	(segment
		(start 209.4484 -124.587)
		(end 209.4484 -128.635506)
		(width 0.15494)
		(layer "In7.Cu")
		(net "RST_BIC_I2C9_SSD_MUX1_R_N")
	)
	(segment
		(start 213.054946 -207.202532)
		(end 213.054946 -209.864198)
		(width 0.15494)
		(layer "In7.Cu")
		(net "RST_BIC_I2C9_SSD_MUX1_R_N")
	)
	(segment
		(start 214.416894 -89.456514)
		(end 213.79688 -90.076528)
		(width 0.15494)
		(layer "In7.Cu")
		(net "RST_BIC_I2C9_SSD_MUX1_R_N")
	)
	(segment
		(start 209.4484 -128.635506)
		(end 213.863428 -133.050534)
		(width 0.15494)
		(layer "In7.Cu")
		(net "RST_BIC_I2C9_SSD_MUX1_R_N")
	)
	(segment
		(start 213.054946 -209.864198)
		(end 212.557106 -210.362038)
		(width 0.15494)
		(layer "In7.Cu")
		(net "RST_BIC_I2C9_SSD_MUX1_R_N")
	)
	(segment
		(start 212.388958 -186.304174)
		(end 211.963 -186.730132)
		(width 0.15494)
		(layer "In7.Cu")
		(net "RST_BIC_I2C9_SSD_MUX1_R_N")
	)
	(segment
		(start 225.89744 -85.679534)
		(end 222.14078 -89.436194)
		(width 0.15494)
		(layer "In7.Cu")
		(net "RST_BIC_I2C9_SSD_MUX1_R_N")
	)
	(segment
		(start 208.2038 -121.8692)
		(end 208.2038 -123.3424)
		(width 0.15494)
		(layer "In7.Cu")
		(net "RST_BIC_I2C9_SSD_MUX1_R_N")
	)
	(segment
		(start 211.02066 -168.900602)
		(end 211.02066 -170.319446)
		(width 0.15494)
		(layer "In7.Cu")
		(net "RST_BIC_I2C9_SSD_MUX1_R_N")
	)
	(segment
		(start 213.79688 -90.858848)
		(end 213.806786 -90.868754)
		(width 0.15494)
		(layer "In7.Cu")
		(net "RST_BIC_I2C9_SSD_MUX1_R_N")
	)
	(segment
		(start 242.598448 -78.0542)
		(end 244.302026 -79.757778)
		(width 0.15494)
		(layer "In15.Cu")
		(net "RST_BIC_I2C9_SSD_MUX1_R_N")
	)
	(segment
		(start 333.964788 -91.597734)
		(end 335.633314 -93.26626)
		(width 0.15494)
		(layer "In15.Cu")
		(net "RST_BIC_I2C9_SSD_MUX1_R_N")
	)
	(segment
		(start 248.1072 -91.4908)
		(end 255.320546 -91.4908)
		(width 0.15494)
		(layer "In15.Cu")
		(net "RST_BIC_I2C9_SSD_MUX1_R_N")
	)
	(segment
		(start 229.743 -79.502)
		(end 235.1024 -79.502)
		(width 0.15494)
		(layer "In15.Cu")
		(net "RST_BIC_I2C9_SSD_MUX1_R_N")
	)
	(segment
		(start 345.924378 -96.826578)
		(end 357.848916 -96.826578)
		(width 0.15494)
		(layer "In15.Cu")
		(net "RST_BIC_I2C9_SSD_MUX1_R_N")
	)
	(segment
		(start 325.2216 -89.535)
		(end 327.6346 -91.948)
		(width 0.15494)
		(layer "In15.Cu")
		(net "RST_BIC_I2C9_SSD_MUX1_R_N")
	)
	(segment
		(start 275.844254 -89.9414)
		(end 277.015956 -88.769698)
		(width 0.15494)
		(layer "In15.Cu")
		(net "RST_BIC_I2C9_SSD_MUX1_R_N")
	)
	(segment
		(start 342.36406 -93.26626)
		(end 345.924378 -96.826578)
		(width 0.15494)
		(layer "In15.Cu")
		(net "RST_BIC_I2C9_SSD_MUX1_R_N")
	)
	(segment
		(start 265.947144 -90.770456)
		(end 267.7414 -88.9762)
		(width 0.15494)
		(layer "In15.Cu")
		(net "RST_BIC_I2C9_SSD_MUX1_R_N")
	)
	(segment
		(start 228.227382 -84.962492)
		(end 228.227382 -81.017618)
		(width 0.15494)
		(layer "In15.Cu")
		(net "RST_BIC_I2C9_SSD_MUX1_R_N")
	)
	(segment
		(start 314.9854 -90.4748)
		(end 315.9252 -89.535)
		(width 0.15494)
		(layer "In15.Cu")
		(net "RST_BIC_I2C9_SSD_MUX1_R_N")
	)
	(segment
		(start 255.320546 -91.4908)
		(end 256.04089 -90.770456)
		(width 0.15494)
		(layer "In15.Cu")
		(net "RST_BIC_I2C9_SSD_MUX1_R_N")
	)
	(segment
		(start 267.7414 -88.9762)
		(end 271.094454 -88.9762)
		(width 0.15494)
		(layer "In15.Cu")
		(net "RST_BIC_I2C9_SSD_MUX1_R_N")
	)
	(segment
		(start 335.633314 -93.26626)
		(end 342.36406 -93.26626)
		(width 0.15494)
		(layer "In15.Cu")
		(net "RST_BIC_I2C9_SSD_MUX1_R_N")
	)
	(segment
		(start 331.063854 -91.948)
		(end 331.41412 -91.597734)
		(width 0.15494)
		(layer "In15.Cu")
		(net "RST_BIC_I2C9_SSD_MUX1_R_N")
	)
	(segment
		(start 244.302026 -79.757778)
		(end 244.302026 -87.685626)
		(width 0.15494)
		(layer "In15.Cu")
		(net "RST_BIC_I2C9_SSD_MUX1_R_N")
	)
	(segment
		(start 281.149298 -88.769698)
		(end 281.813 -89.4334)
		(width 0.15494)
		(layer "In15.Cu")
		(net "RST_BIC_I2C9_SSD_MUX1_R_N")
	)
	(segment
		(start 256.04089 -90.770456)
		(end 265.947144 -90.770456)
		(width 0.15494)
		(layer "In15.Cu")
		(net "RST_BIC_I2C9_SSD_MUX1_R_N")
	)
	(segment
		(start 327.6346 -91.948)
		(end 331.063854 -91.948)
		(width 0.15494)
		(layer "In15.Cu")
		(net "RST_BIC_I2C9_SSD_MUX1_R_N")
	)
	(segment
		(start 311.2262 -89.4334)
		(end 312.2676 -90.4748)
		(width 0.15494)
		(layer "In15.Cu")
		(net "RST_BIC_I2C9_SSD_MUX1_R_N")
	)
	(segment
		(start 228.227382 -81.017618)
		(end 229.743 -79.502)
		(width 0.15494)
		(layer "In15.Cu")
		(net "RST_BIC_I2C9_SSD_MUX1_R_N")
	)
	(segment
		(start 312.2676 -90.4748)
		(end 314.9854 -90.4748)
		(width 0.15494)
		(layer "In15.Cu")
		(net "RST_BIC_I2C9_SSD_MUX1_R_N")
	)
	(segment
		(start 315.9252 -89.535)
		(end 325.2216 -89.535)
		(width 0.15494)
		(layer "In15.Cu")
		(net "RST_BIC_I2C9_SSD_MUX1_R_N")
	)
	(segment
		(start 272.059654 -89.9414)
		(end 275.844254 -89.9414)
		(width 0.15494)
		(layer "In15.Cu")
		(net "RST_BIC_I2C9_SSD_MUX1_R_N")
	)
	(segment
		(start 271.094454 -88.9762)
		(end 272.059654 -89.9414)
		(width 0.15494)
		(layer "In15.Cu")
		(net "RST_BIC_I2C9_SSD_MUX1_R_N")
	)
	(segment
		(start 281.813 -89.4334)
		(end 311.2262 -89.4334)
		(width 0.15494)
		(layer "In15.Cu")
		(net "RST_BIC_I2C9_SSD_MUX1_R_N")
	)
	(segment
		(start 277.015956 -88.769698)
		(end 281.149298 -88.769698)
		(width 0.15494)
		(layer "In15.Cu")
		(net "RST_BIC_I2C9_SSD_MUX1_R_N")
	)
	(segment
		(start 235.1024 -79.502)
		(end 236.5502 -78.0542)
		(width 0.15494)
		(layer "In15.Cu")
		(net "RST_BIC_I2C9_SSD_MUX1_R_N")
	)
	(segment
		(start 331.41412 -91.597734)
		(end 333.964788 -91.597734)
		(width 0.15494)
		(layer "In15.Cu")
		(net "RST_BIC_I2C9_SSD_MUX1_R_N")
	)
	(segment
		(start 244.302026 -87.685626)
		(end 248.1072 -91.4908)
		(width 0.15494)
		(layer "In15.Cu")
		(net "RST_BIC_I2C9_SSD_MUX1_R_N")
	)
	(segment
		(start 236.5502 -78.0542)
		(end 242.598448 -78.0542)
		(width 0.15494)
		(layer "In15.Cu")
		(net "RST_BIC_I2C9_SSD_MUX1_R_N")
	)
	(segment
		(start 140.11148 -99.243642)
		(end 139.385294 -99.243642)
		(width 0.13208)
		(layer "F.Cu")
		(net "SMB_BIC_I2C9_SSD_MUX1_SDA")
	)
	(segment
		(start 359.895648 -98.273362)
		(end 360.791252 -97.377758)
		(width 0.13208)
		(layer "F.Cu")
		(net "SMB_BIC_I2C9_SSD_MUX1_SDA")
	)
	(segment
		(start 361.318048 -89.415112)
		(end 362.30814 -89.415112)
		(width 0.13208)
		(layer "F.Cu")
		(net "SMB_BIC_I2C9_SSD_MUX1_SDA")
	)
	(segment
		(start 360.791252 -89.941908)
		(end 361.318048 -89.415112)
		(width 0.13208)
		(layer "F.Cu")
		(net "SMB_BIC_I2C9_SSD_MUX1_SDA")
	)
	(segment
		(start 360.791252 -97.377758)
		(end 360.791252 -89.941908)
		(width 0.13208)
		(layer "F.Cu")
		(net "SMB_BIC_I2C9_SSD_MUX1_SDA")
	)
	(via
		(at 359.895648 -98.273362)
		(size 0.508)
		(drill 0.254)
		(layers "F.Cu" "B.Cu")
		(net "SMB_BIC_I2C9_SSD_MUX1_SDA")
	)
	(via
		(at 140.11148 -99.243642)
		(size 0.508)
		(drill 0.254)
		(layers "F.Cu" "B.Cu")
		(net "SMB_BIC_I2C9_SSD_MUX1_SDA")
	)
	(segment
		(start 140.512038 -99.6442)
		(end 143.585946 -99.6442)
		(width 0.15494)
		(layer "In15.Cu")
		(net "SMB_BIC_I2C9_SSD_MUX1_SDA")
	)
	(segment
		(start 271.551146 -90.9066)
		(end 310.642254 -90.9066)
		(width 0.15494)
		(layer "In15.Cu")
		(net "SMB_BIC_I2C9_SSD_MUX1_SDA")
	)
	(segment
		(start 248.490232 -92.5068)
		(end 255.761998 -92.5068)
		(width 0.15494)
		(layer "In15.Cu")
		(net "SMB_BIC_I2C9_SSD_MUX1_SDA")
	)
	(segment
		(start 256.396998 -91.8718)
		(end 266.242546 -91.8718)
		(width 0.15494)
		(layer "In15.Cu")
		(net "SMB_BIC_I2C9_SSD_MUX1_SDA")
	)
	(segment
		(start 229.396036 -96.716342)
		(end 234.244642 -96.716342)
		(width 0.15494)
		(layer "In15.Cu")
		(net "SMB_BIC_I2C9_SSD_MUX1_SDA")
	)
	(segment
		(start 270.585946 -89.9414)
		(end 271.551146 -90.9066)
		(width 0.15494)
		(layer "In15.Cu")
		(net "SMB_BIC_I2C9_SSD_MUX1_SDA")
	)
	(segment
		(start 344.9574 -98.0948)
		(end 359.394252 -98.0948)
		(width 0.15494)
		(layer "In15.Cu")
		(net "SMB_BIC_I2C9_SSD_MUX1_SDA")
	)
	(segment
		(start 202.513946 -86.7918)
		(end 205.180946 -89.4588)
		(width 0.15494)
		(layer "In15.Cu")
		(net "SMB_BIC_I2C9_SSD_MUX1_SDA")
	)
	(segment
		(start 140.11148 -99.243642)
		(end 140.512038 -99.6442)
		(width 0.15494)
		(layer "In15.Cu")
		(net "SMB_BIC_I2C9_SSD_MUX1_SDA")
	)
	(segment
		(start 223.416114 -93.11132)
		(end 226.596194 -96.2914)
		(width 0.15494)
		(layer "In15.Cu")
		(net "SMB_BIC_I2C9_SSD_MUX1_SDA")
	)
	(segment
		(start 266.242546 -91.8718)
		(end 268.173708 -89.9414)
		(width 0.15494)
		(layer "In15.Cu")
		(net "SMB_BIC_I2C9_SSD_MUX1_SDA")
	)
	(segment
		(start 205.180946 -89.4588)
		(end 222.638366 -89.4588)
		(width 0.15494)
		(layer "In15.Cu")
		(net "SMB_BIC_I2C9_SSD_MUX1_SDA")
	)
	(segment
		(start 234.244642 -96.716342)
		(end 235.791248 -95.169736)
		(width 0.15494)
		(layer "In15.Cu")
		(net "SMB_BIC_I2C9_SSD_MUX1_SDA")
	)
	(segment
		(start 333.007208 -92.976954)
		(end 333.6417 -93.611446)
		(width 0.15494)
		(layer "In15.Cu")
		(net "SMB_BIC_I2C9_SSD_MUX1_SDA")
	)
	(segment
		(start 315.79058 -91.932506)
		(end 316.714886 -91.0082)
		(width 0.15494)
		(layer "In15.Cu")
		(net "SMB_BIC_I2C9_SSD_MUX1_SDA")
	)
	(segment
		(start 325.983346 -93.472)
		(end 331.635354 -93.472)
		(width 0.15494)
		(layer "In15.Cu")
		(net "SMB_BIC_I2C9_SSD_MUX1_SDA")
	)
	(segment
		(start 332.1304 -92.976954)
		(end 333.007208 -92.976954)
		(width 0.15494)
		(layer "In15.Cu")
		(net "SMB_BIC_I2C9_SSD_MUX1_SDA")
	)
	(segment
		(start 222.638366 -89.4588)
		(end 223.416114 -90.236548)
		(width 0.15494)
		(layer "In15.Cu")
		(net "SMB_BIC_I2C9_SSD_MUX1_SDA")
	)
	(segment
		(start 226.596194 -96.2914)
		(end 228.971094 -96.2914)
		(width 0.15494)
		(layer "In15.Cu")
		(net "SMB_BIC_I2C9_SSD_MUX1_SDA")
	)
	(segment
		(start 316.714886 -91.0082)
		(end 323.519546 -91.0082)
		(width 0.15494)
		(layer "In15.Cu")
		(net "SMB_BIC_I2C9_SSD_MUX1_SDA")
	)
	(segment
		(start 359.572814 -98.273362)
		(end 359.895648 -98.273362)
		(width 0.15494)
		(layer "In15.Cu")
		(net "SMB_BIC_I2C9_SSD_MUX1_SDA")
	)
	(segment
		(start 323.519546 -91.0082)
		(end 325.983346 -93.472)
		(width 0.15494)
		(layer "In15.Cu")
		(net "SMB_BIC_I2C9_SSD_MUX1_SDA")
	)
	(segment
		(start 195.0212 -86.7918)
		(end 202.513946 -86.7918)
		(width 0.15494)
		(layer "In15.Cu")
		(net "SMB_BIC_I2C9_SSD_MUX1_SDA")
	)
	(segment
		(start 228.971094 -96.2914)
		(end 229.396036 -96.716342)
		(width 0.15494)
		(layer "In15.Cu")
		(net "SMB_BIC_I2C9_SSD_MUX1_SDA")
	)
	(segment
		(start 237.0328 -95.169736)
		(end 237.290864 -95.4278)
		(width 0.15494)
		(layer "In15.Cu")
		(net "SMB_BIC_I2C9_SSD_MUX1_SDA")
	)
	(segment
		(start 268.173708 -89.9414)
		(end 270.585946 -89.9414)
		(width 0.15494)
		(layer "In15.Cu")
		(net "SMB_BIC_I2C9_SSD_MUX1_SDA")
	)
	(segment
		(start 255.761998 -92.5068)
		(end 256.396998 -91.8718)
		(width 0.15494)
		(layer "In15.Cu")
		(net "SMB_BIC_I2C9_SSD_MUX1_SDA")
	)
	(segment
		(start 333.6417 -93.789246)
		(end 335.889854 -96.0374)
		(width 0.15494)
		(layer "In15.Cu")
		(net "SMB_BIC_I2C9_SSD_MUX1_SDA")
	)
	(segment
		(start 155.447746 -87.7824)
		(end 194.0306 -87.7824)
		(width 0.15494)
		(layer "In15.Cu")
		(net "SMB_BIC_I2C9_SSD_MUX1_SDA")
	)
	(segment
		(start 143.585946 -99.6442)
		(end 155.447746 -87.7824)
		(width 0.15494)
		(layer "In15.Cu")
		(net "SMB_BIC_I2C9_SSD_MUX1_SDA")
	)
	(segment
		(start 237.290864 -95.4278)
		(end 245.569232 -95.4278)
		(width 0.15494)
		(layer "In15.Cu")
		(net "SMB_BIC_I2C9_SSD_MUX1_SDA")
	)
	(segment
		(start 194.0306 -87.7824)
		(end 195.0212 -86.7918)
		(width 0.15494)
		(layer "In15.Cu")
		(net "SMB_BIC_I2C9_SSD_MUX1_SDA")
	)
	(segment
		(start 311.66816 -91.932506)
		(end 315.79058 -91.932506)
		(width 0.15494)
		(layer "In15.Cu")
		(net "SMB_BIC_I2C9_SSD_MUX1_SDA")
	)
	(segment
		(start 310.642254 -90.9066)
		(end 311.66816 -91.932506)
		(width 0.15494)
		(layer "In15.Cu")
		(net "SMB_BIC_I2C9_SSD_MUX1_SDA")
	)
	(segment
		(start 359.394252 -98.0948)
		(end 359.572814 -98.273362)
		(width 0.15494)
		(layer "In15.Cu")
		(net "SMB_BIC_I2C9_SSD_MUX1_SDA")
	)
	(segment
		(start 342.9 -96.0374)
		(end 344.9574 -98.0948)
		(width 0.15494)
		(layer "In15.Cu")
		(net "SMB_BIC_I2C9_SSD_MUX1_SDA")
	)
	(segment
		(start 331.635354 -93.472)
		(end 332.1304 -92.976954)
		(width 0.15494)
		(layer "In15.Cu")
		(net "SMB_BIC_I2C9_SSD_MUX1_SDA")
	)
	(segment
		(start 335.889854 -96.0374)
		(end 342.9 -96.0374)
		(width 0.15494)
		(layer "In15.Cu")
		(net "SMB_BIC_I2C9_SSD_MUX1_SDA")
	)
	(segment
		(start 235.791248 -95.169736)
		(end 237.0328 -95.169736)
		(width 0.15494)
		(layer "In15.Cu")
		(net "SMB_BIC_I2C9_SSD_MUX1_SDA")
	)
	(segment
		(start 245.569232 -95.4278)
		(end 248.490232 -92.5068)
		(width 0.15494)
		(layer "In15.Cu")
		(net "SMB_BIC_I2C9_SSD_MUX1_SDA")
	)
	(segment
		(start 333.6417 -93.611446)
		(end 333.6417 -93.789246)
		(width 0.15494)
		(layer "In15.Cu")
		(net "SMB_BIC_I2C9_SSD_MUX1_SDA")
	)
	(segment
		(start 223.416114 -90.236548)
		(end 223.416114 -93.11132)
		(width 0.15494)
		(layer "In15.Cu")
		(net "SMB_BIC_I2C9_SSD_MUX1_SDA")
	)
	(segment
		(start 334.899 -232.920032)
		(end 335.332832 -232.4862)
		(width 0.13208)
		(layer "F.Cu")
		(net "SSD2_PWRDIS")
	)
	(segment
		(start 337.185 -229.616254)
		(end 337.185 -228.473)
		(width 0.13208)
		(layer "F.Cu")
		(net "SSD2_PWRDIS")
	)
	(segment
		(start 335.915 -230.886254)
		(end 337.185 -229.616254)
		(width 0.13208)
		(layer "F.Cu")
		(net "SSD2_PWRDIS")
	)
	(segment
		(start 335.915 -232.4862)
		(end 335.915 -230.886254)
		(width 0.13208)
		(layer "F.Cu")
		(net "SSD2_PWRDIS")
	)
	(segment
		(start 334.899 -233.66095)
		(end 334.899 -232.920032)
		(width 0.13208)
		(layer "F.Cu")
		(net "SSD2_PWRDIS")
	)
	(segment
		(start 335.332832 -232.4862)
		(end 335.915 -232.4862)
		(width 0.13208)
		(layer "F.Cu")
		(net "SSD2_PWRDIS")
	)
	(segment
		(start 337.185 -228.473)
		(end 337.293966 -228.364034)
		(width 0.13208)
		(layer "F.Cu")
		(net "SSD2_PWRDIS")
	)
	(segment
		(start 337.293966 -228.364034)
		(end 337.293966 -227.987098)
		(width 0.13208)
		(layer "F.Cu")
		(net "SSD2_PWRDIS")
	)
	(via
		(at 335.915 -232.4862)
		(size 0.762)
		(drill 0.381)
		(layers "F.Cu" "B.Cu")
		(net "SSD2_PWRDIS")
	)
	(segment
		(start 243.722906 -127.051308)
		(end 243.326158 -127.051308)
		(width 0.13208)
		(layer "F.Cu")
		(net "P3V3_NIC4_SS")
	)
	(segment
		(start 244.379496 -126.394718)
		(end 243.722906 -127.051308)
		(width 0.13208)
		(layer "F.Cu")
		(net "P3V3_NIC4_SS")
	)
	(segment
		(start 244.431058 -126.394718)
		(end 244.379496 -126.394718)
		(width 0.13208)
		(layer "F.Cu")
		(net "P3V3_NIC4_SS")
	)
	(segment
		(start 242.766342 -127.051308)
		(end 242.710462 -126.995428)
		(width 0.13208)
		(layer "F.Cu")
		(net "P3V3_NIC4_SS")
	)
	(segment
		(start 243.326158 -127.051308)
		(end 242.766342 -127.051308)
		(width 0.13208)
		(layer "F.Cu")
		(net "P3V3_NIC4_SS")
	)
	(via
		(at 243.326158 -127.051308)
		(size 0.508)
		(drill 0.254)
		(layers "F.Cu" "B.Cu")
		(net "P3V3_NIC4_SS")
	)
	(segment
		(start 138.399012 -207.342486)
		(end 145.160238 -207.342486)
		(width 0.13208)
		(layer "F.Cu")
		(net "UART_PEX1_CLI_BUF_TX")
	)
	(segment
		(start 145.160238 -207.342486)
		(end 145.28165 -207.463898)
		(width 0.13208)
		(layer "F.Cu")
		(net "UART_PEX1_CLI_BUF_TX")
	)
	(via
		(at 138.399012 -207.342486)
		(size 0.508)
		(drill 0.254)
		(layers "F.Cu" "B.Cu")
		(net "UART_PEX1_CLI_BUF_TX")
	)
	(segment
		(start 137.602214 -208.139284)
		(end 138.399012 -207.342486)
		(width 0.13208)
		(layer "B.Cu")
		(net "UART_PEX1_CLI_BUF_TX")
	)
	(segment
		(start 134.408164 -212.889846)
		(end 134.535164 -213.016846)
		(width 0.13208)
		(layer "B.Cu")
		(net "UART_PEX1_CLI_BUF_TX")
	)
	(segment
		(start 135.697214 -213.016846)
		(end 135.824214 -212.889846)
		(width 0.13208)
		(layer "B.Cu")
		(net "UART_PEX1_CLI_BUF_TX")
	)
	(segment
		(start 137.602214 -209.488278)
		(end 137.602214 -208.139284)
		(width 0.13208)
		(layer "B.Cu")
		(net "UART_PEX1_CLI_BUF_TX")
	)
	(segment
		(start 135.824214 -211.266278)
		(end 137.602214 -209.488278)
		(width 0.13208)
		(layer "B.Cu")
		(net "UART_PEX1_CLI_BUF_TX")
	)
	(segment
		(start 134.408164 -212.381846)
		(end 134.408164 -212.889846)
		(width 0.13208)
		(layer "B.Cu")
		(net "UART_PEX1_CLI_BUF_TX")
	)
	(segment
		(start 133.430264 -212.381846)
		(end 134.408164 -212.381846)
		(width 0.13208)
		(layer "B.Cu")
		(net "UART_PEX1_CLI_BUF_TX")
	)
	(segment
		(start 134.535164 -213.016846)
		(end 135.697214 -213.016846)
		(width 0.13208)
		(layer "B.Cu")
		(net "UART_PEX1_CLI_BUF_TX")
	)
	(segment
		(start 135.824214 -212.889846)
		(end 135.824214 -211.266278)
		(width 0.13208)
		(layer "B.Cu")
		(net "UART_PEX1_CLI_BUF_TX")
	)
	(segment
		(start 130.471164 -178.400456)
		(end 130.938016 -178.143154)
		(width 0.3048)
		(layer "F.Cu")
		(net "FM_DB2000QL_VSBEN")
	)
	(via
		(at 130.938016 -178.143154)
		(size 0.49022)
		(drill 0.254)
		(layers "F.Cu" "B.Cu")
		(net "FM_DB2000QL_VSBEN")
	)
	(via
		(at 129.706116 -178.766724)
		(size 0.508)
		(drill 0.254)
		(layers "F.Cu" "B.Cu")
		(net "FM_DB2000QL_VSBEN")
	)
	(segment
		(start 129.706116 -178.766724)
		(end 129.46507 -179.00777)
		(width 0.13208)
		(layer "B.Cu")
		(net "FM_DB2000QL_VSBEN")
	)
	(segment
		(start 130.938016 -178.143154)
		(end 130.329686 -178.143154)
		(width 0.13208)
		(layer "B.Cu")
		(net "FM_DB2000QL_VSBEN")
	)
	(segment
		(start 129.46507 -179.00777)
		(end 128.641094 -179.00777)
		(width 0.13208)
		(layer "B.Cu")
		(net "FM_DB2000QL_VSBEN")
	)
	(segment
		(start 128.641094 -180.02377)
		(end 128.641094 -179.00777)
		(width 0.13208)
		(layer "B.Cu")
		(net "FM_DB2000QL_VSBEN")
	)
	(segment
		(start 130.329686 -178.143154)
		(end 129.706116 -178.766724)
		(width 0.13208)
		(layer "B.Cu")
		(net "FM_DB2000QL_VSBEN")
	)
	(segment
		(start 341.52967 -88.907874)
		(end 341.473282 -88.964262)
		(width 0.13462)
		(layer "F.Cu")
		(net "CLK_100M_DB800ZL_SSD14_DN")
	)
	(segment
		(start 343.188798 -89.856056)
		(end 342.240616 -88.907874)
		(width 0.13462)
		(layer "F.Cu")
		(net "CLK_100M_DB800ZL_SSD14_DN")
	)
	(segment
		(start 341.473282 -88.964262)
		(end 341.045546 -88.964262)
		(width 0.13462)
		(layer "F.Cu")
		(net "CLK_100M_DB800ZL_SSD14_DN")
	)
	(segment
		(start 342.240616 -88.907874)
		(end 341.52967 -88.907874)
		(width 0.13462)
		(layer "F.Cu")
		(net "CLK_100M_DB800ZL_SSD14_DN")
	)
	(segment
		(start 344.212926 -90.169746)
		(end 343.899236 -89.856056)
		(width 0.13462)
		(layer "F.Cu")
		(net "CLK_100M_DB800ZL_SSD14_DN")
	)
	(segment
		(start 343.899236 -89.856056)
		(end 343.188798 -89.856056)
		(width 0.13462)
		(layer "F.Cu")
		(net "CLK_100M_DB800ZL_SSD14_DN")
	)
	(segment
		(start 260.233922 -308.450488)
		(end 260.660134 -308.450488)
		(width 0.13208)
		(layer "F.Cu")
		(net "PEX2_DBG_SEL0")
	)
	(segment
		(start 259.869686 -308.086252)
		(end 260.233922 -308.450488)
		(width 0.13208)
		(layer "F.Cu")
		(net "PEX2_DBG_SEL0")
	)
	(segment
		(start 285.199836 -309.199788)
		(end 284.724856 -308.724808)
		(width 0.13208)
		(layer "F.Cu")
		(net "PEX2_DBG_SEL0")
	)
	(segment
		(start 260.587998 -307.36794)
		(end 259.869686 -308.086252)
		(width 0.13208)
		(layer "F.Cu")
		(net "PEX2_DBG_SEL0")
	)
	(via
		(at 260.660134 -308.450488)
		(size 0.508)
		(drill 0.254)
		(layers "F.Cu" "B.Cu")
		(net "PEX2_DBG_SEL0")
	)
	(via
		(at 284.724856 -308.724808)
		(size 0.4064)
		(drill 0.2032)
		(layers "F.Cu" "B.Cu")
		(net "PEX2_DBG_SEL0")
	)
	(segment
		(start 280.652474 -308.166262)
		(end 284.16631 -308.166262)
		(width 0.13208)
		(layer "B.Cu")
		(net "PEX2_DBG_SEL0")
	)
	(segment
		(start 260.660134 -308.450488)
		(end 262.394192 -308.450488)
		(width 0.13208)
		(layer "B.Cu")
		(net "PEX2_DBG_SEL0")
	)
	(segment
		(start 280.161746 -307.265578)
		(end 280.415238 -307.51907)
		(width 0.13208)
		(layer "B.Cu")
		(net "PEX2_DBG_SEL0")
	)
	(segment
		(start 266.4714 -306.8574)
		(end 277.9776 -306.8574)
		(width 0.13208)
		(layer "B.Cu")
		(net "PEX2_DBG_SEL0")
	)
	(segment
		(start 262.69188 -308.1528)
		(end 265.176 -308.1528)
		(width 0.13208)
		(layer "B.Cu")
		(net "PEX2_DBG_SEL0")
	)
	(segment
		(start 278.385778 -307.265578)
		(end 280.161746 -307.265578)
		(width 0.13208)
		(layer "B.Cu")
		(net "PEX2_DBG_SEL0")
	)
	(segment
		(start 280.415238 -307.929026)
		(end 280.652474 -308.166262)
		(width 0.13208)
		(layer "B.Cu")
		(net "PEX2_DBG_SEL0")
	)
	(segment
		(start 280.415238 -307.51907)
		(end 280.415238 -307.929026)
		(width 0.13208)
		(layer "B.Cu")
		(net "PEX2_DBG_SEL0")
	)
	(segment
		(start 277.9776 -306.8574)
		(end 278.385778 -307.265578)
		(width 0.13208)
		(layer "B.Cu")
		(net "PEX2_DBG_SEL0")
	)
	(segment
		(start 262.394192 -308.450488)
		(end 262.69188 -308.1528)
		(width 0.13208)
		(layer "B.Cu")
		(net "PEX2_DBG_SEL0")
	)
	(segment
		(start 284.16631 -308.166262)
		(end 284.724856 -308.724808)
		(width 0.13208)
		(layer "B.Cu")
		(net "PEX2_DBG_SEL0")
	)
	(segment
		(start 265.176 -308.1528)
		(end 266.4714 -306.8574)
		(width 0.13208)
		(layer "B.Cu")
		(net "PEX2_DBG_SEL0")
	)
	(segment
		(start 220.751654 -220.385132)
		(end 220.893386 -220.2434)
		(width 0.13208)
		(layer "F.Cu")
		(net "SMB_BIC_I2C9_SSD_MUX_SDA")
	)
	(segment
		(start 220.893386 -220.2434)
		(end 223.128332 -220.2434)
		(width 0.13208)
		(layer "F.Cu")
		(net "SMB_BIC_I2C9_SSD_MUX_SDA")
	)
	(segment
		(start 223.128332 -220.2434)
		(end 223.467676 -219.904056)
		(width 0.13208)
		(layer "F.Cu")
		(net "SMB_BIC_I2C9_SSD_MUX_SDA")
	)
	(segment
		(start 218.601036 -220.385386)
		(end 219.225114 -220.385386)
		(width 0.13208)
		(layer "F.Cu")
		(net "SMB_BIC_I2C9_SSD_MUX_SDA")
	)
	(segment
		(start 219.225114 -220.385386)
		(end 219.225368 -220.385132)
		(width 0.13208)
		(layer "F.Cu")
		(net "SMB_BIC_I2C9_SSD_MUX_SDA")
	)
	(segment
		(start 217.635836 -221.350586)
		(end 218.601036 -220.385386)
		(width 0.13208)
		(layer "F.Cu")
		(net "SMB_BIC_I2C9_SSD_MUX_SDA")
	)
	(segment
		(start 219.225368 -220.385132)
		(end 220.751654 -220.385132)
		(width 0.13208)
		(layer "F.Cu")
		(net "SMB_BIC_I2C9_SSD_MUX_SDA")
	)
	(via
		(at 219.225114 -220.385386)
		(size 0.762)
		(drill 0.381)
		(layers "F.Cu" "B.Cu")
		(net "SMB_BIC_I2C9_SSD_MUX_SDA")
	)
	(via
		(at 104.394 -370.967)
		(size 0.508)
		(drill 0.254)
		(layers "F.Cu" "B.Cu")
		(net "RST_GPU_PERST_1_BUF_R_N")
	)
	(via
		(at 199.843898 -364.1852)
		(size 0.508)
		(drill 0.254)
		(layers "F.Cu" "B.Cu")
		(net "RST_GPU_PERST_1_BUF_R_N")
	)
	(via
		(at 302.877474 -220.62948)
		(size 0.508)
		(drill 0.254)
		(layers "F.Cu" "B.Cu")
		(net "RST_GPU_PERST_1_BUF_R_N")
	)
	(via
		(at 63.70066 -391.098786)
		(size 0.508)
		(drill 0.254)
		(layers "F.Cu" "B.Cu")
		(net "RST_GPU_PERST_1_BUF_R_N")
	)
	(via
		(at 274.04568 -217.6018)
		(size 0.508)
		(drill 0.254)
		(layers "F.Cu" "B.Cu")
		(net "RST_GPU_PERST_1_BUF_R_N")
	)
	(segment
		(start 63.70066 -392.254994)
		(end 62.936628 -393.019026)
		(width 0.13208)
		(layer "B.Cu")
		(net "RST_GPU_PERST_1_BUF_R_N")
	)
	(segment
		(start 51.746404 -413.53486)
		(end 50.421286 -414.859978)
		(width 0.13208)
		(layer "B.Cu")
		(net "RST_GPU_PERST_1_BUF_R_N")
	)
	(segment
		(start 38.389306 -413.769302)
		(end 36.710112 -412.090108)
		(width 0.13208)
		(layer "B.Cu")
		(net "RST_GPU_PERST_1_BUF_R_N")
	)
	(segment
		(start 198.843392 -364.1852)
		(end 199.843898 -364.1852)
		(width 0.13208)
		(layer "B.Cu")
		(net "RST_GPU_PERST_1_BUF_R_N")
	)
	(segment
		(start 104.394 -370.967)
		(end 104.53878 -370.82222)
		(width 0.13208)
		(layer "B.Cu")
		(net "RST_GPU_PERST_1_BUF_R_N")
	)
	(segment
		(start 104.53878 -370.82222)
		(end 108.406184 -370.82222)
		(width 0.13208)
		(layer "B.Cu")
		(net "RST_GPU_PERST_1_BUF_R_N")
	)
	(segment
		(start 62.936628 -393.019026)
		(end 52.487322 -393.019026)
		(width 0.13208)
		(layer "B.Cu")
		(net "RST_GPU_PERST_1_BUF_R_N")
	)
	(segment
		(start 63.70066 -391.098786)
		(end 63.70066 -392.254994)
		(width 0.13208)
		(layer "B.Cu")
		(net "RST_GPU_PERST_1_BUF_R_N")
	)
	(segment
		(start 50.421286 -414.859978)
		(end 46.29023 -414.859978)
		(width 0.13208)
		(layer "B.Cu")
		(net "RST_GPU_PERST_1_BUF_R_N")
	)
	(segment
		(start 46.29023 -414.859978)
		(end 45.199554 -413.769302)
		(width 0.13208)
		(layer "B.Cu")
		(net "RST_GPU_PERST_1_BUF_R_N")
	)
	(segment
		(start 51.746404 -393.759944)
		(end 51.746404 -413.53486)
		(width 0.13208)
		(layer "B.Cu")
		(net "RST_GPU_PERST_1_BUF_R_N")
	)
	(segment
		(start 116.12626 -363.102144)
		(end 197.760336 -363.102144)
		(width 0.13208)
		(layer "B.Cu")
		(net "RST_GPU_PERST_1_BUF_R_N")
	)
	(segment
		(start 302.877474 -221.294452)
		(end 302.877474 -220.62948)
		(width 0.13208)
		(layer "B.Cu")
		(net "RST_GPU_PERST_1_BUF_R_N")
	)
	(segment
		(start 52.487322 -393.019026)
		(end 51.746404 -393.759944)
		(width 0.13208)
		(layer "B.Cu")
		(net "RST_GPU_PERST_1_BUF_R_N")
	)
	(segment
		(start 197.760336 -363.102144)
		(end 198.843392 -364.1852)
		(width 0.13208)
		(layer "B.Cu")
		(net "RST_GPU_PERST_1_BUF_R_N")
	)
	(segment
		(start 45.199554 -413.769302)
		(end 38.389306 -413.769302)
		(width 0.13208)
		(layer "B.Cu")
		(net "RST_GPU_PERST_1_BUF_R_N")
	)
	(segment
		(start 108.406184 -370.82222)
		(end 116.12626 -363.102144)
		(width 0.13208)
		(layer "B.Cu")
		(net "RST_GPU_PERST_1_BUF_R_N")
	)
	(segment
		(start 245.379748 -322.2752)
		(end 252.359668 -305.424078)
		(width 0.15494)
		(layer "In5.Cu")
		(net "RST_GPU_PERST_1_BUF_R_N")
	)
	(segment
		(start 276.134576 -266.561062)
		(end 276.134576 -248.87936)
		(width 0.15494)
		(layer "In5.Cu")
		(net "RST_GPU_PERST_1_BUF_R_N")
	)
	(segment
		(start 276.134576 -248.87936)
		(end 274.04568 -246.790464)
		(width 0.15494)
		(layer "In5.Cu")
		(net "RST_GPU_PERST_1_BUF_R_N")
	)
	(segment
		(start 199.843898 -364.1852)
		(end 200.301098 -363.728)
		(width 0.15494)
		(layer "In5.Cu")
		(net "RST_GPU_PERST_1_BUF_R_N")
	)
	(segment
		(start 262.899398 -277.34895)
		(end 270.565372 -269.682976)
		(width 0.15494)
		(layer "In5.Cu")
		(net "RST_GPU_PERST_1_BUF_R_N")
	)
	(segment
		(start 274.04568 -246.790464)
		(end 274.04568 -217.6018)
		(width 0.15494)
		(layer "In5.Cu")
		(net "RST_GPU_PERST_1_BUF_R_N")
	)
	(segment
		(start 219.792296 -359.044748)
		(end 233.32948 -345.507564)
		(width 0.15494)
		(layer "In5.Cu")
		(net "RST_GPU_PERST_1_BUF_R_N")
	)
	(segment
		(start 258.481576 -277.34895)
		(end 262.899398 -277.34895)
		(width 0.15494)
		(layer "In5.Cu")
		(net "RST_GPU_PERST_1_BUF_R_N")
	)
	(segment
		(start 204.322172 -362.293916)
		(end 207.57134 -359.044748)
		(width 0.15494)
		(layer "In5.Cu")
		(net "RST_GPU_PERST_1_BUF_R_N")
	)
	(segment
		(start 202.29957 -364.391956)
		(end 203.4794 -364.391956)
		(width 0.15494)
		(layer "In5.Cu")
		(net "RST_GPU_PERST_1_BUF_R_N")
	)
	(segment
		(start 203.6064 -364.264956)
		(end 203.6064 -363.509052)
		(width 0.15494)
		(layer "In5.Cu")
		(net "RST_GPU_PERST_1_BUF_R_N")
	)
	(segment
		(start 204.16774 -362.947458)
		(end 204.322172 -362.793026)
		(width 0.15494)
		(layer "In5.Cu")
		(net "RST_GPU_PERST_1_BUF_R_N")
	)
	(segment
		(start 201.635614 -363.728)
		(end 202.29957 -364.391956)
		(width 0.15494)
		(layer "In5.Cu")
		(net "RST_GPU_PERST_1_BUF_R_N")
	)
	(segment
		(start 233.32948 -345.507564)
		(end 233.32948 -334.325468)
		(width 0.15494)
		(layer "In5.Cu")
		(net "RST_GPU_PERST_1_BUF_R_N")
	)
	(segment
		(start 200.301098 -363.728)
		(end 201.635614 -363.728)
		(width 0.15494)
		(layer "In5.Cu")
		(net "RST_GPU_PERST_1_BUF_R_N")
	)
	(segment
		(start 252.359668 -305.424078)
		(end 254.545592 -303.238154)
		(width 0.15494)
		(layer "In5.Cu")
		(net "RST_GPU_PERST_1_BUF_R_N")
	)
	(segment
		(start 203.4794 -364.391956)
		(end 203.6064 -364.264956)
		(width 0.15494)
		(layer "In5.Cu")
		(net "RST_GPU_PERST_1_BUF_R_N")
	)
	(segment
		(start 254.545592 -303.238154)
		(end 256.623566 -298.221146)
		(width 0.15494)
		(layer "In5.Cu")
		(net "RST_GPU_PERST_1_BUF_R_N")
	)
	(segment
		(start 207.57134 -359.044748)
		(end 219.792296 -359.044748)
		(width 0.15494)
		(layer "In5.Cu")
		(net "RST_GPU_PERST_1_BUF_R_N")
	)
	(segment
		(start 273.012662 -269.682976)
		(end 276.134576 -266.561062)
		(width 0.15494)
		(layer "In5.Cu")
		(net "RST_GPU_PERST_1_BUF_R_N")
	)
	(segment
		(start 233.32948 -334.325468)
		(end 245.379748 -322.2752)
		(width 0.15494)
		(layer "In5.Cu")
		(net "RST_GPU_PERST_1_BUF_R_N")
	)
	(segment
		(start 204.16774 -362.947712)
		(end 204.16774 -362.947458)
		(width 0.15494)
		(layer "In5.Cu")
		(net "RST_GPU_PERST_1_BUF_R_N")
	)
	(segment
		(start 270.565372 -269.682976)
		(end 273.012662 -269.682976)
		(width 0.15494)
		(layer "In5.Cu")
		(net "RST_GPU_PERST_1_BUF_R_N")
	)
	(segment
		(start 204.322172 -362.793026)
		(end 204.322172 -362.293916)
		(width 0.15494)
		(layer "In5.Cu")
		(net "RST_GPU_PERST_1_BUF_R_N")
	)
	(segment
		(start 256.623566 -298.221146)
		(end 256.623566 -279.20696)
		(width 0.15494)
		(layer "In5.Cu")
		(net "RST_GPU_PERST_1_BUF_R_N")
	)
	(segment
		(start 203.6064 -363.509052)
		(end 204.16774 -362.947712)
		(width 0.15494)
		(layer "In5.Cu")
		(net "RST_GPU_PERST_1_BUF_R_N")
	)
	(segment
		(start 256.623566 -279.20696)
		(end 258.481576 -277.34895)
		(width 0.15494)
		(layer "In5.Cu")
		(net "RST_GPU_PERST_1_BUF_R_N")
	)
	(segment
		(start 296.040302 -220.02877)
		(end 302.276764 -220.02877)
		(width 0.15494)
		(layer "In13.Cu")
		(net "RST_GPU_PERST_1_BUF_R_N")
	)
	(segment
		(start 294.862758 -218.851226)
		(end 296.040302 -220.02877)
		(width 0.15494)
		(layer "In13.Cu")
		(net "RST_GPU_PERST_1_BUF_R_N")
	)
	(segment
		(start 274.04568 -217.6018)
		(end 275.295106 -218.851226)
		(width 0.15494)
		(layer "In13.Cu")
		(net "RST_GPU_PERST_1_BUF_R_N")
	)
	(segment
		(start 275.295106 -218.851226)
		(end 294.862758 -218.851226)
		(width 0.15494)
		(layer "In13.Cu")
		(net "RST_GPU_PERST_1_BUF_R_N")
	)
	(segment
		(start 302.276764 -220.02877)
		(end 302.877474 -220.62948)
		(width 0.15494)
		(layer "In13.Cu")
		(net "RST_GPU_PERST_1_BUF_R_N")
	)
	(segment
		(start 104.394 -370.967)
		(end 97.66046 -377.70054)
		(width 0.15494)
		(layer "In15.Cu")
		(net "RST_GPU_PERST_1_BUF_R_N")
	)
	(segment
		(start 97.66046 -377.70054)
		(end 97.66046 -384.736594)
		(width 0.15494)
		(layer "In15.Cu")
		(net "RST_GPU_PERST_1_BUF_R_N")
	)
	(segment
		(start 91.298268 -391.098786)
		(end 63.70066 -391.098786)
		(width 0.15494)
		(layer "In15.Cu")
		(net "RST_GPU_PERST_1_BUF_R_N")
	)
	(segment
		(start 97.66046 -384.736594)
		(end 91.298268 -391.098786)
		(width 0.15494)
		(layer "In15.Cu")
		(net "RST_GPU_PERST_1_BUF_R_N")
	)
	(segment
		(start 349.18777 -229.172516)
		(end 351.028 -231.012746)
		(width 0.13208)
		(layer "F.Cu")
		(net "SSD7_PWR_EN")
	)
	(segment
		(start 349.18777 -228.442774)
		(end 349.18777 -229.172516)
		(width 0.13208)
		(layer "F.Cu")
		(net "SSD7_PWR_EN")
	)
	(segment
		(start 349.293942 -228.336602)
		(end 349.18777 -228.442774)
		(width 0.13208)
		(layer "F.Cu")
		(net "SSD7_PWR_EN")
	)
	(segment
		(start 351.028 -231.521)
		(end 351.028 -232.918)
		(width 0.13208)
		(layer "F.Cu")
		(net "SSD7_PWR_EN")
	)
	(segment
		(start 349.293942 -227.987098)
		(end 349.293942 -228.336602)
		(width 0.13208)
		(layer "F.Cu")
		(net "SSD7_PWR_EN")
	)
	(segment
		(start 351.155 -233.045)
		(end 351.155 -233.66095)
		(width 0.13208)
		(layer "F.Cu")
		(net "SSD7_PWR_EN")
	)
	(segment
		(start 351.028 -231.012746)
		(end 351.028 -231.521)
		(width 0.13208)
		(layer "F.Cu")
		(net "SSD7_PWR_EN")
	)
	(segment
		(start 351.028 -232.918)
		(end 351.155 -233.045)
		(width 0.13208)
		(layer "F.Cu")
		(net "SSD7_PWR_EN")
	)
	(via
		(at 351.028 -231.521)
		(size 0.762)
		(drill 0.381)
		(layers "F.Cu" "B.Cu")
		(net "SSD7_PWR_EN")
	)
	(segment
		(start 342.52535 -85.833712)
		(end 341.541354 -85.833712)
		(width 0.13462)
		(layer "F.Cu")
		(net "CLK_100M_DB800ZL_SSD12_DP")
	)
	(segment
		(start 341.541354 -85.833712)
		(end 341.472012 -85.76437)
		(width 0.13462)
		(layer "F.Cu")
		(net "CLK_100M_DB800ZL_SSD12_DP")
	)
	(segment
		(start 344.212926 -85.255354)
		(end 343.886536 -85.581744)
		(width 0.13462)
		(layer "F.Cu")
		(net "CLK_100M_DB800ZL_SSD12_DP")
	)
	(segment
		(start 343.886536 -85.581744)
		(end 343.13368 -85.581744)
		(width 0.13462)
		(layer "F.Cu")
		(net "CLK_100M_DB800ZL_SSD12_DP")
	)
	(segment
		(start 341.472012 -85.76437)
		(end 341.045546 -85.76437)
		(width 0.13462)
		(layer "F.Cu")
		(net "CLK_100M_DB800ZL_SSD12_DP")
	)
	(segment
		(start 343.13368 -85.581744)
		(end 342.52535 -85.833712)
		(width 0.13462)
		(layer "F.Cu")
		(net "CLK_100M_DB800ZL_SSD12_DP")
	)
	(segment
		(start 296.599864 -282.599892)
		(end 297.074844 -283.074872)
		(width 0.13208)
		(layer "F.Cu")
		(net "PEX2_DBG_MODE2")
	)
	(segment
		(start 265.686286 -251.158502)
		(end 265.686286 -250.470924)
		(width 0.13208)
		(layer "F.Cu")
		(net "PEX2_DBG_MODE2")
	)
	(segment
		(start 265.686286 -251.956824)
		(end 265.686286 -251.158502)
		(width 0.13208)
		(layer "F.Cu")
		(net "PEX2_DBG_MODE2")
	)
	(via
		(at 265.686286 -251.158502)
		(size 0.508)
		(drill 0.254)
		(layers "F.Cu" "B.Cu")
		(net "PEX2_DBG_MODE2")
	)
	(via
		(at 297.074844 -283.074872)
		(size 0.4064)
		(drill 0.2032)
		(layers "F.Cu" "B.Cu")
		(net "PEX2_DBG_MODE2")
	)
	(via
		(at 293.31158 -267.544296)
		(size 0.6604)
		(drill 0.3302)
		(layers "F.Cu" "B.Cu")
		(net "PEX2_DBG_MODE2")
	)
	(segment
		(start 268.50975 -255.47193)
		(end 281.239214 -255.47193)
		(width 0.13208)
		(layer "B.Cu")
		(net "PEX2_DBG_MODE2")
	)
	(segment
		(start 298.037758 -271.977358)
		(end 298.037758 -282.111958)
		(width 0.13208)
		(layer "B.Cu")
		(net "PEX2_DBG_MODE2")
	)
	(segment
		(start 265.213846 -253.732284)
		(end 266.401042 -254.91948)
		(width 0.13208)
		(layer "B.Cu")
		(net "PEX2_DBG_MODE2")
	)
	(segment
		(start 281.239214 -255.47193)
		(end 293.31158 -267.544296)
		(width 0.13208)
		(layer "B.Cu")
		(net "PEX2_DBG_MODE2")
	)
	(segment
		(start 267.9573 -254.91948)
		(end 268.50975 -255.47193)
		(width 0.13208)
		(layer "B.Cu")
		(net "PEX2_DBG_MODE2")
	)
	(segment
		(start 265.213846 -251.630942)
		(end 265.213846 -253.732284)
		(width 0.13208)
		(layer "B.Cu")
		(net "PEX2_DBG_MODE2")
	)
	(segment
		(start 265.686286 -251.158502)
		(end 265.213846 -251.630942)
		(width 0.13208)
		(layer "B.Cu")
		(net "PEX2_DBG_MODE2")
	)
	(segment
		(start 293.604696 -267.544296)
		(end 298.037758 -271.977358)
		(width 0.13208)
		(layer "B.Cu")
		(net "PEX2_DBG_MODE2")
	)
	(segment
		(start 293.31158 -267.544296)
		(end 293.604696 -267.544296)
		(width 0.13208)
		(layer "B.Cu")
		(net "PEX2_DBG_MODE2")
	)
	(segment
		(start 266.401042 -254.91948)
		(end 267.9573 -254.91948)
		(width 0.13208)
		(layer "B.Cu")
		(net "PEX2_DBG_MODE2")
	)
	(segment
		(start 298.037758 -282.111958)
		(end 297.074844 -283.074872)
		(width 0.13208)
		(layer "B.Cu")
		(net "PEX2_DBG_MODE2")
	)
	(segment
		(start 217.800174 -221.969584)
		(end 217.635836 -222.366586)
		(width 0.13208)
		(layer "F.Cu")
		(net "SMB_BIC_I2C9_SSD_MUX_SCL")
	)
	(segment
		(start 220.731334 -220.8276)
		(end 223.344232 -220.8276)
		(width 0.13208)
		(layer "F.Cu")
		(net "SMB_BIC_I2C9_SSD_MUX_SCL")
	)
	(segment
		(start 220.503242 -221.055692)
		(end 220.731334 -220.8276)
		(width 0.13208)
		(layer "F.Cu")
		(net "SMB_BIC_I2C9_SSD_MUX_SCL")
	)
	(segment
		(start 218.714066 -221.055692)
		(end 217.800174 -221.969584)
		(width 0.13208)
		(layer "F.Cu")
		(net "SMB_BIC_I2C9_SSD_MUX_SCL")
	)
	(segment
		(start 223.344232 -220.8276)
		(end 223.467676 -220.704156)
		(width 0.13208)
		(layer "F.Cu")
		(net "SMB_BIC_I2C9_SSD_MUX_SCL")
	)
	(segment
		(start 220.503242 -221.055692)
		(end 218.714066 -221.055692)
		(width 0.13208)
		(layer "F.Cu")
		(net "SMB_BIC_I2C9_SSD_MUX_SCL")
	)
	(via
		(at 220.503242 -221.055692)
		(size 0.762)
		(drill 0.381)
		(layers "F.Cu" "B.Cu")
		(net "SMB_BIC_I2C9_SSD_MUX_SCL")
	)
	(segment
		(start 338.582 -228.6)
		(end 338.582 -229.263702)
		(width 0.13208)
		(layer "F.Cu")
		(net "FPGA_HEARTBEAT_N")
	)
	(segment
		(start 323.409056 -227.494084)
		(end 323.663056 -227.748084)
		(width 0.13208)
		(layer "F.Cu")
		(net "FPGA_HEARTBEAT_N")
	)
	(segment
		(start 338.490052 -227.583238)
		(end 338.490052 -228.508052)
		(width 0.13208)
		(layer "F.Cu")
		(net "FPGA_HEARTBEAT_N")
	)
	(segment
		(start 338.490052 -228.508052)
		(end 338.582 -228.6)
		(width 0.13208)
		(layer "F.Cu")
		(net "FPGA_HEARTBEAT_N")
	)
	(segment
		(start 338.093812 -227.186998)
		(end 338.490052 -227.583238)
		(width 0.13208)
		(layer "F.Cu")
		(net "FPGA_HEARTBEAT_N")
	)
	(segment
		(start 323.663056 -227.748084)
		(end 323.663056 -228.242114)
		(width 0.13208)
		(layer "F.Cu")
		(net "FPGA_HEARTBEAT_N")
	)
	(segment
		(start 338.582 -229.263702)
		(end 338.088224 -229.757478)
		(width 0.13208)
		(layer "F.Cu")
		(net "FPGA_HEARTBEAT_N")
	)
	(via
		(at 338.088224 -229.757478)
		(size 0.508)
		(drill 0.254)
		(layers "F.Cu" "B.Cu")
		(net "FPGA_HEARTBEAT_N")
	)
	(via
		(at 323.663056 -228.242114)
		(size 0.508)
		(drill 0.254)
		(layers "F.Cu" "B.Cu")
		(net "FPGA_HEARTBEAT_N")
	)
	(segment
		(start 336.749898 -228.34727)
		(end 338.088224 -229.685596)
		(width 0.15494)
		(layer "In9.Cu")
		(net "FPGA_HEARTBEAT_N")
	)
	(segment
		(start 330.11872 -229.530148)
		(end 330.409804 -229.821232)
		(width 0.15494)
		(layer "In9.Cu")
		(net "FPGA_HEARTBEAT_N")
	)
	(segment
		(start 332.81493 -229.046532)
		(end 333.980536 -229.046532)
		(width 0.15494)
		(layer "In9.Cu")
		(net "FPGA_HEARTBEAT_N")
	)
	(segment
		(start 324.95109 -229.530148)
		(end 330.11872 -229.530148)
		(width 0.15494)
		(layer "In9.Cu")
		(net "FPGA_HEARTBEAT_N")
	)
	(segment
		(start 330.409804 -229.821232)
		(end 332.04023 -229.821232)
		(width 0.15494)
		(layer "In9.Cu")
		(net "FPGA_HEARTBEAT_N")
	)
	(segment
		(start 338.088224 -229.685596)
		(end 338.088224 -229.757478)
		(width 0.15494)
		(layer "In9.Cu")
		(net "FPGA_HEARTBEAT_N")
	)
	(segment
		(start 334.679798 -228.34727)
		(end 336.749898 -228.34727)
		(width 0.15494)
		(layer "In9.Cu")
		(net "FPGA_HEARTBEAT_N")
	)
	(segment
		(start 323.663056 -228.242114)
		(end 324.95109 -229.530148)
		(width 0.15494)
		(layer "In9.Cu")
		(net "FPGA_HEARTBEAT_N")
	)
	(segment
		(start 333.980536 -229.046532)
		(end 334.679798 -228.34727)
		(width 0.15494)
		(layer "In9.Cu")
		(net "FPGA_HEARTBEAT_N")
	)
	(segment
		(start 332.04023 -229.821232)
		(end 332.81493 -229.046532)
		(width 0.15494)
		(layer "In9.Cu")
		(net "FPGA_HEARTBEAT_N")
	)
	(segment
		(start 446.875662 -121.509028)
		(end 446.536572 -121.509028)
		(width 0.13208)
		(layer "F.Cu")
		(net "P3V3_NIC7_OCP")
	)
	(segment
		(start 446.536572 -121.509028)
		(end 446.266316 -121.238772)
		(width 0.13208)
		(layer "F.Cu")
		(net "P3V3_NIC7_OCP")
	)
	(segment
		(start 446.069466 -121.041922)
		(end 446.266316 -121.238772)
		(width 0.13208)
		(layer "F.Cu")
		(net "P3V3_NIC7_OCP")
	)
	(segment
		(start 445.0715 -121.041922)
		(end 446.069466 -121.041922)
		(width 0.13208)
		(layer "F.Cu")
		(net "P3V3_NIC7_OCP")
	)
	(via
		(at 446.266316 -121.238772)
		(size 0.508)
		(drill 0.254)
		(layers "F.Cu" "B.Cu")
		(net "P3V3_NIC7_OCP")
	)
	(segment
		(start 336.226404 -82.632804)
		(end 336.226404 -83.317588)
		(width 0.13462)
		(layer "F.Cu")
		(net "CLK_100M_DB800ZL_SSD8_DN")
	)
	(segment
		(start 335.426558 -81.832958)
		(end 336.226404 -82.632804)
		(width 0.13462)
		(layer "F.Cu")
		(net "CLK_100M_DB800ZL_SSD8_DN")
	)
	(segment
		(start 336.295492 -83.386676)
		(end 336.295492 -83.814412)
		(width 0.13462)
		(layer "F.Cu")
		(net "CLK_100M_DB800ZL_SSD8_DN")
	)
	(segment
		(start 335.426558 -81.334102)
		(end 335.426558 -81.832958)
		(width 0.13462)
		(layer "F.Cu")
		(net "CLK_100M_DB800ZL_SSD8_DN")
	)
	(segment
		(start 336.226404 -83.317588)
		(end 336.295492 -83.386676)
		(width 0.13462)
		(layer "F.Cu")
		(net "CLK_100M_DB800ZL_SSD8_DN")
	)
	(segment
		(start 335.752948 -81.007712)
		(end 335.426558 -81.334102)
		(width 0.13462)
		(layer "F.Cu")
		(net "CLK_100M_DB800ZL_SSD8_DN")
	)
	(via
		(at 112.052862 -335.270094)
		(size 0.6604)
		(drill 0.3302)
		(layers "F.Cu" "B.Cu")
		(net "PU_9ZXL0451E_HBW")
	)
	(segment
		(start 109.340396 -334.570832)
		(end 109.85119 -335.081626)
		(width 0.13208)
		(layer "B.Cu")
		(net "PU_9ZXL0451E_HBW")
	)
	(segment
		(start 108.191554 -334.570832)
		(end 109.340396 -334.570832)
		(width 0.13208)
		(layer "B.Cu")
		(net "PU_9ZXL0451E_HBW")
	)
	(segment
		(start 108.064554 -333.925418)
		(end 108.064554 -334.443832)
		(width 0.13208)
		(layer "B.Cu")
		(net "PU_9ZXL0451E_HBW")
	)
	(segment
		(start 110.86719 -335.081626)
		(end 111.25962 -335.081626)
		(width 0.13208)
		(layer "B.Cu")
		(net "PU_9ZXL0451E_HBW")
	)
	(segment
		(start 111.448088 -335.270094)
		(end 112.052862 -335.270094)
		(width 0.13208)
		(layer "B.Cu")
		(net "PU_9ZXL0451E_HBW")
	)
	(segment
		(start 108.064554 -334.443832)
		(end 108.191554 -334.570832)
		(width 0.13208)
		(layer "B.Cu")
		(net "PU_9ZXL0451E_HBW")
	)
	(segment
		(start 109.85119 -335.081626)
		(end 110.86719 -335.081626)
		(width 0.13208)
		(layer "B.Cu")
		(net "PU_9ZXL0451E_HBW")
	)
	(segment
		(start 111.25962 -335.081626)
		(end 111.448088 -335.270094)
		(width 0.13208)
		(layer "B.Cu")
		(net "PU_9ZXL0451E_HBW")
	)
	(segment
		(start 298.499784 -282.599892)
		(end 298.974764 -283.074872)
		(width 0.13208)
		(layer "F.Cu")
		(net "PEX2_MODE_SEL12")
	)
	(segment
		(start 267.718286 -251.956824)
		(end 267.718286 -251.158502)
		(width 0.13208)
		(layer "F.Cu")
		(net "PEX2_MODE_SEL12")
	)
	(segment
		(start 267.718286 -251.158502)
		(end 267.718286 -250.470924)
		(width 0.13208)
		(layer "F.Cu")
		(net "PEX2_MODE_SEL12")
	)
	(via
		(at 298.974764 -283.074872)
		(size 0.4064)
		(drill 0.2032)
		(layers "F.Cu" "B.Cu")
		(net "PEX2_MODE_SEL12")
	)
	(via
		(at 267.718286 -251.158502)
		(size 0.508)
		(drill 0.254)
		(layers "F.Cu" "B.Cu")
		(net "PEX2_MODE_SEL12")
	)
	(via
		(at 295.741852 -268.169898)
		(size 0.6604)
		(drill 0.3302)
		(layers "F.Cu" "B.Cu")
		(net "PEX2_MODE_SEL12")
	)
	(segment
		(start 267.245846 -251.630942)
		(end 267.245846 -253.652274)
		(width 0.13208)
		(layer "B.Cu")
		(net "PEX2_MODE_SEL12")
	)
	(segment
		(start 267.245846 -253.652274)
		(end 267.571728 -253.978156)
		(width 0.13208)
		(layer "B.Cu")
		(net "PEX2_MODE_SEL12")
	)
	(segment
		(start 298.974764 -282.79344)
		(end 298.974764 -283.074872)
		(width 0.13208)
		(layer "B.Cu")
		(net "PEX2_MODE_SEL12")
	)
	(segment
		(start 268.108176 -253.978156)
		(end 269.03299 -254.90297)
		(width 0.13208)
		(layer "B.Cu")
		(net "PEX2_MODE_SEL12")
	)
	(segment
		(start 267.718286 -251.158502)
		(end 267.245846 -251.630942)
		(width 0.13208)
		(layer "B.Cu")
		(net "PEX2_MODE_SEL12")
	)
	(segment
		(start 282.474924 -254.90297)
		(end 295.741852 -268.169898)
		(width 0.13208)
		(layer "B.Cu")
		(net "PEX2_MODE_SEL12")
	)
	(segment
		(start 299.892466 -281.875738)
		(end 298.974764 -282.79344)
		(width 0.13208)
		(layer "B.Cu")
		(net "PEX2_MODE_SEL12")
	)
	(segment
		(start 295.741852 -268.169898)
		(end 296.02684 -268.169898)
		(width 0.13208)
		(layer "B.Cu")
		(net "PEX2_MODE_SEL12")
	)
	(segment
		(start 269.03299 -254.90297)
		(end 282.474924 -254.90297)
		(width 0.13208)
		(layer "B.Cu")
		(net "PEX2_MODE_SEL12")
	)
	(segment
		(start 267.571728 -253.978156)
		(end 268.108176 -253.978156)
		(width 0.13208)
		(layer "B.Cu")
		(net "PEX2_MODE_SEL12")
	)
	(segment
		(start 299.892466 -272.035524)
		(end 299.892466 -281.875738)
		(width 0.13208)
		(layer "B.Cu")
		(net "PEX2_MODE_SEL12")
	)
	(segment
		(start 296.02684 -268.169898)
		(end 299.892466 -272.035524)
		(width 0.13208)
		(layer "B.Cu")
		(net "PEX2_MODE_SEL12")
	)
	(segment
		(start 137.593324 -98.100642)
		(end 138.585194 -98.100642)
		(width 0.13208)
		(layer "F.Cu")
		(net "SMB_BIC_I2C9_SSD_MUX_R_SCL")
	)
	(segment
		(start 215.692736 -221.858586)
		(end 213.143846 -221.858586)
		(width 0.13208)
		(layer "F.Cu")
		(net "SMB_BIC_I2C9_SSD_MUX_R_SCL")
	)
	(segment
		(start 216.200736 -222.366586)
		(end 215.692736 -221.858586)
		(width 0.13208)
		(layer "F.Cu")
		(net "SMB_BIC_I2C9_SSD_MUX_R_SCL")
	)
	(segment
		(start 213.143846 -221.858586)
		(end 213.00313 -221.999302)
		(width 0.13208)
		(layer "F.Cu")
		(net "SMB_BIC_I2C9_SSD_MUX_R_SCL")
	)
	(segment
		(start 213.00313 -221.999302)
		(end 212.422994 -221.999302)
		(width 0.13208)
		(layer "F.Cu")
		(net "SMB_BIC_I2C9_SSD_MUX_R_SCL")
	)
	(segment
		(start 136.845294 -98.100642)
		(end 137.593324 -98.100642)
		(width 0.13208)
		(layer "F.Cu")
		(net "SMB_BIC_I2C9_SSD_MUX_R_SCL")
	)
	(segment
		(start 216.200736 -222.366586)
		(end 216.835736 -222.366586)
		(width 0.13208)
		(layer "F.Cu")
		(net "SMB_BIC_I2C9_SSD_MUX_R_SCL")
	)
	(via
		(at 217.441526 -90.532204)
		(size 0.508)
		(drill 0.254)
		(layers "F.Cu" "B.Cu")
		(net "SMB_BIC_I2C9_SSD_MUX_R_SCL")
	)
	(via
		(at 137.593324 -98.100642)
		(size 0.508)
		(drill 0.254)
		(layers "F.Cu" "B.Cu")
		(net "SMB_BIC_I2C9_SSD_MUX_R_SCL")
	)
	(via
		(at 216.200736 -222.366586)
		(size 0.508)
		(drill 0.254)
		(layers "F.Cu" "B.Cu")
		(net "SMB_BIC_I2C9_SSD_MUX_R_SCL")
	)
	(segment
		(start 225.7298 -187.706)
		(end 225.7298 -191.262)
		(width 0.15494)
		(layer "In7.Cu")
		(net "SMB_BIC_I2C9_SSD_MUX_R_SCL")
	)
	(segment
		(start 220.726 -219.468954)
		(end 217.828368 -222.366586)
		(width 0.15494)
		(layer "In7.Cu")
		(net "SMB_BIC_I2C9_SSD_MUX_R_SCL")
	)
	(segment
		(start 222.710756 -170.057826)
		(end 223.148652 -170.495722)
		(width 0.15494)
		(layer "In7.Cu")
		(net "SMB_BIC_I2C9_SSD_MUX_R_SCL")
	)
	(segment
		(start 223.235012 -202.096624)
		(end 223.249236 -202.096624)
		(width 0.15494)
		(layer "In7.Cu")
		(net "SMB_BIC_I2C9_SSD_MUX_R_SCL")
	)
	(segment
		(start 221.714314 -181.04104)
		(end 221.215458 -181.539896)
		(width 0.15494)
		(layer "In7.Cu")
		(net "SMB_BIC_I2C9_SSD_MUX_R_SCL")
	)
	(segment
		(start 221.215458 -182.815992)
		(end 221.777306 -183.37784)
		(width 0.15494)
		(layer "In7.Cu")
		(net "SMB_BIC_I2C9_SSD_MUX_R_SCL")
	)
	(segment
		(start 216.281 -131.953254)
		(end 216.281 -152.665176)
		(width 0.15494)
		(layer "In7.Cu")
		(net "SMB_BIC_I2C9_SSD_MUX_R_SCL")
	)
	(segment
		(start 217.441526 -90.532204)
		(end 217.679016 -90.769694)
		(width 0.15494)
		(layer "In7.Cu")
		(net "SMB_BIC_I2C9_SSD_MUX_R_SCL")
	)
	(segment
		(start 217.679016 -90.769694)
		(end 217.679016 -91.73591)
		(width 0.15494)
		(layer "In7.Cu")
		(net "SMB_BIC_I2C9_SSD_MUX_R_SCL")
	)
	(segment
		(start 222.81769 -201.089006)
		(end 222.81769 -201.679302)
		(width 0.15494)
		(layer "In7.Cu")
		(net "SMB_BIC_I2C9_SSD_MUX_R_SCL")
	)
	(segment
		(start 217.828368 -222.366586)
		(end 216.200736 -222.366586)
		(width 0.15494)
		(layer "In7.Cu")
		(net "SMB_BIC_I2C9_SSD_MUX_R_SCL")
	)
	(segment
		(start 216.281 -152.665176)
		(end 221.0562 -157.440376)
		(width 0.15494)
		(layer "In7.Cu")
		(net "SMB_BIC_I2C9_SSD_MUX_R_SCL")
	)
	(segment
		(start 223.361758 -202.209146)
		(end 223.361758 -202.920854)
		(width 0.15494)
		(layer "In7.Cu")
		(net "SMB_BIC_I2C9_SSD_MUX_R_SCL")
	)
	(segment
		(start 221.0562 -165.640258)
		(end 222.710756 -167.294814)
		(width 0.15494)
		(layer "In7.Cu")
		(net "SMB_BIC_I2C9_SSD_MUX_R_SCL")
	)
	(segment
		(start 223.148652 -170.495722)
		(end 223.148652 -177.660554)
		(width 0.15494)
		(layer "In7.Cu")
		(net "SMB_BIC_I2C9_SSD_MUX_R_SCL")
	)
	(segment
		(start 214.884 -120.4976)
		(end 214.4776 -120.904)
		(width 0.15494)
		(layer "In7.Cu")
		(net "SMB_BIC_I2C9_SSD_MUX_R_SCL")
	)
	(segment
		(start 221.215458 -181.539896)
		(end 221.215458 -182.815992)
		(width 0.15494)
		(layer "In7.Cu")
		(net "SMB_BIC_I2C9_SSD_MUX_R_SCL")
	)
	(segment
		(start 221.777306 -183.37784)
		(end 221.777306 -185.150506)
		(width 0.15494)
		(layer "In7.Cu")
		(net "SMB_BIC_I2C9_SSD_MUX_R_SCL")
	)
	(segment
		(start 222.81769 -201.679302)
		(end 223.235012 -202.096624)
		(width 0.15494)
		(layer "In7.Cu")
		(net "SMB_BIC_I2C9_SSD_MUX_R_SCL")
	)
	(segment
		(start 223.249236 -202.096624)
		(end 223.361758 -202.209146)
		(width 0.15494)
		(layer "In7.Cu")
		(net "SMB_BIC_I2C9_SSD_MUX_R_SCL")
	)
	(segment
		(start 223.148652 -177.660554)
		(end 221.714314 -179.094892)
		(width 0.15494)
		(layer "In7.Cu")
		(net "SMB_BIC_I2C9_SSD_MUX_R_SCL")
	)
	(segment
		(start 214.4776 -120.904)
		(end 214.122 -120.904)
		(width 0.15494)
		(layer "In7.Cu")
		(net "SMB_BIC_I2C9_SSD_MUX_R_SCL")
	)
	(segment
		(start 216.1286 -101.701346)
		(end 214.30615 -103.523796)
		(width 0.15494)
		(layer "In7.Cu")
		(net "SMB_BIC_I2C9_SSD_MUX_R_SCL")
	)
	(segment
		(start 214.122 -120.904)
		(end 213.4108 -121.6152)
		(width 0.15494)
		(layer "In7.Cu")
		(net "SMB_BIC_I2C9_SSD_MUX_R_SCL")
	)
	(segment
		(start 223.361758 -202.920854)
		(end 223.012 -203.270612)
		(width 0.15494)
		(layer "In7.Cu")
		(net "SMB_BIC_I2C9_SSD_MUX_R_SCL")
	)
	(segment
		(start 225.3234 -196.265546)
		(end 224.2566 -197.332346)
		(width 0.15494)
		(layer "In7.Cu")
		(net "SMB_BIC_I2C9_SSD_MUX_R_SCL")
	)
	(segment
		(start 214.884 -116.995448)
		(end 214.884 -120.4976)
		(width 0.15494)
		(layer "In7.Cu")
		(net "SMB_BIC_I2C9_SSD_MUX_R_SCL")
	)
	(segment
		(start 224.25406 -199.951594)
		(end 223.53397 -200.671684)
		(width 0.15494)
		(layer "In7.Cu")
		(net "SMB_BIC_I2C9_SSD_MUX_R_SCL")
	)
	(segment
		(start 214.30615 -116.417598)
		(end 214.884 -116.995448)
		(width 0.15494)
		(layer "In7.Cu")
		(net "SMB_BIC_I2C9_SSD_MUX_R_SCL")
	)
	(segment
		(start 220.726 -209.318606)
		(end 220.726 -219.468954)
		(width 0.15494)
		(layer "In7.Cu")
		(net "SMB_BIC_I2C9_SSD_MUX_R_SCL")
	)
	(segment
		(start 213.4108 -129.083054)
		(end 216.281 -131.953254)
		(width 0.15494)
		(layer "In7.Cu")
		(net "SMB_BIC_I2C9_SSD_MUX_R_SCL")
	)
	(segment
		(start 223.012 -207.032606)
		(end 220.726 -209.318606)
		(width 0.15494)
		(layer "In7.Cu")
		(net "SMB_BIC_I2C9_SSD_MUX_R_SCL")
	)
	(segment
		(start 225.7298 -191.262)
		(end 225.3234 -191.6684)
		(width 0.15494)
		(layer "In7.Cu")
		(net "SMB_BIC_I2C9_SSD_MUX_R_SCL")
	)
	(segment
		(start 223.012 -203.270612)
		(end 223.012 -207.032606)
		(width 0.15494)
		(layer "In7.Cu")
		(net "SMB_BIC_I2C9_SSD_MUX_R_SCL")
	)
	(segment
		(start 223.235012 -200.671684)
		(end 222.81769 -201.089006)
		(width 0.15494)
		(layer "In7.Cu")
		(net "SMB_BIC_I2C9_SSD_MUX_R_SCL")
	)
	(segment
		(start 217.679016 -91.73591)
		(end 216.1286 -93.286326)
		(width 0.15494)
		(layer "In7.Cu")
		(net "SMB_BIC_I2C9_SSD_MUX_R_SCL")
	)
	(segment
		(start 224.2566 -197.332346)
		(end 224.2566 -197.393306)
		(width 0.15494)
		(layer "In7.Cu")
		(net "SMB_BIC_I2C9_SSD_MUX_R_SCL")
	)
	(segment
		(start 221.777306 -185.150506)
		(end 223.647 -187.0202)
		(width 0.15494)
		(layer "In7.Cu")
		(net "SMB_BIC_I2C9_SSD_MUX_R_SCL")
	)
	(segment
		(start 224.25406 -197.395846)
		(end 224.25406 -199.951594)
		(width 0.15494)
		(layer "In7.Cu")
		(net "SMB_BIC_I2C9_SSD_MUX_R_SCL")
	)
	(segment
		(start 225.3234 -191.6684)
		(end 225.3234 -196.265546)
		(width 0.15494)
		(layer "In7.Cu")
		(net "SMB_BIC_I2C9_SSD_MUX_R_SCL")
	)
	(segment
		(start 221.0562 -157.440376)
		(end 221.0562 -165.640258)
		(width 0.15494)
		(layer "In7.Cu")
		(net "SMB_BIC_I2C9_SSD_MUX_R_SCL")
	)
	(segment
		(start 223.647 -187.0202)
		(end 225.044 -187.0202)
		(width 0.15494)
		(layer "In7.Cu")
		(net "SMB_BIC_I2C9_SSD_MUX_R_SCL")
	)
	(segment
		(start 213.4108 -121.6152)
		(end 213.4108 -129.083054)
		(width 0.15494)
		(layer "In7.Cu")
		(net "SMB_BIC_I2C9_SSD_MUX_R_SCL")
	)
	(segment
		(start 216.1286 -93.286326)
		(end 216.1286 -101.701346)
		(width 0.15494)
		(layer "In7.Cu")
		(net "SMB_BIC_I2C9_SSD_MUX_R_SCL")
	)
	(segment
		(start 225.044 -187.0202)
		(end 225.7298 -187.706)
		(width 0.15494)
		(layer "In7.Cu")
		(net "SMB_BIC_I2C9_SSD_MUX_R_SCL")
	)
	(segment
		(start 221.714314 -179.094892)
		(end 221.714314 -181.04104)
		(width 0.15494)
		(layer "In7.Cu")
		(net "SMB_BIC_I2C9_SSD_MUX_R_SCL")
	)
	(segment
		(start 222.710756 -167.294814)
		(end 222.710756 -170.057826)
		(width 0.15494)
		(layer "In7.Cu")
		(net "SMB_BIC_I2C9_SSD_MUX_R_SCL")
	)
	(segment
		(start 214.30615 -103.523796)
		(end 214.30615 -116.417598)
		(width 0.15494)
		(layer "In7.Cu")
		(net "SMB_BIC_I2C9_SSD_MUX_R_SCL")
	)
	(segment
		(start 223.53397 -200.671684)
		(end 223.235012 -200.671684)
		(width 0.15494)
		(layer "In7.Cu")
		(net "SMB_BIC_I2C9_SSD_MUX_R_SCL")
	)
	(segment
		(start 224.2566 -197.393306)
		(end 224.25406 -197.395846)
		(width 0.15494)
		(layer "In7.Cu")
		(net "SMB_BIC_I2C9_SSD_MUX_R_SCL")
	)
	(segment
		(start 216.850722 -89.9414)
		(end 204.216254 -89.9414)
		(width 0.15494)
		(layer "In15.Cu")
		(net "SMB_BIC_I2C9_SSD_MUX_R_SCL")
	)
	(segment
		(start 194.284346 -88.2904)
		(end 155.6258 -88.2904)
		(width 0.15494)
		(layer "In15.Cu")
		(net "SMB_BIC_I2C9_SSD_MUX_R_SCL")
	)
	(segment
		(start 143.7894 -100.1268)
		(end 140.247878 -100.1268)
		(width 0.15494)
		(layer "In15.Cu")
		(net "SMB_BIC_I2C9_SSD_MUX_R_SCL")
	)
	(segment
		(start 204.216254 -89.9414)
		(end 201.600054 -87.3252)
		(width 0.15494)
		(layer "In15.Cu")
		(net "SMB_BIC_I2C9_SSD_MUX_R_SCL")
	)
	(segment
		(start 195.249546 -87.3252)
		(end 194.284346 -88.2904)
		(width 0.15494)
		(layer "In15.Cu")
		(net "SMB_BIC_I2C9_SSD_MUX_R_SCL")
	)
	(segment
		(start 140.247878 -100.1268)
		(end 138.22172 -98.100642)
		(width 0.15494)
		(layer "In15.Cu")
		(net "SMB_BIC_I2C9_SSD_MUX_R_SCL")
	)
	(segment
		(start 201.600054 -87.3252)
		(end 195.249546 -87.3252)
		(width 0.15494)
		(layer "In15.Cu")
		(net "SMB_BIC_I2C9_SSD_MUX_R_SCL")
	)
	(segment
		(start 138.22172 -98.100642)
		(end 137.593324 -98.100642)
		(width 0.15494)
		(layer "In15.Cu")
		(net "SMB_BIC_I2C9_SSD_MUX_R_SCL")
	)
	(segment
		(start 155.6258 -88.2904)
		(end 143.7894 -100.1268)
		(width 0.15494)
		(layer "In15.Cu")
		(net "SMB_BIC_I2C9_SSD_MUX_R_SCL")
	)
	(segment
		(start 217.441526 -90.532204)
		(end 216.850722 -89.9414)
		(width 0.15494)
		(layer "In15.Cu")
		(net "SMB_BIC_I2C9_SSD_MUX_R_SCL")
	)
	(segment
		(start 57.09412 -376.292872)
		(end 57.09412 -375.449846)
		(width 0.13208)
		(layer "F.Cu")
		(net "GPU_BASE_PWR_EN_R")
	)
	(segment
		(start 57.341516 -376.540268)
		(end 57.09412 -376.292872)
		(width 0.13208)
		(layer "F.Cu")
		(net "GPU_BASE_PWR_EN_R")
	)
	(segment
		(start 57.776872 -376.540268)
		(end 57.341516 -376.540268)
		(width 0.13208)
		(layer "F.Cu")
		(net "GPU_BASE_PWR_EN_R")
	)
	(via
		(at 57.09412 -375.449846)
		(size 0.508)
		(drill 0.254)
		(layers "F.Cu" "B.Cu")
		(net "GPU_BASE_PWR_EN_R")
	)
	(segment
		(start 52.337208 -373.448072)
		(end 52.337208 -369.429284)
		(width 0.15494)
		(layer "In9.Cu")
		(net "GPU_BASE_PWR_EN_R")
	)
	(segment
		(start 35.962082 -367.538)
		(end 34.509964 -368.990118)
		(width 0.15494)
		(layer "In9.Cu")
		(net "GPU_BASE_PWR_EN_R")
	)
	(segment
		(start 52.337208 -369.429284)
		(end 50.445924 -367.538)
		(width 0.15494)
		(layer "In9.Cu")
		(net "GPU_BASE_PWR_EN_R")
	)
	(segment
		(start 50.445924 -367.538)
		(end 35.962082 -367.538)
		(width 0.15494)
		(layer "In9.Cu")
		(net "GPU_BASE_PWR_EN_R")
	)
	(segment
		(start 57.09412 -375.449846)
		(end 56.439054 -376.104912)
		(width 0.15494)
		(layer "In9.Cu")
		(net "GPU_BASE_PWR_EN_R")
	)
	(segment
		(start 56.439054 -376.104912)
		(end 54.994048 -376.104912)
		(width 0.15494)
		(layer "In9.Cu")
		(net "GPU_BASE_PWR_EN_R")
	)
	(segment
		(start 54.994048 -376.104912)
		(end 52.337208 -373.448072)
		(width 0.15494)
		(layer "In9.Cu")
		(net "GPU_BASE_PWR_EN_R")
	)
	(segment
		(start 138.364214 -205.650846)
		(end 139.253214 -205.650846)
		(width 0.13208)
		(layer "F.Cu")
		(net "UART_PEX0_CLI_BUF_TX")
	)
	(segment
		(start 139.253214 -205.650846)
		(end 142.440152 -202.463908)
		(width 0.13208)
		(layer "F.Cu")
		(net "UART_PEX0_CLI_BUF_TX")
	)
	(segment
		(start 142.440152 -202.463908)
		(end 145.28165 -202.463908)
		(width 0.13208)
		(layer "F.Cu")
		(net "UART_PEX0_CLI_BUF_TX")
	)
	(via
		(at 138.364214 -205.650846)
		(size 0.508)
		(drill 0.254)
		(layers "F.Cu" "B.Cu")
		(net "UART_PEX0_CLI_BUF_TX")
	)
	(segment
		(start 134.398766 -211.080858)
		(end 134.398766 -210.632294)
		(width 0.13208)
		(layer "B.Cu")
		(net "UART_PEX0_CLI_BUF_TX")
	)
	(segment
		(start 134.398766 -210.632294)
		(end 134.554214 -210.476846)
		(width 0.13208)
		(layer "B.Cu")
		(net "UART_PEX0_CLI_BUF_TX")
	)
	(segment
		(start 133.420866 -211.080858)
		(end 134.398766 -211.080858)
		(width 0.13208)
		(layer "B.Cu")
		(net "UART_PEX0_CLI_BUF_TX")
	)
	(segment
		(start 134.554214 -210.476846)
		(end 135.918194 -210.476846)
		(width 0.13208)
		(layer "B.Cu")
		(net "UART_PEX0_CLI_BUF_TX")
	)
	(segment
		(start 136.713214 -207.301846)
		(end 138.364214 -205.650846)
		(width 0.13208)
		(layer "B.Cu")
		(net "UART_PEX0_CLI_BUF_TX")
	)
	(segment
		(start 136.713214 -209.681826)
		(end 136.713214 -207.301846)
		(width 0.13208)
		(layer "B.Cu")
		(net "UART_PEX0_CLI_BUF_TX")
	)
	(segment
		(start 135.918194 -210.476846)
		(end 136.713214 -209.681826)
		(width 0.13208)
		(layer "B.Cu")
		(net "UART_PEX0_CLI_BUF_TX")
	)
	(segment
		(start 337.439 -81.321656)
		(end 337.439 -83.330034)
		(width 0.13462)
		(layer "F.Cu")
		(net "CLK_100M_DB800ZL_SSD9_DN")
	)
	(segment
		(start 337.495642 -83.386676)
		(end 337.495642 -83.814412)
		(width 0.13462)
		(layer "F.Cu")
		(net "CLK_100M_DB800ZL_SSD9_DN")
	)
	(segment
		(start 337.752944 -81.007712)
		(end 337.439 -81.321656)
		(width 0.13462)
		(layer "F.Cu")
		(net "CLK_100M_DB800ZL_SSD9_DN")
	)
	(segment
		(start 337.439 -83.330034)
		(end 337.495642 -83.386676)
		(width 0.13462)
		(layer "F.Cu")
		(net "CLK_100M_DB800ZL_SSD9_DN")
	)
	(segment
		(start 138.05408 -99.243642)
		(end 138.585194 -99.243642)
		(width 0.13208)
		(layer "F.Cu")
		(net "SMB_BIC_I2C9_SSD_MUX_R_SDA")
	)
	(segment
		(start 137.676636 -99.621086)
		(end 138.05408 -99.243642)
		(width 0.13208)
		(layer "F.Cu")
		(net "SMB_BIC_I2C9_SSD_MUX_R_SDA")
	)
	(segment
		(start 215.725248 -220.875098)
		(end 216.200736 -221.350586)
		(width 0.13208)
		(layer "F.Cu")
		(net "SMB_BIC_I2C9_SSD_MUX_R_SDA")
	)
	(segment
		(start 214.783416 -221.350586)
		(end 215.258904 -220.875098)
		(width 0.13208)
		(layer "F.Cu")
		(net "SMB_BIC_I2C9_SSD_MUX_R_SDA")
	)
	(segment
		(start 136.845294 -99.243642)
		(end 137.299192 -99.243642)
		(width 0.13208)
		(layer "F.Cu")
		(net "SMB_BIC_I2C9_SSD_MUX_R_SDA")
	)
	(segment
		(start 137.299192 -99.243642)
		(end 137.676636 -99.621086)
		(width 0.13208)
		(layer "F.Cu")
		(net "SMB_BIC_I2C9_SSD_MUX_R_SDA")
	)
	(segment
		(start 215.258904 -220.875098)
		(end 215.725248 -220.875098)
		(width 0.13208)
		(layer "F.Cu")
		(net "SMB_BIC_I2C9_SSD_MUX_R_SDA")
	)
	(segment
		(start 216.200736 -221.350586)
		(end 216.835736 -221.350586)
		(width 0.13208)
		(layer "F.Cu")
		(net "SMB_BIC_I2C9_SSD_MUX_R_SDA")
	)
	(segment
		(start 214.209122 -221.350586)
		(end 214.783416 -221.350586)
		(width 0.13208)
		(layer "F.Cu")
		(net "SMB_BIC_I2C9_SSD_MUX_R_SDA")
	)
	(via
		(at 137.676636 -99.621086)
		(size 0.508)
		(drill 0.254)
		(layers "F.Cu" "B.Cu")
		(net "SMB_BIC_I2C9_SSD_MUX_R_SDA")
	)
	(via
		(at 216.200736 -221.350586)
		(size 0.508)
		(drill 0.254)
		(layers "F.Cu" "B.Cu")
		(net "SMB_BIC_I2C9_SSD_MUX_R_SDA")
	)
	(via
		(at 216.552526 -90.604848)
		(size 0.508)
		(drill 0.254)
		(layers "F.Cu" "B.Cu")
		(net "SMB_BIC_I2C9_SSD_MUX_R_SDA")
	)
	(segment
		(start 221.248986 -183.49976)
		(end 221.248986 -185.307986)
		(width 0.15494)
		(layer "In7.Cu")
		(net "SMB_BIC_I2C9_SSD_MUX_R_SDA")
	)
	(segment
		(start 220.44914 -169.08526)
		(end 220.44914 -169.113962)
		(width 0.15494)
		(layer "In7.Cu")
		(net "SMB_BIC_I2C9_SSD_MUX_R_SDA")
	)
	(segment
		(start 221.11208 -179.16398)
		(end 221.11208 -180.838348)
		(width 0.15494)
		(layer "In7.Cu")
		(net "SMB_BIC_I2C9_SSD_MUX_R_SDA")
	)
	(segment
		(start 220.44914 -169.113962)
		(end 220.0656 -169.497502)
		(width 0.15494)
		(layer "In7.Cu")
		(net "SMB_BIC_I2C9_SSD_MUX_R_SDA")
	)
	(segment
		(start 221.11208 -180.838348)
		(end 220.755718 -181.19471)
		(width 0.15494)
		(layer "In7.Cu")
		(net "SMB_BIC_I2C9_SSD_MUX_R_SDA")
	)
	(segment
		(start 220.5482 -157.58287)
		(end 220.5482 -168.9862)
		(width 0.15494)
		(layer "In7.Cu")
		(net "SMB_BIC_I2C9_SSD_MUX_R_SDA")
	)
	(segment
		(start 220.5482 -168.9862)
		(end 220.44914 -169.08526)
		(width 0.15494)
		(layer "In7.Cu")
		(net "SMB_BIC_I2C9_SSD_MUX_R_SDA")
	)
	(segment
		(start 222.1738 -201.82967)
		(end 221.309438 -202.694032)
		(width 0.15494)
		(layer "In7.Cu")
		(net "SMB_BIC_I2C9_SSD_MUX_R_SDA")
	)
	(segment
		(start 220.755718 -183.006492)
		(end 221.248986 -183.49976)
		(width 0.15494)
		(layer "In7.Cu")
		(net "SMB_BIC_I2C9_SSD_MUX_R_SDA")
	)
	(segment
		(start 215.7984 -132.1816)
		(end 215.7984 -152.83307)
		(width 0.15494)
		(layer "In7.Cu")
		(net "SMB_BIC_I2C9_SSD_MUX_R_SDA")
	)
	(segment
		(start 221.47276 -203.265024)
		(end 221.615 -203.407264)
		(width 0.15494)
		(layer "In7.Cu")
		(net "SMB_BIC_I2C9_SSD_MUX_R_SDA")
	)
	(segment
		(start 223.4438 -187.5028)
		(end 224.78492 -187.5028)
		(width 0.15494)
		(layer "In7.Cu")
		(net "SMB_BIC_I2C9_SSD_MUX_R_SDA")
	)
	(segment
		(start 212.9028 -129.286)
		(end 215.7984 -132.1816)
		(width 0.15494)
		(layer "In7.Cu")
		(net "SMB_BIC_I2C9_SSD_MUX_R_SDA")
	)
	(segment
		(start 220.0656 -178.1175)
		(end 221.11208 -179.16398)
		(width 0.15494)
		(layer "In7.Cu")
		(net "SMB_BIC_I2C9_SSD_MUX_R_SDA")
	)
	(segment
		(start 213.5124 -103.641906)
		(end 213.5124 -119.8626)
		(width 0.15494)
		(layer "In7.Cu")
		(net "SMB_BIC_I2C9_SSD_MUX_R_SDA")
	)
	(segment
		(start 221.615 -203.407264)
		(end 221.615 -206.573882)
		(width 0.15494)
		(layer "In7.Cu")
		(net "SMB_BIC_I2C9_SSD_MUX_R_SDA")
	)
	(segment
		(start 218.11996 -221.350586)
		(end 216.200736 -221.350586)
		(width 0.15494)
		(layer "In7.Cu")
		(net "SMB_BIC_I2C9_SSD_MUX_R_SDA")
	)
	(segment
		(start 225.267774 -187.985654)
		(end 225.267774 -190.911226)
		(width 0.15494)
		(layer "In7.Cu")
		(net "SMB_BIC_I2C9_SSD_MUX_R_SDA")
	)
	(segment
		(start 221.309438 -202.694032)
		(end 221.309438 -203.098146)
		(width 0.15494)
		(layer "In7.Cu")
		(net "SMB_BIC_I2C9_SSD_MUX_R_SDA")
	)
	(segment
		(start 213.5124 -119.8626)
		(end 212.9028 -120.4722)
		(width 0.15494)
		(layer "In7.Cu")
		(net "SMB_BIC_I2C9_SSD_MUX_R_SDA")
	)
	(segment
		(start 212.9028 -120.4722)
		(end 212.9028 -129.286)
		(width 0.15494)
		(layer "In7.Cu")
		(net "SMB_BIC_I2C9_SSD_MUX_R_SDA")
	)
	(segment
		(start 221.47276 -203.261468)
		(end 221.47276 -203.265024)
		(width 0.15494)
		(layer "In7.Cu")
		(net "SMB_BIC_I2C9_SSD_MUX_R_SDA")
	)
	(segment
		(start 216.552526 -90.604848)
		(end 216.552526 -91.668346)
		(width 0.15494)
		(layer "In7.Cu")
		(net "SMB_BIC_I2C9_SSD_MUX_R_SDA")
	)
	(segment
		(start 225.267774 -190.911226)
		(end 223.4946 -192.6844)
		(width 0.15494)
		(layer "In7.Cu")
		(net "SMB_BIC_I2C9_SSD_MUX_R_SDA")
	)
	(segment
		(start 215.646 -101.47808)
		(end 215.646 -101.508306)
		(width 0.15494)
		(layer "In7.Cu")
		(net "SMB_BIC_I2C9_SSD_MUX_R_SDA")
	)
	(segment
		(start 220.755718 -181.19471)
		(end 220.755718 -183.006492)
		(width 0.15494)
		(layer "In7.Cu")
		(net "SMB_BIC_I2C9_SSD_MUX_R_SDA")
	)
	(segment
		(start 215.65997 -92.560902)
		(end 215.65997 -101.46411)
		(width 0.15494)
		(layer "In7.Cu")
		(net "SMB_BIC_I2C9_SSD_MUX_R_SDA")
	)
	(segment
		(start 223.4946 -196.974206)
		(end 222.1738 -200.163176)
		(width 0.15494)
		(layer "In7.Cu")
		(net "SMB_BIC_I2C9_SSD_MUX_R_SDA")
	)
	(segment
		(start 215.7984 -152.83307)
		(end 220.5482 -157.58287)
		(width 0.15494)
		(layer "In7.Cu")
		(net "SMB_BIC_I2C9_SSD_MUX_R_SDA")
	)
	(segment
		(start 215.646 -101.508306)
		(end 213.5124 -103.641906)
		(width 0.15494)
		(layer "In7.Cu")
		(net "SMB_BIC_I2C9_SSD_MUX_R_SDA")
	)
	(segment
		(start 221.248986 -185.307986)
		(end 223.4438 -187.5028)
		(width 0.15494)
		(layer "In7.Cu")
		(net "SMB_BIC_I2C9_SSD_MUX_R_SDA")
	)
	(segment
		(start 220.0656 -169.497502)
		(end 220.0656 -178.1175)
		(width 0.15494)
		(layer "In7.Cu")
		(net "SMB_BIC_I2C9_SSD_MUX_R_SDA")
	)
	(segment
		(start 222.1738 -200.163176)
		(end 222.1738 -201.82967)
		(width 0.15494)
		(layer "In7.Cu")
		(net "SMB_BIC_I2C9_SSD_MUX_R_SDA")
	)
	(segment
		(start 220.218 -219.252546)
		(end 218.11996 -221.350586)
		(width 0.15494)
		(layer "In7.Cu")
		(net "SMB_BIC_I2C9_SSD_MUX_R_SDA")
	)
	(segment
		(start 221.309438 -203.098146)
		(end 221.47276 -203.261468)
		(width 0.15494)
		(layer "In7.Cu")
		(net "SMB_BIC_I2C9_SSD_MUX_R_SDA")
	)
	(segment
		(start 223.4946 -192.6844)
		(end 223.4946 -196.974206)
		(width 0.15494)
		(layer "In7.Cu")
		(net "SMB_BIC_I2C9_SSD_MUX_R_SDA")
	)
	(segment
		(start 221.178882 -207.01)
		(end 221.178882 -208.215484)
		(width 0.15494)
		(layer "In7.Cu")
		(net "SMB_BIC_I2C9_SSD_MUX_R_SDA")
	)
	(segment
		(start 215.65997 -101.46411)
		(end 215.646 -101.47808)
		(width 0.15494)
		(layer "In7.Cu")
		(net "SMB_BIC_I2C9_SSD_MUX_R_SDA")
	)
	(segment
		(start 224.78492 -187.5028)
		(end 225.267774 -187.985654)
		(width 0.15494)
		(layer "In7.Cu")
		(net "SMB_BIC_I2C9_SSD_MUX_R_SDA")
	)
	(segment
		(start 220.218 -209.176366)
		(end 220.218 -219.252546)
		(width 0.15494)
		(layer "In7.Cu")
		(net "SMB_BIC_I2C9_SSD_MUX_R_SDA")
	)
	(segment
		(start 221.615 -206.573882)
		(end 221.178882 -207.01)
		(width 0.15494)
		(layer "In7.Cu")
		(net "SMB_BIC_I2C9_SSD_MUX_R_SDA")
	)
	(segment
		(start 216.552526 -91.668346)
		(end 215.65997 -92.560902)
		(width 0.15494)
		(layer "In7.Cu")
		(net "SMB_BIC_I2C9_SSD_MUX_R_SDA")
	)
	(segment
		(start 221.178882 -208.215484)
		(end 220.218 -209.176366)
		(width 0.15494)
		(layer "In7.Cu")
		(net "SMB_BIC_I2C9_SSD_MUX_R_SDA")
	)
	(segment
		(start 213.122256 -90.9066)
		(end 213.197694 -90.982038)
		(width 0.15494)
		(layer "In15.Cu")
		(net "SMB_BIC_I2C9_SSD_MUX_R_SDA")
	)
	(segment
		(start 143.96847 -100.6602)
		(end 155.85567 -88.773)
		(width 0.15494)
		(layer "In15.Cu")
		(net "SMB_BIC_I2C9_SSD_MUX_R_SDA")
	)
	(segment
		(start 138.914632 -99.621086)
		(end 139.953746 -100.6602)
		(width 0.15494)
		(layer "In15.Cu")
		(net "SMB_BIC_I2C9_SSD_MUX_R_SDA")
	)
	(segment
		(start 203.606146 -90.9066)
		(end 213.122256 -90.9066)
		(width 0.15494)
		(layer "In15.Cu")
		(net "SMB_BIC_I2C9_SSD_MUX_R_SDA")
	)
	(segment
		(start 194.6402 -88.773)
		(end 194.7672 -88.9)
		(width 0.15494)
		(layer "In15.Cu")
		(net "SMB_BIC_I2C9_SSD_MUX_R_SDA")
	)
	(segment
		(start 216.175336 -90.982038)
		(end 216.552526 -90.604848)
		(width 0.15494)
		(layer "In15.Cu")
		(net "SMB_BIC_I2C9_SSD_MUX_R_SDA")
	)
	(segment
		(start 201.599546 -88.9)
		(end 203.606146 -90.9066)
		(width 0.15494)
		(layer "In15.Cu")
		(net "SMB_BIC_I2C9_SSD_MUX_R_SDA")
	)
	(segment
		(start 194.7672 -88.9)
		(end 201.599546 -88.9)
		(width 0.15494)
		(layer "In15.Cu")
		(net "SMB_BIC_I2C9_SSD_MUX_R_SDA")
	)
	(segment
		(start 213.197694 -90.982038)
		(end 216.175336 -90.982038)
		(width 0.15494)
		(layer "In15.Cu")
		(net "SMB_BIC_I2C9_SSD_MUX_R_SDA")
	)
	(segment
		(start 155.85567 -88.773)
		(end 194.6402 -88.773)
		(width 0.15494)
		(layer "In15.Cu")
		(net "SMB_BIC_I2C9_SSD_MUX_R_SDA")
	)
	(segment
		(start 137.676636 -99.621086)
		(end 138.914632 -99.621086)
		(width 0.15494)
		(layer "In15.Cu")
		(net "SMB_BIC_I2C9_SSD_MUX_R_SDA")
	)
	(segment
		(start 139.953746 -100.6602)
		(end 143.96847 -100.6602)
		(width 0.15494)
		(layer "In15.Cu")
		(net "SMB_BIC_I2C9_SSD_MUX_R_SDA")
	)
	(segment
		(start 36.6649 -22.3901)
		(end 38.467538 -22.3901)
		(width 0.13208)
		(layer "F.Cu")
		(net "SMB_ISO_SSD1_R_SCL")
	)
	(segment
		(start 48.658272 -18.44421)
		(end 48.665384 -18.437098)
		(width 0.13208)
		(layer "F.Cu")
		(net "SMB_ISO_SSD1_R_SCL")
	)
	(segment
		(start 38.467538 -22.3901)
		(end 39.093648 -23.01621)
		(width 0.13208)
		(layer "F.Cu")
		(net "SMB_ISO_SSD1_R_SCL")
	)
	(segment
		(start 48.665384 -18.437098)
		(end 49.267872 -18.437098)
		(width 0.13208)
		(layer "F.Cu")
		(net "SMB_ISO_SSD1_R_SCL")
	)
	(via
		(at 39.093648 -23.01621)
		(size 0.508)
		(drill 0.254)
		(layers "F.Cu" "B.Cu")
		(net "SMB_ISO_SSD1_R_SCL")
	)
	(via
		(at 48.658272 -18.44421)
		(size 0.508)
		(drill 0.254)
		(layers "F.Cu" "B.Cu")
		(net "SMB_ISO_SSD1_R_SCL")
	)
	(segment
		(start 49.226978 -21.791676)
		(end 48.002444 -23.01621)
		(width 0.15494)
		(layer "In5.Cu")
		(net "SMB_ISO_SSD1_R_SCL")
	)
	(segment
		(start 48.658272 -18.44421)
		(end 49.226978 -19.012916)
		(width 0.15494)
		(layer "In5.Cu")
		(net "SMB_ISO_SSD1_R_SCL")
	)
	(segment
		(start 48.002444 -23.01621)
		(end 39.093648 -23.01621)
		(width 0.15494)
		(layer "In5.Cu")
		(net "SMB_ISO_SSD1_R_SCL")
	)
	(segment
		(start 49.226978 -19.012916)
		(end 49.226978 -21.791676)
		(width 0.15494)
		(layer "In5.Cu")
		(net "SMB_ISO_SSD1_R_SCL")
	)
	(segment
		(start 131.471162 -179.900326)
		(end 131.670806 -179.422552)
		(width 0.13208)
		(layer "F.Cu")
		(net "FM_DB2000QL_SMB_SA0")
	)
	(via
		(at 131.670806 -179.422552)
		(size 0.49022)
		(drill 0.254)
		(layers "F.Cu" "B.Cu")
		(net "FM_DB2000QL_SMB_SA0")
	)
	(via
		(at 129.965958 -181.050692)
		(size 0.6604)
		(drill 0.3302)
		(layers "F.Cu" "B.Cu")
		(net "FM_DB2000QL_SMB_SA0")
	)
	(segment
		(start 128.470914 -182.204614)
		(end 129.486914 -182.204614)
		(width 0.13208)
		(layer "B.Cu")
		(net "FM_DB2000QL_SMB_SA0")
	)
	(segment
		(start 129.486914 -181.873906)
		(end 129.965958 -181.394862)
		(width 0.13208)
		(layer "B.Cu")
		(net "FM_DB2000QL_SMB_SA0")
	)
	(segment
		(start 129.965958 -181.050692)
		(end 130.042666 -181.050692)
		(width 0.13208)
		(layer "B.Cu")
		(net "FM_DB2000QL_SMB_SA0")
	)
	(segment
		(start 129.486914 -182.204614)
		(end 129.486914 -181.873906)
		(width 0.13208)
		(layer "B.Cu")
		(net "FM_DB2000QL_SMB_SA0")
	)
	(segment
		(start 129.965958 -181.394862)
		(end 129.965958 -181.050692)
		(width 0.13208)
		(layer "B.Cu")
		(net "FM_DB2000QL_SMB_SA0")
	)
	(segment
		(start 130.042666 -181.050692)
		(end 131.670806 -179.422552)
		(width 0.13208)
		(layer "B.Cu")
		(net "FM_DB2000QL_SMB_SA0")
	)
	(segment
		(start 341.472266 -84.564474)
		(end 341.045546 -84.564474)
		(width 0.13462)
		(layer "F.Cu")
		(net "CLK_100M_DB800ZL_SSD11_DP")
	)
	(segment
		(start 341.88908 -84.620862)
		(end 341.528654 -84.620862)
		(width 0.13462)
		(layer "F.Cu")
		(net "CLK_100M_DB800ZL_SSD11_DP")
	)
	(segment
		(start 344.212926 -83.255358)
		(end 343.899236 -83.569048)
		(width 0.13462)
		(layer "F.Cu")
		(net "CLK_100M_DB800ZL_SSD11_DP")
	)
	(segment
		(start 341.528654 -84.620862)
		(end 341.472266 -84.564474)
		(width 0.13462)
		(layer "F.Cu")
		(net "CLK_100M_DB800ZL_SSD11_DP")
	)
	(segment
		(start 342.940894 -83.569048)
		(end 341.88908 -84.620862)
		(width 0.13462)
		(layer "F.Cu")
		(net "CLK_100M_DB800ZL_SSD11_DP")
	)
	(segment
		(start 343.899236 -83.569048)
		(end 342.940894 -83.569048)
		(width 0.13462)
		(layer "F.Cu")
		(net "CLK_100M_DB800ZL_SSD11_DP")
	)
	(segment
		(start 260.606286 -251.956824)
		(end 260.606286 -251.158502)
		(width 0.13208)
		(layer "F.Cu")
		(net "PEX2_DBG_MODE3")
	)
	(segment
		(start 260.606286 -251.158502)
		(end 260.606286 -250.470924)
		(width 0.13208)
		(layer "F.Cu")
		(net "PEX2_DBG_MODE3")
	)
	(segment
		(start 292.79977 -282.599892)
		(end 293.27475 -283.074872)
		(width 0.1651)
		(layer "F.Cu")
		(net "PEX2_DBG_MODE3")
	)
	(via
		(at 260.606286 -251.158502)
		(size 0.508)
		(drill 0.254)
		(layers "F.Cu" "B.Cu")
		(net "PEX2_DBG_MODE3")
	)
	(via
		(at 293.27475 -283.074872)
		(size 0.4064)
		(drill 0.2032)
		(layers "F.Cu" "B.Cu")
		(net "PEX2_DBG_MODE3")
	)
	(segment
		(start 263.783064 -255.305052)
		(end 266.540996 -258.062984)
		(width 0.13208)
		(layer "B.Cu")
		(net "PEX2_DBG_MODE3")
	)
	(segment
		(start 260.829806 -254.060706)
		(end 262.074152 -255.305052)
		(width 0.13208)
		(layer "B.Cu")
		(net "PEX2_DBG_MODE3")
	)
	(segment
		(start 293.27475 -271.586198)
		(end 293.27475 -283.074872)
		(width 0.13208)
		(layer "B.Cu")
		(net "PEX2_DBG_MODE3")
	)
	(segment
		(start 290.832794 -269.153132)
		(end 291.154104 -269.474442)
		(width 0.13208)
		(layer "B.Cu")
		(net "PEX2_DBG_MODE3")
	)
	(segment
		(start 260.606286 -251.158502)
		(end 260.062726 -251.702062)
		(width 0.13208)
		(layer "B.Cu")
		(net "PEX2_DBG_MODE3")
	)
	(segment
		(start 260.062726 -253.716536)
		(end 260.406896 -254.060706)
		(width 0.13208)
		(layer "B.Cu")
		(net "PEX2_DBG_MODE3")
	)
	(segment
		(start 260.062726 -251.702062)
		(end 260.062726 -253.716536)
		(width 0.13208)
		(layer "B.Cu")
		(net "PEX2_DBG_MODE3")
	)
	(segment
		(start 291.154104 -269.474442)
		(end 291.162994 -269.474442)
		(width 0.13208)
		(layer "B.Cu")
		(net "PEX2_DBG_MODE3")
	)
	(segment
		(start 289.357562 -267.66901)
		(end 289.366198 -267.66901)
		(width 0.13208)
		(layer "B.Cu")
		(net "PEX2_DBG_MODE3")
	)
	(segment
		(start 289.366198 -267.66901)
		(end 289.687508 -267.99032)
		(width 0.13208)
		(layer "B.Cu")
		(net "PEX2_DBG_MODE3")
	)
	(segment
		(start 289.687508 -267.99032)
		(end 289.687508 -267.998956)
		(width 0.13208)
		(layer "B.Cu")
		(net "PEX2_DBG_MODE3")
	)
	(segment
		(start 290.832794 -269.144242)
		(end 290.832794 -269.153132)
		(width 0.13208)
		(layer "B.Cu")
		(net "PEX2_DBG_MODE3")
	)
	(segment
		(start 279.751536 -258.062984)
		(end 289.357562 -267.66901)
		(width 0.13208)
		(layer "B.Cu")
		(net "PEX2_DBG_MODE3")
	)
	(segment
		(start 262.074152 -255.305052)
		(end 263.783064 -255.305052)
		(width 0.13208)
		(layer "B.Cu")
		(net "PEX2_DBG_MODE3")
	)
	(segment
		(start 289.687508 -267.998956)
		(end 290.832794 -269.144242)
		(width 0.13208)
		(layer "B.Cu")
		(net "PEX2_DBG_MODE3")
	)
	(segment
		(start 266.540996 -258.062984)
		(end 279.751536 -258.062984)
		(width 0.13208)
		(layer "B.Cu")
		(net "PEX2_DBG_MODE3")
	)
	(segment
		(start 291.162994 -269.474442)
		(end 293.27475 -271.586198)
		(width 0.13208)
		(layer "B.Cu")
		(net "PEX2_DBG_MODE3")
	)
	(segment
		(start 260.406896 -254.060706)
		(end 260.829806 -254.060706)
		(width 0.13208)
		(layer "B.Cu")
		(net "PEX2_DBG_MODE3")
	)
	(segment
		(start 366.555528 -90.229436)
		(end 366.682528 -90.102436)
		(width 0.13208)
		(layer "F.Cu")
		(net "BIC_I2C9_SSD_MUX1_A2")
	)
	(segment
		(start 366.682528 -90.102436)
		(end 368.55527 -90.102436)
		(width 0.13208)
		(layer "F.Cu")
		(net "BIC_I2C9_SSD_MUX1_A2")
	)
	(segment
		(start 363.44606 -88.24214)
		(end 363.44606 -89.133934)
		(width 0.13208)
		(layer "F.Cu")
		(net "BIC_I2C9_SSD_MUX1_A2")
	)
	(segment
		(start 363.44606 -89.133934)
		(end 364.459012 -90.146886)
		(width 0.13208)
		(layer "F.Cu")
		(net "BIC_I2C9_SSD_MUX1_A2")
	)
	(segment
		(start 366.05972 -90.146886)
		(end 366.555528 -90.642694)
		(width 0.13208)
		(layer "F.Cu")
		(net "BIC_I2C9_SSD_MUX1_A2")
	)
	(segment
		(start 364.459012 -90.146886)
		(end 366.05972 -90.146886)
		(width 0.13208)
		(layer "F.Cu")
		(net "BIC_I2C9_SSD_MUX1_A2")
	)
	(segment
		(start 366.555528 -90.642694)
		(end 366.555528 -90.229436)
		(width 0.13208)
		(layer "F.Cu")
		(net "BIC_I2C9_SSD_MUX1_A2")
	)
	(segment
		(start 362.30814 -88.11514)
		(end 363.31906 -88.11514)
		(width 0.13208)
		(layer "F.Cu")
		(net "BIC_I2C9_SSD_MUX1_A2")
	)
	(segment
		(start 363.31906 -88.11514)
		(end 363.44606 -88.24214)
		(width 0.13208)
		(layer "F.Cu")
		(net "BIC_I2C9_SSD_MUX1_A2")
	)
	(segment
		(start 368.55527 -90.102436)
		(end 369.095528 -90.642694)
		(width 0.13208)
		(layer "F.Cu")
		(net "BIC_I2C9_SSD_MUX1_A2")
	)
	(via
		(at 366.05972 -90.146886)
		(size 0.508)
		(drill 0.254)
		(layers "F.Cu" "B.Cu")
		(net "BIC_I2C9_SSD_MUX1_A2")
	)
	(segment
		(start 206.567532 -22.3901)
		(end 207.193642 -23.01621)
		(width 0.13208)
		(layer "F.Cu")
		(net "SMB_ISO_SSD7_R_SCL")
	)
	(segment
		(start 216.758266 -18.44421)
		(end 216.765378 -18.437098)
		(width 0.13208)
		(layer "F.Cu")
		(net "SMB_ISO_SSD7_R_SCL")
	)
	(segment
		(start 216.765378 -18.437098)
		(end 217.367866 -18.437098)
		(width 0.13208)
		(layer "F.Cu")
		(net "SMB_ISO_SSD7_R_SCL")
	)
	(segment
		(start 204.764894 -22.3901)
		(end 206.567532 -22.3901)
		(width 0.13208)
		(layer "F.Cu")
		(net "SMB_ISO_SSD7_R_SCL")
	)
	(via
		(at 207.193642 -23.01621)
		(size 0.508)
		(drill 0.254)
		(layers "F.Cu" "B.Cu")
		(net "SMB_ISO_SSD7_R_SCL")
	)
	(via
		(at 216.758266 -18.44421)
		(size 0.508)
		(drill 0.254)
		(layers "F.Cu" "B.Cu")
		(net "SMB_ISO_SSD7_R_SCL")
	)
	(segment
		(start 216.758266 -18.44421)
		(end 217.326972 -19.012916)
		(width 0.15494)
		(layer "In5.Cu")
		(net "SMB_ISO_SSD7_R_SCL")
	)
	(segment
		(start 217.326972 -19.012916)
		(end 217.326972 -21.651976)
		(width 0.15494)
		(layer "In5.Cu")
		(net "SMB_ISO_SSD7_R_SCL")
	)
	(segment
		(start 217.326972 -21.651976)
		(end 215.962738 -23.01621)
		(width 0.15494)
		(layer "In5.Cu")
		(net "SMB_ISO_SSD7_R_SCL")
	)
	(segment
		(start 215.962738 -23.01621)
		(end 207.193642 -23.01621)
		(width 0.15494)
		(layer "In5.Cu")
		(net "SMB_ISO_SSD7_R_SCL")
	)
	(via
		(at 146.685254 -206.133192)
		(size 0.6604)
		(drill 0.3302)
		(layers "F.Cu" "B.Cu")
		(net "UART_PEX1_CLI_BUF_R_RX")
	)
	(segment
		(start 146.685254 -205.752192)
		(end 147.559268 -204.878178)
		(width 0.13208)
		(layer "B.Cu")
		(net "UART_PEX1_CLI_BUF_R_RX")
	)
	(segment
		(start 146.685254 -207.384142)
		(end 146.685254 -206.133192)
		(width 0.13208)
		(layer "B.Cu")
		(net "UART_PEX1_CLI_BUF_R_RX")
	)
	(segment
		(start 146.685254 -206.133192)
		(end 146.685254 -205.752192)
		(width 0.13208)
		(layer "B.Cu")
		(net "UART_PEX1_CLI_BUF_R_RX")
	)
	(segment
		(start 147.559268 -204.878178)
		(end 147.559268 -204.46619)
		(width 0.13208)
		(layer "B.Cu")
		(net "UART_PEX1_CLI_BUF_R_RX")
	)
	(segment
		(start 343.899236 -85.856064)
		(end 343.18829 -85.856064)
		(width 0.13462)
		(layer "F.Cu")
		(net "CLK_100M_DB800ZL_SSD12_DN")
	)
	(segment
		(start 342.57996 -86.108032)
		(end 341.52967 -86.108032)
		(width 0.13462)
		(layer "F.Cu")
		(net "CLK_100M_DB800ZL_SSD12_DN")
	)
	(segment
		(start 344.212926 -86.169754)
		(end 343.899236 -85.856064)
		(width 0.13462)
		(layer "F.Cu")
		(net "CLK_100M_DB800ZL_SSD12_DN")
	)
	(segment
		(start 341.473282 -86.16442)
		(end 341.045546 -86.16442)
		(width 0.13462)
		(layer "F.Cu")
		(net "CLK_100M_DB800ZL_SSD12_DN")
	)
	(segment
		(start 343.18829 -85.856064)
		(end 342.57996 -86.108032)
		(width 0.13462)
		(layer "F.Cu")
		(net "CLK_100M_DB800ZL_SSD12_DN")
	)
	(segment
		(start 341.52967 -86.108032)
		(end 341.473282 -86.16442)
		(width 0.13462)
		(layer "F.Cu")
		(net "CLK_100M_DB800ZL_SSD12_DN")
	)
	(segment
		(start 265.355578 -84.150454)
		(end 264.35177 -84.150454)
		(width 0.13208)
		(layer "F.Cu")
		(net "CLK_BUFFER_DB2000QL_OE0_N")
	)
	(segment
		(start 265.668506 -84.463382)
		(end 265.355578 -84.150454)
		(width 0.13208)
		(layer "F.Cu")
		(net "CLK_BUFFER_DB2000QL_OE0_N")
	)
	(segment
		(start 268.106398 -86.171786)
		(end 266.799568 -84.864956)
		(width 0.13208)
		(layer "F.Cu")
		(net "CLK_BUFFER_DB2000QL_OE0_N")
	)
	(segment
		(start 266.07008 -84.864956)
		(end 265.668506 -84.463382)
		(width 0.13208)
		(layer "F.Cu")
		(net "CLK_BUFFER_DB2000QL_OE0_N")
	)
	(segment
		(start 264.007854 -83.806538)
		(end 262.801862 -83.806538)
		(width 0.0889)
		(layer "F.Cu")
		(net "CLK_BUFFER_DB2000QL_OE0_N")
	)
	(segment
		(start 266.799568 -84.864956)
		(end 266.07008 -84.864956)
		(width 0.13208)
		(layer "F.Cu")
		(net "CLK_BUFFER_DB2000QL_OE0_N")
	)
	(segment
		(start 268.106398 -87.251286)
		(end 268.106398 -86.235286)
		(width 0.13208)
		(layer "F.Cu")
		(net "CLK_BUFFER_DB2000QL_OE0_N")
	)
	(segment
		(start 264.35177 -84.150454)
		(end 264.007854 -83.806538)
		(width 0.0889)
		(layer "F.Cu")
		(net "CLK_BUFFER_DB2000QL_OE0_N")
	)
	(segment
		(start 268.106398 -86.235286)
		(end 268.106398 -86.171786)
		(width 0.13208)
		(layer "F.Cu")
		(net "CLK_BUFFER_DB2000QL_OE0_N")
	)
	(via
		(at 265.668506 -84.463382)
		(size 0.762)
		(drill 0.381)
		(layers "F.Cu" "B.Cu")
		(net "CLK_BUFFER_DB2000QL_OE0_N")
	)
	(segment
		(start 263.654286 -251.956824)
		(end 263.654286 -251.158502)
		(width 0.13208)
		(layer "F.Cu")
		(net "PEX2_MODE_SEL4")
	)
	(segment
		(start 294.69969 -282.599892)
		(end 294.699944 -282.599892)
		(width 0.13208)
		(layer "F.Cu")
		(net "PEX2_MODE_SEL4")
	)
	(segment
		(start 263.654286 -251.158502)
		(end 263.654286 -250.470924)
		(width 0.13208)
		(layer "F.Cu")
		(net "PEX2_MODE_SEL4")
	)
	(segment
		(start 294.699944 -282.599892)
		(end 295.174924 -283.074872)
		(width 0.13208)
		(layer "F.Cu")
		(net "PEX2_MODE_SEL4")
	)
	(via
		(at 290.701476 -266.71143)
		(size 0.6604)
		(drill 0.3302)
		(layers "F.Cu" "B.Cu")
		(net "PEX2_MODE_SEL4")
	)
	(via
		(at 263.654286 -251.158502)
		(size 0.508)
		(drill 0.254)
		(layers "F.Cu" "B.Cu")
		(net "PEX2_MODE_SEL4")
	)
	(via
		(at 295.174924 -283.074872)
		(size 0.4064)
		(drill 0.2032)
		(layers "F.Cu" "B.Cu")
		(net "PEX2_MODE_SEL4")
	)
	(segment
		(start 263.999472 -254.225806)
		(end 265.262106 -255.48844)
		(width 0.13208)
		(layer "B.Cu")
		(net "PEX2_MODE_SEL4")
	)
	(segment
		(start 265.262106 -255.48844)
		(end 267.721588 -255.48844)
		(width 0.13208)
		(layer "B.Cu")
		(net "PEX2_MODE_SEL4")
	)
	(segment
		(start 263.181846 -251.630942)
		(end 263.181846 -253.652274)
		(width 0.13208)
		(layer "B.Cu")
		(net "PEX2_MODE_SEL4")
	)
	(segment
		(start 296.122598 -282.127198)
		(end 295.174924 -283.074872)
		(width 0.13208)
		(layer "B.Cu")
		(net "PEX2_MODE_SEL4")
	)
	(segment
		(start 263.654286 -251.158502)
		(end 263.181846 -251.630942)
		(width 0.13208)
		(layer "B.Cu")
		(net "PEX2_MODE_SEL4")
	)
	(segment
		(start 263.755378 -254.225806)
		(end 263.999472 -254.225806)
		(width 0.13208)
		(layer "B.Cu")
		(net "PEX2_MODE_SEL4")
	)
	(segment
		(start 290.701476 -266.71143)
		(end 290.867084 -266.71143)
		(width 0.13208)
		(layer "B.Cu")
		(net "PEX2_MODE_SEL4")
	)
	(segment
		(start 296.122598 -271.966944)
		(end 296.122598 -282.127198)
		(width 0.13208)
		(layer "B.Cu")
		(net "PEX2_MODE_SEL4")
	)
	(segment
		(start 267.721588 -255.48844)
		(end 268.274038 -256.04089)
		(width 0.13208)
		(layer "B.Cu")
		(net "PEX2_MODE_SEL4")
	)
	(segment
		(start 290.867084 -266.71143)
		(end 296.122598 -271.966944)
		(width 0.13208)
		(layer "B.Cu")
		(net "PEX2_MODE_SEL4")
	)
	(segment
		(start 263.181846 -253.652274)
		(end 263.755378 -254.225806)
		(width 0.13208)
		(layer "B.Cu")
		(net "PEX2_MODE_SEL4")
	)
	(segment
		(start 268.274038 -256.04089)
		(end 280.030936 -256.04089)
		(width 0.13208)
		(layer "B.Cu")
		(net "PEX2_MODE_SEL4")
	)
	(segment
		(start 280.030936 -256.04089)
		(end 290.701476 -266.71143)
		(width 0.13208)
		(layer "B.Cu")
		(net "PEX2_MODE_SEL4")
	)
	(segment
		(start 354.514404 -91.574366)
		(end 353.585272 -90.645234)
		(width 0.13208)
		(layer "F.Cu")
		(net "BIC_I2C9_SSD_MUX1_A1")
	)
	(segment
		(start 355.618796 -91.160854)
		(end 355.205284 -91.574366)
		(width 0.13208)
		(layer "F.Cu")
		(net "BIC_I2C9_SSD_MUX1_A1")
	)
	(segment
		(start 353.320604 -90.645234)
		(end 353.320604 -90.289126)
		(width 0.13208)
		(layer "F.Cu")
		(net "BIC_I2C9_SSD_MUX1_A1")
	)
	(segment
		(start 351.263712 -90.162126)
		(end 350.780604 -90.645234)
		(width 0.13208)
		(layer "F.Cu")
		(net "BIC_I2C9_SSD_MUX1_A1")
	)
	(segment
		(start 353.585272 -90.645234)
		(end 353.320604 -90.645234)
		(width 0.13208)
		(layer "F.Cu")
		(net "BIC_I2C9_SSD_MUX1_A1")
	)
	(segment
		(start 355.205284 -91.574366)
		(end 354.514404 -91.574366)
		(width 0.13208)
		(layer "F.Cu")
		(net "BIC_I2C9_SSD_MUX1_A1")
	)
	(segment
		(start 353.320604 -90.289126)
		(end 353.193604 -90.162126)
		(width 0.13208)
		(layer "F.Cu")
		(net "BIC_I2C9_SSD_MUX1_A1")
	)
	(segment
		(start 356.707948 -89.415112)
		(end 356.010972 -89.415112)
		(width 0.13208)
		(layer "F.Cu")
		(net "BIC_I2C9_SSD_MUX1_A1")
	)
	(segment
		(start 355.618796 -89.807288)
		(end 355.618796 -91.160854)
		(width 0.13208)
		(layer "F.Cu")
		(net "BIC_I2C9_SSD_MUX1_A1")
	)
	(segment
		(start 356.010972 -89.415112)
		(end 355.618796 -89.807288)
		(width 0.13208)
		(layer "F.Cu")
		(net "BIC_I2C9_SSD_MUX1_A1")
	)
	(segment
		(start 353.193604 -90.162126)
		(end 351.263712 -90.162126)
		(width 0.13208)
		(layer "F.Cu")
		(net "BIC_I2C9_SSD_MUX1_A1")
	)
	(via
		(at 354.514404 -91.574366)
		(size 0.508)
		(drill 0.254)
		(layers "F.Cu" "B.Cu")
		(net "BIC_I2C9_SSD_MUX1_A1")
	)
	(segment
		(start 260.6548 -21.847048)
		(end 259.860542 -21.05279)
		(width 0.13208)
		(layer "F.Cu")
		(net "SMB_SSD8_ISO_EN")
	)
	(segment
		(start 260.6548 -22.561296)
		(end 260.6548 -21.847048)
		(width 0.13208)
		(layer "F.Cu")
		(net "SMB_SSD8_ISO_EN")
	)
	(segment
		(start 259.860542 -21.05279)
		(end 259.860542 -20.789392)
		(width 0.13208)
		(layer "F.Cu")
		(net "SMB_SSD8_ISO_EN")
	)
	(via
		(at 260.6548 -21.847048)
		(size 0.508)
		(drill 0.254)
		(layers "F.Cu" "B.Cu")
		(net "SMB_SSD8_ISO_EN")
	)
	(segment
		(start 180.567584 -22.3901)
		(end 181.193694 -23.01621)
		(width 0.13208)
		(layer "F.Cu")
		(net "SMB_ISO_SSD6_R_SCL")
	)
	(segment
		(start 190.758318 -18.44421)
		(end 190.76543 -18.437098)
		(width 0.13208)
		(layer "F.Cu")
		(net "SMB_ISO_SSD6_R_SCL")
	)
	(segment
		(start 178.764946 -22.3901)
		(end 180.567584 -22.3901)
		(width 0.13208)
		(layer "F.Cu")
		(net "SMB_ISO_SSD6_R_SCL")
	)
	(segment
		(start 190.76543 -18.437098)
		(end 191.367918 -18.437098)
		(width 0.13208)
		(layer "F.Cu")
		(net "SMB_ISO_SSD6_R_SCL")
	)
	(segment
		(start 191.367918 -18.437098)
		(end 191.367918 -18.430748)
		(width 0.13208)
		(layer "F.Cu")
		(net "SMB_ISO_SSD6_R_SCL")
	)
	(via
		(at 190.758318 -18.44421)
		(size 0.508)
		(drill 0.254)
		(layers "F.Cu" "B.Cu")
		(net "SMB_ISO_SSD6_R_SCL")
	)
	(via
		(at 181.193694 -23.01621)
		(size 0.508)
		(drill 0.254)
		(layers "F.Cu" "B.Cu")
		(net "SMB_ISO_SSD6_R_SCL")
	)
	(segment
		(start 191.327024 -19.012916)
		(end 191.327024 -21.651976)
		(width 0.15494)
		(layer "In5.Cu")
		(net "SMB_ISO_SSD6_R_SCL")
	)
	(segment
		(start 191.327024 -21.651976)
		(end 189.96279 -23.01621)
		(width 0.15494)
		(layer "In5.Cu")
		(net "SMB_ISO_SSD6_R_SCL")
	)
	(segment
		(start 190.758318 -18.44421)
		(end 191.327024 -19.012916)
		(width 0.15494)
		(layer "In5.Cu")
		(net "SMB_ISO_SSD6_R_SCL")
	)
	(segment
		(start 189.96279 -23.01621)
		(end 181.193694 -23.01621)
		(width 0.15494)
		(layer "In5.Cu")
		(net "SMB_ISO_SSD6_R_SCL")
	)
	(segment
		(start 127.633222 -125.962918)
		(end 127.701294 -125.894846)
		(width 0.13208)
		(layer "F.Cu")
		(net "PWRGD_P3V3_NIC2")
	)
	(segment
		(start 127.701294 -125.894846)
		(end 128.33096 -125.894846)
		(width 0.13208)
		(layer "F.Cu")
		(net "PWRGD_P3V3_NIC2")
	)
	(segment
		(start 127.56515 -125.894846)
		(end 127.633222 -125.962918)
		(width 0.13208)
		(layer "F.Cu")
		(net "PWRGD_P3V3_NIC2")
	)
	(segment
		(start 126.610364 -125.979428)
		(end 127.085852 -125.979428)
		(width 0.13208)
		(layer "F.Cu")
		(net "PWRGD_P3V3_NIC2")
	)
	(segment
		(start 127.170434 -125.894846)
		(end 127.56515 -125.894846)
		(width 0.13208)
		(layer "F.Cu")
		(net "PWRGD_P3V3_NIC2")
	)
	(segment
		(start 127.085852 -125.979428)
		(end 127.170434 -125.894846)
		(width 0.13208)
		(layer "F.Cu")
		(net "PWRGD_P3V3_NIC2")
	)
	(segment
		(start 126.610364 -124.963428)
		(end 126.610364 -125.979428)
		(width 0.13208)
		(layer "F.Cu")
		(net "PWRGD_P3V3_NIC2")
	)
	(via
		(at 127.633222 -125.962918)
		(size 0.508)
		(drill 0.254)
		(layers "F.Cu" "B.Cu")
		(net "PWRGD_P3V3_NIC2")
	)
	(segment
		(start 188.099954 -291.149786)
		(end 187.624974 -290.674806)
		(width 0.13208)
		(layer "F.Cu")
		(net "UART_PEX1_CLI_BUF_RX")
	)
	(via
		(at 147.614132 -209.162142)
		(size 0.508)
		(drill 0.254)
		(layers "F.Cu" "B.Cu")
		(net "UART_PEX1_CLI_BUF_RX")
	)
	(via
		(at 187.624974 -290.674806)
		(size 0.4064)
		(drill 0.2032)
		(layers "F.Cu" "B.Cu")
		(net "UART_PEX1_CLI_BUF_RX")
	)
	(via
		(at 151.779224 -245.320566)
		(size 0.508)
		(drill 0.254)
		(layers "F.Cu" "B.Cu")
		(net "UART_PEX1_CLI_BUF_RX")
	)
	(segment
		(start 155.39212 -248.646442)
		(end 152.395682 -245.650004)
		(width 0.13208)
		(layer "B.Cu")
		(net "UART_PEX1_CLI_BUF_RX")
	)
	(segment
		(start 152.395682 -245.650004)
		(end 152.108662 -245.650004)
		(width 0.13208)
		(layer "B.Cu")
		(net "UART_PEX1_CLI_BUF_RX")
	)
	(segment
		(start 190.39332 -287.8582)
		(end 190.52032 -287.7312)
		(width 0.13208)
		(layer "B.Cu")
		(net "UART_PEX1_CLI_BUF_RX")
	)
	(segment
		(start 188.0489 -288.536126)
		(end 188.225938 -288.359088)
		(width 0.13208)
		(layer "B.Cu")
		(net "UART_PEX1_CLI_BUF_RX")
	)
	(segment
		(start 146.685254 -209.162142)
		(end 147.614132 -209.162142)
		(width 0.13208)
		(layer "B.Cu")
		(net "UART_PEX1_CLI_BUF_RX")
	)
	(segment
		(start 188.0489 -290.25088)
		(end 188.0489 -288.536126)
		(width 0.13208)
		(layer "B.Cu")
		(net "UART_PEX1_CLI_BUF_RX")
	)
	(segment
		(start 188.225938 -288.359088)
		(end 189.033912 -288.359088)
		(width 0.13208)
		(layer "B.Cu")
		(net "UART_PEX1_CLI_BUF_RX")
	)
	(segment
		(start 190.52032 -271.738598)
		(end 167.428164 -248.646442)
		(width 0.13208)
		(layer "B.Cu")
		(net "UART_PEX1_CLI_BUF_RX")
	)
	(segment
		(start 189.033912 -288.359088)
		(end 189.5348 -287.8582)
		(width 0.13208)
		(layer "B.Cu")
		(net "UART_PEX1_CLI_BUF_RX")
	)
	(segment
		(start 146.685254 -208.184242)
		(end 146.685254 -209.162142)
		(width 0.13208)
		(layer "B.Cu")
		(net "UART_PEX1_CLI_BUF_RX")
	)
	(segment
		(start 190.52032 -287.7312)
		(end 190.52032 -271.738598)
		(width 0.13208)
		(layer "B.Cu")
		(net "UART_PEX1_CLI_BUF_RX")
	)
	(segment
		(start 152.108662 -245.650004)
		(end 151.779224 -245.320566)
		(width 0.13208)
		(layer "B.Cu")
		(net "UART_PEX1_CLI_BUF_RX")
	)
	(segment
		(start 189.5348 -287.8582)
		(end 190.39332 -287.8582)
		(width 0.13208)
		(layer "B.Cu")
		(net "UART_PEX1_CLI_BUF_RX")
	)
	(segment
		(start 187.624974 -290.674806)
		(end 188.0489 -290.25088)
		(width 0.13208)
		(layer "B.Cu")
		(net "UART_PEX1_CLI_BUF_RX")
	)
	(segment
		(start 167.428164 -248.646442)
		(end 155.39212 -248.646442)
		(width 0.13208)
		(layer "B.Cu")
		(net "UART_PEX1_CLI_BUF_RX")
	)
	(segment
		(start 142.350998 -241.960654)
		(end 142.350998 -233.941112)
		(width 0.15494)
		(layer "In5.Cu")
		(net "UART_PEX1_CLI_BUF_RX")
	)
	(segment
		(start 147.31238 -244.958616)
		(end 146.577558 -244.223794)
		(width 0.15494)
		(layer "In5.Cu")
		(net "UART_PEX1_CLI_BUF_RX")
	)
	(segment
		(start 151.779224 -245.320566)
		(end 151.449786 -245.320566)
		(width 0.15494)
		(layer "In5.Cu")
		(net "UART_PEX1_CLI_BUF_RX")
	)
	(segment
		(start 146.48307 -224.249488)
		(end 147.628864 -223.103694)
		(width 0.15494)
		(layer "In5.Cu")
		(net "UART_PEX1_CLI_BUF_RX")
	)
	(segment
		(start 144.614138 -244.223794)
		(end 142.350998 -241.960654)
		(width 0.15494)
		(layer "In5.Cu")
		(net "UART_PEX1_CLI_BUF_RX")
	)
	(segment
		(start 147.628864 -209.176874)
		(end 147.614132 -209.162142)
		(width 0.15494)
		(layer "In5.Cu")
		(net "UART_PEX1_CLI_BUF_RX")
	)
	(segment
		(start 151.449786 -245.320566)
		(end 151.087836 -244.958616)
		(width 0.15494)
		(layer "In5.Cu")
		(net "UART_PEX1_CLI_BUF_RX")
	)
	(segment
		(start 142.350998 -233.941112)
		(end 144.845532 -231.446578)
		(width 0.15494)
		(layer "In5.Cu")
		(net "UART_PEX1_CLI_BUF_RX")
	)
	(segment
		(start 146.577558 -244.223794)
		(end 144.614138 -244.223794)
		(width 0.15494)
		(layer "In5.Cu")
		(net "UART_PEX1_CLI_BUF_RX")
	)
	(segment
		(start 144.845532 -228.835966)
		(end 146.48307 -227.198428)
		(width 0.15494)
		(layer "In5.Cu")
		(net "UART_PEX1_CLI_BUF_RX")
	)
	(segment
		(start 146.48307 -227.198428)
		(end 146.48307 -224.249488)
		(width 0.15494)
		(layer "In5.Cu")
		(net "UART_PEX1_CLI_BUF_RX")
	)
	(segment
		(start 144.845532 -231.446578)
		(end 144.845532 -228.835966)
		(width 0.15494)
		(layer "In5.Cu")
		(net "UART_PEX1_CLI_BUF_RX")
	)
	(segment
		(start 147.628864 -223.103694)
		(end 147.628864 -209.176874)
		(width 0.15494)
		(layer "In5.Cu")
		(net "UART_PEX1_CLI_BUF_RX")
	)
	(segment
		(start 151.087836 -244.958616)
		(end 147.31238 -244.958616)
		(width 0.15494)
		(layer "In5.Cu")
		(net "UART_PEX1_CLI_BUF_RX")
	)
	(segment
		(start 133.471158 -179.900326)
		(end 133.077966 -179.422552)
		(width 0.13208)
		(layer "F.Cu")
		(net "FM_DB2000QL_SMB_SA1")
	)
	(via
		(at 133.077966 -179.422552)
		(size 0.49022)
		(drill 0.254)
		(layers "F.Cu" "B.Cu")
		(net "FM_DB2000QL_SMB_SA1")
	)
	(via
		(at 134.277862 -180.073808)
		(size 0.6604)
		(drill 0.3302)
		(layers "F.Cu" "B.Cu")
		(net "FM_DB2000QL_SMB_SA1")
	)
	(segment
		(start 136.403842 -181.652418)
		(end 135.387842 -181.652418)
		(width 0.13208)
		(layer "B.Cu")
		(net "FM_DB2000QL_SMB_SA1")
	)
	(segment
		(start 135.387842 -181.183788)
		(end 134.277862 -180.073808)
		(width 0.13208)
		(layer "B.Cu")
		(net "FM_DB2000QL_SMB_SA1")
	)
	(segment
		(start 133.729222 -180.073808)
		(end 133.077966 -179.422552)
		(width 0.13208)
		(layer "B.Cu")
		(net "FM_DB2000QL_SMB_SA1")
	)
	(segment
		(start 135.387842 -181.652418)
		(end 135.387842 -181.183788)
		(width 0.13208)
		(layer "B.Cu")
		(net "FM_DB2000QL_SMB_SA1")
	)
	(segment
		(start 134.277862 -180.073808)
		(end 133.729222 -180.073808)
		(width 0.13208)
		(layer "B.Cu")
		(net "FM_DB2000QL_SMB_SA1")
	)
	(segment
		(start 339.495638 -90.14079)
		(end 339.495638 -89.714324)
		(width 0.13462)
		(layer "F.Cu")
		(net "CLK_100M_DB800ZL_SSD15_DP")
	)
	(segment
		(start 339.44052 -90.195908)
		(end 339.495638 -90.14079)
		(width 0.13462)
		(layer "F.Cu")
		(net "CLK_100M_DB800ZL_SSD15_DP")
	)
	(segment
		(start 339.752686 -92.71889)
		(end 339.44052 -92.406724)
		(width 0.13462)
		(layer "F.Cu")
		(net "CLK_100M_DB800ZL_SSD15_DP")
	)
	(segment
		(start 339.44052 -92.406724)
		(end 339.44052 -90.195908)
		(width 0.13462)
		(layer "F.Cu")
		(net "CLK_100M_DB800ZL_SSD15_DP")
	)
	(segment
		(start 112.261396 -330.96708)
		(end 109.99343 -331.90688)
		(width 0.13462)
		(layer "B.Cu")
		(net "CLK_100M_MB_0_R_DN")
	)
	(segment
		(start 112.739424 -330.96708)
		(end 112.261396 -330.96708)
		(width 0.13462)
		(layer "B.Cu")
		(net "CLK_100M_MB_0_R_DN")
	)
	(segment
		(start 108.996734 -331.91958)
		(end 108.877608 -331.800454)
		(width 0.13462)
		(layer "B.Cu")
		(net "CLK_100M_MB_0_R_DN")
	)
	(segment
		(start 109.027722 -331.90688)
		(end 109.015022 -331.91958)
		(width 0.13462)
		(layer "B.Cu")
		(net "CLK_100M_MB_0_R_DN")
	)
	(segment
		(start 109.99343 -331.90688)
		(end 109.027722 -331.90688)
		(width 0.13462)
		(layer "B.Cu")
		(net "CLK_100M_MB_0_R_DN")
	)
	(segment
		(start 108.877608 -331.800454)
		(end 108.689394 -331.800454)
		(width 0.13462)
		(layer "B.Cu")
		(net "CLK_100M_MB_0_R_DN")
	)
	(segment
		(start 113.114074 -330.59243)
		(end 112.739424 -330.96708)
		(width 0.13462)
		(layer "B.Cu")
		(net "CLK_100M_MB_0_R_DN")
	)
	(segment
		(start 109.015022 -331.91958)
		(end 108.996734 -331.91958)
		(width 0.13462)
		(layer "B.Cu")
		(net "CLK_100M_MB_0_R_DN")
	)
	(segment
		(start 280.449782 -309.199788)
		(end 280.924762 -308.724808)
		(width 0.13208)
		(layer "F.Cu")
		(net "PEX2_DBG_MODE1")
	)
	(segment
		(start 266.33678 -307.698394)
		(end 266.337034 -307.698394)
		(width 0.13208)
		(layer "F.Cu")
		(net "PEX2_DBG_MODE1")
	)
	(segment
		(start 266.68222 -310.237378)
		(end 266.68222 -309.480458)
		(width 0.13208)
		(layer "F.Cu")
		(net "PEX2_DBG_MODE1")
	)
	(segment
		(start 265.618468 -308.416706)
		(end 266.33678 -307.698394)
		(width 0.13208)
		(layer "F.Cu")
		(net "PEX2_DBG_MODE1")
	)
	(segment
		(start 266.68222 -309.480458)
		(end 265.618468 -308.416706)
		(width 0.13208)
		(layer "F.Cu")
		(net "PEX2_DBG_MODE1")
	)
	(via
		(at 266.68222 -310.237378)
		(size 0.508)
		(drill 0.254)
		(layers "F.Cu" "B.Cu")
		(net "PEX2_DBG_MODE1")
	)
	(via
		(at 280.924762 -308.724808)
		(size 0.4064)
		(drill 0.2032)
		(layers "F.Cu" "B.Cu")
		(net "PEX2_DBG_MODE1")
	)
	(segment
		(start 267.242798 -309.6768)
		(end 277.755096 -309.6768)
		(width 0.13208)
		(layer "B.Cu")
		(net "PEX2_DBG_MODE1")
	)
	(segment
		(start 266.68222 -310.237378)
		(end 267.242798 -309.6768)
		(width 0.13208)
		(layer "B.Cu")
		(net "PEX2_DBG_MODE1")
	)
	(segment
		(start 277.755096 -309.6768)
		(end 278.237696 -309.1942)
		(width 0.13208)
		(layer "B.Cu")
		(net "PEX2_DBG_MODE1")
	)
	(segment
		(start 278.237696 -309.1942)
		(end 280.45537 -309.1942)
		(width 0.13208)
		(layer "B.Cu")
		(net "PEX2_DBG_MODE1")
	)
	(segment
		(start 280.45537 -309.1942)
		(end 280.924762 -308.724808)
		(width 0.13208)
		(layer "B.Cu")
		(net "PEX2_DBG_MODE1")
	)
	(segment
		(start 353.320604 -92.623386)
		(end 353.320604 -91.788234)
		(width 0.13208)
		(layer "F.Cu")
		(net "BIC_I2C9_SSD_MUX1_A0")
	)
	(segment
		(start 353.193604 -91.305126)
		(end 351.263712 -91.305126)
		(width 0.13208)
		(layer "F.Cu")
		(net "BIC_I2C9_SSD_MUX1_A0")
	)
	(segment
		(start 351.263712 -91.305126)
		(end 350.780604 -91.788234)
		(width 0.13208)
		(layer "F.Cu")
		(net "BIC_I2C9_SSD_MUX1_A0")
	)
	(segment
		(start 353.541584 -92.844366)
		(end 353.320604 -92.623386)
		(width 0.13208)
		(layer "F.Cu")
		(net "BIC_I2C9_SSD_MUX1_A0")
	)
	(segment
		(start 356.707948 -90.065098)
		(end 356.707948 -91.183714)
		(width 0.13208)
		(layer "F.Cu")
		(net "BIC_I2C9_SSD_MUX1_A0")
	)
	(segment
		(start 355.047296 -92.844366)
		(end 353.541584 -92.844366)
		(width 0.13208)
		(layer "F.Cu")
		(net "BIC_I2C9_SSD_MUX1_A0")
	)
	(segment
		(start 353.320604 -91.432126)
		(end 353.193604 -91.305126)
		(width 0.13208)
		(layer "F.Cu")
		(net "BIC_I2C9_SSD_MUX1_A0")
	)
	(segment
		(start 356.707948 -91.183714)
		(end 355.047296 -92.844366)
		(width 0.13208)
		(layer "F.Cu")
		(net "BIC_I2C9_SSD_MUX1_A0")
	)
	(segment
		(start 353.320604 -91.788234)
		(end 353.320604 -91.432126)
		(width 0.13208)
		(layer "F.Cu")
		(net "BIC_I2C9_SSD_MUX1_A0")
	)
	(via
		(at 353.541584 -92.844366)
		(size 0.508)
		(drill 0.254)
		(layers "F.Cu" "B.Cu")
		(net "BIC_I2C9_SSD_MUX1_A0")
	)
	(segment
		(start 256.821686 -18.990818)
		(end 256.267966 -18.437098)
		(width 0.13208)
		(layer "F.Cu")
		(net "SMB_ISO_SSD8_SCL")
	)
	(segment
		(start 256.224278 -18.437098)
		(end 256.267966 -18.437098)
		(width 0.13208)
		(layer "F.Cu")
		(net "SMB_ISO_SSD8_SCL")
	)
	(segment
		(start 258.659376 -23.355554)
		(end 258.659376 -23.965154)
		(width 0.13208)
		(layer "F.Cu")
		(net "SMB_ISO_SSD8_SCL")
	)
	(segment
		(start 255.456436 -17.419574)
		(end 255.456436 -17.669256)
		(width 0.13208)
		(layer "F.Cu")
		(net "SMB_ISO_SSD8_SCL")
	)
	(segment
		(start 258.485386 -16.439388)
		(end 258.485386 -18.476214)
		(width 0.13208)
		(layer "F.Cu")
		(net "SMB_ISO_SSD8_SCL")
	)
	(segment
		(start 258.485386 -16.439388)
		(end 258.485386 -15.370302)
		(width 0.13208)
		(layer "F.Cu")
		(net "SMB_ISO_SSD8_SCL")
	)
	(segment
		(start 258.485386 -18.476214)
		(end 257.970782 -18.990818)
		(width 0.13208)
		(layer "F.Cu")
		(net "SMB_ISO_SSD8_SCL")
	)
	(segment
		(start 255.456436 -17.669256)
		(end 256.224278 -18.437098)
		(width 0.13208)
		(layer "F.Cu")
		(net "SMB_ISO_SSD8_SCL")
	)
	(segment
		(start 257.970782 -18.990818)
		(end 256.821686 -18.990818)
		(width 0.13208)
		(layer "F.Cu")
		(net "SMB_ISO_SSD8_SCL")
	)
	(via
		(at 258.485386 -15.370302)
		(size 0.508)
		(drill 0.254)
		(layers "F.Cu" "B.Cu")
		(net "SMB_ISO_SSD8_SCL")
	)
	(via
		(at 258.659376 -23.965154)
		(size 0.508)
		(drill 0.254)
		(layers "F.Cu" "B.Cu")
		(net "SMB_ISO_SSD8_SCL")
	)
	(segment
		(start 258.659376 -23.965154)
		(end 259.925058 -22.699472)
		(width 0.13208)
		(layer "B.Cu")
		(net "SMB_ISO_SSD8_SCL")
	)
	(segment
		(start 259.925058 -22.699472)
		(end 259.925058 -16.809974)
		(width 0.13208)
		(layer "B.Cu")
		(net "SMB_ISO_SSD8_SCL")
	)
	(segment
		(start 259.925058 -16.809974)
		(end 258.485386 -15.370302)
		(width 0.13208)
		(layer "B.Cu")
		(net "SMB_ISO_SSD8_SCL")
	)
	(segment
		(start 62.664848 -22.3901)
		(end 64.467486 -22.3901)
		(width 0.13208)
		(layer "F.Cu")
		(net "SMB_ISO_SSD2_R_SCL")
	)
	(segment
		(start 74.65822 -18.44421)
		(end 74.665332 -18.437098)
		(width 0.13208)
		(layer "F.Cu")
		(net "SMB_ISO_SSD2_R_SCL")
	)
	(segment
		(start 64.467486 -22.3901)
		(end 65.093596 -23.01621)
		(width 0.13208)
		(layer "F.Cu")
		(net "SMB_ISO_SSD2_R_SCL")
	)
	(segment
		(start 74.665332 -18.437098)
		(end 75.26782 -18.437098)
		(width 0.13208)
		(layer "F.Cu")
		(net "SMB_ISO_SSD2_R_SCL")
	)
	(via
		(at 74.65822 -18.44421)
		(size 0.508)
		(drill 0.254)
		(layers "F.Cu" "B.Cu")
		(net "SMB_ISO_SSD2_R_SCL")
	)
	(via
		(at 65.093596 -23.01621)
		(size 0.508)
		(drill 0.254)
		(layers "F.Cu" "B.Cu")
		(net "SMB_ISO_SSD2_R_SCL")
	)
	(segment
		(start 75.226926 -19.012916)
		(end 75.226926 -21.472144)
		(width 0.15494)
		(layer "In5.Cu")
		(net "SMB_ISO_SSD2_R_SCL")
	)
	(segment
		(start 74.65822 -18.44421)
		(end 75.226926 -19.012916)
		(width 0.15494)
		(layer "In5.Cu")
		(net "SMB_ISO_SSD2_R_SCL")
	)
	(segment
		(start 73.68286 -23.01621)
		(end 65.093596 -23.01621)
		(width 0.15494)
		(layer "In5.Cu")
		(net "SMB_ISO_SSD2_R_SCL")
	)
	(segment
		(start 75.226926 -21.472144)
		(end 73.68286 -23.01621)
		(width 0.15494)
		(layer "In5.Cu")
		(net "SMB_ISO_SSD2_R_SCL")
	)
	(segment
		(start 339.75294 -81.007712)
		(end 339.44052 -81.320132)
		(width 0.13462)
		(layer "F.Cu")
		(net "CLK_100M_DB800ZL_SSD10_DN")
	)
	(segment
		(start 339.495638 -83.386676)
		(end 339.495638 -83.814412)
		(width 0.13462)
		(layer "F.Cu")
		(net "CLK_100M_DB800ZL_SSD10_DN")
	)
	(segment
		(start 339.44052 -81.320132)
		(end 339.44052 -83.331558)
		(width 0.13462)
		(layer "F.Cu")
		(net "CLK_100M_DB800ZL_SSD10_DN")
	)
	(segment
		(start 339.44052 -83.331558)
		(end 339.495638 -83.386676)
		(width 0.13462)
		(layer "F.Cu")
		(net "CLK_100M_DB800ZL_SSD10_DN")
	)
	(segment
		(start 250.96343 -90.376248)
		(end 252.752606 -90.376248)
		(width 0.13208)
		(layer "F.Cu")
		(net "FM_CK440Q_DEV_25M_EN")
	)
	(segment
		(start 250.96343 -90.376248)
		(end 250.96343 -91.696286)
		(width 0.13208)
		(layer "F.Cu")
		(net "FM_CK440Q_DEV_25M_EN")
	)
	(segment
		(start 255.293622 -87.66937)
		(end 255.406652 -87.55634)
		(width 0.13208)
		(layer "F.Cu")
		(net "FM_CK440Q_DEV_25M_EN")
	)
	(segment
		(start 253.720854 -89.408)
		(end 254.5842 -89.408)
		(width 0.13208)
		(layer "F.Cu")
		(net "FM_CK440Q_DEV_25M_EN")
	)
	(segment
		(start 252.752606 -90.376248)
		(end 253.720854 -89.408)
		(width 0.13208)
		(layer "F.Cu")
		(net "FM_CK440Q_DEV_25M_EN")
	)
	(segment
		(start 248.93143 -91.696286)
		(end 249.94743 -91.696286)
		(width 0.13208)
		(layer "F.Cu")
		(net "FM_CK440Q_DEV_25M_EN")
	)
	(segment
		(start 254.5842 -89.408)
		(end 255.293622 -88.698578)
		(width 0.13208)
		(layer "F.Cu")
		(net "FM_CK440Q_DEV_25M_EN")
	)
	(segment
		(start 249.94743 -91.696286)
		(end 250.96343 -91.696286)
		(width 0.13208)
		(layer "F.Cu")
		(net "FM_CK440Q_DEV_25M_EN")
	)
	(segment
		(start 255.293622 -88.698578)
		(end 255.293622 -87.66937)
		(width 0.13208)
		(layer "F.Cu")
		(net "FM_CK440Q_DEV_25M_EN")
	)
	(segment
		(start 255.406652 -87.55634)
		(end 255.801876 -87.55634)
		(width 0.13208)
		(layer "F.Cu")
		(net "FM_CK440Q_DEV_25M_EN")
	)
	(via
		(at 250.96343 -90.376248)
		(size 0.762)
		(drill 0.381)
		(layers "F.Cu" "B.Cu")
		(net "FM_CK440Q_DEV_25M_EN")
	)
	(segment
		(start 332.54061 -261.111746)
		(end 319.058798 -261.111746)
		(width 0.13208)
		(layer "F.Cu")
		(net "PEX2_MODE_SEL2")
	)
	(segment
		(start 365.660686 -219.195904)
		(end 361.870498 -219.195904)
		(width 0.13208)
		(layer "F.Cu")
		(net "PEX2_MODE_SEL2")
	)
	(segment
		(start 269.249398 -249.035824)
		(end 259.568696 -249.035824)
		(width 0.13208)
		(layer "F.Cu")
		(net "PEX2_MODE_SEL2")
	)
	(segment
		(start 360.65714 -220.409262)
		(end 360.65714 -227.634292)
		(width 0.13208)
		(layer "F.Cu")
		(net "PEX2_MODE_SEL2")
	)
	(segment
		(start 258.574286 -251.158502)
		(end 258.574286 -250.470924)
		(width 0.13208)
		(layer "F.Cu")
		(net "PEX2_MODE_SEL2")
	)
	(segment
		(start 360.65714 -227.634292)
		(end 360.145838 -228.145594)
		(width 0.13208)
		(layer "F.Cu")
		(net "PEX2_MODE_SEL2")
	)
	(segment
		(start 382.254252 -218.366594)
		(end 381.588264 -217.700606)
		(width 0.13208)
		(layer "F.Cu")
		(net "PEX2_MODE_SEL2")
	)
	(segment
		(start 292.934898 -265.459464)
		(end 275.730208 -248.254774)
		(width 0.13208)
		(layer "F.Cu")
		(net "PEX2_MODE_SEL2")
	)
	(segment
		(start 275.730208 -248.254774)
		(end 270.030448 -248.254774)
		(width 0.13208)
		(layer "F.Cu")
		(net "PEX2_MODE_SEL2")
	)
	(segment
		(start 360.520234 -230.42118)
		(end 360.520234 -233.132122)
		(width 0.13208)
		(layer "F.Cu")
		(net "PEX2_MODE_SEL2")
	)
	(segment
		(start 361.870498 -219.195904)
		(end 360.65714 -220.409262)
		(width 0.13208)
		(layer "F.Cu")
		(net "PEX2_MODE_SEL2")
	)
	(segment
		(start 258.574286 -251.956824)
		(end 258.574286 -251.158502)
		(width 0.13208)
		(layer "F.Cu")
		(net "PEX2_MODE_SEL2")
	)
	(segment
		(start 291.84981 -283.549852)
		(end 292.32479 -284.024832)
		(width 0.1651)
		(layer "F.Cu")
		(net "PEX2_MODE_SEL2")
	)
	(segment
		(start 381.588264 -217.700606)
		(end 367.155984 -217.700606)
		(width 0.13208)
		(layer "F.Cu")
		(net "PEX2_MODE_SEL2")
	)
	(segment
		(start 367.155984 -217.700606)
		(end 365.660686 -219.195904)
		(width 0.13208)
		(layer "F.Cu")
		(net "PEX2_MODE_SEL2")
	)
	(segment
		(start 319.058798 -261.111746)
		(end 314.71108 -265.459464)
		(width 0.13208)
		(layer "F.Cu")
		(net "PEX2_MODE_SEL2")
	)
	(segment
		(start 360.145838 -230.046784)
		(end 360.520234 -230.42118)
		(width 0.13208)
		(layer "F.Cu")
		(net "PEX2_MODE_SEL2")
	)
	(segment
		(start 270.030448 -248.254774)
		(end 269.249398 -249.035824)
		(width 0.13208)
		(layer "F.Cu")
		(net "PEX2_MODE_SEL2")
	)
	(segment
		(start 360.520234 -233.132122)
		(end 332.54061 -261.111746)
		(width 0.13208)
		(layer "F.Cu")
		(net "PEX2_MODE_SEL2")
	)
	(segment
		(start 408.529282 -201.962258)
		(end 409.415742 -201.962258)
		(width 0.13208)
		(layer "F.Cu")
		(net "PEX2_MODE_SEL2")
	)
	(segment
		(start 360.145838 -228.145594)
		(end 360.145838 -230.046784)
		(width 0.13208)
		(layer "F.Cu")
		(net "PEX2_MODE_SEL2")
	)
	(segment
		(start 314.71108 -265.459464)
		(end 292.934898 -265.459464)
		(width 0.13208)
		(layer "F.Cu")
		(net "PEX2_MODE_SEL2")
	)
	(via
		(at 382.254252 -218.366594)
		(size 0.508)
		(drill 0.254)
		(layers "F.Cu" "B.Cu")
		(net "PEX2_MODE_SEL2")
	)
	(via
		(at 409.415742 -201.962258)
		(size 0.508)
		(drill 0.254)
		(layers "F.Cu" "B.Cu")
		(net "PEX2_MODE_SEL2")
	)
	(via
		(at 259.568696 -249.035824)
		(size 0.508)
		(drill 0.254)
		(layers "F.Cu" "B.Cu")
		(net "PEX2_MODE_SEL2")
	)
	(via
		(at 258.574286 -251.158502)
		(size 0.508)
		(drill 0.254)
		(layers "F.Cu" "B.Cu")
		(net "PEX2_MODE_SEL2")
	)
	(via
		(at 292.32479 -284.024832)
		(size 0.4064)
		(drill 0.2032)
		(layers "F.Cu" "B.Cu")
		(net "PEX2_MODE_SEL2")
	)
	(segment
		(start 257.05435 -251.614178)
		(end 257.05435 -250.831096)
		(width 0.13208)
		(layer "B.Cu")
		(net "PEX2_MODE_SEL2")
	)
	(segment
		(start 288.590228 -268.44498)
		(end 288.911538 -268.76629)
		(width 0.13208)
		(layer "B.Cu")
		(net "PEX2_MODE_SEL2")
	)
	(segment
		(start 258.416044 -250.589288)
		(end 258.574286 -250.74753)
		(width 0.13208)
		(layer "B.Cu")
		(net "PEX2_MODE_SEL2")
	)
	(segment
		(start 408.926792 -201.962258)
		(end 409.415742 -201.962258)
		(width 0.13208)
		(layer "B.Cu")
		(net "PEX2_MODE_SEL2")
	)
	(segment
		(start 258.8133 -249.817636)
		(end 256.10058 -249.817636)
		(width 0.13208)
		(layer "B.Cu")
		(net "PEX2_MODE_SEL2")
	)
	(segment
		(start 393.220448 -202.753214)
		(end 408.135836 -202.753214)
		(width 0.13208)
		(layer "B.Cu")
		(net "PEX2_MODE_SEL2")
	)
	(segment
		(start 291.380164 -271.226026)
		(end 291.380164 -283.080206)
		(width 0.13208)
		(layer "B.Cu")
		(net "PEX2_MODE_SEL2")
	)
	(segment
		(start 258.058666 -252.316234)
		(end 258.058666 -254.07874)
		(width 0.13208)
		(layer "B.Cu")
		(net "PEX2_MODE_SEL2")
	)
	(segment
		(start 256.10058 -249.817636)
		(end 255.774444 -250.143772)
		(width 0.13208)
		(layer "B.Cu")
		(net "PEX2_MODE_SEL2")
	)
	(segment
		(start 259.739384 -257.00736)
		(end 260.407912 -257.675888)
		(width 0.13208)
		(layer "B.Cu")
		(net "PEX2_MODE_SEL2")
	)
	(segment
		(start 259.739384 -255.759458)
		(end 259.739384 -257.00736)
		(width 0.13208)
		(layer "B.Cu")
		(net "PEX2_MODE_SEL2")
	)
	(segment
		(start 257.05435 -250.831096)
		(end 257.296158 -250.589288)
		(width 0.13208)
		(layer "B.Cu")
		(net "PEX2_MODE_SEL2")
	)
	(segment
		(start 382.254252 -217.668856)
		(end 385.04749 -214.875618)
		(width 0.13208)
		(layer "B.Cu")
		(net "PEX2_MODE_SEL2")
	)
	(segment
		(start 288.590228 -268.43609)
		(end 288.590228 -268.44498)
		(width 0.13208)
		(layer "B.Cu")
		(net "PEX2_MODE_SEL2")
	)
	(segment
		(start 385.04749 -210.926172)
		(end 393.220448 -202.753214)
		(width 0.13208)
		(layer "B.Cu")
		(net "PEX2_MODE_SEL2")
	)
	(segment
		(start 257.296158 -250.589288)
		(end 258.416044 -250.589288)
		(width 0.13208)
		(layer "B.Cu")
		(net "PEX2_MODE_SEL2")
	)
	(segment
		(start 264.700766 -257.675888)
		(end 265.682476 -258.657598)
		(width 0.13208)
		(layer "B.Cu")
		(net "PEX2_MODE_SEL2")
	)
	(segment
		(start 255.774444 -250.143772)
		(end 255.774444 -251.41555)
		(width 0.13208)
		(layer "B.Cu")
		(net "PEX2_MODE_SEL2")
	)
	(segment
		(start 289.577526 -269.414498)
		(end 289.898836 -269.735808)
		(width 0.13208)
		(layer "B.Cu")
		(net "PEX2_MODE_SEL2")
	)
	(segment
		(start 289.898836 -269.744698)
		(end 291.380164 -271.226026)
		(width 0.13208)
		(layer "B.Cu")
		(net "PEX2_MODE_SEL2")
	)
	(segment
		(start 256.81813 -251.850398)
		(end 257.05435 -251.614178)
		(width 0.13208)
		(layer "B.Cu")
		(net "PEX2_MODE_SEL2")
	)
	(segment
		(start 265.682476 -258.657598)
		(end 278.811736 -258.657598)
		(width 0.13208)
		(layer "B.Cu")
		(net "PEX2_MODE_SEL2")
	)
	(segment
		(start 289.568636 -269.414498)
		(end 289.577526 -269.414498)
		(width 0.13208)
		(layer "B.Cu")
		(net "PEX2_MODE_SEL2")
	)
	(segment
		(start 408.135836 -202.753214)
		(end 408.926792 -201.962258)
		(width 0.13208)
		(layer "B.Cu")
		(net "PEX2_MODE_SEL2")
	)
	(segment
		(start 258.574286 -251.800614)
		(end 258.058666 -252.316234)
		(width 0.13208)
		(layer "B.Cu")
		(net "PEX2_MODE_SEL2")
	)
	(segment
		(start 278.811736 -258.657598)
		(end 288.590228 -268.43609)
		(width 0.13208)
		(layer "B.Cu")
		(net "PEX2_MODE_SEL2")
	)
	(segment
		(start 258.574286 -250.74753)
		(end 258.574286 -251.158502)
		(width 0.13208)
		(layer "B.Cu")
		(net "PEX2_MODE_SEL2")
	)
	(segment
		(start 260.407912 -257.675888)
		(end 264.700766 -257.675888)
		(width 0.13208)
		(layer "B.Cu")
		(net "PEX2_MODE_SEL2")
	)
	(segment
		(start 256.209292 -251.850398)
		(end 256.81813 -251.850398)
		(width 0.13208)
		(layer "B.Cu")
		(net "PEX2_MODE_SEL2")
	)
	(segment
		(start 288.920428 -268.76629)
		(end 289.568636 -269.414498)
		(width 0.13208)
		(layer "B.Cu")
		(net "PEX2_MODE_SEL2")
	)
	(segment
		(start 259.568696 -249.06224)
		(end 258.8133 -249.817636)
		(width 0.13208)
		(layer "B.Cu")
		(net "PEX2_MODE_SEL2")
	)
	(segment
		(start 258.574286 -251.158502)
		(end 258.574286 -251.800614)
		(width 0.13208)
		(layer "B.Cu")
		(net "PEX2_MODE_SEL2")
	)
	(segment
		(start 259.568696 -249.035824)
		(end 259.568696 -249.06224)
		(width 0.13208)
		(layer "B.Cu")
		(net "PEX2_MODE_SEL2")
	)
	(segment
		(start 382.254252 -218.366594)
		(end 382.254252 -217.668856)
		(width 0.13208)
		(layer "B.Cu")
		(net "PEX2_MODE_SEL2")
	)
	(segment
		(start 289.898836 -269.735808)
		(end 289.898836 -269.744698)
		(width 0.13208)
		(layer "B.Cu")
		(net "PEX2_MODE_SEL2")
	)
	(segment
		(start 385.04749 -214.875618)
		(end 385.04749 -210.926172)
		(width 0.13208)
		(layer "B.Cu")
		(net "PEX2_MODE_SEL2")
	)
	(segment
		(start 258.058666 -254.07874)
		(end 259.739384 -255.759458)
		(width 0.13208)
		(layer "B.Cu")
		(net "PEX2_MODE_SEL2")
	)
	(segment
		(start 288.911538 -268.76629)
		(end 288.920428 -268.76629)
		(width 0.13208)
		(layer "B.Cu")
		(net "PEX2_MODE_SEL2")
	)
	(segment
		(start 291.380164 -283.080206)
		(end 292.32479 -284.024832)
		(width 0.13208)
		(layer "B.Cu")
		(net "PEX2_MODE_SEL2")
	)
	(segment
		(start 255.774444 -251.41555)
		(end 256.209292 -251.850398)
		(width 0.13208)
		(layer "B.Cu")
		(net "PEX2_MODE_SEL2")
	)
	(segment
		(start 189.049914 -299.699934)
		(end 188.574934 -299.224954)
		(width 0.254)
		(layer "F.Cu")
		(net "PEX1_ADCTEMP_VINP1")
	)
	(via
		(at 191.398398 -299.330618)
		(size 0.6604)
		(drill 0.3302)
		(layers "F.Cu" "B.Cu")
		(net "PEX1_ADCTEMP_VINP1")
	)
	(via
		(at 188.574934 -299.224954)
		(size 0.4064)
		(drill 0.2032)
		(layers "F.Cu" "B.Cu")
		(net "PEX1_ADCTEMP_VINP1")
	)
	(segment
		(start 190.039244 -299.71238)
		(end 190.126874 -299.62475)
		(width 0.254)
		(layer "B.Cu")
		(net "PEX1_ADCTEMP_VINP1")
	)
	(segment
		(start 191.104266 -299.62475)
		(end 190.126874 -299.62475)
		(width 0.13208)
		(layer "B.Cu")
		(net "PEX1_ADCTEMP_VINP1")
	)
	(segment
		(start 189.06236 -299.71238)
		(end 190.039244 -299.71238)
		(width 0.254)
		(layer "B.Cu")
		(net "PEX1_ADCTEMP_VINP1")
	)
	(segment
		(start 191.398398 -299.330618)
		(end 191.104266 -299.62475)
		(width 0.13208)
		(layer "B.Cu")
		(net "PEX1_ADCTEMP_VINP1")
	)
	(segment
		(start 188.574934 -299.224954)
		(end 189.06236 -299.71238)
		(width 0.254)
		(layer "B.Cu")
		(net "PEX1_ADCTEMP_VINP1")
	)
	(segment
		(start 259.211826 -16.363188)
		(end 259.211826 -15.351252)
		(width 0.13208)
		(layer "F.Cu")
		(net "SMB_ISO_SSD8_SDA")
	)
	(segment
		(start 259.135626 -16.439388)
		(end 259.211826 -16.363188)
		(width 0.13208)
		(layer "F.Cu")
		(net "SMB_ISO_SSD8_SDA")
	)
	(segment
		(start 255.456436 -20.467574)
		(end 255.456436 -20.222972)
		(width 0.13208)
		(layer "F.Cu")
		(net "SMB_ISO_SSD8_SDA")
	)
	(segment
		(start 256.267966 -19.453098)
		(end 258.216146 -19.453098)
		(width 0.13208)
		(layer "F.Cu")
		(net "SMB_ISO_SSD8_SDA")
	)
	(segment
		(start 256.22631 -19.453098)
		(end 256.267966 -19.453098)
		(width 0.13208)
		(layer "F.Cu")
		(net "SMB_ISO_SSD8_SDA")
	)
	(segment
		(start 259.662422 -23.337266)
		(end 259.662422 -23.946866)
		(width 0.13208)
		(layer "F.Cu")
		(net "SMB_ISO_SSD8_SDA")
	)
	(segment
		(start 259.135626 -18.533618)
		(end 259.135626 -16.439388)
		(width 0.13208)
		(layer "F.Cu")
		(net "SMB_ISO_SSD8_SDA")
	)
	(segment
		(start 258.216146 -19.453098)
		(end 259.135626 -18.533618)
		(width 0.13208)
		(layer "F.Cu")
		(net "SMB_ISO_SSD8_SDA")
	)
	(segment
		(start 255.456436 -20.222972)
		(end 256.22631 -19.453098)
		(width 0.13208)
		(layer "F.Cu")
		(net "SMB_ISO_SSD8_SDA")
	)
	(via
		(at 259.211826 -15.351252)
		(size 0.508)
		(drill 0.254)
		(layers "F.Cu" "B.Cu")
		(net "SMB_ISO_SSD8_SDA")
	)
	(via
		(at 259.662422 -23.946866)
		(size 0.508)
		(drill 0.254)
		(layers "F.Cu" "B.Cu")
		(net "SMB_ISO_SSD8_SDA")
	)
	(segment
		(start 259.211826 -15.420594)
		(end 259.211826 -15.351252)
		(width 0.13208)
		(layer "B.Cu")
		(net "SMB_ISO_SSD8_SDA")
	)
	(segment
		(start 259.662422 -23.946866)
		(end 261.235444 -22.373844)
		(width 0.13208)
		(layer "B.Cu")
		(net "SMB_ISO_SSD8_SDA")
	)
	(segment
		(start 261.235444 -22.373844)
		(end 261.235444 -17.444212)
		(width 0.13208)
		(layer "B.Cu")
		(net "SMB_ISO_SSD8_SDA")
	)
	(segment
		(start 261.235444 -17.444212)
		(end 259.211826 -15.420594)
		(width 0.13208)
		(layer "B.Cu")
		(net "SMB_ISO_SSD8_SDA")
	)
	(segment
		(start 204.764894 -22.990048)
		(end 205.809342 -22.990048)
		(width 0.13208)
		(layer "F.Cu")
		(net "SMB_ISO_SSD7_R_SDA")
	)
	(segment
		(start 205.809342 -22.990048)
		(end 205.844394 -23.0251)
		(width 0.13208)
		(layer "F.Cu")
		(net "SMB_ISO_SSD7_R_SDA")
	)
	(segment
		(start 216.758266 -19.453098)
		(end 217.367866 -19.453098)
		(width 0.13208)
		(layer "F.Cu")
		(net "SMB_ISO_SSD7_R_SDA")
	)
	(via
		(at 205.844394 -23.0251)
		(size 0.508)
		(drill 0.254)
		(layers "F.Cu" "B.Cu")
		(net "SMB_ISO_SSD7_R_SDA")
	)
	(via
		(at 216.758266 -19.453098)
		(size 0.508)
		(drill 0.254)
		(layers "F.Cu" "B.Cu")
		(net "SMB_ISO_SSD7_R_SDA")
	)
	(segment
		(start 216.758266 -19.453098)
		(end 216.758266 -21.570188)
		(width 0.15494)
		(layer "In5.Cu")
		(net "SMB_ISO_SSD7_R_SDA")
	)
	(segment
		(start 206.337154 -22.53234)
		(end 205.844394 -23.0251)
		(width 0.15494)
		(layer "In5.Cu")
		(net "SMB_ISO_SSD7_R_SDA")
	)
	(segment
		(start 215.796114 -22.53234)
		(end 206.337154 -22.53234)
		(width 0.15494)
		(layer "In5.Cu")
		(net "SMB_ISO_SSD7_R_SDA")
	)
	(segment
		(start 216.758266 -21.570188)
		(end 215.796114 -22.53234)
		(width 0.15494)
		(layer "In5.Cu")
		(net "SMB_ISO_SSD7_R_SDA")
	)
	(via
		(at 149.479254 -206.006192)
		(size 0.6604)
		(drill 0.3302)
		(layers "F.Cu" "B.Cu")
		(net "UART_PEX0_CLI_BUF_R_RX")
	)
	(segment
		(start 149.479254 -206.006192)
		(end 149.479254 -207.257142)
		(width 0.13208)
		(layer "B.Cu")
		(net "UART_PEX0_CLI_BUF_R_RX")
	)
	(segment
		(start 148.85924 -204.46619)
		(end 148.85924 -205.386178)
		(width 0.13208)
		(layer "B.Cu")
		(net "UART_PEX0_CLI_BUF_R_RX")
	)
	(segment
		(start 149.479254 -207.257142)
		(end 149.352254 -207.384142)
		(width 0.13208)
		(layer "B.Cu")
		(net "UART_PEX0_CLI_BUF_R_RX")
	)
	(segment
		(start 148.85924 -205.386178)
		(end 149.479254 -206.006192)
		(width 0.13208)
		(layer "B.Cu")
		(net "UART_PEX0_CLI_BUF_R_RX")
	)
	(segment
		(start 296.37482 -204.309218)
		(end 297.194732 -204.309218)
		(width 0.13208)
		(layer "F.Cu")
		(net "SPI_BIC1_CLK_LS23_DIR2")
	)
	(segment
		(start 297.194732 -204.309218)
		(end 297.506136 -204.620622)
		(width 0.13208)
		(layer "F.Cu")
		(net "SPI_BIC1_CLK_LS23_DIR2")
	)
	(segment
		(start 295.841928 -203.776326)
		(end 296.37482 -204.309218)
		(width 0.13208)
		(layer "F.Cu")
		(net "SPI_BIC1_CLK_LS23_DIR2")
	)
	(segment
		(start 297.506136 -204.620622)
		(end 297.506136 -205.318868)
		(width 0.13208)
		(layer "F.Cu")
		(net "SPI_BIC1_CLK_LS23_DIR2")
	)
	(via
		(at 295.841928 -203.776326)
		(size 0.508)
		(drill 0.254)
		(layers "F.Cu" "B.Cu")
		(net "SPI_BIC1_CLK_LS23_DIR2")
	)
	(segment
		(start 295.841928 -202.69708)
		(end 295.841928 -203.776326)
		(width 0.13208)
		(layer "B.Cu")
		(net "SPI_BIC1_CLK_LS23_DIR2")
	)
	(segment
		(start 295.706038 -202.56119)
		(end 295.841928 -202.69708)
		(width 0.13208)
		(layer "B.Cu")
		(net "SPI_BIC1_CLK_LS23_DIR2")
	)
	(segment
		(start 294.690038 -202.56119)
		(end 295.706038 -202.56119)
		(width 0.13208)
		(layer "B.Cu")
		(net "SPI_BIC1_CLK_LS23_DIR2")
	)
	(segment
		(start 341.541354 -88.633554)
		(end 341.472266 -88.564466)
		(width 0.13462)
		(layer "F.Cu")
		(net "CLK_100M_DB800ZL_SSD14_DP")
	)
	(segment
		(start 342.354408 -88.633554)
		(end 341.541354 -88.633554)
		(width 0.13462)
		(layer "F.Cu")
		(net "CLK_100M_DB800ZL_SSD14_DP")
	)
	(segment
		(start 343.886536 -89.581736)
		(end 343.30259 -89.581736)
		(width 0.13462)
		(layer "F.Cu")
		(net "CLK_100M_DB800ZL_SSD14_DP")
	)
	(segment
		(start 344.212926 -89.255346)
		(end 343.886536 -89.581736)
		(width 0.13462)
		(layer "F.Cu")
		(net "CLK_100M_DB800ZL_SSD14_DP")
	)
	(segment
		(start 341.472266 -88.564466)
		(end 341.045546 -88.564466)
		(width 0.13462)
		(layer "F.Cu")
		(net "CLK_100M_DB800ZL_SSD14_DP")
	)
	(segment
		(start 343.30259 -89.581736)
		(end 342.354408 -88.633554)
		(width 0.13462)
		(layer "F.Cu")
		(net "CLK_100M_DB800ZL_SSD14_DP")
	)
	(segment
		(start 266.766802 -83.175602)
		(end 263.946132 -83.175602)
		(width 0.13462)
		(layer "F.Cu")
		(net "CLK_100M_CK440Q_0_DB2000QL_DN")
	)
	(segment
		(start 267.80871 -83.678014)
		(end 267.269214 -83.678014)
		(width 0.13462)
		(layer "F.Cu")
		(net "CLK_100M_CK440Q_0_DB2000QL_DN")
	)
	(segment
		(start 267.269214 -83.678014)
		(end 266.766802 -83.175602)
		(width 0.13462)
		(layer "F.Cu")
		(net "CLK_100M_CK440Q_0_DB2000QL_DN")
	)
	(segment
		(start 263.827006 -83.056476)
		(end 263.551924 -83.056476)
		(width 0.13462)
		(layer "F.Cu")
		(net "CLK_100M_CK440Q_0_DB2000QL_DN")
	)
	(segment
		(start 263.946132 -83.175602)
		(end 263.827006 -83.056476)
		(width 0.13462)
		(layer "F.Cu")
		(net "CLK_100M_CK440Q_0_DB2000QL_DN")
	)
	(segment
		(start 268.1351 -83.351624)
		(end 267.80871 -83.678014)
		(width 0.13462)
		(layer "F.Cu")
		(net "CLK_100M_CK440Q_0_DB2000QL_DN")
	)
	(segment
		(start 251.054616 -84.174838)
		(end 250.64085 -84.174838)
		(width 0.13208)
		(layer "F.Cu")
		(net "CLK_CK440_SMB_ADDR1")
	)
	(segment
		(start 252.225048 -83.004406)
		(end 251.054616 -84.174838)
		(width 0.13208)
		(layer "F.Cu")
		(net "CLK_CK440_SMB_ADDR1")
	)
	(segment
		(start 250.64085 -84.174838)
		(end 249.6058 -85.209888)
		(width 0.13208)
		(layer "F.Cu")
		(net "CLK_CK440_SMB_ADDR1")
	)
	(segment
		(start 252.68682 -83.004406)
		(end 252.225048 -83.004406)
		(width 0.13208)
		(layer "F.Cu")
		(net "CLK_CK440_SMB_ADDR1")
	)
	(segment
		(start 253.64948 -82.80019)
		(end 253.445264 -83.004406)
		(width 0.13208)
		(layer "F.Cu")
		(net "CLK_CK440_SMB_ADDR1")
	)
	(segment
		(start 256.551938 -82.806286)
		(end 255.244346 -82.806286)
		(width 0.0889)
		(layer "F.Cu")
		(net "CLK_CK440_SMB_ADDR1")
	)
	(segment
		(start 255.23825 -82.80019)
		(end 253.64948 -82.80019)
		(width 0.13208)
		(layer "F.Cu")
		(net "CLK_CK440_SMB_ADDR1")
	)
	(segment
		(start 249.6058 -86.098888)
		(end 249.6058 -85.209888)
		(width 0.13208)
		(layer "F.Cu")
		(net "CLK_CK440_SMB_ADDR1")
	)
	(segment
		(start 253.445264 -83.004406)
		(end 252.68682 -83.004406)
		(width 0.13208)
		(layer "F.Cu")
		(net "CLK_CK440_SMB_ADDR1")
	)
	(segment
		(start 255.244346 -82.806286)
		(end 255.23825 -82.80019)
		(width 0.13208)
		(layer "F.Cu")
		(net "CLK_CK440_SMB_ADDR1")
	)
	(via
		(at 252.68682 -83.004406)
		(size 0.762)
		(drill 0.381)
		(layers "F.Cu" "B.Cu")
		(net "CLK_CK440_SMB_ADDR1")
	)
	(segment
		(start 110.04804 -332.1812)
		(end 109.027722 -332.1812)
		(width 0.13462)
		(layer "B.Cu")
		(net "CLK_100M_MB_0_R_DP")
	)
	(segment
		(start 113.114074 -331.60843)
		(end 112.747044 -331.2414)
		(width 0.13462)
		(layer "B.Cu")
		(net "CLK_100M_MB_0_R_DP")
	)
	(segment
		(start 112.316006 -331.2414)
		(end 110.04804 -332.1812)
		(width 0.13462)
		(layer "B.Cu")
		(net "CLK_100M_MB_0_R_DP")
	)
	(segment
		(start 112.747044 -331.2414)
		(end 112.316006 -331.2414)
		(width 0.13462)
		(layer "B.Cu")
		(net "CLK_100M_MB_0_R_DP")
	)
	(segment
		(start 108.908342 -332.30058)
		(end 108.689394 -332.30058)
		(width 0.13462)
		(layer "B.Cu")
		(net "CLK_100M_MB_0_R_DP")
	)
	(segment
		(start 109.027722 -332.1812)
		(end 108.908342 -332.30058)
		(width 0.13462)
		(layer "B.Cu")
		(net "CLK_100M_MB_0_R_DP")
	)
	(segment
		(start 261.819644 -312.21553)
		(end 261.366762 -312.21553)
		(width 0.13208)
		(layer "F.Cu")
		(net "PEX2_DBG_SEL1")
	)
	(segment
		(start 263.799066 -312.00852)
		(end 264.313924 -312.523378)
		(width 0.13208)
		(layer "F.Cu")
		(net "PEX2_DBG_SEL1")
	)
	(segment
		(start 260.707886 -311.556654)
		(end 260.038596 -311.556654)
		(width 0.13208)
		(layer "F.Cu")
		(net "PEX2_DBG_SEL1")
	)
	(segment
		(start 261.366762 -312.21553)
		(end 260.707886 -311.556654)
		(width 0.13208)
		(layer "F.Cu")
		(net "PEX2_DBG_SEL1")
	)
	(segment
		(start 262.026654 -312.00852)
		(end 263.799066 -312.00852)
		(width 0.13208)
		(layer "F.Cu")
		(net "PEX2_DBG_SEL1")
	)
	(segment
		(start 262.026654 -312.00852)
		(end 261.819644 -312.21553)
		(width 0.13208)
		(layer "F.Cu")
		(net "PEX2_DBG_SEL1")
	)
	(segment
		(start 286.149796 -308.249828)
		(end 285.674816 -308.724808)
		(width 0.13208)
		(layer "F.Cu")
		(net "PEX2_DBG_SEL1")
	)
	(via
		(at 264.313924 -312.523378)
		(size 0.508)
		(drill 0.254)
		(layers "F.Cu" "B.Cu")
		(net "PEX2_DBG_SEL1")
	)
	(via
		(at 285.674816 -308.724808)
		(size 0.4064)
		(drill 0.2032)
		(layers "F.Cu" "B.Cu")
		(net "PEX2_DBG_SEL1")
	)
	(segment
		(start 285.7246 -309.829454)
		(end 285.5722 -309.677054)
		(width 0.13208)
		(layer "B.Cu")
		(net "PEX2_DBG_SEL1")
	)
	(segment
		(start 264.313924 -312.523378)
		(end 264.845546 -313.055)
		(width 0.13208)
		(layer "B.Cu")
		(net "PEX2_DBG_SEL1")
	)
	(segment
		(start 285.4452 -314.4012)
		(end 285.7246 -314.1218)
		(width 0.13208)
		(layer "B.Cu")
		(net "PEX2_DBG_SEL1")
	)
	(segment
		(start 268.485112 -314.4012)
		(end 285.4452 -314.4012)
		(width 0.13208)
		(layer "B.Cu")
		(net "PEX2_DBG_SEL1")
	)
	(segment
		(start 264.845546 -313.055)
		(end 267.138912 -313.055)
		(width 0.13208)
		(layer "B.Cu")
		(net "PEX2_DBG_SEL1")
	)
	(segment
		(start 285.7246 -314.1218)
		(end 285.7246 -309.829454)
		(width 0.13208)
		(layer "B.Cu")
		(net "PEX2_DBG_SEL1")
	)
	(segment
		(start 267.138912 -313.055)
		(end 268.485112 -314.4012)
		(width 0.13208)
		(layer "B.Cu")
		(net "PEX2_DBG_SEL1")
	)
	(segment
		(start 285.5722 -309.677054)
		(end 285.5722 -308.827424)
		(width 0.13208)
		(layer "B.Cu")
		(net "PEX2_DBG_SEL1")
	)
	(segment
		(start 285.5722 -308.827424)
		(end 285.674816 -308.724808)
		(width 0.13208)
		(layer "B.Cu")
		(net "PEX2_DBG_SEL1")
	)
	(segment
		(start 189.049914 -300.649894)
		(end 189.524894 -300.174914)
		(width 0.254)
		(layer "F.Cu")
		(net "PEX1_ADCTEMP_VINP0")
	)
	(via
		(at 191.287146 -301.120556)
		(size 0.6604)
		(drill 0.3302)
		(layers "F.Cu" "B.Cu")
		(net "PEX1_ADCTEMP_VINP0")
	)
	(via
		(at 189.524894 -300.174914)
		(size 0.4064)
		(drill 0.2032)
		(layers "F.Cu" "B.Cu")
		(net "PEX1_ADCTEMP_VINP0")
	)
	(segment
		(start 190.074804 -300.724824)
		(end 190.126874 -300.724824)
		(width 0.254)
		(layer "B.Cu")
		(net "PEX1_ADCTEMP_VINP0")
	)
	(segment
		(start 189.524894 -300.174914)
		(end 190.074804 -300.724824)
		(width 0.254)
		(layer "B.Cu")
		(net "PEX1_ADCTEMP_VINP0")
	)
	(segment
		(start 190.891414 -300.724824)
		(end 190.126874 -300.724824)
		(width 0.13208)
		(layer "B.Cu")
		(net "PEX1_ADCTEMP_VINP0")
	)
	(segment
		(start 191.287146 -301.120556)
		(end 190.891414 -300.724824)
		(width 0.13208)
		(layer "B.Cu")
		(net "PEX1_ADCTEMP_VINP0")
	)
	(segment
		(start 89.709244 -22.990048)
		(end 89.744296 -23.0251)
		(width 0.13208)
		(layer "F.Cu")
		(net "SMB_ISO_SSD3_R_SDA")
	)
	(segment
		(start 102.790244 -11.543792)
		(end 102.790244 -10.934192)
		(width 0.13208)
		(layer "F.Cu")
		(net "SMB_ISO_SSD3_R_SDA")
	)
	(segment
		(start 88.664796 -22.990048)
		(end 89.709244 -22.990048)
		(width 0.13208)
		(layer "F.Cu")
		(net "SMB_ISO_SSD3_R_SDA")
	)
	(via
		(at 102.790244 -11.543792)
		(size 0.508)
		(drill 0.254)
		(layers "F.Cu" "B.Cu")
		(net "SMB_ISO_SSD3_R_SDA")
	)
	(via
		(at 89.744296 -23.0251)
		(size 0.508)
		(drill 0.254)
		(layers "F.Cu" "B.Cu")
		(net "SMB_ISO_SSD3_R_SDA")
	)
	(segment
		(start 100.658168 -11.670792)
		(end 101.50856 -10.8204)
		(width 0.15494)
		(layer "In5.Cu")
		(net "SMB_ISO_SSD3_R_SDA")
	)
	(segment
		(start 102.066852 -10.8204)
		(end 102.790244 -11.543792)
		(width 0.15494)
		(layer "In5.Cu")
		(net "SMB_ISO_SSD3_R_SDA")
	)
	(segment
		(start 89.744296 -23.0251)
		(end 90.237056 -22.53234)
		(width 0.15494)
		(layer "In5.Cu")
		(net "SMB_ISO_SSD3_R_SDA")
	)
	(segment
		(start 101.50856 -10.8204)
		(end 102.066852 -10.8204)
		(width 0.15494)
		(layer "In5.Cu")
		(net "SMB_ISO_SSD3_R_SDA")
	)
	(segment
		(start 90.237056 -22.53234)
		(end 99.516184 -22.53234)
		(width 0.15494)
		(layer "In5.Cu")
		(net "SMB_ISO_SSD3_R_SDA")
	)
	(segment
		(start 100.658168 -21.390356)
		(end 100.658168 -11.670792)
		(width 0.15494)
		(layer "In5.Cu")
		(net "SMB_ISO_SSD3_R_SDA")
	)
	(segment
		(start 99.516184 -22.53234)
		(end 100.658168 -21.390356)
		(width 0.15494)
		(layer "In5.Cu")
		(net "SMB_ISO_SSD3_R_SDA")
	)
	(segment
		(start 140.071856 -241.3254)
		(end 143.937482 -245.191026)
		(width 0.13208)
		(layer "F.Cu")
		(net "UART_PEX0_CLI_BUF_RX")
	)
	(segment
		(start 71.999856 -291.149786)
		(end 71.524876 -290.674806)
		(width 0.13208)
		(layer "F.Cu")
		(net "UART_PEX0_CLI_BUF_RX")
	)
	(segment
		(start 143.937482 -245.191026)
		(end 145.76933 -245.191026)
		(width 0.13208)
		(layer "F.Cu")
		(net "UART_PEX0_CLI_BUF_RX")
	)
	(segment
		(start 126.477522 -247.015)
		(end 132.167122 -241.3254)
		(width 0.13208)
		(layer "F.Cu")
		(net "UART_PEX0_CLI_BUF_RX")
	)
	(segment
		(start 113.604294 -247.015)
		(end 126.477522 -247.015)
		(width 0.13208)
		(layer "F.Cu")
		(net "UART_PEX0_CLI_BUF_RX")
	)
	(segment
		(start 96.25711 -254.230632)
		(end 106.388662 -254.230632)
		(width 0.13208)
		(layer "F.Cu")
		(net "UART_PEX0_CLI_BUF_RX")
	)
	(segment
		(start 96.21266 -254.275082)
		(end 96.25711 -254.230632)
		(width 0.13208)
		(layer "F.Cu")
		(net "UART_PEX0_CLI_BUF_RX")
	)
	(segment
		(start 132.167122 -241.3254)
		(end 140.071856 -241.3254)
		(width 0.13208)
		(layer "F.Cu")
		(net "UART_PEX0_CLI_BUF_RX")
	)
	(segment
		(start 106.388662 -254.230632)
		(end 113.604294 -247.015)
		(width 0.13208)
		(layer "F.Cu")
		(net "UART_PEX0_CLI_BUF_RX")
	)
	(via
		(at 148.015198 -208.237074)
		(size 0.508)
		(drill 0.254)
		(layers "F.Cu" "B.Cu")
		(net "UART_PEX0_CLI_BUF_RX")
	)
	(via
		(at 96.21266 -254.275082)
		(size 0.508)
		(drill 0.254)
		(layers "F.Cu" "B.Cu")
		(net "UART_PEX0_CLI_BUF_RX")
	)
	(via
		(at 145.76933 -245.191026)
		(size 0.508)
		(drill 0.254)
		(layers "F.Cu" "B.Cu")
		(net "UART_PEX0_CLI_BUF_RX")
	)
	(via
		(at 71.524876 -290.674806)
		(size 0.4064)
		(drill 0.2032)
		(layers "F.Cu" "B.Cu")
		(net "UART_PEX0_CLI_BUF_RX")
	)
	(segment
		(start 74.193654 -287.8074)
		(end 74.420222 -287.580832)
		(width 0.13208)
		(layer "B.Cu")
		(net "UART_PEX0_CLI_BUF_RX")
	)
	(segment
		(start 73.685654 -287.8074)
		(end 74.193654 -287.8074)
		(width 0.13208)
		(layer "B.Cu")
		(net "UART_PEX0_CLI_BUF_RX")
	)
	(segment
		(start 71.948802 -290.25088)
		(end 71.948802 -288.536126)
		(width 0.13208)
		(layer "B.Cu")
		(net "UART_PEX0_CLI_BUF_RX")
	)
	(segment
		(start 73.133966 -288.359088)
		(end 73.685654 -287.8074)
		(width 0.13208)
		(layer "B.Cu")
		(net "UART_PEX0_CLI_BUF_RX")
	)
	(segment
		(start 149.352254 -208.184242)
		(end 149.352254 -209.162142)
		(width 0.13208)
		(layer "B.Cu")
		(net "UART_PEX0_CLI_BUF_RX")
	)
	(segment
		(start 148.940266 -209.162142)
		(end 148.015198 -208.237074)
		(width 0.13208)
		(layer "B.Cu")
		(net "UART_PEX0_CLI_BUF_RX")
	)
	(segment
		(start 71.524876 -290.674806)
		(end 71.948802 -290.25088)
		(width 0.13208)
		(layer "B.Cu")
		(net "UART_PEX0_CLI_BUF_RX")
	)
	(segment
		(start 74.420222 -287.580832)
		(end 74.420222 -268.07287)
		(width 0.13208)
		(layer "B.Cu")
		(net "UART_PEX0_CLI_BUF_RX")
	)
	(segment
		(start 88.21801 -254.275082)
		(end 96.21266 -254.275082)
		(width 0.13208)
		(layer "B.Cu")
		(net "UART_PEX0_CLI_BUF_RX")
	)
	(segment
		(start 149.352254 -209.162142)
		(end 148.940266 -209.162142)
		(width 0.13208)
		(layer "B.Cu")
		(net "UART_PEX0_CLI_BUF_RX")
	)
	(segment
		(start 72.12584 -288.359088)
		(end 73.133966 -288.359088)
		(width 0.13208)
		(layer "B.Cu")
		(net "UART_PEX0_CLI_BUF_RX")
	)
	(segment
		(start 74.420222 -268.07287)
		(end 88.21801 -254.275082)
		(width 0.13208)
		(layer "B.Cu")
		(net "UART_PEX0_CLI_BUF_RX")
	)
	(segment
		(start 71.948802 -288.536126)
		(end 72.12584 -288.359088)
		(width 0.13208)
		(layer "B.Cu")
		(net "UART_PEX0_CLI_BUF_RX")
	)
	(segment
		(start 145.602706 -221.227396)
		(end 147.169124 -219.660978)
		(width 0.15494)
		(layer "In5.Cu")
		(net "UART_PEX0_CLI_BUF_RX")
	)
	(segment
		(start 145.602706 -227.131372)
		(end 145.602706 -221.227396)
		(width 0.15494)
		(layer "In5.Cu")
		(net "UART_PEX0_CLI_BUF_RX")
	)
	(segment
		(start 141.1478 -233.653076)
		(end 144.034002 -230.766874)
		(width 0.15494)
		(layer "In5.Cu")
		(net "UART_PEX0_CLI_BUF_RX")
	)
	(segment
		(start 147.600924 -208.237074)
		(end 148.015198 -208.237074)
		(width 0.15494)
		(layer "In5.Cu")
		(net "UART_PEX0_CLI_BUF_RX")
	)
	(segment
		(start 144.034002 -228.700076)
		(end 145.602706 -227.131372)
		(width 0.15494)
		(layer "In5.Cu")
		(net "UART_PEX0_CLI_BUF_RX")
	)
	(segment
		(start 146.9898 -209.681064)
		(end 146.9898 -208.848198)
		(width 0.15494)
		(layer "In5.Cu")
		(net "UART_PEX0_CLI_BUF_RX")
	)
	(segment
		(start 147.169124 -209.860388)
		(end 146.9898 -209.681064)
		(width 0.15494)
		(layer "In5.Cu")
		(net "UART_PEX0_CLI_BUF_RX")
	)
	(segment
		(start 143.611854 -245.191026)
		(end 141.1478 -242.726972)
		(width 0.15494)
		(layer "In5.Cu")
		(net "UART_PEX0_CLI_BUF_RX")
	)
	(segment
		(start 147.169124 -219.660978)
		(end 147.169124 -209.860388)
		(width 0.15494)
		(layer "In5.Cu")
		(net "UART_PEX0_CLI_BUF_RX")
	)
	(segment
		(start 141.1478 -242.726972)
		(end 141.1478 -233.653076)
		(width 0.15494)
		(layer "In5.Cu")
		(net "UART_PEX0_CLI_BUF_RX")
	)
	(segment
		(start 146.9898 -208.848198)
		(end 147.600924 -208.237074)
		(width 0.15494)
		(layer "In5.Cu")
		(net "UART_PEX0_CLI_BUF_RX")
	)
	(segment
		(start 145.76933 -245.191026)
		(end 143.611854 -245.191026)
		(width 0.15494)
		(layer "In5.Cu")
		(net "UART_PEX0_CLI_BUF_RX")
	)
	(segment
		(start 144.034002 -230.766874)
		(end 144.034002 -228.700076)
		(width 0.15494)
		(layer "In5.Cu")
		(net "UART_PEX0_CLI_BUF_RX")
	)
	(via
		(at 125.866906 -201.93)
		(size 0.6604)
		(drill 0.3302)
		(layers "F.Cu" "B.Cu")
		(net "FT4232_CLI_EEPROM_R_SDA")
	)
	(segment
		(start 125.472952 -205.292198)
		(end 125.866906 -204.898244)
		(width 0.13208)
		(layer "B.Cu")
		(net "FT4232_CLI_EEPROM_R_SDA")
	)
	(segment
		(start 124.731272 -200.92035)
		(end 124.921772 -200.72985)
		(width 0.13208)
		(layer "B.Cu")
		(net "FT4232_CLI_EEPROM_R_SDA")
	)
	(segment
		(start 124.921772 -200.72985)
		(end 126.246128 -200.72985)
		(width 0.13208)
		(layer "B.Cu")
		(net "FT4232_CLI_EEPROM_R_SDA")
	)
	(segment
		(start 126.246128 -201.550778)
		(end 125.866906 -201.93)
		(width 0.13208)
		(layer "B.Cu")
		(net "FT4232_CLI_EEPROM_R_SDA")
	)
	(segment
		(start 126.246128 -200.72985)
		(end 126.246128 -201.550778)
		(width 0.13208)
		(layer "B.Cu")
		(net "FT4232_CLI_EEPROM_R_SDA")
	)
	(segment
		(start 124.4727 -205.292198)
		(end 125.472952 -205.292198)
		(width 0.13208)
		(layer "B.Cu")
		(net "FT4232_CLI_EEPROM_R_SDA")
	)
	(segment
		(start 125.866906 -204.898244)
		(end 125.866906 -201.93)
		(width 0.13208)
		(layer "B.Cu")
		(net "FT4232_CLI_EEPROM_R_SDA")
	)
	(segment
		(start 297.972988 -203.900786)
		(end 297.988228 -203.900786)
		(width 0.13208)
		(layer "F.Cu")
		(net "SPI_BIC1_CS0_LS23_N_DIR1")
	)
	(segment
		(start 298.156122 -204.06868)
		(end 298.156122 -205.318868)
		(width 0.13208)
		(layer "F.Cu")
		(net "SPI_BIC1_CS0_LS23_N_DIR1")
	)
	(segment
		(start 297.988228 -203.900786)
		(end 298.156122 -204.06868)
		(width 0.13208)
		(layer "F.Cu")
		(net "SPI_BIC1_CS0_LS23_N_DIR1")
	)
	(via
		(at 297.972988 -203.900786)
		(size 0.508)
		(drill 0.254)
		(layers "F.Cu" "B.Cu")
		(net "SPI_BIC1_CS0_LS23_N_DIR1")
	)
	(segment
		(start 297.972988 -203.900786)
		(end 297.988228 -203.885546)
		(width 0.13208)
		(layer "B.Cu")
		(net "SPI_BIC1_CS0_LS23_N_DIR1")
	)
	(segment
		(start 297.103038 -202.56119)
		(end 298.119038 -202.56119)
		(width 0.13208)
		(layer "B.Cu")
		(net "SPI_BIC1_CS0_LS23_N_DIR1")
	)
	(segment
		(start 297.988228 -203.285344)
		(end 298.119038 -203.154534)
		(width 0.13208)
		(layer "B.Cu")
		(net "SPI_BIC1_CS0_LS23_N_DIR1")
	)
	(segment
		(start 297.988228 -203.885546)
		(end 297.988228 -203.285344)
		(width 0.13208)
		(layer "B.Cu")
		(net "SPI_BIC1_CS0_LS23_N_DIR1")
	)
	(segment
		(start 298.119038 -203.154534)
		(end 298.119038 -202.56119)
		(width 0.13208)
		(layer "B.Cu")
		(net "SPI_BIC1_CS0_LS23_N_DIR1")
	)
	(segment
		(start 343.891108 -87.577168)
		(end 343.003124 -87.577168)
		(width 0.13462)
		(layer "F.Cu")
		(net "CLK_100M_DB800ZL_SSD13_DP")
	)
	(segment
		(start 342.656414 -87.433658)
		(end 341.541354 -87.433658)
		(width 0.13462)
		(layer "F.Cu")
		(net "CLK_100M_DB800ZL_SSD13_DP")
	)
	(segment
		(start 343.003124 -87.577168)
		(end 342.656414 -87.433658)
		(width 0.13462)
		(layer "F.Cu")
		(net "CLK_100M_DB800ZL_SSD13_DP")
	)
	(segment
		(start 341.541354 -87.433658)
		(end 341.472012 -87.364316)
		(width 0.13462)
		(layer "F.Cu")
		(net "CLK_100M_DB800ZL_SSD13_DP")
	)
	(segment
		(start 341.472012 -87.364316)
		(end 341.045546 -87.364316)
		(width 0.13462)
		(layer "F.Cu")
		(net "CLK_100M_DB800ZL_SSD13_DP")
	)
	(segment
		(start 344.212926 -87.25535)
		(end 343.891108 -87.577168)
		(width 0.13462)
		(layer "F.Cu")
		(net "CLK_100M_DB800ZL_SSD13_DP")
	)
	(segment
		(start 257.558286 -251.956824)
		(end 257.558286 -251.158502)
		(width 0.13208)
		(layer "F.Cu")
		(net "PEX2_MODE_SEL7")
	)
	(segment
		(start 257.558286 -251.158502)
		(end 257.558286 -250.470924)
		(width 0.13208)
		(layer "F.Cu")
		(net "PEX2_MODE_SEL7")
	)
	(segment
		(start 292.79977 -283.549852)
		(end 293.27475 -284.024832)
		(width 0.1651)
		(layer "F.Cu")
		(net "PEX2_MODE_SEL7")
	)
	(via
		(at 293.27475 -284.024832)
		(size 0.4064)
		(drill 0.2032)
		(layers "F.Cu" "B.Cu")
		(net "PEX2_MODE_SEL7")
	)
	(via
		(at 289.350196 -269.963138)
		(size 0.6604)
		(drill 0.3302)
		(layers "F.Cu" "B.Cu")
		(net "PEX2_MODE_SEL7")
	)
	(via
		(at 257.558286 -251.158502)
		(size 0.508)
		(drill 0.254)
		(layers "F.Cu" "B.Cu")
		(net "PEX2_MODE_SEL7")
	)
	(segment
		(start 290.377626 -270.990568)
		(end 290.377626 -282.032964)
		(width 0.13208)
		(layer "B.Cu")
		(net "PEX2_MODE_SEL7")
	)
	(segment
		(start 292.805866 -284.493716)
		(end 293.27475 -284.024832)
		(width 0.13208)
		(layer "B.Cu")
		(net "PEX2_MODE_SEL7")
	)
	(segment
		(start 257.558286 -252.788166)
		(end 257.085846 -253.260606)
		(width 0.13208)
		(layer "B.Cu")
		(net "PEX2_MODE_SEL7")
	)
	(segment
		(start 289.94989 -283.320744)
		(end 290.206938 -283.577792)
		(width 0.13208)
		(layer "B.Cu")
		(net "PEX2_MODE_SEL7")
	)
	(segment
		(start 257.085846 -253.94285)
		(end 259.25907 -256.116074)
		(width 0.13208)
		(layer "B.Cu")
		(net "PEX2_MODE_SEL7")
	)
	(segment
		(start 290.206938 -283.577792)
		(end 291.205158 -283.577792)
		(width 0.13208)
		(layer "B.Cu")
		(net "PEX2_MODE_SEL7")
	)
	(segment
		(start 291.205158 -283.577792)
		(end 292.121082 -284.493716)
		(width 0.13208)
		(layer "B.Cu")
		(net "PEX2_MODE_SEL7")
	)
	(segment
		(start 257.085846 -253.260606)
		(end 257.085846 -253.94285)
		(width 0.13208)
		(layer "B.Cu")
		(net "PEX2_MODE_SEL7")
	)
	(segment
		(start 257.558286 -251.158502)
		(end 257.558286 -252.788166)
		(width 0.13208)
		(layer "B.Cu")
		(net "PEX2_MODE_SEL7")
	)
	(segment
		(start 259.25907 -256.116074)
		(end 259.25907 -256.929382)
		(width 0.13208)
		(layer "B.Cu")
		(net "PEX2_MODE_SEL7")
	)
	(segment
		(start 259.25907 -256.929382)
		(end 261.271766 -258.942078)
		(width 0.13208)
		(layer "B.Cu")
		(net "PEX2_MODE_SEL7")
	)
	(segment
		(start 289.350196 -269.963138)
		(end 290.377626 -270.990568)
		(width 0.13208)
		(layer "B.Cu")
		(net "PEX2_MODE_SEL7")
	)
	(segment
		(start 261.271766 -258.942078)
		(end 278.329136 -258.942078)
		(width 0.13208)
		(layer "B.Cu")
		(net "PEX2_MODE_SEL7")
	)
	(segment
		(start 278.329136 -258.942078)
		(end 289.350196 -269.963138)
		(width 0.13208)
		(layer "B.Cu")
		(net "PEX2_MODE_SEL7")
	)
	(segment
		(start 289.94989 -282.4607)
		(end 289.94989 -283.320744)
		(width 0.13208)
		(layer "B.Cu")
		(net "PEX2_MODE_SEL7")
	)
	(segment
		(start 292.121082 -284.493716)
		(end 292.805866 -284.493716)
		(width 0.13208)
		(layer "B.Cu")
		(net "PEX2_MODE_SEL7")
	)
	(segment
		(start 290.377626 -282.032964)
		(end 289.94989 -282.4607)
		(width 0.13208)
		(layer "B.Cu")
		(net "PEX2_MODE_SEL7")
	)
	(segment
		(start 88.664796 -22.3901)
		(end 90.467434 -22.3901)
		(width 0.13208)
		(layer "F.Cu")
		(net "SMB_ISO_SSD3_R_SCL")
	)
	(segment
		(start 101.781356 -11.543792)
		(end 101.774244 -11.53668)
		(width 0.13208)
		(layer "F.Cu")
		(net "SMB_ISO_SSD3_R_SCL")
	)
	(segment
		(start 90.467434 -22.3901)
		(end 91.093544 -23.01621)
		(width 0.13208)
		(layer "F.Cu")
		(net "SMB_ISO_SSD3_R_SCL")
	)
	(segment
		(start 101.774244 -11.53668)
		(end 101.774244 -10.934192)
		(width 0.13208)
		(layer "F.Cu")
		(net "SMB_ISO_SSD3_R_SCL")
	)
	(via
		(at 91.093544 -23.01621)
		(size 0.508)
		(drill 0.254)
		(layers "F.Cu" "B.Cu")
		(net "SMB_ISO_SSD3_R_SCL")
	)
	(via
		(at 101.781356 -11.543792)
		(size 0.508)
		(drill 0.254)
		(layers "F.Cu" "B.Cu")
		(net "SMB_ISO_SSD3_R_SCL")
	)
	(segment
		(start 99.682808 -23.01621)
		(end 101.226874 -21.472144)
		(width 0.15494)
		(layer "In5.Cu")
		(net "SMB_ISO_SSD3_R_SCL")
	)
	(segment
		(start 91.093544 -23.01621)
		(end 99.682808 -23.01621)
		(width 0.15494)
		(layer "In5.Cu")
		(net "SMB_ISO_SSD3_R_SCL")
	)
	(segment
		(start 101.226874 -12.098274)
		(end 101.781356 -11.543792)
		(width 0.15494)
		(layer "In5.Cu")
		(net "SMB_ISO_SSD3_R_SCL")
	)
	(segment
		(start 101.226874 -21.472144)
		(end 101.226874 -12.098274)
		(width 0.15494)
		(layer "In5.Cu")
		(net "SMB_ISO_SSD3_R_SCL")
	)
	(segment
		(start 138.30681 -200.489058)
		(end 138.30681 -201.64425)
		(width 0.13208)
		(layer "F.Cu")
		(net "FT4232_CLI_REF")
	)
	(via
		(at 138.30681 -201.64425)
		(size 0.508)
		(drill 0.254)
		(layers "F.Cu" "B.Cu")
		(net "FT4232_CLI_REF")
	)
	(segment
		(start 138.618214 -201.955654)
		(end 138.30681 -201.64425)
		(width 0.13208)
		(layer "B.Cu")
		(net "FT4232_CLI_REF")
	)
	(segment
		(start 138.618214 -202.837796)
		(end 138.618214 -201.955654)
		(width 0.13208)
		(layer "B.Cu")
		(net "FT4232_CLI_REF")
	)
	(segment
		(start 293.980108 -203.935838)
		(end 294.255952 -204.211682)
		(width 0.13208)
		(layer "F.Cu")
		(net "SPI_BIC1_MOSI_LS23_DIR3")
	)
	(segment
		(start 294.255952 -204.211682)
		(end 294.255952 -205.318868)
		(width 0.13208)
		(layer "F.Cu")
		(net "SPI_BIC1_MOSI_LS23_DIR3")
	)
	(segment
		(start 293.36619 -203.935838)
		(end 293.980108 -203.935838)
		(width 0.13208)
		(layer "F.Cu")
		(net "SPI_BIC1_MOSI_LS23_DIR3")
	)
	(via
		(at 293.36619 -203.935838)
		(size 0.508)
		(drill 0.254)
		(layers "F.Cu" "B.Cu")
		(net "SPI_BIC1_MOSI_LS23_DIR3")
	)
	(segment
		(start 291.86124 -203.363068)
		(end 292.79342 -203.363068)
		(width 0.13208)
		(layer "B.Cu")
		(net "SPI_BIC1_MOSI_LS23_DIR3")
	)
	(segment
		(start 292.79342 -203.363068)
		(end 293.36619 -203.935838)
		(width 0.13208)
		(layer "B.Cu")
		(net "SPI_BIC1_MOSI_LS23_DIR3")
	)
	(segment
		(start 291.86124 -202.474068)
		(end 291.86124 -203.363068)
		(width 0.13208)
		(layer "B.Cu")
		(net "SPI_BIC1_MOSI_LS23_DIR3")
	)
	(segment
		(start 339.1662 -92.390976)
		(end 339.1662 -90.212672)
		(width 0.13462)
		(layer "F.Cu")
		(net "CLK_100M_DB800ZL_SSD15_DN")
	)
	(segment
		(start 339.1662 -90.212672)
		(end 339.095588 -90.14206)
		(width 0.13462)
		(layer "F.Cu")
		(net "CLK_100M_DB800ZL_SSD15_DN")
	)
	(segment
		(start 338.838286 -92.71889)
		(end 339.1662 -92.390976)
		(width 0.13462)
		(layer "F.Cu")
		(net "CLK_100M_DB800ZL_SSD15_DN")
	)
	(segment
		(start 339.095588 -90.14206)
		(end 339.095588 -89.714324)
		(width 0.13462)
		(layer "F.Cu")
		(net "CLK_100M_DB800ZL_SSD15_DN")
	)
	(segment
		(start 263.959848 -83.449922)
		(end 263.947148 -83.437222)
		(width 0.13462)
		(layer "F.Cu")
		(net "CLK_100M_CK440Q_0_DB2000QL_DP")
	)
	(segment
		(start 267.155422 -83.952334)
		(end 266.65301 -83.449922)
		(width 0.13462)
		(layer "F.Cu")
		(net "CLK_100M_CK440Q_0_DB2000QL_DP")
	)
	(segment
		(start 263.828022 -83.556348)
		(end 263.551924 -83.556348)
		(width 0.13462)
		(layer "F.Cu")
		(net "CLK_100M_CK440Q_0_DB2000QL_DP")
	)
	(segment
		(start 263.947148 -83.437222)
		(end 263.828022 -83.556348)
		(width 0.13462)
		(layer "F.Cu")
		(net "CLK_100M_CK440Q_0_DB2000QL_DP")
	)
	(segment
		(start 266.65301 -83.449922)
		(end 263.959848 -83.449922)
		(width 0.13462)
		(layer "F.Cu")
		(net "CLK_100M_CK440Q_0_DB2000QL_DP")
	)
	(segment
		(start 267.82141 -83.952334)
		(end 267.155422 -83.952334)
		(width 0.13462)
		(layer "F.Cu")
		(net "CLK_100M_CK440Q_0_DB2000QL_DP")
	)
	(segment
		(start 268.1351 -84.266024)
		(end 267.82141 -83.952334)
		(width 0.13462)
		(layer "F.Cu")
		(net "CLK_100M_CK440Q_0_DB2000QL_DP")
	)
	(segment
		(start 252.927866 -82.404966)
		(end 253.05131 -82.52841)
		(width 0.13208)
		(layer "F.Cu")
		(net "CLK_CK440_SMB_ADDR0")
	)
	(segment
		(start 249.6058 -84.320888)
		(end 249.6058 -83.431888)
		(width 0.13208)
		(layer "F.Cu")
		(net "CLK_CK440_SMB_ADDR0")
	)
	(segment
		(start 249.837194 -83.200494)
		(end 249.6058 -83.431888)
		(width 0.13208)
		(layer "F.Cu")
		(net "CLK_CK440_SMB_ADDR0")
	)
	(segment
		(start 255.328674 -82.52841)
		(end 255.356614 -82.55635)
		(width 0.13208)
		(layer "F.Cu")
		(net "CLK_CK440_SMB_ADDR0")
	)
	(segment
		(start 253.05131 -82.52841)
		(end 255.328674 -82.52841)
		(width 0.13208)
		(layer "F.Cu")
		(net "CLK_CK440_SMB_ADDR0")
	)
	(segment
		(start 251.52096 -83.200494)
		(end 252.316488 -82.404966)
		(width 0.13208)
		(layer "F.Cu")
		(net "CLK_CK440_SMB_ADDR0")
	)
	(segment
		(start 251.000768 -83.200494)
		(end 249.837194 -83.200494)
		(width 0.13208)
		(layer "F.Cu")
		(net "CLK_CK440_SMB_ADDR0")
	)
	(segment
		(start 252.316488 -82.404966)
		(end 252.927866 -82.404966)
		(width 0.13208)
		(layer "F.Cu")
		(net "CLK_CK440_SMB_ADDR0")
	)
	(segment
		(start 255.356614 -82.55635)
		(end 255.801876 -82.55635)
		(width 0.13208)
		(layer "F.Cu")
		(net "CLK_CK440_SMB_ADDR0")
	)
	(segment
		(start 251.000768 -83.200494)
		(end 251.52096 -83.200494)
		(width 0.13208)
		(layer "F.Cu")
		(net "CLK_CK440_SMB_ADDR0")
	)
	(via
		(at 251.000768 -83.200494)
		(size 0.762)
		(drill 0.381)
		(layers "F.Cu" "B.Cu")
		(net "CLK_CK440_SMB_ADDR0")
	)
	(segment
		(start 2.614168 -24.545544)
		(end 2.614168 -23.935944)
		(width 0.13208)
		(layer "F.Cu")
		(net "SMB_ISO_SSD0_R_SCL")
	)
	(segment
		(start 12.46759 -22.3901)
		(end 10.664952 -22.3901)
		(width 0.13208)
		(layer "F.Cu")
		(net "SMB_ISO_SSD0_R_SCL")
	)
	(segment
		(start 13.0937 -23.01621)
		(end 12.46759 -22.3901)
		(width 0.13208)
		(layer "F.Cu")
		(net "SMB_ISO_SSD0_R_SCL")
	)
	(via
		(at 13.0937 -23.01621)
		(size 0.508)
		(drill 0.254)
		(layers "F.Cu" "B.Cu")
		(net "SMB_ISO_SSD0_R_SCL")
	)
	(via
		(at 2.614168 -23.935944)
		(size 0.508)
		(drill 0.254)
		(layers "F.Cu" "B.Cu")
		(net "SMB_ISO_SSD0_R_SCL")
	)
	(segment
		(start 4.886452 -24.323548)
		(end 4.572 -24.638)
		(width 0.15494)
		(layer "In5.Cu")
		(net "SMB_ISO_SSD0_R_SCL")
	)
	(segment
		(start 12.23899 -24.323548)
		(end 4.886452 -24.323548)
		(width 0.15494)
		(layer "In5.Cu")
		(net "SMB_ISO_SSD0_R_SCL")
	)
	(segment
		(start 3.316224 -24.638)
		(end 2.614168 -23.935944)
		(width 0.15494)
		(layer "In5.Cu")
		(net "SMB_ISO_SSD0_R_SCL")
	)
	(segment
		(start 13.0937 -23.468838)
		(end 12.23899 -24.323548)
		(width 0.15494)
		(layer "In5.Cu")
		(net "SMB_ISO_SSD0_R_SCL")
	)
	(segment
		(start 4.572 -24.638)
		(end 3.316224 -24.638)
		(width 0.15494)
		(layer "In5.Cu")
		(net "SMB_ISO_SSD0_R_SCL")
	)
	(segment
		(start 13.0937 -23.01621)
		(end 13.0937 -23.468838)
		(width 0.15494)
		(layer "In5.Cu")
		(net "SMB_ISO_SSD0_R_SCL")
	)
	(segment
		(start 213.557104 -117.632734)
		(end 213.99881 -117.191028)
		(width 0.13208)
		(layer "F.Cu")
		(net "P3V3_NIC3_SS")
	)
	(segment
		(start 213.99881 -117.191028)
		(end 214.675466 -117.191028)
		(width 0.13208)
		(layer "F.Cu")
		(net "P3V3_NIC3_SS")
	)
	(segment
		(start 212.93582 -118.771924)
		(end 213.557104 -118.15064)
		(width 0.13208)
		(layer "F.Cu")
		(net "P3V3_NIC3_SS")
	)
	(segment
		(start 212.871304 -118.771924)
		(end 212.93582 -118.771924)
		(width 0.13208)
		(layer "F.Cu")
		(net "P3V3_NIC3_SS")
	)
	(segment
		(start 213.557104 -118.15064)
		(end 213.557104 -117.632734)
		(width 0.13208)
		(layer "F.Cu")
		(net "P3V3_NIC3_SS")
	)
	(via
		(at 213.99881 -117.191028)
		(size 0.508)
		(drill 0.254)
		(layers "F.Cu" "B.Cu")
		(net "P3V3_NIC3_SS")
	)
	(segment
		(start 107.6198 -202.4888)
		(end 107.241594 -202.867006)
		(width 0.13208)
		(layer "F.Cu")
		(net "UART_PEX1_CLI_R_RX")
	)
	(segment
		(start 107.6198 -202.057)
		(end 107.6198 -202.4888)
		(width 0.13208)
		(layer "F.Cu")
		(net "UART_PEX1_CLI_R_RX")
	)
	(segment
		(start 72.7202 -226.273106)
		(end 70.7136 -226.273106)
		(width 0.13208)
		(layer "F.Cu")
		(net "UART_PEX1_CLI_R_RX")
	)
	(segment
		(start 147.850606 -200.0504)
		(end 147.8534 -200.0504)
		(width 0.13208)
		(layer "F.Cu")
		(net "UART_PEX1_CLI_R_RX")
	)
	(segment
		(start 147.178776 -199.37857)
		(end 147.850606 -200.0504)
		(width 0.13208)
		(layer "F.Cu")
		(net "UART_PEX1_CLI_R_RX")
	)
	(segment
		(start 146.098006 -198.2978)
		(end 147.178776 -199.37857)
		(width 0.13208)
		(layer "F.Cu")
		(net "UART_PEX1_CLI_R_RX")
	)
	(segment
		(start 107.241594 -202.867006)
		(end 106.7816 -202.867006)
		(width 0.13208)
		(layer "F.Cu")
		(net "UART_PEX1_CLI_R_RX")
	)
	(via
		(at 147.8534 -200.0504)
		(size 0.508)
		(drill 0.254)
		(layers "F.Cu" "B.Cu")
		(net "UART_PEX1_CLI_R_RX")
	)
	(via
		(at 70.7136 -226.273106)
		(size 0.508)
		(drill 0.254)
		(layers "F.Cu" "B.Cu")
		(net "UART_PEX1_CLI_R_RX")
	)
	(via
		(at 107.6198 -202.057)
		(size 0.508)
		(drill 0.254)
		(layers "F.Cu" "B.Cu")
		(net "UART_PEX1_CLI_R_RX")
	)
	(via
		(at 147.178776 -199.37857)
		(size 0.762)
		(drill 0.381)
		(layers "F.Cu" "B.Cu")
		(net "UART_PEX1_CLI_R_RX")
	)
	(segment
		(start 105.876598 -202.057)
		(end 107.6198 -202.057)
		(width 0.13208)
		(layer "B.Cu")
		(net "UART_PEX1_CLI_R_RX")
	)
	(segment
		(start 92.148406 -209.12328)
		(end 98.803206 -209.12328)
		(width 0.13208)
		(layer "B.Cu")
		(net "UART_PEX1_CLI_R_RX")
	)
	(segment
		(start 74.996294 -226.273106)
		(end 75.45832 -225.81108)
		(width 0.13208)
		(layer "B.Cu")
		(net "UART_PEX1_CLI_R_RX")
	)
	(segment
		(start 98.80473 -209.121756)
		(end 98.811842 -209.121756)
		(width 0.13208)
		(layer "B.Cu")
		(net "UART_PEX1_CLI_R_RX")
	)
	(segment
		(start 75.460606 -225.81108)
		(end 92.148406 -209.12328)
		(width 0.13208)
		(layer "B.Cu")
		(net "UART_PEX1_CLI_R_RX")
	)
	(segment
		(start 147.8534 -200.0504)
		(end 147.8534 -200.5076)
		(width 0.13208)
		(layer "B.Cu")
		(net "UART_PEX1_CLI_R_RX")
	)
	(segment
		(start 98.811842 -209.121756)
		(end 105.876598 -202.057)
		(width 0.13208)
		(layer "B.Cu")
		(net "UART_PEX1_CLI_R_RX")
	)
	(segment
		(start 75.45832 -225.81108)
		(end 75.460606 -225.81108)
		(width 0.13208)
		(layer "B.Cu")
		(net "UART_PEX1_CLI_R_RX")
	)
	(segment
		(start 70.7136 -226.273106)
		(end 74.996294 -226.273106)
		(width 0.13208)
		(layer "B.Cu")
		(net "UART_PEX1_CLI_R_RX")
	)
	(segment
		(start 147.8534 -200.5076)
		(end 147.559268 -200.801732)
		(width 0.13208)
		(layer "B.Cu")
		(net "UART_PEX1_CLI_R_RX")
	)
	(segment
		(start 147.559268 -200.801732)
		(end 147.559268 -202.466194)
		(width 0.13208)
		(layer "B.Cu")
		(net "UART_PEX1_CLI_R_RX")
	)
	(segment
		(start 98.803206 -209.12328)
		(end 98.80473 -209.121756)
		(width 0.13208)
		(layer "B.Cu")
		(net "UART_PEX1_CLI_R_RX")
	)
	(segment
		(start 135.89 -206.1972)
		(end 135.0518 -205.359)
		(width 0.15494)
		(layer "In13.Cu")
		(net "UART_PEX1_CLI_R_RX")
	)
	(segment
		(start 135.0518 -205.359)
		(end 124.5362 -205.359)
		(width 0.15494)
		(layer "In13.Cu")
		(net "UART_PEX1_CLI_R_RX")
	)
	(segment
		(start 123.707652 -204.8256)
		(end 123.707144 -204.826108)
		(width 0.15494)
		(layer "In13.Cu")
		(net "UART_PEX1_CLI_R_RX")
	)
	(segment
		(start 139.2428 -206.1972)
		(end 135.89 -206.1972)
		(width 0.15494)
		(layer "In13.Cu")
		(net "UART_PEX1_CLI_R_RX")
	)
	(segment
		(start 124.5362 -205.359)
		(end 124.0028 -204.8256)
		(width 0.15494)
		(layer "In13.Cu")
		(net "UART_PEX1_CLI_R_RX")
	)
	(segment
		(start 123.305824 -204.826108)
		(end 123.305316 -204.8256)
		(width 0.15494)
		(layer "In13.Cu")
		(net "UART_PEX1_CLI_R_RX")
	)
	(segment
		(start 112.268 -203.3016)
		(end 110.9218 -201.9554)
		(width 0.15494)
		(layer "In13.Cu")
		(net "UART_PEX1_CLI_R_RX")
	)
	(segment
		(start 147.8534 -200.0504)
		(end 147.8534 -202.8698)
		(width 0.15494)
		(layer "In13.Cu")
		(net "UART_PEX1_CLI_R_RX")
	)
	(segment
		(start 120.142 -204.8256)
		(end 118.618 -203.3016)
		(width 0.15494)
		(layer "In13.Cu")
		(net "UART_PEX1_CLI_R_RX")
	)
	(segment
		(start 123.707144 -204.826108)
		(end 123.305824 -204.826108)
		(width 0.15494)
		(layer "In13.Cu")
		(net "UART_PEX1_CLI_R_RX")
	)
	(segment
		(start 147.8534 -202.8698)
		(end 145.2626 -205.4606)
		(width 0.15494)
		(layer "In13.Cu")
		(net "UART_PEX1_CLI_R_RX")
	)
	(segment
		(start 107.7214 -201.9554)
		(end 107.6198 -202.057)
		(width 0.15494)
		(layer "In13.Cu")
		(net "UART_PEX1_CLI_R_RX")
	)
	(segment
		(start 110.9218 -201.9554)
		(end 107.7214 -201.9554)
		(width 0.15494)
		(layer "In13.Cu")
		(net "UART_PEX1_CLI_R_RX")
	)
	(segment
		(start 124.0028 -204.8256)
		(end 123.707652 -204.8256)
		(width 0.15494)
		(layer "In13.Cu")
		(net "UART_PEX1_CLI_R_RX")
	)
	(segment
		(start 123.305316 -204.8256)
		(end 120.142 -204.8256)
		(width 0.15494)
		(layer "In13.Cu")
		(net "UART_PEX1_CLI_R_RX")
	)
	(segment
		(start 118.618 -203.3016)
		(end 112.268 -203.3016)
		(width 0.15494)
		(layer "In13.Cu")
		(net "UART_PEX1_CLI_R_RX")
	)
	(segment
		(start 145.2626 -205.4606)
		(end 139.9794 -205.4606)
		(width 0.15494)
		(layer "In13.Cu")
		(net "UART_PEX1_CLI_R_RX")
	)
	(segment
		(start 139.9794 -205.4606)
		(end 139.2428 -206.1972)
		(width 0.15494)
		(layer "In13.Cu")
		(net "UART_PEX1_CLI_R_RX")
	)
	(via
		(at 128.839214 -203.745846)
		(size 0.6604)
		(drill 0.3302)
		(layers "F.Cu" "B.Cu")
		(net "FT4232_CLI_EEPROM_R_CS")
	)
	(segment
		(start 129.68351 -204.209142)
		(end 130.139694 -204.209142)
		(width 0.13208)
		(layer "B.Cu")
		(net "FT4232_CLI_EEPROM_R_CS")
	)
	(segment
		(start 128.839214 -203.745846)
		(end 129.220214 -203.745846)
		(width 0.13208)
		(layer "B.Cu")
		(net "FT4232_CLI_EEPROM_R_CS")
	)
	(segment
		(start 128.458214 -203.745846)
		(end 128.839214 -203.745846)
		(width 0.13208)
		(layer "B.Cu")
		(net "FT4232_CLI_EEPROM_R_CS")
	)
	(segment
		(start 129.220214 -203.745846)
		(end 129.68351 -204.209142)
		(width 0.13208)
		(layer "B.Cu")
		(net "FT4232_CLI_EEPROM_R_CS")
	)
	(segment
		(start 127.861822 -204.342238)
		(end 128.458214 -203.745846)
		(width 0.13208)
		(layer "B.Cu")
		(net "FT4232_CLI_EEPROM_R_CS")
	)
	(segment
		(start 130.139694 -203.193142)
		(end 130.139694 -204.209142)
		(width 0.13208)
		(layer "B.Cu")
		(net "FT4232_CLI_EEPROM_R_CS")
	)
	(segment
		(start 127.272796 -204.342238)
		(end 127.861822 -204.342238)
		(width 0.13208)
		(layer "B.Cu")
		(net "FT4232_CLI_EEPROM_R_CS")
	)
	(segment
		(start 293.605966 -205.917292)
		(end 293.605966 -205.318868)
		(width 0.13208)
		(layer "F.Cu")
		(net "SPI_BIC1_MISO_LS23_DIR4")
	)
	(segment
		(start 292.98519 -206.538068)
		(end 293.605966 -205.917292)
		(width 0.13208)
		(layer "F.Cu")
		(net "SPI_BIC1_MISO_LS23_DIR4")
	)
	(via
		(at 292.98519 -206.538068)
		(size 0.508)
		(drill 0.254)
		(layers "F.Cu" "B.Cu")
		(net "SPI_BIC1_MISO_LS23_DIR4")
	)
	(segment
		(start 291.86124 -204.887068)
		(end 291.86124 -205.776068)
		(width 0.13208)
		(layer "B.Cu")
		(net "SPI_BIC1_MISO_LS23_DIR4")
	)
	(segment
		(start 291.86124 -205.776068)
		(end 292.22319 -205.776068)
		(width 0.13208)
		(layer "B.Cu")
		(net "SPI_BIC1_MISO_LS23_DIR4")
	)
	(segment
		(start 292.22319 -205.776068)
		(end 292.98519 -206.538068)
		(width 0.13208)
		(layer "B.Cu")
		(net "SPI_BIC1_MISO_LS23_DIR4")
	)
	(via
		(at 110.66907 -330.80452)
		(size 0.6604)
		(drill 0.3302)
		(layers "F.Cu" "B.Cu")
		(net "SMB_9ZXL0451E_ADDR0")
	)
	(segment
		(start 112.02416 -329.44943)
		(end 110.66907 -330.80452)
		(width 0.13208)
		(layer "B.Cu")
		(net "SMB_9ZXL0451E_ADDR0")
	)
	(segment
		(start 113.114074 -329.44943)
		(end 112.02416 -329.44943)
		(width 0.13208)
		(layer "B.Cu")
		(net "SMB_9ZXL0451E_ADDR0")
	)
	(segment
		(start 110.626398 -330.847192)
		(end 110.66907 -330.80452)
		(width 0.13208)
		(layer "B.Cu")
		(net "SMB_9ZXL0451E_ADDR0")
	)
	(segment
		(start 109.531912 -331.300582)
		(end 110.626398 -330.847192)
		(width 0.13208)
		(layer "B.Cu")
		(net "SMB_9ZXL0451E_ADDR0")
	)
	(segment
		(start 113.114074 -328.43343)
		(end 113.114074 -329.44943)
		(width 0.13208)
		(layer "B.Cu")
		(net "SMB_9ZXL0451E_ADDR0")
	)
	(segment
		(start 108.689394 -331.300582)
		(end 109.531912 -331.300582)
		(width 0.13208)
		(layer "B.Cu")
		(net "SMB_9ZXL0451E_ADDR0")
	)
	(segment
		(start 126.76505 -22.3901)
		(end 128.567688 -22.3901)
		(width 0.13208)
		(layer "F.Cu")
		(net "SMB_ISO_SSD4_R_SCL")
	)
	(segment
		(start 138.765534 -18.437098)
		(end 139.368022 -18.437098)
		(width 0.13208)
		(layer "F.Cu")
		(net "SMB_ISO_SSD4_R_SCL")
	)
	(segment
		(start 138.758422 -18.44421)
		(end 138.765534 -18.437098)
		(width 0.13208)
		(layer "F.Cu")
		(net "SMB_ISO_SSD4_R_SCL")
	)
	(segment
		(start 128.567688 -22.3901)
		(end 129.193798 -23.01621)
		(width 0.13208)
		(layer "F.Cu")
		(net "SMB_ISO_SSD4_R_SCL")
	)
	(via
		(at 129.193798 -23.01621)
		(size 0.508)
		(drill 0.254)
		(layers "F.Cu" "B.Cu")
		(net "SMB_ISO_SSD4_R_SCL")
	)
	(via
		(at 138.758422 -18.44421)
		(size 0.508)
		(drill 0.254)
		(layers "F.Cu" "B.Cu")
		(net "SMB_ISO_SSD4_R_SCL")
	)
	(segment
		(start 137.783062 -23.01621)
		(end 129.193798 -23.01621)
		(width 0.15494)
		(layer "In5.Cu")
		(net "SMB_ISO_SSD4_R_SCL")
	)
	(segment
		(start 139.327128 -19.012916)
		(end 139.327128 -21.472144)
		(width 0.15494)
		(layer "In5.Cu")
		(net "SMB_ISO_SSD4_R_SCL")
	)
	(segment
		(start 138.758422 -18.44421)
		(end 139.327128 -19.012916)
		(width 0.15494)
		(layer "In5.Cu")
		(net "SMB_ISO_SSD4_R_SCL")
	)
	(segment
		(start 139.327128 -21.472144)
		(end 137.783062 -23.01621)
		(width 0.15494)
		(layer "In5.Cu")
		(net "SMB_ISO_SSD4_R_SCL")
	)
	(via
		(at 104.394 -371.729)
		(size 0.508)
		(drill 0.254)
		(layers "F.Cu" "B.Cu")
		(net "RST_GPU_PERST_2_BUF_R_N")
	)
	(via
		(at 191.77889 -366.655096)
		(size 0.508)
		(drill 0.254)
		(layers "F.Cu" "B.Cu")
		(net "RST_GPU_PERST_2_BUF_R_N")
	)
	(via
		(at 277.563326 -237.99165)
		(size 0.508)
		(drill 0.254)
		(layers "F.Cu" "B.Cu")
		(net "RST_GPU_PERST_2_BUF_R_N")
	)
	(via
		(at 65.000886 -391.678922)
		(size 0.508)
		(drill 0.254)
		(layers "F.Cu" "B.Cu")
		(net "RST_GPU_PERST_2_BUF_R_N")
	)
	(segment
		(start 277.563326 -237.99165)
		(end 278.51989 -238.948214)
		(width 0.13208)
		(layer "B.Cu")
		(net "RST_GPU_PERST_2_BUF_R_N")
	)
	(segment
		(start 300.07941 -238.948214)
		(end 300.9773 -238.050324)
		(width 0.13208)
		(layer "B.Cu")
		(net "RST_GPU_PERST_2_BUF_R_N")
	)
	(segment
		(start 301.09668 -237.136686)
		(end 301.536354 -237.136686)
		(width 0.13208)
		(layer "B.Cu")
		(net "RST_GPU_PERST_2_BUF_R_N")
	)
	(segment
		(start 104.394 -371.729)
		(end 104.412542 -371.710458)
		(width 0.13208)
		(layer "B.Cu")
		(net "RST_GPU_PERST_2_BUF_R_N")
	)
	(segment
		(start 116.389912 -363.508544)
		(end 188.632338 -363.508544)
		(width 0.13208)
		(layer "B.Cu")
		(net "RST_GPU_PERST_2_BUF_R_N")
	)
	(segment
		(start 300.9773 -237.256066)
		(end 301.09668 -237.136686)
		(width 0.13208)
		(layer "B.Cu")
		(net "RST_GPU_PERST_2_BUF_R_N")
	)
	(segment
		(start 278.51989 -238.948214)
		(end 300.07941 -238.948214)
		(width 0.13208)
		(layer "B.Cu")
		(net "RST_GPU_PERST_2_BUF_R_N")
	)
	(segment
		(start 300.9773 -238.050324)
		(end 300.9773 -237.256066)
		(width 0.13208)
		(layer "B.Cu")
		(net "RST_GPU_PERST_2_BUF_R_N")
	)
	(segment
		(start 188.632338 -363.508544)
		(end 191.77889 -366.655096)
		(width 0.13208)
		(layer "B.Cu")
		(net "RST_GPU_PERST_2_BUF_R_N")
	)
	(segment
		(start 108.187998 -371.710458)
		(end 116.389912 -363.508544)
		(width 0.13208)
		(layer "B.Cu")
		(net "RST_GPU_PERST_2_BUF_R_N")
	)
	(segment
		(start 104.412542 -371.710458)
		(end 108.187998 -371.710458)
		(width 0.13208)
		(layer "B.Cu")
		(net "RST_GPU_PERST_2_BUF_R_N")
	)
	(segment
		(start 201.410316 -364.554516)
		(end 200.832974 -365.131858)
		(width 0.15494)
		(layer "In5.Cu")
		(net "RST_GPU_PERST_2_BUF_R_N")
	)
	(segment
		(start 277.563326 -237.99165)
		(end 276.594316 -238.96066)
		(width 0.15494)
		(layer "In5.Cu")
		(net "RST_GPU_PERST_2_BUF_R_N")
	)
	(segment
		(start 252.723904 -305.74615)
		(end 245.7704 -322.534788)
		(width 0.15494)
		(layer "In5.Cu")
		(net "RST_GPU_PERST_2_BUF_R_N")
	)
	(segment
		(start 201.811636 -364.554516)
		(end 201.410316 -364.554516)
		(width 0.15494)
		(layer "In5.Cu")
		(net "RST_GPU_PERST_2_BUF_R_N")
	)
	(segment
		(start 207.76184 -359.504488)
		(end 205.330806 -361.935522)
		(width 0.15494)
		(layer "In5.Cu")
		(net "RST_GPU_PERST_2_BUF_R_N")
	)
	(segment
		(start 203.763626 -364.9218)
		(end 202.17892 -364.9218)
		(width 0.15494)
		(layer "In5.Cu")
		(net "RST_GPU_PERST_2_BUF_R_N")
	)
	(segment
		(start 258.903216 -277.849584)
		(end 257.1242 -279.6286)
		(width 0.15494)
		(layer "In5.Cu")
		(net "RST_GPU_PERST_2_BUF_R_N")
	)
	(segment
		(start 257.1242 -298.214542)
		(end 254.910082 -303.559972)
		(width 0.15494)
		(layer "In5.Cu")
		(net "RST_GPU_PERST_2_BUF_R_N")
	)
	(segment
		(start 202.17892 -364.9218)
		(end 201.811636 -364.554516)
		(width 0.15494)
		(layer "In5.Cu")
		(net "RST_GPU_PERST_2_BUF_R_N")
	)
	(segment
		(start 205.330806 -362.663994)
		(end 204.51445 -363.48035)
		(width 0.15494)
		(layer "In5.Cu")
		(net "RST_GPU_PERST_2_BUF_R_N")
	)
	(segment
		(start 200.832974 -365.131858)
		(end 197.093586 -365.131858)
		(width 0.15494)
		(layer "In5.Cu")
		(net "RST_GPU_PERST_2_BUF_R_N")
	)
	(segment
		(start 204.49794 -364.054136)
		(end 204.49794 -364.187486)
		(width 0.15494)
		(layer "In5.Cu")
		(net "RST_GPU_PERST_2_BUF_R_N")
	)
	(segment
		(start 205.330806 -361.935522)
		(end 205.330806 -362.663994)
		(width 0.15494)
		(layer "In5.Cu")
		(net "RST_GPU_PERST_2_BUF_R_N")
	)
	(segment
		(start 254.910082 -303.559972)
		(end 252.723904 -305.74615)
		(width 0.15494)
		(layer "In5.Cu")
		(net "RST_GPU_PERST_2_BUF_R_N")
	)
	(segment
		(start 219.982796 -359.504488)
		(end 207.76184 -359.504488)
		(width 0.15494)
		(layer "In5.Cu")
		(net "RST_GPU_PERST_2_BUF_R_N")
	)
	(segment
		(start 276.594316 -238.96066)
		(end 276.594316 -266.751816)
		(width 0.15494)
		(layer "In5.Cu")
		(net "RST_GPU_PERST_2_BUF_R_N")
	)
	(segment
		(start 263.049004 -277.849584)
		(end 258.903216 -277.849584)
		(width 0.15494)
		(layer "In5.Cu")
		(net "RST_GPU_PERST_2_BUF_R_N")
	)
	(segment
		(start 204.51445 -364.037626)
		(end 204.49794 -364.054136)
		(width 0.15494)
		(layer "In5.Cu")
		(net "RST_GPU_PERST_2_BUF_R_N")
	)
	(segment
		(start 233.78922 -345.698064)
		(end 219.982796 -359.504488)
		(width 0.15494)
		(layer "In5.Cu")
		(net "RST_GPU_PERST_2_BUF_R_N")
	)
	(segment
		(start 245.7704 -322.534788)
		(end 233.78922 -334.515968)
		(width 0.15494)
		(layer "In5.Cu")
		(net "RST_GPU_PERST_2_BUF_R_N")
	)
	(segment
		(start 204.51445 -363.48035)
		(end 204.51445 -364.037626)
		(width 0.15494)
		(layer "In5.Cu")
		(net "RST_GPU_PERST_2_BUF_R_N")
	)
	(segment
		(start 273.203416 -270.142716)
		(end 270.755872 -270.142716)
		(width 0.15494)
		(layer "In5.Cu")
		(net "RST_GPU_PERST_2_BUF_R_N")
	)
	(segment
		(start 276.594316 -266.751816)
		(end 273.203416 -270.142716)
		(width 0.15494)
		(layer "In5.Cu")
		(net "RST_GPU_PERST_2_BUF_R_N")
	)
	(segment
		(start 204.49794 -364.187486)
		(end 203.763626 -364.9218)
		(width 0.15494)
		(layer "In5.Cu")
		(net "RST_GPU_PERST_2_BUF_R_N")
	)
	(segment
		(start 195.570348 -366.655096)
		(end 191.77889 -366.655096)
		(width 0.15494)
		(layer "In5.Cu")
		(net "RST_GPU_PERST_2_BUF_R_N")
	)
	(segment
		(start 270.755872 -270.142716)
		(end 263.049004 -277.849584)
		(width 0.15494)
		(layer "In5.Cu")
		(net "RST_GPU_PERST_2_BUF_R_N")
	)
	(segment
		(start 233.78922 -334.515968)
		(end 233.78922 -345.698064)
		(width 0.15494)
		(layer "In5.Cu")
		(net "RST_GPU_PERST_2_BUF_R_N")
	)
	(segment
		(start 257.1242 -279.6286)
		(end 257.1242 -298.214542)
		(width 0.15494)
		(layer "In5.Cu")
		(net "RST_GPU_PERST_2_BUF_R_N")
	)
	(segment
		(start 197.093586 -365.131858)
		(end 195.570348 -366.655096)
		(width 0.15494)
		(layer "In5.Cu")
		(net "RST_GPU_PERST_2_BUF_R_N")
	)
	(segment
		(start 30.65272 -414.8328)
		(end 27.910028 -412.090108)
		(width 0.15494)
		(layer "In9.Cu")
		(net "RST_GPU_PERST_2_BUF_R_N")
	)
	(segment
		(start 65.000886 -391.678922)
		(end 62.573408 -394.1064)
		(width 0.15494)
		(layer "In9.Cu")
		(net "RST_GPU_PERST_2_BUF_R_N")
	)
	(segment
		(start 52.9336 -394.2334)
		(end 52.9336 -414.0962)
		(width 0.15494)
		(layer "In9.Cu")
		(net "RST_GPU_PERST_2_BUF_R_N")
	)
	(segment
		(start 53.0606 -394.1064)
		(end 52.9336 -394.2334)
		(width 0.15494)
		(layer "In9.Cu")
		(net "RST_GPU_PERST_2_BUF_R_N")
	)
	(segment
		(start 62.573408 -394.1064)
		(end 53.0606 -394.1064)
		(width 0.15494)
		(layer "In9.Cu")
		(net "RST_GPU_PERST_2_BUF_R_N")
	)
	(segment
		(start 50.673 -416.3568)
		(end 45.7454 -416.3568)
		(width 0.15494)
		(layer "In9.Cu")
		(net "RST_GPU_PERST_2_BUF_R_N")
	)
	(segment
		(start 45.7454 -416.3568)
		(end 44.2214 -414.8328)
		(width 0.15494)
		(layer "In9.Cu")
		(net "RST_GPU_PERST_2_BUF_R_N")
	)
	(segment
		(start 52.9336 -414.0962)
		(end 50.673 -416.3568)
		(width 0.15494)
		(layer "In9.Cu")
		(net "RST_GPU_PERST_2_BUF_R_N")
	)
	(segment
		(start 44.2214 -414.8328)
		(end 30.65272 -414.8328)
		(width 0.15494)
		(layer "In9.Cu")
		(net "RST_GPU_PERST_2_BUF_R_N")
	)
	(segment
		(start 91.403678 -391.678922)
		(end 65.000886 -391.678922)
		(width 0.15494)
		(layer "In15.Cu")
		(net "RST_GPU_PERST_2_BUF_R_N")
	)
	(segment
		(start 98.1202 -384.9624)
		(end 91.403678 -391.678922)
		(width 0.15494)
		(layer "In15.Cu")
		(net "RST_GPU_PERST_2_BUF_R_N")
	)
	(segment
		(start 98.1202 -378.0028)
		(end 98.1202 -384.9624)
		(width 0.15494)
		(layer "In15.Cu")
		(net "RST_GPU_PERST_2_BUF_R_N")
	)
	(segment
		(start 104.394 -371.729)
		(end 98.1202 -378.0028)
		(width 0.15494)
		(layer "In15.Cu")
		(net "RST_GPU_PERST_2_BUF_R_N")
	)
	(segment
		(start 330.150978 -119.89308)
		(end 330.150978 -119.569992)
		(width 0.13208)
		(layer "F.Cu")
		(net "PWRGD_P3V3_NIC5")
	)
	(segment
		(start 329.502262 -120.541796)
		(end 330.150978 -119.89308)
		(width 0.13208)
		(layer "F.Cu")
		(net "PWRGD_P3V3_NIC5")
	)
	(segment
		(start 330.243942 -119.477028)
		(end 330.775564 -119.477028)
		(width 0.13208)
		(layer "F.Cu")
		(net "PWRGD_P3V3_NIC5")
	)
	(segment
		(start 328.971402 -120.541796)
		(end 329.502262 -120.541796)
		(width 0.13208)
		(layer "F.Cu")
		(net "PWRGD_P3V3_NIC5")
	)
	(segment
		(start 330.775564 -120.493028)
		(end 330.775564 -119.477028)
		(width 0.13208)
		(layer "F.Cu")
		(net "PWRGD_P3V3_NIC5")
	)
	(segment
		(start 330.150978 -119.569992)
		(end 330.243942 -119.477028)
		(width 0.13208)
		(layer "F.Cu")
		(net "PWRGD_P3V3_NIC5")
	)
	(via
		(at 330.150978 -119.89308)
		(size 0.508)
		(drill 0.254)
		(layers "F.Cu" "B.Cu")
		(net "PWRGD_P3V3_NIC5")
	)
	(segment
		(start 145.283936 -198.31177)
		(end 145.283936 -199.264778)
		(width 0.13208)
		(layer "F.Cu")
		(net "UART_PEX1_CLI_RX")
	)
	(segment
		(start 145.297906 -198.2978)
		(end 145.283936 -198.31177)
		(width 0.13208)
		(layer "F.Cu")
		(net "UART_PEX1_CLI_RX")
	)
	(segment
		(start 146.746214 -201.911712)
		(end 145.283936 -200.449434)
		(width 0.13208)
		(layer "F.Cu")
		(net "UART_PEX1_CLI_RX")
	)
	(segment
		(start 146.746214 -206.539846)
		(end 146.746214 -201.911712)
		(width 0.13208)
		(layer "F.Cu")
		(net "UART_PEX1_CLI_RX")
	)
	(segment
		(start 145.28165 -206.964026)
		(end 146.322034 -206.964026)
		(width 0.13208)
		(layer "F.Cu")
		(net "UART_PEX1_CLI_RX")
	)
	(segment
		(start 146.322034 -206.964026)
		(end 146.746214 -206.539846)
		(width 0.13208)
		(layer "F.Cu")
		(net "UART_PEX1_CLI_RX")
	)
	(segment
		(start 145.283936 -200.449434)
		(end 145.283936 -199.264778)
		(width 0.13208)
		(layer "F.Cu")
		(net "UART_PEX1_CLI_RX")
	)
	(via
		(at 145.283936 -199.264778)
		(size 0.508)
		(drill 0.254)
		(layers "F.Cu" "B.Cu")
		(net "UART_PEX1_CLI_RX")
	)
	(via
		(at 128.966214 -205.225142)
		(size 0.6604)
		(drill 0.3302)
		(layers "F.Cu" "B.Cu")
		(net "FT4232_CLI_EEPROM_R_SCL")
	)
	(segment
		(start 130.139694 -206.241142)
		(end 130.139694 -205.225142)
		(width 0.13208)
		(layer "B.Cu")
		(net "FT4232_CLI_EEPROM_R_SCL")
	)
	(segment
		(start 127.272796 -205.292198)
		(end 127.339852 -205.225142)
		(width 0.13208)
		(layer "B.Cu")
		(net "FT4232_CLI_EEPROM_R_SCL")
	)
	(segment
		(start 127.339852 -205.225142)
		(end 128.966214 -205.225142)
		(width 0.13208)
		(layer "B.Cu")
		(net "FT4232_CLI_EEPROM_R_SCL")
	)
	(segment
		(start 128.966214 -205.225142)
		(end 130.139694 -205.225142)
		(width 0.13208)
		(layer "B.Cu")
		(net "FT4232_CLI_EEPROM_R_SCL")
	)
	(segment
		(start 334.717898 -87.364316)
		(end 334.64881 -87.433404)
		(width 0.13462)
		(layer "F.Cu")
		(net "CLK_100M_CK440Q_2_DB800ZL_R_DN")
	)
	(segment
		(start 333.162656 -86.952074)
		(end 332.206854 -86.761828)
		(width 0.13462)
		(layer "F.Cu")
		(net "CLK_100M_CK440Q_2_DB800ZL_R_DN")
	)
	(segment
		(start 334.32623 -87.433404)
		(end 333.162656 -86.952074)
		(width 0.13462)
		(layer "F.Cu")
		(net "CLK_100M_CK440Q_2_DB800ZL_R_DN")
	)
	(segment
		(start 335.145634 -87.364316)
		(end 334.717898 -87.364316)
		(width 0.13462)
		(layer "F.Cu")
		(net "CLK_100M_CK440Q_2_DB800ZL_R_DN")
	)
	(segment
		(start 262.89 -76.56449)
		(end 262.581644 -76.872846)
		(width 0.13462)
		(layer "F.Cu")
		(net "CLK_100M_CK440Q_2_DB800ZL_R_DN")
	)
	(segment
		(start 334.64881 -87.433404)
		(end 334.32623 -87.433404)
		(width 0.13462)
		(layer "F.Cu")
		(net "CLK_100M_CK440Q_2_DB800ZL_R_DN")
	)
	(segment
		(start 331.236574 -86.761828)
		(end 330.935584 -86.460838)
		(width 0.13462)
		(layer "F.Cu")
		(net "CLK_100M_CK440Q_2_DB800ZL_R_DN")
	)
	(segment
		(start 262.60806 -75.258422)
		(end 262.89 -75.540362)
		(width 0.13462)
		(layer "F.Cu")
		(net "CLK_100M_CK440Q_2_DB800ZL_R_DN")
	)
	(segment
		(start 332.206854 -86.761828)
		(end 331.236574 -86.761828)
		(width 0.13462)
		(layer "F.Cu")
		(net "CLK_100M_CK440Q_2_DB800ZL_R_DN")
	)
	(segment
		(start 262.89 -75.540362)
		(end 262.89 -76.56449)
		(width 0.13462)
		(layer "F.Cu")
		(net "CLK_100M_CK440Q_2_DB800ZL_R_DN")
	)
	(segment
		(start 262.581644 -76.872846)
		(end 262.581644 -76.879704)
		(width 0.13462)
		(layer "F.Cu")
		(net "CLK_100M_CK440Q_2_DB800ZL_R_DN")
	)
	(via
		(at 262.60806 -75.258422)
		(size 0.508)
		(drill 0.254)
		(layers "F.Cu" "B.Cu")
		(net "CLK_100M_CK440Q_2_DB800ZL_R_DN")
	)
	(via
		(at 330.935584 -86.460838)
		(size 0.508)
		(drill 0.254)
		(layers "F.Cu" "B.Cu")
		(net "CLK_100M_CK440Q_2_DB800ZL_R_DN")
	)
	(segment
		(start 273.42084 -75.76566)
		(end 317.21806 -75.76566)
		(width 0.1651)
		(layer "In13.Cu")
		(net "CLK_100M_CK440Q_2_DB800ZL_R_DN")
	)
	(segment
		(start 328.204068 -86.751668)
		(end 330.644754 -86.751668)
		(width 0.1651)
		(layer "In13.Cu")
		(net "CLK_100M_CK440Q_2_DB800ZL_R_DN")
	)
	(segment
		(start 263.474962 -74.041)
		(end 271.69618 -74.041)
		(width 0.1651)
		(layer "In13.Cu")
		(net "CLK_100M_CK440Q_2_DB800ZL_R_DN")
	)
	(segment
		(start 262.89889 -74.617072)
		(end 263.474962 -74.041)
		(width 0.1651)
		(layer "In13.Cu")
		(net "CLK_100M_CK440Q_2_DB800ZL_R_DN")
	)
	(segment
		(start 330.644754 -86.751668)
		(end 330.935584 -86.460838)
		(width 0.1651)
		(layer "In13.Cu")
		(net "CLK_100M_CK440Q_2_DB800ZL_R_DN")
	)
	(segment
		(start 317.21806 -75.76566)
		(end 328.204068 -86.751668)
		(width 0.1651)
		(layer "In13.Cu")
		(net "CLK_100M_CK440Q_2_DB800ZL_R_DN")
	)
	(segment
		(start 262.89889 -74.967592)
		(end 262.89889 -74.617072)
		(width 0.1651)
		(layer "In13.Cu")
		(net "CLK_100M_CK440Q_2_DB800ZL_R_DN")
	)
	(segment
		(start 262.60806 -75.258422)
		(end 262.89889 -74.967592)
		(width 0.1651)
		(layer "In13.Cu")
		(net "CLK_100M_CK440Q_2_DB800ZL_R_DN")
	)
	(segment
		(start 271.69618 -74.041)
		(end 273.42084 -75.76566)
		(width 0.1651)
		(layer "In13.Cu")
		(net "CLK_100M_CK440Q_2_DB800ZL_R_DN")
	)
	(segment
		(start 10.664952 -22.990048)
		(end 11.680952 -22.990048)
		(width 0.13208)
		(layer "F.Cu")
		(net "SMB_ISO_SSD0_R_SDA")
	)
	(segment
		(start 3.630168 -23.943056)
		(end 3.623056 -23.935944)
		(width 0.13208)
		(layer "F.Cu")
		(net "SMB_ISO_SSD0_R_SDA")
	)
	(segment
		(start 3.630168 -24.545544)
		(end 3.630168 -23.943056)
		(width 0.13208)
		(layer "F.Cu")
		(net "SMB_ISO_SSD0_R_SDA")
	)
	(via
		(at 11.680952 -22.990048)
		(size 0.508)
		(drill 0.254)
		(layers "F.Cu" "B.Cu")
		(net "SMB_ISO_SSD0_R_SDA")
	)
	(via
		(at 3.623056 -23.935944)
		(size 0.508)
		(drill 0.254)
		(layers "F.Cu" "B.Cu")
		(net "SMB_ISO_SSD0_R_SDA")
	)
	(segment
		(start 10.807192 -23.863808)
		(end 11.680952 -22.990048)
		(width 0.15494)
		(layer "In5.Cu")
		(net "SMB_ISO_SSD0_R_SDA")
	)
	(segment
		(start 3.623056 -23.935944)
		(end 3.695192 -23.863808)
		(width 0.15494)
		(layer "In5.Cu")
		(net "SMB_ISO_SSD0_R_SDA")
	)
	(segment
		(start 3.695192 -23.863808)
		(end 10.807192 -23.863808)
		(width 0.15494)
		(layer "In5.Cu")
		(net "SMB_ISO_SSD0_R_SDA")
	)
	(segment
		(start 218.313 -204.216)
		(end 217.764106 -203.667106)
		(width 0.3556)
		(layer "F.Cu")
		(net "P3V3_NIC5")
	)
	(segment
		(start 296.277792 -113.251742)
		(end 296.888154 -113.251742)
		(width 0.4572)
		(layer "F.Cu")
		(net "P3V3_NIC5")
	)
	(segment
		(start 219.60205 -202.184)
		(end 219.60205 -201.168)
		(width 0.381)
		(layer "F.Cu")
		(net "P3V3_NIC5")
	)
	(segment
		(start 333.730346 -120.79224)
		(end 333.117952 -120.79224)
		(width 0.4572)
		(layer "F.Cu")
		(net "P3V3_NIC5")
	)
	(segment
		(start 315.26607 -77.206348)
		(end 315.26607 -77.889608)
		(width 0.4572)
		(layer "F.Cu")
		(net "P3V3_NIC5")
	)
	(segment
		(start 217.764106 -203.667106)
		(end 216.991946 -203.667106)
		(width 0.3556)
		(layer "F.Cu")
		(net "P3V3_NIC5")
	)
	(segment
		(start 295.008554 -157.680152)
		(end 295.008554 -157.045152)
		(width 0.4064)
		(layer "F.Cu")
		(net "P3V3_NIC5")
	)
	(segment
		(start 218.80195 -204.216)
		(end 218.80195 -204.851)
		(width 0.4572)
		(layer "F.Cu")
		(net "P3V3_NIC5")
	)
	(segment
		(start 311.514744 -79.18196)
		(end 312.173112 -79.18196)
		(width 0.4572)
		(layer "F.Cu")
		(net "P3V3_NIC5")
	)
	(segment
		(start 219.60205 -201.168)
		(end 220.218 -201.168)
		(width 0.381)
		(layer "F.Cu")
		(net "P3V3_NIC5")
	)
	(segment
		(start 219.60205 -203.2)
		(end 219.60205 -202.184)
		(width 0.381)
		(layer "F.Cu")
		(net "P3V3_NIC5")
	)
	(segment
		(start 315.3664 -77.989938)
		(end 315.3664 -79.463646)
		(width 0.4572)
		(layer "F.Cu")
		(net "P3V3_NIC5")
	)
	(segment
		(start 315.26607 -77.889608)
		(end 315.3664 -77.989938)
		(width 0.4572)
		(layer "F.Cu")
		(net "P3V3_NIC5")
	)
	(segment
		(start 331.575664 -119.477028)
		(end 332.19009 -119.477028)
		(width 0.4572)
		(layer "F.Cu")
		(net "P3V3_NIC5")
	)
	(segment
		(start 218.80195 -204.216)
		(end 218.313 -204.216)
		(width 0.3556)
		(layer "F.Cu")
		(net "P3V3_NIC5")
	)
	(segment
		(start 290.794948 -100.766372)
		(end 290.17976 -100.766372)
		(width 0.4064)
		(layer "F.Cu")
		(net "P3V3_NIC5")
	)
	(via
		(at 322.032122 -120.922034)
		(size 0.508)
		(drill 0.254)
		(layers "F.Cu" "B.Cu")
		(net "P3V3_NIC5")
	)
	(via
		(at 323.70141 -121.171462)
		(size 0.508)
		(drill 0.254)
		(layers "F.Cu" "B.Cu")
		(net "P3V3_NIC5")
	)
	(via
		(at 325.280274 -121.969276)
		(size 0.508)
		(drill 0.254)
		(layers "F.Cu" "B.Cu")
		(net "P3V3_NIC5")
	)
	(via
		(at 220.218 -201.168)
		(size 0.508)
		(drill 0.254)
		(layers "F.Cu" "B.Cu")
		(net "P3V3_NIC5")
	)
	(via
		(at 324.085458 -117.36324)
		(size 0.508)
		(drill 0.254)
		(layers "F.Cu" "B.Cu")
		(net "P3V3_NIC5")
	)
	(via
		(at 306.69992 -115.360958)
		(size 0.508)
		(drill 0.254)
		(layers "F.Cu" "B.Cu")
		(net "P3V3_NIC5")
	)
	(via
		(at 312.173112 -79.18196)
		(size 0.508)
		(drill 0.254)
		(layers "F.Cu" "B.Cu")
		(net "P3V3_NIC5")
	)
	(via
		(at 322.032122 -122.192034)
		(size 0.508)
		(drill 0.254)
		(layers "F.Cu" "B.Cu")
		(net "P3V3_NIC5")
	)
	(via
		(at 307.33492 -115.360958)
		(size 0.508)
		(drill 0.254)
		(layers "F.Cu" "B.Cu")
		(net "P3V3_NIC5")
	)
	(via
		(at 313.124342 -115.965986)
		(size 0.6604)
		(drill 0.3302)
		(layers "F.Cu" "B.Cu")
		(net "P3V3_NIC5")
	)
	(via
		(at 297.29811 -172.170344)
		(size 0.508)
		(drill 0.254)
		(layers "F.Cu" "B.Cu")
		(net "P3V3_NIC5")
	)
	(via
		(at 324.585838 -120.999504)
		(size 0.508)
		(drill 0.254)
		(layers "F.Cu" "B.Cu")
		(net "P3V3_NIC5")
	)
	(via
		(at 226.685094 -169.334434)
		(size 0.508)
		(drill 0.254)
		(layers "F.Cu" "B.Cu")
		(net "P3V3_NIC5")
	)
	(via
		(at 302.036988 -112.421924)
		(size 0.508)
		(drill 0.254)
		(layers "F.Cu" "B.Cu")
		(net "P3V3_NIC5")
	)
	(via
		(at 323.06641 -121.171462)
		(size 0.508)
		(drill 0.254)
		(layers "F.Cu" "B.Cu")
		(net "P3V3_NIC5")
	)
	(via
		(at 310.751474 -97.005648)
		(size 0.508)
		(drill 0.254)
		(layers "F.Cu" "B.Cu")
		(net "P3V3_NIC5")
	)
	(via
		(at 324.585838 -121.634504)
		(size 0.508)
		(drill 0.254)
		(layers "F.Cu" "B.Cu")
		(net "P3V3_NIC5")
	)
	(via
		(at 295.008554 -157.045152)
		(size 0.508)
		(drill 0.254)
		(layers "F.Cu" "B.Cu")
		(net "P3V3_NIC5")
	)
	(via
		(at 322.032122 -121.557034)
		(size 0.508)
		(drill 0.254)
		(layers "F.Cu" "B.Cu")
		(net "P3V3_NIC5")
	)
	(via
		(at 310.751474 -101.069648)
		(size 0.508)
		(drill 0.254)
		(layers "F.Cu" "B.Cu")
		(net "P3V3_NIC5")
	)
	(via
		(at 306.69992 -114.725958)
		(size 0.508)
		(drill 0.254)
		(layers "F.Cu" "B.Cu")
		(net "P3V3_NIC5")
	)
	(via
		(at 332.19009 -119.477028)
		(size 0.508)
		(drill 0.254)
		(layers "F.Cu" "B.Cu")
		(net "P3V3_NIC5")
	)
	(via
		(at 218.80195 -204.851)
		(size 0.508)
		(drill 0.254)
		(layers "F.Cu" "B.Cu")
		(net "P3V3_NIC5")
	)
	(via
		(at 333.117952 -120.79224)
		(size 0.508)
		(drill 0.254)
		(layers "F.Cu" "B.Cu")
		(net "P3V3_NIC5")
	)
	(via
		(at 325.280274 -121.334276)
		(size 0.508)
		(drill 0.254)
		(layers "F.Cu" "B.Cu")
		(net "P3V3_NIC5")
	)
	(via
		(at 290.17976 -100.766372)
		(size 0.508)
		(drill 0.254)
		(layers "F.Cu" "B.Cu")
		(net "P3V3_NIC5")
	)
	(via
		(at 296.888154 -113.251742)
		(size 0.508)
		(drill 0.254)
		(layers "F.Cu" "B.Cu")
		(net "P3V3_NIC5")
	)
	(via
		(at 323.323458 -117.36324)
		(size 0.508)
		(drill 0.254)
		(layers "F.Cu" "B.Cu")
		(net "P3V3_NIC5")
	)
	(via
		(at 310.751474 -95.989648)
		(size 0.508)
		(drill 0.254)
		(layers "F.Cu" "B.Cu")
		(net "P3V3_NIC5")
	)
	(via
		(at 307.33492 -114.725958)
		(size 0.508)
		(drill 0.254)
		(layers "F.Cu" "B.Cu")
		(net "P3V3_NIC5")
	)
	(via
		(at 318.09182 -115.82527)
		(size 0.6604)
		(drill 0.3302)
		(layers "F.Cu" "B.Cu")
		(net "P3V3_NIC5")
	)
	(via
		(at 315.26607 -77.206348)
		(size 0.508)
		(drill 0.254)
		(layers "F.Cu" "B.Cu")
		(net "P3V3_NIC5")
	)
	(via
		(at 301.939706 -113.437924)
		(size 0.508)
		(drill 0.254)
		(layers "F.Cu" "B.Cu")
		(net "P3V3_NIC5")
	)
	(via
		(at 322.032122 -120.287034)
		(size 0.508)
		(drill 0.254)
		(layers "F.Cu" "B.Cu")
		(net "P3V3_NIC5")
	)
	(segment
		(start 301.272194 -112.421924)
		(end 302.036988 -112.421924)
		(width 0.4572)
		(layer "B.Cu")
		(net "P3V3_NIC5")
	)
	(segment
		(start 301.272194 -113.437924)
		(end 301.939706 -113.437924)
		(width 0.4572)
		(layer "B.Cu")
		(net "P3V3_NIC5")
	)
	(segment
		(start 310.141874 -97.005648)
		(end 310.751474 -97.005648)
		(width 0.4572)
		(layer "B.Cu")
		(net "P3V3_NIC5")
	)
	(segment
		(start 310.141874 -101.069648)
		(end 310.751474 -101.069648)
		(width 0.4572)
		(layer "B.Cu")
		(net "P3V3_NIC5")
	)
	(segment
		(start 310.141874 -95.989648)
		(end 310.751474 -95.989648)
		(width 0.4572)
		(layer "B.Cu")
		(net "P3V3_NIC5")
	)
	(segment
		(start 297.29811 -172.170344)
		(end 296.637456 -171.50969)
		(width 0.508)
		(layer "In5.Cu")
		(net "P3V3_NIC5")
	)
	(segment
		(start 295.008554 -160.276794)
		(end 295.008554 -157.045152)
		(width 0.508)
		(layer "In5.Cu")
		(net "P3V3_NIC5")
	)
	(segment
		(start 293.383208 -114.2238)
		(end 294.355266 -113.251742)
		(width 0.508)
		(layer "In5.Cu")
		(net "P3V3_NIC5")
	)
	(segment
		(start 294.355266 -113.251742)
		(end 296.888154 -113.251742)
		(width 0.508)
		(layer "In5.Cu")
		(net "P3V3_NIC5")
	)
	(segment
		(start 295.008554 -157.045152)
		(end 295.008554 -144.08658)
		(width 0.508)
		(layer "In5.Cu")
		(net "P3V3_NIC5")
	)
	(segment
		(start 293.383208 -142.461234)
		(end 293.383208 -114.2238)
		(width 0.508)
		(layer "In5.Cu")
		(net "P3V3_NIC5")
	)
	(segment
		(start 295.008554 -144.08658)
		(end 293.383208 -142.461234)
		(width 0.508)
		(layer "In5.Cu")
		(net "P3V3_NIC5")
	)
	(segment
		(start 296.637456 -161.905696)
		(end 295.008554 -160.276794)
		(width 0.508)
		(layer "In5.Cu")
		(net "P3V3_NIC5")
	)
	(segment
		(start 296.637456 -171.50969)
		(end 296.637456 -161.905696)
		(width 0.508)
		(layer "In5.Cu")
		(net "P3V3_NIC5")
	)
	(segment
		(start 306.761388 -83.450938)
		(end 311.030366 -79.18196)
		(width 0.508)
		(layer "In7.Cu")
		(net "P3V3_NIC5")
	)
	(segment
		(start 310.751474 -95.989648)
		(end 310.205882 -95.444056)
		(width 0.508)
		(layer "In7.Cu")
		(net "P3V3_NIC5")
	)
	(segment
		(start 310.751474 -97.005648)
		(end 310.751474 -95.989648)
		(width 0.508)
		(layer "In7.Cu")
		(net "P3V3_NIC5")
	)
	(segment
		(start 309.207916 -95.444056)
		(end 306.761388 -92.997528)
		(width 0.508)
		(layer "In7.Cu")
		(net "P3V3_NIC5")
	)
	(segment
		(start 306.761388 -92.997528)
		(end 306.761388 -83.450938)
		(width 0.508)
		(layer "In7.Cu")
		(net "P3V3_NIC5")
	)
	(segment
		(start 312.173112 -79.18196)
		(end 313.017408 -78.337664)
		(width 0.508)
		(layer "In7.Cu")
		(net "P3V3_NIC5")
	)
	(segment
		(start 314.249816 -78.337664)
		(end 315.26607 -77.32141)
		(width 0.508)
		(layer "In7.Cu")
		(net "P3V3_NIC5")
	)
	(segment
		(start 311.030366 -79.18196)
		(end 312.173112 -79.18196)
		(width 0.508)
		(layer "In7.Cu")
		(net "P3V3_NIC5")
	)
	(segment
		(start 315.26607 -77.32141)
		(end 315.26607 -77.206348)
		(width 0.508)
		(layer "In7.Cu")
		(net "P3V3_NIC5")
	)
	(segment
		(start 313.017408 -78.337664)
		(end 314.249816 -78.337664)
		(width 0.508)
		(layer "In7.Cu")
		(net "P3V3_NIC5")
	)
	(segment
		(start 310.205882 -95.444056)
		(end 309.207916 -95.444056)
		(width 0.508)
		(layer "In7.Cu")
		(net "P3V3_NIC5")
	)
	(segment
		(start 222.28302 -199.10298)
		(end 220.218 -201.168)
		(width 0.508)
		(layer "In9.Cu")
		(net "P3V3_NIC5")
	)
	(segment
		(start 219.304616 -203.732638)
		(end 219.304616 -202.081384)
		(width 0.508)
		(layer "In9.Cu")
		(net "P3V3_NIC5")
	)
	(segment
		(start 225.548952 -189.5094)
		(end 225.548952 -189.512956)
		(width 0.508)
		(layer "In9.Cu")
		(net "P3V3_NIC5")
	)
	(segment
		(start 225.533712 -189.549786)
		(end 225.531426 -189.552072)
		(width 0.508)
		(layer "In9.Cu")
		(net "P3V3_NIC5")
	)
	(segment
		(start 222.28302 -198.241412)
		(end 222.28302 -199.10298)
		(width 0.508)
		(layer "In9.Cu")
		(net "P3V3_NIC5")
	)
	(segment
		(start 218.80195 -204.235304)
		(end 219.304616 -203.732638)
		(width 0.508)
		(layer "In9.Cu")
		(net "P3V3_NIC5")
	)
	(segment
		(start 225.531426 -194.993006)
		(end 222.28302 -198.241412)
		(width 0.508)
		(layer "In9.Cu")
		(net "P3V3_NIC5")
	)
	(segment
		(start 226.645216 -171.240196)
		(end 227.648262 -172.243242)
		(width 0.508)
		(layer "In9.Cu")
		(net "P3V3_NIC5")
	)
	(segment
		(start 226.685094 -169.334434)
		(end 226.685094 -169.359326)
		(width 0.508)
		(layer "In9.Cu")
		(net "P3V3_NIC5")
	)
	(segment
		(start 225.531426 -189.552072)
		(end 225.531426 -194.993006)
		(width 0.508)
		(layer "In9.Cu")
		(net "P3V3_NIC5")
	)
	(segment
		(start 227.51923 -187.448952)
		(end 227.51923 -187.508642)
		(width 0.508)
		(layer "In9.Cu")
		(net "P3V3_NIC5")
	)
	(segment
		(start 218.80195 -204.851)
		(end 218.80195 -204.235304)
		(width 0.508)
		(layer "In9.Cu")
		(net "P3V3_NIC5")
	)
	(segment
		(start 227.477066 -187.58154)
		(end 225.549206 -189.5094)
		(width 0.508)
		(layer "In9.Cu")
		(net "P3V3_NIC5")
	)
	(segment
		(start 227.51923 -187.508642)
		(end 227.477066 -187.550806)
		(width 0.508)
		(layer "In9.Cu")
		(net "P3V3_NIC5")
	)
	(segment
		(start 226.685094 -169.359326)
		(end 226.68484 -169.35958)
		(width 0.508)
		(layer "In9.Cu")
		(net "P3V3_NIC5")
	)
	(segment
		(start 226.68484 -169.35958)
		(end 226.68484 -171.200572)
		(width 0.508)
		(layer "In9.Cu")
		(net "P3V3_NIC5")
	)
	(segment
		(start 225.548952 -189.512956)
		(end 225.533712 -189.528196)
		(width 0.508)
		(layer "In9.Cu")
		(net "P3V3_NIC5")
	)
	(segment
		(start 225.549206 -189.5094)
		(end 225.548952 -189.5094)
		(width 0.508)
		(layer "In9.Cu")
		(net "P3V3_NIC5")
	)
	(segment
		(start 226.68484 -171.200572)
		(end 226.645216 -171.240196)
		(width 0.508)
		(layer "In9.Cu")
		(net "P3V3_NIC5")
	)
	(segment
		(start 227.477066 -187.550806)
		(end 227.477066 -187.58154)
		(width 0.508)
		(layer "In9.Cu")
		(net "P3V3_NIC5")
	)
	(segment
		(start 227.648262 -172.243242)
		(end 227.648262 -187.31992)
		(width 0.508)
		(layer "In9.Cu")
		(net "P3V3_NIC5")
	)
	(segment
		(start 225.533712 -189.528196)
		(end 225.533712 -189.549786)
		(width 0.508)
		(layer "In9.Cu")
		(net "P3V3_NIC5")
	)
	(segment
		(start 219.304616 -202.081384)
		(end 220.218 -201.168)
		(width 0.508)
		(layer "In9.Cu")
		(net "P3V3_NIC5")
	)
	(segment
		(start 227.648262 -187.31992)
		(end 227.51923 -187.448952)
		(width 0.508)
		(layer "In9.Cu")
		(net "P3V3_NIC5")
	)
	(segment
		(start 297.29811 -172.170344)
		(end 297.29811 -173.30928)
		(width 0.508)
		(layer "In13.Cu")
		(net "P3V3_NIC5")
	)
	(segment
		(start 282.880562 -167.02405)
		(end 280.157174 -164.300662)
		(width 0.508)
		(layer "In13.Cu")
		(net "P3V3_NIC5")
	)
	(segment
		(start 296.595038 -174.012352)
		(end 292.911022 -174.012352)
		(width 0.508)
		(layer "In13.Cu")
		(net "P3V3_NIC5")
	)
	(segment
		(start 272.559526 -160.250886)
		(end 267.17117 -160.250886)
		(width 0.508)
		(layer "In13.Cu")
		(net "P3V3_NIC5")
	)
	(segment
		(start 292.911022 -174.012352)
		(end 285.92272 -167.02405)
		(width 0.508)
		(layer "In13.Cu")
		(net "P3V3_NIC5")
	)
	(segment
		(start 276.609302 -164.300662)
		(end 272.559526 -160.250886)
		(width 0.508)
		(layer "In13.Cu")
		(net "P3V3_NIC5")
	)
	(segment
		(start 297.29811 -173.30928)
		(end 296.595038 -174.012352)
		(width 0.508)
		(layer "In13.Cu")
		(net "P3V3_NIC5")
	)
	(segment
		(start 228.697028 -169.334434)
		(end 226.685094 -169.334434)
		(width 0.508)
		(layer "In13.Cu")
		(net "P3V3_NIC5")
	)
	(segment
		(start 267.17117 -160.250886)
		(end 259.606288 -167.815768)
		(width 0.508)
		(layer "In13.Cu")
		(net "P3V3_NIC5")
	)
	(segment
		(start 230.215694 -167.815768)
		(end 228.697028 -169.334434)
		(width 0.508)
		(layer "In13.Cu")
		(net "P3V3_NIC5")
	)
	(segment
		(start 259.606288 -167.815768)
		(end 230.215694 -167.815768)
		(width 0.508)
		(layer "In13.Cu")
		(net "P3V3_NIC5")
	)
	(segment
		(start 280.157174 -164.300662)
		(end 276.609302 -164.300662)
		(width 0.508)
		(layer "In13.Cu")
		(net "P3V3_NIC5")
	)
	(segment
		(start 285.92272 -167.02405)
		(end 282.880562 -167.02405)
		(width 0.508)
		(layer "In13.Cu")
		(net "P3V3_NIC5")
	)
	(segment
		(start 233.65968 -77.36459)
		(end 234.627928 -77.36459)
		(width 0.13208)
		(layer "F.Cu")
		(net "PWRGD_P3V3_AUX_MUX_N")
	)
	(segment
		(start 234.627928 -77.36459)
		(end 234.798108 -77.53477)
		(width 0.13208)
		(layer "F.Cu")
		(net "PWRGD_P3V3_AUX_MUX_N")
	)
	(segment
		(start 234.798108 -77.53477)
		(end 235.604558 -77.53477)
		(width 0.13208)
		(layer "F.Cu")
		(net "PWRGD_P3V3_AUX_MUX_N")
	)
	(via
		(at 297.950636 -194.32524)
		(size 0.508)
		(drill 0.254)
		(layers "F.Cu" "B.Cu")
		(net "PWRGD_P3V3_AUX_MUX_N")
	)
	(via
		(at 234.627928 -77.36459)
		(size 0.508)
		(drill 0.254)
		(layers "F.Cu" "B.Cu")
		(net "PWRGD_P3V3_AUX_MUX_N")
	)
	(via
		(at 230.809546 -180.184298)
		(size 0.508)
		(drill 0.254)
		(layers "F.Cu" "B.Cu")
		(net "PWRGD_P3V3_AUX_MUX_N")
	)
	(segment
		(start 304.604928 -209.380328)
		(end 304.604928 -204.848206)
		(width 0.13208)
		(layer "B.Cu")
		(net "PWRGD_P3V3_AUX_MUX_N")
	)
	(segment
		(start 300.836838 -201.080116)
		(end 300.836838 -196.389752)
		(width 0.13208)
		(layer "B.Cu")
		(net "PWRGD_P3V3_AUX_MUX_N")
	)
	(segment
		(start 300.836838 -196.389752)
		(end 298.772326 -194.32524)
		(width 0.13208)
		(layer "B.Cu")
		(net "PWRGD_P3V3_AUX_MUX_N")
	)
	(segment
		(start 298.772326 -194.32524)
		(end 297.950636 -194.32524)
		(width 0.13208)
		(layer "B.Cu")
		(net "PWRGD_P3V3_AUX_MUX_N")
	)
	(segment
		(start 321.562222 -238.175038)
		(end 317.713614 -234.32643)
		(width 0.13208)
		(layer "B.Cu")
		(net "PWRGD_P3V3_AUX_MUX_N")
	)
	(segment
		(start 322.516246 -238.175038)
		(end 321.562222 -238.175038)
		(width 0.13208)
		(layer "B.Cu")
		(net "PWRGD_P3V3_AUX_MUX_N")
	)
	(segment
		(start 317.713614 -222.489014)
		(end 304.604928 -209.380328)
		(width 0.13208)
		(layer "B.Cu")
		(net "PWRGD_P3V3_AUX_MUX_N")
	)
	(segment
		(start 304.604928 -204.848206)
		(end 300.836838 -201.080116)
		(width 0.13208)
		(layer "B.Cu")
		(net "PWRGD_P3V3_AUX_MUX_N")
	)
	(segment
		(start 317.713614 -234.32643)
		(end 317.713614 -222.489014)
		(width 0.13208)
		(layer "B.Cu")
		(net "PWRGD_P3V3_AUX_MUX_N")
	)
	(segment
		(start 257.136646 -163.004754)
		(end 257.136646 -115.638326)
		(width 0.15494)
		(layer "In5.Cu")
		(net "PWRGD_P3V3_AUX_MUX_N")
	)
	(segment
		(start 229.840028 -179.21478)
		(end 229.840028 -172.325284)
		(width 0.15494)
		(layer "In5.Cu")
		(net "PWRGD_P3V3_AUX_MUX_N")
	)
	(segment
		(start 244.906038 -103.407718)
		(end 244.906038 -79.984346)
		(width 0.15494)
		(layer "In5.Cu")
		(net "PWRGD_P3V3_AUX_MUX_N")
	)
	(segment
		(start 244.906038 -79.984346)
		(end 243.479828 -78.558136)
		(width 0.15494)
		(layer "In5.Cu")
		(net "PWRGD_P3V3_AUX_MUX_N")
	)
	(segment
		(start 229.840028 -172.325284)
		(end 232.100374 -170.064938)
		(width 0.15494)
		(layer "In5.Cu")
		(net "PWRGD_P3V3_AUX_MUX_N")
	)
	(segment
		(start 243.479828 -78.558136)
		(end 239.862106 -78.558136)
		(width 0.15494)
		(layer "In5.Cu")
		(net "PWRGD_P3V3_AUX_MUX_N")
	)
	(segment
		(start 238.66856 -77.36459)
		(end 234.627928 -77.36459)
		(width 0.15494)
		(layer "In5.Cu")
		(net "PWRGD_P3V3_AUX_MUX_N")
	)
	(segment
		(start 238.3282 -165.8366)
		(end 254.3048 -165.8366)
		(width 0.15494)
		(layer "In5.Cu")
		(net "PWRGD_P3V3_AUX_MUX_N")
	)
	(segment
		(start 254.3048 -165.8366)
		(end 257.136646 -163.004754)
		(width 0.15494)
		(layer "In5.Cu")
		(net "PWRGD_P3V3_AUX_MUX_N")
	)
	(segment
		(start 230.809546 -180.184298)
		(end 229.840028 -179.21478)
		(width 0.15494)
		(layer "In5.Cu")
		(net "PWRGD_P3V3_AUX_MUX_N")
	)
	(segment
		(start 257.136646 -115.638326)
		(end 244.906038 -103.407718)
		(width 0.15494)
		(layer "In5.Cu")
		(net "PWRGD_P3V3_AUX_MUX_N")
	)
	(segment
		(start 239.862106 -78.558136)
		(end 238.66856 -77.36459)
		(width 0.15494)
		(layer "In5.Cu")
		(net "PWRGD_P3V3_AUX_MUX_N")
	)
	(segment
		(start 232.100374 -170.064938)
		(end 234.099862 -170.064938)
		(width 0.15494)
		(layer "In5.Cu")
		(net "PWRGD_P3V3_AUX_MUX_N")
	)
	(segment
		(start 234.099862 -170.064938)
		(end 238.3282 -165.8366)
		(width 0.15494)
		(layer "In5.Cu")
		(net "PWRGD_P3V3_AUX_MUX_N")
	)
	(segment
		(start 240.260632 -178.782472)
		(end 239.998504 -179.0446)
		(width 0.15494)
		(layer "In13.Cu")
		(net "PWRGD_P3V3_AUX_MUX_N")
	)
	(segment
		(start 251.988828 -178.782472)
		(end 240.260632 -178.782472)
		(width 0.15494)
		(layer "In13.Cu")
		(net "PWRGD_P3V3_AUX_MUX_N")
	)
	(segment
		(start 254.114554 -180.908198)
		(end 251.988828 -178.782472)
		(width 0.15494)
		(layer "In13.Cu")
		(net "PWRGD_P3V3_AUX_MUX_N")
	)
	(segment
		(start 280.195782 -198.430642)
		(end 265.42492 -183.65978)
		(width 0.15494)
		(layer "In13.Cu")
		(net "PWRGD_P3V3_AUX_MUX_N")
	)
	(segment
		(start 291.015928 -193.283078)
		(end 285.868364 -198.430642)
		(width 0.15494)
		(layer "In13.Cu")
		(net "PWRGD_P3V3_AUX_MUX_N")
	)
	(segment
		(start 260.465824 -183.65978)
		(end 257.714242 -180.908198)
		(width 0.15494)
		(layer "In13.Cu")
		(net "PWRGD_P3V3_AUX_MUX_N")
	)
	(segment
		(start 265.42492 -183.65978)
		(end 260.465824 -183.65978)
		(width 0.15494)
		(layer "In13.Cu")
		(net "PWRGD_P3V3_AUX_MUX_N")
	)
	(segment
		(start 231.949244 -179.0446)
		(end 230.809546 -180.184298)
		(width 0.15494)
		(layer "In13.Cu")
		(net "PWRGD_P3V3_AUX_MUX_N")
	)
	(segment
		(start 297.950636 -194.32524)
		(end 296.908474 -193.283078)
		(width 0.15494)
		(layer "In13.Cu")
		(net "PWRGD_P3V3_AUX_MUX_N")
	)
	(segment
		(start 296.908474 -193.283078)
		(end 291.015928 -193.283078)
		(width 0.15494)
		(layer "In13.Cu")
		(net "PWRGD_P3V3_AUX_MUX_N")
	)
	(segment
		(start 285.868364 -198.430642)
		(end 280.195782 -198.430642)
		(width 0.15494)
		(layer "In13.Cu")
		(net "PWRGD_P3V3_AUX_MUX_N")
	)
	(segment
		(start 239.998504 -179.0446)
		(end 231.949244 -179.0446)
		(width 0.15494)
		(layer "In13.Cu")
		(net "PWRGD_P3V3_AUX_MUX_N")
	)
	(segment
		(start 257.714242 -180.908198)
		(end 254.114554 -180.908198)
		(width 0.15494)
		(layer "In13.Cu")
		(net "PWRGD_P3V3_AUX_MUX_N")
	)
	(via
		(at 122.548904 -202.733656)
		(size 0.6604)
		(drill 0.3302)
		(layers "F.Cu" "B.Cu")
		(net "FT4232_CLI_EEPROM_DO")
	)
	(segment
		(start 124.4727 -203.392278)
		(end 123.207526 -203.392278)
		(width 0.13208)
		(layer "B.Cu")
		(net "FT4232_CLI_EEPROM_DO")
	)
	(segment
		(start 123.931172 -200.92035)
		(end 123.931172 -201.93635)
		(width 0.13208)
		(layer "B.Cu")
		(net "FT4232_CLI_EEPROM_DO")
	)
	(segment
		(start 122.548904 -202.733656)
		(end 123.34621 -201.93635)
		(width 0.13208)
		(layer "B.Cu")
		(net "FT4232_CLI_EEPROM_DO")
	)
	(segment
		(start 123.34621 -201.93635)
		(end 123.931172 -201.93635)
		(width 0.13208)
		(layer "B.Cu")
		(net "FT4232_CLI_EEPROM_DO")
	)
	(segment
		(start 123.207526 -203.392278)
		(end 122.548904 -202.733656)
		(width 0.13208)
		(layer "B.Cu")
		(net "FT4232_CLI_EEPROM_DO")
	)
	(segment
		(start 62.664848 -22.990048)
		(end 63.709296 -22.990048)
		(width 0.13208)
		(layer "F.Cu")
		(net "SMB_ISO_SSD2_R_SDA")
	)
	(segment
		(start 63.709296 -22.990048)
		(end 63.744348 -23.0251)
		(width 0.13208)
		(layer "F.Cu")
		(net "SMB_ISO_SSD2_R_SDA")
	)
	(segment
		(start 74.65822 -19.453098)
		(end 75.26782 -19.453098)
		(width 0.13208)
		(layer "F.Cu")
		(net "SMB_ISO_SSD2_R_SDA")
	)
	(via
		(at 74.65822 -19.453098)
		(size 0.508)
		(drill 0.254)
		(layers "F.Cu" "B.Cu")
		(net "SMB_ISO_SSD2_R_SDA")
	)
	(via
		(at 63.744348 -23.0251)
		(size 0.508)
		(drill 0.254)
		(layers "F.Cu" "B.Cu")
		(net "SMB_ISO_SSD2_R_SDA")
	)
	(segment
		(start 74.65822 -19.453098)
		(end 74.65822 -21.390356)
		(width 0.15494)
		(layer "In5.Cu")
		(net "SMB_ISO_SSD2_R_SDA")
	)
	(segment
		(start 74.65822 -21.390356)
		(end 73.516236 -22.53234)
		(width 0.15494)
		(layer "In5.Cu")
		(net "SMB_ISO_SSD2_R_SDA")
	)
	(segment
		(start 73.516236 -22.53234)
		(end 64.237108 -22.53234)
		(width 0.15494)
		(layer "In5.Cu")
		(net "SMB_ISO_SSD2_R_SDA")
	)
	(segment
		(start 64.237108 -22.53234)
		(end 63.744348 -23.0251)
		(width 0.15494)
		(layer "In5.Cu")
		(net "SMB_ISO_SSD2_R_SDA")
	)
	(segment
		(start 243.363496 -124.897642)
		(end 242.936014 -124.47016)
		(width 0.13208)
		(layer "F.Cu")
		(net "P3V3_NIC4_OCP")
	)
	(segment
		(start 242.936014 -124.47016)
		(end 242.867434 -124.47016)
		(width 0.13208)
		(layer "F.Cu")
		(net "P3V3_NIC4_OCP")
	)
	(segment
		(start 243.478558 -125.057916)
		(end 243.363496 -125.057916)
		(width 0.13208)
		(layer "F.Cu")
		(net "P3V3_NIC4_OCP")
	)
	(segment
		(start 242.710462 -124.313188)
		(end 242.710462 -123.947428)
		(width 0.13208)
		(layer "F.Cu")
		(net "P3V3_NIC4_OCP")
	)
	(segment
		(start 244.431058 -125.39472)
		(end 243.815362 -125.39472)
		(width 0.13208)
		(layer "F.Cu")
		(net "P3V3_NIC4_OCP")
	)
	(segment
		(start 243.815362 -125.39472)
		(end 243.478558 -125.057916)
		(width 0.13208)
		(layer "F.Cu")
		(net "P3V3_NIC4_OCP")
	)
	(segment
		(start 243.363496 -125.057916)
		(end 243.363496 -124.897642)
		(width 0.13208)
		(layer "F.Cu")
		(net "P3V3_NIC4_OCP")
	)
	(segment
		(start 242.867434 -124.47016)
		(end 242.710462 -124.313188)
		(width 0.13208)
		(layer "F.Cu")
		(net "P3V3_NIC4_OCP")
	)
	(via
		(at 243.363496 -125.057916)
		(size 0.508)
		(drill 0.254)
		(layers "F.Cu" "B.Cu")
		(net "P3V3_NIC4_OCP")
	)
	(segment
		(start 144.050004 -197.882764)
		(end 144.650968 -197.2818)
		(width 0.13208)
		(layer "F.Cu")
		(net "UART_PEX0_CLI_RX")
	)
	(segment
		(start 144.650968 -197.2818)
		(end 145.297906 -197.2818)
		(width 0.13208)
		(layer "F.Cu")
		(net "UART_PEX0_CLI_RX")
	)
	(segment
		(start 143.3068 -200.489058)
		(end 143.3068 -198.625968)
		(width 0.13208)
		(layer "F.Cu")
		(net "UART_PEX0_CLI_RX")
	)
	(segment
		(start 143.3068 -198.625968)
		(end 144.050004 -197.882764)
		(width 0.13208)
		(layer "F.Cu")
		(net "UART_PEX0_CLI_RX")
	)
	(via
		(at 144.050004 -197.882764)
		(size 0.508)
		(drill 0.254)
		(layers "F.Cu" "B.Cu")
		(net "UART_PEX0_CLI_RX")
	)
	(segment
		(start 142.306802 -198.680578)
		(end 142.305024 -198.6788)
		(width 0.13208)
		(layer "F.Cu")
		(net "RST_FT4232_CLI_R_N")
	)
	(segment
		(start 142.306802 -200.489058)
		(end 142.306802 -198.680578)
		(width 0.13208)
		(layer "F.Cu")
		(net "RST_FT4232_CLI_R_N")
	)
	(segment
		(start 142.305024 -198.6788)
		(end 142.305024 -197.929246)
		(width 0.13208)
		(layer "F.Cu")
		(net "RST_FT4232_CLI_R_N")
	)
	(via
		(at 142.306802 -198.680578)
		(size 0.508)
		(drill 0.254)
		(layers "F.Cu" "B.Cu")
		(net "RST_FT4232_CLI_R_N")
	)
	(via
		(at 126.564136 -172.454062)
		(size 0.508)
		(drill 0.254)
		(layers "F.Cu" "B.Cu")
		(net "P3V3_DB2000QL_FB_VDD")
	)
	(via
		(at 126.028704 -173.983142)
		(size 0.6604)
		(drill 0.3302)
		(layers "F.Cu" "B.Cu")
		(net "P3V3_DB2000QL_FB_VDD")
	)
	(via
		(at 126.564136 -173.089062)
		(size 0.508)
		(drill 0.254)
		(layers "F.Cu" "B.Cu")
		(net "P3V3_DB2000QL_FB_VDD")
	)
	(via
		(at 130.690874 -181.965092)
		(size 0.508)
		(drill 0.254)
		(layers "F.Cu" "B.Cu")
		(net "P3V3_DB2000QL_FB_VDD")
	)
	(via
		(at 130.18262 -182.448454)
		(size 0.508)
		(drill 0.254)
		(layers "F.Cu" "B.Cu")
		(net "P3V3_DB2000QL_FB_VDD")
	)
	(segment
		(start 263.496044 -76.879704)
		(end 263.16432 -76.54798)
		(width 0.13462)
		(layer "F.Cu")
		(net "CLK_100M_CK440Q_2_DB800ZL_R_DP")
	)
	(segment
		(start 263.16432 -75.565762)
		(end 263.47166 -75.258422)
		(width 0.13462)
		(layer "F.Cu")
		(net "CLK_100M_CK440Q_2_DB800ZL_R_DP")
	)
	(segment
		(start 331.223874 -87.036148)
		(end 332.179676 -87.036148)
		(width 0.13462)
		(layer "F.Cu")
		(net "CLK_100M_CK440Q_2_DB800ZL_R_DP")
	)
	(segment
		(start 330.935584 -87.324438)
		(end 331.223874 -87.036148)
		(width 0.13462)
		(layer "F.Cu")
		(net "CLK_100M_CK440Q_2_DB800ZL_R_DP")
	)
	(segment
		(start 334.662526 -87.707724)
		(end 334.719168 -87.764366)
		(width 0.13462)
		(layer "F.Cu")
		(net "CLK_100M_CK440Q_2_DB800ZL_R_DP")
	)
	(segment
		(start 333.082646 -87.21598)
		(end 334.27162 -87.707724)
		(width 0.13462)
		(layer "F.Cu")
		(net "CLK_100M_CK440Q_2_DB800ZL_R_DP")
	)
	(segment
		(start 334.719168 -87.764366)
		(end 335.145634 -87.764366)
		(width 0.13462)
		(layer "F.Cu")
		(net "CLK_100M_CK440Q_2_DB800ZL_R_DP")
	)
	(segment
		(start 332.179676 -87.036148)
		(end 333.082646 -87.21598)
		(width 0.13462)
		(layer "F.Cu")
		(net "CLK_100M_CK440Q_2_DB800ZL_R_DP")
	)
	(segment
		(start 263.16432 -76.54798)
		(end 263.16432 -75.565762)
		(width 0.13462)
		(layer "F.Cu")
		(net "CLK_100M_CK440Q_2_DB800ZL_R_DP")
	)
	(segment
		(start 334.27162 -87.707724)
		(end 334.662526 -87.707724)
		(width 0.13462)
		(layer "F.Cu")
		(net "CLK_100M_CK440Q_2_DB800ZL_R_DP")
	)
	(via
		(at 263.47166 -75.258422)
		(size 0.508)
		(drill 0.254)
		(layers "F.Cu" "B.Cu")
		(net "CLK_100M_CK440Q_2_DB800ZL_R_DP")
	)
	(via
		(at 330.935584 -87.324438)
		(size 0.508)
		(drill 0.254)
		(layers "F.Cu" "B.Cu")
		(net "CLK_100M_CK440Q_2_DB800ZL_R_DP")
	)
	(segment
		(start 327.686924 -86.633304)
		(end 328.087228 -87.033608)
		(width 0.1651)
		(layer "In13.Cu")
		(net "CLK_100M_CK440Q_2_DB800ZL_R_DP")
	)
	(segment
		(start 325.401686 -84.348066)
		(end 325.685404 -84.631784)
		(width 0.1651)
		(layer "In13.Cu")
		(net "CLK_100M_CK440Q_2_DB800ZL_R_DP")
	)
	(segment
		(start 263.591802 -74.32294)
		(end 271.57934 -74.32294)
		(width 0.1651)
		(layer "In13.Cu")
		(net "CLK_100M_CK440Q_2_DB800ZL_R_DP")
	)
	(segment
		(start 327.492868 -86.633304)
		(end 327.686924 -86.633304)
		(width 0.1651)
		(layer "In13.Cu")
		(net "CLK_100M_CK440Q_2_DB800ZL_R_DP")
	)
	(segment
		(start 273.304 -76.0476)
		(end 317.10122 -76.0476)
		(width 0.1651)
		(layer "In13.Cu")
		(net "CLK_100M_CK440Q_2_DB800ZL_R_DP")
	)
	(segment
		(start 326.925178 -85.871558)
		(end 327.208896 -86.155276)
		(width 0.1651)
		(layer "In13.Cu")
		(net "CLK_100M_CK440Q_2_DB800ZL_R_DP")
	)
	(segment
		(start 317.10122 -76.0476)
		(end 324.923658 -83.870038)
		(width 0.1651)
		(layer "In13.Cu")
		(net "CLK_100M_CK440Q_2_DB800ZL_R_DP")
	)
	(segment
		(start 325.207884 -84.348066)
		(end 325.401686 -84.348066)
		(width 0.1651)
		(layer "In13.Cu")
		(net "CLK_100M_CK440Q_2_DB800ZL_R_DP")
	)
	(segment
		(start 325.685404 -84.82584)
		(end 325.96963 -85.109812)
		(width 0.1651)
		(layer "In13.Cu")
		(net "CLK_100M_CK440Q_2_DB800ZL_R_DP")
	)
	(segment
		(start 326.731376 -85.871558)
		(end 326.925178 -85.871558)
		(width 0.1651)
		(layer "In13.Cu")
		(net "CLK_100M_CK440Q_2_DB800ZL_R_DP")
	)
	(segment
		(start 263.18083 -74.967592)
		(end 263.18083 -74.733912)
		(width 0.1651)
		(layer "In13.Cu")
		(net "CLK_100M_CK440Q_2_DB800ZL_R_DP")
	)
	(segment
		(start 328.087228 -87.033608)
		(end 330.644754 -87.033608)
		(width 0.1651)
		(layer "In13.Cu")
		(net "CLK_100M_CK440Q_2_DB800ZL_R_DP")
	)
	(segment
		(start 330.644754 -87.033608)
		(end 330.935584 -87.324438)
		(width 0.1651)
		(layer "In13.Cu")
		(net "CLK_100M_CK440Q_2_DB800ZL_R_DP")
	)
	(segment
		(start 324.923658 -83.870038)
		(end 324.923658 -84.064094)
		(width 0.1651)
		(layer "In13.Cu")
		(net "CLK_100M_CK440Q_2_DB800ZL_R_DP")
	)
	(segment
		(start 325.685404 -84.631784)
		(end 325.685404 -84.82584)
		(width 0.1651)
		(layer "In13.Cu")
		(net "CLK_100M_CK440Q_2_DB800ZL_R_DP")
	)
	(segment
		(start 327.208896 -86.155276)
		(end 327.208896 -86.349332)
		(width 0.1651)
		(layer "In13.Cu")
		(net "CLK_100M_CK440Q_2_DB800ZL_R_DP")
	)
	(segment
		(start 271.57934 -74.32294)
		(end 273.304 -76.0476)
		(width 0.1651)
		(layer "In13.Cu")
		(net "CLK_100M_CK440Q_2_DB800ZL_R_DP")
	)
	(segment
		(start 263.18083 -74.733912)
		(end 263.591802 -74.32294)
		(width 0.1651)
		(layer "In13.Cu")
		(net "CLK_100M_CK440Q_2_DB800ZL_R_DP")
	)
	(segment
		(start 325.96963 -85.109812)
		(end 326.163432 -85.109812)
		(width 0.1651)
		(layer "In13.Cu")
		(net "CLK_100M_CK440Q_2_DB800ZL_R_DP")
	)
	(segment
		(start 327.208896 -86.349332)
		(end 327.492868 -86.633304)
		(width 0.1651)
		(layer "In13.Cu")
		(net "CLK_100M_CK440Q_2_DB800ZL_R_DP")
	)
	(segment
		(start 326.44715 -85.39353)
		(end 326.44715 -85.587586)
		(width 0.1651)
		(layer "In13.Cu")
		(net "CLK_100M_CK440Q_2_DB800ZL_R_DP")
	)
	(segment
		(start 326.163432 -85.109812)
		(end 326.44715 -85.39353)
		(width 0.1651)
		(layer "In13.Cu")
		(net "CLK_100M_CK440Q_2_DB800ZL_R_DP")
	)
	(segment
		(start 326.44715 -85.587586)
		(end 326.731376 -85.871558)
		(width 0.1651)
		(layer "In13.Cu")
		(net "CLK_100M_CK440Q_2_DB800ZL_R_DP")
	)
	(segment
		(start 324.923658 -84.064094)
		(end 325.207884 -84.348066)
		(width 0.1651)
		(layer "In13.Cu")
		(net "CLK_100M_CK440Q_2_DB800ZL_R_DP")
	)
	(segment
		(start 263.47166 -75.258422)
		(end 263.18083 -74.967592)
		(width 0.1651)
		(layer "In13.Cu")
		(net "CLK_100M_CK440Q_2_DB800ZL_R_DP")
	)
	(segment
		(start 258.176776 -87.431372)
		(end 258.176776 -88.689688)
		(width 0.0889)
		(layer "F.Cu")
		(net "PU_CK440_SHFT_LD_N")
	)
	(segment
		(start 260.11505 -90.501978)
		(end 264.717276 -90.501978)
		(width 0.13208)
		(layer "F.Cu")
		(net "PU_CK440_SHFT_LD_N")
	)
	(segment
		(start 258.176776 -88.689688)
		(end 258.176776 -89.244424)
		(width 0.13208)
		(layer "F.Cu")
		(net "PU_CK440_SHFT_LD_N")
	)
	(segment
		(start 268.002766 -92.526104)
		(end 266.741402 -92.526104)
		(width 0.13208)
		(layer "F.Cu")
		(net "PU_CK440_SHFT_LD_N")
	)
	(segment
		(start 258.176776 -89.244424)
		(end 258.856226 -89.923874)
		(width 0.13208)
		(layer "F.Cu")
		(net "PU_CK440_SHFT_LD_N")
	)
	(segment
		(start 268.002766 -93.542104)
		(end 268.002766 -92.526104)
		(width 0.13208)
		(layer "F.Cu")
		(net "PU_CK440_SHFT_LD_N")
	)
	(segment
		(start 266.741402 -92.526104)
		(end 265.954002 -91.738704)
		(width 0.13208)
		(layer "F.Cu")
		(net "PU_CK440_SHFT_LD_N")
	)
	(segment
		(start 258.856226 -89.923874)
		(end 259.536946 -89.923874)
		(width 0.13208)
		(layer "F.Cu")
		(net "PU_CK440_SHFT_LD_N")
	)
	(segment
		(start 264.717276 -90.501978)
		(end 265.954002 -91.738704)
		(width 0.13208)
		(layer "F.Cu")
		(net "PU_CK440_SHFT_LD_N")
	)
	(segment
		(start 259.536946 -89.923874)
		(end 260.11505 -90.501978)
		(width 0.13208)
		(layer "F.Cu")
		(net "PU_CK440_SHFT_LD_N")
	)
	(via
		(at 265.954002 -91.738704)
		(size 0.762)
		(drill 0.381)
		(layers "F.Cu" "B.Cu")
		(net "PU_CK440_SHFT_LD_N")
	)
	(segment
		(start 256.926842 -80.431386)
		(end 256.926842 -80.047846)
		(width 0.13208)
		(layer "F.Cu")
		(net "FM_CLK_CK440_SS_EN")
	)
	(segment
		(start 254.177292 -77.679804)
		(end 255.17729 -77.679804)
		(width 0.13208)
		(layer "F.Cu")
		(net "FM_CLK_CK440_SS_EN")
	)
	(segment
		(start 256.926842 -80.047846)
		(end 256.231898 -79.352902)
		(width 0.13208)
		(layer "F.Cu")
		(net "FM_CLK_CK440_SS_EN")
	)
	(segment
		(start 256.231898 -79.352902)
		(end 255.364996 -79.352902)
		(width 0.13208)
		(layer "F.Cu")
		(net "FM_CLK_CK440_SS_EN")
	)
	(segment
		(start 254.65532 -78.643226)
		(end 255.17729 -78.121256)
		(width 0.13208)
		(layer "F.Cu")
		(net "FM_CLK_CK440_SS_EN")
	)
	(segment
		(start 255.17729 -78.121256)
		(end 255.17729 -77.679804)
		(width 0.13208)
		(layer "F.Cu")
		(net "FM_CLK_CK440_SS_EN")
	)
	(segment
		(start 255.364996 -79.352902)
		(end 254.65532 -78.643226)
		(width 0.13208)
		(layer "F.Cu")
		(net "FM_CLK_CK440_SS_EN")
	)
	(via
		(at 254.65532 -78.643226)
		(size 0.508)
		(drill 0.254)
		(layers "F.Cu" "B.Cu")
		(net "FM_CLK_CK440_SS_EN")
	)
	(segment
		(start 152.764998 -22.3901)
		(end 154.567636 -22.3901)
		(width 0.13208)
		(layer "F.Cu")
		(net "SMB_ISO_SSD5_R_SCL")
	)
	(segment
		(start 154.567636 -22.3901)
		(end 155.193746 -23.01621)
		(width 0.13208)
		(layer "F.Cu")
		(net "SMB_ISO_SSD5_R_SCL")
	)
	(segment
		(start 164.75837 -18.44421)
		(end 164.765482 -18.437098)
		(width 0.13208)
		(layer "F.Cu")
		(net "SMB_ISO_SSD5_R_SCL")
	)
	(segment
		(start 164.765482 -18.437098)
		(end 165.36797 -18.437098)
		(width 0.13208)
		(layer "F.Cu")
		(net "SMB_ISO_SSD5_R_SCL")
	)
	(via
		(at 155.193746 -23.01621)
		(size 0.508)
		(drill 0.254)
		(layers "F.Cu" "B.Cu")
		(net "SMB_ISO_SSD5_R_SCL")
	)
	(via
		(at 164.75837 -18.44421)
		(size 0.508)
		(drill 0.254)
		(layers "F.Cu" "B.Cu")
		(net "SMB_ISO_SSD5_R_SCL")
	)
	(segment
		(start 163.78301 -23.01621)
		(end 155.193746 -23.01621)
		(width 0.15494)
		(layer "In5.Cu")
		(net "SMB_ISO_SSD5_R_SCL")
	)
	(segment
		(start 164.75837 -18.44421)
		(end 165.327076 -19.012916)
		(width 0.15494)
		(layer "In5.Cu")
		(net "SMB_ISO_SSD5_R_SCL")
	)
	(segment
		(start 165.327076 -19.012916)
		(end 165.327076 -21.472144)
		(width 0.15494)
		(layer "In5.Cu")
		(net "SMB_ISO_SSD5_R_SCL")
	)
	(segment
		(start 165.327076 -21.472144)
		(end 163.78301 -23.01621)
		(width 0.15494)
		(layer "In5.Cu")
		(net "SMB_ISO_SSD5_R_SCL")
	)
	(segment
		(start 98.236532 -121.509028)
		(end 97.966276 -121.238772)
		(width 0.13208)
		(layer "F.Cu")
		(net "P3V3_NIC1_OCP")
	)
	(segment
		(start 97.769426 -121.041922)
		(end 97.966276 -121.238772)
		(width 0.13208)
		(layer "F.Cu")
		(net "P3V3_NIC1_OCP")
	)
	(segment
		(start 96.77146 -121.041922)
		(end 97.769426 -121.041922)
		(width 0.13208)
		(layer "F.Cu")
		(net "P3V3_NIC1_OCP")
	)
	(segment
		(start 98.575622 -121.509028)
		(end 98.236532 -121.509028)
		(width 0.13208)
		(layer "F.Cu")
		(net "P3V3_NIC1_OCP")
	)
	(via
		(at 97.966276 -121.238772)
		(size 0.508)
		(drill 0.254)
		(layers "F.Cu" "B.Cu")
		(net "P3V3_NIC1_OCP")
	)
	(segment
		(start 137.77722 -194.249802)
		(end 137.77722 -195.568316)
		(width 0.13208)
		(layer "F.Cu")
		(net "OSC_CLI_IN")
	)
	(segment
		(start 136.479788 -196.196712)
		(end 136.544812 -196.196712)
		(width 0.13208)
		(layer "F.Cu")
		(net "OSC_CLI_IN")
	)
	(segment
		(start 136.78662 -195.954904)
		(end 136.544812 -196.196712)
		(width 0.13208)
		(layer "F.Cu")
		(net "OSC_CLI_IN")
	)
	(segment
		(start 136.637776 -193.238628)
		(end 136.766046 -193.238628)
		(width 0.13208)
		(layer "F.Cu")
		(net "OSC_CLI_IN")
	)
	(segment
		(start 135.794496 -197.35546)
		(end 136.042146 -197.60311)
		(width 0.13208)
		(layer "F.Cu")
		(net "OSC_CLI_IN")
	)
	(segment
		(start 136.042146 -198.966074)
		(end 136.042146 -198.091806)
		(width 0.13208)
		(layer "F.Cu")
		(net "OSC_CLI_IN")
	)
	(segment
		(start 137.77722 -195.568316)
		(end 137.390632 -195.954904)
		(width 0.13208)
		(layer "F.Cu")
		(net "OSC_CLI_IN")
	)
	(segment
		(start 136.306814 -199.230742)
		(end 136.042146 -198.966074)
		(width 0.13208)
		(layer "F.Cu")
		(net "OSC_CLI_IN")
	)
	(segment
		(start 135.794496 -196.821806)
		(end 135.794496 -197.35546)
		(width 0.13208)
		(layer "F.Cu")
		(net "OSC_CLI_IN")
	)
	(segment
		(start 136.766046 -193.238628)
		(end 137.77722 -194.249802)
		(width 0.13208)
		(layer "F.Cu")
		(net "OSC_CLI_IN")
	)
	(segment
		(start 137.390632 -195.954904)
		(end 136.78662 -195.954904)
		(width 0.13208)
		(layer "F.Cu")
		(net "OSC_CLI_IN")
	)
	(segment
		(start 136.042146 -197.60311)
		(end 136.042146 -198.091806)
		(width 0.13208)
		(layer "F.Cu")
		(net "OSC_CLI_IN")
	)
	(segment
		(start 136.306814 -200.489058)
		(end 136.306814 -199.230742)
		(width 0.13208)
		(layer "F.Cu")
		(net "OSC_CLI_IN")
	)
	(segment
		(start 135.854694 -196.821806)
		(end 136.479788 -196.196712)
		(width 0.13208)
		(layer "F.Cu")
		(net "OSC_CLI_IN")
	)
	(segment
		(start 135.794496 -196.821806)
		(end 135.854694 -196.821806)
		(width 0.13208)
		(layer "F.Cu")
		(net "OSC_CLI_IN")
	)
	(via
		(at 136.544812 -196.196712)
		(size 0.508)
		(drill 0.254)
		(layers "F.Cu" "B.Cu")
		(net "OSC_CLI_IN")
	)
	(segment
		(start 130.471164 -176.900332)
		(end 130.932936 -176.722278)
		(width 0.3048)
		(layer "F.Cu")
		(net "P3V3_DB2000QL_VDDR")
	)
	(via
		(at 130.900678 -177.356262)
		(size 0.508)
		(drill 0.254)
		(layers "F.Cu" "B.Cu")
		(net "P3V3_DB2000QL_VDDR")
	)
	(via
		(at 129.885186 -177.417476)
		(size 0.508)
		(drill 0.254)
		(layers "F.Cu" "B.Cu")
		(net "P3V3_DB2000QL_VDDR")
	)
	(via
		(at 130.384296 -176.248568)
		(size 0.508)
		(drill 0.254)
		(layers "F.Cu" "B.Cu")
		(net "P3V3_DB2000QL_VDDR")
	)
	(via
		(at 130.932936 -176.722278)
		(size 0.49022)
		(drill 0.254)
		(layers "F.Cu" "B.Cu")
		(net "P3V3_DB2000QL_VDDR")
	)
	(segment
		(start 219.386658 -221.670372)
		(end 219.386404 -221.670626)
		(width 0.13208)
		(layer "F.Cu")
		(net "I3C_MB_SDA")
	)
	(segment
		(start 220.248734 -221.670626)
		(end 220.24848 -221.670372)
		(width 0.13208)
		(layer "F.Cu")
		(net "I3C_MB_SDA")
	)
	(segment
		(start 220.24848 -221.670372)
		(end 219.386658 -221.670372)
		(width 0.13208)
		(layer "F.Cu")
		(net "I3C_MB_SDA")
	)
	(segment
		(start 223.4057 -221.44228)
		(end 220.986096 -221.44228)
		(width 0.13208)
		(layer "F.Cu")
		(net "I3C_MB_SDA")
	)
	(segment
		(start 223.467676 -221.504256)
		(end 223.4057 -221.44228)
		(width 0.13208)
		(layer "F.Cu")
		(net "I3C_MB_SDA")
	)
	(segment
		(start 220.986096 -221.44228)
		(end 220.758004 -221.670372)
		(width 0.13208)
		(layer "F.Cu")
		(net "I3C_MB_SDA")
	)
	(segment
		(start 220.288866 -221.670626)
		(end 220.248734 -221.670626)
		(width 0.13208)
		(layer "F.Cu")
		(net "I3C_MB_SDA")
	)
	(segment
		(start 217.888058 -223.005396)
		(end 217.635836 -223.382586)
		(width 0.13208)
		(layer "F.Cu")
		(net "I3C_MB_SDA")
	)
	(segment
		(start 218.17076 -222.722694)
		(end 217.888058 -223.005396)
		(width 0.13208)
		(layer "F.Cu")
		(net "I3C_MB_SDA")
	)
	(segment
		(start 220.758004 -221.670372)
		(end 220.28912 -221.670372)
		(width 0.13208)
		(layer "F.Cu")
		(net "I3C_MB_SDA")
	)
	(segment
		(start 218.968828 -221.670626)
		(end 218.350338 -222.289116)
		(width 0.13208)
		(layer "F.Cu")
		(net "I3C_MB_SDA")
	)
	(segment
		(start 219.386404 -221.670626)
		(end 218.968828 -221.670626)
		(width 0.13208)
		(layer "F.Cu")
		(net "I3C_MB_SDA")
	)
	(segment
		(start 220.28912 -221.670372)
		(end 220.288866 -221.670626)
		(width 0.13208)
		(layer "F.Cu")
		(net "I3C_MB_SDA")
	)
	(segment
		(start 218.350338 -222.289116)
		(end 218.17076 -222.722694)
		(width 0.13208)
		(layer "F.Cu")
		(net "I3C_MB_SDA")
	)
	(via
		(at 219.386404 -221.670626)
		(size 0.762)
		(drill 0.381)
		(layers "F.Cu" "B.Cu")
		(net "I3C_MB_SDA")
	)
	(segment
		(start 126.76505 -22.990048)
		(end 127.809498 -22.990048)
		(width 0.13208)
		(layer "F.Cu")
		(net "SMB_ISO_SSD4_R_SDA")
	)
	(segment
		(start 138.758422 -19.453098)
		(end 139.368022 -19.453098)
		(width 0.13208)
		(layer "F.Cu")
		(net "SMB_ISO_SSD4_R_SDA")
	)
	(segment
		(start 127.809498 -22.990048)
		(end 127.84455 -23.0251)
		(width 0.13208)
		(layer "F.Cu")
		(net "SMB_ISO_SSD4_R_SDA")
	)
	(via
		(at 138.758422 -19.453098)
		(size 0.508)
		(drill 0.254)
		(layers "F.Cu" "B.Cu")
		(net "SMB_ISO_SSD4_R_SDA")
	)
	(via
		(at 127.84455 -23.0251)
		(size 0.508)
		(drill 0.254)
		(layers "F.Cu" "B.Cu")
		(net "SMB_ISO_SSD4_R_SDA")
	)
	(segment
		(start 138.758422 -21.390356)
		(end 137.616438 -22.53234)
		(width 0.15494)
		(layer "In5.Cu")
		(net "SMB_ISO_SSD4_R_SDA")
	)
	(segment
		(start 137.616438 -22.53234)
		(end 128.33731 -22.53234)
		(width 0.15494)
		(layer "In5.Cu")
		(net "SMB_ISO_SSD4_R_SDA")
	)
	(segment
		(start 138.758422 -19.453098)
		(end 138.758422 -21.390356)
		(width 0.15494)
		(layer "In5.Cu")
		(net "SMB_ISO_SSD4_R_SDA")
	)
	(segment
		(start 128.33731 -22.53234)
		(end 127.84455 -23.0251)
		(width 0.15494)
		(layer "In5.Cu")
		(net "SMB_ISO_SSD4_R_SDA")
	)
	(segment
		(start 56.373268 -389.71474)
		(end 57.298082 -389.71474)
		(width 0.13208)
		(layer "F.Cu")
		(net "GPU_PEX_STRAP0")
	)
	(segment
		(start 57.341262 -389.67156)
		(end 56.964326 -389.294624)
		(width 0.13208)
		(layer "F.Cu")
		(net "GPU_PEX_STRAP0")
	)
	(segment
		(start 57.50433 -388.265416)
		(end 60.34532 -388.265416)
		(width 0.13208)
		(layer "F.Cu")
		(net "GPU_PEX_STRAP0")
	)
	(segment
		(start 56.964326 -388.80542)
		(end 57.50433 -388.265416)
		(width 0.13208)
		(layer "F.Cu")
		(net "GPU_PEX_STRAP0")
	)
	(segment
		(start 57.298082 -389.71474)
		(end 57.341262 -389.67156)
		(width 0.13208)
		(layer "F.Cu")
		(net "GPU_PEX_STRAP0")
	)
	(segment
		(start 56.964326 -389.294624)
		(end 56.964326 -388.80542)
		(width 0.13208)
		(layer "F.Cu")
		(net "GPU_PEX_STRAP0")
	)
	(via
		(at 60.34532 -388.265416)
		(size 0.508)
		(drill 0.254)
		(layers "F.Cu" "B.Cu")
		(net "GPU_PEX_STRAP0")
	)
	(segment
		(start 65.125854 -389.9154)
		(end 61.995304 -389.9154)
		(width 0.15494)
		(layer "In9.Cu")
		(net "GPU_PEX_STRAP0")
	)
	(segment
		(start 61.995304 -389.9154)
		(end 60.34532 -388.265416)
		(width 0.15494)
		(layer "In9.Cu")
		(net "GPU_PEX_STRAP0")
	)
	(segment
		(start 90.678 -409.358338)
		(end 90.678 -412.7246)
		(width 0.15494)
		(layer "In9.Cu")
		(net "GPU_PEX_STRAP0")
	)
	(segment
		(start 87.122 -416.2806)
		(end 70.370192 -416.2806)
		(width 0.15494)
		(layer "In9.Cu")
		(net "GPU_PEX_STRAP0")
	)
	(segment
		(start 67.185794 -391.97534)
		(end 65.125854 -389.9154)
		(width 0.15494)
		(layer "In9.Cu")
		(net "GPU_PEX_STRAP0")
	)
	(segment
		(start 90.678 -412.7246)
		(end 87.122 -416.2806)
		(width 0.15494)
		(layer "In9.Cu")
		(net "GPU_PEX_STRAP0")
	)
	(segment
		(start 70.370192 -416.2806)
		(end 67.185794 -413.096202)
		(width 0.15494)
		(layer "In9.Cu")
		(net "GPU_PEX_STRAP0")
	)
	(segment
		(start 67.185794 -413.096202)
		(end 67.185794 -391.97534)
		(width 0.15494)
		(layer "In9.Cu")
		(net "GPU_PEX_STRAP0")
	)
	(segment
		(start 89.509854 -408.190192)
		(end 90.678 -409.358338)
		(width 0.15494)
		(layer "In9.Cu")
		(net "GPU_PEX_STRAP0")
	)
	(segment
		(start 330.064364 -118.467886)
		(end 330.775564 -118.467886)
		(width 0.13208)
		(layer "F.Cu")
		(net "P3V3_NIC5_SS")
	)
	(segment
		(start 329.035918 -120.041924)
		(end 329.126596 -119.951246)
		(width 0.13208)
		(layer "F.Cu")
		(net "P3V3_NIC5_SS")
	)
	(segment
		(start 329.126596 -119.951246)
		(end 329.126596 -119.405654)
		(width 0.13208)
		(layer "F.Cu")
		(net "P3V3_NIC5_SS")
	)
	(segment
		(start 328.971402 -120.041924)
		(end 329.035918 -120.041924)
		(width 0.13208)
		(layer "F.Cu")
		(net "P3V3_NIC5_SS")
	)
	(segment
		(start 329.126596 -119.405654)
		(end 330.064364 -118.467886)
		(width 0.13208)
		(layer "F.Cu")
		(net "P3V3_NIC5_SS")
	)
	(via
		(at 330.064364 -118.467886)
		(size 0.508)
		(drill 0.254)
		(layers "F.Cu" "B.Cu")
		(net "P3V3_NIC5_SS")
	)
	(segment
		(start 452.137018 -208.8134)
		(end 448.385946 -208.8134)
		(width 0.13462)
		(layer "F.Cu")
		(net "USB2_FT4232_MUX_D_DN")
	)
	(segment
		(start 453.86625 -208.8134)
		(end 455.488548 -208.8134)
		(width 0.13462)
		(layer "F.Cu")
		(net "USB2_FT4232_MUX_D_DN")
	)
	(segment
		(start 455.488548 -208.8134)
		(end 455.681842 -208.620106)
		(width 0.13462)
		(layer "F.Cu")
		(net "USB2_FT4232_MUX_D_DN")
	)
	(segment
		(start 455.681842 -208.620106)
		(end 456.294998 -208.620106)
		(width 0.13462)
		(layer "F.Cu")
		(net "USB2_FT4232_MUX_D_DN")
	)
	(segment
		(start 453.001634 -207.948784)
		(end 452.137018 -208.8134)
		(width 0.13462)
		(layer "F.Cu")
		(net "USB2_FT4232_MUX_D_DN")
	)
	(segment
		(start 453.001634 -207.948784)
		(end 453.86625 -208.8134)
		(width 0.13462)
		(layer "F.Cu")
		(net "USB2_FT4232_MUX_D_DN")
	)
	(segment
		(start 448.385946 -208.8134)
		(end 448.076828 -208.504282)
		(width 0.13462)
		(layer "F.Cu")
		(net "USB2_FT4232_MUX_D_DN")
	)
	(segment
		(start 130.695446 -205.06182)
		(end 128.80213 -206.955136)
		(width 0.13208)
		(layer "F.Cu")
		(net "FT4232_CLI_EEPROM_SDA")
	)
	(segment
		(start 132.9944 -203.964032)
		(end 132.776214 -204.182218)
		(width 0.13208)
		(layer "F.Cu")
		(net "FT4232_CLI_EEPROM_SDA")
	)
	(segment
		(start 132.415534 -205.06182)
		(end 130.695446 -205.06182)
		(width 0.13208)
		(layer "F.Cu")
		(net "FT4232_CLI_EEPROM_SDA")
	)
	(segment
		(start 132.776214 -204.70114)
		(end 132.415534 -205.06182)
		(width 0.13208)
		(layer "F.Cu")
		(net "FT4232_CLI_EEPROM_SDA")
	)
	(segment
		(start 133.831838 -203.964032)
		(end 132.9944 -203.964032)
		(width 0.13208)
		(layer "F.Cu")
		(net "FT4232_CLI_EEPROM_SDA")
	)
	(segment
		(start 132.776214 -204.182218)
		(end 132.776214 -204.70114)
		(width 0.13208)
		(layer "F.Cu")
		(net "FT4232_CLI_EEPROM_SDA")
	)
	(via
		(at 128.80213 -206.955136)
		(size 0.508)
		(drill 0.254)
		(layers "F.Cu" "B.Cu")
		(net "FT4232_CLI_EEPROM_SDA")
	)
	(segment
		(start 121.92 -204.416406)
		(end 121.92 -201.915522)
		(width 0.13208)
		(layer "B.Cu")
		(net "FT4232_CLI_EEPROM_SDA")
	)
	(segment
		(start 126.569978 -200.2536)
		(end 127.046228 -200.72985)
		(width 0.13208)
		(layer "B.Cu")
		(net "FT4232_CLI_EEPROM_SDA")
	)
	(segment
		(start 123.581922 -200.2536)
		(end 126.569978 -200.2536)
		(width 0.13208)
		(layer "B.Cu")
		(net "FT4232_CLI_EEPROM_SDA")
	)
	(segment
		(start 128.80213 -206.955136)
		(end 124.45873 -206.955136)
		(width 0.13208)
		(layer "B.Cu")
		(net "FT4232_CLI_EEPROM_SDA")
	)
	(segment
		(start 124.45873 -206.955136)
		(end 121.92 -204.416406)
		(width 0.13208)
		(layer "B.Cu")
		(net "FT4232_CLI_EEPROM_SDA")
	)
	(segment
		(start 121.92 -201.915522)
		(end 123.581922 -200.2536)
		(width 0.13208)
		(layer "B.Cu")
		(net "FT4232_CLI_EEPROM_SDA")
	)
	(segment
		(start 130.471164 -175.400462)
		(end 130.955542 -175.89881)
		(width 0.2032)
		(layer "F.Cu")
		(net "P3V3_DB2000QL_VDD")
	)
	(segment
		(start 130.974846 -179.422552)
		(end 130.956812 -179.440586)
		(width 0.2032)
		(layer "F.Cu")
		(net "P3V3_DB2000QL_VDD")
	)
	(segment
		(start 130.956812 -179.440586)
		(end 130.912616 -179.458874)
		(width 0.2032)
		(layer "F.Cu")
		(net "P3V3_DB2000QL_VDD")
	)
	(segment
		(start 134.485126 -179.414424)
		(end 134.971028 -179.900326)
		(width 0.2032)
		(layer "F.Cu")
		(net "P3V3_DB2000QL_VDD")
	)
	(segment
		(start 134.971028 -175.400462)
		(end 134.491222 -175.880522)
		(width 0.2032)
		(layer "F.Cu")
		(net "P3V3_DB2000QL_VDD")
	)
	(segment
		(start 134.485126 -179.38242)
		(end 134.485126 -179.414424)
		(width 0.2032)
		(layer "F.Cu")
		(net "P3V3_DB2000QL_VDD")
	)
	(segment
		(start 130.912616 -179.458874)
		(end 130.471164 -179.900326)
		(width 0.2032)
		(layer "F.Cu")
		(net "P3V3_DB2000QL_VDD")
	)
	(via
		(at 130.108706 -179.942236)
		(size 0.6604)
		(drill 0.3302)
		(layers "F.Cu" "B.Cu")
		(net "P3V3_DB2000QL_VDD")
	)
	(via
		(at 139.156694 -175.916082)
		(size 0.6604)
		(drill 0.3302)
		(layers "F.Cu" "B.Cu")
		(net "P3V3_DB2000QL_VDD")
	)
	(via
		(at 136.34974 -175.565562)
		(size 0.6604)
		(drill 0.3302)
		(layers "F.Cu" "B.Cu")
		(net "P3V3_DB2000QL_VDD")
	)
	(via
		(at 130.955542 -175.89881)
		(size 0.4572)
		(drill 0.254)
		(layers "F.Cu" "B.Cu")
		(net "P3V3_DB2000QL_VDD")
	)
	(via
		(at 134.485126 -179.38242)
		(size 0.49022)
		(drill 0.254)
		(layers "F.Cu" "B.Cu")
		(net "P3V3_DB2000QL_VDD")
	)
	(via
		(at 136.732264 -174.588678)
		(size 0.508)
		(drill 0.254)
		(layers "F.Cu" "B.Cu")
		(net "P3V3_DB2000QL_VDD")
	)
	(via
		(at 136.077452 -174.622206)
		(size 0.508)
		(drill 0.254)
		(layers "F.Cu" "B.Cu")
		(net "P3V3_DB2000QL_VDD")
	)
	(via
		(at 130.974846 -179.422552)
		(size 0.49022)
		(drill 0.254)
		(layers "F.Cu" "B.Cu")
		(net "P3V3_DB2000QL_VDD")
	)
	(via
		(at 134.491222 -175.880522)
		(size 0.4572)
		(drill 0.254)
		(layers "F.Cu" "B.Cu")
		(net "P3V3_DB2000QL_VDD")
	)
	(segment
		(start 129.011172 -181.03977)
		(end 130.108706 -179.942236)
		(width 0.381)
		(layer "B.Cu")
		(net "P3V3_DB2000QL_VDD")
	)
	(segment
		(start 134.803642 -179.38242)
		(end 135.433816 -180.012594)
		(width 0.381)
		(layer "B.Cu")
		(net "P3V3_DB2000QL_VDD")
	)
	(segment
		(start 130.108706 -179.942236)
		(end 130.62839 -179.422552)
		(width 0.381)
		(layer "B.Cu")
		(net "P3V3_DB2000QL_VDD")
	)
	(segment
		(start 130.62839 -179.422552)
		(end 130.974846 -179.422552)
		(width 0.381)
		(layer "B.Cu")
		(net "P3V3_DB2000QL_VDD")
	)
	(segment
		(start 130.906774 -175.850042)
		(end 130.955542 -175.89881)
		(width 0.381)
		(layer "B.Cu")
		(net "P3V3_DB2000QL_VDD")
	)
	(segment
		(start 130.906774 -174.996094)
		(end 130.906774 -175.850042)
		(width 0.381)
		(layer "B.Cu")
		(net "P3V3_DB2000QL_VDD")
	)
	(segment
		(start 134.485126 -179.38242)
		(end 134.803642 -179.38242)
		(width 0.381)
		(layer "B.Cu")
		(net "P3V3_DB2000QL_VDD")
	)
	(segment
		(start 128.641094 -181.03977)
		(end 129.011172 -181.03977)
		(width 0.381)
		(layer "B.Cu")
		(net "P3V3_DB2000QL_VDD")
	)
	(segment
		(start 253.40056 -92.848684)
		(end 253.678944 -92.848684)
		(width 0.13208)
		(layer "F.Cu")
		(net "TP_CK440_SBI_DATA_OUT")
	)
	(segment
		(start 253.678944 -92.848684)
		(end 255.740662 -90.786966)
		(width 0.13208)
		(layer "F.Cu")
		(net "TP_CK440_SBI_DATA_OUT")
	)
	(segment
		(start 250.538742 -94.098618)
		(end 252.150626 -94.098618)
		(width 0.13208)
		(layer "F.Cu")
		(net "TP_CK440_SBI_DATA_OUT")
	)
	(segment
		(start 257.201924 -90.786966)
		(end 257.92684 -90.06205)
		(width 0.13208)
		(layer "F.Cu")
		(net "TP_CK440_SBI_DATA_OUT")
	)
	(segment
		(start 257.92684 -90.06205)
		(end 257.92684 -88.181434)
		(width 0.13208)
		(layer "F.Cu")
		(net "TP_CK440_SBI_DATA_OUT")
	)
	(segment
		(start 255.740662 -90.786966)
		(end 257.201924 -90.786966)
		(width 0.13208)
		(layer "F.Cu")
		(net "TP_CK440_SBI_DATA_OUT")
	)
	(segment
		(start 252.150626 -94.098618)
		(end 253.40056 -92.848684)
		(width 0.13208)
		(layer "F.Cu")
		(net "TP_CK440_SBI_DATA_OUT")
	)
	(via
		(at 250.538742 -94.098618)
		(size 0.508)
		(drill 0.254)
		(layers "F.Cu" "B.Cu")
		(net "TP_CK440_SBI_DATA_OUT")
	)
	(segment
		(start 322.25361 -233.414824)
		(end 316.744604 -238.92383)
		(width 0.13208)
		(layer "F.Cu")
		(net "SMB_MB_R_SCL")
	)
	(segment
		(start 243.476018 -236.281976)
		(end 243.476018 -235.624116)
		(width 0.13208)
		(layer "F.Cu")
		(net "SMB_MB_R_SCL")
	)
	(segment
		(start 316.744604 -238.92383)
		(end 304.081942 -238.92383)
		(width 0.13208)
		(layer "F.Cu")
		(net "SMB_MB_R_SCL")
	)
	(via
		(at 243.476018 -235.624116)
		(size 0.508)
		(drill 0.254)
		(layers "F.Cu" "B.Cu")
		(net "SMB_MB_R_SCL")
	)
	(via
		(at 304.081942 -238.92383)
		(size 0.508)
		(drill 0.254)
		(layers "F.Cu" "B.Cu")
		(net "SMB_MB_R_SCL")
	)
	(segment
		(start 305.109626 -239.576356)
		(end 304.4571 -238.92383)
		(width 0.13208)
		(layer "B.Cu")
		(net "SMB_MB_R_SCL")
	)
	(segment
		(start 304.4571 -238.92383)
		(end 304.081942 -238.92383)
		(width 0.13208)
		(layer "B.Cu")
		(net "SMB_MB_R_SCL")
	)
	(segment
		(start 257.151886 -236.1692)
		(end 255.061974 -236.1692)
		(width 0.15494)
		(layer "In13.Cu")
		(net "SMB_MB_R_SCL")
	)
	(segment
		(start 277.784814 -238.454692)
		(end 277.763986 -238.47552)
		(width 0.15494)
		(layer "In13.Cu")
		(net "SMB_MB_R_SCL")
	)
	(segment
		(start 259.969508 -235.406438)
		(end 257.914648 -235.406438)
		(width 0.15494)
		(layer "In13.Cu")
		(net "SMB_MB_R_SCL")
	)
	(segment
		(start 304.081942 -238.92383)
		(end 303.612804 -238.454692)
		(width 0.15494)
		(layer "In13.Cu")
		(net "SMB_MB_R_SCL")
	)
	(segment
		(start 253.995174 -237.236)
		(end 249.046746 -237.236)
		(width 0.15494)
		(layer "In13.Cu")
		(net "SMB_MB_R_SCL")
	)
	(segment
		(start 260.451346 -234.9246)
		(end 259.969508 -235.406438)
		(width 0.15494)
		(layer "In13.Cu")
		(net "SMB_MB_R_SCL")
	)
	(segment
		(start 277.763986 -238.47552)
		(end 277.362666 -238.47552)
		(width 0.15494)
		(layer "In13.Cu")
		(net "SMB_MB_R_SCL")
	)
	(segment
		(start 273.3802 -234.9246)
		(end 260.451346 -234.9246)
		(width 0.15494)
		(layer "In13.Cu")
		(net "SMB_MB_R_SCL")
	)
	(segment
		(start 277.341838 -238.454692)
		(end 276.910292 -238.454692)
		(width 0.15494)
		(layer "In13.Cu")
		(net "SMB_MB_R_SCL")
	)
	(segment
		(start 249.046746 -237.236)
		(end 247.687592 -235.876846)
		(width 0.15494)
		(layer "In13.Cu")
		(net "SMB_MB_R_SCL")
	)
	(segment
		(start 243.997734 -235.1024)
		(end 243.476018 -235.624116)
		(width 0.15494)
		(layer "In13.Cu")
		(net "SMB_MB_R_SCL")
	)
	(segment
		(start 303.612804 -238.454692)
		(end 277.784814 -238.454692)
		(width 0.15494)
		(layer "In13.Cu")
		(net "SMB_MB_R_SCL")
	)
	(segment
		(start 276.910292 -238.454692)
		(end 273.3802 -234.9246)
		(width 0.15494)
		(layer "In13.Cu")
		(net "SMB_MB_R_SCL")
	)
	(segment
		(start 244.898926 -235.1024)
		(end 243.997734 -235.1024)
		(width 0.15494)
		(layer "In13.Cu")
		(net "SMB_MB_R_SCL")
	)
	(segment
		(start 246.769382 -235.876846)
		(end 244.898926 -235.1024)
		(width 0.15494)
		(layer "In13.Cu")
		(net "SMB_MB_R_SCL")
	)
	(segment
		(start 257.914648 -235.406438)
		(end 257.151886 -236.1692)
		(width 0.15494)
		(layer "In13.Cu")
		(net "SMB_MB_R_SCL")
	)
	(segment
		(start 277.362666 -238.47552)
		(end 277.341838 -238.454692)
		(width 0.15494)
		(layer "In13.Cu")
		(net "SMB_MB_R_SCL")
	)
	(segment
		(start 255.061974 -236.1692)
		(end 253.995174 -237.236)
		(width 0.15494)
		(layer "In13.Cu")
		(net "SMB_MB_R_SCL")
	)
	(segment
		(start 247.687592 -235.876846)
		(end 246.769382 -235.876846)
		(width 0.15494)
		(layer "In13.Cu")
		(net "SMB_MB_R_SCL")
	)
	(segment
		(start 178.764946 -22.990048)
		(end 179.809394 -22.990048)
		(width 0.13208)
		(layer "F.Cu")
		(net "SMB_ISO_SSD6_R_SDA")
	)
	(segment
		(start 179.809394 -22.990048)
		(end 179.844446 -23.0251)
		(width 0.13208)
		(layer "F.Cu")
		(net "SMB_ISO_SSD6_R_SDA")
	)
	(segment
		(start 190.758318 -19.453098)
		(end 191.367918 -19.453098)
		(width 0.13208)
		(layer "F.Cu")
		(net "SMB_ISO_SSD6_R_SDA")
	)
	(via
		(at 190.758318 -19.453098)
		(size 0.508)
		(drill 0.254)
		(layers "F.Cu" "B.Cu")
		(net "SMB_ISO_SSD6_R_SDA")
	)
	(via
		(at 179.844446 -23.0251)
		(size 0.508)
		(drill 0.254)
		(layers "F.Cu" "B.Cu")
		(net "SMB_ISO_SSD6_R_SDA")
	)
	(segment
		(start 190.758318 -21.570188)
		(end 189.796166 -22.53234)
		(width 0.15494)
		(layer "In5.Cu")
		(net "SMB_ISO_SSD6_R_SDA")
	)
	(segment
		(start 180.337206 -22.53234)
		(end 179.844446 -23.0251)
		(width 0.15494)
		(layer "In5.Cu")
		(net "SMB_ISO_SSD6_R_SDA")
	)
	(segment
		(start 189.796166 -22.53234)
		(end 180.337206 -22.53234)
		(width 0.15494)
		(layer "In5.Cu")
		(net "SMB_ISO_SSD6_R_SDA")
	)
	(segment
		(start 190.758318 -19.453098)
		(end 190.758318 -21.570188)
		(width 0.15494)
		(layer "In5.Cu")
		(net "SMB_ISO_SSD6_R_SDA")
	)
	(segment
		(start 359.568242 -125.036072)
		(end 359.747312 -125.036072)
		(width 0.13208)
		(layer "F.Cu")
		(net "P3V3_NIC6_OCP")
	)
	(segment
		(start 358.967532 -124.47016)
		(end 359.059734 -124.47016)
		(width 0.13208)
		(layer "F.Cu")
		(net "P3V3_NIC6_OCP")
	)
	(segment
		(start 359.059734 -124.47016)
		(end 359.568242 -124.978668)
		(width 0.13208)
		(layer "F.Cu")
		(net "P3V3_NIC6_OCP")
	)
	(segment
		(start 360.10596 -125.39472)
		(end 360.531156 -125.39472)
		(width 0.13208)
		(layer "F.Cu")
		(net "P3V3_NIC6_OCP")
	)
	(segment
		(start 359.568242 -124.978668)
		(end 359.568242 -125.036072)
		(width 0.13208)
		(layer "F.Cu")
		(net "P3V3_NIC6_OCP")
	)
	(segment
		(start 358.81056 -124.313188)
		(end 358.967532 -124.47016)
		(width 0.13208)
		(layer "F.Cu")
		(net "P3V3_NIC6_OCP")
	)
	(segment
		(start 358.81056 -123.947428)
		(end 358.81056 -124.313188)
		(width 0.13208)
		(layer "F.Cu")
		(net "P3V3_NIC6_OCP")
	)
	(segment
		(start 359.747312 -125.036072)
		(end 360.10596 -125.39472)
		(width 0.13208)
		(layer "F.Cu")
		(net "P3V3_NIC6_OCP")
	)
	(via
		(at 359.568242 -125.036072)
		(size 0.508)
		(drill 0.254)
		(layers "F.Cu" "B.Cu")
		(net "P3V3_NIC6_OCP")
	)
	(segment
		(start 456.294998 -207.97012)
		(end 454.928224 -207.97012)
		(width 0.381)
		(layer "F.Cu")
		(net "USB_VBUS_CONN")
	)
	(segment
		(start 454.928224 -207.97012)
		(end 454.924414 -207.97393)
		(width 0.381)
		(layer "F.Cu")
		(net "USB_VBUS_CONN")
	)
	(segment
		(start 451.101714 -209.94878)
		(end 451.968616 -209.94878)
		(width 0.508)
		(layer "F.Cu")
		(net "USB_VBUS_CONN")
	)
	(segment
		(start 451.122034 -209.9691)
		(end 451.101714 -209.94878)
		(width 0.508)
		(layer "F.Cu")
		(net "USB_VBUS_CONN")
	)
	(segment
		(start 451.122034 -211.663026)
		(end 451.122034 -209.9691)
		(width 0.508)
		(layer "F.Cu")
		(net "USB_VBUS_CONN")
	)
	(via
		(at 451.968616 -209.94878)
		(size 0.508)
		(drill 0.254)
		(layers "F.Cu" "B.Cu")
		(net "USB_VBUS_CONN")
	)
	(via
		(at 454.924414 -207.97393)
		(size 0.508)
		(drill 0.254)
		(layers "F.Cu" "B.Cu")
		(net "USB_VBUS_CONN")
	)
	(segment
		(start 453.943466 -207.97393)
		(end 454.924414 -207.97393)
		(width 0.508)
		(layer "B.Cu")
		(net "USB_VBUS_CONN")
	)
	(segment
		(start 451.968616 -209.94878)
		(end 453.943466 -207.97393)
		(width 0.508)
		(layer "B.Cu")
		(net "USB_VBUS_CONN")
	)
	(segment
		(start 132.268214 -204.507846)
		(end 132.268214 -203.938378)
		(width 0.13208)
		(layer "F.Cu")
		(net "FT4232_CLI_EEPROM_SCL")
	)
	(segment
		(start 132.742686 -203.463906)
		(end 133.831838 -203.463906)
		(width 0.13208)
		(layer "F.Cu")
		(net "FT4232_CLI_EEPROM_SCL")
	)
	(segment
		(start 132.268214 -203.938378)
		(end 132.742686 -203.463906)
		(width 0.13208)
		(layer "F.Cu")
		(net "FT4232_CLI_EEPROM_SCL")
	)
	(via
		(at 132.268214 -204.507846)
		(size 0.508)
		(drill 0.254)
		(layers "F.Cu" "B.Cu")
		(net "FT4232_CLI_EEPROM_SCL")
	)
	(segment
		(start 131.550918 -205.225142)
		(end 132.268214 -204.507846)
		(width 0.13208)
		(layer "B.Cu")
		(net "FT4232_CLI_EEPROM_SCL")
	)
	(segment
		(start 130.939794 -205.225142)
		(end 131.550918 -205.225142)
		(width 0.13208)
		(layer "B.Cu")
		(net "FT4232_CLI_EEPROM_SCL")
	)
	(segment
		(start 132.374386 -179.422552)
		(end 132.374386 -179.803552)
		(width 0.3048)
		(layer "F.Cu")
		(net "P3V3_DB2000QL_VDDA")
	)
	(segment
		(start 132.374386 -179.803552)
		(end 132.47116 -179.900326)
		(width 0.3048)
		(layer "F.Cu")
		(net "P3V3_DB2000QL_VDDA")
	)
	(via
		(at 131.844288 -180.132482)
		(size 0.508)
		(drill 0.254)
		(layers "F.Cu" "B.Cu")
		(net "P3V3_DB2000QL_VDDA")
	)
	(via
		(at 132.917946 -180.165502)
		(size 0.508)
		(drill 0.254)
		(layers "F.Cu" "B.Cu")
		(net "P3V3_DB2000QL_VDDA")
	)
	(via
		(at 132.374386 -179.422552)
		(size 0.49022)
		(drill 0.254)
		(layers "F.Cu" "B.Cu")
		(net "P3V3_DB2000QL_VDDA")
	)
	(via
		(at 131.311142 -181.124352)
		(size 0.6604)
		(drill 0.3302)
		(layers "F.Cu" "B.Cu")
		(net "P3V3_DB2000QL_VDDA")
	)
	(segment
		(start 252.99543 -91.696286)
		(end 254.352298 -91.696286)
		(width 0.13208)
		(layer "F.Cu")
		(net "PD_CK440_SBI_DATA_IN")
	)
	(segment
		(start 256.06248 -89.986104)
		(end 257.012948 -89.986104)
		(width 0.13208)
		(layer "F.Cu")
		(net "PD_CK440_SBI_DATA_IN")
	)
	(segment
		(start 257.676904 -87.431372)
		(end 257.676904 -88.710516)
		(width 0.0889)
		(layer "F.Cu")
		(net "PD_CK440_SBI_DATA_IN")
	)
	(segment
		(start 257.676904 -89.322148)
		(end 257.012948 -89.986104)
		(width 0.13208)
		(layer "F.Cu")
		(net "PD_CK440_SBI_DATA_IN")
	)
	(segment
		(start 257.676904 -88.710516)
		(end 257.676904 -89.322148)
		(width 0.13208)
		(layer "F.Cu")
		(net "PD_CK440_SBI_DATA_IN")
	)
	(segment
		(start 254.352298 -91.696286)
		(end 256.06248 -89.986104)
		(width 0.13208)
		(layer "F.Cu")
		(net "PD_CK440_SBI_DATA_IN")
	)
	(via
		(at 257.012948 -89.986104)
		(size 0.762)
		(drill 0.381)
		(layers "F.Cu" "B.Cu")
		(net "PD_CK440_SBI_DATA_IN")
	)
	(segment
		(start 72.949816 -300.649894)
		(end 73.424796 -300.174914)
		(width 0.254)
		(layer "F.Cu")
		(net "PEX0_ADCTEMP_VINP0")
	)
	(via
		(at 73.424796 -300.174914)
		(size 0.4064)
		(drill 0.2032)
		(layers "F.Cu" "B.Cu")
		(net "PEX0_ADCTEMP_VINP0")
	)
	(via
		(at 75.187048 -301.120556)
		(size 0.6604)
		(drill 0.3302)
		(layers "F.Cu" "B.Cu")
		(net "PEX0_ADCTEMP_VINP0")
	)
	(segment
		(start 74.791316 -300.724824)
		(end 75.187048 -301.120556)
		(width 0.13208)
		(layer "B.Cu")
		(net "PEX0_ADCTEMP_VINP0")
	)
	(segment
		(start 74.026776 -300.724824)
		(end 74.791316 -300.724824)
		(width 0.13208)
		(layer "B.Cu")
		(net "PEX0_ADCTEMP_VINP0")
	)
	(segment
		(start 73.974706 -300.724824)
		(end 74.026776 -300.724824)
		(width 0.254)
		(layer "B.Cu")
		(net "PEX0_ADCTEMP_VINP0")
	)
	(segment
		(start 73.424796 -300.174914)
		(end 73.974706 -300.724824)
		(width 0.254)
		(layer "B.Cu")
		(net "PEX0_ADCTEMP_VINP0")
	)
	(segment
		(start 153.809446 -22.990048)
		(end 153.844498 -23.0251)
		(width 0.13208)
		(layer "F.Cu")
		(net "SMB_ISO_SSD5_R_SDA")
	)
	(segment
		(start 152.764998 -22.990048)
		(end 153.809446 -22.990048)
		(width 0.13208)
		(layer "F.Cu")
		(net "SMB_ISO_SSD5_R_SDA")
	)
	(segment
		(start 164.75837 -19.453098)
		(end 165.36797 -19.453098)
		(width 0.13208)
		(layer "F.Cu")
		(net "SMB_ISO_SSD5_R_SDA")
	)
	(via
		(at 153.844498 -23.0251)
		(size 0.508)
		(drill 0.254)
		(layers "F.Cu" "B.Cu")
		(net "SMB_ISO_SSD5_R_SDA")
	)
	(via
		(at 164.75837 -19.453098)
		(size 0.508)
		(drill 0.254)
		(layers "F.Cu" "B.Cu")
		(net "SMB_ISO_SSD5_R_SDA")
	)
	(segment
		(start 154.337258 -22.53234)
		(end 153.844498 -23.0251)
		(width 0.15494)
		(layer "In5.Cu")
		(net "SMB_ISO_SSD5_R_SDA")
	)
	(segment
		(start 164.75837 -19.453098)
		(end 164.75837 -21.390356)
		(width 0.15494)
		(layer "In5.Cu")
		(net "SMB_ISO_SSD5_R_SDA")
	)
	(segment
		(start 163.616386 -22.53234)
		(end 154.337258 -22.53234)
		(width 0.15494)
		(layer "In5.Cu")
		(net "SMB_ISO_SSD5_R_SDA")
	)
	(segment
		(start 164.75837 -21.390356)
		(end 163.616386 -22.53234)
		(width 0.15494)
		(layer "In5.Cu")
		(net "SMB_ISO_SSD5_R_SDA")
	)
	(via
		(at 97.255584 -379.725936)
		(size 0.6604)
		(drill 0.3302)
		(layers "F.Cu" "B.Cu")
		(net "SMB_GPU_1_SDA")
	)
	(segment
		(start 92.04579 -379.725936)
		(end 97.255584 -379.725936)
		(width 0.13208)
		(layer "B.Cu")
		(net "SMB_GPU_1_SDA")
	)
	(segment
		(start 100.122482 -379.725936)
		(end 100.358194 -379.490224)
		(width 0.13208)
		(layer "B.Cu")
		(net "SMB_GPU_1_SDA")
	)
	(segment
		(start 91.710002 -379.390148)
		(end 92.04579 -379.725936)
		(width 0.13208)
		(layer "B.Cu")
		(net "SMB_GPU_1_SDA")
	)
	(segment
		(start 97.255584 -379.725936)
		(end 100.122482 -379.725936)
		(width 0.13208)
		(layer "B.Cu")
		(net "SMB_GPU_1_SDA")
	)
	(segment
		(start 455.493882 -209.08772)
		(end 455.676254 -209.270092)
		(width 0.13462)
		(layer "F.Cu")
		(net "USB2_FT4232_MUX_D_DP")
	)
	(segment
		(start 453.862694 -209.08772)
		(end 455.493882 -209.08772)
		(width 0.13462)
		(layer "F.Cu")
		(net "USB2_FT4232_MUX_D_DP")
	)
	(segment
		(start 453.001634 -209.94878)
		(end 452.140574 -209.08772)
		(width 0.13462)
		(layer "F.Cu")
		(net "USB2_FT4232_MUX_D_DP")
	)
	(segment
		(start 448.38239 -209.08772)
		(end 448.076828 -209.393282)
		(width 0.13462)
		(layer "F.Cu")
		(net "USB2_FT4232_MUX_D_DP")
	)
	(segment
		(start 453.001634 -209.94878)
		(end 453.862694 -209.08772)
		(width 0.13462)
		(layer "F.Cu")
		(net "USB2_FT4232_MUX_D_DP")
	)
	(segment
		(start 455.676254 -209.270092)
		(end 456.294998 -209.270092)
		(width 0.13462)
		(layer "F.Cu")
		(net "USB2_FT4232_MUX_D_DP")
	)
	(segment
		(start 452.140574 -209.08772)
		(end 448.38239 -209.08772)
		(width 0.13462)
		(layer "F.Cu")
		(net "USB2_FT4232_MUX_D_DP")
	)
	(segment
		(start 132.50672 -202.964034)
		(end 132.052314 -202.509628)
		(width 0.13208)
		(layer "F.Cu")
		(net "FT4232_CLI_EEPROM_CS")
	)
	(segment
		(start 133.831838 -202.964034)
		(end 132.50672 -202.964034)
		(width 0.13208)
		(layer "F.Cu")
		(net "FT4232_CLI_EEPROM_CS")
	)
	(segment
		(start 132.052314 -202.509628)
		(end 132.052314 -202.145392)
		(width 0.13208)
		(layer "F.Cu")
		(net "FT4232_CLI_EEPROM_CS")
	)
	(via
		(at 132.052314 -202.145392)
		(size 0.508)
		(drill 0.254)
		(layers "F.Cu" "B.Cu")
		(net "FT4232_CLI_EEPROM_CS")
	)
	(segment
		(start 131.414012 -203.193142)
		(end 132.052314 -202.55484)
		(width 0.13208)
		(layer "B.Cu")
		(net "FT4232_CLI_EEPROM_CS")
	)
	(segment
		(start 132.052314 -202.55484)
		(end 132.052314 -202.145392)
		(width 0.13208)
		(layer "B.Cu")
		(net "FT4232_CLI_EEPROM_CS")
	)
	(segment
		(start 130.939794 -203.193142)
		(end 131.414012 -203.193142)
		(width 0.13208)
		(layer "B.Cu")
		(net "FT4232_CLI_EEPROM_CS")
	)
	(segment
		(start 133.96468 -169.829988)
		(end 133.96468 -168.963848)
		(width 0.13462)
		(layer "F.Cu")
		(net "CLK_100M_DB2000QL_NIC0_R_DP")
	)
	(segment
		(start 45.60316 -137.765028)
		(end 46.042326 -137.765028)
		(width 0.13462)
		(layer "F.Cu")
		(net "CLK_100M_DB2000QL_NIC0_R_DP")
	)
	(segment
		(start 133.96468 -168.963848)
		(end 133.671056 -168.670224)
		(width 0.13462)
		(layer "F.Cu")
		(net "CLK_100M_DB2000QL_NIC0_R_DP")
	)
	(segment
		(start 44.430442 -137.633202)
		(end 44.725082 -137.927842)
		(width 0.13462)
		(layer "F.Cu")
		(net "CLK_100M_DB2000QL_NIC0_R_DP")
	)
	(segment
		(start 133.594856 -170.199812)
		(end 133.96468 -169.829988)
		(width 0.13462)
		(layer "F.Cu")
		(net "CLK_100M_DB2000QL_NIC0_R_DP")
	)
	(segment
		(start 44.725082 -137.927842)
		(end 45.440346 -137.927842)
		(width 0.13462)
		(layer "F.Cu")
		(net "CLK_100M_DB2000QL_NIC0_R_DP")
	)
	(segment
		(start 45.440346 -137.927842)
		(end 45.60316 -137.765028)
		(width 0.13462)
		(layer "F.Cu")
		(net "CLK_100M_DB2000QL_NIC0_R_DP")
	)
	(via
		(at 44.430442 -137.633202)
		(size 0.508)
		(drill 0.254)
		(layers "F.Cu" "B.Cu")
		(net "CLK_100M_DB2000QL_NIC0_R_DP")
	)
	(via
		(at 133.671056 -168.670224)
		(size 0.508)
		(drill 0.254)
		(layers "F.Cu" "B.Cu")
		(net "CLK_100M_DB2000QL_NIC0_R_DP")
	)
	(segment
		(start 83.93684 -164.81806)
		(end 57.01284 -164.81806)
		(width 0.1651)
		(layer "In15.Cu")
		(net "CLK_100M_DB2000QL_NIC0_R_DP")
	)
	(segment
		(start 54.15534 -143.29156)
		(end 53.46954 -142.60576)
		(width 0.1651)
		(layer "In15.Cu")
		(net "CLK_100M_DB2000QL_NIC0_R_DP")
	)
	(segment
		(start 98.501962 -179.221384)
		(end 98.340164 -179.221384)
		(width 0.1651)
		(layer "In15.Cu")
		(net "CLK_100M_DB2000QL_NIC0_R_DP")
	)
	(segment
		(start 99.714812 -180.434234)
		(end 99.364292 -180.083714)
		(width 0.1651)
		(layer "In15.Cu")
		(net "CLK_100M_DB2000QL_NIC0_R_DP")
	)
	(segment
		(start 49.87544 -137.48766)
		(end 45.78096 -137.48766)
		(width 0.1651)
		(layer "In15.Cu")
		(net "CLK_100M_DB2000QL_NIC0_R_DP")
	)
	(segment
		(start 99.714812 -180.596032)
		(end 99.714812 -180.434234)
		(width 0.1651)
		(layer "In15.Cu")
		(net "CLK_100M_DB2000QL_NIC0_R_DP")
	)
	(segment
		(start 97.990152 -178.709574)
		(end 97.639632 -178.359054)
		(width 0.1651)
		(layer "In15.Cu")
		(net "CLK_100M_DB2000QL_NIC0_R_DP")
	)
	(segment
		(start 97.477834 -178.359054)
		(end 97.127822 -178.009042)
		(width 0.1651)
		(layer "In15.Cu")
		(net "CLK_100M_DB2000QL_NIC0_R_DP")
	)
	(segment
		(start 110.417356 -185.627264)
		(end 106.44505 -185.627264)
		(width 0.1651)
		(layer "In15.Cu")
		(net "CLK_100M_DB2000QL_NIC0_R_DP")
	)
	(segment
		(start 54.15534 -161.96056)
		(end 54.15534 -143.29156)
		(width 0.1651)
		(layer "In15.Cu")
		(net "CLK_100M_DB2000QL_NIC0_R_DP")
	)
	(segment
		(start 97.990152 -178.871372)
		(end 97.990152 -178.709574)
		(width 0.1651)
		(layer "In15.Cu")
		(net "CLK_100M_DB2000QL_NIC0_R_DP")
	)
	(segment
		(start 99.202494 -180.083714)
		(end 98.852482 -179.733702)
		(width 0.1651)
		(layer "In15.Cu")
		(net "CLK_100M_DB2000QL_NIC0_R_DP")
	)
	(segment
		(start 96.777302 -177.496978)
		(end 96.615758 -177.496978)
		(width 0.1651)
		(layer "In15.Cu")
		(net "CLK_100M_DB2000QL_NIC0_R_DP")
	)
	(segment
		(start 53.46954 -142.60576)
		(end 53.46954 -139.45616)
		(width 0.1651)
		(layer "In15.Cu")
		(net "CLK_100M_DB2000QL_NIC0_R_DP")
	)
	(segment
		(start 97.127822 -178.009042)
		(end 97.127822 -177.847498)
		(width 0.1651)
		(layer "In15.Cu")
		(net "CLK_100M_DB2000QL_NIC0_R_DP")
	)
	(segment
		(start 45.78096 -137.48766)
		(end 45.344588 -137.924032)
		(width 0.1651)
		(layer "In15.Cu")
		(net "CLK_100M_DB2000QL_NIC0_R_DP")
	)
	(segment
		(start 125.23216 -169.97426)
		(end 121.79046 -173.41596)
		(width 0.1651)
		(layer "In15.Cu")
		(net "CLK_100M_DB2000QL_NIC0_R_DP")
	)
	(segment
		(start 120.22836 -184.50306)
		(end 111.54156 -184.50306)
		(width 0.1651)
		(layer "In15.Cu")
		(net "CLK_100M_DB2000QL_NIC0_R_DP")
	)
	(segment
		(start 50.51044 -138.12266)
		(end 49.87544 -137.48766)
		(width 0.1651)
		(layer "In15.Cu")
		(net "CLK_100M_DB2000QL_NIC0_R_DP")
	)
	(segment
		(start 98.852482 -179.733702)
		(end 98.852482 -179.571904)
		(width 0.1651)
		(layer "In15.Cu")
		(net "CLK_100M_DB2000QL_NIC0_R_DP")
	)
	(segment
		(start 97.127822 -177.847498)
		(end 96.777302 -177.496978)
		(width 0.1651)
		(layer "In15.Cu")
		(net "CLK_100M_DB2000QL_NIC0_R_DP")
	)
	(segment
		(start 133.961886 -169.448734)
		(end 133.43636 -169.97426)
		(width 0.1651)
		(layer "In15.Cu")
		(net "CLK_100M_DB2000QL_NIC0_R_DP")
	)
	(segment
		(start 133.961886 -168.961054)
		(end 133.961886 -169.448734)
		(width 0.1651)
		(layer "In15.Cu")
		(net "CLK_100M_DB2000QL_NIC0_R_DP")
	)
	(segment
		(start 97.639632 -178.359054)
		(end 97.477834 -178.359054)
		(width 0.1651)
		(layer "In15.Cu")
		(net "CLK_100M_DB2000QL_NIC0_R_DP")
	)
	(segment
		(start 98.852482 -179.571904)
		(end 98.501962 -179.221384)
		(width 0.1651)
		(layer "In15.Cu")
		(net "CLK_100M_DB2000QL_NIC0_R_DP")
	)
	(segment
		(start 133.43636 -169.97426)
		(end 125.23216 -169.97426)
		(width 0.1651)
		(layer "In15.Cu")
		(net "CLK_100M_DB2000QL_NIC0_R_DP")
	)
	(segment
		(start 133.671056 -168.670224)
		(end 133.961886 -168.961054)
		(width 0.1651)
		(layer "In15.Cu")
		(net "CLK_100M_DB2000QL_NIC0_R_DP")
	)
	(segment
		(start 45.344588 -137.924032)
		(end 44.721272 -137.924032)
		(width 0.1651)
		(layer "In15.Cu")
		(net "CLK_100M_DB2000QL_NIC0_R_DP")
	)
	(segment
		(start 103.544878 -184.426098)
		(end 99.714812 -180.596032)
		(width 0.1651)
		(layer "In15.Cu")
		(net "CLK_100M_DB2000QL_NIC0_R_DP")
	)
	(segment
		(start 111.54156 -184.50306)
		(end 110.417356 -185.627264)
		(width 0.1651)
		(layer "In15.Cu")
		(net "CLK_100M_DB2000QL_NIC0_R_DP")
	)
	(segment
		(start 52.13604 -138.12266)
		(end 50.51044 -138.12266)
		(width 0.1651)
		(layer "In15.Cu")
		(net "CLK_100M_DB2000QL_NIC0_R_DP")
	)
	(segment
		(start 121.79046 -173.41596)
		(end 121.79046 -182.94096)
		(width 0.1651)
		(layer "In15.Cu")
		(net "CLK_100M_DB2000QL_NIC0_R_DP")
	)
	(segment
		(start 106.44505 -185.627264)
		(end 103.544878 -184.426098)
		(width 0.1651)
		(layer "In15.Cu")
		(net "CLK_100M_DB2000QL_NIC0_R_DP")
	)
	(segment
		(start 96.615758 -177.496978)
		(end 83.93684 -164.81806)
		(width 0.1651)
		(layer "In15.Cu")
		(net "CLK_100M_DB2000QL_NIC0_R_DP")
	)
	(segment
		(start 99.364292 -180.083714)
		(end 99.202494 -180.083714)
		(width 0.1651)
		(layer "In15.Cu")
		(net "CLK_100M_DB2000QL_NIC0_R_DP")
	)
	(segment
		(start 98.340164 -179.221384)
		(end 97.990152 -178.871372)
		(width 0.1651)
		(layer "In15.Cu")
		(net "CLK_100M_DB2000QL_NIC0_R_DP")
	)
	(segment
		(start 44.721272 -137.924032)
		(end 44.430442 -137.633202)
		(width 0.1651)
		(layer "In15.Cu")
		(net "CLK_100M_DB2000QL_NIC0_R_DP")
	)
	(segment
		(start 121.79046 -182.94096)
		(end 120.22836 -184.50306)
		(width 0.1651)
		(layer "In15.Cu")
		(net "CLK_100M_DB2000QL_NIC0_R_DP")
	)
	(segment
		(start 57.01284 -164.81806)
		(end 54.15534 -161.96056)
		(width 0.1651)
		(layer "In15.Cu")
		(net "CLK_100M_DB2000QL_NIC0_R_DP")
	)
	(segment
		(start 53.46954 -139.45616)
		(end 52.13604 -138.12266)
		(width 0.1651)
		(layer "In15.Cu")
		(net "CLK_100M_DB2000QL_NIC0_R_DP")
	)
	(segment
		(start 72.949816 -299.699934)
		(end 72.474836 -299.224954)
		(width 0.254)
		(layer "F.Cu")
		(net "PEX0_ADCTEMP_VINP1")
	)
	(via
		(at 72.474836 -299.224954)
		(size 0.4064)
		(drill 0.2032)
		(layers "F.Cu" "B.Cu")
		(net "PEX0_ADCTEMP_VINP1")
	)
	(via
		(at 75.2983 -299.330618)
		(size 0.6604)
		(drill 0.3302)
		(layers "F.Cu" "B.Cu")
		(net "PEX0_ADCTEMP_VINP1")
	)
	(segment
		(start 72.474836 -299.224954)
		(end 72.964802 -299.71492)
		(width 0.254)
		(layer "B.Cu")
		(net "PEX0_ADCTEMP_VINP1")
	)
	(segment
		(start 74.026776 -299.62475)
		(end 75.004168 -299.62475)
		(width 0.13208)
		(layer "B.Cu")
		(net "PEX0_ADCTEMP_VINP1")
	)
	(segment
		(start 73.936606 -299.71492)
		(end 74.026776 -299.62475)
		(width 0.254)
		(layer "B.Cu")
		(net "PEX0_ADCTEMP_VINP1")
	)
	(segment
		(start 72.964802 -299.71492)
		(end 73.936606 -299.71492)
		(width 0.254)
		(layer "B.Cu")
		(net "PEX0_ADCTEMP_VINP1")
	)
	(segment
		(start 75.004168 -299.62475)
		(end 75.2983 -299.330618)
		(width 0.13208)
		(layer "B.Cu")
		(net "PEX0_ADCTEMP_VINP1")
	)
	(segment
		(start 37.709348 -22.990048)
		(end 37.7444 -23.0251)
		(width 0.13208)
		(layer "F.Cu")
		(net "SMB_ISO_SSD1_R_SDA")
	)
	(segment
		(start 36.6649 -22.990048)
		(end 37.709348 -22.990048)
		(width 0.13208)
		(layer "F.Cu")
		(net "SMB_ISO_SSD1_R_SDA")
	)
	(segment
		(start 48.658272 -19.453098)
		(end 49.267872 -19.453098)
		(width 0.13208)
		(layer "F.Cu")
		(net "SMB_ISO_SSD1_R_SDA")
	)
	(via
		(at 37.7444 -23.0251)
		(size 0.508)
		(drill 0.254)
		(layers "F.Cu" "B.Cu")
		(net "SMB_ISO_SSD1_R_SDA")
	)
	(via
		(at 48.658272 -19.453098)
		(size 0.508)
		(drill 0.254)
		(layers "F.Cu" "B.Cu")
		(net "SMB_ISO_SSD1_R_SDA")
	)
	(segment
		(start 38.3667 -22.4028)
		(end 37.7444 -23.0251)
		(width 0.15494)
		(layer "In5.Cu")
		(net "SMB_ISO_SSD1_R_SDA")
	)
	(segment
		(start 48.658272 -21.390356)
		(end 47.645828 -22.4028)
		(width 0.15494)
		(layer "In5.Cu")
		(net "SMB_ISO_SSD1_R_SDA")
	)
	(segment
		(start 48.658272 -19.453098)
		(end 48.658272 -21.390356)
		(width 0.15494)
		(layer "In5.Cu")
		(net "SMB_ISO_SSD1_R_SDA")
	)
	(segment
		(start 47.645828 -22.4028)
		(end 38.3667 -22.4028)
		(width 0.15494)
		(layer "In5.Cu")
		(net "SMB_ISO_SSD1_R_SDA")
	)
	(segment
		(start 101.829362 -385.205224)
		(end 101.39045 -385.205224)
		(width 0.13462)
		(layer "F.Cu")
		(net "USB2_MB_BMC_DP")
	)
	(segment
		(start 101.39045 -385.205224)
		(end 100.905564 -384.720338)
		(width 0.13462)
		(layer "F.Cu")
		(net "USB2_MB_BMC_DP")
	)
	(via
		(at 100.905564 -384.720338)
		(size 0.508)
		(drill 0.254)
		(layers "F.Cu" "B.Cu")
		(net "USB2_MB_BMC_DP")
	)
	(via
		(at 99.75723 -385.002024)
		(size 0.4064)
		(drill 0.2032)
		(layers "F.Cu" "B.Cu")
		(net "USB2_MB_BMC_DP")
	)
	(segment
		(start 99.003612 -385.002024)
		(end 99.75723 -385.002024)
		(width 0.13462)
		(layer "B.Cu")
		(net "USB2_MB_BMC_DP")
	)
	(segment
		(start 90.003376 -397.009366)
		(end 90.390472 -396.62227)
		(width 0.13462)
		(layer "B.Cu")
		(net "USB2_MB_BMC_DP")
	)
	(segment
		(start 100.905564 -384.720338)
		(end 100.623878 -385.002024)
		(width 0.13462)
		(layer "B.Cu")
		(net "USB2_MB_BMC_DP")
	)
	(segment
		(start 91.841066 -393.120626)
		(end 96.602042 -385.996688)
		(width 0.13462)
		(layer "B.Cu")
		(net "USB2_MB_BMC_DP")
	)
	(segment
		(start 100.623878 -385.002024)
		(end 99.75723 -385.002024)
		(width 0.13462)
		(layer "B.Cu")
		(net "USB2_MB_BMC_DP")
	)
	(segment
		(start 89.631774 -397.009366)
		(end 90.003376 -397.009366)
		(width 0.13462)
		(layer "B.Cu")
		(net "USB2_MB_BMC_DP")
	)
	(segment
		(start 89.509854 -396.887446)
		(end 89.631774 -397.009366)
		(width 0.13462)
		(layer "B.Cu")
		(net "USB2_MB_BMC_DP")
	)
	(segment
		(start 90.390472 -396.62227)
		(end 91.841066 -393.120626)
		(width 0.13462)
		(layer "B.Cu")
		(net "USB2_MB_BMC_DP")
	)
	(segment
		(start 96.602042 -385.996688)
		(end 99.003612 -385.002024)
		(width 0.13462)
		(layer "B.Cu")
		(net "USB2_MB_BMC_DP")
	)
	(segment
		(start 89.509854 -396.49019)
		(end 89.509854 -396.887446)
		(width 0.13462)
		(layer "B.Cu")
		(net "USB2_MB_BMC_DP")
	)
	(segment
		(start 137.020046 -197.069456)
		(end 137.267696 -196.821806)
		(width 0.13208)
		(layer "F.Cu")
		(net "OSC_CLI_OUT")
	)
	(segment
		(start 136.806686 -199.611742)
		(end 137.020046 -199.398382)
		(width 0.13208)
		(layer "F.Cu")
		(net "OSC_CLI_OUT")
	)
	(segment
		(start 137.020046 -198.091806)
		(end 137.020046 -197.069456)
		(width 0.13208)
		(layer "F.Cu")
		(net "OSC_CLI_OUT")
	)
	(segment
		(start 137.020046 -198.726806)
		(end 137.020046 -198.091806)
		(width 0.13208)
		(layer "F.Cu")
		(net "OSC_CLI_OUT")
	)
	(segment
		(start 139.613894 -195.61175)
		(end 139.613894 -196.557392)
		(width 0.13208)
		(layer "F.Cu")
		(net "OSC_CLI_OUT")
	)
	(segment
		(start 136.806686 -200.489058)
		(end 136.806686 -199.611742)
		(width 0.13208)
		(layer "F.Cu")
		(net "OSC_CLI_OUT")
	)
	(segment
		(start 137.020046 -199.398382)
		(end 137.020046 -198.726806)
		(width 0.13208)
		(layer "F.Cu")
		(net "OSC_CLI_OUT")
	)
	(segment
		(start 139.34948 -196.821806)
		(end 137.267696 -196.821806)
		(width 0.13208)
		(layer "F.Cu")
		(net "OSC_CLI_OUT")
	)
	(segment
		(start 139.613894 -196.557392)
		(end 139.34948 -196.821806)
		(width 0.13208)
		(layer "F.Cu")
		(net "OSC_CLI_OUT")
	)
	(segment
		(start 138.94054 -194.938396)
		(end 139.613894 -195.61175)
		(width 0.13208)
		(layer "F.Cu")
		(net "OSC_CLI_OUT")
	)
	(segment
		(start 138.837924 -194.938396)
		(end 138.94054 -194.938396)
		(width 0.13208)
		(layer "F.Cu")
		(net "OSC_CLI_OUT")
	)
	(via
		(at 137.020046 -198.726806)
		(size 0.508)
		(drill 0.254)
		(layers "F.Cu" "B.Cu")
		(net "OSC_CLI_OUT")
	)
	(segment
		(start 191.032638 -117.758972)
		(end 190.745872 -117.472206)
		(width 0.13462)
		(layer "F.Cu")
		(net "CLK_100M_DB2000QL_NIC3_R_DP")
	)
	(segment
		(start 190.019686 -117.472206)
		(end 189.856872 -117.63502)
		(width 0.13462)
		(layer "F.Cu")
		(net "CLK_100M_DB2000QL_NIC3_R_DP")
	)
	(segment
		(start 190.745872 -117.472206)
		(end 190.019686 -117.472206)
		(width 0.13462)
		(layer "F.Cu")
		(net "CLK_100M_DB2000QL_NIC3_R_DP")
	)
	(segment
		(start 140.857986 -176.28108)
		(end 142.331186 -176.28108)
		(width 0.13462)
		(layer "F.Cu")
		(net "CLK_100M_DB2000QL_NIC3_R_DP")
	)
	(segment
		(start 140.474192 -175.897286)
		(end 140.857986 -176.28108)
		(width 0.13462)
		(layer "F.Cu")
		(net "CLK_100M_DB2000QL_NIC3_R_DP")
	)
	(segment
		(start 189.856872 -117.63502)
		(end 189.357508 -117.63502)
		(width 0.13462)
		(layer "F.Cu")
		(net "CLK_100M_DB2000QL_NIC3_R_DP")
	)
	(segment
		(start 142.331186 -176.28108)
		(end 142.63878 -175.973486)
		(width 0.13462)
		(layer "F.Cu")
		(net "CLK_100M_DB2000QL_NIC3_R_DP")
	)
	(via
		(at 191.032638 -117.758972)
		(size 0.508)
		(drill 0.254)
		(layers "F.Cu" "B.Cu")
		(net "CLK_100M_DB2000QL_NIC3_R_DP")
	)
	(via
		(at 142.63878 -175.973486)
		(size 0.508)
		(drill 0.254)
		(layers "F.Cu" "B.Cu")
		(net "CLK_100M_DB2000QL_NIC3_R_DP")
	)
	(segment
		(start 143.98498 -176.278794)
		(end 142.944088 -176.278794)
		(width 0.13462)
		(layer "B.Cu")
		(net "CLK_100M_DB2000QL_NIC3_R_DP")
	)
	(segment
		(start 149.50694 -176.141634)
		(end 149.36978 -176.278794)
		(width 0.13462)
		(layer "B.Cu")
		(net "CLK_100M_DB2000QL_NIC3_R_DP")
	)
	(segment
		(start 155.323032 -171.776898)
		(end 154.933904 -171.776898)
		(width 0.13462)
		(layer "B.Cu")
		(net "CLK_100M_DB2000QL_NIC3_R_DP")
	)
	(segment
		(start 152.701752 -174.00905)
		(end 152.701752 -174.398178)
		(width 0.13462)
		(layer "B.Cu")
		(net "CLK_100M_DB2000QL_NIC3_R_DP")
	)
	(segment
		(start 152.948894 -176.278794)
		(end 151.12238 -176.278794)
		(width 0.13462)
		(layer "B.Cu")
		(net "CLK_100M_DB2000QL_NIC3_R_DP")
	)
	(segment
		(start 155.950412 -171.149518)
		(end 156.920438 -172.119544)
		(width 0.13462)
		(layer "B.Cu")
		(net "CLK_100M_DB2000QL_NIC3_R_DP")
	)
	(segment
		(start 150.98522 -176.141634)
		(end 150.5839 -176.141634)
		(width 0.13462)
		(layer "B.Cu")
		(net "CLK_100M_DB2000QL_NIC3_R_DP")
	)
	(segment
		(start 189.910974 -120.83288)
		(end 185.885074 -124.85878)
		(width 0.13462)
		(layer "B.Cu")
		(net "CLK_100M_DB2000QL_NIC3_R_DP")
	)
	(segment
		(start 148.29282 -176.278794)
		(end 147.8915 -176.278794)
		(width 0.13462)
		(layer "B.Cu")
		(net "CLK_100M_DB2000QL_NIC3_R_DP")
	)
	(segment
		(start 144.12214 -176.141634)
		(end 143.98498 -176.278794)
		(width 0.13462)
		(layer "B.Cu")
		(net "CLK_100M_DB2000QL_NIC3_R_DP")
	)
	(segment
		(start 191.327278 -117.464332)
		(end 191.701674 -117.464332)
		(width 0.13462)
		(layer "B.Cu")
		(net "CLK_100M_DB2000QL_NIC3_R_DP")
	)
	(segment
		(start 149.90826 -176.141634)
		(end 149.50694 -176.141634)
		(width 0.13462)
		(layer "B.Cu")
		(net "CLK_100M_DB2000QL_NIC3_R_DP")
	)
	(segment
		(start 175.432212 -156.415486)
		(end 175.432212 -164.180774)
		(width 0.13462)
		(layer "B.Cu")
		(net "CLK_100M_DB2000QL_NIC3_R_DP")
	)
	(segment
		(start 192.093596 -119.256556)
		(end 190.517272 -120.83288)
		(width 0.13462)
		(layer "B.Cu")
		(net "CLK_100M_DB2000QL_NIC3_R_DP")
	)
	(segment
		(start 148.96846 -176.278794)
		(end 148.8313 -176.141634)
		(width 0.13462)
		(layer "B.Cu")
		(net "CLK_100M_DB2000QL_NIC3_R_DP")
	)
	(segment
		(start 153.309574 -173.401228)
		(end 152.701752 -174.00905)
		(width 0.13462)
		(layer "B.Cu")
		(net "CLK_100M_DB2000QL_NIC3_R_DP")
	)
	(segment
		(start 146.67738 -176.141634)
		(end 146.27606 -176.141634)
		(width 0.13462)
		(layer "B.Cu")
		(net "CLK_100M_DB2000QL_NIC3_R_DP")
	)
	(segment
		(start 155.950412 -170.76039)
		(end 155.950412 -171.149518)
		(width 0.13462)
		(layer "B.Cu")
		(net "CLK_100M_DB2000QL_NIC3_R_DP")
	)
	(segment
		(start 153.659078 -175.56861)
		(end 152.948894 -176.278794)
		(width 0.13462)
		(layer "B.Cu")
		(net "CLK_100M_DB2000QL_NIC3_R_DP")
	)
	(segment
		(start 172.428154 -167.184832)
		(end 159.52597 -167.184832)
		(width 0.13462)
		(layer "B.Cu")
		(net "CLK_100M_DB2000QL_NIC3_R_DP")
	)
	(segment
		(start 157.574742 -169.13606)
		(end 157.574742 -169.525188)
		(width 0.13462)
		(layer "B.Cu")
		(net "CLK_100M_DB2000QL_NIC3_R_DP")
	)
	(segment
		(start 145.1991 -176.141634)
		(end 145.06194 -176.278794)
		(width 0.13462)
		(layer "B.Cu")
		(net "CLK_100M_DB2000QL_NIC3_R_DP")
	)
	(segment
		(start 148.42998 -176.141634)
		(end 148.29282 -176.278794)
		(width 0.13462)
		(layer "B.Cu")
		(net "CLK_100M_DB2000QL_NIC3_R_DP")
	)
	(segment
		(start 154.933904 -171.776898)
		(end 154.326082 -172.38472)
		(width 0.13462)
		(layer "B.Cu")
		(net "CLK_100M_DB2000QL_NIC3_R_DP")
	)
	(segment
		(start 142.944088 -176.278794)
		(end 142.63878 -175.973486)
		(width 0.13462)
		(layer "B.Cu")
		(net "CLK_100M_DB2000QL_NIC3_R_DP")
	)
	(segment
		(start 154.326082 -172.38472)
		(end 154.326082 -172.773848)
		(width 0.13462)
		(layer "B.Cu")
		(net "CLK_100M_DB2000QL_NIC3_R_DP")
	)
	(segment
		(start 146.81454 -176.278794)
		(end 146.67738 -176.141634)
		(width 0.13462)
		(layer "B.Cu")
		(net "CLK_100M_DB2000QL_NIC3_R_DP")
	)
	(segment
		(start 146.27606 -176.141634)
		(end 146.1389 -176.278794)
		(width 0.13462)
		(layer "B.Cu")
		(net "CLK_100M_DB2000QL_NIC3_R_DP")
	)
	(segment
		(start 156.920438 -172.119544)
		(end 156.920438 -172.291756)
		(width 0.13462)
		(layer "B.Cu")
		(net "CLK_100M_DB2000QL_NIC3_R_DP")
	)
	(segment
		(start 153.659078 -175.355504)
		(end 153.659078 -175.56861)
		(width 0.13462)
		(layer "B.Cu")
		(net "CLK_100M_DB2000QL_NIC3_R_DP")
	)
	(segment
		(start 190.517272 -120.83288)
		(end 189.910974 -120.83288)
		(width 0.13462)
		(layer "B.Cu")
		(net "CLK_100M_DB2000QL_NIC3_R_DP")
	)
	(segment
		(start 155.296108 -173.916086)
		(end 154.84094 -174.371254)
		(width 0.13462)
		(layer "B.Cu")
		(net "CLK_100M_DB2000QL_NIC3_R_DP")
	)
	(segment
		(start 145.06194 -176.278794)
		(end 144.66062 -176.278794)
		(width 0.13462)
		(layer "B.Cu")
		(net "CLK_100M_DB2000QL_NIC3_R_DP")
	)
	(segment
		(start 156.293058 -172.746924)
		(end 155.323032 -171.776898)
		(width 0.13462)
		(layer "B.Cu")
		(net "CLK_100M_DB2000QL_NIC3_R_DP")
	)
	(segment
		(start 158.544768 -170.495214)
		(end 158.544768 -170.667426)
		(width 0.13462)
		(layer "B.Cu")
		(net "CLK_100M_DB2000QL_NIC3_R_DP")
	)
	(segment
		(start 191.032638 -117.758972)
		(end 191.327278 -117.464332)
		(width 0.13462)
		(layer "B.Cu")
		(net "CLK_100M_DB2000QL_NIC3_R_DP")
	)
	(segment
		(start 144.52346 -176.141634)
		(end 144.12214 -176.141634)
		(width 0.13462)
		(layer "B.Cu")
		(net "CLK_100M_DB2000QL_NIC3_R_DP")
	)
	(segment
		(start 149.36978 -176.278794)
		(end 148.96846 -176.278794)
		(width 0.13462)
		(layer "B.Cu")
		(net "CLK_100M_DB2000QL_NIC3_R_DP")
	)
	(segment
		(start 191.701674 -117.464332)
		(end 192.093596 -117.856254)
		(width 0.13462)
		(layer "B.Cu")
		(net "CLK_100M_DB2000QL_NIC3_R_DP")
	)
	(segment
		(start 157.917388 -171.122594)
		(end 156.947362 -170.152568)
		(width 0.13462)
		(layer "B.Cu")
		(net "CLK_100M_DB2000QL_NIC3_R_DP")
	)
	(segment
		(start 150.04542 -176.278794)
		(end 149.90826 -176.141634)
		(width 0.13462)
		(layer "B.Cu")
		(net "CLK_100M_DB2000QL_NIC3_R_DP")
	)
	(segment
		(start 150.5839 -176.141634)
		(end 150.44674 -176.278794)
		(width 0.13462)
		(layer "B.Cu")
		(net "CLK_100M_DB2000QL_NIC3_R_DP")
	)
	(segment
		(start 152.701752 -174.398178)
		(end 153.659078 -175.355504)
		(width 0.13462)
		(layer "B.Cu")
		(net "CLK_100M_DB2000QL_NIC3_R_DP")
	)
	(segment
		(start 156.46527 -172.746924)
		(end 156.293058 -172.746924)
		(width 0.13462)
		(layer "B.Cu")
		(net "CLK_100M_DB2000QL_NIC3_R_DP")
	)
	(segment
		(start 185.148474 -124.85878)
		(end 179.363878 -130.643376)
		(width 0.13462)
		(layer "B.Cu")
		(net "CLK_100M_DB2000QL_NIC3_R_DP")
	)
	(segment
		(start 154.668728 -174.371254)
		(end 153.698702 -173.401228)
		(width 0.13462)
		(layer "B.Cu")
		(net "CLK_100M_DB2000QL_NIC3_R_DP")
	)
	(segment
		(start 155.296108 -173.743874)
		(end 155.296108 -173.916086)
		(width 0.13462)
		(layer "B.Cu")
		(net "CLK_100M_DB2000QL_NIC3_R_DP")
	)
	(segment
		(start 156.947362 -170.152568)
		(end 156.558234 -170.152568)
		(width 0.13462)
		(layer "B.Cu")
		(net "CLK_100M_DB2000QL_NIC3_R_DP")
	)
	(segment
		(start 175.432212 -164.180774)
		(end 172.428154 -167.184832)
		(width 0.13462)
		(layer "B.Cu")
		(net "CLK_100M_DB2000QL_NIC3_R_DP")
	)
	(segment
		(start 147.35302 -176.141634)
		(end 147.21586 -176.278794)
		(width 0.13462)
		(layer "B.Cu")
		(net "CLK_100M_DB2000QL_NIC3_R_DP")
	)
	(segment
		(start 154.326082 -172.773848)
		(end 155.296108 -173.743874)
		(width 0.13462)
		(layer "B.Cu")
		(net "CLK_100M_DB2000QL_NIC3_R_DP")
	)
	(segment
		(start 185.885074 -124.85878)
		(end 185.148474 -124.85878)
		(width 0.13462)
		(layer "B.Cu")
		(net "CLK_100M_DB2000QL_NIC3_R_DP")
	)
	(segment
		(start 148.8313 -176.141634)
		(end 148.42998 -176.141634)
		(width 0.13462)
		(layer "B.Cu")
		(net "CLK_100M_DB2000QL_NIC3_R_DP")
	)
	(segment
		(start 192.093596 -117.856254)
		(end 192.093596 -119.256556)
		(width 0.13462)
		(layer "B.Cu")
		(net "CLK_100M_DB2000QL_NIC3_R_DP")
	)
	(segment
		(start 145.60042 -176.141634)
		(end 145.1991 -176.141634)
		(width 0.13462)
		(layer "B.Cu")
		(net "CLK_100M_DB2000QL_NIC3_R_DP")
	)
	(segment
		(start 147.75434 -176.141634)
		(end 147.35302 -176.141634)
		(width 0.13462)
		(layer "B.Cu")
		(net "CLK_100M_DB2000QL_NIC3_R_DP")
	)
	(segment
		(start 144.66062 -176.278794)
		(end 144.52346 -176.141634)
		(width 0.13462)
		(layer "B.Cu")
		(net "CLK_100M_DB2000QL_NIC3_R_DP")
	)
	(segment
		(start 158.0896 -171.122594)
		(end 157.917388 -171.122594)
		(width 0.13462)
		(layer "B.Cu")
		(net "CLK_100M_DB2000QL_NIC3_R_DP")
	)
	(segment
		(start 153.698702 -173.401228)
		(end 153.309574 -173.401228)
		(width 0.13462)
		(layer "B.Cu")
		(net "CLK_100M_DB2000QL_NIC3_R_DP")
	)
	(segment
		(start 157.574742 -169.525188)
		(end 158.544768 -170.495214)
		(width 0.13462)
		(layer "B.Cu")
		(net "CLK_100M_DB2000QL_NIC3_R_DP")
	)
	(segment
		(start 159.52597 -167.184832)
		(end 157.574742 -169.13606)
		(width 0.13462)
		(layer "B.Cu")
		(net "CLK_100M_DB2000QL_NIC3_R_DP")
	)
	(segment
		(start 154.84094 -174.371254)
		(end 154.668728 -174.371254)
		(width 0.13462)
		(layer "B.Cu")
		(net "CLK_100M_DB2000QL_NIC3_R_DP")
	)
	(segment
		(start 151.12238 -176.278794)
		(end 150.98522 -176.141634)
		(width 0.13462)
		(layer "B.Cu")
		(net "CLK_100M_DB2000QL_NIC3_R_DP")
	)
	(segment
		(start 158.544768 -170.667426)
		(end 158.0896 -171.122594)
		(width 0.13462)
		(layer "B.Cu")
		(net "CLK_100M_DB2000QL_NIC3_R_DP")
	)
	(segment
		(start 156.920438 -172.291756)
		(end 156.46527 -172.746924)
		(width 0.13462)
		(layer "B.Cu")
		(net "CLK_100M_DB2000QL_NIC3_R_DP")
	)
	(segment
		(start 147.21586 -176.278794)
		(end 146.81454 -176.278794)
		(width 0.13462)
		(layer "B.Cu")
		(net "CLK_100M_DB2000QL_NIC3_R_DP")
	)
	(segment
		(start 145.73758 -176.278794)
		(end 145.60042 -176.141634)
		(width 0.13462)
		(layer "B.Cu")
		(net "CLK_100M_DB2000QL_NIC3_R_DP")
	)
	(segment
		(start 146.1389 -176.278794)
		(end 145.73758 -176.278794)
		(width 0.13462)
		(layer "B.Cu")
		(net "CLK_100M_DB2000QL_NIC3_R_DP")
	)
	(segment
		(start 179.363878 -152.48382)
		(end 175.432212 -156.415486)
		(width 0.13462)
		(layer "B.Cu")
		(net "CLK_100M_DB2000QL_NIC3_R_DP")
	)
	(segment
		(start 150.44674 -176.278794)
		(end 150.04542 -176.278794)
		(width 0.13462)
		(layer "B.Cu")
		(net "CLK_100M_DB2000QL_NIC3_R_DP")
	)
	(segment
		(start 179.363878 -130.643376)
		(end 179.363878 -152.48382)
		(width 0.13462)
		(layer "B.Cu")
		(net "CLK_100M_DB2000QL_NIC3_R_DP")
	)
	(segment
		(start 147.8915 -176.278794)
		(end 147.75434 -176.141634)
		(width 0.13462)
		(layer "B.Cu")
		(net "CLK_100M_DB2000QL_NIC3_R_DP")
	)
	(segment
		(start 156.558234 -170.152568)
		(end 155.950412 -170.76039)
		(width 0.13462)
		(layer "B.Cu")
		(net "CLK_100M_DB2000QL_NIC3_R_DP")
	)
	(segment
		(start 257.018282 -88.826848)
		(end 257.426968 -88.418162)
		(width 0.13208)
		(layer "F.Cu")
		(net "PD_CK440_SBI_CLK")
	)
	(segment
		(start 251.97943 -91.696286)
		(end 251.97943 -91.298014)
		(width 0.13208)
		(layer "F.Cu")
		(net "PD_CK440_SBI_CLK")
	)
	(segment
		(start 256.350516 -88.826848)
		(end 257.018282 -88.826848)
		(width 0.13208)
		(layer "F.Cu")
		(net "PD_CK440_SBI_CLK")
	)
	(segment
		(start 254.366522 -90.810842)
		(end 256.350516 -88.826848)
		(width 0.13208)
		(layer "F.Cu")
		(net "PD_CK440_SBI_CLK")
	)
	(segment
		(start 257.426968 -88.418162)
		(end 257.426968 -88.181434)
		(width 0.13208)
		(layer "F.Cu")
		(net "PD_CK440_SBI_CLK")
	)
	(segment
		(start 252.466602 -90.810842)
		(end 254.366522 -90.810842)
		(width 0.13208)
		(layer "F.Cu")
		(net "PD_CK440_SBI_CLK")
	)
	(segment
		(start 251.97943 -91.298014)
		(end 252.466602 -90.810842)
		(width 0.13208)
		(layer "F.Cu")
		(net "PD_CK440_SBI_CLK")
	)
	(via
		(at 254.366522 -90.810842)
		(size 0.762)
		(drill 0.381)
		(layers "F.Cu" "B.Cu")
		(net "PD_CK440_SBI_CLK")
	)
	(segment
		(start 58.877454 -387.223)
		(end 59.086242 -387.014212)
		(width 0.13208)
		(layer "F.Cu")
		(net "GPU_BASE_ID0")
	)
	(segment
		(start 56.58866 -386.725668)
		(end 57.085992 -387.223)
		(width 0.13208)
		(layer "F.Cu")
		(net "GPU_BASE_ID0")
	)
	(segment
		(start 57.085992 -387.223)
		(end 58.877454 -387.223)
		(width 0.13208)
		(layer "F.Cu")
		(net "GPU_BASE_ID0")
	)
	(segment
		(start 59.086242 -386.734812)
		(end 59.864498 -386.734812)
		(width 0.13208)
		(layer "F.Cu")
		(net "GPU_BASE_ID0")
	)
	(segment
		(start 59.086242 -387.014212)
		(end 59.086242 -386.734812)
		(width 0.13208)
		(layer "F.Cu")
		(net "GPU_BASE_ID0")
	)
	(via
		(at 59.864498 -386.734812)
		(size 0.508)
		(drill 0.254)
		(layers "F.Cu" "B.Cu")
		(net "GPU_BASE_ID0")
	)
	(segment
		(start 86.119716 -414.224724)
		(end 88.01227 -412.33217)
		(width 0.15494)
		(layer "In9.Cu")
		(net "GPU_BASE_ID0")
	)
	(segment
		(start 88.01227 -412.33217)
		(end 88.01227 -404.772876)
		(width 0.15494)
		(layer "In9.Cu")
		(net "GPU_BASE_ID0")
	)
	(segment
		(start 62.321948 -386.5118)
		(end 64.4398 -386.5118)
		(width 0.15494)
		(layer "In9.Cu")
		(net "GPU_BASE_ID0")
	)
	(segment
		(start 62.098936 -386.734812)
		(end 62.321948 -386.5118)
		(width 0.15494)
		(layer "In9.Cu")
		(net "GPU_BASE_ID0")
	)
	(segment
		(start 88.495124 -404.290022)
		(end 89.509854 -404.290022)
		(width 0.15494)
		(layer "In9.Cu")
		(net "GPU_BASE_ID0")
	)
	(segment
		(start 88.01227 -404.772876)
		(end 88.495124 -404.290022)
		(width 0.15494)
		(layer "In9.Cu")
		(net "GPU_BASE_ID0")
	)
	(segment
		(start 64.4398 -386.5118)
		(end 68.821554 -390.893554)
		(width 0.15494)
		(layer "In9.Cu")
		(net "GPU_BASE_ID0")
	)
	(segment
		(start 68.821554 -390.893554)
		(end 68.821554 -412.153354)
		(width 0.15494)
		(layer "In9.Cu")
		(net "GPU_BASE_ID0")
	)
	(segment
		(start 59.864498 -386.734812)
		(end 62.098936 -386.734812)
		(width 0.15494)
		(layer "In9.Cu")
		(net "GPU_BASE_ID0")
	)
	(segment
		(start 68.821554 -412.153354)
		(end 70.892924 -414.224724)
		(width 0.15494)
		(layer "In9.Cu")
		(net "GPU_BASE_ID0")
	)
	(segment
		(start 70.892924 -414.224724)
		(end 86.119716 -414.224724)
		(width 0.15494)
		(layer "In9.Cu")
		(net "GPU_BASE_ID0")
	)
	(segment
		(start 141.696694 -178.562)
		(end 142.00378 -178.869086)
		(width 0.13462)
		(layer "F.Cu")
		(net "CLK_100M_DB2000QL_NIC4_R_DN")
	)
	(segment
		(start 276.951186 -138.176)
		(end 277.615904 -138.176)
		(width 0.13462)
		(layer "F.Cu")
		(net "CLK_100M_DB2000QL_NIC4_R_DN")
	)
	(segment
		(start 140.857478 -178.562)
		(end 141.696694 -178.562)
		(width 0.13462)
		(layer "F.Cu")
		(net "CLK_100M_DB2000QL_NIC4_R_DN")
	)
	(segment
		(start 277.615904 -138.176)
		(end 277.80488 -138.364976)
		(width 0.13462)
		(layer "F.Cu")
		(net "CLK_100M_DB2000QL_NIC4_R_DN")
	)
	(segment
		(start 140.474192 -178.945286)
		(end 140.857478 -178.562)
		(width 0.13462)
		(layer "F.Cu")
		(net "CLK_100M_DB2000QL_NIC4_R_DN")
	)
	(segment
		(start 277.80488 -138.364976)
		(end 278.242268 -138.364976)
		(width 0.13462)
		(layer "F.Cu")
		(net "CLK_100M_DB2000QL_NIC4_R_DN")
	)
	(segment
		(start 276.630384 -138.496802)
		(end 276.951186 -138.176)
		(width 0.13462)
		(layer "F.Cu")
		(net "CLK_100M_DB2000QL_NIC4_R_DN")
	)
	(via
		(at 276.630384 -138.496802)
		(size 0.508)
		(drill 0.254)
		(layers "F.Cu" "B.Cu")
		(net "CLK_100M_DB2000QL_NIC4_R_DN")
	)
	(via
		(at 142.00378 -178.869086)
		(size 0.508)
		(drill 0.254)
		(layers "F.Cu" "B.Cu")
		(net "CLK_100M_DB2000QL_NIC4_R_DN")
	)
	(segment
		(start 238.771938 -161.911792)
		(end 241.161062 -164.300916)
		(width 0.1651)
		(layer "In15.Cu")
		(net "CLK_100M_DB2000QL_NIC4_R_DN")
	)
	(segment
		(start 142.29842 -178.574446)
		(end 166.129208 -178.574446)
		(width 0.1651)
		(layer "In15.Cu")
		(net "CLK_100M_DB2000QL_NIC4_R_DN")
	)
	(segment
		(start 253.394464 -164.300916)
		(end 254.608584 -163.086796)
		(width 0.1651)
		(layer "In15.Cu")
		(net "CLK_100M_DB2000QL_NIC4_R_DN")
	)
	(segment
		(start 274.004786 -143.722598)
		(end 274.004786 -139.779756)
		(width 0.1651)
		(layer "In15.Cu")
		(net "CLK_100M_DB2000QL_NIC4_R_DN")
	)
	(segment
		(start 166.129208 -178.574446)
		(end 174.8409 -169.862754)
		(width 0.1651)
		(layer "In15.Cu")
		(net "CLK_100M_DB2000QL_NIC4_R_DN")
	)
	(segment
		(start 179.812442 -168.98874)
		(end 207.18272 -168.98874)
		(width 0.1651)
		(layer "In15.Cu")
		(net "CLK_100M_DB2000QL_NIC4_R_DN")
	)
	(segment
		(start 254.608584 -161.53765)
		(end 255.33858 -160.807654)
		(width 0.1651)
		(layer "In15.Cu")
		(net "CLK_100M_DB2000QL_NIC4_R_DN")
	)
	(segment
		(start 255.33858 -160.807654)
		(end 256.304542 -160.407604)
		(width 0.1651)
		(layer "In15.Cu")
		(net "CLK_100M_DB2000QL_NIC4_R_DN")
	)
	(segment
		(start 214.259668 -161.911792)
		(end 238.771938 -161.911792)
		(width 0.1651)
		(layer "In15.Cu")
		(net "CLK_100M_DB2000QL_NIC4_R_DN")
	)
	(segment
		(start 142.00378 -178.869086)
		(end 142.29842 -178.574446)
		(width 0.1651)
		(layer "In15.Cu")
		(net "CLK_100M_DB2000QL_NIC4_R_DN")
	)
	(segment
		(start 276.309582 -138.176)
		(end 276.630384 -138.496802)
		(width 0.1651)
		(layer "In15.Cu")
		(net "CLK_100M_DB2000QL_NIC4_R_DN")
	)
	(segment
		(start 275.608542 -138.176)
		(end 276.309582 -138.176)
		(width 0.1651)
		(layer "In15.Cu")
		(net "CLK_100M_DB2000QL_NIC4_R_DN")
	)
	(segment
		(start 274.004786 -139.779756)
		(end 275.608542 -138.176)
		(width 0.1651)
		(layer "In15.Cu")
		(net "CLK_100M_DB2000QL_NIC4_R_DN")
	)
	(segment
		(start 178.938428 -169.862754)
		(end 179.812442 -168.98874)
		(width 0.1651)
		(layer "In15.Cu")
		(net "CLK_100M_DB2000QL_NIC4_R_DN")
	)
	(segment
		(start 256.304542 -160.407604)
		(end 257.31978 -160.407604)
		(width 0.1651)
		(layer "In15.Cu")
		(net "CLK_100M_DB2000QL_NIC4_R_DN")
	)
	(segment
		(start 174.8409 -169.862754)
		(end 178.938428 -169.862754)
		(width 0.1651)
		(layer "In15.Cu")
		(net "CLK_100M_DB2000QL_NIC4_R_DN")
	)
	(segment
		(start 207.18272 -168.98874)
		(end 214.259668 -161.911792)
		(width 0.1651)
		(layer "In15.Cu")
		(net "CLK_100M_DB2000QL_NIC4_R_DN")
	)
	(segment
		(start 241.161062 -164.300916)
		(end 253.394464 -164.300916)
		(width 0.1651)
		(layer "In15.Cu")
		(net "CLK_100M_DB2000QL_NIC4_R_DN")
	)
	(segment
		(start 254.608584 -163.086796)
		(end 254.608584 -161.53765)
		(width 0.1651)
		(layer "In15.Cu")
		(net "CLK_100M_DB2000QL_NIC4_R_DN")
	)
	(segment
		(start 257.31978 -160.407604)
		(end 274.004786 -143.722598)
		(width 0.1651)
		(layer "In15.Cu")
		(net "CLK_100M_DB2000QL_NIC4_R_DN")
	)
	(segment
		(start 60.389262 -390.47166)
		(end 60.389262 -390.90219)
		(width 0.13208)
		(layer "F.Cu")
		(net "GPU_HGX_DETECT_N")
	)
	(segment
		(start 60.389262 -390.90219)
		(end 60.947046 -391.459974)
		(width 0.13208)
		(layer "F.Cu")
		(net "GPU_HGX_DETECT_N")
	)
	(segment
		(start 60.437268 -392.006836)
		(end 60.947046 -391.497058)
		(width 0.13208)
		(layer "F.Cu")
		(net "GPU_HGX_DETECT_N")
	)
	(segment
		(start 60.437268 -392.76274)
		(end 60.437268 -392.006836)
		(width 0.13208)
		(layer "F.Cu")
		(net "GPU_HGX_DETECT_N")
	)
	(segment
		(start 60.947046 -391.459974)
		(end 60.947046 -391.497058)
		(width 0.13208)
		(layer "F.Cu")
		(net "GPU_HGX_DETECT_N")
	)
	(via
		(at 60.947046 -391.497058)
		(size 0.508)
		(drill 0.254)
		(layers "F.Cu" "B.Cu")
		(net "GPU_HGX_DETECT_N")
	)
	(segment
		(start 46.108112 -415.299398)
		(end 50.603404 -415.299398)
		(width 0.15494)
		(layer "In9.Cu")
		(net "GPU_HGX_DETECT_N")
	)
	(segment
		(start 58.985658 -393.458446)
		(end 60.947046 -391.497058)
		(width 0.15494)
		(layer "In9.Cu")
		(net "GPU_HGX_DETECT_N")
	)
	(segment
		(start 50.603404 -415.299398)
		(end 52.208938 -413.693864)
		(width 0.15494)
		(layer "In9.Cu")
		(net "GPU_HGX_DETECT_N")
	)
	(segment
		(start 52.66944 -393.458446)
		(end 58.985658 -393.458446)
		(width 0.15494)
		(layer "In9.Cu")
		(net "GPU_HGX_DETECT_N")
	)
	(segment
		(start 52.208938 -413.693864)
		(end 52.208938 -393.918948)
		(width 0.15494)
		(layer "In9.Cu")
		(net "GPU_HGX_DETECT_N")
	)
	(segment
		(start 52.208938 -393.918948)
		(end 52.66944 -393.458446)
		(width 0.15494)
		(layer "In9.Cu")
		(net "GPU_HGX_DETECT_N")
	)
	(segment
		(start 45.017436 -414.208722)
		(end 46.108112 -415.299398)
		(width 0.15494)
		(layer "In9.Cu")
		(net "GPU_HGX_DETECT_N")
	)
	(segment
		(start 32.31007 -412.090108)
		(end 34.428684 -414.208722)
		(width 0.15494)
		(layer "In9.Cu")
		(net "GPU_HGX_DETECT_N")
	)
	(segment
		(start 34.428684 -414.208722)
		(end 45.017436 -414.208722)
		(width 0.15494)
		(layer "In9.Cu")
		(net "GPU_HGX_DETECT_N")
	)
	(segment
		(start 62.808612 -157.680152)
		(end 62.808612 -157.045152)
		(width 0.4064)
		(layer "F.Cu")
		(net "P3V3_NIC1")
	)
	(segment
		(start 64.07785 -113.251742)
		(end 64.688212 -113.251742)
		(width 0.4572)
		(layer "F.Cu")
		(net "P3V3_NIC1")
	)
	(segment
		(start 101.530404 -120.79224)
		(end 100.91801 -120.79224)
		(width 0.4572)
		(layer "F.Cu")
		(net "P3V3_NIC1")
	)
	(segment
		(start 83.066128 -77.889608)
		(end 83.166458 -77.989938)
		(width 0.4572)
		(layer "F.Cu")
		(net "P3V3_NIC1")
	)
	(segment
		(start 83.166458 -77.989938)
		(end 83.166458 -79.463646)
		(width 0.4572)
		(layer "F.Cu")
		(net "P3V3_NIC1")
	)
	(segment
		(start 99.375722 -119.477028)
		(end 99.990148 -119.477028)
		(width 0.4572)
		(layer "F.Cu")
		(net "P3V3_NIC1")
	)
	(segment
		(start 83.066128 -77.206348)
		(end 83.066128 -77.889608)
		(width 0.4572)
		(layer "F.Cu")
		(net "P3V3_NIC1")
	)
	(segment
		(start 58.595006 -100.766372)
		(end 57.979818 -100.766372)
		(width 0.4064)
		(layer "F.Cu")
		(net "P3V3_NIC1")
	)
	(segment
		(start 79.314802 -79.18196)
		(end 79.97317 -79.18196)
		(width 0.4572)
		(layer "F.Cu")
		(net "P3V3_NIC1")
	)
	(via
		(at 64.145668 -128.799336)
		(size 0.6604)
		(drill 0.3302)
		(layers "F.Cu" "B.Cu")
		(net "P3V3_NIC1")
	)
	(via
		(at 92.376244 -121.581672)
		(size 0.508)
		(drill 0.254)
		(layers "F.Cu" "B.Cu")
		(net "P3V3_NIC1")
	)
	(via
		(at 100.91801 -120.79224)
		(size 0.508)
		(drill 0.254)
		(layers "F.Cu" "B.Cu")
		(net "P3V3_NIC1")
	)
	(via
		(at 69.815964 -113.437924)
		(size 0.508)
		(drill 0.254)
		(layers "F.Cu" "B.Cu")
		(net "P3V3_NIC1")
	)
	(via
		(at 90.866468 -121.171462)
		(size 0.508)
		(drill 0.254)
		(layers "F.Cu" "B.Cu")
		(net "P3V3_NIC1")
	)
	(via
		(at 64.688212 -113.251742)
		(size 0.508)
		(drill 0.254)
		(layers "F.Cu" "B.Cu")
		(net "P3V3_NIC1")
	)
	(via
		(at 89.83218 -120.922034)
		(size 0.508)
		(drill 0.254)
		(layers "F.Cu" "B.Cu")
		(net "P3V3_NIC1")
	)
	(via
		(at 89.83218 -121.557034)
		(size 0.508)
		(drill 0.254)
		(layers "F.Cu" "B.Cu")
		(net "P3V3_NIC1")
	)
	(via
		(at 89.83218 -120.287034)
		(size 0.508)
		(drill 0.254)
		(layers "F.Cu" "B.Cu")
		(net "P3V3_NIC1")
	)
	(via
		(at 75.134978 -114.725958)
		(size 0.508)
		(drill 0.254)
		(layers "F.Cu" "B.Cu")
		(net "P3V3_NIC1")
	)
	(via
		(at 91.885516 -117.36324)
		(size 0.508)
		(drill 0.254)
		(layers "F.Cu" "B.Cu")
		(net "P3V3_NIC1")
	)
	(via
		(at 69.837046 -112.421924)
		(size 0.508)
		(drill 0.254)
		(layers "F.Cu" "B.Cu")
		(net "P3V3_NIC1")
	)
	(via
		(at 83.066128 -77.206348)
		(size 0.508)
		(drill 0.254)
		(layers "F.Cu" "B.Cu")
		(net "P3V3_NIC1")
	)
	(via
		(at 75.134978 -115.360958)
		(size 0.508)
		(drill 0.254)
		(layers "F.Cu" "B.Cu")
		(net "P3V3_NIC1")
	)
	(via
		(at 91.123516 -117.36324)
		(size 0.508)
		(drill 0.254)
		(layers "F.Cu" "B.Cu")
		(net "P3V3_NIC1")
	)
	(via
		(at 61.568584 -126.976124)
		(size 0.6604)
		(drill 0.3302)
		(layers "F.Cu" "B.Cu")
		(net "P3V3_NIC1")
	)
	(via
		(at 93.07068 -121.281444)
		(size 0.508)
		(drill 0.254)
		(layers "F.Cu" "B.Cu")
		(net "P3V3_NIC1")
	)
	(via
		(at 93.07068 -121.916444)
		(size 0.508)
		(drill 0.254)
		(layers "F.Cu" "B.Cu")
		(net "P3V3_NIC1")
	)
	(via
		(at 91.501468 -121.171462)
		(size 0.508)
		(drill 0.254)
		(layers "F.Cu" "B.Cu")
		(net "P3V3_NIC1")
	)
	(via
		(at 89.83218 -122.192034)
		(size 0.508)
		(drill 0.254)
		(layers "F.Cu" "B.Cu")
		(net "P3V3_NIC1")
	)
	(via
		(at 62.808612 -157.045152)
		(size 0.508)
		(drill 0.254)
		(layers "F.Cu" "B.Cu")
		(net "P3V3_NIC1")
	)
	(via
		(at 57.979818 -100.766372)
		(size 0.508)
		(drill 0.254)
		(layers "F.Cu" "B.Cu")
		(net "P3V3_NIC1")
	)
	(via
		(at 99.990148 -119.477028)
		(size 0.508)
		(drill 0.254)
		(layers "F.Cu" "B.Cu")
		(net "P3V3_NIC1")
	)
	(via
		(at 74.499978 -114.725958)
		(size 0.508)
		(drill 0.254)
		(layers "F.Cu" "B.Cu")
		(net "P3V3_NIC1")
	)
	(via
		(at 79.97317 -79.18196)
		(size 0.508)
		(drill 0.254)
		(layers "F.Cu" "B.Cu")
		(net "P3V3_NIC1")
	)
	(via
		(at 92.376244 -120.946672)
		(size 0.508)
		(drill 0.254)
		(layers "F.Cu" "B.Cu")
		(net "P3V3_NIC1")
	)
	(via
		(at 74.499978 -115.360958)
		(size 0.508)
		(drill 0.254)
		(layers "F.Cu" "B.Cu")
		(net "P3V3_NIC1")
	)
	(segment
		(start 69.072252 -113.437924)
		(end 69.815964 -113.437924)
		(width 0.4572)
		(layer "B.Cu")
		(net "P3V3_NIC1")
	)
	(segment
		(start 69.072252 -112.421924)
		(end 69.837046 -112.421924)
		(width 0.4572)
		(layer "B.Cu")
		(net "P3V3_NIC1")
	)
	(segment
		(start 63.66764 -137.71626)
		(end 62.521592 -136.570212)
		(width 0.508)
		(layer "In5.Cu")
		(net "P3V3_NIC1")
	)
	(segment
		(start 62.521592 -115.418362)
		(end 64.688212 -113.251742)
		(width 0.508)
		(layer "In5.Cu")
		(net "P3V3_NIC1")
	)
	(segment
		(start 62.521592 -136.570212)
		(end 62.521592 -115.418362)
		(width 0.508)
		(layer "In5.Cu")
		(net "P3V3_NIC1")
	)
	(segment
		(start 62.808612 -157.045152)
		(end 62.808612 -155.980384)
		(width 0.508)
		(layer "In5.Cu")
		(net "P3V3_NIC1")
	)
	(segment
		(start 62.808612 -155.980384)
		(end 63.66764 -155.121356)
		(width 0.508)
		(layer "In5.Cu")
		(net "P3V3_NIC1")
	)
	(segment
		(start 63.66764 -155.121356)
		(end 63.66764 -137.71626)
		(width 0.508)
		(layer "In5.Cu")
		(net "P3V3_NIC1")
	)
	(segment
		(start 140.474192 -176.913286)
		(end 140.832078 -176.5554)
		(width 0.13462)
		(layer "F.Cu")
		(net "CLK_100M_DB2000QL_NIC3_R_DN")
	)
	(segment
		(start 191.032638 -116.895372)
		(end 190.730124 -117.197886)
		(width 0.13462)
		(layer "F.Cu")
		(net "CLK_100M_DB2000QL_NIC3_R_DN")
	)
	(segment
		(start 190.019686 -117.197886)
		(end 189.856872 -117.035072)
		(width 0.13462)
		(layer "F.Cu")
		(net "CLK_100M_DB2000QL_NIC3_R_DN")
	)
	(segment
		(start 189.856872 -117.035072)
		(end 189.357508 -117.035072)
		(width 0.13462)
		(layer "F.Cu")
		(net "CLK_100M_DB2000QL_NIC3_R_DN")
	)
	(segment
		(start 142.357094 -176.5554)
		(end 142.63878 -176.837086)
		(width 0.13462)
		(layer "F.Cu")
		(net "CLK_100M_DB2000QL_NIC3_R_DN")
	)
	(segment
		(start 190.730124 -117.197886)
		(end 190.019686 -117.197886)
		(width 0.13462)
		(layer "F.Cu")
		(net "CLK_100M_DB2000QL_NIC3_R_DN")
	)
	(segment
		(start 140.832078 -176.5554)
		(end 142.357094 -176.5554)
		(width 0.13462)
		(layer "F.Cu")
		(net "CLK_100M_DB2000QL_NIC3_R_DN")
	)
	(via
		(at 191.032638 -116.895372)
		(size 0.508)
		(drill 0.254)
		(layers "F.Cu" "B.Cu")
		(net "CLK_100M_DB2000QL_NIC3_R_DN")
	)
	(via
		(at 142.63878 -176.837086)
		(size 0.508)
		(drill 0.254)
		(layers "F.Cu" "B.Cu")
		(net "CLK_100M_DB2000QL_NIC3_R_DN")
	)
	(segment
		(start 152.976072 -174.122842)
		(end 152.976072 -174.284386)
		(width 0.13462)
		(layer "B.Cu")
		(net "CLK_100M_DB2000QL_NIC3_R_DN")
	)
	(segment
		(start 190.024766 -121.1072)
		(end 185.998866 -125.1331)
		(width 0.13462)
		(layer "B.Cu")
		(net "CLK_100M_DB2000QL_NIC3_R_DN")
	)
	(segment
		(start 153.933398 -175.241712)
		(end 153.933398 -175.682402)
		(width 0.13462)
		(layer "B.Cu")
		(net "CLK_100M_DB2000QL_NIC3_R_DN")
	)
	(segment
		(start 190.631064 -121.1072)
		(end 190.024766 -121.1072)
		(width 0.13462)
		(layer "B.Cu")
		(net "CLK_100M_DB2000QL_NIC3_R_DN")
	)
	(segment
		(start 175.706532 -156.529278)
		(end 175.706532 -164.294566)
		(width 0.13462)
		(layer "B.Cu")
		(net "CLK_100M_DB2000QL_NIC3_R_DN")
	)
	(segment
		(start 153.423366 -173.675548)
		(end 152.976072 -174.122842)
		(width 0.13462)
		(layer "B.Cu")
		(net "CLK_100M_DB2000QL_NIC3_R_DN")
	)
	(segment
		(start 157.849062 -169.249852)
		(end 157.849062 -169.411396)
		(width 0.13462)
		(layer "B.Cu")
		(net "CLK_100M_DB2000QL_NIC3_R_DN")
	)
	(segment
		(start 153.062686 -176.553114)
		(end 142.922752 -176.553114)
		(width 0.13462)
		(layer "B.Cu")
		(net "CLK_100M_DB2000QL_NIC3_R_DN")
	)
	(segment
		(start 157.803596 -171.396914)
		(end 156.83357 -170.426888)
		(width 0.13462)
		(layer "B.Cu")
		(net "CLK_100M_DB2000QL_NIC3_R_DN")
	)
	(segment
		(start 155.20924 -172.051218)
		(end 155.047696 -172.051218)
		(width 0.13462)
		(layer "B.Cu")
		(net "CLK_100M_DB2000QL_NIC3_R_DN")
	)
	(segment
		(start 155.047696 -172.051218)
		(end 154.600402 -172.498512)
		(width 0.13462)
		(layer "B.Cu")
		(net "CLK_100M_DB2000QL_NIC3_R_DN")
	)
	(segment
		(start 156.579062 -173.021244)
		(end 156.179266 -173.021244)
		(width 0.13462)
		(layer "B.Cu")
		(net "CLK_100M_DB2000QL_NIC3_R_DN")
	)
	(segment
		(start 153.933398 -175.682402)
		(end 153.062686 -176.553114)
		(width 0.13462)
		(layer "B.Cu")
		(net "CLK_100M_DB2000QL_NIC3_R_DN")
	)
	(segment
		(start 179.625498 -152.49652)
		(end 179.625498 -152.592278)
		(width 0.13462)
		(layer "B.Cu")
		(net "CLK_100M_DB2000QL_NIC3_R_DN")
	)
	(segment
		(start 157.194758 -172.005752)
		(end 157.194758 -172.405548)
		(width 0.13462)
		(layer "B.Cu")
		(net "CLK_100M_DB2000QL_NIC3_R_DN")
	)
	(segment
		(start 179.638198 -130.757168)
		(end 179.638198 -152.48382)
		(width 0.13462)
		(layer "B.Cu")
		(net "CLK_100M_DB2000QL_NIC3_R_DN")
	)
	(segment
		(start 158.819088 -170.381422)
		(end 158.819088 -170.781218)
		(width 0.13462)
		(layer "B.Cu")
		(net "CLK_100M_DB2000QL_NIC3_R_DN")
	)
	(segment
		(start 158.203392 -171.396914)
		(end 157.803596 -171.396914)
		(width 0.13462)
		(layer "B.Cu")
		(net "CLK_100M_DB2000QL_NIC3_R_DN")
	)
	(segment
		(start 191.032638 -116.895372)
		(end 191.327278 -117.190012)
		(width 0.13462)
		(layer "B.Cu")
		(net "CLK_100M_DB2000QL_NIC3_R_DN")
	)
	(segment
		(start 154.600402 -172.498512)
		(end 154.600402 -172.660056)
		(width 0.13462)
		(layer "B.Cu")
		(net "CLK_100M_DB2000QL_NIC3_R_DN")
	)
	(segment
		(start 191.327278 -117.190012)
		(end 191.815466 -117.190012)
		(width 0.13462)
		(layer "B.Cu")
		(net "CLK_100M_DB2000QL_NIC3_R_DN")
	)
	(segment
		(start 179.549044 -152.668732)
		(end 179.549044 -152.686766)
		(width 0.13462)
		(layer "B.Cu")
		(net "CLK_100M_DB2000QL_NIC3_R_DN")
	)
	(segment
		(start 175.706532 -164.294566)
		(end 172.541946 -167.459152)
		(width 0.13462)
		(layer "B.Cu")
		(net "CLK_100M_DB2000QL_NIC3_R_DN")
	)
	(segment
		(start 156.224732 -171.035726)
		(end 157.194758 -172.005752)
		(width 0.13462)
		(layer "B.Cu")
		(net "CLK_100M_DB2000QL_NIC3_R_DN")
	)
	(segment
		(start 156.224732 -170.874182)
		(end 156.224732 -171.035726)
		(width 0.13462)
		(layer "B.Cu")
		(net "CLK_100M_DB2000QL_NIC3_R_DN")
	)
	(segment
		(start 192.367916 -119.370348)
		(end 190.631064 -121.1072)
		(width 0.13462)
		(layer "B.Cu")
		(net "CLK_100M_DB2000QL_NIC3_R_DN")
	)
	(segment
		(start 156.179266 -173.021244)
		(end 155.20924 -172.051218)
		(width 0.13462)
		(layer "B.Cu")
		(net "CLK_100M_DB2000QL_NIC3_R_DN")
	)
	(segment
		(start 156.672026 -170.426888)
		(end 156.224732 -170.874182)
		(width 0.13462)
		(layer "B.Cu")
		(net "CLK_100M_DB2000QL_NIC3_R_DN")
	)
	(segment
		(start 154.554936 -174.645574)
		(end 153.58491 -173.675548)
		(width 0.13462)
		(layer "B.Cu")
		(net "CLK_100M_DB2000QL_NIC3_R_DN")
	)
	(segment
		(start 179.638198 -152.48382)
		(end 179.625498 -152.49652)
		(width 0.13462)
		(layer "B.Cu")
		(net "CLK_100M_DB2000QL_NIC3_R_DN")
	)
	(segment
		(start 142.922752 -176.553114)
		(end 142.63878 -176.837086)
		(width 0.13462)
		(layer "B.Cu")
		(net "CLK_100M_DB2000QL_NIC3_R_DN")
	)
	(segment
		(start 159.639762 -167.459152)
		(end 157.849062 -169.249852)
		(width 0.13462)
		(layer "B.Cu")
		(net "CLK_100M_DB2000QL_NIC3_R_DN")
	)
	(segment
		(start 179.549044 -152.686766)
		(end 175.706532 -156.529278)
		(width 0.13462)
		(layer "B.Cu")
		(net "CLK_100M_DB2000QL_NIC3_R_DN")
	)
	(segment
		(start 155.570428 -174.029878)
		(end 154.954732 -174.645574)
		(width 0.13462)
		(layer "B.Cu")
		(net "CLK_100M_DB2000QL_NIC3_R_DN")
	)
	(segment
		(start 156.83357 -170.426888)
		(end 156.672026 -170.426888)
		(width 0.13462)
		(layer "B.Cu")
		(net "CLK_100M_DB2000QL_NIC3_R_DN")
	)
	(segment
		(start 157.194758 -172.405548)
		(end 156.579062 -173.021244)
		(width 0.13462)
		(layer "B.Cu")
		(net "CLK_100M_DB2000QL_NIC3_R_DN")
	)
	(segment
		(start 153.58491 -173.675548)
		(end 153.423366 -173.675548)
		(width 0.13462)
		(layer "B.Cu")
		(net "CLK_100M_DB2000QL_NIC3_R_DN")
	)
	(segment
		(start 157.849062 -169.411396)
		(end 158.819088 -170.381422)
		(width 0.13462)
		(layer "B.Cu")
		(net "CLK_100M_DB2000QL_NIC3_R_DN")
	)
	(segment
		(start 154.600402 -172.660056)
		(end 155.570428 -173.630082)
		(width 0.13462)
		(layer "B.Cu")
		(net "CLK_100M_DB2000QL_NIC3_R_DN")
	)
	(segment
		(start 172.541946 -167.459152)
		(end 159.639762 -167.459152)
		(width 0.13462)
		(layer "B.Cu")
		(net "CLK_100M_DB2000QL_NIC3_R_DN")
	)
	(segment
		(start 155.570428 -173.630082)
		(end 155.570428 -174.029878)
		(width 0.13462)
		(layer "B.Cu")
		(net "CLK_100M_DB2000QL_NIC3_R_DN")
	)
	(segment
		(start 154.954732 -174.645574)
		(end 154.554936 -174.645574)
		(width 0.13462)
		(layer "B.Cu")
		(net "CLK_100M_DB2000QL_NIC3_R_DN")
	)
	(segment
		(start 152.976072 -174.284386)
		(end 153.933398 -175.241712)
		(width 0.13462)
		(layer "B.Cu")
		(net "CLK_100M_DB2000QL_NIC3_R_DN")
	)
	(segment
		(start 185.262266 -125.1331)
		(end 179.638198 -130.757168)
		(width 0.13462)
		(layer "B.Cu")
		(net "CLK_100M_DB2000QL_NIC3_R_DN")
	)
	(segment
		(start 192.367916 -117.742462)
		(end 192.367916 -119.370348)
		(width 0.13462)
		(layer "B.Cu")
		(net "CLK_100M_DB2000QL_NIC3_R_DN")
	)
	(segment
		(start 191.815466 -117.190012)
		(end 192.367916 -117.742462)
		(width 0.13462)
		(layer "B.Cu")
		(net "CLK_100M_DB2000QL_NIC3_R_DN")
	)
	(segment
		(start 185.998866 -125.1331)
		(end 185.262266 -125.1331)
		(width 0.13462)
		(layer "B.Cu")
		(net "CLK_100M_DB2000QL_NIC3_R_DN")
	)
	(segment
		(start 179.625498 -152.592278)
		(end 179.549044 -152.668732)
		(width 0.13462)
		(layer "B.Cu")
		(net "CLK_100M_DB2000QL_NIC3_R_DN")
	)
	(segment
		(start 158.819088 -170.781218)
		(end 158.203392 -171.396914)
		(width 0.13462)
		(layer "B.Cu")
		(net "CLK_100M_DB2000QL_NIC3_R_DN")
	)
	(segment
		(start 260.176772 -89.225374)
		(end 260.176772 -88.645746)
		(width 0.13208)
		(layer "F.Cu")
		(net "FM_CK440_MXCK_25M_100M")
	)
	(segment
		(start 264.896854 -89.623392)
		(end 265.735816 -90.462354)
		(width 0.13208)
		(layer "F.Cu")
		(net "FM_CK440_MXCK_25M_100M")
	)
	(segment
		(start 268.002766 -91.478354)
		(end 268.002766 -90.462354)
		(width 0.13208)
		(layer "F.Cu")
		(net "FM_CK440_MXCK_25M_100M")
	)
	(segment
		(start 265.735816 -90.462354)
		(end 268.002766 -90.462354)
		(width 0.13208)
		(layer "F.Cu")
		(net "FM_CK440_MXCK_25M_100M")
	)
	(segment
		(start 260.57479 -89.623392)
		(end 264.896854 -89.623392)
		(width 0.13208)
		(layer "F.Cu")
		(net "FM_CK440_MXCK_25M_100M")
	)
	(segment
		(start 260.176772 -88.645746)
		(end 260.176772 -87.431372)
		(width 0.0889)
		(layer "F.Cu")
		(net "FM_CK440_MXCK_25M_100M")
	)
	(segment
		(start 260.57479 -89.623392)
		(end 260.176772 -89.225374)
		(width 0.13208)
		(layer "F.Cu")
		(net "FM_CK440_MXCK_25M_100M")
	)
	(via
		(at 260.57479 -89.623392)
		(size 0.762)
		(drill 0.381)
		(layers "F.Cu" "B.Cu")
		(net "FM_CK440_MXCK_25M_100M")
	)
	(segment
		(start 220.503242 -222.325692)
		(end 220.543882 -222.285052)
		(width 0.13208)
		(layer "F.Cu")
		(net "I3C_MB_SCL")
	)
	(segment
		(start 218.788488 -223.455484)
		(end 218.788488 -222.83801)
		(width 0.13208)
		(layer "F.Cu")
		(net "I3C_MB_SCL")
	)
	(segment
		(start 223.303338 -221.907862)
		(end 223.409256 -221.907862)
		(width 0.13208)
		(layer "F.Cu")
		(net "I3C_MB_SCL")
	)
	(segment
		(start 220.543882 -222.285052)
		(end 221.097348 -222.285052)
		(width 0.13208)
		(layer "F.Cu")
		(net "I3C_MB_SCL")
	)
	(segment
		(start 223.15424 -222.05696)
		(end 223.303338 -221.907862)
		(width 0.13208)
		(layer "F.Cu")
		(net "I3C_MB_SCL")
	)
	(segment
		(start 221.097348 -222.285052)
		(end 221.32544 -222.05696)
		(width 0.13208)
		(layer "F.Cu")
		(net "I3C_MB_SCL")
	)
	(segment
		(start 218.4654 -224.0026)
		(end 218.629992 -223.838008)
		(width 0.13208)
		(layer "F.Cu")
		(net "I3C_MB_SCL")
	)
	(segment
		(start 223.412812 -221.904306)
		(end 223.867726 -221.904306)
		(width 0.13208)
		(layer "F.Cu")
		(net "I3C_MB_SCL")
	)
	(segment
		(start 217.635836 -224.398586)
		(end 217.900504 -224.0026)
		(width 0.13208)
		(layer "F.Cu")
		(net "I3C_MB_SCL")
	)
	(segment
		(start 218.629992 -223.838008)
		(end 218.788488 -223.455484)
		(width 0.13208)
		(layer "F.Cu")
		(net "I3C_MB_SCL")
	)
	(segment
		(start 223.867726 -221.904306)
		(end 224.267776 -221.504256)
		(width 0.13208)
		(layer "F.Cu")
		(net "I3C_MB_SCL")
	)
	(segment
		(start 221.32544 -222.05696)
		(end 223.15424 -222.05696)
		(width 0.13208)
		(layer "F.Cu")
		(net "I3C_MB_SCL")
	)
	(segment
		(start 219.162884 -222.346012)
		(end 219.169742 -222.346012)
		(width 0.13208)
		(layer "F.Cu")
		(net "I3C_MB_SCL")
	)
	(segment
		(start 217.900504 -224.0026)
		(end 218.4654 -224.0026)
		(width 0.13208)
		(layer "F.Cu")
		(net "I3C_MB_SCL")
	)
	(segment
		(start 223.409256 -221.907862)
		(end 223.412812 -221.904306)
		(width 0.13208)
		(layer "F.Cu")
		(net "I3C_MB_SCL")
	)
	(segment
		(start 219.169742 -222.346012)
		(end 219.190062 -222.325692)
		(width 0.13208)
		(layer "F.Cu")
		(net "I3C_MB_SCL")
	)
	(segment
		(start 218.788488 -222.83801)
		(end 218.871546 -222.63735)
		(width 0.13208)
		(layer "F.Cu")
		(net "I3C_MB_SCL")
	)
	(segment
		(start 218.871546 -222.63735)
		(end 219.162884 -222.346012)
		(width 0.13208)
		(layer "F.Cu")
		(net "I3C_MB_SCL")
	)
	(segment
		(start 219.190062 -222.325692)
		(end 220.503242 -222.325692)
		(width 0.13208)
		(layer "F.Cu")
		(net "I3C_MB_SCL")
	)
	(via
		(at 220.503242 -222.325692)
		(size 0.762)
		(drill 0.381)
		(layers "F.Cu" "B.Cu")
		(net "I3C_MB_SCL")
	)
	(segment
		(start 84.861654 -393.923774)
		(end 84.861654 -393.924028)
		(width 0.1651)
		(layer "In15.Cu")
		(net "CLK_100M_GPU_FPGA_REF_DP")
	)
	(segment
		(start 90.95359 -394.00734)
		(end 91.545918 -394.203936)
		(width 0.1651)
		(layer "In15.Cu")
		(net "CLK_100M_GPU_FPGA_REF_DP")
	)
	(segment
		(start 57.376314 -393.260834)
		(end 57.885584 -393.273026)
		(width 0.1651)
		(layer "In15.Cu")
		(net "CLK_100M_GPU_FPGA_REF_DP")
	)
	(segment
		(start 51.806602 -393.125706)
		(end 52.832762 -393.150344)
		(width 0.1651)
		(layer "In15.Cu")
		(net "CLK_100M_GPU_FPGA_REF_DP")
	)
	(segment
		(start 50.028602 -393.861798)
		(end 50.028602 -393.862052)
		(width 0.1651)
		(layer "In15.Cu")
		(net "CLK_100M_GPU_FPGA_REF_DP")
	)
	(segment
		(start 82.780886 -393.873736)
		(end 84.150454 -393.906756)
		(width 0.1651)
		(layer "In15.Cu")
		(net "CLK_100M_GPU_FPGA_REF_DP")
	)
	(segment
		(start 58.596784 -393.290298)
		(end 59.07913 -393.301728)
		(width 0.1651)
		(layer "In15.Cu")
		(net "CLK_100M_GPU_FPGA_REF_DP")
	)
	(segment
		(start 89.6493 -394.12164)
		(end 90.1319 -394.12164)
		(width 0.1651)
		(layer "In15.Cu")
		(net "CLK_100M_GPU_FPGA_REF_DP")
	)
	(segment
		(start 48.448214 -394.626592)
		(end 48.894238 -394.441934)
		(width 0.1651)
		(layer "In15.Cu")
		(net "CLK_100M_GPU_FPGA_REF_DP")
	)
	(segment
		(start 57.99709 -393.390374)
		(end 58.479944 -393.401804)
		(width 0.1651)
		(layer "In15.Cu")
		(net "CLK_100M_GPU_FPGA_REF_DP")
	)
	(segment
		(start 80.191102 -393.811252)
		(end 80.673448 -393.822682)
		(width 0.1651)
		(layer "In15.Cu")
		(net "CLK_100M_GPU_FPGA_REF_DP")
	)
	(segment
		(start 48.949102 -394.309092)
		(end 49.394872 -394.124688)
		(width 0.1651)
		(layer "In15.Cu")
		(net "CLK_100M_GPU_FPGA_REF_DP")
	)
	(segment
		(start 55.583074 -393.3317)
		(end 56.065674 -393.343384)
		(width 0.1651)
		(layer "In15.Cu")
		(net "CLK_100M_GPU_FPGA_REF_DP")
	)
	(segment
		(start 51.108102 -393.415012)
		(end 51.806602 -393.125706)
		(width 0.1651)
		(layer "In15.Cu")
		(net "CLK_100M_GPU_FPGA_REF_DP")
	)
	(segment
		(start 54.277768 -393.185396)
		(end 54.389274 -393.302744)
		(width 0.1651)
		(layer "In15.Cu")
		(net "CLK_100M_GPU_FPGA_REF_DP")
	)
	(segment
		(start 47.869602 -394.756132)
		(end 48.315372 -394.571728)
		(width 0.1651)
		(layer "In15.Cu")
		(net "CLK_100M_GPU_FPGA_REF_DP")
	)
	(segment
		(start 86.5124 -393.963906)
		(end 88.319864 -394.00734)
		(width 0.1651)
		(layer "In15.Cu")
		(net "CLK_100M_GPU_FPGA_REF_DP")
	)
	(segment
		(start 51.053238 -393.547854)
		(end 51.108102 -393.414758)
		(width 0.1651)
		(layer "In15.Cu")
		(net "CLK_100M_GPU_FPGA_REF_DP")
	)
	(segment
		(start 82.069432 -393.85621)
		(end 82.180938 -393.973558)
		(width 0.1651)
		(layer "In15.Cu")
		(net "CLK_100M_GPU_FPGA_REF_DP")
	)
	(segment
		(start 56.665114 -393.243308)
		(end 56.77662 -393.360656)
		(width 0.1651)
		(layer "In15.Cu")
		(net "CLK_100M_GPU_FPGA_REF_DP")
	)
	(segment
		(start 80.784954 -393.94003)
		(end 81.267554 -393.95146)
		(width 0.1651)
		(layer "In15.Cu")
		(net "CLK_100M_GPU_FPGA_REF_DP")
	)
	(segment
		(start 51.108102 -393.414758)
		(end 51.108102 -393.415012)
		(width 0.1651)
		(layer "In15.Cu")
		(net "CLK_100M_GPU_FPGA_REF_DP")
	)
	(segment
		(start 49.394872 -394.124688)
		(end 49.527714 -394.179552)
		(width 0.1651)
		(layer "In15.Cu")
		(net "CLK_100M_GPU_FPGA_REF_DP")
	)
	(segment
		(start 79.479902 -393.79398)
		(end 79.479902 -393.793726)
		(width 0.1651)
		(layer "In15.Cu")
		(net "CLK_100M_GPU_FPGA_REF_DP")
	)
	(segment
		(start 59.190636 -393.419076)
		(end 59.673236 -393.43076)
		(width 0.1651)
		(layer "In15.Cu")
		(net "CLK_100M_GPU_FPGA_REF_DP")
	)
	(segment
		(start 52.944268 -393.267692)
		(end 53.426868 -393.279376)
		(width 0.1651)
		(layer "In15.Cu")
		(net "CLK_100M_GPU_FPGA_REF_DP")
	)
	(segment
		(start 75.880468 -393.821666)
		(end 76.363322 -393.83335)
		(width 0.1651)
		(layer "In15.Cu")
		(net "CLK_100M_GPU_FPGA_REF_DP")
	)
	(segment
		(start 89.535 -394.00734)
		(end 89.6493 -394.12164)
		(width 0.1651)
		(layer "In15.Cu")
		(net "CLK_100M_GPU_FPGA_REF_DP")
	)
	(segment
		(start 47.582836 -398.09928)
		(end 47.031148 -398.09928)
		(width 0.1651)
		(layer "In15.Cu")
		(net "CLK_100M_GPU_FPGA_REF_DP")
	)
	(segment
		(start 46.80204 -395.823694)
		(end 47.869602 -394.756132)
		(width 0.1651)
		(layer "In15.Cu")
		(net "CLK_100M_GPU_FPGA_REF_DP")
	)
	(segment
		(start 84.26196 -394.02385)
		(end 84.744814 -394.03528)
		(width 0.1651)
		(layer "In15.Cu")
		(net "CLK_100M_GPU_FPGA_REF_DP")
	)
	(segment
		(start 85.800946 -393.946888)
		(end 85.8012 -393.94638)
		(width 0.1651)
		(layer "In15.Cu")
		(net "CLK_100M_GPU_FPGA_REF_DP")
	)
	(segment
		(start 57.885584 -393.273026)
		(end 57.99709 -393.390374)
		(width 0.1651)
		(layer "In15.Cu")
		(net "CLK_100M_GPU_FPGA_REF_DP")
	)
	(segment
		(start 92.466414 -395.285976)
		(end 92.627958 -395.285976)
		(width 0.1651)
		(layer "In15.Cu")
		(net "CLK_100M_GPU_FPGA_REF_DP")
	)
	(segment
		(start 50.607214 -393.732512)
		(end 51.053238 -393.547854)
		(width 0.1651)
		(layer "In15.Cu")
		(net "CLK_100M_GPU_FPGA_REF_DP")
	)
	(segment
		(start 53.543962 -393.16787)
		(end 54.277768 -393.185396)
		(width 0.1651)
		(layer "In15.Cu")
		(net "CLK_100M_GPU_FPGA_REF_DP")
	)
	(segment
		(start 81.384648 -393.839954)
		(end 82.069432 -393.856464)
		(width 0.1651)
		(layer "In15.Cu")
		(net "CLK_100M_GPU_FPGA_REF_DP")
	)
	(segment
		(start 49.973738 -393.994894)
		(end 50.028602 -393.861798)
		(width 0.1651)
		(layer "In15.Cu")
		(net "CLK_100M_GPU_FPGA_REF_DP")
	)
	(segment
		(start 48.949102 -394.308838)
		(end 48.949102 -394.309092)
		(width 0.1651)
		(layer "In15.Cu")
		(net "CLK_100M_GPU_FPGA_REF_DP")
	)
	(segment
		(start 56.182768 -393.231878)
		(end 56.665114 -393.243308)
		(width 0.1651)
		(layer "In15.Cu")
		(net "CLK_100M_GPU_FPGA_REF_DP")
	)
	(segment
		(start 59.673236 -393.43076)
		(end 59.79033 -393.319254)
		(width 0.1651)
		(layer "In15.Cu")
		(net "CLK_100M_GPU_FPGA_REF_DP")
	)
	(segment
		(start 91.545918 -394.203936)
		(end 92.124784 -394.782802)
		(width 0.1651)
		(layer "In15.Cu")
		(net "CLK_100M_GPU_FPGA_REF_DP")
	)
	(segment
		(start 92.627958 -395.285976)
		(end 92.96908 -395.627098)
		(width 0.1651)
		(layer "In15.Cu")
		(net "CLK_100M_GPU_FPGA_REF_DP")
	)
	(segment
		(start 85.912706 -394.063728)
		(end 86.395306 -394.075412)
		(width 0.1651)
		(layer "In15.Cu")
		(net "CLK_100M_GPU_FPGA_REF_DP")
	)
	(segment
		(start 48.315372 -394.571728)
		(end 48.448214 -394.626592)
		(width 0.1651)
		(layer "In15.Cu")
		(net "CLK_100M_GPU_FPGA_REF_DP")
	)
	(segment
		(start 56.065674 -393.343384)
		(end 56.182768 -393.231878)
		(width 0.1651)
		(layer "In15.Cu")
		(net "CLK_100M_GPU_FPGA_REF_DP")
	)
	(segment
		(start 75.768962 -393.704318)
		(end 75.880468 -393.821666)
		(width 0.1651)
		(layer "In15.Cu")
		(net "CLK_100M_GPU_FPGA_REF_DP")
	)
	(segment
		(start 90.1319 -394.12164)
		(end 90.2462 -394.00734)
		(width 0.1651)
		(layer "In15.Cu")
		(net "CLK_100M_GPU_FPGA_REF_DP")
	)
	(segment
		(start 58.479944 -393.401804)
		(end 58.596784 -393.290298)
		(width 0.1651)
		(layer "In15.Cu")
		(net "CLK_100M_GPU_FPGA_REF_DP")
	)
	(segment
		(start 92.124784 -394.782802)
		(end 92.124784 -394.944346)
		(width 0.1651)
		(layer "In15.Cu")
		(net "CLK_100M_GPU_FPGA_REF_DP")
	)
	(segment
		(start 92.96908 -395.627098)
		(end 93.28912 -396.399766)
		(width 0.1651)
		(layer "In15.Cu")
		(net "CLK_100M_GPU_FPGA_REF_DP")
	)
	(segment
		(start 49.527714 -394.179552)
		(end 49.973738 -393.994894)
		(width 0.1651)
		(layer "In15.Cu")
		(net "CLK_100M_GPU_FPGA_REF_DP")
	)
	(segment
		(start 78.286356 -393.765278)
		(end 78.286356 -393.765024)
		(width 0.1651)
		(layer "In15.Cu")
		(net "CLK_100M_GPU_FPGA_REF_DP")
	)
	(segment
		(start 54.872128 -393.314428)
		(end 54.989222 -393.202922)
		(width 0.1651)
		(layer "In15.Cu")
		(net "CLK_100M_GPU_FPGA_REF_DP")
	)
	(segment
		(start 60.272676 -393.330684)
		(end 60.384182 -393.448032)
		(width 0.1651)
		(layer "In15.Cu")
		(net "CLK_100M_GPU_FPGA_REF_DP")
	)
	(segment
		(start 84.861654 -393.924028)
		(end 85.800946 -393.946888)
		(width 0.1651)
		(layer "In15.Cu")
		(net "CLK_100M_GPU_FPGA_REF_DP")
	)
	(segment
		(start 78.397862 -393.882372)
		(end 78.880462 -393.894056)
		(width 0.1651)
		(layer "In15.Cu")
		(net "CLK_100M_GPU_FPGA_REF_DP")
	)
	(segment
		(start 48.894238 -394.441934)
		(end 48.949102 -394.308838)
		(width 0.1651)
		(layer "In15.Cu")
		(net "CLK_100M_GPU_FPGA_REF_DP")
	)
	(segment
		(start 91.710002 -397.97609)
		(end 91.710002 -397.59001)
		(width 0.1651)
		(layer "In15.Cu")
		(net "CLK_100M_GPU_FPGA_REF_DP")
	)
	(segment
		(start 59.79033 -393.319254)
		(end 60.272676 -393.330684)
		(width 0.1651)
		(layer "In15.Cu")
		(net "CLK_100M_GPU_FPGA_REF_DP")
	)
	(segment
		(start 53.426868 -393.279376)
		(end 53.543962 -393.16787)
		(width 0.1651)
		(layer "In15.Cu")
		(net "CLK_100M_GPU_FPGA_REF_DP")
	)
	(segment
		(start 92.534486 -398.099026)
		(end 91.832938 -398.099026)
		(width 0.1651)
		(layer "In15.Cu")
		(net "CLK_100M_GPU_FPGA_REF_DP")
	)
	(segment
		(start 60.384182 -393.448032)
		(end 60.866782 -393.459716)
		(width 0.1651)
		(layer "In15.Cu")
		(net "CLK_100M_GPU_FPGA_REF_DP")
	)
	(segment
		(start 60.983876 -393.34821)
		(end 60.984638 -393.347448)
		(width 0.1651)
		(layer "In15.Cu")
		(net "CLK_100M_GPU_FPGA_REF_DP")
	)
	(segment
		(start 86.395306 -394.075412)
		(end 86.5124 -393.963906)
		(width 0.1651)
		(layer "In15.Cu")
		(net "CLK_100M_GPU_FPGA_REF_DP")
	)
	(segment
		(start 82.663792 -393.985242)
		(end 82.780886 -393.873736)
		(width 0.1651)
		(layer "In15.Cu")
		(net "CLK_100M_GPU_FPGA_REF_DP")
	)
	(segment
		(start 81.267554 -393.95146)
		(end 81.384648 -393.839954)
		(width 0.1651)
		(layer "In15.Cu")
		(net "CLK_100M_GPU_FPGA_REF_DP")
	)
	(segment
		(start 82.069432 -393.856464)
		(end 82.069432 -393.85621)
		(width 0.1651)
		(layer "In15.Cu")
		(net "CLK_100M_GPU_FPGA_REF_DP")
	)
	(segment
		(start 46.80204 -397.870172)
		(end 46.80204 -395.823694)
		(width 0.1651)
		(layer "In15.Cu")
		(net "CLK_100M_GPU_FPGA_REF_DP")
	)
	(segment
		(start 79.479902 -393.793726)
		(end 79.591408 -393.911074)
		(width 0.1651)
		(layer "In15.Cu")
		(net "CLK_100M_GPU_FPGA_REF_DP")
	)
	(segment
		(start 82.180938 -393.973558)
		(end 82.663792 -393.985242)
		(width 0.1651)
		(layer "In15.Cu")
		(net "CLK_100M_GPU_FPGA_REF_DP")
	)
	(segment
		(start 78.880462 -393.894056)
		(end 78.997556 -393.78255)
		(width 0.1651)
		(layer "In15.Cu")
		(net "CLK_100M_GPU_FPGA_REF_DP")
	)
	(segment
		(start 93.28912 -396.399766)
		(end 93.28912 -397.344392)
		(width 0.1651)
		(layer "In15.Cu")
		(net "CLK_100M_GPU_FPGA_REF_DP")
	)
	(segment
		(start 85.8012 -393.94638)
		(end 85.912706 -394.063728)
		(width 0.1651)
		(layer "In15.Cu")
		(net "CLK_100M_GPU_FPGA_REF_DP")
	)
	(segment
		(start 59.07913 -393.301728)
		(end 59.190636 -393.419076)
		(width 0.1651)
		(layer "In15.Cu")
		(net "CLK_100M_GPU_FPGA_REF_DP")
	)
	(segment
		(start 90.2462 -394.00734)
		(end 90.95359 -394.00734)
		(width 0.1651)
		(layer "In15.Cu")
		(net "CLK_100M_GPU_FPGA_REF_DP")
	)
	(segment
		(start 54.989222 -393.202922)
		(end 55.471568 -393.214352)
		(width 0.1651)
		(layer "In15.Cu")
		(net "CLK_100M_GPU_FPGA_REF_DP")
	)
	(segment
		(start 50.028602 -393.862052)
		(end 50.474372 -393.677648)
		(width 0.1651)
		(layer "In15.Cu")
		(net "CLK_100M_GPU_FPGA_REF_DP")
	)
	(segment
		(start 92.124784 -394.944346)
		(end 92.466414 -395.285976)
		(width 0.1651)
		(layer "In15.Cu")
		(net "CLK_100M_GPU_FPGA_REF_DP")
	)
	(segment
		(start 84.150454 -393.906502)
		(end 84.26196 -394.02385)
		(width 0.1651)
		(layer "In15.Cu")
		(net "CLK_100M_GPU_FPGA_REF_DP")
	)
	(segment
		(start 47.71009 -397.972026)
		(end 47.582836 -398.09928)
		(width 0.1651)
		(layer "In15.Cu")
		(net "CLK_100M_GPU_FPGA_REF_DP")
	)
	(segment
		(start 80.074008 -393.922758)
		(end 80.191102 -393.811252)
		(width 0.1651)
		(layer "In15.Cu")
		(net "CLK_100M_GPU_FPGA_REF_DP")
	)
	(segment
		(start 91.832938 -398.099026)
		(end 91.710002 -397.97609)
		(width 0.1651)
		(layer "In15.Cu")
		(net "CLK_100M_GPU_FPGA_REF_DP")
	)
	(segment
		(start 52.832762 -393.150344)
		(end 52.944268 -393.267692)
		(width 0.1651)
		(layer "In15.Cu")
		(net "CLK_100M_GPU_FPGA_REF_DP")
	)
	(segment
		(start 78.997556 -393.78255)
		(end 79.479902 -393.79398)
		(width 0.1651)
		(layer "In15.Cu")
		(net "CLK_100M_GPU_FPGA_REF_DP")
	)
	(segment
		(start 47.71009 -397.59001)
		(end 47.71009 -397.972026)
		(width 0.1651)
		(layer "In15.Cu")
		(net "CLK_100M_GPU_FPGA_REF_DP")
	)
	(segment
		(start 60.984638 -393.347448)
		(end 75.768962 -393.704318)
		(width 0.1651)
		(layer "In15.Cu")
		(net "CLK_100M_GPU_FPGA_REF_DP")
	)
	(segment
		(start 76.363322 -393.83335)
		(end 76.480416 -393.721844)
		(width 0.1651)
		(layer "In15.Cu")
		(net "CLK_100M_GPU_FPGA_REF_DP")
	)
	(segment
		(start 50.474372 -393.677648)
		(end 50.607214 -393.732512)
		(width 0.1651)
		(layer "In15.Cu")
		(net "CLK_100M_GPU_FPGA_REF_DP")
	)
	(segment
		(start 84.744814 -394.03528)
		(end 84.861654 -393.923774)
		(width 0.1651)
		(layer "In15.Cu")
		(net "CLK_100M_GPU_FPGA_REF_DP")
	)
	(segment
		(start 88.319864 -394.00734)
		(end 89.535 -394.00734)
		(width 0.1651)
		(layer "In15.Cu")
		(net "CLK_100M_GPU_FPGA_REF_DP")
	)
	(segment
		(start 78.286356 -393.765024)
		(end 78.397862 -393.882372)
		(width 0.1651)
		(layer "In15.Cu")
		(net "CLK_100M_GPU_FPGA_REF_DP")
	)
	(segment
		(start 57.25922 -393.37234)
		(end 57.376314 -393.260834)
		(width 0.1651)
		(layer "In15.Cu")
		(net "CLK_100M_GPU_FPGA_REF_DP")
	)
	(segment
		(start 47.031148 -398.09928)
		(end 46.80204 -397.870172)
		(width 0.1651)
		(layer "In15.Cu")
		(net "CLK_100M_GPU_FPGA_REF_DP")
	)
	(segment
		(start 60.866782 -393.459716)
		(end 60.983876 -393.34821)
		(width 0.1651)
		(layer "In15.Cu")
		(net "CLK_100M_GPU_FPGA_REF_DP")
	)
	(segment
		(start 76.480416 -393.721844)
		(end 78.286356 -393.765278)
		(width 0.1651)
		(layer "In15.Cu")
		(net "CLK_100M_GPU_FPGA_REF_DP")
	)
	(segment
		(start 84.150454 -393.906756)
		(end 84.150454 -393.906502)
		(width 0.1651)
		(layer "In15.Cu")
		(net "CLK_100M_GPU_FPGA_REF_DP")
	)
	(segment
		(start 54.389274 -393.302744)
		(end 54.872128 -393.314428)
		(width 0.1651)
		(layer "In15.Cu")
		(net "CLK_100M_GPU_FPGA_REF_DP")
	)
	(segment
		(start 79.591408 -393.911074)
		(end 80.074008 -393.922758)
		(width 0.1651)
		(layer "In15.Cu")
		(net "CLK_100M_GPU_FPGA_REF_DP")
	)
	(segment
		(start 80.673448 -393.822682)
		(end 80.784954 -393.94003)
		(width 0.1651)
		(layer "In15.Cu")
		(net "CLK_100M_GPU_FPGA_REF_DP")
	)
	(segment
		(start 55.471568 -393.214352)
		(end 55.583074 -393.3317)
		(width 0.1651)
		(layer "In15.Cu")
		(net "CLK_100M_GPU_FPGA_REF_DP")
	)
	(segment
		(start 93.28912 -397.344392)
		(end 92.534486 -398.099026)
		(width 0.1651)
		(layer "In15.Cu")
		(net "CLK_100M_GPU_FPGA_REF_DP")
	)
	(segment
		(start 56.77662 -393.360656)
		(end 57.25922 -393.37234)
		(width 0.1651)
		(layer "In15.Cu")
		(net "CLK_100M_GPU_FPGA_REF_DP")
	)
	(segment
		(start 445.226694 -119.951246)
		(end 445.226694 -119.405654)
		(width 0.13208)
		(layer "F.Cu")
		(net "P3V3_NIC7_SS")
	)
	(segment
		(start 445.0715 -120.041924)
		(end 445.136016 -120.041924)
		(width 0.13208)
		(layer "F.Cu")
		(net "P3V3_NIC7_SS")
	)
	(segment
		(start 445.136016 -120.041924)
		(end 445.226694 -119.951246)
		(width 0.13208)
		(layer "F.Cu")
		(net "P3V3_NIC7_SS")
	)
	(segment
		(start 445.226694 -119.405654)
		(end 446.164462 -118.467886)
		(width 0.13208)
		(layer "F.Cu")
		(net "P3V3_NIC7_SS")
	)
	(segment
		(start 446.164462 -118.467886)
		(end 446.875662 -118.467886)
		(width 0.13208)
		(layer "F.Cu")
		(net "P3V3_NIC7_SS")
	)
	(via
		(at 446.164462 -118.467886)
		(size 0.508)
		(drill 0.254)
		(layers "F.Cu" "B.Cu")
		(net "P3V3_NIC7_SS")
	)
	(segment
		(start 136.6012 -185.434224)
		(end 136.6012 -186.793632)
		(width 0.13462)
		(layer "F.Cu")
		(net "CLK_100M_DB2000QL_NIC7_R_DP")
	)
	(segment
		(start 136.97839 -185.057034)
		(end 136.6012 -185.434224)
		(width 0.13462)
		(layer "F.Cu")
		(net "CLK_100M_DB2000QL_NIC7_R_DP")
	)
	(segment
		(start 422.948862 -117.475)
		(end 422.208198 -117.475)
		(width 0.13462)
		(layer "F.Cu")
		(net "CLK_100M_DB2000QL_NIC7_R_DP")
	)
	(segment
		(start 423.232834 -117.758972)
		(end 422.948862 -117.475)
		(width 0.13462)
		(layer "F.Cu")
		(net "CLK_100M_DB2000QL_NIC7_R_DP")
	)
	(segment
		(start 422.048178 -117.63502)
		(end 421.557704 -117.63502)
		(width 0.13462)
		(layer "F.Cu")
		(net "CLK_100M_DB2000QL_NIC7_R_DP")
	)
	(segment
		(start 136.6012 -186.793632)
		(end 136.90219 -187.094622)
		(width 0.13462)
		(layer "F.Cu")
		(net "CLK_100M_DB2000QL_NIC7_R_DP")
	)
	(segment
		(start 422.208198 -117.475)
		(end 422.048178 -117.63502)
		(width 0.13462)
		(layer "F.Cu")
		(net "CLK_100M_DB2000QL_NIC7_R_DP")
	)
	(via
		(at 423.232834 -117.758972)
		(size 0.508)
		(drill 0.254)
		(layers "F.Cu" "B.Cu")
		(net "CLK_100M_DB2000QL_NIC7_R_DP")
	)
	(via
		(at 136.90219 -187.094622)
		(size 0.508)
		(drill 0.254)
		(layers "F.Cu" "B.Cu")
		(net "CLK_100M_DB2000QL_NIC7_R_DP")
	)
	(segment
		(start 421.78224 -162.964114)
		(end 421.944038 -162.964114)
		(width 0.1651)
		(layer "In15.Cu")
		(net "CLK_100M_DB2000QL_NIC7_R_DP")
	)
	(segment
		(start 368.96167 -168.808654)
		(end 370.351812 -167.418512)
		(width 0.1651)
		(layer "In15.Cu")
		(net "CLK_100M_DB2000QL_NIC7_R_DP")
	)
	(segment
		(start 421.43172 -163.314634)
		(end 421.78224 -162.964114)
		(width 0.1651)
		(layer "In15.Cu")
		(net "CLK_100M_DB2000QL_NIC7_R_DP")
	)
	(segment
		(start 424.904408 -119.01678)
		(end 424.904408 -118.52148)
		(width 0.1651)
		(layer "In15.Cu")
		(net "CLK_100M_DB2000QL_NIC7_R_DP")
	)
	(segment
		(start 343.784428 -166.41318)
		(end 346.155772 -166.41318)
		(width 0.1651)
		(layer "In15.Cu")
		(net "CLK_100M_DB2000QL_NIC7_R_DP")
	)
	(segment
		(start 208.168494 -171.5008)
		(end 209.516472 -170.152822)
		(width 0.1651)
		(layer "In15.Cu")
		(net "CLK_100M_DB2000QL_NIC7_R_DP")
	)
	(segment
		(start 342.40216 -165.030912)
		(end 343.784428 -166.41318)
		(width 0.1651)
		(layer "In15.Cu")
		(net "CLK_100M_DB2000QL_NIC7_R_DP")
	)
	(segment
		(start 424.904408 -118.52148)
		(end 423.85488 -117.471952)
		(width 0.1651)
		(layer "In15.Cu")
		(net "CLK_100M_DB2000QL_NIC7_R_DP")
	)
	(segment
		(start 144.10436 -184.09666)
		(end 144.284192 -183.916828)
		(width 0.1651)
		(layer "In15.Cu")
		(net "CLK_100M_DB2000QL_NIC7_R_DP")
	)
	(segment
		(start 179.38242 -172.9994)
		(end 179.672488 -172.879258)
		(width 0.1651)
		(layer "In15.Cu")
		(net "CLK_100M_DB2000QL_NIC7_R_DP")
	)
	(segment
		(start 422.806368 -162.101784)
		(end 423.15638 -161.751772)
		(width 0.1651)
		(layer "In15.Cu")
		(net "CLK_100M_DB2000QL_NIC7_R_DP")
	)
	(segment
		(start 424.904408 -125.83668)
		(end 424.790108 -125.72238)
		(width 0.1651)
		(layer "In15.Cu")
		(net "CLK_100M_DB2000QL_NIC7_R_DP")
	)
	(segment
		(start 370.351812 -167.418512)
		(end 401.679664 -167.418512)
		(width 0.1651)
		(layer "In15.Cu")
		(net "CLK_100M_DB2000QL_NIC7_R_DP")
	)
	(segment
		(start 424.790108 -119.62638)
		(end 424.790108 -119.13108)
		(width 0.1651)
		(layer "In15.Cu")
		(net "CLK_100M_DB2000QL_NIC7_R_DP")
	)
	(segment
		(start 181.050946 -171.5008)
		(end 208.168494 -171.5008)
		(width 0.1651)
		(layer "In15.Cu")
		(net "CLK_100M_DB2000QL_NIC7_R_DP")
	)
	(segment
		(start 290.51123 -166.796974)
		(end 291.95268 -165.355524)
		(width 0.1651)
		(layer "In15.Cu")
		(net "CLK_100M_DB2000QL_NIC7_R_DP")
	)
	(segment
		(start 144.284192 -183.916828)
		(end 162.546792 -183.916828)
		(width 0.1651)
		(layer "In15.Cu")
		(net "CLK_100M_DB2000QL_NIC7_R_DP")
	)
	(segment
		(start 424.790108 -124.00788)
		(end 424.904408 -123.89358)
		(width 0.1651)
		(layer "In15.Cu")
		(net "CLK_100M_DB2000QL_NIC7_R_DP")
	)
	(segment
		(start 257.641598 -167.706802)
		(end 280.280618 -167.706802)
		(width 0.1651)
		(layer "In15.Cu")
		(net "CLK_100M_DB2000QL_NIC7_R_DP")
	)
	(segment
		(start 424.790108 -119.13108)
		(end 424.904408 -119.01678)
		(width 0.1651)
		(layer "In15.Cu")
		(net "CLK_100M_DB2000QL_NIC7_R_DP")
	)
	(segment
		(start 348.551246 -168.808654)
		(end 368.96167 -168.808654)
		(width 0.1651)
		(layer "In15.Cu")
		(net "CLK_100M_DB2000QL_NIC7_R_DP")
	)
	(segment
		(start 136.61517 -187.381642)
		(end 136.61517 -187.600844)
		(width 0.1651)
		(layer "In15.Cu")
		(net "CLK_100M_DB2000QL_NIC7_R_DP")
	)
	(segment
		(start 420.920164 -163.826444)
		(end 421.081708 -163.826444)
		(width 0.1651)
		(layer "In15.Cu")
		(net "CLK_100M_DB2000QL_NIC7_R_DP")
	)
	(segment
		(start 424.531028 -160.377124)
		(end 424.904408 -160.003744)
		(width 0.1651)
		(layer "In15.Cu")
		(net "CLK_100M_DB2000QL_NIC7_R_DP")
	)
	(segment
		(start 424.904408 -123.89358)
		(end 424.904408 -123.39828)
		(width 0.1651)
		(layer "In15.Cu")
		(net "CLK_100M_DB2000QL_NIC7_R_DP")
	)
	(segment
		(start 423.15638 -161.589974)
		(end 423.5069 -161.239454)
		(width 0.1651)
		(layer "In15.Cu")
		(net "CLK_100M_DB2000QL_NIC7_R_DP")
	)
	(segment
		(start 165.709092 -183.916828)
		(end 166.204392 -183.916828)
		(width 0.1651)
		(layer "In15.Cu")
		(net "CLK_100M_DB2000QL_NIC7_R_DP")
	)
	(segment
		(start 424.790108 -122.78868)
		(end 424.904408 -122.67438)
		(width 0.1651)
		(layer "In15.Cu")
		(net "CLK_100M_DB2000QL_NIC7_R_DP")
	)
	(segment
		(start 424.904408 -125.11278)
		(end 424.904408 -124.61748)
		(width 0.1651)
		(layer "In15.Cu")
		(net "CLK_100M_DB2000QL_NIC7_R_DP")
	)
	(segment
		(start 424.790108 -121.56948)
		(end 424.904408 -121.45518)
		(width 0.1651)
		(layer "In15.Cu")
		(net "CLK_100M_DB2000QL_NIC7_R_DP")
	)
	(segment
		(start 237.504986 -167.66286)
		(end 240.320068 -170.477942)
		(width 0.1651)
		(layer "In15.Cu")
		(net "CLK_100M_DB2000QL_NIC7_R_DP")
	)
	(segment
		(start 164.489892 -183.916828)
		(end 164.985192 -183.916828)
		(width 0.1651)
		(layer "In15.Cu")
		(net "CLK_100M_DB2000QL_NIC7_R_DP")
	)
	(segment
		(start 336.471006 -165.030912)
		(end 342.40216 -165.030912)
		(width 0.1651)
		(layer "In15.Cu")
		(net "CLK_100M_DB2000QL_NIC7_R_DP")
	)
	(segment
		(start 424.904408 -121.45518)
		(end 424.904408 -120.95988)
		(width 0.1651)
		(layer "In15.Cu")
		(net "CLK_100M_DB2000QL_NIC7_R_DP")
	)
	(segment
		(start 423.15638 -161.751772)
		(end 423.15638 -161.589974)
		(width 0.1651)
		(layer "In15.Cu")
		(net "CLK_100M_DB2000QL_NIC7_R_DP")
	)
	(segment
		(start 424.790108 -123.28398)
		(end 424.790108 -122.78868)
		(width 0.1651)
		(layer "In15.Cu")
		(net "CLK_100M_DB2000QL_NIC7_R_DP")
	)
	(segment
		(start 421.944038 -162.964114)
		(end 422.29405 -162.614102)
		(width 0.1651)
		(layer "In15.Cu")
		(net "CLK_100M_DB2000QL_NIC7_R_DP")
	)
	(segment
		(start 164.375592 -183.802528)
		(end 164.489892 -183.916828)
		(width 0.1651)
		(layer "In15.Cu")
		(net "CLK_100M_DB2000QL_NIC7_R_DP")
	)
	(segment
		(start 424.790108 -120.84558)
		(end 424.790108 -120.35028)
		(width 0.1651)
		(layer "In15.Cu")
		(net "CLK_100M_DB2000QL_NIC7_R_DP")
	)
	(segment
		(start 330.442316 -165.355524)
		(end 331.753464 -164.044376)
		(width 0.1651)
		(layer "In15.Cu")
		(net "CLK_100M_DB2000QL_NIC7_R_DP")
	)
	(segment
		(start 420.569644 -164.338508)
		(end 420.569644 -164.176964)
		(width 0.1651)
		(layer "In15.Cu")
		(net "CLK_100M_DB2000QL_NIC7_R_DP")
	)
	(segment
		(start 179.672488 -172.879258)
		(end 181.050946 -171.5008)
		(width 0.1651)
		(layer "In15.Cu")
		(net "CLK_100M_DB2000QL_NIC7_R_DP")
	)
	(segment
		(start 404.33752 -164.760656)
		(end 420.147496 -164.760656)
		(width 0.1651)
		(layer "In15.Cu")
		(net "CLK_100M_DB2000QL_NIC7_R_DP")
	)
	(segment
		(start 423.668698 -161.239454)
		(end 424.01871 -160.889442)
		(width 0.1651)
		(layer "In15.Cu")
		(net "CLK_100M_DB2000QL_NIC7_R_DP")
	)
	(segment
		(start 424.904408 -119.74068)
		(end 424.790108 -119.62638)
		(width 0.1651)
		(layer "In15.Cu")
		(net "CLK_100M_DB2000QL_NIC7_R_DP")
	)
	(segment
		(start 142.01013 -184.09666)
		(end 144.10436 -184.09666)
		(width 0.1651)
		(layer "In15.Cu")
		(net "CLK_100M_DB2000QL_NIC7_R_DP")
	)
	(segment
		(start 424.904408 -123.39828)
		(end 424.790108 -123.28398)
		(width 0.1651)
		(layer "In15.Cu")
		(net "CLK_100M_DB2000QL_NIC7_R_DP")
	)
	(segment
		(start 163.880292 -183.802528)
		(end 164.375592 -183.802528)
		(width 0.1651)
		(layer "In15.Cu")
		(net "CLK_100M_DB2000QL_NIC7_R_DP")
	)
	(segment
		(start 138.369294 -187.737496)
		(end 142.01013 -184.09666)
		(width 0.1651)
		(layer "In15.Cu")
		(net "CLK_100M_DB2000QL_NIC7_R_DP")
	)
	(segment
		(start 240.320068 -170.477942)
		(end 254.870458 -170.477942)
		(width 0.1651)
		(layer "In15.Cu")
		(net "CLK_100M_DB2000QL_NIC7_R_DP")
	)
	(segment
		(start 163.270692 -183.916828)
		(end 163.765992 -183.916828)
		(width 0.1651)
		(layer "In15.Cu")
		(net "CLK_100M_DB2000QL_NIC7_R_DP")
	)
	(segment
		(start 424.36923 -160.377124)
		(end 424.531028 -160.377124)
		(width 0.1651)
		(layer "In15.Cu")
		(net "CLK_100M_DB2000QL_NIC7_R_DP")
	)
	(segment
		(start 422.64457 -162.101784)
		(end 422.806368 -162.101784)
		(width 0.1651)
		(layer "In15.Cu")
		(net "CLK_100M_DB2000QL_NIC7_R_DP")
	)
	(segment
		(start 423.5069 -161.239454)
		(end 423.668698 -161.239454)
		(width 0.1651)
		(layer "In15.Cu")
		(net "CLK_100M_DB2000QL_NIC7_R_DP")
	)
	(segment
		(start 424.790108 -122.06478)
		(end 424.790108 -121.56948)
		(width 0.1651)
		(layer "In15.Cu")
		(net "CLK_100M_DB2000QL_NIC7_R_DP")
	)
	(segment
		(start 424.790108 -125.72238)
		(end 424.790108 -125.22708)
		(width 0.1651)
		(layer "In15.Cu")
		(net "CLK_100M_DB2000QL_NIC7_R_DP")
	)
	(segment
		(start 424.904408 -160.003744)
		(end 424.904408 -125.83668)
		(width 0.1651)
		(layer "In15.Cu")
		(net "CLK_100M_DB2000QL_NIC7_R_DP")
	)
	(segment
		(start 177.12182 -172.9994)
		(end 179.38242 -172.9994)
		(width 0.1651)
		(layer "In15.Cu")
		(net "CLK_100M_DB2000QL_NIC7_R_DP")
	)
	(segment
		(start 213.324948 -170.152822)
		(end 215.81491 -167.66286)
		(width 0.1651)
		(layer "In15.Cu")
		(net "CLK_100M_DB2000QL_NIC7_R_DP")
	)
	(segment
		(start 424.790108 -124.50318)
		(end 424.790108 -124.00788)
		(width 0.1651)
		(layer "In15.Cu")
		(net "CLK_100M_DB2000QL_NIC7_R_DP")
	)
	(segment
		(start 424.790108 -125.22708)
		(end 424.904408 -125.11278)
		(width 0.1651)
		(layer "In15.Cu")
		(net "CLK_100M_DB2000QL_NIC7_R_DP")
	)
	(segment
		(start 422.29405 -162.452304)
		(end 422.64457 -162.101784)
		(width 0.1651)
		(layer "In15.Cu")
		(net "CLK_100M_DB2000QL_NIC7_R_DP")
	)
	(segment
		(start 420.569644 -164.176964)
		(end 420.920164 -163.826444)
		(width 0.1651)
		(layer "In15.Cu")
		(net "CLK_100M_DB2000QL_NIC7_R_DP")
	)
	(segment
		(start 423.85488 -117.471952)
		(end 423.519854 -117.471952)
		(width 0.1651)
		(layer "In15.Cu")
		(net "CLK_100M_DB2000QL_NIC7_R_DP")
	)
	(segment
		(start 401.679664 -167.418512)
		(end 404.33752 -164.760656)
		(width 0.1651)
		(layer "In15.Cu")
		(net "CLK_100M_DB2000QL_NIC7_R_DP")
	)
	(segment
		(start 163.765992 -183.916828)
		(end 163.880292 -183.802528)
		(width 0.1651)
		(layer "In15.Cu")
		(net "CLK_100M_DB2000QL_NIC7_R_DP")
	)
	(segment
		(start 424.904408 -122.17908)
		(end 424.790108 -122.06478)
		(width 0.1651)
		(layer "In15.Cu")
		(net "CLK_100M_DB2000QL_NIC7_R_DP")
	)
	(segment
		(start 331.753464 -164.044376)
		(end 335.48447 -164.044376)
		(width 0.1651)
		(layer "In15.Cu")
		(net "CLK_100M_DB2000QL_NIC7_R_DP")
	)
	(segment
		(start 420.147496 -164.760656)
		(end 420.569644 -164.338508)
		(width 0.1651)
		(layer "In15.Cu")
		(net "CLK_100M_DB2000QL_NIC7_R_DP")
	)
	(segment
		(start 335.48447 -164.044376)
		(end 336.471006 -165.030912)
		(width 0.1651)
		(layer "In15.Cu")
		(net "CLK_100M_DB2000QL_NIC7_R_DP")
	)
	(segment
		(start 424.790108 -120.35028)
		(end 424.904408 -120.23598)
		(width 0.1651)
		(layer "In15.Cu")
		(net "CLK_100M_DB2000QL_NIC7_R_DP")
	)
	(segment
		(start 424.01871 -160.889442)
		(end 424.01871 -160.727644)
		(width 0.1651)
		(layer "In15.Cu")
		(net "CLK_100M_DB2000QL_NIC7_R_DP")
	)
	(segment
		(start 165.594792 -183.802528)
		(end 165.709092 -183.916828)
		(width 0.1651)
		(layer "In15.Cu")
		(net "CLK_100M_DB2000QL_NIC7_R_DP")
	)
	(segment
		(start 209.516472 -170.152822)
		(end 213.324948 -170.152822)
		(width 0.1651)
		(layer "In15.Cu")
		(net "CLK_100M_DB2000QL_NIC7_R_DP")
	)
	(segment
		(start 280.280618 -167.706802)
		(end 281.190446 -166.796974)
		(width 0.1651)
		(layer "In15.Cu")
		(net "CLK_100M_DB2000QL_NIC7_R_DP")
	)
	(segment
		(start 281.190446 -166.796974)
		(end 290.51123 -166.796974)
		(width 0.1651)
		(layer "In15.Cu")
		(net "CLK_100M_DB2000QL_NIC7_R_DP")
	)
	(segment
		(start 424.01871 -160.727644)
		(end 424.36923 -160.377124)
		(width 0.1651)
		(layer "In15.Cu")
		(net "CLK_100M_DB2000QL_NIC7_R_DP")
	)
	(segment
		(start 162.661092 -183.802528)
		(end 163.156392 -183.802528)
		(width 0.1651)
		(layer "In15.Cu")
		(net "CLK_100M_DB2000QL_NIC7_R_DP")
	)
	(segment
		(start 424.904408 -124.61748)
		(end 424.790108 -124.50318)
		(width 0.1651)
		(layer "In15.Cu")
		(net "CLK_100M_DB2000QL_NIC7_R_DP")
	)
	(segment
		(start 424.904408 -120.95988)
		(end 424.790108 -120.84558)
		(width 0.1651)
		(layer "In15.Cu")
		(net "CLK_100M_DB2000QL_NIC7_R_DP")
	)
	(segment
		(start 291.95268 -165.355524)
		(end 330.442316 -165.355524)
		(width 0.1651)
		(layer "In15.Cu")
		(net "CLK_100M_DB2000QL_NIC7_R_DP")
	)
	(segment
		(start 421.081708 -163.826444)
		(end 421.43172 -163.476432)
		(width 0.1651)
		(layer "In15.Cu")
		(net "CLK_100M_DB2000QL_NIC7_R_DP")
	)
	(segment
		(start 423.519854 -117.471952)
		(end 423.232834 -117.758972)
		(width 0.1651)
		(layer "In15.Cu")
		(net "CLK_100M_DB2000QL_NIC7_R_DP")
	)
	(segment
		(start 424.904408 -120.23598)
		(end 424.904408 -119.74068)
		(width 0.1651)
		(layer "In15.Cu")
		(net "CLK_100M_DB2000QL_NIC7_R_DP")
	)
	(segment
		(start 165.099492 -183.802528)
		(end 165.594792 -183.802528)
		(width 0.1651)
		(layer "In15.Cu")
		(net "CLK_100M_DB2000QL_NIC7_R_DP")
	)
	(segment
		(start 136.61517 -187.600844)
		(end 136.751822 -187.737496)
		(width 0.1651)
		(layer "In15.Cu")
		(net "CLK_100M_DB2000QL_NIC7_R_DP")
	)
	(segment
		(start 254.870458 -170.477942)
		(end 257.641598 -167.706802)
		(width 0.1651)
		(layer "In15.Cu")
		(net "CLK_100M_DB2000QL_NIC7_R_DP")
	)
	(segment
		(start 136.90219 -187.094622)
		(end 136.61517 -187.381642)
		(width 0.1651)
		(layer "In15.Cu")
		(net "CLK_100M_DB2000QL_NIC7_R_DP")
	)
	(segment
		(start 164.985192 -183.916828)
		(end 165.099492 -183.802528)
		(width 0.1651)
		(layer "In15.Cu")
		(net "CLK_100M_DB2000QL_NIC7_R_DP")
	)
	(segment
		(start 163.156392 -183.802528)
		(end 163.270692 -183.916828)
		(width 0.1651)
		(layer "In15.Cu")
		(net "CLK_100M_DB2000QL_NIC7_R_DP")
	)
	(segment
		(start 136.751822 -187.737496)
		(end 138.369294 -187.737496)
		(width 0.1651)
		(layer "In15.Cu")
		(net "CLK_100M_DB2000QL_NIC7_R_DP")
	)
	(segment
		(start 346.155772 -166.41318)
		(end 348.551246 -168.808654)
		(width 0.1651)
		(layer "In15.Cu")
		(net "CLK_100M_DB2000QL_NIC7_R_DP")
	)
	(segment
		(start 215.81491 -167.66286)
		(end 237.504986 -167.66286)
		(width 0.1651)
		(layer "In15.Cu")
		(net "CLK_100M_DB2000QL_NIC7_R_DP")
	)
	(segment
		(start 166.204392 -183.916828)
		(end 177.12182 -172.9994)
		(width 0.1651)
		(layer "In15.Cu")
		(net "CLK_100M_DB2000QL_NIC7_R_DP")
	)
	(segment
		(start 162.546792 -183.916828)
		(end 162.661092 -183.802528)
		(width 0.1651)
		(layer "In15.Cu")
		(net "CLK_100M_DB2000QL_NIC7_R_DP")
	)
	(segment
		(start 422.29405 -162.614102)
		(end 422.29405 -162.452304)
		(width 0.1651)
		(layer "In15.Cu")
		(net "CLK_100M_DB2000QL_NIC7_R_DP")
	)
	(segment
		(start 424.904408 -122.67438)
		(end 424.904408 -122.17908)
		(width 0.1651)
		(layer "In15.Cu")
		(net "CLK_100M_DB2000QL_NIC7_R_DP")
	)
	(segment
		(start 421.43172 -163.476432)
		(end 421.43172 -163.314634)
		(width 0.1651)
		(layer "In15.Cu")
		(net "CLK_100M_DB2000QL_NIC7_R_DP")
	)
	(via
		(at 91.258898 -414.95091)
		(size 0.6604)
		(drill 0.3302)
		(layers "F.Cu" "B.Cu")
		(net "TP_CLK_100M_MB_2_DP")
	)
	(segment
		(start 90.794332 -401.674584)
		(end 89.509854 -400.390106)
		(width 0.13208)
		(layer "B.Cu")
		(net "TP_CLK_100M_MB_2_DP")
	)
	(segment
		(start 91.258898 -414.95091)
		(end 90.794332 -414.486344)
		(width 0.13208)
		(layer "B.Cu")
		(net "TP_CLK_100M_MB_2_DP")
	)
	(segment
		(start 90.794332 -414.486344)
		(end 90.794332 -401.674584)
		(width 0.13208)
		(layer "B.Cu")
		(net "TP_CLK_100M_MB_2_DP")
	)
	(segment
		(start 134.610856 -170.199812)
		(end 134.239 -169.827956)
		(width 0.13462)
		(layer "F.Cu")
		(net "CLK_100M_DB2000QL_NIC0_R_DN")
	)
	(segment
		(start 44.725082 -138.202162)
		(end 45.440346 -138.202162)
		(width 0.13462)
		(layer "F.Cu")
		(net "CLK_100M_DB2000QL_NIC0_R_DN")
	)
	(segment
		(start 134.239 -169.827956)
		(end 134.239 -168.96588)
		(width 0.13462)
		(layer "F.Cu")
		(net "CLK_100M_DB2000QL_NIC0_R_DN")
	)
	(segment
		(start 45.440346 -138.202162)
		(end 45.60316 -138.364976)
		(width 0.13462)
		(layer "F.Cu")
		(net "CLK_100M_DB2000QL_NIC0_R_DN")
	)
	(segment
		(start 134.239 -168.96588)
		(end 134.534656 -168.670224)
		(width 0.13462)
		(layer "F.Cu")
		(net "CLK_100M_DB2000QL_NIC0_R_DN")
	)
	(segment
		(start 44.430442 -138.496802)
		(end 44.725082 -138.202162)
		(width 0.13462)
		(layer "F.Cu")
		(net "CLK_100M_DB2000QL_NIC0_R_DN")
	)
	(segment
		(start 45.60316 -138.364976)
		(end 46.042326 -138.364976)
		(width 0.13462)
		(layer "F.Cu")
		(net "CLK_100M_DB2000QL_NIC0_R_DN")
	)
	(via
		(at 44.430442 -138.496802)
		(size 0.508)
		(drill 0.254)
		(layers "F.Cu" "B.Cu")
		(net "CLK_100M_DB2000QL_NIC0_R_DN")
	)
	(via
		(at 134.534656 -168.670224)
		(size 0.508)
		(drill 0.254)
		(layers "F.Cu" "B.Cu")
		(net "CLK_100M_DB2000QL_NIC0_R_DN")
	)
	(segment
		(start 53.1876 -142.7226)
		(end 53.1876 -139.573)
		(width 0.1651)
		(layer "In15.Cu")
		(net "CLK_100M_DB2000QL_NIC0_R_DN")
	)
	(segment
		(start 50.3936 -138.4046)
		(end 49.7586 -137.7696)
		(width 0.1651)
		(layer "In15.Cu")
		(net "CLK_100M_DB2000QL_NIC0_R_DN")
	)
	(segment
		(start 134.243826 -169.565574)
		(end 133.5532 -170.2562)
		(width 0.1651)
		(layer "In15.Cu")
		(net "CLK_100M_DB2000QL_NIC0_R_DN")
	)
	(segment
		(start 122.0724 -183.0578)
		(end 120.3452 -184.785)
		(width 0.1651)
		(layer "In15.Cu")
		(net "CLK_100M_DB2000QL_NIC0_R_DN")
	)
	(segment
		(start 106.388916 -185.909204)
		(end 103.385112 -184.665112)
		(width 0.1651)
		(layer "In15.Cu")
		(net "CLK_100M_DB2000QL_NIC0_R_DN")
	)
	(segment
		(start 110.534196 -185.909204)
		(end 106.388916 -185.909204)
		(width 0.1651)
		(layer "In15.Cu")
		(net "CLK_100M_DB2000QL_NIC0_R_DN")
	)
	(segment
		(start 83.82 -165.1)
		(end 56.896 -165.1)
		(width 0.1651)
		(layer "In15.Cu")
		(net "CLK_100M_DB2000QL_NIC0_R_DN")
	)
	(segment
		(start 56.896 -165.1)
		(end 53.8734 -162.0774)
		(width 0.1651)
		(layer "In15.Cu")
		(net "CLK_100M_DB2000QL_NIC0_R_DN")
	)
	(segment
		(start 45.8978 -137.7696)
		(end 45.461428 -138.205972)
		(width 0.1651)
		(layer "In15.Cu")
		(net "CLK_100M_DB2000QL_NIC0_R_DN")
	)
	(segment
		(start 53.1876 -139.573)
		(end 52.0192 -138.4046)
		(width 0.1651)
		(layer "In15.Cu")
		(net "CLK_100M_DB2000QL_NIC0_R_DN")
	)
	(segment
		(start 52.0192 -138.4046)
		(end 50.3936 -138.4046)
		(width 0.1651)
		(layer "In15.Cu")
		(net "CLK_100M_DB2000QL_NIC0_R_DN")
	)
	(segment
		(start 53.8734 -143.4084)
		(end 53.1876 -142.7226)
		(width 0.1651)
		(layer "In15.Cu")
		(net "CLK_100M_DB2000QL_NIC0_R_DN")
	)
	(segment
		(start 111.6584 -184.785)
		(end 110.534196 -185.909204)
		(width 0.1651)
		(layer "In15.Cu")
		(net "CLK_100M_DB2000QL_NIC0_R_DN")
	)
	(segment
		(start 44.721272 -138.205972)
		(end 44.430442 -138.496802)
		(width 0.1651)
		(layer "In15.Cu")
		(net "CLK_100M_DB2000QL_NIC0_R_DN")
	)
	(segment
		(start 134.534656 -168.670224)
		(end 134.243826 -168.961054)
		(width 0.1651)
		(layer "In15.Cu")
		(net "CLK_100M_DB2000QL_NIC0_R_DN")
	)
	(segment
		(start 134.243826 -168.961054)
		(end 134.243826 -169.565574)
		(width 0.1651)
		(layer "In15.Cu")
		(net "CLK_100M_DB2000QL_NIC0_R_DN")
	)
	(segment
		(start 49.7586 -137.7696)
		(end 45.8978 -137.7696)
		(width 0.1651)
		(layer "In15.Cu")
		(net "CLK_100M_DB2000QL_NIC0_R_DN")
	)
	(segment
		(start 125.349 -170.2562)
		(end 122.0724 -173.5328)
		(width 0.1651)
		(layer "In15.Cu")
		(net "CLK_100M_DB2000QL_NIC0_R_DN")
	)
	(segment
		(start 122.0724 -173.5328)
		(end 122.0724 -183.0578)
		(width 0.1651)
		(layer "In15.Cu")
		(net "CLK_100M_DB2000QL_NIC0_R_DN")
	)
	(segment
		(start 45.461428 -138.205972)
		(end 44.721272 -138.205972)
		(width 0.1651)
		(layer "In15.Cu")
		(net "CLK_100M_DB2000QL_NIC0_R_DN")
	)
	(segment
		(start 120.3452 -184.785)
		(end 111.6584 -184.785)
		(width 0.1651)
		(layer "In15.Cu")
		(net "CLK_100M_DB2000QL_NIC0_R_DN")
	)
	(segment
		(start 103.385112 -184.665112)
		(end 83.82 -165.1)
		(width 0.1651)
		(layer "In15.Cu")
		(net "CLK_100M_DB2000QL_NIC0_R_DN")
	)
	(segment
		(start 133.5532 -170.2562)
		(end 125.349 -170.2562)
		(width 0.1651)
		(layer "In15.Cu")
		(net "CLK_100M_DB2000QL_NIC0_R_DN")
	)
	(segment
		(start 53.8734 -162.0774)
		(end 53.8734 -143.4084)
		(width 0.1651)
		(layer "In15.Cu")
		(net "CLK_100M_DB2000QL_NIC0_R_DN")
	)
	(via
		(at 97.347786 -377.899168)
		(size 0.6604)
		(drill 0.3302)
		(layers "F.Cu" "B.Cu")
		(net "SMB_GPU_2_SDA")
	)
	(segment
		(start 97.347786 -377.899168)
		(end 97.347786 -376.908314)
		(width 0.13208)
		(layer "B.Cu")
		(net "SMB_GPU_2_SDA")
	)
	(segment
		(start 97.347786 -376.908314)
		(end 97.767394 -376.488706)
		(width 0.13208)
		(layer "B.Cu")
		(net "SMB_GPU_2_SDA")
	)
	(segment
		(start 89.509854 -378.290074)
		(end 90.3732 -377.426728)
		(width 0.13208)
		(layer "B.Cu")
		(net "SMB_GPU_2_SDA")
	)
	(segment
		(start 97.767394 -376.488706)
		(end 98.5012 -376.488706)
		(width 0.13208)
		(layer "B.Cu")
		(net "SMB_GPU_2_SDA")
	)
	(segment
		(start 90.3732 -377.426728)
		(end 96.875346 -377.426728)
		(width 0.13208)
		(layer "B.Cu")
		(net "SMB_GPU_2_SDA")
	)
	(segment
		(start 96.875346 -377.426728)
		(end 97.347786 -377.899168)
		(width 0.13208)
		(layer "B.Cu")
		(net "SMB_GPU_2_SDA")
	)
	(segment
		(start 431.366168 -77.206348)
		(end 431.366168 -77.889608)
		(width 0.4572)
		(layer "F.Cu")
		(net "P3V3_NIC7")
	)
	(segment
		(start 449.830444 -120.79224)
		(end 449.21805 -120.79224)
		(width 0.4572)
		(layer "F.Cu")
		(net "P3V3_NIC7")
	)
	(segment
		(start 218.80195 -195.072)
		(end 218.313 -195.072)
		(width 0.3556)
		(layer "F.Cu")
		(net "P3V3_NIC7")
	)
	(segment
		(start 412.37789 -113.251742)
		(end 412.988252 -113.251742)
		(width 0.4572)
		(layer "F.Cu")
		(net "P3V3_NIC7")
	)
	(segment
		(start 431.466498 -77.989938)
		(end 431.466498 -79.463646)
		(width 0.4572)
		(layer "F.Cu")
		(net "P3V3_NIC7")
	)
	(segment
		(start 411.108652 -157.680152)
		(end 411.108652 -157.045152)
		(width 0.4064)
		(layer "F.Cu")
		(net "P3V3_NIC7")
	)
	(segment
		(start 427.614842 -79.18196)
		(end 428.27321 -79.18196)
		(width 0.4572)
		(layer "F.Cu")
		(net "P3V3_NIC7")
	)
	(segment
		(start 406.895046 -100.766372)
		(end 406.279858 -100.766372)
		(width 0.4064)
		(layer "F.Cu")
		(net "P3V3_NIC7")
	)
	(segment
		(start 218.313 -195.072)
		(end 217.764106 -194.523106)
		(width 0.3556)
		(layer "F.Cu")
		(net "P3V3_NIC7")
	)
	(segment
		(start 217.764106 -194.523106)
		(end 216.991946 -194.523106)
		(width 0.3556)
		(layer "F.Cu")
		(net "P3V3_NIC7")
	)
	(segment
		(start 431.366168 -77.889608)
		(end 431.466498 -77.989938)
		(width 0.4572)
		(layer "F.Cu")
		(net "P3V3_NIC7")
	)
	(segment
		(start 219.60205 -192.024)
		(end 219.60205 -193.04)
		(width 0.381)
		(layer "F.Cu")
		(net "P3V3_NIC7")
	)
	(segment
		(start 219.60205 -191.614044)
		(end 219.60205 -192.024)
		(width 0.381)
		(layer "F.Cu")
		(net "P3V3_NIC7")
	)
	(segment
		(start 219.314522 -191.326516)
		(end 219.60205 -191.614044)
		(width 0.381)
		(layer "F.Cu")
		(net "P3V3_NIC7")
	)
	(segment
		(start 219.60205 -193.04)
		(end 219.60205 -194.056)
		(width 0.381)
		(layer "F.Cu")
		(net "P3V3_NIC7")
	)
	(segment
		(start 218.80195 -195.707)
		(end 218.80195 -195.072)
		(width 0.4572)
		(layer "F.Cu")
		(net "P3V3_NIC7")
	)
	(segment
		(start 447.675762 -119.477028)
		(end 448.285362 -119.477028)
		(width 0.4572)
		(layer "F.Cu")
		(net "P3V3_NIC7")
	)
	(via
		(at 426.851572 -97.005648)
		(size 0.508)
		(drill 0.254)
		(layers "F.Cu" "B.Cu")
		(net "P3V3_NIC7")
	)
	(via
		(at 224.360486 -169.318432)
		(size 0.508)
		(drill 0.254)
		(layers "F.Cu" "B.Cu")
		(net "P3V3_NIC7")
	)
	(via
		(at 441.362084 -121.847102)
		(size 0.508)
		(drill 0.254)
		(layers "F.Cu" "B.Cu")
		(net "P3V3_NIC7")
	)
	(via
		(at 439.801508 -121.171462)
		(size 0.508)
		(drill 0.254)
		(layers "F.Cu" "B.Cu")
		(net "P3V3_NIC7")
	)
	(via
		(at 439.166508 -121.171462)
		(size 0.508)
		(drill 0.254)
		(layers "F.Cu" "B.Cu")
		(net "P3V3_NIC7")
	)
	(via
		(at 426.851572 -95.989648)
		(size 0.508)
		(drill 0.254)
		(layers "F.Cu" "B.Cu")
		(net "P3V3_NIC7")
	)
	(via
		(at 440.677808 -121.086118)
		(size 0.508)
		(drill 0.254)
		(layers "F.Cu" "B.Cu")
		(net "P3V3_NIC7")
	)
	(via
		(at 431.366168 -77.206348)
		(size 0.508)
		(drill 0.254)
		(layers "F.Cu" "B.Cu")
		(net "P3V3_NIC7")
	)
	(via
		(at 422.800018 -115.360958)
		(size 0.508)
		(drill 0.254)
		(layers "F.Cu" "B.Cu")
		(net "P3V3_NIC7")
	)
	(via
		(at 418.861494 -85.482684)
		(size 0.6604)
		(drill 0.3302)
		(layers "F.Cu" "B.Cu")
		(net "P3V3_NIC7")
	)
	(via
		(at 423.435018 -114.725958)
		(size 0.508)
		(drill 0.254)
		(layers "F.Cu" "B.Cu")
		(net "P3V3_NIC7")
	)
	(via
		(at 418.137086 -112.421924)
		(size 0.508)
		(drill 0.254)
		(layers "F.Cu" "B.Cu")
		(net "P3V3_NIC7")
	)
	(via
		(at 438.13222 -121.557034)
		(size 0.508)
		(drill 0.254)
		(layers "F.Cu" "B.Cu")
		(net "P3V3_NIC7")
	)
	(via
		(at 412.988252 -113.251742)
		(size 0.508)
		(drill 0.254)
		(layers "F.Cu" "B.Cu")
		(net "P3V3_NIC7")
	)
	(via
		(at 449.21805 -120.79224)
		(size 0.508)
		(drill 0.254)
		(layers "F.Cu" "B.Cu")
		(net "P3V3_NIC7")
	)
	(via
		(at 440.185556 -117.36324)
		(size 0.508)
		(drill 0.254)
		(layers "F.Cu" "B.Cu")
		(net "P3V3_NIC7")
	)
	(via
		(at 406.466548 -121.812558)
		(size 0.6604)
		(drill 0.3302)
		(layers "F.Cu" "B.Cu")
		(net "P3V3_NIC7")
	)
	(via
		(at 423.435018 -115.360958)
		(size 0.508)
		(drill 0.254)
		(layers "F.Cu" "B.Cu")
		(net "P3V3_NIC7")
	)
	(via
		(at 410.86913 -101.510592)
		(size 0.6604)
		(drill 0.3302)
		(layers "F.Cu" "B.Cu")
		(net "P3V3_NIC7")
	)
	(via
		(at 218.80195 -195.707)
		(size 0.508)
		(drill 0.254)
		(layers "F.Cu" "B.Cu")
		(net "P3V3_NIC7")
	)
	(via
		(at 438.13222 -120.287034)
		(size 0.508)
		(drill 0.254)
		(layers "F.Cu" "B.Cu")
		(net "P3V3_NIC7")
	)
	(via
		(at 441.362084 -121.212102)
		(size 0.508)
		(drill 0.254)
		(layers "F.Cu" "B.Cu")
		(net "P3V3_NIC7")
	)
	(via
		(at 418.039804 -113.437924)
		(size 0.508)
		(drill 0.254)
		(layers "F.Cu" "B.Cu")
		(net "P3V3_NIC7")
	)
	(via
		(at 438.13222 -120.922034)
		(size 0.508)
		(drill 0.254)
		(layers "F.Cu" "B.Cu")
		(net "P3V3_NIC7")
	)
	(via
		(at 439.423556 -117.36324)
		(size 0.508)
		(drill 0.254)
		(layers "F.Cu" "B.Cu")
		(net "P3V3_NIC7")
	)
	(via
		(at 438.13222 -122.192034)
		(size 0.508)
		(drill 0.254)
		(layers "F.Cu" "B.Cu")
		(net "P3V3_NIC7")
	)
	(via
		(at 406.279858 -100.766372)
		(size 0.508)
		(drill 0.254)
		(layers "F.Cu" "B.Cu")
		(net "P3V3_NIC7")
	)
	(via
		(at 448.285362 -119.477028)
		(size 0.508)
		(drill 0.254)
		(layers "F.Cu" "B.Cu")
		(net "P3V3_NIC7")
	)
	(via
		(at 428.27321 -79.18196)
		(size 0.508)
		(drill 0.254)
		(layers "F.Cu" "B.Cu")
		(net "P3V3_NIC7")
	)
	(via
		(at 440.677808 -121.721118)
		(size 0.508)
		(drill 0.254)
		(layers "F.Cu" "B.Cu")
		(net "P3V3_NIC7")
	)
	(via
		(at 422.800018 -114.725958)
		(size 0.508)
		(drill 0.254)
		(layers "F.Cu" "B.Cu")
		(net "P3V3_NIC7")
	)
	(via
		(at 413.314896 -163.386008)
		(size 0.508)
		(drill 0.254)
		(layers "F.Cu" "B.Cu")
		(net "P3V3_NIC7")
	)
	(via
		(at 219.314522 -191.326516)
		(size 0.508)
		(drill 0.254)
		(layers "F.Cu" "B.Cu")
		(net "P3V3_NIC7")
	)
	(via
		(at 411.108652 -157.045152)
		(size 0.508)
		(drill 0.254)
		(layers "F.Cu" "B.Cu")
		(net "P3V3_NIC7")
	)
	(via
		(at 431.59807 -93.688916)
		(size 0.6604)
		(drill 0.3302)
		(layers "F.Cu" "B.Cu")
		(net "P3V3_NIC7")
	)
	(via
		(at 426.851572 -101.069648)
		(size 0.508)
		(drill 0.254)
		(layers "F.Cu" "B.Cu")
		(net "P3V3_NIC7")
	)
	(segment
		(start 426.241972 -95.989648)
		(end 426.851572 -95.989648)
		(width 0.4572)
		(layer "B.Cu")
		(net "P3V3_NIC7")
	)
	(segment
		(start 417.372292 -112.421924)
		(end 418.137086 -112.421924)
		(width 0.4572)
		(layer "B.Cu")
		(net "P3V3_NIC7")
	)
	(segment
		(start 417.372292 -113.437924)
		(end 418.039804 -113.437924)
		(width 0.4572)
		(layer "B.Cu")
		(net "P3V3_NIC7")
	)
	(segment
		(start 426.241972 -101.069648)
		(end 426.851572 -101.069648)
		(width 0.4572)
		(layer "B.Cu")
		(net "P3V3_NIC7")
	)
	(segment
		(start 426.241972 -97.005648)
		(end 426.851572 -97.005648)
		(width 0.4572)
		(layer "B.Cu")
		(net "P3V3_NIC7")
	)
	(segment
		(start 409.381452 -114.864642)
		(end 410.994352 -113.251742)
		(width 0.508)
		(layer "In5.Cu")
		(net "P3V3_NIC7")
	)
	(segment
		(start 411.108652 -142.38859)
		(end 409.381452 -140.66139)
		(width 0.508)
		(layer "In5.Cu")
		(net "P3V3_NIC7")
	)
	(segment
		(start 411.108652 -157.045152)
		(end 413.314896 -162.371532)
		(width 0.508)
		(layer "In5.Cu")
		(net "P3V3_NIC7")
	)
	(segment
		(start 410.994352 -113.251742)
		(end 412.988252 -113.251742)
		(width 0.508)
		(layer "In5.Cu")
		(net "P3V3_NIC7")
	)
	(segment
		(start 413.314896 -162.371532)
		(end 413.314896 -163.386008)
		(width 0.508)
		(layer "In5.Cu")
		(net "P3V3_NIC7")
	)
	(segment
		(start 409.381452 -140.66139)
		(end 409.381452 -114.864642)
		(width 0.508)
		(layer "In5.Cu")
		(net "P3V3_NIC7")
	)
	(segment
		(start 411.108652 -157.045152)
		(end 411.108652 -142.38859)
		(width 0.508)
		(layer "In5.Cu")
		(net "P3V3_NIC7")
	)
	(segment
		(start 225.862134 -176.837848)
		(end 225.862134 -172.651928)
		(width 0.508)
		(layer "In9.Cu")
		(net "P3V3_NIC7")
	)
	(segment
		(start 218.80195 -195.707)
		(end 218.80195 -194.945)
		(width 0.508)
		(layer "In9.Cu")
		(net "P3V3_NIC7")
	)
	(segment
		(start 219.935552 -190.705486)
		(end 219.935552 -187.446666)
		(width 0.508)
		(layer "In9.Cu")
		(net "P3V3_NIC7")
	)
	(segment
		(start 224.360486 -171.125388)
		(end 224.360486 -169.318432)
		(width 0.508)
		(layer "In9.Cu")
		(net "P3V3_NIC7")
	)
	(segment
		(start 223.397318 -181.17947)
		(end 222.986854 -180.769006)
		(width 0.508)
		(layer "In9.Cu")
		(net "P3V3_NIC7")
	)
	(segment
		(start 218.80195 -194.945)
		(end 218.973146 -194.773804)
		(width 0.508)
		(layer "In9.Cu")
		(net "P3V3_NIC7")
	)
	(segment
		(start 218.973146 -191.667892)
		(end 219.314522 -191.326516)
		(width 0.508)
		(layer "In9.Cu")
		(net "P3V3_NIC7")
	)
	(segment
		(start 222.986854 -180.769006)
		(end 222.986854 -180.221382)
		(width 0.508)
		(layer "In9.Cu")
		(net "P3V3_NIC7")
	)
	(segment
		(start 224.362772 -171.149264)
		(end 224.362772 -171.127674)
		(width 0.508)
		(layer "In9.Cu")
		(net "P3V3_NIC7")
	)
	(segment
		(start 223.824038 -178.875944)
		(end 225.862134 -176.837848)
		(width 0.508)
		(layer "In9.Cu")
		(net "P3V3_NIC7")
	)
	(segment
		(start 223.397318 -183.9849)
		(end 223.397318 -181.17947)
		(width 0.508)
		(layer "In9.Cu")
		(net "P3V3_NIC7")
	)
	(segment
		(start 219.935552 -187.446666)
		(end 223.397318 -183.9849)
		(width 0.508)
		(layer "In9.Cu")
		(net "P3V3_NIC7")
	)
	(segment
		(start 224.378012 -171.167806)
		(end 224.378012 -171.164504)
		(width 0.508)
		(layer "In9.Cu")
		(net "P3V3_NIC7")
	)
	(segment
		(start 223.824038 -179.384198)
		(end 223.824038 -178.875944)
		(width 0.508)
		(layer "In9.Cu")
		(net "P3V3_NIC7")
	)
	(segment
		(start 219.314522 -191.326516)
		(end 219.935552 -190.705486)
		(width 0.508)
		(layer "In9.Cu")
		(net "P3V3_NIC7")
	)
	(segment
		(start 225.862134 -172.651928)
		(end 224.378012 -171.167806)
		(width 0.508)
		(layer "In9.Cu")
		(net "P3V3_NIC7")
	)
	(segment
		(start 222.986854 -180.221382)
		(end 223.824038 -179.384198)
		(width 0.508)
		(layer "In9.Cu")
		(net "P3V3_NIC7")
	)
	(segment
		(start 224.378012 -171.164504)
		(end 224.362772 -171.149264)
		(width 0.508)
		(layer "In9.Cu")
		(net "P3V3_NIC7")
	)
	(segment
		(start 218.973146 -194.773804)
		(end 218.973146 -191.667892)
		(width 0.508)
		(layer "In9.Cu")
		(net "P3V3_NIC7")
	)
	(segment
		(start 224.362772 -171.127674)
		(end 224.360486 -171.125388)
		(width 0.508)
		(layer "In9.Cu")
		(net "P3V3_NIC7")
	)
	(segment
		(start 411.004004 -174.8536)
		(end 409.000706 -174.8536)
		(width 0.15494)
		(layer "In13.Cu")
		(net "P3V3_NIC7")
	)
	(segment
		(start 340.378796 -157.0736)
		(end 311.460896 -157.0736)
		(width 0.15494)
		(layer "In13.Cu")
		(net "P3V3_NIC7")
	)
	(segment
		(start 355.058726 -160.505394)
		(end 354.45827 -159.904938)
		(width 0.15494)
		(layer "In13.Cu")
		(net "P3V3_NIC7")
	)
	(segment
		(start 296.510456 -172.802804)
		(end 296.032174 -173.281086)
		(width 0.15494)
		(layer "In13.Cu")
		(net "P3V3_NIC7")
	)
	(segment
		(start 400.805396 -163.386008)
		(end 391.510012 -163.386008)
		(width 0.15494)
		(layer "In13.Cu")
		(net "P3V3_NIC7")
	)
	(segment
		(start 391.510012 -163.386008)
		(end 387.754368 -159.630364)
		(width 0.15494)
		(layer "In13.Cu")
		(net "P3V3_NIC7")
	)
	(segment
		(start 413.314896 -172.542708)
		(end 411.004004 -174.8536)
		(width 0.15494)
		(layer "In13.Cu")
		(net "P3V3_NIC7")
	)
	(segment
		(start 405.589994 -168.170606)
		(end 400.805396 -163.386008)
		(width 0.15494)
		(layer "In13.Cu")
		(net "P3V3_NIC7")
	)
	(segment
		(start 283.195268 -166.26459)
		(end 280.47188 -163.541202)
		(width 0.15494)
		(layer "In13.Cu")
		(net "P3V3_NIC7")
	)
	(segment
		(start 361.233212 -160.984692)
		(end 360.551984 -160.303464)
		(width 0.15494)
		(layer "In13.Cu")
		(net "P3V3_NIC7")
	)
	(segment
		(start 259.291582 -167.056308)
		(end 229.791768 -167.056308)
		(width 0.15494)
		(layer "In13.Cu")
		(net "P3V3_NIC7")
	)
	(segment
		(start 405.589994 -171.442888)
		(end 405.589994 -168.170606)
		(width 0.15494)
		(layer "In13.Cu")
		(net "P3V3_NIC7")
	)
	(segment
		(start 343.375996 -157.743906)
		(end 342.19134 -156.55925)
		(width 0.15494)
		(layer "In13.Cu")
		(net "P3V3_NIC7")
	)
	(segment
		(start 342.19134 -156.55925)
		(end 340.893146 -156.55925)
		(width 0.15494)
		(layer "In13.Cu")
		(net "P3V3_NIC7")
	)
	(segment
		(start 368.981736 -163.775136)
		(end 364.003844 -163.775136)
		(width 0.15494)
		(layer "In13.Cu")
		(net "P3V3_NIC7")
	)
	(segment
		(start 364.003844 -163.775136)
		(end 361.233212 -161.004504)
		(width 0.15494)
		(layer "In13.Cu")
		(net "P3V3_NIC7")
	)
	(segment
		(start 357.090472 -160.303464)
		(end 356.888542 -160.505394)
		(width 0.15494)
		(layer "In13.Cu")
		(net "P3V3_NIC7")
	)
	(segment
		(start 280.47188 -163.541202)
		(end 276.924008 -163.541202)
		(width 0.15494)
		(layer "In13.Cu")
		(net "P3V3_NIC7")
	)
	(segment
		(start 373.126508 -159.630364)
		(end 368.981736 -163.775136)
		(width 0.15494)
		(layer "In13.Cu")
		(net "P3V3_NIC7")
	)
	(segment
		(start 225.053906 -168.462452)
		(end 224.360486 -169.155872)
		(width 0.15494)
		(layer "In13.Cu")
		(net "P3V3_NIC7")
	)
	(segment
		(start 361.233212 -161.004504)
		(end 361.233212 -160.984692)
		(width 0.15494)
		(layer "In13.Cu")
		(net "P3V3_NIC7")
	)
	(segment
		(start 228.385624 -168.462452)
		(end 225.053906 -168.462452)
		(width 0.15494)
		(layer "In13.Cu")
		(net "P3V3_NIC7")
	)
	(segment
		(start 286.259778 -166.26459)
		(end 283.195268 -166.26459)
		(width 0.15494)
		(layer "In13.Cu")
		(net "P3V3_NIC7")
	)
	(segment
		(start 276.924008 -163.541202)
		(end 272.922492 -159.539686)
		(width 0.15494)
		(layer "In13.Cu")
		(net "P3V3_NIC7")
	)
	(segment
		(start 360.551984 -160.303464)
		(end 357.090472 -160.303464)
		(width 0.15494)
		(layer "In13.Cu")
		(net "P3V3_NIC7")
	)
	(segment
		(start 340.893146 -156.55925)
		(end 340.378796 -157.0736)
		(width 0.15494)
		(layer "In13.Cu")
		(net "P3V3_NIC7")
	)
	(segment
		(start 311.460896 -157.0736)
		(end 296.510456 -172.02404)
		(width 0.15494)
		(layer "In13.Cu")
		(net "P3V3_NIC7")
	)
	(segment
		(start 296.510456 -172.02404)
		(end 296.510456 -172.802804)
		(width 0.15494)
		(layer "In13.Cu")
		(net "P3V3_NIC7")
	)
	(segment
		(start 387.754368 -159.630364)
		(end 373.126508 -159.630364)
		(width 0.15494)
		(layer "In13.Cu")
		(net "P3V3_NIC7")
	)
	(segment
		(start 354.45827 -158.479236)
		(end 353.72294 -157.743906)
		(width 0.15494)
		(layer "In13.Cu")
		(net "P3V3_NIC7")
	)
	(segment
		(start 356.888542 -160.505394)
		(end 355.058726 -160.505394)
		(width 0.15494)
		(layer "In13.Cu")
		(net "P3V3_NIC7")
	)
	(segment
		(start 272.922492 -159.539686)
		(end 266.808204 -159.539686)
		(width 0.15494)
		(layer "In13.Cu")
		(net "P3V3_NIC7")
	)
	(segment
		(start 293.276274 -173.281086)
		(end 286.259778 -166.26459)
		(width 0.15494)
		(layer "In13.Cu")
		(net "P3V3_NIC7")
	)
	(segment
		(start 354.45827 -159.904938)
		(end 354.45827 -158.479236)
		(width 0.15494)
		(layer "In13.Cu")
		(net "P3V3_NIC7")
	)
	(segment
		(start 266.808204 -159.539686)
		(end 259.291582 -167.056308)
		(width 0.15494)
		(layer "In13.Cu")
		(net "P3V3_NIC7")
	)
	(segment
		(start 353.72294 -157.743906)
		(end 343.375996 -157.743906)
		(width 0.15494)
		(layer "In13.Cu")
		(net "P3V3_NIC7")
	)
	(segment
		(start 409.000706 -174.8536)
		(end 405.589994 -171.442888)
		(width 0.15494)
		(layer "In13.Cu")
		(net "P3V3_NIC7")
	)
	(segment
		(start 229.791768 -167.056308)
		(end 228.385624 -168.462452)
		(width 0.15494)
		(layer "In13.Cu")
		(net "P3V3_NIC7")
	)
	(segment
		(start 413.314896 -163.386008)
		(end 413.314896 -172.542708)
		(width 0.15494)
		(layer "In13.Cu")
		(net "P3V3_NIC7")
	)
	(segment
		(start 224.360486 -169.155872)
		(end 224.360486 -169.318432)
		(width 0.15494)
		(layer "In13.Cu")
		(net "P3V3_NIC7")
	)
	(segment
		(start 296.032174 -173.281086)
		(end 293.276274 -173.281086)
		(width 0.15494)
		(layer "In13.Cu")
		(net "P3V3_NIC7")
	)
	(segment
		(start 140.837158 -174.51832)
		(end 141.717014 -174.51832)
		(width 0.13462)
		(layer "F.Cu")
		(net "CLK_100M_DB2000QL_NIC2_R_DN")
	)
	(segment
		(start 161.682176 -138.364976)
		(end 162.14217 -138.364976)
		(width 0.13462)
		(layer "F.Cu")
		(net "CLK_100M_DB2000QL_NIC2_R_DN")
	)
	(segment
		(start 161.519362 -138.202162)
		(end 161.682176 -138.364976)
		(width 0.13462)
		(layer "F.Cu")
		(net "CLK_100M_DB2000QL_NIC2_R_DN")
	)
	(segment
		(start 160.530286 -138.496802)
		(end 160.824926 -138.202162)
		(width 0.13462)
		(layer "F.Cu")
		(net "CLK_100M_DB2000QL_NIC2_R_DN")
	)
	(segment
		(start 160.824926 -138.202162)
		(end 161.519362 -138.202162)
		(width 0.13462)
		(layer "F.Cu")
		(net "CLK_100M_DB2000QL_NIC2_R_DN")
	)
	(segment
		(start 141.717014 -174.51832)
		(end 142.00378 -174.805086)
		(width 0.13462)
		(layer "F.Cu")
		(net "CLK_100M_DB2000QL_NIC2_R_DN")
	)
	(segment
		(start 140.474192 -174.881286)
		(end 140.837158 -174.51832)
		(width 0.13462)
		(layer "F.Cu")
		(net "CLK_100M_DB2000QL_NIC2_R_DN")
	)
	(via
		(at 160.530286 -138.496802)
		(size 0.508)
		(drill 0.254)
		(layers "F.Cu" "B.Cu")
		(net "CLK_100M_DB2000QL_NIC2_R_DN")
	)
	(via
		(at 142.00378 -174.805086)
		(size 0.508)
		(drill 0.254)
		(layers "F.Cu" "B.Cu")
		(net "CLK_100M_DB2000QL_NIC2_R_DN")
	)
	(segment
		(start 148.647404 -173.433994)
		(end 148.647404 -171.100242)
		(width 0.1651)
		(layer "In15.Cu")
		(net "CLK_100M_DB2000QL_NIC2_R_DN")
	)
	(segment
		(start 148.794724 -157.630622)
		(end 148.64969 -157.485588)
		(width 0.1651)
		(layer "In15.Cu")
		(net "CLK_100M_DB2000QL_NIC2_R_DN")
	)
	(segment
		(start 150.789894 -152.885902)
		(end 148.794724 -152.885902)
		(width 0.1651)
		(layer "In15.Cu")
		(net "CLK_100M_DB2000QL_NIC2_R_DN")
	)
	(segment
		(start 150.847552 -157.630622)
		(end 148.794724 -157.630622)
		(width 0.1651)
		(layer "In15.Cu")
		(net "CLK_100M_DB2000QL_NIC2_R_DN")
	)
	(segment
		(start 148.64969 -166.353236)
		(end 148.794724 -166.208202)
		(width 0.1651)
		(layer "In15.Cu")
		(net "CLK_100M_DB2000QL_NIC2_R_DN")
	)
	(segment
		(start 150.789894 -154.346402)
		(end 151.097742 -154.038554)
		(width 0.1651)
		(layer "In15.Cu")
		(net "CLK_100M_DB2000QL_NIC2_R_DN")
	)
	(segment
		(start 151.0792 -160.31083)
		(end 150.771352 -160.002982)
		(width 0.1651)
		(layer "In15.Cu")
		(net "CLK_100M_DB2000QL_NIC2_R_DN")
	)
	(segment
		(start 148.794724 -168.580562)
		(end 150.796752 -168.580562)
		(width 0.1651)
		(layer "In15.Cu")
		(net "CLK_100M_DB2000QL_NIC2_R_DN")
	)
	(segment
		(start 150.881842 -144.272)
		(end 156.104844 -144.272)
		(width 0.1651)
		(layer "In15.Cu")
		(net "CLK_100M_DB2000QL_NIC2_R_DN")
	)
	(segment
		(start 148.794724 -163.835842)
		(end 150.771352 -163.835842)
		(width 0.1651)
		(layer "In15.Cu")
		(net "CLK_100M_DB2000QL_NIC2_R_DN")
	)
	(segment
		(start 158.698438 -138.202162)
		(end 160.235646 -138.202162)
		(width 0.1651)
		(layer "In15.Cu")
		(net "CLK_100M_DB2000QL_NIC2_R_DN")
	)
	(segment
		(start 151.0792 -169.80027)
		(end 150.771352 -169.492422)
		(width 0.1651)
		(layer "In15.Cu")
		(net "CLK_100M_DB2000QL_NIC2_R_DN")
	)
	(segment
		(start 148.784056 -160.002982)
		(end 148.64969 -159.868616)
		(width 0.1651)
		(layer "In15.Cu")
		(net "CLK_100M_DB2000QL_NIC2_R_DN")
	)
	(segment
		(start 150.771352 -169.492422)
		(end 148.784056 -169.492422)
		(width 0.1651)
		(layer "In15.Cu")
		(net "CLK_100M_DB2000QL_NIC2_R_DN")
	)
	(segment
		(start 148.794724 -167.120062)
		(end 148.64969 -166.975028)
		(width 0.1651)
		(layer "In15.Cu")
		(net "CLK_100M_DB2000QL_NIC2_R_DN")
	)
	(segment
		(start 150.796752 -168.580562)
		(end 151.1046 -168.272714)
		(width 0.1651)
		(layer "In15.Cu")
		(net "CLK_100M_DB2000QL_NIC2_R_DN")
	)
	(segment
		(start 151.0792 -163.527994)
		(end 151.0792 -162.68319)
		(width 0.1651)
		(layer "In15.Cu")
		(net "CLK_100M_DB2000QL_NIC2_R_DN")
	)
	(segment
		(start 148.647404 -155.110942)
		(end 148.647404 -154.493722)
		(width 0.1651)
		(layer "In15.Cu")
		(net "CLK_100M_DB2000QL_NIC2_R_DN")
	)
	(segment
		(start 148.784056 -169.492422)
		(end 148.64969 -169.358056)
		(width 0.1651)
		(layer "In15.Cu")
		(net "CLK_100M_DB2000QL_NIC2_R_DN")
	)
	(segment
		(start 150.789894 -148.141182)
		(end 148.78812 -148.141182)
		(width 0.1651)
		(layer "In15.Cu")
		(net "CLK_100M_DB2000QL_NIC2_R_DN")
	)
	(segment
		(start 148.784056 -162.375342)
		(end 148.64969 -162.240976)
		(width 0.1651)
		(layer "In15.Cu")
		(net "CLK_100M_DB2000QL_NIC2_R_DN")
	)
	(segment
		(start 148.78812 -148.141182)
		(end 148.6408 -147.993862)
		(width 0.1651)
		(layer "In15.Cu")
		(net "CLK_100M_DB2000QL_NIC2_R_DN")
	)
	(segment
		(start 151.097742 -155.56611)
		(end 150.789894 -155.258262)
		(width 0.1651)
		(layer "In15.Cu")
		(net "CLK_100M_DB2000QL_NIC2_R_DN")
	)
	(segment
		(start 151.0792 -161.155634)
		(end 151.0792 -160.31083)
		(width 0.1651)
		(layer "In15.Cu")
		(net "CLK_100M_DB2000QL_NIC2_R_DN")
	)
	(segment
		(start 156.104844 -144.272)
		(end 157.418532 -142.958312)
		(width 0.1651)
		(layer "In15.Cu")
		(net "CLK_100M_DB2000QL_NIC2_R_DN")
	)
	(segment
		(start 148.64969 -161.608516)
		(end 148.794724 -161.463482)
		(width 0.1651)
		(layer "In15.Cu")
		(net "CLK_100M_DB2000QL_NIC2_R_DN")
	)
	(segment
		(start 150.789894 -156.718762)
		(end 151.097742 -156.410914)
		(width 0.1651)
		(layer "In15.Cu")
		(net "CLK_100M_DB2000QL_NIC2_R_DN")
	)
	(segment
		(start 148.794724 -156.718762)
		(end 150.789894 -156.718762)
		(width 0.1651)
		(layer "In15.Cu")
		(net "CLK_100M_DB2000QL_NIC2_R_DN")
	)
	(segment
		(start 148.64969 -168.725596)
		(end 148.794724 -168.580562)
		(width 0.1651)
		(layer "In15.Cu")
		(net "CLK_100M_DB2000QL_NIC2_R_DN")
	)
	(segment
		(start 157.418532 -142.958312)
		(end 157.418532 -139.482068)
		(width 0.1651)
		(layer "In15.Cu")
		(net "CLK_100M_DB2000QL_NIC2_R_DN")
	)
	(segment
		(start 157.418532 -139.482068)
		(end 158.698438 -138.202162)
		(width 0.1651)
		(layer "In15.Cu")
		(net "CLK_100M_DB2000QL_NIC2_R_DN")
	)
	(segment
		(start 150.796752 -164.747702)
		(end 148.794724 -164.747702)
		(width 0.1651)
		(layer "In15.Cu")
		(net "CLK_100M_DB2000QL_NIC2_R_DN")
	)
	(segment
		(start 148.64969 -159.868616)
		(end 148.64969 -159.236156)
		(width 0.1651)
		(layer "In15.Cu")
		(net "CLK_100M_DB2000QL_NIC2_R_DN")
	)
	(segment
		(start 148.64969 -156.863796)
		(end 148.794724 -156.718762)
		(width 0.1651)
		(layer "In15.Cu")
		(net "CLK_100M_DB2000QL_NIC2_R_DN")
	)
	(segment
		(start 142.00378 -174.805086)
		(end 142.282926 -174.52594)
		(width 0.1651)
		(layer "In15.Cu")
		(net "CLK_100M_DB2000QL_NIC2_R_DN")
	)
	(segment
		(start 148.64969 -157.485588)
		(end 148.64969 -156.863796)
		(width 0.1651)
		(layer "In15.Cu")
		(net "CLK_100M_DB2000QL_NIC2_R_DN")
	)
	(segment
		(start 151.097742 -156.410914)
		(end 151.097742 -155.56611)
		(width 0.1651)
		(layer "In15.Cu")
		(net "CLK_100M_DB2000QL_NIC2_R_DN")
	)
	(segment
		(start 151.097742 -154.038554)
		(end 151.097742 -153.19375)
		(width 0.1651)
		(layer "In15.Cu")
		(net "CLK_100M_DB2000QL_NIC2_R_DN")
	)
	(segment
		(start 150.771352 -170.952922)
		(end 151.0792 -170.645074)
		(width 0.1651)
		(layer "In15.Cu")
		(net "CLK_100M_DB2000QL_NIC2_R_DN")
	)
	(segment
		(start 150.771352 -162.375342)
		(end 148.784056 -162.375342)
		(width 0.1651)
		(layer "In15.Cu")
		(net "CLK_100M_DB2000QL_NIC2_R_DN")
	)
	(segment
		(start 151.1046 -167.42791)
		(end 150.796752 -167.120062)
		(width 0.1651)
		(layer "In15.Cu")
		(net "CLK_100M_DB2000QL_NIC2_R_DN")
	)
	(segment
		(start 148.647404 -154.493722)
		(end 148.794724 -154.346402)
		(width 0.1651)
		(layer "In15.Cu")
		(net "CLK_100M_DB2000QL_NIC2_R_DN")
	)
	(segment
		(start 150.771352 -163.835842)
		(end 151.0792 -163.527994)
		(width 0.1651)
		(layer "In15.Cu")
		(net "CLK_100M_DB2000QL_NIC2_R_DN")
	)
	(segment
		(start 150.789894 -155.258262)
		(end 148.794724 -155.258262)
		(width 0.1651)
		(layer "In15.Cu")
		(net "CLK_100M_DB2000QL_NIC2_R_DN")
	)
	(segment
		(start 151.097742 -150.82139)
		(end 150.789894 -150.513542)
		(width 0.1651)
		(layer "In15.Cu")
		(net "CLK_100M_DB2000QL_NIC2_R_DN")
	)
	(segment
		(start 148.647404 -150.366222)
		(end 148.647404 -149.749002)
		(width 0.1651)
		(layer "In15.Cu")
		(net "CLK_100M_DB2000QL_NIC2_R_DN")
	)
	(segment
		(start 150.771352 -161.463482)
		(end 151.0792 -161.155634)
		(width 0.1651)
		(layer "In15.Cu")
		(net "CLK_100M_DB2000QL_NIC2_R_DN")
	)
	(segment
		(start 148.794724 -149.601682)
		(end 150.789894 -149.601682)
		(width 0.1651)
		(layer "In15.Cu")
		(net "CLK_100M_DB2000QL_NIC2_R_DN")
	)
	(segment
		(start 148.794724 -159.091122)
		(end 150.847552 -159.091122)
		(width 0.1651)
		(layer "In15.Cu")
		(net "CLK_100M_DB2000QL_NIC2_R_DN")
	)
	(segment
		(start 148.794724 -155.258262)
		(end 148.647404 -155.110942)
		(width 0.1651)
		(layer "In15.Cu")
		(net "CLK_100M_DB2000QL_NIC2_R_DN")
	)
	(segment
		(start 148.794724 -152.885902)
		(end 148.647404 -152.738582)
		(width 0.1651)
		(layer "In15.Cu")
		(net "CLK_100M_DB2000QL_NIC2_R_DN")
	)
	(segment
		(start 148.794724 -150.513542)
		(end 148.647404 -150.366222)
		(width 0.1651)
		(layer "In15.Cu")
		(net "CLK_100M_DB2000QL_NIC2_R_DN")
	)
	(segment
		(start 150.789894 -151.974042)
		(end 151.097742 -151.666194)
		(width 0.1651)
		(layer "In15.Cu")
		(net "CLK_100M_DB2000QL_NIC2_R_DN")
	)
	(segment
		(start 148.64969 -159.236156)
		(end 148.794724 -159.091122)
		(width 0.1651)
		(layer "In15.Cu")
		(net "CLK_100M_DB2000QL_NIC2_R_DN")
	)
	(segment
		(start 150.796752 -166.208202)
		(end 151.1046 -165.900354)
		(width 0.1651)
		(layer "In15.Cu")
		(net "CLK_100M_DB2000QL_NIC2_R_DN")
	)
	(segment
		(start 151.097742 -153.19375)
		(end 150.789894 -152.885902)
		(width 0.1651)
		(layer "In15.Cu")
		(net "CLK_100M_DB2000QL_NIC2_R_DN")
	)
	(segment
		(start 150.789894 -149.601682)
		(end 151.097742 -149.293834)
		(width 0.1651)
		(layer "In15.Cu")
		(net "CLK_100M_DB2000QL_NIC2_R_DN")
	)
	(segment
		(start 148.64969 -164.602668)
		(end 148.64969 -163.980876)
		(width 0.1651)
		(layer "In15.Cu")
		(net "CLK_100M_DB2000QL_NIC2_R_DN")
	)
	(segment
		(start 148.6408 -146.513042)
		(end 150.881842 -144.272)
		(width 0.1651)
		(layer "In15.Cu")
		(net "CLK_100M_DB2000QL_NIC2_R_DN")
	)
	(segment
		(start 151.1554 -157.93847)
		(end 150.847552 -157.630622)
		(width 0.1651)
		(layer "In15.Cu")
		(net "CLK_100M_DB2000QL_NIC2_R_DN")
	)
	(segment
		(start 151.097742 -151.666194)
		(end 151.097742 -150.82139)
		(width 0.1651)
		(layer "In15.Cu")
		(net "CLK_100M_DB2000QL_NIC2_R_DN")
	)
	(segment
		(start 148.794724 -170.952922)
		(end 150.771352 -170.952922)
		(width 0.1651)
		(layer "In15.Cu")
		(net "CLK_100M_DB2000QL_NIC2_R_DN")
	)
	(segment
		(start 151.097742 -149.293834)
		(end 151.097742 -148.44903)
		(width 0.1651)
		(layer "In15.Cu")
		(net "CLK_100M_DB2000QL_NIC2_R_DN")
	)
	(segment
		(start 148.794724 -166.208202)
		(end 150.796752 -166.208202)
		(width 0.1651)
		(layer "In15.Cu")
		(net "CLK_100M_DB2000QL_NIC2_R_DN")
	)
	(segment
		(start 148.647404 -152.121362)
		(end 148.794724 -151.974042)
		(width 0.1651)
		(layer "In15.Cu")
		(net "CLK_100M_DB2000QL_NIC2_R_DN")
	)
	(segment
		(start 151.0792 -170.645074)
		(end 151.0792 -169.80027)
		(width 0.1651)
		(layer "In15.Cu")
		(net "CLK_100M_DB2000QL_NIC2_R_DN")
	)
	(segment
		(start 142.282926 -174.52594)
		(end 147.555458 -174.52594)
		(width 0.1651)
		(layer "In15.Cu")
		(net "CLK_100M_DB2000QL_NIC2_R_DN")
	)
	(segment
		(start 151.1554 -158.783274)
		(end 151.1554 -157.93847)
		(width 0.1651)
		(layer "In15.Cu")
		(net "CLK_100M_DB2000QL_NIC2_R_DN")
	)
	(segment
		(start 148.6408 -147.993862)
		(end 148.6408 -146.513042)
		(width 0.1651)
		(layer "In15.Cu")
		(net "CLK_100M_DB2000QL_NIC2_R_DN")
	)
	(segment
		(start 147.555458 -174.52594)
		(end 148.647404 -173.433994)
		(width 0.1651)
		(layer "In15.Cu")
		(net "CLK_100M_DB2000QL_NIC2_R_DN")
	)
	(segment
		(start 151.1046 -165.900354)
		(end 151.1046 -165.05555)
		(width 0.1651)
		(layer "In15.Cu")
		(net "CLK_100M_DB2000QL_NIC2_R_DN")
	)
	(segment
		(start 151.0792 -162.68319)
		(end 150.771352 -162.375342)
		(width 0.1651)
		(layer "In15.Cu")
		(net "CLK_100M_DB2000QL_NIC2_R_DN")
	)
	(segment
		(start 150.847552 -159.091122)
		(end 151.1554 -158.783274)
		(width 0.1651)
		(layer "In15.Cu")
		(net "CLK_100M_DB2000QL_NIC2_R_DN")
	)
	(segment
		(start 148.64969 -162.240976)
		(end 148.64969 -161.608516)
		(width 0.1651)
		(layer "In15.Cu")
		(net "CLK_100M_DB2000QL_NIC2_R_DN")
	)
	(segment
		(start 150.796752 -167.120062)
		(end 148.794724 -167.120062)
		(width 0.1651)
		(layer "In15.Cu")
		(net "CLK_100M_DB2000QL_NIC2_R_DN")
	)
	(segment
		(start 148.794724 -154.346402)
		(end 150.789894 -154.346402)
		(width 0.1651)
		(layer "In15.Cu")
		(net "CLK_100M_DB2000QL_NIC2_R_DN")
	)
	(segment
		(start 148.647404 -149.749002)
		(end 148.794724 -149.601682)
		(width 0.1651)
		(layer "In15.Cu")
		(net "CLK_100M_DB2000QL_NIC2_R_DN")
	)
	(segment
		(start 148.794724 -151.974042)
		(end 150.789894 -151.974042)
		(width 0.1651)
		(layer "In15.Cu")
		(net "CLK_100M_DB2000QL_NIC2_R_DN")
	)
	(segment
		(start 160.235646 -138.202162)
		(end 160.530286 -138.496802)
		(width 0.1651)
		(layer "In15.Cu")
		(net "CLK_100M_DB2000QL_NIC2_R_DN")
	)
	(segment
		(start 148.647404 -171.100242)
		(end 148.794724 -170.952922)
		(width 0.1651)
		(layer "In15.Cu")
		(net "CLK_100M_DB2000QL_NIC2_R_DN")
	)
	(segment
		(start 151.1046 -168.272714)
		(end 151.1046 -167.42791)
		(width 0.1651)
		(layer "In15.Cu")
		(net "CLK_100M_DB2000QL_NIC2_R_DN")
	)
	(segment
		(start 148.794724 -164.747702)
		(end 148.64969 -164.602668)
		(width 0.1651)
		(layer "In15.Cu")
		(net "CLK_100M_DB2000QL_NIC2_R_DN")
	)
	(segment
		(start 148.64969 -169.358056)
		(end 148.64969 -168.725596)
		(width 0.1651)
		(layer "In15.Cu")
		(net "CLK_100M_DB2000QL_NIC2_R_DN")
	)
	(segment
		(start 151.097742 -148.44903)
		(end 150.789894 -148.141182)
		(width 0.1651)
		(layer "In15.Cu")
		(net "CLK_100M_DB2000QL_NIC2_R_DN")
	)
	(segment
		(start 148.64969 -163.980876)
		(end 148.794724 -163.835842)
		(width 0.1651)
		(layer "In15.Cu")
		(net "CLK_100M_DB2000QL_NIC2_R_DN")
	)
	(segment
		(start 148.647404 -152.738582)
		(end 148.647404 -152.121362)
		(width 0.1651)
		(layer "In15.Cu")
		(net "CLK_100M_DB2000QL_NIC2_R_DN")
	)
	(segment
		(start 151.1046 -165.05555)
		(end 150.796752 -164.747702)
		(width 0.1651)
		(layer "In15.Cu")
		(net "CLK_100M_DB2000QL_NIC2_R_DN")
	)
	(segment
		(start 150.789894 -150.513542)
		(end 148.794724 -150.513542)
		(width 0.1651)
		(layer "In15.Cu")
		(net "CLK_100M_DB2000QL_NIC2_R_DN")
	)
	(segment
		(start 150.771352 -160.002982)
		(end 148.784056 -160.002982)
		(width 0.1651)
		(layer "In15.Cu")
		(net "CLK_100M_DB2000QL_NIC2_R_DN")
	)
	(segment
		(start 148.64969 -166.975028)
		(end 148.64969 -166.353236)
		(width 0.1651)
		(layer "In15.Cu")
		(net "CLK_100M_DB2000QL_NIC2_R_DN")
	)
	(segment
		(start 148.794724 -161.463482)
		(end 150.771352 -161.463482)
		(width 0.1651)
		(layer "In15.Cu")
		(net "CLK_100M_DB2000QL_NIC2_R_DN")
	)
	(via
		(at 218.889834 -222.089472)
		(size 0.6604)
		(drill 0.3302)
		(layers "F.Cu" "B.Cu")
		(net "SMB_BIC_FPGA_SDA")
	)
	(segment
		(start 219.119196 -223.251268)
		(end 219.119196 -222.318834)
		(width 0.13208)
		(layer "B.Cu")
		(net "SMB_BIC_FPGA_SDA")
	)
	(segment
		(start 213.763606 -222.866204)
		(end 213.17585 -222.866204)
		(width 0.13208)
		(layer "B.Cu")
		(net "SMB_BIC_FPGA_SDA")
	)
	(segment
		(start 212.948012 -222.638366)
		(end 212.729826 -222.638366)
		(width 0.13208)
		(layer "B.Cu")
		(net "SMB_BIC_FPGA_SDA")
	)
	(segment
		(start 211.323174 -223.61906)
		(end 210.858862 -223.61906)
		(width 0.13208)
		(layer "B.Cu")
		(net "SMB_BIC_FPGA_SDA")
	)
	(segment
		(start 214.032592 -222.597218)
		(end 213.763606 -222.866204)
		(width 0.13208)
		(layer "B.Cu")
		(net "SMB_BIC_FPGA_SDA")
	)
	(segment
		(start 218.750642 -222.089472)
		(end 217.988642 -222.851472)
		(width 0.13208)
		(layer "B.Cu")
		(net "SMB_BIC_FPGA_SDA")
	)
	(segment
		(start 217.988642 -222.851472)
		(end 214.51316 -222.851472)
		(width 0.13208)
		(layer "B.Cu")
		(net "SMB_BIC_FPGA_SDA")
	)
	(segment
		(start 213.17585 -222.866204)
		(end 212.948012 -222.638366)
		(width 0.13208)
		(layer "B.Cu")
		(net "SMB_BIC_FPGA_SDA")
	)
	(segment
		(start 218.889834 -222.089472)
		(end 218.750642 -222.089472)
		(width 0.13208)
		(layer "B.Cu")
		(net "SMB_BIC_FPGA_SDA")
	)
	(segment
		(start 212.04301 -223.325182)
		(end 211.617052 -223.325182)
		(width 0.13208)
		(layer "B.Cu")
		(net "SMB_BIC_FPGA_SDA")
	)
	(segment
		(start 214.032592 -222.370904)
		(end 214.032592 -222.597218)
		(width 0.13208)
		(layer "B.Cu")
		(net "SMB_BIC_FPGA_SDA")
	)
	(segment
		(start 214.51316 -222.851472)
		(end 214.032592 -222.370904)
		(width 0.13208)
		(layer "B.Cu")
		(net "SMB_BIC_FPGA_SDA")
	)
	(segment
		(start 212.729826 -222.638366)
		(end 212.04301 -223.325182)
		(width 0.13208)
		(layer "B.Cu")
		(net "SMB_BIC_FPGA_SDA")
	)
	(segment
		(start 219.119196 -222.318834)
		(end 218.889834 -222.089472)
		(width 0.13208)
		(layer "B.Cu")
		(net "SMB_BIC_FPGA_SDA")
	)
	(segment
		(start 211.617052 -223.325182)
		(end 211.323174 -223.61906)
		(width 0.13208)
		(layer "B.Cu")
		(net "SMB_BIC_FPGA_SDA")
	)
	(segment
		(start 47.59071 -409.795218)
		(end 47.71009 -409.675838)
		(width 0.1651)
		(layer "In11.Cu")
		(net "P2E_GPU_FPGA_PEX_TX_DP<0>")
	)
	(segment
		(start 48.335438 -394.435076)
		(end 48.273716 -394.584682)
		(width 0.1651)
		(layer "In11.Cu")
		(net "P2E_GPU_FPGA_PEX_TX_DP<0>")
	)
	(segment
		(start 59.281568 -392.864086)
		(end 58.791348 -392.867134)
		(width 0.1651)
		(layer "In11.Cu")
		(net "P2E_GPU_FPGA_PEX_TX_DP<0>")
	)
	(segment
		(start 49.399698 -394.11656)
		(end 48.94199 -394.306806)
		(width 0.1651)
		(layer "In11.Cu")
		(net "P2E_GPU_FPGA_PEX_TX_DP<0>")
	)
	(segment
		(start 75.31735 -392.773154)
		(end 75.203812 -392.888216)
		(width 0.1651)
		(layer "In11.Cu")
		(net "P2E_GPU_FPGA_PEX_TX_DP<0>")
	)
	(segment
		(start 72.765412 -392.90244)
		(end 72.269858 -392.905488)
		(width 0.1651)
		(layer "In11.Cu")
		(net "P2E_GPU_FPGA_PEX_TX_DP<0>")
	)
	(segment
		(start 91.710002 -409.675838)
		(end 91.829382 -409.795218)
		(width 0.1651)
		(layer "In11.Cu")
		(net "P2E_GPU_FPGA_PEX_TX_DP<0>")
	)
	(segment
		(start 72.269858 -392.905488)
		(end 72.153272 -392.790172)
		(width 0.1651)
		(layer "In11.Cu")
		(net "P2E_GPU_FPGA_PEX_TX_DP<0>")
	)
	(segment
		(start 74.09942 -392.778996)
		(end 73.984612 -392.895328)
		(width 0.1651)
		(layer "In11.Cu")
		(net "P2E_GPU_FPGA_PEX_TX_DP<0>")
	)
	(segment
		(start 64.41313 -392.837162)
		(end 64.411098 -392.834876)
		(width 0.1651)
		(layer "In11.Cu")
		(net "P2E_GPU_FPGA_PEX_TX_DP<0>")
	)
	(segment
		(start 55.738522 -392.998706)
		(end 55.623714 -392.885168)
		(width 0.1651)
		(layer "In11.Cu")
		(net "P2E_GPU_FPGA_PEX_TX_DP<0>")
	)
	(segment
		(start 59.39917 -392.980418)
		(end 59.281568 -392.864086)
		(width 0.1651)
		(layer "In11.Cu")
		(net "P2E_GPU_FPGA_PEX_TX_DP<0>")
	)
	(segment
		(start 61.229748 -392.85291)
		(end 61.113924 -392.970512)
		(width 0.1651)
		(layer "In11.Cu")
		(net "P2E_GPU_FPGA_PEX_TX_DP<0>")
	)
	(segment
		(start 47.666656 -394.713206)
		(end 47.209456 -394.903198)
		(width 0.1651)
		(layer "In11.Cu")
		(net "P2E_GPU_FPGA_PEX_TX_DP<0>")
	)
	(segment
		(start 52.046632 -392.892026)
		(end 50.587402 -393.498832)
		(width 0.1651)
		(layer "In11.Cu")
		(net "P2E_GPU_FPGA_PEX_TX_DP<0>")
	)
	(segment
		(start 69.831204 -392.919712)
		(end 69.714364 -392.804142)
		(width 0.1651)
		(layer "In11.Cu")
		(net "P2E_GPU_FPGA_PEX_TX_DP<0>")
	)
	(segment
		(start 73.984612 -392.895328)
		(end 73.489058 -392.898376)
		(width 0.1651)
		(layer "In11.Cu")
		(net "P2E_GPU_FPGA_PEX_TX_DP<0>")
	)
	(segment
		(start 90.160856 -393.095988)
		(end 88.45042 -392.6967)
		(width 0.1651)
		(layer "In11.Cu")
		(net "P2E_GPU_FPGA_PEX_TX_DP<0>")
	)
	(segment
		(start 47.380652 -409.795218)
		(end 47.59071 -409.795218)
		(width 0.1651)
		(layer "In11.Cu")
		(net "P2E_GPU_FPGA_PEX_TX_DP<0>")
	)
	(segment
		(start 64.41313 -392.836908)
		(end 64.41313 -392.837162)
		(width 0.1651)
		(layer "In11.Cu")
		(net "P2E_GPU_FPGA_PEX_TX_DP<0>")
	)
	(segment
		(start 56.234076 -392.995912)
		(end 55.738522 -392.998706)
		(width 0.1651)
		(layer "In11.Cu")
		(net "P2E_GPU_FPGA_PEX_TX_DP<0>")
	)
	(segment
		(start 60.501022 -392.857228)
		(end 60.010548 -392.860022)
		(width 0.1651)
		(layer "In11.Cu")
		(net "P2E_GPU_FPGA_PEX_TX_DP<0>")
	)
	(segment
		(start 58.17997 -392.98753)
		(end 58.062368 -392.871198)
		(width 0.1651)
		(layer "In11.Cu")
		(net "P2E_GPU_FPGA_PEX_TX_DP<0>")
	)
	(segment
		(start 54.4068 -392.892026)
		(end 52.046632 -392.892026)
		(width 0.1651)
		(layer "In11.Cu")
		(net "P2E_GPU_FPGA_PEX_TX_DP<0>")
	)
	(segment
		(start 47.71009 -409.675838)
		(end 47.71009 -409.290012)
		(width 0.1651)
		(layer "In11.Cu")
		(net "P2E_GPU_FPGA_PEX_TX_DP<0>")
	)
	(segment
		(start 73.372726 -392.783314)
		(end 72.88022 -392.786108)
		(width 0.1651)
		(layer "In11.Cu")
		(net "P2E_GPU_FPGA_PEX_TX_DP<0>")
	)
	(segment
		(start 73.489058 -392.898376)
		(end 73.372726 -392.783314)
		(width 0.1651)
		(layer "In11.Cu")
		(net "P2E_GPU_FPGA_PEX_TX_DP<0>")
	)
	(segment
		(start 48.94199 -394.306806)
		(end 48.792638 -394.245084)
		(width 0.1651)
		(layer "In11.Cu")
		(net "P2E_GPU_FPGA_PEX_TX_DP<0>")
	)
	(segment
		(start 55.623714 -392.885168)
		(end 54.4068 -392.892026)
		(width 0.1651)
		(layer "In11.Cu")
		(net "P2E_GPU_FPGA_PEX_TX_DP<0>")
	)
	(segment
		(start 70.442074 -392.800078)
		(end 70.326758 -392.916918)
		(width 0.1651)
		(layer "In11.Cu")
		(net "P2E_GPU_FPGA_PEX_TX_DP<0>")
	)
	(segment
		(start 92.6719 -406.26665)
		(end 92.6719 -405.77135)
		(width 0.1651)
		(layer "In11.Cu")
		(net "P2E_GPU_FPGA_PEX_TX_DP<0>")
	)
	(segment
		(start 50.067972 -393.838684)
		(end 49.91862 -393.776962)
		(width 0.1651)
		(layer "In11.Cu")
		(net "P2E_GPU_FPGA_PEX_TX_DP<0>")
	)
	(segment
		(start 49.46142 -393.966954)
		(end 49.399698 -394.11656)
		(width 0.1651)
		(layer "In11.Cu")
		(net "P2E_GPU_FPGA_PEX_TX_DP<0>")
	)
	(segment
		(start 58.675524 -392.984482)
		(end 58.17997 -392.98753)
		(width 0.1651)
		(layer "In11.Cu")
		(net "P2E_GPU_FPGA_PEX_TX_DP<0>")
	)
	(segment
		(start 61.113924 -392.970512)
		(end 60.61837 -392.973306)
		(width 0.1651)
		(layer "In11.Cu")
		(net "P2E_GPU_FPGA_PEX_TX_DP<0>")
	)
	(segment
		(start 59.894724 -392.977624)
		(end 59.39917 -392.980418)
		(width 0.1651)
		(layer "In11.Cu")
		(net "P2E_GPU_FPGA_PEX_TX_DP<0>")
	)
	(segment
		(start 71.661274 -392.792966)
		(end 71.546212 -392.909552)
		(width 0.1651)
		(layer "In11.Cu")
		(net "P2E_GPU_FPGA_PEX_TX_DP<0>")
	)
	(segment
		(start 72.153272 -392.790172)
		(end 71.661274 -392.792966)
		(width 0.1651)
		(layer "In11.Cu")
		(net "P2E_GPU_FPGA_PEX_TX_DP<0>")
	)
	(segment
		(start 60.61837 -392.973306)
		(end 60.501022 -392.857228)
		(width 0.1651)
		(layer "In11.Cu")
		(net "P2E_GPU_FPGA_PEX_TX_DP<0>")
	)
	(segment
		(start 56.347868 -392.881104)
		(end 56.347868 -392.88085)
		(width 0.1651)
		(layer "In11.Cu")
		(net "P2E_GPU_FPGA_PEX_TX_DP<0>")
	)
	(segment
		(start 92.7862 -409.024074)
		(end 92.7862 -406.38095)
		(width 0.1651)
		(layer "In11.Cu")
		(net "P2E_GPU_FPGA_PEX_TX_DP<0>")
	)
	(segment
		(start 91.710002 -409.290012)
		(end 91.710002 -409.675838)
		(width 0.1651)
		(layer "In11.Cu")
		(net "P2E_GPU_FPGA_PEX_TX_DP<0>")
	)
	(segment
		(start 47.816008 -394.774928)
		(end 47.666656 -394.713206)
		(width 0.1651)
		(layer "In11.Cu")
		(net "P2E_GPU_FPGA_PEX_TX_DP<0>")
	)
	(segment
		(start 58.791348 -392.867134)
		(end 58.675524 -392.984482)
		(width 0.1651)
		(layer "In11.Cu")
		(net "P2E_GPU_FPGA_PEX_TX_DP<0>")
	)
	(segment
		(start 70.326758 -392.916918)
		(end 69.831204 -392.919712)
		(width 0.1651)
		(layer "In11.Cu")
		(net "P2E_GPU_FPGA_PEX_TX_DP<0>")
	)
	(segment
		(start 75.203812 -392.888216)
		(end 74.708258 -392.891264)
		(width 0.1651)
		(layer "In11.Cu")
		(net "P2E_GPU_FPGA_PEX_TX_DP<0>")
	)
	(segment
		(start 47.209456 -394.903198)
		(end 46.828964 -395.82217)
		(width 0.1651)
		(layer "In11.Cu")
		(net "P2E_GPU_FPGA_PEX_TX_DP<0>")
	)
	(segment
		(start 70.934072 -392.797284)
		(end 70.442074 -392.800078)
		(width 0.1651)
		(layer "In11.Cu")
		(net "P2E_GPU_FPGA_PEX_TX_DP<0>")
	)
	(segment
		(start 46.828964 -409.24353)
		(end 47.380652 -409.795218)
		(width 0.1651)
		(layer "In11.Cu")
		(net "P2E_GPU_FPGA_PEX_TX_DP<0>")
	)
	(segment
		(start 92.458794 -394.939774)
		(end 90.887296 -393.368276)
		(width 0.1651)
		(layer "In11.Cu")
		(net "P2E_GPU_FPGA_PEX_TX_DP<0>")
	)
	(segment
		(start 69.714364 -392.804142)
		(end 64.415416 -392.834368)
		(width 0.1651)
		(layer "In11.Cu")
		(net "P2E_GPU_FPGA_PEX_TX_DP<0>")
	)
	(segment
		(start 57.456324 -392.991594)
		(end 56.96077 -392.994642)
		(width 0.1651)
		(layer "In11.Cu")
		(net "P2E_GPU_FPGA_PEX_TX_DP<0>")
	)
	(segment
		(start 56.96077 -392.994642)
		(end 56.842914 -392.878056)
		(width 0.1651)
		(layer "In11.Cu")
		(net "P2E_GPU_FPGA_PEX_TX_DP<0>")
	)
	(segment
		(start 49.91862 -393.776962)
		(end 49.46142 -393.966954)
		(width 0.1651)
		(layer "In11.Cu")
		(net "P2E_GPU_FPGA_PEX_TX_DP<0>")
	)
	(segment
		(start 64.411098 -392.834876)
		(end 61.229748 -392.85291)
		(width 0.1651)
		(layer "In11.Cu")
		(net "P2E_GPU_FPGA_PEX_TX_DP<0>")
	)
	(segment
		(start 74.591926 -392.776202)
		(end 74.09942 -392.778996)
		(width 0.1651)
		(layer "In11.Cu")
		(net "P2E_GPU_FPGA_PEX_TX_DP<0>")
	)
	(segment
		(start 90.887296 -393.368276)
		(end 90.160856 -393.095988)
		(width 0.1651)
		(layer "In11.Cu")
		(net "P2E_GPU_FPGA_PEX_TX_DP<0>")
	)
	(segment
		(start 60.010548 -392.860022)
		(end 59.894724 -392.977624)
		(width 0.1651)
		(layer "In11.Cu")
		(net "P2E_GPU_FPGA_PEX_TX_DP<0>")
	)
	(segment
		(start 74.708258 -392.891264)
		(end 74.591926 -392.776202)
		(width 0.1651)
		(layer "In11.Cu")
		(net "P2E_GPU_FPGA_PEX_TX_DP<0>")
	)
	(segment
		(start 58.062368 -392.871198)
		(end 57.572148 -392.874246)
		(width 0.1651)
		(layer "In11.Cu")
		(net "P2E_GPU_FPGA_PEX_TX_DP<0>")
	)
	(segment
		(start 92.6719 -405.77135)
		(end 92.7862 -405.65705)
		(width 0.1651)
		(layer "In11.Cu")
		(net "P2E_GPU_FPGA_PEX_TX_DP<0>")
	)
	(segment
		(start 71.050658 -392.9126)
		(end 70.934072 -392.797284)
		(width 0.1651)
		(layer "In11.Cu")
		(net "P2E_GPU_FPGA_PEX_TX_DP<0>")
	)
	(segment
		(start 57.572148 -392.874246)
		(end 57.456324 -392.991594)
		(width 0.1651)
		(layer "In11.Cu")
		(net "P2E_GPU_FPGA_PEX_TX_DP<0>")
	)
	(segment
		(start 48.273716 -394.584682)
		(end 47.816008 -394.774928)
		(width 0.1651)
		(layer "In11.Cu")
		(net "P2E_GPU_FPGA_PEX_TX_DP<0>")
	)
	(segment
		(start 48.792638 -394.245084)
		(end 48.335438 -394.435076)
		(width 0.1651)
		(layer "In11.Cu")
		(net "P2E_GPU_FPGA_PEX_TX_DP<0>")
	)
	(segment
		(start 56.842914 -392.878056)
		(end 56.842914 -392.87831)
		(width 0.1651)
		(layer "In11.Cu")
		(net "P2E_GPU_FPGA_PEX_TX_DP<0>")
	)
	(segment
		(start 71.546212 -392.909552)
		(end 71.050658 -392.9126)
		(width 0.1651)
		(layer "In11.Cu")
		(net "P2E_GPU_FPGA_PEX_TX_DP<0>")
	)
	(segment
		(start 92.7862 -395.730222)
		(end 92.458794 -394.939774)
		(width 0.1651)
		(layer "In11.Cu")
		(net "P2E_GPU_FPGA_PEX_TX_DP<0>")
	)
	(segment
		(start 56.347868 -392.88085)
		(end 56.234076 -392.995912)
		(width 0.1651)
		(layer "In11.Cu")
		(net "P2E_GPU_FPGA_PEX_TX_DP<0>")
	)
	(segment
		(start 92.7862 -406.38095)
		(end 92.6719 -406.26665)
		(width 0.1651)
		(layer "In11.Cu")
		(net "P2E_GPU_FPGA_PEX_TX_DP<0>")
	)
	(segment
		(start 92.7862 -405.65705)
		(end 92.7862 -395.730222)
		(width 0.1651)
		(layer "In11.Cu")
		(net "P2E_GPU_FPGA_PEX_TX_DP<0>")
	)
	(segment
		(start 92.015056 -409.795218)
		(end 92.7862 -409.024074)
		(width 0.1651)
		(layer "In11.Cu")
		(net "P2E_GPU_FPGA_PEX_TX_DP<0>")
	)
	(segment
		(start 88.45042 -392.6967)
		(end 75.31735 -392.773154)
		(width 0.1651)
		(layer "In11.Cu")
		(net "P2E_GPU_FPGA_PEX_TX_DP<0>")
	)
	(segment
		(start 64.415416 -392.834368)
		(end 64.41313 -392.836908)
		(width 0.1651)
		(layer "In11.Cu")
		(net "P2E_GPU_FPGA_PEX_TX_DP<0>")
	)
	(segment
		(start 56.842914 -392.87831)
		(end 56.347868 -392.881104)
		(width 0.1651)
		(layer "In11.Cu")
		(net "P2E_GPU_FPGA_PEX_TX_DP<0>")
	)
	(segment
		(start 72.88022 -392.786108)
		(end 72.765412 -392.90244)
		(width 0.1651)
		(layer "In11.Cu")
		(net "P2E_GPU_FPGA_PEX_TX_DP<0>")
	)
	(segment
		(start 50.52568 -393.648438)
		(end 50.067972 -393.838684)
		(width 0.1651)
		(layer "In11.Cu")
		(net "P2E_GPU_FPGA_PEX_TX_DP<0>")
	)
	(segment
		(start 50.587402 -393.498832)
		(end 50.52568 -393.648438)
		(width 0.1651)
		(layer "In11.Cu")
		(net "P2E_GPU_FPGA_PEX_TX_DP<0>")
	)
	(segment
		(start 91.829382 -409.795218)
		(end 92.015056 -409.795218)
		(width 0.1651)
		(layer "In11.Cu")
		(net "P2E_GPU_FPGA_PEX_TX_DP<0>")
	)
	(segment
		(start 46.828964 -395.82217)
		(end 46.828964 -409.24353)
		(width 0.1651)
		(layer "In11.Cu")
		(net "P2E_GPU_FPGA_PEX_TX_DP<0>")
	)
	(segment
		(start 360.531156 -126.394718)
		(end 360.479594 -126.394718)
		(width 0.13208)
		(layer "F.Cu")
		(net "P3V3_NIC6_SS")
	)
	(segment
		(start 359.426256 -127.051308)
		(end 358.86644 -127.051308)
		(width 0.13208)
		(layer "F.Cu")
		(net "P3V3_NIC6_SS")
	)
	(segment
		(start 359.823004 -127.051308)
		(end 359.426256 -127.051308)
		(width 0.13208)
		(layer "F.Cu")
		(net "P3V3_NIC6_SS")
	)
	(segment
		(start 358.86644 -127.051308)
		(end 358.81056 -126.995428)
		(width 0.13208)
		(layer "F.Cu")
		(net "P3V3_NIC6_SS")
	)
	(segment
		(start 360.479594 -126.394718)
		(end 359.823004 -127.051308)
		(width 0.13208)
		(layer "F.Cu")
		(net "P3V3_NIC6_SS")
	)
	(via
		(at 359.426256 -127.051308)
		(size 0.508)
		(drill 0.254)
		(layers "F.Cu" "B.Cu")
		(net "P3V3_NIC6_SS")
	)
	(segment
		(start 227.188776 -59.837066)
		(end 226.894136 -60.131706)
		(width 0.13462)
		(layer "F.Cu")
		(net "USB2_FIO_DN")
	)
	(segment
		(start 230.329994 -78.182978)
		(end 230.329994 -78.54569)
		(width 0.13462)
		(layer "F.Cu")
		(net "USB2_FIO_DN")
	)
	(segment
		(start 228.935788 -60.000134)
		(end 228.77272 -59.837066)
		(width 0.13462)
		(layer "F.Cu")
		(net "USB2_FIO_DN")
	)
	(segment
		(start 229.437438 -60.000134)
		(end 228.935788 -60.000134)
		(width 0.13462)
		(layer "F.Cu")
		(net "USB2_FIO_DN")
	)
	(segment
		(start 230.098092 -76.796138)
		(end 230.386382 -77.084428)
		(width 0.13462)
		(layer "F.Cu")
		(net "USB2_FIO_DN")
	)
	(segment
		(start 230.386382 -78.12659)
		(end 230.329994 -78.182978)
		(width 0.13462)
		(layer "F.Cu")
		(net "USB2_FIO_DN")
	)
	(segment
		(start 228.77272 -59.837066)
		(end 227.188776 -59.837066)
		(width 0.13462)
		(layer "F.Cu")
		(net "USB2_FIO_DN")
	)
	(segment
		(start 230.386382 -77.084428)
		(end 230.386382 -78.12659)
		(width 0.13462)
		(layer "F.Cu")
		(net "USB2_FIO_DN")
	)
	(via
		(at 226.894136 -60.131706)
		(size 0.508)
		(drill 0.254)
		(layers "F.Cu" "B.Cu")
		(net "USB2_FIO_DN")
	)
	(via
		(at 230.098092 -76.796138)
		(size 0.508)
		(drill 0.254)
		(layers "F.Cu" "B.Cu")
		(net "USB2_FIO_DN")
	)
	(segment
		(start 229.083108 -60.332874)
		(end 228.592634 -59.8424)
		(width 0.13462)
		(layer "B.Cu")
		(net "USB2_FIO_DN")
	)
	(segment
		(start 229.083108 -70.46341)
		(end 228.945948 -70.32625)
		(width 0.13462)
		(layer "B.Cu")
		(net "USB2_FIO_DN")
	)
	(segment
		(start 230.394764 -76.498958)
		(end 230.394764 -74.775822)
		(width 0.13462)
		(layer "B.Cu")
		(net "USB2_FIO_DN")
	)
	(segment
		(start 230.098092 -76.796138)
		(end 230.394764 -76.498958)
		(width 0.13462)
		(layer "B.Cu")
		(net "USB2_FIO_DN")
	)
	(segment
		(start 228.592634 -59.8424)
		(end 227.183442 -59.8424)
		(width 0.13462)
		(layer "B.Cu")
		(net "USB2_FIO_DN")
	)
	(segment
		(start 229.083108 -69.78523)
		(end 229.083108 -60.332874)
		(width 0.13462)
		(layer "B.Cu")
		(net "USB2_FIO_DN")
	)
	(segment
		(start 228.945948 -69.92239)
		(end 229.083108 -69.78523)
		(width 0.13462)
		(layer "B.Cu")
		(net "USB2_FIO_DN")
	)
	(segment
		(start 228.945948 -70.32625)
		(end 228.945948 -69.92239)
		(width 0.13462)
		(layer "B.Cu")
		(net "USB2_FIO_DN")
	)
	(segment
		(start 227.183442 -59.8424)
		(end 226.894136 -60.131706)
		(width 0.13462)
		(layer "B.Cu")
		(net "USB2_FIO_DN")
	)
	(segment
		(start 229.083108 -72.62749)
		(end 228.945948 -72.49033)
		(width 0.13462)
		(layer "B.Cu")
		(net "USB2_FIO_DN")
	)
	(segment
		(start 229.083108 -73.464166)
		(end 229.083108 -72.62749)
		(width 0.13462)
		(layer "B.Cu")
		(net "USB2_FIO_DN")
	)
	(segment
		(start 230.394764 -74.775822)
		(end 229.083108 -73.464166)
		(width 0.13462)
		(layer "B.Cu")
		(net "USB2_FIO_DN")
	)
	(segment
		(start 228.945948 -71.00443)
		(end 229.083108 -70.86727)
		(width 0.13462)
		(layer "B.Cu")
		(net "USB2_FIO_DN")
	)
	(segment
		(start 229.083108 -71.54545)
		(end 228.945948 -71.40829)
		(width 0.13462)
		(layer "B.Cu")
		(net "USB2_FIO_DN")
	)
	(segment
		(start 228.945948 -71.40829)
		(end 228.945948 -71.00443)
		(width 0.13462)
		(layer "B.Cu")
		(net "USB2_FIO_DN")
	)
	(segment
		(start 228.945948 -72.08647)
		(end 229.083108 -71.94931)
		(width 0.13462)
		(layer "B.Cu")
		(net "USB2_FIO_DN")
	)
	(segment
		(start 229.083108 -70.86727)
		(end 229.083108 -70.46341)
		(width 0.13462)
		(layer "B.Cu")
		(net "USB2_FIO_DN")
	)
	(segment
		(start 228.945948 -72.49033)
		(end 228.945948 -72.08647)
		(width 0.13462)
		(layer "B.Cu")
		(net "USB2_FIO_DN")
	)
	(segment
		(start 229.083108 -71.94931)
		(end 229.083108 -71.54545)
		(width 0.13462)
		(layer "B.Cu")
		(net "USB2_FIO_DN")
	)
	(segment
		(start 142.331694 -180.594)
		(end 142.63878 -180.901086)
		(width 0.13462)
		(layer "F.Cu")
		(net "CLK_100M_DB2000QL_NIC5_R_DN")
	)
	(segment
		(start 306.819808 -117.2083)
		(end 306.093368 -117.2083)
		(width 0.13462)
		(layer "F.Cu")
		(net "CLK_100M_DB2000QL_NIC5_R_DN")
	)
	(segment
		(start 140.857478 -180.594)
		(end 142.331694 -180.594)
		(width 0.13462)
		(layer "F.Cu")
		(net "CLK_100M_DB2000QL_NIC5_R_DN")
	)
	(segment
		(start 305.92014 -117.035072)
		(end 305.457606 -117.035072)
		(width 0.13462)
		(layer "F.Cu")
		(net "CLK_100M_DB2000QL_NIC5_R_DN")
	)
	(segment
		(start 140.474192 -180.977286)
		(end 140.857478 -180.594)
		(width 0.13462)
		(layer "F.Cu")
		(net "CLK_100M_DB2000QL_NIC5_R_DN")
	)
	(segment
		(start 307.132736 -116.895372)
		(end 306.819808 -117.2083)
		(width 0.13462)
		(layer "F.Cu")
		(net "CLK_100M_DB2000QL_NIC5_R_DN")
	)
	(segment
		(start 306.093368 -117.2083)
		(end 305.92014 -117.035072)
		(width 0.13462)
		(layer "F.Cu")
		(net "CLK_100M_DB2000QL_NIC5_R_DN")
	)
	(via
		(at 142.63878 -180.901086)
		(size 0.508)
		(drill 0.254)
		(layers "F.Cu" "B.Cu")
		(net "CLK_100M_DB2000QL_NIC5_R_DN")
	)
	(via
		(at 307.132736 -116.895372)
		(size 0.508)
		(drill 0.254)
		(layers "F.Cu" "B.Cu")
		(net "CLK_100M_DB2000QL_NIC5_R_DN")
	)
	(segment
		(start 180.031898 -169.903902)
		(end 207.552798 -169.903902)
		(width 0.1651)
		(layer "In15.Cu")
		(net "CLK_100M_DB2000QL_NIC5_R_DN")
	)
	(segment
		(start 142.945866 -180.594)
		(end 165.445948 -180.594)
		(width 0.1651)
		(layer "In15.Cu")
		(net "CLK_100M_DB2000QL_NIC5_R_DN")
	)
	(segment
		(start 240.80216 -165.25494)
		(end 253.81204 -165.25494)
		(width 0.1651)
		(layer "In15.Cu")
		(net "CLK_100M_DB2000QL_NIC5_R_DN")
	)
	(segment
		(start 214.680038 -162.776662)
		(end 238.323882 -162.776662)
		(width 0.1651)
		(layer "In15.Cu")
		(net "CLK_100M_DB2000QL_NIC5_R_DN")
	)
	(segment
		(start 179.256944 -170.678856)
		(end 180.031898 -169.903902)
		(width 0.1651)
		(layer "In15.Cu")
		(net "CLK_100M_DB2000QL_NIC5_R_DN")
	)
	(segment
		(start 267.161518 -162.802062)
		(end 271.916144 -158.047436)
		(width 0.1651)
		(layer "In15.Cu")
		(net "CLK_100M_DB2000QL_NIC5_R_DN")
	)
	(segment
		(start 142.63878 -180.901086)
		(end 142.945866 -180.594)
		(width 0.1651)
		(layer "In15.Cu")
		(net "CLK_100M_DB2000QL_NIC5_R_DN")
	)
	(segment
		(start 308.991 -117.9068)
		(end 308.274212 -117.190012)
		(width 0.1651)
		(layer "In15.Cu")
		(net "CLK_100M_DB2000QL_NIC5_R_DN")
	)
	(segment
		(start 207.552798 -169.903902)
		(end 214.680038 -162.776662)
		(width 0.1651)
		(layer "In15.Cu")
		(net "CLK_100M_DB2000QL_NIC5_R_DN")
	)
	(segment
		(start 308.274212 -117.190012)
		(end 307.427376 -117.190012)
		(width 0.1651)
		(layer "In15.Cu")
		(net "CLK_100M_DB2000QL_NIC5_R_DN")
	)
	(segment
		(start 308.991 -155.626308)
		(end 308.991 -117.9068)
		(width 0.1651)
		(layer "In15.Cu")
		(net "CLK_100M_DB2000QL_NIC5_R_DN")
	)
	(segment
		(start 238.323882 -162.776662)
		(end 240.80216 -165.25494)
		(width 0.1651)
		(layer "In15.Cu")
		(net "CLK_100M_DB2000QL_NIC5_R_DN")
	)
	(segment
		(start 306.569872 -158.047436)
		(end 308.991 -155.626308)
		(width 0.1651)
		(layer "In15.Cu")
		(net "CLK_100M_DB2000QL_NIC5_R_DN")
	)
	(segment
		(start 256.264918 -162.802062)
		(end 267.161518 -162.802062)
		(width 0.1651)
		(layer "In15.Cu")
		(net "CLK_100M_DB2000QL_NIC5_R_DN")
	)
	(segment
		(start 271.916144 -158.047436)
		(end 306.569872 -158.047436)
		(width 0.1651)
		(layer "In15.Cu")
		(net "CLK_100M_DB2000QL_NIC5_R_DN")
	)
	(segment
		(start 253.81204 -165.25494)
		(end 256.264918 -162.802062)
		(width 0.1651)
		(layer "In15.Cu")
		(net "CLK_100M_DB2000QL_NIC5_R_DN")
	)
	(segment
		(start 165.445948 -180.594)
		(end 175.361092 -170.678856)
		(width 0.1651)
		(layer "In15.Cu")
		(net "CLK_100M_DB2000QL_NIC5_R_DN")
	)
	(segment
		(start 307.427376 -117.190012)
		(end 307.132736 -116.895372)
		(width 0.1651)
		(layer "In15.Cu")
		(net "CLK_100M_DB2000QL_NIC5_R_DN")
	)
	(segment
		(start 175.361092 -170.678856)
		(end 179.256944 -170.678856)
		(width 0.1651)
		(layer "In15.Cu")
		(net "CLK_100M_DB2000QL_NIC5_R_DN")
	)
	(segment
		(start 105.992422 -328.902314)
		(end 106.064558 -328.97445)
		(width 0.1143)
		(layer "B.Cu")
		(net "CLK_100M_DB800ZL_PEX0_S0_DP")
	)
	(segment
		(start 106.35869 -326.552306)
		(end 106.04119 -326.869806)
		(width 0.1143)
		(layer "B.Cu")
		(net "CLK_100M_DB800ZL_PEX0_S0_DP")
	)
	(segment
		(start 106.064558 -328.97445)
		(end 106.064558 -329.175618)
		(width 0.1143)
		(layer "B.Cu")
		(net "CLK_100M_DB800ZL_PEX0_S0_DP")
	)
	(segment
		(start 106.04119 -327.93051)
		(end 105.992422 -327.979278)
		(width 0.1143)
		(layer "B.Cu")
		(net "CLK_100M_DB800ZL_PEX0_S0_DP")
	)
	(segment
		(start 105.992422 -327.979278)
		(end 105.992422 -328.902314)
		(width 0.1143)
		(layer "B.Cu")
		(net "CLK_100M_DB800ZL_PEX0_S0_DP")
	)
	(segment
		(start 106.04119 -326.869806)
		(end 106.04119 -327.93051)
		(width 0.1143)
		(layer "B.Cu")
		(net "CLK_100M_DB800ZL_PEX0_S0_DP")
	)
	(segment
		(start 302.703484 -238.296704)
		(end 302.061626 -238.938562)
		(width 0.13208)
		(layer "F.Cu")
		(net "SMB_MB_R_SDA")
	)
	(segment
		(start 244.932962 -235.6612)
		(end 244.932962 -235.841032)
		(width 0.13208)
		(layer "F.Cu")
		(net "SMB_MB_R_SDA")
	)
	(segment
		(start 316.353952 -238.296704)
		(end 302.703484 -238.296704)
		(width 0.13208)
		(layer "F.Cu")
		(net "SMB_MB_R_SDA")
	)
	(segment
		(start 244.932962 -235.841032)
		(end 244.492018 -236.281976)
		(width 0.13208)
		(layer "F.Cu")
		(net "SMB_MB_R_SDA")
	)
	(segment
		(start 244.92712 -235.655358)
		(end 244.932962 -235.6612)
		(width 0.13208)
		(layer "F.Cu")
		(net "SMB_MB_R_SDA")
	)
	(segment
		(start 322.25361 -232.397046)
		(end 316.353952 -238.296704)
		(width 0.13208)
		(layer "F.Cu")
		(net "SMB_MB_R_SDA")
	)
	(via
		(at 244.92712 -235.655358)
		(size 0.508)
		(drill 0.254)
		(layers "F.Cu" "B.Cu")
		(net "SMB_MB_R_SDA")
	)
	(via
		(at 302.061626 -238.938562)
		(size 0.508)
		(drill 0.254)
		(layers "F.Cu" "B.Cu")
		(net "SMB_MB_R_SDA")
	)
	(segment
		(start 302.061626 -239.576356)
		(end 302.061626 -238.938562)
		(width 0.13208)
		(layer "B.Cu")
		(net "SMB_MB_R_SDA")
	)
	(segment
		(start 258.2164 -235.966)
		(end 260.1976 -235.966)
		(width 0.15494)
		(layer "In13.Cu")
		(net "SMB_MB_R_SDA")
	)
	(segment
		(start 246.991124 -236.336586)
		(end 247.725438 -236.640878)
		(width 0.15494)
		(layer "In13.Cu")
		(net "SMB_MB_R_SDA")
	)
	(segment
		(start 254.330962 -237.7186)
		(end 255.372362 -236.6772)
		(width 0.15494)
		(layer "In13.Cu")
		(net "SMB_MB_R_SDA")
	)
	(segment
		(start 301.859188 -239.141)
		(end 302.061626 -238.938562)
		(width 0.15494)
		(layer "In13.Cu")
		(net "SMB_MB_R_SDA")
	)
	(segment
		(start 260.694932 -235.468668)
		(end 273.136868 -235.468668)
		(width 0.15494)
		(layer "In13.Cu")
		(net "SMB_MB_R_SDA")
	)
	(segment
		(start 248.80316 -237.7186)
		(end 254.330962 -237.7186)
		(width 0.15494)
		(layer "In13.Cu")
		(net "SMB_MB_R_SDA")
	)
	(segment
		(start 246.571516 -236.336586)
		(end 246.991124 -236.336586)
		(width 0.15494)
		(layer "In13.Cu")
		(net "SMB_MB_R_SDA")
	)
	(segment
		(start 257.5052 -236.6772)
		(end 258.2164 -235.966)
		(width 0.15494)
		(layer "In13.Cu")
		(net "SMB_MB_R_SDA")
	)
	(segment
		(start 255.372362 -236.6772)
		(end 257.5052 -236.6772)
		(width 0.15494)
		(layer "In13.Cu")
		(net "SMB_MB_R_SDA")
	)
	(segment
		(start 276.8092 -239.141)
		(end 301.859188 -239.141)
		(width 0.15494)
		(layer "In13.Cu")
		(net "SMB_MB_R_SDA")
	)
	(segment
		(start 273.136868 -235.468668)
		(end 276.8092 -239.141)
		(width 0.15494)
		(layer "In13.Cu")
		(net "SMB_MB_R_SDA")
	)
	(segment
		(start 244.92712 -235.655358)
		(end 246.571516 -236.336586)
		(width 0.15494)
		(layer "In13.Cu")
		(net "SMB_MB_R_SDA")
	)
	(segment
		(start 260.1976 -235.966)
		(end 260.694932 -235.468668)
		(width 0.15494)
		(layer "In13.Cu")
		(net "SMB_MB_R_SDA")
	)
	(segment
		(start 247.725438 -236.640878)
		(end 248.80316 -237.7186)
		(width 0.15494)
		(layer "In13.Cu")
		(net "SMB_MB_R_SDA")
	)
	(segment
		(start 137.306812 -200.489058)
		(end 137.306812 -201.647806)
		(width 0.2794)
		(layer "F.Cu")
		(net "P3V3_CLI_VPHY")
	)
	(via
		(at 137.306812 -201.647806)
		(size 0.508)
		(drill 0.254)
		(layers "F.Cu" "B.Cu")
		(net "P3V3_CLI_VPHY")
	)
	(via
		(at 137.122408 -200.177146)
		(size 0.6604)
		(drill 0.3302)
		(layers "F.Cu" "B.Cu")
		(net "P3V3_CLI_VPHY")
	)
	(segment
		(start 135.9916 -169.835068)
		(end 135.9916 -168.323768)
		(width 0.13462)
		(layer "F.Cu")
		(net "CLK_100M_DB2000QL_NIC1_R_DP")
	)
	(segment
		(start 74.638154 -117.464332)
		(end 73.873868 -117.464332)
		(width 0.13462)
		(layer "F.Cu")
		(net "CLK_100M_DB2000QL_NIC1_R_DP")
	)
	(segment
		(start 135.626856 -170.199812)
		(end 135.9916 -169.835068)
		(width 0.13462)
		(layer "F.Cu")
		(net "CLK_100M_DB2000QL_NIC1_R_DP")
	)
	(segment
		(start 73.873868 -117.464332)
		(end 73.70318 -117.63502)
		(width 0.13462)
		(layer "F.Cu")
		(net "CLK_100M_DB2000QL_NIC1_R_DP")
	)
	(segment
		(start 74.932794 -117.758972)
		(end 74.638154 -117.464332)
		(width 0.13462)
		(layer "F.Cu")
		(net "CLK_100M_DB2000QL_NIC1_R_DP")
	)
	(segment
		(start 135.9916 -168.323768)
		(end 135.703056 -168.035224)
		(width 0.13462)
		(layer "F.Cu")
		(net "CLK_100M_DB2000QL_NIC1_R_DP")
	)
	(segment
		(start 73.70318 -117.63502)
		(end 73.257664 -117.63502)
		(width 0.13462)
		(layer "F.Cu")
		(net "CLK_100M_DB2000QL_NIC1_R_DP")
	)
	(via
		(at 135.703056 -168.035224)
		(size 0.508)
		(drill 0.254)
		(layers "F.Cu" "B.Cu")
		(net "CLK_100M_DB2000QL_NIC1_R_DP")
	)
	(via
		(at 74.932794 -117.758972)
		(size 0.508)
		(drill 0.254)
		(layers "F.Cu" "B.Cu")
		(net "CLK_100M_DB2000QL_NIC1_R_DP")
	)
	(segment
		(start 123.443238 -133.509004)
		(end 123.443238 -145.513044)
		(width 0.13462)
		(layer "B.Cu")
		(net "CLK_100M_DB2000QL_NIC1_R_DP")
	)
	(segment
		(start 134.45744 -165.725094)
		(end 134.8613 -165.725094)
		(width 0.13462)
		(layer "B.Cu")
		(net "CLK_100M_DB2000QL_NIC1_R_DP")
	)
	(segment
		(start 122.903234 -132.969)
		(end 123.443238 -133.509004)
		(width 0.13462)
		(layer "B.Cu")
		(net "CLK_100M_DB2000QL_NIC1_R_DP")
	)
	(segment
		(start 133.91642 -165.587934)
		(end 134.32028 -165.587934)
		(width 0.13462)
		(layer "B.Cu")
		(net "CLK_100M_DB2000QL_NIC1_R_DP")
	)
	(segment
		(start 74.932794 -117.758972)
		(end 75.221084 -117.470682)
		(width 0.13462)
		(layer "B.Cu")
		(net "CLK_100M_DB2000QL_NIC1_R_DP")
	)
	(segment
		(start 133.77926 -165.725094)
		(end 133.91642 -165.587934)
		(width 0.13462)
		(layer "B.Cu")
		(net "CLK_100M_DB2000QL_NIC1_R_DP")
	)
	(segment
		(start 135.40232 -165.587934)
		(end 135.99668 -166.182294)
		(width 0.13462)
		(layer "B.Cu")
		(net "CLK_100M_DB2000QL_NIC1_R_DP")
	)
	(segment
		(start 75.626976 -117.470682)
		(end 76.175616 -118.019322)
		(width 0.13462)
		(layer "B.Cu")
		(net "CLK_100M_DB2000QL_NIC1_R_DP")
	)
	(segment
		(start 132.1562 -165.587934)
		(end 132.29336 -165.725094)
		(width 0.13462)
		(layer "B.Cu")
		(net "CLK_100M_DB2000QL_NIC1_R_DP")
	)
	(segment
		(start 135.99668 -167.7416)
		(end 135.703056 -168.035224)
		(width 0.13462)
		(layer "B.Cu")
		(net "CLK_100M_DB2000QL_NIC1_R_DP")
	)
	(segment
		(start 131.07416 -165.587934)
		(end 131.21132 -165.725094)
		(width 0.13462)
		(layer "B.Cu")
		(net "CLK_100M_DB2000QL_NIC1_R_DP")
	)
	(segment
		(start 134.32028 -165.587934)
		(end 134.45744 -165.725094)
		(width 0.13462)
		(layer "B.Cu")
		(net "CLK_100M_DB2000QL_NIC1_R_DP")
	)
	(segment
		(start 131.75234 -165.587934)
		(end 132.1562 -165.587934)
		(width 0.13462)
		(layer "B.Cu")
		(net "CLK_100M_DB2000QL_NIC1_R_DP")
	)
	(segment
		(start 133.23824 -165.587934)
		(end 133.3754 -165.725094)
		(width 0.13462)
		(layer "B.Cu")
		(net "CLK_100M_DB2000QL_NIC1_R_DP")
	)
	(segment
		(start 134.99846 -165.587934)
		(end 135.40232 -165.587934)
		(width 0.13462)
		(layer "B.Cu")
		(net "CLK_100M_DB2000QL_NIC1_R_DP")
	)
	(segment
		(start 131.21132 -165.725094)
		(end 131.61518 -165.725094)
		(width 0.13462)
		(layer "B.Cu")
		(net "CLK_100M_DB2000QL_NIC1_R_DP")
	)
	(segment
		(start 76.175616 -118.019322)
		(end 76.175616 -121.236232)
		(width 0.13462)
		(layer "B.Cu")
		(net "CLK_100M_DB2000QL_NIC1_R_DP")
	)
	(segment
		(start 132.69722 -165.725094)
		(end 132.83438 -165.587934)
		(width 0.13462)
		(layer "B.Cu")
		(net "CLK_100M_DB2000QL_NIC1_R_DP")
	)
	(segment
		(start 131.61518 -165.725094)
		(end 131.75234 -165.587934)
		(width 0.13462)
		(layer "B.Cu")
		(net "CLK_100M_DB2000QL_NIC1_R_DP")
	)
	(segment
		(start 133.3754 -165.725094)
		(end 133.77926 -165.725094)
		(width 0.13462)
		(layer "B.Cu")
		(net "CLK_100M_DB2000QL_NIC1_R_DP")
	)
	(segment
		(start 87.908384 -132.969)
		(end 122.903234 -132.969)
		(width 0.13462)
		(layer "B.Cu")
		(net "CLK_100M_DB2000QL_NIC1_R_DP")
	)
	(segment
		(start 121.726706 -147.229576)
		(end 121.726706 -160.880298)
		(width 0.13462)
		(layer "B.Cu")
		(net "CLK_100M_DB2000QL_NIC1_R_DP")
	)
	(segment
		(start 132.29336 -165.725094)
		(end 132.69722 -165.725094)
		(width 0.13462)
		(layer "B.Cu")
		(net "CLK_100M_DB2000QL_NIC1_R_DP")
	)
	(segment
		(start 75.221084 -117.470682)
		(end 75.626976 -117.470682)
		(width 0.13462)
		(layer "B.Cu")
		(net "CLK_100M_DB2000QL_NIC1_R_DP")
	)
	(segment
		(start 121.726706 -160.880298)
		(end 126.434342 -165.587934)
		(width 0.13462)
		(layer "B.Cu")
		(net "CLK_100M_DB2000QL_NIC1_R_DP")
	)
	(segment
		(start 134.8613 -165.725094)
		(end 134.99846 -165.587934)
		(width 0.13462)
		(layer "B.Cu")
		(net "CLK_100M_DB2000QL_NIC1_R_DP")
	)
	(segment
		(start 123.443238 -145.513044)
		(end 121.726706 -147.229576)
		(width 0.13462)
		(layer "B.Cu")
		(net "CLK_100M_DB2000QL_NIC1_R_DP")
	)
	(segment
		(start 76.175616 -121.236232)
		(end 87.908384 -132.969)
		(width 0.13462)
		(layer "B.Cu")
		(net "CLK_100M_DB2000QL_NIC1_R_DP")
	)
	(segment
		(start 135.99668 -166.182294)
		(end 135.99668 -167.7416)
		(width 0.13462)
		(layer "B.Cu")
		(net "CLK_100M_DB2000QL_NIC1_R_DP")
	)
	(segment
		(start 126.434342 -165.587934)
		(end 131.07416 -165.587934)
		(width 0.13462)
		(layer "B.Cu")
		(net "CLK_100M_DB2000QL_NIC1_R_DP")
	)
	(segment
		(start 132.83438 -165.587934)
		(end 133.23824 -165.587934)
		(width 0.13462)
		(layer "B.Cu")
		(net "CLK_100M_DB2000QL_NIC1_R_DP")
	)
	(segment
		(start 335.895696 -89.714324)
		(end 335.895696 -90.2081)
		(width 0.13208)
		(layer "F.Cu")
		(net "PU_9ZXL0851_8_15_HBW")
	)
	(segment
		(start 335.895696 -90.2081)
		(end 334.788002 -91.315794)
		(width 0.13208)
		(layer "F.Cu")
		(net "PU_9ZXL0851_8_15_HBW")
	)
	(segment
		(start 334.788002 -91.315794)
		(end 334.493362 -91.610434)
		(width 0.13208)
		(layer "F.Cu")
		(net "PU_9ZXL0851_8_15_HBW")
	)
	(segment
		(start 335.509362 -92.752164)
		(end 334.493362 -92.752164)
		(width 0.13208)
		(layer "F.Cu")
		(net "PU_9ZXL0851_8_15_HBW")
	)
	(segment
		(start 334.493362 -91.610434)
		(end 334.493362 -92.752164)
		(width 0.13208)
		(layer "F.Cu")
		(net "PU_9ZXL0851_8_15_HBW")
	)
	(via
		(at 334.788002 -91.315794)
		(size 0.762)
		(drill 0.381)
		(layers "F.Cu" "B.Cu")
		(net "PU_9ZXL0851_8_15_HBW")
	)
	(segment
		(start 106.064558 -334.11287)
		(end 106.064558 -333.925418)
		(width 0.1143)
		(layer "B.Cu")
		(net "CLK_100M_DB800ZL_PEX3_S0_DN")
	)
	(segment
		(start 106.281474 -337.002882)
		(end 105.9561 -336.677508)
		(width 0.1143)
		(layer "B.Cu")
		(net "CLK_100M_DB800ZL_PEX3_S0_DN")
	)
	(segment
		(start 105.9561 -336.677508)
		(end 105.9561 -335.688432)
		(width 0.1143)
		(layer "B.Cu")
		(net "CLK_100M_DB800ZL_PEX3_S0_DN")
	)
	(segment
		(start 105.9561 -335.688432)
		(end 105.9942 -335.650332)
		(width 0.1143)
		(layer "B.Cu")
		(net "CLK_100M_DB800ZL_PEX3_S0_DN")
	)
	(segment
		(start 105.9942 -335.650332)
		(end 105.9942 -334.183228)
		(width 0.1143)
		(layer "B.Cu")
		(net "CLK_100M_DB800ZL_PEX3_S0_DN")
	)
	(segment
		(start 105.9942 -334.183228)
		(end 106.064558 -334.11287)
		(width 0.1143)
		(layer "B.Cu")
		(net "CLK_100M_DB800ZL_PEX3_S0_DN")
	)
	(via
		(at 220.29674 -221.930722)
		(size 0.6604)
		(drill 0.3302)
		(layers "F.Cu" "B.Cu")
		(net "SMB_BIC_FPGA_SCL")
	)
	(segment
		(start 217.63355 -222.368872)
		(end 217.635836 -222.366586)
		(width 0.13208)
		(layer "B.Cu")
		(net "SMB_BIC_FPGA_SCL")
	)
	(segment
		(start 219.018612 -221.350586)
		(end 218.651836 -221.350586)
		(width 0.13208)
		(layer "B.Cu")
		(net "SMB_BIC_FPGA_SCL")
	)
	(segment
		(start 219.52077 -220.762068)
		(end 220.29674 -221.538038)
		(width 0.13208)
		(layer "B.Cu")
		(net "SMB_BIC_FPGA_SCL")
	)
	(segment
		(start 220.29674 -221.930722)
		(end 219.598748 -221.930722)
		(width 0.13208)
		(layer "B.Cu")
		(net "SMB_BIC_FPGA_SCL")
	)
	(segment
		(start 219.598748 -221.930722)
		(end 219.018612 -221.350586)
		(width 0.13208)
		(layer "B.Cu")
		(net "SMB_BIC_FPGA_SCL")
	)
	(segment
		(start 218.651836 -221.350586)
		(end 217.635836 -222.366586)
		(width 0.13208)
		(layer "B.Cu")
		(net "SMB_BIC_FPGA_SCL")
	)
	(segment
		(start 220.29674 -221.538038)
		(end 220.29674 -221.930722)
		(width 0.13208)
		(layer "B.Cu")
		(net "SMB_BIC_FPGA_SCL")
	)
	(segment
		(start 217.635836 -221.350586)
		(end 217.635836 -222.366586)
		(width 0.13208)
		(layer "B.Cu")
		(net "SMB_BIC_FPGA_SCL")
	)
	(segment
		(start 90.731086 -394.587222)
		(end 90.65006 -394.506196)
		(width 0.1651)
		(layer "In11.Cu")
		(net "P2E_GPU_FPGA_PEX_RX_DP<0>")
	)
	(segment
		(start 91.710002 -405.390096)
		(end 91.710002 -405.775922)
		(width 0.1651)
		(layer "In11.Cu")
		(net "P2E_GPU_FPGA_PEX_RX_DP<0>")
	)
	(segment
		(start 50.773838 -397.036544)
		(end 49.19091 -404.994364)
		(width 0.1651)
		(layer "In11.Cu")
		(net "P2E_GPU_FPGA_PEX_RX_DP<0>")
	)
	(segment
		(start 47.71009 -405.775922)
		(end 47.71009 -405.390096)
		(width 0.1651)
		(layer "In11.Cu")
		(net "P2E_GPU_FPGA_PEX_RX_DP<0>")
	)
	(segment
		(start 91.410028 -405.895302)
		(end 90.731086 -405.21636)
		(width 0.1651)
		(layer "In11.Cu")
		(net "P2E_GPU_FPGA_PEX_RX_DP<0>")
	)
	(segment
		(start 47.82947 -405.895302)
		(end 47.71009 -405.775922)
		(width 0.1651)
		(layer "In11.Cu")
		(net "P2E_GPU_FPGA_PEX_RX_DP<0>")
	)
	(segment
		(start 90.639392 -394.506196)
		(end 89.98331 -393.850114)
		(width 0.1651)
		(layer "In11.Cu")
		(net "P2E_GPU_FPGA_PEX_RX_DP<0>")
	)
	(segment
		(start 88.617806 -393.535662)
		(end 54.918864 -393.73175)
		(width 0.1651)
		(layer "In11.Cu")
		(net "P2E_GPU_FPGA_PEX_RX_DP<0>")
	)
	(segment
		(start 52.417726 -393.73175)
		(end 52.036218 -393.986512)
		(width 0.1651)
		(layer "In11.Cu")
		(net "P2E_GPU_FPGA_PEX_RX_DP<0>")
	)
	(segment
		(start 89.98331 -393.850114)
		(end 88.617806 -393.535662)
		(width 0.1651)
		(layer "In11.Cu")
		(net "P2E_GPU_FPGA_PEX_RX_DP<0>")
	)
	(segment
		(start 54.918864 -393.73175)
		(end 52.417726 -393.73175)
		(width 0.1651)
		(layer "In11.Cu")
		(net "P2E_GPU_FPGA_PEX_RX_DP<0>")
	)
	(segment
		(start 52.036218 -393.986512)
		(end 50.773838 -397.036544)
		(width 0.1651)
		(layer "In11.Cu")
		(net "P2E_GPU_FPGA_PEX_RX_DP<0>")
	)
	(segment
		(start 90.65006 -394.506196)
		(end 90.639392 -394.506196)
		(width 0.1651)
		(layer "In11.Cu")
		(net "P2E_GPU_FPGA_PEX_RX_DP<0>")
	)
	(segment
		(start 91.710002 -405.775922)
		(end 91.590622 -405.895302)
		(width 0.1651)
		(layer "In11.Cu")
		(net "P2E_GPU_FPGA_PEX_RX_DP<0>")
	)
	(segment
		(start 90.731086 -405.21636)
		(end 90.731086 -394.587222)
		(width 0.1651)
		(layer "In11.Cu")
		(net "P2E_GPU_FPGA_PEX_RX_DP<0>")
	)
	(segment
		(start 48.289972 -405.895302)
		(end 47.82947 -405.895302)
		(width 0.1651)
		(layer "In11.Cu")
		(net "P2E_GPU_FPGA_PEX_RX_DP<0>")
	)
	(segment
		(start 91.590622 -405.895302)
		(end 91.410028 -405.895302)
		(width 0.1651)
		(layer "In11.Cu")
		(net "P2E_GPU_FPGA_PEX_RX_DP<0>")
	)
	(segment
		(start 49.19091 -404.994364)
		(end 48.289972 -405.895302)
		(width 0.1651)
		(layer "In11.Cu")
		(net "P2E_GPU_FPGA_PEX_RX_DP<0>")
	)
	(segment
		(start 230.961692 -76.796138)
		(end 230.660702 -77.097128)
		(width 0.13462)
		(layer "F.Cu")
		(net "USB2_FIO_DP")
	)
	(segment
		(start 230.72979 -78.18247)
		(end 230.72979 -78.54569)
		(width 0.13462)
		(layer "F.Cu")
		(net "USB2_FIO_DP")
	)
	(segment
		(start 230.660702 -78.113382)
		(end 230.72979 -78.18247)
		(width 0.13462)
		(layer "F.Cu")
		(net "USB2_FIO_DP")
	)
	(segment
		(start 227.188776 -59.562746)
		(end 226.894136 -59.268106)
		(width 0.13462)
		(layer "F.Cu")
		(net "USB2_FIO_DP")
	)
	(segment
		(start 228.77272 -59.562746)
		(end 227.188776 -59.562746)
		(width 0.13462)
		(layer "F.Cu")
		(net "USB2_FIO_DP")
	)
	(segment
		(start 229.437438 -59.399932)
		(end 228.935534 -59.399932)
		(width 0.13462)
		(layer "F.Cu")
		(net "USB2_FIO_DP")
	)
	(segment
		(start 230.660702 -77.097128)
		(end 230.660702 -78.113382)
		(width 0.13462)
		(layer "F.Cu")
		(net "USB2_FIO_DP")
	)
	(segment
		(start 228.935534 -59.399932)
		(end 228.77272 -59.562746)
		(width 0.13462)
		(layer "F.Cu")
		(net "USB2_FIO_DP")
	)
	(via
		(at 230.961692 -76.796138)
		(size 0.508)
		(drill 0.254)
		(layers "F.Cu" "B.Cu")
		(net "USB2_FIO_DP")
	)
	(via
		(at 226.894136 -59.268106)
		(size 0.508)
		(drill 0.254)
		(layers "F.Cu" "B.Cu")
		(net "USB2_FIO_DP")
	)
	(segment
		(start 229.357428 -73.350374)
		(end 229.357428 -60.219082)
		(width 0.13462)
		(layer "B.Cu")
		(net "USB2_FIO_DP")
	)
	(segment
		(start 230.961692 -76.796138)
		(end 230.669084 -76.50353)
		(width 0.13462)
		(layer "B.Cu")
		(net "USB2_FIO_DP")
	)
	(segment
		(start 230.669084 -74.66203)
		(end 229.357428 -73.350374)
		(width 0.13462)
		(layer "B.Cu")
		(net "USB2_FIO_DP")
	)
	(segment
		(start 228.706426 -59.56808)
		(end 227.19411 -59.56808)
		(width 0.13462)
		(layer "B.Cu")
		(net "USB2_FIO_DP")
	)
	(segment
		(start 229.357428 -60.219082)
		(end 228.706426 -59.56808)
		(width 0.13462)
		(layer "B.Cu")
		(net "USB2_FIO_DP")
	)
	(segment
		(start 227.19411 -59.56808)
		(end 226.894136 -59.268106)
		(width 0.13462)
		(layer "B.Cu")
		(net "USB2_FIO_DP")
	)
	(segment
		(start 230.669084 -76.50353)
		(end 230.669084 -74.66203)
		(width 0.13462)
		(layer "B.Cu")
		(net "USB2_FIO_DP")
	)
	(segment
		(start 141.690344 -216.323926)
		(end 141.421866 -216.323926)
		(width 0.381)
		(layer "F.Cu")
		(net "P1V8_CLI_VCORE")
	)
	(segment
		(start 140.996416 -215.898476)
		(end 140.996416 -214.982806)
		(width 0.381)
		(layer "F.Cu")
		(net "P1V8_CLI_VCORE")
	)
	(segment
		(start 133.831838 -209.96402)
		(end 134.953502 -209.96402)
		(width 0.2794)
		(layer "F.Cu")
		(net "P1V8_CLI_VCORE")
	)
	(segment
		(start 140.996416 -213.86419)
		(end 141.148054 -213.712552)
		(width 0.381)
		(layer "F.Cu")
		(net "P1V8_CLI_VCORE")
	)
	(segment
		(start 141.306804 -210.817206)
		(end 141.306804 -211.93887)
		(width 0.2794)
		(layer "F.Cu")
		(net "P1V8_CLI_VCORE")
	)
	(segment
		(start 141.421866 -216.323926)
		(end 140.996416 -215.898476)
		(width 0.381)
		(layer "F.Cu")
		(net "P1V8_CLI_VCORE")
	)
	(segment
		(start 141.306804 -213.553802)
		(end 141.306804 -211.93887)
		(width 0.3048)
		(layer "F.Cu")
		(net "P1V8_CLI_VCORE")
	)
	(segment
		(start 133.831838 -202.463908)
		(end 132.765038 -202.463908)
		(width 0.2794)
		(layer "F.Cu")
		(net "P1V8_CLI_VCORE")
	)
	(segment
		(start 140.996416 -214.982806)
		(end 140.996416 -213.86419)
		(width 0.381)
		(layer "F.Cu")
		(net "P1V8_CLI_VCORE")
	)
	(segment
		(start 141.148054 -213.712552)
		(end 141.306804 -213.553802)
		(width 0.3048)
		(layer "F.Cu")
		(net "P1V8_CLI_VCORE")
	)
	(segment
		(start 141.306804 -200.489058)
		(end 141.306804 -201.610722)
		(width 0.2794)
		(layer "F.Cu")
		(net "P1V8_CLI_VCORE")
	)
	(via
		(at 142.433548 -201.021188)
		(size 0.6604)
		(drill 0.3302)
		(layers "F.Cu" "B.Cu")
		(net "P1V8_CLI_VCORE")
	)
	(via
		(at 134.953502 -209.96402)
		(size 0.508)
		(drill 0.254)
		(layers "F.Cu" "B.Cu")
		(net "P1V8_CLI_VCORE")
	)
	(via
		(at 141.306804 -201.610722)
		(size 0.508)
		(drill 0.254)
		(layers "F.Cu" "B.Cu")
		(net "P1V8_CLI_VCORE")
	)
	(via
		(at 141.690344 -216.323926)
		(size 0.508)
		(drill 0.254)
		(layers "F.Cu" "B.Cu")
		(net "P1V8_CLI_VCORE")
	)
	(via
		(at 132.765038 -202.463908)
		(size 0.508)
		(drill 0.254)
		(layers "F.Cu" "B.Cu")
		(net "P1V8_CLI_VCORE")
	)
	(via
		(at 133.647434 -203.50607)
		(size 0.6604)
		(drill 0.3302)
		(layers "F.Cu" "B.Cu")
		(net "P1V8_CLI_VCORE")
	)
	(via
		(at 141.306804 -210.817206)
		(size 0.508)
		(drill 0.254)
		(layers "F.Cu" "B.Cu")
		(net "P1V8_CLI_VCORE")
	)
	(segment
		(start 141.268196 -201.572114)
		(end 141.306804 -201.610722)
		(width 0.4572)
		(layer "B.Cu")
		(net "P1V8_CLI_VCORE")
	)
	(segment
		(start 133.411214 -202.367896)
		(end 132.863082 -202.367896)
		(width 0.381)
		(layer "B.Cu")
		(net "P1V8_CLI_VCORE")
	)
	(segment
		(start 141.268196 -200.91146)
		(end 141.268196 -201.572114)
		(width 0.4572)
		(layer "B.Cu")
		(net "P1V8_CLI_VCORE")
	)
	(segment
		(start 135.697214 -209.733896)
		(end 135.183626 -209.733896)
		(width 0.381)
		(layer "B.Cu")
		(net "P1V8_CLI_VCORE")
	)
	(segment
		(start 132.863082 -202.367896)
		(end 132.76707 -202.463908)
		(width 0.381)
		(layer "B.Cu")
		(net "P1V8_CLI_VCORE")
	)
	(segment
		(start 132.76707 -202.463908)
		(end 132.765038 -202.463908)
		(width 0.381)
		(layer "B.Cu")
		(net "P1V8_CLI_VCORE")
	)
	(segment
		(start 135.183626 -209.733896)
		(end 134.953502 -209.96402)
		(width 0.381)
		(layer "B.Cu")
		(net "P1V8_CLI_VCORE")
	)
	(segment
		(start 421.557704 -117.035072)
		(end 422.020238 -117.035072)
		(width 0.13462)
		(layer "F.Cu")
		(net "CLK_100M_DB2000QL_NIC7_R_DN")
	)
	(segment
		(start 422.927526 -117.20068)
		(end 423.232834 -116.895372)
		(width 0.13462)
		(layer "F.Cu")
		(net "CLK_100M_DB2000QL_NIC7_R_DN")
	)
	(segment
		(start 136.32688 -186.806332)
		(end 136.03859 -187.094622)
		(width 0.13462)
		(layer "F.Cu")
		(net "CLK_100M_DB2000QL_NIC7_R_DN")
	)
	(segment
		(start 422.185846 -117.20068)
		(end 422.927526 -117.20068)
		(width 0.13462)
		(layer "F.Cu")
		(net "CLK_100M_DB2000QL_NIC7_R_DN")
	)
	(segment
		(start 422.020238 -117.035072)
		(end 422.185846 -117.20068)
		(width 0.13462)
		(layer "F.Cu")
		(net "CLK_100M_DB2000QL_NIC7_R_DN")
	)
	(segment
		(start 136.32688 -185.421524)
		(end 136.32688 -186.806332)
		(width 0.13462)
		(layer "F.Cu")
		(net "CLK_100M_DB2000QL_NIC7_R_DN")
	)
	(segment
		(start 135.96239 -185.057034)
		(end 136.32688 -185.421524)
		(width 0.13462)
		(layer "F.Cu")
		(net "CLK_100M_DB2000QL_NIC7_R_DN")
	)
	(via
		(at 423.232834 -116.895372)
		(size 0.508)
		(drill 0.254)
		(layers "F.Cu" "B.Cu")
		(net "CLK_100M_DB2000QL_NIC7_R_DN")
	)
	(via
		(at 136.03859 -187.094622)
		(size 0.508)
		(drill 0.254)
		(layers "F.Cu" "B.Cu")
		(net "CLK_100M_DB2000QL_NIC7_R_DN")
	)
	(segment
		(start 179.438554 -173.28134)
		(end 179.832254 -173.118272)
		(width 0.1651)
		(layer "In15.Cu")
		(net "CLK_100M_DB2000QL_NIC7_R_DN")
	)
	(segment
		(start 280.397458 -167.988742)
		(end 281.307286 -167.078914)
		(width 0.1651)
		(layer "In15.Cu")
		(net "CLK_100M_DB2000QL_NIC7_R_DN")
	)
	(segment
		(start 290.62807 -167.078914)
		(end 292.06952 -165.637464)
		(width 0.1651)
		(layer "In15.Cu")
		(net "CLK_100M_DB2000QL_NIC7_R_DN")
	)
	(segment
		(start 336.354166 -165.312852)
		(end 342.28532 -165.312852)
		(width 0.1651)
		(layer "In15.Cu")
		(net "CLK_100M_DB2000QL_NIC7_R_DN")
	)
	(segment
		(start 425.186348 -160.120584)
		(end 425.186348 -118.40464)
		(width 0.1651)
		(layer "In15.Cu")
		(net "CLK_100M_DB2000QL_NIC7_R_DN")
	)
	(segment
		(start 292.06952 -165.637464)
		(end 330.559156 -165.637464)
		(width 0.1651)
		(layer "In15.Cu")
		(net "CLK_100M_DB2000QL_NIC7_R_DN")
	)
	(segment
		(start 346.038932 -166.69512)
		(end 348.434406 -169.090594)
		(width 0.1651)
		(layer "In15.Cu")
		(net "CLK_100M_DB2000QL_NIC7_R_DN")
	)
	(segment
		(start 237.388146 -167.9448)
		(end 240.203228 -170.759882)
		(width 0.1651)
		(layer "In15.Cu")
		(net "CLK_100M_DB2000QL_NIC7_R_DN")
	)
	(segment
		(start 209.633312 -170.434762)
		(end 213.441788 -170.434762)
		(width 0.1651)
		(layer "In15.Cu")
		(net "CLK_100M_DB2000QL_NIC7_R_DN")
	)
	(segment
		(start 257.758438 -167.988742)
		(end 280.397458 -167.988742)
		(width 0.1651)
		(layer "In15.Cu")
		(net "CLK_100M_DB2000QL_NIC7_R_DN")
	)
	(segment
		(start 179.832254 -173.118272)
		(end 181.167786 -171.78274)
		(width 0.1651)
		(layer "In15.Cu")
		(net "CLK_100M_DB2000QL_NIC7_R_DN")
	)
	(segment
		(start 136.634982 -188.019436)
		(end 138.486134 -188.019436)
		(width 0.1651)
		(layer "In15.Cu")
		(net "CLK_100M_DB2000QL_NIC7_R_DN")
	)
	(segment
		(start 330.559156 -165.637464)
		(end 331.870304 -164.326316)
		(width 0.1651)
		(layer "In15.Cu")
		(net "CLK_100M_DB2000QL_NIC7_R_DN")
	)
	(segment
		(start 142.12697 -184.3786)
		(end 144.2212 -184.3786)
		(width 0.1651)
		(layer "In15.Cu")
		(net "CLK_100M_DB2000QL_NIC7_R_DN")
	)
	(segment
		(start 370.468652 -167.700452)
		(end 401.796504 -167.700452)
		(width 0.1651)
		(layer "In15.Cu")
		(net "CLK_100M_DB2000QL_NIC7_R_DN")
	)
	(segment
		(start 254.987298 -170.759882)
		(end 257.758438 -167.988742)
		(width 0.1651)
		(layer "In15.Cu")
		(net "CLK_100M_DB2000QL_NIC7_R_DN")
	)
	(segment
		(start 144.401032 -184.198768)
		(end 166.321232 -184.198768)
		(width 0.1651)
		(layer "In15.Cu")
		(net "CLK_100M_DB2000QL_NIC7_R_DN")
	)
	(segment
		(start 420.264336 -165.042596)
		(end 425.186348 -160.120584)
		(width 0.1651)
		(layer "In15.Cu")
		(net "CLK_100M_DB2000QL_NIC7_R_DN")
	)
	(segment
		(start 136.33323 -187.717684)
		(end 136.634982 -188.019436)
		(width 0.1651)
		(layer "In15.Cu")
		(net "CLK_100M_DB2000QL_NIC7_R_DN")
	)
	(segment
		(start 423.97172 -117.190012)
		(end 423.527474 -117.190012)
		(width 0.1651)
		(layer "In15.Cu")
		(net "CLK_100M_DB2000QL_NIC7_R_DN")
	)
	(segment
		(start 181.167786 -171.78274)
		(end 208.285334 -171.78274)
		(width 0.1651)
		(layer "In15.Cu")
		(net "CLK_100M_DB2000QL_NIC7_R_DN")
	)
	(segment
		(start 348.434406 -169.090594)
		(end 369.07851 -169.090594)
		(width 0.1651)
		(layer "In15.Cu")
		(net "CLK_100M_DB2000QL_NIC7_R_DN")
	)
	(segment
		(start 343.667588 -166.69512)
		(end 346.038932 -166.69512)
		(width 0.1651)
		(layer "In15.Cu")
		(net "CLK_100M_DB2000QL_NIC7_R_DN")
	)
	(segment
		(start 425.186348 -118.40464)
		(end 423.97172 -117.190012)
		(width 0.1651)
		(layer "In15.Cu")
		(net "CLK_100M_DB2000QL_NIC7_R_DN")
	)
	(segment
		(start 423.527474 -117.190012)
		(end 423.232834 -116.895372)
		(width 0.1651)
		(layer "In15.Cu")
		(net "CLK_100M_DB2000QL_NIC7_R_DN")
	)
	(segment
		(start 144.2212 -184.3786)
		(end 144.401032 -184.198768)
		(width 0.1651)
		(layer "In15.Cu")
		(net "CLK_100M_DB2000QL_NIC7_R_DN")
	)
	(segment
		(start 138.486134 -188.019436)
		(end 142.12697 -184.3786)
		(width 0.1651)
		(layer "In15.Cu")
		(net "CLK_100M_DB2000QL_NIC7_R_DN")
	)
	(segment
		(start 166.321232 -184.198768)
		(end 177.23866 -173.28134)
		(width 0.1651)
		(layer "In15.Cu")
		(net "CLK_100M_DB2000QL_NIC7_R_DN")
	)
	(segment
		(start 136.33323 -187.389262)
		(end 136.33323 -187.717684)
		(width 0.1651)
		(layer "In15.Cu")
		(net "CLK_100M_DB2000QL_NIC7_R_DN")
	)
	(segment
		(start 177.23866 -173.28134)
		(end 179.438554 -173.28134)
		(width 0.1651)
		(layer "In15.Cu")
		(net "CLK_100M_DB2000QL_NIC7_R_DN")
	)
	(segment
		(start 240.203228 -170.759882)
		(end 254.987298 -170.759882)
		(width 0.1651)
		(layer "In15.Cu")
		(net "CLK_100M_DB2000QL_NIC7_R_DN")
	)
	(segment
		(start 342.28532 -165.312852)
		(end 343.667588 -166.69512)
		(width 0.1651)
		(layer "In15.Cu")
		(net "CLK_100M_DB2000QL_NIC7_R_DN")
	)
	(segment
		(start 213.441788 -170.434762)
		(end 215.93175 -167.9448)
		(width 0.1651)
		(layer "In15.Cu")
		(net "CLK_100M_DB2000QL_NIC7_R_DN")
	)
	(segment
		(start 136.03859 -187.094622)
		(end 136.33323 -187.389262)
		(width 0.1651)
		(layer "In15.Cu")
		(net "CLK_100M_DB2000QL_NIC7_R_DN")
	)
	(segment
		(start 208.285334 -171.78274)
		(end 209.633312 -170.434762)
		(width 0.1651)
		(layer "In15.Cu")
		(net "CLK_100M_DB2000QL_NIC7_R_DN")
	)
	(segment
		(start 404.45436 -165.042596)
		(end 420.264336 -165.042596)
		(width 0.1651)
		(layer "In15.Cu")
		(net "CLK_100M_DB2000QL_NIC7_R_DN")
	)
	(segment
		(start 369.07851 -169.090594)
		(end 370.468652 -167.700452)
		(width 0.1651)
		(layer "In15.Cu")
		(net "CLK_100M_DB2000QL_NIC7_R_DN")
	)
	(segment
		(start 335.36763 -164.326316)
		(end 336.354166 -165.312852)
		(width 0.1651)
		(layer "In15.Cu")
		(net "CLK_100M_DB2000QL_NIC7_R_DN")
	)
	(segment
		(start 401.796504 -167.700452)
		(end 404.45436 -165.042596)
		(width 0.1651)
		(layer "In15.Cu")
		(net "CLK_100M_DB2000QL_NIC7_R_DN")
	)
	(segment
		(start 215.93175 -167.9448)
		(end 237.388146 -167.9448)
		(width 0.1651)
		(layer "In15.Cu")
		(net "CLK_100M_DB2000QL_NIC7_R_DN")
	)
	(segment
		(start 331.870304 -164.326316)
		(end 335.36763 -164.326316)
		(width 0.1651)
		(layer "In15.Cu")
		(net "CLK_100M_DB2000QL_NIC7_R_DN")
	)
	(segment
		(start 281.307286 -167.078914)
		(end 290.62807 -167.078914)
		(width 0.1651)
		(layer "In15.Cu")
		(net "CLK_100M_DB2000QL_NIC7_R_DN")
	)
	(segment
		(start 103.673402 -330.872592)
		(end 103.745538 -330.800456)
		(width 0.1143)
		(layer "B.Cu")
		(net "CLK_100M_DB800ZL_PEX1_S0_DP")
	)
	(segment
		(start 100.555044 -330.01585)
		(end 100.878894 -330.3397)
		(width 0.1143)
		(layer "B.Cu")
		(net "CLK_100M_DB800ZL_PEX1_S0_DP")
	)
	(segment
		(start 102.67061 -330.3397)
		(end 103.190802 -330.859892)
		(width 0.1143)
		(layer "B.Cu")
		(net "CLK_100M_DB800ZL_PEX1_S0_DP")
	)
	(segment
		(start 103.745538 -330.800456)
		(end 103.939594 -330.800456)
		(width 0.1143)
		(layer "B.Cu")
		(net "CLK_100M_DB800ZL_PEX1_S0_DP")
	)
	(segment
		(start 103.6701 -330.872592)
		(end 103.673402 -330.872592)
		(width 0.1143)
		(layer "B.Cu")
		(net "CLK_100M_DB800ZL_PEX1_S0_DP")
	)
	(segment
		(start 103.190802 -330.859892)
		(end 103.6574 -330.859892)
		(width 0.1143)
		(layer "B.Cu")
		(net "CLK_100M_DB800ZL_PEX1_S0_DP")
	)
	(segment
		(start 100.878894 -330.3397)
		(end 102.67061 -330.3397)
		(width 0.1143)
		(layer "B.Cu")
		(net "CLK_100M_DB800ZL_PEX1_S0_DP")
	)
	(segment
		(start 103.6574 -330.859892)
		(end 103.6701 -330.872592)
		(width 0.1143)
		(layer "B.Cu")
		(net "CLK_100M_DB800ZL_PEX1_S0_DP")
	)
	(segment
		(start 139.80668 -200.489058)
		(end 139.80668 -201.610722)
		(width 0.2794)
		(layer "F.Cu")
		(net "P3V3_CLI_VPLL")
	)
	(via
		(at 139.928854 -200.535286)
		(size 0.6604)
		(drill 0.3302)
		(layers "F.Cu" "B.Cu")
		(net "P3V3_CLI_VPLL")
	)
	(via
		(at 139.80668 -201.610722)
		(size 0.508)
		(drill 0.254)
		(layers "F.Cu" "B.Cu")
		(net "P3V3_CLI_VPLL")
	)
	(segment
		(start 136.26592 -169.822876)
		(end 136.26592 -168.33596)
		(width 0.13462)
		(layer "F.Cu")
		(net "CLK_100M_DB2000QL_NIC1_R_DN")
	)
	(segment
		(start 74.932794 -116.895372)
		(end 74.638154 -117.190012)
		(width 0.13462)
		(layer "F.Cu")
		(net "CLK_100M_DB2000QL_NIC1_R_DN")
	)
	(segment
		(start 73.873868 -117.190012)
		(end 73.718928 -117.035072)
		(width 0.13462)
		(layer "F.Cu")
		(net "CLK_100M_DB2000QL_NIC1_R_DN")
	)
	(segment
		(start 136.26592 -168.33596)
		(end 136.566656 -168.035224)
		(width 0.13462)
		(layer "F.Cu")
		(net "CLK_100M_DB2000QL_NIC1_R_DN")
	)
	(segment
		(start 73.718928 -117.035072)
		(end 73.257664 -117.035072)
		(width 0.13462)
		(layer "F.Cu")
		(net "CLK_100M_DB2000QL_NIC1_R_DN")
	)
	(segment
		(start 74.638154 -117.190012)
		(end 73.873868 -117.190012)
		(width 0.13462)
		(layer "F.Cu")
		(net "CLK_100M_DB2000QL_NIC1_R_DN")
	)
	(segment
		(start 136.642856 -170.199812)
		(end 136.26592 -169.822876)
		(width 0.13462)
		(layer "F.Cu")
		(net "CLK_100M_DB2000QL_NIC1_R_DN")
	)
	(via
		(at 136.566656 -168.035224)
		(size 0.508)
		(drill 0.254)
		(layers "F.Cu" "B.Cu")
		(net "CLK_100M_DB2000QL_NIC1_R_DN")
	)
	(via
		(at 74.932794 -116.895372)
		(size 0.508)
		(drill 0.254)
		(layers "F.Cu" "B.Cu")
		(net "CLK_100M_DB2000QL_NIC1_R_DN")
	)
	(segment
		(start 126.548134 -165.313614)
		(end 135.516112 -165.313614)
		(width 0.13462)
		(layer "B.Cu")
		(net "CLK_100M_DB2000QL_NIC1_R_DN")
	)
	(segment
		(start 136.271 -167.739568)
		(end 136.566656 -168.035224)
		(width 0.13462)
		(layer "B.Cu")
		(net "CLK_100M_DB2000QL_NIC1_R_DN")
	)
	(segment
		(start 75.233784 -117.196362)
		(end 75.740768 -117.196362)
		(width 0.13462)
		(layer "B.Cu")
		(net "CLK_100M_DB2000QL_NIC1_R_DN")
	)
	(segment
		(start 123.017026 -132.69468)
		(end 123.717558 -133.395212)
		(width 0.13462)
		(layer "B.Cu")
		(net "CLK_100M_DB2000QL_NIC1_R_DN")
	)
	(segment
		(start 75.740768 -117.196362)
		(end 76.449936 -117.90553)
		(width 0.13462)
		(layer "B.Cu")
		(net "CLK_100M_DB2000QL_NIC1_R_DN")
	)
	(segment
		(start 74.932794 -116.895372)
		(end 75.233784 -117.196362)
		(width 0.13462)
		(layer "B.Cu")
		(net "CLK_100M_DB2000QL_NIC1_R_DN")
	)
	(segment
		(start 76.449936 -117.90553)
		(end 76.449936 -121.12244)
		(width 0.13462)
		(layer "B.Cu")
		(net "CLK_100M_DB2000QL_NIC1_R_DN")
	)
	(segment
		(start 136.271 -166.068502)
		(end 136.271 -167.739568)
		(width 0.13462)
		(layer "B.Cu")
		(net "CLK_100M_DB2000QL_NIC1_R_DN")
	)
	(segment
		(start 122.001026 -147.343368)
		(end 122.001026 -160.766506)
		(width 0.13462)
		(layer "B.Cu")
		(net "CLK_100M_DB2000QL_NIC1_R_DN")
	)
	(segment
		(start 88.022176 -132.69468)
		(end 123.017026 -132.69468)
		(width 0.13462)
		(layer "B.Cu")
		(net "CLK_100M_DB2000QL_NIC1_R_DN")
	)
	(segment
		(start 123.717558 -133.395212)
		(end 123.717558 -145.626836)
		(width 0.13462)
		(layer "B.Cu")
		(net "CLK_100M_DB2000QL_NIC1_R_DN")
	)
	(segment
		(start 123.717558 -145.626836)
		(end 122.001026 -147.343368)
		(width 0.13462)
		(layer "B.Cu")
		(net "CLK_100M_DB2000QL_NIC1_R_DN")
	)
	(segment
		(start 135.516112 -165.313614)
		(end 136.271 -166.068502)
		(width 0.13462)
		(layer "B.Cu")
		(net "CLK_100M_DB2000QL_NIC1_R_DN")
	)
	(segment
		(start 122.001026 -160.766506)
		(end 126.548134 -165.313614)
		(width 0.13462)
		(layer "B.Cu")
		(net "CLK_100M_DB2000QL_NIC1_R_DN")
	)
	(segment
		(start 76.449936 -121.12244)
		(end 88.022176 -132.69468)
		(width 0.13462)
		(layer "B.Cu")
		(net "CLK_100M_DB2000QL_NIC1_R_DN")
	)
	(segment
		(start 336.295492 -89.714324)
		(end 336.295492 -90.761312)
		(width 0.13208)
		(layer "F.Cu")
		(net "PU_9ZXL0851_8_15_100M")
	)
	(segment
		(start 336.551778 -91.505786)
		(end 336.551778 -92.754196)
		(width 0.13208)
		(layer "F.Cu")
		(net "PU_9ZXL0851_8_15_100M")
	)
	(segment
		(start 336.295492 -90.761312)
		(end 336.551778 -91.017598)
		(width 0.13208)
		(layer "F.Cu")
		(net "PU_9ZXL0851_8_15_100M")
	)
	(segment
		(start 336.551778 -91.017598)
		(end 336.551778 -91.505786)
		(width 0.13208)
		(layer "F.Cu")
		(net "PU_9ZXL0851_8_15_100M")
	)
	(segment
		(start 337.582256 -92.754196)
		(end 336.551778 -92.754196)
		(width 0.13208)
		(layer "F.Cu")
		(net "PU_9ZXL0851_8_15_100M")
	)
	(via
		(at 336.551778 -91.505786)
		(size 0.762)
		(drill 0.381)
		(layers "F.Cu" "B.Cu")
		(net "PU_9ZXL0851_8_15_100M")
	)
	(segment
		(start 103.65867 -332.741016)
		(end 103.718106 -332.800452)
		(width 0.1143)
		(layer "B.Cu")
		(net "CLK_100M_DB800ZL_PEX2_S0_DN")
	)
	(segment
		(start 102.315772 -333.149956)
		(end 103.30307 -332.741016)
		(width 0.1143)
		(layer "B.Cu")
		(net "CLK_100M_DB800ZL_PEX2_S0_DN")
	)
	(segment
		(start 103.718106 -332.800452)
		(end 103.939594 -332.800452)
		(width 0.1143)
		(layer "B.Cu")
		(net "CLK_100M_DB800ZL_PEX2_S0_DN")
	)
	(segment
		(start 99.75342 -334.083406)
		(end 100.080826 -333.756)
		(width 0.1143)
		(layer "B.Cu")
		(net "CLK_100M_DB800ZL_PEX2_S0_DN")
	)
	(segment
		(start 100.419408 -333.756)
		(end 101.025452 -333.149956)
		(width 0.1143)
		(layer "B.Cu")
		(net "CLK_100M_DB800ZL_PEX2_S0_DN")
	)
	(segment
		(start 100.080826 -333.756)
		(end 100.419408 -333.756)
		(width 0.1143)
		(layer "B.Cu")
		(net "CLK_100M_DB800ZL_PEX2_S0_DN")
	)
	(segment
		(start 103.30307 -332.741016)
		(end 103.65867 -332.741016)
		(width 0.1143)
		(layer "B.Cu")
		(net "CLK_100M_DB800ZL_PEX2_S0_DN")
	)
	(segment
		(start 101.025452 -333.149956)
		(end 102.315772 -333.149956)
		(width 0.1143)
		(layer "B.Cu")
		(net "CLK_100M_DB800ZL_PEX2_S0_DN")
	)
	(segment
		(start 63.7286 -388.0612)
		(end 63.60414 -387.93674)
		(width 0.13208)
		(layer "F.Cu")
		(net "GPU_PEX_STRAP1")
	)
	(segment
		(start 62.332616 -387.93674)
		(end 59.098688 -384.702812)
		(width 0.13208)
		(layer "F.Cu")
		(net "GPU_PEX_STRAP1")
	)
	(segment
		(start 63.722504 -389.326628)
		(end 63.7286 -389.320532)
		(width 0.13208)
		(layer "F.Cu")
		(net "GPU_PEX_STRAP1")
	)
	(segment
		(start 63.60414 -387.93674)
		(end 63.002668 -387.93674)
		(width 0.13208)
		(layer "F.Cu")
		(net "GPU_PEX_STRAP1")
	)
	(segment
		(start 63.7286 -389.320532)
		(end 63.7286 -388.0612)
		(width 0.13208)
		(layer "F.Cu")
		(net "GPU_PEX_STRAP1")
	)
	(segment
		(start 63.002668 -387.93674)
		(end 62.332616 -387.93674)
		(width 0.13208)
		(layer "F.Cu")
		(net "GPU_PEX_STRAP1")
	)
	(segment
		(start 59.098688 -384.702812)
		(end 59.086242 -384.702812)
		(width 0.13208)
		(layer "F.Cu")
		(net "GPU_PEX_STRAP1")
	)
	(via
		(at 63.722504 -389.326628)
		(size 0.508)
		(drill 0.254)
		(layers "F.Cu" "B.Cu")
		(net "GPU_PEX_STRAP1")
	)
	(segment
		(start 70.252844 -416.099244)
		(end 92.256356 -416.099244)
		(width 0.13208)
		(layer "B.Cu")
		(net "GPU_PEX_STRAP1")
	)
	(segment
		(start 92.867988 -402.648166)
		(end 91.710002 -401.49018)
		(width 0.13208)
		(layer "B.Cu")
		(net "GPU_PEX_STRAP1")
	)
	(segment
		(start 66.764154 -412.610554)
		(end 70.252844 -416.099244)
		(width 0.13208)
		(layer "B.Cu")
		(net "GPU_PEX_STRAP1")
	)
	(segment
		(start 92.256356 -416.099244)
		(end 92.867988 -415.487612)
		(width 0.13208)
		(layer "B.Cu")
		(net "GPU_PEX_STRAP1")
	)
	(segment
		(start 92.867988 -415.487612)
		(end 92.867988 -402.648166)
		(width 0.13208)
		(layer "B.Cu")
		(net "GPU_PEX_STRAP1")
	)
	(segment
		(start 63.722504 -389.326628)
		(end 66.764154 -392.368278)
		(width 0.13208)
		(layer "B.Cu")
		(net "GPU_PEX_STRAP1")
	)
	(segment
		(start 66.764154 -392.368278)
		(end 66.764154 -412.610554)
		(width 0.13208)
		(layer "B.Cu")
		(net "GPU_PEX_STRAP1")
	)
	(segment
		(start 447.276728 -208.504282)
		(end 446.96253 -208.81848)
		(width 0.13462)
		(layer "F.Cu")
		(net "USB2_MICRO_DN")
	)
	(segment
		(start 445.746124 -208.516982)
		(end 445.746124 -208.467198)
		(width 0.13462)
		(layer "F.Cu")
		(net "USB2_MICRO_DN")
	)
	(segment
		(start 446.047622 -208.81848)
		(end 445.746124 -208.516982)
		(width 0.13462)
		(layer "F.Cu")
		(net "USB2_MICRO_DN")
	)
	(segment
		(start 446.96253 -208.81848)
		(end 446.047622 -208.81848)
		(width 0.13462)
		(layer "F.Cu")
		(net "USB2_MICRO_DN")
	)
	(segment
		(start 229.545896 -79.005684)
		(end 229.468934 -78.928722)
		(width 0.13462)
		(layer "F.Cu")
		(net "USB2_MICRO_DN")
	)
	(segment
		(start 229.468934 -78.928722)
		(end 228.744526 -78.928722)
		(width 0.13462)
		(layer "F.Cu")
		(net "USB2_MICRO_DN")
	)
	(segment
		(start 228.744526 -78.928722)
		(end 228.435408 -79.23784)
		(width 0.13462)
		(layer "F.Cu")
		(net "USB2_MICRO_DN")
	)
	(segment
		(start 229.794816 -79.005684)
		(end 229.545896 -79.005684)
		(width 0.13462)
		(layer "F.Cu")
		(net "USB2_MICRO_DN")
	)
	(via
		(at 445.746124 -208.467198)
		(size 0.508)
		(drill 0.254)
		(layers "F.Cu" "B.Cu")
		(net "USB2_MICRO_DN")
	)
	(via
		(at 413.202628 -167.519604)
		(size 0.4064)
		(drill 0.2032)
		(layers "F.Cu" "B.Cu")
		(net "USB2_MICRO_DN")
	)
	(via
		(at 228.435408 -79.23784)
		(size 0.508)
		(drill 0.254)
		(layers "F.Cu" "B.Cu")
		(net "USB2_MICRO_DN")
	)
	(segment
		(start 407.605992 -161.225992)
		(end 413.202628 -166.822628)
		(width 0.13462)
		(layer "B.Cu")
		(net "USB2_MICRO_DN")
	)
	(segment
		(start 276.237192 -75.457558)
		(end 277.049992 -75.457558)
		(width 0.13462)
		(layer "B.Cu")
		(net "USB2_MICRO_DN")
	)
	(segment
		(start 264.043668 -67.805554)
		(end 264.417048 -67.959986)
		(width 0.13462)
		(layer "B.Cu")
		(net "USB2_MICRO_DN")
	)
	(segment
		(start 330.763118 -78.503018)
		(end 330.763118 -78.308962)
		(width 0.13462)
		(layer "B.Cu")
		(net "USB2_MICRO_DN")
	)
	(segment
		(start 228.435408 -79.23784)
		(end 228.723698 -78.94955)
		(width 0.13462)
		(layer "B.Cu")
		(net "USB2_MICRO_DN")
	)
	(segment
		(start 231.656636 -80.553814)
		(end 235.048298 -80.553814)
		(width 0.13462)
		(layer "B.Cu")
		(net "USB2_MICRO_DN")
	)
	(segment
		(start 235.048298 -80.553814)
		(end 240.267998 -75.334114)
		(width 0.13462)
		(layer "B.Cu")
		(net "USB2_MICRO_DN")
	)
	(segment
		(start 329.712066 -79.553816)
		(end 329.997816 -79.268066)
		(width 0.13462)
		(layer "B.Cu")
		(net "USB2_MICRO_DN")
	)
	(segment
		(start 228.723698 -78.94955)
		(end 230.052372 -78.94955)
		(width 0.13462)
		(layer "B.Cu")
		(net "USB2_MICRO_DN")
	)
	(segment
		(start 266.41679 -68.788534)
		(end 266.59586 -68.714112)
		(width 0.13462)
		(layer "B.Cu")
		(net "USB2_MICRO_DN")
	)
	(segment
		(start 407.605992 -130.283458)
		(end 407.605992 -145.59407)
		(width 0.13462)
		(layer "B.Cu")
		(net "USB2_MICRO_DN")
	)
	(segment
		(start 291.723826 -80.834738)
		(end 293.246556 -82.357468)
		(width 0.13462)
		(layer "B.Cu")
		(net "USB2_MICRO_DN")
	)
	(segment
		(start 329.997816 -79.268066)
		(end 329.997816 -79.074264)
		(width 0.13462)
		(layer "B.Cu")
		(net "USB2_MICRO_DN")
	)
	(segment
		(start 264.969244 -68.04025)
		(end 265.043666 -68.219574)
		(width 0.13462)
		(layer "B.Cu")
		(net "USB2_MICRO_DN")
	)
	(segment
		(start 266.04341 -68.633848)
		(end 266.41679 -68.788534)
		(width 0.13462)
		(layer "B.Cu")
		(net "USB2_MICRO_DN")
	)
	(segment
		(start 332.055724 -77.016356)
		(end 341.869522 -77.016356)
		(width 0.13462)
		(layer "B.Cu")
		(net "USB2_MICRO_DN")
	)
	(segment
		(start 311.485026 -78.35392)
		(end 313.474862 -78.35392)
		(width 0.13462)
		(layer "B.Cu")
		(net "USB2_MICRO_DN")
	)
	(segment
		(start 413.202628 -167.519604)
		(end 413.202628 -168.727374)
		(width 0.13462)
		(layer "B.Cu")
		(net "USB2_MICRO_DN")
	)
	(segment
		(start 329.518264 -79.553816)
		(end 329.712066 -79.553816)
		(width 0.13462)
		(layer "B.Cu")
		(net "USB2_MICRO_DN")
	)
	(segment
		(start 413.202628 -166.822628)
		(end 413.202628 -167.519604)
		(width 0.13462)
		(layer "B.Cu")
		(net "USB2_MICRO_DN")
	)
	(segment
		(start 315.100462 -79.97952)
		(end 329.09256 -79.97952)
		(width 0.13462)
		(layer "B.Cu")
		(net "USB2_MICRO_DN")
	)
	(segment
		(start 447.176144 -208.788)
		(end 446.066926 -208.788)
		(width 0.13462)
		(layer "B.Cu")
		(net "USB2_MICRO_DN")
	)
	(segment
		(start 446.066926 -208.788)
		(end 445.746124 -208.467198)
		(width 0.13462)
		(layer "B.Cu")
		(net "USB2_MICRO_DN")
	)
	(segment
		(start 380.417578 -104.397556)
		(end 380.417578 -127.397256)
		(width 0.13462)
		(layer "B.Cu")
		(net "USB2_MICRO_DN")
	)
	(segment
		(start 330.763118 -78.308962)
		(end 331.048614 -78.023466)
		(width 0.13462)
		(layer "B.Cu")
		(net "USB2_MICRO_DN")
	)
	(segment
		(start 407.605992 -147.35429)
		(end 407.605992 -161.225992)
		(width 0.13462)
		(layer "B.Cu")
		(net "USB2_MICRO_DN")
	)
	(segment
		(start 380.417578 -127.397256)
		(end 382.428242 -129.40792)
		(width 0.13462)
		(layer "B.Cu")
		(net "USB2_MICRO_DN")
	)
	(segment
		(start 407.468832 -146.13509)
		(end 407.605992 -146.27225)
		(width 0.13462)
		(layer "B.Cu")
		(net "USB2_MICRO_DN")
	)
	(segment
		(start 230.052372 -78.94955)
		(end 231.656636 -80.553814)
		(width 0.13462)
		(layer "B.Cu")
		(net "USB2_MICRO_DN")
	)
	(segment
		(start 447.666364 -203.19111)
		(end 447.666364 -208.29778)
		(width 0.13462)
		(layer "B.Cu")
		(net "USB2_MICRO_DN")
	)
	(segment
		(start 407.605992 -146.27225)
		(end 407.605992 -146.67611)
		(width 0.13462)
		(layer "B.Cu")
		(net "USB2_MICRO_DN")
	)
	(segment
		(start 273.113754 -72.33412)
		(end 276.237192 -75.457558)
		(width 0.13462)
		(layer "B.Cu")
		(net "USB2_MICRO_DN")
	)
	(segment
		(start 264.417048 -67.959986)
		(end 264.596372 -67.885818)
		(width 0.13462)
		(layer "B.Cu")
		(net "USB2_MICRO_DN")
	)
	(segment
		(start 288.171128 -79.781908)
		(end 289.223958 -80.834738)
		(width 0.13462)
		(layer "B.Cu")
		(net "USB2_MICRO_DN")
	)
	(segment
		(start 241.614198 -75.334114)
		(end 242.557808 -74.390504)
		(width 0.13462)
		(layer "B.Cu")
		(net "USB2_MICRO_DN")
	)
	(segment
		(start 407.605992 -146.67611)
		(end 407.468832 -146.81327)
		(width 0.13462)
		(layer "B.Cu")
		(net "USB2_MICRO_DN")
	)
	(segment
		(start 331.52842 -77.737716)
		(end 331.52842 -77.54366)
		(width 0.13462)
		(layer "B.Cu")
		(net "USB2_MICRO_DN")
	)
	(segment
		(start 373.79148 -82.960464)
		(end 373.79148 -97.771458)
		(width 0.13462)
		(layer "B.Cu")
		(net "USB2_MICRO_DN")
	)
	(segment
		(start 407.468832 -147.21713)
		(end 407.605992 -147.35429)
		(width 0.13462)
		(layer "B.Cu")
		(net "USB2_MICRO_DN")
	)
	(segment
		(start 447.666364 -208.29778)
		(end 447.176144 -208.788)
		(width 0.13462)
		(layer "B.Cu")
		(net "USB2_MICRO_DN")
	)
	(segment
		(start 329.997816 -79.074264)
		(end 330.283312 -78.788768)
		(width 0.13462)
		(layer "B.Cu")
		(net "USB2_MICRO_DN")
	)
	(segment
		(start 407.468832 -146.81327)
		(end 407.468832 -147.21713)
		(width 0.13462)
		(layer "B.Cu")
		(net "USB2_MICRO_DN")
	)
	(segment
		(start 265.969242 -68.454524)
		(end 266.04341 -68.633848)
		(width 0.13462)
		(layer "B.Cu")
		(net "USB2_MICRO_DN")
	)
	(segment
		(start 330.477114 -78.788768)
		(end 330.763118 -78.503018)
		(width 0.13462)
		(layer "B.Cu")
		(net "USB2_MICRO_DN")
	)
	(segment
		(start 249.25655 -66.59372)
		(end 261.476744 -66.59372)
		(width 0.13462)
		(layer "B.Cu")
		(net "USB2_MICRO_DN")
	)
	(segment
		(start 299.22216 -82.357468)
		(end 300.177708 -81.40192)
		(width 0.13462)
		(layer "B.Cu")
		(net "USB2_MICRO_DN")
	)
	(segment
		(start 344.959686 -80.10652)
		(end 370.937536 -80.10652)
		(width 0.13462)
		(layer "B.Cu")
		(net "USB2_MICRO_DN")
	)
	(segment
		(start 242.557808 -74.390504)
		(end 242.557808 -73.292462)
		(width 0.13462)
		(layer "B.Cu")
		(net "USB2_MICRO_DN")
	)
	(segment
		(start 268.89837 -69.667628)
		(end 271.564862 -72.33412)
		(width 0.13462)
		(layer "B.Cu")
		(net "USB2_MICRO_DN")
	)
	(segment
		(start 341.869522 -77.016356)
		(end 344.959686 -80.10652)
		(width 0.13462)
		(layer "B.Cu")
		(net "USB2_MICRO_DN")
	)
	(segment
		(start 373.79148 -97.771458)
		(end 380.417578 -104.397556)
		(width 0.13462)
		(layer "B.Cu")
		(net "USB2_MICRO_DN")
	)
	(segment
		(start 242.557808 -73.292462)
		(end 249.25655 -66.59372)
		(width 0.13462)
		(layer "B.Cu")
		(net "USB2_MICRO_DN")
	)
	(segment
		(start 407.468832 -145.73123)
		(end 407.468832 -146.13509)
		(width 0.13462)
		(layer "B.Cu")
		(net "USB2_MICRO_DN")
	)
	(segment
		(start 331.52842 -77.54366)
		(end 332.055724 -77.016356)
		(width 0.13462)
		(layer "B.Cu")
		(net "USB2_MICRO_DN")
	)
	(segment
		(start 329.09256 -79.97952)
		(end 329.518264 -79.553816)
		(width 0.13462)
		(layer "B.Cu")
		(net "USB2_MICRO_DN")
	)
	(segment
		(start 265.043666 -68.219574)
		(end 265.417046 -68.37426)
		(width 0.13462)
		(layer "B.Cu")
		(net "USB2_MICRO_DN")
	)
	(segment
		(start 406.730454 -129.40792)
		(end 407.605992 -130.283458)
		(width 0.13462)
		(layer "B.Cu")
		(net "USB2_MICRO_DN")
	)
	(segment
		(start 263.9695 -67.62623)
		(end 264.043668 -67.805554)
		(width 0.13462)
		(layer "B.Cu")
		(net "USB2_MICRO_DN")
	)
	(segment
		(start 407.605992 -145.59407)
		(end 407.468832 -145.73123)
		(width 0.13462)
		(layer "B.Cu")
		(net "USB2_MICRO_DN")
	)
	(segment
		(start 261.476744 -66.59372)
		(end 263.9695 -67.62623)
		(width 0.13462)
		(layer "B.Cu")
		(net "USB2_MICRO_DN")
	)
	(segment
		(start 240.267998 -75.334114)
		(end 241.614198 -75.334114)
		(width 0.13462)
		(layer "B.Cu")
		(net "USB2_MICRO_DN")
	)
	(segment
		(start 331.242416 -78.023466)
		(end 331.52842 -77.737716)
		(width 0.13462)
		(layer "B.Cu")
		(net "USB2_MICRO_DN")
	)
	(segment
		(start 265.417046 -68.37426)
		(end 265.596116 -68.300092)
		(width 0.13462)
		(layer "B.Cu")
		(net "USB2_MICRO_DN")
	)
	(segment
		(start 271.564862 -72.33412)
		(end 273.113754 -72.33412)
		(width 0.13462)
		(layer "B.Cu")
		(net "USB2_MICRO_DN")
	)
	(segment
		(start 313.474862 -78.35392)
		(end 315.100462 -79.97952)
		(width 0.13462)
		(layer "B.Cu")
		(net "USB2_MICRO_DN")
	)
	(segment
		(start 265.596116 -68.300092)
		(end 265.969242 -68.454524)
		(width 0.13462)
		(layer "B.Cu")
		(net "USB2_MICRO_DN")
	)
	(segment
		(start 413.202628 -168.727374)
		(end 447.666364 -203.19111)
		(width 0.13462)
		(layer "B.Cu")
		(net "USB2_MICRO_DN")
	)
	(segment
		(start 277.049992 -75.457558)
		(end 281.374342 -79.781908)
		(width 0.13462)
		(layer "B.Cu")
		(net "USB2_MICRO_DN")
	)
	(segment
		(start 289.223958 -80.834738)
		(end 291.723826 -80.834738)
		(width 0.13462)
		(layer "B.Cu")
		(net "USB2_MICRO_DN")
	)
	(segment
		(start 308.437026 -81.40192)
		(end 311.485026 -78.35392)
		(width 0.13462)
		(layer "B.Cu")
		(net "USB2_MICRO_DN")
	)
	(segment
		(start 370.937536 -80.10652)
		(end 373.79148 -82.960464)
		(width 0.13462)
		(layer "B.Cu")
		(net "USB2_MICRO_DN")
	)
	(segment
		(start 382.428242 -129.40792)
		(end 406.730454 -129.40792)
		(width 0.13462)
		(layer "B.Cu")
		(net "USB2_MICRO_DN")
	)
	(segment
		(start 293.246556 -82.357468)
		(end 299.22216 -82.357468)
		(width 0.13462)
		(layer "B.Cu")
		(net "USB2_MICRO_DN")
	)
	(segment
		(start 331.048614 -78.023466)
		(end 331.242416 -78.023466)
		(width 0.13462)
		(layer "B.Cu")
		(net "USB2_MICRO_DN")
	)
	(segment
		(start 300.177708 -81.40192)
		(end 308.437026 -81.40192)
		(width 0.13462)
		(layer "B.Cu")
		(net "USB2_MICRO_DN")
	)
	(segment
		(start 281.374342 -79.781908)
		(end 288.171128 -79.781908)
		(width 0.13462)
		(layer "B.Cu")
		(net "USB2_MICRO_DN")
	)
	(segment
		(start 266.59586 -68.714112)
		(end 268.89837 -69.667628)
		(width 0.13462)
		(layer "B.Cu")
		(net "USB2_MICRO_DN")
	)
	(segment
		(start 330.283312 -78.788768)
		(end 330.477114 -78.788768)
		(width 0.13462)
		(layer "B.Cu")
		(net "USB2_MICRO_DN")
	)
	(segment
		(start 264.596372 -67.885818)
		(end 264.969244 -68.04025)
		(width 0.13462)
		(layer "B.Cu")
		(net "USB2_MICRO_DN")
	)
	(segment
		(start 161.512758 -137.927842)
		(end 161.675572 -137.765028)
		(width 0.13462)
		(layer "F.Cu")
		(net "CLK_100M_DB2000QL_NIC2_R_DP")
	)
	(segment
		(start 160.530286 -137.633202)
		(end 160.824926 -137.927842)
		(width 0.13462)
		(layer "F.Cu")
		(net "CLK_100M_DB2000QL_NIC2_R_DP")
	)
	(segment
		(start 140.474192 -173.865286)
		(end 140.852906 -174.244)
		(width 0.13462)
		(layer "F.Cu")
		(net "CLK_100M_DB2000QL_NIC2_R_DP")
	)
	(segment
		(start 141.701266 -174.244)
		(end 142.00378 -173.941486)
		(width 0.13462)
		(layer "F.Cu")
		(net "CLK_100M_DB2000QL_NIC2_R_DP")
	)
	(segment
		(start 160.824926 -137.927842)
		(end 161.512758 -137.927842)
		(width 0.13462)
		(layer "F.Cu")
		(net "CLK_100M_DB2000QL_NIC2_R_DP")
	)
	(segment
		(start 161.675572 -137.765028)
		(end 162.14217 -137.765028)
		(width 0.13462)
		(layer "F.Cu")
		(net "CLK_100M_DB2000QL_NIC2_R_DP")
	)
	(segment
		(start 140.852906 -174.244)
		(end 141.701266 -174.244)
		(width 0.13462)
		(layer "F.Cu")
		(net "CLK_100M_DB2000QL_NIC2_R_DP")
	)
	(via
		(at 160.530286 -137.633202)
		(size 0.508)
		(drill 0.254)
		(layers "F.Cu" "B.Cu")
		(net "CLK_100M_DB2000QL_NIC2_R_DP")
	)
	(via
		(at 142.00378 -173.941486)
		(size 0.508)
		(drill 0.254)
		(layers "F.Cu" "B.Cu")
		(net "CLK_100M_DB2000QL_NIC2_R_DP")
	)
	(segment
		(start 148.36775 -162.357816)
		(end 148.36775 -161.491676)
		(width 0.1651)
		(layer "In15.Cu")
		(net "CLK_100M_DB2000QL_NIC2_R_DP")
	)
	(segment
		(start 148.365464 -155.227782)
		(end 148.365464 -154.376882)
		(width 0.1651)
		(layer "In15.Cu")
		(net "CLK_100M_DB2000QL_NIC2_R_DP")
	)
	(segment
		(start 148.365464 -150.483062)
		(end 148.365464 -149.632162)
		(width 0.1651)
		(layer "In15.Cu")
		(net "CLK_100M_DB2000QL_NIC2_R_DP")
	)
	(segment
		(start 150.79726 -161.038794)
		(end 150.79726 -160.42767)
		(width 0.1651)
		(layer "In15.Cu")
		(net "CLK_100M_DB2000QL_NIC2_R_DP")
	)
	(segment
		(start 148.677884 -151.692102)
		(end 150.673054 -151.692102)
		(width 0.1651)
		(layer "In15.Cu")
		(net "CLK_100M_DB2000QL_NIC2_R_DP")
	)
	(segment
		(start 150.815802 -148.56587)
		(end 150.673054 -148.423122)
		(width 0.1651)
		(layer "In15.Cu")
		(net "CLK_100M_DB2000QL_NIC2_R_DP")
	)
	(segment
		(start 150.654512 -161.181542)
		(end 150.79726 -161.038794)
		(width 0.1651)
		(layer "In15.Cu")
		(net "CLK_100M_DB2000QL_NIC2_R_DP")
	)
	(segment
		(start 150.654512 -169.774362)
		(end 148.667216 -169.774362)
		(width 0.1651)
		(layer "In15.Cu")
		(net "CLK_100M_DB2000QL_NIC2_R_DP")
	)
	(segment
		(start 150.679912 -167.402002)
		(end 148.677884 -167.402002)
		(width 0.1651)
		(layer "In15.Cu")
		(net "CLK_100M_DB2000QL_NIC2_R_DP")
	)
	(segment
		(start 150.82266 -168.155874)
		(end 150.82266 -167.54475)
		(width 0.1651)
		(layer "In15.Cu")
		(net "CLK_100M_DB2000QL_NIC2_R_DP")
	)
	(segment
		(start 150.79726 -169.91711)
		(end 150.654512 -169.774362)
		(width 0.1651)
		(layer "In15.Cu")
		(net "CLK_100M_DB2000QL_NIC2_R_DP")
	)
	(segment
		(start 148.36775 -157.602428)
		(end 148.36775 -156.746956)
		(width 0.1651)
		(layer "In15.Cu")
		(net "CLK_100M_DB2000QL_NIC2_R_DP")
	)
	(segment
		(start 150.673054 -149.319742)
		(end 150.815802 -149.176994)
		(width 0.1651)
		(layer "In15.Cu")
		(net "CLK_100M_DB2000QL_NIC2_R_DP")
	)
	(segment
		(start 148.36775 -164.719508)
		(end 148.36775 -163.864036)
		(width 0.1651)
		(layer "In15.Cu")
		(net "CLK_100M_DB2000QL_NIC2_R_DP")
	)
	(segment
		(start 148.365464 -149.632162)
		(end 148.677884 -149.319742)
		(width 0.1651)
		(layer "In15.Cu")
		(net "CLK_100M_DB2000QL_NIC2_R_DP")
	)
	(segment
		(start 150.815802 -155.68295)
		(end 150.673054 -155.540202)
		(width 0.1651)
		(layer "In15.Cu")
		(net "CLK_100M_DB2000QL_NIC2_R_DP")
	)
	(segment
		(start 150.815802 -149.176994)
		(end 150.815802 -148.56587)
		(width 0.1651)
		(layer "In15.Cu")
		(net "CLK_100M_DB2000QL_NIC2_R_DP")
	)
	(segment
		(start 148.677884 -168.298622)
		(end 150.679912 -168.298622)
		(width 0.1651)
		(layer "In15.Cu")
		(net "CLK_100M_DB2000QL_NIC2_R_DP")
	)
	(segment
		(start 148.677884 -154.064462)
		(end 150.673054 -154.064462)
		(width 0.1651)
		(layer "In15.Cu")
		(net "CLK_100M_DB2000QL_NIC2_R_DP")
	)
	(segment
		(start 148.677884 -170.670982)
		(end 150.654512 -170.670982)
		(width 0.1651)
		(layer "In15.Cu")
		(net "CLK_100M_DB2000QL_NIC2_R_DP")
	)
	(segment
		(start 148.35886 -148.110702)
		(end 148.35886 -146.396202)
		(width 0.1651)
		(layer "In15.Cu")
		(net "CLK_100M_DB2000QL_NIC2_R_DP")
	)
	(segment
		(start 150.673054 -154.064462)
		(end 150.815802 -153.921714)
		(width 0.1651)
		(layer "In15.Cu")
		(net "CLK_100M_DB2000QL_NIC2_R_DP")
	)
	(segment
		(start 157.136592 -139.365228)
		(end 158.581598 -137.920222)
		(width 0.1651)
		(layer "In15.Cu")
		(net "CLK_100M_DB2000QL_NIC2_R_DP")
	)
	(segment
		(start 148.365464 -152.855422)
		(end 148.365464 -152.004522)
		(width 0.1651)
		(layer "In15.Cu")
		(net "CLK_100M_DB2000QL_NIC2_R_DP")
	)
	(segment
		(start 148.36775 -159.985456)
		(end 148.36775 -159.119316)
		(width 0.1651)
		(layer "In15.Cu")
		(net "CLK_100M_DB2000QL_NIC2_R_DP")
	)
	(segment
		(start 150.79726 -160.42767)
		(end 150.654512 -160.284922)
		(width 0.1651)
		(layer "In15.Cu")
		(net "CLK_100M_DB2000QL_NIC2_R_DP")
	)
	(segment
		(start 150.815802 -150.93823)
		(end 150.673054 -150.795482)
		(width 0.1651)
		(layer "In15.Cu")
		(net "CLK_100M_DB2000QL_NIC2_R_DP")
	)
	(segment
		(start 150.673054 -151.692102)
		(end 150.815802 -151.549354)
		(width 0.1651)
		(layer "In15.Cu")
		(net "CLK_100M_DB2000QL_NIC2_R_DP")
	)
	(segment
		(start 148.677884 -165.029642)
		(end 148.36775 -164.719508)
		(width 0.1651)
		(layer "In15.Cu")
		(net "CLK_100M_DB2000QL_NIC2_R_DP")
	)
	(segment
		(start 148.677884 -163.553902)
		(end 150.654512 -163.553902)
		(width 0.1651)
		(layer "In15.Cu")
		(net "CLK_100M_DB2000QL_NIC2_R_DP")
	)
	(segment
		(start 148.677884 -161.181542)
		(end 150.654512 -161.181542)
		(width 0.1651)
		(layer "In15.Cu")
		(net "CLK_100M_DB2000QL_NIC2_R_DP")
	)
	(segment
		(start 148.667216 -169.774362)
		(end 148.36775 -169.474896)
		(width 0.1651)
		(layer "In15.Cu")
		(net "CLK_100M_DB2000QL_NIC2_R_DP")
	)
	(segment
		(start 148.35886 -146.396202)
		(end 150.765002 -143.99006)
		(width 0.1651)
		(layer "In15.Cu")
		(net "CLK_100M_DB2000QL_NIC2_R_DP")
	)
	(segment
		(start 150.79726 -170.528234)
		(end 150.79726 -169.91711)
		(width 0.1651)
		(layer "In15.Cu")
		(net "CLK_100M_DB2000QL_NIC2_R_DP")
	)
	(segment
		(start 150.87346 -158.05531)
		(end 150.730712 -157.912562)
		(width 0.1651)
		(layer "In15.Cu")
		(net "CLK_100M_DB2000QL_NIC2_R_DP")
	)
	(segment
		(start 148.36775 -168.608756)
		(end 148.677884 -168.298622)
		(width 0.1651)
		(layer "In15.Cu")
		(net "CLK_100M_DB2000QL_NIC2_R_DP")
	)
	(segment
		(start 157.136592 -142.841472)
		(end 157.136592 -139.365228)
		(width 0.1651)
		(layer "In15.Cu")
		(net "CLK_100M_DB2000QL_NIC2_R_DP")
	)
	(segment
		(start 148.36775 -159.119316)
		(end 148.677884 -158.809182)
		(width 0.1651)
		(layer "In15.Cu")
		(net "CLK_100M_DB2000QL_NIC2_R_DP")
	)
	(segment
		(start 148.677884 -158.809182)
		(end 150.730712 -158.809182)
		(width 0.1651)
		(layer "In15.Cu")
		(net "CLK_100M_DB2000QL_NIC2_R_DP")
	)
	(segment
		(start 150.654512 -162.657282)
		(end 148.667216 -162.657282)
		(width 0.1651)
		(layer "In15.Cu")
		(net "CLK_100M_DB2000QL_NIC2_R_DP")
	)
	(segment
		(start 148.365464 -154.376882)
		(end 148.677884 -154.064462)
		(width 0.1651)
		(layer "In15.Cu")
		(net "CLK_100M_DB2000QL_NIC2_R_DP")
	)
	(segment
		(start 148.677884 -155.540202)
		(end 148.365464 -155.227782)
		(width 0.1651)
		(layer "In15.Cu")
		(net "CLK_100M_DB2000QL_NIC2_R_DP")
	)
	(segment
		(start 148.365464 -173.317154)
		(end 148.365464 -170.983402)
		(width 0.1651)
		(layer "In15.Cu")
		(net "CLK_100M_DB2000QL_NIC2_R_DP")
	)
	(segment
		(start 150.679912 -165.029642)
		(end 148.677884 -165.029642)
		(width 0.1651)
		(layer "In15.Cu")
		(net "CLK_100M_DB2000QL_NIC2_R_DP")
	)
	(segment
		(start 148.67128 -148.423122)
		(end 148.35886 -148.110702)
		(width 0.1651)
		(layer "In15.Cu")
		(net "CLK_100M_DB2000QL_NIC2_R_DP")
	)
	(segment
		(start 150.730712 -157.912562)
		(end 148.677884 -157.912562)
		(width 0.1651)
		(layer "In15.Cu")
		(net "CLK_100M_DB2000QL_NIC2_R_DP")
	)
	(segment
		(start 148.667216 -162.657282)
		(end 148.36775 -162.357816)
		(width 0.1651)
		(layer "In15.Cu")
		(net "CLK_100M_DB2000QL_NIC2_R_DP")
	)
	(segment
		(start 150.673054 -153.167842)
		(end 148.677884 -153.167842)
		(width 0.1651)
		(layer "In15.Cu")
		(net "CLK_100M_DB2000QL_NIC2_R_DP")
	)
	(segment
		(start 150.82266 -165.17239)
		(end 150.679912 -165.029642)
		(width 0.1651)
		(layer "In15.Cu")
		(net "CLK_100M_DB2000QL_NIC2_R_DP")
	)
	(segment
		(start 150.673054 -156.436822)
		(end 150.815802 -156.294074)
		(width 0.1651)
		(layer "In15.Cu")
		(net "CLK_100M_DB2000QL_NIC2_R_DP")
	)
	(segment
		(start 148.677884 -157.912562)
		(end 148.36775 -157.602428)
		(width 0.1651)
		(layer "In15.Cu")
		(net "CLK_100M_DB2000QL_NIC2_R_DP")
	)
	(segment
		(start 150.673054 -148.423122)
		(end 148.67128 -148.423122)
		(width 0.1651)
		(layer "In15.Cu")
		(net "CLK_100M_DB2000QL_NIC2_R_DP")
	)
	(segment
		(start 142.306294 -174.244)
		(end 147.438618 -174.244)
		(width 0.1651)
		(layer "In15.Cu")
		(net "CLK_100M_DB2000QL_NIC2_R_DP")
	)
	(segment
		(start 148.677884 -156.436822)
		(end 150.673054 -156.436822)
		(width 0.1651)
		(layer "In15.Cu")
		(net "CLK_100M_DB2000QL_NIC2_R_DP")
	)
	(segment
		(start 150.87346 -158.666434)
		(end 150.87346 -158.05531)
		(width 0.1651)
		(layer "In15.Cu")
		(net "CLK_100M_DB2000QL_NIC2_R_DP")
	)
	(segment
		(start 158.581598 -137.920222)
		(end 160.243266 -137.920222)
		(width 0.1651)
		(layer "In15.Cu")
		(net "CLK_100M_DB2000QL_NIC2_R_DP")
	)
	(segment
		(start 150.654512 -170.670982)
		(end 150.79726 -170.528234)
		(width 0.1651)
		(layer "In15.Cu")
		(net "CLK_100M_DB2000QL_NIC2_R_DP")
	)
	(segment
		(start 150.679912 -168.298622)
		(end 150.82266 -168.155874)
		(width 0.1651)
		(layer "In15.Cu")
		(net "CLK_100M_DB2000QL_NIC2_R_DP")
	)
	(segment
		(start 142.00378 -173.941486)
		(end 142.306294 -174.244)
		(width 0.1651)
		(layer "In15.Cu")
		(net "CLK_100M_DB2000QL_NIC2_R_DP")
	)
	(segment
		(start 148.667216 -160.284922)
		(end 148.36775 -159.985456)
		(width 0.1651)
		(layer "In15.Cu")
		(net "CLK_100M_DB2000QL_NIC2_R_DP")
	)
	(segment
		(start 150.79726 -163.411154)
		(end 150.79726 -162.80003)
		(width 0.1651)
		(layer "In15.Cu")
		(net "CLK_100M_DB2000QL_NIC2_R_DP")
	)
	(segment
		(start 150.765002 -143.99006)
		(end 155.988004 -143.99006)
		(width 0.1651)
		(layer "In15.Cu")
		(net "CLK_100M_DB2000QL_NIC2_R_DP")
	)
	(segment
		(start 148.365464 -152.004522)
		(end 148.677884 -151.692102)
		(width 0.1651)
		(layer "In15.Cu")
		(net "CLK_100M_DB2000QL_NIC2_R_DP")
	)
	(segment
		(start 150.673054 -150.795482)
		(end 148.677884 -150.795482)
		(width 0.1651)
		(layer "In15.Cu")
		(net "CLK_100M_DB2000QL_NIC2_R_DP")
	)
	(segment
		(start 148.365464 -170.983402)
		(end 148.677884 -170.670982)
		(width 0.1651)
		(layer "In15.Cu")
		(net "CLK_100M_DB2000QL_NIC2_R_DP")
	)
	(segment
		(start 148.36775 -166.236396)
		(end 148.677884 -165.926262)
		(width 0.1651)
		(layer "In15.Cu")
		(net "CLK_100M_DB2000QL_NIC2_R_DP")
	)
	(segment
		(start 150.730712 -158.809182)
		(end 150.87346 -158.666434)
		(width 0.1651)
		(layer "In15.Cu")
		(net "CLK_100M_DB2000QL_NIC2_R_DP")
	)
	(segment
		(start 148.677884 -165.926262)
		(end 150.679912 -165.926262)
		(width 0.1651)
		(layer "In15.Cu")
		(net "CLK_100M_DB2000QL_NIC2_R_DP")
	)
	(segment
		(start 148.36775 -163.864036)
		(end 148.677884 -163.553902)
		(width 0.1651)
		(layer "In15.Cu")
		(net "CLK_100M_DB2000QL_NIC2_R_DP")
	)
	(segment
		(start 148.36775 -161.491676)
		(end 148.677884 -161.181542)
		(width 0.1651)
		(layer "In15.Cu")
		(net "CLK_100M_DB2000QL_NIC2_R_DP")
	)
	(segment
		(start 148.677884 -167.402002)
		(end 148.36775 -167.091868)
		(width 0.1651)
		(layer "In15.Cu")
		(net "CLK_100M_DB2000QL_NIC2_R_DP")
	)
	(segment
		(start 148.36775 -167.091868)
		(end 148.36775 -166.236396)
		(width 0.1651)
		(layer "In15.Cu")
		(net "CLK_100M_DB2000QL_NIC2_R_DP")
	)
	(segment
		(start 148.677884 -150.795482)
		(end 148.365464 -150.483062)
		(width 0.1651)
		(layer "In15.Cu")
		(net "CLK_100M_DB2000QL_NIC2_R_DP")
	)
	(segment
		(start 150.815802 -153.31059)
		(end 150.673054 -153.167842)
		(width 0.1651)
		(layer "In15.Cu")
		(net "CLK_100M_DB2000QL_NIC2_R_DP")
	)
	(segment
		(start 150.679912 -165.926262)
		(end 150.82266 -165.783514)
		(width 0.1651)
		(layer "In15.Cu")
		(net "CLK_100M_DB2000QL_NIC2_R_DP")
	)
	(segment
		(start 150.654512 -163.553902)
		(end 150.79726 -163.411154)
		(width 0.1651)
		(layer "In15.Cu")
		(net "CLK_100M_DB2000QL_NIC2_R_DP")
	)
	(segment
		(start 148.36775 -169.474896)
		(end 148.36775 -168.608756)
		(width 0.1651)
		(layer "In15.Cu")
		(net "CLK_100M_DB2000QL_NIC2_R_DP")
	)
	(segment
		(start 150.654512 -160.284922)
		(end 148.667216 -160.284922)
		(width 0.1651)
		(layer "In15.Cu")
		(net "CLK_100M_DB2000QL_NIC2_R_DP")
	)
	(segment
		(start 155.988004 -143.99006)
		(end 157.136592 -142.841472)
		(width 0.1651)
		(layer "In15.Cu")
		(net "CLK_100M_DB2000QL_NIC2_R_DP")
	)
	(segment
		(start 160.243266 -137.920222)
		(end 160.530286 -137.633202)
		(width 0.1651)
		(layer "In15.Cu")
		(net "CLK_100M_DB2000QL_NIC2_R_DP")
	)
	(segment
		(start 150.82266 -167.54475)
		(end 150.679912 -167.402002)
		(width 0.1651)
		(layer "In15.Cu")
		(net "CLK_100M_DB2000QL_NIC2_R_DP")
	)
	(segment
		(start 150.815802 -156.294074)
		(end 150.815802 -155.68295)
		(width 0.1651)
		(layer "In15.Cu")
		(net "CLK_100M_DB2000QL_NIC2_R_DP")
	)
	(segment
		(start 147.438618 -174.244)
		(end 148.365464 -173.317154)
		(width 0.1651)
		(layer "In15.Cu")
		(net "CLK_100M_DB2000QL_NIC2_R_DP")
	)
	(segment
		(start 150.673054 -155.540202)
		(end 148.677884 -155.540202)
		(width 0.1651)
		(layer "In15.Cu")
		(net "CLK_100M_DB2000QL_NIC2_R_DP")
	)
	(segment
		(start 150.815802 -153.921714)
		(end 150.815802 -153.31059)
		(width 0.1651)
		(layer "In15.Cu")
		(net "CLK_100M_DB2000QL_NIC2_R_DP")
	)
	(segment
		(start 150.79726 -162.80003)
		(end 150.654512 -162.657282)
		(width 0.1651)
		(layer "In15.Cu")
		(net "CLK_100M_DB2000QL_NIC2_R_DP")
	)
	(segment
		(start 148.36775 -156.746956)
		(end 148.677884 -156.436822)
		(width 0.1651)
		(layer "In15.Cu")
		(net "CLK_100M_DB2000QL_NIC2_R_DP")
	)
	(segment
		(start 150.815802 -151.549354)
		(end 150.815802 -150.93823)
		(width 0.1651)
		(layer "In15.Cu")
		(net "CLK_100M_DB2000QL_NIC2_R_DP")
	)
	(segment
		(start 148.677884 -149.319742)
		(end 150.673054 -149.319742)
		(width 0.1651)
		(layer "In15.Cu")
		(net "CLK_100M_DB2000QL_NIC2_R_DP")
	)
	(segment
		(start 150.82266 -165.783514)
		(end 150.82266 -165.17239)
		(width 0.1651)
		(layer "In15.Cu")
		(net "CLK_100M_DB2000QL_NIC2_R_DP")
	)
	(segment
		(start 148.677884 -153.167842)
		(end 148.365464 -152.855422)
		(width 0.1651)
		(layer "In15.Cu")
		(net "CLK_100M_DB2000QL_NIC2_R_DP")
	)
	(segment
		(start 105.67289 -326.882506)
		(end 105.67289 -327.777856)
		(width 0.1143)
		(layer "B.Cu")
		(net "CLK_100M_DB800ZL_PEX0_S0_DN")
	)
	(segment
		(start 105.624122 -327.826624)
		(end 105.624122 -328.89317)
		(width 0.1143)
		(layer "B.Cu")
		(net "CLK_100M_DB800ZL_PEX0_S0_DN")
	)
	(segment
		(start 105.624122 -328.89317)
		(end 105.636822 -328.90587)
		(width 0.1143)
		(layer "B.Cu")
		(net "CLK_100M_DB800ZL_PEX0_S0_DN")
	)
	(segment
		(start 105.636822 -328.909426)
		(end 105.564432 -328.981816)
		(width 0.1143)
		(layer "B.Cu")
		(net "CLK_100M_DB800ZL_PEX0_S0_DN")
	)
	(segment
		(start 105.564432 -328.981816)
		(end 105.564432 -329.175618)
		(width 0.1143)
		(layer "B.Cu")
		(net "CLK_100M_DB800ZL_PEX0_S0_DN")
	)
	(segment
		(start 105.636822 -328.90587)
		(end 105.636822 -328.909426)
		(width 0.1143)
		(layer "B.Cu")
		(net "CLK_100M_DB800ZL_PEX0_S0_DN")
	)
	(segment
		(start 105.34269 -326.552306)
		(end 105.67289 -326.882506)
		(width 0.1143)
		(layer "B.Cu")
		(net "CLK_100M_DB800ZL_PEX0_S0_DN")
	)
	(segment
		(start 105.67289 -327.777856)
		(end 105.624122 -327.826624)
		(width 0.1143)
		(layer "B.Cu")
		(net "CLK_100M_DB800ZL_PEX0_S0_DN")
	)
	(segment
		(start 98.575622 -120.493028)
		(end 98.575622 -119.477028)
		(width 0.13208)
		(layer "F.Cu")
		(net "PWRGD_P3V3_NIC1")
	)
	(segment
		(start 97.30232 -120.541796)
		(end 97.951036 -119.89308)
		(width 0.13208)
		(layer "F.Cu")
		(net "PWRGD_P3V3_NIC1")
	)
	(segment
		(start 97.951036 -119.89308)
		(end 97.951036 -119.569992)
		(width 0.13208)
		(layer "F.Cu")
		(net "PWRGD_P3V3_NIC1")
	)
	(segment
		(start 96.77146 -120.541796)
		(end 97.30232 -120.541796)
		(width 0.13208)
		(layer "F.Cu")
		(net "PWRGD_P3V3_NIC1")
	)
	(segment
		(start 97.951036 -119.569992)
		(end 98.044 -119.477028)
		(width 0.13208)
		(layer "F.Cu")
		(net "PWRGD_P3V3_NIC1")
	)
	(segment
		(start 98.044 -119.477028)
		(end 98.575622 -119.477028)
		(width 0.13208)
		(layer "F.Cu")
		(net "PWRGD_P3V3_NIC1")
	)
	(via
		(at 97.951036 -119.89308)
		(size 0.508)
		(drill 0.254)
		(layers "F.Cu" "B.Cu")
		(net "PWRGD_P3V3_NIC1")
	)
	(segment
		(start 277.611332 -137.90168)
		(end 277.747984 -137.765028)
		(width 0.13462)
		(layer "F.Cu")
		(net "CLK_100M_DB2000QL_NIC4_R_DP")
	)
	(segment
		(start 141.721586 -178.28768)
		(end 142.00378 -178.005486)
		(width 0.13462)
		(layer "F.Cu")
		(net "CLK_100M_DB2000QL_NIC4_R_DP")
	)
	(segment
		(start 140.832586 -178.28768)
		(end 141.721586 -178.28768)
		(width 0.13462)
		(layer "F.Cu")
		(net "CLK_100M_DB2000QL_NIC4_R_DP")
	)
	(segment
		(start 140.474192 -177.929286)
		(end 140.832586 -178.28768)
		(width 0.13462)
		(layer "F.Cu")
		(net "CLK_100M_DB2000QL_NIC4_R_DP")
	)
	(segment
		(start 277.747984 -137.765028)
		(end 278.242268 -137.765028)
		(width 0.13462)
		(layer "F.Cu")
		(net "CLK_100M_DB2000QL_NIC4_R_DP")
	)
	(segment
		(start 276.898862 -137.90168)
		(end 277.611332 -137.90168)
		(width 0.13462)
		(layer "F.Cu")
		(net "CLK_100M_DB2000QL_NIC4_R_DP")
	)
	(segment
		(start 276.630384 -137.633202)
		(end 276.898862 -137.90168)
		(width 0.13462)
		(layer "F.Cu")
		(net "CLK_100M_DB2000QL_NIC4_R_DP")
	)
	(via
		(at 142.00378 -178.005486)
		(size 0.508)
		(drill 0.254)
		(layers "F.Cu" "B.Cu")
		(net "CLK_100M_DB2000QL_NIC4_R_DP")
	)
	(via
		(at 276.630384 -137.633202)
		(size 0.508)
		(drill 0.254)
		(layers "F.Cu" "B.Cu")
		(net "CLK_100M_DB2000QL_NIC4_R_DP")
	)
	(segment
		(start 214.142828 -161.629852)
		(end 238.888778 -161.629852)
		(width 0.1651)
		(layer "In15.Cu")
		(net "CLK_100M_DB2000QL_NIC4_R_DP")
	)
	(segment
		(start 273.722846 -139.662916)
		(end 275.491702 -137.89406)
		(width 0.1651)
		(layer "In15.Cu")
		(net "CLK_100M_DB2000QL_NIC4_R_DP")
	)
	(segment
		(start 238.888778 -161.629852)
		(end 241.277902 -164.018976)
		(width 0.1651)
		(layer "In15.Cu")
		(net "CLK_100M_DB2000QL_NIC4_R_DP")
	)
	(segment
		(start 256.248408 -160.125664)
		(end 257.20294 -160.125664)
		(width 0.1651)
		(layer "In15.Cu")
		(net "CLK_100M_DB2000QL_NIC4_R_DP")
	)
	(segment
		(start 257.20294 -160.125664)
		(end 273.722846 -143.605758)
		(width 0.1651)
		(layer "In15.Cu")
		(net "CLK_100M_DB2000QL_NIC4_R_DP")
	)
	(segment
		(start 254.326644 -161.42081)
		(end 255.178814 -160.56864)
		(width 0.1651)
		(layer "In15.Cu")
		(net "CLK_100M_DB2000QL_NIC4_R_DP")
	)
	(segment
		(start 273.722846 -143.605758)
		(end 273.722846 -139.662916)
		(width 0.1651)
		(layer "In15.Cu")
		(net "CLK_100M_DB2000QL_NIC4_R_DP")
	)
	(segment
		(start 207.06588 -168.7068)
		(end 214.142828 -161.629852)
		(width 0.1651)
		(layer "In15.Cu")
		(net "CLK_100M_DB2000QL_NIC4_R_DP")
	)
	(segment
		(start 275.491702 -137.89406)
		(end 276.369526 -137.89406)
		(width 0.1651)
		(layer "In15.Cu")
		(net "CLK_100M_DB2000QL_NIC4_R_DP")
	)
	(segment
		(start 142.2908 -178.292506)
		(end 166.012368 -178.292506)
		(width 0.1651)
		(layer "In15.Cu")
		(net "CLK_100M_DB2000QL_NIC4_R_DP")
	)
	(segment
		(start 255.178814 -160.56864)
		(end 256.248408 -160.125664)
		(width 0.1651)
		(layer "In15.Cu")
		(net "CLK_100M_DB2000QL_NIC4_R_DP")
	)
	(segment
		(start 142.00378 -178.005486)
		(end 142.2908 -178.292506)
		(width 0.1651)
		(layer "In15.Cu")
		(net "CLK_100M_DB2000QL_NIC4_R_DP")
	)
	(segment
		(start 178.821588 -169.580814)
		(end 179.695602 -168.7068)
		(width 0.1651)
		(layer "In15.Cu")
		(net "CLK_100M_DB2000QL_NIC4_R_DP")
	)
	(segment
		(start 174.72406 -169.580814)
		(end 178.821588 -169.580814)
		(width 0.1651)
		(layer "In15.Cu")
		(net "CLK_100M_DB2000QL_NIC4_R_DP")
	)
	(segment
		(start 254.326644 -162.969956)
		(end 254.326644 -161.42081)
		(width 0.1651)
		(layer "In15.Cu")
		(net "CLK_100M_DB2000QL_NIC4_R_DP")
	)
	(segment
		(start 253.277624 -164.018976)
		(end 254.326644 -162.969956)
		(width 0.1651)
		(layer "In15.Cu")
		(net "CLK_100M_DB2000QL_NIC4_R_DP")
	)
	(segment
		(start 179.695602 -168.7068)
		(end 207.06588 -168.7068)
		(width 0.1651)
		(layer "In15.Cu")
		(net "CLK_100M_DB2000QL_NIC4_R_DP")
	)
	(segment
		(start 166.012368 -178.292506)
		(end 174.72406 -169.580814)
		(width 0.1651)
		(layer "In15.Cu")
		(net "CLK_100M_DB2000QL_NIC4_R_DP")
	)
	(segment
		(start 276.369526 -137.89406)
		(end 276.630384 -137.633202)
		(width 0.1651)
		(layer "In15.Cu")
		(net "CLK_100M_DB2000QL_NIC4_R_DP")
	)
	(segment
		(start 241.277902 -164.018976)
		(end 253.277624 -164.018976)
		(width 0.1651)
		(layer "In15.Cu")
		(net "CLK_100M_DB2000QL_NIC4_R_DP")
	)
	(segment
		(start 103.666798 -331.228192)
		(end 103.739188 -331.300582)
		(width 0.1143)
		(layer "B.Cu")
		(net "CLK_100M_DB800ZL_PEX1_S0_DN")
	)
	(segment
		(start 102.517956 -330.708)
		(end 103.038148 -331.228192)
		(width 0.1143)
		(layer "B.Cu")
		(net "CLK_100M_DB800ZL_PEX1_S0_DN")
	)
	(segment
		(start 100.555044 -331.03185)
		(end 100.878894 -330.708)
		(width 0.1143)
		(layer "B.Cu")
		(net "CLK_100M_DB800ZL_PEX1_S0_DN")
	)
	(segment
		(start 103.739188 -331.300582)
		(end 103.939594 -331.300582)
		(width 0.1143)
		(layer "B.Cu")
		(net "CLK_100M_DB800ZL_PEX1_S0_DN")
	)
	(segment
		(start 103.038148 -331.228192)
		(end 103.666798 -331.228192)
		(width 0.1143)
		(layer "B.Cu")
		(net "CLK_100M_DB800ZL_PEX1_S0_DN")
	)
	(segment
		(start 100.878894 -330.708)
		(end 102.517956 -330.708)
		(width 0.1143)
		(layer "B.Cu")
		(net "CLK_100M_DB800ZL_PEX1_S0_DN")
	)
	(via
		(at 115.41379 -331.53223)
		(size 0.508)
		(drill 0.254)
		(layers "F.Cu" "B.Cu")
		(net "CLK_100M_MB_0_DP")
	)
	(segment
		(start 115.41379 -331.53223)
		(end 115.12296 -331.2414)
		(width 0.13462)
		(layer "B.Cu")
		(net "CLK_100M_MB_0_DP")
	)
	(segment
		(start 115.12296 -331.2414)
		(end 114.281204 -331.2414)
		(width 0.13462)
		(layer "B.Cu")
		(net "CLK_100M_MB_0_DP")
	)
	(segment
		(start 114.281204 -331.2414)
		(end 113.914174 -331.60843)
		(width 0.13462)
		(layer "B.Cu")
		(net "CLK_100M_MB_0_DP")
	)
	(segment
		(start 92.966032 -364.821216)
		(end 92.692728 -365.219488)
		(width 0.1651)
		(layer "In5.Cu")
		(net "CLK_100M_MB_0_DP")
	)
	(segment
		(start 114.718338 -334.279494)
		(end 114.718338 -334.437736)
		(width 0.1651)
		(layer "In5.Cu")
		(net "CLK_100M_MB_0_DP")
	)
	(segment
		(start 94.312486 -362.861352)
		(end 94.038928 -363.259624)
		(width 0.1651)
		(layer "In5.Cu")
		(net "CLK_100M_MB_0_DP")
	)
	(segment
		(start 90.385646 -368.775234)
		(end 90.385646 -382.315974)
		(width 0.1651)
		(layer "In5.Cu")
		(net "CLK_100M_MB_0_DP")
	)
	(segment
		(start 90.00617 -382.69545)
		(end 89.629234 -382.69545)
		(width 0.1651)
		(layer "In5.Cu")
		(net "CLK_100M_MB_0_DP")
	)
	(segment
		(start 96.39046 -358.36225)
		(end 96.39046 -358.84485)
		(width 0.1651)
		(layer "In5.Cu")
		(net "CLK_100M_MB_0_DP")
	)
	(segment
		(start 94.038928 -363.259624)
		(end 94.06763 -363.414818)
		(width 0.1651)
		(layer "In5.Cu")
		(net "CLK_100M_MB_0_DP")
	)
	(segment
		(start 106.860848 -339.681312)
		(end 101.534214 -340.740746)
		(width 0.1651)
		(layer "In5.Cu")
		(net "CLK_100M_MB_0_DP")
	)
	(segment
		(start 89.509854 -382.57607)
		(end 89.509854 -382.18999)
		(width 0.1651)
		(layer "In5.Cu")
		(net "CLK_100M_MB_0_DP")
	)
	(segment
		(start 115.217956 -333.938118)
		(end 115.059968 -333.938118)
		(width 0.1651)
		(layer "In5.Cu")
		(net "CLK_100M_MB_0_DP")
	)
	(segment
		(start 96.39046 -345.8845)
		(end 96.39046 -356.46741)
		(width 0.1651)
		(layer "In5.Cu")
		(net "CLK_100M_MB_0_DP")
	)
	(segment
		(start 93.12148 -364.792514)
		(end 92.966032 -364.821216)
		(width 0.1651)
		(layer "In5.Cu")
		(net "CLK_100M_MB_0_DP")
	)
	(segment
		(start 94.712028 -362.279692)
		(end 94.74073 -362.434886)
		(width 0.1651)
		(layer "In5.Cu")
		(net "CLK_100M_MB_0_DP")
	)
	(segment
		(start 95.658686 -360.901742)
		(end 95.385128 -361.29976)
		(width 0.1651)
		(layer "In5.Cu")
		(net "CLK_100M_MB_0_DP")
	)
	(segment
		(start 95.41383 -361.454954)
		(end 95.14078 -361.852718)
		(width 0.1651)
		(layer "In5.Cu")
		(net "CLK_100M_MB_0_DP")
	)
	(segment
		(start 92.692728 -365.219488)
		(end 92.72143 -365.374682)
		(width 0.1651)
		(layer "In5.Cu")
		(net "CLK_100M_MB_0_DP")
	)
	(segment
		(start 96.2787 -358.25049)
		(end 96.39046 -358.36225)
		(width 0.1651)
		(layer "In5.Cu")
		(net "CLK_100M_MB_0_DP")
	)
	(segment
		(start 95.81388 -360.872786)
		(end 95.658686 -360.901742)
		(width 0.1651)
		(layer "In5.Cu")
		(net "CLK_100M_MB_0_DP")
	)
	(segment
		(start 94.06763 -363.414818)
		(end 93.79458 -363.812582)
		(width 0.1651)
		(layer "In5.Cu")
		(net "CLK_100M_MB_0_DP")
	)
	(segment
		(start 94.46768 -362.83265)
		(end 94.312486 -362.861352)
		(width 0.1651)
		(layer "In5.Cu")
		(net "CLK_100M_MB_0_DP")
	)
	(segment
		(start 92.04833 -366.354614)
		(end 90.385646 -368.775234)
		(width 0.1651)
		(layer "In5.Cu")
		(net "CLK_100M_MB_0_DP")
	)
	(segment
		(start 93.39453 -364.39475)
		(end 93.12148 -364.792514)
		(width 0.1651)
		(layer "In5.Cu")
		(net "CLK_100M_MB_0_DP")
	)
	(segment
		(start 115.70462 -331.2414)
		(end 115.92941 -331.2414)
		(width 0.1651)
		(layer "In5.Cu")
		(net "CLK_100M_MB_0_DP")
	)
	(segment
		(start 92.72143 -365.374682)
		(end 92.44838 -365.772446)
		(width 0.1651)
		(layer "In5.Cu")
		(net "CLK_100M_MB_0_DP")
	)
	(segment
		(start 96.39046 -359.55097)
		(end 96.39046 -360.03357)
		(width 0.1651)
		(layer "In5.Cu")
		(net "CLK_100M_MB_0_DP")
	)
	(segment
		(start 96.39046 -360.03357)
		(end 95.81388 -360.872786)
		(width 0.1651)
		(layer "In5.Cu")
		(net "CLK_100M_MB_0_DP")
	)
	(segment
		(start 96.2787 -357.06177)
		(end 96.39046 -357.17353)
		(width 0.1651)
		(layer "In5.Cu")
		(net "CLK_100M_MB_0_DP")
	)
	(segment
		(start 115.559078 -333.596996)
		(end 115.217956 -333.938118)
		(width 0.1651)
		(layer "In5.Cu")
		(net "CLK_100M_MB_0_DP")
	)
	(segment
		(start 90.385646 -382.315974)
		(end 90.00617 -382.69545)
		(width 0.1651)
		(layer "In5.Cu")
		(net "CLK_100M_MB_0_DP")
	)
	(segment
		(start 96.39046 -357.17353)
		(end 96.39046 -357.65613)
		(width 0.1651)
		(layer "In5.Cu")
		(net "CLK_100M_MB_0_DP")
	)
	(segment
		(start 114.718338 -334.437736)
		(end 112.476026 -336.679794)
		(width 0.1651)
		(layer "In5.Cu")
		(net "CLK_100M_MB_0_DP")
	)
	(segment
		(start 96.2787 -357.76789)
		(end 96.2787 -358.25049)
		(width 0.1651)
		(layer "In5.Cu")
		(net "CLK_100M_MB_0_DP")
	)
	(segment
		(start 115.41379 -331.53223)
		(end 115.70462 -331.2414)
		(width 0.1651)
		(layer "In5.Cu")
		(net "CLK_100M_MB_0_DP")
	)
	(segment
		(start 94.74073 -362.434886)
		(end 94.46768 -362.83265)
		(width 0.1651)
		(layer "In5.Cu")
		(net "CLK_100M_MB_0_DP")
	)
	(segment
		(start 94.985586 -361.881674)
		(end 94.712028 -362.279692)
		(width 0.1651)
		(layer "In5.Cu")
		(net "CLK_100M_MB_0_DP")
	)
	(segment
		(start 115.92941 -331.2414)
		(end 116.06022 -331.37221)
		(width 0.1651)
		(layer "In5.Cu")
		(net "CLK_100M_MB_0_DP")
	)
	(segment
		(start 101.534214 -340.740746)
		(end 96.39046 -345.8845)
		(width 0.1651)
		(layer "In5.Cu")
		(net "CLK_100M_MB_0_DP")
	)
	(segment
		(start 93.639386 -363.841284)
		(end 93.365828 -364.239556)
		(width 0.1651)
		(layer "In5.Cu")
		(net "CLK_100M_MB_0_DP")
	)
	(segment
		(start 96.39046 -357.65613)
		(end 96.2787 -357.76789)
		(width 0.1651)
		(layer "In5.Cu")
		(net "CLK_100M_MB_0_DP")
	)
	(segment
		(start 95.14078 -361.852718)
		(end 94.985586 -361.881674)
		(width 0.1651)
		(layer "In5.Cu")
		(net "CLK_100M_MB_0_DP")
	)
	(segment
		(start 96.2787 -358.95661)
		(end 96.2787 -359.43921)
		(width 0.1651)
		(layer "In5.Cu")
		(net "CLK_100M_MB_0_DP")
	)
	(segment
		(start 92.292932 -365.801148)
		(end 92.019628 -366.19942)
		(width 0.1651)
		(layer "In5.Cu")
		(net "CLK_100M_MB_0_DP")
	)
	(segment
		(start 112.476026 -336.679794)
		(end 106.860848 -339.681312)
		(width 0.1651)
		(layer "In5.Cu")
		(net "CLK_100M_MB_0_DP")
	)
	(segment
		(start 116.06022 -331.37221)
		(end 116.06022 -332.387194)
		(width 0.1651)
		(layer "In5.Cu")
		(net "CLK_100M_MB_0_DP")
	)
	(segment
		(start 96.2787 -356.57917)
		(end 96.2787 -357.06177)
		(width 0.1651)
		(layer "In5.Cu")
		(net "CLK_100M_MB_0_DP")
	)
	(segment
		(start 92.019628 -366.19942)
		(end 92.04833 -366.354614)
		(width 0.1651)
		(layer "In5.Cu")
		(net "CLK_100M_MB_0_DP")
	)
	(segment
		(start 96.39046 -356.46741)
		(end 96.2787 -356.57917)
		(width 0.1651)
		(layer "In5.Cu")
		(net "CLK_100M_MB_0_DP")
	)
	(segment
		(start 115.059968 -333.938118)
		(end 114.718338 -334.279494)
		(width 0.1651)
		(layer "In5.Cu")
		(net "CLK_100M_MB_0_DP")
	)
	(segment
		(start 93.79458 -363.812582)
		(end 93.639386 -363.841284)
		(width 0.1651)
		(layer "In5.Cu")
		(net "CLK_100M_MB_0_DP")
	)
	(segment
		(start 116.06022 -332.387194)
		(end 115.559078 -333.596996)
		(width 0.1651)
		(layer "In5.Cu")
		(net "CLK_100M_MB_0_DP")
	)
	(segment
		(start 93.365828 -364.239556)
		(end 93.39453 -364.39475)
		(width 0.1651)
		(layer "In5.Cu")
		(net "CLK_100M_MB_0_DP")
	)
	(segment
		(start 92.44838 -365.772446)
		(end 92.292932 -365.801148)
		(width 0.1651)
		(layer "In5.Cu")
		(net "CLK_100M_MB_0_DP")
	)
	(segment
		(start 95.385128 -361.29976)
		(end 95.41383 -361.454954)
		(width 0.1651)
		(layer "In5.Cu")
		(net "CLK_100M_MB_0_DP")
	)
	(segment
		(start 96.39046 -358.84485)
		(end 96.2787 -358.95661)
		(width 0.1651)
		(layer "In5.Cu")
		(net "CLK_100M_MB_0_DP")
	)
	(segment
		(start 89.629234 -382.69545)
		(end 89.509854 -382.57607)
		(width 0.1651)
		(layer "In5.Cu")
		(net "CLK_100M_MB_0_DP")
	)
	(segment
		(start 96.2787 -359.43921)
		(end 96.39046 -359.55097)
		(width 0.1651)
		(layer "In5.Cu")
		(net "CLK_100M_MB_0_DP")
	)
	(segment
		(start 223.06788 -216.304368)
		(end 223.467676 -215.904572)
		(width 0.13208)
		(layer "F.Cu")
		(net "RST_MB_BMC_N")
	)
	(segment
		(start 275.710396 -415.29)
		(end 276.726396 -415.29)
		(width 0.13208)
		(layer "F.Cu")
		(net "RST_MB_BMC_N")
	)
	(segment
		(start 223.467676 -215.904572)
		(end 223.467676 -215.904064)
		(width 0.13208)
		(layer "F.Cu")
		(net "RST_MB_BMC_N")
	)
	(segment
		(start 276.726396 -415.29)
		(end 276.726396 -416.106102)
		(width 0.13208)
		(layer "F.Cu")
		(net "RST_MB_BMC_N")
	)
	(via
		(at 227.24364 -252.55982)
		(size 0.508)
		(drill 0.254)
		(layers "F.Cu" "B.Cu")
		(net "RST_MB_BMC_N")
	)
	(via
		(at 223.06788 -216.304368)
		(size 0.4572)
		(drill 0.254)
		(layers "F.Cu" "B.Cu")
		(net "RST_MB_BMC_N")
	)
	(via
		(at 276.726396 -416.106102)
		(size 0.508)
		(drill 0.254)
		(layers "F.Cu" "B.Cu")
		(net "RST_MB_BMC_N")
	)
	(segment
		(start 223.06788 -216.304368)
		(end 222.94342 -216.428828)
		(width 0.15494)
		(layer "In5.Cu")
		(net "RST_MB_BMC_N")
	)
	(segment
		(start 226.445826 -229.93731)
		(end 226.445826 -231.719374)
		(width 0.15494)
		(layer "In5.Cu")
		(net "RST_MB_BMC_N")
	)
	(segment
		(start 226.324922 -229.816152)
		(end 226.324922 -229.816406)
		(width 0.15494)
		(layer "In5.Cu")
		(net "RST_MB_BMC_N")
	)
	(segment
		(start 226.2124 -231.9528)
		(end 226.2124 -235.458)
		(width 0.15494)
		(layer "In5.Cu")
		(net "RST_MB_BMC_N")
	)
	(segment
		(start 222.9866 -225.4758)
		(end 222.9866 -226.47783)
		(width 0.15494)
		(layer "In5.Cu")
		(net "RST_MB_BMC_N")
	)
	(segment
		(start 222.94342 -220.418152)
		(end 222.35414 -221.007432)
		(width 0.15494)
		(layer "In5.Cu")
		(net "RST_MB_BMC_N")
	)
	(segment
		(start 222.35414 -224.84334)
		(end 222.9866 -225.4758)
		(width 0.15494)
		(layer "In5.Cu")
		(net "RST_MB_BMC_N")
	)
	(segment
		(start 226.445826 -231.719374)
		(end 226.2124 -231.9528)
		(width 0.15494)
		(layer "In5.Cu")
		(net "RST_MB_BMC_N")
	)
	(segment
		(start 222.94342 -216.428828)
		(end 222.94342 -220.418152)
		(width 0.15494)
		(layer "In5.Cu")
		(net "RST_MB_BMC_N")
	)
	(segment
		(start 222.9866 -226.47783)
		(end 226.324922 -229.816152)
		(width 0.15494)
		(layer "In5.Cu")
		(net "RST_MB_BMC_N")
	)
	(segment
		(start 226.324922 -229.816406)
		(end 226.445826 -229.93731)
		(width 0.15494)
		(layer "In5.Cu")
		(net "RST_MB_BMC_N")
	)
	(segment
		(start 225.9076 -251.22378)
		(end 227.24364 -252.55982)
		(width 0.15494)
		(layer "In5.Cu")
		(net "RST_MB_BMC_N")
	)
	(segment
		(start 222.35414 -221.007432)
		(end 222.35414 -224.84334)
		(width 0.15494)
		(layer "In5.Cu")
		(net "RST_MB_BMC_N")
	)
	(segment
		(start 225.9076 -235.7628)
		(end 225.9076 -251.22378)
		(width 0.15494)
		(layer "In5.Cu")
		(net "RST_MB_BMC_N")
	)
	(segment
		(start 226.2124 -235.458)
		(end 225.9076 -235.7628)
		(width 0.15494)
		(layer "In5.Cu")
		(net "RST_MB_BMC_N")
	)
	(segment
		(start 255.455928 -337.630262)
		(end 264.07872 -346.2528)
		(width 0.15494)
		(layer "In7.Cu")
		(net "RST_MB_BMC_N")
	)
	(segment
		(start 267.25372 -373.8626)
		(end 265.52652 -375.5898)
		(width 0.15494)
		(layer "In7.Cu")
		(net "RST_MB_BMC_N")
	)
	(segment
		(start 265.52652 -381.3302)
		(end 275.63572 -391.4394)
		(width 0.15494)
		(layer "In7.Cu")
		(net "RST_MB_BMC_N")
	)
	(segment
		(start 264.07872 -357.886)
		(end 267.25372 -361.061)
		(width 0.15494)
		(layer "In7.Cu")
		(net "RST_MB_BMC_N")
	)
	(segment
		(start 275.63572 -403.105366)
		(end 274.388834 -404.352252)
		(width 0.15494)
		(layer "In7.Cu")
		(net "RST_MB_BMC_N")
	)
	(segment
		(start 236.163104 -333.482696)
		(end 251.989844 -333.482696)
		(width 0.15494)
		(layer "In7.Cu")
		(net "RST_MB_BMC_N")
	)
	(segment
		(start 265.52652 -375.5898)
		(end 265.52652 -381.3302)
		(width 0.15494)
		(layer "In7.Cu")
		(net "RST_MB_BMC_N")
	)
	(segment
		(start 274.388834 -404.352252)
		(end 274.388834 -414.266888)
		(width 0.15494)
		(layer "In7.Cu")
		(net "RST_MB_BMC_N")
	)
	(segment
		(start 254.961644 -336.454496)
		(end 255.443482 -337.617562)
		(width 0.15494)
		(layer "In7.Cu")
		(net "RST_MB_BMC_N")
	)
	(segment
		(start 255.443482 -337.617562)
		(end 255.455674 -337.629754)
		(width 0.15494)
		(layer "In7.Cu")
		(net "RST_MB_BMC_N")
	)
	(segment
		(start 251.989844 -333.482696)
		(end 254.961644 -336.454496)
		(width 0.15494)
		(layer "In7.Cu")
		(net "RST_MB_BMC_N")
	)
	(segment
		(start 275.63572 -391.4394)
		(end 275.63572 -403.105366)
		(width 0.15494)
		(layer "In7.Cu")
		(net "RST_MB_BMC_N")
	)
	(segment
		(start 255.455674 -337.629754)
		(end 255.455928 -337.630262)
		(width 0.15494)
		(layer "In7.Cu")
		(net "RST_MB_BMC_N")
	)
	(segment
		(start 227.24364 -252.55982)
		(end 233.8578 -259.17398)
		(width 0.15494)
		(layer "In7.Cu")
		(net "RST_MB_BMC_N")
	)
	(segment
		(start 264.07872 -346.2528)
		(end 264.07872 -357.886)
		(width 0.15494)
		(layer "In7.Cu")
		(net "RST_MB_BMC_N")
	)
	(segment
		(start 233.8578 -259.17398)
		(end 233.8578 -331.177392)
		(width 0.15494)
		(layer "In7.Cu")
		(net "RST_MB_BMC_N")
	)
	(segment
		(start 274.388834 -414.266888)
		(end 276.228048 -416.106102)
		(width 0.15494)
		(layer "In7.Cu")
		(net "RST_MB_BMC_N")
	)
	(segment
		(start 267.25372 -361.061)
		(end 267.25372 -373.8626)
		(width 0.15494)
		(layer "In7.Cu")
		(net "RST_MB_BMC_N")
	)
	(segment
		(start 276.228048 -416.106102)
		(end 276.726396 -416.106102)
		(width 0.15494)
		(layer "In7.Cu")
		(net "RST_MB_BMC_N")
	)
	(segment
		(start 233.8578 -331.177392)
		(end 236.163104 -333.482696)
		(width 0.15494)
		(layer "In7.Cu")
		(net "RST_MB_BMC_N")
	)
	(segment
		(start 446.976246 -209.0928)
		(end 446.033906 -209.0928)
		(width 0.13462)
		(layer "F.Cu")
		(net "USB2_MICRO_DP")
	)
	(segment
		(start 229.488492 -78.667102)
		(end 228.72827 -78.667102)
		(width 0.13462)
		(layer "F.Cu")
		(net "USB2_MICRO_DP")
	)
	(segment
		(start 447.276728 -209.393282)
		(end 446.976246 -209.0928)
		(width 0.13462)
		(layer "F.Cu")
		(net "USB2_MICRO_DP")
	)
	(segment
		(start 229.54996 -78.605634)
		(end 229.488492 -78.667102)
		(width 0.13462)
		(layer "F.Cu")
		(net "USB2_MICRO_DP")
	)
	(segment
		(start 228.72827 -78.667102)
		(end 228.435408 -78.37424)
		(width 0.13462)
		(layer "F.Cu")
		(net "USB2_MICRO_DP")
	)
	(segment
		(start 229.794816 -78.605634)
		(end 229.54996 -78.605634)
		(width 0.13462)
		(layer "F.Cu")
		(net "USB2_MICRO_DP")
	)
	(segment
		(start 446.033906 -209.0928)
		(end 445.746124 -209.380582)
		(width 0.13462)
		(layer "F.Cu")
		(net "USB2_MICRO_DP")
	)
	(via
		(at 447.940684 -203.915518)
		(size 0.4064)
		(drill 0.2032)
		(layers "F.Cu" "B.Cu")
		(net "USB2_MICRO_DP")
	)
	(via
		(at 228.435408 -78.37424)
		(size 0.508)
		(drill 0.254)
		(layers "F.Cu" "B.Cu")
		(net "USB2_MICRO_DP")
	)
	(via
		(at 445.746124 -209.380582)
		(size 0.508)
		(drill 0.254)
		(layers "F.Cu" "B.Cu")
		(net "USB2_MICRO_DP")
	)
	(segment
		(start 299.108368 -82.083148)
		(end 300.063916 -81.1276)
		(width 0.13462)
		(layer "B.Cu")
		(net "USB2_MICRO_DP")
	)
	(segment
		(start 242.283488 -74.276712)
		(end 242.283488 -73.17867)
		(width 0.13462)
		(layer "B.Cu")
		(net "USB2_MICRO_DP")
	)
	(segment
		(start 293.360348 -82.083148)
		(end 299.108368 -82.083148)
		(width 0.13462)
		(layer "B.Cu")
		(net "USB2_MICRO_DP")
	)
	(segment
		(start 413.476948 -166.708836)
		(end 413.476948 -168.613582)
		(width 0.13462)
		(layer "B.Cu")
		(net "USB2_MICRO_DP")
	)
	(segment
		(start 407.880312 -130.169666)
		(end 407.880312 -161.1122)
		(width 0.13462)
		(layer "B.Cu")
		(net "USB2_MICRO_DP")
	)
	(segment
		(start 447.940684 -203.915518)
		(end 447.940684 -208.411572)
		(width 0.13462)
		(layer "B.Cu")
		(net "USB2_MICRO_DP")
	)
	(segment
		(start 313.588654 -78.0796)
		(end 315.214254 -79.7052)
		(width 0.13462)
		(layer "B.Cu")
		(net "USB2_MICRO_DP")
	)
	(segment
		(start 277.163784 -75.183238)
		(end 281.488134 -79.507588)
		(width 0.13462)
		(layer "B.Cu")
		(net "USB2_MICRO_DP")
	)
	(segment
		(start 228.435408 -78.37424)
		(end 228.736398 -78.67523)
		(width 0.13462)
		(layer "B.Cu")
		(net "USB2_MICRO_DP")
	)
	(segment
		(start 380.691898 -127.283464)
		(end 382.542034 -129.1336)
		(width 0.13462)
		(layer "B.Cu")
		(net "USB2_MICRO_DP")
	)
	(segment
		(start 241.500406 -75.059794)
		(end 242.283488 -74.276712)
		(width 0.13462)
		(layer "B.Cu")
		(net "USB2_MICRO_DP")
	)
	(segment
		(start 230.166164 -78.67523)
		(end 231.770428 -80.279494)
		(width 0.13462)
		(layer "B.Cu")
		(net "USB2_MICRO_DP")
	)
	(segment
		(start 380.691898 -104.283764)
		(end 380.691898 -127.283464)
		(width 0.13462)
		(layer "B.Cu")
		(net "USB2_MICRO_DP")
	)
	(segment
		(start 374.0658 -82.846672)
		(end 374.0658 -97.657666)
		(width 0.13462)
		(layer "B.Cu")
		(net "USB2_MICRO_DP")
	)
	(segment
		(start 447.289936 -209.06232)
		(end 446.064386 -209.06232)
		(width 0.13462)
		(layer "B.Cu")
		(net "USB2_MICRO_DP")
	)
	(segment
		(start 374.0658 -97.657666)
		(end 380.691898 -104.283764)
		(width 0.13462)
		(layer "B.Cu")
		(net "USB2_MICRO_DP")
	)
	(segment
		(start 269.053818 -69.434964)
		(end 271.678654 -72.0598)
		(width 0.13462)
		(layer "B.Cu")
		(net "USB2_MICRO_DP")
	)
	(segment
		(start 311.371234 -78.0796)
		(end 313.588654 -78.0796)
		(width 0.13462)
		(layer "B.Cu")
		(net "USB2_MICRO_DP")
	)
	(segment
		(start 273.227546 -72.0598)
		(end 276.350984 -75.183238)
		(width 0.13462)
		(layer "B.Cu")
		(net "USB2_MICRO_DP")
	)
	(segment
		(start 240.154206 -75.059794)
		(end 241.500406 -75.059794)
		(width 0.13462)
		(layer "B.Cu")
		(net "USB2_MICRO_DP")
	)
	(segment
		(start 371.051328 -79.8322)
		(end 374.0658 -82.846672)
		(width 0.13462)
		(layer "B.Cu")
		(net "USB2_MICRO_DP")
	)
	(segment
		(start 228.736398 -78.67523)
		(end 230.166164 -78.67523)
		(width 0.13462)
		(layer "B.Cu")
		(net "USB2_MICRO_DP")
	)
	(segment
		(start 345.073478 -79.8322)
		(end 371.051328 -79.8322)
		(width 0.13462)
		(layer "B.Cu")
		(net "USB2_MICRO_DP")
	)
	(segment
		(start 289.33775 -80.560418)
		(end 291.837618 -80.560418)
		(width 0.13462)
		(layer "B.Cu")
		(net "USB2_MICRO_DP")
	)
	(segment
		(start 249.142758 -66.3194)
		(end 261.531354 -66.3194)
		(width 0.13462)
		(layer "B.Cu")
		(net "USB2_MICRO_DP")
	)
	(segment
		(start 231.770428 -80.279494)
		(end 234.934506 -80.279494)
		(width 0.13462)
		(layer "B.Cu")
		(net "USB2_MICRO_DP")
	)
	(segment
		(start 315.214254 -79.7052)
		(end 328.978768 -79.7052)
		(width 0.13462)
		(layer "B.Cu")
		(net "USB2_MICRO_DP")
	)
	(segment
		(start 308.323234 -81.1276)
		(end 311.371234 -78.0796)
		(width 0.13462)
		(layer "B.Cu")
		(net "USB2_MICRO_DP")
	)
	(segment
		(start 276.350984 -75.183238)
		(end 277.163784 -75.183238)
		(width 0.13462)
		(layer "B.Cu")
		(net "USB2_MICRO_DP")
	)
	(segment
		(start 331.941932 -76.742036)
		(end 341.983314 -76.742036)
		(width 0.13462)
		(layer "B.Cu")
		(net "USB2_MICRO_DP")
	)
	(segment
		(start 271.678654 -72.0598)
		(end 273.227546 -72.0598)
		(width 0.13462)
		(layer "B.Cu")
		(net "USB2_MICRO_DP")
	)
	(segment
		(start 447.940684 -203.077318)
		(end 447.940684 -203.915518)
		(width 0.13462)
		(layer "B.Cu")
		(net "USB2_MICRO_DP")
	)
	(segment
		(start 288.28492 -79.507588)
		(end 289.33775 -80.560418)
		(width 0.13462)
		(layer "B.Cu")
		(net "USB2_MICRO_DP")
	)
	(segment
		(start 382.542034 -129.1336)
		(end 406.844246 -129.1336)
		(width 0.13462)
		(layer "B.Cu")
		(net "USB2_MICRO_DP")
	)
	(segment
		(start 281.488134 -79.507588)
		(end 288.28492 -79.507588)
		(width 0.13462)
		(layer "B.Cu")
		(net "USB2_MICRO_DP")
	)
	(segment
		(start 300.063916 -81.1276)
		(end 308.323234 -81.1276)
		(width 0.13462)
		(layer "B.Cu")
		(net "USB2_MICRO_DP")
	)
	(segment
		(start 242.283488 -73.17867)
		(end 249.142758 -66.3194)
		(width 0.13462)
		(layer "B.Cu")
		(net "USB2_MICRO_DP")
	)
	(segment
		(start 413.476948 -168.613582)
		(end 447.940684 -203.077318)
		(width 0.13462)
		(layer "B.Cu")
		(net "USB2_MICRO_DP")
	)
	(segment
		(start 291.837618 -80.560418)
		(end 293.360348 -82.083148)
		(width 0.13462)
		(layer "B.Cu")
		(net "USB2_MICRO_DP")
	)
	(segment
		(start 234.934506 -80.279494)
		(end 240.154206 -75.059794)
		(width 0.13462)
		(layer "B.Cu")
		(net "USB2_MICRO_DP")
	)
	(segment
		(start 328.978768 -79.7052)
		(end 331.941932 -76.742036)
		(width 0.13462)
		(layer "B.Cu")
		(net "USB2_MICRO_DP")
	)
	(segment
		(start 261.531354 -66.3194)
		(end 269.053818 -69.434964)
		(width 0.13462)
		(layer "B.Cu")
		(net "USB2_MICRO_DP")
	)
	(segment
		(start 407.880312 -161.1122)
		(end 413.476948 -166.708836)
		(width 0.13462)
		(layer "B.Cu")
		(net "USB2_MICRO_DP")
	)
	(segment
		(start 341.983314 -76.742036)
		(end 345.073478 -79.8322)
		(width 0.13462)
		(layer "B.Cu")
		(net "USB2_MICRO_DP")
	)
	(segment
		(start 406.844246 -129.1336)
		(end 407.880312 -130.169666)
		(width 0.13462)
		(layer "B.Cu")
		(net "USB2_MICRO_DP")
	)
	(segment
		(start 446.064386 -209.06232)
		(end 445.746124 -209.380582)
		(width 0.13462)
		(layer "B.Cu")
		(net "USB2_MICRO_DP")
	)
	(segment
		(start 447.940684 -208.411572)
		(end 447.289936 -209.06232)
		(width 0.13462)
		(layer "B.Cu")
		(net "USB2_MICRO_DP")
	)
	(segment
		(start 392.730482 -138.496802)
		(end 393.051284 -138.176)
		(width 0.13462)
		(layer "F.Cu")
		(net "CLK_100M_DB2000QL_NIC6_R_DN")
	)
	(segment
		(start 140.474192 -183.009286)
		(end 140.837158 -182.64632)
		(width 0.13462)
		(layer "F.Cu")
		(net "CLK_100M_DB2000QL_NIC6_R_DN")
	)
	(segment
		(start 140.837158 -182.64632)
		(end 141.717014 -182.64632)
		(width 0.13462)
		(layer "F.Cu")
		(net "CLK_100M_DB2000QL_NIC6_R_DN")
	)
	(segment
		(start 393.904978 -138.364976)
		(end 394.342366 -138.364976)
		(width 0.13462)
		(layer "F.Cu")
		(net "CLK_100M_DB2000QL_NIC6_R_DN")
	)
	(segment
		(start 393.051284 -138.176)
		(end 393.716002 -138.176)
		(width 0.13462)
		(layer "F.Cu")
		(net "CLK_100M_DB2000QL_NIC6_R_DN")
	)
	(segment
		(start 141.717014 -182.64632)
		(end 142.00378 -182.933086)
		(width 0.13462)
		(layer "F.Cu")
		(net "CLK_100M_DB2000QL_NIC6_R_DN")
	)
	(segment
		(start 393.716002 -138.176)
		(end 393.904978 -138.364976)
		(width 0.13462)
		(layer "F.Cu")
		(net "CLK_100M_DB2000QL_NIC6_R_DN")
	)
	(via
		(at 392.730482 -138.496802)
		(size 0.508)
		(drill 0.254)
		(layers "F.Cu" "B.Cu")
		(net "CLK_100M_DB2000QL_NIC6_R_DN")
	)
	(via
		(at 142.00378 -182.933086)
		(size 0.508)
		(drill 0.254)
		(layers "F.Cu" "B.Cu")
		(net "CLK_100M_DB2000QL_NIC6_R_DN")
	)
	(segment
		(start 214.936324 -163.599622)
		(end 238.029242 -163.599622)
		(width 0.1651)
		(layer "In15.Cu")
		(net "CLK_100M_DB2000QL_NIC6_R_DN")
	)
	(segment
		(start 179.714906 -171.541694)
		(end 180.42128 -170.83532)
		(width 0.1651)
		(layer "In15.Cu")
		(net "CLK_100M_DB2000QL_NIC6_R_DN")
	)
	(segment
		(start 368.469164 -164.061902)
		(end 386.333746 -146.19732)
		(width 0.1651)
		(layer "In15.Cu")
		(net "CLK_100M_DB2000QL_NIC6_R_DN")
	)
	(segment
		(start 142.282926 -182.65394)
		(end 142.63624 -182.65394)
		(width 0.1651)
		(layer "In15.Cu")
		(net "CLK_100M_DB2000QL_NIC6_R_DN")
	)
	(segment
		(start 386.333746 -146.19732)
		(end 386.333746 -141.8971)
		(width 0.1651)
		(layer "In15.Cu")
		(net "CLK_100M_DB2000QL_NIC6_R_DN")
	)
	(segment
		(start 358.032558 -163.775644)
		(end 358.318816 -164.061902)
		(width 0.1651)
		(layer "In15.Cu")
		(net "CLK_100M_DB2000QL_NIC6_R_DN")
	)
	(segment
		(start 142.94358 -182.3466)
		(end 166.799768 -182.3466)
		(width 0.1651)
		(layer "In15.Cu")
		(net "CLK_100M_DB2000QL_NIC6_R_DN")
	)
	(segment
		(start 207.989424 -170.543982)
		(end 214.936324 -163.599622)
		(width 0.1651)
		(layer "In15.Cu")
		(net "CLK_100M_DB2000QL_NIC6_R_DN")
	)
	(segment
		(start 392.443462 -138.209782)
		(end 392.730482 -138.496802)
		(width 0.1651)
		(layer "In15.Cu")
		(net "CLK_100M_DB2000QL_NIC6_R_DN")
	)
	(segment
		(start 358.318816 -164.061902)
		(end 368.469164 -164.061902)
		(width 0.1651)
		(layer "In15.Cu")
		(net "CLK_100M_DB2000QL_NIC6_R_DN")
	)
	(segment
		(start 256.45364 -164.13734)
		(end 269.383002 -164.13734)
		(width 0.1651)
		(layer "In15.Cu")
		(net "CLK_100M_DB2000QL_NIC6_R_DN")
	)
	(segment
		(start 307.633624 -158.850076)
		(end 309.391558 -157.092142)
		(width 0.1651)
		(layer "In15.Cu")
		(net "CLK_100M_DB2000QL_NIC6_R_DN")
	)
	(segment
		(start 254.54864 -166.04234)
		(end 256.45364 -164.13734)
		(width 0.1651)
		(layer "In15.Cu")
		(net "CLK_100M_DB2000QL_NIC6_R_DN")
	)
	(segment
		(start 142.63624 -182.65394)
		(end 142.94358 -182.3466)
		(width 0.1651)
		(layer "In15.Cu")
		(net "CLK_100M_DB2000QL_NIC6_R_DN")
	)
	(segment
		(start 166.799768 -182.3466)
		(end 177.604674 -171.541694)
		(width 0.1651)
		(layer "In15.Cu")
		(net "CLK_100M_DB2000QL_NIC6_R_DN")
	)
	(segment
		(start 340.532212 -157.346142)
		(end 341.281766 -156.596588)
		(width 0.1651)
		(layer "In15.Cu")
		(net "CLK_100M_DB2000QL_NIC6_R_DN")
	)
	(segment
		(start 269.383002 -164.13734)
		(end 274.670266 -158.850076)
		(width 0.1651)
		(layer "In15.Cu")
		(net "CLK_100M_DB2000QL_NIC6_R_DN")
	)
	(segment
		(start 386.333746 -141.8971)
		(end 390.021064 -138.209782)
		(width 0.1651)
		(layer "In15.Cu")
		(net "CLK_100M_DB2000QL_NIC6_R_DN")
	)
	(segment
		(start 390.021064 -138.209782)
		(end 392.443462 -138.209782)
		(width 0.1651)
		(layer "In15.Cu")
		(net "CLK_100M_DB2000QL_NIC6_R_DN")
	)
	(segment
		(start 180.42128 -170.83532)
		(end 207.687164 -170.83532)
		(width 0.1651)
		(layer "In15.Cu")
		(net "CLK_100M_DB2000QL_NIC6_R_DN")
	)
	(segment
		(start 274.670266 -158.850076)
		(end 307.633624 -158.850076)
		(width 0.1651)
		(layer "In15.Cu")
		(net "CLK_100M_DB2000QL_NIC6_R_DN")
	)
	(segment
		(start 309.391558 -157.092142)
		(end 337.524852 -157.092142)
		(width 0.1651)
		(layer "In15.Cu")
		(net "CLK_100M_DB2000QL_NIC6_R_DN")
	)
	(segment
		(start 177.604674 -171.541694)
		(end 179.714906 -171.541694)
		(width 0.1651)
		(layer "In15.Cu")
		(net "CLK_100M_DB2000QL_NIC6_R_DN")
	)
	(segment
		(start 337.778852 -157.346142)
		(end 340.532212 -157.346142)
		(width 0.1651)
		(layer "In15.Cu")
		(net "CLK_100M_DB2000QL_NIC6_R_DN")
	)
	(segment
		(start 207.687164 -170.83532)
		(end 207.97901 -170.543728)
		(width 0.1651)
		(layer "In15.Cu")
		(net "CLK_100M_DB2000QL_NIC6_R_DN")
	)
	(segment
		(start 240.47196 -166.04234)
		(end 254.54864 -166.04234)
		(width 0.1651)
		(layer "In15.Cu")
		(net "CLK_100M_DB2000QL_NIC6_R_DN")
	)
	(segment
		(start 142.00378 -182.933086)
		(end 142.282926 -182.65394)
		(width 0.1651)
		(layer "In15.Cu")
		(net "CLK_100M_DB2000QL_NIC6_R_DN")
	)
	(segment
		(start 341.281766 -156.596588)
		(end 348.83471 -156.596588)
		(width 0.1651)
		(layer "In15.Cu")
		(net "CLK_100M_DB2000QL_NIC6_R_DN")
	)
	(segment
		(start 337.524852 -157.092142)
		(end 337.778852 -157.346142)
		(width 0.1651)
		(layer "In15.Cu")
		(net "CLK_100M_DB2000QL_NIC6_R_DN")
	)
	(segment
		(start 348.83471 -156.596588)
		(end 356.013766 -163.775644)
		(width 0.1651)
		(layer "In15.Cu")
		(net "CLK_100M_DB2000QL_NIC6_R_DN")
	)
	(segment
		(start 207.97901 -170.543728)
		(end 207.989424 -170.543982)
		(width 0.1651)
		(layer "In15.Cu")
		(net "CLK_100M_DB2000QL_NIC6_R_DN")
	)
	(segment
		(start 238.029242 -163.599622)
		(end 240.47196 -166.04234)
		(width 0.1651)
		(layer "In15.Cu")
		(net "CLK_100M_DB2000QL_NIC6_R_DN")
	)
	(segment
		(start 356.013766 -163.775644)
		(end 358.032558 -163.775644)
		(width 0.1651)
		(layer "In15.Cu")
		(net "CLK_100M_DB2000QL_NIC6_R_DN")
	)
	(segment
		(start 103.672386 -332.372716)
		(end 103.744522 -332.30058)
		(width 0.1143)
		(layer "B.Cu")
		(net "CLK_100M_DB800ZL_PEX2_S0_DP")
	)
	(segment
		(start 100.872798 -332.781656)
		(end 102.242366 -332.781656)
		(width 0.1143)
		(layer "B.Cu")
		(net "CLK_100M_DB800ZL_PEX2_S0_DP")
	)
	(segment
		(start 99.75342 -333.067406)
		(end 100.073714 -333.3877)
		(width 0.1143)
		(layer "B.Cu")
		(net "CLK_100M_DB800ZL_PEX2_S0_DP")
	)
	(segment
		(start 102.242366 -332.781656)
		(end 103.229664 -332.372716)
		(width 0.1143)
		(layer "B.Cu")
		(net "CLK_100M_DB800ZL_PEX2_S0_DP")
	)
	(segment
		(start 103.229664 -332.372716)
		(end 103.672386 -332.372716)
		(width 0.1143)
		(layer "B.Cu")
		(net "CLK_100M_DB800ZL_PEX2_S0_DP")
	)
	(segment
		(start 100.266754 -333.3877)
		(end 100.872798 -332.781656)
		(width 0.1143)
		(layer "B.Cu")
		(net "CLK_100M_DB800ZL_PEX2_S0_DP")
	)
	(segment
		(start 100.073714 -333.3877)
		(end 100.266754 -333.3877)
		(width 0.1143)
		(layer "B.Cu")
		(net "CLK_100M_DB800ZL_PEX2_S0_DP")
	)
	(segment
		(start 103.744522 -332.30058)
		(end 103.939594 -332.30058)
		(width 0.1143)
		(layer "B.Cu")
		(net "CLK_100M_DB800ZL_PEX2_S0_DP")
	)
	(segment
		(start 59.373262 -389.67156)
		(end 59.373262 -389.18769)
		(width 0.13208)
		(layer "F.Cu")
		(net "RST_GPU_FPGA_PEX_RST_N")
	)
	(segment
		(start 58.866786 -389.119618)
		(end 58.866786 -391.519664)
		(width 0.13208)
		(layer "F.Cu")
		(net "RST_GPU_FPGA_PEX_RST_N")
	)
	(segment
		(start 59.421268 -392.074146)
		(end 59.421268 -392.76274)
		(width 0.13208)
		(layer "F.Cu")
		(net "RST_GPU_FPGA_PEX_RST_N")
	)
	(segment
		(start 58.866786 -391.519664)
		(end 59.421268 -392.074146)
		(width 0.13208)
		(layer "F.Cu")
		(net "RST_GPU_FPGA_PEX_RST_N")
	)
	(segment
		(start 59.085988 -388.900416)
		(end 58.866786 -389.119618)
		(width 0.13208)
		(layer "F.Cu")
		(net "RST_GPU_FPGA_PEX_RST_N")
	)
	(segment
		(start 59.373262 -389.18769)
		(end 59.085988 -388.900416)
		(width 0.13208)
		(layer "F.Cu")
		(net "RST_GPU_FPGA_PEX_RST_N")
	)
	(via
		(at 59.085988 -388.900416)
		(size 0.508)
		(drill 0.254)
		(layers "F.Cu" "B.Cu")
		(net "RST_GPU_FPGA_PEX_RST_N")
	)
	(segment
		(start 68.003674 -391.36066)
		(end 68.003674 -412.681928)
		(width 0.15494)
		(layer "In9.Cu")
		(net "RST_GPU_FPGA_PEX_RST_N")
	)
	(segment
		(start 68.003674 -412.681928)
		(end 70.784466 -415.46272)
		(width 0.15494)
		(layer "In9.Cu")
		(net "RST_GPU_FPGA_PEX_RST_N")
	)
	(segment
		(start 64.466978 -387.8326)
		(end 64.566038 -387.93166)
		(width 0.15494)
		(layer "In9.Cu")
		(net "RST_GPU_FPGA_PEX_RST_N")
	)
	(segment
		(start 57.479946 -389.6106)
		(end 57.2262 -389.356854)
		(width 0.15494)
		(layer "In9.Cu")
		(net "RST_GPU_FPGA_PEX_RST_N")
	)
	(segment
		(start 64.574674 -387.93166)
		(end 68.003674 -391.36066)
		(width 0.15494)
		(layer "In9.Cu")
		(net "RST_GPU_FPGA_PEX_RST_N")
	)
	(segment
		(start 64.566038 -387.93166)
		(end 64.574674 -387.93166)
		(width 0.15494)
		(layer "In9.Cu")
		(net "RST_GPU_FPGA_PEX_RST_N")
	)
	(segment
		(start 58.242454 -387.2484)
		(end 61.341 -387.2484)
		(width 0.15494)
		(layer "In9.Cu")
		(net "RST_GPU_FPGA_PEX_RST_N")
	)
	(segment
		(start 59.085988 -388.900416)
		(end 58.375804 -389.6106)
		(width 0.15494)
		(layer "In9.Cu")
		(net "RST_GPU_FPGA_PEX_RST_N")
	)
	(segment
		(start 61.9252 -387.8326)
		(end 64.466978 -387.8326)
		(width 0.15494)
		(layer "In9.Cu")
		(net "RST_GPU_FPGA_PEX_RST_N")
	)
	(segment
		(start 61.341 -387.2484)
		(end 61.9252 -387.8326)
		(width 0.15494)
		(layer "In9.Cu")
		(net "RST_GPU_FPGA_PEX_RST_N")
	)
	(segment
		(start 57.2262 -389.356854)
		(end 57.2262 -388.264654)
		(width 0.15494)
		(layer "In9.Cu")
		(net "RST_GPU_FPGA_PEX_RST_N")
	)
	(segment
		(start 70.784466 -415.46272)
		(end 86.137242 -415.46272)
		(width 0.15494)
		(layer "In9.Cu")
		(net "RST_GPU_FPGA_PEX_RST_N")
	)
	(segment
		(start 57.2262 -388.264654)
		(end 58.242454 -387.2484)
		(width 0.15494)
		(layer "In9.Cu")
		(net "RST_GPU_FPGA_PEX_RST_N")
	)
	(segment
		(start 58.375804 -389.6106)
		(end 57.479946 -389.6106)
		(width 0.15494)
		(layer "In9.Cu")
		(net "RST_GPU_FPGA_PEX_RST_N")
	)
	(segment
		(start 86.137242 -415.46272)
		(end 89.509854 -412.090108)
		(width 0.15494)
		(layer "In9.Cu")
		(net "RST_GPU_FPGA_PEX_RST_N")
	)
	(segment
		(start 212.871304 -119.771922)
		(end 213.676484 -119.771922)
		(width 0.13208)
		(layer "F.Cu")
		(net "P3V3_NIC3_OCP")
	)
	(segment
		(start 214.597742 -120.161304)
		(end 214.065866 -120.161304)
		(width 0.13208)
		(layer "F.Cu")
		(net "P3V3_NIC3_OCP")
	)
	(segment
		(start 213.676484 -119.771922)
		(end 214.065866 -120.161304)
		(width 0.13208)
		(layer "F.Cu")
		(net "P3V3_NIC3_OCP")
	)
	(segment
		(start 214.675466 -120.239028)
		(end 214.597742 -120.161304)
		(width 0.13208)
		(layer "F.Cu")
		(net "P3V3_NIC3_OCP")
	)
	(via
		(at 214.065866 -120.161304)
		(size 0.508)
		(drill 0.254)
		(layers "F.Cu" "B.Cu")
		(net "P3V3_NIC3_OCP")
	)
	(segment
		(start 140.832586 -180.31968)
		(end 142.356586 -180.31968)
		(width 0.13462)
		(layer "F.Cu")
		(net "CLK_100M_DB2000QL_NIC5_R_DP")
	)
	(segment
		(start 142.356586 -180.31968)
		(end 142.63878 -180.037486)
		(width 0.13462)
		(layer "F.Cu")
		(net "CLK_100M_DB2000QL_NIC5_R_DP")
	)
	(segment
		(start 307.132736 -117.758972)
		(end 306.856384 -117.48262)
		(width 0.13462)
		(layer "F.Cu")
		(net "CLK_100M_DB2000QL_NIC5_R_DP")
	)
	(segment
		(start 305.94808 -117.63502)
		(end 305.457606 -117.63502)
		(width 0.13462)
		(layer "F.Cu")
		(net "CLK_100M_DB2000QL_NIC5_R_DP")
	)
	(segment
		(start 140.474192 -179.961286)
		(end 140.832586 -180.31968)
		(width 0.13462)
		(layer "F.Cu")
		(net "CLK_100M_DB2000QL_NIC5_R_DP")
	)
	(segment
		(start 306.10048 -117.48262)
		(end 305.94808 -117.63502)
		(width 0.13462)
		(layer "F.Cu")
		(net "CLK_100M_DB2000QL_NIC5_R_DP")
	)
	(segment
		(start 306.856384 -117.48262)
		(end 306.10048 -117.48262)
		(width 0.13462)
		(layer "F.Cu")
		(net "CLK_100M_DB2000QL_NIC5_R_DP")
	)
	(via
		(at 142.63878 -180.037486)
		(size 0.508)
		(drill 0.254)
		(layers "F.Cu" "B.Cu")
		(net "CLK_100M_DB2000QL_NIC5_R_DP")
	)
	(via
		(at 307.132736 -117.758972)
		(size 0.508)
		(drill 0.254)
		(layers "F.Cu" "B.Cu")
		(net "CLK_100M_DB2000QL_NIC5_R_DP")
	)
	(segment
		(start 238.440722 -162.494722)
		(end 240.919 -164.973)
		(width 0.1651)
		(layer "In15.Cu")
		(net "CLK_100M_DB2000QL_NIC5_R_DP")
	)
	(segment
		(start 297.60545 -157.765496)
		(end 297.71975 -157.651196)
		(width 0.1651)
		(layer "In15.Cu")
		(net "CLK_100M_DB2000QL_NIC5_R_DP")
	)
	(segment
		(start 304.31105 -157.651196)
		(end 304.42535 -157.765496)
		(width 0.1651)
		(layer "In15.Cu")
		(net "CLK_100M_DB2000QL_NIC5_R_DP")
	)
	(segment
		(start 306.803044 -157.415484)
		(end 306.803044 -157.253686)
		(width 0.1651)
		(layer "In15.Cu")
		(net "CLK_100M_DB2000QL_NIC5_R_DP")
	)
	(segment
		(start 307.315362 -156.903166)
		(end 308.70906 -155.509468)
		(width 0.1651)
		(layer "In15.Cu")
		(net "CLK_100M_DB2000QL_NIC5_R_DP")
	)
	(segment
		(start 256.148078 -162.520122)
		(end 267.044678 -162.520122)
		(width 0.1651)
		(layer "In15.Cu")
		(net "CLK_100M_DB2000QL_NIC5_R_DP")
	)
	(segment
		(start 175.244252 -170.396916)
		(end 179.140104 -170.396916)
		(width 0.1651)
		(layer "In15.Cu")
		(net "CLK_100M_DB2000QL_NIC5_R_DP")
	)
	(segment
		(start 303.09185 -157.651196)
		(end 303.20615 -157.765496)
		(width 0.1651)
		(layer "In15.Cu")
		(net "CLK_100M_DB2000QL_NIC5_R_DP")
	)
	(segment
		(start 308.70906 -155.509468)
		(end 308.70906 -118.02364)
		(width 0.1651)
		(layer "In15.Cu")
		(net "CLK_100M_DB2000QL_NIC5_R_DP")
	)
	(segment
		(start 304.92065 -157.765496)
		(end 305.03495 -157.651196)
		(width 0.1651)
		(layer "In15.Cu")
		(net "CLK_100M_DB2000QL_NIC5_R_DP")
	)
	(segment
		(start 296.50055 -157.651196)
		(end 296.99585 -157.651196)
		(width 0.1651)
		(layer "In15.Cu")
		(net "CLK_100M_DB2000QL_NIC5_R_DP")
	)
	(segment
		(start 207.435958 -169.621962)
		(end 214.563198 -162.494722)
		(width 0.1651)
		(layer "In15.Cu")
		(net "CLK_100M_DB2000QL_NIC5_R_DP")
	)
	(segment
		(start 298.82465 -157.765496)
		(end 298.93895 -157.651196)
		(width 0.1651)
		(layer "In15.Cu")
		(net "CLK_100M_DB2000QL_NIC5_R_DP")
	)
	(segment
		(start 165.329108 -180.31206)
		(end 175.244252 -170.396916)
		(width 0.1651)
		(layer "In15.Cu")
		(net "CLK_100M_DB2000QL_NIC5_R_DP")
	)
	(segment
		(start 301.98695 -157.765496)
		(end 302.48225 -157.765496)
		(width 0.1651)
		(layer "In15.Cu")
		(net "CLK_100M_DB2000QL_NIC5_R_DP")
	)
	(segment
		(start 301.26305 -157.765496)
		(end 301.37735 -157.651196)
		(width 0.1651)
		(layer "In15.Cu")
		(net "CLK_100M_DB2000QL_NIC5_R_DP")
	)
	(segment
		(start 305.64455 -157.765496)
		(end 306.453032 -157.765496)
		(width 0.1651)
		(layer "In15.Cu")
		(net "CLK_100M_DB2000QL_NIC5_R_DP")
	)
	(segment
		(start 271.799304 -157.765496)
		(end 295.16705 -157.765496)
		(width 0.1651)
		(layer "In15.Cu")
		(net "CLK_100M_DB2000QL_NIC5_R_DP")
	)
	(segment
		(start 306.803044 -157.253686)
		(end 307.153564 -156.903166)
		(width 0.1651)
		(layer "In15.Cu")
		(net "CLK_100M_DB2000QL_NIC5_R_DP")
	)
	(segment
		(start 142.913354 -180.31206)
		(end 165.329108 -180.31206)
		(width 0.1651)
		(layer "In15.Cu")
		(net "CLK_100M_DB2000QL_NIC5_R_DP")
	)
	(segment
		(start 307.153564 -156.903166)
		(end 307.315362 -156.903166)
		(width 0.1651)
		(layer "In15.Cu")
		(net "CLK_100M_DB2000QL_NIC5_R_DP")
	)
	(segment
		(start 295.16705 -157.765496)
		(end 295.28135 -157.651196)
		(width 0.1651)
		(layer "In15.Cu")
		(net "CLK_100M_DB2000QL_NIC5_R_DP")
	)
	(segment
		(start 179.915058 -169.621962)
		(end 207.435958 -169.621962)
		(width 0.1651)
		(layer "In15.Cu")
		(net "CLK_100M_DB2000QL_NIC5_R_DP")
	)
	(segment
		(start 298.93895 -157.651196)
		(end 299.43425 -157.651196)
		(width 0.1651)
		(layer "In15.Cu")
		(net "CLK_100M_DB2000QL_NIC5_R_DP")
	)
	(segment
		(start 300.04385 -157.765496)
		(end 300.15815 -157.651196)
		(width 0.1651)
		(layer "In15.Cu")
		(net "CLK_100M_DB2000QL_NIC5_R_DP")
	)
	(segment
		(start 142.63878 -180.037486)
		(end 142.913354 -180.31206)
		(width 0.1651)
		(layer "In15.Cu")
		(net "CLK_100M_DB2000QL_NIC5_R_DP")
	)
	(segment
		(start 301.37735 -157.651196)
		(end 301.87265 -157.651196)
		(width 0.1651)
		(layer "In15.Cu")
		(net "CLK_100M_DB2000QL_NIC5_R_DP")
	)
	(segment
		(start 295.77665 -157.651196)
		(end 295.89095 -157.765496)
		(width 0.1651)
		(layer "In15.Cu")
		(net "CLK_100M_DB2000QL_NIC5_R_DP")
	)
	(segment
		(start 303.20615 -157.765496)
		(end 303.70145 -157.765496)
		(width 0.1651)
		(layer "In15.Cu")
		(net "CLK_100M_DB2000QL_NIC5_R_DP")
	)
	(segment
		(start 299.43425 -157.651196)
		(end 299.54855 -157.765496)
		(width 0.1651)
		(layer "In15.Cu")
		(net "CLK_100M_DB2000QL_NIC5_R_DP")
	)
	(segment
		(start 253.6952 -164.973)
		(end 256.148078 -162.520122)
		(width 0.1651)
		(layer "In15.Cu")
		(net "CLK_100M_DB2000QL_NIC5_R_DP")
	)
	(segment
		(start 303.70145 -157.765496)
		(end 303.81575 -157.651196)
		(width 0.1651)
		(layer "In15.Cu")
		(net "CLK_100M_DB2000QL_NIC5_R_DP")
	)
	(segment
		(start 179.140104 -170.396916)
		(end 179.915058 -169.621962)
		(width 0.1651)
		(layer "In15.Cu")
		(net "CLK_100M_DB2000QL_NIC5_R_DP")
	)
	(segment
		(start 240.919 -164.973)
		(end 253.6952 -164.973)
		(width 0.1651)
		(layer "In15.Cu")
		(net "CLK_100M_DB2000QL_NIC5_R_DP")
	)
	(segment
		(start 302.48225 -157.765496)
		(end 302.59655 -157.651196)
		(width 0.1651)
		(layer "In15.Cu")
		(net "CLK_100M_DB2000QL_NIC5_R_DP")
	)
	(segment
		(start 297.11015 -157.765496)
		(end 297.60545 -157.765496)
		(width 0.1651)
		(layer "In15.Cu")
		(net "CLK_100M_DB2000QL_NIC5_R_DP")
	)
	(segment
		(start 308.157372 -117.471952)
		(end 307.419756 -117.471952)
		(width 0.1651)
		(layer "In15.Cu")
		(net "CLK_100M_DB2000QL_NIC5_R_DP")
	)
	(segment
		(start 300.65345 -157.651196)
		(end 300.76775 -157.765496)
		(width 0.1651)
		(layer "In15.Cu")
		(net "CLK_100M_DB2000QL_NIC5_R_DP")
	)
	(segment
		(start 214.563198 -162.494722)
		(end 238.440722 -162.494722)
		(width 0.1651)
		(layer "In15.Cu")
		(net "CLK_100M_DB2000QL_NIC5_R_DP")
	)
	(segment
		(start 295.89095 -157.765496)
		(end 296.38625 -157.765496)
		(width 0.1651)
		(layer "In15.Cu")
		(net "CLK_100M_DB2000QL_NIC5_R_DP")
	)
	(segment
		(start 295.28135 -157.651196)
		(end 295.77665 -157.651196)
		(width 0.1651)
		(layer "In15.Cu")
		(net "CLK_100M_DB2000QL_NIC5_R_DP")
	)
	(segment
		(start 304.42535 -157.765496)
		(end 304.92065 -157.765496)
		(width 0.1651)
		(layer "In15.Cu")
		(net "CLK_100M_DB2000QL_NIC5_R_DP")
	)
	(segment
		(start 299.54855 -157.765496)
		(end 300.04385 -157.765496)
		(width 0.1651)
		(layer "In15.Cu")
		(net "CLK_100M_DB2000QL_NIC5_R_DP")
	)
	(segment
		(start 307.419756 -117.471952)
		(end 307.132736 -117.758972)
		(width 0.1651)
		(layer "In15.Cu")
		(net "CLK_100M_DB2000QL_NIC5_R_DP")
	)
	(segment
		(start 267.044678 -162.520122)
		(end 271.799304 -157.765496)
		(width 0.1651)
		(layer "In15.Cu")
		(net "CLK_100M_DB2000QL_NIC5_R_DP")
	)
	(segment
		(start 308.70906 -118.02364)
		(end 308.157372 -117.471952)
		(width 0.1651)
		(layer "In15.Cu")
		(net "CLK_100M_DB2000QL_NIC5_R_DP")
	)
	(segment
		(start 300.15815 -157.651196)
		(end 300.65345 -157.651196)
		(width 0.1651)
		(layer "In15.Cu")
		(net "CLK_100M_DB2000QL_NIC5_R_DP")
	)
	(segment
		(start 296.38625 -157.765496)
		(end 296.50055 -157.651196)
		(width 0.1651)
		(layer "In15.Cu")
		(net "CLK_100M_DB2000QL_NIC5_R_DP")
	)
	(segment
		(start 305.03495 -157.651196)
		(end 305.53025 -157.651196)
		(width 0.1651)
		(layer "In15.Cu")
		(net "CLK_100M_DB2000QL_NIC5_R_DP")
	)
	(segment
		(start 303.81575 -157.651196)
		(end 304.31105 -157.651196)
		(width 0.1651)
		(layer "In15.Cu")
		(net "CLK_100M_DB2000QL_NIC5_R_DP")
	)
	(segment
		(start 298.32935 -157.765496)
		(end 298.82465 -157.765496)
		(width 0.1651)
		(layer "In15.Cu")
		(net "CLK_100M_DB2000QL_NIC5_R_DP")
	)
	(segment
		(start 296.99585 -157.651196)
		(end 297.11015 -157.765496)
		(width 0.1651)
		(layer "In15.Cu")
		(net "CLK_100M_DB2000QL_NIC5_R_DP")
	)
	(segment
		(start 298.21505 -157.651196)
		(end 298.32935 -157.765496)
		(width 0.1651)
		(layer "In15.Cu")
		(net "CLK_100M_DB2000QL_NIC5_R_DP")
	)
	(segment
		(start 306.453032 -157.765496)
		(end 306.803044 -157.415484)
		(width 0.1651)
		(layer "In15.Cu")
		(net "CLK_100M_DB2000QL_NIC5_R_DP")
	)
	(segment
		(start 300.76775 -157.765496)
		(end 301.26305 -157.765496)
		(width 0.1651)
		(layer "In15.Cu")
		(net "CLK_100M_DB2000QL_NIC5_R_DP")
	)
	(segment
		(start 301.87265 -157.651196)
		(end 301.98695 -157.765496)
		(width 0.1651)
		(layer "In15.Cu")
		(net "CLK_100M_DB2000QL_NIC5_R_DP")
	)
	(segment
		(start 305.53025 -157.651196)
		(end 305.64455 -157.765496)
		(width 0.1651)
		(layer "In15.Cu")
		(net "CLK_100M_DB2000QL_NIC5_R_DP")
	)
	(segment
		(start 297.71975 -157.651196)
		(end 298.21505 -157.651196)
		(width 0.1651)
		(layer "In15.Cu")
		(net "CLK_100M_DB2000QL_NIC5_R_DP")
	)
	(segment
		(start 302.59655 -157.651196)
		(end 303.09185 -157.651196)
		(width 0.1651)
		(layer "In15.Cu")
		(net "CLK_100M_DB2000QL_NIC5_R_DP")
	)
	(via
		(at 257.881374 -78.64348)
		(size 0.6604)
		(drill 0.3302)
		(layers "F.Cu" "B.Cu")
		(net "P3V3_CLK_GEN_VDDA100M_CK440")
	)
	(via
		(at 259.69849 -79.46771)
		(size 0.508)
		(drill 0.254)
		(layers "F.Cu" "B.Cu")
		(net "P3V3_CLK_GEN_VDDA100M_CK440")
	)
	(via
		(at 259.549392 -78.840584)
		(size 0.508)
		(drill 0.254)
		(layers "F.Cu" "B.Cu")
		(net "P3V3_CLK_GEN_VDDA100M_CK440")
	)
	(segment
		(start 105.6259 -335.497678)
		(end 105.6259 -334.165448)
		(width 0.1143)
		(layer "B.Cu")
		(net "CLK_100M_DB800ZL_PEX3_S0_DP")
	)
	(segment
		(start 105.5878 -336.680556)
		(end 105.5878 -335.535778)
		(width 0.1143)
		(layer "B.Cu")
		(net "CLK_100M_DB800ZL_PEX3_S0_DP")
	)
	(segment
		(start 105.5878 -335.535778)
		(end 105.6259 -335.497678)
		(width 0.1143)
		(layer "B.Cu")
		(net "CLK_100M_DB800ZL_PEX3_S0_DP")
	)
	(segment
		(start 105.564432 -334.10398)
		(end 105.564432 -333.925418)
		(width 0.1143)
		(layer "B.Cu")
		(net "CLK_100M_DB800ZL_PEX3_S0_DP")
	)
	(segment
		(start 105.6259 -334.165448)
		(end 105.564432 -334.10398)
		(width 0.1143)
		(layer "B.Cu")
		(net "CLK_100M_DB800ZL_PEX3_S0_DP")
	)
	(segment
		(start 105.265474 -337.002882)
		(end 105.5878 -336.680556)
		(width 0.1143)
		(layer "B.Cu")
		(net "CLK_100M_DB800ZL_PEX3_S0_DP")
	)
	(segment
		(start 58.357262 -389.371332)
		(end 57.798208 -388.812278)
		(width 0.13208)
		(layer "F.Cu")
		(net "GPU_THERM_OVERT_R_N")
	)
	(segment
		(start 57.798208 -388.812278)
		(end 57.798208 -388.79145)
		(width 0.13208)
		(layer "F.Cu")
		(net "GPU_THERM_OVERT_R_N")
	)
	(segment
		(start 58.357262 -389.67156)
		(end 58.357262 -389.371332)
		(width 0.13208)
		(layer "F.Cu")
		(net "GPU_THERM_OVERT_R_N")
	)
	(via
		(at 57.798208 -388.79145)
		(size 0.508)
		(drill 0.254)
		(layers "F.Cu" "B.Cu")
		(net "GPU_THERM_OVERT_R_N")
	)
	(segment
		(start 61.645546 -388.3914)
		(end 60.985146 -387.731)
		(width 0.15494)
		(layer "In9.Cu")
		(net "GPU_THERM_OVERT_R_N")
	)
	(segment
		(start 60.985146 -387.731)
		(end 58.858658 -387.731)
		(width 0.15494)
		(layer "In9.Cu")
		(net "GPU_THERM_OVERT_R_N")
	)
	(segment
		(start 64.384174 -388.3914)
		(end 61.645546 -388.3914)
		(width 0.15494)
		(layer "In9.Cu")
		(net "GPU_THERM_OVERT_R_N")
	)
	(segment
		(start 90.2843 -410.26461)
		(end 90.2843 -412.305246)
		(width 0.15494)
		(layer "In9.Cu")
		(net "GPU_THERM_OVERT_R_N")
	)
	(segment
		(start 67.543934 -391.55116)
		(end 64.384174 -388.3914)
		(width 0.15494)
		(layer "In9.Cu")
		(net "GPU_THERM_OVERT_R_N")
	)
	(segment
		(start 89.509854 -409.490164)
		(end 90.2843 -410.26461)
		(width 0.15494)
		(layer "In9.Cu")
		(net "GPU_THERM_OVERT_R_N")
	)
	(segment
		(start 70.518782 -415.92246)
		(end 67.543934 -412.947612)
		(width 0.15494)
		(layer "In9.Cu")
		(net "GPU_THERM_OVERT_R_N")
	)
	(segment
		(start 67.543934 -412.947612)
		(end 67.543934 -391.55116)
		(width 0.15494)
		(layer "In9.Cu")
		(net "GPU_THERM_OVERT_R_N")
	)
	(segment
		(start 90.2843 -412.305246)
		(end 86.667086 -415.92246)
		(width 0.15494)
		(layer "In9.Cu")
		(net "GPU_THERM_OVERT_R_N")
	)
	(segment
		(start 58.858658 -387.731)
		(end 57.798208 -388.79145)
		(width 0.15494)
		(layer "In9.Cu")
		(net "GPU_THERM_OVERT_R_N")
	)
	(segment
		(start 86.667086 -415.92246)
		(end 70.518782 -415.92246)
		(width 0.15494)
		(layer "In9.Cu")
		(net "GPU_THERM_OVERT_R_N")
	)
	(segment
		(start 350.893888 -220.78696)
		(end 351.293684 -221.186756)
		(width 0.13208)
		(layer "F.Cu")
		(net "PWRGD_NIC5_PWR_GOOD_R")
	)
	(via
		(at 301.903892 -96.901)
		(size 0.508)
		(drill 0.254)
		(layers "F.Cu" "B.Cu")
		(net "PWRGD_NIC5_PWR_GOOD_R")
	)
	(via
		(at 351.293684 -221.186756)
		(size 0.4572)
		(drill 0.254)
		(layers "F.Cu" "B.Cu")
		(net "PWRGD_NIC5_PWR_GOOD_R")
	)
	(via
		(at 371.63883 -99.461066)
		(size 0.508)
		(drill 0.254)
		(layers "F.Cu" "B.Cu")
		(net "PWRGD_NIC5_PWR_GOOD_R")
	)
	(segment
		(start 301.903892 -97.663)
		(end 301.903892 -96.901)
		(width 0.13208)
		(layer "B.Cu")
		(net "PWRGD_NIC5_PWR_GOOD_R")
	)
	(segment
		(start 371.9195 -101.549962)
		(end 371.63883 -101.269292)
		(width 0.15494)
		(layer "In5.Cu")
		(net "PWRGD_NIC5_PWR_GOOD_R")
	)
	(segment
		(start 363.601 -218.955366)
		(end 366.39119 -218.955366)
		(width 0.15494)
		(layer "In5.Cu")
		(net "PWRGD_NIC5_PWR_GOOD_R")
	)
	(segment
		(start 374.233948 -208.944464)
		(end 374.285002 -208.89341)
		(width 0.15494)
		(layer "In5.Cu")
		(net "PWRGD_NIC5_PWR_GOOD_R")
	)
	(segment
		(start 374.093232 -111.191548)
		(end 371.9195 -109.017816)
		(width 0.15494)
		(layer "In5.Cu")
		(net "PWRGD_NIC5_PWR_GOOD_R")
	)
	(segment
		(start 353.768406 -221.826328)
		(end 356.192328 -221.826328)
		(width 0.15494)
		(layer "In5.Cu")
		(net "PWRGD_NIC5_PWR_GOOD_R")
	)
	(segment
		(start 374.093232 -176.270412)
		(end 374.093232 -111.191548)
		(width 0.15494)
		(layer "In5.Cu")
		(net "PWRGD_NIC5_PWR_GOOD_R")
	)
	(segment
		(start 371.9195 -109.017816)
		(end 371.9195 -101.549962)
		(width 0.15494)
		(layer "In5.Cu")
		(net "PWRGD_NIC5_PWR_GOOD_R")
	)
	(segment
		(start 374.285002 -194.49542)
		(end 376.67946 -192.100962)
		(width 0.15494)
		(layer "In5.Cu")
		(net "PWRGD_NIC5_PWR_GOOD_R")
	)
	(segment
		(start 376.67946 -178.85664)
		(end 374.093232 -176.270412)
		(width 0.15494)
		(layer "In5.Cu")
		(net "PWRGD_NIC5_PWR_GOOD_R")
	)
	(segment
		(start 359.554526 -223.00184)
		(end 363.601 -218.955366)
		(width 0.15494)
		(layer "In5.Cu")
		(net "PWRGD_NIC5_PWR_GOOD_R")
	)
	(segment
		(start 374.285002 -208.89341)
		(end 374.285002 -194.49542)
		(width 0.15494)
		(layer "In5.Cu")
		(net "PWRGD_NIC5_PWR_GOOD_R")
	)
	(segment
		(start 366.39119 -218.955366)
		(end 374.233948 -211.112608)
		(width 0.15494)
		(layer "In5.Cu")
		(net "PWRGD_NIC5_PWR_GOOD_R")
	)
	(segment
		(start 376.67946 -192.100962)
		(end 376.67946 -178.85664)
		(width 0.15494)
		(layer "In5.Cu")
		(net "PWRGD_NIC5_PWR_GOOD_R")
	)
	(segment
		(start 374.233948 -211.112608)
		(end 374.233948 -208.944464)
		(width 0.15494)
		(layer "In5.Cu")
		(net "PWRGD_NIC5_PWR_GOOD_R")
	)
	(segment
		(start 371.63883 -101.269292)
		(end 371.63883 -99.461066)
		(width 0.15494)
		(layer "In5.Cu")
		(net "PWRGD_NIC5_PWR_GOOD_R")
	)
	(segment
		(start 353.128834 -221.186756)
		(end 353.768406 -221.826328)
		(width 0.15494)
		(layer "In5.Cu")
		(net "PWRGD_NIC5_PWR_GOOD_R")
	)
	(segment
		(start 356.192328 -221.826328)
		(end 357.36784 -223.00184)
		(width 0.15494)
		(layer "In5.Cu")
		(net "PWRGD_NIC5_PWR_GOOD_R")
	)
	(segment
		(start 351.293684 -221.186756)
		(end 353.128834 -221.186756)
		(width 0.15494)
		(layer "In5.Cu")
		(net "PWRGD_NIC5_PWR_GOOD_R")
	)
	(segment
		(start 357.36784 -223.00184)
		(end 359.554526 -223.00184)
		(width 0.15494)
		(layer "In5.Cu")
		(net "PWRGD_NIC5_PWR_GOOD_R")
	)
	(segment
		(start 305.480466 -96.373188)
		(end 306.933854 -94.9198)
		(width 0.15494)
		(layer "In13.Cu")
		(net "PWRGD_NIC5_PWR_GOOD_R")
	)
	(segment
		(start 333.1464 -102.434898)
		(end 335.384902 -104.6734)
		(width 0.15494)
		(layer "In13.Cu")
		(net "PWRGD_NIC5_PWR_GOOD_R")
	)
	(segment
		(start 363.05109 -102.570026)
		(end 366.713516 -98.9076)
		(width 0.15494)
		(layer "In13.Cu")
		(net "PWRGD_NIC5_PWR_GOOD_R")
	)
	(segment
		(start 302.431704 -96.373188)
		(end 305.480466 -96.373188)
		(width 0.15494)
		(layer "In13.Cu")
		(net "PWRGD_NIC5_PWR_GOOD_R")
	)
	(segment
		(start 335.384902 -104.6734)
		(end 339.292946 -104.6734)
		(width 0.15494)
		(layer "In13.Cu")
		(net "PWRGD_NIC5_PWR_GOOD_R")
	)
	(segment
		(start 306.933854 -94.9198)
		(end 311.6326 -94.9198)
		(width 0.15494)
		(layer "In13.Cu")
		(net "PWRGD_NIC5_PWR_GOOD_R")
	)
	(segment
		(start 366.713516 -98.9076)
		(end 371.085364 -98.9076)
		(width 0.15494)
		(layer "In13.Cu")
		(net "PWRGD_NIC5_PWR_GOOD_R")
	)
	(segment
		(start 326.846946 -99.8982)
		(end 331.978254 -99.8982)
		(width 0.15494)
		(layer "In13.Cu")
		(net "PWRGD_NIC5_PWR_GOOD_R")
	)
	(segment
		(start 326.516746 -100.2284)
		(end 326.846946 -99.8982)
		(width 0.15494)
		(layer "In13.Cu")
		(net "PWRGD_NIC5_PWR_GOOD_R")
	)
	(segment
		(start 371.085364 -98.9076)
		(end 371.63883 -99.461066)
		(width 0.15494)
		(layer "In13.Cu")
		(net "PWRGD_NIC5_PWR_GOOD_R")
	)
	(segment
		(start 339.292946 -104.6734)
		(end 341.39632 -102.570026)
		(width 0.15494)
		(layer "In13.Cu")
		(net "PWRGD_NIC5_PWR_GOOD_R")
	)
	(segment
		(start 311.6326 -94.9198)
		(end 316.9412 -100.2284)
		(width 0.15494)
		(layer "In13.Cu")
		(net "PWRGD_NIC5_PWR_GOOD_R")
	)
	(segment
		(start 316.9412 -100.2284)
		(end 326.516746 -100.2284)
		(width 0.15494)
		(layer "In13.Cu")
		(net "PWRGD_NIC5_PWR_GOOD_R")
	)
	(segment
		(start 341.39632 -102.570026)
		(end 363.05109 -102.570026)
		(width 0.15494)
		(layer "In13.Cu")
		(net "PWRGD_NIC5_PWR_GOOD_R")
	)
	(segment
		(start 301.903892 -96.901)
		(end 302.431704 -96.373188)
		(width 0.15494)
		(layer "In13.Cu")
		(net "PWRGD_NIC5_PWR_GOOD_R")
	)
	(segment
		(start 331.978254 -99.8982)
		(end 333.1464 -101.066346)
		(width 0.15494)
		(layer "In13.Cu")
		(net "PWRGD_NIC5_PWR_GOOD_R")
	)
	(segment
		(start 333.1464 -101.066346)
		(end 333.1464 -102.434898)
		(width 0.15494)
		(layer "In13.Cu")
		(net "PWRGD_NIC5_PWR_GOOD_R")
	)
	(segment
		(start 392.99896 -137.90168)
		(end 393.71143 -137.90168)
		(width 0.13462)
		(layer "F.Cu")
		(net "CLK_100M_DB2000QL_NIC6_R_DP")
	)
	(segment
		(start 141.701266 -182.372)
		(end 142.00378 -182.069486)
		(width 0.13462)
		(layer "F.Cu")
		(net "CLK_100M_DB2000QL_NIC6_R_DP")
	)
	(segment
		(start 392.730482 -137.633202)
		(end 392.99896 -137.90168)
		(width 0.13462)
		(layer "F.Cu")
		(net "CLK_100M_DB2000QL_NIC6_R_DP")
	)
	(segment
		(start 140.474192 -181.993286)
		(end 140.852906 -182.372)
		(width 0.13462)
		(layer "F.Cu")
		(net "CLK_100M_DB2000QL_NIC6_R_DP")
	)
	(segment
		(start 393.848082 -137.765028)
		(end 394.342366 -137.765028)
		(width 0.13462)
		(layer "F.Cu")
		(net "CLK_100M_DB2000QL_NIC6_R_DP")
	)
	(segment
		(start 393.71143 -137.90168)
		(end 393.848082 -137.765028)
		(width 0.13462)
		(layer "F.Cu")
		(net "CLK_100M_DB2000QL_NIC6_R_DP")
	)
	(segment
		(start 140.852906 -182.372)
		(end 141.701266 -182.372)
		(width 0.13462)
		(layer "F.Cu")
		(net "CLK_100M_DB2000QL_NIC6_R_DP")
	)
	(via
		(at 392.730482 -137.633202)
		(size 0.508)
		(drill 0.254)
		(layers "F.Cu" "B.Cu")
		(net "CLK_100M_DB2000QL_NIC6_R_DP")
	)
	(via
		(at 142.00378 -182.069486)
		(size 0.508)
		(drill 0.254)
		(layers "F.Cu" "B.Cu")
		(net "CLK_100M_DB2000QL_NIC6_R_DP")
	)
	(segment
		(start 337.641692 -156.810202)
		(end 337.895692 -157.064202)
		(width 0.1651)
		(layer "In15.Cu")
		(net "CLK_100M_DB2000QL_NIC6_R_DP")
	)
	(segment
		(start 142.306294 -182.372)
		(end 142.5194 -182.372)
		(width 0.1651)
		(layer "In15.Cu")
		(net "CLK_100M_DB2000QL_NIC6_R_DP")
	)
	(segment
		(start 368.352324 -163.779962)
		(end 386.051806 -146.08048)
		(width 0.1651)
		(layer "In15.Cu")
		(net "CLK_100M_DB2000QL_NIC6_R_DP")
	)
	(segment
		(start 337.895692 -157.064202)
		(end 340.415372 -157.064202)
		(width 0.1651)
		(layer "In15.Cu")
		(net "CLK_100M_DB2000QL_NIC6_R_DP")
	)
	(segment
		(start 307.516784 -158.568136)
		(end 309.274718 -156.810202)
		(width 0.1651)
		(layer "In15.Cu")
		(net "CLK_100M_DB2000QL_NIC6_R_DP")
	)
	(segment
		(start 240.5888 -165.7604)
		(end 254.4318 -165.7604)
		(width 0.1651)
		(layer "In15.Cu")
		(net "CLK_100M_DB2000QL_NIC6_R_DP")
	)
	(segment
		(start 207.864964 -170.25874)
		(end 207.875378 -170.258994)
		(width 0.1651)
		(layer "In15.Cu")
		(net "CLK_100M_DB2000QL_NIC6_R_DP")
	)
	(segment
		(start 356.130606 -163.493704)
		(end 358.149398 -163.493704)
		(width 0.1651)
		(layer "In15.Cu")
		(net "CLK_100M_DB2000QL_NIC6_R_DP")
	)
	(segment
		(start 238.146082 -163.317682)
		(end 240.5888 -165.7604)
		(width 0.1651)
		(layer "In15.Cu")
		(net "CLK_100M_DB2000QL_NIC6_R_DP")
	)
	(segment
		(start 177.487834 -171.259754)
		(end 179.598066 -171.259754)
		(width 0.1651)
		(layer "In15.Cu")
		(net "CLK_100M_DB2000QL_NIC6_R_DP")
	)
	(segment
		(start 392.435842 -137.927842)
		(end 392.730482 -137.633202)
		(width 0.1651)
		(layer "In15.Cu")
		(net "CLK_100M_DB2000QL_NIC6_R_DP")
	)
	(segment
		(start 386.051806 -141.78026)
		(end 389.904224 -137.927842)
		(width 0.1651)
		(layer "In15.Cu")
		(net "CLK_100M_DB2000QL_NIC6_R_DP")
	)
	(segment
		(start 358.149398 -163.493704)
		(end 358.435656 -163.779962)
		(width 0.1651)
		(layer "In15.Cu")
		(net "CLK_100M_DB2000QL_NIC6_R_DP")
	)
	(segment
		(start 254.4318 -165.7604)
		(end 256.3368 -163.8554)
		(width 0.1651)
		(layer "In15.Cu")
		(net "CLK_100M_DB2000QL_NIC6_R_DP")
	)
	(segment
		(start 358.435656 -163.779962)
		(end 368.352324 -163.779962)
		(width 0.1651)
		(layer "In15.Cu")
		(net "CLK_100M_DB2000QL_NIC6_R_DP")
	)
	(segment
		(start 341.164926 -156.314648)
		(end 348.95155 -156.314648)
		(width 0.1651)
		(layer "In15.Cu")
		(net "CLK_100M_DB2000QL_NIC6_R_DP")
	)
	(segment
		(start 142.82674 -182.06466)
		(end 166.682928 -182.06466)
		(width 0.1651)
		(layer "In15.Cu")
		(net "CLK_100M_DB2000QL_NIC6_R_DP")
	)
	(segment
		(start 348.95155 -156.314648)
		(end 356.130606 -163.493704)
		(width 0.1651)
		(layer "In15.Cu")
		(net "CLK_100M_DB2000QL_NIC6_R_DP")
	)
	(segment
		(start 207.875378 -170.258994)
		(end 214.819484 -163.317682)
		(width 0.1651)
		(layer "In15.Cu")
		(net "CLK_100M_DB2000QL_NIC6_R_DP")
	)
	(segment
		(start 256.3368 -163.8554)
		(end 269.266162 -163.8554)
		(width 0.1651)
		(layer "In15.Cu")
		(net "CLK_100M_DB2000QL_NIC6_R_DP")
	)
	(segment
		(start 274.553426 -158.568136)
		(end 307.516784 -158.568136)
		(width 0.1651)
		(layer "In15.Cu")
		(net "CLK_100M_DB2000QL_NIC6_R_DP")
	)
	(segment
		(start 142.00378 -182.069486)
		(end 142.306294 -182.372)
		(width 0.1651)
		(layer "In15.Cu")
		(net "CLK_100M_DB2000QL_NIC6_R_DP")
	)
	(segment
		(start 166.682928 -182.06466)
		(end 177.487834 -171.259754)
		(width 0.1651)
		(layer "In15.Cu")
		(net "CLK_100M_DB2000QL_NIC6_R_DP")
	)
	(segment
		(start 309.274718 -156.810202)
		(end 337.641692 -156.810202)
		(width 0.1651)
		(layer "In15.Cu")
		(net "CLK_100M_DB2000QL_NIC6_R_DP")
	)
	(segment
		(start 269.266162 -163.8554)
		(end 274.553426 -158.568136)
		(width 0.1651)
		(layer "In15.Cu")
		(net "CLK_100M_DB2000QL_NIC6_R_DP")
	)
	(segment
		(start 207.570324 -170.55338)
		(end 207.864964 -170.25874)
		(width 0.1651)
		(layer "In15.Cu")
		(net "CLK_100M_DB2000QL_NIC6_R_DP")
	)
	(segment
		(start 180.30444 -170.55338)
		(end 207.570324 -170.55338)
		(width 0.1651)
		(layer "In15.Cu")
		(net "CLK_100M_DB2000QL_NIC6_R_DP")
	)
	(segment
		(start 214.819484 -163.317682)
		(end 238.146082 -163.317682)
		(width 0.1651)
		(layer "In15.Cu")
		(net "CLK_100M_DB2000QL_NIC6_R_DP")
	)
	(segment
		(start 142.5194 -182.372)
		(end 142.82674 -182.06466)
		(width 0.1651)
		(layer "In15.Cu")
		(net "CLK_100M_DB2000QL_NIC6_R_DP")
	)
	(segment
		(start 389.904224 -137.927842)
		(end 392.435842 -137.927842)
		(width 0.1651)
		(layer "In15.Cu")
		(net "CLK_100M_DB2000QL_NIC6_R_DP")
	)
	(segment
		(start 386.051806 -146.08048)
		(end 386.051806 -141.78026)
		(width 0.1651)
		(layer "In15.Cu")
		(net "CLK_100M_DB2000QL_NIC6_R_DP")
	)
	(segment
		(start 179.598066 -171.259754)
		(end 180.30444 -170.55338)
		(width 0.1651)
		(layer "In15.Cu")
		(net "CLK_100M_DB2000QL_NIC6_R_DP")
	)
	(segment
		(start 340.415372 -157.064202)
		(end 341.164926 -156.314648)
		(width 0.1651)
		(layer "In15.Cu")
		(net "CLK_100M_DB2000QL_NIC6_R_DP")
	)
	(segment
		(start 261.67588 -79.642716)
		(end 261.67588 -80.360012)
		(width 0.0889)
		(layer "F.Cu")
		(net "P3V3_CLK_GEN_VDD_CK440")
	)
	(segment
		(start 264.603484 -81.562956)
		(end 264.612882 -81.562956)
		(width 0.2032)
		(layer "F.Cu")
		(net "P3V3_CLK_GEN_VDD_CK440")
	)
	(segment
		(start 264.02157 -81.804002)
		(end 264.603484 -81.562956)
		(width 0.2032)
		(layer "F.Cu")
		(net "P3V3_CLK_GEN_VDD_CK440")
	)
	(segment
		(start 262.82142 -81.804002)
		(end 264.02157 -81.804002)
		(width 0.0889)
		(layer "F.Cu")
		(net "P3V3_CLK_GEN_VDD_CK440")
	)
	(segment
		(start 262.81888 -81.801462)
		(end 262.82142 -81.804002)
		(width 0.0889)
		(layer "F.Cu")
		(net "P3V3_CLK_GEN_VDD_CK440")
	)
	(via
		(at 264.612882 -81.562956)
		(size 0.508)
		(drill 0.254)
		(layers "F.Cu" "B.Cu")
		(net "P3V3_CLK_GEN_VDD_CK440")
	)
	(via
		(at 261.67588 -79.642716)
		(size 0.508)
		(drill 0.254)
		(layers "F.Cu" "B.Cu")
		(net "P3V3_CLK_GEN_VDD_CK440")
	)
	(via
		(at 388.949946 -298.74972)
		(size 0.4064)
		(drill 0.2032)
		(layers "F.Cu" "B.Cu")
		(net "CLK_100M_DB800ZL_PEX3_S0_R_DP")
	)
	(segment
		(start 384.10896 -301.284894)
		(end 384.10896 -301.286418)
		(width 0.0889)
		(layer "B.Cu")
		(net "CLK_100M_DB800ZL_PEX3_S0_R_DP")
	)
	(segment
		(start 105.5878 -338.125308)
		(end 105.265474 -337.802982)
		(width 0.1143)
		(layer "B.Cu")
		(net "CLK_100M_DB800ZL_PEX3_S0_R_DP")
	)
	(segment
		(start 352.1202 -328.4855)
		(end 349.5802 -331.0255)
		(width 0.1143)
		(layer "B.Cu")
		(net "CLK_100M_DB800ZL_PEX3_S0_R_DP")
	)
	(segment
		(start 372.837456 -322.38696)
		(end 368.897916 -326.3265)
		(width 0.1143)
		(layer "B.Cu")
		(net "CLK_100M_DB800ZL_PEX3_S0_R_DP")
	)
	(segment
		(start 225.231198 -335.736438)
		(end 221.59849 -332.10373)
		(width 0.1143)
		(layer "B.Cu")
		(net "CLK_100M_DB800ZL_PEX3_S0_R_DP")
	)
	(segment
		(start 374.976136 -308.506876)
		(end 374.976136 -313.313064)
		(width 0.1143)
		(layer "B.Cu")
		(net "CLK_100M_DB800ZL_PEX3_S0_R_DP")
	)
	(segment
		(start 388.282688 -301.215044)
		(end 384.189732 -301.215044)
		(width 0.0889)
		(layer "B.Cu")
		(net "CLK_100M_DB800ZL_PEX3_S0_R_DP")
	)
	(segment
		(start 121.18848 -332.109064)
		(end 113.356644 -339.9409)
		(width 0.1143)
		(layer "B.Cu")
		(net "CLK_100M_DB800ZL_PEX3_S0_R_DP")
	)
	(segment
		(start 368.897916 -326.3265)
		(end 361.213654 -326.3265)
		(width 0.1143)
		(layer "B.Cu")
		(net "CLK_100M_DB800ZL_PEX3_S0_R_DP")
	)
	(segment
		(start 105.5878 -338.713826)
		(end 105.5878 -338.125308)
		(width 0.1143)
		(layer "B.Cu")
		(net "CLK_100M_DB800ZL_PEX3_S0_R_DP")
	)
	(segment
		(start 388.576566 -300.921166)
		(end 388.282688 -301.215044)
		(width 0.0889)
		(layer "B.Cu")
		(net "CLK_100M_DB800ZL_PEX3_S0_R_DP")
	)
	(segment
		(start 106.814874 -339.9409)
		(end 105.5878 -338.713826)
		(width 0.1143)
		(layer "B.Cu")
		(net "CLK_100M_DB800ZL_PEX3_S0_R_DP")
	)
	(segment
		(start 349.5802 -331.0255)
		(end 252.64364 -331.0255)
		(width 0.1143)
		(layer "B.Cu")
		(net "CLK_100M_DB800ZL_PEX3_S0_R_DP")
	)
	(segment
		(start 236.909864 -330.2889)
		(end 231.462326 -335.736438)
		(width 0.1143)
		(layer "B.Cu")
		(net "CLK_100M_DB800ZL_PEX3_S0_R_DP")
	)
	(segment
		(start 252.64364 -331.0255)
		(end 251.90704 -330.2889)
		(width 0.1143)
		(layer "B.Cu")
		(net "CLK_100M_DB800ZL_PEX3_S0_R_DP")
	)
	(segment
		(start 384.119882 -301.284894)
		(end 384.10896 -301.284894)
		(width 0.0889)
		(layer "B.Cu")
		(net "CLK_100M_DB800ZL_PEX3_S0_R_DP")
	)
	(segment
		(start 384.10896 -301.286418)
		(end 384.120136 -301.297594)
		(width 0.0889)
		(layer "B.Cu")
		(net "CLK_100M_DB800ZL_PEX3_S0_R_DP")
	)
	(segment
		(start 356.510844 -328.4855)
		(end 352.1202 -328.4855)
		(width 0.1143)
		(layer "B.Cu")
		(net "CLK_100M_DB800ZL_PEX3_S0_R_DP")
	)
	(segment
		(start 251.90704 -330.2889)
		(end 236.909864 -330.2889)
		(width 0.1143)
		(layer "B.Cu")
		(net "CLK_100M_DB800ZL_PEX3_S0_R_DP")
	)
	(segment
		(start 374.976136 -313.313064)
		(end 372.837456 -315.451744)
		(width 0.1143)
		(layer "B.Cu")
		(net "CLK_100M_DB800ZL_PEX3_S0_R_DP")
	)
	(segment
		(start 121.18848 -332.10373)
		(end 121.18848 -332.109064)
		(width 0.1143)
		(layer "B.Cu")
		(net "CLK_100M_DB800ZL_PEX3_S0_R_DP")
	)
	(segment
		(start 388.665466 -298.74972)
		(end 388.576566 -298.83862)
		(width 0.0889)
		(layer "B.Cu")
		(net "CLK_100M_DB800ZL_PEX3_S0_R_DP")
	)
	(segment
		(start 388.576566 -298.83862)
		(end 388.576566 -300.921166)
		(width 0.0889)
		(layer "B.Cu")
		(net "CLK_100M_DB800ZL_PEX3_S0_R_DP")
	)
	(segment
		(start 231.462326 -335.736438)
		(end 225.231198 -335.736438)
		(width 0.1143)
		(layer "B.Cu")
		(net "CLK_100M_DB800ZL_PEX3_S0_R_DP")
	)
	(segment
		(start 382.185418 -301.297594)
		(end 374.976136 -308.506876)
		(width 0.1143)
		(layer "B.Cu")
		(net "CLK_100M_DB800ZL_PEX3_S0_R_DP")
	)
	(segment
		(start 384.189732 -301.215044)
		(end 384.119882 -301.284894)
		(width 0.0889)
		(layer "B.Cu")
		(net "CLK_100M_DB800ZL_PEX3_S0_R_DP")
	)
	(segment
		(start 372.837456 -315.451744)
		(end 372.837456 -322.38696)
		(width 0.1143)
		(layer "B.Cu")
		(net "CLK_100M_DB800ZL_PEX3_S0_R_DP")
	)
	(segment
		(start 113.356644 -339.9409)
		(end 106.814874 -339.9409)
		(width 0.1143)
		(layer "B.Cu")
		(net "CLK_100M_DB800ZL_PEX3_S0_R_DP")
	)
	(segment
		(start 361.213654 -326.3265)
		(end 359.803954 -327.7362)
		(width 0.1143)
		(layer "B.Cu")
		(net "CLK_100M_DB800ZL_PEX3_S0_R_DP")
	)
	(segment
		(start 388.949946 -298.74972)
		(end 388.665466 -298.74972)
		(width 0.0889)
		(layer "B.Cu")
		(net "CLK_100M_DB800ZL_PEX3_S0_R_DP")
	)
	(segment
		(start 221.59849 -332.10373)
		(end 121.18848 -332.10373)
		(width 0.1143)
		(layer "B.Cu")
		(net "CLK_100M_DB800ZL_PEX3_S0_R_DP")
	)
	(segment
		(start 384.097784 -301.297594)
		(end 382.185418 -301.297594)
		(width 0.1143)
		(layer "B.Cu")
		(net "CLK_100M_DB800ZL_PEX3_S0_R_DP")
	)
	(segment
		(start 359.803954 -327.7362)
		(end 357.260144 -327.7362)
		(width 0.1143)
		(layer "B.Cu")
		(net "CLK_100M_DB800ZL_PEX3_S0_R_DP")
	)
	(segment
		(start 384.120136 -301.297594)
		(end 384.097784 -301.297594)
		(width 0.0889)
		(layer "B.Cu")
		(net "CLK_100M_DB800ZL_PEX3_S0_R_DP")
	)
	(segment
		(start 357.260144 -327.7362)
		(end 356.510844 -328.4855)
		(width 0.1143)
		(layer "B.Cu")
		(net "CLK_100M_DB800ZL_PEX3_S0_R_DP")
	)
	(segment
		(start 446.875662 -120.493028)
		(end 446.875662 -119.477028)
		(width 0.13208)
		(layer "F.Cu")
		(net "PWRGD_P3V3_NIC7")
	)
	(segment
		(start 446.251076 -119.569992)
		(end 446.34404 -119.477028)
		(width 0.13208)
		(layer "F.Cu")
		(net "PWRGD_P3V3_NIC7")
	)
	(segment
		(start 446.34404 -119.477028)
		(end 446.875662 -119.477028)
		(width 0.13208)
		(layer "F.Cu")
		(net "PWRGD_P3V3_NIC7")
	)
	(segment
		(start 445.0715 -120.541796)
		(end 445.60236 -120.541796)
		(width 0.13208)
		(layer "F.Cu")
		(net "PWRGD_P3V3_NIC7")
	)
	(segment
		(start 445.60236 -120.541796)
		(end 446.251076 -119.89308)
		(width 0.13208)
		(layer "F.Cu")
		(net "PWRGD_P3V3_NIC7")
	)
	(segment
		(start 446.251076 -119.89308)
		(end 446.251076 -119.569992)
		(width 0.13208)
		(layer "F.Cu")
		(net "PWRGD_P3V3_NIC7")
	)
	(via
		(at 446.251076 -119.89308)
		(size 0.508)
		(drill 0.254)
		(layers "F.Cu" "B.Cu")
		(net "PWRGD_P3V3_NIC7")
	)
	(segment
		(start 245.598696 -96.13646)
		(end 240.635028 -101.100128)
		(width 0.13208)
		(layer "F.Cu")
		(net "PEX_USB2_SEL")
	)
	(segment
		(start 232.915968 -78.55331)
		(end 233.104436 -78.364842)
		(width 0.13208)
		(layer "F.Cu")
		(net "PEX_USB2_SEL")
	)
	(segment
		(start 233.333036 -77.825854)
		(end 233.993436 -77.825854)
		(width 0.13208)
		(layer "F.Cu")
		(net "PEX_USB2_SEL")
	)
	(segment
		(start 233.104436 -78.364842)
		(end 233.104436 -78.054454)
		(width 0.13208)
		(layer "F.Cu")
		(net "PEX_USB2_SEL")
	)
	(segment
		(start 245.598696 -83.20151)
		(end 245.598696 -96.13646)
		(width 0.13208)
		(layer "F.Cu")
		(net "PEX_USB2_SEL")
	)
	(segment
		(start 233.104436 -78.054454)
		(end 233.333036 -77.825854)
		(width 0.13208)
		(layer "F.Cu")
		(net "PEX_USB2_SEL")
	)
	(segment
		(start 232.64622 -78.99019)
		(end 232.915968 -78.99019)
		(width 0.13208)
		(layer "F.Cu")
		(net "PEX_USB2_SEL")
	)
	(segment
		(start 232.05821 -79.5782)
		(end 232.64622 -78.99019)
		(width 0.13208)
		(layer "F.Cu")
		(net "PEX_USB2_SEL")
	)
	(segment
		(start 240.635028 -101.100128)
		(end 240.635028 -125.083824)
		(width 0.13208)
		(layer "F.Cu")
		(net "PEX_USB2_SEL")
	)
	(segment
		(start 237.835186 -78.034134)
		(end 238.142018 -77.727302)
		(width 0.13208)
		(layer "F.Cu")
		(net "PEX_USB2_SEL")
	)
	(segment
		(start 231.264968 -79.405734)
		(end 231.483408 -79.405734)
		(width 0.13208)
		(layer "F.Cu")
		(net "PEX_USB2_SEL")
	)
	(segment
		(start 237.085886 -128.632966)
		(end 232.612946 -128.632966)
		(width 0.13208)
		(layer "F.Cu")
		(net "PEX_USB2_SEL")
	)
	(segment
		(start 234.201716 -78.034134)
		(end 237.835186 -78.034134)
		(width 0.13208)
		(layer "F.Cu")
		(net "PEX_USB2_SEL")
	)
	(segment
		(start 238.142018 -77.727302)
		(end 240.124488 -77.727302)
		(width 0.13208)
		(layer "F.Cu")
		(net "PEX_USB2_SEL")
	)
	(segment
		(start 233.993436 -77.825854)
		(end 234.201716 -78.034134)
		(width 0.13208)
		(layer "F.Cu")
		(net "PEX_USB2_SEL")
	)
	(segment
		(start 232.915968 -78.99019)
		(end 232.915968 -78.55331)
		(width 0.13208)
		(layer "F.Cu")
		(net "PEX_USB2_SEL")
	)
	(segment
		(start 240.124488 -77.727302)
		(end 245.598696 -83.20151)
		(width 0.13208)
		(layer "F.Cu")
		(net "PEX_USB2_SEL")
	)
	(segment
		(start 240.635028 -125.083824)
		(end 237.085886 -128.632966)
		(width 0.13208)
		(layer "F.Cu")
		(net "PEX_USB2_SEL")
	)
	(segment
		(start 231.483408 -79.405734)
		(end 231.655874 -79.5782)
		(width 0.13208)
		(layer "F.Cu")
		(net "PEX_USB2_SEL")
	)
	(segment
		(start 231.655874 -79.5782)
		(end 232.05821 -79.5782)
		(width 0.13208)
		(layer "F.Cu")
		(net "PEX_USB2_SEL")
	)
	(via
		(at 238.142018 -77.727302)
		(size 0.762)
		(drill 0.381)
		(layers "F.Cu" "B.Cu")
		(net "PEX_USB2_SEL")
	)
	(via
		(at 254.781304 -84.453984)
		(size 0.508)
		(drill 0.254)
		(layers "F.Cu" "B.Cu")
		(net "P3V3_CLK_GEN_VDDPT_CK440")
	)
	(via
		(at 253.252986 -88.524588)
		(size 0.6604)
		(drill 0.3302)
		(layers "F.Cu" "B.Cu")
		(net "P3V3_CLK_GEN_VDDPT_CK440")
	)
	(segment
		(start 253.252986 -88.524588)
		(end 254.71628 -87.061294)
		(width 0.13208)
		(layer "B.Cu")
		(net "P3V3_CLK_GEN_VDDPT_CK440")
	)
	(segment
		(start 254.838962 -84.453984)
		(end 254.98933 -84.604352)
		(width 0.381)
		(layer "B.Cu")
		(net "P3V3_CLK_GEN_VDDPT_CK440")
	)
	(segment
		(start 254.71628 -87.061294)
		(end 254.71628 -86.856316)
		(width 0.13208)
		(layer "B.Cu")
		(net "P3V3_CLK_GEN_VDDPT_CK440")
	)
	(segment
		(start 254.98933 -84.604352)
		(end 255.951482 -84.604352)
		(width 0.381)
		(layer "B.Cu")
		(net "P3V3_CLK_GEN_VDDPT_CK440")
	)
	(segment
		(start 254.781304 -84.453984)
		(end 254.838962 -84.453984)
		(width 0.381)
		(layer "B.Cu")
		(net "P3V3_CLK_GEN_VDDPT_CK440")
	)
	(segment
		(start 99.986084 -120.493028)
		(end 99.375722 -120.493028)
		(width 0.13208)
		(layer "F.Cu")
		(net "PWRGD_P3V3_NIC1_R")
	)
	(segment
		(start 100.3808 -119.792496)
		(end 100.3808 -120.098312)
		(width 0.13208)
		(layer "F.Cu")
		(net "PWRGD_P3V3_NIC1_R")
	)
	(segment
		(start 100.565204 -119.347742)
		(end 100.3808 -119.792496)
		(width 0.13208)
		(layer "F.Cu")
		(net "PWRGD_P3V3_NIC1_R")
	)
	(segment
		(start 100.3808 -120.098312)
		(end 99.986084 -120.493028)
		(width 0.13208)
		(layer "F.Cu")
		(net "PWRGD_P3V3_NIC1_R")
	)
	(segment
		(start 348.493842 -224.786952)
		(end 348.893638 -225.186748)
		(width 0.13208)
		(layer "F.Cu")
		(net "PWRGD_P3V3_NIC1_R")
	)
	(segment
		(start 101.152706 -118.76024)
		(end 100.565204 -119.347742)
		(width 0.13208)
		(layer "F.Cu")
		(net "PWRGD_P3V3_NIC1_R")
	)
	(segment
		(start 101.530404 -118.76024)
		(end 101.152706 -118.76024)
		(width 0.13208)
		(layer "F.Cu")
		(net "PWRGD_P3V3_NIC1_R")
	)
	(via
		(at 118.234968 -218.94038)
		(size 0.508)
		(drill 0.254)
		(layers "F.Cu" "B.Cu")
		(net "PWRGD_P3V3_NIC1_R")
	)
	(via
		(at 99.986084 -120.493028)
		(size 0.508)
		(drill 0.254)
		(layers "F.Cu" "B.Cu")
		(net "PWRGD_P3V3_NIC1_R")
	)
	(via
		(at 348.893638 -225.186748)
		(size 0.4572)
		(drill 0.254)
		(layers "F.Cu" "B.Cu")
		(net "PWRGD_P3V3_NIC1_R")
	)
	(segment
		(start 98.817684 -123.485148)
		(end 92.71 -129.592832)
		(width 0.15494)
		(layer "In5.Cu")
		(net "PWRGD_P3V3_NIC1_R")
	)
	(segment
		(start 108.458 -199.517)
		(end 109.1184 -200.1774)
		(width 0.15494)
		(layer "In5.Cu")
		(net "PWRGD_P3V3_NIC1_R")
	)
	(segment
		(start 99.986084 -120.493028)
		(end 98.817684 -121.661428)
		(width 0.15494)
		(layer "In5.Cu")
		(net "PWRGD_P3V3_NIC1_R")
	)
	(segment
		(start 96.06788 -176.96688)
		(end 97.561908 -178.460908)
		(width 0.15494)
		(layer "In5.Cu")
		(net "PWRGD_P3V3_NIC1_R")
	)
	(segment
		(start 109.855 -200.1774)
		(end 117.712998 -208.035398)
		(width 0.15494)
		(layer "In5.Cu")
		(net "PWRGD_P3V3_NIC1_R")
	)
	(segment
		(start 92.71 -133.543548)
		(end 96.06788 -141.650212)
		(width 0.15494)
		(layer "In5.Cu")
		(net "PWRGD_P3V3_NIC1_R")
	)
	(segment
		(start 117.712998 -208.035398)
		(end 117.712998 -214.182198)
		(width 0.15494)
		(layer "In5.Cu")
		(net "PWRGD_P3V3_NIC1_R")
	)
	(segment
		(start 102.25151 -190.761874)
		(end 105.809034 -190.761874)
		(width 0.15494)
		(layer "In5.Cu")
		(net "PWRGD_P3V3_NIC1_R")
	)
	(segment
		(start 92.71 -129.592832)
		(end 92.71 -133.543548)
		(width 0.15494)
		(layer "In5.Cu")
		(net "PWRGD_P3V3_NIC1_R")
	)
	(segment
		(start 101.473 -189.983364)
		(end 102.25151 -190.761874)
		(width 0.15494)
		(layer "In5.Cu")
		(net "PWRGD_P3V3_NIC1_R")
	)
	(segment
		(start 117.712998 -214.182198)
		(end 118.234968 -214.704168)
		(width 0.15494)
		(layer "In5.Cu")
		(net "PWRGD_P3V3_NIC1_R")
	)
	(segment
		(start 97.561908 -178.460908)
		(end 97.561908 -182.093362)
		(width 0.15494)
		(layer "In5.Cu")
		(net "PWRGD_P3V3_NIC1_R")
	)
	(segment
		(start 118.234968 -214.704168)
		(end 118.234968 -218.94038)
		(width 0.15494)
		(layer "In5.Cu")
		(net "PWRGD_P3V3_NIC1_R")
	)
	(segment
		(start 98.817684 -121.661428)
		(end 98.817684 -123.485148)
		(width 0.15494)
		(layer "In5.Cu")
		(net "PWRGD_P3V3_NIC1_R")
	)
	(segment
		(start 101.473 -186.004454)
		(end 101.473 -189.983364)
		(width 0.15494)
		(layer "In5.Cu")
		(net "PWRGD_P3V3_NIC1_R")
	)
	(segment
		(start 96.06788 -141.650212)
		(end 96.06788 -176.96688)
		(width 0.15494)
		(layer "In5.Cu")
		(net "PWRGD_P3V3_NIC1_R")
	)
	(segment
		(start 109.1184 -200.1774)
		(end 109.855 -200.1774)
		(width 0.15494)
		(layer "In5.Cu")
		(net "PWRGD_P3V3_NIC1_R")
	)
	(segment
		(start 108.458 -193.41084)
		(end 108.458 -199.517)
		(width 0.15494)
		(layer "In5.Cu")
		(net "PWRGD_P3V3_NIC1_R")
	)
	(segment
		(start 105.809034 -190.761874)
		(end 108.458 -193.41084)
		(width 0.15494)
		(layer "In5.Cu")
		(net "PWRGD_P3V3_NIC1_R")
	)
	(segment
		(start 97.561908 -182.093362)
		(end 101.473 -186.004454)
		(width 0.15494)
		(layer "In5.Cu")
		(net "PWRGD_P3V3_NIC1_R")
	)
	(segment
		(start 346.2528 -236.8804)
		(end 345.186 -237.9472)
		(width 0.15494)
		(layer "In13.Cu")
		(net "PWRGD_P3V3_NIC1_R")
	)
	(segment
		(start 179.199794 -242.496594)
		(end 171.914566 -235.211366)
		(width 0.15494)
		(layer "In13.Cu")
		(net "PWRGD_P3V3_NIC1_R")
	)
	(segment
		(start 347.345 -236.8804)
		(end 346.2528 -236.8804)
		(width 0.15494)
		(layer "In13.Cu")
		(net "PWRGD_P3V3_NIC1_R")
	)
	(segment
		(start 329.53452 -241.98834)
		(end 329.03414 -242.48872)
		(width 0.15494)
		(layer "In13.Cu")
		(net "PWRGD_P3V3_NIC1_R")
	)
	(segment
		(start 239.649 -238.9124)
		(end 230.124 -238.9124)
		(width 0.15494)
		(layer "In13.Cu")
		(net "PWRGD_P3V3_NIC1_R")
	)
	(segment
		(start 329.03414 -242.48872)
		(end 306.601114 -242.48872)
		(width 0.15494)
		(layer "In13.Cu")
		(net "PWRGD_P3V3_NIC1_R")
	)
	(segment
		(start 345.186 -237.9472)
		(end 344.41257 -237.9472)
		(width 0.15494)
		(layer "In13.Cu")
		(net "PWRGD_P3V3_NIC1_R")
	)
	(segment
		(start 121.135394 -221.840806)
		(end 118.234968 -218.94038)
		(width 0.15494)
		(layer "In13.Cu")
		(net "PWRGD_P3V3_NIC1_R")
	)
	(segment
		(start 349.291402 -225.584512)
		(end 349.291402 -227.3808)
		(width 0.0889)
		(layer "In13.Cu")
		(net "PWRGD_P3V3_NIC1_R")
	)
	(segment
		(start 276.465538 -242.046252)
		(end 274.578064 -240.158778)
		(width 0.15494)
		(layer "In13.Cu")
		(net "PWRGD_P3V3_NIC1_R")
	)
	(segment
		(start 205.718156 -242.496594)
		(end 179.199794 -242.496594)
		(width 0.15494)
		(layer "In13.Cu")
		(net "PWRGD_P3V3_NIC1_R")
	)
	(segment
		(start 349.02013 -233.07167)
		(end 347.599 -234.4928)
		(width 0.15494)
		(layer "In13.Cu")
		(net "PWRGD_P3V3_NIC1_R")
	)
	(segment
		(start 349.291402 -227.3808)
		(end 349.291402 -228.558598)
		(width 0.15494)
		(layer "In13.Cu")
		(net "PWRGD_P3V3_NIC1_R")
	)
	(segment
		(start 340.37143 -241.98834)
		(end 329.53452 -241.98834)
		(width 0.15494)
		(layer "In13.Cu")
		(net "PWRGD_P3V3_NIC1_R")
	)
	(segment
		(start 215.115648 -239.56137)
		(end 214.619078 -240.05794)
		(width 0.15494)
		(layer "In13.Cu")
		(net "PWRGD_P3V3_NIC1_R")
	)
	(segment
		(start 348.893638 -225.186748)
		(end 349.291402 -225.584512)
		(width 0.0889)
		(layer "In13.Cu")
		(net "PWRGD_P3V3_NIC1_R")
	)
	(segment
		(start 306.158646 -242.046252)
		(end 276.465538 -242.046252)
		(width 0.15494)
		(layer "In13.Cu")
		(net "PWRGD_P3V3_NIC1_R")
	)
	(segment
		(start 344.41257 -237.9472)
		(end 340.37143 -241.98834)
		(width 0.15494)
		(layer "In13.Cu")
		(net "PWRGD_P3V3_NIC1_R")
	)
	(segment
		(start 347.599 -234.4928)
		(end 347.599 -236.6264)
		(width 0.15494)
		(layer "In13.Cu")
		(net "PWRGD_P3V3_NIC1_R")
	)
	(segment
		(start 132.46862 -235.211366)
		(end 121.135394 -223.87814)
		(width 0.15494)
		(layer "In13.Cu")
		(net "PWRGD_P3V3_NIC1_R")
	)
	(segment
		(start 230.124 -238.9124)
		(end 229.47503 -239.56137)
		(width 0.15494)
		(layer "In13.Cu")
		(net "PWRGD_P3V3_NIC1_R")
	)
	(segment
		(start 121.135394 -223.87814)
		(end 121.135394 -221.840806)
		(width 0.15494)
		(layer "In13.Cu")
		(net "PWRGD_P3V3_NIC1_R")
	)
	(segment
		(start 229.47503 -239.56137)
		(end 215.115648 -239.56137)
		(width 0.15494)
		(layer "In13.Cu")
		(net "PWRGD_P3V3_NIC1_R")
	)
	(segment
		(start 274.578064 -240.158778)
		(end 240.895378 -240.158778)
		(width 0.15494)
		(layer "In13.Cu")
		(net "PWRGD_P3V3_NIC1_R")
	)
	(segment
		(start 347.599 -236.6264)
		(end 347.345 -236.8804)
		(width 0.15494)
		(layer "In13.Cu")
		(net "PWRGD_P3V3_NIC1_R")
	)
	(segment
		(start 214.619078 -240.05794)
		(end 208.15681 -240.05794)
		(width 0.15494)
		(layer "In13.Cu")
		(net "PWRGD_P3V3_NIC1_R")
	)
	(segment
		(start 208.15681 -240.05794)
		(end 205.718156 -242.496594)
		(width 0.15494)
		(layer "In13.Cu")
		(net "PWRGD_P3V3_NIC1_R")
	)
	(segment
		(start 349.02013 -228.82987)
		(end 349.02013 -233.07167)
		(width 0.15494)
		(layer "In13.Cu")
		(net "PWRGD_P3V3_NIC1_R")
	)
	(segment
		(start 349.291402 -228.558598)
		(end 349.02013 -228.82987)
		(width 0.15494)
		(layer "In13.Cu")
		(net "PWRGD_P3V3_NIC1_R")
	)
	(segment
		(start 306.601114 -242.48872)
		(end 306.158646 -242.046252)
		(width 0.15494)
		(layer "In13.Cu")
		(net "PWRGD_P3V3_NIC1_R")
	)
	(segment
		(start 171.914566 -235.211366)
		(end 132.46862 -235.211366)
		(width 0.15494)
		(layer "In13.Cu")
		(net "PWRGD_P3V3_NIC1_R")
	)
	(segment
		(start 240.895378 -240.158778)
		(end 239.649 -238.9124)
		(width 0.15494)
		(layer "In13.Cu")
		(net "PWRGD_P3V3_NIC1_R")
	)
	(segment
		(start 127.622808 -127.051308)
		(end 127.22606 -127.051308)
		(width 0.13208)
		(layer "F.Cu")
		(net "P3V3_NIC2_SS")
	)
	(segment
		(start 128.33096 -126.394718)
		(end 128.279398 -126.394718)
		(width 0.13208)
		(layer "F.Cu")
		(net "P3V3_NIC2_SS")
	)
	(segment
		(start 126.666244 -127.051308)
		(end 126.610364 -126.995428)
		(width 0.13208)
		(layer "F.Cu")
		(net "P3V3_NIC2_SS")
	)
	(segment
		(start 128.279398 -126.394718)
		(end 127.622808 -127.051308)
		(width 0.13208)
		(layer "F.Cu")
		(net "P3V3_NIC2_SS")
	)
	(segment
		(start 127.22606 -127.051308)
		(end 126.666244 -127.051308)
		(width 0.13208)
		(layer "F.Cu")
		(net "P3V3_NIC2_SS")
	)
	(via
		(at 127.22606 -127.051308)
		(size 0.508)
		(drill 0.254)
		(layers "F.Cu" "B.Cu")
		(net "P3V3_NIC2_SS")
	)
	(segment
		(start 259.183124 -88.552274)
		(end 259.183124 -89.096088)
		(width 0.11684)
		(layer "F.Cu")
		(net "P3V3_CLK_GEN_VDDMXCK_CK440")
	)
	(via
		(at 253.24308 -87.719916)
		(size 0.508)
		(drill 0.254)
		(layers "F.Cu" "B.Cu")
		(net "P3V3_CLK_GEN_VDDMXCK_CK440")
	)
	(via
		(at 260.57987 -89.88806)
		(size 0.6604)
		(drill 0.3302)
		(layers "F.Cu" "B.Cu")
		(net "P3V3_CLK_GEN_VDDMXCK_CK440")
	)
	(via
		(at 261.939786 -89.008458)
		(size 0.508)
		(drill 0.254)
		(layers "F.Cu" "B.Cu")
		(net "P3V3_CLK_GEN_VDDMXCK_CK440")
	)
	(via
		(at 259.183124 -89.096088)
		(size 0.508)
		(drill 0.254)
		(layers "F.Cu" "B.Cu")
		(net "P3V3_CLK_GEN_VDDMXCK_CK440")
	)
	(via
		(at 264.948924 -86.41842)
		(size 0.508)
		(drill 0.254)
		(layers "F.Cu" "B.Cu")
		(net "P3V3_CLK_GEN_VDDMXCK_CK440")
	)
	(via
		(at 264.908792 -84.758784)
		(size 0.508)
		(drill 0.254)
		(layers "F.Cu" "B.Cu")
		(net "P3V3_CLK_GEN_VDDMXCK_CK440")
	)
	(segment
		(start 253.24308 -86.856316)
		(end 253.24308 -87.719916)
		(width 0.508)
		(layer "B.Cu")
		(net "P3V3_CLK_GEN_VDDMXCK_CK440")
	)
	(via
		(at 387.999986 -298.74972)
		(size 0.4064)
		(drill 0.2032)
		(layers "F.Cu" "B.Cu")
		(net "CLK_100M_DB800ZL_PEX3_S0_R_DN")
	)
	(segment
		(start 372.469156 -322.234306)
		(end 371.041168 -323.662294)
		(width 0.1143)
		(layer "B.Cu")
		(net "CLK_100M_DB800ZL_PEX3_S0_R_DN")
	)
	(segment
		(start 379.690122 -303.07788)
		(end 379.690122 -303.271936)
		(width 0.1143)
		(layer "B.Cu")
		(net "CLK_100M_DB800ZL_PEX3_S0_R_DN")
	)
	(segment
		(start 231.309672 -335.368138)
		(end 225.383852 -335.368138)
		(width 0.1143)
		(layer "B.Cu")
		(net "CLK_100M_DB800ZL_PEX3_S0_R_DN")
	)
	(segment
		(start 381.700532 -301.261526)
		(end 381.506476 -301.261526)
		(width 0.1143)
		(layer "B.Cu")
		(net "CLK_100M_DB800ZL_PEX3_S0_R_DN")
	)
	(segment
		(start 105.9561 -338.561172)
		(end 105.9561 -338.128356)
		(width 0.1143)
		(layer "B.Cu")
		(net "CLK_100M_DB800ZL_PEX3_S0_R_DN")
	)
	(segment
		(start 388.19836 -301.011844)
		(end 384.202432 -301.011844)
		(width 0.0889)
		(layer "B.Cu")
		(net "CLK_100M_DB800ZL_PEX3_S0_R_DN")
	)
	(segment
		(start 388.284466 -298.74972)
		(end 388.373366 -298.83862)
		(width 0.0889)
		(layer "B.Cu")
		(net "CLK_100M_DB800ZL_PEX3_S0_R_DN")
	)
	(segment
		(start 381.220726 -301.741332)
		(end 380.93523 -302.026828)
		(width 0.1143)
		(layer "B.Cu")
		(net "CLK_100M_DB800ZL_PEX3_S0_R_DN")
	)
	(segment
		(start 372.469156 -315.29909)
		(end 372.469156 -322.234306)
		(width 0.1143)
		(layer "B.Cu")
		(net "CLK_100M_DB800ZL_PEX3_S0_R_DN")
	)
	(segment
		(start 378.639324 -304.322734)
		(end 378.445522 -304.322734)
		(width 0.1143)
		(layer "B.Cu")
		(net "CLK_100M_DB800ZL_PEX3_S0_R_DN")
	)
	(segment
		(start 380.455424 -302.506634)
		(end 380.169928 -302.79213)
		(width 0.1143)
		(layer "B.Cu")
		(net "CLK_100M_DB800ZL_PEX3_S0_R_DN")
	)
	(segment
		(start 380.93523 -302.026828)
		(end 380.741428 -302.026828)
		(width 0.1143)
		(layer "B.Cu")
		(net "CLK_100M_DB800ZL_PEX3_S0_R_DN")
	)
	(segment
		(start 380.169928 -302.79213)
		(end 379.976126 -302.79213)
		(width 0.1143)
		(layer "B.Cu")
		(net "CLK_100M_DB800ZL_PEX3_S0_R_DN")
	)
	(segment
		(start 361.061 -325.9582)
		(end 359.6513 -327.3679)
		(width 0.1143)
		(layer "B.Cu")
		(net "CLK_100M_DB800ZL_PEX3_S0_R_DN")
	)
	(segment
		(start 379.404626 -303.557432)
		(end 379.210824 -303.557432)
		(width 0.1143)
		(layer "B.Cu")
		(net "CLK_100M_DB800ZL_PEX3_S0_R_DN")
	)
	(segment
		(start 380.455424 -302.312578)
		(end 380.455424 -302.506634)
		(width 0.1143)
		(layer "B.Cu")
		(net "CLK_100M_DB800ZL_PEX3_S0_R_DN")
	)
	(segment
		(start 384.097784 -300.929294)
		(end 382.032764 -300.929294)
		(width 0.1143)
		(layer "B.Cu")
		(net "CLK_100M_DB800ZL_PEX3_S0_R_DN")
	)
	(segment
		(start 374.607836 -308.354222)
		(end 374.607836 -313.16041)
		(width 0.1143)
		(layer "B.Cu")
		(net "CLK_100M_DB800ZL_PEX3_S0_R_DN")
	)
	(segment
		(start 369.79606 -324.907402)
		(end 369.510564 -325.192898)
		(width 0.1143)
		(layer "B.Cu")
		(net "CLK_100M_DB800ZL_PEX3_S0_R_DN")
	)
	(segment
		(start 387.999986 -298.74972)
		(end 388.284466 -298.74972)
		(width 0.0889)
		(layer "B.Cu")
		(net "CLK_100M_DB800ZL_PEX3_S0_R_DN")
	)
	(segment
		(start 378.445522 -304.322734)
		(end 378.159518 -304.608484)
		(width 0.1143)
		(layer "B.Cu")
		(net "CLK_100M_DB800ZL_PEX3_S0_R_DN")
	)
	(segment
		(start 106.967528 -339.5726)
		(end 105.9561 -338.561172)
		(width 0.1143)
		(layer "B.Cu")
		(net "CLK_100M_DB800ZL_PEX3_S0_R_DN")
	)
	(segment
		(start 384.119882 -300.929294)
		(end 384.097784 -300.929294)
		(width 0.0889)
		(layer "B.Cu")
		(net "CLK_100M_DB800ZL_PEX3_S0_R_DN")
	)
	(segment
		(start 369.510564 -325.192898)
		(end 369.316508 -325.192898)
		(width 0.1143)
		(layer "B.Cu")
		(net "CLK_100M_DB800ZL_PEX3_S0_R_DN")
	)
	(segment
		(start 374.607836 -313.16041)
		(end 372.469156 -315.29909)
		(width 0.1143)
		(layer "B.Cu")
		(net "CLK_100M_DB800ZL_PEX3_S0_R_DN")
	)
	(segment
		(start 252.059694 -329.9206)
		(end 236.75721 -329.9206)
		(width 0.1143)
		(layer "B.Cu")
		(net "CLK_100M_DB800ZL_PEX3_S0_R_DN")
	)
	(segment
		(start 378.92482 -304.037238)
		(end 378.639324 -304.322734)
		(width 0.1143)
		(layer "B.Cu")
		(net "CLK_100M_DB800ZL_PEX3_S0_R_DN")
	)
	(segment
		(start 356.35819 -328.1172)
		(end 351.967546 -328.1172)
		(width 0.1143)
		(layer "B.Cu")
		(net "CLK_100M_DB800ZL_PEX3_S0_R_DN")
	)
	(segment
		(start 378.92482 -303.843182)
		(end 378.92482 -304.037238)
		(width 0.1143)
		(layer "B.Cu")
		(net "CLK_100M_DB800ZL_PEX3_S0_R_DN")
	)
	(segment
		(start 379.690122 -303.271936)
		(end 379.404626 -303.557432)
		(width 0.1143)
		(layer "B.Cu")
		(net "CLK_100M_DB800ZL_PEX3_S0_R_DN")
	)
	(segment
		(start 378.159518 -304.608484)
		(end 378.159518 -304.80254)
		(width 0.1143)
		(layer "B.Cu")
		(net "CLK_100M_DB800ZL_PEX3_S0_R_DN")
	)
	(segment
		(start 368.745262 -325.9582)
		(end 361.061 -325.9582)
		(width 0.1143)
		(layer "B.Cu")
		(net "CLK_100M_DB800ZL_PEX3_S0_R_DN")
	)
	(segment
		(start 380.741428 -302.026828)
		(end 380.455424 -302.312578)
		(width 0.1143)
		(layer "B.Cu")
		(net "CLK_100M_DB800ZL_PEX3_S0_R_DN")
	)
	(segment
		(start 369.79606 -324.7136)
		(end 369.79606 -324.907402)
		(width 0.1143)
		(layer "B.Cu")
		(net "CLK_100M_DB800ZL_PEX3_S0_R_DN")
	)
	(segment
		(start 370.08181 -324.427596)
		(end 369.79606 -324.7136)
		(width 0.1143)
		(layer "B.Cu")
		(net "CLK_100M_DB800ZL_PEX3_S0_R_DN")
	)
	(segment
		(start 388.373366 -300.836838)
		(end 388.19836 -301.011844)
		(width 0.0889)
		(layer "B.Cu")
		(net "CLK_100M_DB800ZL_PEX3_S0_R_DN")
	)
	(segment
		(start 105.9561 -338.128356)
		(end 106.281474 -337.802982)
		(width 0.1143)
		(layer "B.Cu")
		(net "CLK_100M_DB800ZL_PEX3_S0_R_DN")
	)
	(segment
		(start 369.030758 -325.478902)
		(end 369.030758 -325.672704)
		(width 0.1143)
		(layer "B.Cu")
		(net "CLK_100M_DB800ZL_PEX3_S0_R_DN")
	)
	(segment
		(start 121.04116 -331.73543)
		(end 113.20399 -339.5726)
		(width 0.1143)
		(layer "B.Cu")
		(net "CLK_100M_DB800ZL_PEX3_S0_R_DN")
	)
	(segment
		(start 349.427546 -330.6572)
		(end 252.796294 -330.6572)
		(width 0.1143)
		(layer "B.Cu")
		(net "CLK_100M_DB800ZL_PEX3_S0_R_DN")
	)
	(segment
		(start 378.159518 -304.80254)
		(end 374.607836 -308.354222)
		(width 0.1143)
		(layer "B.Cu")
		(net "CLK_100M_DB800ZL_PEX3_S0_R_DN")
	)
	(segment
		(start 370.561362 -324.1421)
		(end 370.275866 -324.427596)
		(width 0.1143)
		(layer "B.Cu")
		(net "CLK_100M_DB800ZL_PEX3_S0_R_DN")
	)
	(segment
		(start 369.030758 -325.672704)
		(end 368.745262 -325.9582)
		(width 0.1143)
		(layer "B.Cu")
		(net "CLK_100M_DB800ZL_PEX3_S0_R_DN")
	)
	(segment
		(start 221.751144 -331.73543)
		(end 121.04116 -331.73543)
		(width 0.1143)
		(layer "B.Cu")
		(net "CLK_100M_DB800ZL_PEX3_S0_R_DN")
	)
	(segment
		(start 351.967546 -328.1172)
		(end 349.427546 -330.6572)
		(width 0.1143)
		(layer "B.Cu")
		(net "CLK_100M_DB800ZL_PEX3_S0_R_DN")
	)
	(segment
		(start 381.220726 -301.547276)
		(end 381.220726 -301.741332)
		(width 0.1143)
		(layer "B.Cu")
		(net "CLK_100M_DB800ZL_PEX3_S0_R_DN")
	)
	(segment
		(start 369.316508 -325.192898)
		(end 369.030758 -325.478902)
		(width 0.1143)
		(layer "B.Cu")
		(net "CLK_100M_DB800ZL_PEX3_S0_R_DN")
	)
	(segment
		(start 370.847112 -323.662294)
		(end 370.561362 -323.948298)
		(width 0.1143)
		(layer "B.Cu")
		(net "CLK_100M_DB800ZL_PEX3_S0_R_DN")
	)
	(segment
		(start 359.6513 -327.3679)
		(end 357.10749 -327.3679)
		(width 0.1143)
		(layer "B.Cu")
		(net "CLK_100M_DB800ZL_PEX3_S0_R_DN")
	)
	(segment
		(start 379.976126 -302.79213)
		(end 379.690122 -303.07788)
		(width 0.1143)
		(layer "B.Cu")
		(net "CLK_100M_DB800ZL_PEX3_S0_R_DN")
	)
	(segment
		(start 370.275866 -324.427596)
		(end 370.08181 -324.427596)
		(width 0.1143)
		(layer "B.Cu")
		(net "CLK_100M_DB800ZL_PEX3_S0_R_DN")
	)
	(segment
		(start 379.210824 -303.557432)
		(end 378.92482 -303.843182)
		(width 0.1143)
		(layer "B.Cu")
		(net "CLK_100M_DB800ZL_PEX3_S0_R_DN")
	)
	(segment
		(start 371.041168 -323.662294)
		(end 370.847112 -323.662294)
		(width 0.1143)
		(layer "B.Cu")
		(net "CLK_100M_DB800ZL_PEX3_S0_R_DN")
	)
	(segment
		(start 381.506476 -301.261526)
		(end 381.220726 -301.547276)
		(width 0.1143)
		(layer "B.Cu")
		(net "CLK_100M_DB800ZL_PEX3_S0_R_DN")
	)
	(segment
		(start 357.10749 -327.3679)
		(end 356.35819 -328.1172)
		(width 0.1143)
		(layer "B.Cu")
		(net "CLK_100M_DB800ZL_PEX3_S0_R_DN")
	)
	(segment
		(start 113.20399 -339.5726)
		(end 106.967528 -339.5726)
		(width 0.1143)
		(layer "B.Cu")
		(net "CLK_100M_DB800ZL_PEX3_S0_R_DN")
	)
	(segment
		(start 225.383852 -335.368138)
		(end 221.751144 -331.73543)
		(width 0.1143)
		(layer "B.Cu")
		(net "CLK_100M_DB800ZL_PEX3_S0_R_DN")
	)
	(segment
		(start 252.796294 -330.6572)
		(end 252.059694 -329.9206)
		(width 0.1143)
		(layer "B.Cu")
		(net "CLK_100M_DB800ZL_PEX3_S0_R_DN")
	)
	(segment
		(start 370.561362 -323.948298)
		(end 370.561362 -324.1421)
		(width 0.1143)
		(layer "B.Cu")
		(net "CLK_100M_DB800ZL_PEX3_S0_R_DN")
	)
	(segment
		(start 236.75721 -329.9206)
		(end 231.309672 -335.368138)
		(width 0.1143)
		(layer "B.Cu")
		(net "CLK_100M_DB800ZL_PEX3_S0_R_DN")
	)
	(segment
		(start 384.202432 -301.011844)
		(end 384.119882 -300.929294)
		(width 0.0889)
		(layer "B.Cu")
		(net "CLK_100M_DB800ZL_PEX3_S0_R_DN")
	)
	(segment
		(start 388.373366 -298.83862)
		(end 388.373366 -300.836838)
		(width 0.0889)
		(layer "B.Cu")
		(net "CLK_100M_DB800ZL_PEX3_S0_R_DN")
	)
	(segment
		(start 382.032764 -300.929294)
		(end 381.700532 -301.261526)
		(width 0.1143)
		(layer "B.Cu")
		(net "CLK_100M_DB800ZL_PEX3_S0_R_DN")
	)
	(segment
		(start 346.893896 -223.187006)
		(end 347.293692 -223.586802)
		(width 0.13208)
		(layer "F.Cu")
		(net "RST_NIC2_PERST_N")
	)
	(segment
		(start 357.61295 -226.568)
		(end 356.108 -226.568)
		(width 0.13208)
		(layer "F.Cu")
		(net "RST_NIC2_PERST_N")
	)
	(via
		(at 347.293692 -223.586802)
		(size 0.4572)
		(drill 0.254)
		(layers "F.Cu" "B.Cu")
		(net "RST_NIC2_PERST_N")
	)
	(via
		(at 356.108 -226.568)
		(size 0.508)
		(drill 0.254)
		(layers "F.Cu" "B.Cu")
		(net "RST_NIC2_PERST_N")
	)
	(segment
		(start 353.252532 -225.6409)
		(end 354.076508 -225.6409)
		(width 0.15494)
		(layer "In5.Cu")
		(net "RST_NIC2_PERST_N")
	)
	(segment
		(start 355.003608 -226.568)
		(end 356.108 -226.568)
		(width 0.15494)
		(layer "In5.Cu")
		(net "RST_NIC2_PERST_N")
	)
	(segment
		(start 351.601024 -223.989392)
		(end 353.252532 -225.6409)
		(width 0.15494)
		(layer "In5.Cu")
		(net "RST_NIC2_PERST_N")
	)
	(segment
		(start 354.076508 -225.6409)
		(end 355.003608 -226.568)
		(width 0.15494)
		(layer "In5.Cu")
		(net "RST_NIC2_PERST_N")
	)
	(segment
		(start 347.293692 -223.586802)
		(end 347.696282 -223.989392)
		(width 0.0889)
		(layer "In5.Cu")
		(net "RST_NIC2_PERST_N")
	)
	(segment
		(start 347.696282 -223.989392)
		(end 351.601024 -223.989392)
		(width 0.0889)
		(layer "In5.Cu")
		(net "RST_NIC2_PERST_N")
	)
	(segment
		(start 232.85958 -77.805534)
		(end 232.575862 -78.089252)
		(width 0.13208)
		(layer "F.Cu")
		(net "PWRGD_P3V3_AUX_MUX_R_N")
	)
	(segment
		(start 232.85958 -77.36459)
		(end 232.85958 -77.805534)
		(width 0.13208)
		(layer "F.Cu")
		(net "PWRGD_P3V3_AUX_MUX_R_N")
	)
	(segment
		(start 231.264968 -78.605634)
		(end 231.483408 -78.605634)
		(width 0.13208)
		(layer "F.Cu")
		(net "PWRGD_P3V3_AUX_MUX_R_N")
	)
	(segment
		(start 231.67975 -78.409292)
		(end 232.255822 -78.409292)
		(width 0.13208)
		(layer "F.Cu")
		(net "PWRGD_P3V3_AUX_MUX_R_N")
	)
	(segment
		(start 232.255822 -78.409292)
		(end 232.575862 -78.089252)
		(width 0.13208)
		(layer "F.Cu")
		(net "PWRGD_P3V3_AUX_MUX_R_N")
	)
	(segment
		(start 231.483408 -78.605634)
		(end 231.67975 -78.409292)
		(width 0.13208)
		(layer "F.Cu")
		(net "PWRGD_P3V3_AUX_MUX_R_N")
	)
	(via
		(at 232.575862 -78.089252)
		(size 0.508)
		(drill 0.254)
		(layers "F.Cu" "B.Cu")
		(net "PWRGD_P3V3_AUX_MUX_R_N")
	)
	(segment
		(start 288.479992 -141.9352)
		(end 289.106102 -141.9352)
		(width 0.4064)
		(layer "F.Cu")
		(net "P3V3_NIC4")
	)
	(segment
		(start 244.809264 -119.505476)
		(end 244.809264 -120.11787)
		(width 0.4572)
		(layer "F.Cu")
		(net "P3V3_NIC4")
	)
	(segment
		(start 270.407892 -158.3944)
		(end 269.772892 -158.3944)
		(width 0.4064)
		(layer "F.Cu")
		(net "P3V3_NIC4")
	)
	(segment
		(start 270.407892 -157.3784)
		(end 269.772892 -157.3784)
		(width 0.4064)
		(layer "F.Cu")
		(net "P3V3_NIC4")
	)
	(segment
		(start 270.407892 -153.3144)
		(end 269.772892 -153.3144)
		(width 0.4064)
		(layer "F.Cu")
		(net "P3V3_NIC4")
	)
	(segment
		(start 289.385502 -141.6558)
		(end 289.864292 -141.6558)
		(width 0.4572)
		(layer "F.Cu")
		(net "P3V3_NIC4")
	)
	(segment
		(start 218.80195 -208.788)
		(end 218.313 -208.788)
		(width 0.3556)
		(layer "F.Cu")
		(net "P3V3_NIC4")
	)
	(segment
		(start 241.910362 -125.979428)
		(end 241.255042 -125.979428)
		(width 0.4064)
		(layer "F.Cu")
		(net "P3V3_NIC4")
	)
	(segment
		(start 294.429942 -170.77182)
		(end 294.429942 -171.661328)
		(width 0.4572)
		(layer "F.Cu")
		(net "P3V3_NIC4")
	)
	(segment
		(start 217.764106 -208.239106)
		(end 216.991946 -208.239106)
		(width 0.3556)
		(layer "F.Cu")
		(net "P3V3_NIC4")
	)
	(segment
		(start 293.69385 -166.070534)
		(end 293.69385 -166.705534)
		(width 0.4064)
		(layer "F.Cu")
		(net "P3V3_NIC4")
	)
	(segment
		(start 288.479992 -142.9512)
		(end 289.122358 -142.9512)
		(width 0.4064)
		(layer "F.Cu")
		(net "P3V3_NIC4")
	)
	(segment
		(start 218.80195 -208.788)
		(end 218.80195 -209.423)
		(width 0.4572)
		(layer "F.Cu")
		(net "P3V3_NIC4")
	)
	(segment
		(start 294.429942 -172.329348)
		(end 294.429942 -171.661328)
		(width 0.4572)
		(layer "F.Cu")
		(net "P3V3_NIC4")
	)
	(segment
		(start 218.313 -208.788)
		(end 217.764106 -208.239106)
		(width 0.3556)
		(layer "F.Cu")
		(net "P3V3_NIC4")
	)
	(segment
		(start 293.816024 -170.157902)
		(end 294.429942 -170.77182)
		(width 0.4572)
		(layer "F.Cu")
		(net "P3V3_NIC4")
	)
	(segment
		(start 289.106102 -141.9352)
		(end 289.385502 -141.6558)
		(width 0.4572)
		(layer "F.Cu")
		(net "P3V3_NIC4")
	)
	(segment
		(start 219.60205 -206.756)
		(end 219.60205 -205.74)
		(width 0.381)
		(layer "F.Cu")
		(net "P3V3_NIC4")
	)
	(segment
		(start 295.367202 -172.343826)
		(end 295.367202 -171.675806)
		(width 0.4572)
		(layer "F.Cu")
		(net "P3V3_NIC4")
	)
	(segment
		(start 219.60205 -207.772)
		(end 219.60205 -206.756)
		(width 0.381)
		(layer "F.Cu")
		(net "P3V3_NIC4")
	)
	(segment
		(start 219.60205 -205.74)
		(end 220.218 -205.74)
		(width 0.381)
		(layer "F.Cu")
		(net "P3V3_NIC4")
	)
	(via
		(at 269.772892 -153.3144)
		(size 0.508)
		(drill 0.254)
		(layers "F.Cu" "B.Cu")
		(net "P3V3_NIC4")
	)
	(via
		(at 267.869416 -138.88847)
		(size 0.6604)
		(drill 0.3302)
		(layers "F.Cu" "B.Cu")
		(net "P3V3_NIC4")
	)
	(via
		(at 295.367202 -172.343826)
		(size 0.508)
		(drill 0.254)
		(layers "F.Cu" "B.Cu")
		(net "P3V3_NIC4")
	)
	(via
		(at 276.806152 -140.565378)
		(size 0.508)
		(drill 0.254)
		(layers "F.Cu" "B.Cu")
		(net "P3V3_NIC4")
	)
	(via
		(at 252.020324 -126.017782)
		(size 0.508)
		(drill 0.254)
		(layers "F.Cu" "B.Cu")
		(net "P3V3_NIC4")
	)
	(via
		(at 250.901962 -117.386608)
		(size 0.508)
		(drill 0.254)
		(layers "F.Cu" "B.Cu")
		(net "P3V3_NIC4")
	)
	(via
		(at 294.429942 -172.329348)
		(size 0.508)
		(drill 0.254)
		(layers "F.Cu" "B.Cu")
		(net "P3V3_NIC4")
	)
	(via
		(at 269.772892 -157.3784)
		(size 0.508)
		(drill 0.254)
		(layers "F.Cu" "B.Cu")
		(net "P3V3_NIC4")
	)
	(via
		(at 244.809264 -120.11787)
		(size 0.508)
		(drill 0.254)
		(layers "F.Cu" "B.Cu")
		(net "P3V3_NIC4")
	)
	(via
		(at 252.020324 -126.652782)
		(size 0.508)
		(drill 0.254)
		(layers "F.Cu" "B.Cu")
		(net "P3V3_NIC4")
	)
	(via
		(at 280.745692 -155.0416)
		(size 0.508)
		(drill 0.254)
		(layers "F.Cu" "B.Cu")
		(net "P3V3_NIC4")
	)
	(via
		(at 276.806152 -139.930378)
		(size 0.508)
		(drill 0.254)
		(layers "F.Cu" "B.Cu")
		(net "P3V3_NIC4")
	)
	(via
		(at 250.351036 -125.768354)
		(size 0.508)
		(drill 0.254)
		(layers "F.Cu" "B.Cu")
		(net "P3V3_NIC4")
	)
	(via
		(at 241.255042 -125.979428)
		(size 0.508)
		(drill 0.254)
		(layers "F.Cu" "B.Cu")
		(net "P3V3_NIC4")
	)
	(via
		(at 250.274836 -126.530354)
		(size 0.508)
		(drill 0.254)
		(layers "F.Cu" "B.Cu")
		(net "P3V3_NIC4")
	)
	(via
		(at 276.171152 -139.930378)
		(size 0.508)
		(drill 0.254)
		(layers "F.Cu" "B.Cu")
		(net "P3V3_NIC4")
	)
	(via
		(at 269.772892 -158.3944)
		(size 0.508)
		(drill 0.254)
		(layers "F.Cu" "B.Cu")
		(net "P3V3_NIC4")
	)
	(via
		(at 249.066304 -125.218698)
		(size 0.508)
		(drill 0.254)
		(layers "F.Cu" "B.Cu")
		(net "P3V3_NIC4")
	)
	(via
		(at 250.901962 -118.021608)
		(size 0.508)
		(drill 0.254)
		(layers "F.Cu" "B.Cu")
		(net "P3V3_NIC4")
	)
	(via
		(at 250.266962 -118.021608)
		(size 0.508)
		(drill 0.254)
		(layers "F.Cu" "B.Cu")
		(net "P3V3_NIC4")
	)
	(via
		(at 250.986036 -125.768354)
		(size 0.508)
		(drill 0.254)
		(layers "F.Cu" "B.Cu")
		(net "P3V3_NIC4")
	)
	(via
		(at 289.106102 -141.9352)
		(size 0.508)
		(drill 0.254)
		(layers "F.Cu" "B.Cu")
		(net "P3V3_NIC4")
	)
	(via
		(at 250.986036 -126.530354)
		(size 0.508)
		(drill 0.254)
		(layers "F.Cu" "B.Cu")
		(net "P3V3_NIC4")
	)
	(via
		(at 262.054848 -139.171172)
		(size 0.6604)
		(drill 0.3302)
		(layers "F.Cu" "B.Cu")
		(net "P3V3_NIC4")
	)
	(via
		(at 289.122358 -142.9512)
		(size 0.508)
		(drill 0.254)
		(layers "F.Cu" "B.Cu")
		(net "P3V3_NIC4")
	)
	(via
		(at 228.791262 -166.85895)
		(size 0.508)
		(drill 0.254)
		(layers "F.Cu" "B.Cu")
		(net "P3V3_NIC4")
	)
	(via
		(at 293.69385 -166.705534)
		(size 0.508)
		(drill 0.254)
		(layers "F.Cu" "B.Cu")
		(net "P3V3_NIC4")
	)
	(via
		(at 273.275552 -138.699748)
		(size 0.6604)
		(drill 0.3302)
		(layers "F.Cu" "B.Cu")
		(net "P3V3_NIC4")
	)
	(via
		(at 250.901962 -116.751608)
		(size 0.508)
		(drill 0.254)
		(layers "F.Cu" "B.Cu")
		(net "P3V3_NIC4")
	)
	(via
		(at 249.066304 -125.853698)
		(size 0.508)
		(drill 0.254)
		(layers "F.Cu" "B.Cu")
		(net "P3V3_NIC4")
	)
	(via
		(at 276.171152 -140.565378)
		(size 0.508)
		(drill 0.254)
		(layers "F.Cu" "B.Cu")
		(net "P3V3_NIC4")
	)
	(via
		(at 220.218 -205.74)
		(size 0.508)
		(drill 0.254)
		(layers "F.Cu" "B.Cu")
		(net "P3V3_NIC4")
	)
	(via
		(at 252.020324 -124.747782)
		(size 0.508)
		(drill 0.254)
		(layers "F.Cu" "B.Cu")
		(net "P3V3_NIC4")
	)
	(via
		(at 248.125742 -124.768356)
		(size 0.508)
		(drill 0.254)
		(layers "F.Cu" "B.Cu")
		(net "P3V3_NIC4")
	)
	(via
		(at 248.125742 -125.403356)
		(size 0.508)
		(drill 0.254)
		(layers "F.Cu" "B.Cu")
		(net "P3V3_NIC4")
	)
	(via
		(at 250.266962 -116.751608)
		(size 0.508)
		(drill 0.254)
		(layers "F.Cu" "B.Cu")
		(net "P3V3_NIC4")
	)
	(via
		(at 218.80195 -209.423)
		(size 0.508)
		(drill 0.254)
		(layers "F.Cu" "B.Cu")
		(net "P3V3_NIC4")
	)
	(via
		(at 252.020324 -125.382782)
		(size 0.508)
		(drill 0.254)
		(layers "F.Cu" "B.Cu")
		(net "P3V3_NIC4")
	)
	(via
		(at 250.266962 -117.386608)
		(size 0.508)
		(drill 0.254)
		(layers "F.Cu" "B.Cu")
		(net "P3V3_NIC4")
	)
	(segment
		(start 281.355292 -155.0416)
		(end 280.745692 -155.0416)
		(width 0.4572)
		(layer "B.Cu")
		(net "P3V3_NIC4")
	)
	(segment
		(start 222.463614 -200.207626)
		(end 220.273372 -202.397868)
		(width 0.508)
		(layer "In9.Cu")
		(net "P3V3_NIC4")
	)
	(segment
		(start 226.242626 -189.82182)
		(end 226.242626 -195.287646)
		(width 0.508)
		(layer "In9.Cu")
		(net "P3V3_NIC4")
	)
	(segment
		(start 218.80195 -208.25841)
		(end 218.80195 -209.423)
		(width 0.508)
		(layer "In9.Cu")
		(net "P3V3_NIC4")
	)
	(segment
		(start 228.444806 -187.61964)
		(end 226.242626 -189.82182)
		(width 0.508)
		(layer "In9.Cu")
		(net "P3V3_NIC4")
	)
	(segment
		(start 226.242626 -195.287646)
		(end 224.380298 -197.149974)
		(width 0.508)
		(layer "In9.Cu")
		(net "P3V3_NIC4")
	)
	(segment
		(start 220.273372 -205.684628)
		(end 220.218 -205.74)
		(width 0.508)
		(layer "In9.Cu")
		(net "P3V3_NIC4")
	)
	(segment
		(start 228.791262 -166.85895)
		(end 228.444806 -167.205406)
		(width 0.508)
		(layer "In9.Cu")
		(net "P3V3_NIC4")
	)
	(segment
		(start 223.859598 -200.207626)
		(end 222.463614 -200.207626)
		(width 0.508)
		(layer "In9.Cu")
		(net "P3V3_NIC4")
	)
	(segment
		(start 220.218 -205.74)
		(end 219.924122 -206.033878)
		(width 0.508)
		(layer "In9.Cu")
		(net "P3V3_NIC4")
	)
	(segment
		(start 224.380298 -199.686926)
		(end 223.859598 -200.207626)
		(width 0.508)
		(layer "In9.Cu")
		(net "P3V3_NIC4")
	)
	(segment
		(start 219.924122 -206.033878)
		(end 219.924122 -207.136238)
		(width 0.508)
		(layer "In9.Cu")
		(net "P3V3_NIC4")
	)
	(segment
		(start 220.273372 -202.397868)
		(end 220.273372 -205.684628)
		(width 0.508)
		(layer "In9.Cu")
		(net "P3V3_NIC4")
	)
	(segment
		(start 228.444806 -167.205406)
		(end 228.444806 -187.61964)
		(width 0.508)
		(layer "In9.Cu")
		(net "P3V3_NIC4")
	)
	(segment
		(start 219.924122 -207.136238)
		(end 218.80195 -208.25841)
		(width 0.508)
		(layer "In9.Cu")
		(net "P3V3_NIC4")
	)
	(segment
		(start 224.380298 -197.149974)
		(end 224.380298 -199.686926)
		(width 0.508)
		(layer "In9.Cu")
		(net "P3V3_NIC4")
	)
	(segment
		(start 257.857752 -166.521638)
		(end 229.128574 -166.521638)
		(width 0.508)
		(layer "In13.Cu")
		(net "P3V3_NIC4")
	)
	(segment
		(start 266.17041 -158.20898)
		(end 257.857752 -166.521638)
		(width 0.508)
		(layer "In13.Cu")
		(net "P3V3_NIC4")
	)
	(segment
		(start 229.128574 -166.521638)
		(end 228.791262 -166.85895)
		(width 0.508)
		(layer "In13.Cu")
		(net "P3V3_NIC4")
	)
	(segment
		(start 269.150846 -158.20898)
		(end 266.17041 -158.20898)
		(width 0.508)
		(layer "In13.Cu")
		(net "P3V3_NIC4")
	)
	(segment
		(start 123.241054 -57.16397)
		(end 123.241054 -58.364628)
		(width 0.13208)
		(layer "F.Cu")
		(net "P3V3_SSD4_OCP")
	)
	(segment
		(start 123.241054 -58.364628)
		(end 123.044458 -58.561224)
		(width 0.13208)
		(layer "F.Cu")
		(net "P3V3_SSD4_OCP")
	)
	(segment
		(start 123.203462 -59.171586)
		(end 123.044458 -59.012582)
		(width 0.13208)
		(layer "F.Cu")
		(net "P3V3_SSD4_OCP")
	)
	(segment
		(start 123.044458 -59.012582)
		(end 123.044458 -58.561224)
		(width 0.13208)
		(layer "F.Cu")
		(net "P3V3_SSD4_OCP")
	)
	(via
		(at 123.044458 -58.561224)
		(size 0.508)
		(drill 0.254)
		(layers "F.Cu" "B.Cu")
		(net "P3V3_SSD4_OCP")
	)
	(segment
		(start 336.695542 -83.814412)
		(end 336.695542 -82.986626)
		(width 0.1778)
		(layer "F.Cu")
		(net "P3V3_VDD_9ZXL0851_8_15")
	)
	(segment
		(start 334.427322 -85.47354)
		(end 334.075024 -85.47354)
		(width 0.1778)
		(layer "F.Cu")
		(net "P3V3_VDD_9ZXL0851_8_15")
	)
	(segment
		(start 338.471002 -82.99577)
		(end 338.471002 -82.894424)
		(width 0.1778)
		(layer "F.Cu")
		(net "P3V3_VDD_9ZXL0851_8_15")
	)
	(segment
		(start 331.041502 -90.666316)
		(end 330.189586 -90.666316)
		(width 0.381)
		(layer "F.Cu")
		(net "P3V3_VDD_9ZXL0851_8_15")
	)
	(segment
		(start 338.295488 -90.373962)
		(end 338.07527 -90.59418)
		(width 0.1778)
		(layer "F.Cu")
		(net "P3V3_VDD_9ZXL0851_8_15")
	)
	(segment
		(start 338.295488 -83.814412)
		(end 338.295488 -83.171284)
		(width 0.1778)
		(layer "F.Cu")
		(net "P3V3_VDD_9ZXL0851_8_15")
	)
	(segment
		(start 341.045546 -85.36432)
		(end 341.886286 -85.36432)
		(width 0.1778)
		(layer "F.Cu")
		(net "P3V3_VDD_9ZXL0851_8_15")
	)
	(segment
		(start 334.536542 -85.36432)
		(end 334.427322 -85.47354)
		(width 0.1778)
		(layer "F.Cu")
		(net "P3V3_VDD_9ZXL0851_8_15")
	)
	(segment
		(start 338.295488 -83.171284)
		(end 338.471002 -82.99577)
		(width 0.1778)
		(layer "F.Cu")
		(net "P3V3_VDD_9ZXL0851_8_15")
	)
	(segment
		(start 339.895688 -89.714324)
		(end 339.895688 -90.59164)
		(width 0.1778)
		(layer "F.Cu")
		(net "P3V3_VDD_9ZXL0851_8_15")
	)
	(segment
		(start 338.295488 -89.714324)
		(end 338.295488 -90.373962)
		(width 0.1778)
		(layer "F.Cu")
		(net "P3V3_VDD_9ZXL0851_8_15")
	)
	(segment
		(start 341.900002 -88.164416)
		(end 341.90051 -88.164924)
		(width 0.2032)
		(layer "F.Cu")
		(net "P3V3_VDD_9ZXL0851_8_15")
	)
	(segment
		(start 341.045546 -88.164416)
		(end 341.900002 -88.164416)
		(width 0.2032)
		(layer "F.Cu")
		(net "P3V3_VDD_9ZXL0851_8_15")
	)
	(segment
		(start 339.895688 -90.59164)
		(end 339.971634 -90.667586)
		(width 0.1778)
		(layer "F.Cu")
		(net "P3V3_VDD_9ZXL0851_8_15")
	)
	(segment
		(start 335.145634 -85.36432)
		(end 334.536542 -85.36432)
		(width 0.1778)
		(layer "F.Cu")
		(net "P3V3_VDD_9ZXL0851_8_15")
	)
	(via
		(at 341.886286 -85.36432)
		(size 0.508)
		(drill 0.254)
		(layers "F.Cu" "B.Cu")
		(net "P3V3_VDD_9ZXL0851_8_15")
	)
	(via
		(at 334.075024 -85.47354)
		(size 0.508)
		(drill 0.254)
		(layers "F.Cu" "B.Cu")
		(net "P3V3_VDD_9ZXL0851_8_15")
	)
	(via
		(at 339.971634 -90.667586)
		(size 0.508)
		(drill 0.254)
		(layers "F.Cu" "B.Cu")
		(net "P3V3_VDD_9ZXL0851_8_15")
	)
	(via
		(at 335.926938 -82.099404)
		(size 0.6604)
		(drill 0.3302)
		(layers "F.Cu" "B.Cu")
		(net "P3V3_VDD_9ZXL0851_8_15")
	)
	(via
		(at 341.90051 -88.164924)
		(size 0.508)
		(drill 0.254)
		(layers "F.Cu" "B.Cu")
		(net "P3V3_VDD_9ZXL0851_8_15")
	)
	(via
		(at 338.471002 -82.894424)
		(size 0.508)
		(drill 0.254)
		(layers "F.Cu" "B.Cu")
		(net "P3V3_VDD_9ZXL0851_8_15")
	)
	(via
		(at 330.189586 -90.666316)
		(size 0.508)
		(drill 0.254)
		(layers "F.Cu" "B.Cu")
		(net "P3V3_VDD_9ZXL0851_8_15")
	)
	(via
		(at 338.07527 -90.59418)
		(size 0.508)
		(drill 0.254)
		(layers "F.Cu" "B.Cu")
		(net "P3V3_VDD_9ZXL0851_8_15")
	)
	(via
		(at 342.01354 -90.337132)
		(size 0.6604)
		(drill 0.3302)
		(layers "F.Cu" "B.Cu")
		(net "P3V3_VDD_9ZXL0851_8_15")
	)
	(via
		(at 336.695542 -82.986626)
		(size 0.508)
		(drill 0.254)
		(layers "F.Cu" "B.Cu")
		(net "P3V3_VDD_9ZXL0851_8_15")
	)
	(segment
		(start 340.545674 -90.0557)
		(end 339.971634 -90.62974)
		(width 0.254)
		(layer "B.Cu")
		(net "P3V3_VDD_9ZXL0851_8_15")
	)
	(segment
		(start 339.971634 -90.62974)
		(end 339.971634 -90.667586)
		(width 0.254)
		(layer "B.Cu")
		(net "P3V3_VDD_9ZXL0851_8_15")
	)
	(segment
		(start 334.075024 -85.47354)
		(end 334.355694 -85.75421)
		(width 0.254)
		(layer "B.Cu")
		(net "P3V3_VDD_9ZXL0851_8_15")
	)
	(segment
		(start 341.61095 -87.875364)
		(end 341.90051 -88.164924)
		(width 0.254)
		(layer "B.Cu")
		(net "P3V3_VDD_9ZXL0851_8_15")
	)
	(segment
		(start 340.540848 -89.602818)
		(end 340.545674 -89.607644)
		(width 0.254)
		(layer "B.Cu")
		(net "P3V3_VDD_9ZXL0851_8_15")
	)
	(segment
		(start 340.545674 -89.607644)
		(end 340.545674 -90.0557)
		(width 0.254)
		(layer "B.Cu")
		(net "P3V3_VDD_9ZXL0851_8_15")
	)
	(segment
		(start 337.998562 -89.608152)
		(end 337.998562 -90.517472)
		(width 0.254)
		(layer "B.Cu")
		(net "P3V3_VDD_9ZXL0851_8_15")
	)
	(segment
		(start 340.823296 -87.875364)
		(end 341.61095 -87.875364)
		(width 0.254)
		(layer "B.Cu")
		(net "P3V3_VDD_9ZXL0851_8_15")
	)
	(segment
		(start 337.998562 -90.517472)
		(end 338.07527 -90.59418)
		(width 0.254)
		(layer "B.Cu")
		(net "P3V3_VDD_9ZXL0851_8_15")
	)
	(segment
		(start 334.355694 -85.75421)
		(end 335.42732 -85.75421)
		(width 0.254)
		(layer "B.Cu")
		(net "P3V3_VDD_9ZXL0851_8_15")
	)
	(segment
		(start 271.899888 -298.74972)
		(end 271.899888 -298.749974)
		(width 0.1143)
		(layer "F.Cu")
		(net "CLK_100M_DB800ZL_PEX2_S0_R_DN")
	)
	(segment
		(start 271.899888 -298.749974)
		(end 271.424908 -299.224954)
		(width 0.1143)
		(layer "F.Cu")
		(net "CLK_100M_DB800ZL_PEX2_S0_R_DN")
	)
	(via
		(at 271.424908 -299.224954)
		(size 0.4064)
		(drill 0.2032)
		(layers "F.Cu" "B.Cu")
		(net "CLK_100M_DB800ZL_PEX2_S0_R_DN")
	)
	(via
		(at 234.8611 -336.402426)
		(size 0.508)
		(drill 0.254)
		(layers "F.Cu" "B.Cu")
		(net "CLK_100M_DB800ZL_PEX2_S0_R_DN")
	)
	(segment
		(start 224.827846 -336.656426)
		(end 234.6071 -336.656426)
		(width 0.1143)
		(layer "B.Cu")
		(net "CLK_100M_DB800ZL_PEX2_S0_R_DN")
	)
	(segment
		(start 106.193082 -340.605872)
		(end 114.384328 -340.605872)
		(width 0.1143)
		(layer "B.Cu")
		(net "CLK_100M_DB800ZL_PEX2_S0_R_DN")
	)
	(segment
		(start 106.015282 -340.428072)
		(end 106.193082 -340.605872)
		(width 0.1143)
		(layer "B.Cu")
		(net "CLK_100M_DB800ZL_PEX2_S0_R_DN")
	)
	(segment
		(start 103.221282 -340.605872)
		(end 103.399082 -340.428072)
		(width 0.1143)
		(layer "B.Cu")
		(net "CLK_100M_DB800ZL_PEX2_S0_R_DN")
	)
	(segment
		(start 97.314258 -333.895954)
		(end 97.314258 -334.527652)
		(width 0.1143)
		(layer "B.Cu")
		(net "CLK_100M_DB800ZL_PEX2_S0_R_DN")
	)
	(segment
		(start 101.668072 -340.605872)
		(end 102.103682 -340.605872)
		(width 0.1143)
		(layer "B.Cu")
		(net "CLK_100M_DB800ZL_PEX2_S0_R_DN")
	)
	(segment
		(start 97.479358 -334.692752)
		(end 97.479358 -335.073752)
		(width 0.1143)
		(layer "B.Cu")
		(net "CLK_100M_DB800ZL_PEX2_S0_R_DN")
	)
	(segment
		(start 100.617274 -339.361272)
		(end 100.617274 -339.555074)
		(width 0.1143)
		(layer "B.Cu")
		(net "CLK_100M_DB800ZL_PEX2_S0_R_DN")
	)
	(segment
		(start 102.281482 -340.428072)
		(end 102.662482 -340.428072)
		(width 0.1143)
		(layer "B.Cu")
		(net "CLK_100M_DB800ZL_PEX2_S0_R_DN")
	)
	(segment
		(start 234.6071 -336.656426)
		(end 234.8611 -336.402426)
		(width 0.1143)
		(layer "B.Cu")
		(net "CLK_100M_DB800ZL_PEX2_S0_R_DN")
	)
	(segment
		(start 104.338882 -340.605872)
		(end 104.516682 -340.428072)
		(width 0.1143)
		(layer "B.Cu")
		(net "CLK_100M_DB800ZL_PEX2_S0_R_DN")
	)
	(segment
		(start 114.384328 -340.605872)
		(end 114.669824 -340.320376)
		(width 0.1143)
		(layer "B.Cu")
		(net "CLK_100M_DB800ZL_PEX2_S0_R_DN")
	)
	(segment
		(start 100.90277 -339.84057)
		(end 101.096826 -339.84057)
		(width 0.1143)
		(layer "B.Cu")
		(net "CLK_100M_DB800ZL_PEX2_S0_R_DN")
	)
	(segment
		(start 101.382576 -340.320376)
		(end 101.668072 -340.605872)
		(width 0.1143)
		(layer "B.Cu")
		(net "CLK_100M_DB800ZL_PEX2_S0_R_DN")
	)
	(segment
		(start 105.634282 -340.428072)
		(end 106.015282 -340.428072)
		(width 0.1143)
		(layer "B.Cu")
		(net "CLK_100M_DB800ZL_PEX2_S0_R_DN")
	)
	(segment
		(start 97.314258 -336.252058)
		(end 99.372166 -338.309966)
		(width 0.1143)
		(layer "B.Cu")
		(net "CLK_100M_DB800ZL_PEX2_S0_R_DN")
	)
	(segment
		(start 221.453202 -333.281782)
		(end 224.827846 -336.656426)
		(width 0.1143)
		(layer "B.Cu")
		(net "CLK_100M_DB800ZL_PEX2_S0_R_DN")
	)
	(segment
		(start 121.708418 -333.281782)
		(end 221.453202 -333.281782)
		(width 0.1143)
		(layer "B.Cu")
		(net "CLK_100M_DB800ZL_PEX2_S0_R_DN")
	)
	(segment
		(start 102.662482 -340.428072)
		(end 102.840282 -340.605872)
		(width 0.1143)
		(layer "B.Cu")
		(net "CLK_100M_DB800ZL_PEX2_S0_R_DN")
	)
	(segment
		(start 103.780082 -340.428072)
		(end 103.957882 -340.605872)
		(width 0.1143)
		(layer "B.Cu")
		(net "CLK_100M_DB800ZL_PEX2_S0_R_DN")
	)
	(segment
		(start 115.14963 -339.84057)
		(end 121.708418 -333.281782)
		(width 0.1143)
		(layer "B.Cu")
		(net "CLK_100M_DB800ZL_PEX2_S0_R_DN")
	)
	(segment
		(start 105.075482 -340.605872)
		(end 105.456482 -340.605872)
		(width 0.1143)
		(layer "B.Cu")
		(net "CLK_100M_DB800ZL_PEX2_S0_R_DN")
	)
	(segment
		(start 99.566222 -338.309966)
		(end 99.851972 -338.59597)
		(width 0.1143)
		(layer "B.Cu")
		(net "CLK_100M_DB800ZL_PEX2_S0_R_DN")
	)
	(segment
		(start 98.638614 -333.7687)
		(end 97.441512 -333.7687)
		(width 0.1143)
		(layer "B.Cu")
		(net "CLK_100M_DB800ZL_PEX2_S0_R_DN")
	)
	(segment
		(start 97.441512 -333.7687)
		(end 97.314258 -333.895954)
		(width 0.1143)
		(layer "B.Cu")
		(net "CLK_100M_DB800ZL_PEX2_S0_R_DN")
	)
	(segment
		(start 114.669824 -340.126574)
		(end 114.955574 -339.84057)
		(width 0.1143)
		(layer "B.Cu")
		(net "CLK_100M_DB800ZL_PEX2_S0_R_DN")
	)
	(segment
		(start 103.957882 -340.605872)
		(end 104.338882 -340.605872)
		(width 0.1143)
		(layer "B.Cu")
		(net "CLK_100M_DB800ZL_PEX2_S0_R_DN")
	)
	(segment
		(start 101.096826 -339.84057)
		(end 101.382576 -340.126574)
		(width 0.1143)
		(layer "B.Cu")
		(net "CLK_100M_DB800ZL_PEX2_S0_R_DN")
	)
	(segment
		(start 99.851972 -338.59597)
		(end 99.851972 -338.789772)
		(width 0.1143)
		(layer "B.Cu")
		(net "CLK_100M_DB800ZL_PEX2_S0_R_DN")
	)
	(segment
		(start 105.456482 -340.605872)
		(end 105.634282 -340.428072)
		(width 0.1143)
		(layer "B.Cu")
		(net "CLK_100M_DB800ZL_PEX2_S0_R_DN")
	)
	(segment
		(start 103.399082 -340.428072)
		(end 103.780082 -340.428072)
		(width 0.1143)
		(layer "B.Cu")
		(net "CLK_100M_DB800ZL_PEX2_S0_R_DN")
	)
	(segment
		(start 100.617274 -339.555074)
		(end 100.90277 -339.84057)
		(width 0.1143)
		(layer "B.Cu")
		(net "CLK_100M_DB800ZL_PEX2_S0_R_DN")
	)
	(segment
		(start 104.516682 -340.428072)
		(end 104.897682 -340.428072)
		(width 0.1143)
		(layer "B.Cu")
		(net "CLK_100M_DB800ZL_PEX2_S0_R_DN")
	)
	(segment
		(start 101.382576 -340.126574)
		(end 101.382576 -340.320376)
		(width 0.1143)
		(layer "B.Cu")
		(net "CLK_100M_DB800ZL_PEX2_S0_R_DN")
	)
	(segment
		(start 102.103682 -340.605872)
		(end 102.281482 -340.428072)
		(width 0.1143)
		(layer "B.Cu")
		(net "CLK_100M_DB800ZL_PEX2_S0_R_DN")
	)
	(segment
		(start 97.479358 -335.073752)
		(end 97.314258 -335.238852)
		(width 0.1143)
		(layer "B.Cu")
		(net "CLK_100M_DB800ZL_PEX2_S0_R_DN")
	)
	(segment
		(start 97.314258 -334.527652)
		(end 97.479358 -334.692752)
		(width 0.1143)
		(layer "B.Cu")
		(net "CLK_100M_DB800ZL_PEX2_S0_R_DN")
	)
	(segment
		(start 97.314258 -335.238852)
		(end 97.314258 -336.252058)
		(width 0.1143)
		(layer "B.Cu")
		(net "CLK_100M_DB800ZL_PEX2_S0_R_DN")
	)
	(segment
		(start 99.851972 -338.789772)
		(end 100.137468 -339.075268)
		(width 0.1143)
		(layer "B.Cu")
		(net "CLK_100M_DB800ZL_PEX2_S0_R_DN")
	)
	(segment
		(start 99.372166 -338.309966)
		(end 99.566222 -338.309966)
		(width 0.1143)
		(layer "B.Cu")
		(net "CLK_100M_DB800ZL_PEX2_S0_R_DN")
	)
	(segment
		(start 100.137468 -339.075268)
		(end 100.331524 -339.075268)
		(width 0.1143)
		(layer "B.Cu")
		(net "CLK_100M_DB800ZL_PEX2_S0_R_DN")
	)
	(segment
		(start 98.95332 -334.083406)
		(end 98.638614 -333.7687)
		(width 0.1143)
		(layer "B.Cu")
		(net "CLK_100M_DB800ZL_PEX2_S0_R_DN")
	)
	(segment
		(start 114.669824 -340.320376)
		(end 114.669824 -340.126574)
		(width 0.1143)
		(layer "B.Cu")
		(net "CLK_100M_DB800ZL_PEX2_S0_R_DN")
	)
	(segment
		(start 102.840282 -340.605872)
		(end 103.221282 -340.605872)
		(width 0.1143)
		(layer "B.Cu")
		(net "CLK_100M_DB800ZL_PEX2_S0_R_DN")
	)
	(segment
		(start 100.331524 -339.075268)
		(end 100.617274 -339.361272)
		(width 0.1143)
		(layer "B.Cu")
		(net "CLK_100M_DB800ZL_PEX2_S0_R_DN")
	)
	(segment
		(start 104.897682 -340.428072)
		(end 105.075482 -340.605872)
		(width 0.1143)
		(layer "B.Cu")
		(net "CLK_100M_DB800ZL_PEX2_S0_R_DN")
	)
	(segment
		(start 114.955574 -339.84057)
		(end 115.14963 -339.84057)
		(width 0.1143)
		(layer "B.Cu")
		(net "CLK_100M_DB800ZL_PEX2_S0_R_DN")
	)
	(segment
		(start 263.015222 -304.35677)
		(end 262.745474 -304.626518)
		(width 0.1397)
		(layer "In9.Cu")
		(net "CLK_100M_DB800ZL_PEX2_S0_R_DN")
	)
	(segment
		(start 263.266682 -304.35677)
		(end 263.015222 -304.35677)
		(width 0.1397)
		(layer "In9.Cu")
		(net "CLK_100M_DB800ZL_PEX2_S0_R_DN")
	)
	(segment
		(start 241.939318 -329.084178)
		(end 241.939318 -331.448918)
		(width 0.1397)
		(layer "In9.Cu")
		(net "CLK_100M_DB800ZL_PEX2_S0_R_DN")
	)
	(segment
		(start 271.715738 -299.224954)
		(end 271.804638 -299.313854)
		(width 0.0889)
		(layer "In9.Cu")
		(net "CLK_100M_DB800ZL_PEX2_S0_R_DN")
	)
	(segment
		(start 267.452602 -300.268894)
		(end 267.354558 -300.268894)
		(width 0.0889)
		(layer "In9.Cu")
		(net "CLK_100M_DB800ZL_PEX2_S0_R_DN")
	)
	(segment
		(start 260.79323 -306.578762)
		(end 260.79323 -306.830222)
		(width 0.1397)
		(layer "In9.Cu")
		(net "CLK_100M_DB800ZL_PEX2_S0_R_DN")
	)
	(segment
		(start 252.151642 -315.47181)
		(end 252.151642 -318.871854)
		(width 0.1397)
		(layer "In9.Cu")
		(net "CLK_100M_DB800ZL_PEX2_S0_R_DN")
	)
	(segment
		(start 271.424908 -299.224954)
		(end 271.715738 -299.224954)
		(width 0.0889)
		(layer "In9.Cu")
		(net "CLK_100M_DB800ZL_PEX2_S0_R_DN")
	)
	(segment
		(start 261.314438 -306.309014)
		(end 261.062978 -306.309014)
		(width 0.1397)
		(layer "In9.Cu")
		(net "CLK_100M_DB800ZL_PEX2_S0_R_DN")
	)
	(segment
		(start 241.939318 -331.448918)
		(end 236.71911 -336.669126)
		(width 0.1397)
		(layer "In9.Cu")
		(net "CLK_100M_DB800ZL_PEX2_S0_R_DN")
	)
	(segment
		(start 262.157718 -305.465734)
		(end 261.906258 -305.465734)
		(width 0.1397)
		(layer "In9.Cu")
		(net "CLK_100M_DB800ZL_PEX2_S0_R_DN")
	)
	(segment
		(start 271.634458 -299.609764)
		(end 268.111732 -299.609764)
		(width 0.0889)
		(layer "In9.Cu")
		(net "CLK_100M_DB800ZL_PEX2_S0_R_DN")
	)
	(segment
		(start 260.79323 -306.830222)
		(end 252.151642 -315.47181)
		(width 0.1397)
		(layer "In9.Cu")
		(net "CLK_100M_DB800ZL_PEX2_S0_R_DN")
	)
	(segment
		(start 236.71911 -336.669126)
		(end 235.1278 -336.669126)
		(width 0.1397)
		(layer "In9.Cu")
		(net "CLK_100M_DB800ZL_PEX2_S0_R_DN")
	)
	(segment
		(start 261.63651 -305.735482)
		(end 261.63651 -305.986942)
		(width 0.1397)
		(layer "In9.Cu")
		(net "CLK_100M_DB800ZL_PEX2_S0_R_DN")
	)
	(segment
		(start 252.151642 -318.871854)
		(end 241.939318 -329.084178)
		(width 0.1397)
		(layer "In9.Cu")
		(net "CLK_100M_DB800ZL_PEX2_S0_R_DN")
	)
	(segment
		(start 235.1278 -336.669126)
		(end 234.8611 -336.402426)
		(width 0.1397)
		(layer "In9.Cu")
		(net "CLK_100M_DB800ZL_PEX2_S0_R_DN")
	)
	(segment
		(start 268.111732 -299.609764)
		(end 267.452602 -300.268894)
		(width 0.0889)
		(layer "In9.Cu")
		(net "CLK_100M_DB800ZL_PEX2_S0_R_DN")
	)
	(segment
		(start 271.804638 -299.439584)
		(end 271.634458 -299.609764)
		(width 0.0889)
		(layer "In9.Cu")
		(net "CLK_100M_DB800ZL_PEX2_S0_R_DN")
	)
	(segment
		(start 261.63651 -305.986942)
		(end 261.314438 -306.309014)
		(width 0.1397)
		(layer "In9.Cu")
		(net "CLK_100M_DB800ZL_PEX2_S0_R_DN")
	)
	(segment
		(start 261.906258 -305.465734)
		(end 261.63651 -305.735482)
		(width 0.1397)
		(layer "In9.Cu")
		(net "CLK_100M_DB800ZL_PEX2_S0_R_DN")
	)
	(segment
		(start 262.745474 -304.877978)
		(end 262.157718 -305.465734)
		(width 0.1397)
		(layer "In9.Cu")
		(net "CLK_100M_DB800ZL_PEX2_S0_R_DN")
	)
	(segment
		(start 271.804638 -299.313854)
		(end 271.804638 -299.439584)
		(width 0.0889)
		(layer "In9.Cu")
		(net "CLK_100M_DB800ZL_PEX2_S0_R_DN")
	)
	(segment
		(start 262.745474 -304.626518)
		(end 262.745474 -304.877978)
		(width 0.1397)
		(layer "In9.Cu")
		(net "CLK_100M_DB800ZL_PEX2_S0_R_DN")
	)
	(segment
		(start 267.339064 -300.284388)
		(end 263.266682 -304.35677)
		(width 0.1397)
		(layer "In9.Cu")
		(net "CLK_100M_DB800ZL_PEX2_S0_R_DN")
	)
	(segment
		(start 261.062978 -306.309014)
		(end 260.79323 -306.578762)
		(width 0.1397)
		(layer "In9.Cu")
		(net "CLK_100M_DB800ZL_PEX2_S0_R_DN")
	)
	(segment
		(start 267.354558 -300.268894)
		(end 267.339064 -300.284388)
		(width 0.0889)
		(layer "In9.Cu")
		(net "CLK_100M_DB800ZL_PEX2_S0_R_DN")
	)
	(segment
		(start 126.610364 -124.096526)
		(end 126.610364 -123.947428)
		(width 0.13208)
		(layer "F.Cu")
		(net "P3V3_NIC2_OCP")
	)
	(segment
		(start 127.724916 -125.39472)
		(end 128.33096 -125.39472)
		(width 0.13208)
		(layer "F.Cu")
		(net "P3V3_NIC2_OCP")
	)
	(segment
		(start 127.310896 -124.797058)
		(end 126.610364 -124.096526)
		(width 0.13208)
		(layer "F.Cu")
		(net "P3V3_NIC2_OCP")
	)
	(segment
		(start 127.310896 -124.9807)
		(end 127.724916 -125.39472)
		(width 0.13208)
		(layer "F.Cu")
		(net "P3V3_NIC2_OCP")
	)
	(segment
		(start 127.310896 -124.9807)
		(end 127.310896 -124.797058)
		(width 0.13208)
		(layer "F.Cu")
		(net "P3V3_NIC2_OCP")
	)
	(via
		(at 127.310896 -124.9807)
		(size 0.508)
		(drill 0.254)
		(layers "F.Cu" "B.Cu")
		(net "P3V3_NIC2_OCP")
	)
	(segment
		(start 166.15664 -17.419574)
		(end 166.76624 -17.419574)
		(width 0.508)
		(layer "F.Cu")
		(net "P3V3_SSD5")
	)
	(segment
		(start 163.985702 -27.492198)
		(end 163.85413 -27.492198)
		(width 0.381)
		(layer "F.Cu")
		(net "P3V3_SSD5")
	)
	(segment
		(start 147.794218 -34.248852)
		(end 147.794218 -32.787336)
		(width 0.381)
		(layer "F.Cu")
		(net "P3V3_SSD5")
	)
	(segment
		(start 157.364938 -24.790146)
		(end 158.33344 -24.790146)
		(width 0.381)
		(layer "F.Cu")
		(net "P3V3_SSD5")
	)
	(segment
		(start 167.660574 -14.799818)
		(end 167.660574 -16.439388)
		(width 0.381)
		(layer "F.Cu")
		(net "P3V3_SSD5")
	)
	(segment
		(start 167.006778 -14.735302)
		(end 167.72509 -14.735302)
		(width 0.381)
		(layer "F.Cu")
		(net "P3V3_SSD5")
	)
	(segment
		(start 167.72509 -14.735302)
		(end 167.660574 -14.799818)
		(width 0.381)
		(layer "F.Cu")
		(net "P3V3_SSD5")
	)
	(segment
		(start 160.026604 -25.031954)
		(end 160.669986 -25.031954)
		(width 0.4572)
		(layer "F.Cu")
		(net "P3V3_SSD5")
	)
	(segment
		(start 158.575248 -25.031954)
		(end 160.026604 -25.031954)
		(width 0.381)
		(layer "F.Cu")
		(net "P3V3_SSD5")
	)
	(segment
		(start 148.068792 -30.971236)
		(end 147.494244 -30.396688)
		(width 0.381)
		(layer "F.Cu")
		(net "P3V3_SSD5")
	)
	(segment
		(start 161.571686 -25.742392)
		(end 161.571686 -26.360882)
		(width 0.4572)
		(layer "F.Cu")
		(net "P3V3_SSD5")
	)
	(segment
		(start 163.85413 -27.492198)
		(end 163.333176 -26.971244)
		(width 0.381)
		(layer "F.Cu")
		(net "P3V3_SSD5")
	)
	(segment
		(start 134.946898 -37.47516)
		(end 134.241286 -37.47516)
		(width 0.4572)
		(layer "F.Cu")
		(net "P3V3_SSD5")
	)
	(segment
		(start 148.068792 -32.512762)
		(end 148.068792 -30.971236)
		(width 0.381)
		(layer "F.Cu")
		(net "P3V3_SSD5")
	)
	(segment
		(start 158.33344 -24.790146)
		(end 158.575248 -25.031954)
		(width 0.381)
		(layer "F.Cu")
		(net "P3V3_SSD5")
	)
	(segment
		(start 147.794218 -32.787336)
		(end 148.068792 -32.512762)
		(width 0.381)
		(layer "F.Cu")
		(net "P3V3_SSD5")
	)
	(segment
		(start 150.2791 -59.978036)
		(end 150.2791 -60.633356)
		(width 0.381)
		(layer "F.Cu")
		(net "P3V3_SSD5")
	)
	(segment
		(start 166.769542 -20.467574)
		(end 166.15664 -20.467574)
		(width 0.508)
		(layer "F.Cu")
		(net "P3V3_SSD5")
	)
	(segment
		(start 149.471888 -24.807418)
		(end 148.853398 -24.807418)
		(width 0.4572)
		(layer "F.Cu")
		(net "P3V3_SSD5")
	)
	(via
		(at 149.06498 -52.528724)
		(size 0.508)
		(drill 0.254)
		(layers "F.Cu" "B.Cu")
		(net "P3V3_SSD5")
	)
	(via
		(at 149.249638 -53.469286)
		(size 0.508)
		(drill 0.254)
		(layers "F.Cu" "B.Cu")
		(net "P3V3_SSD5")
	)
	(via
		(at 149.614636 -51.243992)
		(size 0.508)
		(drill 0.254)
		(layers "F.Cu" "B.Cu")
		(net "P3V3_SSD5")
	)
	(via
		(at 149.69998 -52.528724)
		(size 0.508)
		(drill 0.254)
		(layers "F.Cu" "B.Cu")
		(net "P3V3_SSD5")
	)
	(via
		(at 150.2791 -60.633356)
		(size 0.508)
		(drill 0.254)
		(layers "F.Cu" "B.Cu")
		(net "P3V3_SSD5")
	)
	(via
		(at 150.376636 -51.320192)
		(size 0.508)
		(drill 0.254)
		(layers "F.Cu" "B.Cu")
		(net "P3V3_SSD5")
	)
	(via
		(at 149.229064 -49.574704)
		(size 0.508)
		(drill 0.254)
		(layers "F.Cu" "B.Cu")
		(net "P3V3_SSD5")
	)
	(via
		(at 148.594064 -49.574704)
		(size 0.508)
		(drill 0.254)
		(layers "F.Cu" "B.Cu")
		(net "P3V3_SSD5")
	)
	(via
		(at 163.333176 -26.971244)
		(size 0.508)
		(drill 0.254)
		(layers "F.Cu" "B.Cu")
		(net "P3V3_SSD5")
	)
	(via
		(at 134.241286 -37.47516)
		(size 0.508)
		(drill 0.254)
		(layers "F.Cu" "B.Cu")
		(net "P3V3_SSD5")
	)
	(via
		(at 166.76624 -17.419574)
		(size 0.508)
		(drill 0.254)
		(layers "F.Cu" "B.Cu")
		(net "P3V3_SSD5")
	)
	(via
		(at 146.41068 -30.376876)
		(size 0.508)
		(drill 0.254)
		(layers "F.Cu" "B.Cu")
		(net "P3V3_SSD5")
	)
	(via
		(at 149.864064 -49.574704)
		(size 0.508)
		(drill 0.254)
		(layers "F.Cu" "B.Cu")
		(net "P3V3_SSD5")
	)
	(via
		(at 148.594064 -50.478182)
		(size 0.6604)
		(drill 0.3302)
		(layers "F.Cu" "B.Cu")
		(net "P3V3_SSD5")
	)
	(via
		(at 160.669986 -25.031954)
		(size 0.508)
		(drill 0.254)
		(layers "F.Cu" "B.Cu")
		(net "P3V3_SSD5")
	)
	(via
		(at 148.614638 -53.469286)
		(size 0.508)
		(drill 0.254)
		(layers "F.Cu" "B.Cu")
		(net "P3V3_SSD5")
	)
	(via
		(at 146.41068 -29.614876)
		(size 0.508)
		(drill 0.254)
		(layers "F.Cu" "B.Cu")
		(net "P3V3_SSD5")
	)
	(via
		(at 167.006778 -14.735302)
		(size 0.508)
		(drill 0.254)
		(layers "F.Cu" "B.Cu")
		(net "P3V3_SSD5")
	)
	(via
		(at 161.571686 -26.360882)
		(size 0.508)
		(drill 0.254)
		(layers "F.Cu" "B.Cu")
		(net "P3V3_SSD5")
	)
	(via
		(at 166.769542 -20.467574)
		(size 0.508)
		(drill 0.254)
		(layers "F.Cu" "B.Cu")
		(net "P3V3_SSD5")
	)
	(via
		(at 148.853398 -24.807418)
		(size 0.508)
		(drill 0.254)
		(layers "F.Cu" "B.Cu")
		(net "P3V3_SSD5")
	)
	(via
		(at 150.376636 -50.608992)
		(size 0.508)
		(drill 0.254)
		(layers "F.Cu" "B.Cu")
		(net "P3V3_SSD5")
	)
	(via
		(at 149.614636 -50.608992)
		(size 0.508)
		(drill 0.254)
		(layers "F.Cu" "B.Cu")
		(net "P3V3_SSD5")
	)
	(via
		(at 150.499064 -49.574704)
		(size 0.508)
		(drill 0.254)
		(layers "F.Cu" "B.Cu")
		(net "P3V3_SSD5")
	)
	(segment
		(start 148.594064 -49.574704)
		(end 148.594064 -50.478182)
		(width 0.13208)
		(layer "B.Cu")
		(net "P3V3_SSD5")
	)
	(segment
		(start 143.863822 -37.872924)
		(end 137.154158 -37.872924)
		(width 0.508)
		(layer "In9.Cu")
		(net "P3V3_SSD5")
	)
	(segment
		(start 137.154158 -37.872924)
		(end 136.704324 -38.322758)
		(width 0.508)
		(layer "In9.Cu")
		(net "P3V3_SSD5")
	)
	(segment
		(start 136.704324 -38.322758)
		(end 135.088884 -38.322758)
		(width 0.508)
		(layer "In9.Cu")
		(net "P3V3_SSD5")
	)
	(segment
		(start 135.088884 -38.322758)
		(end 134.241286 -37.47516)
		(width 0.508)
		(layer "In9.Cu")
		(net "P3V3_SSD5")
	)
	(segment
		(start 231.60863 -93.266514)
		(end 230.164894 -93.266514)
		(width 0.13208)
		(layer "F.Cu")
		(net "PEX_USB_HUB_PGANG")
	)
	(segment
		(start 229.852982 -92.954602)
		(end 229.852982 -92.701618)
		(width 0.13208)
		(layer "F.Cu")
		(net "PEX_USB_HUB_PGANG")
	)
	(segment
		(start 230.164894 -93.266514)
		(end 229.852982 -92.954602)
		(width 0.13208)
		(layer "F.Cu")
		(net "PEX_USB_HUB_PGANG")
	)
	(segment
		(start 229.852982 -92.701618)
		(end 229.19309 -92.041726)
		(width 0.13208)
		(layer "F.Cu")
		(net "PEX_USB_HUB_PGANG")
	)
	(via
		(at 230.164894 -93.266514)
		(size 0.508)
		(drill 0.254)
		(layers "F.Cu" "B.Cu")
		(net "PEX_USB_HUB_PGANG")
	)
	(segment
		(start 337.495642 -90.383614)
		(end 337.215226 -90.66403)
		(width 0.1778)
		(layer "F.Cu")
		(net "P3V3_VDDAR_9ZXL0851_8_15")
	)
	(segment
		(start 333.433674 -88.402414)
		(end 333.671672 -88.164416)
		(width 0.1778)
		(layer "F.Cu")
		(net "P3V3_VDDAR_9ZXL0851_8_15")
	)
	(segment
		(start 333.671672 -88.164416)
		(end 335.145634 -88.164416)
		(width 0.1778)
		(layer "F.Cu")
		(net "P3V3_VDDAR_9ZXL0851_8_15")
	)
	(segment
		(start 337.495642 -89.714324)
		(end 337.495642 -90.383614)
		(width 0.1778)
		(layer "F.Cu")
		(net "P3V3_VDDAR_9ZXL0851_8_15")
	)
	(segment
		(start 337.215226 -90.66403)
		(end 336.928206 -90.66403)
		(width 0.1778)
		(layer "F.Cu")
		(net "P3V3_VDDAR_9ZXL0851_8_15")
	)
	(via
		(at 336.928206 -90.66403)
		(size 0.508)
		(drill 0.254)
		(layers "F.Cu" "B.Cu")
		(net "P3V3_VDDAR_9ZXL0851_8_15")
	)
	(via
		(at 335.51495 -90.585544)
		(size 0.6604)
		(drill 0.3302)
		(layers "F.Cu" "B.Cu")
		(net "P3V3_VDDAR_9ZXL0851_8_15")
	)
	(via
		(at 334.214978 -89.86139)
		(size 0.6604)
		(drill 0.3302)
		(layers "F.Cu" "B.Cu")
		(net "P3V3_VDDAR_9ZXL0851_8_15")
	)
	(via
		(at 332.235048 -88.419686)
		(size 0.508)
		(drill 0.254)
		(layers "F.Cu" "B.Cu")
		(net "P3V3_VDDAR_9ZXL0851_8_15")
	)
	(segment
		(start 335.32953 -87.890604)
		(end 332.76413 -87.890604)
		(width 0.254)
		(layer "B.Cu")
		(net "P3V3_VDDAR_9ZXL0851_8_15")
	)
	(segment
		(start 332.76413 -87.890604)
		(end 332.235048 -88.419686)
		(width 0.254)
		(layer "B.Cu")
		(net "P3V3_VDDAR_9ZXL0851_8_15")
	)
	(segment
		(start 336.928206 -89.827354)
		(end 336.928206 -90.66403)
		(width 0.254)
		(layer "B.Cu")
		(net "P3V3_VDDAR_9ZXL0851_8_15")
	)
	(segment
		(start 336.928206 -90.66403)
		(end 336.616802 -90.975434)
		(width 0.508)
		(layer "In7.Cu")
		(net "P3V3_VDDAR_9ZXL0851_8_15")
	)
	(segment
		(start 335.43367 -90.975434)
		(end 333.982314 -89.524078)
		(width 0.508)
		(layer "In7.Cu")
		(net "P3V3_VDDAR_9ZXL0851_8_15")
	)
	(segment
		(start 333.33944 -89.524078)
		(end 332.235048 -88.419686)
		(width 0.508)
		(layer "In7.Cu")
		(net "P3V3_VDDAR_9ZXL0851_8_15")
	)
	(segment
		(start 336.616802 -90.975434)
		(end 335.43367 -90.975434)
		(width 0.508)
		(layer "In7.Cu")
		(net "P3V3_VDDAR_9ZXL0851_8_15")
	)
	(segment
		(start 333.982314 -89.524078)
		(end 333.33944 -89.524078)
		(width 0.508)
		(layer "In7.Cu")
		(net "P3V3_VDDAR_9ZXL0851_8_15")
	)
	(segment
		(start 348.493842 -223.987106)
		(end 348.893638 -224.386902)
		(width 0.13208)
		(layer "F.Cu")
		(net "NIC1_CLK_EN_N")
	)
	(segment
		(start 357.61295 -227.584)
		(end 356.997 -227.584)
		(width 0.13208)
		(layer "F.Cu")
		(net "NIC1_CLK_EN_N")
	)
	(via
		(at 356.997 -227.584)
		(size 0.508)
		(drill 0.254)
		(layers "F.Cu" "B.Cu")
		(net "NIC1_CLK_EN_N")
	)
	(via
		(at 348.893638 -224.386902)
		(size 0.4572)
		(drill 0.254)
		(layers "F.Cu" "B.Cu")
		(net "NIC1_CLK_EN_N")
	)
	(segment
		(start 353.942142 -226.156774)
		(end 352.945954 -226.156774)
		(width 0.15494)
		(layer "In5.Cu")
		(net "NIC1_CLK_EN_N")
	)
	(segment
		(start 355.369368 -227.584)
		(end 353.942142 -226.156774)
		(width 0.15494)
		(layer "In5.Cu")
		(net "NIC1_CLK_EN_N")
	)
	(segment
		(start 349.291148 -224.784412)
		(end 348.893638 -224.386902)
		(width 0.0889)
		(layer "In5.Cu")
		(net "NIC1_CLK_EN_N")
	)
	(segment
		(start 356.997 -227.584)
		(end 355.369368 -227.584)
		(width 0.15494)
		(layer "In5.Cu")
		(net "NIC1_CLK_EN_N")
	)
	(segment
		(start 352.945954 -226.156774)
		(end 351.573592 -224.784412)
		(width 0.15494)
		(layer "In5.Cu")
		(net "NIC1_CLK_EN_N")
	)
	(segment
		(start 351.573592 -224.784412)
		(end 349.291148 -224.784412)
		(width 0.0889)
		(layer "In5.Cu")
		(net "NIC1_CLK_EN_N")
	)
	(segment
		(start 330.775564 -121.509028)
		(end 330.436474 -121.509028)
		(width 0.13208)
		(layer "F.Cu")
		(net "P3V3_NIC5_OCP")
	)
	(segment
		(start 328.971402 -121.041922)
		(end 329.969368 -121.041922)
		(width 0.13208)
		(layer "F.Cu")
		(net "P3V3_NIC5_OCP")
	)
	(segment
		(start 330.436474 -121.509028)
		(end 330.166218 -121.238772)
		(width 0.13208)
		(layer "F.Cu")
		(net "P3V3_NIC5_OCP")
	)
	(segment
		(start 329.969368 -121.041922)
		(end 330.166218 -121.238772)
		(width 0.13208)
		(layer "F.Cu")
		(net "P3V3_NIC5_OCP")
	)
	(via
		(at 330.166218 -121.238772)
		(size 0.508)
		(drill 0.254)
		(layers "F.Cu" "B.Cu")
		(net "P3V3_NIC5_OCP")
	)
	(segment
		(start 61.073284 -58.166)
		(end 61.190886 -58.449718)
		(width 0.2032)
		(layer "F.Cu")
		(net "P3V3_SSD2_SS")
	)
	(segment
		(start 61.190886 -58.449718)
		(end 61.19495 -58.453782)
		(width 0.2032)
		(layer "F.Cu")
		(net "P3V3_SSD2_SS")
	)
	(segment
		(start 60.14085 -57.233566)
		(end 61.073284 -58.166)
		(width 0.2032)
		(layer "F.Cu")
		(net "P3V3_SSD2_SS")
	)
	(segment
		(start 61.19495 -58.453782)
		(end 61.19495 -59.177936)
		(width 0.2032)
		(layer "F.Cu")
		(net "P3V3_SSD2_SS")
	)
	(segment
		(start 60.14085 -57.16397)
		(end 60.14085 -57.233566)
		(width 0.2032)
		(layer "F.Cu")
		(net "P3V3_SSD2_SS")
	)
	(via
		(at 61.190886 -58.449718)
		(size 0.508)
		(drill 0.254)
		(layers "F.Cu" "B.Cu")
		(net "P3V3_SSD2_SS")
	)
	(segment
		(start 272.374868 -299.224954)
		(end 272.849848 -298.749974)
		(width 0.1143)
		(layer "F.Cu")
		(net "CLK_100M_DB800ZL_PEX2_S0_R_DP")
	)
	(segment
		(start 272.849848 -298.749974)
		(end 272.849848 -298.74972)
		(width 0.1143)
		(layer "F.Cu")
		(net "CLK_100M_DB800ZL_PEX2_S0_R_DP")
	)
	(via
		(at 234.8611 -337.266026)
		(size 0.508)
		(drill 0.254)
		(layers "F.Cu" "B.Cu")
		(net "CLK_100M_DB800ZL_PEX2_S0_R_DP")
	)
	(via
		(at 272.374868 -299.224954)
		(size 0.4064)
		(drill 0.2032)
		(layers "F.Cu" "B.Cu")
		(net "CLK_100M_DB800ZL_PEX2_S0_R_DP")
	)
	(segment
		(start 121.861072 -333.650082)
		(end 114.536982 -340.974172)
		(width 0.1143)
		(layer "B.Cu")
		(net "CLK_100M_DB800ZL_PEX2_S0_R_DP")
	)
	(segment
		(start 98.620326 -333.4004)
		(end 98.95332 -333.067406)
		(width 0.1143)
		(layer "B.Cu")
		(net "CLK_100M_DB800ZL_PEX2_S0_R_DP")
	)
	(segment
		(start 96.945958 -336.404712)
		(end 96.945958 -333.7433)
		(width 0.1143)
		(layer "B.Cu")
		(net "CLK_100M_DB800ZL_PEX2_S0_R_DP")
	)
	(segment
		(start 234.6198 -337.024726)
		(end 224.675192 -337.024726)
		(width 0.1143)
		(layer "B.Cu")
		(net "CLK_100M_DB800ZL_PEX2_S0_R_DP")
	)
	(segment
		(start 221.300548 -333.650082)
		(end 121.861072 -333.650082)
		(width 0.1143)
		(layer "B.Cu")
		(net "CLK_100M_DB800ZL_PEX2_S0_R_DP")
	)
	(segment
		(start 97.288858 -333.4004)
		(end 98.620326 -333.4004)
		(width 0.1143)
		(layer "B.Cu")
		(net "CLK_100M_DB800ZL_PEX2_S0_R_DP")
	)
	(segment
		(start 114.536982 -340.974172)
		(end 101.515418 -340.974172)
		(width 0.1143)
		(layer "B.Cu")
		(net "CLK_100M_DB800ZL_PEX2_S0_R_DP")
	)
	(segment
		(start 224.675192 -337.024726)
		(end 221.300548 -333.650082)
		(width 0.1143)
		(layer "B.Cu")
		(net "CLK_100M_DB800ZL_PEX2_S0_R_DP")
	)
	(segment
		(start 96.945958 -333.7433)
		(end 97.288858 -333.4004)
		(width 0.1143)
		(layer "B.Cu")
		(net "CLK_100M_DB800ZL_PEX2_S0_R_DP")
	)
	(segment
		(start 101.515418 -340.974172)
		(end 96.945958 -336.404712)
		(width 0.1143)
		(layer "B.Cu")
		(net "CLK_100M_DB800ZL_PEX2_S0_R_DP")
	)
	(segment
		(start 234.8611 -337.266026)
		(end 234.6198 -337.024726)
		(width 0.1143)
		(layer "B.Cu")
		(net "CLK_100M_DB800ZL_PEX2_S0_R_DP")
	)
	(segment
		(start 271.713452 -299.800264)
		(end 268.190726 -299.800264)
		(width 0.0889)
		(layer "In9.Cu")
		(net "CLK_100M_DB800ZL_PEX2_S0_R_DP")
	)
	(segment
		(start 242.269518 -329.221084)
		(end 242.269518 -331.585824)
		(width 0.1397)
		(layer "In9.Cu")
		(net "CLK_100M_DB800ZL_PEX2_S0_R_DP")
	)
	(segment
		(start 272.374868 -299.224954)
		(end 272.084038 -299.224954)
		(width 0.0889)
		(layer "In9.Cu")
		(net "CLK_100M_DB800ZL_PEX2_S0_R_DP")
	)
	(segment
		(start 236.856016 -336.999326)
		(end 235.1278 -336.999326)
		(width 0.1397)
		(layer "In9.Cu")
		(net "CLK_100M_DB800ZL_PEX2_S0_R_DP")
	)
	(segment
		(start 235.1278 -336.999326)
		(end 234.8611 -337.266026)
		(width 0.1397)
		(layer "In9.Cu")
		(net "CLK_100M_DB800ZL_PEX2_S0_R_DP")
	)
	(segment
		(start 268.190726 -299.800264)
		(end 267.876782 -300.114208)
		(width 0.0889)
		(layer "In9.Cu")
		(net "CLK_100M_DB800ZL_PEX2_S0_R_DP")
	)
	(segment
		(start 242.269518 -331.585824)
		(end 236.856016 -336.999326)
		(width 0.1397)
		(layer "In9.Cu")
		(net "CLK_100M_DB800ZL_PEX2_S0_R_DP")
	)
	(segment
		(start 272.084038 -299.224954)
		(end 271.995138 -299.313854)
		(width 0.0889)
		(layer "In9.Cu")
		(net "CLK_100M_DB800ZL_PEX2_S0_R_DP")
	)
	(segment
		(start 267.588238 -300.40326)
		(end 267.588238 -300.50232)
		(width 0.0889)
		(layer "In9.Cu")
		(net "CLK_100M_DB800ZL_PEX2_S0_R_DP")
	)
	(segment
		(start 267.876782 -300.114208)
		(end 267.876782 -300.114716)
		(width 0.0889)
		(layer "In9.Cu")
		(net "CLK_100M_DB800ZL_PEX2_S0_R_DP")
	)
	(segment
		(start 271.995138 -299.518578)
		(end 271.713452 -299.800264)
		(width 0.0889)
		(layer "In9.Cu")
		(net "CLK_100M_DB800ZL_PEX2_S0_R_DP")
	)
	(segment
		(start 267.876782 -300.114716)
		(end 267.588238 -300.40326)
		(width 0.0889)
		(layer "In9.Cu")
		(net "CLK_100M_DB800ZL_PEX2_S0_R_DP")
	)
	(segment
		(start 271.995138 -299.313854)
		(end 271.995138 -299.518578)
		(width 0.0889)
		(layer "In9.Cu")
		(net "CLK_100M_DB800ZL_PEX2_S0_R_DP")
	)
	(segment
		(start 267.572744 -300.517814)
		(end 252.481842 -315.608716)
		(width 0.1397)
		(layer "In9.Cu")
		(net "CLK_100M_DB800ZL_PEX2_S0_R_DP")
	)
	(segment
		(start 267.588238 -300.50232)
		(end 267.572744 -300.517814)
		(width 0.0889)
		(layer "In9.Cu")
		(net "CLK_100M_DB800ZL_PEX2_S0_R_DP")
	)
	(segment
		(start 252.481842 -315.608716)
		(end 252.481842 -319.00876)
		(width 0.1397)
		(layer "In9.Cu")
		(net "CLK_100M_DB800ZL_PEX2_S0_R_DP")
	)
	(segment
		(start 252.481842 -319.00876)
		(end 242.269518 -329.221084)
		(width 0.1397)
		(layer "In9.Cu")
		(net "CLK_100M_DB800ZL_PEX2_S0_R_DP")
	)
	(segment
		(start 38.20795 -159.4104)
		(end 38.20795 -160.380934)
		(width 0.13208)
		(layer "F.Cu")
		(net "NIC0_MAIN_PWR_EN")
	)
	(segment
		(start 37.965126 -161.08426)
		(end 38.20795 -160.841436)
		(width 0.13208)
		(layer "F.Cu")
		(net "NIC0_MAIN_PWR_EN")
	)
	(segment
		(start 350.093788 -225.587052)
		(end 350.493584 -225.986848)
		(width 0.13208)
		(layer "F.Cu")
		(net "NIC0_MAIN_PWR_EN")
	)
	(segment
		(start 38.20795 -160.841436)
		(end 38.20795 -160.380934)
		(width 0.13208)
		(layer "F.Cu")
		(net "NIC0_MAIN_PWR_EN")
	)
	(via
		(at 51.573684 -176.203864)
		(size 0.508)
		(drill 0.254)
		(layers "F.Cu" "B.Cu")
		(net "NIC0_MAIN_PWR_EN")
	)
	(via
		(at 37.965126 -161.08426)
		(size 0.508)
		(drill 0.254)
		(layers "F.Cu" "B.Cu")
		(net "NIC0_MAIN_PWR_EN")
	)
	(via
		(at 350.493584 -225.986848)
		(size 0.4572)
		(drill 0.254)
		(layers "F.Cu" "B.Cu")
		(net "NIC0_MAIN_PWR_EN")
	)
	(segment
		(start 37.965126 -161.08426)
		(end 37.965126 -161.917126)
		(width 0.13208)
		(layer "B.Cu")
		(net "NIC0_MAIN_PWR_EN")
	)
	(segment
		(start 37.965126 -161.917126)
		(end 50.86096 -174.81296)
		(width 0.13208)
		(layer "B.Cu")
		(net "NIC0_MAIN_PWR_EN")
	)
	(segment
		(start 50.86096 -174.81296)
		(end 50.86096 -175.49114)
		(width 0.13208)
		(layer "B.Cu")
		(net "NIC0_MAIN_PWR_EN")
	)
	(segment
		(start 50.86096 -175.49114)
		(end 51.573684 -176.203864)
		(width 0.13208)
		(layer "B.Cu")
		(net "NIC0_MAIN_PWR_EN")
	)
	(segment
		(start 369.219734 -183.805576)
		(end 369.219734 -180.37048)
		(width 0.15494)
		(layer "In15.Cu")
		(net "NIC0_MAIN_PWR_EN")
	)
	(segment
		(start 285.891732 -171.68114)
		(end 257.779266 -171.68114)
		(width 0.15494)
		(layer "In15.Cu")
		(net "NIC0_MAIN_PWR_EN")
	)
	(segment
		(start 357.76916 -231.862884)
		(end 358.84739 -232.941114)
		(width 0.15494)
		(layer "In15.Cu")
		(net "NIC0_MAIN_PWR_EN")
	)
	(segment
		(start 335.616042 -170.974512)
		(end 335.22666 -170.58513)
		(width 0.15494)
		(layer "In15.Cu")
		(net "NIC0_MAIN_PWR_EN")
	)
	(segment
		(start 367.34623 -232.941114)
		(end 372.366286 -227.921058)
		(width 0.15494)
		(layer "In15.Cu")
		(net "NIC0_MAIN_PWR_EN")
	)
	(segment
		(start 113.247932 -187.030868)
		(end 112.38738 -187.89142)
		(width 0.15494)
		(layer "In15.Cu")
		(net "NIC0_MAIN_PWR_EN")
	)
	(segment
		(start 213.926674 -173.808644)
		(end 182.04053 -173.808644)
		(width 0.15494)
		(layer "In15.Cu")
		(net "NIC0_MAIN_PWR_EN")
	)
	(segment
		(start 353.509326 -226.318572)
		(end 354.187506 -226.996752)
		(width 0.15494)
		(layer "In15.Cu")
		(net "NIC0_MAIN_PWR_EN")
	)
	(segment
		(start 350.493584 -225.986848)
		(end 350.871536 -226.3648)
		(width 0.0889)
		(layer "In15.Cu")
		(net "NIC0_MAIN_PWR_EN")
	)
	(segment
		(start 335.22666 -170.58513)
		(end 286.987742 -170.58513)
		(width 0.15494)
		(layer "In15.Cu")
		(net "NIC0_MAIN_PWR_EN")
	)
	(segment
		(start 124.674122 -187.030868)
		(end 113.247932 -187.030868)
		(width 0.15494)
		(layer "In15.Cu")
		(net "NIC0_MAIN_PWR_EN")
	)
	(segment
		(start 141.649958 -187.37453)
		(end 139.154916 -189.869572)
		(width 0.15494)
		(layer "In15.Cu")
		(net "NIC0_MAIN_PWR_EN")
	)
	(segment
		(start 356.916482 -173.50613)
		(end 355.809042 -174.61357)
		(width 0.15494)
		(layer "In15.Cu")
		(net "NIC0_MAIN_PWR_EN")
	)
	(segment
		(start 351.607628 -226.318572)
		(end 353.509326 -226.318572)
		(width 0.15494)
		(layer "In15.Cu")
		(net "NIC0_MAIN_PWR_EN")
	)
	(segment
		(start 355.809042 -174.61357)
		(end 347.229684 -174.61357)
		(width 0.15494)
		(layer "In15.Cu")
		(net "NIC0_MAIN_PWR_EN")
	)
	(segment
		(start 106.089196 -187.89142)
		(end 101.94925 -186.176666)
		(width 0.15494)
		(layer "In15.Cu")
		(net "NIC0_MAIN_PWR_EN")
	)
	(segment
		(start 354.187506 -228.048058)
		(end 357.76916 -231.629712)
		(width 0.15494)
		(layer "In15.Cu")
		(net "NIC0_MAIN_PWR_EN")
	)
	(segment
		(start 354.187506 -226.996752)
		(end 354.187506 -228.048058)
		(width 0.15494)
		(layer "In15.Cu")
		(net "NIC0_MAIN_PWR_EN")
	)
	(segment
		(start 357.76916 -231.629712)
		(end 357.76916 -231.862884)
		(width 0.15494)
		(layer "In15.Cu")
		(net "NIC0_MAIN_PWR_EN")
	)
	(segment
		(start 360.37266 -173.50613)
		(end 356.916482 -173.50613)
		(width 0.15494)
		(layer "In15.Cu")
		(net "NIC0_MAIN_PWR_EN")
	)
	(segment
		(start 372.366286 -186.952128)
		(end 369.219734 -183.805576)
		(width 0.15494)
		(layer "In15.Cu")
		(net "NIC0_MAIN_PWR_EN")
	)
	(segment
		(start 178.56073 -175.394366)
		(end 166.580566 -187.37453)
		(width 0.15494)
		(layer "In15.Cu")
		(net "NIC0_MAIN_PWR_EN")
	)
	(segment
		(start 235.583476 -173.4312)
		(end 233.828336 -171.67606)
		(width 0.15494)
		(layer "In15.Cu")
		(net "NIC0_MAIN_PWR_EN")
	)
	(segment
		(start 180.817774 -175.0314)
		(end 179.941728 -175.394366)
		(width 0.15494)
		(layer "In15.Cu")
		(net "NIC0_MAIN_PWR_EN")
	)
	(segment
		(start 363.688376 -174.839122)
		(end 361.705652 -174.839122)
		(width 0.15494)
		(layer "In15.Cu")
		(net "NIC0_MAIN_PWR_EN")
	)
	(segment
		(start 347.229684 -174.61357)
		(end 344.0938 -171.477686)
		(width 0.15494)
		(layer "In15.Cu")
		(net "NIC0_MAIN_PWR_EN")
	)
	(segment
		(start 166.580566 -187.37453)
		(end 141.649958 -187.37453)
		(width 0.15494)
		(layer "In15.Cu")
		(net "NIC0_MAIN_PWR_EN")
	)
	(segment
		(start 216.059258 -171.67606)
		(end 213.926674 -173.808644)
		(width 0.15494)
		(layer "In15.Cu")
		(net "NIC0_MAIN_PWR_EN")
	)
	(segment
		(start 233.828336 -171.67606)
		(end 216.059258 -171.67606)
		(width 0.15494)
		(layer "In15.Cu")
		(net "NIC0_MAIN_PWR_EN")
	)
	(segment
		(start 51.730148 -176.0474)
		(end 51.573684 -176.203864)
		(width 0.15494)
		(layer "In15.Cu")
		(net "NIC0_MAIN_PWR_EN")
	)
	(segment
		(start 257.779266 -171.68114)
		(end 255.658366 -173.80204)
		(width 0.15494)
		(layer "In15.Cu")
		(net "NIC0_MAIN_PWR_EN")
	)
	(segment
		(start 372.366286 -227.921058)
		(end 372.366286 -186.952128)
		(width 0.15494)
		(layer "In15.Cu")
		(net "NIC0_MAIN_PWR_EN")
	)
	(segment
		(start 286.987742 -170.58513)
		(end 285.891732 -171.68114)
		(width 0.15494)
		(layer "In15.Cu")
		(net "NIC0_MAIN_PWR_EN")
	)
	(segment
		(start 344.0938 -171.477686)
		(end 341.748364 -171.477686)
		(width 0.15494)
		(layer "In15.Cu")
		(net "NIC0_MAIN_PWR_EN")
	)
	(segment
		(start 369.219734 -180.37048)
		(end 363.688376 -174.839122)
		(width 0.15494)
		(layer "In15.Cu")
		(net "NIC0_MAIN_PWR_EN")
	)
	(segment
		(start 255.658366 -173.80204)
		(end 236.564424 -173.80204)
		(width 0.15494)
		(layer "In15.Cu")
		(net "NIC0_MAIN_PWR_EN")
	)
	(segment
		(start 91.819984 -176.0474)
		(end 51.730148 -176.0474)
		(width 0.15494)
		(layer "In15.Cu")
		(net "NIC0_MAIN_PWR_EN")
	)
	(segment
		(start 236.193584 -173.4312)
		(end 235.583476 -173.4312)
		(width 0.15494)
		(layer "In15.Cu")
		(net "NIC0_MAIN_PWR_EN")
	)
	(segment
		(start 101.94925 -186.176666)
		(end 91.819984 -176.0474)
		(width 0.15494)
		(layer "In15.Cu")
		(net "NIC0_MAIN_PWR_EN")
	)
	(segment
		(start 236.564424 -173.80204)
		(end 236.193584 -173.4312)
		(width 0.15494)
		(layer "In15.Cu")
		(net "NIC0_MAIN_PWR_EN")
	)
	(segment
		(start 179.941728 -175.394366)
		(end 178.56073 -175.394366)
		(width 0.15494)
		(layer "In15.Cu")
		(net "NIC0_MAIN_PWR_EN")
	)
	(segment
		(start 182.04053 -173.808644)
		(end 180.817774 -175.0314)
		(width 0.15494)
		(layer "In15.Cu")
		(net "NIC0_MAIN_PWR_EN")
	)
	(segment
		(start 112.38738 -187.89142)
		(end 106.089196 -187.89142)
		(width 0.15494)
		(layer "In15.Cu")
		(net "NIC0_MAIN_PWR_EN")
	)
	(segment
		(start 351.5614 -226.3648)
		(end 351.607628 -226.318572)
		(width 0.15494)
		(layer "In15.Cu")
		(net "NIC0_MAIN_PWR_EN")
	)
	(segment
		(start 350.871536 -226.3648)
		(end 351.5614 -226.3648)
		(width 0.0889)
		(layer "In15.Cu")
		(net "NIC0_MAIN_PWR_EN")
	)
	(segment
		(start 358.84739 -232.941114)
		(end 367.34623 -232.941114)
		(width 0.15494)
		(layer "In15.Cu")
		(net "NIC0_MAIN_PWR_EN")
	)
	(segment
		(start 139.154916 -189.869572)
		(end 127.512826 -189.869572)
		(width 0.15494)
		(layer "In15.Cu")
		(net "NIC0_MAIN_PWR_EN")
	)
	(segment
		(start 341.24519 -170.974512)
		(end 335.616042 -170.974512)
		(width 0.15494)
		(layer "In15.Cu")
		(net "NIC0_MAIN_PWR_EN")
	)
	(segment
		(start 361.705652 -174.839122)
		(end 360.37266 -173.50613)
		(width 0.15494)
		(layer "In15.Cu")
		(net "NIC0_MAIN_PWR_EN")
	)
	(segment
		(start 127.512826 -189.869572)
		(end 124.674122 -187.030868)
		(width 0.15494)
		(layer "In15.Cu")
		(net "NIC0_MAIN_PWR_EN")
	)
	(segment
		(start 341.748364 -171.477686)
		(end 341.24519 -170.974512)
		(width 0.15494)
		(layer "In15.Cu")
		(net "NIC0_MAIN_PWR_EN")
	)
	(segment
		(start 279.774396 -414.4899)
		(end 280.148284 -414.4899)
		(width 0.13208)
		(layer "F.Cu")
		(net "MB_BIC_MON")
	)
	(segment
		(start 227.467668 -215.104218)
		(end 227.067872 -214.704422)
		(width 0.13208)
		(layer "F.Cu")
		(net "MB_BIC_MON")
	)
	(segment
		(start 280.283412 -414.625028)
		(end 280.283412 -415.241994)
		(width 0.13208)
		(layer "F.Cu")
		(net "MB_BIC_MON")
	)
	(segment
		(start 280.283412 -415.241994)
		(end 280.331418 -415.29)
		(width 0.13208)
		(layer "F.Cu")
		(net "MB_BIC_MON")
	)
	(segment
		(start 280.331418 -415.29)
		(end 280.790396 -415.29)
		(width 0.13208)
		(layer "F.Cu")
		(net "MB_BIC_MON")
	)
	(segment
		(start 280.148284 -414.4899)
		(end 280.283412 -414.625028)
		(width 0.13208)
		(layer "F.Cu")
		(net "MB_BIC_MON")
	)
	(segment
		(start 280.790396 -415.29)
		(end 280.790396 -416.160204)
		(width 0.13208)
		(layer "F.Cu")
		(net "MB_BIC_MON")
	)
	(via
		(at 227.067872 -214.704422)
		(size 0.4572)
		(drill 0.254)
		(layers "F.Cu" "B.Cu")
		(net "MB_BIC_MON")
	)
	(via
		(at 225.6536 -252.623066)
		(size 0.508)
		(drill 0.254)
		(layers "F.Cu" "B.Cu")
		(net "MB_BIC_MON")
	)
	(via
		(at 280.790396 -416.160204)
		(size 0.508)
		(drill 0.254)
		(layers "F.Cu" "B.Cu")
		(net "MB_BIC_MON")
	)
	(via
		(at 226.124516 -212.338412)
		(size 0.6604)
		(drill 0.3302)
		(layers "F.Cu" "B.Cu")
		(net "MB_BIC_MON")
	)
	(segment
		(start 226.124516 -213.156546)
		(end 226.124516 -212.338412)
		(width 0.13208)
		(layer "B.Cu")
		(net "MB_BIC_MON")
	)
	(segment
		(start 226.671632 -213.703662)
		(end 226.124516 -213.156546)
		(width 0.13208)
		(layer "B.Cu")
		(net "MB_BIC_MON")
	)
	(segment
		(start 227.067872 -214.704422)
		(end 226.671632 -214.308182)
		(width 0.0889)
		(layer "B.Cu")
		(net "MB_BIC_MON")
	)
	(segment
		(start 226.671632 -214.308182)
		(end 226.671632 -213.703662)
		(width 0.0889)
		(layer "B.Cu")
		(net "MB_BIC_MON")
	)
	(segment
		(start 221.8944 -220.816932)
		(end 222.529146 -220.182186)
		(width 0.15494)
		(layer "In5.Cu")
		(net "MB_BIC_MON")
	)
	(segment
		(start 221.8944 -225.046032)
		(end 221.8944 -220.816932)
		(width 0.15494)
		(layer "In5.Cu")
		(net "MB_BIC_MON")
	)
	(segment
		(start 225.6536 -252.623066)
		(end 224.92843 -251.897896)
		(width 0.15494)
		(layer "In5.Cu")
		(net "MB_BIC_MON")
	)
	(segment
		(start 222.529146 -220.182186)
		(end 222.529146 -214.427054)
		(width 0.15494)
		(layer "In5.Cu")
		(net "MB_BIC_MON")
	)
	(segment
		(start 222.4786 -226.634548)
		(end 222.4786 -225.630232)
		(width 0.15494)
		(layer "In5.Cu")
		(net "MB_BIC_MON")
	)
	(segment
		(start 225.2218 -234.061)
		(end 225.2218 -229.377748)
		(width 0.15494)
		(layer "In5.Cu")
		(net "MB_BIC_MON")
	)
	(segment
		(start 224.92843 -234.35437)
		(end 225.2218 -234.061)
		(width 0.15494)
		(layer "In5.Cu")
		(net "MB_BIC_MON")
	)
	(segment
		(start 226.667822 -214.304372)
		(end 227.067872 -214.704422)
		(width 0.15494)
		(layer "In5.Cu")
		(net "MB_BIC_MON")
	)
	(segment
		(start 224.1042 -214.304372)
		(end 224.3074 -214.304372)
		(width 0.15494)
		(layer "In5.Cu")
		(net "MB_BIC_MON")
	)
	(segment
		(start 225.2218 -229.377748)
		(end 222.4786 -226.634548)
		(width 0.15494)
		(layer "In5.Cu")
		(net "MB_BIC_MON")
	)
	(segment
		(start 223.947228 -214.1474)
		(end 224.1042 -214.304372)
		(width 0.15494)
		(layer "In5.Cu")
		(net "MB_BIC_MON")
	)
	(segment
		(start 224.3074 -214.304372)
		(end 226.667822 -214.304372)
		(width 0.0889)
		(layer "In5.Cu")
		(net "MB_BIC_MON")
	)
	(segment
		(start 222.8088 -214.1474)
		(end 223.947228 -214.1474)
		(width 0.15494)
		(layer "In5.Cu")
		(net "MB_BIC_MON")
	)
	(segment
		(start 222.529146 -214.427054)
		(end 222.8088 -214.1474)
		(width 0.15494)
		(layer "In5.Cu")
		(net "MB_BIC_MON")
	)
	(segment
		(start 222.4786 -225.630232)
		(end 221.8944 -225.046032)
		(width 0.15494)
		(layer "In5.Cu")
		(net "MB_BIC_MON")
	)
	(segment
		(start 224.92843 -251.897896)
		(end 224.92843 -234.35437)
		(width 0.15494)
		(layer "In5.Cu")
		(net "MB_BIC_MON")
	)
	(segment
		(start 233.3498 -282.516072)
		(end 233.3498 -331.393546)
		(width 0.15494)
		(layer "In7.Cu")
		(net "MB_BIC_MON")
	)
	(segment
		(start 225.6536 -252.623066)
		(end 226.090734 -253.0602)
		(width 0.15494)
		(layer "In7.Cu")
		(net "MB_BIC_MON")
	)
	(segment
		(start 232.240074 -258.224528)
		(end 232.240074 -281.406346)
		(width 0.15494)
		(layer "In7.Cu")
		(net "MB_BIC_MON")
	)
	(segment
		(start 266.79398 -373.6721)
		(end 265.06678 -375.3993)
		(width 0.15494)
		(layer "In7.Cu")
		(net "MB_BIC_MON")
	)
	(segment
		(start 233.3498 -331.393546)
		(end 235.991654 -334.0354)
		(width 0.15494)
		(layer "In7.Cu")
		(net "MB_BIC_MON")
	)
	(segment
		(start 226.090734 -253.0602)
		(end 227.075746 -253.0602)
		(width 0.15494)
		(layer "In7.Cu")
		(net "MB_BIC_MON")
	)
	(segment
		(start 235.991654 -334.0354)
		(end 251.892308 -334.0354)
		(width 0.15494)
		(layer "In7.Cu")
		(net "MB_BIC_MON")
	)
	(segment
		(start 251.892308 -334.0354)
		(end 254.5715 -336.714592)
		(width 0.15494)
		(layer "In7.Cu")
		(net "MB_BIC_MON")
	)
	(segment
		(start 273.929094 -404.161498)
		(end 273.929094 -414.721294)
		(width 0.15494)
		(layer "In7.Cu")
		(net "MB_BIC_MON")
	)
	(segment
		(start 255.053338 -337.877658)
		(end 255.053592 -337.878166)
		(width 0.15494)
		(layer "In7.Cu")
		(net "MB_BIC_MON")
	)
	(segment
		(start 266.79398 -361.2515)
		(end 266.79398 -373.6721)
		(width 0.15494)
		(layer "In7.Cu")
		(net "MB_BIC_MON")
	)
	(segment
		(start 227.075746 -253.0602)
		(end 232.240074 -258.224528)
		(width 0.15494)
		(layer "In7.Cu")
		(net "MB_BIC_MON")
	)
	(segment
		(start 273.929094 -414.721294)
		(end 276.0218 -416.814)
		(width 0.15494)
		(layer "In7.Cu")
		(net "MB_BIC_MON")
	)
	(segment
		(start 275.17598 -391.6299)
		(end 275.17598 -402.914612)
		(width 0.15494)
		(layer "In7.Cu")
		(net "MB_BIC_MON")
	)
	(segment
		(start 263.61898 -346.4433)
		(end 263.61898 -358.0765)
		(width 0.15494)
		(layer "In7.Cu")
		(net "MB_BIC_MON")
	)
	(segment
		(start 265.06678 -375.3993)
		(end 265.06678 -381.5207)
		(width 0.15494)
		(layer "In7.Cu")
		(net "MB_BIC_MON")
	)
	(segment
		(start 275.17598 -402.914612)
		(end 273.929094 -404.161498)
		(width 0.15494)
		(layer "In7.Cu")
		(net "MB_BIC_MON")
	)
	(segment
		(start 280.1366 -416.814)
		(end 280.790396 -416.160204)
		(width 0.15494)
		(layer "In7.Cu")
		(net "MB_BIC_MON")
	)
	(segment
		(start 276.0218 -416.814)
		(end 280.1366 -416.814)
		(width 0.15494)
		(layer "In7.Cu")
		(net "MB_BIC_MON")
	)
	(segment
		(start 232.240074 -281.406346)
		(end 233.3498 -282.516072)
		(width 0.15494)
		(layer "In7.Cu")
		(net "MB_BIC_MON")
	)
	(segment
		(start 254.5715 -336.714592)
		(end 255.053338 -337.877658)
		(width 0.15494)
		(layer "In7.Cu")
		(net "MB_BIC_MON")
	)
	(segment
		(start 265.06678 -381.5207)
		(end 275.17598 -391.6299)
		(width 0.15494)
		(layer "In7.Cu")
		(net "MB_BIC_MON")
	)
	(segment
		(start 255.053592 -337.878166)
		(end 263.61898 -346.4433)
		(width 0.15494)
		(layer "In7.Cu")
		(net "MB_BIC_MON")
	)
	(segment
		(start 263.61898 -358.0765)
		(end 266.79398 -361.2515)
		(width 0.15494)
		(layer "In7.Cu")
		(net "MB_BIC_MON")
	)
	(segment
		(start 350.093788 -219.987114)
		(end 350.493584 -220.38691)
		(width 0.13208)
		(layer "F.Cu")
		(net "NIC5_MAIN_PWR_EN")
	)
	(via
		(at 370.807742 -99.49307)
		(size 0.508)
		(drill 0.254)
		(layers "F.Cu" "B.Cu")
		(net "NIC5_MAIN_PWR_EN")
	)
	(via
		(at 302.703992 -99.739704)
		(size 0.508)
		(drill 0.254)
		(layers "F.Cu" "B.Cu")
		(net "NIC5_MAIN_PWR_EN")
	)
	(via
		(at 350.493584 -220.38691)
		(size 0.4572)
		(drill 0.254)
		(layers "F.Cu" "B.Cu")
		(net "NIC5_MAIN_PWR_EN")
	)
	(segment
		(start 303.554892 -98.552)
		(end 302.703992 -98.552)
		(width 0.13208)
		(layer "B.Cu")
		(net "NIC5_MAIN_PWR_EN")
	)
	(segment
		(start 302.703992 -98.552)
		(end 302.703992 -99.739704)
		(width 0.13208)
		(layer "B.Cu")
		(net "NIC5_MAIN_PWR_EN")
	)
	(segment
		(start 370.807742 -101.173534)
		(end 371.48008 -101.845872)
		(width 0.15494)
		(layer "In5.Cu")
		(net "NIC5_MAIN_PWR_EN")
	)
	(segment
		(start 360.557572 -220.98)
		(end 358.6226 -220.98)
		(width 0.15494)
		(layer "In5.Cu")
		(net "NIC5_MAIN_PWR_EN")
	)
	(segment
		(start 373.517668 -210.815428)
		(end 366.09401 -218.239086)
		(width 0.15494)
		(layer "In5.Cu")
		(net "NIC5_MAIN_PWR_EN")
	)
	(segment
		(start 358.492552 -221.110048)
		(end 354.35921 -221.110048)
		(width 0.15494)
		(layer "In5.Cu")
		(net "NIC5_MAIN_PWR_EN")
	)
	(segment
		(start 371.48008 -110.457996)
		(end 373.376952 -112.354868)
		(width 0.15494)
		(layer "In5.Cu")
		(net "NIC5_MAIN_PWR_EN")
	)
	(segment
		(start 372.482364 -180.485542)
		(end 372.671594 -180.674772)
		(width 0.15494)
		(layer "In5.Cu")
		(net "NIC5_MAIN_PWR_EN")
	)
	(segment
		(start 370.807742 -99.49307)
		(end 370.807742 -101.173534)
		(width 0.15494)
		(layer "In5.Cu")
		(net "NIC5_MAIN_PWR_EN")
	)
	(segment
		(start 373.376952 -168.024556)
		(end 372.482364 -168.919144)
		(width 0.15494)
		(layer "In5.Cu")
		(net "NIC5_MAIN_PWR_EN")
	)
	(segment
		(start 374.231916 -190.68034)
		(end 373.568722 -191.343534)
		(width 0.15494)
		(layer "In5.Cu")
		(net "NIC5_MAIN_PWR_EN")
	)
	(segment
		(start 371.48008 -101.845872)
		(end 371.48008 -110.457996)
		(width 0.15494)
		(layer "In5.Cu")
		(net "NIC5_MAIN_PWR_EN")
	)
	(segment
		(start 373.517668 -208.647284)
		(end 373.517668 -210.815428)
		(width 0.15494)
		(layer "In5.Cu")
		(net "NIC5_MAIN_PWR_EN")
	)
	(segment
		(start 354.35921 -221.110048)
		(end 353.636072 -220.38691)
		(width 0.15494)
		(layer "In5.Cu")
		(net "NIC5_MAIN_PWR_EN")
	)
	(segment
		(start 372.482364 -168.919144)
		(end 372.482364 -180.485542)
		(width 0.15494)
		(layer "In5.Cu")
		(net "NIC5_MAIN_PWR_EN")
	)
	(segment
		(start 373.092218 -189.667896)
		(end 373.942102 -189.667896)
		(width 0.15494)
		(layer "In5.Cu")
		(net "NIC5_MAIN_PWR_EN")
	)
	(segment
		(start 373.568722 -191.343534)
		(end 373.568722 -208.59623)
		(width 0.15494)
		(layer "In5.Cu")
		(net "NIC5_MAIN_PWR_EN")
	)
	(segment
		(start 363.298486 -218.239086)
		(end 360.557572 -220.98)
		(width 0.15494)
		(layer "In5.Cu")
		(net "NIC5_MAIN_PWR_EN")
	)
	(segment
		(start 353.636072 -220.38691)
		(end 350.493584 -220.38691)
		(width 0.15494)
		(layer "In5.Cu")
		(net "NIC5_MAIN_PWR_EN")
	)
	(segment
		(start 358.6226 -220.98)
		(end 358.492552 -221.110048)
		(width 0.15494)
		(layer "In5.Cu")
		(net "NIC5_MAIN_PWR_EN")
	)
	(segment
		(start 373.942102 -189.667896)
		(end 374.231916 -189.95771)
		(width 0.15494)
		(layer "In5.Cu")
		(net "NIC5_MAIN_PWR_EN")
	)
	(segment
		(start 372.671594 -189.247272)
		(end 373.092218 -189.667896)
		(width 0.15494)
		(layer "In5.Cu")
		(net "NIC5_MAIN_PWR_EN")
	)
	(segment
		(start 373.376952 -112.354868)
		(end 373.376952 -168.024556)
		(width 0.15494)
		(layer "In5.Cu")
		(net "NIC5_MAIN_PWR_EN")
	)
	(segment
		(start 374.231916 -189.95771)
		(end 374.231916 -190.68034)
		(width 0.15494)
		(layer "In5.Cu")
		(net "NIC5_MAIN_PWR_EN")
	)
	(segment
		(start 366.09401 -218.239086)
		(end 363.298486 -218.239086)
		(width 0.15494)
		(layer "In5.Cu")
		(net "NIC5_MAIN_PWR_EN")
	)
	(segment
		(start 372.671594 -180.674772)
		(end 372.671594 -189.247272)
		(width 0.15494)
		(layer "In5.Cu")
		(net "NIC5_MAIN_PWR_EN")
	)
	(segment
		(start 373.568722 -208.59623)
		(end 373.517668 -208.647284)
		(width 0.15494)
		(layer "In5.Cu")
		(net "NIC5_MAIN_PWR_EN")
	)
	(segment
		(start 316.611254 -100.7364)
		(end 321.233546 -100.7364)
		(width 0.15494)
		(layer "In13.Cu")
		(net "NIC5_MAIN_PWR_EN")
	)
	(segment
		(start 367.372646 -102.928166)
		(end 370.807742 -99.49307)
		(width 0.15494)
		(layer "In13.Cu")
		(net "NIC5_MAIN_PWR_EN")
	)
	(segment
		(start 327.178924 -101.373178)
		(end 328.678286 -102.87254)
		(width 0.15494)
		(layer "In13.Cu")
		(net "NIC5_MAIN_PWR_EN")
	)
	(segment
		(start 321.870324 -101.373178)
		(end 327.178924 -101.373178)
		(width 0.15494)
		(layer "In13.Cu")
		(net "NIC5_MAIN_PWR_EN")
	)
	(segment
		(start 342.4682 -105.1814)
		(end 344.721434 -102.928166)
		(width 0.15494)
		(layer "In13.Cu")
		(net "NIC5_MAIN_PWR_EN")
	)
	(segment
		(start 304.9016 -97.1804)
		(end 305.5874 -97.1804)
		(width 0.15494)
		(layer "In13.Cu")
		(net "NIC5_MAIN_PWR_EN")
	)
	(segment
		(start 321.233546 -100.7364)
		(end 321.870324 -101.373178)
		(width 0.15494)
		(layer "In13.Cu")
		(net "NIC5_MAIN_PWR_EN")
	)
	(segment
		(start 307.3146 -95.4532)
		(end 311.328054 -95.4532)
		(width 0.15494)
		(layer "In13.Cu")
		(net "NIC5_MAIN_PWR_EN")
	)
	(segment
		(start 305.5874 -97.1804)
		(end 307.3146 -95.4532)
		(width 0.15494)
		(layer "In13.Cu")
		(net "NIC5_MAIN_PWR_EN")
	)
	(segment
		(start 328.678286 -102.87254)
		(end 333.04734 -102.87254)
		(width 0.15494)
		(layer "In13.Cu")
		(net "NIC5_MAIN_PWR_EN")
	)
	(segment
		(start 344.721434 -102.928166)
		(end 367.372646 -102.928166)
		(width 0.15494)
		(layer "In13.Cu")
		(net "NIC5_MAIN_PWR_EN")
	)
	(segment
		(start 335.3562 -105.1814)
		(end 342.4682 -105.1814)
		(width 0.15494)
		(layer "In13.Cu")
		(net "NIC5_MAIN_PWR_EN")
	)
	(segment
		(start 302.703992 -99.739704)
		(end 302.703992 -99.378008)
		(width 0.15494)
		(layer "In13.Cu")
		(net "NIC5_MAIN_PWR_EN")
	)
	(segment
		(start 333.04734 -102.87254)
		(end 335.3562 -105.1814)
		(width 0.15494)
		(layer "In13.Cu")
		(net "NIC5_MAIN_PWR_EN")
	)
	(segment
		(start 311.328054 -95.4532)
		(end 316.611254 -100.7364)
		(width 0.15494)
		(layer "In13.Cu")
		(net "NIC5_MAIN_PWR_EN")
	)
	(segment
		(start 302.703992 -99.378008)
		(end 304.9016 -97.1804)
		(width 0.15494)
		(layer "In13.Cu")
		(net "NIC5_MAIN_PWR_EN")
	)
	(segment
		(start 242.710462 -124.963428)
		(end 242.710462 -125.979428)
		(width 0.13208)
		(layer "F.Cu")
		(net "PWRGD_P3V3_NIC4")
	)
	(segment
		(start 243.950998 -125.894846)
		(end 244.431058 -125.894846)
		(width 0.13208)
		(layer "F.Cu")
		(net "PWRGD_P3V3_NIC4")
	)
	(segment
		(start 243.610384 -125.979428)
		(end 243.7384 -126.107444)
		(width 0.13208)
		(layer "F.Cu")
		(net "PWRGD_P3V3_NIC4")
	)
	(segment
		(start 242.710462 -125.979428)
		(end 243.610384 -125.979428)
		(width 0.13208)
		(layer "F.Cu")
		(net "PWRGD_P3V3_NIC4")
	)
	(segment
		(start 243.7384 -126.107444)
		(end 243.950998 -125.894846)
		(width 0.13208)
		(layer "F.Cu")
		(net "PWRGD_P3V3_NIC4")
	)
	(via
		(at 243.7384 -126.107444)
		(size 0.508)
		(drill 0.254)
		(layers "F.Cu" "B.Cu")
		(net "PWRGD_P3V3_NIC4")
	)
	(segment
		(start 155.800044 -298.74972)
		(end 155.800044 -298.749974)
		(width 0.1143)
		(layer "F.Cu")
		(net "CLK_100M_DB800ZL_PEX1_S0_R_DN")
	)
	(segment
		(start 155.800044 -298.749974)
		(end 155.325064 -299.224954)
		(width 0.1143)
		(layer "F.Cu")
		(net "CLK_100M_DB800ZL_PEX1_S0_R_DN")
	)
	(via
		(at 155.325064 -299.224954)
		(size 0.4064)
		(drill 0.2032)
		(layers "F.Cu" "B.Cu")
		(net "CLK_100M_DB800ZL_PEX1_S0_R_DN")
	)
	(via
		(at 97.813114 -330.416662)
		(size 0.508)
		(drill 0.254)
		(layers "F.Cu" "B.Cu")
		(net "CLK_100M_DB800ZL_PEX1_S0_R_DN")
	)
	(segment
		(start 98.054414 -330.175362)
		(end 97.813114 -330.416662)
		(width 0.1143)
		(layer "B.Cu")
		(net "CLK_100M_DB800ZL_PEX1_S0_R_DN")
	)
	(segment
		(start 99.0981 -330.708254)
		(end 98.565208 -330.175362)
		(width 0.1143)
		(layer "B.Cu")
		(net "CLK_100M_DB800ZL_PEX1_S0_R_DN")
	)
	(segment
		(start 99.431348 -330.708254)
		(end 99.0981 -330.708254)
		(width 0.1143)
		(layer "B.Cu")
		(net "CLK_100M_DB800ZL_PEX1_S0_R_DN")
	)
	(segment
		(start 99.754944 -331.03185)
		(end 99.431348 -330.708254)
		(width 0.1143)
		(layer "B.Cu")
		(net "CLK_100M_DB800ZL_PEX1_S0_R_DN")
	)
	(segment
		(start 98.565208 -330.175362)
		(end 98.054414 -330.175362)
		(width 0.1143)
		(layer "B.Cu")
		(net "CLK_100M_DB800ZL_PEX1_S0_R_DN")
	)
	(segment
		(start 151.384508 -298.88434)
		(end 150.499572 -298.88434)
		(width 0.1397)
		(layer "In11.Cu")
		(net "CLK_100M_DB800ZL_PEX1_S0_R_DN")
	)
	(segment
		(start 130.097022 -326.703182)
		(end 121.119392 -326.703182)
		(width 0.1397)
		(layer "In11.Cu")
		(net "CLK_100M_DB800ZL_PEX1_S0_R_DN")
	)
	(segment
		(start 146.47037 -299.10024)
		(end 146.397218 -299.340778)
		(width 0.1397)
		(layer "In11.Cu")
		(net "CLK_100M_DB800ZL_PEX1_S0_R_DN")
	)
	(segment
		(start 146.061176 -299.52061)
		(end 145.820384 -299.447458)
		(width 0.1397)
		(layer "In11.Cu")
		(net "CLK_100M_DB800ZL_PEX1_S0_R_DN")
	)
	(segment
		(start 118.959122 -326.346312)
		(end 115.298728 -326.346312)
		(width 0.1397)
		(layer "In11.Cu")
		(net "CLK_100M_DB800ZL_PEX1_S0_R_DN")
	)
	(segment
		(start 149.32152 -298.48302)
		(end 149.14372 -298.66082)
		(width 0.1397)
		(layer "In11.Cu")
		(net "CLK_100M_DB800ZL_PEX1_S0_R_DN")
	)
	(segment
		(start 155.615894 -299.224954)
		(end 155.704794 -299.136054)
		(width 0.0889)
		(layer "In11.Cu")
		(net "CLK_100M_DB800ZL_PEX1_S0_R_DN")
	)
	(segment
		(start 155.325064 -299.224954)
		(end 155.615894 -299.224954)
		(width 0.0889)
		(layer "In11.Cu")
		(net "CLK_100M_DB800ZL_PEX1_S0_R_DN")
	)
	(segment
		(start 130.877818 -325.922386)
		(end 130.097022 -326.703182)
		(width 0.1397)
		(layer "In11.Cu")
		(net "CLK_100M_DB800ZL_PEX1_S0_R_DN")
	)
	(segment
		(start 119.442992 -326.830182)
		(end 118.959122 -326.346312)
		(width 0.1397)
		(layer "In11.Cu")
		(net "CLK_100M_DB800ZL_PEX1_S0_R_DN")
	)
	(segment
		(start 103.79964 -329.363578)
		(end 103.013256 -330.149962)
		(width 0.1397)
		(layer "In11.Cu")
		(net "CLK_100M_DB800ZL_PEX1_S0_R_DN")
	)
	(segment
		(start 119.763286 -329.141582)
		(end 119.442992 -328.821288)
		(width 0.1397)
		(layer "In11.Cu")
		(net "CLK_100M_DB800ZL_PEX1_S0_R_DN")
	)
	(segment
		(start 98.079814 -330.149962)
		(end 97.813114 -330.416662)
		(width 0.1397)
		(layer "In11.Cu")
		(net "CLK_100M_DB800ZL_PEX1_S0_R_DN")
	)
	(segment
		(start 151.476456 -298.81449)
		(end 151.406606 -298.88434)
		(width 0.0889)
		(layer "In11.Cu")
		(net "CLK_100M_DB800ZL_PEX1_S0_R_DN")
	)
	(segment
		(start 121.119392 -326.703182)
		(end 120.992392 -326.830182)
		(width 0.1397)
		(layer "In11.Cu")
		(net "CLK_100M_DB800ZL_PEX1_S0_R_DN")
	)
	(segment
		(start 155.50896 -298.81449)
		(end 151.476456 -298.81449)
		(width 0.0889)
		(layer "In11.Cu")
		(net "CLK_100M_DB800ZL_PEX1_S0_R_DN")
	)
	(segment
		(start 119.442992 -328.821288)
		(end 119.442992 -326.830182)
		(width 0.1397)
		(layer "In11.Cu")
		(net "CLK_100M_DB800ZL_PEX1_S0_R_DN")
	)
	(segment
		(start 148.76272 -298.66082)
		(end 148.58492 -298.48302)
		(width 0.1397)
		(layer "In11.Cu")
		(net "CLK_100M_DB800ZL_PEX1_S0_R_DN")
	)
	(segment
		(start 121.119392 -327.592182)
		(end 129.658364 -327.592182)
		(width 0.1397)
		(layer "In11.Cu")
		(net "CLK_100M_DB800ZL_PEX1_S0_R_DN")
	)
	(segment
		(start 120.992392 -326.830182)
		(end 120.992392 -327.465182)
		(width 0.1397)
		(layer "In11.Cu")
		(net "CLK_100M_DB800ZL_PEX1_S0_R_DN")
	)
	(segment
		(start 148.58492 -298.48302)
		(end 147.624546 -298.48302)
		(width 0.1397)
		(layer "In11.Cu")
		(net "CLK_100M_DB800ZL_PEX1_S0_R_DN")
	)
	(segment
		(start 142.3416 -300.074838)
		(end 140.142976 -302.273462)
		(width 0.1397)
		(layer "In11.Cu")
		(net "CLK_100M_DB800ZL_PEX1_S0_R_DN")
	)
	(segment
		(start 155.704794 -299.010324)
		(end 155.50896 -298.81449)
		(width 0.0889)
		(layer "In11.Cu")
		(net "CLK_100M_DB800ZL_PEX1_S0_R_DN")
	)
	(segment
		(start 147.624546 -298.48302)
		(end 146.47037 -299.10024)
		(width 0.1397)
		(layer "In11.Cu")
		(net "CLK_100M_DB800ZL_PEX1_S0_R_DN")
	)
	(segment
		(start 120.992392 -327.465182)
		(end 121.119392 -327.592182)
		(width 0.1397)
		(layer "In11.Cu")
		(net "CLK_100M_DB800ZL_PEX1_S0_R_DN")
	)
	(segment
		(start 133.835902 -311.71261)
		(end 130.877818 -318.854328)
		(width 0.1397)
		(layer "In11.Cu")
		(net "CLK_100M_DB800ZL_PEX1_S0_R_DN")
	)
	(segment
		(start 112.281462 -329.363578)
		(end 103.79964 -329.363578)
		(width 0.1397)
		(layer "In11.Cu")
		(net "CLK_100M_DB800ZL_PEX1_S0_R_DN")
	)
	(segment
		(start 145.820384 -299.447712)
		(end 144.646904 -300.074838)
		(width 0.1397)
		(layer "In11.Cu")
		(net "CLK_100M_DB800ZL_PEX1_S0_R_DN")
	)
	(segment
		(start 150.499572 -298.88434)
		(end 150.098252 -298.48302)
		(width 0.1397)
		(layer "In11.Cu")
		(net "CLK_100M_DB800ZL_PEX1_S0_R_DN")
	)
	(segment
		(start 129.658364 -327.592182)
		(end 129.978658 -327.912476)
		(width 0.1397)
		(layer "In11.Cu")
		(net "CLK_100M_DB800ZL_PEX1_S0_R_DN")
	)
	(segment
		(start 150.098252 -298.48302)
		(end 149.32152 -298.48302)
		(width 0.1397)
		(layer "In11.Cu")
		(net "CLK_100M_DB800ZL_PEX1_S0_R_DN")
	)
	(segment
		(start 145.820384 -299.447458)
		(end 145.820384 -299.447712)
		(width 0.1397)
		(layer "In11.Cu")
		(net "CLK_100M_DB800ZL_PEX1_S0_R_DN")
	)
	(segment
		(start 151.406606 -298.88434)
		(end 151.384508 -298.88434)
		(width 0.0889)
		(layer "In11.Cu")
		(net "CLK_100M_DB800ZL_PEX1_S0_R_DN")
	)
	(segment
		(start 155.704794 -299.136054)
		(end 155.704794 -299.010324)
		(width 0.0889)
		(layer "In11.Cu")
		(net "CLK_100M_DB800ZL_PEX1_S0_R_DN")
	)
	(segment
		(start 144.646904 -300.074838)
		(end 142.3416 -300.074838)
		(width 0.1397)
		(layer "In11.Cu")
		(net "CLK_100M_DB800ZL_PEX1_S0_R_DN")
	)
	(segment
		(start 140.142976 -302.273462)
		(end 133.835902 -311.71261)
		(width 0.1397)
		(layer "In11.Cu")
		(net "CLK_100M_DB800ZL_PEX1_S0_R_DN")
	)
	(segment
		(start 129.658364 -329.141582)
		(end 119.763286 -329.141582)
		(width 0.1397)
		(layer "In11.Cu")
		(net "CLK_100M_DB800ZL_PEX1_S0_R_DN")
	)
	(segment
		(start 115.298728 -326.346312)
		(end 112.281462 -329.363578)
		(width 0.1397)
		(layer "In11.Cu")
		(net "CLK_100M_DB800ZL_PEX1_S0_R_DN")
	)
	(segment
		(start 146.397218 -299.340778)
		(end 146.061176 -299.52061)
		(width 0.1397)
		(layer "In11.Cu")
		(net "CLK_100M_DB800ZL_PEX1_S0_R_DN")
	)
	(segment
		(start 130.877818 -318.854328)
		(end 130.877818 -325.922386)
		(width 0.1397)
		(layer "In11.Cu")
		(net "CLK_100M_DB800ZL_PEX1_S0_R_DN")
	)
	(segment
		(start 149.14372 -298.66082)
		(end 148.76272 -298.66082)
		(width 0.1397)
		(layer "In11.Cu")
		(net "CLK_100M_DB800ZL_PEX1_S0_R_DN")
	)
	(segment
		(start 129.978658 -327.912476)
		(end 129.978658 -328.821288)
		(width 0.1397)
		(layer "In11.Cu")
		(net "CLK_100M_DB800ZL_PEX1_S0_R_DN")
	)
	(segment
		(start 129.978658 -328.821288)
		(end 129.658364 -329.141582)
		(width 0.1397)
		(layer "In11.Cu")
		(net "CLK_100M_DB800ZL_PEX1_S0_R_DN")
	)
	(segment
		(start 103.013256 -330.149962)
		(end 98.079814 -330.149962)
		(width 0.1397)
		(layer "In11.Cu")
		(net "CLK_100M_DB800ZL_PEX1_S0_R_DN")
	)
	(segment
		(start 38.775132 -163.928806)
		(end 38.597332 -163.928806)
		(width 0.13208)
		(layer "F.Cu")
		(net "PWRGD_NIC0_PWR_GOOD_R")
	)
	(segment
		(start 350.893888 -225.587052)
		(end 351.293684 -225.986848)
		(width 0.13208)
		(layer "F.Cu")
		(net "PWRGD_NIC0_PWR_GOOD_R")
	)
	(segment
		(start 38.597332 -163.928806)
		(end 38.20795 -163.539424)
		(width 0.13208)
		(layer "F.Cu")
		(net "PWRGD_NIC0_PWR_GOOD_R")
	)
	(segment
		(start 38.20795 -163.539424)
		(end 38.20795 -163.061396)
		(width 0.13208)
		(layer "F.Cu")
		(net "PWRGD_NIC0_PWR_GOOD_R")
	)
	(via
		(at 351.293684 -225.986848)
		(size 0.4572)
		(drill 0.254)
		(layers "F.Cu" "B.Cu")
		(net "PWRGD_NIC0_PWR_GOOD_R")
	)
	(via
		(at 38.775132 -163.928806)
		(size 0.508)
		(drill 0.254)
		(layers "F.Cu" "B.Cu")
		(net "PWRGD_NIC0_PWR_GOOD_R")
	)
	(via
		(at 51.08321 -176.677574)
		(size 0.508)
		(drill 0.254)
		(layers "F.Cu" "B.Cu")
		(net "PWRGD_NIC0_PWR_GOOD_R")
	)
	(segment
		(start 50.70856 -176.677574)
		(end 51.08321 -176.677574)
		(width 0.13208)
		(layer "B.Cu")
		(net "PWRGD_NIC0_PWR_GOOD_R")
	)
	(segment
		(start 38.724332 -163.928806)
		(end 38.597332 -164.055806)
		(width 0.13208)
		(layer "B.Cu")
		(net "PWRGD_NIC0_PWR_GOOD_R")
	)
	(segment
		(start 38.597332 -164.055806)
		(end 38.597332 -164.566346)
		(width 0.13208)
		(layer "B.Cu")
		(net "PWRGD_NIC0_PWR_GOOD_R")
	)
	(segment
		(start 38.597332 -164.566346)
		(end 50.70856 -176.677574)
		(width 0.13208)
		(layer "B.Cu")
		(net "PWRGD_NIC0_PWR_GOOD_R")
	)
	(segment
		(start 38.775132 -163.928806)
		(end 38.724332 -163.928806)
		(width 0.13208)
		(layer "B.Cu")
		(net "PWRGD_NIC0_PWR_GOOD_R")
	)
	(segment
		(start 362.726732 -176.876202)
		(end 360.37266 -174.52213)
		(width 0.15494)
		(layer "In15.Cu")
		(net "PWRGD_NIC0_PWR_GOOD_R")
	)
	(segment
		(start 356.950518 -174.52213)
		(end 356.500938 -174.97171)
		(width 0.15494)
		(layer "In15.Cu")
		(net "PWRGD_NIC0_PWR_GOOD_R")
	)
	(segment
		(start 285.485078 -172.655992)
		(end 260.80593 -172.655992)
		(width 0.15494)
		(layer "In15.Cu")
		(net "PWRGD_NIC0_PWR_GOOD_R")
	)
	(segment
		(start 236.408722 -174.253398)
		(end 236.002322 -173.846998)
		(width 0.15494)
		(layer "In15.Cu")
		(net "PWRGD_NIC0_PWR_GOOD_R")
	)
	(segment
		(start 368.76863 -184.009538)
		(end 368.76863 -180.567838)
		(width 0.15494)
		(layer "In15.Cu")
		(net "PWRGD_NIC0_PWR_GOOD_R")
	)
	(segment
		(start 51.367436 -176.9618)
		(end 51.08321 -176.677574)
		(width 0.15494)
		(layer "In15.Cu")
		(net "PWRGD_NIC0_PWR_GOOD_R")
	)
	(segment
		(start 182.275734 -174.166784)
		(end 181.106318 -175.3362)
		(width 0.15494)
		(layer "In15.Cu")
		(net "PWRGD_NIC0_PWR_GOOD_R")
	)
	(segment
		(start 341.183722 -171.998386)
		(end 340.693248 -171.507912)
		(width 0.15494)
		(layer "In15.Cu")
		(net "PWRGD_NIC0_PWR_GOOD_R")
	)
	(segment
		(start 368.76863 -180.567838)
		(end 365.076994 -176.876202)
		(width 0.15494)
		(layer "In15.Cu")
		(net "PWRGD_NIC0_PWR_GOOD_R")
	)
	(segment
		(start 360.37266 -174.52213)
		(end 356.950518 -174.52213)
		(width 0.15494)
		(layer "In15.Cu")
		(net "PWRGD_NIC0_PWR_GOOD_R")
	)
	(segment
		(start 106.017568 -188.24956)
		(end 101.74605 -186.480196)
		(width 0.15494)
		(layer "In15.Cu")
		(net "PWRGD_NIC0_PWR_GOOD_R")
	)
	(segment
		(start 181.106318 -175.3362)
		(end 180.100478 -175.752506)
		(width 0.15494)
		(layer "In15.Cu")
		(net "PWRGD_NIC0_PWR_GOOD_R")
	)
	(segment
		(start 343.905332 -171.998386)
		(end 341.183722 -171.998386)
		(width 0.15494)
		(layer "In15.Cu")
		(net "PWRGD_NIC0_PWR_GOOD_R")
	)
	(segment
		(start 140.962126 -188.644276)
		(end 139.29741 -190.308992)
		(width 0.15494)
		(layer "In15.Cu")
		(net "PWRGD_NIC0_PWR_GOOD_R")
	)
	(segment
		(start 346.878656 -174.97171)
		(end 343.905332 -171.998386)
		(width 0.15494)
		(layer "In15.Cu")
		(net "PWRGD_NIC0_PWR_GOOD_R")
	)
	(segment
		(start 351.3201 -225.960432)
		(end 353.657916 -225.960432)
		(width 0.15494)
		(layer "In15.Cu")
		(net "PWRGD_NIC0_PWR_GOOD_R")
	)
	(segment
		(start 139.29741 -190.308992)
		(end 127.291592 -190.308992)
		(width 0.15494)
		(layer "In15.Cu")
		(net "PWRGD_NIC0_PWR_GOOD_R")
	)
	(segment
		(start 113.398046 -187.389008)
		(end 112.537494 -188.24956)
		(width 0.15494)
		(layer "In15.Cu")
		(net "PWRGD_NIC0_PWR_GOOD_R")
	)
	(segment
		(start 260.80593 -172.655992)
		(end 259.208524 -174.253398)
		(width 0.15494)
		(layer "In15.Cu")
		(net "PWRGD_NIC0_PWR_GOOD_R")
	)
	(segment
		(start 372.008146 -227.772468)
		(end 372.008146 -187.249054)
		(width 0.15494)
		(layer "In15.Cu")
		(net "PWRGD_NIC0_PWR_GOOD_R")
	)
	(segment
		(start 286.5882 -171.55287)
		(end 285.485078 -172.655992)
		(width 0.15494)
		(layer "In15.Cu")
		(net "PWRGD_NIC0_PWR_GOOD_R")
	)
	(segment
		(start 259.208524 -174.253398)
		(end 236.408722 -174.253398)
		(width 0.15494)
		(layer "In15.Cu")
		(net "PWRGD_NIC0_PWR_GOOD_R")
	)
	(segment
		(start 180.100478 -175.752506)
		(end 178.70932 -175.752506)
		(width 0.15494)
		(layer "In15.Cu")
		(net "PWRGD_NIC0_PWR_GOOD_R")
	)
	(segment
		(start 367.867946 -231.912668)
		(end 372.008146 -227.772468)
		(width 0.15494)
		(layer "In15.Cu")
		(net "PWRGD_NIC0_PWR_GOOD_R")
	)
	(segment
		(start 365.076994 -176.876202)
		(end 362.726732 -176.876202)
		(width 0.15494)
		(layer "In15.Cu")
		(net "PWRGD_NIC0_PWR_GOOD_R")
	)
	(segment
		(start 127.291592 -190.308992)
		(end 124.371608 -187.389008)
		(width 0.15494)
		(layer "In15.Cu")
		(net "PWRGD_NIC0_PWR_GOOD_R")
	)
	(segment
		(start 233.226356 -173.846998)
		(end 232.466388 -173.08703)
		(width 0.15494)
		(layer "In15.Cu")
		(net "PWRGD_NIC0_PWR_GOOD_R")
	)
	(segment
		(start 51.971702 -176.9618)
		(end 51.367436 -176.9618)
		(width 0.15494)
		(layer "In15.Cu")
		(net "PWRGD_NIC0_PWR_GOOD_R")
	)
	(segment
		(start 112.537494 -188.24956)
		(end 106.017568 -188.24956)
		(width 0.15494)
		(layer "In15.Cu")
		(net "PWRGD_NIC0_PWR_GOOD_R")
	)
	(segment
		(start 124.371608 -187.389008)
		(end 113.398046 -187.389008)
		(width 0.15494)
		(layer "In15.Cu")
		(net "PWRGD_NIC0_PWR_GOOD_R")
	)
	(segment
		(start 354.545646 -227.849176)
		(end 358.609138 -231.912668)
		(width 0.15494)
		(layer "In15.Cu")
		(net "PWRGD_NIC0_PWR_GOOD_R")
	)
	(segment
		(start 232.466388 -173.08703)
		(end 215.269826 -173.08703)
		(width 0.15494)
		(layer "In15.Cu")
		(net "PWRGD_NIC0_PWR_GOOD_R")
	)
	(segment
		(start 236.002322 -173.846998)
		(end 233.226356 -173.846998)
		(width 0.15494)
		(layer "In15.Cu")
		(net "PWRGD_NIC0_PWR_GOOD_R")
	)
	(segment
		(start 356.500938 -174.97171)
		(end 346.878656 -174.97171)
		(width 0.15494)
		(layer "In15.Cu")
		(net "PWRGD_NIC0_PWR_GOOD_R")
	)
	(segment
		(start 101.74605 -186.480196)
		(end 91.719654 -176.4538)
		(width 0.15494)
		(layer "In15.Cu")
		(net "PWRGD_NIC0_PWR_GOOD_R")
	)
	(segment
		(start 351.293684 -225.986848)
		(end 351.3201 -225.960432)
		(width 0.15494)
		(layer "In15.Cu")
		(net "PWRGD_NIC0_PWR_GOOD_R")
	)
	(segment
		(start 214.190072 -174.166784)
		(end 182.275734 -174.166784)
		(width 0.15494)
		(layer "In15.Cu")
		(net "PWRGD_NIC0_PWR_GOOD_R")
	)
	(segment
		(start 178.70932 -175.752506)
		(end 165.81755 -188.644276)
		(width 0.15494)
		(layer "In15.Cu")
		(net "PWRGD_NIC0_PWR_GOOD_R")
	)
	(segment
		(start 353.657916 -225.960432)
		(end 354.545646 -226.848162)
		(width 0.15494)
		(layer "In15.Cu")
		(net "PWRGD_NIC0_PWR_GOOD_R")
	)
	(segment
		(start 335.22666 -171.55287)
		(end 286.5882 -171.55287)
		(width 0.15494)
		(layer "In15.Cu")
		(net "PWRGD_NIC0_PWR_GOOD_R")
	)
	(segment
		(start 165.81755 -188.644276)
		(end 140.962126 -188.644276)
		(width 0.15494)
		(layer "In15.Cu")
		(net "PWRGD_NIC0_PWR_GOOD_R")
	)
	(segment
		(start 91.719654 -176.4538)
		(end 52.479702 -176.4538)
		(width 0.15494)
		(layer "In15.Cu")
		(net "PWRGD_NIC0_PWR_GOOD_R")
	)
	(segment
		(start 335.271618 -171.507912)
		(end 335.22666 -171.55287)
		(width 0.15494)
		(layer "In15.Cu")
		(net "PWRGD_NIC0_PWR_GOOD_R")
	)
	(segment
		(start 354.545646 -226.848162)
		(end 354.545646 -227.849176)
		(width 0.15494)
		(layer "In15.Cu")
		(net "PWRGD_NIC0_PWR_GOOD_R")
	)
	(segment
		(start 52.479702 -176.4538)
		(end 51.971702 -176.9618)
		(width 0.15494)
		(layer "In15.Cu")
		(net "PWRGD_NIC0_PWR_GOOD_R")
	)
	(segment
		(start 215.269826 -173.08703)
		(end 214.190072 -174.166784)
		(width 0.15494)
		(layer "In15.Cu")
		(net "PWRGD_NIC0_PWR_GOOD_R")
	)
	(segment
		(start 358.609138 -231.912668)
		(end 367.867946 -231.912668)
		(width 0.15494)
		(layer "In15.Cu")
		(net "PWRGD_NIC0_PWR_GOOD_R")
	)
	(segment
		(start 340.693248 -171.507912)
		(end 335.271618 -171.507912)
		(width 0.15494)
		(layer "In15.Cu")
		(net "PWRGD_NIC0_PWR_GOOD_R")
	)
	(segment
		(start 372.008146 -187.249054)
		(end 368.76863 -184.009538)
		(width 0.15494)
		(layer "In15.Cu")
		(net "PWRGD_NIC0_PWR_GOOD_R")
	)
	(segment
		(start 277.717504 -395.562582)
		(end 277.717504 -396.111222)
		(width 0.13208)
		(layer "F.Cu")
		(net "MB_BMC_MON")
	)
	(segment
		(start 144.100296 -388.150354)
		(end 144.100296 -387.762242)
		(width 0.13208)
		(layer "F.Cu")
		(net "MB_BMC_MON")
	)
	(segment
		(start 143.3322 -387.363208)
		(end 143.3322 -386.9944)
		(width 0.13208)
		(layer "F.Cu")
		(net "MB_BMC_MON")
	)
	(segment
		(start 143.3322 -386.9944)
		(end 143.4084 -386.9182)
		(width 0.13208)
		(layer "F.Cu")
		(net "MB_BMC_MON")
	)
	(segment
		(start 143.891254 -387.5532)
		(end 143.492728 -387.5532)
		(width 0.13208)
		(layer "F.Cu")
		(net "MB_BMC_MON")
	)
	(segment
		(start 277.80107 -397.112744)
		(end 277.80107 -398.000982)
		(width 0.13208)
		(layer "F.Cu")
		(net "MB_BMC_MON")
	)
	(segment
		(start 277.717504 -396.111222)
		(end 277.258526 -396.5702)
		(width 0.13208)
		(layer "F.Cu")
		(net "MB_BMC_MON")
	)
	(segment
		(start 143.4084 -386.9182)
		(end 144.3228 -386.9182)
		(width 0.13208)
		(layer "F.Cu")
		(net "MB_BMC_MON")
	)
	(segment
		(start 143.317468 -387.37794)
		(end 143.3322 -387.363208)
		(width 0.13208)
		(layer "F.Cu")
		(net "MB_BMC_MON")
	)
	(segment
		(start 277.258526 -396.5702)
		(end 277.80107 -397.112744)
		(width 0.13208)
		(layer "F.Cu")
		(net "MB_BMC_MON")
	)
	(segment
		(start 145.065496 -387.660896)
		(end 145.334228 -387.660896)
		(width 0.13208)
		(layer "F.Cu")
		(net "MB_BMC_MON")
	)
	(segment
		(start 144.3228 -386.9182)
		(end 145.065496 -387.660896)
		(width 0.13208)
		(layer "F.Cu")
		(net "MB_BMC_MON")
	)
	(segment
		(start 143.492728 -387.5532)
		(end 143.317468 -387.37794)
		(width 0.13208)
		(layer "F.Cu")
		(net "MB_BMC_MON")
	)
	(segment
		(start 144.100296 -387.762242)
		(end 143.891254 -387.5532)
		(width 0.13208)
		(layer "F.Cu")
		(net "MB_BMC_MON")
	)
	(via
		(at 277.258526 -396.5702)
		(size 0.508)
		(drill 0.254)
		(layers "F.Cu" "B.Cu")
		(net "MB_BMC_MON")
	)
	(via
		(at 144.100296 -388.150354)
		(size 0.508)
		(drill 0.254)
		(layers "F.Cu" "B.Cu")
		(net "MB_BMC_MON")
	)
	(segment
		(start 182.65267 -415.179002)
		(end 184.278524 -416.804856)
		(width 0.13208)
		(layer "B.Cu")
		(net "MB_BMC_MON")
	)
	(segment
		(start 243.582444 -401.114768)
		(end 245.214648 -399.482564)
		(width 0.13208)
		(layer "B.Cu")
		(net "MB_BMC_MON")
	)
	(segment
		(start 137.9474 -400.7866)
		(end 137.9474 -390.7282)
		(width 0.13208)
		(layer "B.Cu")
		(net "MB_BMC_MON")
	)
	(segment
		(start 152.4762 -386.9182)
		(end 177.164238 -386.9182)
		(width 0.13208)
		(layer "B.Cu")
		(net "MB_BMC_MON")
	)
	(segment
		(start 245.214648 -399.482564)
		(end 245.214648 -391.91565)
		(width 0.13208)
		(layer "B.Cu")
		(net "MB_BMC_MON")
	)
	(segment
		(start 137.24382 -401.49018)
		(end 137.9474 -400.7866)
		(width 0.13208)
		(layer "B.Cu")
		(net "MB_BMC_MON")
	)
	(segment
		(start 201.62901 -415.46526)
		(end 237.091474 -415.46526)
		(width 0.13208)
		(layer "B.Cu")
		(net "MB_BMC_MON")
	)
	(segment
		(start 260.262116 -391.200386)
		(end 264.879836 -386.582666)
		(width 0.13208)
		(layer "B.Cu")
		(net "MB_BMC_MON")
	)
	(segment
		(start 245.929912 -391.200386)
		(end 260.262116 -391.200386)
		(width 0.13208)
		(layer "B.Cu")
		(net "MB_BMC_MON")
	)
	(segment
		(start 245.214648 -391.91565)
		(end 245.929912 -391.200386)
		(width 0.13208)
		(layer "B.Cu")
		(net "MB_BMC_MON")
	)
	(segment
		(start 140.525246 -388.150354)
		(end 144.100296 -388.150354)
		(width 0.13208)
		(layer "B.Cu")
		(net "MB_BMC_MON")
	)
	(segment
		(start 184.278524 -416.804856)
		(end 200.289414 -416.804856)
		(width 0.13208)
		(layer "B.Cu")
		(net "MB_BMC_MON")
	)
	(segment
		(start 238.488982 -414.067752)
		(end 238.488982 -403.01545)
		(width 0.13208)
		(layer "B.Cu")
		(net "MB_BMC_MON")
	)
	(segment
		(start 152.0444 -386.4864)
		(end 152.4762 -386.9182)
		(width 0.13208)
		(layer "B.Cu")
		(net "MB_BMC_MON")
	)
	(segment
		(start 238.488982 -403.01545)
		(end 240.389664 -401.114768)
		(width 0.13208)
		(layer "B.Cu")
		(net "MB_BMC_MON")
	)
	(segment
		(start 144.100296 -388.150354)
		(end 144.67205 -387.5786)
		(width 0.13208)
		(layer "B.Cu")
		(net "MB_BMC_MON")
	)
	(segment
		(start 270.710914 -386.582666)
		(end 276.038056 -391.909808)
		(width 0.13208)
		(layer "B.Cu")
		(net "MB_BMC_MON")
	)
	(segment
		(start 177.164238 -386.9182)
		(end 182.65267 -392.406632)
		(width 0.13208)
		(layer "B.Cu")
		(net "MB_BMC_MON")
	)
	(segment
		(start 276.038056 -395.34973)
		(end 277.258526 -396.5702)
		(width 0.13208)
		(layer "B.Cu")
		(net "MB_BMC_MON")
	)
	(segment
		(start 149.3012 -386.4864)
		(end 152.0444 -386.4864)
		(width 0.13208)
		(layer "B.Cu")
		(net "MB_BMC_MON")
	)
	(segment
		(start 137.9474 -390.7282)
		(end 140.525246 -388.150354)
		(width 0.13208)
		(layer "B.Cu")
		(net "MB_BMC_MON")
	)
	(segment
		(start 135.710168 -401.49018)
		(end 137.24382 -401.49018)
		(width 0.13208)
		(layer "B.Cu")
		(net "MB_BMC_MON")
	)
	(segment
		(start 182.65267 -392.406632)
		(end 182.65267 -415.179002)
		(width 0.13208)
		(layer "B.Cu")
		(net "MB_BMC_MON")
	)
	(segment
		(start 200.289414 -416.804856)
		(end 201.62901 -415.46526)
		(width 0.13208)
		(layer "B.Cu")
		(net "MB_BMC_MON")
	)
	(segment
		(start 237.091474 -415.46526)
		(end 238.488982 -414.067752)
		(width 0.13208)
		(layer "B.Cu")
		(net "MB_BMC_MON")
	)
	(segment
		(start 264.879836 -386.582666)
		(end 270.710914 -386.582666)
		(width 0.13208)
		(layer "B.Cu")
		(net "MB_BMC_MON")
	)
	(segment
		(start 240.389664 -401.114768)
		(end 243.582444 -401.114768)
		(width 0.13208)
		(layer "B.Cu")
		(net "MB_BMC_MON")
	)
	(segment
		(start 276.038056 -391.909808)
		(end 276.038056 -395.34973)
		(width 0.13208)
		(layer "B.Cu")
		(net "MB_BMC_MON")
	)
	(segment
		(start 148.209 -387.5786)
		(end 149.3012 -386.4864)
		(width 0.13208)
		(layer "B.Cu")
		(net "MB_BMC_MON")
	)
	(segment
		(start 144.67205 -387.5786)
		(end 148.209 -387.5786)
		(width 0.13208)
		(layer "B.Cu")
		(net "MB_BMC_MON")
	)
	(segment
		(start 332.5876 -120.091454)
		(end 332.186026 -120.493028)
		(width 0.13208)
		(layer "F.Cu")
		(net "PWRGD_P3V3_NIC5_R")
	)
	(segment
		(start 332.186026 -120.493028)
		(end 331.575664 -120.493028)
		(width 0.13208)
		(layer "F.Cu")
		(net "PWRGD_P3V3_NIC5_R")
	)
	(segment
		(start 333.730346 -118.76024)
		(end 333.41056 -118.76024)
		(width 0.13208)
		(layer "F.Cu")
		(net "PWRGD_P3V3_NIC5_R")
	)
	(segment
		(start 333.41056 -118.76024)
		(end 332.728316 -119.442484)
		(width 0.13208)
		(layer "F.Cu")
		(net "PWRGD_P3V3_NIC5_R")
	)
	(segment
		(start 348.493842 -219.987114)
		(end 348.893638 -220.38691)
		(width 0.13208)
		(layer "F.Cu")
		(net "PWRGD_P3V3_NIC5_R")
	)
	(segment
		(start 332.728316 -119.442484)
		(end 332.5876 -119.782082)
		(width 0.13208)
		(layer "F.Cu")
		(net "PWRGD_P3V3_NIC5_R")
	)
	(segment
		(start 332.5876 -119.782082)
		(end 332.5876 -120.091454)
		(width 0.13208)
		(layer "F.Cu")
		(net "PWRGD_P3V3_NIC5_R")
	)
	(via
		(at 348.893638 -220.38691)
		(size 0.4572)
		(drill 0.254)
		(layers "F.Cu" "B.Cu")
		(net "PWRGD_P3V3_NIC5_R")
	)
	(via
		(at 371.992144 -110.010956)
		(size 0.508)
		(drill 0.254)
		(layers "F.Cu" "B.Cu")
		(net "PWRGD_P3V3_NIC5_R")
	)
	(via
		(at 332.186026 -120.493028)
		(size 0.508)
		(drill 0.254)
		(layers "F.Cu" "B.Cu")
		(net "PWRGD_P3V3_NIC5_R")
	)
	(segment
		(start 373.875808 -208.795874)
		(end 373.875808 -210.964018)
		(width 0.15494)
		(layer "In5.Cu")
		(net "PWRGD_P3V3_NIC5_R")
	)
	(segment
		(start 373.64162 -180.26888)
		(end 373.64162 -182.06974)
		(width 0.15494)
		(layer "In5.Cu")
		(net "PWRGD_P3V3_NIC5_R")
	)
	(segment
		(start 360.061002 -221.9833)
		(end 357.0351 -221.9833)
		(width 0.15494)
		(layer "In5.Cu")
		(net "PWRGD_P3V3_NIC5_R")
	)
	(segment
		(start 373.926862 -194.34683)
		(end 373.926862 -208.74482)
		(width 0.15494)
		(layer "In5.Cu")
		(net "PWRGD_P3V3_NIC5_R")
	)
	(segment
		(start 376.32132 -190.308738)
		(end 376.32132 -191.952372)
		(width 0.15494)
		(layer "In5.Cu")
		(net "PWRGD_P3V3_NIC5_R")
	)
	(segment
		(start 375.07926 -189.066678)
		(end 376.32132 -190.308738)
		(width 0.15494)
		(layer "In5.Cu")
		(net "PWRGD_P3V3_NIC5_R")
	)
	(segment
		(start 373.875808 -210.964018)
		(end 366.2426 -218.597226)
		(width 0.15494)
		(layer "In5.Cu")
		(net "PWRGD_P3V3_NIC5_R")
	)
	(segment
		(start 373.85498 -179.25288)
		(end 373.85498 -180.05552)
		(width 0.15494)
		(layer "In5.Cu")
		(net "PWRGD_P3V3_NIC5_R")
	)
	(segment
		(start 354.03282 -221.468188)
		(end 353.349306 -220.784674)
		(width 0.15494)
		(layer "In5.Cu")
		(net "PWRGD_P3V3_NIC5_R")
	)
	(segment
		(start 373.85498 -180.05552)
		(end 373.64162 -180.26888)
		(width 0.15494)
		(layer "In5.Cu")
		(net "PWRGD_P3V3_NIC5_R")
	)
	(segment
		(start 375.07926 -183.50738)
		(end 375.07926 -189.066678)
		(width 0.15494)
		(layer "In5.Cu")
		(net "PWRGD_P3V3_NIC5_R")
	)
	(segment
		(start 356.519988 -221.468188)
		(end 354.03282 -221.468188)
		(width 0.15494)
		(layer "In5.Cu")
		(net "PWRGD_P3V3_NIC5_R")
	)
	(segment
		(start 366.2426 -218.597226)
		(end 363.447076 -218.597226)
		(width 0.15494)
		(layer "In5.Cu")
		(net "PWRGD_P3V3_NIC5_R")
	)
	(segment
		(start 351.46234 -220.784674)
		(end 349.291402 -220.784674)
		(width 0.0889)
		(layer "In5.Cu")
		(net "PWRGD_P3V3_NIC5_R")
	)
	(segment
		(start 376.32132 -191.952372)
		(end 373.926862 -194.34683)
		(width 0.15494)
		(layer "In5.Cu")
		(net "PWRGD_P3V3_NIC5_R")
	)
	(segment
		(start 353.349306 -220.784674)
		(end 351.46234 -220.784674)
		(width 0.15494)
		(layer "In5.Cu")
		(net "PWRGD_P3V3_NIC5_R")
	)
	(segment
		(start 349.291402 -220.784674)
		(end 348.893638 -220.38691)
		(width 0.0889)
		(layer "In5.Cu")
		(net "PWRGD_P3V3_NIC5_R")
	)
	(segment
		(start 373.735092 -111.753904)
		(end 373.735092 -179.132992)
		(width 0.15494)
		(layer "In5.Cu")
		(net "PWRGD_P3V3_NIC5_R")
	)
	(segment
		(start 357.0351 -221.9833)
		(end 356.519988 -221.468188)
		(width 0.15494)
		(layer "In5.Cu")
		(net "PWRGD_P3V3_NIC5_R")
	)
	(segment
		(start 363.447076 -218.597226)
		(end 360.061002 -221.9833)
		(width 0.15494)
		(layer "In5.Cu")
		(net "PWRGD_P3V3_NIC5_R")
	)
	(segment
		(start 371.992144 -110.010956)
		(end 373.735092 -111.753904)
		(width 0.15494)
		(layer "In5.Cu")
		(net "PWRGD_P3V3_NIC5_R")
	)
	(segment
		(start 373.926862 -208.74482)
		(end 373.875808 -208.795874)
		(width 0.15494)
		(layer "In5.Cu")
		(net "PWRGD_P3V3_NIC5_R")
	)
	(segment
		(start 373.64162 -182.06974)
		(end 375.07926 -183.50738)
		(width 0.15494)
		(layer "In5.Cu")
		(net "PWRGD_P3V3_NIC5_R")
	)
	(segment
		(start 373.735092 -179.132992)
		(end 373.85498 -179.25288)
		(width 0.15494)
		(layer "In5.Cu")
		(net "PWRGD_P3V3_NIC5_R")
	)
	(segment
		(start 358.608884 -115.915186)
		(end 358.608884 -114.690652)
		(width 0.15494)
		(layer "In13.Cu")
		(net "PWRGD_P3V3_NIC5_R")
	)
	(segment
		(start 332.186026 -120.493028)
		(end 332.410054 -120.269)
		(width 0.15494)
		(layer "In13.Cu")
		(net "PWRGD_P3V3_NIC5_R")
	)
	(segment
		(start 334.454246 -121.3358)
		(end 339.3948 -121.3358)
		(width 0.15494)
		(layer "In13.Cu")
		(net "PWRGD_P3V3_NIC5_R")
	)
	(segment
		(start 332.410054 -120.269)
		(end 333.387446 -120.269)
		(width 0.15494)
		(layer "In13.Cu")
		(net "PWRGD_P3V3_NIC5_R")
	)
	(segment
		(start 358.608884 -114.690652)
		(end 361.919266 -111.38027)
		(width 0.15494)
		(layer "In13.Cu")
		(net "PWRGD_P3V3_NIC5_R")
	)
	(segment
		(start 361.919266 -111.38027)
		(end 370.62283 -111.38027)
		(width 0.15494)
		(layer "In13.Cu")
		(net "PWRGD_P3V3_NIC5_R")
	)
	(segment
		(start 333.387446 -120.269)
		(end 334.454246 -121.3358)
		(width 0.15494)
		(layer "In13.Cu")
		(net "PWRGD_P3V3_NIC5_R")
	)
	(segment
		(start 342.338152 -118.392448)
		(end 356.131622 -118.392448)
		(width 0.15494)
		(layer "In13.Cu")
		(net "PWRGD_P3V3_NIC5_R")
	)
	(segment
		(start 339.3948 -121.3358)
		(end 342.338152 -118.392448)
		(width 0.15494)
		(layer "In13.Cu")
		(net "PWRGD_P3V3_NIC5_R")
	)
	(segment
		(start 370.62283 -111.38027)
		(end 371.992144 -110.010956)
		(width 0.15494)
		(layer "In13.Cu")
		(net "PWRGD_P3V3_NIC5_R")
	)
	(segment
		(start 356.131622 -118.392448)
		(end 358.608884 -115.915186)
		(width 0.15494)
		(layer "In13.Cu")
		(net "PWRGD_P3V3_NIC5_R")
	)
	(segment
		(start 59.10326 -59.171586)
		(end 58.944256 -59.012582)
		(width 0.13208)
		(layer "F.Cu")
		(net "P3V3_SSD2_OCP")
	)
	(segment
		(start 59.140852 -58.364628)
		(end 58.944256 -58.561224)
		(width 0.13208)
		(layer "F.Cu")
		(net "P3V3_SSD2_OCP")
	)
	(segment
		(start 59.140852 -57.16397)
		(end 59.140852 -58.364628)
		(width 0.13208)
		(layer "F.Cu")
		(net "P3V3_SSD2_OCP")
	)
	(segment
		(start 58.944256 -59.012582)
		(end 58.944256 -58.561224)
		(width 0.13208)
		(layer "F.Cu")
		(net "P3V3_SSD2_OCP")
	)
	(via
		(at 58.944256 -58.561224)
		(size 0.508)
		(drill 0.254)
		(layers "F.Cu" "B.Cu")
		(net "P3V3_SSD2_OCP")
	)
	(segment
		(start 156.750004 -298.74972)
		(end 156.750004 -298.749974)
		(width 0.1143)
		(layer "F.Cu")
		(net "CLK_100M_DB800ZL_PEX1_S0_R_DP")
	)
	(segment
		(start 156.750004 -298.749974)
		(end 156.275024 -299.224954)
		(width 0.1143)
		(layer "F.Cu")
		(net "CLK_100M_DB800ZL_PEX1_S0_R_DP")
	)
	(via
		(at 97.813114 -329.553062)
		(size 0.508)
		(drill 0.254)
		(layers "F.Cu" "B.Cu")
		(net "CLK_100M_DB800ZL_PEX1_S0_R_DP")
	)
	(via
		(at 156.275024 -299.224954)
		(size 0.4064)
		(drill 0.2032)
		(layers "F.Cu" "B.Cu")
		(net "CLK_100M_DB800ZL_PEX1_S0_R_DP")
	)
	(segment
		(start 98.067114 -329.807062)
		(end 97.813114 -329.553062)
		(width 0.1143)
		(layer "B.Cu")
		(net "CLK_100M_DB800ZL_PEX1_S0_R_DP")
	)
	(segment
		(start 98.717862 -329.807062)
		(end 98.067114 -329.807062)
		(width 0.1143)
		(layer "B.Cu")
		(net "CLK_100M_DB800ZL_PEX1_S0_R_DP")
	)
	(segment
		(start 99.754944 -330.01585)
		(end 99.43084 -330.339954)
		(width 0.1143)
		(layer "B.Cu")
		(net "CLK_100M_DB800ZL_PEX1_S0_R_DP")
	)
	(segment
		(start 99.250754 -330.339954)
		(end 98.717862 -329.807062)
		(width 0.1143)
		(layer "B.Cu")
		(net "CLK_100M_DB800ZL_PEX1_S0_R_DP")
	)
	(segment
		(start 99.43084 -330.339954)
		(end 99.250754 -330.339954)
		(width 0.1143)
		(layer "B.Cu")
		(net "CLK_100M_DB800ZL_PEX1_S0_R_DP")
	)
	(segment
		(start 112.144556 -329.033378)
		(end 103.662734 -329.033378)
		(width 0.1397)
		(layer "In11.Cu")
		(net "CLK_100M_DB800ZL_PEX1_S0_R_DP")
	)
	(segment
		(start 120.662192 -327.602088)
		(end 120.982486 -327.922382)
		(width 0.1397)
		(layer "In11.Cu")
		(net "CLK_100M_DB800ZL_PEX1_S0_R_DP")
	)
	(segment
		(start 103.662734 -329.033378)
		(end 102.87635 -329.819762)
		(width 0.1397)
		(layer "In11.Cu")
		(net "CLK_100M_DB800ZL_PEX1_S0_R_DP")
	)
	(segment
		(start 102.87635 -329.819762)
		(end 98.079814 -329.819762)
		(width 0.1397)
		(layer "In11.Cu")
		(net "CLK_100M_DB800ZL_PEX1_S0_R_DP")
	)
	(segment
		(start 150.636478 -298.55414)
		(end 150.235158 -298.15282)
		(width 0.1397)
		(layer "In11.Cu")
		(net "CLK_100M_DB800ZL_PEX1_S0_R_DP")
	)
	(segment
		(start 115.161822 -326.016112)
		(end 112.144556 -329.033378)
		(width 0.1397)
		(layer "In11.Cu")
		(net "CLK_100M_DB800ZL_PEX1_S0_R_DP")
	)
	(segment
		(start 129.960116 -326.372982)
		(end 120.982486 -326.372982)
		(width 0.1397)
		(layer "In11.Cu")
		(net "CLK_100M_DB800ZL_PEX1_S0_R_DP")
	)
	(segment
		(start 120.982486 -326.372982)
		(end 120.662192 -326.693276)
		(width 0.1397)
		(layer "In11.Cu")
		(net "CLK_100M_DB800ZL_PEX1_S0_R_DP")
	)
	(segment
		(start 155.984194 -299.224954)
		(end 155.895294 -299.136054)
		(width 0.0889)
		(layer "In11.Cu")
		(net "CLK_100M_DB800ZL_PEX1_S0_R_DP")
	)
	(segment
		(start 119.773192 -328.684382)
		(end 119.773192 -326.693276)
		(width 0.1397)
		(layer "In11.Cu")
		(net "CLK_100M_DB800ZL_PEX1_S0_R_DP")
	)
	(segment
		(start 130.547618 -325.78548)
		(end 129.960116 -326.372982)
		(width 0.1397)
		(layer "In11.Cu")
		(net "CLK_100M_DB800ZL_PEX1_S0_R_DP")
	)
	(segment
		(start 119.773192 -326.693276)
		(end 119.096028 -326.016112)
		(width 0.1397)
		(layer "In11.Cu")
		(net "CLK_100M_DB800ZL_PEX1_S0_R_DP")
	)
	(segment
		(start 98.079814 -329.819762)
		(end 97.813114 -329.553062)
		(width 0.1397)
		(layer "In11.Cu")
		(net "CLK_100M_DB800ZL_PEX1_S0_R_DP")
	)
	(segment
		(start 139.886436 -302.062896)
		(end 133.543294 -311.556146)
		(width 0.1397)
		(layer "In11.Cu")
		(net "CLK_100M_DB800ZL_PEX1_S0_R_DP")
	)
	(segment
		(start 129.648458 -328.684382)
		(end 129.521458 -328.811382)
		(width 0.1397)
		(layer "In11.Cu")
		(net "CLK_100M_DB800ZL_PEX1_S0_R_DP")
	)
	(segment
		(start 120.662192 -326.693276)
		(end 120.662192 -327.602088)
		(width 0.1397)
		(layer "In11.Cu")
		(net "CLK_100M_DB800ZL_PEX1_S0_R_DP")
	)
	(segment
		(start 129.648458 -328.049382)
		(end 129.648458 -328.684382)
		(width 0.1397)
		(layer "In11.Cu")
		(net "CLK_100M_DB800ZL_PEX1_S0_R_DP")
	)
	(segment
		(start 119.900192 -328.811382)
		(end 119.773192 -328.684382)
		(width 0.1397)
		(layer "In11.Cu")
		(net "CLK_100M_DB800ZL_PEX1_S0_R_DP")
	)
	(segment
		(start 120.982486 -327.922382)
		(end 129.521458 -327.922382)
		(width 0.1397)
		(layer "In11.Cu")
		(net "CLK_100M_DB800ZL_PEX1_S0_R_DP")
	)
	(segment
		(start 151.476456 -298.62399)
		(end 151.406606 -298.55414)
		(width 0.0889)
		(layer "In11.Cu")
		(net "CLK_100M_DB800ZL_PEX1_S0_R_DP")
	)
	(segment
		(start 155.587954 -298.62399)
		(end 151.476456 -298.62399)
		(width 0.0889)
		(layer "In11.Cu")
		(net "CLK_100M_DB800ZL_PEX1_S0_R_DP")
	)
	(segment
		(start 133.543294 -311.556146)
		(end 130.547618 -318.788542)
		(width 0.1397)
		(layer "In11.Cu")
		(net "CLK_100M_DB800ZL_PEX1_S0_R_DP")
	)
	(segment
		(start 155.895294 -299.136054)
		(end 155.895294 -298.93133)
		(width 0.0889)
		(layer "In11.Cu")
		(net "CLK_100M_DB800ZL_PEX1_S0_R_DP")
	)
	(segment
		(start 155.895294 -298.93133)
		(end 155.587954 -298.62399)
		(width 0.0889)
		(layer "In11.Cu")
		(net "CLK_100M_DB800ZL_PEX1_S0_R_DP")
	)
	(segment
		(start 129.521458 -328.811382)
		(end 119.900192 -328.811382)
		(width 0.1397)
		(layer "In11.Cu")
		(net "CLK_100M_DB800ZL_PEX1_S0_R_DP")
	)
	(segment
		(start 142.204694 -299.744638)
		(end 139.886436 -302.062896)
		(width 0.1397)
		(layer "In11.Cu")
		(net "CLK_100M_DB800ZL_PEX1_S0_R_DP")
	)
	(segment
		(start 129.521458 -327.922382)
		(end 129.648458 -328.049382)
		(width 0.1397)
		(layer "In11.Cu")
		(net "CLK_100M_DB800ZL_PEX1_S0_R_DP")
	)
	(segment
		(start 151.406606 -298.55414)
		(end 151.384508 -298.55414)
		(width 0.0889)
		(layer "In11.Cu")
		(net "CLK_100M_DB800ZL_PEX1_S0_R_DP")
	)
	(segment
		(start 151.384508 -298.55414)
		(end 150.636478 -298.55414)
		(width 0.1397)
		(layer "In11.Cu")
		(net "CLK_100M_DB800ZL_PEX1_S0_R_DP")
	)
	(segment
		(start 150.235158 -298.15282)
		(end 147.541742 -298.15282)
		(width 0.1397)
		(layer "In11.Cu")
		(net "CLK_100M_DB800ZL_PEX1_S0_R_DP")
	)
	(segment
		(start 147.541742 -298.15282)
		(end 144.5641 -299.744638)
		(width 0.1397)
		(layer "In11.Cu")
		(net "CLK_100M_DB800ZL_PEX1_S0_R_DP")
	)
	(segment
		(start 144.5641 -299.744638)
		(end 142.204694 -299.744638)
		(width 0.1397)
		(layer "In11.Cu")
		(net "CLK_100M_DB800ZL_PEX1_S0_R_DP")
	)
	(segment
		(start 119.096028 -326.016112)
		(end 115.161822 -326.016112)
		(width 0.1397)
		(layer "In11.Cu")
		(net "CLK_100M_DB800ZL_PEX1_S0_R_DP")
	)
	(segment
		(start 156.275024 -299.224954)
		(end 155.984194 -299.224954)
		(width 0.0889)
		(layer "In11.Cu")
		(net "CLK_100M_DB800ZL_PEX1_S0_R_DP")
	)
	(segment
		(start 130.547618 -318.788542)
		(end 130.547618 -325.78548)
		(width 0.1397)
		(layer "In11.Cu")
		(net "CLK_100M_DB800ZL_PEX1_S0_R_DP")
	)
	(segment
		(start 215.689942 -236.157008)
		(end 215.69807 -236.165136)
		(width 0.13208)
		(layer "F.Cu")
		(net "SMB_PEX_LS_SDA")
	)
	(segment
		(start 214.73033 -236.157008)
		(end 215.689942 -236.157008)
		(width 0.13208)
		(layer "F.Cu")
		(net "SMB_PEX_LS_SDA")
	)
	(segment
		(start 213.062566 -236.412024)
		(end 213.062566 -236.157008)
		(width 0.13208)
		(layer "F.Cu")
		(net "SMB_PEX_LS_SDA")
	)
	(segment
		(start 212.405722 -237.687866)
		(end 212.405722 -237.068868)
		(width 0.13208)
		(layer "F.Cu")
		(net "SMB_PEX_LS_SDA")
	)
	(segment
		(start 212.405722 -237.068868)
		(end 213.062566 -236.412024)
		(width 0.13208)
		(layer "F.Cu")
		(net "SMB_PEX_LS_SDA")
	)
	(segment
		(start 212.405722 -237.687866)
		(end 212.405722 -238.653066)
		(width 0.13208)
		(layer "F.Cu")
		(net "SMB_PEX_LS_SDA")
	)
	(segment
		(start 213.062566 -236.157008)
		(end 214.73033 -236.157008)
		(width 0.13208)
		(layer "F.Cu")
		(net "SMB_PEX_LS_SDA")
	)
	(via
		(at 212.405722 -238.653066)
		(size 0.508)
		(drill 0.254)
		(layers "F.Cu" "B.Cu")
		(net "SMB_PEX_LS_SDA")
	)
	(via
		(at 213.789006 -239.075722)
		(size 0.6604)
		(drill 0.3302)
		(layers "F.Cu" "B.Cu")
		(net "SMB_PEX_LS_SDA")
	)
	(segment
		(start 212.569044 -237.97006)
		(end 212.405722 -238.133382)
		(width 0.13208)
		(layer "B.Cu")
		(net "SMB_PEX_LS_SDA")
	)
	(segment
		(start 213.320884 -237.97006)
		(end 212.569044 -237.97006)
		(width 0.13208)
		(layer "B.Cu")
		(net "SMB_PEX_LS_SDA")
	)
	(segment
		(start 213.789006 -239.075722)
		(end 213.413086 -239.451642)
		(width 0.13208)
		(layer "B.Cu")
		(net "SMB_PEX_LS_SDA")
	)
	(segment
		(start 212.405722 -238.133382)
		(end 212.405722 -238.653066)
		(width 0.13208)
		(layer "B.Cu")
		(net "SMB_PEX_LS_SDA")
	)
	(segment
		(start 213.789006 -238.438182)
		(end 213.320884 -237.97006)
		(width 0.13208)
		(layer "B.Cu")
		(net "SMB_PEX_LS_SDA")
	)
	(segment
		(start 213.413086 -239.451642)
		(end 212.585808 -239.451642)
		(width 0.13208)
		(layer "B.Cu")
		(net "SMB_PEX_LS_SDA")
	)
	(segment
		(start 213.789006 -239.075722)
		(end 213.789006 -238.438182)
		(width 0.13208)
		(layer "B.Cu")
		(net "SMB_PEX_LS_SDA")
	)
	(segment
		(start 349.293942 -225.587052)
		(end 349.693738 -225.986848)
		(width 0.13208)
		(layer "F.Cu")
		(net "NIC0_CLK_EN_N")
	)
	(via
		(at 351.155 -230.505)
		(size 0.6604)
		(drill 0.3302)
		(layers "F.Cu" "B.Cu")
		(net "NIC0_CLK_EN_N")
	)
	(via
		(at 349.693738 -225.986848)
		(size 0.4572)
		(drill 0.254)
		(layers "F.Cu" "B.Cu")
		(net "NIC0_CLK_EN_N")
	)
	(segment
		(start 351.155 -233.15295)
		(end 351.155 -230.505)
		(width 0.13208)
		(layer "B.Cu")
		(net "NIC0_CLK_EN_N")
	)
	(segment
		(start 350.092518 -227.24618)
		(end 350.880172 -228.033834)
		(width 0.13208)
		(layer "B.Cu")
		(net "NIC0_CLK_EN_N")
	)
	(segment
		(start 350.880172 -228.994462)
		(end 351.155 -229.26929)
		(width 0.13208)
		(layer "B.Cu")
		(net "NIC0_CLK_EN_N")
	)
	(segment
		(start 351.155 -229.26929)
		(end 351.155 -230.505)
		(width 0.13208)
		(layer "B.Cu")
		(net "NIC0_CLK_EN_N")
	)
	(segment
		(start 350.092518 -226.385628)
		(end 350.092518 -227.24618)
		(width 0.0889)
		(layer "B.Cu")
		(net "NIC0_CLK_EN_N")
	)
	(segment
		(start 350.880172 -228.033834)
		(end 350.880172 -228.994462)
		(width 0.13208)
		(layer "B.Cu")
		(net "NIC0_CLK_EN_N")
	)
	(segment
		(start 349.693738 -225.986848)
		(end 350.092518 -226.385628)
		(width 0.0889)
		(layer "B.Cu")
		(net "NIC0_CLK_EN_N")
	)
	(segment
		(start 223.633792 -66.722498)
		(end 224.311972 -66.722498)
		(width 0.13208)
		(layer "F.Cu")
		(net "SMB_FIO_R1_SDA")
	)
	(segment
		(start 341.044022 -198.4629)
		(end 341.571072 -198.4629)
		(width 0.13208)
		(layer "F.Cu")
		(net "SMB_FIO_R1_SDA")
	)
	(segment
		(start 223.45396 -66.112136)
		(end 223.45396 -66.542666)
		(width 0.13208)
		(layer "F.Cu")
		(net "SMB_FIO_R1_SDA")
	)
	(segment
		(start 223.45396 -66.542666)
		(end 223.633792 -66.722498)
		(width 0.13208)
		(layer "F.Cu")
		(net "SMB_FIO_R1_SDA")
	)
	(segment
		(start 340.961472 -198.54545)
		(end 341.044022 -198.4629)
		(width 0.13208)
		(layer "F.Cu")
		(net "SMB_FIO_R1_SDA")
	)
	(via
		(at 215.473788 -225.658934)
		(size 0.508)
		(drill 0.254)
		(layers "F.Cu" "B.Cu")
		(net "SMB_FIO_R1_SDA")
	)
	(via
		(at 224.311972 -66.722498)
		(size 0.508)
		(drill 0.254)
		(layers "F.Cu" "B.Cu")
		(net "SMB_FIO_R1_SDA")
	)
	(via
		(at 206.667862 -189.701424)
		(size 0.508)
		(drill 0.254)
		(layers "F.Cu" "B.Cu")
		(net "SMB_FIO_R1_SDA")
	)
	(via
		(at 341.571072 -198.4629)
		(size 0.508)
		(drill 0.254)
		(layers "F.Cu" "B.Cu")
		(net "SMB_FIO_R1_SDA")
	)
	(segment
		(start 216.866724 -225.500692)
		(end 216.84361 -225.477578)
		(width 0.13208)
		(layer "B.Cu")
		(net "SMB_FIO_R1_SDA")
	)
	(segment
		(start 216.84361 -226.004882)
		(end 216.84361 -225.937572)
		(width 0.13208)
		(layer "B.Cu")
		(net "SMB_FIO_R1_SDA")
	)
	(segment
		(start 215.489536 -225.674682)
		(end 215.489536 -225.777298)
		(width 0.13208)
		(layer "B.Cu")
		(net "SMB_FIO_R1_SDA")
	)
	(segment
		(start 216.712292 -226.1362)
		(end 216.84361 -226.004882)
		(width 0.13208)
		(layer "B.Cu")
		(net "SMB_FIO_R1_SDA")
	)
	(segment
		(start 215.848438 -226.1362)
		(end 216.712292 -226.1362)
		(width 0.13208)
		(layer "B.Cu")
		(net "SMB_FIO_R1_SDA")
	)
	(segment
		(start 215.489536 -225.777298)
		(end 215.848438 -226.1362)
		(width 0.13208)
		(layer "B.Cu")
		(net "SMB_FIO_R1_SDA")
	)
	(segment
		(start 216.866724 -225.914458)
		(end 216.866724 -225.500692)
		(width 0.13208)
		(layer "B.Cu")
		(net "SMB_FIO_R1_SDA")
	)
	(segment
		(start 216.84361 -225.937572)
		(end 216.866724 -225.914458)
		(width 0.13208)
		(layer "B.Cu")
		(net "SMB_FIO_R1_SDA")
	)
	(segment
		(start 215.473788 -225.658934)
		(end 215.489536 -225.674682)
		(width 0.13208)
		(layer "B.Cu")
		(net "SMB_FIO_R1_SDA")
	)
	(segment
		(start 204.7748 -113.3094)
		(end 204.7748 -125.374654)
		(width 0.15494)
		(layer "In7.Cu")
		(net "SMB_FIO_R1_SDA")
	)
	(segment
		(start 211.340192 -135.949436)
		(end 211.455 -136.527032)
		(width 0.15494)
		(layer "In7.Cu")
		(net "SMB_FIO_R1_SDA")
	)
	(segment
		(start 222.1103 -73.17994)
		(end 214.91194 -80.3783)
		(width 0.15494)
		(layer "In7.Cu")
		(net "SMB_FIO_R1_SDA")
	)
	(segment
		(start 203.7842 -112.3188)
		(end 204.7748 -113.3094)
		(width 0.15494)
		(layer "In7.Cu")
		(net "SMB_FIO_R1_SDA")
	)
	(segment
		(start 214.585296 -226.079558)
		(end 212.612224 -226.079558)
		(width 0.15494)
		(layer "In7.Cu")
		(net "SMB_FIO_R1_SDA")
	)
	(segment
		(start 203.7842 -103.124)
		(end 203.7842 -112.3188)
		(width 0.15494)
		(layer "In7.Cu")
		(net "SMB_FIO_R1_SDA")
	)
	(segment
		(start 212.2932 -225.760534)
		(end 210.972146 -225.760534)
		(width 0.15494)
		(layer "In7.Cu")
		(net "SMB_FIO_R1_SDA")
	)
	(segment
		(start 224.66554 -71.3105)
		(end 222.7961 -73.17994)
		(width 0.15494)
		(layer "In7.Cu")
		(net "SMB_FIO_R1_SDA")
	)
	(segment
		(start 214.91194 -87.1347)
		(end 212.701886 -89.344754)
		(width 0.15494)
		(layer "In7.Cu")
		(net "SMB_FIO_R1_SDA")
	)
	(segment
		(start 215.38438 -225.748342)
		(end 214.585296 -226.079558)
		(width 0.15494)
		(layer "In7.Cu")
		(net "SMB_FIO_R1_SDA")
	)
	(segment
		(start 209.384646 -89.344754)
		(end 203.314554 -95.414846)
		(width 0.15494)
		(layer "In7.Cu")
		(net "SMB_FIO_R1_SDA")
	)
	(segment
		(start 207.620362 -185.776616)
		(end 207.620362 -186.378342)
		(width 0.15494)
		(layer "In7.Cu")
		(net "SMB_FIO_R1_SDA")
	)
	(segment
		(start 203.314554 -95.414846)
		(end 202.2856 -97.898712)
		(width 0.15494)
		(layer "In7.Cu")
		(net "SMB_FIO_R1_SDA")
	)
	(segment
		(start 202.2856 -101.6254)
		(end 203.7842 -103.124)
		(width 0.15494)
		(layer "In7.Cu")
		(net "SMB_FIO_R1_SDA")
	)
	(segment
		(start 210.683094 -225.471482)
		(end 209.468974 -225.471482)
		(width 0.15494)
		(layer "In7.Cu")
		(net "SMB_FIO_R1_SDA")
	)
	(segment
		(start 214.91194 -80.3783)
		(end 214.91194 -87.1347)
		(width 0.15494)
		(layer "In7.Cu")
		(net "SMB_FIO_R1_SDA")
	)
	(segment
		(start 224.66554 -67.076066)
		(end 224.66554 -71.3105)
		(width 0.15494)
		(layer "In7.Cu")
		(net "SMB_FIO_R1_SDA")
	)
	(segment
		(start 202.19924 -194.170046)
		(end 206.667862 -189.701424)
		(width 0.15494)
		(layer "In7.Cu")
		(net "SMB_FIO_R1_SDA")
	)
	(segment
		(start 224.311972 -66.722498)
		(end 224.66554 -67.076066)
		(width 0.15494)
		(layer "In7.Cu")
		(net "SMB_FIO_R1_SDA")
	)
	(segment
		(start 211.340192 -131.940046)
		(end 211.340192 -135.949436)
		(width 0.15494)
		(layer "In7.Cu")
		(net "SMB_FIO_R1_SDA")
	)
	(segment
		(start 212.612224 -226.079558)
		(end 212.2932 -225.760534)
		(width 0.15494)
		(layer "In7.Cu")
		(net "SMB_FIO_R1_SDA")
	)
	(segment
		(start 210.7946 -164.875972)
		(end 206.370428 -169.300144)
		(width 0.15494)
		(layer "In7.Cu")
		(net "SMB_FIO_R1_SDA")
	)
	(segment
		(start 212.701886 -89.344754)
		(end 209.384646 -89.344754)
		(width 0.15494)
		(layer "In7.Cu")
		(net "SMB_FIO_R1_SDA")
	)
	(segment
		(start 205.6638 -222.07728)
		(end 202.19924 -218.61272)
		(width 0.15494)
		(layer "In7.Cu")
		(net "SMB_FIO_R1_SDA")
	)
	(segment
		(start 207.1878 -189.181486)
		(end 206.667862 -189.701424)
		(width 0.15494)
		(layer "In7.Cu")
		(net "SMB_FIO_R1_SDA")
	)
	(segment
		(start 206.370428 -169.300144)
		(end 206.370428 -184.526682)
		(width 0.15494)
		(layer "In7.Cu")
		(net "SMB_FIO_R1_SDA")
	)
	(segment
		(start 204.7748 -125.374654)
		(end 211.340192 -131.940046)
		(width 0.15494)
		(layer "In7.Cu")
		(net "SMB_FIO_R1_SDA")
	)
	(segment
		(start 210.972146 -225.760534)
		(end 210.683094 -225.471482)
		(width 0.15494)
		(layer "In7.Cu")
		(net "SMB_FIO_R1_SDA")
	)
	(segment
		(start 206.074772 -222.07728)
		(end 205.6638 -222.07728)
		(width 0.15494)
		(layer "In7.Cu")
		(net "SMB_FIO_R1_SDA")
	)
	(segment
		(start 210.7946 -161.239454)
		(end 210.7946 -164.875972)
		(width 0.15494)
		(layer "In7.Cu")
		(net "SMB_FIO_R1_SDA")
	)
	(segment
		(start 202.19924 -218.61272)
		(end 202.19924 -194.170046)
		(width 0.15494)
		(layer "In7.Cu")
		(net "SMB_FIO_R1_SDA")
	)
	(segment
		(start 202.2856 -97.898712)
		(end 202.2856 -101.6254)
		(width 0.15494)
		(layer "In7.Cu")
		(net "SMB_FIO_R1_SDA")
	)
	(segment
		(start 215.473788 -225.658934)
		(end 215.38438 -225.748342)
		(width 0.15494)
		(layer "In7.Cu")
		(net "SMB_FIO_R1_SDA")
	)
	(segment
		(start 209.468974 -225.471482)
		(end 206.074772 -222.07728)
		(width 0.15494)
		(layer "In7.Cu")
		(net "SMB_FIO_R1_SDA")
	)
	(segment
		(start 207.620362 -186.378342)
		(end 207.1878 -186.810904)
		(width 0.15494)
		(layer "In7.Cu")
		(net "SMB_FIO_R1_SDA")
	)
	(segment
		(start 207.1878 -186.810904)
		(end 207.1878 -189.181486)
		(width 0.15494)
		(layer "In7.Cu")
		(net "SMB_FIO_R1_SDA")
	)
	(segment
		(start 222.7961 -73.17994)
		(end 222.1103 -73.17994)
		(width 0.15494)
		(layer "In7.Cu")
		(net "SMB_FIO_R1_SDA")
	)
	(segment
		(start 211.455 -136.527032)
		(end 211.455 -160.579054)
		(width 0.15494)
		(layer "In7.Cu")
		(net "SMB_FIO_R1_SDA")
	)
	(segment
		(start 211.455 -160.579054)
		(end 210.7946 -161.239454)
		(width 0.15494)
		(layer "In7.Cu")
		(net "SMB_FIO_R1_SDA")
	)
	(segment
		(start 206.370428 -184.526682)
		(end 207.620362 -185.776616)
		(width 0.15494)
		(layer "In7.Cu")
		(net "SMB_FIO_R1_SDA")
	)
	(segment
		(start 206.667862 -189.701424)
		(end 207.97012 -189.701424)
		(width 0.15494)
		(layer "In15.Cu")
		(net "SMB_FIO_R1_SDA")
	)
	(segment
		(start 327.770744 -192.809622)
		(end 330.528168 -195.567046)
		(width 0.15494)
		(layer "In15.Cu")
		(net "SMB_FIO_R1_SDA")
	)
	(segment
		(start 255.276604 -189.011052)
		(end 272.119344 -189.011052)
		(width 0.15494)
		(layer "In15.Cu")
		(net "SMB_FIO_R1_SDA")
	)
	(segment
		(start 330.528168 -195.567046)
		(end 338.675218 -195.567046)
		(width 0.15494)
		(layer "In15.Cu")
		(net "SMB_FIO_R1_SDA")
	)
	(segment
		(start 209.54492 -188.126624)
		(end 220.434916 -188.126624)
		(width 0.15494)
		(layer "In15.Cu")
		(net "SMB_FIO_R1_SDA")
	)
	(segment
		(start 241.381534 -192.498472)
		(end 251.789184 -192.498472)
		(width 0.15494)
		(layer "In15.Cu")
		(net "SMB_FIO_R1_SDA")
	)
	(segment
		(start 325.846694 -192.809622)
		(end 327.770744 -192.809622)
		(width 0.15494)
		(layer "In15.Cu")
		(net "SMB_FIO_R1_SDA")
	)
	(segment
		(start 207.97012 -189.701424)
		(end 209.54492 -188.126624)
		(width 0.15494)
		(layer "In15.Cu")
		(net "SMB_FIO_R1_SDA")
	)
	(segment
		(start 272.119344 -189.011052)
		(end 275.000466 -191.892174)
		(width 0.15494)
		(layer "In15.Cu")
		(net "SMB_FIO_R1_SDA")
	)
	(segment
		(start 338.675218 -195.567046)
		(end 341.571072 -198.4629)
		(width 0.15494)
		(layer "In15.Cu")
		(net "SMB_FIO_R1_SDA")
	)
	(segment
		(start 220.434916 -188.126624)
		(end 221.329504 -187.232036)
		(width 0.15494)
		(layer "In15.Cu")
		(net "SMB_FIO_R1_SDA")
	)
	(segment
		(start 221.329504 -187.232036)
		(end 236.115098 -187.232036)
		(width 0.15494)
		(layer "In15.Cu")
		(net "SMB_FIO_R1_SDA")
	)
	(segment
		(start 236.115098 -187.232036)
		(end 241.381534 -192.498472)
		(width 0.15494)
		(layer "In15.Cu")
		(net "SMB_FIO_R1_SDA")
	)
	(segment
		(start 251.789184 -192.498472)
		(end 255.276604 -189.011052)
		(width 0.15494)
		(layer "In15.Cu")
		(net "SMB_FIO_R1_SDA")
	)
	(segment
		(start 275.000466 -191.892174)
		(end 324.929246 -191.892174)
		(width 0.15494)
		(layer "In15.Cu")
		(net "SMB_FIO_R1_SDA")
	)
	(segment
		(start 324.929246 -191.892174)
		(end 325.846694 -192.809622)
		(width 0.15494)
		(layer "In15.Cu")
		(net "SMB_FIO_R1_SDA")
	)
	(segment
		(start 346.093796 -223.187006)
		(end 346.493592 -223.586802)
		(width 0.13208)
		(layer "F.Cu")
		(net "NIC0_AUX_PWR_EN")
	)
	(via
		(at 50.53076 -139.96416)
		(size 0.6604)
		(drill 0.3302)
		(layers "F.Cu" "B.Cu")
		(net "NIC0_AUX_PWR_EN")
	)
	(via
		(at 50.92573 -146.795998)
		(size 0.508)
		(drill 0.254)
		(layers "F.Cu" "B.Cu")
		(net "NIC0_AUX_PWR_EN")
	)
	(via
		(at 346.493592 -223.586802)
		(size 0.4572)
		(drill 0.254)
		(layers "F.Cu" "B.Cu")
		(net "NIC0_AUX_PWR_EN")
	)
	(via
		(at 52.309014 -169.909236)
		(size 0.508)
		(drill 0.254)
		(layers "F.Cu" "B.Cu")
		(net "NIC0_AUX_PWR_EN")
	)
	(segment
		(start 50.243994 -138.421618)
		(end 50.243994 -139.677394)
		(width 0.13208)
		(layer "B.Cu")
		(net "NIC0_AUX_PWR_EN")
	)
	(segment
		(start 50.243994 -139.677394)
		(end 50.53076 -139.96416)
		(width 0.13208)
		(layer "B.Cu")
		(net "NIC0_AUX_PWR_EN")
	)
	(segment
		(start 49.266094 -138.421618)
		(end 50.243994 -138.421618)
		(width 0.13208)
		(layer "B.Cu")
		(net "NIC0_AUX_PWR_EN")
	)
	(segment
		(start 50.53076 -139.96416)
		(end 50.92573 -140.35913)
		(width 0.13208)
		(layer "B.Cu")
		(net "NIC0_AUX_PWR_EN")
	)
	(segment
		(start 50.92573 -140.35913)
		(end 50.92573 -146.795998)
		(width 0.13208)
		(layer "B.Cu")
		(net "NIC0_AUX_PWR_EN")
	)
	(segment
		(start 53.744114 -168.474136)
		(end 53.744114 -148.296122)
		(width 0.15494)
		(layer "In9.Cu")
		(net "NIC0_AUX_PWR_EN")
	)
	(segment
		(start 52.309014 -169.909236)
		(end 53.744114 -168.474136)
		(width 0.15494)
		(layer "In9.Cu")
		(net "NIC0_AUX_PWR_EN")
	)
	(segment
		(start 53.744114 -148.296122)
		(end 52.24399 -146.795998)
		(width 0.15494)
		(layer "In9.Cu")
		(net "NIC0_AUX_PWR_EN")
	)
	(segment
		(start 52.24399 -146.795998)
		(end 50.92573 -146.795998)
		(width 0.15494)
		(layer "In9.Cu")
		(net "NIC0_AUX_PWR_EN")
	)
	(segment
		(start 113.03254 -186.2328)
		(end 125.170946 -186.2328)
		(width 0.15494)
		(layer "In15.Cu")
		(net "NIC0_AUX_PWR_EN")
	)
	(segment
		(start 86.69528 -169.909236)
		(end 102.355396 -185.569352)
		(width 0.15494)
		(layer "In15.Cu")
		(net "NIC0_AUX_PWR_EN")
	)
	(segment
		(start 237.049056 -170.95978)
		(end 239.147096 -173.05782)
		(width 0.15494)
		(layer "In15.Cu")
		(net "NIC0_AUX_PWR_EN")
	)
	(segment
		(start 350.095312 -227.765102)
		(end 350.095312 -227.2792)
		(width 0.15494)
		(layer "In15.Cu")
		(net "NIC0_AUX_PWR_EN")
	)
	(segment
		(start 180.59146 -174.244254)
		(end 181.74335 -173.092364)
		(width 0.15494)
		(layer "In15.Cu")
		(net "NIC0_AUX_PWR_EN")
	)
	(segment
		(start 257.482086 -170.96486)
		(end 285.47949 -170.96486)
		(width 0.15494)
		(layer "In15.Cu")
		(net "NIC0_AUX_PWR_EN")
	)
	(segment
		(start 349.022162 -223.985582)
		(end 347.962474 -223.985582)
		(width 0.0889)
		(layer "In15.Cu")
		(net "NIC0_AUX_PWR_EN")
	)
	(segment
		(start 366.538764 -176.141126)
		(end 370.934996 -180.537358)
		(width 0.15494)
		(layer "In15.Cu")
		(net "NIC0_AUX_PWR_EN")
	)
	(segment
		(start 106.231944 -187.17514)
		(end 112.0902 -187.17514)
		(width 0.15494)
		(layer "In15.Cu")
		(net "NIC0_AUX_PWR_EN")
	)
	(segment
		(start 255.389126 -173.05782)
		(end 257.482086 -170.96486)
		(width 0.15494)
		(layer "In15.Cu")
		(net "NIC0_AUX_PWR_EN")
	)
	(segment
		(start 369.276884 -233.657394)
		(end 356.949248 -233.657394)
		(width 0.15494)
		(layer "In15.Cu")
		(net "NIC0_AUX_PWR_EN")
	)
	(segment
		(start 373.15267 -191.721486)
		(end 373.15267 -229.781608)
		(width 0.15494)
		(layer "In15.Cu")
		(net "NIC0_AUX_PWR_EN")
	)
	(segment
		(start 364.396528 -172.13199)
		(end 366.538764 -174.274226)
		(width 0.15494)
		(layer "In15.Cu")
		(net "NIC0_AUX_PWR_EN")
	)
	(segment
		(start 179.715668 -174.606966)
		(end 180.302662 -174.363888)
		(width 0.15494)
		(layer "In15.Cu")
		(net "NIC0_AUX_PWR_EN")
	)
	(segment
		(start 370.934996 -183.263794)
		(end 374.22328 -186.552078)
		(width 0.15494)
		(layer "In15.Cu")
		(net "NIC0_AUX_PWR_EN")
	)
	(segment
		(start 177.886106 -174.606966)
		(end 179.715668 -174.606966)
		(width 0.15494)
		(layer "In15.Cu")
		(net "NIC0_AUX_PWR_EN")
	)
	(segment
		(start 112.0902 -187.17514)
		(end 113.03254 -186.2328)
		(width 0.15494)
		(layer "In15.Cu")
		(net "NIC0_AUX_PWR_EN")
	)
	(segment
		(start 102.355396 -185.569352)
		(end 106.231944 -187.17514)
		(width 0.15494)
		(layer "In15.Cu")
		(net "NIC0_AUX_PWR_EN")
	)
	(segment
		(start 370.934996 -180.537358)
		(end 370.934996 -183.263794)
		(width 0.15494)
		(layer "In15.Cu")
		(net "NIC0_AUX_PWR_EN")
	)
	(segment
		(start 141.310614 -186.65825)
		(end 165.834822 -186.65825)
		(width 0.15494)
		(layer "In15.Cu")
		(net "NIC0_AUX_PWR_EN")
	)
	(segment
		(start 335.946242 -169.046398)
		(end 343.509854 -169.046398)
		(width 0.15494)
		(layer "In15.Cu")
		(net "NIC0_AUX_PWR_EN")
	)
	(segment
		(start 349.296228 -224.259648)
		(end 349.022162 -223.985582)
		(width 0.0889)
		(layer "In15.Cu")
		(net "NIC0_AUX_PWR_EN")
	)
	(segment
		(start 215.532462 -170.95978)
		(end 237.049056 -170.95978)
		(width 0.15494)
		(layer "In15.Cu")
		(net "NIC0_AUX_PWR_EN")
	)
	(segment
		(start 213.399878 -173.092364)
		(end 215.532462 -170.95978)
		(width 0.15494)
		(layer "In15.Cu")
		(net "NIC0_AUX_PWR_EN")
	)
	(segment
		(start 333.58074 -169.79773)
		(end 334.82534 -168.55313)
		(width 0.15494)
		(layer "In15.Cu")
		(net "NIC0_AUX_PWR_EN")
	)
	(segment
		(start 373.15267 -229.781608)
		(end 369.276884 -233.657394)
		(width 0.15494)
		(layer "In15.Cu")
		(net "NIC0_AUX_PWR_EN")
	)
	(segment
		(start 346.882466 -172.41901)
		(end 353.05619 -172.41901)
		(width 0.15494)
		(layer "In15.Cu")
		(net "NIC0_AUX_PWR_EN")
	)
	(segment
		(start 374.22328 -190.650876)
		(end 373.15267 -191.721486)
		(width 0.15494)
		(layer "In15.Cu")
		(net "NIC0_AUX_PWR_EN")
	)
	(segment
		(start 239.147096 -173.05782)
		(end 255.389126 -173.05782)
		(width 0.15494)
		(layer "In15.Cu")
		(net "NIC0_AUX_PWR_EN")
	)
	(segment
		(start 353.05619 -172.41901)
		(end 353.34321 -172.13199)
		(width 0.15494)
		(layer "In15.Cu")
		(net "NIC0_AUX_PWR_EN")
	)
	(segment
		(start 347.962474 -223.985582)
		(end 347.691202 -223.71431)
		(width 0.0889)
		(layer "In15.Cu")
		(net "NIC0_AUX_PWR_EN")
	)
	(segment
		(start 347.691202 -223.454468)
		(end 347.448886 -223.212152)
		(width 0.0889)
		(layer "In15.Cu")
		(net "NIC0_AUX_PWR_EN")
	)
	(segment
		(start 343.509854 -169.046398)
		(end 346.882466 -172.41901)
		(width 0.15494)
		(layer "In15.Cu")
		(net "NIC0_AUX_PWR_EN")
	)
	(segment
		(start 351.495106 -229.164896)
		(end 350.095312 -227.765102)
		(width 0.15494)
		(layer "In15.Cu")
		(net "NIC0_AUX_PWR_EN")
	)
	(segment
		(start 374.22328 -186.552078)
		(end 374.22328 -190.650876)
		(width 0.15494)
		(layer "In15.Cu")
		(net "NIC0_AUX_PWR_EN")
	)
	(segment
		(start 52.309014 -169.909236)
		(end 86.69528 -169.909236)
		(width 0.15494)
		(layer "In15.Cu")
		(net "NIC0_AUX_PWR_EN")
	)
	(segment
		(start 350.095312 -227.2792)
		(end 350.095312 -226.658678)
		(width 0.0889)
		(layer "In15.Cu")
		(net "NIC0_AUX_PWR_EN")
	)
	(segment
		(start 349.82404 -226.387406)
		(end 349.564452 -226.387406)
		(width 0.0889)
		(layer "In15.Cu")
		(net "NIC0_AUX_PWR_EN")
	)
	(segment
		(start 180.302662 -174.363888)
		(end 180.59146 -174.244254)
		(width 0.15494)
		(layer "In15.Cu")
		(net "NIC0_AUX_PWR_EN")
	)
	(segment
		(start 128.01092 -189.072012)
		(end 138.896852 -189.072012)
		(width 0.15494)
		(layer "In15.Cu")
		(net "NIC0_AUX_PWR_EN")
	)
	(segment
		(start 347.691202 -223.71431)
		(end 347.691202 -223.454468)
		(width 0.0889)
		(layer "In15.Cu")
		(net "NIC0_AUX_PWR_EN")
	)
	(segment
		(start 350.095312 -226.658678)
		(end 349.82404 -226.387406)
		(width 0.0889)
		(layer "In15.Cu")
		(net "NIC0_AUX_PWR_EN")
	)
	(segment
		(start 356.949248 -233.657394)
		(end 352.45675 -229.164896)
		(width 0.15494)
		(layer "In15.Cu")
		(net "NIC0_AUX_PWR_EN")
	)
	(segment
		(start 349.296228 -226.119182)
		(end 349.296228 -224.259648)
		(width 0.0889)
		(layer "In15.Cu")
		(net "NIC0_AUX_PWR_EN")
	)
	(segment
		(start 347.448886 -223.212152)
		(end 346.868242 -223.212152)
		(width 0.0889)
		(layer "In15.Cu")
		(net "NIC0_AUX_PWR_EN")
	)
	(segment
		(start 366.538764 -174.274226)
		(end 366.538764 -176.141126)
		(width 0.15494)
		(layer "In15.Cu")
		(net "NIC0_AUX_PWR_EN")
	)
	(segment
		(start 285.47949 -170.96486)
		(end 286.648144 -169.79773)
		(width 0.15494)
		(layer "In15.Cu")
		(net "NIC0_AUX_PWR_EN")
	)
	(segment
		(start 334.82534 -168.55313)
		(end 335.452974 -168.55313)
		(width 0.15494)
		(layer "In15.Cu")
		(net "NIC0_AUX_PWR_EN")
	)
	(segment
		(start 353.34321 -172.13199)
		(end 364.396528 -172.13199)
		(width 0.15494)
		(layer "In15.Cu")
		(net "NIC0_AUX_PWR_EN")
	)
	(segment
		(start 335.452974 -168.55313)
		(end 335.946242 -169.046398)
		(width 0.15494)
		(layer "In15.Cu")
		(net "NIC0_AUX_PWR_EN")
	)
	(segment
		(start 181.74335 -173.092364)
		(end 213.399878 -173.092364)
		(width 0.15494)
		(layer "In15.Cu")
		(net "NIC0_AUX_PWR_EN")
	)
	(segment
		(start 138.896852 -189.072012)
		(end 141.310614 -186.65825)
		(width 0.15494)
		(layer "In15.Cu")
		(net "NIC0_AUX_PWR_EN")
	)
	(segment
		(start 346.868242 -223.212152)
		(end 346.493592 -223.586802)
		(width 0.0889)
		(layer "In15.Cu")
		(net "NIC0_AUX_PWR_EN")
	)
	(segment
		(start 349.564452 -226.387406)
		(end 349.296228 -226.119182)
		(width 0.0889)
		(layer "In15.Cu")
		(net "NIC0_AUX_PWR_EN")
	)
	(segment
		(start 125.170946 -186.2328)
		(end 128.01092 -189.072012)
		(width 0.15494)
		(layer "In15.Cu")
		(net "NIC0_AUX_PWR_EN")
	)
	(segment
		(start 352.45675 -229.164896)
		(end 351.495106 -229.164896)
		(width 0.15494)
		(layer "In15.Cu")
		(net "NIC0_AUX_PWR_EN")
	)
	(segment
		(start 165.834822 -186.65825)
		(end 177.886106 -174.606966)
		(width 0.15494)
		(layer "In15.Cu")
		(net "NIC0_AUX_PWR_EN")
	)
	(segment
		(start 286.648144 -169.79773)
		(end 333.58074 -169.79773)
		(width 0.15494)
		(layer "In15.Cu")
		(net "NIC0_AUX_PWR_EN")
	)
	(via
		(at 39.699946 -298.74972)
		(size 0.4064)
		(drill 0.2032)
		(layers "F.Cu" "B.Cu")
		(net "CLK_100M_DB800ZL_PEX0_S0_R_DN")
	)
	(segment
		(start 35.334702 -300.93285)
		(end 35.3568 -300.93285)
		(width 0.0889)
		(layer "B.Cu")
		(net "CLK_100M_DB800ZL_PEX0_S0_R_DN")
	)
	(segment
		(start 39.869872 -301.0154)
		(end 40.073326 -300.811946)
		(width 0.0889)
		(layer "B.Cu")
		(net "CLK_100M_DB800ZL_PEX0_S0_R_DN")
	)
	(segment
		(start 40.073326 -298.83862)
		(end 39.984426 -298.74972)
		(width 0.0889)
		(layer "B.Cu")
		(net "CLK_100M_DB800ZL_PEX0_S0_R_DN")
	)
	(segment
		(start 35.3568 -300.93285)
		(end 35.43935 -301.0154)
		(width 0.0889)
		(layer "B.Cu")
		(net "CLK_100M_DB800ZL_PEX0_S0_R_DN")
	)
	(segment
		(start 39.984426 -298.74972)
		(end 39.699946 -298.74972)
		(width 0.0889)
		(layer "B.Cu")
		(net "CLK_100M_DB800ZL_PEX0_S0_R_DN")
	)
	(segment
		(start 35.43935 -301.0154)
		(end 39.869872 -301.0154)
		(width 0.0889)
		(layer "B.Cu")
		(net "CLK_100M_DB800ZL_PEX0_S0_R_DN")
	)
	(segment
		(start 95.201994 -328.439272)
		(end 55.99557 -328.439272)
		(width 0.1143)
		(layer "B.Cu")
		(net "CLK_100M_DB800ZL_PEX0_S0_R_DN")
	)
	(segment
		(start 30.30855 -300.93285)
		(end 35.334702 -300.93285)
		(width 0.1143)
		(layer "B.Cu")
		(net "CLK_100M_DB800ZL_PEX0_S0_R_DN")
	)
	(segment
		(start 105.34269 -325.752206)
		(end 105.664 -325.430896)
		(width 0.1143)
		(layer "B.Cu")
		(net "CLK_100M_DB800ZL_PEX0_S0_R_DN")
	)
	(segment
		(start 40.073326 -300.811946)
		(end 40.073326 -298.83862)
		(width 0.0889)
		(layer "B.Cu")
		(net "CLK_100M_DB800ZL_PEX0_S0_R_DN")
	)
	(segment
		(start 105.664 -325.061072)
		(end 105.443528 -324.8406)
		(width 0.1143)
		(layer "B.Cu")
		(net "CLK_100M_DB800ZL_PEX0_S0_R_DN")
	)
	(segment
		(start 36.954206 -320.552064)
		(end 26.1493 -309.746904)
		(width 0.1143)
		(layer "B.Cu")
		(net "CLK_100M_DB800ZL_PEX0_S0_R_DN")
	)
	(segment
		(start 105.664 -325.430896)
		(end 105.664 -325.061072)
		(width 0.1143)
		(layer "B.Cu")
		(net "CLK_100M_DB800ZL_PEX0_S0_R_DN")
	)
	(segment
		(start 103.890572 -324.8406)
		(end 95.201994 -328.439272)
		(width 0.1143)
		(layer "B.Cu")
		(net "CLK_100M_DB800ZL_PEX0_S0_R_DN")
	)
	(segment
		(start 55.99557 -328.439272)
		(end 36.954206 -320.552064)
		(width 0.1143)
		(layer "B.Cu")
		(net "CLK_100M_DB800ZL_PEX0_S0_R_DN")
	)
	(segment
		(start 26.1493 -305.0921)
		(end 30.30855 -300.93285)
		(width 0.1143)
		(layer "B.Cu")
		(net "CLK_100M_DB800ZL_PEX0_S0_R_DN")
	)
	(segment
		(start 26.1493 -309.746904)
		(end 26.1493 -305.0921)
		(width 0.1143)
		(layer "B.Cu")
		(net "CLK_100M_DB800ZL_PEX0_S0_R_DN")
	)
	(segment
		(start 105.443528 -324.8406)
		(end 103.890572 -324.8406)
		(width 0.1143)
		(layer "B.Cu")
		(net "CLK_100M_DB800ZL_PEX0_S0_R_DN")
	)
	(segment
		(start 99.97948 -385.177792)
		(end 100.499418 -385.177792)
		(width 0.13462)
		(layer "F.Cu")
		(net "USB2_MB_BMC_DN")
	)
	(segment
		(start 100.499418 -385.177792)
		(end 100.905564 -385.583938)
		(width 0.13462)
		(layer "F.Cu")
		(net "USB2_MB_BMC_DN")
	)
	(via
		(at 94.495112 -389.643366)
		(size 0.4064)
		(drill 0.2032)
		(layers "F.Cu" "B.Cu")
		(net "USB2_MB_BMC_DN")
	)
	(via
		(at 100.905564 -385.583938)
		(size 0.508)
		(drill 0.254)
		(layers "F.Cu" "B.Cu")
		(net "USB2_MB_BMC_DN")
	)
	(segment
		(start 94.495112 -389.643366)
		(end 92.084144 -393.250674)
		(width 0.13462)
		(layer "B.Cu")
		(net "USB2_MB_BMC_DN")
	)
	(segment
		(start 94.495112 -389.643366)
		(end 96.78416 -386.21843)
		(width 0.13462)
		(layer "B.Cu")
		(net "USB2_MB_BMC_DN")
	)
	(segment
		(start 100.59797 -385.276344)
		(end 100.905564 -385.583938)
		(width 0.13462)
		(layer "B.Cu")
		(net "USB2_MB_BMC_DN")
	)
	(segment
		(start 89.509854 -397.392906)
		(end 89.509854 -397.790162)
		(width 0.13462)
		(layer "B.Cu")
		(net "USB2_MB_BMC_DN")
	)
	(segment
		(start 90.117168 -397.283686)
		(end 89.619074 -397.283686)
		(width 0.13462)
		(layer "B.Cu")
		(net "USB2_MB_BMC_DN")
	)
	(segment
		(start 92.084144 -393.250674)
		(end 90.623136 -396.777718)
		(width 0.13462)
		(layer "B.Cu")
		(net "USB2_MB_BMC_DN")
	)
	(segment
		(start 99.058222 -385.276344)
		(end 100.59797 -385.276344)
		(width 0.13462)
		(layer "B.Cu")
		(net "USB2_MB_BMC_DN")
	)
	(segment
		(start 90.623136 -396.777718)
		(end 90.117168 -397.283686)
		(width 0.13462)
		(layer "B.Cu")
		(net "USB2_MB_BMC_DN")
	)
	(segment
		(start 89.619074 -397.283686)
		(end 89.509854 -397.392906)
		(width 0.13462)
		(layer "B.Cu")
		(net "USB2_MB_BMC_DN")
	)
	(segment
		(start 96.78416 -386.21843)
		(end 99.058222 -385.276344)
		(width 0.13462)
		(layer "B.Cu")
		(net "USB2_MB_BMC_DN")
	)
	(segment
		(start 349.293942 -222.38716)
		(end 349.693738 -222.786956)
		(width 0.13208)
		(layer "F.Cu")
		(net "NIC2_CLK_EN_N")
	)
	(segment
		(start 357.61295 -224.536)
		(end 356.108 -224.536)
		(width 0.13208)
		(layer "F.Cu")
		(net "NIC2_CLK_EN_N")
	)
	(via
		(at 356.108 -224.536)
		(size 0.508)
		(drill 0.254)
		(layers "F.Cu" "B.Cu")
		(net "NIC2_CLK_EN_N")
	)
	(via
		(at 349.693738 -222.786956)
		(size 0.4572)
		(drill 0.254)
		(layers "F.Cu" "B.Cu")
		(net "NIC2_CLK_EN_N")
	)
	(segment
		(start 352.87204 -224.536)
		(end 351.520506 -223.184466)
		(width 0.15494)
		(layer "In5.Cu")
		(net "NIC2_CLK_EN_N")
	)
	(segment
		(start 351.520506 -223.184466)
		(end 350.091248 -223.184466)
		(width 0.0889)
		(layer "In5.Cu")
		(net "NIC2_CLK_EN_N")
	)
	(segment
		(start 350.091248 -223.184466)
		(end 349.693738 -222.786956)
		(width 0.0889)
		(layer "In5.Cu")
		(net "NIC2_CLK_EN_N")
	)
	(segment
		(start 356.108 -224.536)
		(end 352.87204 -224.536)
		(width 0.15494)
		(layer "In5.Cu")
		(net "NIC2_CLK_EN_N")
	)
	(segment
		(start 207.514952 -188.595508)
		(end 207.12811 -188.208666)
		(width 0.13208)
		(layer "F.Cu")
		(net "SMB_FIO_R1_SCL")
	)
	(segment
		(start 206.710534 -188.172344)
		(end 206.674212 -188.208666)
		(width 0.13208)
		(layer "F.Cu")
		(net "SMB_FIO_R1_SCL")
	)
	(segment
		(start 207.12811 -188.208666)
		(end 206.674212 -188.208666)
		(width 0.13208)
		(layer "F.Cu")
		(net "SMB_FIO_R1_SCL")
	)
	(segment
		(start 206.710534 -187.565284)
		(end 206.710534 -188.172344)
		(width 0.13208)
		(layer "F.Cu")
		(net "SMB_FIO_R1_SCL")
	)
	(via
		(at 215.713818 -226.712018)
		(size 0.508)
		(drill 0.254)
		(layers "F.Cu" "B.Cu")
		(net "SMB_FIO_R1_SCL")
	)
	(via
		(at 206.674212 -188.208666)
		(size 0.508)
		(drill 0.254)
		(layers "F.Cu" "B.Cu")
		(net "SMB_FIO_R1_SCL")
	)
	(segment
		(start 216.844372 -226.755452)
		(end 215.757252 -226.755452)
		(width 0.13208)
		(layer "B.Cu")
		(net "SMB_FIO_R1_SCL")
	)
	(segment
		(start 215.757252 -226.755452)
		(end 215.713818 -226.712018)
		(width 0.13208)
		(layer "B.Cu")
		(net "SMB_FIO_R1_SCL")
	)
	(segment
		(start 205.884018 -222.53702)
		(end 205.4733 -222.53702)
		(width 0.15494)
		(layer "In7.Cu")
		(net "SMB_FIO_R1_SCL")
	)
	(segment
		(start 210.476592 -226.0854)
		(end 209.432398 -226.0854)
		(width 0.15494)
		(layer "In7.Cu")
		(net "SMB_FIO_R1_SCL")
	)
	(segment
		(start 211.651596 -227.827078)
		(end 211.289392 -227.464874)
		(width 0.15494)
		(layer "In7.Cu")
		(net "SMB_FIO_R1_SCL")
	)
	(segment
		(start 209.432398 -226.0854)
		(end 205.884018 -222.53702)
		(width 0.15494)
		(layer "In7.Cu")
		(net "SMB_FIO_R1_SCL")
	)
	(segment
		(start 215.527636 -226.8982)
		(end 213.658958 -226.8982)
		(width 0.15494)
		(layer "In7.Cu")
		(net "SMB_FIO_R1_SCL")
	)
	(segment
		(start 205.4733 -222.53702)
		(end 201.7395 -218.80322)
		(width 0.15494)
		(layer "In7.Cu")
		(net "SMB_FIO_R1_SCL")
	)
	(segment
		(start 201.7395 -193.143378)
		(end 206.674212 -188.208666)
		(width 0.15494)
		(layer "In7.Cu")
		(net "SMB_FIO_R1_SCL")
	)
	(segment
		(start 215.713818 -226.712018)
		(end 215.527636 -226.8982)
		(width 0.15494)
		(layer "In7.Cu")
		(net "SMB_FIO_R1_SCL")
	)
	(segment
		(start 213.658958 -226.8982)
		(end 212.73008 -227.827078)
		(width 0.15494)
		(layer "In7.Cu")
		(net "SMB_FIO_R1_SCL")
	)
	(segment
		(start 212.73008 -227.827078)
		(end 211.651596 -227.827078)
		(width 0.15494)
		(layer "In7.Cu")
		(net "SMB_FIO_R1_SCL")
	)
	(segment
		(start 201.7395 -218.80322)
		(end 201.7395 -193.143378)
		(width 0.15494)
		(layer "In7.Cu")
		(net "SMB_FIO_R1_SCL")
	)
	(segment
		(start 211.289392 -227.464874)
		(end 211.289392 -226.8982)
		(width 0.15494)
		(layer "In7.Cu")
		(net "SMB_FIO_R1_SCL")
	)
	(segment
		(start 211.289392 -226.8982)
		(end 210.476592 -226.0854)
		(width 0.15494)
		(layer "In7.Cu")
		(net "SMB_FIO_R1_SCL")
	)
	(segment
		(start 212.046566 -236.157008)
		(end 212.046566 -236.644688)
		(width 0.13208)
		(layer "F.Cu")
		(net "SMB_PEX_LS_SCL")
	)
	(segment
		(start 212.046566 -236.644688)
		(end 211.755482 -236.935772)
		(width 0.13208)
		(layer "F.Cu")
		(net "SMB_PEX_LS_SCL")
	)
	(segment
		(start 211.755482 -236.935772)
		(end 211.755482 -237.687866)
		(width 0.13208)
		(layer "F.Cu")
		(net "SMB_PEX_LS_SCL")
	)
	(segment
		(start 211.755482 -238.653066)
		(end 211.755482 -237.687866)
		(width 0.13208)
		(layer "F.Cu")
		(net "SMB_PEX_LS_SCL")
	)
	(segment
		(start 212.046566 -236.157008)
		(end 211.051902 -236.157008)
		(width 0.13208)
		(layer "F.Cu")
		(net "SMB_PEX_LS_SCL")
	)
	(segment
		(start 211.051902 -236.157008)
		(end 210.06181 -236.157008)
		(width 0.13208)
		(layer "F.Cu")
		(net "SMB_PEX_LS_SCL")
	)
	(segment
		(start 210.06181 -236.157008)
		(end 210.054698 -236.16412)
		(width 0.13208)
		(layer "F.Cu")
		(net "SMB_PEX_LS_SCL")
	)
	(via
		(at 211.755482 -237.932722)
		(size 0.6604)
		(drill 0.3302)
		(layers "F.Cu" "B.Cu")
		(net "SMB_PEX_LS_SCL")
	)
	(via
		(at 211.755482 -238.653066)
		(size 0.508)
		(drill 0.254)
		(layers "F.Cu" "B.Cu")
		(net "SMB_PEX_LS_SCL")
	)
	(segment
		(start 211.755482 -238.653066)
		(end 211.755482 -239.265968)
		(width 0.13208)
		(layer "B.Cu")
		(net "SMB_PEX_LS_SCL")
	)
	(segment
		(start 211.755482 -237.932722)
		(end 211.755482 -238.653066)
		(width 0.13208)
		(layer "B.Cu")
		(net "SMB_PEX_LS_SCL")
	)
	(segment
		(start 211.755482 -239.265968)
		(end 211.569808 -239.451642)
		(width 0.13208)
		(layer "B.Cu")
		(net "SMB_PEX_LS_SCL")
	)
	(via
		(at 40.649906 -298.74972)
		(size 0.4064)
		(drill 0.2032)
		(layers "F.Cu" "B.Cu")
		(net "CLK_100M_DB800ZL_PEX0_S0_R_DP")
	)
	(segment
		(start 33.24225 -301.30115)
		(end 33.64611 -301.30115)
		(width 0.1143)
		(layer "B.Cu")
		(net "CLK_100M_DB800ZL_PEX0_S0_R_DP")
	)
	(segment
		(start 40.276526 -298.83862)
		(end 40.365426 -298.74972)
		(width 0.0889)
		(layer "B.Cu")
		(net "CLK_100M_DB800ZL_PEX0_S0_R_DP")
	)
	(segment
		(start 30.461204 -301.30115)
		(end 32.56407 -301.30115)
		(width 0.1143)
		(layer "B.Cu")
		(net "CLK_100M_DB800ZL_PEX0_S0_R_DP")
	)
	(segment
		(start 40.365426 -298.74972)
		(end 40.649906 -298.74972)
		(width 0.0889)
		(layer "B.Cu")
		(net "CLK_100M_DB800ZL_PEX0_S0_R_DP")
	)
	(segment
		(start 32.56407 -301.30115)
		(end 32.70123 -301.43831)
		(width 0.1143)
		(layer "B.Cu")
		(net "CLK_100M_DB800ZL_PEX0_S0_R_DP")
	)
	(segment
		(start 106.35869 -325.752206)
		(end 106.0323 -325.425816)
		(width 0.1143)
		(layer "B.Cu")
		(net "CLK_100M_DB800ZL_PEX0_S0_R_DP")
	)
	(segment
		(start 34.18713 -301.43831)
		(end 34.32429 -301.30115)
		(width 0.1143)
		(layer "B.Cu")
		(net "CLK_100M_DB800ZL_PEX0_S0_R_DP")
	)
	(segment
		(start 95.128588 -328.070972)
		(end 56.068976 -328.070972)
		(width 0.1143)
		(layer "B.Cu")
		(net "CLK_100M_DB800ZL_PEX0_S0_R_DP")
	)
	(segment
		(start 37.162994 -320.239644)
		(end 26.5176 -309.59425)
		(width 0.1143)
		(layer "B.Cu")
		(net "CLK_100M_DB800ZL_PEX0_S0_R_DP")
	)
	(segment
		(start 106.0323 -324.908418)
		(end 105.596182 -324.4723)
		(width 0.1143)
		(layer "B.Cu")
		(net "CLK_100M_DB800ZL_PEX0_S0_R_DP")
	)
	(segment
		(start 33.64611 -301.30115)
		(end 33.78327 -301.43831)
		(width 0.1143)
		(layer "B.Cu")
		(net "CLK_100M_DB800ZL_PEX0_S0_R_DP")
	)
	(segment
		(start 105.596182 -324.4723)
		(end 103.817166 -324.4723)
		(width 0.1143)
		(layer "B.Cu")
		(net "CLK_100M_DB800ZL_PEX0_S0_R_DP")
	)
	(segment
		(start 35.334702 -301.30115)
		(end 35.3568 -301.30115)
		(width 0.0889)
		(layer "B.Cu")
		(net "CLK_100M_DB800ZL_PEX0_S0_R_DP")
	)
	(segment
		(start 103.817166 -324.4723)
		(end 95.128588 -328.070972)
		(width 0.1143)
		(layer "B.Cu")
		(net "CLK_100M_DB800ZL_PEX0_S0_R_DP")
	)
	(segment
		(start 35.3568 -301.30115)
		(end 35.43935 -301.2186)
		(width 0.0889)
		(layer "B.Cu")
		(net "CLK_100M_DB800ZL_PEX0_S0_R_DP")
	)
	(segment
		(start 39.9542 -301.2186)
		(end 40.276526 -300.896274)
		(width 0.0889)
		(layer "B.Cu")
		(net "CLK_100M_DB800ZL_PEX0_S0_R_DP")
	)
	(segment
		(start 106.0323 -325.425816)
		(end 106.0323 -324.908418)
		(width 0.1143)
		(layer "B.Cu")
		(net "CLK_100M_DB800ZL_PEX0_S0_R_DP")
	)
	(segment
		(start 33.78327 -301.43831)
		(end 34.18713 -301.43831)
		(width 0.1143)
		(layer "B.Cu")
		(net "CLK_100M_DB800ZL_PEX0_S0_R_DP")
	)
	(segment
		(start 34.32429 -301.30115)
		(end 35.334702 -301.30115)
		(width 0.1143)
		(layer "B.Cu")
		(net "CLK_100M_DB800ZL_PEX0_S0_R_DP")
	)
	(segment
		(start 40.276526 -300.896274)
		(end 40.276526 -298.83862)
		(width 0.0889)
		(layer "B.Cu")
		(net "CLK_100M_DB800ZL_PEX0_S0_R_DP")
	)
	(segment
		(start 26.5176 -305.244754)
		(end 30.461204 -301.30115)
		(width 0.1143)
		(layer "B.Cu")
		(net "CLK_100M_DB800ZL_PEX0_S0_R_DP")
	)
	(segment
		(start 32.70123 -301.43831)
		(end 33.10509 -301.43831)
		(width 0.1143)
		(layer "B.Cu")
		(net "CLK_100M_DB800ZL_PEX0_S0_R_DP")
	)
	(segment
		(start 33.10509 -301.43831)
		(end 33.24225 -301.30115)
		(width 0.1143)
		(layer "B.Cu")
		(net "CLK_100M_DB800ZL_PEX0_S0_R_DP")
	)
	(segment
		(start 35.43935 -301.2186)
		(end 39.9542 -301.2186)
		(width 0.0889)
		(layer "B.Cu")
		(net "CLK_100M_DB800ZL_PEX0_S0_R_DP")
	)
	(segment
		(start 56.068976 -328.070972)
		(end 37.162994 -320.239644)
		(width 0.1143)
		(layer "B.Cu")
		(net "CLK_100M_DB800ZL_PEX0_S0_R_DP")
	)
	(segment
		(start 26.5176 -309.59425)
		(end 26.5176 -305.244754)
		(width 0.1143)
		(layer "B.Cu")
		(net "CLK_100M_DB800ZL_PEX0_S0_R_DP")
	)
	(segment
		(start 229.437438 -65.39992)
		(end 227.839016 -65.39992)
		(width 0.13208)
		(layer "F.Cu")
		(net "SMB_FIO_R2_SDA")
	)
	(segment
		(start 223.45396 -65.312036)
		(end 223.541844 -65.39992)
		(width 0.13208)
		(layer "F.Cu")
		(net "SMB_FIO_R2_SDA")
	)
	(segment
		(start 223.541844 -65.39992)
		(end 227.839016 -65.39992)
		(width 0.13208)
		(layer "F.Cu")
		(net "SMB_FIO_R2_SDA")
	)
	(via
		(at 227.839016 -65.39992)
		(size 0.508)
		(drill 0.254)
		(layers "F.Cu" "B.Cu")
		(net "SMB_FIO_R2_SDA")
	)
	(segment
		(start 33.103312 -59.171586)
		(end 32.944308 -59.012582)
		(width 0.13208)
		(layer "F.Cu")
		(net "P3V3_SSD1_OCP")
	)
	(segment
		(start 33.140904 -57.16397)
		(end 33.140904 -58.364628)
		(width 0.13208)
		(layer "F.Cu")
		(net "P3V3_SSD1_OCP")
	)
	(segment
		(start 33.140904 -58.364628)
		(end 32.944308 -58.561224)
		(width 0.13208)
		(layer "F.Cu")
		(net "P3V3_SSD1_OCP")
	)
	(segment
		(start 32.944308 -59.012582)
		(end 32.944308 -58.561224)
		(width 0.13208)
		(layer "F.Cu")
		(net "P3V3_SSD1_OCP")
	)
	(via
		(at 32.944308 -58.561224)
		(size 0.508)
		(drill 0.254)
		(layers "F.Cu" "B.Cu")
		(net "P3V3_SSD1_OCP")
	)
	(segment
		(start 206.47914 -186.53379)
		(end 206.47914 -185.85942)
		(width 0.13208)
		(layer "F.Cu")
		(net "SMB_FIO_R2_SCL")
	)
	(segment
		(start 229.437438 -64.799972)
		(end 225.014536 -64.799972)
		(width 0.13208)
		(layer "F.Cu")
		(net "SMB_FIO_R2_SCL")
	)
	(segment
		(start 206.47914 -185.85942)
		(end 206.731108 -185.607452)
		(width 0.13208)
		(layer "F.Cu")
		(net "SMB_FIO_R2_SCL")
	)
	(segment
		(start 206.710534 -186.765184)
		(end 206.47914 -186.53379)
		(width 0.13208)
		(layer "F.Cu")
		(net "SMB_FIO_R2_SCL")
	)
	(via
		(at 225.014536 -64.799972)
		(size 0.508)
		(drill 0.254)
		(layers "F.Cu" "B.Cu")
		(net "SMB_FIO_R2_SCL")
	)
	(via
		(at 206.731108 -185.607452)
		(size 0.508)
		(drill 0.254)
		(layers "F.Cu" "B.Cu")
		(net "SMB_FIO_R2_SCL")
	)
	(segment
		(start 202.900534 -95.143066)
		(end 201.7776 -97.854262)
		(width 0.15494)
		(layer "In7.Cu")
		(net "SMB_FIO_R2_SCL")
	)
	(segment
		(start 212.511386 -88.885014)
		(end 209.158586 -88.885014)
		(width 0.15494)
		(layer "In7.Cu")
		(net "SMB_FIO_R2_SCL")
	)
	(segment
		(start 201.7776 -101.777546)
		(end 203.32446 -103.324406)
		(width 0.15494)
		(layer "In7.Cu")
		(net "SMB_FIO_R2_SCL")
	)
	(segment
		(start 204.2414 -125.5014)
		(end 210.880452 -132.140452)
		(width 0.15494)
		(layer "In7.Cu")
		(net "SMB_FIO_R2_SCL")
	)
	(segment
		(start 210.9724 -160.2232)
		(end 210.2866 -160.909)
		(width 0.15494)
		(layer "In7.Cu")
		(net "SMB_FIO_R2_SCL")
	)
	(segment
		(start 205.910688 -169.109644)
		(end 205.910688 -184.787032)
		(width 0.15494)
		(layer "In7.Cu")
		(net "SMB_FIO_R2_SCL")
	)
	(segment
		(start 203.32446 -112.51946)
		(end 204.2414 -113.4364)
		(width 0.15494)
		(layer "In7.Cu")
		(net "SMB_FIO_R2_SCL")
	)
	(segment
		(start 210.2866 -164.733732)
		(end 205.910688 -169.109644)
		(width 0.15494)
		(layer "In7.Cu")
		(net "SMB_FIO_R2_SCL")
	)
	(segment
		(start 225.014536 -65.33515)
		(end 223.828102 -66.521584)
		(width 0.15494)
		(layer "In7.Cu")
		(net "SMB_FIO_R2_SCL")
	)
	(segment
		(start 210.9724 -136.475724)
		(end 210.9724 -160.2232)
		(width 0.15494)
		(layer "In7.Cu")
		(net "SMB_FIO_R2_SCL")
	)
	(segment
		(start 224.2058 -67.30111)
		(end 224.2058 -71.12)
		(width 0.15494)
		(layer "In7.Cu")
		(net "SMB_FIO_R2_SCL")
	)
	(segment
		(start 201.7776 -97.854262)
		(end 201.7776 -101.777546)
		(width 0.15494)
		(layer "In7.Cu")
		(net "SMB_FIO_R2_SCL")
	)
	(segment
		(start 210.2866 -160.909)
		(end 210.2866 -164.733732)
		(width 0.15494)
		(layer "In7.Cu")
		(net "SMB_FIO_R2_SCL")
	)
	(segment
		(start 214.4522 -86.9442)
		(end 212.511386 -88.885014)
		(width 0.15494)
		(layer "In7.Cu")
		(net "SMB_FIO_R2_SCL")
	)
	(segment
		(start 214.4522 -80.1878)
		(end 214.4522 -86.9442)
		(width 0.15494)
		(layer "In7.Cu")
		(net "SMB_FIO_R2_SCL")
	)
	(segment
		(start 223.828102 -66.923412)
		(end 224.2058 -67.30111)
		(width 0.15494)
		(layer "In7.Cu")
		(net "SMB_FIO_R2_SCL")
	)
	(segment
		(start 222.6056 -72.7202)
		(end 221.9198 -72.7202)
		(width 0.15494)
		(layer "In7.Cu")
		(net "SMB_FIO_R2_SCL")
	)
	(segment
		(start 203.32446 -103.324406)
		(end 203.32446 -112.51946)
		(width 0.15494)
		(layer "In7.Cu")
		(net "SMB_FIO_R2_SCL")
	)
	(segment
		(start 221.9198 -72.7202)
		(end 214.4522 -80.1878)
		(width 0.15494)
		(layer "In7.Cu")
		(net "SMB_FIO_R2_SCL")
	)
	(segment
		(start 204.2414 -113.4364)
		(end 204.2414 -125.5014)
		(width 0.15494)
		(layer "In7.Cu")
		(net "SMB_FIO_R2_SCL")
	)
	(segment
		(start 210.880452 -132.140452)
		(end 210.880452 -136.013698)
		(width 0.15494)
		(layer "In7.Cu")
		(net "SMB_FIO_R2_SCL")
	)
	(segment
		(start 225.014536 -64.799972)
		(end 225.014536 -65.33515)
		(width 0.15494)
		(layer "In7.Cu")
		(net "SMB_FIO_R2_SCL")
	)
	(segment
		(start 223.828102 -66.521584)
		(end 223.828102 -66.923412)
		(width 0.15494)
		(layer "In7.Cu")
		(net "SMB_FIO_R2_SCL")
	)
	(segment
		(start 210.880452 -136.013698)
		(end 210.9724 -136.475724)
		(width 0.15494)
		(layer "In7.Cu")
		(net "SMB_FIO_R2_SCL")
	)
	(segment
		(start 205.910688 -184.787032)
		(end 206.731108 -185.607452)
		(width 0.15494)
		(layer "In7.Cu")
		(net "SMB_FIO_R2_SCL")
	)
	(segment
		(start 209.158586 -88.885014)
		(end 202.900534 -95.143066)
		(width 0.15494)
		(layer "In7.Cu")
		(net "SMB_FIO_R2_SCL")
	)
	(segment
		(start 224.2058 -71.12)
		(end 222.6056 -72.7202)
		(width 0.15494)
		(layer "In7.Cu")
		(net "SMB_FIO_R2_SCL")
	)
	(segment
		(start 357.61295 -222.504)
		(end 356.108 -222.504)
		(width 0.13208)
		(layer "F.Cu")
		(net "RST_NIC4_PERST_N")
	)
	(segment
		(start 346.893896 -220.78696)
		(end 347.293692 -221.186756)
		(width 0.13208)
		(layer "F.Cu")
		(net "RST_NIC4_PERST_N")
	)
	(via
		(at 356.108 -222.504)
		(size 0.508)
		(drill 0.254)
		(layers "F.Cu" "B.Cu")
		(net "RST_NIC4_PERST_N")
	)
	(via
		(at 347.293692 -221.186756)
		(size 0.4572)
		(drill 0.254)
		(layers "F.Cu" "B.Cu")
		(net "RST_NIC4_PERST_N")
	)
	(segment
		(start 355.565964 -223.046036)
		(end 356.108 -222.504)
		(width 0.15494)
		(layer "In5.Cu")
		(net "RST_NIC4_PERST_N")
	)
	(segment
		(start 347.293692 -221.186756)
		(end 347.696282 -221.589346)
		(width 0.0889)
		(layer "In5.Cu")
		(net "RST_NIC4_PERST_N")
	)
	(segment
		(start 351.479866 -221.589346)
		(end 352.39452 -222.504)
		(width 0.15494)
		(layer "In5.Cu")
		(net "RST_NIC4_PERST_N")
	)
	(segment
		(start 353.600512 -222.504)
		(end 354.142548 -223.046036)
		(width 0.15494)
		(layer "In5.Cu")
		(net "RST_NIC4_PERST_N")
	)
	(segment
		(start 352.39452 -222.504)
		(end 353.600512 -222.504)
		(width 0.15494)
		(layer "In5.Cu")
		(net "RST_NIC4_PERST_N")
	)
	(segment
		(start 347.696282 -221.589346)
		(end 351.479866 -221.589346)
		(width 0.0889)
		(layer "In5.Cu")
		(net "RST_NIC4_PERST_N")
	)
	(segment
		(start 354.142548 -223.046036)
		(end 355.565964 -223.046036)
		(width 0.15494)
		(layer "In5.Cu")
		(net "RST_NIC4_PERST_N")
	)
	(segment
		(start 138.190732 -180.600096)
		(end 139.296902 -180.600096)
		(width 0.13462)
		(layer "F.Cu")
		(net "CLK_100M_DB2000QL_NIC5_DN")
	)
	(segment
		(start 139.296902 -180.600096)
		(end 139.674092 -180.977286)
		(width 0.13462)
		(layer "F.Cu")
		(net "CLK_100M_DB2000QL_NIC5_DN")
	)
	(segment
		(start 135.598408 -179.2732)
		(end 136.863836 -179.2732)
		(width 0.13462)
		(layer "F.Cu")
		(net "CLK_100M_DB2000QL_NIC5_DN")
	)
	(segment
		(start 135.471154 -179.400454)
		(end 135.598408 -179.2732)
		(width 0.13462)
		(layer "F.Cu")
		(net "CLK_100M_DB2000QL_NIC5_DN")
	)
	(segment
		(start 136.863836 -179.2732)
		(end 138.190732 -180.600096)
		(width 0.13462)
		(layer "F.Cu")
		(net "CLK_100M_DB2000QL_NIC5_DN")
	)
	(segment
		(start 416.95751 -113.43513)
		(end 415.33699 -113.43513)
		(width 0.13208)
		(layer "F.Cu")
		(net "SMB_NIC7_LS_SDA")
	)
	(via
		(at 415.33699 -113.43513)
		(size 0.508)
		(drill 0.254)
		(layers "F.Cu" "B.Cu")
		(net "SMB_NIC7_LS_SDA")
	)
	(via
		(at 214.03056 -168.354756)
		(size 0.508)
		(drill 0.254)
		(layers "F.Cu" "B.Cu")
		(net "SMB_NIC7_LS_SDA")
	)
	(via
		(at 215.773 -193.929)
		(size 0.508)
		(drill 0.254)
		(layers "F.Cu" "B.Cu")
		(net "SMB_NIC7_LS_SDA")
	)
	(segment
		(start 415.615628 -113.437924)
		(end 416.572192 -113.437924)
		(width 0.13208)
		(layer "B.Cu")
		(net "SMB_NIC7_LS_SDA")
	)
	(segment
		(start 415.612834 -113.43513)
		(end 415.615628 -113.437924)
		(width 0.13208)
		(layer "B.Cu")
		(net "SMB_NIC7_LS_SDA")
	)
	(segment
		(start 415.33699 -113.43513)
		(end 415.612834 -113.43513)
		(width 0.13208)
		(layer "B.Cu")
		(net "SMB_NIC7_LS_SDA")
	)
	(segment
		(start 215.773 -193.929)
		(end 215.010746 -193.929)
		(width 0.13208)
		(layer "B.Cu")
		(net "SMB_NIC7_LS_SDA")
	)
	(segment
		(start 215.010746 -193.929)
		(end 214.864696 -193.78295)
		(width 0.13208)
		(layer "B.Cu")
		(net "SMB_NIC7_LS_SDA")
	)
	(segment
		(start 214.864696 -193.78295)
		(end 213.106 -193.78295)
		(width 0.13208)
		(layer "B.Cu")
		(net "SMB_NIC7_LS_SDA")
	)
	(segment
		(start 214.33028 -168.654476)
		(end 214.03056 -168.354756)
		(width 0.15494)
		(layer "In7.Cu")
		(net "SMB_NIC7_LS_SDA")
	)
	(segment
		(start 216.05494 -190.387478)
		(end 216.05494 -187.062364)
		(width 0.15494)
		(layer "In7.Cu")
		(net "SMB_NIC7_LS_SDA")
	)
	(segment
		(start 214.834724 -185.842148)
		(end 214.834724 -183.110124)
		(width 0.15494)
		(layer "In7.Cu")
		(net "SMB_NIC7_LS_SDA")
	)
	(segment
		(start 215.773 -193.929)
		(end 215.848946 -193.929)
		(width 0.15494)
		(layer "In7.Cu")
		(net "SMB_NIC7_LS_SDA")
	)
	(segment
		(start 216.25687 -193.521076)
		(end 216.25687 -190.589408)
		(width 0.15494)
		(layer "In7.Cu")
		(net "SMB_NIC7_LS_SDA")
	)
	(segment
		(start 216.05494 -187.062364)
		(end 214.834724 -185.842148)
		(width 0.15494)
		(layer "In7.Cu")
		(net "SMB_NIC7_LS_SDA")
	)
	(segment
		(start 214.33028 -182.60568)
		(end 214.33028 -168.654476)
		(width 0.15494)
		(layer "In7.Cu")
		(net "SMB_NIC7_LS_SDA")
	)
	(segment
		(start 216.25687 -190.589408)
		(end 216.05494 -190.387478)
		(width 0.15494)
		(layer "In7.Cu")
		(net "SMB_NIC7_LS_SDA")
	)
	(segment
		(start 214.834724 -183.110124)
		(end 214.33028 -182.60568)
		(width 0.15494)
		(layer "In7.Cu")
		(net "SMB_NIC7_LS_SDA")
	)
	(segment
		(start 215.848946 -193.929)
		(end 216.25687 -193.521076)
		(width 0.15494)
		(layer "In7.Cu")
		(net "SMB_NIC7_LS_SDA")
	)
	(segment
		(start 279.623012 -166.801292)
		(end 280.045922 -166.378382)
		(width 0.15494)
		(layer "In15.Cu")
		(net "SMB_NIC7_LS_SDA")
	)
	(segment
		(start 359.102152 -166.62273)
		(end 369.981734 -166.62273)
		(width 0.15494)
		(layer "In15.Cu")
		(net "SMB_NIC7_LS_SDA")
	)
	(segment
		(start 413.150812 -115.621308)
		(end 415.33699 -113.43513)
		(width 0.15494)
		(layer "In15.Cu")
		(net "SMB_NIC7_LS_SDA")
	)
	(segment
		(start 214.03056 -168.354756)
		(end 214.03056 -168.059608)
		(width 0.15494)
		(layer "In15.Cu")
		(net "SMB_NIC7_LS_SDA")
	)
	(segment
		(start 214.857838 -167.032432)
		(end 215.58885 -166.30142)
		(width 0.15494)
		(layer "In15.Cu")
		(net "SMB_NIC7_LS_SDA")
	)
	(segment
		(start 280.045922 -166.378382)
		(end 280.045922 -165.702234)
		(width 0.15494)
		(layer "In15.Cu")
		(net "SMB_NIC7_LS_SDA")
	)
	(segment
		(start 239.785652 -168.6433)
		(end 255.28397 -168.6433)
		(width 0.15494)
		(layer "In15.Cu")
		(net "SMB_NIC7_LS_SDA")
	)
	(segment
		(start 407.431494 -124.361956)
		(end 413.150812 -118.642638)
		(width 0.15494)
		(layer "In15.Cu")
		(net "SMB_NIC7_LS_SDA")
	)
	(segment
		(start 280.730452 -165.419024)
		(end 281.236928 -165.9255)
		(width 0.15494)
		(layer "In15.Cu")
		(net "SMB_NIC7_LS_SDA")
	)
	(segment
		(start 413.150812 -118.642638)
		(end 413.150812 -115.621308)
		(width 0.15494)
		(layer "In15.Cu")
		(net "SMB_NIC7_LS_SDA")
	)
	(segment
		(start 369.981734 -166.62273)
		(end 373.091964 -163.5125)
		(width 0.15494)
		(layer "In15.Cu")
		(net "SMB_NIC7_LS_SDA")
	)
	(segment
		(start 290.15055 -165.9255)
		(end 291.615114 -164.460936)
		(width 0.15494)
		(layer "In15.Cu")
		(net "SMB_NIC7_LS_SDA")
	)
	(segment
		(start 280.329132 -165.419024)
		(end 280.730452 -165.419024)
		(width 0.15494)
		(layer "In15.Cu")
		(net "SMB_NIC7_LS_SDA")
	)
	(segment
		(start 329.010772 -164.460936)
		(end 331.14615 -162.325558)
		(width 0.15494)
		(layer "In15.Cu")
		(net "SMB_NIC7_LS_SDA")
	)
	(segment
		(start 281.236928 -165.9255)
		(end 290.15055 -165.9255)
		(width 0.15494)
		(layer "In15.Cu")
		(net "SMB_NIC7_LS_SDA")
	)
	(segment
		(start 373.091964 -163.5125)
		(end 399.468086 -163.5125)
		(width 0.15494)
		(layer "In15.Cu")
		(net "SMB_NIC7_LS_SDA")
	)
	(segment
		(start 215.58885 -166.30142)
		(end 237.443772 -166.30142)
		(width 0.15494)
		(layer "In15.Cu")
		(net "SMB_NIC7_LS_SDA")
	)
	(segment
		(start 349.828612 -167.10787)
		(end 358.617012 -167.10787)
		(width 0.15494)
		(layer "In15.Cu")
		(net "SMB_NIC7_LS_SDA")
	)
	(segment
		(start 214.857838 -167.23233)
		(end 214.857838 -167.032432)
		(width 0.15494)
		(layer "In15.Cu")
		(net "SMB_NIC7_LS_SDA")
	)
	(segment
		(start 214.03056 -168.059608)
		(end 214.857838 -167.23233)
		(width 0.15494)
		(layer "In15.Cu")
		(net "SMB_NIC7_LS_SDA")
	)
	(segment
		(start 237.443772 -166.30142)
		(end 239.785652 -168.6433)
		(width 0.15494)
		(layer "In15.Cu")
		(net "SMB_NIC7_LS_SDA")
	)
	(segment
		(start 358.617012 -167.10787)
		(end 359.102152 -166.62273)
		(width 0.15494)
		(layer "In15.Cu")
		(net "SMB_NIC7_LS_SDA")
	)
	(segment
		(start 291.615114 -164.460936)
		(end 329.010772 -164.460936)
		(width 0.15494)
		(layer "In15.Cu")
		(net "SMB_NIC7_LS_SDA")
	)
	(segment
		(start 399.468086 -163.5125)
		(end 407.431494 -155.549092)
		(width 0.15494)
		(layer "In15.Cu")
		(net "SMB_NIC7_LS_SDA")
	)
	(segment
		(start 255.28397 -168.6433)
		(end 257.125978 -166.801292)
		(width 0.15494)
		(layer "In15.Cu")
		(net "SMB_NIC7_LS_SDA")
	)
	(segment
		(start 257.125978 -166.801292)
		(end 279.623012 -166.801292)
		(width 0.15494)
		(layer "In15.Cu")
		(net "SMB_NIC7_LS_SDA")
	)
	(segment
		(start 331.14615 -162.325558)
		(end 345.0463 -162.325558)
		(width 0.15494)
		(layer "In15.Cu")
		(net "SMB_NIC7_LS_SDA")
	)
	(segment
		(start 407.431494 -155.549092)
		(end 407.431494 -124.361956)
		(width 0.15494)
		(layer "In15.Cu")
		(net "SMB_NIC7_LS_SDA")
	)
	(segment
		(start 280.045922 -165.702234)
		(end 280.329132 -165.419024)
		(width 0.15494)
		(layer "In15.Cu")
		(net "SMB_NIC7_LS_SDA")
	)
	(segment
		(start 345.0463 -162.325558)
		(end 349.828612 -167.10787)
		(width 0.15494)
		(layer "In15.Cu")
		(net "SMB_NIC7_LS_SDA")
	)
	(segment
		(start 349.293942 -219.987114)
		(end 349.693738 -220.38691)
		(width 0.13208)
		(layer "F.Cu")
		(net "NIC5_AUX_PWR_EN")
	)
	(via
		(at 371.214396 -166.574978)
		(size 0.508)
		(drill 0.254)
		(layers "F.Cu" "B.Cu")
		(net "NIC5_AUX_PWR_EN")
	)
	(via
		(at 349.693738 -220.38691)
		(size 0.4572)
		(drill 0.254)
		(layers "F.Cu" "B.Cu")
		(net "NIC5_AUX_PWR_EN")
	)
	(segment
		(start 336.4611 -131.076446)
		(end 320.9163 -131.076446)
		(width 0.13208)
		(layer "B.Cu")
		(net "NIC5_AUX_PWR_EN")
	)
	(segment
		(start 354.368354 -161.627566)
		(end 349.20428 -156.463492)
		(width 0.13208)
		(layer "B.Cu")
		(net "NIC5_AUX_PWR_EN")
	)
	(segment
		(start 314.543186 -124.703332)
		(end 303.510188 -124.703332)
		(width 0.13208)
		(layer "B.Cu")
		(net "NIC5_AUX_PWR_EN")
	)
	(segment
		(start 371.214396 -166.574978)
		(end 367.944908 -163.30549)
		(width 0.13208)
		(layer "B.Cu")
		(net "NIC5_AUX_PWR_EN")
	)
	(segment
		(start 320.9163 -131.076446)
		(end 314.543186 -124.703332)
		(width 0.13208)
		(layer "B.Cu")
		(net "NIC5_AUX_PWR_EN")
	)
	(segment
		(start 303.510188 -124.703332)
		(end 302.391318 -123.584462)
		(width 0.13208)
		(layer "B.Cu")
		(net "NIC5_AUX_PWR_EN")
	)
	(segment
		(start 364.473744 -161.627566)
		(end 354.368354 -161.627566)
		(width 0.13208)
		(layer "B.Cu")
		(net "NIC5_AUX_PWR_EN")
	)
	(segment
		(start 302.391318 -119.41048)
		(end 303.09058 -118.711218)
		(width 0.13208)
		(layer "B.Cu")
		(net "NIC5_AUX_PWR_EN")
	)
	(segment
		(start 302.391318 -123.584462)
		(end 302.391318 -119.41048)
		(width 0.13208)
		(layer "B.Cu")
		(net "NIC5_AUX_PWR_EN")
	)
	(segment
		(start 303.086262 -117.66169)
		(end 303.086262 -118.7069)
		(width 0.13208)
		(layer "B.Cu")
		(net "NIC5_AUX_PWR_EN")
	)
	(segment
		(start 349.20428 -156.463492)
		(end 349.20428 -143.819626)
		(width 0.13208)
		(layer "B.Cu")
		(net "NIC5_AUX_PWR_EN")
	)
	(segment
		(start 366.151668 -163.30549)
		(end 364.473744 -161.627566)
		(width 0.13208)
		(layer "B.Cu")
		(net "NIC5_AUX_PWR_EN")
	)
	(segment
		(start 349.20428 -143.819626)
		(end 336.4611 -131.076446)
		(width 0.13208)
		(layer "B.Cu")
		(net "NIC5_AUX_PWR_EN")
	)
	(segment
		(start 367.944908 -163.30549)
		(end 366.151668 -163.30549)
		(width 0.13208)
		(layer "B.Cu")
		(net "NIC5_AUX_PWR_EN")
	)
	(segment
		(start 303.086262 -118.7069)
		(end 303.09058 -118.711218)
		(width 0.13208)
		(layer "B.Cu")
		(net "NIC5_AUX_PWR_EN")
	)
	(segment
		(start 373.159528 -210.666838)
		(end 373.159528 -208.498694)
		(width 0.15494)
		(layer "In5.Cu")
		(net "NIC5_AUX_PWR_EN")
	)
	(segment
		(start 373.210582 -191.767968)
		(end 372.313454 -190.87084)
		(width 0.15494)
		(layer "In5.Cu")
		(net "NIC5_AUX_PWR_EN")
	)
	(segment
		(start 372.313454 -180.823362)
		(end 371.973602 -180.48351)
		(width 0.15494)
		(layer "In5.Cu")
		(net "NIC5_AUX_PWR_EN")
	)
	(segment
		(start 373.210582 -208.44764)
		(end 373.210582 -191.767968)
		(width 0.15494)
		(layer "In5.Cu")
		(net "NIC5_AUX_PWR_EN")
	)
	(segment
		(start 354.251514 -219.97924)
		(end 354.296472 -220.024198)
		(width 0.15494)
		(layer "In5.Cu")
		(net "NIC5_AUX_PWR_EN")
	)
	(segment
		(start 371.973602 -180.48351)
		(end 371.973602 -171.882562)
		(width 0.15494)
		(layer "In5.Cu")
		(net "NIC5_AUX_PWR_EN")
	)
	(segment
		(start 367.443258 -216.383108)
		(end 373.159528 -210.666838)
		(width 0.15494)
		(layer "In5.Cu")
		(net "NIC5_AUX_PWR_EN")
	)
	(segment
		(start 349.693738 -220.38691)
		(end 350.101408 -219.97924)
		(width 0.15494)
		(layer "In5.Cu")
		(net "NIC5_AUX_PWR_EN")
	)
	(segment
		(start 356.784402 -220.024198)
		(end 356.84968 -219.95892)
		(width 0.15494)
		(layer "In5.Cu")
		(net "NIC5_AUX_PWR_EN")
	)
	(segment
		(start 356.84968 -219.95892)
		(end 360.660188 -219.95892)
		(width 0.15494)
		(layer "In5.Cu")
		(net "NIC5_AUX_PWR_EN")
	)
	(segment
		(start 350.101408 -219.97924)
		(end 354.251514 -219.97924)
		(width 0.15494)
		(layer "In5.Cu")
		(net "NIC5_AUX_PWR_EN")
	)
	(segment
		(start 373.159528 -208.498694)
		(end 373.210582 -208.44764)
		(width 0.15494)
		(layer "In5.Cu")
		(net "NIC5_AUX_PWR_EN")
	)
	(segment
		(start 371.214396 -171.123356)
		(end 371.214396 -166.574978)
		(width 0.15494)
		(layer "In5.Cu")
		(net "NIC5_AUX_PWR_EN")
	)
	(segment
		(start 354.296472 -220.024198)
		(end 356.784402 -220.024198)
		(width 0.15494)
		(layer "In5.Cu")
		(net "NIC5_AUX_PWR_EN")
	)
	(segment
		(start 364.236 -216.383108)
		(end 367.443258 -216.383108)
		(width 0.15494)
		(layer "In5.Cu")
		(net "NIC5_AUX_PWR_EN")
	)
	(segment
		(start 371.973602 -171.882562)
		(end 371.214396 -171.123356)
		(width 0.15494)
		(layer "In5.Cu")
		(net "NIC5_AUX_PWR_EN")
	)
	(segment
		(start 372.313454 -190.87084)
		(end 372.313454 -180.823362)
		(width 0.15494)
		(layer "In5.Cu")
		(net "NIC5_AUX_PWR_EN")
	)
	(segment
		(start 360.660188 -219.95892)
		(end 364.236 -216.383108)
		(width 0.15494)
		(layer "In5.Cu")
		(net "NIC5_AUX_PWR_EN")
	)
	(segment
		(start 136.6139 -183.892444)
		(end 136.6139 -182.453788)
		(width 0.13462)
		(layer "F.Cu")
		(net "CLK_100M_DB2000QL_NIC7_DP")
	)
	(segment
		(start 136.97839 -184.256934)
		(end 136.6139 -183.892444)
		(width 0.13462)
		(layer "F.Cu")
		(net "CLK_100M_DB2000QL_NIC7_DP")
	)
	(segment
		(start 136.6139 -182.453788)
		(end 134.873238 -180.713126)
		(width 0.13462)
		(layer "F.Cu")
		(net "CLK_100M_DB2000QL_NIC7_DP")
	)
	(segment
		(start 134.873238 -180.713126)
		(end 134.873238 -180.532278)
		(width 0.13462)
		(layer "F.Cu")
		(net "CLK_100M_DB2000QL_NIC7_DP")
	)
	(segment
		(start 134.860538 -180.519578)
		(end 134.860538 -180.510942)
		(width 0.13462)
		(layer "F.Cu")
		(net "CLK_100M_DB2000QL_NIC7_DP")
	)
	(segment
		(start 134.860538 -180.510942)
		(end 134.971028 -180.400452)
		(width 0.13462)
		(layer "F.Cu")
		(net "CLK_100M_DB2000QL_NIC7_DP")
	)
	(segment
		(start 134.873238 -180.532278)
		(end 134.860538 -180.519578)
		(width 0.13462)
		(layer "F.Cu")
		(net "CLK_100M_DB2000QL_NIC7_DP")
	)
	(segment
		(start 442.475366 -299.084492)
		(end 442.355986 -299.203872)
		(width 0.13208)
		(layer "F.Cu")
		(net "SMB_PEX3_SCL")
	)
	(segment
		(start 434.438552 -305.62931)
		(end 434.296058 -305.62931)
		(width 0.13208)
		(layer "F.Cu")
		(net "SMB_PEX3_SCL")
	)
	(segment
		(start 442.475366 -299.747432)
		(end 442.475366 -299.932852)
		(width 0.13208)
		(layer "F.Cu")
		(net "SMB_PEX3_SCL")
	)
	(segment
		(start 441.921392 -299.628052)
		(end 442.355986 -299.628052)
		(width 0.13208)
		(layer "F.Cu")
		(net "SMB_PEX3_SCL")
	)
	(segment
		(start 442.475366 -301.566834)
		(end 441.9854 -302.0568)
		(width 0.13208)
		(layer "F.Cu")
		(net "SMB_PEX3_SCL")
	)
	(segment
		(start 442.355986 -298.355512)
		(end 441.821316 -298.355512)
		(width 0.13208)
		(layer "F.Cu")
		(net "SMB_PEX3_SCL")
	)
	(segment
		(start 442.14669 -284.700726)
		(end 442.475366 -285.029402)
		(width 0.13208)
		(layer "F.Cu")
		(net "SMB_PEX3_SCL")
	)
	(segment
		(start 441.921392 -300.476412)
		(end 442.355986 -300.476412)
		(width 0.13208)
		(layer "F.Cu")
		(net "SMB_PEX3_SCL")
	)
	(segment
		(start 436.793386 -302.0568)
		(end 435.499256 -303.35093)
		(width 0.13208)
		(layer "F.Cu")
		(net "SMB_PEX3_SCL")
	)
	(segment
		(start 442.355986 -298.779692)
		(end 442.475366 -298.899072)
		(width 0.13208)
		(layer "F.Cu")
		(net "SMB_PEX3_SCL")
	)
	(segment
		(start 441.821316 -298.355512)
		(end 441.701936 -298.474892)
		(width 0.13208)
		(layer "F.Cu")
		(net "SMB_PEX3_SCL")
	)
	(segment
		(start 213.630256 -233.430572)
		(end 214.09025 -233.430572)
		(width 0.13208)
		(layer "F.Cu")
		(net "SMB_PEX3_SCL")
	)
	(segment
		(start 441.802012 -299.323252)
		(end 441.802012 -299.508672)
		(width 0.13208)
		(layer "F.Cu")
		(net "SMB_PEX3_SCL")
	)
	(segment
		(start 442.475366 -283.527754)
		(end 442.14669 -283.85643)
		(width 0.13208)
		(layer "F.Cu")
		(net "SMB_PEX3_SCL")
	)
	(segment
		(start 441.802012 -299.508672)
		(end 441.921392 -299.628052)
		(width 0.13208)
		(layer "F.Cu")
		(net "SMB_PEX3_SCL")
	)
	(segment
		(start 441.701936 -298.474892)
		(end 441.701936 -298.660312)
		(width 0.13208)
		(layer "F.Cu")
		(net "SMB_PEX3_SCL")
	)
	(segment
		(start 441.921392 -299.203872)
		(end 441.802012 -299.323252)
		(width 0.13208)
		(layer "F.Cu")
		(net "SMB_PEX3_SCL")
	)
	(segment
		(start 442.355986 -300.052232)
		(end 441.921392 -300.052232)
		(width 0.13208)
		(layer "F.Cu")
		(net "SMB_PEX3_SCL")
	)
	(segment
		(start 441.9854 -302.0568)
		(end 436.793386 -302.0568)
		(width 0.13208)
		(layer "F.Cu")
		(net "SMB_PEX3_SCL")
	)
	(segment
		(start 442.475366 -285.029402)
		(end 442.475366 -298.236132)
		(width 0.13208)
		(layer "F.Cu")
		(net "SMB_PEX3_SCL")
	)
	(segment
		(start 442.475366 -300.595792)
		(end 442.475366 -301.566834)
		(width 0.13208)
		(layer "F.Cu")
		(net "SMB_PEX3_SCL")
	)
	(segment
		(start 441.701936 -298.660312)
		(end 441.821316 -298.779692)
		(width 0.13208)
		(layer "F.Cu")
		(net "SMB_PEX3_SCL")
	)
	(segment
		(start 214.20201 -233.318812)
		(end 214.20201 -232.819448)
		(width 0.13208)
		(layer "F.Cu")
		(net "SMB_PEX3_SCL")
	)
	(segment
		(start 435.499256 -303.35093)
		(end 435.499256 -304.568606)
		(width 0.13208)
		(layer "F.Cu")
		(net "SMB_PEX3_SCL")
	)
	(segment
		(start 442.475366 -299.932852)
		(end 442.355986 -300.052232)
		(width 0.13208)
		(layer "F.Cu")
		(net "SMB_PEX3_SCL")
	)
	(segment
		(start 214.09025 -233.430572)
		(end 214.20201 -233.318812)
		(width 0.13208)
		(layer "F.Cu")
		(net "SMB_PEX3_SCL")
	)
	(segment
		(start 442.475366 -298.236132)
		(end 442.355986 -298.355512)
		(width 0.13208)
		(layer "F.Cu")
		(net "SMB_PEX3_SCL")
	)
	(segment
		(start 442.475366 -298.899072)
		(end 442.475366 -299.084492)
		(width 0.13208)
		(layer "F.Cu")
		(net "SMB_PEX3_SCL")
	)
	(segment
		(start 442.355986 -300.476412)
		(end 442.475366 -300.595792)
		(width 0.13208)
		(layer "F.Cu")
		(net "SMB_PEX3_SCL")
	)
	(segment
		(start 442.355986 -299.203872)
		(end 441.921392 -299.203872)
		(width 0.13208)
		(layer "F.Cu")
		(net "SMB_PEX3_SCL")
	)
	(segment
		(start 435.499256 -304.568606)
		(end 434.438552 -305.62931)
		(width 0.13208)
		(layer "F.Cu")
		(net "SMB_PEX3_SCL")
	)
	(segment
		(start 441.802012 -300.171612)
		(end 441.802012 -300.357032)
		(width 0.13208)
		(layer "F.Cu")
		(net "SMB_PEX3_SCL")
	)
	(segment
		(start 442.355986 -299.628052)
		(end 442.475366 -299.747432)
		(width 0.13208)
		(layer "F.Cu")
		(net "SMB_PEX3_SCL")
	)
	(segment
		(start 442.14669 -283.85643)
		(end 442.14669 -284.700726)
		(width 0.13208)
		(layer "F.Cu")
		(net "SMB_PEX3_SCL")
	)
	(segment
		(start 441.802012 -300.357032)
		(end 441.921392 -300.476412)
		(width 0.13208)
		(layer "F.Cu")
		(net "SMB_PEX3_SCL")
	)
	(segment
		(start 441.821316 -298.779692)
		(end 442.355986 -298.779692)
		(width 0.13208)
		(layer "F.Cu")
		(net "SMB_PEX3_SCL")
	)
	(segment
		(start 441.921392 -300.052232)
		(end 441.802012 -300.171612)
		(width 0.13208)
		(layer "F.Cu")
		(net "SMB_PEX3_SCL")
	)
	(via
		(at 214.20201 -232.819448)
		(size 0.508)
		(drill 0.254)
		(layers "F.Cu" "B.Cu")
		(net "SMB_PEX3_SCL")
	)
	(via
		(at 442.475366 -283.527754)
		(size 0.508)
		(drill 0.254)
		(layers "F.Cu" "B.Cu")
		(net "SMB_PEX3_SCL")
	)
	(via
		(at 450.54774 -251.668534)
		(size 0.508)
		(drill 0.254)
		(layers "F.Cu" "B.Cu")
		(net "SMB_PEX3_SCL")
	)
	(via
		(at 274.00377 -262.005572)
		(size 0.508)
		(drill 0.254)
		(layers "F.Cu" "B.Cu")
		(net "SMB_PEX3_SCL")
	)
	(via
		(at 261.51078 -233.100372)
		(size 0.508)
		(drill 0.254)
		(layers "F.Cu" "B.Cu")
		(net "SMB_PEX3_SCL")
	)
	(segment
		(start 442.475366 -283.104844)
		(end 442.475366 -283.527754)
		(width 0.13208)
		(layer "B.Cu")
		(net "SMB_PEX3_SCL")
	)
	(segment
		(start 450.54774 -251.668534)
		(end 449.039488 -251.668534)
		(width 0.13208)
		(layer "B.Cu")
		(net "SMB_PEX3_SCL")
	)
	(segment
		(start 444.336424 -256.371598)
		(end 444.336424 -281.243786)
		(width 0.13208)
		(layer "B.Cu")
		(net "SMB_PEX3_SCL")
	)
	(segment
		(start 449.039488 -251.668534)
		(end 444.336424 -256.371598)
		(width 0.13208)
		(layer "B.Cu")
		(net "SMB_PEX3_SCL")
	)
	(segment
		(start 444.336424 -281.243786)
		(end 442.475366 -283.104844)
		(width 0.13208)
		(layer "B.Cu")
		(net "SMB_PEX3_SCL")
	)
	(segment
		(start 214.472774 -233.090212)
		(end 214.20201 -232.819448)
		(width 0.13208)
		(layer "B.Cu")
		(net "SMB_PEX3_SCL")
	)
	(segment
		(start 214.472774 -233.805476)
		(end 214.472774 -233.090212)
		(width 0.13208)
		(layer "B.Cu")
		(net "SMB_PEX3_SCL")
	)
	(segment
		(start 261.51078 -233.100372)
		(end 266.024868 -237.61446)
		(width 0.15494)
		(layer "In5.Cu")
		(net "SMB_PEX3_SCL")
	)
	(segment
		(start 270.31696 -256.649474)
		(end 270.31696 -257.642106)
		(width 0.15494)
		(layer "In5.Cu")
		(net "SMB_PEX3_SCL")
	)
	(segment
		(start 269.258034 -255.590548)
		(end 270.31696 -256.649474)
		(width 0.15494)
		(layer "In5.Cu")
		(net "SMB_PEX3_SCL")
	)
	(segment
		(start 266.024868 -245.790974)
		(end 269.258034 -249.02414)
		(width 0.15494)
		(layer "In5.Cu")
		(net "SMB_PEX3_SCL")
	)
	(segment
		(start 266.024868 -237.61446)
		(end 266.024868 -245.790974)
		(width 0.15494)
		(layer "In5.Cu")
		(net "SMB_PEX3_SCL")
	)
	(segment
		(start 269.258034 -249.02414)
		(end 269.258034 -255.590548)
		(width 0.15494)
		(layer "In5.Cu")
		(net "SMB_PEX3_SCL")
	)
	(segment
		(start 270.31696 -257.642106)
		(end 274.00377 -261.328916)
		(width 0.15494)
		(layer "In5.Cu")
		(net "SMB_PEX3_SCL")
	)
	(segment
		(start 274.00377 -261.328916)
		(end 274.00377 -262.005572)
		(width 0.15494)
		(layer "In5.Cu")
		(net "SMB_PEX3_SCL")
	)
	(segment
		(start 215.660224 -235.6866)
		(end 230.833676 -235.6866)
		(width 0.15494)
		(layer "In13.Cu")
		(net "SMB_PEX3_SCL")
	)
	(segment
		(start 242.578128 -236.329474)
		(end 242.963192 -235.94441)
		(width 0.15494)
		(layer "In13.Cu")
		(net "SMB_PEX3_SCL")
	)
	(segment
		(start 274.00377 -262.005572)
		(end 275.339302 -260.67004)
		(width 0.15494)
		(layer "In13.Cu")
		(net "SMB_PEX3_SCL")
	)
	(segment
		(start 444.894208 -245.702074)
		(end 450.24929 -251.057156)
		(width 0.15494)
		(layer "In13.Cu")
		(net "SMB_PEX3_SCL")
	)
	(segment
		(start 389.39851 -244.13591)
		(end 390.152382 -244.889782)
		(width 0.15494)
		(layer "In13.Cu")
		(net "SMB_PEX3_SCL")
	)
	(segment
		(start 390.152382 -244.889782)
		(end 395.105636 -244.889782)
		(width 0.15494)
		(layer "In13.Cu")
		(net "SMB_PEX3_SCL")
	)
	(segment
		(start 367.117884 -246.7356)
		(end 370.357654 -246.7356)
		(width 0.15494)
		(layer "In13.Cu")
		(net "SMB_PEX3_SCL")
	)
	(segment
		(start 246.654066 -235.331)
		(end 247.79224 -235.331)
		(width 0.15494)
		(layer "In13.Cu")
		(net "SMB_PEX3_SCL")
	)
	(segment
		(start 355.62921 -247.437656)
		(end 358.623362 -247.437656)
		(width 0.15494)
		(layer "In13.Cu")
		(net "SMB_PEX3_SCL")
	)
	(segment
		(start 331.146912 -258.42722)
		(end 340.174326 -258.42722)
		(width 0.15494)
		(layer "In13.Cu")
		(net "SMB_PEX3_SCL")
	)
	(segment
		(start 345.3892 -252.72238)
		(end 348.45752 -249.65406)
		(width 0.15494)
		(layer "In13.Cu")
		(net "SMB_PEX3_SCL")
	)
	(segment
		(start 214.20201 -232.819448)
		(end 214.20201 -234.228386)
		(width 0.15494)
		(layer "In13.Cu")
		(net "SMB_PEX3_SCL")
	)
	(segment
		(start 275.339302 -260.67004)
		(end 297.616626 -260.67004)
		(width 0.15494)
		(layer "In13.Cu")
		(net "SMB_PEX3_SCL")
	)
	(segment
		(start 395.105636 -244.889782)
		(end 395.917928 -245.702074)
		(width 0.15494)
		(layer "In13.Cu")
		(net "SMB_PEX3_SCL")
	)
	(segment
		(start 231.47655 -236.329474)
		(end 242.578128 -236.329474)
		(width 0.15494)
		(layer "In13.Cu")
		(net "SMB_PEX3_SCL")
	)
	(segment
		(start 385.098036 -245.458742)
		(end 386.420868 -244.13591)
		(width 0.15494)
		(layer "In13.Cu")
		(net "SMB_PEX3_SCL")
	)
	(segment
		(start 320.083434 -260.680962)
		(end 328.89317 -260.680962)
		(width 0.15494)
		(layer "In13.Cu")
		(net "SMB_PEX3_SCL")
	)
	(segment
		(start 300.189646 -263.24306)
		(end 311.84469 -263.24306)
		(width 0.15494)
		(layer "In13.Cu")
		(net "SMB_PEX3_SCL")
	)
	(segment
		(start 253.842774 -236.733842)
		(end 254.890016 -235.6866)
		(width 0.15494)
		(layer "In13.Cu")
		(net "SMB_PEX3_SCL")
	)
	(segment
		(start 297.616626 -260.67004)
		(end 300.189646 -263.24306)
		(width 0.15494)
		(layer "In13.Cu")
		(net "SMB_PEX3_SCL")
	)
	(segment
		(start 244.938042 -234.6198)
		(end 246.654066 -235.331)
		(width 0.15494)
		(layer "In13.Cu")
		(net "SMB_PEX3_SCL")
	)
	(segment
		(start 360.100372 -245.960646)
		(end 366.34293 -245.960646)
		(width 0.15494)
		(layer "In13.Cu")
		(net "SMB_PEX3_SCL")
	)
	(segment
		(start 384.048762 -245.458742)
		(end 385.098036 -245.458742)
		(width 0.15494)
		(layer "In13.Cu")
		(net "SMB_PEX3_SCL")
	)
	(segment
		(start 254.890016 -235.6866)
		(end 256.8956 -235.6866)
		(width 0.15494)
		(layer "In13.Cu")
		(net "SMB_PEX3_SCL")
	)
	(segment
		(start 242.963192 -235.193586)
		(end 243.536978 -234.6198)
		(width 0.15494)
		(layer "In13.Cu")
		(net "SMB_PEX3_SCL")
	)
	(segment
		(start 249.195082 -236.733842)
		(end 253.842774 -236.733842)
		(width 0.15494)
		(layer "In13.Cu")
		(net "SMB_PEX3_SCL")
	)
	(segment
		(start 450.24929 -251.370084)
		(end 450.54774 -251.668534)
		(width 0.15494)
		(layer "In13.Cu")
		(net "SMB_PEX3_SCL")
	)
	(segment
		(start 358.623362 -247.437656)
		(end 360.100372 -245.960646)
		(width 0.15494)
		(layer "In13.Cu")
		(net "SMB_PEX3_SCL")
	)
	(segment
		(start 374.832626 -248.43105)
		(end 375.423176 -249.0216)
		(width 0.15494)
		(layer "In13.Cu")
		(net "SMB_PEX3_SCL")
	)
	(segment
		(start 370.357654 -246.7356)
		(end 371.605048 -247.982994)
		(width 0.15494)
		(layer "In13.Cu")
		(net "SMB_PEX3_SCL")
	)
	(segment
		(start 256.8956 -235.6866)
		(end 257.81 -234.7722)
		(width 0.15494)
		(layer "In13.Cu")
		(net "SMB_PEX3_SCL")
	)
	(segment
		(start 243.536978 -234.6198)
		(end 244.938042 -234.6198)
		(width 0.15494)
		(layer "In13.Cu")
		(net "SMB_PEX3_SCL")
	)
	(segment
		(start 242.963192 -235.94441)
		(end 242.963192 -235.193586)
		(width 0.15494)
		(layer "In13.Cu")
		(net "SMB_PEX3_SCL")
	)
	(segment
		(start 214.20201 -234.228386)
		(end 215.660224 -235.6866)
		(width 0.15494)
		(layer "In13.Cu")
		(net "SMB_PEX3_SCL")
	)
	(segment
		(start 340.174326 -258.42722)
		(end 345.3892 -253.212346)
		(width 0.15494)
		(layer "In13.Cu")
		(net "SMB_PEX3_SCL")
	)
	(segment
		(start 382.708912 -249.0216)
		(end 383.149602 -248.58091)
		(width 0.15494)
		(layer "In13.Cu")
		(net "SMB_PEX3_SCL")
	)
	(segment
		(start 230.833676 -235.6866)
		(end 231.47655 -236.329474)
		(width 0.15494)
		(layer "In13.Cu")
		(net "SMB_PEX3_SCL")
	)
	(segment
		(start 259.838952 -234.7722)
		(end 261.51078 -233.100372)
		(width 0.15494)
		(layer "In13.Cu")
		(net "SMB_PEX3_SCL")
	)
	(segment
		(start 366.34293 -245.960646)
		(end 367.117884 -246.7356)
		(width 0.15494)
		(layer "In13.Cu")
		(net "SMB_PEX3_SCL")
	)
	(segment
		(start 395.917928 -245.702074)
		(end 444.894208 -245.702074)
		(width 0.15494)
		(layer "In13.Cu")
		(net "SMB_PEX3_SCL")
	)
	(segment
		(start 247.79224 -235.331)
		(end 249.195082 -236.733842)
		(width 0.15494)
		(layer "In13.Cu")
		(net "SMB_PEX3_SCL")
	)
	(segment
		(start 319.15735 -261.607046)
		(end 320.083434 -260.680962)
		(width 0.15494)
		(layer "In13.Cu")
		(net "SMB_PEX3_SCL")
	)
	(segment
		(start 372.686834 -248.43105)
		(end 374.832626 -248.43105)
		(width 0.15494)
		(layer "In13.Cu")
		(net "SMB_PEX3_SCL")
	)
	(segment
		(start 311.84469 -263.24306)
		(end 313.480704 -261.607046)
		(width 0.15494)
		(layer "In13.Cu")
		(net "SMB_PEX3_SCL")
	)
	(segment
		(start 386.420868 -244.13591)
		(end 389.39851 -244.13591)
		(width 0.15494)
		(layer "In13.Cu")
		(net "SMB_PEX3_SCL")
	)
	(segment
		(start 328.89317 -260.680962)
		(end 331.146912 -258.42722)
		(width 0.15494)
		(layer "In13.Cu")
		(net "SMB_PEX3_SCL")
	)
	(segment
		(start 383.149602 -248.58091)
		(end 383.149602 -246.357902)
		(width 0.15494)
		(layer "In13.Cu")
		(net "SMB_PEX3_SCL")
	)
	(segment
		(start 257.81 -234.7722)
		(end 259.838952 -234.7722)
		(width 0.15494)
		(layer "In13.Cu")
		(net "SMB_PEX3_SCL")
	)
	(segment
		(start 450.24929 -251.057156)
		(end 450.24929 -251.370084)
		(width 0.15494)
		(layer "In13.Cu")
		(net "SMB_PEX3_SCL")
	)
	(segment
		(start 353.412806 -249.65406)
		(end 355.62921 -247.437656)
		(width 0.15494)
		(layer "In13.Cu")
		(net "SMB_PEX3_SCL")
	)
	(segment
		(start 313.480704 -261.607046)
		(end 319.15735 -261.607046)
		(width 0.15494)
		(layer "In13.Cu")
		(net "SMB_PEX3_SCL")
	)
	(segment
		(start 375.423176 -249.0216)
		(end 382.708912 -249.0216)
		(width 0.15494)
		(layer "In13.Cu")
		(net "SMB_PEX3_SCL")
	)
	(segment
		(start 371.605048 -247.982994)
		(end 372.686834 -248.43105)
		(width 0.15494)
		(layer "In13.Cu")
		(net "SMB_PEX3_SCL")
	)
	(segment
		(start 345.3892 -253.212346)
		(end 345.3892 -252.72238)
		(width 0.15494)
		(layer "In13.Cu")
		(net "SMB_PEX3_SCL")
	)
	(segment
		(start 383.149602 -246.357902)
		(end 384.048762 -245.458742)
		(width 0.15494)
		(layer "In13.Cu")
		(net "SMB_PEX3_SCL")
	)
	(segment
		(start 348.45752 -249.65406)
		(end 353.412806 -249.65406)
		(width 0.15494)
		(layer "In13.Cu")
		(net "SMB_PEX3_SCL")
	)
	(segment
		(start 270.797274 -163.928806)
		(end 270.407892 -163.539424)
		(width 0.13208)
		(layer "F.Cu")
		(net "PWRGD_NIC4_PWR_GOOD_R")
	)
	(segment
		(start 348.493842 -220.78696)
		(end 348.893638 -221.186756)
		(width 0.13208)
		(layer "F.Cu")
		(net "PWRGD_NIC4_PWR_GOOD_R")
	)
	(segment
		(start 271.000474 -163.928806)
		(end 270.797274 -163.928806)
		(width 0.13208)
		(layer "F.Cu")
		(net "PWRGD_NIC4_PWR_GOOD_R")
	)
	(segment
		(start 270.407892 -163.539424)
		(end 270.407892 -163.061396)
		(width 0.13208)
		(layer "F.Cu")
		(net "PWRGD_NIC4_PWR_GOOD_R")
	)
	(via
		(at 369.763294 -173.595792)
		(size 0.508)
		(drill 0.254)
		(layers "F.Cu" "B.Cu")
		(net "PWRGD_NIC4_PWR_GOOD_R")
	)
	(via
		(at 271.000474 -163.928806)
		(size 0.508)
		(drill 0.254)
		(layers "F.Cu" "B.Cu")
		(net "PWRGD_NIC4_PWR_GOOD_R")
	)
	(via
		(at 348.893638 -221.186756)
		(size 0.4572)
		(drill 0.254)
		(layers "F.Cu" "B.Cu")
		(net "PWRGD_NIC4_PWR_GOOD_R")
	)
	(segment
		(start 372.3386 -185.524648)
		(end 372.3386 -184.281064)
		(width 0.15494)
		(layer "In7.Cu")
		(net "PWRGD_NIC4_PWR_GOOD_R")
	)
	(segment
		(start 348.893638 -221.186756)
		(end 349.293688 -220.786706)
		(width 0.0889)
		(layer "In7.Cu")
		(net "PWRGD_NIC4_PWR_GOOD_R")
	)
	(segment
		(start 371.470682 -183.413146)
		(end 371.470682 -175.639222)
		(width 0.15494)
		(layer "In7.Cu")
		(net "PWRGD_NIC4_PWR_GOOD_R")
	)
	(segment
		(start 349.293688 -220.786706)
		(end 351.5614 -220.786706)
		(width 0.0889)
		(layer "In7.Cu")
		(net "PWRGD_NIC4_PWR_GOOD_R")
	)
	(segment
		(start 371.9576 -185.905648)
		(end 372.3386 -185.524648)
		(width 0.15494)
		(layer "In7.Cu")
		(net "PWRGD_NIC4_PWR_GOOD_R")
	)
	(segment
		(start 372.3386 -184.281064)
		(end 371.470682 -183.413146)
		(width 0.15494)
		(layer "In7.Cu")
		(net "PWRGD_NIC4_PWR_GOOD_R")
	)
	(segment
		(start 366.681258 -206.495142)
		(end 366.681258 -205.76286)
		(width 0.15494)
		(layer "In7.Cu")
		(net "PWRGD_NIC4_PWR_GOOD_R")
	)
	(segment
		(start 364.744 -208.4324)
		(end 366.681258 -206.495142)
		(width 0.15494)
		(layer "In7.Cu")
		(net "PWRGD_NIC4_PWR_GOOD_R")
	)
	(segment
		(start 358.043988 -216.706958)
		(end 358.043988 -209.493866)
		(width 0.15494)
		(layer "In7.Cu")
		(net "PWRGD_NIC4_PWR_GOOD_R")
	)
	(segment
		(start 354.9904 -219.760546)
		(end 358.043988 -216.706958)
		(width 0.15494)
		(layer "In7.Cu")
		(net "PWRGD_NIC4_PWR_GOOD_R")
	)
	(segment
		(start 371.9576 -191.214248)
		(end 371.9576 -185.905648)
		(width 0.15494)
		(layer "In7.Cu")
		(net "PWRGD_NIC4_PWR_GOOD_R")
	)
	(segment
		(start 352.626422 -220.786706)
		(end 353.652582 -219.760546)
		(width 0.15494)
		(layer "In7.Cu")
		(net "PWRGD_NIC4_PWR_GOOD_R")
	)
	(segment
		(start 372.255796 -201.642472)
		(end 372.255796 -191.512444)
		(width 0.15494)
		(layer "In7.Cu")
		(net "PWRGD_NIC4_PWR_GOOD_R")
	)
	(segment
		(start 353.652582 -219.760546)
		(end 354.9904 -219.760546)
		(width 0.15494)
		(layer "In7.Cu")
		(net "PWRGD_NIC4_PWR_GOOD_R")
	)
	(segment
		(start 351.5614 -220.786706)
		(end 352.626422 -220.786706)
		(width 0.15494)
		(layer "In7.Cu")
		(net "PWRGD_NIC4_PWR_GOOD_R")
	)
	(segment
		(start 367.228374 -205.215744)
		(end 368.682524 -205.215744)
		(width 0.15494)
		(layer "In7.Cu")
		(net "PWRGD_NIC4_PWR_GOOD_R")
	)
	(segment
		(start 366.681258 -205.76286)
		(end 367.228374 -205.215744)
		(width 0.15494)
		(layer "In7.Cu")
		(net "PWRGD_NIC4_PWR_GOOD_R")
	)
	(segment
		(start 372.255796 -191.512444)
		(end 371.9576 -191.214248)
		(width 0.15494)
		(layer "In7.Cu")
		(net "PWRGD_NIC4_PWR_GOOD_R")
	)
	(segment
		(start 362.956602 -208.4324)
		(end 364.744 -208.4324)
		(width 0.15494)
		(layer "In7.Cu")
		(net "PWRGD_NIC4_PWR_GOOD_R")
	)
	(segment
		(start 358.775254 -208.7626)
		(end 362.626402 -208.7626)
		(width 0.15494)
		(layer "In7.Cu")
		(net "PWRGD_NIC4_PWR_GOOD_R")
	)
	(segment
		(start 371.470682 -175.639222)
		(end 369.763294 -173.931834)
		(width 0.15494)
		(layer "In7.Cu")
		(net "PWRGD_NIC4_PWR_GOOD_R")
	)
	(segment
		(start 369.763294 -173.931834)
		(end 369.763294 -173.595792)
		(width 0.15494)
		(layer "In7.Cu")
		(net "PWRGD_NIC4_PWR_GOOD_R")
	)
	(segment
		(start 368.682524 -205.215744)
		(end 372.255796 -201.642472)
		(width 0.15494)
		(layer "In7.Cu")
		(net "PWRGD_NIC4_PWR_GOOD_R")
	)
	(segment
		(start 362.626402 -208.7626)
		(end 362.956602 -208.4324)
		(width 0.15494)
		(layer "In7.Cu")
		(net "PWRGD_NIC4_PWR_GOOD_R")
	)
	(segment
		(start 358.043988 -209.493866)
		(end 358.775254 -208.7626)
		(width 0.15494)
		(layer "In7.Cu")
		(net "PWRGD_NIC4_PWR_GOOD_R")
	)
	(segment
		(start 355.933248 -166.472108)
		(end 356.57917 -167.11803)
		(width 0.15494)
		(layer "In13.Cu")
		(net "PWRGD_NIC4_PWR_GOOD_R")
	)
	(segment
		(start 289.784028 -175.952658)
		(end 326.537066 -175.952658)
		(width 0.15494)
		(layer "In13.Cu")
		(net "PWRGD_NIC4_PWR_GOOD_R")
	)
	(segment
		(start 364.988602 -172.96892)
		(end 369.136422 -172.96892)
		(width 0.15494)
		(layer "In13.Cu")
		(net "PWRGD_NIC4_PWR_GOOD_R")
	)
	(segment
		(start 354.972366 -165.0238)
		(end 355.933248 -165.984682)
		(width 0.15494)
		(layer "In13.Cu")
		(net "PWRGD_NIC4_PWR_GOOD_R")
	)
	(segment
		(start 326.537066 -175.952658)
		(end 334.163924 -168.3258)
		(width 0.15494)
		(layer "In13.Cu")
		(net "PWRGD_NIC4_PWR_GOOD_R")
	)
	(segment
		(start 271.000474 -164.132006)
		(end 280.49474 -173.626272)
		(width 0.15494)
		(layer "In13.Cu")
		(net "PWRGD_NIC4_PWR_GOOD_R")
	)
	(segment
		(start 287.457642 -173.626272)
		(end 289.784028 -175.952658)
		(width 0.15494)
		(layer "In13.Cu")
		(net "PWRGD_NIC4_PWR_GOOD_R")
	)
	(segment
		(start 271.000474 -163.928806)
		(end 271.000474 -164.132006)
		(width 0.15494)
		(layer "In13.Cu")
		(net "PWRGD_NIC4_PWR_GOOD_R")
	)
	(segment
		(start 350.4946 -168.3258)
		(end 353.7966 -165.0238)
		(width 0.15494)
		(layer "In13.Cu")
		(net "PWRGD_NIC4_PWR_GOOD_R")
	)
	(segment
		(start 355.933248 -165.984682)
		(end 355.933248 -166.472108)
		(width 0.15494)
		(layer "In13.Cu")
		(net "PWRGD_NIC4_PWR_GOOD_R")
	)
	(segment
		(start 353.7966 -165.0238)
		(end 354.972366 -165.0238)
		(width 0.15494)
		(layer "In13.Cu")
		(net "PWRGD_NIC4_PWR_GOOD_R")
	)
	(segment
		(start 334.163924 -168.3258)
		(end 350.4946 -168.3258)
		(width 0.15494)
		(layer "In13.Cu")
		(net "PWRGD_NIC4_PWR_GOOD_R")
	)
	(segment
		(start 280.49474 -173.626272)
		(end 287.457642 -173.626272)
		(width 0.15494)
		(layer "In13.Cu")
		(net "PWRGD_NIC4_PWR_GOOD_R")
	)
	(segment
		(start 359.137712 -167.11803)
		(end 364.988602 -172.96892)
		(width 0.15494)
		(layer "In13.Cu")
		(net "PWRGD_NIC4_PWR_GOOD_R")
	)
	(segment
		(start 369.136422 -172.96892)
		(end 369.763294 -173.595792)
		(width 0.15494)
		(layer "In13.Cu")
		(net "PWRGD_NIC4_PWR_GOOD_R")
	)
	(segment
		(start 356.57917 -167.11803)
		(end 359.137712 -167.11803)
		(width 0.15494)
		(layer "In13.Cu")
		(net "PWRGD_NIC4_PWR_GOOD_R")
	)
	(segment
		(start 135.96239 -184.256934)
		(end 136.33958 -183.879744)
		(width 0.13462)
		(layer "F.Cu")
		(net "CLK_100M_DB2000QL_NIC7_DN")
	)
	(segment
		(start 136.33958 -182.56758)
		(end 134.598918 -180.826918)
		(width 0.13462)
		(layer "F.Cu")
		(net "CLK_100M_DB2000QL_NIC7_DN")
	)
	(segment
		(start 134.598918 -180.826918)
		(end 134.598918 -180.528214)
		(width 0.13462)
		(layer "F.Cu")
		(net "CLK_100M_DB2000QL_NIC7_DN")
	)
	(segment
		(start 136.33958 -183.879744)
		(end 136.33958 -182.56758)
		(width 0.13462)
		(layer "F.Cu")
		(net "CLK_100M_DB2000QL_NIC7_DN")
	)
	(segment
		(start 134.598918 -180.528214)
		(end 134.471156 -180.400452)
		(width 0.13462)
		(layer "F.Cu")
		(net "CLK_100M_DB2000QL_NIC7_DN")
	)
	(segment
		(start 415.33318 -112.485424)
		(end 415.33318 -112.56518)
		(width 0.13208)
		(layer "F.Cu")
		(net "SMB_NIC7_LS_SCL")
	)
	(segment
		(start 416.374072 -112.834928)
		(end 416.95751 -112.834928)
		(width 0.13208)
		(layer "F.Cu")
		(net "SMB_NIC7_LS_SCL")
	)
	(segment
		(start 416.3314 -112.8776)
		(end 416.374072 -112.834928)
		(width 0.13208)
		(layer "F.Cu")
		(net "SMB_NIC7_LS_SCL")
	)
	(segment
		(start 415.6456 -112.8776)
		(end 416.3314 -112.8776)
		(width 0.13208)
		(layer "F.Cu")
		(net "SMB_NIC7_LS_SCL")
	)
	(segment
		(start 415.33318 -112.56518)
		(end 415.6456 -112.8776)
		(width 0.13208)
		(layer "F.Cu")
		(net "SMB_NIC7_LS_SCL")
	)
	(via
		(at 215.773 -192.659)
		(size 0.508)
		(drill 0.254)
		(layers "F.Cu" "B.Cu")
		(net "SMB_NIC7_LS_SCL")
	)
	(via
		(at 415.33318 -112.485424)
		(size 0.508)
		(drill 0.254)
		(layers "F.Cu" "B.Cu")
		(net "SMB_NIC7_LS_SCL")
	)
	(via
		(at 213.957408 -167.447722)
		(size 0.508)
		(drill 0.254)
		(layers "F.Cu" "B.Cu")
		(net "SMB_NIC7_LS_SCL")
	)
	(segment
		(start 213.46795 -193.167)
		(end 213.106 -192.80505)
		(width 0.13208)
		(layer "B.Cu")
		(net "SMB_NIC7_LS_SCL")
	)
	(segment
		(start 215.773 -192.659)
		(end 215.011 -192.659)
		(width 0.13208)
		(layer "B.Cu")
		(net "SMB_NIC7_LS_SCL")
	)
	(segment
		(start 416.508692 -112.485424)
		(end 415.33318 -112.485424)
		(width 0.13208)
		(layer "B.Cu")
		(net "SMB_NIC7_LS_SCL")
	)
	(segment
		(start 214.503 -193.167)
		(end 213.46795 -193.167)
		(width 0.13208)
		(layer "B.Cu")
		(net "SMB_NIC7_LS_SCL")
	)
	(segment
		(start 215.011 -192.659)
		(end 214.503 -193.167)
		(width 0.13208)
		(layer "B.Cu")
		(net "SMB_NIC7_LS_SCL")
	)
	(segment
		(start 416.572192 -112.421924)
		(end 416.508692 -112.485424)
		(width 0.13208)
		(layer "B.Cu")
		(net "SMB_NIC7_LS_SCL")
	)
	(segment
		(start 213.40953 -168.755568)
		(end 213.40953 -167.9956)
		(width 0.15494)
		(layer "In7.Cu")
		(net "SMB_NIC7_LS_SCL")
	)
	(segment
		(start 214.374984 -186.003946)
		(end 214.356442 -185.985404)
		(width 0.15494)
		(layer "In7.Cu")
		(net "SMB_NIC7_LS_SCL")
	)
	(segment
		(start 215.5952 -192.4812)
		(end 215.5952 -187.252864)
		(width 0.15494)
		(layer "In7.Cu")
		(net "SMB_NIC7_LS_SCL")
	)
	(segment
		(start 215.5952 -187.252864)
		(end 214.374984 -186.032648)
		(width 0.15494)
		(layer "In7.Cu")
		(net "SMB_NIC7_LS_SCL")
	)
	(segment
		(start 213.87054 -169.216578)
		(end 213.40953 -168.755568)
		(width 0.15494)
		(layer "In7.Cu")
		(net "SMB_NIC7_LS_SCL")
	)
	(segment
		(start 214.356442 -185.985404)
		(end 214.356442 -183.292242)
		(width 0.15494)
		(layer "In7.Cu")
		(net "SMB_NIC7_LS_SCL")
	)
	(segment
		(start 214.374984 -186.032648)
		(end 214.374984 -186.003946)
		(width 0.15494)
		(layer "In7.Cu")
		(net "SMB_NIC7_LS_SCL")
	)
	(segment
		(start 214.356442 -183.292242)
		(end 213.87054 -182.80634)
		(width 0.15494)
		(layer "In7.Cu")
		(net "SMB_NIC7_LS_SCL")
	)
	(segment
		(start 213.87054 -182.80634)
		(end 213.87054 -169.216578)
		(width 0.15494)
		(layer "In7.Cu")
		(net "SMB_NIC7_LS_SCL")
	)
	(segment
		(start 213.40953 -167.9956)
		(end 213.957408 -167.447722)
		(width 0.15494)
		(layer "In7.Cu")
		(net "SMB_NIC7_LS_SCL")
	)
	(segment
		(start 215.773 -192.659)
		(end 215.5952 -192.4812)
		(width 0.15494)
		(layer "In7.Cu")
		(net "SMB_NIC7_LS_SCL")
	)
	(segment
		(start 282.967176 -163.5252)
		(end 282.687776 -163.8046)
		(width 0.15494)
		(layer "In15.Cu")
		(net "SMB_NIC7_LS_SCL")
	)
	(segment
		(start 406.795732 -124.216414)
		(end 406.795732 -155.534614)
		(width 0.15494)
		(layer "In15.Cu")
		(net "SMB_NIC7_LS_SCL")
	)
	(segment
		(start 255.134872 -168.105836)
		(end 239.955578 -168.105836)
		(width 0.15494)
		(layer "In15.Cu")
		(net "SMB_NIC7_LS_SCL")
	)
	(segment
		(start 412.51505 -118.497096)
		(end 406.795732 -124.216414)
		(width 0.15494)
		(layer "In15.Cu")
		(net "SMB_NIC7_LS_SCL")
	)
	(segment
		(start 214.398098 -166.841932)
		(end 214.398098 -167.007032)
		(width 0.15494)
		(layer "In15.Cu")
		(net "SMB_NIC7_LS_SCL")
	)
	(segment
		(start 237.691422 -165.84168)
		(end 215.39835 -165.84168)
		(width 0.15494)
		(layer "In15.Cu")
		(net "SMB_NIC7_LS_SCL")
	)
	(segment
		(start 413.822134 -113.99647)
		(end 413.822134 -114.212878)
		(width 0.15494)
		(layer "In15.Cu")
		(net "SMB_NIC7_LS_SCL")
	)
	(segment
		(start 369.855242 -166.098982)
		(end 351.852992 -166.098982)
		(width 0.15494)
		(layer "In15.Cu")
		(net "SMB_NIC7_LS_SCL")
	)
	(segment
		(start 372.901464 -163.05276)
		(end 369.855242 -166.098982)
		(width 0.15494)
		(layer "In15.Cu")
		(net "SMB_NIC7_LS_SCL")
	)
	(segment
		(start 239.955578 -168.105836)
		(end 237.691422 -165.84168)
		(width 0.15494)
		(layer "In15.Cu")
		(net "SMB_NIC7_LS_SCL")
	)
	(segment
		(start 412.51505 -115.519962)
		(end 412.51505 -118.497096)
		(width 0.15494)
		(layer "In15.Cu")
		(net "SMB_NIC7_LS_SCL")
	)
	(segment
		(start 215.39835 -165.84168)
		(end 214.398098 -166.841932)
		(width 0.15494)
		(layer "In15.Cu")
		(net "SMB_NIC7_LS_SCL")
	)
	(segment
		(start 293.7256 -163.5252)
		(end 282.967176 -163.5252)
		(width 0.15494)
		(layer "In15.Cu")
		(net "SMB_NIC7_LS_SCL")
	)
	(segment
		(start 256.899156 -166.341552)
		(end 255.134872 -168.105836)
		(width 0.15494)
		(layer "In15.Cu")
		(net "SMB_NIC7_LS_SCL")
	)
	(segment
		(start 281.091386 -163.8046)
		(end 278.554434 -166.341552)
		(width 0.15494)
		(layer "In15.Cu")
		(net "SMB_NIC7_LS_SCL")
	)
	(segment
		(start 413.822134 -114.212878)
		(end 412.51505 -115.519962)
		(width 0.15494)
		(layer "In15.Cu")
		(net "SMB_NIC7_LS_SCL")
	)
	(segment
		(start 399.277586 -163.05276)
		(end 372.901464 -163.05276)
		(width 0.15494)
		(layer "In15.Cu")
		(net "SMB_NIC7_LS_SCL")
	)
	(segment
		(start 415.33318 -112.485424)
		(end 413.822134 -113.99647)
		(width 0.15494)
		(layer "In15.Cu")
		(net "SMB_NIC7_LS_SCL")
	)
	(segment
		(start 351.852992 -166.098982)
		(end 347.021912 -161.267902)
		(width 0.15494)
		(layer "In15.Cu")
		(net "SMB_NIC7_LS_SCL")
	)
	(segment
		(start 329.067668 -163.7538)
		(end 293.9542 -163.7538)
		(width 0.15494)
		(layer "In15.Cu")
		(net "SMB_NIC7_LS_SCL")
	)
	(segment
		(start 406.795732 -155.534614)
		(end 399.277586 -163.05276)
		(width 0.15494)
		(layer "In15.Cu")
		(net "SMB_NIC7_LS_SCL")
	)
	(segment
		(start 293.9542 -163.7538)
		(end 293.7256 -163.5252)
		(width 0.15494)
		(layer "In15.Cu")
		(net "SMB_NIC7_LS_SCL")
	)
	(segment
		(start 278.554434 -166.341552)
		(end 256.899156 -166.341552)
		(width 0.15494)
		(layer "In15.Cu")
		(net "SMB_NIC7_LS_SCL")
	)
	(segment
		(start 214.398098 -167.007032)
		(end 213.957408 -167.447722)
		(width 0.15494)
		(layer "In15.Cu")
		(net "SMB_NIC7_LS_SCL")
	)
	(segment
		(start 331.553566 -161.267902)
		(end 329.067668 -163.7538)
		(width 0.15494)
		(layer "In15.Cu")
		(net "SMB_NIC7_LS_SCL")
	)
	(segment
		(start 347.021912 -161.267902)
		(end 331.553566 -161.267902)
		(width 0.15494)
		(layer "In15.Cu")
		(net "SMB_NIC7_LS_SCL")
	)
	(segment
		(start 282.687776 -163.8046)
		(end 281.091386 -163.8046)
		(width 0.15494)
		(layer "In15.Cu")
		(net "SMB_NIC7_LS_SCL")
	)
	(segment
		(start 442.227208 -302.538892)
		(end 443.110366 -301.655734)
		(width 0.13208)
		(layer "F.Cu")
		(net "SMB_PEX3_SDA")
	)
	(segment
		(start 435.94528 -304.980848)
		(end 435.94528 -303.587404)
		(width 0.13208)
		(layer "F.Cu")
		(net "SMB_PEX3_SDA")
	)
	(segment
		(start 443.432184 -283.849572)
		(end 443.110366 -283.527754)
		(width 0.13208)
		(layer "F.Cu")
		(net "SMB_PEX3_SDA")
	)
	(segment
		(start 443.110366 -284.802834)
		(end 443.432184 -284.481016)
		(width 0.13208)
		(layer "F.Cu")
		(net "SMB_PEX3_SDA")
	)
	(segment
		(start 435.94528 -303.587404)
		(end 436.993792 -302.538892)
		(width 0.13208)
		(layer "F.Cu")
		(net "SMB_PEX3_SDA")
	)
	(segment
		(start 443.110366 -301.655734)
		(end 443.110366 -284.802834)
		(width 0.13208)
		(layer "F.Cu")
		(net "SMB_PEX3_SDA")
	)
	(segment
		(start 443.432184 -284.481016)
		(end 443.432184 -283.849572)
		(width 0.13208)
		(layer "F.Cu")
		(net "SMB_PEX3_SDA")
	)
	(segment
		(start 213.683596 -232.025698)
		(end 213.590886 -231.932988)
		(width 0.13208)
		(layer "F.Cu")
		(net "SMB_PEX3_SDA")
	)
	(segment
		(start 213.683596 -232.17124)
		(end 213.683596 -232.025698)
		(width 0.13208)
		(layer "F.Cu")
		(net "SMB_PEX3_SDA")
	)
	(segment
		(start 436.993792 -302.538892)
		(end 442.227208 -302.538892)
		(width 0.13208)
		(layer "F.Cu")
		(net "SMB_PEX3_SDA")
	)
	(segment
		(start 213.590886 -231.932988)
		(end 213.590886 -231.550972)
		(width 0.13208)
		(layer "F.Cu")
		(net "SMB_PEX3_SDA")
	)
	(segment
		(start 435.285134 -305.640994)
		(end 435.94528 -304.980848)
		(width 0.13208)
		(layer "F.Cu")
		(net "SMB_PEX3_SDA")
	)
	(via
		(at 443.110366 -283.527754)
		(size 0.508)
		(drill 0.254)
		(layers "F.Cu" "B.Cu")
		(net "SMB_PEX3_SDA")
	)
	(via
		(at 450.716904 -252.742446)
		(size 0.508)
		(drill 0.254)
		(layers "F.Cu" "B.Cu")
		(net "SMB_PEX3_SDA")
	)
	(via
		(at 273.33194 -261.50189)
		(size 0.508)
		(drill 0.254)
		(layers "F.Cu" "B.Cu")
		(net "SMB_PEX3_SDA")
	)
	(via
		(at 259.675884 -233.087926)
		(size 0.508)
		(drill 0.254)
		(layers "F.Cu" "B.Cu")
		(net "SMB_PEX3_SDA")
	)
	(via
		(at 213.683596 -232.17124)
		(size 0.508)
		(drill 0.254)
		(layers "F.Cu" "B.Cu")
		(net "SMB_PEX3_SDA")
	)
	(segment
		(start 450.716904 -252.742446)
		(end 448.583558 -252.742446)
		(width 0.13208)
		(layer "B.Cu")
		(net "SMB_PEX3_SDA")
	)
	(segment
		(start 213.683596 -232.17124)
		(end 213.683596 -232.816908)
		(width 0.13208)
		(layer "B.Cu")
		(net "SMB_PEX3_SDA")
	)
	(segment
		(start 444.773304 -281.864816)
		(end 443.110366 -283.527754)
		(width 0.13208)
		(layer "B.Cu")
		(net "SMB_PEX3_SDA")
	)
	(segment
		(start 213.456774 -233.04373)
		(end 213.456774 -233.805476)
		(width 0.13208)
		(layer "B.Cu")
		(net "SMB_PEX3_SDA")
	)
	(segment
		(start 444.773304 -256.5527)
		(end 444.773304 -281.864816)
		(width 0.13208)
		(layer "B.Cu")
		(net "SMB_PEX3_SDA")
	)
	(segment
		(start 213.683596 -232.816908)
		(end 213.456774 -233.04373)
		(width 0.13208)
		(layer "B.Cu")
		(net "SMB_PEX3_SDA")
	)
	(segment
		(start 448.583558 -252.742446)
		(end 444.773304 -256.5527)
		(width 0.13208)
		(layer "B.Cu")
		(net "SMB_PEX3_SDA")
	)
	(segment
		(start 268.229588 -255.473454)
		(end 269.668752 -256.912618)
		(width 0.15494)
		(layer "In5.Cu")
		(net "SMB_PEX3_SDA")
	)
	(segment
		(start 265.561064 -245.97741)
		(end 268.229588 -248.645934)
		(width 0.15494)
		(layer "In5.Cu")
		(net "SMB_PEX3_SDA")
	)
	(segment
		(start 265.561064 -238.121698)
		(end 265.561064 -245.97741)
		(width 0.15494)
		(layer "In5.Cu")
		(net "SMB_PEX3_SDA")
	)
	(segment
		(start 269.668752 -256.912618)
		(end 269.668752 -257.838702)
		(width 0.15494)
		(layer "In5.Cu")
		(net "SMB_PEX3_SDA")
	)
	(segment
		(start 262.102092 -234.662726)
		(end 265.561064 -238.121698)
		(width 0.15494)
		(layer "In5.Cu")
		(net "SMB_PEX3_SDA")
	)
	(segment
		(start 259.675884 -233.087926)
		(end 261.250684 -234.662726)
		(width 0.15494)
		(layer "In5.Cu")
		(net "SMB_PEX3_SDA")
	)
	(segment
		(start 268.229588 -248.645934)
		(end 268.229588 -255.473454)
		(width 0.15494)
		(layer "In5.Cu")
		(net "SMB_PEX3_SDA")
	)
	(segment
		(start 261.250684 -234.662726)
		(end 262.102092 -234.662726)
		(width 0.15494)
		(layer "In5.Cu")
		(net "SMB_PEX3_SDA")
	)
	(segment
		(start 269.668752 -257.838702)
		(end 273.33194 -261.50189)
		(width 0.15494)
		(layer "In5.Cu")
		(net "SMB_PEX3_SDA")
	)
	(segment
		(start 372.90883 -247.943878)
		(end 371.873526 -247.515126)
		(width 0.15494)
		(layer "In13.Cu")
		(net "SMB_PEX3_SDA")
	)
	(segment
		(start 370.5606 -246.2022)
		(end 367.284254 -246.2022)
		(width 0.15494)
		(layer "In13.Cu")
		(net "SMB_PEX3_SDA")
	)
	(segment
		(start 389.650986 -243.6622)
		(end 386.232654 -243.6622)
		(width 0.15494)
		(layer "In13.Cu")
		(net "SMB_PEX3_SDA")
	)
	(segment
		(start 353.222306 -249.19432)
		(end 348.26702 -249.19432)
		(width 0.15494)
		(layer "In13.Cu")
		(net "SMB_PEX3_SDA")
	)
	(segment
		(start 383.861818 -244.98427)
		(end 382.67513 -246.170958)
		(width 0.15494)
		(layer "In13.Cu")
		(net "SMB_PEX3_SDA")
	)
	(segment
		(start 214.370158 -232.15092)
		(end 213.703916 -232.15092)
		(width 0.15494)
		(layer "In13.Cu")
		(net "SMB_PEX3_SDA")
	)
	(segment
		(start 375.646188 -248.539)
		(end 375.051066 -247.943878)
		(width 0.15494)
		(layer "In13.Cu")
		(net "SMB_PEX3_SDA")
	)
	(segment
		(start 248.130314 -234.87126)
		(end 246.747792 -234.87126)
		(width 0.15494)
		(layer "In13.Cu")
		(net "SMB_PEX3_SDA")
	)
	(segment
		(start 451.1294 -251.192792)
		(end 445.176402 -245.239794)
		(width 0.15494)
		(layer "In13.Cu")
		(net "SMB_PEX3_SDA")
	)
	(segment
		(start 396.166594 -245.239794)
		(end 395.356842 -244.430042)
		(width 0.15494)
		(layer "In13.Cu")
		(net "SMB_PEX3_SDA")
	)
	(segment
		(start 323.86397 -259.77342)
		(end 313.199018 -259.77342)
		(width 0.15494)
		(layer "In13.Cu")
		(net "SMB_PEX3_SDA")
	)
	(segment
		(start 330.956412 -257.96748)
		(end 329.69327 -259.230622)
		(width 0.15494)
		(layer "In13.Cu")
		(net "SMB_PEX3_SDA")
	)
	(segment
		(start 249.501914 -236.24286)
		(end 248.130314 -234.87126)
		(width 0.15494)
		(layer "In13.Cu")
		(net "SMB_PEX3_SDA")
	)
	(segment
		(start 244.91315 -234.1118)
		(end 242.956588 -234.1118)
		(width 0.15494)
		(layer "In13.Cu")
		(net "SMB_PEX3_SDA")
	)
	(segment
		(start 344.8558 -252.60554)
		(end 344.8558 -253.078234)
		(width 0.15494)
		(layer "In13.Cu")
		(net "SMB_PEX3_SDA")
	)
	(segment
		(start 214.921338 -232.7021)
		(end 214.370158 -232.15092)
		(width 0.15494)
		(layer "In13.Cu")
		(net "SMB_PEX3_SDA")
	)
	(segment
		(start 242.029234 -235.039154)
		(end 231.501188 -235.039154)
		(width 0.15494)
		(layer "In13.Cu")
		(net "SMB_PEX3_SDA")
	)
	(segment
		(start 231.436164 -235.104178)
		(end 227.358194 -235.104178)
		(width 0.15494)
		(layer "In13.Cu")
		(net "SMB_PEX3_SDA")
	)
	(segment
		(start 382.67513 -246.170958)
		(end 382.67513 -248.330974)
		(width 0.15494)
		(layer "In13.Cu")
		(net "SMB_PEX3_SDA")
	)
	(segment
		(start 254.533654 -235.204)
		(end 253.494794 -236.24286)
		(width 0.15494)
		(layer "In13.Cu")
		(net "SMB_PEX3_SDA")
	)
	(segment
		(start 227.358194 -235.104178)
		(end 227.29317 -235.039154)
		(width 0.15494)
		(layer "In13.Cu")
		(net "SMB_PEX3_SDA")
	)
	(segment
		(start 382.67513 -248.330974)
		(end 382.467104 -248.539)
		(width 0.15494)
		(layer "In13.Cu")
		(net "SMB_PEX3_SDA")
	)
	(segment
		(start 253.494794 -236.24286)
		(end 249.501914 -236.24286)
		(width 0.15494)
		(layer "In13.Cu")
		(net "SMB_PEX3_SDA")
	)
	(segment
		(start 227.29317 -235.039154)
		(end 217.785696 -235.039154)
		(width 0.15494)
		(layer "In13.Cu")
		(net "SMB_PEX3_SDA")
	)
	(segment
		(start 258.52501 -234.2388)
		(end 257.657346 -234.2388)
		(width 0.15494)
		(layer "In13.Cu")
		(net "SMB_PEX3_SDA")
	)
	(segment
		(start 297.807126 -260.2103)
		(end 274.62353 -260.2103)
		(width 0.15494)
		(layer "In13.Cu")
		(net "SMB_PEX3_SDA")
	)
	(segment
		(start 231.501188 -235.039154)
		(end 231.436164 -235.104178)
		(width 0.15494)
		(layer "In13.Cu")
		(net "SMB_PEX3_SDA")
	)
	(segment
		(start 217.785696 -235.039154)
		(end 216.851738 -234.105196)
		(width 0.15494)
		(layer "In13.Cu")
		(net "SMB_PEX3_SDA")
	)
	(segment
		(start 365.76508 -244.683026)
		(end 360.130852 -244.683026)
		(width 0.15494)
		(layer "In13.Cu")
		(net "SMB_PEX3_SDA")
	)
	(segment
		(start 360.130852 -244.683026)
		(end 357.92156 -246.892318)
		(width 0.15494)
		(layer "In13.Cu")
		(net "SMB_PEX3_SDA")
	)
	(segment
		(start 344.8558 -253.078234)
		(end 339.966554 -257.96748)
		(width 0.15494)
		(layer "In13.Cu")
		(net "SMB_PEX3_SDA")
	)
	(segment
		(start 242.956588 -234.1118)
		(end 242.029234 -235.039154)
		(width 0.15494)
		(layer "In13.Cu")
		(net "SMB_PEX3_SDA")
	)
	(segment
		(start 300.380146 -262.78332)
		(end 297.807126 -260.2103)
		(width 0.15494)
		(layer "In13.Cu")
		(net "SMB_PEX3_SDA")
	)
	(segment
		(start 451.1294 -252.32995)
		(end 451.1294 -251.192792)
		(width 0.15494)
		(layer "In13.Cu")
		(net "SMB_PEX3_SDA")
	)
	(segment
		(start 339.966554 -257.96748)
		(end 330.956412 -257.96748)
		(width 0.15494)
		(layer "In13.Cu")
		(net "SMB_PEX3_SDA")
	)
	(segment
		(start 371.873526 -247.515126)
		(end 370.5606 -246.2022)
		(width 0.15494)
		(layer "In13.Cu")
		(net "SMB_PEX3_SDA")
	)
	(segment
		(start 450.716904 -252.742446)
		(end 451.1294 -252.32995)
		(width 0.15494)
		(layer "In13.Cu")
		(net "SMB_PEX3_SDA")
	)
	(segment
		(start 357.92156 -246.892318)
		(end 355.524308 -246.892318)
		(width 0.15494)
		(layer "In13.Cu")
		(net "SMB_PEX3_SDA")
	)
	(segment
		(start 329.69327 -259.230622)
		(end 324.406768 -259.230622)
		(width 0.15494)
		(layer "In13.Cu")
		(net "SMB_PEX3_SDA")
	)
	(segment
		(start 355.524308 -246.892318)
		(end 353.222306 -249.19432)
		(width 0.15494)
		(layer "In13.Cu")
		(net "SMB_PEX3_SDA")
	)
	(segment
		(start 259.675884 -233.087926)
		(end 258.52501 -234.2388)
		(width 0.15494)
		(layer "In13.Cu")
		(net "SMB_PEX3_SDA")
	)
	(segment
		(start 382.467104 -248.539)
		(end 375.646188 -248.539)
		(width 0.15494)
		(layer "In13.Cu")
		(net "SMB_PEX3_SDA")
	)
	(segment
		(start 213.703916 -232.15092)
		(end 213.683596 -232.17124)
		(width 0.15494)
		(layer "In13.Cu")
		(net "SMB_PEX3_SDA")
	)
	(segment
		(start 384.910584 -244.98427)
		(end 383.861818 -244.98427)
		(width 0.15494)
		(layer "In13.Cu")
		(net "SMB_PEX3_SDA")
	)
	(segment
		(start 257.657346 -234.2388)
		(end 256.692146 -235.204)
		(width 0.15494)
		(layer "In13.Cu")
		(net "SMB_PEX3_SDA")
	)
	(segment
		(start 375.051066 -247.943878)
		(end 372.90883 -247.943878)
		(width 0.15494)
		(layer "In13.Cu")
		(net "SMB_PEX3_SDA")
	)
	(segment
		(start 256.692146 -235.204)
		(end 254.533654 -235.204)
		(width 0.15494)
		(layer "In13.Cu")
		(net "SMB_PEX3_SDA")
	)
	(segment
		(start 386.232654 -243.6622)
		(end 384.910584 -244.98427)
		(width 0.15494)
		(layer "In13.Cu")
		(net "SMB_PEX3_SDA")
	)
	(segment
		(start 445.176402 -245.239794)
		(end 396.166594 -245.239794)
		(width 0.15494)
		(layer "In13.Cu")
		(net "SMB_PEX3_SDA")
	)
	(segment
		(start 310.189118 -262.78332)
		(end 300.380146 -262.78332)
		(width 0.15494)
		(layer "In13.Cu")
		(net "SMB_PEX3_SDA")
	)
	(segment
		(start 324.406768 -259.230622)
		(end 323.86397 -259.77342)
		(width 0.15494)
		(layer "In13.Cu")
		(net "SMB_PEX3_SDA")
	)
	(segment
		(start 395.356842 -244.430042)
		(end 390.418828 -244.430042)
		(width 0.15494)
		(layer "In13.Cu")
		(net "SMB_PEX3_SDA")
	)
	(segment
		(start 348.26702 -249.19432)
		(end 344.8558 -252.60554)
		(width 0.15494)
		(layer "In13.Cu")
		(net "SMB_PEX3_SDA")
	)
	(segment
		(start 367.284254 -246.2022)
		(end 365.76508 -244.683026)
		(width 0.15494)
		(layer "In13.Cu")
		(net "SMB_PEX3_SDA")
	)
	(segment
		(start 216.851738 -234.105196)
		(end 215.060784 -234.105196)
		(width 0.15494)
		(layer "In13.Cu")
		(net "SMB_PEX3_SDA")
	)
	(segment
		(start 214.921338 -233.96575)
		(end 214.921338 -232.7021)
		(width 0.15494)
		(layer "In13.Cu")
		(net "SMB_PEX3_SDA")
	)
	(segment
		(start 390.418828 -244.430042)
		(end 389.650986 -243.6622)
		(width 0.15494)
		(layer "In13.Cu")
		(net "SMB_PEX3_SDA")
	)
	(segment
		(start 313.199018 -259.77342)
		(end 310.189118 -262.78332)
		(width 0.15494)
		(layer "In13.Cu")
		(net "SMB_PEX3_SDA")
	)
	(segment
		(start 274.62353 -260.2103)
		(end 273.33194 -261.50189)
		(width 0.15494)
		(layer "In13.Cu")
		(net "SMB_PEX3_SDA")
	)
	(segment
		(start 246.747792 -234.87126)
		(end 244.91315 -234.1118)
		(width 0.15494)
		(layer "In13.Cu")
		(net "SMB_PEX3_SDA")
	)
	(segment
		(start 215.060784 -234.105196)
		(end 214.921338 -233.96575)
		(width 0.15494)
		(layer "In13.Cu")
		(net "SMB_PEX3_SDA")
	)
	(segment
		(start 349.293942 -220.78696)
		(end 349.693738 -221.186756)
		(width 0.13208)
		(layer "F.Cu")
		(net "NIC4_AUX_PWR_EN")
	)
	(via
		(at 282.730702 -139.96416)
		(size 0.6604)
		(drill 0.3302)
		(layers "F.Cu" "B.Cu")
		(net "NIC4_AUX_PWR_EN")
	)
	(via
		(at 349.693738 -221.186756)
		(size 0.4572)
		(drill 0.254)
		(layers "F.Cu" "B.Cu")
		(net "NIC4_AUX_PWR_EN")
	)
	(via
		(at 297.671236 -186.399678)
		(size 0.508)
		(drill 0.254)
		(layers "F.Cu" "B.Cu")
		(net "NIC4_AUX_PWR_EN")
	)
	(via
		(at 283.125672 -146.795998)
		(size 0.508)
		(drill 0.254)
		(layers "F.Cu" "B.Cu")
		(net "NIC4_AUX_PWR_EN")
	)
	(segment
		(start 282.730702 -139.96416)
		(end 282.443936 -139.677394)
		(width 0.13208)
		(layer "B.Cu")
		(net "NIC4_AUX_PWR_EN")
	)
	(segment
		(start 282.443936 -139.677394)
		(end 282.443936 -138.421618)
		(width 0.13208)
		(layer "B.Cu")
		(net "NIC4_AUX_PWR_EN")
	)
	(segment
		(start 283.125672 -146.795998)
		(end 283.125672 -140.35913)
		(width 0.13208)
		(layer "B.Cu")
		(net "NIC4_AUX_PWR_EN")
	)
	(segment
		(start 283.125672 -140.35913)
		(end 282.730702 -139.96416)
		(width 0.13208)
		(layer "B.Cu")
		(net "NIC4_AUX_PWR_EN")
	)
	(segment
		(start 281.466036 -138.421618)
		(end 282.443936 -138.421618)
		(width 0.13208)
		(layer "B.Cu")
		(net "NIC4_AUX_PWR_EN")
	)
	(segment
		(start 295.86047 -185.590688)
		(end 289.706812 -179.43703)
		(width 0.15494)
		(layer "In9.Cu")
		(net "NIC4_AUX_PWR_EN")
	)
	(segment
		(start 297.671236 -186.399678)
		(end 296.862246 -185.590688)
		(width 0.15494)
		(layer "In9.Cu")
		(net "NIC4_AUX_PWR_EN")
	)
	(segment
		(start 286.65551 -147.57654)
		(end 285.874968 -146.795998)
		(width 0.15494)
		(layer "In9.Cu")
		(net "NIC4_AUX_PWR_EN")
	)
	(segment
		(start 289.706812 -168.963594)
		(end 286.65551 -165.912292)
		(width 0.15494)
		(layer "In9.Cu")
		(net "NIC4_AUX_PWR_EN")
	)
	(segment
		(start 285.874968 -146.795998)
		(end 283.125672 -146.795998)
		(width 0.15494)
		(layer "In9.Cu")
		(net "NIC4_AUX_PWR_EN")
	)
	(segment
		(start 296.862246 -185.590688)
		(end 295.86047 -185.590688)
		(width 0.15494)
		(layer "In9.Cu")
		(net "NIC4_AUX_PWR_EN")
	)
	(segment
		(start 286.65551 -165.912292)
		(end 286.65551 -147.57654)
		(width 0.15494)
		(layer "In9.Cu")
		(net "NIC4_AUX_PWR_EN")
	)
	(segment
		(start 289.706812 -179.43703)
		(end 289.706812 -168.963594)
		(width 0.15494)
		(layer "In9.Cu")
		(net "NIC4_AUX_PWR_EN")
	)
	(segment
		(start 353.979988 -220.599)
		(end 352.425 -220.599)
		(width 0.15494)
		(layer "In15.Cu")
		(net "NIC4_AUX_PWR_EN")
	)
	(segment
		(start 359.51287 -220.67266)
		(end 359.22966 -220.95587)
		(width 0.15494)
		(layer "In15.Cu")
		(net "NIC4_AUX_PWR_EN")
	)
	(segment
		(start 356.634542 -220.149928)
		(end 354.836222 -220.149928)
		(width 0.15494)
		(layer "In15.Cu")
		(net "NIC4_AUX_PWR_EN")
	)
	(segment
		(start 358.54513 -220.67266)
		(end 358.54513 -220.658182)
		(width 0.15494)
		(layer "In15.Cu")
		(net "NIC4_AUX_PWR_EN")
	)
	(segment
		(start 358.82834 -220.95587)
		(end 358.54513 -220.67266)
		(width 0.15494)
		(layer "In15.Cu")
		(net "NIC4_AUX_PWR_EN")
	)
	(segment
		(start 350.091248 -221.584266)
		(end 349.693738 -221.186756)
		(width 0.0889)
		(layer "In15.Cu")
		(net "NIC4_AUX_PWR_EN")
	)
	(segment
		(start 340.402672 -187.85332)
		(end 341.370412 -186.88558)
		(width 0.15494)
		(layer "In15.Cu")
		(net "NIC4_AUX_PWR_EN")
	)
	(segment
		(start 359.22966 -220.95587)
		(end 358.82834 -220.95587)
		(width 0.15494)
		(layer "In15.Cu")
		(net "NIC4_AUX_PWR_EN")
	)
	(segment
		(start 356.32009 -191.714628)
		(end 356.32009 -196.879718)
		(width 0.15494)
		(layer "In15.Cu")
		(net "NIC4_AUX_PWR_EN")
	)
	(segment
		(start 352.55581 -187.950348)
		(end 356.32009 -191.714628)
		(width 0.15494)
		(layer "In15.Cu")
		(net "NIC4_AUX_PWR_EN")
	)
	(segment
		(start 359.51287 -220.65361)
		(end 359.51287 -220.67266)
		(width 0.15494)
		(layer "In15.Cu")
		(net "NIC4_AUX_PWR_EN")
	)
	(segment
		(start 360.227118 -218.92895)
		(end 359.51287 -220.65361)
		(width 0.15494)
		(layer "In15.Cu")
		(net "NIC4_AUX_PWR_EN")
	)
	(segment
		(start 354.141532 -220.422978)
		(end 354.141532 -220.437456)
		(width 0.15494)
		(layer "In15.Cu")
		(net "NIC4_AUX_PWR_EN")
	)
	(segment
		(start 360.22915 -218.926918)
		(end 360.227118 -218.92895)
		(width 0.15494)
		(layer "In15.Cu")
		(net "NIC4_AUX_PWR_EN")
	)
	(segment
		(start 357.876348 -219.9894)
		(end 357.19893 -219.9894)
		(width 0.15494)
		(layer "In15.Cu")
		(net "NIC4_AUX_PWR_EN")
	)
	(segment
		(start 351.439734 -221.584266)
		(end 350.091248 -221.584266)
		(width 0.0889)
		(layer "In15.Cu")
		(net "NIC4_AUX_PWR_EN")
	)
	(segment
		(start 354.141532 -220.437456)
		(end 353.979988 -220.599)
		(width 0.15494)
		(layer "In15.Cu")
		(net "NIC4_AUX_PWR_EN")
	)
	(segment
		(start 341.370412 -186.88558)
		(end 346.693998 -186.88558)
		(width 0.15494)
		(layer "In15.Cu")
		(net "NIC4_AUX_PWR_EN")
	)
	(segment
		(start 352.425 -220.599)
		(end 351.9297 -221.0943)
		(width 0.15494)
		(layer "In15.Cu")
		(net "NIC4_AUX_PWR_EN")
	)
	(segment
		(start 346.693998 -186.88558)
		(end 347.758766 -187.950348)
		(width 0.15494)
		(layer "In15.Cu")
		(net "NIC4_AUX_PWR_EN")
	)
	(segment
		(start 358.54513 -220.658182)
		(end 357.876348 -219.9894)
		(width 0.15494)
		(layer "In15.Cu")
		(net "NIC4_AUX_PWR_EN")
	)
	(segment
		(start 347.758766 -187.950348)
		(end 352.55581 -187.950348)
		(width 0.15494)
		(layer "In15.Cu")
		(net "NIC4_AUX_PWR_EN")
	)
	(segment
		(start 354.424742 -220.139768)
		(end 354.141532 -220.422978)
		(width 0.15494)
		(layer "In15.Cu")
		(net "NIC4_AUX_PWR_EN")
	)
	(segment
		(start 351.9297 -221.0943)
		(end 351.439734 -221.584266)
		(width 0.0889)
		(layer "In15.Cu")
		(net "NIC4_AUX_PWR_EN")
	)
	(segment
		(start 297.995594 -186.07532)
		(end 331.520292 -186.07532)
		(width 0.15494)
		(layer "In15.Cu")
		(net "NIC4_AUX_PWR_EN")
	)
	(segment
		(start 357.19766 -219.98813)
		(end 356.79634 -219.98813)
		(width 0.15494)
		(layer "In15.Cu")
		(net "NIC4_AUX_PWR_EN")
	)
	(segment
		(start 357.19893 -219.9894)
		(end 357.19766 -219.98813)
		(width 0.15494)
		(layer "In15.Cu")
		(net "NIC4_AUX_PWR_EN")
	)
	(segment
		(start 360.22915 -200.788778)
		(end 360.22915 -218.926918)
		(width 0.15494)
		(layer "In15.Cu")
		(net "NIC4_AUX_PWR_EN")
	)
	(segment
		(start 333.298292 -187.85332)
		(end 340.402672 -187.85332)
		(width 0.15494)
		(layer "In15.Cu")
		(net "NIC4_AUX_PWR_EN")
	)
	(segment
		(start 354.836222 -220.149928)
		(end 354.826062 -220.139768)
		(width 0.15494)
		(layer "In15.Cu")
		(net "NIC4_AUX_PWR_EN")
	)
	(segment
		(start 356.32009 -196.879718)
		(end 360.22915 -200.788778)
		(width 0.15494)
		(layer "In15.Cu")
		(net "NIC4_AUX_PWR_EN")
	)
	(segment
		(start 356.79634 -219.98813)
		(end 356.634542 -220.149928)
		(width 0.15494)
		(layer "In15.Cu")
		(net "NIC4_AUX_PWR_EN")
	)
	(segment
		(start 297.671236 -186.399678)
		(end 297.995594 -186.07532)
		(width 0.15494)
		(layer "In15.Cu")
		(net "NIC4_AUX_PWR_EN")
	)
	(segment
		(start 331.520292 -186.07532)
		(end 333.298292 -187.85332)
		(width 0.15494)
		(layer "In15.Cu")
		(net "NIC4_AUX_PWR_EN")
	)
	(segment
		(start 354.826062 -220.139768)
		(end 354.424742 -220.139768)
		(width 0.15494)
		(layer "In15.Cu")
		(net "NIC4_AUX_PWR_EN")
	)
	(segment
		(start 137.08507 -177.52568)
		(end 137.84707 -178.28768)
		(width 0.13462)
		(layer "F.Cu")
		(net "CLK_100M_DB2000QL_NIC4_DP")
	)
	(segment
		(start 135.471154 -177.400458)
		(end 135.596376 -177.52568)
		(width 0.13462)
		(layer "F.Cu")
		(net "CLK_100M_DB2000QL_NIC4_DP")
	)
	(segment
		(start 139.315698 -178.28768)
		(end 139.674092 -177.929286)
		(width 0.13462)
		(layer "F.Cu")
		(net "CLK_100M_DB2000QL_NIC4_DP")
	)
	(segment
		(start 135.596376 -177.52568)
		(end 137.08507 -177.52568)
		(width 0.13462)
		(layer "F.Cu")
		(net "CLK_100M_DB2000QL_NIC4_DP")
	)
	(segment
		(start 137.84707 -178.28768)
		(end 139.315698 -178.28768)
		(width 0.13462)
		(layer "F.Cu")
		(net "CLK_100M_DB2000QL_NIC4_DP")
	)
	(segment
		(start 409.90266 -386.926836)
		(end 410.650436 -386.17906)
		(width 0.13208)
		(layer "F.Cu")
		(net "GPU_3V3IO_RSVD4")
	)
	(segment
		(start 406.81783 -368.483134)
		(end 412.328106 -368.483134)
		(width 0.13208)
		(layer "F.Cu")
		(net "GPU_3V3IO_RSVD4")
	)
	(segment
		(start 408.78125 -372.309898)
		(end 406.854152 -372.309898)
		(width 0.13208)
		(layer "F.Cu")
		(net "GPU_3V3IO_RSVD4")
	)
	(segment
		(start 415.003488 -360.264456)
		(end 445.25692 -360.264456)
		(width 0.13208)
		(layer "F.Cu")
		(net "GPU_3V3IO_RSVD4")
	)
	(segment
		(start 410.650436 -386.17906)
		(end 410.650436 -374.179084)
		(width 0.13208)
		(layer "F.Cu")
		(net "GPU_3V3IO_RSVD4")
	)
	(segment
		(start 406.50414 -371.693948)
		(end 406.50414 -370.824506)
		(width 0.13208)
		(layer "F.Cu")
		(net "GPU_3V3IO_RSVD4")
	)
	(segment
		(start 405.375872 -370.42344)
		(end 405.137366 -370.184934)
		(width 0.13208)
		(layer "F.Cu")
		(net "GPU_3V3IO_RSVD4")
	)
	(segment
		(start 452.33971 -366.404144)
		(end 452.048372 -366.695482)
		(width 0.13208)
		(layer "F.Cu")
		(net "GPU_3V3IO_RSVD4")
	)
	(segment
		(start 409.157932 -386.94106)
		(end 409.888436 -386.94106)
		(width 0.13208)
		(layer "F.Cu")
		(net "GPU_3V3IO_RSVD4")
	)
	(segment
		(start 452.650352 -363.462824)
		(end 452.33971 -363.773466)
		(width 0.13208)
		(layer "F.Cu")
		(net "GPU_3V3IO_RSVD4")
	)
	(segment
		(start 447.402204 -362.40974)
		(end 447.402204 -365.775494)
		(width 0.13208)
		(layer "F.Cu")
		(net "GPU_3V3IO_RSVD4")
	)
	(segment
		(start 412.842456 -362.425488)
		(end 415.003488 -360.264456)
		(width 0.13208)
		(layer "F.Cu")
		(net "GPU_3V3IO_RSVD4")
	)
	(segment
		(start 452.33971 -363.773466)
		(end 452.33971 -366.404144)
		(width 0.13208)
		(layer "F.Cu")
		(net "GPU_3V3IO_RSVD4")
	)
	(segment
		(start 406.236424 -368.598958)
		(end 406.702006 -368.598958)
		(width 0.13208)
		(layer "F.Cu")
		(net "GPU_3V3IO_RSVD4")
	)
	(segment
		(start 405.137366 -368.745008)
		(end 405.429974 -368.4524)
		(width 0.13208)
		(layer "F.Cu")
		(net "GPU_3V3IO_RSVD4")
	)
	(segment
		(start 405.137366 -370.184934)
		(end 405.137366 -368.745008)
		(width 0.13208)
		(layer "F.Cu")
		(net "GPU_3V3IO_RSVD4")
	)
	(segment
		(start 448.3227 -366.69599)
		(end 450.682106 -366.69599)
		(width 0.13208)
		(layer "F.Cu")
		(net "GPU_3V3IO_RSVD4")
	)
	(segment
		(start 406.854152 -372.309898)
		(end 406.50414 -371.959886)
		(width 0.13208)
		(layer "F.Cu")
		(net "GPU_3V3IO_RSVD4")
	)
	(segment
		(start 406.103074 -370.42344)
		(end 405.375872 -370.42344)
		(width 0.13208)
		(layer "F.Cu")
		(net "GPU_3V3IO_RSVD4")
	)
	(segment
		(start 445.25692 -360.264456)
		(end 447.402204 -362.40974)
		(width 0.13208)
		(layer "F.Cu")
		(net "GPU_3V3IO_RSVD4")
	)
	(segment
		(start 409.888436 -386.94106)
		(end 409.90266 -386.926836)
		(width 0.13208)
		(layer "F.Cu")
		(net "GPU_3V3IO_RSVD4")
	)
	(segment
		(start 412.328106 -368.483134)
		(end 412.842456 -367.968784)
		(width 0.13208)
		(layer "F.Cu")
		(net "GPU_3V3IO_RSVD4")
	)
	(segment
		(start 452.048372 -366.695482)
		(end 451.669658 -366.695482)
		(width 0.13208)
		(layer "F.Cu")
		(net "GPU_3V3IO_RSVD4")
	)
	(segment
		(start 406.702006 -368.598958)
		(end 406.81783 -368.483134)
		(width 0.13208)
		(layer "F.Cu")
		(net "GPU_3V3IO_RSVD4")
	)
	(segment
		(start 406.089866 -368.4524)
		(end 406.236424 -368.598958)
		(width 0.13208)
		(layer "F.Cu")
		(net "GPU_3V3IO_RSVD4")
	)
	(segment
		(start 451.66915 -366.69599)
		(end 451.669658 -366.695482)
		(width 0.13208)
		(layer "F.Cu")
		(net "GPU_3V3IO_RSVD4")
	)
	(segment
		(start 406.50414 -370.824506)
		(end 406.103074 -370.42344)
		(width 0.13208)
		(layer "F.Cu")
		(net "GPU_3V3IO_RSVD4")
	)
	(segment
		(start 453.912986 -363.462824)
		(end 452.650352 -363.462824)
		(width 0.13208)
		(layer "F.Cu")
		(net "GPU_3V3IO_RSVD4")
	)
	(segment
		(start 406.50414 -371.959886)
		(end 406.50414 -371.693948)
		(width 0.13208)
		(layer "F.Cu")
		(net "GPU_3V3IO_RSVD4")
	)
	(segment
		(start 405.429974 -368.4524)
		(end 406.089866 -368.4524)
		(width 0.13208)
		(layer "F.Cu")
		(net "GPU_3V3IO_RSVD4")
	)
	(segment
		(start 447.402204 -365.775494)
		(end 448.3227 -366.69599)
		(width 0.13208)
		(layer "F.Cu")
		(net "GPU_3V3IO_RSVD4")
	)
	(segment
		(start 450.682106 -366.69599)
		(end 451.66915 -366.69599)
		(width 0.13208)
		(layer "F.Cu")
		(net "GPU_3V3IO_RSVD4")
	)
	(segment
		(start 410.650436 -374.179084)
		(end 408.78125 -372.309898)
		(width 0.13208)
		(layer "F.Cu")
		(net "GPU_3V3IO_RSVD4")
	)
	(segment
		(start 412.842456 -367.968784)
		(end 412.842456 -362.425488)
		(width 0.13208)
		(layer "F.Cu")
		(net "GPU_3V3IO_RSVD4")
	)
	(via
		(at 452.650352 -363.462824)
		(size 0.762)
		(drill 0.381)
		(layers "F.Cu" "B.Cu")
		(net "GPU_3V3IO_RSVD4")
	)
	(via
		(at 409.90266 -386.926836)
		(size 0.508)
		(drill 0.254)
		(layers "F.Cu" "B.Cu")
		(net "GPU_3V3IO_RSVD4")
	)
	(segment
		(start 436.90413 -414.085278)
		(end 438.266078 -412.72333)
		(width 0.15494)
		(layer "In9.Cu")
		(net "GPU_3V3IO_RSVD4")
	)
	(segment
		(start 409.90266 -386.926836)
		(end 409.105608 -386.926836)
		(width 0.15494)
		(layer "In9.Cu")
		(net "GPU_3V3IO_RSVD4")
	)
	(segment
		(start 439.432954 -412.72333)
		(end 439.947558 -412.208726)
		(width 0.15494)
		(layer "In9.Cu")
		(net "GPU_3V3IO_RSVD4")
	)
	(segment
		(start 439.947558 -402.147786)
		(end 439.289952 -401.49018)
		(width 0.15494)
		(layer "In9.Cu")
		(net "GPU_3V3IO_RSVD4")
	)
	(segment
		(start 439.947558 -412.208726)
		(end 439.947558 -402.147786)
		(width 0.15494)
		(layer "In9.Cu")
		(net "GPU_3V3IO_RSVD4")
	)
	(segment
		(start 407.557732 -390.45642)
		(end 408.475942 -391.37463)
		(width 0.15494)
		(layer "In9.Cu")
		(net "GPU_3V3IO_RSVD4")
	)
	(segment
		(start 408.475942 -391.37463)
		(end 411.677358 -391.37463)
		(width 0.15494)
		(layer "In9.Cu")
		(net "GPU_3V3IO_RSVD4")
	)
	(segment
		(start 416.593528 -412.021274)
		(end 418.657532 -414.085278)
		(width 0.15494)
		(layer "In9.Cu")
		(net "GPU_3V3IO_RSVD4")
	)
	(segment
		(start 409.105608 -386.926836)
		(end 407.557732 -388.474712)
		(width 0.15494)
		(layer "In9.Cu")
		(net "GPU_3V3IO_RSVD4")
	)
	(segment
		(start 416.593528 -396.2908)
		(end 416.593528 -412.021274)
		(width 0.15494)
		(layer "In9.Cu")
		(net "GPU_3V3IO_RSVD4")
	)
	(segment
		(start 407.557732 -388.474712)
		(end 407.557732 -390.45642)
		(width 0.15494)
		(layer "In9.Cu")
		(net "GPU_3V3IO_RSVD4")
	)
	(segment
		(start 418.657532 -414.085278)
		(end 436.90413 -414.085278)
		(width 0.15494)
		(layer "In9.Cu")
		(net "GPU_3V3IO_RSVD4")
	)
	(segment
		(start 438.266078 -412.72333)
		(end 439.432954 -412.72333)
		(width 0.15494)
		(layer "In9.Cu")
		(net "GPU_3V3IO_RSVD4")
	)
	(segment
		(start 411.677358 -391.37463)
		(end 416.593528 -396.2908)
		(width 0.15494)
		(layer "In9.Cu")
		(net "GPU_3V3IO_RSVD4")
	)
	(segment
		(start 61.165232 -385.732528)
		(end 61.165232 -386.065268)
		(width 0.13208)
		(layer "F.Cu")
		(net "PRSNT_SWB_C_N")
	)
	(segment
		(start 59.084972 -383.652268)
		(end 61.165232 -385.732528)
		(width 0.13208)
		(layer "F.Cu")
		(net "PRSNT_SWB_C_N")
	)
	(via
		(at 61.165232 -386.065268)
		(size 0.508)
		(drill 0.254)
		(layers "F.Cu" "B.Cu")
		(net "PRSNT_SWB_C_N")
	)
	(segment
		(start 69.194934 -411.917388)
		(end 71.129144 -413.851598)
		(width 0.15494)
		(layer "In9.Cu")
		(net "PRSNT_SWB_C_N")
	)
	(segment
		(start 64.526922 -386.065268)
		(end 69.194934 -390.73328)
		(width 0.15494)
		(layer "In9.Cu")
		(net "PRSNT_SWB_C_N")
	)
	(segment
		(start 83.348322 -413.851598)
		(end 85.109812 -412.090108)
		(width 0.15494)
		(layer "In9.Cu")
		(net "PRSNT_SWB_C_N")
	)
	(segment
		(start 61.165232 -386.065268)
		(end 64.526922 -386.065268)
		(width 0.15494)
		(layer "In9.Cu")
		(net "PRSNT_SWB_C_N")
	)
	(segment
		(start 71.129144 -413.851598)
		(end 83.348322 -413.851598)
		(width 0.15494)
		(layer "In9.Cu")
		(net "PRSNT_SWB_C_N")
	)
	(segment
		(start 69.194934 -390.73328)
		(end 69.194934 -411.917388)
		(width 0.15494)
		(layer "In9.Cu")
		(net "PRSNT_SWB_C_N")
	)
	(segment
		(start 331.989176 -263.993376)
		(end 334.202024 -263.993376)
		(width 0.13208)
		(layer "F.Cu")
		(net "SMB_PEX2_SCL")
	)
	(segment
		(start 211.088478 -232.960164)
		(end 211.177886 -233.049572)
		(width 0.13208)
		(layer "F.Cu")
		(net "SMB_PEX2_SCL")
	)
	(segment
		(start 317.30442 -302.093884)
		(end 317.30442 -301.967646)
		(width 0.13208)
		(layer "F.Cu")
		(net "SMB_PEX2_SCL")
	)
	(segment
		(start 329.960224 -274.394422)
		(end 329.960224 -266.022328)
		(width 0.13208)
		(layer "F.Cu")
		(net "SMB_PEX2_SCL")
	)
	(segment
		(start 329.960224 -266.022328)
		(end 331.989176 -263.993376)
		(width 0.13208)
		(layer "F.Cu")
		(net "SMB_PEX2_SCL")
	)
	(segment
		(start 315.8998 -300.563026)
		(end 315.8998 -289.3568)
		(width 0.13208)
		(layer "F.Cu")
		(net "SMB_PEX2_SCL")
	)
	(segment
		(start 316.272672 -288.983928)
		(end 316.272672 -288.081974)
		(width 0.13208)
		(layer "F.Cu")
		(net "SMB_PEX2_SCL")
	)
	(segment
		(start 316.272672 -288.081974)
		(end 329.960224 -274.394422)
		(width 0.13208)
		(layer "F.Cu")
		(net "SMB_PEX2_SCL")
	)
	(segment
		(start 211.088478 -232.85323)
		(end 211.088478 -232.960164)
		(width 0.13208)
		(layer "F.Cu")
		(net "SMB_PEX2_SCL")
	)
	(segment
		(start 315.8998 -289.3568)
		(end 316.272672 -288.983928)
		(width 0.13208)
		(layer "F.Cu")
		(net "SMB_PEX2_SCL")
	)
	(segment
		(start 211.177886 -233.049572)
		(end 211.177886 -233.481372)
		(width 0.13208)
		(layer "F.Cu")
		(net "SMB_PEX2_SCL")
	)
	(segment
		(start 317.30442 -301.967646)
		(end 315.8998 -300.563026)
		(width 0.13208)
		(layer "F.Cu")
		(net "SMB_PEX2_SCL")
	)
	(via
		(at 211.088478 -232.85323)
		(size 0.508)
		(drill 0.254)
		(layers "F.Cu" "B.Cu")
		(net "SMB_PEX2_SCL")
	)
	(via
		(at 216.776046 -255.790192)
		(size 0.508)
		(drill 0.254)
		(layers "F.Cu" "B.Cu")
		(net "SMB_PEX2_SCL")
	)
	(via
		(at 334.202024 -263.993376)
		(size 0.508)
		(drill 0.254)
		(layers "F.Cu" "B.Cu")
		(net "SMB_PEX2_SCL")
	)
	(segment
		(start 210.81873 -233.680254)
		(end 211.088478 -233.410506)
		(width 0.13208)
		(layer "B.Cu")
		(net "SMB_PEX2_SCL")
	)
	(segment
		(start 211.088478 -233.410506)
		(end 211.088478 -232.85323)
		(width 0.13208)
		(layer "B.Cu")
		(net "SMB_PEX2_SCL")
	)
	(segment
		(start 215.14054 -240.91138)
		(end 214.029798 -238.229902)
		(width 0.15494)
		(layer "In5.Cu")
		(net "SMB_PEX2_SCL")
	)
	(segment
		(start 216.776046 -255.790192)
		(end 216.776046 -255.409192)
		(width 0.15494)
		(layer "In5.Cu")
		(net "SMB_PEX2_SCL")
	)
	(segment
		(start 214.029798 -238.229902)
		(end 211.088478 -235.288582)
		(width 0.15494)
		(layer "In5.Cu")
		(net "SMB_PEX2_SCL")
	)
	(segment
		(start 216.776046 -255.409192)
		(end 215.14054 -253.773686)
		(width 0.15494)
		(layer "In5.Cu")
		(net "SMB_PEX2_SCL")
	)
	(segment
		(start 215.14054 -253.773686)
		(end 215.14054 -240.91138)
		(width 0.15494)
		(layer "In5.Cu")
		(net "SMB_PEX2_SCL")
	)
	(segment
		(start 211.088478 -235.288582)
		(end 211.088478 -232.85323)
		(width 0.15494)
		(layer "In5.Cu")
		(net "SMB_PEX2_SCL")
	)
	(segment
		(start 299.024802 -265.034522)
		(end 317.970408 -265.034522)
		(width 0.15494)
		(layer "In13.Cu")
		(net "SMB_PEX2_SCL")
	)
	(segment
		(start 323.96811 -263.62279)
		(end 330.035662 -263.62279)
		(width 0.15494)
		(layer "In13.Cu")
		(net "SMB_PEX2_SCL")
	)
	(segment
		(start 323.05625 -263.62279)
		(end 323.19087 -263.75741)
		(width 0.15494)
		(layer "In13.Cu")
		(net "SMB_PEX2_SCL")
	)
	(segment
		(start 270.05407 -269.997682)
		(end 275.109178 -269.997682)
		(width 0.15494)
		(layer "In13.Cu")
		(net "SMB_PEX2_SCL")
	)
	(segment
		(start 334.674972 -264.566908)
		(end 334.202024 -264.09396)
		(width 0.15494)
		(layer "In13.Cu")
		(net "SMB_PEX2_SCL")
	)
	(segment
		(start 322.41363 -264.481056)
		(end 322.54825 -264.346436)
		(width 0.15494)
		(layer "In13.Cu")
		(net "SMB_PEX2_SCL")
	)
	(segment
		(start 220.54312 -256.86512)
		(end 229.874826 -256.86512)
		(width 0.15494)
		(layer "In13.Cu")
		(net "SMB_PEX2_SCL")
	)
	(segment
		(start 219.468192 -255.790192)
		(end 220.54312 -256.86512)
		(width 0.15494)
		(layer "In13.Cu")
		(net "SMB_PEX2_SCL")
	)
	(segment
		(start 216.776046 -255.790192)
		(end 219.468192 -255.790192)
		(width 0.15494)
		(layer "In13.Cu")
		(net "SMB_PEX2_SCL")
	)
	(segment
		(start 323.32549 -264.481056)
		(end 323.69887 -264.481056)
		(width 0.15494)
		(layer "In13.Cu")
		(net "SMB_PEX2_SCL")
	)
	(segment
		(start 275.109178 -269.997682)
		(end 282.151836 -262.955024)
		(width 0.15494)
		(layer "In13.Cu")
		(net "SMB_PEX2_SCL")
	)
	(segment
		(start 334.202024 -264.09396)
		(end 334.202024 -263.993376)
		(width 0.15494)
		(layer "In13.Cu")
		(net "SMB_PEX2_SCL")
	)
	(segment
		(start 333.289402 -265.486896)
		(end 334.4291 -265.486896)
		(width 0.15494)
		(layer "In13.Cu")
		(net "SMB_PEX2_SCL")
	)
	(segment
		(start 282.151836 -262.955024)
		(end 296.945304 -262.955024)
		(width 0.15494)
		(layer "In13.Cu")
		(net "SMB_PEX2_SCL")
	)
	(segment
		(start 319.38214 -263.62279)
		(end 321.77101 -263.62279)
		(width 0.15494)
		(layer "In13.Cu")
		(net "SMB_PEX2_SCL")
	)
	(segment
		(start 332.837028 -265.034522)
		(end 333.289402 -265.486896)
		(width 0.15494)
		(layer "In13.Cu")
		(net "SMB_PEX2_SCL")
	)
	(segment
		(start 331.447394 -265.034522)
		(end 332.837028 -265.034522)
		(width 0.15494)
		(layer "In13.Cu")
		(net "SMB_PEX2_SCL")
	)
	(segment
		(start 334.674972 -265.241024)
		(end 334.674972 -264.566908)
		(width 0.15494)
		(layer "In13.Cu")
		(net "SMB_PEX2_SCL")
	)
	(segment
		(start 321.77101 -263.62279)
		(end 321.90563 -263.75741)
		(width 0.15494)
		(layer "In13.Cu")
		(net "SMB_PEX2_SCL")
	)
	(segment
		(start 323.83349 -263.75741)
		(end 323.96811 -263.62279)
		(width 0.15494)
		(layer "In13.Cu")
		(net "SMB_PEX2_SCL")
	)
	(segment
		(start 321.90563 -264.346436)
		(end 322.04025 -264.481056)
		(width 0.15494)
		(layer "In13.Cu")
		(net "SMB_PEX2_SCL")
	)
	(segment
		(start 229.874826 -256.86512)
		(end 230.244142 -257.234436)
		(width 0.15494)
		(layer "In13.Cu")
		(net "SMB_PEX2_SCL")
	)
	(segment
		(start 323.19087 -264.346436)
		(end 323.32549 -264.481056)
		(width 0.15494)
		(layer "In13.Cu")
		(net "SMB_PEX2_SCL")
	)
	(segment
		(start 321.90563 -263.75741)
		(end 321.90563 -264.346436)
		(width 0.15494)
		(layer "In13.Cu")
		(net "SMB_PEX2_SCL")
	)
	(segment
		(start 265.393932 -265.337544)
		(end 270.05407 -269.997682)
		(width 0.15494)
		(layer "In13.Cu")
		(net "SMB_PEX2_SCL")
	)
	(segment
		(start 317.970408 -265.034522)
		(end 319.38214 -263.62279)
		(width 0.15494)
		(layer "In13.Cu")
		(net "SMB_PEX2_SCL")
	)
	(segment
		(start 334.4291 -265.486896)
		(end 334.674972 -265.241024)
		(width 0.15494)
		(layer "In13.Cu")
		(net "SMB_PEX2_SCL")
	)
	(segment
		(start 296.945304 -262.955024)
		(end 299.024802 -265.034522)
		(width 0.15494)
		(layer "In13.Cu")
		(net "SMB_PEX2_SCL")
	)
	(segment
		(start 330.035662 -263.62279)
		(end 331.447394 -265.034522)
		(width 0.15494)
		(layer "In13.Cu")
		(net "SMB_PEX2_SCL")
	)
	(segment
		(start 323.19087 -263.75741)
		(end 323.19087 -264.346436)
		(width 0.15494)
		(layer "In13.Cu")
		(net "SMB_PEX2_SCL")
	)
	(segment
		(start 322.04025 -264.481056)
		(end 322.41363 -264.481056)
		(width 0.15494)
		(layer "In13.Cu")
		(net "SMB_PEX2_SCL")
	)
	(segment
		(start 244.102382 -257.234436)
		(end 252.20549 -265.337544)
		(width 0.15494)
		(layer "In13.Cu")
		(net "SMB_PEX2_SCL")
	)
	(segment
		(start 322.54825 -264.346436)
		(end 322.54825 -263.75741)
		(width 0.15494)
		(layer "In13.Cu")
		(net "SMB_PEX2_SCL")
	)
	(segment
		(start 323.83349 -264.346436)
		(end 323.83349 -263.75741)
		(width 0.15494)
		(layer "In13.Cu")
		(net "SMB_PEX2_SCL")
	)
	(segment
		(start 322.68287 -263.62279)
		(end 323.05625 -263.62279)
		(width 0.15494)
		(layer "In13.Cu")
		(net "SMB_PEX2_SCL")
	)
	(segment
		(start 322.54825 -263.75741)
		(end 322.68287 -263.62279)
		(width 0.15494)
		(layer "In13.Cu")
		(net "SMB_PEX2_SCL")
	)
	(segment
		(start 230.244142 -257.234436)
		(end 244.102382 -257.234436)
		(width 0.15494)
		(layer "In13.Cu")
		(net "SMB_PEX2_SCL")
	)
	(segment
		(start 252.20549 -265.337544)
		(end 265.393932 -265.337544)
		(width 0.15494)
		(layer "In13.Cu")
		(net "SMB_PEX2_SCL")
	)
	(segment
		(start 323.69887 -264.481056)
		(end 323.83349 -264.346436)
		(width 0.15494)
		(layer "In13.Cu")
		(net "SMB_PEX2_SCL")
	)
	(segment
		(start 137.985754 -27.492198)
		(end 137.854182 -27.492198)
		(width 0.381)
		(layer "F.Cu")
		(net "P3V3_SSD4")
	)
	(segment
		(start 122.068844 -32.512762)
		(end 122.068844 -30.971236)
		(width 0.381)
		(layer "F.Cu")
		(net "P3V3_SSD4")
	)
	(segment
		(start 135.571738 -25.742392)
		(end 135.571738 -26.360882)
		(width 0.4572)
		(layer "F.Cu")
		(net "P3V3_SSD4")
	)
	(segment
		(start 123.47194 -24.807418)
		(end 122.85345 -24.807418)
		(width 0.4572)
		(layer "F.Cu")
		(net "P3V3_SSD4")
	)
	(segment
		(start 122.068844 -30.971236)
		(end 121.494296 -30.396688)
		(width 0.381)
		(layer "F.Cu")
		(net "P3V3_SSD4")
	)
	(segment
		(start 121.79427 -32.787336)
		(end 122.068844 -32.512762)
		(width 0.381)
		(layer "F.Cu")
		(net "P3V3_SSD4")
	)
	(segment
		(start 140.769594 -20.467574)
		(end 140.156692 -20.467574)
		(width 0.508)
		(layer "F.Cu")
		(net "P3V3_SSD4")
	)
	(segment
		(start 108.94695 -37.47516)
		(end 108.241338 -37.47516)
		(width 0.4572)
		(layer "F.Cu")
		(net "P3V3_SSD4")
	)
	(segment
		(start 141.660626 -14.799818)
		(end 141.660626 -16.439388)
		(width 0.381)
		(layer "F.Cu")
		(net "P3V3_SSD4")
	)
	(segment
		(start 121.79427 -34.248852)
		(end 121.79427 -32.787336)
		(width 0.381)
		(layer "F.Cu")
		(net "P3V3_SSD4")
	)
	(segment
		(start 141.725142 -14.100302)
		(end 141.725142 -14.735302)
		(width 0.381)
		(layer "F.Cu")
		(net "P3V3_SSD4")
	)
	(segment
		(start 124.279152 -59.978036)
		(end 124.279152 -60.633356)
		(width 0.381)
		(layer "F.Cu")
		(net "P3V3_SSD4")
	)
	(segment
		(start 132.333492 -24.790146)
		(end 132.5753 -25.031954)
		(width 0.381)
		(layer "F.Cu")
		(net "P3V3_SSD4")
	)
	(segment
		(start 132.5753 -25.031954)
		(end 134.026656 -25.031954)
		(width 0.381)
		(layer "F.Cu")
		(net "P3V3_SSD4")
	)
	(segment
		(start 141.725142 -14.735302)
		(end 141.660626 -14.799818)
		(width 0.381)
		(layer "F.Cu")
		(net "P3V3_SSD4")
	)
	(segment
		(start 140.156692 -17.419574)
		(end 140.766292 -17.419574)
		(width 0.508)
		(layer "F.Cu")
		(net "P3V3_SSD4")
	)
	(segment
		(start 131.36499 -24.790146)
		(end 132.333492 -24.790146)
		(width 0.381)
		(layer "F.Cu")
		(net "P3V3_SSD4")
	)
	(segment
		(start 137.854182 -27.492198)
		(end 137.333228 -26.971244)
		(width 0.381)
		(layer "F.Cu")
		(net "P3V3_SSD4")
	)
	(segment
		(start 134.026656 -25.031954)
		(end 134.670038 -25.031954)
		(width 0.4572)
		(layer "F.Cu")
		(net "P3V3_SSD4")
	)
	(via
		(at 122.85345 -24.807418)
		(size 0.508)
		(drill 0.254)
		(layers "F.Cu" "B.Cu")
		(net "P3V3_SSD4")
	)
	(via
		(at 123.24969 -53.469286)
		(size 0.508)
		(drill 0.254)
		(layers "F.Cu" "B.Cu")
		(net "P3V3_SSD4")
	)
	(via
		(at 120.410732 -30.376876)
		(size 0.508)
		(drill 0.254)
		(layers "F.Cu" "B.Cu")
		(net "P3V3_SSD4")
	)
	(via
		(at 123.700032 -52.528724)
		(size 0.508)
		(drill 0.254)
		(layers "F.Cu" "B.Cu")
		(net "P3V3_SSD4")
	)
	(via
		(at 123.614688 -51.243992)
		(size 0.508)
		(drill 0.254)
		(layers "F.Cu" "B.Cu")
		(net "P3V3_SSD4")
	)
	(via
		(at 120.410732 -29.614876)
		(size 0.508)
		(drill 0.254)
		(layers "F.Cu" "B.Cu")
		(net "P3V3_SSD4")
	)
	(via
		(at 123.864116 -49.574704)
		(size 0.508)
		(drill 0.254)
		(layers "F.Cu" "B.Cu")
		(net "P3V3_SSD4")
	)
	(via
		(at 135.571738 -26.360882)
		(size 0.508)
		(drill 0.254)
		(layers "F.Cu" "B.Cu")
		(net "P3V3_SSD4")
	)
	(via
		(at 123.614688 -50.608992)
		(size 0.508)
		(drill 0.254)
		(layers "F.Cu" "B.Cu")
		(net "P3V3_SSD4")
	)
	(via
		(at 140.766292 -17.419574)
		(size 0.508)
		(drill 0.254)
		(layers "F.Cu" "B.Cu")
		(net "P3V3_SSD4")
	)
	(via
		(at 124.499116 -49.574704)
		(size 0.508)
		(drill 0.254)
		(layers "F.Cu" "B.Cu")
		(net "P3V3_SSD4")
	)
	(via
		(at 122.61469 -53.469286)
		(size 0.508)
		(drill 0.254)
		(layers "F.Cu" "B.Cu")
		(net "P3V3_SSD4")
	)
	(via
		(at 134.670038 -25.031954)
		(size 0.508)
		(drill 0.254)
		(layers "F.Cu" "B.Cu")
		(net "P3V3_SSD4")
	)
	(via
		(at 123.065032 -52.528724)
		(size 0.508)
		(drill 0.254)
		(layers "F.Cu" "B.Cu")
		(net "P3V3_SSD4")
	)
	(via
		(at 122.594116 -49.574704)
		(size 0.508)
		(drill 0.254)
		(layers "F.Cu" "B.Cu")
		(net "P3V3_SSD4")
	)
	(via
		(at 124.279152 -60.633356)
		(size 0.508)
		(drill 0.254)
		(layers "F.Cu" "B.Cu")
		(net "P3V3_SSD4")
	)
	(via
		(at 123.229116 -49.574704)
		(size 0.508)
		(drill 0.254)
		(layers "F.Cu" "B.Cu")
		(net "P3V3_SSD4")
	)
	(via
		(at 124.376688 -50.608992)
		(size 0.508)
		(drill 0.254)
		(layers "F.Cu" "B.Cu")
		(net "P3V3_SSD4")
	)
	(via
		(at 141.725142 -14.100302)
		(size 0.508)
		(drill 0.254)
		(layers "F.Cu" "B.Cu")
		(net "P3V3_SSD4")
	)
	(via
		(at 137.333228 -26.971244)
		(size 0.508)
		(drill 0.254)
		(layers "F.Cu" "B.Cu")
		(net "P3V3_SSD4")
	)
	(via
		(at 140.769594 -20.467574)
		(size 0.508)
		(drill 0.254)
		(layers "F.Cu" "B.Cu")
		(net "P3V3_SSD4")
	)
	(via
		(at 124.376688 -51.320192)
		(size 0.508)
		(drill 0.254)
		(layers "F.Cu" "B.Cu")
		(net "P3V3_SSD4")
	)
	(via
		(at 108.241338 -37.47516)
		(size 0.508)
		(drill 0.254)
		(layers "F.Cu" "B.Cu")
		(net "P3V3_SSD4")
	)
	(segment
		(start 110.704376 -38.322758)
		(end 109.088936 -38.322758)
		(width 0.508)
		(layer "In9.Cu")
		(net "P3V3_SSD4")
	)
	(segment
		(start 111.15421 -37.872924)
		(end 110.704376 -38.322758)
		(width 0.508)
		(layer "In9.Cu")
		(net "P3V3_SSD4")
	)
	(segment
		(start 109.088936 -38.322758)
		(end 108.241338 -37.47516)
		(width 0.508)
		(layer "In9.Cu")
		(net "P3V3_SSD4")
	)
	(segment
		(start 117.863874 -37.872924)
		(end 111.15421 -37.872924)
		(width 0.508)
		(layer "In9.Cu")
		(net "P3V3_SSD4")
	)
	(segment
		(start 175.765714 -192.933574)
		(end 174.535084 -192.933574)
		(width 0.13208)
		(layer "F.Cu")
		(net "SPI_BIC1_MISO_LS01_DIR4")
	)
	(via
		(at 175.765714 -192.933574)
		(size 0.508)
		(drill 0.254)
		(layers "F.Cu" "B.Cu")
		(net "SPI_BIC1_MISO_LS01_DIR4")
	)
	(segment
		(start 177.023776 -191.381634)
		(end 177.023776 -192.270634)
		(width 0.13208)
		(layer "B.Cu")
		(net "SPI_BIC1_MISO_LS01_DIR4")
	)
	(segment
		(start 176.428654 -192.270634)
		(end 175.765714 -192.933574)
		(width 0.13208)
		(layer "B.Cu")
		(net "SPI_BIC1_MISO_LS01_DIR4")
	)
	(segment
		(start 177.023776 -192.270634)
		(end 176.428654 -192.270634)
		(width 0.13208)
		(layer "B.Cu")
		(net "SPI_BIC1_MISO_LS01_DIR4")
	)
	(segment
		(start 139.290806 -178.562)
		(end 137.733278 -178.562)
		(width 0.13462)
		(layer "F.Cu")
		(net "CLK_100M_DB2000QL_NIC4_DN")
	)
	(segment
		(start 137.733278 -178.562)
		(end 136.971278 -177.8)
		(width 0.13462)
		(layer "F.Cu")
		(net "CLK_100M_DB2000QL_NIC4_DN")
	)
	(segment
		(start 139.674092 -178.945286)
		(end 139.290806 -178.562)
		(width 0.13462)
		(layer "F.Cu")
		(net "CLK_100M_DB2000QL_NIC4_DN")
	)
	(segment
		(start 136.971278 -177.8)
		(end 135.571484 -177.8)
		(width 0.13462)
		(layer "F.Cu")
		(net "CLK_100M_DB2000QL_NIC4_DN")
	)
	(segment
		(start 135.571484 -177.8)
		(end 135.471154 -177.90033)
		(width 0.13462)
		(layer "F.Cu")
		(net "CLK_100M_DB2000QL_NIC4_DN")
	)
	(segment
		(start 217.637106 -192.572894)
		(end 218.186 -192.024)
		(width 0.13208)
		(layer "F.Cu")
		(net "SMB_NIC7_LS_EN")
	)
	(segment
		(start 216.991946 -192.572894)
		(end 217.637106 -192.572894)
		(width 0.13208)
		(layer "F.Cu")
		(net "SMB_NIC7_LS_EN")
	)
	(segment
		(start 218.186 -192.024)
		(end 218.80195 -192.024)
		(width 0.13208)
		(layer "F.Cu")
		(net "SMB_NIC7_LS_EN")
	)
	(via
		(at 218.186 -192.024)
		(size 0.508)
		(drill 0.254)
		(layers "F.Cu" "B.Cu")
		(net "SMB_NIC7_LS_EN")
	)
	(segment
		(start 316.3316 -289.5346)
		(end 316.69228 -289.17392)
		(width 0.13208)
		(layer "F.Cu")
		(net "SMB_PEX2_SDA")
	)
	(segment
		(start 316.69228 -289.17392)
		(end 316.69228 -288.513774)
		(width 0.13208)
		(layer "F.Cu")
		(net "SMB_PEX2_SDA")
	)
	(segment
		(start 331.768196 -264.87755)
		(end 334.163924 -264.87755)
		(width 0.13208)
		(layer "F.Cu")
		(net "SMB_PEX2_SDA")
	)
	(segment
		(start 319.313814 -302.321214)
		(end 318.327532 -302.321214)
		(width 0.13208)
		(layer "F.Cu")
		(net "SMB_PEX2_SDA")
	)
	(segment
		(start 319.478152 -303.922938)
		(end 319.478152 -302.485552)
		(width 0.13208)
		(layer "F.Cu")
		(net "SMB_PEX2_SDA")
	)
	(segment
		(start 318.89319 -304.5079)
		(end 319.478152 -303.922938)
		(width 0.13208)
		(layer "F.Cu")
		(net "SMB_PEX2_SDA")
	)
	(segment
		(start 210.781392 -232.209594)
		(end 211.283042 -232.209594)
		(width 0.13208)
		(layer "F.Cu")
		(net "SMB_PEX2_SDA")
	)
	(segment
		(start 211.283042 -232.209594)
		(end 211.558886 -231.93375)
		(width 0.13208)
		(layer "F.Cu")
		(net "SMB_PEX2_SDA")
	)
	(segment
		(start 316.3316 -300.325282)
		(end 316.3316 -289.5346)
		(width 0.13208)
		(layer "F.Cu")
		(net "SMB_PEX2_SDA")
	)
	(segment
		(start 330.397104 -274.60575)
		(end 330.397104 -266.248642)
		(width 0.13208)
		(layer "F.Cu")
		(net "SMB_PEX2_SDA")
	)
	(segment
		(start 318.327532 -302.321214)
		(end 316.3316 -300.325282)
		(width 0.13208)
		(layer "F.Cu")
		(net "SMB_PEX2_SDA")
	)
	(segment
		(start 316.69228 -288.513774)
		(end 317.60414 -287.601914)
		(width 0.13208)
		(layer "F.Cu")
		(net "SMB_PEX2_SDA")
	)
	(segment
		(start 317.60414 -287.601914)
		(end 317.60414 -287.398714)
		(width 0.13208)
		(layer "F.Cu")
		(net "SMB_PEX2_SDA")
	)
	(segment
		(start 319.478152 -302.485552)
		(end 319.313814 -302.321214)
		(width 0.13208)
		(layer "F.Cu")
		(net "SMB_PEX2_SDA")
	)
	(segment
		(start 330.397104 -266.248642)
		(end 331.768196 -264.87755)
		(width 0.13208)
		(layer "F.Cu")
		(net "SMB_PEX2_SDA")
	)
	(segment
		(start 317.60414 -287.398714)
		(end 330.397104 -274.60575)
		(width 0.13208)
		(layer "F.Cu")
		(net "SMB_PEX2_SDA")
	)
	(segment
		(start 211.558886 -231.93375)
		(end 211.558886 -231.550972)
		(width 0.13208)
		(layer "F.Cu")
		(net "SMB_PEX2_SDA")
	)
	(via
		(at 210.781392 -232.209594)
		(size 0.508)
		(drill 0.254)
		(layers "F.Cu" "B.Cu")
		(net "SMB_PEX2_SDA")
	)
	(via
		(at 334.163924 -264.87755)
		(size 0.508)
		(drill 0.254)
		(layers "F.Cu" "B.Cu")
		(net "SMB_PEX2_SDA")
	)
	(via
		(at 216.074244 -255.758442)
		(size 0.508)
		(drill 0.254)
		(layers "F.Cu" "B.Cu")
		(net "SMB_PEX2_SDA")
	)
	(segment
		(start 210.641184 -232.209594)
		(end 210.43265 -232.418128)
		(width 0.13208)
		(layer "B.Cu")
		(net "SMB_PEX2_SDA")
	)
	(segment
		(start 210.43265 -233.364278)
		(end 209.784442 -234.012486)
		(width 0.13208)
		(layer "B.Cu")
		(net "SMB_PEX2_SDA")
	)
	(segment
		(start 209.784442 -234.012486)
		(end 209.784442 -234.033822)
		(width 0.13208)
		(layer "B.Cu")
		(net "SMB_PEX2_SDA")
	)
	(segment
		(start 210.781392 -232.209594)
		(end 210.641184 -232.209594)
		(width 0.13208)
		(layer "B.Cu")
		(net "SMB_PEX2_SDA")
	)
	(segment
		(start 210.43265 -232.418128)
		(end 210.43265 -233.364278)
		(width 0.13208)
		(layer "B.Cu")
		(net "SMB_PEX2_SDA")
	)
	(segment
		(start 210.438492 -232.412286)
		(end 210.438492 -235.28909)
		(width 0.15494)
		(layer "In5.Cu")
		(net "SMB_PEX2_SDA")
	)
	(segment
		(start 213.623906 -238.474504)
		(end 214.6808 -241.025934)
		(width 0.15494)
		(layer "In5.Cu")
		(net "SMB_PEX2_SDA")
	)
	(segment
		(start 210.781392 -232.209594)
		(end 210.641184 -232.209594)
		(width 0.15494)
		(layer "In5.Cu")
		(net "SMB_PEX2_SDA")
	)
	(segment
		(start 210.438492 -235.28909)
		(end 213.623906 -238.474504)
		(width 0.15494)
		(layer "In5.Cu")
		(net "SMB_PEX2_SDA")
	)
	(segment
		(start 210.641184 -232.209594)
		(end 210.438492 -232.412286)
		(width 0.15494)
		(layer "In5.Cu")
		(net "SMB_PEX2_SDA")
	)
	(segment
		(start 214.6808 -241.025934)
		(end 214.6808 -254.364998)
		(width 0.15494)
		(layer "In5.Cu")
		(net "SMB_PEX2_SDA")
	)
	(segment
		(start 214.6808 -254.364998)
		(end 216.074244 -255.758442)
		(width 0.15494)
		(layer "In5.Cu")
		(net "SMB_PEX2_SDA")
	)
	(segment
		(start 317.779908 -264.574782)
		(end 319.19164 -263.16305)
		(width 0.15494)
		(layer "In13.Cu")
		(net "SMB_PEX2_SDA")
	)
	(segment
		(start 270.200628 -269.494)
		(end 274.96262 -269.494)
		(width 0.15494)
		(layer "In13.Cu")
		(net "SMB_PEX2_SDA")
	)
	(segment
		(start 216.184988 -255.279652)
		(end 219.645484 -255.279652)
		(width 0.15494)
		(layer "In13.Cu")
		(net "SMB_PEX2_SDA")
	)
	(segment
		(start 319.19164 -263.16305)
		(end 330.226162 -263.16305)
		(width 0.15494)
		(layer "In13.Cu")
		(net "SMB_PEX2_SDA")
	)
	(segment
		(start 297.135804 -262.495284)
		(end 299.215302 -264.574782)
		(width 0.15494)
		(layer "In13.Cu")
		(net "SMB_PEX2_SDA")
	)
	(segment
		(start 230.065326 -256.40538)
		(end 230.392732 -256.732786)
		(width 0.15494)
		(layer "In13.Cu")
		(net "SMB_PEX2_SDA")
	)
	(segment
		(start 333.027528 -264.574782)
		(end 333.330296 -264.87755)
		(width 0.15494)
		(layer "In13.Cu")
		(net "SMB_PEX2_SDA")
	)
	(segment
		(start 274.96262 -269.494)
		(end 281.961336 -262.495284)
		(width 0.15494)
		(layer "In13.Cu")
		(net "SMB_PEX2_SDA")
	)
	(segment
		(start 281.961336 -262.495284)
		(end 297.135804 -262.495284)
		(width 0.15494)
		(layer "In13.Cu")
		(net "SMB_PEX2_SDA")
	)
	(segment
		(start 230.392732 -256.732786)
		(end 244.250972 -256.732786)
		(width 0.15494)
		(layer "In13.Cu")
		(net "SMB_PEX2_SDA")
	)
	(segment
		(start 220.771212 -256.40538)
		(end 230.065326 -256.40538)
		(width 0.15494)
		(layer "In13.Cu")
		(net "SMB_PEX2_SDA")
	)
	(segment
		(start 216.087706 -255.74498)
		(end 216.087706 -255.376934)
		(width 0.15494)
		(layer "In13.Cu")
		(net "SMB_PEX2_SDA")
	)
	(segment
		(start 330.226162 -263.16305)
		(end 331.637894 -264.574782)
		(width 0.15494)
		(layer "In13.Cu")
		(net "SMB_PEX2_SDA")
	)
	(segment
		(start 333.330296 -264.87755)
		(end 334.163924 -264.87755)
		(width 0.15494)
		(layer "In13.Cu")
		(net "SMB_PEX2_SDA")
	)
	(segment
		(start 216.087706 -255.376934)
		(end 216.184988 -255.279652)
		(width 0.15494)
		(layer "In13.Cu")
		(net "SMB_PEX2_SDA")
	)
	(segment
		(start 252.39599 -264.877804)
		(end 265.584432 -264.877804)
		(width 0.15494)
		(layer "In13.Cu")
		(net "SMB_PEX2_SDA")
	)
	(segment
		(start 265.584432 -264.877804)
		(end 270.200628 -269.494)
		(width 0.15494)
		(layer "In13.Cu")
		(net "SMB_PEX2_SDA")
	)
	(segment
		(start 299.215302 -264.574782)
		(end 317.779908 -264.574782)
		(width 0.15494)
		(layer "In13.Cu")
		(net "SMB_PEX2_SDA")
	)
	(segment
		(start 216.074244 -255.758442)
		(end 216.087706 -255.74498)
		(width 0.15494)
		(layer "In13.Cu")
		(net "SMB_PEX2_SDA")
	)
	(segment
		(start 219.645484 -255.279652)
		(end 220.771212 -256.40538)
		(width 0.15494)
		(layer "In13.Cu")
		(net "SMB_PEX2_SDA")
	)
	(segment
		(start 331.637894 -264.574782)
		(end 333.027528 -264.574782)
		(width 0.15494)
		(layer "In13.Cu")
		(net "SMB_PEX2_SDA")
	)
	(segment
		(start 244.250972 -256.732786)
		(end 252.39599 -264.877804)
		(width 0.15494)
		(layer "In13.Cu")
		(net "SMB_PEX2_SDA")
	)
	(segment
		(start 136.977628 -178.99888)
		(end 138.304524 -180.325776)
		(width 0.13462)
		(layer "F.Cu")
		(net "CLK_100M_DB2000QL_NIC5_DP")
	)
	(segment
		(start 135.569706 -178.99888)
		(end 136.977628 -178.99888)
		(width 0.13462)
		(layer "F.Cu")
		(net "CLK_100M_DB2000QL_NIC5_DP")
	)
	(segment
		(start 139.309602 -180.325776)
		(end 139.674092 -179.961286)
		(width 0.13462)
		(layer "F.Cu")
		(net "CLK_100M_DB2000QL_NIC5_DP")
	)
	(segment
		(start 135.471154 -178.900328)
		(end 135.569706 -178.99888)
		(width 0.13462)
		(layer "F.Cu")
		(net "CLK_100M_DB2000QL_NIC5_DP")
	)
	(segment
		(start 138.304524 -180.325776)
		(end 139.309602 -180.325776)
		(width 0.13462)
		(layer "F.Cu")
		(net "CLK_100M_DB2000QL_NIC5_DP")
	)
	(segment
		(start 140.07719 -255.688592)
		(end 140.07719 -254.850646)
		(width 0.13208)
		(layer "F.Cu")
		(net "LED_PEX1_SYS_ERR_N")
	)
	(segment
		(start 140.892784 -256.748788)
		(end 140.82776 -256.748788)
		(width 0.13208)
		(layer "F.Cu")
		(net "LED_PEX1_SYS_ERR_N")
	)
	(segment
		(start 140.82776 -256.748788)
		(end 140.07719 -255.998218)
		(width 0.13208)
		(layer "F.Cu")
		(net "LED_PEX1_SYS_ERR_N")
	)
	(segment
		(start 140.07719 -255.998218)
		(end 140.07719 -255.688592)
		(width 0.13208)
		(layer "F.Cu")
		(net "LED_PEX1_SYS_ERR_N")
	)
	(via
		(at 140.07719 -255.688592)
		(size 0.508)
		(drill 0.254)
		(layers "F.Cu" "B.Cu")
		(net "LED_PEX1_SYS_ERR_N")
	)
	(segment
		(start 401.112482 -141.964918)
		(end 401.4724 -141.605)
		(width 0.13208)
		(layer "F.Cu")
		(net "SMB_NIC6_LS_SDA")
	)
	(segment
		(start 401.4724 -141.605)
		(end 403.44979 -141.605)
		(width 0.13208)
		(layer "F.Cu")
		(net "SMB_NIC6_LS_SDA")
	)
	(segment
		(start 400.287236 -141.964918)
		(end 398.94256 -141.964918)
		(width 0.13208)
		(layer "F.Cu")
		(net "SMB_NIC6_LS_SDA")
	)
	(segment
		(start 400.287236 -141.964918)
		(end 401.112482 -141.964918)
		(width 0.13208)
		(layer "F.Cu")
		(net "SMB_NIC6_LS_SDA")
	)
	(segment
		(start 403.44979 -141.605)
		(end 403.77999 -141.9352)
		(width 0.13208)
		(layer "F.Cu")
		(net "SMB_NIC6_LS_SDA")
	)
	(via
		(at 400.577558 -160.454848)
		(size 0.508)
		(drill 0.254)
		(layers "F.Cu" "B.Cu")
		(net "SMB_NIC6_LS_SDA")
	)
	(via
		(at 400.287236 -141.964918)
		(size 0.508)
		(drill 0.254)
		(layers "F.Cu" "B.Cu")
		(net "SMB_NIC6_LS_SDA")
	)
	(via
		(at 213.267544 -169.299382)
		(size 0.508)
		(drill 0.254)
		(layers "F.Cu" "B.Cu")
		(net "SMB_NIC6_LS_SDA")
	)
	(via
		(at 215.773 -198.501)
		(size 0.508)
		(drill 0.254)
		(layers "F.Cu" "B.Cu")
		(net "SMB_NIC6_LS_SDA")
	)
	(segment
		(start 215.773 -198.501)
		(end 214.64905 -198.501)
		(width 0.13208)
		(layer "B.Cu")
		(net "SMB_NIC6_LS_SDA")
	)
	(segment
		(start 214.64905 -198.501)
		(end 214.503 -198.35495)
		(width 0.13208)
		(layer "B.Cu")
		(net "SMB_NIC6_LS_SDA")
	)
	(segment
		(start 214.503 -198.35495)
		(end 213.106 -198.35495)
		(width 0.13208)
		(layer "B.Cu")
		(net "SMB_NIC6_LS_SDA")
	)
	(segment
		(start 215.9254 -198.501)
		(end 216.281 -198.1454)
		(width 0.15494)
		(layer "In7.Cu")
		(net "SMB_NIC6_LS_SDA")
	)
	(segment
		(start 213.82355 -183.57215)
		(end 213.4108 -183.1594)
		(width 0.15494)
		(layer "In7.Cu")
		(net "SMB_NIC6_LS_SDA")
	)
	(segment
		(start 214.1728 -189.972188)
		(end 214.1728 -186.84494)
		(width 0.15494)
		(layer "In7.Cu")
		(net "SMB_NIC6_LS_SDA")
	)
	(segment
		(start 213.82355 -186.483244)
		(end 213.82355 -183.57215)
		(width 0.15494)
		(layer "In7.Cu")
		(net "SMB_NIC6_LS_SDA")
	)
	(segment
		(start 213.4108 -169.442638)
		(end 213.267544 -169.299382)
		(width 0.15494)
		(layer "In7.Cu")
		(net "SMB_NIC6_LS_SDA")
	)
	(segment
		(start 216.281 -198.1454)
		(end 216.281 -195.86956)
		(width 0.15494)
		(layer "In7.Cu")
		(net "SMB_NIC6_LS_SDA")
	)
	(segment
		(start 214.817198 -190.616586)
		(end 214.1728 -189.972188)
		(width 0.15494)
		(layer "In7.Cu")
		(net "SMB_NIC6_LS_SDA")
	)
	(segment
		(start 214.1728 -186.84494)
		(end 213.943692 -186.615832)
		(width 0.15494)
		(layer "In7.Cu")
		(net "SMB_NIC6_LS_SDA")
	)
	(segment
		(start 213.943692 -186.615832)
		(end 213.943692 -186.603386)
		(width 0.15494)
		(layer "In7.Cu")
		(net "SMB_NIC6_LS_SDA")
	)
	(segment
		(start 216.281 -195.86956)
		(end 214.817198 -194.405758)
		(width 0.15494)
		(layer "In7.Cu")
		(net "SMB_NIC6_LS_SDA")
	)
	(segment
		(start 213.4108 -183.1594)
		(end 213.4108 -169.442638)
		(width 0.15494)
		(layer "In7.Cu")
		(net "SMB_NIC6_LS_SDA")
	)
	(segment
		(start 213.943692 -186.603386)
		(end 213.82355 -186.483244)
		(width 0.15494)
		(layer "In7.Cu")
		(net "SMB_NIC6_LS_SDA")
	)
	(segment
		(start 215.773 -198.501)
		(end 215.9254 -198.501)
		(width 0.15494)
		(layer "In7.Cu")
		(net "SMB_NIC6_LS_SDA")
	)
	(segment
		(start 214.817198 -194.405758)
		(end 214.817198 -190.616586)
		(width 0.15494)
		(layer "In7.Cu")
		(net "SMB_NIC6_LS_SDA")
	)
	(segment
		(start 403.321012 -144.586452)
		(end 400.699478 -141.964918)
		(width 0.15494)
		(layer "In9.Cu")
		(net "SMB_NIC6_LS_SDA")
	)
	(segment
		(start 400.577558 -160.454848)
		(end 403.321012 -157.711394)
		(width 0.15494)
		(layer "In9.Cu")
		(net "SMB_NIC6_LS_SDA")
	)
	(segment
		(start 403.321012 -157.711394)
		(end 403.321012 -144.586452)
		(width 0.15494)
		(layer "In9.Cu")
		(net "SMB_NIC6_LS_SDA")
	)
	(segment
		(start 400.699478 -141.964918)
		(end 400.287236 -141.964918)
		(width 0.15494)
		(layer "In9.Cu")
		(net "SMB_NIC6_LS_SDA")
	)
	(segment
		(start 294.1574 -163.0172)
		(end 282.807664 -163.0172)
		(width 0.15494)
		(layer "In15.Cu")
		(net "SMB_NIC6_LS_SDA")
	)
	(segment
		(start 237.909608 -165.38194)
		(end 215.20785 -165.38194)
		(width 0.15494)
		(layer "In15.Cu")
		(net "SMB_NIC6_LS_SDA")
	)
	(segment
		(start 328.701908 -163.275264)
		(end 294.415464 -163.275264)
		(width 0.15494)
		(layer "In15.Cu")
		(net "SMB_NIC6_LS_SDA")
	)
	(segment
		(start 357.247698 -165.106604)
		(end 351.62744 -165.106604)
		(width 0.15494)
		(layer "In15.Cu")
		(net "SMB_NIC6_LS_SDA")
	)
	(segment
		(start 254.869696 -167.635682)
		(end 240.16335 -167.635682)
		(width 0.15494)
		(layer "In15.Cu")
		(net "SMB_NIC6_LS_SDA")
	)
	(segment
		(start 282.5496 -163.275264)
		(end 280.970482 -163.275264)
		(width 0.15494)
		(layer "In15.Cu")
		(net "SMB_NIC6_LS_SDA")
	)
	(segment
		(start 387.406388 -162.59302)
		(end 372.710964 -162.59302)
		(width 0.15494)
		(layer "In15.Cu")
		(net "SMB_NIC6_LS_SDA")
	)
	(segment
		(start 213.267544 -168.748456)
		(end 213.267544 -169.299382)
		(width 0.15494)
		(layer "In15.Cu")
		(net "SMB_NIC6_LS_SDA")
	)
	(segment
		(start 215.20785 -165.38194)
		(end 213.35238 -167.23741)
		(width 0.15494)
		(layer "In15.Cu")
		(net "SMB_NIC6_LS_SDA")
	)
	(segment
		(start 280.970482 -163.275264)
		(end 278.363934 -165.881812)
		(width 0.15494)
		(layer "In15.Cu")
		(net "SMB_NIC6_LS_SDA")
	)
	(segment
		(start 369.911122 -165.392862)
		(end 357.533956 -165.392862)
		(width 0.15494)
		(layer "In15.Cu")
		(net "SMB_NIC6_LS_SDA")
	)
	(segment
		(start 397.486632 -158.6738)
		(end 391.325608 -158.6738)
		(width 0.15494)
		(layer "In15.Cu")
		(net "SMB_NIC6_LS_SDA")
	)
	(segment
		(start 213.35238 -167.23741)
		(end 213.35238 -168.66362)
		(width 0.15494)
		(layer "In15.Cu")
		(net "SMB_NIC6_LS_SDA")
	)
	(segment
		(start 372.710964 -162.59302)
		(end 369.911122 -165.392862)
		(width 0.15494)
		(layer "In15.Cu")
		(net "SMB_NIC6_LS_SDA")
	)
	(segment
		(start 400.577558 -160.454848)
		(end 400.561048 -160.471358)
		(width 0.15494)
		(layer "In15.Cu")
		(net "SMB_NIC6_LS_SDA")
	)
	(segment
		(start 357.533956 -165.392862)
		(end 357.247698 -165.106604)
		(width 0.15494)
		(layer "In15.Cu")
		(net "SMB_NIC6_LS_SDA")
	)
	(segment
		(start 399.28419 -160.471358)
		(end 397.486632 -158.6738)
		(width 0.15494)
		(layer "In15.Cu")
		(net "SMB_NIC6_LS_SDA")
	)
	(segment
		(start 337.303618 -160.204912)
		(end 337.25866 -160.24987)
		(width 0.15494)
		(layer "In15.Cu")
		(net "SMB_NIC6_LS_SDA")
	)
	(segment
		(start 294.415464 -163.275264)
		(end 294.1574 -163.0172)
		(width 0.15494)
		(layer "In15.Cu")
		(net "SMB_NIC6_LS_SDA")
	)
	(segment
		(start 278.363934 -165.881812)
		(end 256.623566 -165.881812)
		(width 0.15494)
		(layer "In15.Cu")
		(net "SMB_NIC6_LS_SDA")
	)
	(segment
		(start 240.16335 -167.635682)
		(end 237.909608 -165.38194)
		(width 0.15494)
		(layer "In15.Cu")
		(net "SMB_NIC6_LS_SDA")
	)
	(segment
		(start 256.623566 -165.881812)
		(end 254.869696 -167.635682)
		(width 0.15494)
		(layer "In15.Cu")
		(net "SMB_NIC6_LS_SDA")
	)
	(segment
		(start 351.62744 -165.106604)
		(end 346.725748 -160.204912)
		(width 0.15494)
		(layer "In15.Cu")
		(net "SMB_NIC6_LS_SDA")
	)
	(segment
		(start 337.25866 -160.24987)
		(end 331.727302 -160.24987)
		(width 0.15494)
		(layer "In15.Cu")
		(net "SMB_NIC6_LS_SDA")
	)
	(segment
		(start 400.561048 -160.471358)
		(end 399.28419 -160.471358)
		(width 0.15494)
		(layer "In15.Cu")
		(net "SMB_NIC6_LS_SDA")
	)
	(segment
		(start 213.35238 -168.66362)
		(end 213.267544 -168.748456)
		(width 0.15494)
		(layer "In15.Cu")
		(net "SMB_NIC6_LS_SDA")
	)
	(segment
		(start 331.727302 -160.24987)
		(end 328.701908 -163.275264)
		(width 0.15494)
		(layer "In15.Cu")
		(net "SMB_NIC6_LS_SDA")
	)
	(segment
		(start 282.807664 -163.0172)
		(end 282.5496 -163.275264)
		(width 0.15494)
		(layer "In15.Cu")
		(net "SMB_NIC6_LS_SDA")
	)
	(segment
		(start 391.325608 -158.6738)
		(end 387.406388 -162.59302)
		(width 0.15494)
		(layer "In15.Cu")
		(net "SMB_NIC6_LS_SDA")
	)
	(segment
		(start 346.725748 -160.204912)
		(end 337.303618 -160.204912)
		(width 0.15494)
		(layer "In15.Cu")
		(net "SMB_NIC6_LS_SDA")
	)
	(segment
		(start 408.096212 -387.942836)
		(end 408.774392 -387.942836)
		(width 0.13208)
		(layer "F.Cu")
		(net "GPU_WP_HW_CTRL_R_N")
	)
	(via
		(at 408.774392 -387.942836)
		(size 0.508)
		(drill 0.254)
		(layers "F.Cu" "B.Cu")
		(net "GPU_WP_HW_CTRL_R_N")
	)
	(segment
		(start 411.825948 -391.01649)
		(end 408.624532 -391.01649)
		(width 0.15494)
		(layer "In9.Cu")
		(net "GPU_WP_HW_CTRL_R_N")
	)
	(segment
		(start 416.951668 -396.14221)
		(end 411.825948 -391.01649)
		(width 0.15494)
		(layer "In9.Cu")
		(net "GPU_WP_HW_CTRL_R_N")
	)
	(segment
		(start 436.75554 -413.727138)
		(end 418.806122 -413.727138)
		(width 0.15494)
		(layer "In9.Cu")
		(net "GPU_WP_HW_CTRL_R_N")
	)
	(segment
		(start 438.10555 -412.377128)
		(end 436.75554 -413.727138)
		(width 0.15494)
		(layer "In9.Cu")
		(net "GPU_WP_HW_CTRL_R_N")
	)
	(segment
		(start 407.915872 -390.30783)
		(end 407.915872 -388.801356)
		(width 0.15494)
		(layer "In9.Cu")
		(net "GPU_WP_HW_CTRL_R_N")
	)
	(segment
		(start 437.089804 -404.290022)
		(end 438.10555 -405.305768)
		(width 0.15494)
		(layer "In9.Cu")
		(net "GPU_WP_HW_CTRL_R_N")
	)
	(segment
		(start 408.624532 -391.01649)
		(end 407.915872 -390.30783)
		(width 0.15494)
		(layer "In9.Cu")
		(net "GPU_WP_HW_CTRL_R_N")
	)
	(segment
		(start 416.951668 -411.872684)
		(end 416.951668 -396.14221)
		(width 0.15494)
		(layer "In9.Cu")
		(net "GPU_WP_HW_CTRL_R_N")
	)
	(segment
		(start 438.10555 -405.305768)
		(end 438.10555 -412.377128)
		(width 0.15494)
		(layer "In9.Cu")
		(net "GPU_WP_HW_CTRL_R_N")
	)
	(segment
		(start 418.806122 -413.727138)
		(end 416.951668 -411.872684)
		(width 0.15494)
		(layer "In9.Cu")
		(net "GPU_WP_HW_CTRL_R_N")
	)
	(segment
		(start 407.915872 -388.801356)
		(end 408.774392 -387.942836)
		(width 0.15494)
		(layer "In9.Cu")
		(net "GPU_WP_HW_CTRL_R_N")
	)
	(segment
		(start 208.5975 -284.50921)
		(end 209.635344 -284.50921)
		(width 0.13208)
		(layer "F.Cu")
		(net "SMB_PEX1_SCL")
	)
	(segment
		(start 209.349848 -233.325924)
		(end 209.349848 -233.146092)
		(width 0.13208)
		(layer "F.Cu")
		(net "SMB_PEX1_SCL")
	)
	(segment
		(start 209.754724 -284.048454)
		(end 210.275424 -283.527754)
		(width 0.13208)
		(layer "F.Cu")
		(net "SMB_PEX1_SCL")
	)
	(segment
		(start 208.47812 -284.62859)
		(end 208.5975 -284.50921)
		(width 0.13208)
		(layer "F.Cu")
		(net "SMB_PEX1_SCL")
	)
	(segment
		(start 210.275424 -301.559722)
		(end 210.275424 -286.419798)
		(width 0.13208)
		(layer "F.Cu")
		(net "SMB_PEX1_SCL")
	)
	(segment
		(start 209.754724 -284.38983)
		(end 209.754724 -284.048454)
		(width 0.13208)
		(layer "F.Cu")
		(net "SMB_PEX1_SCL")
	)
	(segment
		(start 208.5975 -285.13659)
		(end 208.47812 -285.01721)
		(width 0.13208)
		(layer "F.Cu")
		(net "SMB_PEX1_SCL")
	)
	(segment
		(start 210.275424 -286.419798)
		(end 209.754724 -285.899098)
		(width 0.13208)
		(layer "F.Cu")
		(net "SMB_PEX1_SCL")
	)
	(segment
		(start 208.47812 -285.01721)
		(end 208.47812 -284.62859)
		(width 0.13208)
		(layer "F.Cu")
		(net "SMB_PEX1_SCL")
	)
	(segment
		(start 209.505296 -233.481372)
		(end 209.349848 -233.325924)
		(width 0.13208)
		(layer "F.Cu")
		(net "SMB_PEX1_SCL")
	)
	(segment
		(start 209.785204 -302.049942)
		(end 210.275424 -301.559722)
		(width 0.13208)
		(layer "F.Cu")
		(net "SMB_PEX1_SCL")
	)
	(segment
		(start 209.754724 -285.25597)
		(end 209.635344 -285.13659)
		(width 0.13208)
		(layer "F.Cu")
		(net "SMB_PEX1_SCL")
	)
	(segment
		(start 202.774296 -302.761396)
		(end 203.48575 -302.049942)
		(width 0.13208)
		(layer "F.Cu")
		(net "SMB_PEX1_SCL")
	)
	(segment
		(start 209.349848 -233.146092)
		(end 209.635344 -232.860596)
		(width 0.13208)
		(layer "F.Cu")
		(net "SMB_PEX1_SCL")
	)
	(segment
		(start 202.774296 -303.538636)
		(end 202.774296 -302.761396)
		(width 0.13208)
		(layer "F.Cu")
		(net "SMB_PEX1_SCL")
	)
	(segment
		(start 209.635344 -284.50921)
		(end 209.754724 -284.38983)
		(width 0.13208)
		(layer "F.Cu")
		(net "SMB_PEX1_SCL")
	)
	(segment
		(start 203.48575 -302.049942)
		(end 209.785204 -302.049942)
		(width 0.13208)
		(layer "F.Cu")
		(net "SMB_PEX1_SCL")
	)
	(segment
		(start 209.754724 -285.899098)
		(end 209.754724 -285.25597)
		(width 0.13208)
		(layer "F.Cu")
		(net "SMB_PEX1_SCL")
	)
	(segment
		(start 209.635344 -285.13659)
		(end 208.5975 -285.13659)
		(width 0.13208)
		(layer "F.Cu")
		(net "SMB_PEX1_SCL")
	)
	(segment
		(start 210.161886 -233.481372)
		(end 209.505296 -233.481372)
		(width 0.13208)
		(layer "F.Cu")
		(net "SMB_PEX1_SCL")
	)
	(via
		(at 209.635344 -232.860596)
		(size 0.508)
		(drill 0.254)
		(layers "F.Cu" "B.Cu")
		(net "SMB_PEX1_SCL")
	)
	(via
		(at 210.275424 -283.527754)
		(size 0.508)
		(drill 0.254)
		(layers "F.Cu" "B.Cu")
		(net "SMB_PEX1_SCL")
	)
	(segment
		(start 209.237834 -232.860596)
		(end 209.635344 -232.860596)
		(width 0.13208)
		(layer "B.Cu")
		(net "SMB_PEX1_SCL")
	)
	(segment
		(start 207.900778 -233.686604)
		(end 208.411826 -233.686604)
		(width 0.13208)
		(layer "B.Cu")
		(net "SMB_PEX1_SCL")
	)
	(segment
		(start 208.411826 -233.686604)
		(end 209.237834 -232.860596)
		(width 0.13208)
		(layer "B.Cu")
		(net "SMB_PEX1_SCL")
	)
	(segment
		(start 213.40064 -241.401854)
		(end 214.139272 -242.140486)
		(width 0.15494)
		(layer "In5.Cu")
		(net "SMB_PEX1_SCL")
	)
	(segment
		(start 210.879944 -236.817154)
		(end 210.879944 -237.967774)
		(width 0.15494)
		(layer "In5.Cu")
		(net "SMB_PEX1_SCL")
	)
	(segment
		(start 211.483448 -283.741368)
		(end 211.145628 -284.079188)
		(width 0.15494)
		(layer "In5.Cu")
		(net "SMB_PEX1_SCL")
	)
	(segment
		(start 211.464398 -239.520476)
		(end 212.268308 -239.520476)
		(width 0.15494)
		(layer "In5.Cu")
		(net "SMB_PEX1_SCL")
	)
	(segment
		(start 210.46059 -284.079188)
		(end 210.275424 -283.894022)
		(width 0.15494)
		(layer "In5.Cu")
		(net "SMB_PEX1_SCL")
	)
	(segment
		(start 209.635344 -232.860596)
		(end 209.635344 -235.572554)
		(width 0.15494)
		(layer "In5.Cu")
		(net "SMB_PEX1_SCL")
	)
	(segment
		(start 211.483448 -282.95473)
		(end 211.483448 -283.741368)
		(width 0.15494)
		(layer "In5.Cu")
		(net "SMB_PEX1_SCL")
	)
	(segment
		(start 217.68562 -278.388826)
		(end 214.032846 -282.0416)
		(width 0.15494)
		(layer "In5.Cu")
		(net "SMB_PEX1_SCL")
	)
	(segment
		(start 214.139272 -242.140486)
		(end 214.139272 -254.67056)
		(width 0.15494)
		(layer "In5.Cu")
		(net "SMB_PEX1_SCL")
	)
	(segment
		(start 211.145628 -284.079188)
		(end 210.46059 -284.079188)
		(width 0.15494)
		(layer "In5.Cu")
		(net "SMB_PEX1_SCL")
	)
	(segment
		(start 209.635344 -235.572554)
		(end 210.879944 -236.817154)
		(width 0.15494)
		(layer "In5.Cu")
		(net "SMB_PEX1_SCL")
	)
	(segment
		(start 214.139272 -254.67056)
		(end 215.334342 -255.86563)
		(width 0.15494)
		(layer "In5.Cu")
		(net "SMB_PEX1_SCL")
	)
	(segment
		(start 210.275424 -283.894022)
		(end 210.275424 -283.527754)
		(width 0.15494)
		(layer "In5.Cu")
		(net "SMB_PEX1_SCL")
	)
	(segment
		(start 215.334342 -255.86563)
		(end 215.334342 -257.409696)
		(width 0.15494)
		(layer "In5.Cu")
		(net "SMB_PEX1_SCL")
	)
	(segment
		(start 213.40064 -240.652808)
		(end 213.40064 -241.401854)
		(width 0.15494)
		(layer "In5.Cu")
		(net "SMB_PEX1_SCL")
	)
	(segment
		(start 210.879944 -237.967774)
		(end 211.213446 -238.301276)
		(width 0.15494)
		(layer "In5.Cu")
		(net "SMB_PEX1_SCL")
	)
	(segment
		(start 214.658194 -259.112004)
		(end 217.68562 -266.420854)
		(width 0.15494)
		(layer "In5.Cu")
		(net "SMB_PEX1_SCL")
	)
	(segment
		(start 211.213446 -239.269524)
		(end 211.464398 -239.520476)
		(width 0.15494)
		(layer "In5.Cu")
		(net "SMB_PEX1_SCL")
	)
	(segment
		(start 214.032846 -282.0416)
		(end 212.396578 -282.0416)
		(width 0.15494)
		(layer "In5.Cu")
		(net "SMB_PEX1_SCL")
	)
	(segment
		(start 212.268308 -239.520476)
		(end 213.40064 -240.652808)
		(width 0.15494)
		(layer "In5.Cu")
		(net "SMB_PEX1_SCL")
	)
	(segment
		(start 215.334342 -257.409696)
		(end 214.658194 -258.085844)
		(width 0.15494)
		(layer "In5.Cu")
		(net "SMB_PEX1_SCL")
	)
	(segment
		(start 217.68562 -266.420854)
		(end 217.68562 -278.388826)
		(width 0.15494)
		(layer "In5.Cu")
		(net "SMB_PEX1_SCL")
	)
	(segment
		(start 212.396578 -282.0416)
		(end 211.483448 -282.95473)
		(width 0.15494)
		(layer "In5.Cu")
		(net "SMB_PEX1_SCL")
	)
	(segment
		(start 214.658194 -258.085844)
		(end 214.658194 -259.112004)
		(width 0.15494)
		(layer "In5.Cu")
		(net "SMB_PEX1_SCL")
	)
	(segment
		(start 211.213446 -238.301276)
		(end 211.213446 -239.269524)
		(width 0.15494)
		(layer "In5.Cu")
		(net "SMB_PEX1_SCL")
	)
	(segment
		(start 346.093796 -222.38716)
		(end 346.493592 -222.786956)
		(width 0.13208)
		(layer "F.Cu")
		(net "NIC3_AUX_PWR_EN")
	)
	(via
		(at 245.831868 -219.659454)
		(size 0.508)
		(drill 0.254)
		(layers "F.Cu" "B.Cu")
		(net "NIC3_AUX_PWR_EN")
	)
	(via
		(at 346.493592 -222.786956)
		(size 0.4572)
		(drill 0.254)
		(layers "F.Cu" "B.Cu")
		(net "NIC3_AUX_PWR_EN")
	)
	(via
		(at 186.29122 -118.711218)
		(size 0.508)
		(drill 0.254)
		(layers "F.Cu" "B.Cu")
		(net "NIC3_AUX_PWR_EN")
	)
	(via
		(at 246.39016 -214.097362)
		(size 0.508)
		(drill 0.254)
		(layers "F.Cu" "B.Cu")
		(net "NIC3_AUX_PWR_EN")
	)
	(via
		(at 207.137 -209.296)
		(size 0.508)
		(drill 0.254)
		(layers "F.Cu" "B.Cu")
		(net "NIC3_AUX_PWR_EN")
	)
	(segment
		(start 186.990482 -118.711218)
		(end 186.29122 -118.711218)
		(width 0.13208)
		(layer "B.Cu")
		(net "NIC3_AUX_PWR_EN")
	)
	(segment
		(start 186.986164 -118.7069)
		(end 186.990482 -118.711218)
		(width 0.13208)
		(layer "B.Cu")
		(net "NIC3_AUX_PWR_EN")
	)
	(segment
		(start 186.986164 -117.66169)
		(end 186.986164 -118.7069)
		(width 0.13208)
		(layer "B.Cu")
		(net "NIC3_AUX_PWR_EN")
	)
	(segment
		(start 190.988188 -118.8212)
		(end 186.401202 -118.8212)
		(width 0.15494)
		(layer "In5.Cu")
		(net "NIC3_AUX_PWR_EN")
	)
	(segment
		(start 207.618838 -184.971944)
		(end 207.2894 -184.642506)
		(width 0.15494)
		(layer "In5.Cu")
		(net "NIC3_AUX_PWR_EN")
	)
	(segment
		(start 203.570586 -131.403598)
		(end 202.297284 -130.130296)
		(width 0.15494)
		(layer "In5.Cu")
		(net "NIC3_AUX_PWR_EN")
	)
	(segment
		(start 207.067658 -191.480186)
		(end 207.305656 -191.242188)
		(width 0.15494)
		(layer "In5.Cu")
		(net "NIC3_AUX_PWR_EN")
	)
	(segment
		(start 245.831868 -219.659454)
		(end 245.779036 -219.606622)
		(width 0.15494)
		(layer "In5.Cu")
		(net "NIC3_AUX_PWR_EN")
	)
	(segment
		(start 245.779036 -219.606622)
		(end 245.779036 -214.708486)
		(width 0.15494)
		(layer "In5.Cu")
		(net "NIC3_AUX_PWR_EN")
	)
	(segment
		(start 245.779036 -214.708486)
		(end 246.39016 -214.097362)
		(width 0.15494)
		(layer "In5.Cu")
		(net "NIC3_AUX_PWR_EN")
	)
	(segment
		(start 202.252834 -130.071876)
		(end 202.197716 -130.030728)
		(width 0.15494)
		(layer "In5.Cu")
		(net "NIC3_AUX_PWR_EN")
	)
	(segment
		(start 207.14716 -209.28584)
		(end 207.14716 -193.34734)
		(width 0.15494)
		(layer "In5.Cu")
		(net "NIC3_AUX_PWR_EN")
	)
	(segment
		(start 207.2894 -136.45388)
		(end 203.570586 -132.735066)
		(width 0.15494)
		(layer "In5.Cu")
		(net "NIC3_AUX_PWR_EN")
	)
	(segment
		(start 207.618838 -186.361578)
		(end 207.618838 -184.971944)
		(width 0.15494)
		(layer "In5.Cu")
		(net "NIC3_AUX_PWR_EN")
	)
	(segment
		(start 202.297284 -130.130296)
		(end 202.252834 -130.071876)
		(width 0.15494)
		(layer "In5.Cu")
		(net "NIC3_AUX_PWR_EN")
	)
	(segment
		(start 207.305656 -191.242188)
		(end 207.305656 -186.67476)
		(width 0.15494)
		(layer "In5.Cu")
		(net "NIC3_AUX_PWR_EN")
	)
	(segment
		(start 207.137 -209.296)
		(end 207.14716 -209.28584)
		(width 0.15494)
		(layer "In5.Cu")
		(net "NIC3_AUX_PWR_EN")
	)
	(segment
		(start 207.14716 -193.34734)
		(end 207.049116 -193.249296)
		(width 0.15494)
		(layer "In5.Cu")
		(net "NIC3_AUX_PWR_EN")
	)
	(segment
		(start 186.401202 -118.8212)
		(end 186.29122 -118.711218)
		(width 0.15494)
		(layer "In5.Cu")
		(net "NIC3_AUX_PWR_EN")
	)
	(segment
		(start 207.049116 -193.249296)
		(end 207.067658 -191.480186)
		(width 0.15494)
		(layer "In5.Cu")
		(net "NIC3_AUX_PWR_EN")
	)
	(segment
		(start 207.305656 -186.67476)
		(end 207.618838 -186.361578)
		(width 0.15494)
		(layer "In5.Cu")
		(net "NIC3_AUX_PWR_EN")
	)
	(segment
		(start 207.2894 -184.642506)
		(end 207.2894 -136.45388)
		(width 0.15494)
		(layer "In5.Cu")
		(net "NIC3_AUX_PWR_EN")
	)
	(segment
		(start 203.570586 -132.735066)
		(end 203.570586 -131.403598)
		(width 0.15494)
		(layer "In5.Cu")
		(net "NIC3_AUX_PWR_EN")
	)
	(segment
		(start 202.197716 -130.030728)
		(end 190.988188 -118.8212)
		(width 0.15494)
		(layer "In5.Cu")
		(net "NIC3_AUX_PWR_EN")
	)
	(segment
		(start 235.958126 -208.27238)
		(end 236.049566 -208.36382)
		(width 0.15494)
		(layer "In13.Cu")
		(net "NIC3_AUX_PWR_EN")
	)
	(segment
		(start 245.62689 -212.51037)
		(end 245.62689 -213.334092)
		(width 0.15494)
		(layer "In13.Cu")
		(net "NIC3_AUX_PWR_EN")
	)
	(segment
		(start 232.473246 -208.27238)
		(end 235.958126 -208.27238)
		(width 0.15494)
		(layer "In13.Cu")
		(net "NIC3_AUX_PWR_EN")
	)
	(segment
		(start 220.422978 -208.48574)
		(end 222.630746 -207.57134)
		(width 0.15494)
		(layer "In13.Cu")
		(net "NIC3_AUX_PWR_EN")
	)
	(segment
		(start 240.391442 -209.1436)
		(end 240.608612 -208.92643)
		(width 0.15494)
		(layer "In13.Cu")
		(net "NIC3_AUX_PWR_EN")
	)
	(segment
		(start 208.02346 -210.18246)
		(end 217.29954 -210.18246)
		(width 0.15494)
		(layer "In13.Cu")
		(net "NIC3_AUX_PWR_EN")
	)
	(segment
		(start 230.779828 -207.57134)
		(end 232.473246 -208.27238)
		(width 0.15494)
		(layer "In13.Cu")
		(net "NIC3_AUX_PWR_EN")
	)
	(segment
		(start 240.608612 -208.92643)
		(end 243.55425 -208.92643)
		(width 0.15494)
		(layer "In13.Cu")
		(net "NIC3_AUX_PWR_EN")
	)
	(segment
		(start 243.55425 -208.92643)
		(end 244.327172 -209.699352)
		(width 0.15494)
		(layer "In13.Cu")
		(net "NIC3_AUX_PWR_EN")
	)
	(segment
		(start 207.137 -209.296)
		(end 208.02346 -210.18246)
		(width 0.15494)
		(layer "In13.Cu")
		(net "NIC3_AUX_PWR_EN")
	)
	(segment
		(start 217.29954 -210.18246)
		(end 218.99626 -208.48574)
		(width 0.15494)
		(layer "In13.Cu")
		(net "NIC3_AUX_PWR_EN")
	)
	(segment
		(start 236.049566 -208.36382)
		(end 238.413544 -208.36382)
		(width 0.15494)
		(layer "In13.Cu")
		(net "NIC3_AUX_PWR_EN")
	)
	(segment
		(start 218.99626 -208.48574)
		(end 220.422978 -208.48574)
		(width 0.15494)
		(layer "In13.Cu")
		(net "NIC3_AUX_PWR_EN")
	)
	(segment
		(start 222.630746 -207.57134)
		(end 230.779828 -207.57134)
		(width 0.15494)
		(layer "In13.Cu")
		(net "NIC3_AUX_PWR_EN")
	)
	(segment
		(start 245.62689 -213.334092)
		(end 246.39016 -214.097362)
		(width 0.15494)
		(layer "In13.Cu")
		(net "NIC3_AUX_PWR_EN")
	)
	(segment
		(start 244.327172 -211.210652)
		(end 245.62689 -212.51037)
		(width 0.15494)
		(layer "In13.Cu")
		(net "NIC3_AUX_PWR_EN")
	)
	(segment
		(start 244.327172 -209.699352)
		(end 244.327172 -211.210652)
		(width 0.15494)
		(layer "In13.Cu")
		(net "NIC3_AUX_PWR_EN")
	)
	(segment
		(start 239.193324 -209.1436)
		(end 240.391442 -209.1436)
		(width 0.15494)
		(layer "In13.Cu")
		(net "NIC3_AUX_PWR_EN")
	)
	(segment
		(start 238.413544 -208.36382)
		(end 239.193324 -209.1436)
		(width 0.15494)
		(layer "In13.Cu")
		(net "NIC3_AUX_PWR_EN")
	)
	(segment
		(start 326.34047 -218.821)
		(end 325.17207 -217.6526)
		(width 0.15494)
		(layer "In15.Cu")
		(net "NIC3_AUX_PWR_EN")
	)
	(segment
		(start 256.9083 -217.5637)
		(end 255.651 -216.3064)
		(width 0.15494)
		(layer "In15.Cu")
		(net "NIC3_AUX_PWR_EN")
	)
	(segment
		(start 264.22731 -218.481656)
		(end 263.291828 -218.481656)
		(width 0.15494)
		(layer "In15.Cu")
		(net "NIC3_AUX_PWR_EN")
	)
	(segment
		(start 263.291828 -218.481656)
		(end 263.171432 -218.602052)
		(width 0.15494)
		(layer "In15.Cu")
		(net "NIC3_AUX_PWR_EN")
	)
	(segment
		(start 334.1116 -220.789246)
		(end 334.015334 -220.69298)
		(width 0.15494)
		(layer "In15.Cu")
		(net "NIC3_AUX_PWR_EN")
	)
	(segment
		(start 334.015334 -220.69298)
		(end 332.654402 -220.69298)
		(width 0.15494)
		(layer "In15.Cu")
		(net "NIC3_AUX_PWR_EN")
	)
	(segment
		(start 255.651 -216.3064)
		(end 254.838454 -216.3064)
		(width 0.15494)
		(layer "In15.Cu")
		(net "NIC3_AUX_PWR_EN")
	)
	(segment
		(start 289.1282 -218.3892)
		(end 288.28619 -219.23121)
		(width 0.15494)
		(layer "In15.Cu")
		(net "NIC3_AUX_PWR_EN")
	)
	(segment
		(start 345.296236 -221.059502)
		(end 345.02598 -220.789246)
		(width 0.0889)
		(layer "In15.Cu")
		(net "NIC3_AUX_PWR_EN")
	)
	(segment
		(start 345.02598 -220.789246)
		(end 334.1116 -220.789246)
		(width 0.0889)
		(layer "In15.Cu")
		(net "NIC3_AUX_PWR_EN")
	)
	(segment
		(start 254.838454 -216.3064)
		(end 253.883922 -217.260932)
		(width 0.15494)
		(layer "In15.Cu")
		(net "NIC3_AUX_PWR_EN")
	)
	(segment
		(start 345.561666 -222.38462)
		(end 345.296236 -222.11919)
		(width 0.0889)
		(layer "In15.Cu")
		(net "NIC3_AUX_PWR_EN")
	)
	(segment
		(start 305.724814 -217.027252)
		(end 304.362866 -218.3892)
		(width 0.15494)
		(layer "In15.Cu")
		(net "NIC3_AUX_PWR_EN")
	)
	(segment
		(start 263.171432 -218.602052)
		(end 260.976618 -218.602052)
		(width 0.15494)
		(layer "In15.Cu")
		(net "NIC3_AUX_PWR_EN")
	)
	(segment
		(start 346.493592 -222.786956)
		(end 346.091256 -222.38462)
		(width 0.0889)
		(layer "In15.Cu")
		(net "NIC3_AUX_PWR_EN")
	)
	(segment
		(start 259.938266 -217.5637)
		(end 256.9083 -217.5637)
		(width 0.15494)
		(layer "In15.Cu")
		(net "NIC3_AUX_PWR_EN")
	)
	(segment
		(start 323.520308 -217.027252)
		(end 305.724814 -217.027252)
		(width 0.15494)
		(layer "In15.Cu")
		(net "NIC3_AUX_PWR_EN")
	)
	(segment
		(start 264.976864 -219.23121)
		(end 264.22731 -218.481656)
		(width 0.15494)
		(layer "In15.Cu")
		(net "NIC3_AUX_PWR_EN")
	)
	(segment
		(start 253.883922 -217.260932)
		(end 250.783598 -217.260932)
		(width 0.15494)
		(layer "In15.Cu")
		(net "NIC3_AUX_PWR_EN")
	)
	(segment
		(start 304.362866 -218.3892)
		(end 289.1282 -218.3892)
		(width 0.15494)
		(layer "In15.Cu")
		(net "NIC3_AUX_PWR_EN")
	)
	(segment
		(start 250.783598 -217.260932)
		(end 249.60453 -218.44)
		(width 0.15494)
		(layer "In15.Cu")
		(net "NIC3_AUX_PWR_EN")
	)
	(segment
		(start 346.091256 -222.38462)
		(end 345.561666 -222.38462)
		(width 0.0889)
		(layer "In15.Cu")
		(net "NIC3_AUX_PWR_EN")
	)
	(segment
		(start 331.812392 -219.85097)
		(end 330.071476 -219.85097)
		(width 0.15494)
		(layer "In15.Cu")
		(net "NIC3_AUX_PWR_EN")
	)
	(segment
		(start 345.296236 -222.11919)
		(end 345.296236 -221.059502)
		(width 0.0889)
		(layer "In15.Cu")
		(net "NIC3_AUX_PWR_EN")
	)
	(segment
		(start 260.976618 -218.602052)
		(end 259.938266 -217.5637)
		(width 0.15494)
		(layer "In15.Cu")
		(net "NIC3_AUX_PWR_EN")
	)
	(segment
		(start 247.051322 -218.44)
		(end 245.831868 -219.659454)
		(width 0.15494)
		(layer "In15.Cu")
		(net "NIC3_AUX_PWR_EN")
	)
	(segment
		(start 330.071476 -219.85097)
		(end 329.041506 -218.821)
		(width 0.15494)
		(layer "In15.Cu")
		(net "NIC3_AUX_PWR_EN")
	)
	(segment
		(start 324.145656 -217.6526)
		(end 323.520308 -217.027252)
		(width 0.15494)
		(layer "In15.Cu")
		(net "NIC3_AUX_PWR_EN")
	)
	(segment
		(start 288.28619 -219.23121)
		(end 264.976864 -219.23121)
		(width 0.15494)
		(layer "In15.Cu")
		(net "NIC3_AUX_PWR_EN")
	)
	(segment
		(start 329.041506 -218.821)
		(end 326.34047 -218.821)
		(width 0.15494)
		(layer "In15.Cu")
		(net "NIC3_AUX_PWR_EN")
	)
	(segment
		(start 249.60453 -218.44)
		(end 247.051322 -218.44)
		(width 0.15494)
		(layer "In15.Cu")
		(net "NIC3_AUX_PWR_EN")
	)
	(segment
		(start 325.17207 -217.6526)
		(end 324.145656 -217.6526)
		(width 0.15494)
		(layer "In15.Cu")
		(net "NIC3_AUX_PWR_EN")
	)
	(segment
		(start 332.654402 -220.69298)
		(end 331.812392 -219.85097)
		(width 0.15494)
		(layer "In15.Cu")
		(net "NIC3_AUX_PWR_EN")
	)
	(segment
		(start 236.433614 -90.766392)
		(end 236.714792 -90.766392)
		(width 0.13208)
		(layer "F.Cu")
		(net "PEX_USB_HUB_RREF")
	)
	(segment
		(start 237.777274 -89.70391)
		(end 238.032036 -89.598246)
		(width 0.13208)
		(layer "F.Cu")
		(net "PEX_USB_HUB_RREF")
	)
	(segment
		(start 238.032036 -89.598246)
		(end 238.404908 -89.225374)
		(width 0.13208)
		(layer "F.Cu")
		(net "PEX_USB_HUB_RREF")
	)
	(segment
		(start 236.714792 -90.766392)
		(end 237.268512 -90.212672)
		(width 0.13208)
		(layer "F.Cu")
		(net "PEX_USB_HUB_RREF")
	)
	(segment
		(start 237.268512 -90.212672)
		(end 237.777274 -89.70391)
		(width 0.13208)
		(layer "F.Cu")
		(net "PEX_USB_HUB_RREF")
	)
	(via
		(at 237.268512 -90.212672)
		(size 0.508)
		(drill 0.254)
		(layers "F.Cu" "B.Cu")
		(net "PEX_USB_HUB_RREF")
	)
	(segment
		(start 175.858424 -194.211956)
		(end 175.230028 -193.58356)
		(width 0.13208)
		(layer "F.Cu")
		(net "SPI_BIC1_MOSI_LS01_DIR3")
	)
	(segment
		(start 175.230028 -193.58356)
		(end 174.535084 -193.58356)
		(width 0.13208)
		(layer "F.Cu")
		(net "SPI_BIC1_MOSI_LS01_DIR3")
	)
	(via
		(at 175.858424 -194.211956)
		(size 0.508)
		(drill 0.254)
		(layers "F.Cu" "B.Cu")
		(net "SPI_BIC1_MOSI_LS01_DIR3")
	)
	(segment
		(start 176.275746 -193.794634)
		(end 175.858424 -194.211956)
		(width 0.13208)
		(layer "B.Cu")
		(net "SPI_BIC1_MOSI_LS01_DIR3")
	)
	(segment
		(start 177.023776 -194.683634)
		(end 177.023776 -193.794634)
		(width 0.13208)
		(layer "B.Cu")
		(net "SPI_BIC1_MOSI_LS01_DIR3")
	)
	(segment
		(start 177.023776 -193.794634)
		(end 176.275746 -193.794634)
		(width 0.13208)
		(layer "B.Cu")
		(net "SPI_BIC1_MOSI_LS01_DIR3")
	)
	(segment
		(start 136.15797 -180.2892)
		(end 138.500866 -182.632096)
		(width 0.13462)
		(layer "F.Cu")
		(net "CLK_100M_DB2000QL_NIC6_DN")
	)
	(segment
		(start 138.500866 -182.632096)
		(end 139.296902 -182.632096)
		(width 0.13462)
		(layer "F.Cu")
		(net "CLK_100M_DB2000QL_NIC6_DN")
	)
	(segment
		(start 139.296902 -182.632096)
		(end 139.674092 -183.009286)
		(width 0.13462)
		(layer "F.Cu")
		(net "CLK_100M_DB2000QL_NIC6_DN")
	)
	(segment
		(start 135.582406 -180.2892)
		(end 136.15797 -180.2892)
		(width 0.13462)
		(layer "F.Cu")
		(net "CLK_100M_DB2000QL_NIC6_DN")
	)
	(segment
		(start 135.471154 -180.400452)
		(end 135.582406 -180.2892)
		(width 0.13462)
		(layer "F.Cu")
		(net "CLK_100M_DB2000QL_NIC6_DN")
	)
	(segment
		(start 139.12723 -254.850646)
		(end 138.59256 -254.850646)
		(width 0.13208)
		(layer "F.Cu")
		(net "PEX1_SYS_ERR_3V3_N")
	)
	(segment
		(start 138.358626 -255.910588)
		(end 138.358626 -256.22504)
		(width 0.13208)
		(layer "F.Cu")
		(net "PEX1_SYS_ERR_3V3_N")
	)
	(segment
		(start 138.59256 -254.850646)
		(end 138.358626 -255.08458)
		(width 0.13208)
		(layer "F.Cu")
		(net "PEX1_SYS_ERR_3V3_N")
	)
	(segment
		(start 138.231626 -256.35204)
		(end 137.608564 -256.35204)
		(width 0.13208)
		(layer "F.Cu")
		(net "PEX1_SYS_ERR_3V3_N")
	)
	(segment
		(start 138.358626 -255.08458)
		(end 138.358626 -255.910588)
		(width 0.13208)
		(layer "F.Cu")
		(net "PEX1_SYS_ERR_3V3_N")
	)
	(segment
		(start 138.358626 -256.22504)
		(end 138.231626 -256.35204)
		(width 0.13208)
		(layer "F.Cu")
		(net "PEX1_SYS_ERR_3V3_N")
	)
	(via
		(at 138.358626 -255.910588)
		(size 0.508)
		(drill 0.254)
		(layers "F.Cu" "B.Cu")
		(net "PEX1_SYS_ERR_3V3_N")
	)
	(segment
		(start 203.909676 -302.538892)
		(end 203.217272 -303.231296)
		(width 0.13208)
		(layer "F.Cu")
		(net "SMB_PEX1_SDA")
	)
	(segment
		(start 209.56905 -231.5464)
		(end 209.573622 -231.550972)
		(width 0.13208)
		(layer "F.Cu")
		(net "SMB_PEX1_SDA")
	)
	(segment
		(start 207.742536 -232.51795)
		(end 208.714086 -231.5464)
		(width 0.13208)
		(layer "F.Cu")
		(net "SMB_PEX1_SDA")
	)
	(segment
		(start 209.573622 -231.550972)
		(end 210.542886 -231.550972)
		(width 0.13208)
		(layer "F.Cu")
		(net "SMB_PEX1_SDA")
	)
	(segment
		(start 203.217272 -303.231296)
		(end 203.217272 -305.464972)
		(width 0.13208)
		(layer "F.Cu")
		(net "SMB_PEX1_SDA")
	)
	(segment
		(start 203.217272 -305.464972)
		(end 203.00442 -305.677824)
		(width 0.13208)
		(layer "F.Cu")
		(net "SMB_PEX1_SDA")
	)
	(segment
		(start 210.910424 -301.655734)
		(end 210.027266 -302.538892)
		(width 0.13208)
		(layer "F.Cu")
		(net "SMB_PEX1_SDA")
	)
	(segment
		(start 208.714086 -231.5464)
		(end 209.56905 -231.5464)
		(width 0.13208)
		(layer "F.Cu")
		(net "SMB_PEX1_SDA")
	)
	(segment
		(start 210.910424 -283.527754)
		(end 210.910424 -301.655734)
		(width 0.13208)
		(layer "F.Cu")
		(net "SMB_PEX1_SDA")
	)
	(segment
		(start 210.027266 -302.538892)
		(end 203.909676 -302.538892)
		(width 0.13208)
		(layer "F.Cu")
		(net "SMB_PEX1_SDA")
	)
	(via
		(at 210.910424 -283.527754)
		(size 0.508)
		(drill 0.254)
		(layers "F.Cu" "B.Cu")
		(net "SMB_PEX1_SDA")
	)
	(via
		(at 207.742536 -232.51795)
		(size 0.508)
		(drill 0.254)
		(layers "F.Cu" "B.Cu")
		(net "SMB_PEX1_SDA")
	)
	(segment
		(start 207.742536 -232.51795)
		(end 207.671416 -232.58907)
		(width 0.13208)
		(layer "B.Cu")
		(net "SMB_PEX1_SDA")
	)
	(segment
		(start 207.671416 -232.58907)
		(end 206.512668 -232.58907)
		(width 0.13208)
		(layer "B.Cu")
		(net "SMB_PEX1_SDA")
	)
	(segment
		(start 210.910424 -282.80741)
		(end 212.235034 -281.4828)
		(width 0.15494)
		(layer "In5.Cu")
		(net "SMB_PEX1_SDA")
	)
	(segment
		(start 209.507582 -239.98301)
		(end 208.755234 -239.230662)
		(width 0.15494)
		(layer "In5.Cu")
		(net "SMB_PEX1_SDA")
	)
	(segment
		(start 214.874602 -257.219196)
		(end 214.874602 -256.060194)
		(width 0.15494)
		(layer "In5.Cu")
		(net "SMB_PEX1_SDA")
	)
	(segment
		(start 217.22588 -266.512548)
		(end 214.198454 -259.203698)
		(width 0.15494)
		(layer "In5.Cu")
		(net "SMB_PEX1_SDA")
	)
	(segment
		(start 214.198454 -257.895344)
		(end 214.874602 -257.219196)
		(width 0.15494)
		(layer "In5.Cu")
		(net "SMB_PEX1_SDA")
	)
	(segment
		(start 210.910424 -283.527754)
		(end 210.910424 -282.80741)
		(width 0.15494)
		(layer "In5.Cu")
		(net "SMB_PEX1_SDA")
	)
	(segment
		(start 217.22588 -278.198072)
		(end 217.22588 -266.512548)
		(width 0.15494)
		(layer "In5.Cu")
		(net "SMB_PEX1_SDA")
	)
	(segment
		(start 213.676738 -242.332256)
		(end 212.938106 -241.593624)
		(width 0.15494)
		(layer "In5.Cu")
		(net "SMB_PEX1_SDA")
	)
	(segment
		(start 207.90281 -237.087156)
		(end 207.90281 -232.678224)
		(width 0.15494)
		(layer "In5.Cu")
		(net "SMB_PEX1_SDA")
	)
	(segment
		(start 212.938106 -241.593624)
		(end 212.938106 -240.844578)
		(width 0.15494)
		(layer "In5.Cu")
		(net "SMB_PEX1_SDA")
	)
	(segment
		(start 212.938106 -240.844578)
		(end 212.076538 -239.98301)
		(width 0.15494)
		(layer "In5.Cu")
		(net "SMB_PEX1_SDA")
	)
	(segment
		(start 213.941152 -281.4828)
		(end 217.22588 -278.198072)
		(width 0.15494)
		(layer "In5.Cu")
		(net "SMB_PEX1_SDA")
	)
	(segment
		(start 212.076538 -239.98301)
		(end 209.507582 -239.98301)
		(width 0.15494)
		(layer "In5.Cu")
		(net "SMB_PEX1_SDA")
	)
	(segment
		(start 213.676738 -254.86233)
		(end 213.676738 -242.332256)
		(width 0.15494)
		(layer "In5.Cu")
		(net "SMB_PEX1_SDA")
	)
	(segment
		(start 214.874602 -256.060194)
		(end 213.676738 -254.86233)
		(width 0.15494)
		(layer "In5.Cu")
		(net "SMB_PEX1_SDA")
	)
	(segment
		(start 212.235034 -281.4828)
		(end 213.941152 -281.4828)
		(width 0.15494)
		(layer "In5.Cu")
		(net "SMB_PEX1_SDA")
	)
	(segment
		(start 208.755234 -239.230662)
		(end 208.755234 -237.93958)
		(width 0.15494)
		(layer "In5.Cu")
		(net "SMB_PEX1_SDA")
	)
	(segment
		(start 207.90281 -232.678224)
		(end 207.742536 -232.51795)
		(width 0.15494)
		(layer "In5.Cu")
		(net "SMB_PEX1_SDA")
	)
	(segment
		(start 208.755234 -237.93958)
		(end 207.90281 -237.087156)
		(width 0.15494)
		(layer "In5.Cu")
		(net "SMB_PEX1_SDA")
	)
	(segment
		(start 214.198454 -259.203698)
		(end 214.198454 -257.895344)
		(width 0.15494)
		(layer "In5.Cu")
		(net "SMB_PEX1_SDA")
	)
	(segment
		(start 346.893896 -219.187014)
		(end 347.293692 -218.787218)
		(width 0.13208)
		(layer "F.Cu")
		(net "NIC5_CLK_EN_N")
	)
	(segment
		(start 357.61295 -220.472)
		(end 356.997 -220.472)
		(width 0.13208)
		(layer "F.Cu")
		(net "NIC5_CLK_EN_N")
	)
	(via
		(at 356.997 -220.472)
		(size 0.508)
		(drill 0.254)
		(layers "F.Cu" "B.Cu")
		(net "NIC5_CLK_EN_N")
	)
	(via
		(at 347.293692 -218.787218)
		(size 0.4572)
		(drill 0.254)
		(layers "F.Cu" "B.Cu")
		(net "NIC5_CLK_EN_N")
	)
	(segment
		(start 355.335586 -220.472)
		(end 354.740464 -219.876878)
		(width 0.15494)
		(layer "In9.Cu")
		(net "NIC5_CLK_EN_N")
	)
	(segment
		(start 356.997 -220.472)
		(end 355.335586 -220.472)
		(width 0.15494)
		(layer "In9.Cu")
		(net "NIC5_CLK_EN_N")
	)
	(segment
		(start 354.740464 -219.876878)
		(end 347.985842 -219.876878)
		(width 0.15494)
		(layer "In9.Cu")
		(net "NIC5_CLK_EN_N")
	)
	(segment
		(start 347.985842 -219.876878)
		(end 347.293692 -219.184728)
		(width 0.15494)
		(layer "In9.Cu")
		(net "NIC5_CLK_EN_N")
	)
	(segment
		(start 347.293692 -219.184728)
		(end 347.293692 -218.787218)
		(width 0.15494)
		(layer "In9.Cu")
		(net "NIC5_CLK_EN_N")
	)
	(segment
		(start 136.271762 -180.01488)
		(end 138.614658 -182.357776)
		(width 0.13462)
		(layer "F.Cu")
		(net "CLK_100M_DB2000QL_NIC6_DP")
	)
	(segment
		(start 135.471154 -179.900326)
		(end 135.585708 -180.01488)
		(width 0.13462)
		(layer "F.Cu")
		(net "CLK_100M_DB2000QL_NIC6_DP")
	)
	(segment
		(start 139.309602 -182.357776)
		(end 139.674092 -181.993286)
		(width 0.13462)
		(layer "F.Cu")
		(net "CLK_100M_DB2000QL_NIC6_DP")
	)
	(segment
		(start 135.585708 -180.01488)
		(end 136.271762 -180.01488)
		(width 0.13462)
		(layer "F.Cu")
		(net "CLK_100M_DB2000QL_NIC6_DP")
	)
	(segment
		(start 138.614658 -182.357776)
		(end 139.309602 -182.357776)
		(width 0.13462)
		(layer "F.Cu")
		(net "CLK_100M_DB2000QL_NIC6_DP")
	)
	(segment
		(start 139.854686 -257.852164)
		(end 139.97559 -257.73126)
		(width 0.13208)
		(layer "F.Cu")
		(net "PEX1_SYS_ERR_N_G")
	)
	(segment
		(start 139.97559 -257.22326)
		(end 139.854432 -257.102102)
		(width 0.13208)
		(layer "F.Cu")
		(net "PEX1_SYS_ERR_N_G")
	)
	(segment
		(start 139.97559 -257.73126)
		(end 139.97559 -257.22326)
		(width 0.13208)
		(layer "F.Cu")
		(net "PEX1_SYS_ERR_N_G")
	)
	(segment
		(start 139.408408 -259.295392)
		(end 139.324842 -259.378958)
		(width 0.13208)
		(layer "F.Cu")
		(net "PEX1_SYS_ERR_N_G")
	)
	(segment
		(start 139.408408 -257.852164)
		(end 139.408408 -258.649978)
		(width 0.13208)
		(layer "F.Cu")
		(net "PEX1_SYS_ERR_N_G")
	)
	(segment
		(start 139.408408 -257.852164)
		(end 139.854686 -257.852164)
		(width 0.13208)
		(layer "F.Cu")
		(net "PEX1_SYS_ERR_N_G")
	)
	(segment
		(start 139.324842 -259.378958)
		(end 139.228576 -259.475224)
		(width 0.13208)
		(layer "F.Cu")
		(net "PEX1_SYS_ERR_N_G")
	)
	(segment
		(start 139.408408 -258.649978)
		(end 139.408408 -259.295392)
		(width 0.13208)
		(layer "F.Cu")
		(net "PEX1_SYS_ERR_N_G")
	)
	(segment
		(start 139.228576 -259.475224)
		(end 139.228576 -260.407658)
		(width 0.13208)
		(layer "F.Cu")
		(net "PEX1_SYS_ERR_N_G")
	)
	(segment
		(start 139.854432 -257.102102)
		(end 139.408408 -257.102102)
		(width 0.13208)
		(layer "F.Cu")
		(net "PEX1_SYS_ERR_N_G")
	)
	(via
		(at 139.408408 -258.649978)
		(size 0.508)
		(drill 0.254)
		(layers "F.Cu" "B.Cu")
		(net "PEX1_SYS_ERR_N_G")
	)
	(segment
		(start 400.988784 -142.60068)
		(end 400.287236 -142.60068)
		(width 0.13208)
		(layer "F.Cu")
		(net "SMB_NIC6_LS_SCL")
	)
	(segment
		(start 399.980404 -142.60068)
		(end 400.287236 -142.60068)
		(width 0.13208)
		(layer "F.Cu")
		(net "SMB_NIC6_LS_SCL")
	)
	(segment
		(start 403.77999 -142.9512)
		(end 401.339304 -142.9512)
		(width 0.13208)
		(layer "F.Cu")
		(net "SMB_NIC6_LS_SCL")
	)
	(segment
		(start 398.94256 -142.56512)
		(end 399.894552 -142.56512)
		(width 0.13208)
		(layer "F.Cu")
		(net "SMB_NIC6_LS_SCL")
	)
	(segment
		(start 401.339304 -142.9512)
		(end 400.988784 -142.60068)
		(width 0.13208)
		(layer "F.Cu")
		(net "SMB_NIC6_LS_SCL")
	)
	(segment
		(start 399.894552 -142.56512)
		(end 399.980404 -142.60068)
		(width 0.13208)
		(layer "F.Cu")
		(net "SMB_NIC6_LS_SCL")
	)
	(via
		(at 400.287236 -142.60068)
		(size 0.508)
		(drill 0.254)
		(layers "F.Cu" "B.Cu")
		(net "SMB_NIC6_LS_SCL")
	)
	(via
		(at 400.379438 -159.4104)
		(size 0.508)
		(drill 0.254)
		(layers "F.Cu" "B.Cu")
		(net "SMB_NIC6_LS_SCL")
	)
	(via
		(at 212.667088 -168.63314)
		(size 0.508)
		(drill 0.254)
		(layers "F.Cu" "B.Cu")
		(net "SMB_NIC6_LS_SCL")
	)
	(via
		(at 215.773 -197.231)
		(size 0.508)
		(drill 0.254)
		(layers "F.Cu" "B.Cu")
		(net "SMB_NIC6_LS_SCL")
	)
	(segment
		(start 213.46795 -197.739)
		(end 213.106 -197.37705)
		(width 0.13208)
		(layer "B.Cu")
		(net "SMB_NIC6_LS_SCL")
	)
	(segment
		(start 215.773 -197.231)
		(end 215.011 -197.231)
		(width 0.13208)
		(layer "B.Cu")
		(net "SMB_NIC6_LS_SCL")
	)
	(segment
		(start 214.503 -197.739)
		(end 213.46795 -197.739)
		(width 0.13208)
		(layer "B.Cu")
		(net "SMB_NIC6_LS_SCL")
	)
	(segment
		(start 215.011 -197.231)
		(end 214.503 -197.739)
		(width 0.13208)
		(layer "B.Cu")
		(net "SMB_NIC6_LS_SCL")
	)
	(segment
		(start 212.304122 -170.216576)
		(end 211.987892 -169.900346)
		(width 0.15494)
		(layer "In7.Cu")
		(net "SMB_NIC6_LS_SCL")
	)
	(segment
		(start 215.773 -197.231)
		(end 215.773 -196.0118)
		(width 0.15494)
		(layer "In7.Cu")
		(net "SMB_NIC6_LS_SCL")
	)
	(segment
		(start 214.357458 -194.596258)
		(end 214.357458 -190.807086)
		(width 0.15494)
		(layer "In7.Cu")
		(net "SMB_NIC6_LS_SCL")
	)
	(segment
		(start 212.9028 -183.3118)
		(end 212.9028 -179.972462)
		(width 0.15494)
		(layer "In7.Cu")
		(net "SMB_NIC6_LS_SCL")
	)
	(segment
		(start 214.357458 -190.807086)
		(end 213.614 -190.063628)
		(width 0.15494)
		(layer "In7.Cu")
		(net "SMB_NIC6_LS_SCL")
	)
	(segment
		(start 211.987892 -169.312336)
		(end 212.667088 -168.63314)
		(width 0.15494)
		(layer "In7.Cu")
		(net "SMB_NIC6_LS_SCL")
	)
	(segment
		(start 212.304122 -179.373784)
		(end 212.304122 -170.216576)
		(width 0.15494)
		(layer "In7.Cu")
		(net "SMB_NIC6_LS_SCL")
	)
	(segment
		(start 211.987892 -169.900346)
		(end 211.987892 -169.312336)
		(width 0.15494)
		(layer "In7.Cu")
		(net "SMB_NIC6_LS_SCL")
	)
	(segment
		(start 213.483952 -186.793886)
		(end 213.358984 -186.668918)
		(width 0.15494)
		(layer "In7.Cu")
		(net "SMB_NIC6_LS_SCL")
	)
	(segment
		(start 213.358984 -186.668918)
		(end 213.358984 -183.767984)
		(width 0.15494)
		(layer "In7.Cu")
		(net "SMB_NIC6_LS_SCL")
	)
	(segment
		(start 213.614 -190.063628)
		(end 213.614 -186.93638)
		(width 0.15494)
		(layer "In7.Cu")
		(net "SMB_NIC6_LS_SCL")
	)
	(segment
		(start 213.614 -186.93638)
		(end 213.483952 -186.806332)
		(width 0.15494)
		(layer "In7.Cu")
		(net "SMB_NIC6_LS_SCL")
	)
	(segment
		(start 213.358984 -183.767984)
		(end 212.9028 -183.3118)
		(width 0.15494)
		(layer "In7.Cu")
		(net "SMB_NIC6_LS_SCL")
	)
	(segment
		(start 212.9028 -179.972462)
		(end 212.304122 -179.373784)
		(width 0.15494)
		(layer "In7.Cu")
		(net "SMB_NIC6_LS_SCL")
	)
	(segment
		(start 213.483952 -186.806332)
		(end 213.483952 -186.793886)
		(width 0.15494)
		(layer "In7.Cu")
		(net "SMB_NIC6_LS_SCL")
	)
	(segment
		(start 215.773 -196.0118)
		(end 214.357458 -194.596258)
		(width 0.15494)
		(layer "In7.Cu")
		(net "SMB_NIC6_LS_SCL")
	)
	(segment
		(start 402.783802 -144.731994)
		(end 402.783802 -157.565344)
		(width 0.15494)
		(layer "In9.Cu")
		(net "SMB_NIC6_LS_SCL")
	)
	(segment
		(start 400.287236 -142.60068)
		(end 400.652488 -142.60068)
		(width 0.15494)
		(layer "In9.Cu")
		(net "SMB_NIC6_LS_SCL")
	)
	(segment
		(start 402.783802 -157.565344)
		(end 400.938746 -159.4104)
		(width 0.15494)
		(layer "In9.Cu")
		(net "SMB_NIC6_LS_SCL")
	)
	(segment
		(start 400.652488 -142.60068)
		(end 402.783802 -144.731994)
		(width 0.15494)
		(layer "In9.Cu")
		(net "SMB_NIC6_LS_SCL")
	)
	(segment
		(start 400.938746 -159.4104)
		(end 400.379438 -159.4104)
		(width 0.15494)
		(layer "In9.Cu")
		(net "SMB_NIC6_LS_SCL")
	)
	(segment
		(start 340.752684 -158.198312)
		(end 341.525606 -158.198312)
		(width 0.15494)
		(layer "In15.Cu")
		(net "SMB_NIC6_LS_SCL")
	)
	(segment
		(start 357.671624 -164.646864)
		(end 357.957882 -164.933122)
		(width 0.15494)
		(layer "In15.Cu")
		(net "SMB_NIC6_LS_SCL")
	)
	(segment
		(start 399.183098 -158.21406)
		(end 400.379438 -159.4104)
		(width 0.15494)
		(layer "In15.Cu")
		(net "SMB_NIC6_LS_SCL")
	)
	(segment
		(start 391.135108 -158.21406)
		(end 399.183098 -158.21406)
		(width 0.15494)
		(layer "In15.Cu")
		(net "SMB_NIC6_LS_SCL")
	)
	(segment
		(start 240.105946 -166.928038)
		(end 254.9271 -166.928038)
		(width 0.15494)
		(layer "In15.Cu")
		(net "SMB_NIC6_LS_SCL")
	)
	(segment
		(start 345.46667 -157.944566)
		(end 352.168968 -164.646864)
		(width 0.15494)
		(layer "In15.Cu")
		(net "SMB_NIC6_LS_SCL")
	)
	(segment
		(start 256.433066 -165.422072)
		(end 278.173434 -165.422072)
		(width 0.15494)
		(layer "In15.Cu")
		(net "SMB_NIC6_LS_SCL")
	)
	(segment
		(start 372.847616 -161.78276)
		(end 387.566408 -161.78276)
		(width 0.15494)
		(layer "In15.Cu")
		(net "SMB_NIC6_LS_SCL")
	)
	(segment
		(start 369.697254 -164.933122)
		(end 372.847616 -161.78276)
		(width 0.15494)
		(layer "In15.Cu")
		(net "SMB_NIC6_LS_SCL")
	)
	(segment
		(start 294.6908 -162.815524)
		(end 327.550272 -162.815524)
		(width 0.15494)
		(layer "In15.Cu")
		(net "SMB_NIC6_LS_SCL")
	)
	(segment
		(start 282.217876 -162.815524)
		(end 282.4988 -162.5346)
		(width 0.15494)
		(layer "In15.Cu")
		(net "SMB_NIC6_LS_SCL")
	)
	(segment
		(start 238.103156 -164.925248)
		(end 240.105946 -166.928038)
		(width 0.15494)
		(layer "In15.Cu")
		(net "SMB_NIC6_LS_SCL")
	)
	(segment
		(start 212.667088 -167.198802)
		(end 214.94369 -164.9222)
		(width 0.15494)
		(layer "In15.Cu")
		(net "SMB_NIC6_LS_SCL")
	)
	(segment
		(start 238.088678 -164.9222)
		(end 238.091726 -164.925248)
		(width 0.15494)
		(layer "In15.Cu")
		(net "SMB_NIC6_LS_SCL")
	)
	(segment
		(start 357.957882 -164.933122)
		(end 369.697254 -164.933122)
		(width 0.15494)
		(layer "In15.Cu")
		(net "SMB_NIC6_LS_SCL")
	)
	(segment
		(start 212.667088 -168.63314)
		(end 212.667088 -167.198802)
		(width 0.15494)
		(layer "In15.Cu")
		(net "SMB_NIC6_LS_SCL")
	)
	(segment
		(start 387.566408 -161.78276)
		(end 391.135108 -158.21406)
		(width 0.15494)
		(layer "In15.Cu")
		(net "SMB_NIC6_LS_SCL")
	)
	(segment
		(start 294.409876 -162.5346)
		(end 294.6908 -162.815524)
		(width 0.15494)
		(layer "In15.Cu")
		(net "SMB_NIC6_LS_SCL")
	)
	(segment
		(start 339.668866 -159.28213)
		(end 340.752684 -158.198312)
		(width 0.15494)
		(layer "In15.Cu")
		(net "SMB_NIC6_LS_SCL")
	)
	(segment
		(start 254.9271 -166.928038)
		(end 256.433066 -165.422072)
		(width 0.15494)
		(layer "In15.Cu")
		(net "SMB_NIC6_LS_SCL")
	)
	(segment
		(start 280.779982 -162.815524)
		(end 282.217876 -162.815524)
		(width 0.15494)
		(layer "In15.Cu")
		(net "SMB_NIC6_LS_SCL")
	)
	(segment
		(start 327.550272 -162.815524)
		(end 331.083666 -159.28213)
		(width 0.15494)
		(layer "In15.Cu")
		(net "SMB_NIC6_LS_SCL")
	)
	(segment
		(start 341.525606 -158.198312)
		(end 341.779352 -157.944566)
		(width 0.15494)
		(layer "In15.Cu")
		(net "SMB_NIC6_LS_SCL")
	)
	(segment
		(start 278.173434 -165.422072)
		(end 280.779982 -162.815524)
		(width 0.15494)
		(layer "In15.Cu")
		(net "SMB_NIC6_LS_SCL")
	)
	(segment
		(start 331.083666 -159.28213)
		(end 339.668866 -159.28213)
		(width 0.15494)
		(layer "In15.Cu")
		(net "SMB_NIC6_LS_SCL")
	)
	(segment
		(start 238.091726 -164.925248)
		(end 238.103156 -164.925248)
		(width 0.15494)
		(layer "In15.Cu")
		(net "SMB_NIC6_LS_SCL")
	)
	(segment
		(start 352.168968 -164.646864)
		(end 357.671624 -164.646864)
		(width 0.15494)
		(layer "In15.Cu")
		(net "SMB_NIC6_LS_SCL")
	)
	(segment
		(start 341.779352 -157.944566)
		(end 345.46667 -157.944566)
		(width 0.15494)
		(layer "In15.Cu")
		(net "SMB_NIC6_LS_SCL")
	)
	(segment
		(start 214.94369 -164.9222)
		(end 238.088678 -164.9222)
		(width 0.15494)
		(layer "In15.Cu")
		(net "SMB_NIC6_LS_SCL")
	)
	(segment
		(start 282.4988 -162.5346)
		(end 294.409876 -162.5346)
		(width 0.15494)
		(layer "In15.Cu")
		(net "SMB_NIC6_LS_SCL")
	)
	(segment
		(start 346.093796 -221.58706)
		(end 346.493592 -221.986856)
		(width 0.13208)
		(layer "F.Cu")
		(net "PWRGD_NIC3_PWR_GOOD_R")
	)
	(via
		(at 346.493592 -221.986856)
		(size 0.4572)
		(drill 0.254)
		(layers "F.Cu" "B.Cu")
		(net "PWRGD_NIC3_PWR_GOOD_R")
	)
	(via
		(at 208.681828 -184.69356)
		(size 0.508)
		(drill 0.254)
		(layers "F.Cu" "B.Cu")
		(net "PWRGD_NIC3_PWR_GOOD_R")
	)
	(via
		(at 185.803794 -96.802702)
		(size 0.508)
		(drill 0.254)
		(layers "F.Cu" "B.Cu")
		(net "PWRGD_NIC3_PWR_GOOD_R")
	)
	(segment
		(start 185.803794 -97.663)
		(end 185.803794 -96.802702)
		(width 0.13208)
		(layer "B.Cu")
		(net "PWRGD_NIC3_PWR_GOOD_R")
	)
	(segment
		(start 188.057536 -102.662736)
		(end 188.057536 -99.056444)
		(width 0.15494)
		(layer "In5.Cu")
		(net "PWRGD_NIC3_PWR_GOOD_R")
	)
	(segment
		(start 204.694536 -130.467608)
		(end 201.88174 -127.654812)
		(width 0.15494)
		(layer "In5.Cu")
		(net "PWRGD_NIC3_PWR_GOOD_R")
	)
	(segment
		(start 201.88174 -119.297704)
		(end 193.999358 -111.415322)
		(width 0.15494)
		(layer "In5.Cu")
		(net "PWRGD_NIC3_PWR_GOOD_R")
	)
	(segment
		(start 201.88174 -127.654812)
		(end 201.88174 -119.297704)
		(width 0.15494)
		(layer "In5.Cu")
		(net "PWRGD_NIC3_PWR_GOOD_R")
	)
	(segment
		(start 190.410338 -105.015538)
		(end 188.057536 -102.662736)
		(width 0.15494)
		(layer "In5.Cu")
		(net "PWRGD_NIC3_PWR_GOOD_R")
	)
	(segment
		(start 208.704942 -182.78221)
		(end 208.704942 -136.459214)
		(width 0.15494)
		(layer "In5.Cu")
		(net "PWRGD_NIC3_PWR_GOOD_R")
	)
	(segment
		(start 204.694536 -132.448808)
		(end 204.694536 -130.467608)
		(width 0.15494)
		(layer "In5.Cu")
		(net "PWRGD_NIC3_PWR_GOOD_R")
	)
	(segment
		(start 193.999358 -111.415322)
		(end 193.999358 -106.734864)
		(width 0.15494)
		(layer "In5.Cu")
		(net "PWRGD_NIC3_PWR_GOOD_R")
	)
	(segment
		(start 208.681828 -184.69356)
		(end 208.681828 -182.805324)
		(width 0.15494)
		(layer "In5.Cu")
		(net "PWRGD_NIC3_PWR_GOOD_R")
	)
	(segment
		(start 208.681828 -182.805324)
		(end 208.704942 -182.78221)
		(width 0.15494)
		(layer "In5.Cu")
		(net "PWRGD_NIC3_PWR_GOOD_R")
	)
	(segment
		(start 193.999358 -106.734864)
		(end 192.280032 -105.015538)
		(width 0.15494)
		(layer "In5.Cu")
		(net "PWRGD_NIC3_PWR_GOOD_R")
	)
	(segment
		(start 188.057536 -99.056444)
		(end 185.803794 -96.802702)
		(width 0.15494)
		(layer "In5.Cu")
		(net "PWRGD_NIC3_PWR_GOOD_R")
	)
	(segment
		(start 192.280032 -105.015538)
		(end 190.410338 -105.015538)
		(width 0.15494)
		(layer "In5.Cu")
		(net "PWRGD_NIC3_PWR_GOOD_R")
	)
	(segment
		(start 208.704942 -136.459214)
		(end 204.694536 -132.448808)
		(width 0.15494)
		(layer "In5.Cu")
		(net "PWRGD_NIC3_PWR_GOOD_R")
	)
	(segment
		(start 355.05644 -212.51799)
		(end 355.05644 -210.866482)
		(width 0.15494)
		(layer "In15.Cu")
		(net "PWRGD_NIC3_PWR_GOOD_R")
	)
	(segment
		(start 354.696268 -203.927202)
		(end 352.001074 -201.232008)
		(width 0.15494)
		(layer "In15.Cu")
		(net "PWRGD_NIC3_PWR_GOOD_R")
	)
	(segment
		(start 339.94217 -194.28079)
		(end 339.104986 -193.443606)
		(width 0.15494)
		(layer "In15.Cu")
		(net "PWRGD_NIC3_PWR_GOOD_R")
	)
	(segment
		(start 354.508308 -213.066122)
		(end 355.05644 -212.51799)
		(width 0.15494)
		(layer "In15.Cu")
		(net "PWRGD_NIC3_PWR_GOOD_R")
	)
	(segment
		(start 341.723472 -195.98132)
		(end 341.370412 -195.98132)
		(width 0.15494)
		(layer "In15.Cu")
		(net "PWRGD_NIC3_PWR_GOOD_R")
	)
	(segment
		(start 346.096082 -221.589346)
		(end 346.096082 -220.222064)
		(width 0.0889)
		(layer "In15.Cu")
		(net "PWRGD_NIC3_PWR_GOOD_R")
	)
	(segment
		(start 346.096082 -220.20784)
		(end 347.042486 -219.261436)
		(width 0.15494)
		(layer "In15.Cu")
		(net "PWRGD_NIC3_PWR_GOOD_R")
	)
	(segment
		(start 353.48164 -218.4908)
		(end 354.508308 -217.464132)
		(width 0.15494)
		(layer "In15.Cu")
		(net "PWRGD_NIC3_PWR_GOOD_R")
	)
	(segment
		(start 354.696268 -210.50631)
		(end 354.696268 -203.927202)
		(width 0.15494)
		(layer "In15.Cu")
		(net "PWRGD_NIC3_PWR_GOOD_R")
	)
	(segment
		(start 351.689924 -219.261436)
		(end 352.46056 -218.4908)
		(width 0.15494)
		(layer "In15.Cu")
		(net "PWRGD_NIC3_PWR_GOOD_R")
	)
	(segment
		(start 251.803408 -190.943738)
		(end 241.12728 -190.943738)
		(width 0.15494)
		(layer "In15.Cu")
		(net "PWRGD_NIC3_PWR_GOOD_R")
	)
	(segment
		(start 347.042486 -219.261436)
		(end 351.689924 -219.261436)
		(width 0.15494)
		(layer "In15.Cu")
		(net "PWRGD_NIC3_PWR_GOOD_R")
	)
	(segment
		(start 346.493592 -221.986856)
		(end 346.096082 -221.589346)
		(width 0.0889)
		(layer "In15.Cu")
		(net "PWRGD_NIC3_PWR_GOOD_R")
	)
	(segment
		(start 236.496098 -186.312556)
		(end 210.300824 -186.312556)
		(width 0.15494)
		(layer "In15.Cu")
		(net "PWRGD_NIC3_PWR_GOOD_R")
	)
	(segment
		(start 324.926198 -189.019434)
		(end 323.6595 -190.286132)
		(width 0.15494)
		(layer "In15.Cu")
		(net "PWRGD_NIC3_PWR_GOOD_R")
	)
	(segment
		(start 354.508308 -217.464132)
		(end 354.508308 -213.066122)
		(width 0.15494)
		(layer "In15.Cu")
		(net "PWRGD_NIC3_PWR_GOOD_R")
	)
	(segment
		(start 339.94217 -194.553078)
		(end 339.94217 -194.28079)
		(width 0.15494)
		(layer "In15.Cu")
		(net "PWRGD_NIC3_PWR_GOOD_R")
	)
	(segment
		(start 352.46056 -218.4908)
		(end 353.48164 -218.4908)
		(width 0.15494)
		(layer "In15.Cu")
		(net "PWRGD_NIC3_PWR_GOOD_R")
	)
	(segment
		(start 272.500344 -188.091572)
		(end 254.655574 -188.091572)
		(width 0.15494)
		(layer "In15.Cu")
		(net "PWRGD_NIC3_PWR_GOOD_R")
	)
	(segment
		(start 346.97416 -201.232008)
		(end 341.723472 -195.98132)
		(width 0.15494)
		(layer "In15.Cu")
		(net "PWRGD_NIC3_PWR_GOOD_R")
	)
	(segment
		(start 210.300824 -186.312556)
		(end 208.681828 -184.69356)
		(width 0.15494)
		(layer "In15.Cu")
		(net "PWRGD_NIC3_PWR_GOOD_R")
	)
	(segment
		(start 241.12728 -190.943738)
		(end 236.496098 -186.312556)
		(width 0.15494)
		(layer "In15.Cu")
		(net "PWRGD_NIC3_PWR_GOOD_R")
	)
	(segment
		(start 339.104986 -193.443606)
		(end 330.389738 -193.443606)
		(width 0.15494)
		(layer "In15.Cu")
		(net "PWRGD_NIC3_PWR_GOOD_R")
	)
	(segment
		(start 355.05644 -210.866482)
		(end 354.696268 -210.50631)
		(width 0.15494)
		(layer "In15.Cu")
		(net "PWRGD_NIC3_PWR_GOOD_R")
	)
	(segment
		(start 274.694904 -190.286132)
		(end 272.500344 -188.091572)
		(width 0.15494)
		(layer "In15.Cu")
		(net "PWRGD_NIC3_PWR_GOOD_R")
	)
	(segment
		(start 341.370412 -195.98132)
		(end 339.94217 -194.553078)
		(width 0.15494)
		(layer "In15.Cu")
		(net "PWRGD_NIC3_PWR_GOOD_R")
	)
	(segment
		(start 346.096082 -220.222064)
		(end 346.096082 -220.20784)
		(width 0.15494)
		(layer "In15.Cu")
		(net "PWRGD_NIC3_PWR_GOOD_R")
	)
	(segment
		(start 254.655574 -188.091572)
		(end 251.803408 -190.943738)
		(width 0.15494)
		(layer "In15.Cu")
		(net "PWRGD_NIC3_PWR_GOOD_R")
	)
	(segment
		(start 352.001074 -201.232008)
		(end 346.97416 -201.232008)
		(width 0.15494)
		(layer "In15.Cu")
		(net "PWRGD_NIC3_PWR_GOOD_R")
	)
	(segment
		(start 330.389738 -193.443606)
		(end 325.965566 -189.019434)
		(width 0.15494)
		(layer "In15.Cu")
		(net "PWRGD_NIC3_PWR_GOOD_R")
	)
	(segment
		(start 323.6595 -190.286132)
		(end 274.694904 -190.286132)
		(width 0.15494)
		(layer "In15.Cu")
		(net "PWRGD_NIC3_PWR_GOOD_R")
	)
	(segment
		(start 325.965566 -189.019434)
		(end 324.926198 -189.019434)
		(width 0.15494)
		(layer "In15.Cu")
		(net "PWRGD_NIC3_PWR_GOOD_R")
	)
	(segment
		(start 175.446436 -196.833744)
		(end 174.535084 -196.833744)
		(width 0.13208)
		(layer "F.Cu")
		(net "SPI_BIC1_CLK_LS01_DIR2")
	)
	(segment
		(start 175.824134 -196.456046)
		(end 175.446436 -196.833744)
		(width 0.13208)
		(layer "F.Cu")
		(net "SPI_BIC1_CLK_LS01_DIR2")
	)
	(via
		(at 175.824134 -196.456046)
		(size 0.508)
		(drill 0.254)
		(layers "F.Cu" "B.Cu")
		(net "SPI_BIC1_CLK_LS01_DIR2")
	)
	(segment
		(start 177.02022 -195.874386)
		(end 177.02022 -196.890386)
		(width 0.13208)
		(layer "B.Cu")
		(net "SPI_BIC1_CLK_LS01_DIR2")
	)
	(segment
		(start 176.258474 -196.890386)
		(end 175.824134 -196.456046)
		(width 0.13208)
		(layer "B.Cu")
		(net "SPI_BIC1_CLK_LS01_DIR2")
	)
	(segment
		(start 177.02022 -196.890386)
		(end 176.258474 -196.890386)
		(width 0.13208)
		(layer "B.Cu")
		(net "SPI_BIC1_CLK_LS01_DIR2")
	)
	(segment
		(start 445.12992 -360.571034)
		(end 447.095626 -362.53674)
		(width 0.13208)
		(layer "F.Cu")
		(net "GPU_3V3IO_RSVD3")
	)
	(segment
		(start 450.650864 -374.87225)
		(end 451.637908 -374.87225)
		(width 0.13208)
		(layer "F.Cu")
		(net "GPU_3V3IO_RSVD3")
	)
	(segment
		(start 453.478646 -374.87987)
		(end 453.881744 -374.476772)
		(width 0.13208)
		(layer "F.Cu")
		(net "GPU_3V3IO_RSVD3")
	)
	(segment
		(start 452.89597 -374.87987)
		(end 453.478646 -374.87987)
		(width 0.13208)
		(layer "F.Cu")
		(net "GPU_3V3IO_RSVD3")
	)
	(segment
		(start 453.881744 -372.850918)
		(end 453.881744 -371.711474)
		(width 0.13208)
		(layer "F.Cu")
		(net "GPU_3V3IO_RSVD3")
	)
	(segment
		(start 410.524706 -387.331966)
		(end 411.451044 -387.331966)
		(width 0.13208)
		(layer "F.Cu")
		(net "GPU_3V3IO_RSVD3")
	)
	(segment
		(start 447.095626 -374.20296)
		(end 447.764916 -374.87225)
		(width 0.13208)
		(layer "F.Cu")
		(net "GPU_3V3IO_RSVD3")
	)
	(segment
		(start 447.764916 -374.87225)
		(end 450.650864 -374.87225)
		(width 0.13208)
		(layer "F.Cu")
		(net "GPU_3V3IO_RSVD3")
	)
	(segment
		(start 409.60294 -388.253732)
		(end 409.60294 -388.659116)
		(width 0.13208)
		(layer "F.Cu")
		(net "GPU_3V3IO_RSVD3")
	)
	(segment
		(start 453.881744 -374.476772)
		(end 453.881744 -372.850918)
		(width 0.13208)
		(layer "F.Cu")
		(net "GPU_3V3IO_RSVD3")
	)
	(segment
		(start 409.60294 -388.253732)
		(end 410.524706 -387.331966)
		(width 0.13208)
		(layer "F.Cu")
		(net "GPU_3V3IO_RSVD3")
	)
	(segment
		(start 413.149034 -362.552488)
		(end 415.130488 -360.571034)
		(width 0.13208)
		(layer "F.Cu")
		(net "GPU_3V3IO_RSVD3")
	)
	(segment
		(start 409.60294 -388.659116)
		(end 409.90266 -388.958836)
		(width 0.13208)
		(layer "F.Cu")
		(net "GPU_3V3IO_RSVD3")
	)
	(segment
		(start 453.881744 -371.711474)
		(end 453.69607 -371.5258)
		(width 0.13208)
		(layer "F.Cu")
		(net "GPU_3V3IO_RSVD3")
	)
	(segment
		(start 451.638416 -374.871742)
		(end 452.887842 -374.871742)
		(width 0.13208)
		(layer "F.Cu")
		(net "GPU_3V3IO_RSVD3")
	)
	(segment
		(start 413.149034 -385.633976)
		(end 413.149034 -362.552488)
		(width 0.13208)
		(layer "F.Cu")
		(net "GPU_3V3IO_RSVD3")
	)
	(segment
		(start 452.887842 -374.871742)
		(end 452.89597 -374.87987)
		(width 0.13208)
		(layer "F.Cu")
		(net "GPU_3V3IO_RSVD3")
	)
	(segment
		(start 451.637908 -374.87225)
		(end 451.638416 -374.871742)
		(width 0.13208)
		(layer "F.Cu")
		(net "GPU_3V3IO_RSVD3")
	)
	(segment
		(start 411.451044 -387.331966)
		(end 413.149034 -385.633976)
		(width 0.13208)
		(layer "F.Cu")
		(net "GPU_3V3IO_RSVD3")
	)
	(segment
		(start 415.130488 -360.571034)
		(end 445.12992 -360.571034)
		(width 0.13208)
		(layer "F.Cu")
		(net "GPU_3V3IO_RSVD3")
	)
	(segment
		(start 447.095626 -362.53674)
		(end 447.095626 -374.20296)
		(width 0.13208)
		(layer "F.Cu")
		(net "GPU_3V3IO_RSVD3")
	)
	(via
		(at 453.881744 -372.850918)
		(size 0.762)
		(drill 0.381)
		(layers "F.Cu" "B.Cu")
		(net "GPU_3V3IO_RSVD3")
	)
	(via
		(at 409.90266 -388.958836)
		(size 0.508)
		(drill 0.254)
		(layers "F.Cu" "B.Cu")
		(net "GPU_3V3IO_RSVD3")
	)
	(segment
		(start 417.309808 -411.724094)
		(end 417.309808 -395.99362)
		(width 0.15494)
		(layer "In9.Cu")
		(net "GPU_3V3IO_RSVD3")
	)
	(segment
		(start 408.773122 -390.65835)
		(end 408.274012 -390.15924)
		(width 0.15494)
		(layer "In9.Cu")
		(net "GPU_3V3IO_RSVD3")
	)
	(segment
		(start 418.954712 -413.368998)
		(end 417.309808 -411.724094)
		(width 0.15494)
		(layer "In9.Cu")
		(net "GPU_3V3IO_RSVD3")
	)
	(segment
		(start 408.274012 -390.15924)
		(end 408.274012 -389.790432)
		(width 0.15494)
		(layer "In9.Cu")
		(net "GPU_3V3IO_RSVD3")
	)
	(segment
		(start 436.60695 -413.368998)
		(end 418.954712 -413.368998)
		(width 0.15494)
		(layer "In9.Cu")
		(net "GPU_3V3IO_RSVD3")
	)
	(segment
		(start 417.309808 -395.99362)
		(end 411.974538 -390.65835)
		(width 0.15494)
		(layer "In9.Cu")
		(net "GPU_3V3IO_RSVD3")
	)
	(segment
		(start 437.089804 -408.190192)
		(end 437.74741 -408.847798)
		(width 0.15494)
		(layer "In9.Cu")
		(net "GPU_3V3IO_RSVD3")
	)
	(segment
		(start 437.74741 -412.228538)
		(end 436.60695 -413.368998)
		(width 0.15494)
		(layer "In9.Cu")
		(net "GPU_3V3IO_RSVD3")
	)
	(segment
		(start 411.974538 -390.65835)
		(end 408.773122 -390.65835)
		(width 0.15494)
		(layer "In9.Cu")
		(net "GPU_3V3IO_RSVD3")
	)
	(segment
		(start 408.274012 -389.790432)
		(end 409.105608 -388.958836)
		(width 0.15494)
		(layer "In9.Cu")
		(net "GPU_3V3IO_RSVD3")
	)
	(segment
		(start 409.105608 -388.958836)
		(end 409.90266 -388.958836)
		(width 0.15494)
		(layer "In9.Cu")
		(net "GPU_3V3IO_RSVD3")
	)
	(segment
		(start 437.74741 -408.847798)
		(end 437.74741 -412.228538)
		(width 0.15494)
		(layer "In9.Cu")
		(net "GPU_3V3IO_RSVD3")
	)
	(segment
		(start 269.627604 -161.621724)
		(end 270.165068 -161.08426)
		(width 0.13208)
		(layer "F.Cu")
		(net "NIC4_MAIN_PWR_EN")
	)
	(segment
		(start 347.693742 -220.78696)
		(end 348.093538 -221.186756)
		(width 0.13208)
		(layer "F.Cu")
		(net "NIC4_MAIN_PWR_EN")
	)
	(segment
		(start 271.505172 -178.18862)
		(end 271.505172 -165.744906)
		(width 0.13208)
		(layer "F.Cu")
		(net "NIC4_MAIN_PWR_EN")
	)
	(segment
		(start 271.505172 -165.744906)
		(end 269.627604 -163.867338)
		(width 0.13208)
		(layer "F.Cu")
		(net "NIC4_MAIN_PWR_EN")
	)
	(segment
		(start 262.4328 -185.8518)
		(end 262.89762 -185.38698)
		(width 0.13208)
		(layer "F.Cu")
		(net "NIC4_MAIN_PWR_EN")
	)
	(segment
		(start 270.165068 -161.08426)
		(end 270.407892 -160.841436)
		(width 0.13208)
		(layer "F.Cu")
		(net "NIC4_MAIN_PWR_EN")
	)
	(segment
		(start 270.407892 -160.841436)
		(end 270.407892 -160.380934)
		(width 0.13208)
		(layer "F.Cu")
		(net "NIC4_MAIN_PWR_EN")
	)
	(segment
		(start 270.407892 -159.4104)
		(end 270.407892 -160.380934)
		(width 0.13208)
		(layer "F.Cu")
		(net "NIC4_MAIN_PWR_EN")
	)
	(segment
		(start 269.627604 -163.867338)
		(end 269.627604 -161.621724)
		(width 0.13208)
		(layer "F.Cu")
		(net "NIC4_MAIN_PWR_EN")
	)
	(segment
		(start 264.306812 -185.38698)
		(end 271.505172 -178.18862)
		(width 0.13208)
		(layer "F.Cu")
		(net "NIC4_MAIN_PWR_EN")
	)
	(segment
		(start 262.89762 -185.38698)
		(end 264.306812 -185.38698)
		(width 0.13208)
		(layer "F.Cu")
		(net "NIC4_MAIN_PWR_EN")
	)
	(via
		(at 270.165068 -161.08426)
		(size 0.508)
		(drill 0.254)
		(layers "F.Cu" "B.Cu")
		(net "NIC4_MAIN_PWR_EN")
	)
	(via
		(at 262.4328 -185.8518)
		(size 0.508)
		(drill 0.254)
		(layers "F.Cu" "B.Cu")
		(net "NIC4_MAIN_PWR_EN")
	)
	(via
		(at 348.093538 -221.186756)
		(size 0.4572)
		(drill 0.254)
		(layers "F.Cu" "B.Cu")
		(net "NIC4_MAIN_PWR_EN")
	)
	(segment
		(start 355.091746 -219.6592)
		(end 357.736648 -217.014298)
		(width 0.15494)
		(layer "In15.Cu")
		(net "NIC4_MAIN_PWR_EN")
	)
	(segment
		(start 341.771732 -192.98158)
		(end 340.786212 -192.98158)
		(width 0.15494)
		(layer "In15.Cu")
		(net "NIC4_MAIN_PWR_EN")
	)
	(segment
		(start 351.028 -220.5482)
		(end 351.949258 -220.5482)
		(width 0.15494)
		(layer "In15.Cu")
		(net "NIC4_MAIN_PWR_EN")
	)
	(segment
		(start 271.780762 -185.8518)
		(end 262.4328 -185.8518)
		(width 0.15494)
		(layer "In15.Cu")
		(net "NIC4_MAIN_PWR_EN")
	)
	(segment
		(start 352.384614 -200.095358)
		(end 347.583252 -200.095358)
		(width 0.15494)
		(layer "In15.Cu")
		(net "NIC4_MAIN_PWR_EN")
	)
	(segment
		(start 330.722224 -192.255902)
		(end 326.411336 -187.945014)
		(width 0.15494)
		(layer "In15.Cu")
		(net "NIC4_MAIN_PWR_EN")
	)
	(segment
		(start 274.24507 -188.316108)
		(end 271.780762 -185.8518)
		(width 0.15494)
		(layer "In15.Cu")
		(net "NIC4_MAIN_PWR_EN")
	)
	(segment
		(start 300.87697 -188.316108)
		(end 274.24507 -188.316108)
		(width 0.15494)
		(layer "In15.Cu")
		(net "NIC4_MAIN_PWR_EN")
	)
	(segment
		(start 353.83343 -219.6592)
		(end 355.091746 -219.6592)
		(width 0.15494)
		(layer "In15.Cu")
		(net "NIC4_MAIN_PWR_EN")
	)
	(segment
		(start 352.54819 -220.12402)
		(end 352.904806 -219.767404)
		(width 0.15494)
		(layer "In15.Cu")
		(net "NIC4_MAIN_PWR_EN")
	)
	(segment
		(start 353.725226 -219.767404)
		(end 353.83343 -219.6592)
		(width 0.15494)
		(layer "In15.Cu")
		(net "NIC4_MAIN_PWR_EN")
	)
	(segment
		(start 340.060534 -192.255902)
		(end 330.722224 -192.255902)
		(width 0.15494)
		(layer "In15.Cu")
		(net "NIC4_MAIN_PWR_EN")
	)
	(segment
		(start 348.093538 -221.186756)
		(end 348.491556 -220.788738)
		(width 0.0889)
		(layer "In15.Cu")
		(net "NIC4_MAIN_PWR_EN")
	)
	(segment
		(start 352.373438 -220.12402)
		(end 352.54819 -220.12402)
		(width 0.15494)
		(layer "In15.Cu")
		(net "NIC4_MAIN_PWR_EN")
	)
	(segment
		(start 348.491556 -220.788738)
		(end 350.787462 -220.788738)
		(width 0.0889)
		(layer "In15.Cu")
		(net "NIC4_MAIN_PWR_EN")
	)
	(segment
		(start 350.787462 -220.788738)
		(end 351.028 -220.5482)
		(width 0.0889)
		(layer "In15.Cu")
		(net "NIC4_MAIN_PWR_EN")
	)
	(segment
		(start 340.786212 -192.98158)
		(end 340.060534 -192.255902)
		(width 0.15494)
		(layer "In15.Cu")
		(net "NIC4_MAIN_PWR_EN")
	)
	(segment
		(start 352.904806 -219.767404)
		(end 353.725226 -219.767404)
		(width 0.15494)
		(layer "In15.Cu")
		(net "NIC4_MAIN_PWR_EN")
	)
	(segment
		(start 344.081354 -195.291202)
		(end 341.771732 -192.98158)
		(width 0.15494)
		(layer "In15.Cu")
		(net "NIC4_MAIN_PWR_EN")
	)
	(segment
		(start 344.081354 -196.59346)
		(end 344.081354 -195.291202)
		(width 0.15494)
		(layer "In15.Cu")
		(net "NIC4_MAIN_PWR_EN")
	)
	(segment
		(start 347.583252 -200.095358)
		(end 344.081354 -196.59346)
		(width 0.15494)
		(layer "In15.Cu")
		(net "NIC4_MAIN_PWR_EN")
	)
	(segment
		(start 351.949258 -220.5482)
		(end 352.373438 -220.12402)
		(width 0.15494)
		(layer "In15.Cu")
		(net "NIC4_MAIN_PWR_EN")
	)
	(segment
		(start 357.736648 -217.014298)
		(end 357.736648 -205.447392)
		(width 0.15494)
		(layer "In15.Cu")
		(net "NIC4_MAIN_PWR_EN")
	)
	(segment
		(start 357.736648 -205.447392)
		(end 352.384614 -200.095358)
		(width 0.15494)
		(layer "In15.Cu")
		(net "NIC4_MAIN_PWR_EN")
	)
	(segment
		(start 326.411336 -187.945014)
		(end 301.248064 -187.945014)
		(width 0.15494)
		(layer "In15.Cu")
		(net "NIC4_MAIN_PWR_EN")
	)
	(segment
		(start 301.248064 -187.945014)
		(end 300.87697 -188.316108)
		(width 0.15494)
		(layer "In15.Cu")
		(net "NIC4_MAIN_PWR_EN")
	)
	(segment
		(start 217.637106 -197.144894)
		(end 218.186 -196.596)
		(width 0.13208)
		(layer "F.Cu")
		(net "SMB_NIC6_LS_EN")
	)
	(segment
		(start 218.186 -196.596)
		(end 218.80195 -196.596)
		(width 0.13208)
		(layer "F.Cu")
		(net "SMB_NIC6_LS_EN")
	)
	(segment
		(start 216.991946 -197.144894)
		(end 217.637106 -197.144894)
		(width 0.13208)
		(layer "F.Cu")
		(net "SMB_NIC6_LS_EN")
	)
	(via
		(at 218.186 -196.596)
		(size 0.508)
		(drill 0.254)
		(layers "F.Cu" "B.Cu")
		(net "SMB_NIC6_LS_EN")
	)
	(segment
		(start 135.797798 -96.710246)
		(end 135.116062 -96.710246)
		(width 0.13208)
		(layer "F.Cu")
		(net "BIC_I2C9_SSD_MUX0_A2")
	)
	(segment
		(start 135.039862 -96.710246)
		(end 134.120128 -95.790512)
		(width 0.13208)
		(layer "F.Cu")
		(net "BIC_I2C9_SSD_MUX0_A2")
	)
	(segment
		(start 134.120128 -95.790512)
		(end 133.062726 -95.790512)
		(width 0.13208)
		(layer "F.Cu")
		(net "BIC_I2C9_SSD_MUX0_A2")
	)
	(segment
		(start 136.045194 -96.957642)
		(end 135.797798 -96.710246)
		(width 0.13208)
		(layer "F.Cu")
		(net "BIC_I2C9_SSD_MUX0_A2")
	)
	(segment
		(start 136.045194 -97.296478)
		(end 136.045194 -96.957642)
		(width 0.13208)
		(layer "F.Cu")
		(net "BIC_I2C9_SSD_MUX0_A2")
	)
	(segment
		(start 137.744454 -97.4852)
		(end 136.233916 -97.4852)
		(width 0.13208)
		(layer "F.Cu")
		(net "BIC_I2C9_SSD_MUX0_A2")
	)
	(segment
		(start 138.585194 -96.957642)
		(end 138.272012 -96.957642)
		(width 0.13208)
		(layer "F.Cu")
		(net "BIC_I2C9_SSD_MUX0_A2")
	)
	(segment
		(start 135.116062 -96.710246)
		(end 135.039862 -96.710246)
		(width 0.13208)
		(layer "F.Cu")
		(net "BIC_I2C9_SSD_MUX0_A2")
	)
	(segment
		(start 136.233916 -97.4852)
		(end 136.045194 -97.296478)
		(width 0.13208)
		(layer "F.Cu")
		(net "BIC_I2C9_SSD_MUX0_A2")
	)
	(segment
		(start 138.272012 -96.957642)
		(end 137.744454 -97.4852)
		(width 0.13208)
		(layer "F.Cu")
		(net "BIC_I2C9_SSD_MUX0_A2")
	)
	(via
		(at 135.116062 -96.710246)
		(size 0.508)
		(drill 0.254)
		(layers "F.Cu" "B.Cu")
		(net "BIC_I2C9_SSD_MUX0_A2")
	)
	(segment
		(start 62.323472 -388.37743)
		(end 59.664854 -385.718812)
		(width 0.13208)
		(layer "F.Cu")
		(net "GPU_BASE_FPGA_READY_R")
	)
	(segment
		(start 62.323472 -388.856728)
		(end 62.323472 -388.37743)
		(width 0.13208)
		(layer "F.Cu")
		(net "GPU_BASE_FPGA_READY_R")
	)
	(segment
		(start 59.664854 -385.718812)
		(end 59.086242 -385.718812)
		(width 0.13208)
		(layer "F.Cu")
		(net "GPU_BASE_FPGA_READY_R")
	)
	(segment
		(start 62.1284 -389.0518)
		(end 62.323472 -388.856728)
		(width 0.13208)
		(layer "F.Cu")
		(net "GPU_BASE_FPGA_READY_R")
	)
	(via
		(at 62.1284 -389.0518)
		(size 0.508)
		(drill 0.254)
		(layers "F.Cu" "B.Cu")
		(net "GPU_BASE_FPGA_READY_R")
	)
	(segment
		(start 62.6618 -388.5184)
		(end 64.1604 -388.5184)
		(width 0.13208)
		(layer "B.Cu")
		(net "GPU_BASE_FPGA_READY_R")
	)
	(segment
		(start 92.530168 -403.610318)
		(end 91.710002 -402.790152)
		(width 0.13208)
		(layer "B.Cu")
		(net "GPU_BASE_FPGA_READY_R")
	)
	(segment
		(start 64.1604 -388.5184)
		(end 67.101974 -391.459974)
		(width 0.13208)
		(layer "B.Cu")
		(net "GPU_BASE_FPGA_READY_R")
	)
	(segment
		(start 62.1284 -389.0518)
		(end 62.6618 -388.5184)
		(width 0.13208)
		(layer "B.Cu")
		(net "GPU_BASE_FPGA_READY_R")
	)
	(segment
		(start 67.101974 -391.459974)
		(end 67.101974 -412.4706)
		(width 0.13208)
		(layer "B.Cu")
		(net "GPU_BASE_FPGA_READY_R")
	)
	(segment
		(start 92.530168 -414.910778)
		(end 92.530168 -403.610318)
		(width 0.13208)
		(layer "B.Cu")
		(net "GPU_BASE_FPGA_READY_R")
	)
	(segment
		(start 91.679522 -415.761424)
		(end 92.530168 -414.910778)
		(width 0.13208)
		(layer "B.Cu")
		(net "GPU_BASE_FPGA_READY_R")
	)
	(segment
		(start 67.101974 -412.4706)
		(end 70.392798 -415.761424)
		(width 0.13208)
		(layer "B.Cu")
		(net "GPU_BASE_FPGA_READY_R")
	)
	(segment
		(start 70.392798 -415.761424)
		(end 91.679522 -415.761424)
		(width 0.13208)
		(layer "B.Cu")
		(net "GPU_BASE_FPGA_READY_R")
	)
	(segment
		(start 230.399082 -79.899002)
		(end 230.329994 -79.829914)
		(width 0.13462)
		(layer "F.Cu")
		(net "USB2_PEX_HUB_DN")
	)
	(segment
		(start 230.09098 -85.34273)
		(end 230.09098 -86.114382)
		(width 0.13462)
		(layer "F.Cu")
		(net "USB2_PEX_HUB_DN")
	)
	(segment
		(start 230.09098 -80.57642)
		(end 230.399082 -80.268318)
		(width 0.13462)
		(layer "F.Cu")
		(net "USB2_PEX_HUB_DN")
	)
	(segment
		(start 230.09098 -85.34273)
		(end 230.09098 -80.57642)
		(width 0.13462)
		(layer "F.Cu")
		(net "USB2_PEX_HUB_DN")
	)
	(segment
		(start 230.329994 -79.829914)
		(end 230.329994 -79.465678)
		(width 0.13462)
		(layer "F.Cu")
		(net "USB2_PEX_HUB_DN")
	)
	(segment
		(start 230.09098 -86.114382)
		(end 229.771956 -86.433406)
		(width 0.13462)
		(layer "F.Cu")
		(net "USB2_PEX_HUB_DN")
	)
	(segment
		(start 230.399082 -80.268318)
		(end 230.399082 -79.899002)
		(width 0.13462)
		(layer "F.Cu")
		(net "USB2_PEX_HUB_DN")
	)
	(via
		(at 230.09098 -85.34273)
		(size 0.4064)
		(drill 0.2032)
		(layers "F.Cu" "B.Cu")
		(net "USB2_PEX_HUB_DN")
	)
	(segment
		(start 175.431704 -197.48373)
		(end 174.535084 -197.48373)
		(width 0.13208)
		(layer "F.Cu")
		(net "SPI_BIC1_CS0_LS01_N_DIR1")
	)
	(segment
		(start 175.80737 -197.859396)
		(end 175.431704 -197.48373)
		(width 0.13208)
		(layer "F.Cu")
		(net "SPI_BIC1_CS0_LS01_N_DIR1")
	)
	(via
		(at 175.80737 -197.859396)
		(size 0.508)
		(drill 0.254)
		(layers "F.Cu" "B.Cu")
		(net "SPI_BIC1_CS0_LS01_N_DIR1")
	)
	(segment
		(start 177.02022 -199.303386)
		(end 177.02022 -198.287386)
		(width 0.13208)
		(layer "B.Cu")
		(net "SPI_BIC1_CS0_LS01_N_DIR1")
	)
	(segment
		(start 177.02022 -198.287386)
		(end 176.23536 -198.287386)
		(width 0.13208)
		(layer "B.Cu")
		(net "SPI_BIC1_CS0_LS01_N_DIR1")
	)
	(segment
		(start 176.23536 -198.287386)
		(end 175.80737 -197.859396)
		(width 0.13208)
		(layer "B.Cu")
		(net "SPI_BIC1_CS0_LS01_N_DIR1")
	)
	(segment
		(start 217.216736 -168.148)
		(end 216.828116 -168.148)
		(width 0.13208)
		(layer "F.Cu")
		(net "SMB_NIC5_LS_SDA")
	)
	(segment
		(start 269.192502 -155.647644)
		(end 268.3764 -156.463746)
		(width 0.13208)
		(layer "F.Cu")
		(net "SMB_NIC5_LS_SDA")
	)
	(segment
		(start 218.710256 -167.472614)
		(end 218.590876 -167.591994)
		(width 0.13208)
		(layer "F.Cu")
		(net "SMB_NIC5_LS_SDA")
	)
	(segment
		(start 217.336116 -168.02862)
		(end 217.216736 -168.148)
		(width 0.13208)
		(layer "F.Cu")
		(net "SMB_NIC5_LS_SDA")
	)
	(segment
		(start 240.456466 -167.428926)
		(end 239.395 -166.36746)
		(width 0.13208)
		(layer "F.Cu")
		(net "SMB_NIC5_LS_SDA")
	)
	(segment
		(start 216.828116 -168.148)
		(end 216.708736 -168.02862)
		(width 0.13208)
		(layer "F.Cu")
		(net "SMB_NIC5_LS_SDA")
	)
	(segment
		(start 239.395 -166.36746)
		(end 221.36735 -166.36746)
		(width 0.13208)
		(layer "F.Cu")
		(net "SMB_NIC5_LS_SDA")
	)
	(segment
		(start 268.3764 -163.737036)
		(end 264.68451 -167.428926)
		(width 0.13208)
		(layer "F.Cu")
		(net "SMB_NIC5_LS_SDA")
	)
	(segment
		(start 269.619984 -155.647644)
		(end 269.192502 -155.647644)
		(width 0.13208)
		(layer "F.Cu")
		(net "SMB_NIC5_LS_SDA")
	)
	(segment
		(start 221.36735 -166.36746)
		(end 220.262196 -167.472614)
		(width 0.13208)
		(layer "F.Cu")
		(net "SMB_NIC5_LS_SDA")
	)
	(segment
		(start 218.082876 -168.148)
		(end 217.963496 -168.02862)
		(width 0.13208)
		(layer "F.Cu")
		(net "SMB_NIC5_LS_SDA")
	)
	(segment
		(start 217.844116 -167.472614)
		(end 217.455496 -167.472614)
		(width 0.13208)
		(layer "F.Cu")
		(net "SMB_NIC5_LS_SDA")
	)
	(segment
		(start 264.68451 -167.428926)
		(end 240.456466 -167.428926)
		(width 0.13208)
		(layer "F.Cu")
		(net "SMB_NIC5_LS_SDA")
	)
	(segment
		(start 218.471496 -168.148)
		(end 218.082876 -168.148)
		(width 0.13208)
		(layer "F.Cu")
		(net "SMB_NIC5_LS_SDA")
	)
	(segment
		(start 217.455496 -167.472614)
		(end 217.336116 -167.591994)
		(width 0.13208)
		(layer "F.Cu")
		(net "SMB_NIC5_LS_SDA")
	)
	(segment
		(start 218.590876 -167.591994)
		(end 218.590876 -168.02862)
		(width 0.13208)
		(layer "F.Cu")
		(net "SMB_NIC5_LS_SDA")
	)
	(segment
		(start 300.857412 -113.43513)
		(end 299.512736 -113.43513)
		(width 0.13208)
		(layer "F.Cu")
		(net "SMB_NIC5_LS_SDA")
	)
	(segment
		(start 216.589356 -167.472614)
		(end 215.907366 -167.472614)
		(width 0.13208)
		(layer "F.Cu")
		(net "SMB_NIC5_LS_SDA")
	)
	(segment
		(start 217.963496 -168.02862)
		(end 217.963496 -167.591994)
		(width 0.13208)
		(layer "F.Cu")
		(net "SMB_NIC5_LS_SDA")
	)
	(segment
		(start 217.336116 -167.591994)
		(end 217.336116 -168.02862)
		(width 0.13208)
		(layer "F.Cu")
		(net "SMB_NIC5_LS_SDA")
	)
	(segment
		(start 216.708736 -167.591994)
		(end 216.589356 -167.472614)
		(width 0.13208)
		(layer "F.Cu")
		(net "SMB_NIC5_LS_SDA")
	)
	(segment
		(start 216.708736 -168.02862)
		(end 216.708736 -167.591994)
		(width 0.13208)
		(layer "F.Cu")
		(net "SMB_NIC5_LS_SDA")
	)
	(segment
		(start 217.963496 -167.591994)
		(end 217.844116 -167.472614)
		(width 0.13208)
		(layer "F.Cu")
		(net "SMB_NIC5_LS_SDA")
	)
	(segment
		(start 218.590876 -168.02862)
		(end 218.471496 -168.148)
		(width 0.13208)
		(layer "F.Cu")
		(net "SMB_NIC5_LS_SDA")
	)
	(segment
		(start 268.3764 -156.463746)
		(end 268.3764 -163.737036)
		(width 0.13208)
		(layer "F.Cu")
		(net "SMB_NIC5_LS_SDA")
	)
	(segment
		(start 220.262196 -167.472614)
		(end 218.710256 -167.472614)
		(width 0.13208)
		(layer "F.Cu")
		(net "SMB_NIC5_LS_SDA")
	)
	(segment
		(start 215.907366 -167.472614)
		(end 215.504776 -167.070024)
		(width 0.13208)
		(layer "F.Cu")
		(net "SMB_NIC5_LS_SDA")
	)
	(via
		(at 299.512736 -113.43513)
		(size 0.508)
		(drill 0.254)
		(layers "F.Cu" "B.Cu")
		(net "SMB_NIC5_LS_SDA")
	)
	(via
		(at 215.773 -203.073)
		(size 0.508)
		(drill 0.254)
		(layers "F.Cu" "B.Cu")
		(net "SMB_NIC5_LS_SDA")
	)
	(via
		(at 269.619984 -155.647644)
		(size 0.508)
		(drill 0.254)
		(layers "F.Cu" "B.Cu")
		(net "SMB_NIC5_LS_SDA")
	)
	(via
		(at 215.504776 -167.070024)
		(size 0.508)
		(drill 0.254)
		(layers "F.Cu" "B.Cu")
		(net "SMB_NIC5_LS_SDA")
	)
	(via
		(at 285.16707 -150.11781)
		(size 0.508)
		(drill 0.254)
		(layers "F.Cu" "B.Cu")
		(net "SMB_NIC5_LS_SDA")
	)
	(segment
		(start 214.64905 -203.073)
		(end 214.503 -202.92695)
		(width 0.13208)
		(layer "B.Cu")
		(net "SMB_NIC5_LS_SDA")
	)
	(segment
		(start 299.51553 -113.437924)
		(end 299.512736 -113.43513)
		(width 0.13208)
		(layer "B.Cu")
		(net "SMB_NIC5_LS_SDA")
	)
	(segment
		(start 300.472094 -113.437924)
		(end 299.51553 -113.437924)
		(width 0.13208)
		(layer "B.Cu")
		(net "SMB_NIC5_LS_SDA")
	)
	(segment
		(start 215.773 -203.073)
		(end 214.64905 -203.073)
		(width 0.13208)
		(layer "B.Cu")
		(net "SMB_NIC5_LS_SDA")
	)
	(segment
		(start 214.503 -202.92695)
		(end 213.106 -202.92695)
		(width 0.13208)
		(layer "B.Cu")
		(net "SMB_NIC5_LS_SDA")
	)
	(segment
		(start 299.109384 -113.43513)
		(end 297.5864 -111.912146)
		(width 0.15494)
		(layer "In5.Cu")
		(net "SMB_NIC5_LS_SDA")
	)
	(segment
		(start 291.42182 -112.737392)
		(end 291.42182 -144.31137)
		(width 0.15494)
		(layer "In5.Cu")
		(net "SMB_NIC5_LS_SDA")
	)
	(segment
		(start 292.247066 -111.912146)
		(end 291.42182 -112.737392)
		(width 0.15494)
		(layer "In5.Cu")
		(net "SMB_NIC5_LS_SDA")
	)
	(segment
		(start 297.5864 -111.912146)
		(end 292.247066 -111.912146)
		(width 0.15494)
		(layer "In5.Cu")
		(net "SMB_NIC5_LS_SDA")
	)
	(segment
		(start 291.42182 -144.31137)
		(end 285.61538 -150.11781)
		(width 0.15494)
		(layer "In5.Cu")
		(net "SMB_NIC5_LS_SDA")
	)
	(segment
		(start 299.512736 -113.43513)
		(end 299.109384 -113.43513)
		(width 0.15494)
		(layer "In5.Cu")
		(net "SMB_NIC5_LS_SDA")
	)
	(segment
		(start 285.61538 -150.11781)
		(end 285.16707 -150.11781)
		(width 0.15494)
		(layer "In5.Cu")
		(net "SMB_NIC5_LS_SDA")
	)
	(segment
		(start 214.79002 -178.06162)
		(end 215.392 -178.6636)
		(width 0.15494)
		(layer "In7.Cu")
		(net "SMB_NIC5_LS_SDA")
	)
	(segment
		(start 215.257634 -199.819006)
		(end 215.257634 -202.938634)
		(width 0.15494)
		(layer "In7.Cu")
		(net "SMB_NIC5_LS_SDA")
	)
	(segment
		(start 216.51468 -190.196978)
		(end 216.74074 -190.423038)
		(width 0.15494)
		(layer "In7.Cu")
		(net "SMB_NIC5_LS_SDA")
	)
	(segment
		(start 214.79002 -168.733978)
		(end 214.79002 -178.06162)
		(width 0.15494)
		(layer "In7.Cu")
		(net "SMB_NIC5_LS_SDA")
	)
	(segment
		(start 215.392 -183.81472)
		(end 216.51468 -184.9374)
		(width 0.15494)
		(layer "In7.Cu")
		(net "SMB_NIC5_LS_SDA")
	)
	(segment
		(start 215.392 -178.6636)
		(end 215.392 -183.81472)
		(width 0.15494)
		(layer "In7.Cu")
		(net "SMB_NIC5_LS_SDA")
	)
	(segment
		(start 215.392 -203.073)
		(end 215.773 -203.073)
		(width 0.15494)
		(layer "In7.Cu")
		(net "SMB_NIC5_LS_SDA")
	)
	(segment
		(start 215.504776 -168.019222)
		(end 214.79002 -168.733978)
		(width 0.15494)
		(layer "In7.Cu")
		(net "SMB_NIC5_LS_SDA")
	)
	(segment
		(start 216.74074 -198.3359)
		(end 215.257634 -199.819006)
		(width 0.15494)
		(layer "In7.Cu")
		(net "SMB_NIC5_LS_SDA")
	)
	(segment
		(start 215.504776 -167.070024)
		(end 215.504776 -168.019222)
		(width 0.15494)
		(layer "In7.Cu")
		(net "SMB_NIC5_LS_SDA")
	)
	(segment
		(start 215.257634 -202.938634)
		(end 215.392 -203.073)
		(width 0.15494)
		(layer "In7.Cu")
		(net "SMB_NIC5_LS_SDA")
	)
	(segment
		(start 216.51468 -184.9374)
		(end 216.51468 -190.196978)
		(width 0.15494)
		(layer "In7.Cu")
		(net "SMB_NIC5_LS_SDA")
	)
	(segment
		(start 216.74074 -190.423038)
		(end 216.74074 -198.3359)
		(width 0.15494)
		(layer "In7.Cu")
		(net "SMB_NIC5_LS_SDA")
	)
	(segment
		(start 285.16707 -150.11781)
		(end 276.068536 -150.11781)
		(width 0.15494)
		(layer "In15.Cu")
		(net "SMB_NIC5_LS_SDA")
	)
	(segment
		(start 276.068536 -150.11781)
		(end 270.538702 -155.647644)
		(width 0.15494)
		(layer "In15.Cu")
		(net "SMB_NIC5_LS_SDA")
	)
	(segment
		(start 270.538702 -155.647644)
		(end 269.619984 -155.647644)
		(width 0.15494)
		(layer "In15.Cu")
		(net "SMB_NIC5_LS_SDA")
	)
	(segment
		(start 403.479508 -377.708922)
		(end 403.479508 -389.163306)
		(width 0.13208)
		(layer "F.Cu")
		(net "GPU_3V3IO_RSVD1")
	)
	(segment
		(start 403.287484 -371.019578)
		(end 404.531322 -371.019578)
		(width 0.13208)
		(layer "F.Cu")
		(net "GPU_3V3IO_RSVD1")
	)
	(segment
		(start 408.793696 -389.955532)
		(end 408.774392 -389.974836)
		(width 0.13208)
		(layer "F.Cu")
		(net "GPU_3V3IO_RSVD1")
	)
	(segment
		(start 403.940518 -372.877842)
		(end 406.219914 -372.877842)
		(width 0.13208)
		(layer "F.Cu")
		(net "GPU_3V3IO_RSVD1")
	)
	(segment
		(start 406.790398 -373.881142)
		(end 407.74493 -374.835674)
		(width 0.13208)
		(layer "F.Cu")
		(net "GPU_3V3IO_RSVD1")
	)
	(segment
		(start 404.792434 -390.476232)
		(end 407.594816 -390.476232)
		(width 0.13208)
		(layer "F.Cu")
		(net "GPU_3V3IO_RSVD1")
	)
	(segment
		(start 406.219914 -373.310658)
		(end 406.790398 -373.881142)
		(width 0.13208)
		(layer "F.Cu")
		(net "GPU_3V3IO_RSVD1")
	)
	(segment
		(start 406.812496 -377.323858)
		(end 406.388062 -376.899424)
		(width 0.13208)
		(layer "F.Cu")
		(net "GPU_3V3IO_RSVD1")
	)
	(segment
		(start 403.479508 -389.163306)
		(end 404.792434 -390.476232)
		(width 0.13208)
		(layer "F.Cu")
		(net "GPU_3V3IO_RSVD1")
	)
	(segment
		(start 406.219914 -372.877842)
		(end 406.219914 -373.310658)
		(width 0.13208)
		(layer "F.Cu")
		(net "GPU_3V3IO_RSVD1")
	)
	(segment
		(start 403.287484 -372.224808)
		(end 403.940518 -372.877842)
		(width 0.13208)
		(layer "F.Cu")
		(net "GPU_3V3IO_RSVD1")
	)
	(segment
		(start 403.287484 -371.019578)
		(end 403.287484 -372.224808)
		(width 0.13208)
		(layer "F.Cu")
		(net "GPU_3V3IO_RSVD1")
	)
	(segment
		(start 404.289006 -376.899424)
		(end 403.479508 -377.708922)
		(width 0.13208)
		(layer "F.Cu")
		(net "GPU_3V3IO_RSVD1")
	)
	(segment
		(start 409.52674 -389.955532)
		(end 408.793696 -389.955532)
		(width 0.13208)
		(layer "F.Cu")
		(net "GPU_3V3IO_RSVD1")
	)
	(segment
		(start 452.927212 -366.70361)
		(end 453.667114 -366.70361)
		(width 0.13208)
		(layer "F.Cu")
		(net "GPU_3V3IO_RSVD1")
	)
	(segment
		(start 407.74493 -374.835674)
		(end 407.74493 -376.855482)
		(width 0.13208)
		(layer "F.Cu")
		(net "GPU_3V3IO_RSVD1")
	)
	(segment
		(start 407.594816 -390.476232)
		(end 408.096212 -389.974836)
		(width 0.13208)
		(layer "F.Cu")
		(net "GPU_3V3IO_RSVD1")
	)
	(segment
		(start 406.388062 -376.899424)
		(end 404.289006 -376.899424)
		(width 0.13208)
		(layer "F.Cu")
		(net "GPU_3V3IO_RSVD1")
	)
	(segment
		(start 408.096212 -389.974836)
		(end 408.774392 -389.974836)
		(width 0.13208)
		(layer "F.Cu")
		(net "GPU_3V3IO_RSVD1")
	)
	(segment
		(start 407.276554 -377.323858)
		(end 406.812496 -377.323858)
		(width 0.13208)
		(layer "F.Cu")
		(net "GPU_3V3IO_RSVD1")
	)
	(segment
		(start 407.74493 -376.855482)
		(end 407.276554 -377.323858)
		(width 0.13208)
		(layer "F.Cu")
		(net "GPU_3V3IO_RSVD1")
	)
	(via
		(at 453.667114 -366.70361)
		(size 0.508)
		(drill 0.254)
		(layers "F.Cu" "B.Cu")
		(net "GPU_3V3IO_RSVD1")
	)
	(via
		(at 404.531322 -371.019578)
		(size 0.508)
		(drill 0.254)
		(layers "F.Cu" "B.Cu")
		(net "GPU_3V3IO_RSVD1")
	)
	(via
		(at 408.774392 -389.974836)
		(size 0.508)
		(drill 0.254)
		(layers "F.Cu" "B.Cu")
		(net "GPU_3V3IO_RSVD1")
	)
	(via
		(at 403.287484 -372.224808)
		(size 0.762)
		(drill 0.381)
		(layers "F.Cu" "B.Cu")
		(net "GPU_3V3IO_RSVD1")
	)
	(segment
		(start 407.801064 -369.410996)
		(end 407.272998 -369.939062)
		(width 0.13208)
		(layer "B.Cu")
		(net "GPU_3V3IO_RSVD1")
	)
	(segment
		(start 450.324982 -362.218478)
		(end 412.706058 -362.218478)
		(width 0.13208)
		(layer "B.Cu")
		(net "GPU_3V3IO_RSVD1")
	)
	(segment
		(start 407.272998 -369.939062)
		(end 405.940006 -370.491258)
		(width 0.13208)
		(layer "B.Cu")
		(net "GPU_3V3IO_RSVD1")
	)
	(segment
		(start 452.351902 -364.245398)
		(end 450.324982 -362.218478)
		(width 0.13208)
		(layer "B.Cu")
		(net "GPU_3V3IO_RSVD1")
	)
	(segment
		(start 452.351902 -365.388398)
		(end 452.351902 -364.245398)
		(width 0.13208)
		(layer "B.Cu")
		(net "GPU_3V3IO_RSVD1")
	)
	(segment
		(start 405.940006 -370.491258)
		(end 405.059642 -370.491258)
		(width 0.13208)
		(layer "B.Cu")
		(net "GPU_3V3IO_RSVD1")
	)
	(segment
		(start 412.706058 -362.218478)
		(end 407.801064 -367.123472)
		(width 0.13208)
		(layer "B.Cu")
		(net "GPU_3V3IO_RSVD1")
	)
	(segment
		(start 453.667114 -366.70361)
		(end 452.351902 -365.388398)
		(width 0.13208)
		(layer "B.Cu")
		(net "GPU_3V3IO_RSVD1")
	)
	(segment
		(start 407.801064 -367.123472)
		(end 407.801064 -369.410996)
		(width 0.13208)
		(layer "B.Cu")
		(net "GPU_3V3IO_RSVD1")
	)
	(segment
		(start 405.059642 -370.491258)
		(end 404.531322 -371.019578)
		(width 0.13208)
		(layer "B.Cu")
		(net "GPU_3V3IO_RSVD1")
	)
	(segment
		(start 436.169054 -413.010858)
		(end 437.089804 -412.090108)
		(width 0.15494)
		(layer "In9.Cu")
		(net "GPU_3V3IO_RSVD1")
	)
	(segment
		(start 408.774392 -389.974836)
		(end 411.797754 -389.974836)
		(width 0.15494)
		(layer "In9.Cu")
		(net "GPU_3V3IO_RSVD1")
	)
	(segment
		(start 419.103302 -413.010858)
		(end 436.169054 -413.010858)
		(width 0.15494)
		(layer "In9.Cu")
		(net "GPU_3V3IO_RSVD1")
	)
	(segment
		(start 417.667948 -411.575504)
		(end 419.103302 -413.010858)
		(width 0.15494)
		(layer "In9.Cu")
		(net "GPU_3V3IO_RSVD1")
	)
	(segment
		(start 411.797754 -389.974836)
		(end 417.667948 -395.84503)
		(width 0.15494)
		(layer "In9.Cu")
		(net "GPU_3V3IO_RSVD1")
	)
	(segment
		(start 417.667948 -395.84503)
		(end 417.667948 -411.575504)
		(width 0.15494)
		(layer "In9.Cu")
		(net "GPU_3V3IO_RSVD1")
	)
	(segment
		(start 123.981464 -98.820986)
		(end 124.07519 -98.72726)
		(width 0.13208)
		(layer "F.Cu")
		(net "BIC_I2C9_SSD_MUX0_A1")
	)
	(segment
		(start 121.53519 -98.320606)
		(end 122.03557 -98.820986)
		(width 0.13208)
		(layer "F.Cu")
		(net "BIC_I2C9_SSD_MUX0_A1")
	)
	(segment
		(start 122.03557 -98.820986)
		(end 123.981464 -98.820986)
		(width 0.13208)
		(layer "F.Cu")
		(net "BIC_I2C9_SSD_MUX0_A1")
	)
	(segment
		(start 124.07519 -98.72726)
		(end 124.07519 -98.320606)
		(width 0.13208)
		(layer "F.Cu")
		(net "BIC_I2C9_SSD_MUX0_A1")
	)
	(segment
		(start 124.07519 -98.320606)
		(end 125.731016 -98.320606)
		(width 0.13208)
		(layer "F.Cu")
		(net "BIC_I2C9_SSD_MUX0_A1")
	)
	(segment
		(start 125.781562 -97.793048)
		(end 126.484126 -97.090484)
		(width 0.13208)
		(layer "F.Cu")
		(net "BIC_I2C9_SSD_MUX0_A1")
	)
	(segment
		(start 125.731016 -98.320606)
		(end 125.781562 -98.27006)
		(width 0.13208)
		(layer "F.Cu")
		(net "BIC_I2C9_SSD_MUX0_A1")
	)
	(segment
		(start 125.781562 -98.27006)
		(end 125.781562 -97.793048)
		(width 0.13208)
		(layer "F.Cu")
		(net "BIC_I2C9_SSD_MUX0_A1")
	)
	(segment
		(start 126.484126 -97.090484)
		(end 127.462534 -97.090484)
		(width 0.13208)
		(layer "F.Cu")
		(net "BIC_I2C9_SSD_MUX0_A1")
	)
	(via
		(at 125.781562 -98.27006)
		(size 0.508)
		(drill 0.254)
		(layers "F.Cu" "B.Cu")
		(net "BIC_I2C9_SSD_MUX0_A1")
	)
	(segment
		(start 350.893888 -223.987106)
		(end 351.293684 -224.386902)
		(width 0.13208)
		(layer "F.Cu")
		(net "PWRGD_NIC1_PWR_GOOD_R")
	)
	(via
		(at 62.043818 -177.015394)
		(size 0.508)
		(drill 0.254)
		(layers "F.Cu" "B.Cu")
		(net "PWRGD_NIC1_PWR_GOOD_R")
	)
	(via
		(at 351.293684 -224.386902)
		(size 0.4572)
		(drill 0.254)
		(layers "F.Cu" "B.Cu")
		(net "PWRGD_NIC1_PWR_GOOD_R")
	)
	(via
		(at 96.99625 -188.046614)
		(size 0.508)
		(drill 0.254)
		(layers "F.Cu" "B.Cu")
		(net "PWRGD_NIC1_PWR_GOOD_R")
	)
	(via
		(at 69.70395 -96.901)
		(size 0.508)
		(drill 0.254)
		(layers "F.Cu" "B.Cu")
		(net "PWRGD_NIC1_PWR_GOOD_R")
	)
	(segment
		(start 69.70395 -97.663)
		(end 69.70395 -96.901)
		(width 0.13208)
		(layer "B.Cu")
		(net "PWRGD_NIC1_PWR_GOOD_R")
	)
	(segment
		(start 60.167266 -175.138842)
		(end 60.167266 -156.581094)
		(width 0.15494)
		(layer "In5.Cu")
		(net "PWRGD_NIC1_PWR_GOOD_R")
	)
	(segment
		(start 62.043818 -177.015394)
		(end 60.167266 -175.138842)
		(width 0.15494)
		(layer "In5.Cu")
		(net "PWRGD_NIC1_PWR_GOOD_R")
	)
	(segment
		(start 61.3918 -106.814366)
		(end 69.70395 -98.502216)
		(width 0.15494)
		(layer "In5.Cu")
		(net "PWRGD_NIC1_PWR_GOOD_R")
	)
	(segment
		(start 61.3918 -155.35656)
		(end 61.3918 -106.814366)
		(width 0.15494)
		(layer "In5.Cu")
		(net "PWRGD_NIC1_PWR_GOOD_R")
	)
	(segment
		(start 60.167266 -156.581094)
		(end 61.3918 -155.35656)
		(width 0.15494)
		(layer "In5.Cu")
		(net "PWRGD_NIC1_PWR_GOOD_R")
	)
	(segment
		(start 69.70395 -98.502216)
		(end 69.70395 -96.901)
		(width 0.15494)
		(layer "In5.Cu")
		(net "PWRGD_NIC1_PWR_GOOD_R")
	)
	(segment
		(start 221.916244 -175.48225)
		(end 217.552524 -175.48225)
		(width 0.15494)
		(layer "In15.Cu")
		(net "PWRGD_NIC1_PWR_GOOD_R")
	)
	(segment
		(start 368.52987 -221.8817)
		(end 368.52987 -213.824312)
		(width 0.15494)
		(layer "In15.Cu")
		(net "PWRGD_NIC1_PWR_GOOD_R")
	)
	(segment
		(start 357.794052 -177.563272)
		(end 357.29291 -177.06213)
		(width 0.15494)
		(layer "In15.Cu")
		(net "PWRGD_NIC1_PWR_GOOD_R")
	)
	(segment
		(start 123.605798 -192.037208)
		(end 120.235218 -188.666628)
		(width 0.15494)
		(layer "In15.Cu")
		(net "PWRGD_NIC1_PWR_GOOD_R")
	)
	(segment
		(start 358.333802 -177.563272)
		(end 357.794052 -177.563272)
		(width 0.15494)
		(layer "In15.Cu")
		(net "PWRGD_NIC1_PWR_GOOD_R")
	)
	(segment
		(start 362.397294 -181.617874)
		(end 362.035344 -181.617874)
		(width 0.15494)
		(layer "In15.Cu")
		(net "PWRGD_NIC1_PWR_GOOD_R")
	)
	(segment
		(start 223.790764 -174.488856)
		(end 223.25711 -175.02251)
		(width 0.15494)
		(layer "In15.Cu")
		(net "PWRGD_NIC1_PWR_GOOD_R")
	)
	(segment
		(start 368.492278 -199.427592)
		(end 368.492278 -188.669168)
		(width 0.15494)
		(layer "In15.Cu")
		(net "PWRGD_NIC1_PWR_GOOD_R")
	)
	(segment
		(start 140.872464 -197.104)
		(end 137.747248 -197.104)
		(width 0.15494)
		(layer "In15.Cu")
		(net "PWRGD_NIC1_PWR_GOOD_R")
	)
	(segment
		(start 222.375984 -175.02251)
		(end 221.916244 -175.48225)
		(width 0.15494)
		(layer "In15.Cu")
		(net "PWRGD_NIC1_PWR_GOOD_R")
	)
	(segment
		(start 120.235218 -188.666628)
		(end 114.253772 -188.666628)
		(width 0.15494)
		(layer "In15.Cu")
		(net "PWRGD_NIC1_PWR_GOOD_R")
	)
	(segment
		(start 355.929184 -227.10013)
		(end 357.64978 -227.10013)
		(width 0.15494)
		(layer "In15.Cu")
		(net "PWRGD_NIC1_PWR_GOOD_R")
	)
	(segment
		(start 166.845488 -191.42202)
		(end 146.554444 -191.42202)
		(width 0.15494)
		(layer "In15.Cu")
		(net "PWRGD_NIC1_PWR_GOOD_R")
	)
	(segment
		(start 185.751978 -175.46447)
		(end 185.575956 -175.537368)
		(width 0.15494)
		(layer "In15.Cu")
		(net "PWRGD_NIC1_PWR_GOOD_R")
	)
	(segment
		(start 342.311736 -175.246284)
		(end 282.563316 -175.246284)
		(width 0.15494)
		(layer "In15.Cu")
		(net "PWRGD_NIC1_PWR_GOOD_R")
	)
	(segment
		(start 99.111054 -190.161418)
		(end 96.99625 -188.046614)
		(width 0.15494)
		(layer "In15.Cu")
		(net "PWRGD_NIC1_PWR_GOOD_R")
	)
	(segment
		(start 368.52987 -213.824312)
		(end 368.31778 -213.612222)
		(width 0.15494)
		(layer "In15.Cu")
		(net "PWRGD_NIC1_PWR_GOOD_R")
	)
	(segment
		(start 350.31807 -177.4698)
		(end 349.91675 -177.4698)
		(width 0.15494)
		(layer "In15.Cu")
		(net "PWRGD_NIC1_PWR_GOOD_R")
	)
	(segment
		(start 359.25887 -178.48834)
		(end 358.333802 -177.563272)
		(width 0.15494)
		(layer "In15.Cu")
		(net "PWRGD_NIC1_PWR_GOOD_R")
	)
	(segment
		(start 123.605798 -193.803016)
		(end 123.605798 -192.037208)
		(width 0.15494)
		(layer "In15.Cu")
		(net "PWRGD_NIC1_PWR_GOOD_R")
	)
	(segment
		(start 137.747248 -197.104)
		(end 136.797542 -197.497446)
		(width 0.15494)
		(layer "In15.Cu")
		(net "PWRGD_NIC1_PWR_GOOD_R")
	)
	(segment
		(start 359.25887 -178.8414)
		(end 359.25887 -178.48834)
		(width 0.15494)
		(layer "In15.Cu")
		(net "PWRGD_NIC1_PWR_GOOD_R")
	)
	(segment
		(start 368.31778 -213.612222)
		(end 368.31778 -205.67142)
		(width 0.15494)
		(layer "In15.Cu")
		(net "PWRGD_NIC1_PWR_GOOD_R")
	)
	(segment
		(start 343.692226 -176.626774)
		(end 342.311736 -175.246284)
		(width 0.15494)
		(layer "In15.Cu")
		(net "PWRGD_NIC1_PWR_GOOD_R")
	)
	(segment
		(start 136.797542 -197.497446)
		(end 127.300228 -197.497446)
		(width 0.15494)
		(layer "In15.Cu")
		(net "PWRGD_NIC1_PWR_GOOD_R")
	)
	(segment
		(start 360.922824 -228.06787)
		(end 363.773212 -225.217482)
		(width 0.15494)
		(layer "In15.Cu")
		(net "PWRGD_NIC1_PWR_GOOD_R")
	)
	(segment
		(start 368.848132 -200.184766)
		(end 368.848132 -199.783446)
		(width 0.15494)
		(layer "In15.Cu")
		(net "PWRGD_NIC1_PWR_GOOD_R")
	)
	(segment
		(start 229.690676 -174.488856)
		(end 223.790764 -174.488856)
		(width 0.15494)
		(layer "In15.Cu")
		(net "PWRGD_NIC1_PWR_GOOD_R")
	)
	(segment
		(start 362.035344 -181.617874)
		(end 359.25887 -178.8414)
		(width 0.15494)
		(layer "In15.Cu")
		(net "PWRGD_NIC1_PWR_GOOD_R")
	)
	(segment
		(start 368.07013 -200.962768)
		(end 368.848132 -200.184766)
		(width 0.15494)
		(layer "In15.Cu")
		(net "PWRGD_NIC1_PWR_GOOD_R")
	)
	(segment
		(start 282.563316 -175.246284)
		(end 281.704796 -176.104804)
		(width 0.15494)
		(layer "In15.Cu")
		(net "PWRGD_NIC1_PWR_GOOD_R")
	)
	(segment
		(start 185.575956 -175.537368)
		(end 184.397396 -176.715928)
		(width 0.15494)
		(layer "In15.Cu")
		(net "PWRGD_NIC1_PWR_GOOD_R")
	)
	(segment
		(start 350.72574 -177.06213)
		(end 350.31807 -177.4698)
		(width 0.15494)
		(layer "In15.Cu")
		(net "PWRGD_NIC1_PWR_GOOD_R")
	)
	(segment
		(start 281.704796 -176.104804)
		(end 231.306624 -176.104804)
		(width 0.15494)
		(layer "In15.Cu")
		(net "PWRGD_NIC1_PWR_GOOD_R")
	)
	(segment
		(start 351.293684 -224.386902)
		(end 353.215956 -224.386902)
		(width 0.15494)
		(layer "In15.Cu")
		(net "PWRGD_NIC1_PWR_GOOD_R")
	)
	(segment
		(start 62.224412 -176.8348)
		(end 62.043818 -177.015394)
		(width 0.15494)
		(layer "In15.Cu")
		(net "PWRGD_NIC1_PWR_GOOD_R")
	)
	(segment
		(start 127.300228 -197.497446)
		(end 123.605798 -193.803016)
		(width 0.15494)
		(layer "In15.Cu")
		(net "PWRGD_NIC1_PWR_GOOD_R")
	)
	(segment
		(start 112.758982 -190.161418)
		(end 99.111054 -190.161418)
		(width 0.15494)
		(layer "In15.Cu")
		(net "PWRGD_NIC1_PWR_GOOD_R")
	)
	(segment
		(start 181.190138 -176.715928)
		(end 180.803042 -176.876202)
		(width 0.15494)
		(layer "In15.Cu")
		(net "PWRGD_NIC1_PWR_GOOD_R")
	)
	(segment
		(start 223.25711 -175.02251)
		(end 222.375984 -175.02251)
		(width 0.15494)
		(layer "In15.Cu")
		(net "PWRGD_NIC1_PWR_GOOD_R")
	)
	(segment
		(start 368.31778 -205.67142)
		(end 368.07013 -205.42377)
		(width 0.15494)
		(layer "In15.Cu")
		(net "PWRGD_NIC1_PWR_GOOD_R")
	)
	(segment
		(start 368.848132 -199.783446)
		(end 368.492278 -199.427592)
		(width 0.15494)
		(layer "In15.Cu")
		(net "PWRGD_NIC1_PWR_GOOD_R")
	)
	(segment
		(start 365.194088 -225.217482)
		(end 368.52987 -221.8817)
		(width 0.15494)
		(layer "In15.Cu")
		(net "PWRGD_NIC1_PWR_GOOD_R")
	)
	(segment
		(start 231.306624 -176.104804)
		(end 229.690676 -174.488856)
		(width 0.15494)
		(layer "In15.Cu")
		(net "PWRGD_NIC1_PWR_GOOD_R")
	)
	(segment
		(start 85.784436 -176.8348)
		(end 62.224412 -176.8348)
		(width 0.15494)
		(layer "In15.Cu")
		(net "PWRGD_NIC1_PWR_GOOD_R")
	)
	(segment
		(start 363.773212 -225.217482)
		(end 365.194088 -225.217482)
		(width 0.15494)
		(layer "In15.Cu")
		(net "PWRGD_NIC1_PWR_GOOD_R")
	)
	(segment
		(start 366.58931 -185.80989)
		(end 362.397294 -181.617874)
		(width 0.15494)
		(layer "In15.Cu")
		(net "PWRGD_NIC1_PWR_GOOD_R")
	)
	(segment
		(start 368.07013 -205.42377)
		(end 368.07013 -200.962768)
		(width 0.15494)
		(layer "In15.Cu")
		(net "PWRGD_NIC1_PWR_GOOD_R")
	)
	(segment
		(start 114.253772 -188.666628)
		(end 112.758982 -190.161418)
		(width 0.15494)
		(layer "In15.Cu")
		(net "PWRGD_NIC1_PWR_GOOD_R")
	)
	(segment
		(start 358.61752 -228.06787)
		(end 360.922824 -228.06787)
		(width 0.15494)
		(layer "In15.Cu")
		(net "PWRGD_NIC1_PWR_GOOD_R")
	)
	(segment
		(start 353.215956 -224.386902)
		(end 355.929184 -227.10013)
		(width 0.15494)
		(layer "In15.Cu")
		(net "PWRGD_NIC1_PWR_GOOD_R")
	)
	(segment
		(start 179.801266 -178.466242)
		(end 166.845488 -191.42202)
		(width 0.15494)
		(layer "In15.Cu")
		(net "PWRGD_NIC1_PWR_GOOD_R")
	)
	(segment
		(start 146.554444 -191.42202)
		(end 140.872464 -197.104)
		(width 0.15494)
		(layer "In15.Cu")
		(net "PWRGD_NIC1_PWR_GOOD_R")
	)
	(segment
		(start 96.99625 -188.046614)
		(end 85.784436 -176.8348)
		(width 0.15494)
		(layer "In15.Cu")
		(net "PWRGD_NIC1_PWR_GOOD_R")
	)
	(segment
		(start 349.073724 -176.626774)
		(end 343.692226 -176.626774)
		(width 0.15494)
		(layer "In15.Cu")
		(net "PWRGD_NIC1_PWR_GOOD_R")
	)
	(segment
		(start 179.801266 -177.877978)
		(end 179.801266 -178.466242)
		(width 0.15494)
		(layer "In15.Cu")
		(net "PWRGD_NIC1_PWR_GOOD_R")
	)
	(segment
		(start 184.397396 -176.715928)
		(end 181.190138 -176.715928)
		(width 0.15494)
		(layer "In15.Cu")
		(net "PWRGD_NIC1_PWR_GOOD_R")
	)
	(segment
		(start 357.29291 -177.06213)
		(end 350.72574 -177.06213)
		(width 0.15494)
		(layer "In15.Cu")
		(net "PWRGD_NIC1_PWR_GOOD_R")
	)
	(segment
		(start 368.492278 -188.669168)
		(end 366.58931 -186.7662)
		(width 0.15494)
		(layer "In15.Cu")
		(net "PWRGD_NIC1_PWR_GOOD_R")
	)
	(segment
		(start 217.534744 -175.46447)
		(end 185.751978 -175.46447)
		(width 0.15494)
		(layer "In15.Cu")
		(net "PWRGD_NIC1_PWR_GOOD_R")
	)
	(segment
		(start 366.58931 -186.7662)
		(end 366.58931 -185.80989)
		(width 0.15494)
		(layer "In15.Cu")
		(net "PWRGD_NIC1_PWR_GOOD_R")
	)
	(segment
		(start 217.552524 -175.48225)
		(end 217.534744 -175.46447)
		(width 0.15494)
		(layer "In15.Cu")
		(net "PWRGD_NIC1_PWR_GOOD_R")
	)
	(segment
		(start 349.91675 -177.4698)
		(end 349.073724 -176.626774)
		(width 0.15494)
		(layer "In15.Cu")
		(net "PWRGD_NIC1_PWR_GOOD_R")
	)
	(segment
		(start 180.803042 -176.876202)
		(end 179.801266 -177.877978)
		(width 0.15494)
		(layer "In15.Cu")
		(net "PWRGD_NIC1_PWR_GOOD_R")
	)
	(segment
		(start 357.64978 -227.10013)
		(end 358.61752 -228.06787)
		(width 0.15494)
		(layer "In15.Cu")
		(net "PWRGD_NIC1_PWR_GOOD_R")
	)
	(segment
		(start 230.3653 -81.958434)
		(end 230.3653 -80.690212)
		(width 0.13462)
		(layer "F.Cu")
		(net "USB2_PEX_HUB_DP")
	)
	(segment
		(start 230.673402 -80.38211)
		(end 230.673402 -79.887318)
		(width 0.13462)
		(layer "F.Cu")
		(net "USB2_PEX_HUB_DP")
	)
	(segment
		(start 230.72979 -79.83093)
		(end 230.72979 -79.465678)
		(width 0.13462)
		(layer "F.Cu")
		(net "USB2_PEX_HUB_DP")
	)
	(segment
		(start 230.3653 -80.690212)
		(end 230.673402 -80.38211)
		(width 0.13462)
		(layer "F.Cu")
		(net "USB2_PEX_HUB_DP")
	)
	(segment
		(start 230.673402 -79.887318)
		(end 230.72979 -79.83093)
		(width 0.13462)
		(layer "F.Cu")
		(net "USB2_PEX_HUB_DP")
	)
	(segment
		(start 230.3653 -86.13775)
		(end 230.660956 -86.433406)
		(width 0.13462)
		(layer "F.Cu")
		(net "USB2_PEX_HUB_DP")
	)
	(segment
		(start 230.3653 -81.958434)
		(end 230.3653 -86.13775)
		(width 0.13462)
		(layer "F.Cu")
		(net "USB2_PEX_HUB_DP")
	)
	(via
		(at 230.3653 -81.958434)
		(size 0.4064)
		(drill 0.2032)
		(layers "F.Cu" "B.Cu")
		(net "USB2_PEX_HUB_DP")
	)
	(segment
		(start 240.6904 -166.9034)
		(end 239.6744 -165.8874)
		(width 0.13208)
		(layer "F.Cu")
		(net "SMB_NIC5_LS_SCL")
	)
	(segment
		(start 267.883894 -156.2354)
		(end 267.883894 -163.408106)
		(width 0.13208)
		(layer "F.Cu")
		(net "SMB_NIC5_LS_SCL")
	)
	(segment
		(start 269.580868 -155.008326)
		(end 269.110968 -155.008326)
		(width 0.13208)
		(layer "F.Cu")
		(net "SMB_NIC5_LS_SCL")
	)
	(segment
		(start 267.883894 -163.408106)
		(end 264.3886 -166.9034)
		(width 0.13208)
		(layer "F.Cu")
		(net "SMB_NIC5_LS_SCL")
	)
	(segment
		(start 300.857412 -112.834928)
		(end 299.582586 -112.834928)
		(width 0.13208)
		(layer "F.Cu")
		(net "SMB_NIC5_LS_SCL")
	)
	(segment
		(start 239.6744 -165.8874)
		(end 221.056454 -165.8874)
		(width 0.13208)
		(layer "F.Cu")
		(net "SMB_NIC5_LS_SCL")
	)
	(segment
		(start 264.3886 -166.9034)
		(end 240.6904 -166.9034)
		(width 0.13208)
		(layer "F.Cu")
		(net "SMB_NIC5_LS_SCL")
	)
	(segment
		(start 219.93733 -167.006524)
		(end 216.911428 -167.006524)
		(width 0.13208)
		(layer "F.Cu")
		(net "SMB_NIC5_LS_SCL")
	)
	(segment
		(start 269.110968 -155.008326)
		(end 267.883894 -156.2354)
		(width 0.13208)
		(layer "F.Cu")
		(net "SMB_NIC5_LS_SCL")
	)
	(segment
		(start 221.056454 -165.8874)
		(end 219.93733 -167.006524)
		(width 0.13208)
		(layer "F.Cu")
		(net "SMB_NIC5_LS_SCL")
	)
	(segment
		(start 299.582586 -112.834928)
		(end 299.233082 -112.485424)
		(width 0.13208)
		(layer "F.Cu")
		(net "SMB_NIC5_LS_SCL")
	)
	(via
		(at 299.233082 -112.485424)
		(size 0.508)
		(drill 0.254)
		(layers "F.Cu" "B.Cu")
		(net "SMB_NIC5_LS_SCL")
	)
	(via
		(at 216.911428 -167.006524)
		(size 0.508)
		(drill 0.254)
		(layers "F.Cu" "B.Cu")
		(net "SMB_NIC5_LS_SCL")
	)
	(via
		(at 269.580868 -155.008326)
		(size 0.508)
		(drill 0.254)
		(layers "F.Cu" "B.Cu")
		(net "SMB_NIC5_LS_SCL")
	)
	(via
		(at 285.16707 -149.48281)
		(size 0.508)
		(drill 0.254)
		(layers "F.Cu" "B.Cu")
		(net "SMB_NIC5_LS_SCL")
	)
	(via
		(at 215.773 -201.803)
		(size 0.508)
		(drill 0.254)
		(layers "F.Cu" "B.Cu")
		(net "SMB_NIC5_LS_SCL")
	)
	(segment
		(start 300.408594 -112.485424)
		(end 299.233082 -112.485424)
		(width 0.13208)
		(layer "B.Cu")
		(net "SMB_NIC5_LS_SCL")
	)
	(segment
		(start 215.773 -201.803)
		(end 215.011 -201.803)
		(width 0.13208)
		(layer "B.Cu")
		(net "SMB_NIC5_LS_SCL")
	)
	(segment
		(start 300.472094 -112.421924)
		(end 300.408594 -112.485424)
		(width 0.13208)
		(layer "B.Cu")
		(net "SMB_NIC5_LS_SCL")
	)
	(segment
		(start 215.011 -201.803)
		(end 214.503 -202.311)
		(width 0.13208)
		(layer "B.Cu")
		(net "SMB_NIC5_LS_SCL")
	)
	(segment
		(start 213.46795 -202.311)
		(end 213.106 -201.94905)
		(width 0.13208)
		(layer "B.Cu")
		(net "SMB_NIC5_LS_SCL")
	)
	(segment
		(start 214.503 -202.311)
		(end 213.46795 -202.311)
		(width 0.13208)
		(layer "B.Cu")
		(net "SMB_NIC5_LS_SCL")
	)
	(segment
		(start 299.233082 -111.603536)
		(end 299.233082 -112.485424)
		(width 0.15494)
		(layer "In5.Cu")
		(net "SMB_NIC5_LS_SCL")
	)
	(segment
		(start 290.9062 -112.505998)
		(end 293.404798 -110.0074)
		(width 0.15494)
		(layer "In5.Cu")
		(net "SMB_NIC5_LS_SCL")
	)
	(segment
		(start 297.636946 -110.0074)
		(end 299.233082 -111.603536)
		(width 0.15494)
		(layer "In5.Cu")
		(net "SMB_NIC5_LS_SCL")
	)
	(segment
		(start 290.9062 -143.74368)
		(end 290.9062 -112.505998)
		(width 0.15494)
		(layer "In5.Cu")
		(net "SMB_NIC5_LS_SCL")
	)
	(segment
		(start 285.16707 -149.48281)
		(end 290.9062 -143.74368)
		(width 0.15494)
		(layer "In5.Cu")
		(net "SMB_NIC5_LS_SCL")
	)
	(segment
		(start 293.404798 -110.0074)
		(end 297.636946 -110.0074)
		(width 0.15494)
		(layer "In5.Cu")
		(net "SMB_NIC5_LS_SCL")
	)
	(segment
		(start 217.20048 -198.5264)
		(end 217.20048 -190.185294)
		(width 0.15494)
		(layer "In7.Cu")
		(net "SMB_NIC5_LS_SCL")
	)
	(segment
		(start 215.773 -201.803)
		(end 215.773 -199.95388)
		(width 0.15494)
		(layer "In7.Cu")
		(net "SMB_NIC5_LS_SCL")
	)
	(segment
		(start 217.01252 -185.547)
		(end 217.01252 -184.785)
		(width 0.15494)
		(layer "In7.Cu")
		(net "SMB_NIC5_LS_SCL")
	)
	(segment
		(start 215.24976 -177.87112)
		(end 215.24976 -169.241216)
		(width 0.15494)
		(layer "In7.Cu")
		(net "SMB_NIC5_LS_SCL")
	)
	(segment
		(start 217.01252 -184.785)
		(end 215.85174 -183.62422)
		(width 0.15494)
		(layer "In7.Cu")
		(net "SMB_NIC5_LS_SCL")
	)
	(segment
		(start 217.20048 -190.185294)
		(end 217.752676 -189.633098)
		(width 0.15494)
		(layer "In7.Cu")
		(net "SMB_NIC5_LS_SCL")
	)
	(segment
		(start 217.752676 -186.287156)
		(end 217.01252 -185.547)
		(width 0.15494)
		(layer "In7.Cu")
		(net "SMB_NIC5_LS_SCL")
	)
	(segment
		(start 215.773 -199.95388)
		(end 217.20048 -198.5264)
		(width 0.15494)
		(layer "In7.Cu")
		(net "SMB_NIC5_LS_SCL")
	)
	(segment
		(start 215.85174 -183.62422)
		(end 215.85174 -178.4731)
		(width 0.15494)
		(layer "In7.Cu")
		(net "SMB_NIC5_LS_SCL")
	)
	(segment
		(start 217.752676 -189.633098)
		(end 217.752676 -186.287156)
		(width 0.15494)
		(layer "In7.Cu")
		(net "SMB_NIC5_LS_SCL")
	)
	(segment
		(start 215.85174 -178.4731)
		(end 215.24976 -177.87112)
		(width 0.15494)
		(layer "In7.Cu")
		(net "SMB_NIC5_LS_SCL")
	)
	(segment
		(start 216.911428 -167.579548)
		(end 216.911428 -167.006524)
		(width 0.15494)
		(layer "In7.Cu")
		(net "SMB_NIC5_LS_SCL")
	)
	(segment
		(start 215.24976 -169.241216)
		(end 216.911428 -167.579548)
		(width 0.15494)
		(layer "In7.Cu")
		(net "SMB_NIC5_LS_SCL")
	)
	(segment
		(start 275.935694 -149.48281)
		(end 270.410178 -155.008326)
		(width 0.15494)
		(layer "In15.Cu")
		(net "SMB_NIC5_LS_SCL")
	)
	(segment
		(start 270.410178 -155.008326)
		(end 269.580868 -155.008326)
		(width 0.15494)
		(layer "In15.Cu")
		(net "SMB_NIC5_LS_SCL")
	)
	(segment
		(start 285.16707 -149.48281)
		(end 275.935694 -149.48281)
		(width 0.15494)
		(layer "In15.Cu")
		(net "SMB_NIC5_LS_SCL")
	)
	(segment
		(start 222.5548 -22.561296)
		(end 222.5548 -21.847048)
		(width 0.13208)
		(layer "F.Cu")
		(net "SMB_SSD7_ISO_EN")
	)
	(segment
		(start 222.5548 -21.847048)
		(end 221.760542 -21.05279)
		(width 0.13208)
		(layer "F.Cu")
		(net "SMB_SSD7_ISO_EN")
	)
	(segment
		(start 221.760542 -21.05279)
		(end 221.760542 -20.789392)
		(width 0.13208)
		(layer "F.Cu")
		(net "SMB_SSD7_ISO_EN")
	)
	(via
		(at 222.5548 -21.847048)
		(size 0.508)
		(drill 0.254)
		(layers "F.Cu" "B.Cu")
		(net "SMB_SSD7_ISO_EN")
	)
	(segment
		(start 409.326588 -391.239756)
		(end 410.274516 -391.239756)
		(width 0.13208)
		(layer "F.Cu")
		(net "GPU_BB_RSVD_1")
	)
	(segment
		(start 408.096212 -390.990836)
		(end 408.345132 -391.239756)
		(width 0.13208)
		(layer "F.Cu")
		(net "GPU_BB_RSVD_1")
	)
	(segment
		(start 408.345132 -391.239756)
		(end 409.326588 -391.239756)
		(width 0.13208)
		(layer "F.Cu")
		(net "GPU_BB_RSVD_1")
	)
	(segment
		(start 410.274516 -391.239756)
		(end 410.51734 -390.996932)
		(width 0.13208)
		(layer "F.Cu")
		(net "GPU_BB_RSVD_1")
	)
	(via
		(at 409.326588 -391.239756)
		(size 0.762)
		(drill 0.381)
		(layers "F.Cu" "B.Cu")
		(net "GPU_BB_RSVD_1")
	)
	(segment
		(start 350.893888 -223.187006)
		(end 351.293684 -223.586802)
		(width 0.13208)
		(layer "F.Cu")
		(net "NIC1_MAIN_PWR_EN")
	)
	(via
		(at 64.677036 -177.353214)
		(size 0.508)
		(drill 0.254)
		(layers "F.Cu" "B.Cu")
		(net "NIC1_MAIN_PWR_EN")
	)
	(via
		(at 70.50405 -100.351336)
		(size 0.508)
		(drill 0.254)
		(layers "F.Cu" "B.Cu")
		(net "NIC1_MAIN_PWR_EN")
	)
	(via
		(at 351.293684 -223.586802)
		(size 0.4572)
		(drill 0.254)
		(layers "F.Cu" "B.Cu")
		(net "NIC1_MAIN_PWR_EN")
	)
	(segment
		(start 71.35495 -98.552)
		(end 70.50405 -98.552)
		(width 0.13208)
		(layer "B.Cu")
		(net "NIC1_MAIN_PWR_EN")
	)
	(segment
		(start 70.50405 -98.552)
		(end 70.50405 -100.351336)
		(width 0.13208)
		(layer "B.Cu")
		(net "NIC1_MAIN_PWR_EN")
	)
	(segment
		(start 60.525406 -174.415704)
		(end 60.525406 -156.729684)
		(width 0.15494)
		(layer "In5.Cu")
		(net "NIC1_MAIN_PWR_EN")
	)
	(segment
		(start 63.462916 -177.353214)
		(end 60.525406 -174.415704)
		(width 0.15494)
		(layer "In5.Cu")
		(net "NIC1_MAIN_PWR_EN")
	)
	(segment
		(start 61.8236 -155.43149)
		(end 61.8236 -107.244388)
		(width 0.15494)
		(layer "In5.Cu")
		(net "NIC1_MAIN_PWR_EN")
	)
	(segment
		(start 68.716652 -100.351336)
		(end 70.50405 -100.351336)
		(width 0.15494)
		(layer "In5.Cu")
		(net "NIC1_MAIN_PWR_EN")
	)
	(segment
		(start 61.8236 -107.244388)
		(end 68.716652 -100.351336)
		(width 0.15494)
		(layer "In5.Cu")
		(net "NIC1_MAIN_PWR_EN")
	)
	(segment
		(start 64.677036 -177.353214)
		(end 63.462916 -177.353214)
		(width 0.15494)
		(layer "In5.Cu")
		(net "NIC1_MAIN_PWR_EN")
	)
	(segment
		(start 60.525406 -156.729684)
		(end 61.8236 -155.43149)
		(width 0.15494)
		(layer "In5.Cu")
		(net "NIC1_MAIN_PWR_EN")
	)
	(segment
		(start 282.648914 -178.80457)
		(end 282.994354 -178.45913)
		(width 0.15494)
		(layer "In15.Cu")
		(net "NIC1_MAIN_PWR_EN")
	)
	(segment
		(start 363.154468 -188.479938)
		(end 363.154468 -189.261242)
		(width 0.15494)
		(layer "In15.Cu")
		(net "NIC1_MAIN_PWR_EN")
	)
	(segment
		(start 362.31322 -224.198942)
		(end 360.476292 -226.03587)
		(width 0.15494)
		(layer "In15.Cu")
		(net "NIC1_MAIN_PWR_EN")
	)
	(segment
		(start 227.893626 -178.028854)
		(end 229.079552 -179.21478)
		(width 0.15494)
		(layer "In15.Cu")
		(net "NIC1_MAIN_PWR_EN")
	)
	(segment
		(start 145.92808 -193.88836)
		(end 148.03628 -191.78016)
		(width 0.15494)
		(layer "In15.Cu")
		(net "NIC1_MAIN_PWR_EN")
	)
	(segment
		(start 183.651144 -178.804062)
		(end 186.755278 -177.518314)
		(width 0.15494)
		(layer "In15.Cu")
		(net "NIC1_MAIN_PWR_EN")
	)
	(segment
		(start 282.994354 -178.45913)
		(end 341.413084 -178.45913)
		(width 0.15494)
		(layer "In15.Cu")
		(net "NIC1_MAIN_PWR_EN")
	)
	(segment
		(start 358.62387 -184.3024)
		(end 360.0196 -185.69813)
		(width 0.15494)
		(layer "In15.Cu")
		(net "NIC1_MAIN_PWR_EN")
	)
	(segment
		(start 242.909598 -178.80457)
		(end 282.648914 -178.80457)
		(width 0.15494)
		(layer "In15.Cu")
		(net "NIC1_MAIN_PWR_EN")
	)
	(segment
		(start 85.557614 -177.353214)
		(end 98.7298 -190.5254)
		(width 0.15494)
		(layer "In15.Cu")
		(net "NIC1_MAIN_PWR_EN")
	)
	(segment
		(start 215.007952 -177.37074)
		(end 215.057228 -177.420016)
		(width 0.15494)
		(layer "In15.Cu")
		(net "NIC1_MAIN_PWR_EN")
	)
	(segment
		(start 365.487458 -218.458542)
		(end 363.75213 -220.19387)
		(width 0.15494)
		(layer "In15.Cu")
		(net "NIC1_MAIN_PWR_EN")
	)
	(segment
		(start 141.591792 -197.554342)
		(end 142.370302 -196.775832)
		(width 0.15494)
		(layer "In15.Cu")
		(net "NIC1_MAIN_PWR_EN")
	)
	(segment
		(start 98.7298 -190.5254)
		(end 112.979454 -190.5254)
		(width 0.15494)
		(layer "In15.Cu")
		(net "NIC1_MAIN_PWR_EN")
	)
	(segment
		(start 114.480086 -189.024768)
		(end 120.002554 -189.024768)
		(width 0.15494)
		(layer "In15.Cu")
		(net "NIC1_MAIN_PWR_EN")
	)
	(segment
		(start 145.92808 -194.544188)
		(end 145.92808 -193.88836)
		(width 0.15494)
		(layer "In15.Cu")
		(net "NIC1_MAIN_PWR_EN")
	)
	(segment
		(start 360.476292 -226.03587)
		(end 358.815132 -226.03587)
		(width 0.15494)
		(layer "In15.Cu")
		(net "NIC1_MAIN_PWR_EN")
	)
	(segment
		(start 215.057228 -177.420016)
		(end 221.77375 -177.420016)
		(width 0.15494)
		(layer "In15.Cu")
		(net "NIC1_MAIN_PWR_EN")
	)
	(segment
		(start 143.696436 -196.775832)
		(end 145.92808 -194.544188)
		(width 0.15494)
		(layer "In15.Cu")
		(net "NIC1_MAIN_PWR_EN")
	)
	(segment
		(start 358.815132 -226.03587)
		(end 356.366064 -223.586802)
		(width 0.15494)
		(layer "In15.Cu")
		(net "NIC1_MAIN_PWR_EN")
	)
	(segment
		(start 348.643956 -180.965348)
		(end 355.639878 -180.965348)
		(width 0.15494)
		(layer "In15.Cu")
		(net "NIC1_MAIN_PWR_EN")
	)
	(segment
		(start 123.180856 -192.20307)
		(end 123.180856 -193.884804)
		(width 0.15494)
		(layer "In15.Cu")
		(net "NIC1_MAIN_PWR_EN")
	)
	(segment
		(start 136.586468 -197.91934)
		(end 137.263378 -197.78472)
		(width 0.15494)
		(layer "In15.Cu")
		(net "NIC1_MAIN_PWR_EN")
	)
	(segment
		(start 221.77375 -177.420016)
		(end 222.382588 -178.028854)
		(width 0.15494)
		(layer "In15.Cu")
		(net "NIC1_MAIN_PWR_EN")
	)
	(segment
		(start 123.180856 -193.884804)
		(end 127.215392 -197.91934)
		(width 0.15494)
		(layer "In15.Cu")
		(net "NIC1_MAIN_PWR_EN")
	)
	(segment
		(start 364.43666 -190.513462)
		(end 365.487458 -191.56426)
		(width 0.15494)
		(layer "In15.Cu")
		(net "NIC1_MAIN_PWR_EN")
	)
	(segment
		(start 364.406688 -190.513462)
		(end 364.43666 -190.513462)
		(width 0.15494)
		(layer "In15.Cu")
		(net "NIC1_MAIN_PWR_EN")
	)
	(segment
		(start 355.639878 -180.965348)
		(end 358.62387 -183.94934)
		(width 0.15494)
		(layer "In15.Cu")
		(net "NIC1_MAIN_PWR_EN")
	)
	(segment
		(start 186.902852 -177.37074)
		(end 215.007952 -177.37074)
		(width 0.15494)
		(layer "In15.Cu")
		(net "NIC1_MAIN_PWR_EN")
	)
	(segment
		(start 229.079552 -179.21478)
		(end 229.551738 -179.21478)
		(width 0.15494)
		(layer "In15.Cu")
		(net "NIC1_MAIN_PWR_EN")
	)
	(segment
		(start 229.551738 -179.21478)
		(end 229.69601 -179.070508)
		(width 0.15494)
		(layer "In15.Cu")
		(net "NIC1_MAIN_PWR_EN")
	)
	(segment
		(start 148.03628 -191.78016)
		(end 170.631866 -191.78016)
		(width 0.15494)
		(layer "In15.Cu")
		(net "NIC1_MAIN_PWR_EN")
	)
	(segment
		(start 360.0196 -185.69813)
		(end 360.37266 -185.69813)
		(width 0.15494)
		(layer "In15.Cu")
		(net "NIC1_MAIN_PWR_EN")
	)
	(segment
		(start 346.595446 -178.916838)
		(end 348.643956 -180.965348)
		(width 0.15494)
		(layer "In15.Cu")
		(net "NIC1_MAIN_PWR_EN")
	)
	(segment
		(start 229.69601 -179.070508)
		(end 242.64366 -179.070508)
		(width 0.15494)
		(layer "In15.Cu")
		(net "NIC1_MAIN_PWR_EN")
	)
	(segment
		(start 358.62387 -183.94934)
		(end 358.62387 -184.3024)
		(width 0.15494)
		(layer "In15.Cu")
		(net "NIC1_MAIN_PWR_EN")
	)
	(segment
		(start 363.75213 -220.19387)
		(end 362.31322 -223.66732)
		(width 0.15494)
		(layer "In15.Cu")
		(net "NIC1_MAIN_PWR_EN")
	)
	(segment
		(start 112.979454 -190.5254)
		(end 114.480086 -189.024768)
		(width 0.15494)
		(layer "In15.Cu")
		(net "NIC1_MAIN_PWR_EN")
	)
	(segment
		(start 64.677036 -177.353214)
		(end 85.557614 -177.353214)
		(width 0.15494)
		(layer "In15.Cu")
		(net "NIC1_MAIN_PWR_EN")
	)
	(segment
		(start 360.37266 -185.69813)
		(end 363.154468 -188.479938)
		(width 0.15494)
		(layer "In15.Cu")
		(net "NIC1_MAIN_PWR_EN")
	)
	(segment
		(start 242.64366 -179.070508)
		(end 242.909598 -178.80457)
		(width 0.15494)
		(layer "In15.Cu")
		(net "NIC1_MAIN_PWR_EN")
	)
	(segment
		(start 356.366064 -223.586802)
		(end 351.293684 -223.586802)
		(width 0.15494)
		(layer "In15.Cu")
		(net "NIC1_MAIN_PWR_EN")
	)
	(segment
		(start 183.607964 -178.804062)
		(end 183.651144 -178.804062)
		(width 0.15494)
		(layer "In15.Cu")
		(net "NIC1_MAIN_PWR_EN")
	)
	(segment
		(start 186.755278 -177.518314)
		(end 186.902852 -177.37074)
		(width 0.15494)
		(layer "In15.Cu")
		(net "NIC1_MAIN_PWR_EN")
	)
	(segment
		(start 127.215392 -197.91934)
		(end 136.586468 -197.91934)
		(width 0.15494)
		(layer "In15.Cu")
		(net "NIC1_MAIN_PWR_EN")
	)
	(segment
		(start 222.382588 -178.028854)
		(end 227.893626 -178.028854)
		(width 0.15494)
		(layer "In15.Cu")
		(net "NIC1_MAIN_PWR_EN")
	)
	(segment
		(start 142.370302 -196.775832)
		(end 143.696436 -196.775832)
		(width 0.15494)
		(layer "In15.Cu")
		(net "NIC1_MAIN_PWR_EN")
	)
	(segment
		(start 363.154468 -189.261242)
		(end 364.406688 -190.513462)
		(width 0.15494)
		(layer "In15.Cu")
		(net "NIC1_MAIN_PWR_EN")
	)
	(segment
		(start 341.870792 -178.916838)
		(end 346.595446 -178.916838)
		(width 0.15494)
		(layer "In15.Cu")
		(net "NIC1_MAIN_PWR_EN")
	)
	(segment
		(start 170.631866 -191.78016)
		(end 183.607964 -178.804062)
		(width 0.15494)
		(layer "In15.Cu")
		(net "NIC1_MAIN_PWR_EN")
	)
	(segment
		(start 365.487458 -191.56426)
		(end 365.487458 -218.458542)
		(width 0.15494)
		(layer "In15.Cu")
		(net "NIC1_MAIN_PWR_EN")
	)
	(segment
		(start 341.413084 -178.45913)
		(end 341.870792 -178.916838)
		(width 0.15494)
		(layer "In15.Cu")
		(net "NIC1_MAIN_PWR_EN")
	)
	(segment
		(start 362.31322 -223.66732)
		(end 362.31322 -224.198942)
		(width 0.15494)
		(layer "In15.Cu")
		(net "NIC1_MAIN_PWR_EN")
	)
	(segment
		(start 120.002554 -189.024768)
		(end 123.180856 -192.20307)
		(width 0.15494)
		(layer "In15.Cu")
		(net "NIC1_MAIN_PWR_EN")
	)
	(segment
		(start 137.263378 -197.78472)
		(end 137.819384 -197.554342)
		(width 0.15494)
		(layer "In15.Cu")
		(net "NIC1_MAIN_PWR_EN")
	)
	(segment
		(start 137.819384 -197.554342)
		(end 141.591792 -197.554342)
		(width 0.15494)
		(layer "In15.Cu")
		(net "NIC1_MAIN_PWR_EN")
	)
	(segment
		(start 124.07519 -99.928934)
		(end 124.07519 -99.463606)
		(width 0.13208)
		(layer "F.Cu")
		(net "BIC_I2C9_SSD_MUX0_A0")
	)
	(segment
		(start 126.432564 -97.74047)
		(end 127.462534 -97.74047)
		(width 0.13208)
		(layer "F.Cu")
		(net "BIC_I2C9_SSD_MUX0_A0")
	)
	(segment
		(start 124.787406 -99.463606)
		(end 125.681486 -99.463606)
		(width 0.13208)
		(layer "F.Cu")
		(net "BIC_I2C9_SSD_MUX0_A0")
	)
	(segment
		(start 126.258828 -97.914206)
		(end 126.432564 -97.74047)
		(width 0.13208)
		(layer "F.Cu")
		(net "BIC_I2C9_SSD_MUX0_A0")
	)
	(segment
		(start 124.07519 -99.463606)
		(end 124.787406 -99.463606)
		(width 0.13208)
		(layer "F.Cu")
		(net "BIC_I2C9_SSD_MUX0_A0")
	)
	(segment
		(start 123.899168 -100.104956)
		(end 124.07519 -99.928934)
		(width 0.13208)
		(layer "F.Cu")
		(net "BIC_I2C9_SSD_MUX0_A0")
	)
	(segment
		(start 121.53519 -99.463606)
		(end 122.17654 -100.104956)
		(width 0.13208)
		(layer "F.Cu")
		(net "BIC_I2C9_SSD_MUX0_A0")
	)
	(segment
		(start 125.681486 -99.463606)
		(end 126.258828 -98.886264)
		(width 0.13208)
		(layer "F.Cu")
		(net "BIC_I2C9_SSD_MUX0_A0")
	)
	(segment
		(start 126.258828 -98.886264)
		(end 126.258828 -97.914206)
		(width 0.13208)
		(layer "F.Cu")
		(net "BIC_I2C9_SSD_MUX0_A0")
	)
	(segment
		(start 122.17654 -100.104956)
		(end 123.899168 -100.104956)
		(width 0.13208)
		(layer "F.Cu")
		(net "BIC_I2C9_SSD_MUX0_A0")
	)
	(via
		(at 124.787406 -99.463606)
		(size 0.508)
		(drill 0.254)
		(layers "F.Cu" "B.Cu")
		(net "BIC_I2C9_SSD_MUX0_A0")
	)
	(segment
		(start 220.385386 -16.439388)
		(end 220.385386 -18.450814)
		(width 0.13208)
		(layer "F.Cu")
		(net "SMB_ISO_SSD7_SCL")
	)
	(segment
		(start 220.559376 -23.355554)
		(end 220.559376 -23.965154)
		(width 0.13208)
		(layer "F.Cu")
		(net "SMB_ISO_SSD7_SCL")
	)
	(segment
		(start 217.356436 -17.419574)
		(end 217.356436 -17.669256)
		(width 0.13208)
		(layer "F.Cu")
		(net "SMB_ISO_SSD7_SCL")
	)
	(segment
		(start 220.385386 -16.439388)
		(end 220.385386 -15.370302)
		(width 0.13208)
		(layer "F.Cu")
		(net "SMB_ISO_SSD7_SCL")
	)
	(segment
		(start 220.385386 -18.450814)
		(end 219.845382 -18.990818)
		(width 0.13208)
		(layer "F.Cu")
		(net "SMB_ISO_SSD7_SCL")
	)
	(segment
		(start 218.124278 -18.437098)
		(end 218.167966 -18.437098)
		(width 0.13208)
		(layer "F.Cu")
		(net "SMB_ISO_SSD7_SCL")
	)
	(segment
		(start 217.356436 -17.669256)
		(end 218.124278 -18.437098)
		(width 0.13208)
		(layer "F.Cu")
		(net "SMB_ISO_SSD7_SCL")
	)
	(segment
		(start 219.845382 -18.990818)
		(end 218.721686 -18.990818)
		(width 0.13208)
		(layer "F.Cu")
		(net "SMB_ISO_SSD7_SCL")
	)
	(segment
		(start 218.721686 -18.990818)
		(end 218.167966 -18.437098)
		(width 0.13208)
		(layer "F.Cu")
		(net "SMB_ISO_SSD7_SCL")
	)
	(via
		(at 220.559376 -23.965154)
		(size 0.508)
		(drill 0.254)
		(layers "F.Cu" "B.Cu")
		(net "SMB_ISO_SSD7_SCL")
	)
	(via
		(at 220.385386 -15.370302)
		(size 0.508)
		(drill 0.254)
		(layers "F.Cu" "B.Cu")
		(net "SMB_ISO_SSD7_SCL")
	)
	(segment
		(start 220.385386 -15.370302)
		(end 221.901766 -16.886682)
		(width 0.13208)
		(layer "B.Cu")
		(net "SMB_ISO_SSD7_SCL")
	)
	(segment
		(start 221.901766 -16.886682)
		(end 221.901766 -22.622764)
		(width 0.13208)
		(layer "B.Cu")
		(net "SMB_ISO_SSD7_SCL")
	)
	(segment
		(start 221.901766 -22.622764)
		(end 220.559376 -23.965154)
		(width 0.13208)
		(layer "B.Cu")
		(net "SMB_ISO_SSD7_SCL")
	)
	(segment
		(start 93.06814 -395.674088)
		(end 92.697808 -394.780008)
		(width 0.1651)
		(layer "In11.Cu")
		(net "P2E_GPU_FPGA_PEX_TX_DN<0>")
	)
	(segment
		(start 47.263812 -410.077158)
		(end 47.58309 -410.077158)
		(width 0.1651)
		(layer "In11.Cu")
		(net "P2E_GPU_FPGA_PEX_TX_DN<0>")
	)
	(segment
		(start 46.993556 -394.687552)
		(end 46.547024 -395.766036)
		(width 0.1651)
		(layer "In11.Cu")
		(net "P2E_GPU_FPGA_PEX_TX_DN<0>")
	)
	(segment
		(start 47.71009 -410.204158)
		(end 47.71009 -410.589984)
		(width 0.1651)
		(layer "In11.Cu")
		(net "P2E_GPU_FPGA_PEX_TX_DN<0>")
	)
	(segment
		(start 46.547024 -395.766036)
		(end 46.547024 -409.36037)
		(width 0.1651)
		(layer "In11.Cu")
		(net "P2E_GPU_FPGA_PEX_TX_DN<0>")
	)
	(segment
		(start 51.990244 -392.610086)
		(end 46.993556 -394.687552)
		(width 0.1651)
		(layer "In11.Cu")
		(net "P2E_GPU_FPGA_PEX_TX_DN<0>")
	)
	(segment
		(start 46.547024 -409.36037)
		(end 47.263812 -410.077158)
		(width 0.1651)
		(layer "In11.Cu")
		(net "P2E_GPU_FPGA_PEX_TX_DN<0>")
	)
	(segment
		(start 91.710002 -410.204158)
		(end 91.837002 -410.077158)
		(width 0.1651)
		(layer "In11.Cu")
		(net "P2E_GPU_FPGA_PEX_TX_DN<0>")
	)
	(segment
		(start 92.131896 -410.077158)
		(end 93.06814 -409.140914)
		(width 0.1651)
		(layer "In11.Cu")
		(net "P2E_GPU_FPGA_PEX_TX_DN<0>")
	)
	(segment
		(start 92.697808 -394.780008)
		(end 91.043506 -393.125706)
		(width 0.1651)
		(layer "In11.Cu")
		(net "P2E_GPU_FPGA_PEX_TX_DN<0>")
	)
	(segment
		(start 91.710002 -410.589984)
		(end 91.710002 -410.204158)
		(width 0.1651)
		(layer "In11.Cu")
		(net "P2E_GPU_FPGA_PEX_TX_DN<0>")
	)
	(segment
		(start 91.837002 -410.077158)
		(end 92.131896 -410.077158)
		(width 0.1651)
		(layer "In11.Cu")
		(net "P2E_GPU_FPGA_PEX_TX_DN<0>")
	)
	(segment
		(start 47.58309 -410.077158)
		(end 47.71009 -410.204158)
		(width 0.1651)
		(layer "In11.Cu")
		(net "P2E_GPU_FPGA_PEX_TX_DN<0>")
	)
	(segment
		(start 93.06814 -409.140914)
		(end 93.06814 -395.674088)
		(width 0.1651)
		(layer "In11.Cu")
		(net "P2E_GPU_FPGA_PEX_TX_DN<0>")
	)
	(segment
		(start 64.413892 -392.552428)
		(end 64.409574 -392.552428)
		(width 0.1651)
		(layer "In11.Cu")
		(net "P2E_GPU_FPGA_PEX_TX_DN<0>")
	)
	(segment
		(start 88.48217 -392.414506)
		(end 64.413892 -392.552428)
		(width 0.1651)
		(layer "In11.Cu")
		(net "P2E_GPU_FPGA_PEX_TX_DN<0>")
	)
	(segment
		(start 64.409574 -392.552428)
		(end 54.405784 -392.610086)
		(width 0.1651)
		(layer "In11.Cu")
		(net "P2E_GPU_FPGA_PEX_TX_DN<0>")
	)
	(segment
		(start 54.405784 -392.610086)
		(end 51.990244 -392.610086)
		(width 0.1651)
		(layer "In11.Cu")
		(net "P2E_GPU_FPGA_PEX_TX_DN<0>")
	)
	(segment
		(start 91.043506 -393.125706)
		(end 90.242644 -392.825478)
		(width 0.1651)
		(layer "In11.Cu")
		(net "P2E_GPU_FPGA_PEX_TX_DN<0>")
	)
	(segment
		(start 90.242644 -392.825478)
		(end 88.48217 -392.414506)
		(width 0.1651)
		(layer "In11.Cu")
		(net "P2E_GPU_FPGA_PEX_TX_DN<0>")
	)
	(segment
		(start 346.893896 -221.58706)
		(end 347.293692 -221.986856)
		(width 0.13208)
		(layer "F.Cu")
		(net "NIC3_MAIN_PWR_EN")
	)
	(via
		(at 347.293692 -221.986856)
		(size 0.4572)
		(drill 0.254)
		(layers "F.Cu" "B.Cu")
		(net "NIC3_MAIN_PWR_EN")
	)
	(via
		(at 186.603894 -99.982782)
		(size 0.508)
		(drill 0.254)
		(layers "F.Cu" "B.Cu")
		(net "NIC3_MAIN_PWR_EN")
	)
	(via
		(at 207.849978 -183.932576)
		(size 0.508)
		(drill 0.254)
		(layers "F.Cu" "B.Cu")
		(net "NIC3_MAIN_PWR_EN")
	)
	(segment
		(start 187.454794 -98.552)
		(end 186.603894 -98.552)
		(width 0.13208)
		(layer "B.Cu")
		(net "NIC3_MAIN_PWR_EN")
	)
	(segment
		(start 186.603894 -98.552)
		(end 186.603894 -99.982782)
		(width 0.13208)
		(layer "B.Cu")
		(net "NIC3_MAIN_PWR_EN")
	)
	(segment
		(start 207.849978 -183.932576)
		(end 207.64754 -183.730138)
		(width 0.15494)
		(layer "In5.Cu")
		(net "NIC3_MAIN_PWR_EN")
	)
	(segment
		(start 186.603894 -103.022146)
		(end 186.603894 -99.982782)
		(width 0.15494)
		(layer "In5.Cu")
		(net "NIC3_MAIN_PWR_EN")
	)
	(segment
		(start 193.387218 -106.744262)
		(end 192.162938 -105.519982)
		(width 0.15494)
		(layer "In5.Cu")
		(net "NIC3_MAIN_PWR_EN")
	)
	(segment
		(start 201.5236 -127.985012)
		(end 201.5236 -119.909844)
		(width 0.15494)
		(layer "In5.Cu")
		(net "NIC3_MAIN_PWR_EN")
	)
	(segment
		(start 207.64754 -136.305036)
		(end 204.1652 -132.822696)
		(width 0.15494)
		(layer "In5.Cu")
		(net "NIC3_MAIN_PWR_EN")
	)
	(segment
		(start 193.387218 -111.773462)
		(end 193.387218 -106.744262)
		(width 0.15494)
		(layer "In5.Cu")
		(net "NIC3_MAIN_PWR_EN")
	)
	(segment
		(start 207.64754 -183.730138)
		(end 207.64754 -136.305036)
		(width 0.15494)
		(layer "In5.Cu")
		(net "NIC3_MAIN_PWR_EN")
	)
	(segment
		(start 192.162938 -105.519982)
		(end 189.10173 -105.519982)
		(width 0.15494)
		(layer "In5.Cu")
		(net "NIC3_MAIN_PWR_EN")
	)
	(segment
		(start 204.1652 -132.822696)
		(end 204.1652 -130.626612)
		(width 0.15494)
		(layer "In5.Cu")
		(net "NIC3_MAIN_PWR_EN")
	)
	(segment
		(start 189.10173 -105.519982)
		(end 186.603894 -103.022146)
		(width 0.15494)
		(layer "In5.Cu")
		(net "NIC3_MAIN_PWR_EN")
	)
	(segment
		(start 201.5236 -119.909844)
		(end 193.387218 -111.773462)
		(width 0.15494)
		(layer "In5.Cu")
		(net "NIC3_MAIN_PWR_EN")
	)
	(segment
		(start 204.1652 -130.626612)
		(end 201.5236 -127.985012)
		(width 0.15494)
		(layer "In5.Cu")
		(net "NIC3_MAIN_PWR_EN")
	)
	(segment
		(start 339.931248 -192.666366)
		(end 330.625958 -192.666366)
		(width 0.15494)
		(layer "In15.Cu")
		(net "NIC3_MAIN_PWR_EN")
	)
	(segment
		(start 236.99343 -185.58383)
		(end 226.161092 -185.58383)
		(width 0.15494)
		(layer "In15.Cu")
		(net "NIC3_MAIN_PWR_EN")
	)
	(segment
		(start 347.696028 -221.58452)
		(end 347.696028 -220.222064)
		(width 0.0889)
		(layer "In15.Cu")
		(net "NIC3_MAIN_PWR_EN")
	)
	(segment
		(start 356.51313 -213.6394)
		(end 356.59187 -213.56066)
		(width 0.15494)
		(layer "In15.Cu")
		(net "NIC3_MAIN_PWR_EN")
	)
	(segment
		(start 356.59187 -213.56066)
		(end 356.59187 -213.15934)
		(width 0.15494)
		(layer "In15.Cu")
		(net "NIC3_MAIN_PWR_EN")
	)
	(segment
		(start 343.723214 -196.74205)
		(end 343.723214 -196.458332)
		(width 0.15494)
		(layer "In15.Cu")
		(net "NIC3_MAIN_PWR_EN")
	)
	(segment
		(start 210.24723 -183.932576)
		(end 207.849978 -183.932576)
		(width 0.15494)
		(layer "In15.Cu")
		(net "NIC3_MAIN_PWR_EN")
	)
	(segment
		(start 326.262746 -188.303154)
		(end 314.20816 -188.303154)
		(width 0.15494)
		(layer "In15.Cu")
		(net "NIC3_MAIN_PWR_EN")
	)
	(segment
		(start 274.09648 -188.674248)
		(end 272.797524 -187.375292)
		(width 0.15494)
		(layer "In15.Cu")
		(net "NIC3_MAIN_PWR_EN")
	)
	(segment
		(start 253.8984 -187.375292)
		(end 253.59233 -187.681362)
		(width 0.15494)
		(layer "In15.Cu")
		(net "NIC3_MAIN_PWR_EN")
	)
	(segment
		(start 356.51313 -215.1126)
		(end 356.51313 -213.6394)
		(width 0.15494)
		(layer "In15.Cu")
		(net "NIC3_MAIN_PWR_EN")
	)
	(segment
		(start 356.59187 -216.39403)
		(end 356.59187 -215.19134)
		(width 0.15494)
		(layer "In15.Cu")
		(net "NIC3_MAIN_PWR_EN")
	)
	(segment
		(start 356.697788 -204.915262)
		(end 352.236024 -200.453498)
		(width 0.15494)
		(layer "In15.Cu")
		(net "NIC3_MAIN_PWR_EN")
	)
	(segment
		(start 225.360484 -184.783222)
		(end 211.097876 -184.783222)
		(width 0.15494)
		(layer "In15.Cu")
		(net "NIC3_MAIN_PWR_EN")
	)
	(segment
		(start 352.224848 -219.76588)
		(end 352.3996 -219.76588)
		(width 0.15494)
		(layer "In15.Cu")
		(net "NIC3_MAIN_PWR_EN")
	)
	(segment
		(start 239.090962 -187.681362)
		(end 236.99343 -185.58383)
		(width 0.15494)
		(layer "In15.Cu")
		(net "NIC3_MAIN_PWR_EN")
	)
	(segment
		(start 352.02241 -219.968318)
		(end 352.224848 -219.76588)
		(width 0.15494)
		(layer "In15.Cu")
		(net "NIC3_MAIN_PWR_EN")
	)
	(segment
		(start 356.697788 -207.848708)
		(end 356.697788 -204.915262)
		(width 0.15494)
		(layer "In15.Cu")
		(net "NIC3_MAIN_PWR_EN")
	)
	(segment
		(start 356.59187 -215.19134)
		(end 356.51313 -215.1126)
		(width 0.15494)
		(layer "In15.Cu")
		(net "NIC3_MAIN_PWR_EN")
	)
	(segment
		(start 343.723214 -196.458332)
		(end 339.931248 -192.666366)
		(width 0.15494)
		(layer "In15.Cu")
		(net "NIC3_MAIN_PWR_EN")
	)
	(segment
		(start 347.696028 -220.222064)
		(end 347.696028 -220.20784)
		(width 0.15494)
		(layer "In15.Cu")
		(net "NIC3_MAIN_PWR_EN")
	)
	(segment
		(start 272.797524 -187.375292)
		(end 253.8984 -187.375292)
		(width 0.15494)
		(layer "In15.Cu")
		(net "NIC3_MAIN_PWR_EN")
	)
	(segment
		(start 352.236024 -200.453498)
		(end 347.434662 -200.453498)
		(width 0.15494)
		(layer "In15.Cu")
		(net "NIC3_MAIN_PWR_EN")
	)
	(segment
		(start 314.20816 -188.303154)
		(end 313.837066 -188.674248)
		(width 0.15494)
		(layer "In15.Cu")
		(net "NIC3_MAIN_PWR_EN")
	)
	(segment
		(start 253.59233 -187.681362)
		(end 239.090962 -187.681362)
		(width 0.15494)
		(layer "In15.Cu")
		(net "NIC3_MAIN_PWR_EN")
	)
	(segment
		(start 352.756216 -219.409264)
		(end 353.576636 -219.409264)
		(width 0.15494)
		(layer "In15.Cu")
		(net "NIC3_MAIN_PWR_EN")
	)
	(segment
		(start 347.293692 -221.986856)
		(end 347.696028 -221.58452)
		(width 0.0889)
		(layer "In15.Cu")
		(net "NIC3_MAIN_PWR_EN")
	)
	(segment
		(start 352.3996 -219.76588)
		(end 352.756216 -219.409264)
		(width 0.15494)
		(layer "In15.Cu")
		(net "NIC3_MAIN_PWR_EN")
	)
	(segment
		(start 356.488238 -213.055708)
		(end 356.488238 -208.058258)
		(width 0.15494)
		(layer "In15.Cu")
		(net "NIC3_MAIN_PWR_EN")
	)
	(segment
		(start 211.097876 -184.783222)
		(end 210.24723 -183.932576)
		(width 0.15494)
		(layer "In15.Cu")
		(net "NIC3_MAIN_PWR_EN")
	)
	(segment
		(start 356.488238 -208.058258)
		(end 356.697788 -207.848708)
		(width 0.15494)
		(layer "In15.Cu")
		(net "NIC3_MAIN_PWR_EN")
	)
	(segment
		(start 347.696028 -220.20784)
		(end 347.93555 -219.968318)
		(width 0.15494)
		(layer "In15.Cu")
		(net "NIC3_MAIN_PWR_EN")
	)
	(segment
		(start 330.625958 -192.666366)
		(end 326.262746 -188.303154)
		(width 0.15494)
		(layer "In15.Cu")
		(net "NIC3_MAIN_PWR_EN")
	)
	(segment
		(start 347.434662 -200.453498)
		(end 343.723214 -196.74205)
		(width 0.15494)
		(layer "In15.Cu")
		(net "NIC3_MAIN_PWR_EN")
	)
	(segment
		(start 313.837066 -188.674248)
		(end 274.09648 -188.674248)
		(width 0.15494)
		(layer "In15.Cu")
		(net "NIC3_MAIN_PWR_EN")
	)
	(segment
		(start 347.93555 -219.968318)
		(end 352.02241 -219.968318)
		(width 0.15494)
		(layer "In15.Cu")
		(net "NIC3_MAIN_PWR_EN")
	)
	(segment
		(start 226.161092 -185.58383)
		(end 225.360484 -184.783222)
		(width 0.15494)
		(layer "In15.Cu")
		(net "NIC3_MAIN_PWR_EN")
	)
	(segment
		(start 356.59187 -213.15934)
		(end 356.488238 -213.055708)
		(width 0.15494)
		(layer "In15.Cu")
		(net "NIC3_MAIN_PWR_EN")
	)
	(segment
		(start 353.576636 -219.409264)
		(end 356.59187 -216.39403)
		(width 0.15494)
		(layer "In15.Cu")
		(net "NIC3_MAIN_PWR_EN")
	)
	(segment
		(start 230.079296 -88.017096)
		(end 230.80472 -88.74252)
		(width 0.13462)
		(layer "F.Cu")
		(net "USB2_PEX_HUB_R_DN")
	)
	(segment
		(start 232.520998 -89.523824)
		(end 232.520998 -89.854024)
		(width 0.13462)
		(layer "F.Cu")
		(net "USB2_PEX_HUB_R_DN")
	)
	(segment
		(start 230.80472 -88.74252)
		(end 232.156254 -88.74252)
		(width 0.13462)
		(layer "F.Cu")
		(net "USB2_PEX_HUB_R_DN")
	)
	(segment
		(start 232.634028 -89.410794)
		(end 232.520998 -89.523824)
		(width 0.13462)
		(layer "F.Cu")
		(net "USB2_PEX_HUB_R_DN")
	)
	(segment
		(start 232.634028 -89.220294)
		(end 232.634028 -89.410794)
		(width 0.13462)
		(layer "F.Cu")
		(net "USB2_PEX_HUB_R_DN")
	)
	(segment
		(start 230.079296 -87.540846)
		(end 230.079296 -88.017096)
		(width 0.13462)
		(layer "F.Cu")
		(net "USB2_PEX_HUB_R_DN")
	)
	(segment
		(start 229.771956 -87.233506)
		(end 230.079296 -87.540846)
		(width 0.13462)
		(layer "F.Cu")
		(net "USB2_PEX_HUB_R_DN")
	)
	(segment
		(start 232.156254 -88.74252)
		(end 232.634028 -89.220294)
		(width 0.13462)
		(layer "F.Cu")
		(net "USB2_PEX_HUB_R_DN")
	)
	(segment
		(start 218.186 -201.168)
		(end 218.80195 -201.168)
		(width 0.13208)
		(layer "F.Cu")
		(net "SMB_NIC5_LS_EN")
	)
	(segment
		(start 216.991946 -201.716894)
		(end 217.637106 -201.716894)
		(width 0.13208)
		(layer "F.Cu")
		(net "SMB_NIC5_LS_EN")
	)
	(segment
		(start 217.637106 -201.716894)
		(end 218.186 -201.168)
		(width 0.13208)
		(layer "F.Cu")
		(net "SMB_NIC5_LS_EN")
	)
	(via
		(at 218.186 -201.168)
		(size 0.508)
		(drill 0.254)
		(layers "F.Cu" "B.Cu")
		(net "SMB_NIC5_LS_EN")
	)
	(segment
		(start 221.111826 -16.363188)
		(end 221.111826 -15.351252)
		(width 0.13208)
		(layer "F.Cu")
		(net "SMB_ISO_SSD7_SDA")
	)
	(segment
		(start 218.12631 -19.453098)
		(end 218.167966 -19.453098)
		(width 0.13208)
		(layer "F.Cu")
		(net "SMB_ISO_SSD7_SDA")
	)
	(segment
		(start 220.116146 -19.453098)
		(end 221.035626 -18.533618)
		(width 0.13208)
		(layer "F.Cu")
		(net "SMB_ISO_SSD7_SDA")
	)
	(segment
		(start 218.167966 -19.453098)
		(end 220.116146 -19.453098)
		(width 0.13208)
		(layer "F.Cu")
		(net "SMB_ISO_SSD7_SDA")
	)
	(segment
		(start 221.035626 -16.439388)
		(end 221.111826 -16.363188)
		(width 0.13208)
		(layer "F.Cu")
		(net "SMB_ISO_SSD7_SDA")
	)
	(segment
		(start 221.035626 -18.533618)
		(end 221.035626 -16.439388)
		(width 0.13208)
		(layer "F.Cu")
		(net "SMB_ISO_SSD7_SDA")
	)
	(segment
		(start 217.356436 -20.222972)
		(end 218.12631 -19.453098)
		(width 0.13208)
		(layer "F.Cu")
		(net "SMB_ISO_SSD7_SDA")
	)
	(segment
		(start 221.562422 -23.337266)
		(end 221.562422 -23.946866)
		(width 0.13208)
		(layer "F.Cu")
		(net "SMB_ISO_SSD7_SDA")
	)
	(segment
		(start 217.356436 -20.467574)
		(end 217.356436 -20.222972)
		(width 0.13208)
		(layer "F.Cu")
		(net "SMB_ISO_SSD7_SDA")
	)
	(via
		(at 221.111826 -15.351252)
		(size 0.508)
		(drill 0.254)
		(layers "F.Cu" "B.Cu")
		(net "SMB_ISO_SSD7_SDA")
	)
	(via
		(at 221.562422 -23.946866)
		(size 0.508)
		(drill 0.254)
		(layers "F.Cu" "B.Cu")
		(net "SMB_ISO_SSD7_SDA")
	)
	(segment
		(start 223.212152 -22.297136)
		(end 221.562422 -23.946866)
		(width 0.13208)
		(layer "B.Cu")
		(net "SMB_ISO_SSD7_SDA")
	)
	(segment
		(start 221.111826 -15.351252)
		(end 221.111826 -15.420594)
		(width 0.13208)
		(layer "B.Cu")
		(net "SMB_ISO_SSD7_SDA")
	)
	(segment
		(start 223.212152 -17.52092)
		(end 223.212152 -22.297136)
		(width 0.13208)
		(layer "B.Cu")
		(net "SMB_ISO_SSD7_SDA")
	)
	(segment
		(start 221.111826 -15.420594)
		(end 223.212152 -17.52092)
		(width 0.13208)
		(layer "B.Cu")
		(net "SMB_ISO_SSD7_SDA")
	)
	(segment
		(start 230.353616 -87.540846)
		(end 230.353616 -87.903304)
		(width 0.13462)
		(layer "F.Cu")
		(net "USB2_PEX_HUB_R_DP")
	)
	(segment
		(start 230.918512 -88.4682)
		(end 232.270046 -88.4682)
		(width 0.13462)
		(layer "F.Cu")
		(net "USB2_PEX_HUB_R_DP")
	)
	(segment
		(start 232.908348 -89.106502)
		(end 232.908348 -89.410794)
		(width 0.13462)
		(layer "F.Cu")
		(net "USB2_PEX_HUB_R_DP")
	)
	(segment
		(start 230.660956 -87.233506)
		(end 230.353616 -87.540846)
		(width 0.13462)
		(layer "F.Cu")
		(net "USB2_PEX_HUB_R_DP")
	)
	(segment
		(start 233.021124 -89.52357)
		(end 233.021124 -89.854024)
		(width 0.13462)
		(layer "F.Cu")
		(net "USB2_PEX_HUB_R_DP")
	)
	(segment
		(start 232.908348 -89.410794)
		(end 233.021124 -89.52357)
		(width 0.13462)
		(layer "F.Cu")
		(net "USB2_PEX_HUB_R_DP")
	)
	(segment
		(start 230.353616 -87.903304)
		(end 230.918512 -88.4682)
		(width 0.13462)
		(layer "F.Cu")
		(net "USB2_PEX_HUB_R_DP")
	)
	(segment
		(start 232.270046 -88.4682)
		(end 232.908348 -89.106502)
		(width 0.13462)
		(layer "F.Cu")
		(net "USB2_PEX_HUB_R_DP")
	)
	(segment
		(start 125.173486 -58.166)
		(end 125.291088 -58.449718)
		(width 0.2032)
		(layer "F.Cu")
		(net "P3V3_SSD4_SS")
	)
	(segment
		(start 125.295152 -58.453782)
		(end 125.295152 -59.177936)
		(width 0.2032)
		(layer "F.Cu")
		(net "P3V3_SSD4_SS")
	)
	(segment
		(start 125.291088 -58.449718)
		(end 125.295152 -58.453782)
		(width 0.2032)
		(layer "F.Cu")
		(net "P3V3_SSD4_SS")
	)
	(segment
		(start 124.241052 -57.16397)
		(end 124.241052 -57.233566)
		(width 0.2032)
		(layer "F.Cu")
		(net "P3V3_SSD4_SS")
	)
	(segment
		(start 124.241052 -57.233566)
		(end 125.173486 -58.166)
		(width 0.2032)
		(layer "F.Cu")
		(net "P3V3_SSD4_SS")
	)
	(via
		(at 125.291088 -58.449718)
		(size 0.508)
		(drill 0.254)
		(layers "F.Cu" "B.Cu")
		(net "P3V3_SSD4_SS")
	)
	(segment
		(start 139.296902 -176.536096)
		(end 139.084304 -176.536096)
		(width 0.13462)
		(layer "F.Cu")
		(net "CLK_100M_DB2000QL_NIC3_DN")
	)
	(segment
		(start 139.674092 -176.913286)
		(end 139.296902 -176.536096)
		(width 0.13462)
		(layer "F.Cu")
		(net "CLK_100M_DB2000QL_NIC3_DN")
	)
	(segment
		(start 139.084304 -176.536096)
		(end 138.839194 -176.781206)
		(width 0.13462)
		(layer "F.Cu")
		(net "CLK_100M_DB2000QL_NIC3_DN")
	)
	(segment
		(start 135.59028 -176.781206)
		(end 135.471154 -176.900332)
		(width 0.13462)
		(layer "F.Cu")
		(net "CLK_100M_DB2000QL_NIC3_DN")
	)
	(segment
		(start 138.839194 -176.781206)
		(end 135.59028 -176.781206)
		(width 0.13462)
		(layer "F.Cu")
		(net "CLK_100M_DB2000QL_NIC3_DN")
	)
	(segment
		(start 405.048974 -387.93674)
		(end 404.049992 -386.937758)
		(width 0.13208)
		(layer "F.Cu")
		(net "GPU_WP_HW_CTRL_N")
	)
	(segment
		(start 405.928068 -387.93674)
		(end 405.048974 -387.93674)
		(width 0.13208)
		(layer "F.Cu")
		(net "GPU_WP_HW_CTRL_N")
	)
	(segment
		(start 407.296112 -387.942836)
		(end 405.934164 -387.942836)
		(width 0.13208)
		(layer "F.Cu")
		(net "GPU_WP_HW_CTRL_N")
	)
	(segment
		(start 405.934164 -387.942836)
		(end 405.928068 -387.93674)
		(width 0.13208)
		(layer "F.Cu")
		(net "GPU_WP_HW_CTRL_N")
	)
	(via
		(at 404.049992 -386.937758)
		(size 0.508)
		(drill 0.254)
		(layers "F.Cu" "B.Cu")
		(net "GPU_WP_HW_CTRL_N")
	)
	(segment
		(start 402.908008 -386.937758)
		(end 394.568934 -395.276832)
		(width 0.15494)
		(layer "In9.Cu")
		(net "GPU_WP_HW_CTRL_N")
	)
	(segment
		(start 404.049992 -386.937758)
		(end 402.908008 -386.937758)
		(width 0.15494)
		(layer "In9.Cu")
		(net "GPU_WP_HW_CTRL_N")
	)
	(segment
		(start 394.568934 -402.81098)
		(end 393.089892 -404.290022)
		(width 0.15494)
		(layer "In9.Cu")
		(net "GPU_WP_HW_CTRL_N")
	)
	(segment
		(start 394.568934 -395.276832)
		(end 394.568934 -402.81098)
		(width 0.15494)
		(layer "In9.Cu")
		(net "GPU_WP_HW_CTRL_N")
	)
	(segment
		(start 195.760594 -21.05279)
		(end 195.760594 -20.789392)
		(width 0.13208)
		(layer "F.Cu")
		(net "SMB_SSD6_ISO_EN")
	)
	(segment
		(start 196.554852 -22.561296)
		(end 196.554852 -21.847048)
		(width 0.13208)
		(layer "F.Cu")
		(net "SMB_SSD6_ISO_EN")
	)
	(segment
		(start 196.554852 -21.847048)
		(end 195.760594 -21.05279)
		(width 0.13208)
		(layer "F.Cu")
		(net "SMB_SSD6_ISO_EN")
	)
	(via
		(at 196.554852 -21.847048)
		(size 0.508)
		(drill 0.254)
		(layers "F.Cu" "B.Cu")
		(net "SMB_SSD6_ISO_EN")
	)
	(segment
		(start 393.99845 -88.209882)
		(end 390.816846 -88.209882)
		(width 0.13208)
		(layer "F.Cu")
		(net "SMB_BIC_I2C6_MUX_FRU_SCL")
	)
	(segment
		(start 390.816846 -88.209882)
		(end 389.393684 -86.78672)
		(width 0.13208)
		(layer "F.Cu")
		(net "SMB_BIC_I2C6_MUX_FRU_SCL")
	)
	(segment
		(start 389.393684 -86.78672)
		(end 388.24027 -86.78672)
		(width 0.13208)
		(layer "F.Cu")
		(net "SMB_BIC_I2C6_MUX_FRU_SCL")
	)
	(via
		(at 330.962 -82.979768)
		(size 0.508)
		(drill 0.254)
		(layers "F.Cu" "B.Cu")
		(net "SMB_BIC_I2C6_MUX_FRU_SCL")
	)
	(via
		(at 393.99845 -88.209882)
		(size 0.508)
		(drill 0.254)
		(layers "F.Cu" "B.Cu")
		(net "SMB_BIC_I2C6_MUX_FRU_SCL")
	)
	(via
		(at 392.362944 -77.509624)
		(size 0.508)
		(drill 0.254)
		(layers "F.Cu" "B.Cu")
		(net "SMB_BIC_I2C6_MUX_FRU_SCL")
	)
	(segment
		(start 322.904358 -82.979768)
		(end 330.962 -82.979768)
		(width 0.13208)
		(layer "B.Cu")
		(net "SMB_BIC_I2C6_MUX_FRU_SCL")
	)
	(segment
		(start 322.760848 -83.123278)
		(end 322.904358 -82.979768)
		(width 0.13208)
		(layer "B.Cu")
		(net "SMB_BIC_I2C6_MUX_FRU_SCL")
	)
	(segment
		(start 392.362944 -78.62824)
		(end 392.362944 -77.509624)
		(width 0.15494)
		(layer "In5.Cu")
		(net "SMB_BIC_I2C6_MUX_FRU_SCL")
	)
	(segment
		(start 393.99845 -88.209882)
		(end 393.14374 -87.355172)
		(width 0.15494)
		(layer "In5.Cu")
		(net "SMB_BIC_I2C6_MUX_FRU_SCL")
	)
	(segment
		(start 393.14374 -87.355172)
		(end 393.14374 -79.409036)
		(width 0.15494)
		(layer "In5.Cu")
		(net "SMB_BIC_I2C6_MUX_FRU_SCL")
	)
	(segment
		(start 393.14374 -79.409036)
		(end 392.362944 -78.62824)
		(width 0.15494)
		(layer "In5.Cu")
		(net "SMB_BIC_I2C6_MUX_FRU_SCL")
	)
	(segment
		(start 343.159842 -83.739482)
		(end 332.659482 -83.739482)
		(width 0.15494)
		(layer "In13.Cu")
		(net "SMB_BIC_I2C6_MUX_FRU_SCL")
	)
	(segment
		(start 353.019106 -90.0938)
		(end 350.7486 -90.0938)
		(width 0.15494)
		(layer "In13.Cu")
		(net "SMB_BIC_I2C6_MUX_FRU_SCL")
	)
	(segment
		(start 350.7486 -90.0938)
		(end 350.1517 -90.6907)
		(width 0.15494)
		(layer "In13.Cu")
		(net "SMB_BIC_I2C6_MUX_FRU_SCL")
	)
	(segment
		(start 366.85855 -77.509624)
		(end 354.67544 -89.692734)
		(width 0.15494)
		(layer "In13.Cu")
		(net "SMB_BIC_I2C6_MUX_FRU_SCL")
	)
	(segment
		(start 344.551 -85.13064)
		(end 343.159842 -83.739482)
		(width 0.15494)
		(layer "In13.Cu")
		(net "SMB_BIC_I2C6_MUX_FRU_SCL")
	)
	(segment
		(start 350.1517 -91.6051)
		(end 349.344742 -92.412058)
		(width 0.15494)
		(layer "In13.Cu")
		(net "SMB_BIC_I2C6_MUX_FRU_SCL")
	)
	(segment
		(start 392.362944 -77.509624)
		(end 366.85855 -77.509624)
		(width 0.15494)
		(layer "In13.Cu")
		(net "SMB_BIC_I2C6_MUX_FRU_SCL")
	)
	(segment
		(start 350.1517 -90.6907)
		(end 350.1517 -91.6051)
		(width 0.15494)
		(layer "In13.Cu")
		(net "SMB_BIC_I2C6_MUX_FRU_SCL")
	)
	(segment
		(start 354.67544 -89.692734)
		(end 353.420172 -89.692734)
		(width 0.15494)
		(layer "In13.Cu")
		(net "SMB_BIC_I2C6_MUX_FRU_SCL")
	)
	(segment
		(start 344.551 -91.14282)
		(end 344.551 -85.13064)
		(width 0.15494)
		(layer "In13.Cu")
		(net "SMB_BIC_I2C6_MUX_FRU_SCL")
	)
	(segment
		(start 353.420172 -89.692734)
		(end 353.019106 -90.0938)
		(width 0.15494)
		(layer "In13.Cu")
		(net "SMB_BIC_I2C6_MUX_FRU_SCL")
	)
	(segment
		(start 332.659482 -83.739482)
		(end 331.899768 -82.979768)
		(width 0.15494)
		(layer "In13.Cu")
		(net "SMB_BIC_I2C6_MUX_FRU_SCL")
	)
	(segment
		(start 345.820238 -92.412058)
		(end 344.551 -91.14282)
		(width 0.15494)
		(layer "In13.Cu")
		(net "SMB_BIC_I2C6_MUX_FRU_SCL")
	)
	(segment
		(start 349.344742 -92.412058)
		(end 345.820238 -92.412058)
		(width 0.15494)
		(layer "In13.Cu")
		(net "SMB_BIC_I2C6_MUX_FRU_SCL")
	)
	(segment
		(start 331.899768 -82.979768)
		(end 330.962 -82.979768)
		(width 0.15494)
		(layer "In13.Cu")
		(net "SMB_BIC_I2C6_MUX_FRU_SCL")
	)
	(segment
		(start 245.744746 -110.5662)
		(end 242.2906 -114.020346)
		(width 0.13208)
		(layer "F.Cu")
		(net "PWRGD_P3V3_NIC4_R")
	)
	(segment
		(start 242.43919 -119.505476)
		(end 242.777264 -119.505476)
		(width 0.13208)
		(layer "F.Cu")
		(net "PWRGD_P3V3_NIC4_R")
	)
	(segment
		(start 242.2906 -119.356886)
		(end 242.43919 -119.505476)
		(width 0.13208)
		(layer "F.Cu")
		(net "PWRGD_P3V3_NIC4_R")
	)
	(segment
		(start 257.098546 -110.5662)
		(end 245.744746 -110.5662)
		(width 0.13208)
		(layer "F.Cu")
		(net "PWRGD_P3V3_NIC4_R")
	)
	(segment
		(start 269.329154 -129.185924)
		(end 265.62431 -125.48108)
		(width 0.13208)
		(layer "F.Cu")
		(net "PWRGD_P3V3_NIC4_R")
	)
	(segment
		(start 242.2906 -114.020346)
		(end 242.2906 -119.356886)
		(width 0.13208)
		(layer "F.Cu")
		(net "PWRGD_P3V3_NIC4_R")
	)
	(segment
		(start 285.565088 -129.185924)
		(end 269.329154 -129.185924)
		(width 0.13208)
		(layer "F.Cu")
		(net "PWRGD_P3V3_NIC4_R")
	)
	(segment
		(start 349.293942 -221.58706)
		(end 349.693738 -221.986856)
		(width 0.13208)
		(layer "F.Cu")
		(net "PWRGD_P3V3_NIC4_R")
	)
	(segment
		(start 241.910362 -124.963428)
		(end 241.255042 -124.963428)
		(width 0.13208)
		(layer "F.Cu")
		(net "PWRGD_P3V3_NIC4_R")
	)
	(segment
		(start 286.161988 -128.589024)
		(end 285.565088 -129.185924)
		(width 0.13208)
		(layer "F.Cu")
		(net "PWRGD_P3V3_NIC4_R")
	)
	(segment
		(start 265.62431 -125.48108)
		(end 265.62431 -119.091964)
		(width 0.13208)
		(layer "F.Cu")
		(net "PWRGD_P3V3_NIC4_R")
	)
	(segment
		(start 265.62431 -119.091964)
		(end 257.098546 -110.5662)
		(width 0.13208)
		(layer "F.Cu")
		(net "PWRGD_P3V3_NIC4_R")
	)
	(segment
		(start 242.777264 -120.248426)
		(end 242.777264 -119.505476)
		(width 0.13208)
		(layer "F.Cu")
		(net "PWRGD_P3V3_NIC4_R")
	)
	(via
		(at 286.161988 -128.589024)
		(size 0.508)
		(drill 0.254)
		(layers "F.Cu" "B.Cu")
		(net "PWRGD_P3V3_NIC4_R")
	)
	(via
		(at 241.255042 -124.963428)
		(size 0.508)
		(drill 0.254)
		(layers "F.Cu" "B.Cu")
		(net "PWRGD_P3V3_NIC4_R")
	)
	(via
		(at 349.693738 -221.986856)
		(size 0.4572)
		(drill 0.254)
		(layers "F.Cu" "B.Cu")
		(net "PWRGD_P3V3_NIC4_R")
	)
	(via
		(at 242.777264 -120.248426)
		(size 0.508)
		(drill 0.254)
		(layers "F.Cu" "B.Cu")
		(net "PWRGD_P3V3_NIC4_R")
	)
	(via
		(at 351.512378 -131.214114)
		(size 0.508)
		(drill 0.254)
		(layers "F.Cu" "B.Cu")
		(net "PWRGD_P3V3_NIC4_R")
	)
	(segment
		(start 371.910102 -175.374554)
		(end 370.3828 -173.847252)
		(width 0.15494)
		(layer "In7.Cu")
		(net "PWRGD_P3V3_NIC4_R")
	)
	(segment
		(start 359.758742 -209.82813)
		(end 360.198162 -209.38871)
		(width 0.15494)
		(layer "In7.Cu")
		(net "PWRGD_P3V3_NIC4_R")
	)
	(segment
		(start 352.067368 -221.314772)
		(end 355.087428 -221.314772)
		(width 0.15494)
		(layer "In7.Cu")
		(net "PWRGD_P3V3_NIC4_R")
	)
	(segment
		(start 371.910102 -183.231282)
		(end 371.910102 -175.374554)
		(width 0.15494)
		(layer "In7.Cu")
		(net "PWRGD_P3V3_NIC4_R")
	)
	(segment
		(start 372.695216 -191.377062)
		(end 372.3894 -191.071246)
		(width 0.15494)
		(layer "In7.Cu")
		(net "PWRGD_P3V3_NIC4_R")
	)
	(segment
		(start 350.948244 -143.030956)
		(end 351.623884 -142.355316)
		(width 0.15494)
		(layer "In7.Cu")
		(net "PWRGD_P3V3_NIC4_R")
	)
	(segment
		(start 363.937042 -165.17493)
		(end 358.081072 -165.17493)
		(width 0.15494)
		(layer "In7.Cu")
		(net "PWRGD_P3V3_NIC4_R")
	)
	(segment
		(start 351.222564 -141.333982)
		(end 351.624138 -141.333982)
		(width 0.15494)
		(layer "In7.Cu")
		(net "PWRGD_P3V3_NIC4_R")
	)
	(segment
		(start 351.876614 -131.57835)
		(end 351.512378 -131.214114)
		(width 0.15494)
		(layer "In7.Cu")
		(net "PWRGD_P3V3_NIC4_R")
	)
	(segment
		(start 350.939354 -141.617192)
		(end 351.222564 -141.333982)
		(width 0.15494)
		(layer "In7.Cu")
		(net "PWRGD_P3V3_NIC4_R")
	)
	(segment
		(start 351.795334 -221.586806)
		(end 352.067368 -221.314772)
		(width 0.15494)
		(layer "In7.Cu")
		(net "PWRGD_P3V3_NIC4_R")
	)
	(segment
		(start 350.948244 -147.110196)
		(end 350.948244 -143.030956)
		(width 0.15494)
		(layer "In7.Cu")
		(net "PWRGD_P3V3_NIC4_R")
	)
	(segment
		(start 351.876614 -141.045692)
		(end 351.907094 -141.015212)
		(width 0.15494)
		(layer "In7.Cu")
		(net "PWRGD_P3V3_NIC4_R")
	)
	(segment
		(start 352.186748 -160.23082)
		(end 350.755966 -158.800038)
		(width 0.15494)
		(layer "In7.Cu")
		(net "PWRGD_P3V3_NIC4_R")
	)
	(segment
		(start 357.700326 -165.175184)
		(end 357.574342 -165.0492)
		(width 0.15494)
		(layer "In7.Cu")
		(net "PWRGD_P3V3_NIC4_R")
	)
	(segment
		(start 357.574342 -165.0492)
		(end 356.006654 -165.0492)
		(width 0.15494)
		(layer "In7.Cu")
		(net "PWRGD_P3V3_NIC4_R")
	)
	(segment
		(start 358.081072 -165.17493)
		(end 358.080818 -165.175184)
		(width 0.15494)
		(layer "In7.Cu")
		(net "PWRGD_P3V3_NIC4_R")
	)
	(segment
		(start 355.087428 -221.314772)
		(end 358.483408 -217.918792)
		(width 0.15494)
		(layer "In7.Cu")
		(net "PWRGD_P3V3_NIC4_R")
	)
	(segment
		(start 352.186748 -161.229294)
		(end 352.186748 -160.23082)
		(width 0.15494)
		(layer "In7.Cu")
		(net "PWRGD_P3V3_NIC4_R")
	)
	(segment
		(start 360.198162 -209.38871)
		(end 362.590588 -209.38871)
		(width 0.15494)
		(layer "In7.Cu")
		(net "PWRGD_P3V3_NIC4_R")
	)
	(segment
		(start 351.876614 -141.081506)
		(end 351.876614 -141.045692)
		(width 0.15494)
		(layer "In7.Cu")
		(net "PWRGD_P3V3_NIC4_R")
	)
	(segment
		(start 349.693738 -221.986856)
		(end 350.093788 -221.586806)
		(width 0.0889)
		(layer "In7.Cu")
		(net "PWRGD_P3V3_NIC4_R")
	)
	(segment
		(start 372.8466 -184.16778)
		(end 371.910102 -183.231282)
		(width 0.15494)
		(layer "In7.Cu")
		(net "PWRGD_P3V3_NIC4_R")
	)
	(segment
		(start 351.222564 -142.301722)
		(end 350.939354 -142.018512)
		(width 0.15494)
		(layer "In7.Cu")
		(net "PWRGD_P3V3_NIC4_R")
	)
	(segment
		(start 370.3828 -173.847252)
		(end 370.3828 -171.620688)
		(width 0.15494)
		(layer "In7.Cu")
		(net "PWRGD_P3V3_NIC4_R")
	)
	(segment
		(start 350.755966 -147.302474)
		(end 350.948244 -147.110196)
		(width 0.15494)
		(layer "In7.Cu")
		(net "PWRGD_P3V3_NIC4_R")
	)
	(segment
		(start 356.006654 -165.0492)
		(end 352.186748 -161.229294)
		(width 0.15494)
		(layer "In7.Cu")
		(net "PWRGD_P3V3_NIC4_R")
	)
	(segment
		(start 358.81818 -209.83829)
		(end 358.82834 -209.82813)
		(width 0.15494)
		(layer "In7.Cu")
		(net "PWRGD_P3V3_NIC4_R")
	)
	(segment
		(start 372.695216 -201.729594)
		(end 372.695216 -191.377062)
		(width 0.15494)
		(layer "In7.Cu")
		(net "PWRGD_P3V3_NIC4_R")
	)
	(segment
		(start 351.623884 -142.301722)
		(end 351.222564 -142.301722)
		(width 0.15494)
		(layer "In7.Cu")
		(net "PWRGD_P3V3_NIC4_R")
	)
	(segment
		(start 372.3894 -191.071246)
		(end 372.3894 -186.091068)
		(width 0.15494)
		(layer "In7.Cu")
		(net "PWRGD_P3V3_NIC4_R")
	)
	(segment
		(start 350.093788 -221.586806)
		(end 351.795334 -221.586806)
		(width 0.0889)
		(layer "In7.Cu")
		(net "PWRGD_P3V3_NIC4_R")
	)
	(segment
		(start 351.624138 -141.333982)
		(end 351.876614 -141.081506)
		(width 0.15494)
		(layer "In7.Cu")
		(net "PWRGD_P3V3_NIC4_R")
	)
	(segment
		(start 351.907094 -141.015212)
		(end 351.907094 -140.613892)
		(width 0.15494)
		(layer "In7.Cu")
		(net "PWRGD_P3V3_NIC4_R")
	)
	(segment
		(start 358.080818 -165.175184)
		(end 357.700326 -165.175184)
		(width 0.15494)
		(layer "In7.Cu")
		(net "PWRGD_P3V3_NIC4_R")
	)
	(segment
		(start 351.876614 -140.583412)
		(end 351.876614 -131.57835)
		(width 0.15494)
		(layer "In7.Cu")
		(net "PWRGD_P3V3_NIC4_R")
	)
	(segment
		(start 358.483408 -217.918792)
		(end 358.483408 -210.171792)
		(width 0.15494)
		(layer "In7.Cu")
		(net "PWRGD_P3V3_NIC4_R")
	)
	(segment
		(start 370.3828 -171.620688)
		(end 363.937042 -165.17493)
		(width 0.15494)
		(layer "In7.Cu")
		(net "PWRGD_P3V3_NIC4_R")
	)
	(segment
		(start 350.755966 -158.800038)
		(end 350.755966 -147.302474)
		(width 0.15494)
		(layer "In7.Cu")
		(net "PWRGD_P3V3_NIC4_R")
	)
	(segment
		(start 351.623884 -142.355316)
		(end 351.623884 -142.301722)
		(width 0.15494)
		(layer "In7.Cu")
		(net "PWRGD_P3V3_NIC4_R")
	)
	(segment
		(start 362.590588 -209.38871)
		(end 363.05617 -208.923128)
		(width 0.15494)
		(layer "In7.Cu")
		(net "PWRGD_P3V3_NIC4_R")
	)
	(segment
		(start 363.05617 -208.923128)
		(end 364.888526 -208.923128)
		(width 0.15494)
		(layer "In7.Cu")
		(net "PWRGD_P3V3_NIC4_R")
	)
	(segment
		(start 367.762536 -206.662274)
		(end 372.695216 -201.729594)
		(width 0.15494)
		(layer "In7.Cu")
		(net "PWRGD_P3V3_NIC4_R")
	)
	(segment
		(start 358.82834 -209.82813)
		(end 359.758742 -209.82813)
		(width 0.15494)
		(layer "In7.Cu")
		(net "PWRGD_P3V3_NIC4_R")
	)
	(segment
		(start 372.3894 -186.091068)
		(end 372.8466 -185.633868)
		(width 0.15494)
		(layer "In7.Cu")
		(net "PWRGD_P3V3_NIC4_R")
	)
	(segment
		(start 358.483408 -210.171792)
		(end 358.81691 -209.83829)
		(width 0.15494)
		(layer "In7.Cu")
		(net "PWRGD_P3V3_NIC4_R")
	)
	(segment
		(start 358.81691 -209.83829)
		(end 358.81818 -209.83829)
		(width 0.15494)
		(layer "In7.Cu")
		(net "PWRGD_P3V3_NIC4_R")
	)
	(segment
		(start 350.939354 -142.018512)
		(end 350.939354 -141.617192)
		(width 0.15494)
		(layer "In7.Cu")
		(net "PWRGD_P3V3_NIC4_R")
	)
	(segment
		(start 351.907094 -140.613892)
		(end 351.876614 -140.583412)
		(width 0.15494)
		(layer "In7.Cu")
		(net "PWRGD_P3V3_NIC4_R")
	)
	(segment
		(start 372.8466 -185.633868)
		(end 372.8466 -184.16778)
		(width 0.15494)
		(layer "In7.Cu")
		(net "PWRGD_P3V3_NIC4_R")
	)
	(segment
		(start 367.14938 -206.662274)
		(end 367.762536 -206.662274)
		(width 0.15494)
		(layer "In7.Cu")
		(net "PWRGD_P3V3_NIC4_R")
	)
	(segment
		(start 364.888526 -208.923128)
		(end 367.14938 -206.662274)
		(width 0.15494)
		(layer "In7.Cu")
		(net "PWRGD_P3V3_NIC4_R")
	)
	(segment
		(start 286.453072 -128.880108)
		(end 315.718444 -128.880108)
		(width 0.15494)
		(layer "In13.Cu")
		(net "PWRGD_P3V3_NIC4_R")
	)
	(segment
		(start 241.255042 -124.963428)
		(end 241.848386 -124.370084)
		(width 0.15494)
		(layer "In13.Cu")
		(net "PWRGD_P3V3_NIC4_R")
	)
	(segment
		(start 241.848386 -121.177304)
		(end 242.777264 -120.248426)
		(width 0.15494)
		(layer "In13.Cu")
		(net "PWRGD_P3V3_NIC4_R")
	)
	(segment
		(start 315.718444 -128.880108)
		(end 321.31508 -134.476744)
		(width 0.15494)
		(layer "In13.Cu")
		(net "PWRGD_P3V3_NIC4_R")
	)
	(segment
		(start 321.31508 -134.476744)
		(end 348.249748 -134.476744)
		(width 0.15494)
		(layer "In13.Cu")
		(net "PWRGD_P3V3_NIC4_R")
	)
	(segment
		(start 241.848386 -124.370084)
		(end 241.848386 -121.177304)
		(width 0.15494)
		(layer "In13.Cu")
		(net "PWRGD_P3V3_NIC4_R")
	)
	(segment
		(start 286.161988 -128.589024)
		(end 286.453072 -128.880108)
		(width 0.15494)
		(layer "In13.Cu")
		(net "PWRGD_P3V3_NIC4_R")
	)
	(segment
		(start 348.249748 -134.476744)
		(end 351.512378 -131.214114)
		(width 0.15494)
		(layer "In13.Cu")
		(net "PWRGD_P3V3_NIC4_R")
	)
	(segment
		(start 138.970512 -176.261776)
		(end 138.725402 -176.506886)
		(width 0.13462)
		(layer "F.Cu")
		(net "CLK_100M_DB2000QL_NIC3_DP")
	)
	(segment
		(start 135.60298 -176.506886)
		(end 135.59028 -176.519586)
		(width 0.13462)
		(layer "F.Cu")
		(net "CLK_100M_DB2000QL_NIC3_DP")
	)
	(segment
		(start 135.59028 -176.519586)
		(end 135.471154 -176.40046)
		(width 0.13462)
		(layer "F.Cu")
		(net "CLK_100M_DB2000QL_NIC3_DP")
	)
	(segment
		(start 139.309602 -176.261776)
		(end 138.970512 -176.261776)
		(width 0.13462)
		(layer "F.Cu")
		(net "CLK_100M_DB2000QL_NIC3_DP")
	)
	(segment
		(start 139.674092 -175.897286)
		(end 139.309602 -176.261776)
		(width 0.13462)
		(layer "F.Cu")
		(net "CLK_100M_DB2000QL_NIC3_DP")
	)
	(segment
		(start 138.725402 -176.506886)
		(end 135.60298 -176.506886)
		(width 0.13462)
		(layer "F.Cu")
		(net "CLK_100M_DB2000QL_NIC3_DP")
	)
	(segment
		(start 195.035678 -18.533618)
		(end 195.035678 -16.439388)
		(width 0.13208)
		(layer "F.Cu")
		(net "SMB_ISO_SSD6_SDA")
	)
	(segment
		(start 194.116198 -19.453098)
		(end 195.035678 -18.533618)
		(width 0.13208)
		(layer "F.Cu")
		(net "SMB_ISO_SSD6_SDA")
	)
	(segment
		(start 191.356488 -20.467574)
		(end 191.356488 -20.222972)
		(width 0.13208)
		(layer "F.Cu")
		(net "SMB_ISO_SSD6_SDA")
	)
	(segment
		(start 195.111878 -16.363188)
		(end 195.111878 -15.351252)
		(width 0.13208)
		(layer "F.Cu")
		(net "SMB_ISO_SSD6_SDA")
	)
	(segment
		(start 195.562474 -23.337266)
		(end 195.562474 -23.946866)
		(width 0.13208)
		(layer "F.Cu")
		(net "SMB_ISO_SSD6_SDA")
	)
	(segment
		(start 191.356488 -20.222972)
		(end 192.126362 -19.453098)
		(width 0.13208)
		(layer "F.Cu")
		(net "SMB_ISO_SSD6_SDA")
	)
	(segment
		(start 192.168018 -19.453098)
		(end 194.116198 -19.453098)
		(width 0.13208)
		(layer "F.Cu")
		(net "SMB_ISO_SSD6_SDA")
	)
	(segment
		(start 192.126362 -19.453098)
		(end 192.168018 -19.453098)
		(width 0.13208)
		(layer "F.Cu")
		(net "SMB_ISO_SSD6_SDA")
	)
	(segment
		(start 195.035678 -16.439388)
		(end 195.111878 -16.363188)
		(width 0.13208)
		(layer "F.Cu")
		(net "SMB_ISO_SSD6_SDA")
	)
	(via
		(at 195.111878 -15.351252)
		(size 0.508)
		(drill 0.254)
		(layers "F.Cu" "B.Cu")
		(net "SMB_ISO_SSD6_SDA")
	)
	(via
		(at 195.562474 -23.946866)
		(size 0.508)
		(drill 0.254)
		(layers "F.Cu" "B.Cu")
		(net "SMB_ISO_SSD6_SDA")
	)
	(segment
		(start 195.562474 -23.946866)
		(end 197.250558 -22.258782)
		(width 0.13208)
		(layer "B.Cu")
		(net "SMB_ISO_SSD6_SDA")
	)
	(segment
		(start 195.111878 -15.420594)
		(end 195.111878 -15.351252)
		(width 0.13208)
		(layer "B.Cu")
		(net "SMB_ISO_SSD6_SDA")
	)
	(segment
		(start 197.250558 -17.559274)
		(end 195.111878 -15.420594)
		(width 0.13208)
		(layer "B.Cu")
		(net "SMB_ISO_SSD6_SDA")
	)
	(segment
		(start 197.250558 -22.258782)
		(end 197.250558 -17.559274)
		(width 0.13208)
		(layer "B.Cu")
		(net "SMB_ISO_SSD6_SDA")
	)
	(segment
		(start 321.909186 -22.990048)
		(end 321.944238 -23.0251)
		(width 0.13208)
		(layer "F.Cu")
		(net "SMB_ISO_SSD11_R_SDA")
	)
	(segment
		(start 334.990186 -11.543792)
		(end 334.990186 -10.934192)
		(width 0.13208)
		(layer "F.Cu")
		(net "SMB_ISO_SSD11_R_SDA")
	)
	(segment
		(start 320.864738 -22.990048)
		(end 321.909186 -22.990048)
		(width 0.13208)
		(layer "F.Cu")
		(net "SMB_ISO_SSD11_R_SDA")
	)
	(via
		(at 321.944238 -23.0251)
		(size 0.508)
		(drill 0.254)
		(layers "F.Cu" "B.Cu")
		(net "SMB_ISO_SSD11_R_SDA")
	)
	(via
		(at 334.990186 -11.543792)
		(size 0.508)
		(drill 0.254)
		(layers "F.Cu" "B.Cu")
		(net "SMB_ISO_SSD11_R_SDA")
	)
	(segment
		(start 334.190848 -10.744454)
		(end 333.373222 -10.744454)
		(width 0.15494)
		(layer "In5.Cu")
		(net "SMB_ISO_SSD11_R_SDA")
	)
	(segment
		(start 332.85811 -11.259566)
		(end 332.85811 -21.390356)
		(width 0.15494)
		(layer "In5.Cu")
		(net "SMB_ISO_SSD11_R_SDA")
	)
	(segment
		(start 331.730096 -22.51837)
		(end 322.450968 -22.51837)
		(width 0.15494)
		(layer "In5.Cu")
		(net "SMB_ISO_SSD11_R_SDA")
	)
	(segment
		(start 334.990186 -11.543792)
		(end 334.190848 -10.744454)
		(width 0.15494)
		(layer "In5.Cu")
		(net "SMB_ISO_SSD11_R_SDA")
	)
	(segment
		(start 322.450968 -22.51837)
		(end 321.944238 -23.0251)
		(width 0.15494)
		(layer "In5.Cu")
		(net "SMB_ISO_SSD11_R_SDA")
	)
	(segment
		(start 333.373222 -10.744454)
		(end 332.85811 -11.259566)
		(width 0.15494)
		(layer "In5.Cu")
		(net "SMB_ISO_SSD11_R_SDA")
	)
	(segment
		(start 332.85811 -21.390356)
		(end 331.730096 -22.51837)
		(width 0.15494)
		(layer "In5.Cu")
		(net "SMB_ISO_SSD11_R_SDA")
	)
	(segment
		(start 392.417554 -87.214202)
		(end 393.269216 -87.214202)
		(width 0.13208)
		(layer "F.Cu")
		(net "SMB_BIC_I2C6_MUX_FRU_SDA")
	)
	(segment
		(start 388.24027 -86.136734)
		(end 389.372348 -86.136734)
		(width 0.13208)
		(layer "F.Cu")
		(net "SMB_BIC_I2C6_MUX_FRU_SDA")
	)
	(segment
		(start 390.449816 -87.214202)
		(end 392.417554 -87.214202)
		(width 0.13208)
		(layer "F.Cu")
		(net "SMB_BIC_I2C6_MUX_FRU_SDA")
	)
	(segment
		(start 389.372348 -86.136734)
		(end 390.449816 -87.214202)
		(width 0.13208)
		(layer "F.Cu")
		(net "SMB_BIC_I2C6_MUX_FRU_SDA")
	)
	(via
		(at 392.417554 -87.214202)
		(size 0.508)
		(drill 0.254)
		(layers "F.Cu" "B.Cu")
		(net "SMB_BIC_I2C6_MUX_FRU_SDA")
	)
	(via
		(at 132.6388 -172.113702)
		(size 0.508)
		(drill 0.254)
		(layers "F.Cu" "B.Cu")
		(net "SMB_BMC_9FGL0451E_SCL")
	)
	(via
		(at 109.891576 -329.395836)
		(size 0.6604)
		(drill 0.3302)
		(layers "F.Cu" "B.Cu")
		(net "SMB_BMC_9FGL0451E_SCL")
	)
	(via
		(at 109.353858 -327.456292)
		(size 0.508)
		(drill 0.254)
		(layers "F.Cu" "B.Cu")
		(net "SMB_BMC_9FGL0451E_SCL")
	)
	(segment
		(start 109.891576 -327.99401)
		(end 109.353858 -327.456292)
		(width 0.13208)
		(layer "B.Cu")
		(net "SMB_BMC_9FGL0451E_SCL")
	)
	(segment
		(start 109.891576 -329.889612)
		(end 109.891576 -329.395836)
		(width 0.13208)
		(layer "B.Cu")
		(net "SMB_BMC_9FGL0451E_SCL")
	)
	(segment
		(start 108.689394 -330.300584)
		(end 109.480604 -330.300584)
		(width 0.13208)
		(layer "B.Cu")
		(net "SMB_BMC_9FGL0451E_SCL")
	)
	(segment
		(start 133.425946 -170.464226)
		(end 133.425946 -171.326556)
		(width 0.13208)
		(layer "B.Cu")
		(net "SMB_BMC_9FGL0451E_SCL")
	)
	(segment
		(start 109.891576 -329.395836)
		(end 109.891576 -327.99401)
		(width 0.13208)
		(layer "B.Cu")
		(net "SMB_BMC_9FGL0451E_SCL")
	)
	(segment
		(start 133.425946 -171.326556)
		(end 132.6388 -172.113702)
		(width 0.13208)
		(layer "B.Cu")
		(net "SMB_BMC_9FGL0451E_SCL")
	)
	(segment
		(start 109.480604 -330.300584)
		(end 109.891576 -329.889612)
		(width 0.13208)
		(layer "B.Cu")
		(net "SMB_BMC_9FGL0451E_SCL")
	)
	(segment
		(start 103.841804 -326.85355)
		(end 108.751116 -326.85355)
		(width 0.15494)
		(layer "In11.Cu")
		(net "SMB_BMC_9FGL0451E_SCL")
	)
	(segment
		(start 78.0542 -190.83274)
		(end 78.0542 -253.441454)
		(width 0.15494)
		(layer "In11.Cu")
		(net "SMB_BMC_9FGL0451E_SCL")
	)
	(segment
		(start 96.647 -294.360346)
		(end 96.647 -310.7436)
		(width 0.15494)
		(layer "In11.Cu")
		(net "SMB_BMC_9FGL0451E_SCL")
	)
	(segment
		(start 100.069142 -314.165742)
		(end 101.4222 -317.432182)
		(width 0.15494)
		(layer "In11.Cu")
		(net "SMB_BMC_9FGL0451E_SCL")
	)
	(segment
		(start 98.264218 -179.341272)
		(end 89.545668 -179.341272)
		(width 0.15494)
		(layer "In11.Cu")
		(net "SMB_BMC_9FGL0451E_SCL")
	)
	(segment
		(start 88.288114 -281.83586)
		(end 94.9452 -288.492946)
		(width 0.15494)
		(layer "In11.Cu")
		(net "SMB_BMC_9FGL0451E_SCL")
	)
	(segment
		(start 108.751116 -326.85355)
		(end 109.353858 -327.456292)
		(width 0.15494)
		(layer "In11.Cu")
		(net "SMB_BMC_9FGL0451E_SCL")
	)
	(segment
		(start 122.25909 -182.49011)
		(end 101.413056 -182.49011)
		(width 0.15494)
		(layer "In11.Cu")
		(net "SMB_BMC_9FGL0451E_SCL")
	)
	(segment
		(start 94.9452 -292.658546)
		(end 96.647 -294.360346)
		(width 0.15494)
		(layer "In11.Cu")
		(net "SMB_BMC_9FGL0451E_SCL")
	)
	(segment
		(start 127.793242 -169.310558)
		(end 124.968 -172.1358)
		(width 0.15494)
		(layer "In11.Cu")
		(net "SMB_BMC_9FGL0451E_SCL")
	)
	(segment
		(start 83.947 -259.334254)
		(end 83.947 -271.355058)
		(width 0.15494)
		(layer "In11.Cu")
		(net "SMB_BMC_9FGL0451E_SCL")
	)
	(segment
		(start 83.947 -271.355058)
		(end 88.288114 -281.83586)
		(width 0.15494)
		(layer "In11.Cu")
		(net "SMB_BMC_9FGL0451E_SCL")
	)
	(segment
		(start 94.9452 -288.492946)
		(end 94.9452 -292.658546)
		(width 0.15494)
		(layer "In11.Cu")
		(net "SMB_BMC_9FGL0451E_SCL")
	)
	(segment
		(start 124.968 -172.1358)
		(end 124.968 -179.7812)
		(width 0.15494)
		(layer "In11.Cu")
		(net "SMB_BMC_9FGL0451E_SCL")
	)
	(segment
		(start 101.4222 -324.433946)
		(end 103.841804 -326.85355)
		(width 0.15494)
		(layer "In11.Cu")
		(net "SMB_BMC_9FGL0451E_SCL")
	)
	(segment
		(start 129.835656 -169.310558)
		(end 127.793242 -169.310558)
		(width 0.15494)
		(layer "In11.Cu")
		(net "SMB_BMC_9FGL0451E_SCL")
	)
	(segment
		(start 101.4222 -317.432182)
		(end 101.4222 -324.433946)
		(width 0.15494)
		(layer "In11.Cu")
		(net "SMB_BMC_9FGL0451E_SCL")
	)
	(segment
		(start 124.968 -179.7812)
		(end 122.25909 -182.49011)
		(width 0.15494)
		(layer "In11.Cu")
		(net "SMB_BMC_9FGL0451E_SCL")
	)
	(segment
		(start 78.0542 -253.441454)
		(end 83.947 -259.334254)
		(width 0.15494)
		(layer "In11.Cu")
		(net "SMB_BMC_9FGL0451E_SCL")
	)
	(segment
		(start 96.647 -310.7436)
		(end 100.069142 -314.165742)
		(width 0.15494)
		(layer "In11.Cu")
		(net "SMB_BMC_9FGL0451E_SCL")
	)
	(segment
		(start 89.545668 -179.341272)
		(end 78.0542 -190.83274)
		(width 0.15494)
		(layer "In11.Cu")
		(net "SMB_BMC_9FGL0451E_SCL")
	)
	(segment
		(start 132.6388 -172.113702)
		(end 129.835656 -169.310558)
		(width 0.15494)
		(layer "In11.Cu")
		(net "SMB_BMC_9FGL0451E_SCL")
	)
	(segment
		(start 101.413056 -182.49011)
		(end 98.264218 -179.341272)
		(width 0.15494)
		(layer "In11.Cu")
		(net "SMB_BMC_9FGL0451E_SCL")
	)
	(segment
		(start 347.693742 -223.187006)
		(end 348.093538 -223.586802)
		(width 0.13208)
		(layer "F.Cu")
		(net "NIC2_AUX_PWR_EN")
	)
	(via
		(at 348.093538 -223.586802)
		(size 0.4572)
		(drill 0.254)
		(layers "F.Cu" "B.Cu")
		(net "NIC2_AUX_PWR_EN")
	)
	(via
		(at 166.630604 -139.96416)
		(size 0.6604)
		(drill 0.3302)
		(layers "F.Cu" "B.Cu")
		(net "NIC2_AUX_PWR_EN")
	)
	(via
		(at 167.025574 -146.795998)
		(size 0.508)
		(drill 0.254)
		(layers "F.Cu" "B.Cu")
		(net "NIC2_AUX_PWR_EN")
	)
	(via
		(at 175.889412 -185.582814)
		(size 0.508)
		(drill 0.254)
		(layers "F.Cu" "B.Cu")
		(net "NIC2_AUX_PWR_EN")
	)
	(segment
		(start 165.365938 -138.421618)
		(end 166.343838 -138.421618)
		(width 0.13208)
		(layer "B.Cu")
		(net "NIC2_AUX_PWR_EN")
	)
	(segment
		(start 166.630604 -139.96416)
		(end 167.025574 -140.35913)
		(width 0.13208)
		(layer "B.Cu")
		(net "NIC2_AUX_PWR_EN")
	)
	(segment
		(start 166.343838 -139.677394)
		(end 166.630604 -139.96416)
		(width 0.13208)
		(layer "B.Cu")
		(net "NIC2_AUX_PWR_EN")
	)
	(segment
		(start 167.025574 -140.35913)
		(end 167.025574 -146.795998)
		(width 0.13208)
		(layer "B.Cu")
		(net "NIC2_AUX_PWR_EN")
	)
	(segment
		(start 166.343838 -138.421618)
		(end 166.343838 -139.677394)
		(width 0.13208)
		(layer "B.Cu")
		(net "NIC2_AUX_PWR_EN")
	)
	(segment
		(start 168.64965 -147.101814)
		(end 170.029886 -148.48205)
		(width 0.15494)
		(layer "In9.Cu")
		(net "NIC2_AUX_PWR_EN")
	)
	(segment
		(start 175.889412 -184.180734)
		(end 175.889412 -185.582814)
		(width 0.15494)
		(layer "In9.Cu")
		(net "NIC2_AUX_PWR_EN")
	)
	(segment
		(start 167.025574 -146.795998)
		(end 167.33139 -147.101814)
		(width 0.15494)
		(layer "In9.Cu")
		(net "NIC2_AUX_PWR_EN")
	)
	(segment
		(start 170.029886 -178.321208)
		(end 175.889412 -184.180734)
		(width 0.15494)
		(layer "In9.Cu")
		(net "NIC2_AUX_PWR_EN")
	)
	(segment
		(start 170.029886 -148.48205)
		(end 170.029886 -178.321208)
		(width 0.15494)
		(layer "In9.Cu")
		(net "NIC2_AUX_PWR_EN")
	)
	(segment
		(start 167.33139 -147.101814)
		(end 168.64965 -147.101814)
		(width 0.15494)
		(layer "In9.Cu")
		(net "NIC2_AUX_PWR_EN")
	)
	(segment
		(start 222.793306 -175.993044)
		(end 222.42145 -175.993044)
		(width 0.15494)
		(layer "In15.Cu")
		(net "NIC2_AUX_PWR_EN")
	)
	(segment
		(start 230.454708 -176.09947)
		(end 229.62616 -175.756316)
		(width 0.15494)
		(layer "In15.Cu")
		(net "NIC2_AUX_PWR_EN")
	)
	(segment
		(start 349.862648 -223.179132)
		(end 350.101408 -223.417892)
		(width 0.0889)
		(layer "In15.Cu")
		(net "NIC2_AUX_PWR_EN")
	)
	(segment
		(start 364.957868 -224.440242)
		(end 367.016284 -222.381826)
		(width 0.15494)
		(layer "In15.Cu")
		(net "NIC2_AUX_PWR_EN")
	)
	(segment
		(start 358.381554 -181.63413)
		(end 357.9876 -181.63413)
		(width 0.15494)
		(layer "In15.Cu")
		(net "NIC2_AUX_PWR_EN")
	)
	(segment
		(start 342.225122 -176.17313)
		(end 335.060798 -176.17313)
		(width 0.15494)
		(layer "In15.Cu")
		(net "NIC2_AUX_PWR_EN")
	)
	(segment
		(start 217.133424 -176.43221)
		(end 216.69375 -175.992536)
		(width 0.15494)
		(layer "In15.Cu")
		(net "NIC2_AUX_PWR_EN")
	)
	(segment
		(start 350.46666 -179.145946)
		(end 348.634558 -179.145946)
		(width 0.15494)
		(layer "In15.Cu")
		(net "NIC2_AUX_PWR_EN")
	)
	(segment
		(start 185.904378 -175.992536)
		(end 184.713626 -177.183288)
		(width 0.15494)
		(layer "In15.Cu")
		(net "NIC2_AUX_PWR_EN")
	)
	(segment
		(start 180.291232 -178.640486)
		(end 175.889412 -183.042306)
		(width 0.15494)
		(layer "In15.Cu")
		(net "NIC2_AUX_PWR_EN")
	)
	(segment
		(start 367.016284 -212.779356)
		(end 366.69599 -212.459062)
		(width 0.15494)
		(layer "In15.Cu")
		(net "NIC2_AUX_PWR_EN")
	)
	(segment
		(start 357.396542 -226.225354)
		(end 358.223058 -227.05187)
		(width 0.15494)
		(layer "In15.Cu")
		(net "NIC2_AUX_PWR_EN")
	)
	(segment
		(start 181.155086 -177.183288)
		(end 180.89499 -177.290984)
		(width 0.15494)
		(layer "In15.Cu")
		(net "NIC2_AUX_PWR_EN")
	)
	(segment
		(start 232.448354 -176.727104)
		(end 231.966008 -177.20945)
		(width 0.15494)
		(layer "In15.Cu")
		(net "NIC2_AUX_PWR_EN")
	)
	(segment
		(start 346.831666 -177.343054)
		(end 343.395046 -177.343054)
		(width 0.15494)
		(layer "In15.Cu")
		(net "NIC2_AUX_PWR_EN")
	)
	(segment
		(start 350.101408 -223.417892)
		(end 350.101408 -223.8121)
		(width 0.0889)
		(layer "In15.Cu")
		(net "NIC2_AUX_PWR_EN")
	)
	(segment
		(start 356.628954 -226.225354)
		(end 357.396542 -226.225354)
		(width 0.15494)
		(layer "In15.Cu")
		(net "NIC2_AUX_PWR_EN")
	)
	(segment
		(start 184.713626 -177.183288)
		(end 181.155086 -177.183288)
		(width 0.15494)
		(layer "In15.Cu")
		(net "NIC2_AUX_PWR_EN")
	)
	(segment
		(start 296.790364 -177.009552)
		(end 296.507916 -176.727104)
		(width 0.15494)
		(layer "In15.Cu")
		(net "NIC2_AUX_PWR_EN")
	)
	(segment
		(start 229.149402 -175.756316)
		(end 228.240082 -174.846996)
		(width 0.15494)
		(layer "In15.Cu")
		(net "NIC2_AUX_PWR_EN")
	)
	(segment
		(start 366.69599 -204.788516)
		(end 367.00587 -204.478636)
		(width 0.15494)
		(layer "In15.Cu")
		(net "NIC2_AUX_PWR_EN")
	)
	(segment
		(start 360.868214 -227.05187)
		(end 363.479842 -224.440242)
		(width 0.15494)
		(layer "In15.Cu")
		(net "NIC2_AUX_PWR_EN")
	)
	(segment
		(start 367.00587 -201.60234)
		(end 366.697514 -201.293984)
		(width 0.15494)
		(layer "In15.Cu")
		(net "NIC2_AUX_PWR_EN")
	)
	(segment
		(start 367.00587 -204.478636)
		(end 367.00587 -201.60234)
		(width 0.15494)
		(layer "In15.Cu")
		(net "NIC2_AUX_PWR_EN")
	)
	(segment
		(start 363.345222 -186.04738)
		(end 363.16285 -186.04738)
		(width 0.15494)
		(layer "In15.Cu")
		(net "NIC2_AUX_PWR_EN")
	)
	(segment
		(start 228.240082 -174.846996)
		(end 223.939354 -174.846996)
		(width 0.15494)
		(layer "In15.Cu")
		(net "NIC2_AUX_PWR_EN")
	)
	(segment
		(start 334.224376 -177.009552)
		(end 296.790364 -177.009552)
		(width 0.15494)
		(layer "In15.Cu")
		(net "NIC2_AUX_PWR_EN")
	)
	(segment
		(start 360.359198 -182.617618)
		(end 359.365042 -182.617618)
		(width 0.15494)
		(layer "In15.Cu")
		(net "NIC2_AUX_PWR_EN")
	)
	(segment
		(start 349.517462 -223.186498)
		(end 349.524828 -223.179132)
		(width 0.0889)
		(layer "In15.Cu")
		(net "NIC2_AUX_PWR_EN")
	)
	(segment
		(start 231.966008 -177.20945)
		(end 231.564688 -177.20945)
		(width 0.15494)
		(layer "In15.Cu")
		(net "NIC2_AUX_PWR_EN")
	)
	(segment
		(start 231.564688 -177.20945)
		(end 230.454708 -176.09947)
		(width 0.15494)
		(layer "In15.Cu")
		(net "NIC2_AUX_PWR_EN")
	)
	(segment
		(start 296.507916 -176.727104)
		(end 232.448354 -176.727104)
		(width 0.15494)
		(layer "In15.Cu")
		(net "NIC2_AUX_PWR_EN")
	)
	(segment
		(start 366.697514 -189.399672)
		(end 363.345222 -186.04738)
		(width 0.15494)
		(layer "In15.Cu")
		(net "NIC2_AUX_PWR_EN")
	)
	(segment
		(start 359.365042 -182.617618)
		(end 358.381554 -181.63413)
		(width 0.15494)
		(layer "In15.Cu")
		(net "NIC2_AUX_PWR_EN")
	)
	(segment
		(start 348.093538 -223.586802)
		(end 348.093538 -223.471486)
		(width 0.0889)
		(layer "In15.Cu")
		(net "NIC2_AUX_PWR_EN")
	)
	(segment
		(start 229.62616 -175.756316)
		(end 229.149402 -175.756316)
		(width 0.15494)
		(layer "In15.Cu")
		(net "NIC2_AUX_PWR_EN")
	)
	(segment
		(start 216.69375 -175.992536)
		(end 185.904378 -175.992536)
		(width 0.15494)
		(layer "In15.Cu")
		(net "NIC2_AUX_PWR_EN")
	)
	(segment
		(start 180.291232 -177.894742)
		(end 180.291232 -178.640486)
		(width 0.15494)
		(layer "In15.Cu")
		(net "NIC2_AUX_PWR_EN")
	)
	(segment
		(start 358.223058 -227.05187)
		(end 360.868214 -227.05187)
		(width 0.15494)
		(layer "In15.Cu")
		(net "NIC2_AUX_PWR_EN")
	)
	(segment
		(start 357.9876 -181.63413)
		(end 355.4476 -179.09413)
		(width 0.15494)
		(layer "In15.Cu")
		(net "NIC2_AUX_PWR_EN")
	)
	(segment
		(start 351.584768 -223.979232)
		(end 354.382832 -223.979232)
		(width 0.15494)
		(layer "In15.Cu")
		(net "NIC2_AUX_PWR_EN")
	)
	(segment
		(start 335.060798 -176.17313)
		(end 334.224376 -177.009552)
		(width 0.15494)
		(layer "In15.Cu")
		(net "NIC2_AUX_PWR_EN")
	)
	(segment
		(start 343.395046 -177.343054)
		(end 342.225122 -176.17313)
		(width 0.15494)
		(layer "In15.Cu")
		(net "NIC2_AUX_PWR_EN")
	)
	(segment
		(start 223.939354 -174.846996)
		(end 222.793306 -175.993044)
		(width 0.15494)
		(layer "In15.Cu")
		(net "NIC2_AUX_PWR_EN")
	)
	(segment
		(start 221.982284 -176.43221)
		(end 217.133424 -176.43221)
		(width 0.15494)
		(layer "In15.Cu")
		(net "NIC2_AUX_PWR_EN")
	)
	(segment
		(start 350.26854 -223.979232)
		(end 351.584768 -223.979232)
		(width 0.0889)
		(layer "In15.Cu")
		(net "NIC2_AUX_PWR_EN")
	)
	(segment
		(start 363.479842 -224.440242)
		(end 364.957868 -224.440242)
		(width 0.15494)
		(layer "In15.Cu")
		(net "NIC2_AUX_PWR_EN")
	)
	(segment
		(start 350.518476 -179.09413)
		(end 350.46666 -179.145946)
		(width 0.15494)
		(layer "In15.Cu")
		(net "NIC2_AUX_PWR_EN")
	)
	(segment
		(start 366.69599 -212.459062)
		(end 366.69599 -204.788516)
		(width 0.15494)
		(layer "In15.Cu")
		(net "NIC2_AUX_PWR_EN")
	)
	(segment
		(start 361.108244 -183.366664)
		(end 360.359198 -182.617618)
		(width 0.15494)
		(layer "In15.Cu")
		(net "NIC2_AUX_PWR_EN")
	)
	(segment
		(start 354.382832 -223.979232)
		(end 356.628954 -226.225354)
		(width 0.15494)
		(layer "In15.Cu")
		(net "NIC2_AUX_PWR_EN")
	)
	(segment
		(start 349.524828 -223.179132)
		(end 349.862648 -223.179132)
		(width 0.0889)
		(layer "In15.Cu")
		(net "NIC2_AUX_PWR_EN")
	)
	(segment
		(start 355.4476 -179.09413)
		(end 350.518476 -179.09413)
		(width 0.15494)
		(layer "In15.Cu")
		(net "NIC2_AUX_PWR_EN")
	)
	(segment
		(start 361.108244 -183.992774)
		(end 361.108244 -183.366664)
		(width 0.15494)
		(layer "In15.Cu")
		(net "NIC2_AUX_PWR_EN")
	)
	(segment
		(start 180.89499 -177.290984)
		(end 180.291232 -177.894742)
		(width 0.15494)
		(layer "In15.Cu")
		(net "NIC2_AUX_PWR_EN")
	)
	(segment
		(start 348.378526 -223.186498)
		(end 349.517462 -223.186498)
		(width 0.0889)
		(layer "In15.Cu")
		(net "NIC2_AUX_PWR_EN")
	)
	(segment
		(start 363.16285 -186.04738)
		(end 361.108244 -183.992774)
		(width 0.15494)
		(layer "In15.Cu")
		(net "NIC2_AUX_PWR_EN")
	)
	(segment
		(start 348.093538 -223.471486)
		(end 348.378526 -223.186498)
		(width 0.0889)
		(layer "In15.Cu")
		(net "NIC2_AUX_PWR_EN")
	)
	(segment
		(start 367.016284 -222.381826)
		(end 367.016284 -212.779356)
		(width 0.15494)
		(layer "In15.Cu")
		(net "NIC2_AUX_PWR_EN")
	)
	(segment
		(start 366.697514 -201.293984)
		(end 366.697514 -189.399672)
		(width 0.15494)
		(layer "In15.Cu")
		(net "NIC2_AUX_PWR_EN")
	)
	(segment
		(start 348.634558 -179.145946)
		(end 346.831666 -177.343054)
		(width 0.15494)
		(layer "In15.Cu")
		(net "NIC2_AUX_PWR_EN")
	)
	(segment
		(start 222.42145 -175.993044)
		(end 221.982284 -176.43221)
		(width 0.15494)
		(layer "In15.Cu")
		(net "NIC2_AUX_PWR_EN")
	)
	(segment
		(start 175.889412 -183.042306)
		(end 175.889412 -185.582814)
		(width 0.15494)
		(layer "In15.Cu")
		(net "NIC2_AUX_PWR_EN")
	)
	(segment
		(start 350.101408 -223.8121)
		(end 350.26854 -223.979232)
		(width 0.0889)
		(layer "In15.Cu")
		(net "NIC2_AUX_PWR_EN")
	)
	(segment
		(start 193.453258 -18.430748)
		(end 192.168018 -18.430748)
		(width 0.13208)
		(layer "F.Cu")
		(net "SMB_ISO_SSD6_SCL")
	)
	(segment
		(start 194.559428 -23.355554)
		(end 194.559428 -23.965154)
		(width 0.13208)
		(layer "F.Cu")
		(net "SMB_ISO_SSD6_SCL")
	)
	(segment
		(start 194.385438 -17.498568)
		(end 193.453258 -18.430748)
		(width 0.13208)
		(layer "F.Cu")
		(net "SMB_ISO_SSD6_SCL")
	)
	(segment
		(start 192.11798 -18.430748)
		(end 191.356488 -17.669256)
		(width 0.13208)
		(layer "F.Cu")
		(net "SMB_ISO_SSD6_SCL")
	)
	(segment
		(start 192.168018 -18.430748)
		(end 192.11798 -18.430748)
		(width 0.13208)
		(layer "F.Cu")
		(net "SMB_ISO_SSD6_SCL")
	)
	(segment
		(start 191.356488 -17.669256)
		(end 191.356488 -17.419574)
		(width 0.13208)
		(layer "F.Cu")
		(net "SMB_ISO_SSD6_SCL")
	)
	(segment
		(start 194.385438 -16.439388)
		(end 194.385438 -17.498568)
		(width 0.13208)
		(layer "F.Cu")
		(net "SMB_ISO_SSD6_SCL")
	)
	(segment
		(start 194.385438 -15.370302)
		(end 194.385438 -16.439388)
		(width 0.13208)
		(layer "F.Cu")
		(net "SMB_ISO_SSD6_SCL")
	)
	(via
		(at 194.385438 -15.370302)
		(size 0.508)
		(drill 0.254)
		(layers "F.Cu" "B.Cu")
		(net "SMB_ISO_SSD6_SCL")
	)
	(via
		(at 194.559428 -23.965154)
		(size 0.508)
		(drill 0.254)
		(layers "F.Cu" "B.Cu")
		(net "SMB_ISO_SSD6_SCL")
	)
	(segment
		(start 195.940172 -22.58441)
		(end 195.940172 -16.925036)
		(width 0.13208)
		(layer "B.Cu")
		(net "SMB_ISO_SSD6_SCL")
	)
	(segment
		(start 194.559428 -23.965154)
		(end 195.940172 -22.58441)
		(width 0.13208)
		(layer "B.Cu")
		(net "SMB_ISO_SSD6_SCL")
	)
	(segment
		(start 195.940172 -16.925036)
		(end 194.385438 -15.370302)
		(width 0.13208)
		(layer "B.Cu")
		(net "SMB_ISO_SSD6_SCL")
	)
	(segment
		(start 370.958364 -18.44421)
		(end 370.965476 -18.437098)
		(width 0.13208)
		(layer "F.Cu")
		(net "SMB_ISO_SSD12_R_SCL")
	)
	(segment
		(start 360.76763 -22.3901)
		(end 361.39374 -23.01621)
		(width 0.13208)
		(layer "F.Cu")
		(net "SMB_ISO_SSD12_R_SCL")
	)
	(segment
		(start 358.964992 -22.3901)
		(end 360.76763 -22.3901)
		(width 0.13208)
		(layer "F.Cu")
		(net "SMB_ISO_SSD12_R_SCL")
	)
	(segment
		(start 370.965476 -18.437098)
		(end 371.567964 -18.437098)
		(width 0.13208)
		(layer "F.Cu")
		(net "SMB_ISO_SSD12_R_SCL")
	)
	(via
		(at 370.958364 -18.44421)
		(size 0.508)
		(drill 0.254)
		(layers "F.Cu" "B.Cu")
		(net "SMB_ISO_SSD12_R_SCL")
	)
	(via
		(at 361.39374 -23.01621)
		(size 0.508)
		(drill 0.254)
		(layers "F.Cu" "B.Cu")
		(net "SMB_ISO_SSD12_R_SCL")
	)
	(segment
		(start 369.98275 -23.01621)
		(end 361.39374 -23.01621)
		(width 0.15494)
		(layer "In5.Cu")
		(net "SMB_ISO_SSD12_R_SCL")
	)
	(segment
		(start 370.958364 -18.44421)
		(end 371.52707 -19.012916)
		(width 0.15494)
		(layer "In5.Cu")
		(net "SMB_ISO_SSD12_R_SCL")
	)
	(segment
		(start 371.52707 -19.012916)
		(end 371.52707 -21.47189)
		(width 0.15494)
		(layer "In5.Cu")
		(net "SMB_ISO_SSD12_R_SCL")
	)
	(segment
		(start 371.52707 -21.47189)
		(end 369.98275 -23.01621)
		(width 0.15494)
		(layer "In5.Cu")
		(net "SMB_ISO_SSD12_R_SCL")
	)
	(segment
		(start 303.7332 -82.296)
		(end 303.7332 -83.294474)
		(width 0.13208)
		(layer "F.Cu")
		(net "SMB_BIC_I2C6_MUX_FRU_R_SCL")
	)
	(segment
		(start 303.360582 -83.667092)
		(end 302.777906 -83.667092)
		(width 0.13208)
		(layer "F.Cu")
		(net "SMB_BIC_I2C6_MUX_FRU_R_SCL")
	)
	(segment
		(start 303.7332 -83.294474)
		(end 303.360582 -83.667092)
		(width 0.13208)
		(layer "F.Cu")
		(net "SMB_BIC_I2C6_MUX_FRU_R_SCL")
	)
	(segment
		(start 322.146676 -83.98637)
		(end 320.675 -83.98637)
		(width 0.13208)
		(layer "F.Cu")
		(net "SMB_BIC_I2C6_MUX_FRU_R_SCL")
	)
	(via
		(at 303.7332 -82.296)
		(size 0.508)
		(drill 0.254)
		(layers "F.Cu" "B.Cu")
		(net "SMB_BIC_I2C6_MUX_FRU_R_SCL")
	)
	(via
		(at 320.675 -83.98637)
		(size 0.508)
		(drill 0.254)
		(layers "F.Cu" "B.Cu")
		(net "SMB_BIC_I2C6_MUX_FRU_R_SCL")
	)
	(segment
		(start 320.675 -83.627976)
		(end 320.79311 -83.509866)
		(width 0.13208)
		(layer "B.Cu")
		(net "SMB_BIC_I2C6_MUX_FRU_R_SCL")
	)
	(segment
		(start 321.057778 -84.144866)
		(end 321.435476 -84.144866)
		(width 0.13208)
		(layer "B.Cu")
		(net "SMB_BIC_I2C6_MUX_FRU_R_SCL")
	)
	(segment
		(start 321.725544 -84.434934)
		(end 323.724016 -84.434934)
		(width 0.13208)
		(layer "B.Cu")
		(net "SMB_BIC_I2C6_MUX_FRU_R_SCL")
	)
	(segment
		(start 320.675 -83.98637)
		(end 320.675 -83.627976)
		(width 0.13208)
		(layer "B.Cu")
		(net "SMB_BIC_I2C6_MUX_FRU_R_SCL")
	)
	(segment
		(start 323.724016 -84.434934)
		(end 324.21195 -83.947)
		(width 0.13208)
		(layer "B.Cu")
		(net "SMB_BIC_I2C6_MUX_FRU_R_SCL")
	)
	(segment
		(start 320.968116 -83.123278)
		(end 321.00647 -83.123278)
		(width 0.13208)
		(layer "B.Cu")
		(net "SMB_BIC_I2C6_MUX_FRU_R_SCL")
	)
	(segment
		(start 321.435476 -84.144866)
		(end 321.725544 -84.434934)
		(width 0.13208)
		(layer "B.Cu")
		(net "SMB_BIC_I2C6_MUX_FRU_R_SCL")
	)
	(segment
		(start 320.79311 -83.509866)
		(end 320.79311 -83.298284)
		(width 0.13208)
		(layer "B.Cu")
		(net "SMB_BIC_I2C6_MUX_FRU_R_SCL")
	)
	(segment
		(start 320.675 -83.98637)
		(end 321.057778 -84.144866)
		(width 0.13208)
		(layer "B.Cu")
		(net "SMB_BIC_I2C6_MUX_FRU_R_SCL")
	)
	(segment
		(start 320.79311 -83.298284)
		(end 320.968116 -83.123278)
		(width 0.13208)
		(layer "B.Cu")
		(net "SMB_BIC_I2C6_MUX_FRU_R_SCL")
	)
	(segment
		(start 321.00647 -83.123278)
		(end 321.960748 -83.123278)
		(width 0.13208)
		(layer "B.Cu")
		(net "SMB_BIC_I2C6_MUX_FRU_R_SCL")
	)
	(segment
		(start 304.416968 -82.979768)
		(end 319.962022 -82.979768)
		(width 0.15494)
		(layer "In15.Cu")
		(net "SMB_BIC_I2C6_MUX_FRU_R_SCL")
	)
	(segment
		(start 319.962022 -82.979768)
		(end 320.467228 -83.484974)
		(width 0.15494)
		(layer "In15.Cu")
		(net "SMB_BIC_I2C6_MUX_FRU_R_SCL")
	)
	(segment
		(start 320.467228 -83.484974)
		(end 320.675 -83.98637)
		(width 0.15494)
		(layer "In15.Cu")
		(net "SMB_BIC_I2C6_MUX_FRU_R_SCL")
	)
	(segment
		(start 303.7332 -82.296)
		(end 304.416968 -82.979768)
		(width 0.15494)
		(layer "In15.Cu")
		(net "SMB_BIC_I2C6_MUX_FRU_R_SCL")
	)
	(via
		(at 111.161576 -329.395836)
		(size 0.6604)
		(drill 0.3302)
		(layers "F.Cu" "B.Cu")
		(net "SMB_BMC_9FGL0451E_SDA")
	)
	(segment
		(start 110.63859 -329.765152)
		(end 110.79226 -329.765152)
		(width 0.13208)
		(layer "B.Cu")
		(net "SMB_BMC_9FGL0451E_SDA")
	)
	(segment
		(start 110.79226 -329.765152)
		(end 111.161576 -329.395836)
		(width 0.13208)
		(layer "B.Cu")
		(net "SMB_BMC_9FGL0451E_SDA")
	)
	(segment
		(start 108.689394 -330.800456)
		(end 109.603286 -330.800456)
		(width 0.13208)
		(layer "B.Cu")
		(net "SMB_BMC_9FGL0451E_SDA")
	)
	(segment
		(start 109.603286 -330.800456)
		(end 110.63859 -329.765152)
		(width 0.13208)
		(layer "B.Cu")
		(net "SMB_BMC_9FGL0451E_SDA")
	)
	(segment
		(start 111.161576 -329.395836)
		(end 111.161576 -328.324464)
		(width 0.13208)
		(layer "B.Cu")
		(net "SMB_BMC_9FGL0451E_SDA")
	)
	(segment
		(start 111.161576 -328.324464)
		(end 111.229648 -328.256392)
		(width 0.13208)
		(layer "B.Cu")
		(net "SMB_BMC_9FGL0451E_SDA")
	)
	(segment
		(start 350.893888 -222.38716)
		(end 351.293684 -222.786956)
		(width 0.13208)
		(layer "F.Cu")
		(net "PWRGD_NIC2_PWR_GOOD_R")
	)
	(segment
		(start 183.13019 -180.761132)
		(end 182.503826 -181.387496)
		(width 0.13208)
		(layer "F.Cu")
		(net "PWRGD_NIC2_PWR_GOOD_R")
	)
	(segment
		(start 154.307794 -163.061396)
		(end 154.307794 -163.883594)
		(width 0.13208)
		(layer "F.Cu")
		(net "PWRGD_NIC2_PWR_GOOD_R")
	)
	(segment
		(start 182.503826 -181.387496)
		(end 166.80942 -181.387496)
		(width 0.13208)
		(layer "F.Cu")
		(net "PWRGD_NIC2_PWR_GOOD_R")
	)
	(segment
		(start 154.307794 -166.360602)
		(end 155.082748 -165.585648)
		(width 0.13208)
		(layer "F.Cu")
		(net "PWRGD_NIC2_PWR_GOOD_R")
	)
	(segment
		(start 155.082748 -165.585648)
		(end 155.082748 -164.658548)
		(width 0.13208)
		(layer "F.Cu")
		(net "PWRGD_NIC2_PWR_GOOD_R")
	)
	(segment
		(start 154.307794 -163.883594)
		(end 155.082748 -164.658548)
		(width 0.13208)
		(layer "F.Cu")
		(net "PWRGD_NIC2_PWR_GOOD_R")
	)
	(segment
		(start 154.307794 -168.88587)
		(end 154.307794 -166.360602)
		(width 0.13208)
		(layer "F.Cu")
		(net "PWRGD_NIC2_PWR_GOOD_R")
	)
	(segment
		(start 166.80942 -181.387496)
		(end 154.307794 -168.88587)
		(width 0.13208)
		(layer "F.Cu")
		(net "PWRGD_NIC2_PWR_GOOD_R")
	)
	(via
		(at 155.082748 -164.658548)
		(size 0.762)
		(drill 0.381)
		(layers "F.Cu" "B.Cu")
		(net "PWRGD_NIC2_PWR_GOOD_R")
	)
	(via
		(at 183.13019 -180.761132)
		(size 0.508)
		(drill 0.254)
		(layers "F.Cu" "B.Cu")
		(net "PWRGD_NIC2_PWR_GOOD_R")
	)
	(via
		(at 351.293684 -222.786956)
		(size 0.4572)
		(drill 0.254)
		(layers "F.Cu" "B.Cu")
		(net "PWRGD_NIC2_PWR_GOOD_R")
	)
	(segment
		(start 253.586488 -180.303678)
		(end 281.746706 -180.303678)
		(width 0.15494)
		(layer "In15.Cu")
		(net "PWRGD_NIC2_PWR_GOOD_R")
	)
	(segment
		(start 354.773738 -184.163208)
		(end 358.62387 -188.01334)
		(width 0.15494)
		(layer "In15.Cu")
		(net "PWRGD_NIC2_PWR_GOOD_R")
	)
	(segment
		(start 248.534682 -182.764684)
		(end 251.125482 -182.764684)
		(width 0.15494)
		(layer "In15.Cu")
		(net "PWRGD_NIC2_PWR_GOOD_R")
	)
	(segment
		(start 360.321098 -223.877124)
		(end 358.716072 -223.877124)
		(width 0.15494)
		(layer "In15.Cu")
		(net "PWRGD_NIC2_PWR_GOOD_R")
	)
	(segment
		(start 360.604308 -223.195896)
		(end 360.604308 -223.593914)
		(width 0.15494)
		(layer "In15.Cu")
		(net "PWRGD_NIC2_PWR_GOOD_R")
	)
	(segment
		(start 358.62387 -188.485272)
		(end 360.83494 -190.696342)
		(width 0.15494)
		(layer "In15.Cu")
		(net "PWRGD_NIC2_PWR_GOOD_R")
	)
	(segment
		(start 354.32365 -222.02013)
		(end 353.556824 -222.786956)
		(width 0.15494)
		(layer "In15.Cu")
		(net "PWRGD_NIC2_PWR_GOOD_R")
	)
	(segment
		(start 232.165398 -180.923946)
		(end 232.45191 -181.210458)
		(width 0.15494)
		(layer "In15.Cu")
		(net "PWRGD_NIC2_PWR_GOOD_R")
	)
	(segment
		(start 295.824148 -181.649116)
		(end 296.56659 -181.649116)
		(width 0.15494)
		(layer "In15.Cu")
		(net "PWRGD_NIC2_PWR_GOOD_R")
	)
	(segment
		(start 184.197498 -179.693824)
		(end 213.644988 -179.693824)
		(width 0.15494)
		(layer "In15.Cu")
		(net "PWRGD_NIC2_PWR_GOOD_R")
	)
	(segment
		(start 362.3056 -219.410026)
		(end 360.831638 -222.968566)
		(width 0.15494)
		(layer "In15.Cu")
		(net "PWRGD_NIC2_PWR_GOOD_R")
	)
	(segment
		(start 183.13019 -180.761132)
		(end 184.197498 -179.693824)
		(width 0.15494)
		(layer "In15.Cu")
		(net "PWRGD_NIC2_PWR_GOOD_R")
	)
	(segment
		(start 281.746706 -180.303678)
		(end 283.117036 -181.674008)
		(width 0.15494)
		(layer "In15.Cu")
		(net "PWRGD_NIC2_PWR_GOOD_R")
	)
	(segment
		(start 341.182452 -183.016652)
		(end 342.329008 -184.163208)
		(width 0.15494)
		(layer "In15.Cu")
		(net "PWRGD_NIC2_PWR_GOOD_R")
	)
	(segment
		(start 339.644482 -183.016652)
		(end 341.182452 -183.016652)
		(width 0.15494)
		(layer "In15.Cu")
		(net "PWRGD_NIC2_PWR_GOOD_R")
	)
	(segment
		(start 214.628476 -178.710336)
		(end 215.029796 -178.710336)
		(width 0.15494)
		(layer "In15.Cu")
		(net "PWRGD_NIC2_PWR_GOOD_R")
	)
	(segment
		(start 342.329008 -184.163208)
		(end 354.773738 -184.163208)
		(width 0.15494)
		(layer "In15.Cu")
		(net "PWRGD_NIC2_PWR_GOOD_R")
	)
	(segment
		(start 219.453968 -180.123846)
		(end 219.56649 -180.011324)
		(width 0.15494)
		(layer "In15.Cu")
		(net "PWRGD_NIC2_PWR_GOOD_R")
	)
	(segment
		(start 358.716072 -223.877124)
		(end 356.859078 -222.02013)
		(width 0.15494)
		(layer "In15.Cu")
		(net "PWRGD_NIC2_PWR_GOOD_R")
	)
	(segment
		(start 231.764078 -180.923946)
		(end 232.165398 -180.923946)
		(width 0.15494)
		(layer "In15.Cu")
		(net "PWRGD_NIC2_PWR_GOOD_R")
	)
	(segment
		(start 358.62387 -188.01334)
		(end 358.62387 -188.485272)
		(width 0.15494)
		(layer "In15.Cu")
		(net "PWRGD_NIC2_PWR_GOOD_R")
	)
	(segment
		(start 362.3056 -217.195654)
		(end 362.3056 -219.410026)
		(width 0.15494)
		(layer "In15.Cu")
		(net "PWRGD_NIC2_PWR_GOOD_R")
	)
	(segment
		(start 296.56659 -181.649116)
		(end 297.213274 -182.2958)
		(width 0.15494)
		(layer "In15.Cu")
		(net "PWRGD_NIC2_PWR_GOOD_R")
	)
	(segment
		(start 334.82534 -182.47487)
		(end 339.1027 -182.47487)
		(width 0.15494)
		(layer "In15.Cu")
		(net "PWRGD_NIC2_PWR_GOOD_R")
	)
	(segment
		(start 231.661716 -181.026308)
		(end 231.764078 -180.923946)
		(width 0.15494)
		(layer "In15.Cu")
		(net "PWRGD_NIC2_PWR_GOOD_R")
	)
	(segment
		(start 227.175822 -180.011324)
		(end 228.190806 -181.026308)
		(width 0.15494)
		(layer "In15.Cu")
		(net "PWRGD_NIC2_PWR_GOOD_R")
	)
	(segment
		(start 213.644988 -179.693824)
		(end 214.628476 -178.710336)
		(width 0.15494)
		(layer "In15.Cu")
		(net "PWRGD_NIC2_PWR_GOOD_R")
	)
	(segment
		(start 251.125482 -182.764684)
		(end 253.586488 -180.303678)
		(width 0.15494)
		(layer "In15.Cu")
		(net "PWRGD_NIC2_PWR_GOOD_R")
	)
	(segment
		(start 215.029796 -178.710336)
		(end 216.443306 -180.123846)
		(width 0.15494)
		(layer "In15.Cu")
		(net "PWRGD_NIC2_PWR_GOOD_R")
	)
	(segment
		(start 360.83494 -198.458836)
		(end 362.94187 -200.565766)
		(width 0.15494)
		(layer "In15.Cu")
		(net "PWRGD_NIC2_PWR_GOOD_R")
	)
	(segment
		(start 356.859078 -222.02013)
		(end 354.32365 -222.02013)
		(width 0.15494)
		(layer "In15.Cu")
		(net "PWRGD_NIC2_PWR_GOOD_R")
	)
	(segment
		(start 362.94187 -216.559384)
		(end 362.3056 -217.195654)
		(width 0.15494)
		(layer "In15.Cu")
		(net "PWRGD_NIC2_PWR_GOOD_R")
	)
	(segment
		(start 362.94187 -200.565766)
		(end 362.94187 -216.559384)
		(width 0.15494)
		(layer "In15.Cu")
		(net "PWRGD_NIC2_PWR_GOOD_R")
	)
	(segment
		(start 283.117036 -181.674008)
		(end 295.799256 -181.674008)
		(width 0.15494)
		(layer "In15.Cu")
		(net "PWRGD_NIC2_PWR_GOOD_R")
	)
	(segment
		(start 216.443306 -180.123846)
		(end 219.453968 -180.123846)
		(width 0.15494)
		(layer "In15.Cu")
		(net "PWRGD_NIC2_PWR_GOOD_R")
	)
	(segment
		(start 360.604308 -223.593914)
		(end 360.321098 -223.877124)
		(width 0.15494)
		(layer "In15.Cu")
		(net "PWRGD_NIC2_PWR_GOOD_R")
	)
	(segment
		(start 228.190806 -181.026308)
		(end 231.661716 -181.026308)
		(width 0.15494)
		(layer "In15.Cu")
		(net "PWRGD_NIC2_PWR_GOOD_R")
	)
	(segment
		(start 353.556824 -222.786956)
		(end 351.293684 -222.786956)
		(width 0.15494)
		(layer "In15.Cu")
		(net "PWRGD_NIC2_PWR_GOOD_R")
	)
	(segment
		(start 334.64627 -182.2958)
		(end 334.82534 -182.47487)
		(width 0.15494)
		(layer "In15.Cu")
		(net "PWRGD_NIC2_PWR_GOOD_R")
	)
	(segment
		(start 360.831638 -222.968566)
		(end 360.604308 -223.195896)
		(width 0.15494)
		(layer "In15.Cu")
		(net "PWRGD_NIC2_PWR_GOOD_R")
	)
	(segment
		(start 246.980456 -181.210458)
		(end 248.534682 -182.764684)
		(width 0.15494)
		(layer "In15.Cu")
		(net "PWRGD_NIC2_PWR_GOOD_R")
	)
	(segment
		(start 219.56649 -180.011324)
		(end 227.175822 -180.011324)
		(width 0.15494)
		(layer "In15.Cu")
		(net "PWRGD_NIC2_PWR_GOOD_R")
	)
	(segment
		(start 297.213274 -182.2958)
		(end 334.64627 -182.2958)
		(width 0.15494)
		(layer "In15.Cu")
		(net "PWRGD_NIC2_PWR_GOOD_R")
	)
	(segment
		(start 339.1027 -182.47487)
		(end 339.644482 -183.016652)
		(width 0.15494)
		(layer "In15.Cu")
		(net "PWRGD_NIC2_PWR_GOOD_R")
	)
	(segment
		(start 360.83494 -190.696342)
		(end 360.83494 -198.458836)
		(width 0.15494)
		(layer "In15.Cu")
		(net "PWRGD_NIC2_PWR_GOOD_R")
	)
	(segment
		(start 232.45191 -181.210458)
		(end 246.980456 -181.210458)
		(width 0.15494)
		(layer "In15.Cu")
		(net "PWRGD_NIC2_PWR_GOOD_R")
	)
	(segment
		(start 295.799256 -181.674008)
		(end 295.824148 -181.649116)
		(width 0.15494)
		(layer "In15.Cu")
		(net "PWRGD_NIC2_PWR_GOOD_R")
	)
	(segment
		(start 138.677904 -174.504096)
		(end 139.296902 -174.504096)
		(width 0.13462)
		(layer "F.Cu")
		(net "CLK_100M_DB2000QL_NIC2_DN")
	)
	(segment
		(start 137.400792 -175.781208)
		(end 138.677904 -174.504096)
		(width 0.13462)
		(layer "F.Cu")
		(net "CLK_100M_DB2000QL_NIC2_DN")
	)
	(segment
		(start 135.59028 -175.781208)
		(end 137.400792 -175.781208)
		(width 0.13462)
		(layer "F.Cu")
		(net "CLK_100M_DB2000QL_NIC2_DN")
	)
	(segment
		(start 139.296902 -174.504096)
		(end 139.674092 -174.881286)
		(width 0.13462)
		(layer "F.Cu")
		(net "CLK_100M_DB2000QL_NIC2_DN")
	)
	(segment
		(start 135.471154 -175.900334)
		(end 135.59028 -175.781208)
		(width 0.13462)
		(layer "F.Cu")
		(net "CLK_100M_DB2000QL_NIC2_DN")
	)
	(segment
		(start 448.958208 -18.44421)
		(end 448.96532 -18.437098)
		(width 0.13208)
		(layer "F.Cu")
		(net "SMB_ISO_SSD15_R_SCL")
	)
	(segment
		(start 436.964836 -22.3901)
		(end 438.767474 -22.3901)
		(width 0.13208)
		(layer "F.Cu")
		(net "SMB_ISO_SSD15_R_SCL")
	)
	(segment
		(start 438.767474 -22.3901)
		(end 439.393584 -23.01621)
		(width 0.13208)
		(layer "F.Cu")
		(net "SMB_ISO_SSD15_R_SCL")
	)
	(segment
		(start 448.96532 -18.437098)
		(end 449.567808 -18.437098)
		(width 0.13208)
		(layer "F.Cu")
		(net "SMB_ISO_SSD15_R_SCL")
	)
	(via
		(at 439.393584 -23.01621)
		(size 0.508)
		(drill 0.254)
		(layers "F.Cu" "B.Cu")
		(net "SMB_ISO_SSD15_R_SCL")
	)
	(via
		(at 448.958208 -18.44421)
		(size 0.508)
		(drill 0.254)
		(layers "F.Cu" "B.Cu")
		(net "SMB_ISO_SSD15_R_SCL")
	)
	(segment
		(start 449.526914 -21.47189)
		(end 447.982594 -23.01621)
		(width 0.15494)
		(layer "In5.Cu")
		(net "SMB_ISO_SSD15_R_SCL")
	)
	(segment
		(start 449.526914 -19.012916)
		(end 449.526914 -21.47189)
		(width 0.15494)
		(layer "In5.Cu")
		(net "SMB_ISO_SSD15_R_SCL")
	)
	(segment
		(start 447.982594 -23.01621)
		(end 439.393584 -23.01621)
		(width 0.15494)
		(layer "In5.Cu")
		(net "SMB_ISO_SSD15_R_SCL")
	)
	(segment
		(start 448.958208 -18.44421)
		(end 449.526914 -19.012916)
		(width 0.15494)
		(layer "In5.Cu")
		(net "SMB_ISO_SSD15_R_SCL")
	)
	(segment
		(start 322.146676 -84.63661)
		(end 321.11061 -84.63661)
		(width 0.13208)
		(layer "F.Cu")
		(net "SMB_BIC_I2C6_MUX_FRU_R_SDA")
	)
	(segment
		(start 394.161264 -87.596218)
		(end 394.069316 -87.50427)
		(width 0.13208)
		(layer "F.Cu")
		(net "SMB_BIC_I2C6_MUX_FRU_R_SDA")
	)
	(segment
		(start 301.538386 -82.332068)
		(end 302.292258 -82.332068)
		(width 0.13208)
		(layer "F.Cu")
		(net "SMB_BIC_I2C6_MUX_FRU_R_SDA")
	)
	(segment
		(start 394.069316 -87.50427)
		(end 394.069316 -87.214202)
		(width 0.13208)
		(layer "F.Cu")
		(net "SMB_BIC_I2C6_MUX_FRU_R_SDA")
	)
	(segment
		(start 394.680948 -87.596218)
		(end 394.161264 -87.596218)
		(width 0.13208)
		(layer "F.Cu")
		(net "SMB_BIC_I2C6_MUX_FRU_R_SDA")
	)
	(segment
		(start 395.062964 -87.214202)
		(end 394.680948 -87.596218)
		(width 0.13208)
		(layer "F.Cu")
		(net "SMB_BIC_I2C6_MUX_FRU_R_SDA")
	)
	(segment
		(start 395.809216 -87.214202)
		(end 395.062964 -87.214202)
		(width 0.13208)
		(layer "F.Cu")
		(net "SMB_BIC_I2C6_MUX_FRU_R_SDA")
	)
	(via
		(at 321.11061 -84.63661)
		(size 0.508)
		(drill 0.254)
		(layers "F.Cu" "B.Cu")
		(net "SMB_BIC_I2C6_MUX_FRU_R_SDA")
	)
	(via
		(at 394.680948 -87.596218)
		(size 0.508)
		(drill 0.254)
		(layers "F.Cu" "B.Cu")
		(net "SMB_BIC_I2C6_MUX_FRU_R_SDA")
	)
	(via
		(at 302.292258 -82.332068)
		(size 0.508)
		(drill 0.254)
		(layers "F.Cu" "B.Cu")
		(net "SMB_BIC_I2C6_MUX_FRU_R_SDA")
	)
	(via
		(at 330.962 -84.074)
		(size 0.508)
		(drill 0.254)
		(layers "F.Cu" "B.Cu")
		(net "SMB_BIC_I2C6_MUX_FRU_R_SDA")
	)
	(via
		(at 393.936474 -77.510132)
		(size 0.508)
		(drill 0.254)
		(layers "F.Cu" "B.Cu")
		(net "SMB_BIC_I2C6_MUX_FRU_R_SDA")
	)
	(segment
		(start 321.437 -84.963)
		(end 321.11061 -84.63661)
		(width 0.13208)
		(layer "B.Cu")
		(net "SMB_BIC_I2C6_MUX_FRU_R_SDA")
	)
	(segment
		(start 324.21195 -84.963)
		(end 321.437 -84.963)
		(width 0.13208)
		(layer "B.Cu")
		(net "SMB_BIC_I2C6_MUX_FRU_R_SDA")
	)
	(segment
		(start 393.60348 -86.878668)
		(end 393.60348 -79.097886)
		(width 0.15494)
		(layer "In5.Cu")
		(net "SMB_BIC_I2C6_MUX_FRU_R_SDA")
	)
	(segment
		(start 394.32103 -87.596218)
		(end 393.60348 -86.878668)
		(width 0.15494)
		(layer "In5.Cu")
		(net "SMB_BIC_I2C6_MUX_FRU_R_SDA")
	)
	(segment
		(start 393.481306 -78.975712)
		(end 393.481306 -77.9653)
		(width 0.15494)
		(layer "In5.Cu")
		(net "SMB_BIC_I2C6_MUX_FRU_R_SDA")
	)
	(segment
		(start 393.481306 -77.9653)
		(end 393.936474 -77.510132)
		(width 0.15494)
		(layer "In5.Cu")
		(net "SMB_BIC_I2C6_MUX_FRU_R_SDA")
	)
	(segment
		(start 393.60348 -79.097886)
		(end 393.481306 -78.975712)
		(width 0.15494)
		(layer "In5.Cu")
		(net "SMB_BIC_I2C6_MUX_FRU_R_SDA")
	)
	(segment
		(start 394.680948 -87.596218)
		(end 394.32103 -87.596218)
		(width 0.15494)
		(layer "In5.Cu")
		(net "SMB_BIC_I2C6_MUX_FRU_R_SDA")
	)
	(segment
		(start 330.962 -84.074)
		(end 331.82941 -84.074)
		(width 0.15494)
		(layer "In13.Cu")
		(net "SMB_BIC_I2C6_MUX_FRU_R_SDA")
	)
	(segment
		(start 345.617546 -92.9386)
		(end 349.923354 -92.9386)
		(width 0.15494)
		(layer "In13.Cu")
		(net "SMB_BIC_I2C6_MUX_FRU_R_SDA")
	)
	(segment
		(start 352.578924 -91.6178)
		(end 353.260152 -90.936572)
		(width 0.15494)
		(layer "In13.Cu")
		(net "SMB_BIC_I2C6_MUX_FRU_R_SDA")
	)
	(segment
		(start 344.0684 -85.343746)
		(end 344.0684 -91.389454)
		(width 0.15494)
		(layer "In13.Cu")
		(net "SMB_BIC_I2C6_MUX_FRU_R_SDA")
	)
	(segment
		(start 349.923354 -92.9386)
		(end 351.244154 -91.6178)
		(width 0.15494)
		(layer "In13.Cu")
		(net "SMB_BIC_I2C6_MUX_FRU_R_SDA")
	)
	(segment
		(start 344.0684 -91.389454)
		(end 345.617546 -92.9386)
		(width 0.15494)
		(layer "In13.Cu")
		(net "SMB_BIC_I2C6_MUX_FRU_R_SDA")
	)
	(segment
		(start 354.597208 -90.936572)
		(end 367.445544 -78.088236)
		(width 0.15494)
		(layer "In13.Cu")
		(net "SMB_BIC_I2C6_MUX_FRU_R_SDA")
	)
	(segment
		(start 393.35837 -78.088236)
		(end 393.936474 -77.510132)
		(width 0.15494)
		(layer "In13.Cu")
		(net "SMB_BIC_I2C6_MUX_FRU_R_SDA")
	)
	(segment
		(start 353.260152 -90.936572)
		(end 354.597208 -90.936572)
		(width 0.15494)
		(layer "In13.Cu")
		(net "SMB_BIC_I2C6_MUX_FRU_R_SDA")
	)
	(segment
		(start 367.445544 -78.088236)
		(end 393.35837 -78.088236)
		(width 0.15494)
		(layer "In13.Cu")
		(net "SMB_BIC_I2C6_MUX_FRU_R_SDA")
	)
	(segment
		(start 351.244154 -91.6178)
		(end 352.578924 -91.6178)
		(width 0.15494)
		(layer "In13.Cu")
		(net "SMB_BIC_I2C6_MUX_FRU_R_SDA")
	)
	(segment
		(start 342.947244 -84.22259)
		(end 344.0684 -85.343746)
		(width 0.15494)
		(layer "In13.Cu")
		(net "SMB_BIC_I2C6_MUX_FRU_R_SDA")
	)
	(segment
		(start 331.978 -84.22259)
		(end 342.947244 -84.22259)
		(width 0.15494)
		(layer "In13.Cu")
		(net "SMB_BIC_I2C6_MUX_FRU_R_SDA")
	)
	(segment
		(start 331.82941 -84.074)
		(end 331.978 -84.22259)
		(width 0.15494)
		(layer "In13.Cu")
		(net "SMB_BIC_I2C6_MUX_FRU_R_SDA")
	)
	(segment
		(start 318.8208 -83.4898)
		(end 319.96761 -84.63661)
		(width 0.15494)
		(layer "In15.Cu")
		(net "SMB_BIC_I2C6_MUX_FRU_R_SDA")
	)
	(segment
		(start 321.11061 -84.63661)
		(end 324.15861 -84.63661)
		(width 0.15494)
		(layer "In15.Cu")
		(net "SMB_BIC_I2C6_MUX_FRU_R_SDA")
	)
	(segment
		(start 325.376032 -83.419188)
		(end 329.125834 -83.419188)
		(width 0.15494)
		(layer "In15.Cu")
		(net "SMB_BIC_I2C6_MUX_FRU_R_SDA")
	)
	(segment
		(start 303.44999 -83.4898)
		(end 318.8208 -83.4898)
		(width 0.15494)
		(layer "In15.Cu")
		(net "SMB_BIC_I2C6_MUX_FRU_R_SDA")
	)
	(segment
		(start 324.15861 -84.63661)
		(end 325.376032 -83.419188)
		(width 0.15494)
		(layer "In15.Cu")
		(net "SMB_BIC_I2C6_MUX_FRU_R_SDA")
	)
	(segment
		(start 319.96761 -84.63661)
		(end 321.11061 -84.63661)
		(width 0.15494)
		(layer "In15.Cu")
		(net "SMB_BIC_I2C6_MUX_FRU_R_SDA")
	)
	(segment
		(start 329.780646 -84.074)
		(end 330.962 -84.074)
		(width 0.15494)
		(layer "In15.Cu")
		(net "SMB_BIC_I2C6_MUX_FRU_R_SDA")
	)
	(segment
		(start 329.125834 -83.419188)
		(end 329.780646 -84.074)
		(width 0.15494)
		(layer "In15.Cu")
		(net "SMB_BIC_I2C6_MUX_FRU_R_SDA")
	)
	(segment
		(start 302.292258 -82.332068)
		(end 303.44999 -83.4898)
		(width 0.15494)
		(layer "In15.Cu")
		(net "SMB_BIC_I2C6_MUX_FRU_R_SDA")
	)
	(segment
		(start 346.093796 -220.78696)
		(end 346.493592 -221.186756)
		(width 0.13208)
		(layer "F.Cu")
		(net "NIC4_CLK_EN_N")
	)
	(segment
		(start 357.61295 -228.6)
		(end 356.108 -228.6)
		(width 0.13208)
		(layer "F.Cu")
		(net "NIC4_CLK_EN_N")
	)
	(via
		(at 356.108 -228.6)
		(size 0.508)
		(drill 0.254)
		(layers "F.Cu" "B.Cu")
		(net "NIC4_CLK_EN_N")
	)
	(via
		(at 346.493592 -221.186756)
		(size 0.4572)
		(drill 0.254)
		(layers "F.Cu" "B.Cu")
		(net "NIC4_CLK_EN_N")
	)
	(segment
		(start 355.070156 -227.562156)
		(end 356.108 -228.6)
		(width 0.15494)
		(layer "In7.Cu")
		(net "NIC4_CLK_EN_N")
	)
	(segment
		(start 355.070156 -225.967798)
		(end 355.070156 -227.562156)
		(width 0.15494)
		(layer "In7.Cu")
		(net "NIC4_CLK_EN_N")
	)
	(segment
		(start 347.091 -223.1644)
		(end 351.6376 -223.1644)
		(width 0.0889)
		(layer "In7.Cu")
		(net "NIC4_CLK_EN_N")
	)
	(segment
		(start 346.493592 -221.186756)
		(end 346.893642 -221.586806)
		(width 0.0889)
		(layer "In7.Cu")
		(net "NIC4_CLK_EN_N")
	)
	(segment
		(start 346.893642 -222.967042)
		(end 347.091 -223.1644)
		(width 0.0889)
		(layer "In7.Cu")
		(net "NIC4_CLK_EN_N")
	)
	(segment
		(start 351.6376 -223.1644)
		(end 352.266758 -223.1644)
		(width 0.15494)
		(layer "In7.Cu")
		(net "NIC4_CLK_EN_N")
	)
	(segment
		(start 346.893642 -221.586806)
		(end 346.893642 -222.967042)
		(width 0.0889)
		(layer "In7.Cu")
		(net "NIC4_CLK_EN_N")
	)
	(segment
		(start 352.266758 -223.1644)
		(end 355.070156 -225.967798)
		(width 0.15494)
		(layer "In7.Cu")
		(net "NIC4_CLK_EN_N")
	)
	(segment
		(start 203.17333 -58.166)
		(end 203.290932 -58.449718)
		(width 0.2032)
		(layer "F.Cu")
		(net "P3V3_SSD7_SS")
	)
	(segment
		(start 202.240896 -57.16397)
		(end 202.240896 -57.233566)
		(width 0.2032)
		(layer "F.Cu")
		(net "P3V3_SSD7_SS")
	)
	(segment
		(start 202.240896 -57.233566)
		(end 203.17333 -58.166)
		(width 0.2032)
		(layer "F.Cu")
		(net "P3V3_SSD7_SS")
	)
	(segment
		(start 203.294996 -58.453782)
		(end 203.294996 -59.177936)
		(width 0.2032)
		(layer "F.Cu")
		(net "P3V3_SSD7_SS")
	)
	(segment
		(start 203.290932 -58.449718)
		(end 203.294996 -58.453782)
		(width 0.2032)
		(layer "F.Cu")
		(net "P3V3_SSD7_SS")
	)
	(via
		(at 203.290932 -58.449718)
		(size 0.508)
		(drill 0.254)
		(layers "F.Cu" "B.Cu")
		(net "P3V3_SSD7_SS")
	)
	(segment
		(start 401.040346 -93.065092)
		(end 400.904964 -92.92971)
		(width 0.13208)
		(layer "F.Cu")
		(net "SMB_BIC_I2C6_MUX_VR_SCL")
	)
	(segment
		(start 401.6248 -92.86367)
		(end 401.433284 -92.86367)
		(width 0.13208)
		(layer "F.Cu")
		(net "SMB_BIC_I2C6_MUX_VR_SCL")
	)
	(segment
		(start 400.904964 -92.92971)
		(end 400.904964 -92.738194)
		(width 0.13208)
		(layer "F.Cu")
		(net "SMB_BIC_I2C6_MUX_VR_SCL")
	)
	(segment
		(start 423.457624 -211.340954)
		(end 418.608256 -206.491586)
		(width 0.13208)
		(layer "F.Cu")
		(net "SMB_BIC_I2C6_MUX_VR_SCL")
	)
	(segment
		(start 403.877018 -95.115888)
		(end 402.278596 -93.517466)
		(width 0.13208)
		(layer "F.Cu")
		(net "SMB_BIC_I2C6_MUX_VR_SCL")
	)
	(segment
		(start 418.608256 -178.306222)
		(end 417.321238 -177.019204)
		(width 0.13208)
		(layer "F.Cu")
		(net "SMB_BIC_I2C6_MUX_VR_SCL")
	)
	(segment
		(start 401.231862 -93.065092)
		(end 401.040346 -93.065092)
		(width 0.13208)
		(layer "F.Cu")
		(net "SMB_BIC_I2C6_MUX_VR_SCL")
	)
	(segment
		(start 403.877018 -112.699292)
		(end 403.877018 -95.115888)
		(width 0.13208)
		(layer "F.Cu")
		(net "SMB_BIC_I2C6_MUX_VR_SCL")
	)
	(segment
		(start 409.345384 -177.019204)
		(end 407.213816 -174.887636)
		(width 0.13208)
		(layer "F.Cu")
		(net "SMB_BIC_I2C6_MUX_VR_SCL")
	)
	(segment
		(start 395.6558 -86.137242)
		(end 395.599158 -86.0806)
		(width 0.13208)
		(layer "F.Cu")
		(net "SMB_BIC_I2C6_MUX_VR_SCL")
	)
	(segment
		(start 418.608256 -206.491586)
		(end 418.608256 -178.306222)
		(width 0.13208)
		(layer "F.Cu")
		(net "SMB_BIC_I2C6_MUX_VR_SCL")
	)
	(segment
		(start 423.457624 -242.776248)
		(end 423.457624 -211.340954)
		(width 0.13208)
		(layer "F.Cu")
		(net "SMB_BIC_I2C6_MUX_VR_SCL")
	)
	(segment
		(start 401.106386 -92.536772)
		(end 401.106386 -92.345256)
		(width 0.13208)
		(layer "F.Cu")
		(net "SMB_BIC_I2C6_MUX_VR_SCL")
	)
	(segment
		(start 407.213816 -174.887636)
		(end 407.213816 -116.03609)
		(width 0.13208)
		(layer "F.Cu")
		(net "SMB_BIC_I2C6_MUX_VR_SCL")
	)
	(segment
		(start 401.760182 -92.999052)
		(end 401.6248 -92.86367)
		(width 0.13208)
		(layer "F.Cu")
		(net "SMB_BIC_I2C6_MUX_VR_SCL")
	)
	(segment
		(start 390.195308 -86.0806)
		(end 389.601202 -85.486494)
		(width 0.13208)
		(layer "F.Cu")
		(net "SMB_BIC_I2C6_MUX_VR_SCL")
	)
	(segment
		(start 418.48151 -249.283728)
		(end 418.7444 -249.020838)
		(width 0.13208)
		(layer "F.Cu")
		(net "SMB_BIC_I2C6_MUX_VR_SCL")
	)
	(segment
		(start 401.885658 -93.718888)
		(end 401.694142 -93.718888)
		(width 0.13208)
		(layer "F.Cu")
		(net "SMB_BIC_I2C6_MUX_VR_SCL")
	)
	(segment
		(start 402.08708 -93.517466)
		(end 401.885658 -93.718888)
		(width 0.13208)
		(layer "F.Cu")
		(net "SMB_BIC_I2C6_MUX_VR_SCL")
	)
	(segment
		(start 401.433284 -92.86367)
		(end 401.231862 -93.065092)
		(width 0.13208)
		(layer "F.Cu")
		(net "SMB_BIC_I2C6_MUX_VR_SCL")
	)
	(segment
		(start 400.904964 -92.738194)
		(end 401.106386 -92.536772)
		(width 0.13208)
		(layer "F.Cu")
		(net "SMB_BIC_I2C6_MUX_VR_SCL")
	)
	(segment
		(start 417.321238 -177.019204)
		(end 409.345384 -177.019204)
		(width 0.13208)
		(layer "F.Cu")
		(net "SMB_BIC_I2C6_MUX_VR_SCL")
	)
	(segment
		(start 401.55876 -93.583506)
		(end 401.55876 -93.39199)
		(width 0.13208)
		(layer "F.Cu")
		(net "SMB_BIC_I2C6_MUX_VR_SCL")
	)
	(segment
		(start 397.52905 -86.137242)
		(end 395.6558 -86.137242)
		(width 0.13208)
		(layer "F.Cu")
		(net "SMB_BIC_I2C6_MUX_VR_SCL")
	)
	(segment
		(start 401.106386 -92.345256)
		(end 397.89862 -89.13749)
		(width 0.13208)
		(layer "F.Cu")
		(net "SMB_BIC_I2C6_MUX_VR_SCL")
	)
	(segment
		(start 401.55876 -93.39199)
		(end 401.760182 -93.190568)
		(width 0.13208)
		(layer "F.Cu")
		(net "SMB_BIC_I2C6_MUX_VR_SCL")
	)
	(segment
		(start 389.601202 -85.486494)
		(end 388.24027 -85.486494)
		(width 0.13208)
		(layer "F.Cu")
		(net "SMB_BIC_I2C6_MUX_VR_SCL")
	)
	(segment
		(start 401.694142 -93.718888)
		(end 401.55876 -93.583506)
		(width 0.13208)
		(layer "F.Cu")
		(net "SMB_BIC_I2C6_MUX_VR_SCL")
	)
	(segment
		(start 418.7444 -249.020838)
		(end 418.7444 -247.489472)
		(width 0.13208)
		(layer "F.Cu")
		(net "SMB_BIC_I2C6_MUX_VR_SCL")
	)
	(segment
		(start 397.89862 -86.506812)
		(end 397.52905 -86.137242)
		(width 0.13208)
		(layer "F.Cu")
		(net "SMB_BIC_I2C6_MUX_VR_SCL")
	)
	(segment
		(start 359.192322 -251.054362)
		(end 359.192322 -250.313444)
		(width 0.13208)
		(layer "F.Cu")
		(net "SMB_BIC_I2C6_MUX_VR_SCL")
	)
	(segment
		(start 397.89862 -89.13749)
		(end 397.89862 -86.506812)
		(width 0.13208)
		(layer "F.Cu")
		(net "SMB_BIC_I2C6_MUX_VR_SCL")
	)
	(segment
		(start 402.278596 -93.517466)
		(end 402.08708 -93.517466)
		(width 0.13208)
		(layer "F.Cu")
		(net "SMB_BIC_I2C6_MUX_VR_SCL")
	)
	(segment
		(start 395.599158 -86.0806)
		(end 390.195308 -86.0806)
		(width 0.13208)
		(layer "F.Cu")
		(net "SMB_BIC_I2C6_MUX_VR_SCL")
	)
	(segment
		(start 418.7444 -247.489472)
		(end 423.457624 -242.776248)
		(width 0.13208)
		(layer "F.Cu")
		(net "SMB_BIC_I2C6_MUX_VR_SCL")
	)
	(segment
		(start 401.760182 -93.190568)
		(end 401.760182 -92.999052)
		(width 0.13208)
		(layer "F.Cu")
		(net "SMB_BIC_I2C6_MUX_VR_SCL")
	)
	(segment
		(start 407.213816 -116.03609)
		(end 403.877018 -112.699292)
		(width 0.13208)
		(layer "F.Cu")
		(net "SMB_BIC_I2C6_MUX_VR_SCL")
	)
	(via
		(at 418.48151 -249.283728)
		(size 0.508)
		(drill 0.254)
		(layers "F.Cu" "B.Cu")
		(net "SMB_BIC_I2C6_MUX_VR_SCL")
	)
	(via
		(at 359.192322 -250.313444)
		(size 0.508)
		(drill 0.254)
		(layers "F.Cu" "B.Cu")
		(net "SMB_BIC_I2C6_MUX_VR_SCL")
	)
	(segment
		(start 361.766612 -250.616212)
		(end 361.766612 -251.114814)
		(width 0.15494)
		(layer "In15.Cu")
		(net "SMB_BIC_I2C6_MUX_VR_SCL")
	)
	(segment
		(start 360.796332 -251.114814)
		(end 360.654346 -251.2568)
		(width 0.15494)
		(layer "In15.Cu")
		(net "SMB_BIC_I2C6_MUX_VR_SCL")
	)
	(segment
		(start 361.766612 -251.114814)
		(end 361.624626 -251.2568)
		(width 0.15494)
		(layer "In15.Cu")
		(net "SMB_BIC_I2C6_MUX_VR_SCL")
	)
	(segment
		(start 360.796332 -250.616212)
		(end 360.796332 -251.114814)
		(width 0.15494)
		(layer "In15.Cu")
		(net "SMB_BIC_I2C6_MUX_VR_SCL")
	)
	(segment
		(start 390.350502 -248.931684)
		(end 388.80796 -250.474226)
		(width 0.15494)
		(layer "In15.Cu")
		(net "SMB_BIC_I2C6_MUX_VR_SCL")
	)
	(segment
		(start 418.48151 -249.283728)
		(end 418.129466 -248.931684)
		(width 0.15494)
		(layer "In15.Cu")
		(net "SMB_BIC_I2C6_MUX_VR_SCL")
	)
	(segment
		(start 360.311192 -250.616212)
		(end 360.169206 -250.474226)
		(width 0.15494)
		(layer "In15.Cu")
		(net "SMB_BIC_I2C6_MUX_VR_SCL")
	)
	(segment
		(start 361.139486 -250.474226)
		(end 360.938318 -250.474226)
		(width 0.15494)
		(layer "In15.Cu")
		(net "SMB_BIC_I2C6_MUX_VR_SCL")
	)
	(segment
		(start 360.654346 -251.2568)
		(end 360.453178 -251.2568)
		(width 0.15494)
		(layer "In15.Cu")
		(net "SMB_BIC_I2C6_MUX_VR_SCL")
	)
	(segment
		(start 360.938318 -250.474226)
		(end 360.796332 -250.616212)
		(width 0.15494)
		(layer "In15.Cu")
		(net "SMB_BIC_I2C6_MUX_VR_SCL")
	)
	(segment
		(start 360.169206 -250.474226)
		(end 359.353104 -250.474226)
		(width 0.15494)
		(layer "In15.Cu")
		(net "SMB_BIC_I2C6_MUX_VR_SCL")
	)
	(segment
		(start 359.353104 -250.474226)
		(end 359.192322 -250.313444)
		(width 0.15494)
		(layer "In15.Cu")
		(net "SMB_BIC_I2C6_MUX_VR_SCL")
	)
	(segment
		(start 361.423458 -251.2568)
		(end 361.281472 -251.114814)
		(width 0.15494)
		(layer "In15.Cu")
		(net "SMB_BIC_I2C6_MUX_VR_SCL")
	)
	(segment
		(start 361.281472 -250.616212)
		(end 361.139486 -250.474226)
		(width 0.15494)
		(layer "In15.Cu")
		(net "SMB_BIC_I2C6_MUX_VR_SCL")
	)
	(segment
		(start 418.129466 -248.931684)
		(end 390.350502 -248.931684)
		(width 0.15494)
		(layer "In15.Cu")
		(net "SMB_BIC_I2C6_MUX_VR_SCL")
	)
	(segment
		(start 360.311192 -251.114814)
		(end 360.311192 -250.616212)
		(width 0.15494)
		(layer "In15.Cu")
		(net "SMB_BIC_I2C6_MUX_VR_SCL")
	)
	(segment
		(start 361.281472 -251.114814)
		(end 361.281472 -250.616212)
		(width 0.15494)
		(layer "In15.Cu")
		(net "SMB_BIC_I2C6_MUX_VR_SCL")
	)
	(segment
		(start 361.908598 -250.474226)
		(end 361.766612 -250.616212)
		(width 0.15494)
		(layer "In15.Cu")
		(net "SMB_BIC_I2C6_MUX_VR_SCL")
	)
	(segment
		(start 388.80796 -250.474226)
		(end 361.908598 -250.474226)
		(width 0.15494)
		(layer "In15.Cu")
		(net "SMB_BIC_I2C6_MUX_VR_SCL")
	)
	(segment
		(start 360.453178 -251.2568)
		(end 360.311192 -251.114814)
		(width 0.15494)
		(layer "In15.Cu")
		(net "SMB_BIC_I2C6_MUX_VR_SCL")
	)
	(segment
		(start 361.624626 -251.2568)
		(end 361.423458 -251.2568)
		(width 0.15494)
		(layer "In15.Cu")
		(net "SMB_BIC_I2C6_MUX_VR_SCL")
	)
	(segment
		(start 126.169166 -118.743476)
		(end 126.169166 -119.486426)
		(width 0.13208)
		(layer "F.Cu")
		(net "PWRGD_P3V3_NIC2_R")
	)
	(segment
		(start 348.493842 -223.187006)
		(end 348.893638 -223.586802)
		(width 0.13208)
		(layer "F.Cu")
		(net "PWRGD_P3V3_NIC2_R")
	)
	(segment
		(start 125.810264 -124.963428)
		(end 125.154944 -124.963428)
		(width 0.13208)
		(layer "F.Cu")
		(net "PWRGD_P3V3_NIC2_R")
	)
	(via
		(at 126.169166 -119.486426)
		(size 0.508)
		(drill 0.254)
		(layers "F.Cu" "B.Cu")
		(net "PWRGD_P3V3_NIC2_R")
	)
	(via
		(at 132.915406 -238.55553)
		(size 0.508)
		(drill 0.254)
		(layers "F.Cu" "B.Cu")
		(net "PWRGD_P3V3_NIC2_R")
	)
	(via
		(at 348.893638 -223.586802)
		(size 0.4572)
		(drill 0.254)
		(layers "F.Cu" "B.Cu")
		(net "PWRGD_P3V3_NIC2_R")
	)
	(via
		(at 125.154944 -124.963428)
		(size 0.508)
		(drill 0.254)
		(layers "F.Cu" "B.Cu")
		(net "PWRGD_P3V3_NIC2_R")
	)
	(segment
		(start 138.9634 -188.31052)
		(end 134.57047 -192.70345)
		(width 0.15494)
		(layer "In5.Cu")
		(net "PWRGD_P3V3_NIC2_R")
	)
	(segment
		(start 134.57047 -192.70345)
		(end 134.57047 -198.23176)
		(width 0.15494)
		(layer "In5.Cu")
		(net "PWRGD_P3V3_NIC2_R")
	)
	(segment
		(start 125.66396 -124.454412)
		(end 125.154944 -124.963428)
		(width 0.15494)
		(layer "In5.Cu")
		(net "PWRGD_P3V3_NIC2_R")
	)
	(segment
		(start 138.376152 -173.100238)
		(end 138.9634 -173.687486)
		(width 0.15494)
		(layer "In5.Cu")
		(net "PWRGD_P3V3_NIC2_R")
	)
	(segment
		(start 126.169166 -119.486426)
		(end 126.169166 -118.37035)
		(width 0.15494)
		(layer "In5.Cu")
		(net "PWRGD_P3V3_NIC2_R")
	)
	(segment
		(start 130.245358 -213.812374)
		(end 130.991864 -214.55888)
		(width 0.15494)
		(layer "In5.Cu")
		(net "PWRGD_P3V3_NIC2_R")
	)
	(segment
		(start 132.5626 -230.606854)
		(end 132.5626 -238.202724)
		(width 0.15494)
		(layer "In5.Cu")
		(net "PWRGD_P3V3_NIC2_R")
	)
	(segment
		(start 132.490718 -200.311512)
		(end 132.490718 -200.960736)
		(width 0.15494)
		(layer "In5.Cu")
		(net "PWRGD_P3V3_NIC2_R")
	)
	(segment
		(start 134.646162 -118.083076)
		(end 138.9126 -122.349514)
		(width 0.15494)
		(layer "In5.Cu")
		(net "PWRGD_P3V3_NIC2_R")
	)
	(segment
		(start 130.245358 -211.784946)
		(end 130.245358 -213.812374)
		(width 0.15494)
		(layer "In5.Cu")
		(net "PWRGD_P3V3_NIC2_R")
	)
	(segment
		(start 130.991864 -229.036118)
		(end 132.5626 -230.606854)
		(width 0.15494)
		(layer "In5.Cu")
		(net "PWRGD_P3V3_NIC2_R")
	)
	(segment
		(start 126.169166 -118.37035)
		(end 126.45644 -118.083076)
		(width 0.15494)
		(layer "In5.Cu")
		(net "PWRGD_P3V3_NIC2_R")
	)
	(segment
		(start 132.5626 -238.202724)
		(end 132.915406 -238.55553)
		(width 0.15494)
		(layer "In5.Cu")
		(net "PWRGD_P3V3_NIC2_R")
	)
	(segment
		(start 126.169166 -119.486426)
		(end 126.169166 -120.756426)
		(width 0.15494)
		(layer "In5.Cu")
		(net "PWRGD_P3V3_NIC2_R")
	)
	(segment
		(start 138.9126 -122.349514)
		(end 138.9126 -169.2148)
		(width 0.15494)
		(layer "In5.Cu")
		(net "PWRGD_P3V3_NIC2_R")
	)
	(segment
		(start 125.66396 -121.261632)
		(end 125.66396 -124.454412)
		(width 0.15494)
		(layer "In5.Cu")
		(net "PWRGD_P3V3_NIC2_R")
	)
	(segment
		(start 138.376152 -169.751248)
		(end 138.376152 -173.100238)
		(width 0.15494)
		(layer "In5.Cu")
		(net "PWRGD_P3V3_NIC2_R")
	)
	(segment
		(start 138.9126 -169.2148)
		(end 138.376152 -169.751248)
		(width 0.15494)
		(layer "In5.Cu")
		(net "PWRGD_P3V3_NIC2_R")
	)
	(segment
		(start 130.991864 -214.55888)
		(end 130.991864 -229.036118)
		(width 0.15494)
		(layer "In5.Cu")
		(net "PWRGD_P3V3_NIC2_R")
	)
	(segment
		(start 134.57047 -198.23176)
		(end 132.490718 -200.311512)
		(width 0.15494)
		(layer "In5.Cu")
		(net "PWRGD_P3V3_NIC2_R")
	)
	(segment
		(start 126.169166 -120.756426)
		(end 125.66396 -121.261632)
		(width 0.15494)
		(layer "In5.Cu")
		(net "PWRGD_P3V3_NIC2_R")
	)
	(segment
		(start 130.694938 -211.335366)
		(end 130.245358 -211.784946)
		(width 0.15494)
		(layer "In5.Cu")
		(net "PWRGD_P3V3_NIC2_R")
	)
	(segment
		(start 130.694938 -202.756516)
		(end 130.694938 -211.335366)
		(width 0.15494)
		(layer "In5.Cu")
		(net "PWRGD_P3V3_NIC2_R")
	)
	(segment
		(start 138.9634 -173.687486)
		(end 138.9634 -188.31052)
		(width 0.15494)
		(layer "In5.Cu")
		(net "PWRGD_P3V3_NIC2_R")
	)
	(segment
		(start 126.45644 -118.083076)
		(end 134.646162 -118.083076)
		(width 0.15494)
		(layer "In5.Cu")
		(net "PWRGD_P3V3_NIC2_R")
	)
	(segment
		(start 132.490718 -200.960736)
		(end 130.694938 -202.756516)
		(width 0.15494)
		(layer "In5.Cu")
		(net "PWRGD_P3V3_NIC2_R")
	)
	(segment
		(start 330.668884 -247.276874)
		(end 331.032358 -246.9134)
		(width 0.15494)
		(layer "In13.Cu")
		(net "PWRGD_P3V3_NIC2_R")
	)
	(segment
		(start 338.70519 -247.11914)
		(end 344.90533 -240.919)
		(width 0.15494)
		(layer "In13.Cu")
		(net "PWRGD_P3V3_NIC2_R")
	)
	(segment
		(start 133.386068 -238.084868)
		(end 141.024102 -238.084868)
		(width 0.15494)
		(layer "In13.Cu")
		(net "PWRGD_P3V3_NIC2_R")
	)
	(segment
		(start 353.792536 -226.550982)
		(end 352.025966 -224.784412)
		(width 0.15494)
		(layer "In13.Cu")
		(net "PWRGD_P3V3_NIC2_R")
	)
	(segment
		(start 352.07194 -236.888528)
		(end 352.07194 -232.940606)
		(width 0.15494)
		(layer "In13.Cu")
		(net "PWRGD_P3V3_NIC2_R")
	)
	(segment
		(start 179.712874 -244.152674)
		(end 206.815436 -244.152674)
		(width 0.15494)
		(layer "In13.Cu")
		(net "PWRGD_P3V3_NIC2_R")
	)
	(segment
		(start 352.025966 -224.784412)
		(end 350.328738 -224.784412)
		(width 0.0889)
		(layer "In13.Cu")
		(net "PWRGD_P3V3_NIC2_R")
	)
	(segment
		(start 348.041468 -240.919)
		(end 352.07194 -236.888528)
		(width 0.15494)
		(layer "In13.Cu")
		(net "PWRGD_P3V3_NIC2_R")
	)
	(segment
		(start 326.594216 -246.96928)
		(end 326.599296 -246.9642)
		(width 0.15494)
		(layer "In13.Cu")
		(net "PWRGD_P3V3_NIC2_R")
	)
	(segment
		(start 141.024102 -238.084868)
		(end 142.91691 -236.19206)
		(width 0.15494)
		(layer "In13.Cu")
		(net "PWRGD_P3V3_NIC2_R")
	)
	(segment
		(start 353.762056 -227.033582)
		(end 353.792536 -227.003102)
		(width 0.15494)
		(layer "In13.Cu")
		(net "PWRGD_P3V3_NIC2_R")
	)
	(segment
		(start 132.915406 -238.55553)
		(end 133.386068 -238.084868)
		(width 0.15494)
		(layer "In13.Cu")
		(net "PWRGD_P3V3_NIC2_R")
	)
	(segment
		(start 142.91691 -236.19206)
		(end 171.75226 -236.19206)
		(width 0.15494)
		(layer "In13.Cu")
		(net "PWRGD_P3V3_NIC2_R")
	)
	(segment
		(start 350.091248 -224.546922)
		(end 350.091248 -224.222056)
		(width 0.0889)
		(layer "In13.Cu")
		(net "PWRGD_P3V3_NIC2_R")
	)
	(segment
		(start 350.328738 -224.784412)
		(end 350.091248 -224.546922)
		(width 0.0889)
		(layer "In13.Cu")
		(net "PWRGD_P3V3_NIC2_R")
	)
	(segment
		(start 252.880622 -245.285768)
		(end 274.267168 -245.285768)
		(width 0.15494)
		(layer "In13.Cu")
		(net "PWRGD_P3V3_NIC2_R")
	)
	(segment
		(start 335.148936 -246.9134)
		(end 335.354676 -247.11914)
		(width 0.15494)
		(layer "In13.Cu")
		(net "PWRGD_P3V3_NIC2_R")
	)
	(segment
		(start 353.792536 -227.003102)
		(end 353.792536 -226.550982)
		(width 0.15494)
		(layer "In13.Cu")
		(net "PWRGD_P3V3_NIC2_R")
	)
	(segment
		(start 344.90533 -240.919)
		(end 348.041468 -240.919)
		(width 0.15494)
		(layer "In13.Cu")
		(net "PWRGD_P3V3_NIC2_R")
	)
	(segment
		(start 274.267168 -245.285768)
		(end 275.787612 -246.806212)
		(width 0.15494)
		(layer "In13.Cu")
		(net "PWRGD_P3V3_NIC2_R")
	)
	(segment
		(start 353.762056 -231.25049)
		(end 353.762056 -227.033582)
		(width 0.15494)
		(layer "In13.Cu")
		(net "PWRGD_P3V3_NIC2_R")
	)
	(segment
		(start 236.634274 -243.79682)
		(end 251.391674 -243.79682)
		(width 0.15494)
		(layer "In13.Cu")
		(net "PWRGD_P3V3_NIC2_R")
	)
	(segment
		(start 349.858584 -223.989392)
		(end 349.296228 -223.989392)
		(width 0.0889)
		(layer "In13.Cu")
		(net "PWRGD_P3V3_NIC2_R")
	)
	(segment
		(start 335.354676 -247.11914)
		(end 338.70519 -247.11914)
		(width 0.15494)
		(layer "In13.Cu")
		(net "PWRGD_P3V3_NIC2_R")
	)
	(segment
		(start 331.032358 -246.9134)
		(end 335.148936 -246.9134)
		(width 0.15494)
		(layer "In13.Cu")
		(net "PWRGD_P3V3_NIC2_R")
	)
	(segment
		(start 275.787612 -246.806212)
		(end 299.86478 -246.806212)
		(width 0.15494)
		(layer "In13.Cu")
		(net "PWRGD_P3V3_NIC2_R")
	)
	(segment
		(start 251.391674 -243.79682)
		(end 252.880622 -245.285768)
		(width 0.15494)
		(layer "In13.Cu")
		(net "PWRGD_P3V3_NIC2_R")
	)
	(segment
		(start 328.77887 -246.9642)
		(end 329.091544 -247.276874)
		(width 0.15494)
		(layer "In13.Cu")
		(net "PWRGD_P3V3_NIC2_R")
	)
	(segment
		(start 326.599296 -246.9642)
		(end 328.77887 -246.9642)
		(width 0.15494)
		(layer "In13.Cu")
		(net "PWRGD_P3V3_NIC2_R")
	)
	(segment
		(start 329.091544 -247.276874)
		(end 330.668884 -247.276874)
		(width 0.15494)
		(layer "In13.Cu")
		(net "PWRGD_P3V3_NIC2_R")
	)
	(segment
		(start 206.815436 -244.152674)
		(end 208.556606 -242.411504)
		(width 0.15494)
		(layer "In13.Cu")
		(net "PWRGD_P3V3_NIC2_R")
	)
	(segment
		(start 349.296228 -223.989392)
		(end 348.893638 -223.586802)
		(width 0.0889)
		(layer "In13.Cu")
		(net "PWRGD_P3V3_NIC2_R")
	)
	(segment
		(start 301.422816 -248.364248)
		(end 303.740058 -248.364248)
		(width 0.15494)
		(layer "In13.Cu")
		(net "PWRGD_P3V3_NIC2_R")
	)
	(segment
		(start 352.07194 -232.940606)
		(end 353.762056 -231.25049)
		(width 0.15494)
		(layer "In13.Cu")
		(net "PWRGD_P3V3_NIC2_R")
	)
	(segment
		(start 299.86478 -246.806212)
		(end 301.422816 -248.364248)
		(width 0.15494)
		(layer "In13.Cu")
		(net "PWRGD_P3V3_NIC2_R")
	)
	(segment
		(start 171.75226 -236.19206)
		(end 179.712874 -244.152674)
		(width 0.15494)
		(layer "In13.Cu")
		(net "PWRGD_P3V3_NIC2_R")
	)
	(segment
		(start 305.135026 -246.96928)
		(end 326.594216 -246.96928)
		(width 0.15494)
		(layer "In13.Cu")
		(net "PWRGD_P3V3_NIC2_R")
	)
	(segment
		(start 303.740058 -248.364248)
		(end 305.135026 -246.96928)
		(width 0.15494)
		(layer "In13.Cu")
		(net "PWRGD_P3V3_NIC2_R")
	)
	(segment
		(start 208.556606 -242.411504)
		(end 235.248958 -242.411504)
		(width 0.15494)
		(layer "In13.Cu")
		(net "PWRGD_P3V3_NIC2_R")
	)
	(segment
		(start 235.248958 -242.411504)
		(end 236.634274 -243.79682)
		(width 0.15494)
		(layer "In13.Cu")
		(net "PWRGD_P3V3_NIC2_R")
	)
	(segment
		(start 350.091248 -224.222056)
		(end 349.858584 -223.989392)
		(width 0.0889)
		(layer "In13.Cu")
		(net "PWRGD_P3V3_NIC2_R")
	)
	(segment
		(start 235.13288 -88.175338)
		(end 235.01858 -88.289638)
		(width 0.13462)
		(layer "F.Cu")
		(net "USB2_FT4232_CLI_R_DN")
	)
	(segment
		(start 234.839256 -87.386414)
		(end 235.13288 -87.680038)
		(width 0.13462)
		(layer "F.Cu")
		(net "USB2_FT4232_CLI_R_DN")
	)
	(segment
		(start 235.01858 -88.784938)
		(end 235.13288 -88.899238)
		(width 0.13462)
		(layer "F.Cu")
		(net "USB2_FT4232_CLI_R_DN")
	)
	(segment
		(start 235.01858 -88.289638)
		(end 235.01858 -88.784938)
		(width 0.13462)
		(layer "F.Cu")
		(net "USB2_FT4232_CLI_R_DN")
	)
	(segment
		(start 238.595408 -84.751418)
		(end 238.324898 -84.751418)
		(width 0.13462)
		(layer "F.Cu")
		(net "USB2_FT4232_CLI_R_DN")
	)
	(segment
		(start 235.13288 -87.680038)
		(end 235.13288 -88.175338)
		(width 0.13462)
		(layer "F.Cu")
		(net "USB2_FT4232_CLI_R_DN")
	)
	(segment
		(start 235.02112 -89.529666)
		(end 235.02112 -89.854024)
		(width 0.13462)
		(layer "F.Cu")
		(net "USB2_FT4232_CLI_R_DN")
	)
	(segment
		(start 235.13288 -89.417906)
		(end 235.02112 -89.529666)
		(width 0.13462)
		(layer "F.Cu")
		(net "USB2_FT4232_CLI_R_DN")
	)
	(segment
		(start 239.013238 -85.169248)
		(end 238.595408 -84.751418)
		(width 0.13462)
		(layer "F.Cu")
		(net "USB2_FT4232_CLI_R_DN")
	)
	(segment
		(start 235.13288 -88.899238)
		(end 235.13288 -89.417906)
		(width 0.13462)
		(layer "F.Cu")
		(net "USB2_FT4232_CLI_R_DN")
	)
	(segment
		(start 238.186214 -86.59876)
		(end 238.681514 -86.59876)
		(width 0.1651)
		(layer "In15.Cu")
		(net "USB2_FT4232_CLI_R_DN")
	)
	(segment
		(start 235.430568 -86.082886)
		(end 235.925868 -86.082886)
		(width 0.1651)
		(layer "In15.Cu")
		(net "USB2_FT4232_CLI_R_DN")
	)
	(segment
		(start 240.015014 -86.71306)
		(end 240.281714 -86.71306)
		(width 0.1651)
		(layer "In15.Cu")
		(net "USB2_FT4232_CLI_R_DN")
	)
	(segment
		(start 239.900714 -86.59876)
		(end 240.015014 -86.71306)
		(width 0.1651)
		(layer "In15.Cu")
		(net "USB2_FT4232_CLI_R_DN")
	)
	(segment
		(start 235.133388 -86.380066)
		(end 235.430568 -86.082886)
		(width 0.1651)
		(layer "In15.Cu")
		(net "USB2_FT4232_CLI_R_DN")
	)
	(segment
		(start 240.294414 -85.56244)
		(end 240.408714 -85.44814)
		(width 0.1651)
		(layer "In15.Cu")
		(net "USB2_FT4232_CLI_R_DN")
	)
	(segment
		(start 240.294414 -86.014052)
		(end 240.294414 -85.56244)
		(width 0.1651)
		(layer "In15.Cu")
		(net "USB2_FT4232_CLI_R_DN")
	)
	(segment
		(start 239.405414 -86.59876)
		(end 239.900714 -86.59876)
		(width 0.1651)
		(layer "In15.Cu")
		(net "USB2_FT4232_CLI_R_DN")
	)
	(segment
		(start 237.868206 -86.71306)
		(end 238.071914 -86.71306)
		(width 0.1651)
		(layer "In15.Cu")
		(net "USB2_FT4232_CLI_R_DN")
	)
	(segment
		(start 235.133388 -87.092282)
		(end 235.133388 -86.380066)
		(width 0.1651)
		(layer "In15.Cu")
		(net "USB2_FT4232_CLI_R_DN")
	)
	(segment
		(start 236.040168 -85.968586)
		(end 236.535468 -85.968586)
		(width 0.1651)
		(layer "In15.Cu")
		(net "USB2_FT4232_CLI_R_DN")
	)
	(segment
		(start 237.238032 -86.082886)
		(end 237.868206 -86.71306)
		(width 0.1651)
		(layer "In15.Cu")
		(net "USB2_FT4232_CLI_R_DN")
	)
	(segment
		(start 240.281714 -84.872576)
		(end 239.30991 -84.872576)
		(width 0.1651)
		(layer "In15.Cu")
		(net "USB2_FT4232_CLI_R_DN")
	)
	(segment
		(start 236.535468 -85.968586)
		(end 236.649768 -86.082886)
		(width 0.1651)
		(layer "In15.Cu")
		(net "USB2_FT4232_CLI_R_DN")
	)
	(segment
		(start 238.071914 -86.71306)
		(end 238.186214 -86.59876)
		(width 0.1651)
		(layer "In15.Cu")
		(net "USB2_FT4232_CLI_R_DN")
	)
	(segment
		(start 240.281714 -86.71306)
		(end 240.408714 -86.58606)
		(width 0.1651)
		(layer "In15.Cu")
		(net "USB2_FT4232_CLI_R_DN")
	)
	(segment
		(start 240.408714 -86.128352)
		(end 240.294414 -86.014052)
		(width 0.1651)
		(layer "In15.Cu")
		(net "USB2_FT4232_CLI_R_DN")
	)
	(segment
		(start 238.795814 -86.71306)
		(end 239.291114 -86.71306)
		(width 0.1651)
		(layer "In15.Cu")
		(net "USB2_FT4232_CLI_R_DN")
	)
	(segment
		(start 240.408714 -84.999576)
		(end 240.281714 -84.872576)
		(width 0.1651)
		(layer "In15.Cu")
		(net "USB2_FT4232_CLI_R_DN")
	)
	(segment
		(start 238.681514 -86.59876)
		(end 238.795814 -86.71306)
		(width 0.1651)
		(layer "In15.Cu")
		(net "USB2_FT4232_CLI_R_DN")
	)
	(segment
		(start 240.408714 -86.58606)
		(end 240.408714 -86.128352)
		(width 0.1651)
		(layer "In15.Cu")
		(net "USB2_FT4232_CLI_R_DN")
	)
	(segment
		(start 235.925868 -86.082886)
		(end 236.040168 -85.968586)
		(width 0.1651)
		(layer "In15.Cu")
		(net "USB2_FT4232_CLI_R_DN")
	)
	(segment
		(start 240.408714 -85.44814)
		(end 240.408714 -84.999576)
		(width 0.1651)
		(layer "In15.Cu")
		(net "USB2_FT4232_CLI_R_DN")
	)
	(segment
		(start 234.839256 -87.386414)
		(end 235.133388 -87.092282)
		(width 0.1651)
		(layer "In15.Cu")
		(net "USB2_FT4232_CLI_R_DN")
	)
	(segment
		(start 239.291114 -86.71306)
		(end 239.405414 -86.59876)
		(width 0.1651)
		(layer "In15.Cu")
		(net "USB2_FT4232_CLI_R_DN")
	)
	(segment
		(start 239.30991 -84.872576)
		(end 239.013238 -85.169248)
		(width 0.1651)
		(layer "In15.Cu")
		(net "USB2_FT4232_CLI_R_DN")
	)
	(segment
		(start 236.649768 -86.082886)
		(end 237.238032 -86.082886)
		(width 0.1651)
		(layer "In15.Cu")
		(net "USB2_FT4232_CLI_R_DN")
	)
	(segment
		(start 135.59028 -175.519588)
		(end 135.60298 -175.506888)
		(width 0.13462)
		(layer "F.Cu")
		(net "CLK_100M_DB2000QL_NIC2_DP")
	)
	(segment
		(start 137.287 -175.506888)
		(end 138.564112 -174.229776)
		(width 0.13462)
		(layer "F.Cu")
		(net "CLK_100M_DB2000QL_NIC2_DP")
	)
	(segment
		(start 135.60298 -175.506888)
		(end 137.287 -175.506888)
		(width 0.13462)
		(layer "F.Cu")
		(net "CLK_100M_DB2000QL_NIC2_DP")
	)
	(segment
		(start 135.471154 -175.400462)
		(end 135.59028 -175.519588)
		(width 0.13462)
		(layer "F.Cu")
		(net "CLK_100M_DB2000QL_NIC2_DP")
	)
	(segment
		(start 138.564112 -174.229776)
		(end 139.309602 -174.229776)
		(width 0.13462)
		(layer "F.Cu")
		(net "CLK_100M_DB2000QL_NIC2_DP")
	)
	(segment
		(start 139.309602 -174.229776)
		(end 139.674092 -173.865286)
		(width 0.13462)
		(layer "F.Cu")
		(net "CLK_100M_DB2000QL_NIC2_DP")
	)
	(segment
		(start 169.760646 -21.05279)
		(end 170.554904 -21.847048)
		(width 0.13208)
		(layer "F.Cu")
		(net "SMB_SSD5_ISO_EN")
	)
	(segment
		(start 170.554904 -21.847048)
		(end 170.554904 -22.561296)
		(width 0.13208)
		(layer "F.Cu")
		(net "SMB_SSD5_ISO_EN")
	)
	(segment
		(start 169.760646 -20.789392)
		(end 169.760646 -21.05279)
		(width 0.13208)
		(layer "F.Cu")
		(net "SMB_SSD5_ISO_EN")
	)
	(via
		(at 170.554904 -21.847048)
		(size 0.508)
		(drill 0.254)
		(layers "F.Cu" "B.Cu")
		(net "SMB_SSD5_ISO_EN")
	)
	(segment
		(start 392.644884 -84.928202)
		(end 393.269216 -84.928202)
		(width 0.13208)
		(layer "F.Cu")
		(net "SMB_BIC_I2C6_MUX_VR_SDA")
	)
	(segment
		(start 388.24027 -84.836508)
		(end 390.669526 -84.836508)
		(width 0.13208)
		(layer "F.Cu")
		(net "SMB_BIC_I2C6_MUX_VR_SDA")
	)
	(segment
		(start 390.669526 -84.836508)
		(end 390.76122 -84.928202)
		(width 0.13208)
		(layer "F.Cu")
		(net "SMB_BIC_I2C6_MUX_VR_SDA")
	)
	(segment
		(start 390.76122 -84.928202)
		(end 392.644884 -84.928202)
		(width 0.13208)
		(layer "F.Cu")
		(net "SMB_BIC_I2C6_MUX_VR_SDA")
	)
	(via
		(at 392.644884 -84.928202)
		(size 0.508)
		(drill 0.254)
		(layers "F.Cu" "B.Cu")
		(net "SMB_BIC_I2C6_MUX_VR_SDA")
	)
	(segment
		(start 407.296112 -390.990836)
		(end 406.585928 -390.990836)
		(width 0.13208)
		(layer "F.Cu")
		(net "GPU_BB_RSVD_1_R")
	)
	(via
		(at 406.585928 -390.990836)
		(size 0.508)
		(drill 0.254)
		(layers "F.Cu" "B.Cu")
		(net "GPU_BB_RSVD_1_R")
	)
	(segment
		(start 150.241 -57.233566)
		(end 151.173434 -58.166)
		(width 0.2032)
		(layer "F.Cu")
		(net "P3V3_SSD5_SS")
	)
	(segment
		(start 151.2951 -58.453782)
		(end 151.2951 -59.177936)
		(width 0.2032)
		(layer "F.Cu")
		(net "P3V3_SSD5_SS")
	)
	(segment
		(start 150.241 -57.16397)
		(end 150.241 -57.233566)
		(width 0.2032)
		(layer "F.Cu")
		(net "P3V3_SSD5_SS")
	)
	(segment
		(start 151.173434 -58.166)
		(end 151.291036 -58.449718)
		(width 0.2032)
		(layer "F.Cu")
		(net "P3V3_SSD5_SS")
	)
	(segment
		(start 151.291036 -58.449718)
		(end 151.2951 -58.453782)
		(width 0.2032)
		(layer "F.Cu")
		(net "P3V3_SSD5_SS")
	)
	(via
		(at 151.291036 -58.449718)
		(size 0.508)
		(drill 0.254)
		(layers "F.Cu" "B.Cu")
		(net "P3V3_SSD5_SS")
	)
	(segment
		(start 239.013238 -84.305648)
		(end 239.459008 -84.751418)
		(width 0.13462)
		(layer "F.Cu")
		(net "USB2_FT4232_CLI_R_DP")
	)
	(segment
		(start 235.702856 -87.386414)
		(end 235.4072 -87.68207)
		(width 0.13462)
		(layer "F.Cu")
		(net "USB2_FT4232_CLI_R_DP")
	)
	(segment
		(start 235.4072 -89.413334)
		(end 235.521246 -89.52738)
		(width 0.13462)
		(layer "F.Cu")
		(net "USB2_FT4232_CLI_R_DP")
	)
	(segment
		(start 235.521246 -89.52738)
		(end 235.521246 -89.854024)
		(width 0.13462)
		(layer "F.Cu")
		(net "USB2_FT4232_CLI_R_DP")
	)
	(segment
		(start 239.459008 -84.751418)
		(end 239.721898 -84.751418)
		(width 0.13462)
		(layer "F.Cu")
		(net "USB2_FT4232_CLI_R_DP")
	)
	(segment
		(start 235.4072 -87.68207)
		(end 235.4072 -89.413334)
		(width 0.13462)
		(layer "F.Cu")
		(net "USB2_FT4232_CLI_R_DP")
	)
	(segment
		(start 237.751366 -86.995)
		(end 237.121192 -86.364826)
		(width 0.1651)
		(layer "In15.Cu")
		(net "USB2_FT4232_CLI_R_DP")
	)
	(segment
		(start 235.415328 -86.496906)
		(end 235.415328 -87.098886)
		(width 0.1651)
		(layer "In15.Cu")
		(net "USB2_FT4232_CLI_R_DP")
	)
	(segment
		(start 240.398554 -86.995)
		(end 237.751366 -86.995)
		(width 0.1651)
		(layer "In15.Cu")
		(net "USB2_FT4232_CLI_R_DP")
	)
	(segment
		(start 240.398554 -84.590636)
		(end 240.690654 -84.882736)
		(width 0.1651)
		(layer "In15.Cu")
		(net "USB2_FT4232_CLI_R_DP")
	)
	(segment
		(start 240.690654 -84.882736)
		(end 240.690654 -86.7029)
		(width 0.1651)
		(layer "In15.Cu")
		(net "USB2_FT4232_CLI_R_DP")
	)
	(segment
		(start 240.690654 -86.7029)
		(end 240.398554 -86.995)
		(width 0.1651)
		(layer "In15.Cu")
		(net "USB2_FT4232_CLI_R_DP")
	)
	(segment
		(start 237.121192 -86.364826)
		(end 235.547408 -86.364826)
		(width 0.1651)
		(layer "In15.Cu")
		(net "USB2_FT4232_CLI_R_DP")
	)
	(segment
		(start 235.547408 -86.364826)
		(end 235.415328 -86.496906)
		(width 0.1651)
		(layer "In15.Cu")
		(net "USB2_FT4232_CLI_R_DP")
	)
	(segment
		(start 239.013238 -84.305648)
		(end 239.298226 -84.590636)
		(width 0.1651)
		(layer "In15.Cu")
		(net "USB2_FT4232_CLI_R_DP")
	)
	(segment
		(start 235.415328 -87.098886)
		(end 235.702856 -87.386414)
		(width 0.1651)
		(layer "In15.Cu")
		(net "USB2_FT4232_CLI_R_DP")
	)
	(segment
		(start 239.298226 -84.590636)
		(end 240.398554 -84.590636)
		(width 0.1651)
		(layer "In15.Cu")
		(net "USB2_FT4232_CLI_R_DP")
	)
	(segment
		(start 169.11193 -16.363188)
		(end 169.03573 -16.439388)
		(width 0.13208)
		(layer "F.Cu")
		(net "SMB_ISO_SSD5_SDA")
	)
	(segment
		(start 166.126414 -19.453098)
		(end 166.16807 -19.453098)
		(width 0.13208)
		(layer "F.Cu")
		(net "SMB_ISO_SSD5_SDA")
	)
	(segment
		(start 169.03573 -16.439388)
		(end 169.03573 -18.533618)
		(width 0.13208)
		(layer "F.Cu")
		(net "SMB_ISO_SSD5_SDA")
	)
	(segment
		(start 165.35654 -20.467574)
		(end 165.35654 -20.222972)
		(width 0.13208)
		(layer "F.Cu")
		(net "SMB_ISO_SSD5_SDA")
	)
	(segment
		(start 169.11193 -15.351252)
		(end 169.11193 -16.363188)
		(width 0.13208)
		(layer "F.Cu")
		(net "SMB_ISO_SSD5_SDA")
	)
	(segment
		(start 168.11625 -19.453098)
		(end 166.16807 -19.453098)
		(width 0.13208)
		(layer "F.Cu")
		(net "SMB_ISO_SSD5_SDA")
	)
	(segment
		(start 169.03573 -18.533618)
		(end 168.11625 -19.453098)
		(width 0.13208)
		(layer "F.Cu")
		(net "SMB_ISO_SSD5_SDA")
	)
	(segment
		(start 165.35654 -20.222972)
		(end 166.126414 -19.453098)
		(width 0.13208)
		(layer "F.Cu")
		(net "SMB_ISO_SSD5_SDA")
	)
	(segment
		(start 169.562526 -23.337266)
		(end 169.562526 -23.946866)
		(width 0.13208)
		(layer "F.Cu")
		(net "SMB_ISO_SSD5_SDA")
	)
	(via
		(at 169.11193 -15.351252)
		(size 0.508)
		(drill 0.254)
		(layers "F.Cu" "B.Cu")
		(net "SMB_ISO_SSD5_SDA")
	)
	(via
		(at 169.562526 -23.946866)
		(size 0.508)
		(drill 0.254)
		(layers "F.Cu" "B.Cu")
		(net "SMB_ISO_SSD5_SDA")
	)
	(segment
		(start 171.173902 -17.482566)
		(end 171.173902 -22.33549)
		(width 0.13208)
		(layer "B.Cu")
		(net "SMB_ISO_SSD5_SDA")
	)
	(segment
		(start 169.11193 -15.351252)
		(end 169.11193 -15.420594)
		(width 0.13208)
		(layer "B.Cu")
		(net "SMB_ISO_SSD5_SDA")
	)
	(segment
		(start 169.11193 -15.420594)
		(end 171.173902 -17.482566)
		(width 0.13208)
		(layer "B.Cu")
		(net "SMB_ISO_SSD5_SDA")
	)
	(segment
		(start 171.173902 -22.33549)
		(end 169.562526 -23.946866)
		(width 0.13208)
		(layer "B.Cu")
		(net "SMB_ISO_SSD5_SDA")
	)
	(segment
		(start 306.858162 -19.453098)
		(end 307.467762 -19.453098)
		(width 0.13208)
		(layer "F.Cu")
		(net "SMB_ISO_SSD10_R_SDA")
	)
	(segment
		(start 295.909238 -22.990048)
		(end 295.94429 -23.0251)
		(width 0.13208)
		(layer "F.Cu")
		(net "SMB_ISO_SSD10_R_SDA")
	)
	(segment
		(start 294.86479 -22.990048)
		(end 295.909238 -22.990048)
		(width 0.13208)
		(layer "F.Cu")
		(net "SMB_ISO_SSD10_R_SDA")
	)
	(via
		(at 306.858162 -19.453098)
		(size 0.508)
		(drill 0.254)
		(layers "F.Cu" "B.Cu")
		(net "SMB_ISO_SSD10_R_SDA")
	)
	(via
		(at 295.94429 -23.0251)
		(size 0.508)
		(drill 0.254)
		(layers "F.Cu" "B.Cu")
		(net "SMB_ISO_SSD10_R_SDA")
	)
	(segment
		(start 296.43705 -22.53234)
		(end 295.94429 -23.0251)
		(width 0.15494)
		(layer "In5.Cu")
		(net "SMB_ISO_SSD10_R_SDA")
	)
	(segment
		(start 306.858162 -21.390356)
		(end 305.716178 -22.53234)
		(width 0.15494)
		(layer "In5.Cu")
		(net "SMB_ISO_SSD10_R_SDA")
	)
	(segment
		(start 305.716178 -22.53234)
		(end 296.43705 -22.53234)
		(width 0.15494)
		(layer "In5.Cu")
		(net "SMB_ISO_SSD10_R_SDA")
	)
	(segment
		(start 306.858162 -19.453098)
		(end 306.858162 -21.390356)
		(width 0.15494)
		(layer "In5.Cu")
		(net "SMB_ISO_SSD10_R_SDA")
	)
	(segment
		(start 357.985568 -251.63907)
		(end 358.392476 -252.045978)
		(width 0.13208)
		(layer "F.Cu")
		(net "SMB_BIC_I2C6_MUX_VR_R_SCL")
	)
	(segment
		(start 124.991114 -251.5997)
		(end 125.245114 -251.3457)
		(width 0.13208)
		(layer "F.Cu")
		(net "SMB_BIC_I2C6_MUX_VR_R_SCL")
	)
	(segment
		(start 131.0386 -248.5644)
		(end 130.8354 -248.7676)
		(width 0.13208)
		(layer "F.Cu")
		(net "SMB_BIC_I2C6_MUX_VR_R_SCL")
	)
	(segment
		(start 130.8354 -248.7676)
		(end 129.26314 -248.7676)
		(width 0.13208)
		(layer "F.Cu")
		(net "SMB_BIC_I2C6_MUX_VR_R_SCL")
	)
	(segment
		(start 127.469138 -250.561856)
		(end 127.469138 -249.803412)
		(width 0.13208)
		(layer "F.Cu")
		(net "SMB_BIC_I2C6_MUX_VR_R_SCL")
	)
	(segment
		(start 124.991114 -252.016514)
		(end 124.991114 -251.5997)
		(width 0.13208)
		(layer "F.Cu")
		(net "SMB_BIC_I2C6_MUX_VR_R_SCL")
	)
	(segment
		(start 357.76027 -251.63907)
		(end 357.985568 -251.63907)
		(width 0.13208)
		(layer "F.Cu")
		(net "SMB_BIC_I2C6_MUX_VR_R_SCL")
	)
	(segment
		(start 126.157736 -249.142504)
		(end 132.731764 -242.568476)
		(width 0.13208)
		(layer "F.Cu")
		(net "SMB_BIC_I2C6_MUX_VR_R_SCL")
	)
	(segment
		(start 125.245114 -251.3457)
		(end 126.157736 -249.142504)
		(width 0.13208)
		(layer "F.Cu")
		(net "SMB_BIC_I2C6_MUX_VR_R_SCL")
	)
	(segment
		(start 357.44531 -251.32411)
		(end 357.76027 -251.63907)
		(width 0.13208)
		(layer "F.Cu")
		(net "SMB_BIC_I2C6_MUX_VR_R_SCL")
	)
	(segment
		(start 128.73863 -249.29211)
		(end 128.017524 -249.29211)
		(width 0.13208)
		(layer "F.Cu")
		(net "SMB_BIC_I2C6_MUX_VR_R_SCL")
	)
	(segment
		(start 128.017524 -249.29211)
		(end 127.998982 -249.273568)
		(width 0.13208)
		(layer "F.Cu")
		(net "SMB_BIC_I2C6_MUX_VR_R_SCL")
	)
	(segment
		(start 129.26314 -248.7676)
		(end 128.73863 -249.29211)
		(width 0.13208)
		(layer "F.Cu")
		(net "SMB_BIC_I2C6_MUX_VR_R_SCL")
	)
	(segment
		(start 132.731764 -242.568476)
		(end 133.368796 -242.568476)
		(width 0.13208)
		(layer "F.Cu")
		(net "SMB_BIC_I2C6_MUX_VR_R_SCL")
	)
	(segment
		(start 357.19131 -252.016514)
		(end 357.19131 -251.57811)
		(width 0.13208)
		(layer "F.Cu")
		(net "SMB_BIC_I2C6_MUX_VR_R_SCL")
	)
	(segment
		(start 357.19131 -251.57811)
		(end 357.44531 -251.32411)
		(width 0.13208)
		(layer "F.Cu")
		(net "SMB_BIC_I2C6_MUX_VR_R_SCL")
	)
	(segment
		(start 129.8448 -247.9548)
		(end 130.8354 -247.9548)
		(width 0.13208)
		(layer "F.Cu")
		(net "SMB_BIC_I2C6_MUX_VR_R_SCL")
	)
	(segment
		(start 131.0386 -248.158)
		(end 131.0386 -248.5644)
		(width 0.13208)
		(layer "F.Cu")
		(net "SMB_BIC_I2C6_MUX_VR_R_SCL")
	)
	(segment
		(start 129.704338 -247.814338)
		(end 129.8448 -247.9548)
		(width 0.13208)
		(layer "F.Cu")
		(net "SMB_BIC_I2C6_MUX_VR_R_SCL")
	)
	(segment
		(start 358.392476 -251.054616)
		(end 358.392476 -252.045978)
		(width 0.13208)
		(layer "F.Cu")
		(net "SMB_BIC_I2C6_MUX_VR_R_SCL")
	)
	(segment
		(start 128.172972 -251.26569)
		(end 127.469138 -250.561856)
		(width 0.13208)
		(layer "F.Cu")
		(net "SMB_BIC_I2C6_MUX_VR_R_SCL")
	)
	(segment
		(start 133.368796 -242.568476)
		(end 134.081266 -241.856006)
		(width 0.13208)
		(layer "F.Cu")
		(net "SMB_BIC_I2C6_MUX_VR_R_SCL")
	)
	(segment
		(start 358.392222 -251.054362)
		(end 358.392476 -251.054616)
		(width 0.13208)
		(layer "F.Cu")
		(net "SMB_BIC_I2C6_MUX_VR_R_SCL")
	)
	(segment
		(start 128.274826 -251.26569)
		(end 128.172972 -251.26569)
		(width 0.13208)
		(layer "F.Cu")
		(net "SMB_BIC_I2C6_MUX_VR_R_SCL")
	)
	(segment
		(start 130.8354 -247.9548)
		(end 131.0386 -248.158)
		(width 0.13208)
		(layer "F.Cu")
		(net "SMB_BIC_I2C6_MUX_VR_R_SCL")
	)
	(segment
		(start 129.704338 -247.36679)
		(end 129.704338 -247.814338)
		(width 0.13208)
		(layer "F.Cu")
		(net "SMB_BIC_I2C6_MUX_VR_R_SCL")
	)
	(segment
		(start 127.469138 -249.803412)
		(end 127.998982 -249.273568)
		(width 0.13208)
		(layer "F.Cu")
		(net "SMB_BIC_I2C6_MUX_VR_R_SCL")
	)
	(via
		(at 127.998982 -249.273568)
		(size 0.508)
		(drill 0.254)
		(layers "F.Cu" "B.Cu")
		(net "SMB_BIC_I2C6_MUX_VR_R_SCL")
	)
	(via
		(at 356.89286 -249.403362)
		(size 0.6604)
		(drill 0.3302)
		(layers "F.Cu" "B.Cu")
		(net "SMB_BIC_I2C6_MUX_VR_R_SCL")
	)
	(via
		(at 125.245114 -251.3457)
		(size 0.508)
		(drill 0.254)
		(layers "F.Cu" "B.Cu")
		(net "SMB_BIC_I2C6_MUX_VR_R_SCL")
	)
	(via
		(at 357.44531 -251.32411)
		(size 0.508)
		(drill 0.254)
		(layers "F.Cu" "B.Cu")
		(net "SMB_BIC_I2C6_MUX_VR_R_SCL")
	)
	(via
		(at 134.081266 -241.856006)
		(size 0.508)
		(drill 0.254)
		(layers "F.Cu" "B.Cu")
		(net "SMB_BIC_I2C6_MUX_VR_R_SCL")
	)
	(via
		(at 304.802032 -256.834894)
		(size 0.508)
		(drill 0.254)
		(layers "F.Cu" "B.Cu")
		(net "SMB_BIC_I2C6_MUX_VR_R_SCL")
	)
	(segment
		(start 358.351074 -251.32411)
		(end 358.62006 -251.593096)
		(width 0.13208)
		(layer "B.Cu")
		(net "SMB_BIC_I2C6_MUX_VR_R_SCL")
	)
	(segment
		(start 344.785188 -248.637298)
		(end 344.688668 -248.733818)
		(width 0.13208)
		(layer "B.Cu")
		(net "SMB_BIC_I2C6_MUX_VR_R_SCL")
	)
	(segment
		(start 356.89286 -249.403362)
		(end 356.126796 -248.637298)
		(width 0.13208)
		(layer "B.Cu")
		(net "SMB_BIC_I2C6_MUX_VR_R_SCL")
	)
	(segment
		(start 356.89286 -249.403362)
		(end 357.44531 -249.955812)
		(width 0.13208)
		(layer "B.Cu")
		(net "SMB_BIC_I2C6_MUX_VR_R_SCL")
	)
	(segment
		(start 308.355746 -253.28118)
		(end 304.802032 -256.834894)
		(width 0.13208)
		(layer "B.Cu")
		(net "SMB_BIC_I2C6_MUX_VR_R_SCL")
	)
	(segment
		(start 340.123272 -253.28118)
		(end 308.355746 -253.28118)
		(width 0.13208)
		(layer "B.Cu")
		(net "SMB_BIC_I2C6_MUX_VR_R_SCL")
	)
	(segment
		(start 344.688668 -248.733818)
		(end 344.670634 -248.733818)
		(width 0.13208)
		(layer "B.Cu")
		(net "SMB_BIC_I2C6_MUX_VR_R_SCL")
	)
	(segment
		(start 344.670634 -248.733818)
		(end 340.123272 -253.28118)
		(width 0.13208)
		(layer "B.Cu")
		(net "SMB_BIC_I2C6_MUX_VR_R_SCL")
	)
	(segment
		(start 356.126796 -248.637298)
		(end 344.785188 -248.637298)
		(width 0.13208)
		(layer "B.Cu")
		(net "SMB_BIC_I2C6_MUX_VR_R_SCL")
	)
	(segment
		(start 357.44531 -251.32411)
		(end 358.351074 -251.32411)
		(width 0.13208)
		(layer "B.Cu")
		(net "SMB_BIC_I2C6_MUX_VR_R_SCL")
	)
	(segment
		(start 358.62006 -251.593096)
		(end 358.62006 -252.186694)
		(width 0.13208)
		(layer "B.Cu")
		(net "SMB_BIC_I2C6_MUX_VR_R_SCL")
	)
	(segment
		(start 357.44531 -249.955812)
		(end 357.44531 -251.32411)
		(width 0.13208)
		(layer "B.Cu")
		(net "SMB_BIC_I2C6_MUX_VR_R_SCL")
	)
	(segment
		(start 207.715866 -248.02719)
		(end 177.694844 -248.02719)
		(width 0.15494)
		(layer "In13.Cu")
		(net "SMB_BIC_I2C6_MUX_VR_R_SCL")
	)
	(segment
		(start 301.234094 -256.834894)
		(end 297.3578 -252.9586)
		(width 0.15494)
		(layer "In13.Cu")
		(net "SMB_BIC_I2C6_MUX_VR_R_SCL")
	)
	(segment
		(start 134.154672 -241.7826)
		(end 134.081266 -241.856006)
		(width 0.15494)
		(layer "In13.Cu")
		(net "SMB_BIC_I2C6_MUX_VR_R_SCL")
	)
	(segment
		(start 173.482254 -243.8146)
		(end 152.044654 -243.8146)
		(width 0.15494)
		(layer "In13.Cu")
		(net "SMB_BIC_I2C6_MUX_VR_R_SCL")
	)
	(segment
		(start 140.6906 -241.7826)
		(end 134.154672 -241.7826)
		(width 0.15494)
		(layer "In13.Cu")
		(net "SMB_BIC_I2C6_MUX_VR_R_SCL")
	)
	(segment
		(start 177.694844 -248.02719)
		(end 173.482254 -243.8146)
		(width 0.15494)
		(layer "In13.Cu")
		(net "SMB_BIC_I2C6_MUX_VR_R_SCL")
	)
	(segment
		(start 148.844254 -241.960908)
		(end 145.98142 -241.960908)
		(width 0.15494)
		(layer "In13.Cu")
		(net "SMB_BIC_I2C6_MUX_VR_R_SCL")
	)
	(segment
		(start 254.213106 -252.26264)
		(end 253.023878 -251.073412)
		(width 0.15494)
		(layer "In13.Cu")
		(net "SMB_BIC_I2C6_MUX_VR_R_SCL")
	)
	(segment
		(start 209.065876 -249.3772)
		(end 207.715866 -248.02719)
		(width 0.15494)
		(layer "In13.Cu")
		(net "SMB_BIC_I2C6_MUX_VR_R_SCL")
	)
	(segment
		(start 227.944172 -247.909842)
		(end 215.956134 -247.909842)
		(width 0.15494)
		(layer "In13.Cu")
		(net "SMB_BIC_I2C6_MUX_VR_R_SCL")
	)
	(segment
		(start 214.488776 -249.3772)
		(end 209.065876 -249.3772)
		(width 0.15494)
		(layer "In13.Cu")
		(net "SMB_BIC_I2C6_MUX_VR_R_SCL")
	)
	(segment
		(start 304.802032 -256.834894)
		(end 301.234094 -256.834894)
		(width 0.15494)
		(layer "In13.Cu")
		(net "SMB_BIC_I2C6_MUX_VR_R_SCL")
	)
	(segment
		(start 150.80996 -242.579906)
		(end 149.463252 -242.579906)
		(width 0.15494)
		(layer "In13.Cu")
		(net "SMB_BIC_I2C6_MUX_VR_R_SCL")
	)
	(segment
		(start 271.49044 -252.26264)
		(end 254.213106 -252.26264)
		(width 0.15494)
		(layer "In13.Cu")
		(net "SMB_BIC_I2C6_MUX_VR_R_SCL")
	)
	(segment
		(start 145.615152 -243.182902)
		(end 144.983454 -243.8146)
		(width 0.15494)
		(layer "In13.Cu")
		(net "SMB_BIC_I2C6_MUX_VR_R_SCL")
	)
	(segment
		(start 142.7226 -243.8146)
		(end 140.6906 -241.7826)
		(width 0.15494)
		(layer "In13.Cu")
		(net "SMB_BIC_I2C6_MUX_VR_R_SCL")
	)
	(segment
		(start 230.083106 -250.048776)
		(end 227.944172 -247.909842)
		(width 0.15494)
		(layer "In13.Cu")
		(net "SMB_BIC_I2C6_MUX_VR_R_SCL")
	)
	(segment
		(start 149.463252 -242.579906)
		(end 148.844254 -241.960908)
		(width 0.15494)
		(layer "In13.Cu")
		(net "SMB_BIC_I2C6_MUX_VR_R_SCL")
	)
	(segment
		(start 253.023878 -251.073412)
		(end 234.461812 -251.073412)
		(width 0.15494)
		(layer "In13.Cu")
		(net "SMB_BIC_I2C6_MUX_VR_R_SCL")
	)
	(segment
		(start 127.317246 -249.273568)
		(end 127.998982 -249.273568)
		(width 0.15494)
		(layer "In13.Cu")
		(net "SMB_BIC_I2C6_MUX_VR_R_SCL")
	)
	(segment
		(start 144.983454 -243.8146)
		(end 142.7226 -243.8146)
		(width 0.15494)
		(layer "In13.Cu")
		(net "SMB_BIC_I2C6_MUX_VR_R_SCL")
	)
	(segment
		(start 297.3578 -252.9586)
		(end 272.1864 -252.9586)
		(width 0.15494)
		(layer "In13.Cu")
		(net "SMB_BIC_I2C6_MUX_VR_R_SCL")
	)
	(segment
		(start 152.044654 -243.8146)
		(end 150.80996 -242.579906)
		(width 0.15494)
		(layer "In13.Cu")
		(net "SMB_BIC_I2C6_MUX_VR_R_SCL")
	)
	(segment
		(start 145.98142 -241.960908)
		(end 145.615152 -242.327176)
		(width 0.15494)
		(layer "In13.Cu")
		(net "SMB_BIC_I2C6_MUX_VR_R_SCL")
	)
	(segment
		(start 233.437176 -250.048776)
		(end 230.083106 -250.048776)
		(width 0.15494)
		(layer "In13.Cu")
		(net "SMB_BIC_I2C6_MUX_VR_R_SCL")
	)
	(segment
		(start 145.615152 -242.327176)
		(end 145.615152 -243.182902)
		(width 0.15494)
		(layer "In13.Cu")
		(net "SMB_BIC_I2C6_MUX_VR_R_SCL")
	)
	(segment
		(start 272.1864 -252.9586)
		(end 271.49044 -252.26264)
		(width 0.15494)
		(layer "In13.Cu")
		(net "SMB_BIC_I2C6_MUX_VR_R_SCL")
	)
	(segment
		(start 125.245114 -251.3457)
		(end 127.317246 -249.273568)
		(width 0.15494)
		(layer "In13.Cu")
		(net "SMB_BIC_I2C6_MUX_VR_R_SCL")
	)
	(segment
		(start 234.461812 -251.073412)
		(end 233.437176 -250.048776)
		(width 0.15494)
		(layer "In13.Cu")
		(net "SMB_BIC_I2C6_MUX_VR_R_SCL")
	)
	(segment
		(start 215.956134 -247.909842)
		(end 214.488776 -249.3772)
		(width 0.15494)
		(layer "In13.Cu")
		(net "SMB_BIC_I2C6_MUX_VR_R_SCL")
	)
	(segment
		(start 183.228996 -181.6862)
		(end 184.197498 -180.717698)
		(width 0.13208)
		(layer "F.Cu")
		(net "NIC2_MAIN_PWR_EN")
	)
	(segment
		(start 154.307794 -159.4104)
		(end 154.307794 -160.380934)
		(width 0.13208)
		(layer "F.Cu")
		(net "NIC2_MAIN_PWR_EN")
	)
	(segment
		(start 184.197498 -179.676806)
		(end 183.808624 -179.287932)
		(width 0.13208)
		(layer "F.Cu")
		(net "NIC2_MAIN_PWR_EN")
	)
	(segment
		(start 166.551102 -181.6862)
		(end 183.228996 -181.6862)
		(width 0.13208)
		(layer "F.Cu")
		(net "NIC2_MAIN_PWR_EN")
	)
	(segment
		(start 350.093788 -222.38716)
		(end 350.493584 -222.786956)
		(width 0.13208)
		(layer "F.Cu")
		(net "NIC2_MAIN_PWR_EN")
	)
	(segment
		(start 154.307794 -160.380934)
		(end 153.753312 -160.935416)
		(width 0.13208)
		(layer "F.Cu")
		(net "NIC2_MAIN_PWR_EN")
	)
	(segment
		(start 184.197498 -180.717698)
		(end 184.197498 -179.676806)
		(width 0.13208)
		(layer "F.Cu")
		(net "NIC2_MAIN_PWR_EN")
	)
	(segment
		(start 153.753312 -168.88841)
		(end 166.551102 -181.6862)
		(width 0.13208)
		(layer "F.Cu")
		(net "NIC2_MAIN_PWR_EN")
	)
	(segment
		(start 153.753312 -160.935416)
		(end 153.753312 -168.88841)
		(width 0.13208)
		(layer "F.Cu")
		(net "NIC2_MAIN_PWR_EN")
	)
	(via
		(at 350.493584 -222.786956)
		(size 0.4572)
		(drill 0.254)
		(layers "F.Cu" "B.Cu")
		(net "NIC2_MAIN_PWR_EN")
	)
	(via
		(at 250.5964 -182.280814)
		(size 0.508)
		(drill 0.254)
		(layers "F.Cu" "B.Cu")
		(net "NIC2_MAIN_PWR_EN")
	)
	(via
		(at 183.808624 -179.287932)
		(size 0.508)
		(drill 0.254)
		(layers "F.Cu" "B.Cu")
		(net "NIC2_MAIN_PWR_EN")
	)
	(segment
		(start 252.931676 -179.945538)
		(end 250.5964 -182.280814)
		(width 0.15494)
		(layer "In15.Cu")
		(net "NIC2_MAIN_PWR_EN")
	)
	(segment
		(start 215.221312 -178.352196)
		(end 214.379556 -178.352196)
		(width 0.15494)
		(layer "In15.Cu")
		(net "NIC2_MAIN_PWR_EN")
	)
	(segment
		(start 209.332068 -179.287932)
		(end 183.808624 -179.287932)
		(width 0.15494)
		(layer "In15.Cu")
		(net "NIC2_MAIN_PWR_EN")
	)
	(segment
		(start 361.39374 -223.817942)
		(end 361.39374 -223.483932)
		(width 0.15494)
		(layer "In15.Cu")
		(net "NIC2_MAIN_PWR_EN")
	)
	(segment
		(start 231.112568 -180.565806)
		(end 231.010206 -180.668168)
		(width 0.15494)
		(layer "In15.Cu")
		(net "NIC2_MAIN_PWR_EN")
	)
	(segment
		(start 209.909664 -178.710336)
		(end 209.332068 -179.287932)
		(width 0.15494)
		(layer "In15.Cu")
		(net "NIC2_MAIN_PWR_EN")
	)
	(segment
		(start 282.06192 -179.945538)
		(end 252.931676 -179.945538)
		(width 0.15494)
		(layer "In15.Cu")
		(net "NIC2_MAIN_PWR_EN")
	)
	(segment
		(start 359.889044 -187.246514)
		(end 358.34066 -185.69813)
		(width 0.15494)
		(layer "In15.Cu")
		(net "NIC2_MAIN_PWR_EN")
	)
	(segment
		(start 210.965796 -178.710336)
		(end 209.909664 -178.710336)
		(width 0.15494)
		(layer "In15.Cu")
		(net "NIC2_MAIN_PWR_EN")
	)
	(segment
		(start 232.6005 -180.852318)
		(end 232.313988 -180.565806)
		(width 0.15494)
		(layer "In15.Cu")
		(net "NIC2_MAIN_PWR_EN")
	)
	(segment
		(start 350.896428 -223.1898)
		(end 351.663 -223.1898)
		(width 0.0889)
		(layer "In15.Cu")
		(net "NIC2_MAIN_PWR_EN")
	)
	(segment
		(start 227.334064 -179.46751)
		(end 219.5576 -179.46751)
		(width 0.15494)
		(layer "In15.Cu")
		(net "NIC2_MAIN_PWR_EN")
	)
	(segment
		(start 361.39374 -223.483932)
		(end 363.02188 -219.553282)
		(width 0.15494)
		(layer "In15.Cu")
		(net "NIC2_MAIN_PWR_EN")
	)
	(segment
		(start 362.94187 -199.552306)
		(end 362.94187 -191.260984)
		(width 0.15494)
		(layer "In15.Cu")
		(net "NIC2_MAIN_PWR_EN")
	)
	(segment
		(start 211.05368 -178.79822)
		(end 210.965796 -178.710336)
		(width 0.15494)
		(layer "In15.Cu")
		(net "NIC2_MAIN_PWR_EN")
	)
	(segment
		(start 362.035852 -189.139322)
		(end 360.143044 -187.246514)
		(width 0.15494)
		(layer "In15.Cu")
		(net "NIC2_MAIN_PWR_EN")
	)
	(segment
		(start 232.313988 -180.565806)
		(end 231.112568 -180.565806)
		(width 0.15494)
		(layer "In15.Cu")
		(net "NIC2_MAIN_PWR_EN")
	)
	(segment
		(start 362.94187 -191.260984)
		(end 362.035852 -190.354966)
		(width 0.15494)
		(layer "In15.Cu")
		(net "NIC2_MAIN_PWR_EN")
	)
	(segment
		(start 215.959182 -179.090066)
		(end 215.221312 -178.352196)
		(width 0.15494)
		(layer "In15.Cu")
		(net "NIC2_MAIN_PWR_EN")
	)
	(segment
		(start 219.180156 -179.090066)
		(end 215.959182 -179.090066)
		(width 0.15494)
		(layer "In15.Cu")
		(net "NIC2_MAIN_PWR_EN")
	)
	(segment
		(start 358.34066 -185.69813)
		(end 357.47833 -185.69813)
		(width 0.15494)
		(layer "In15.Cu")
		(net "NIC2_MAIN_PWR_EN")
	)
	(segment
		(start 354.52304 -223.1898)
		(end 354.67671 -223.03613)
		(width 0.15494)
		(layer "In15.Cu")
		(net "NIC2_MAIN_PWR_EN")
	)
	(segment
		(start 347.770704 -181.884828)
		(end 346.123006 -180.23713)
		(width 0.15494)
		(layer "In15.Cu")
		(net "NIC2_MAIN_PWR_EN")
	)
	(segment
		(start 360.143044 -187.246514)
		(end 359.889044 -187.246514)
		(width 0.15494)
		(layer "In15.Cu")
		(net "NIC2_MAIN_PWR_EN")
	)
	(segment
		(start 357.19766 -223.03613)
		(end 357.48087 -223.31934)
		(width 0.15494)
		(layer "In15.Cu")
		(net "NIC2_MAIN_PWR_EN")
	)
	(segment
		(start 350.493584 -222.786956)
		(end 350.896428 -223.1898)
		(width 0.0889)
		(layer "In15.Cu")
		(net "NIC2_MAIN_PWR_EN")
	)
	(segment
		(start 333.275178 -180.671978)
		(end 282.78836 -180.671978)
		(width 0.15494)
		(layer "In15.Cu")
		(net "NIC2_MAIN_PWR_EN")
	)
	(segment
		(start 231.010206 -180.668168)
		(end 228.534722 -180.668168)
		(width 0.15494)
		(layer "In15.Cu")
		(net "NIC2_MAIN_PWR_EN")
	)
	(segment
		(start 362.035852 -190.354966)
		(end 362.035852 -189.139322)
		(width 0.15494)
		(layer "In15.Cu")
		(net "NIC2_MAIN_PWR_EN")
	)
	(segment
		(start 363.65815 -200.268586)
		(end 362.94187 -199.552306)
		(width 0.15494)
		(layer "In15.Cu")
		(net "NIC2_MAIN_PWR_EN")
	)
	(segment
		(start 214.379556 -178.352196)
		(end 213.933532 -178.79822)
		(width 0.15494)
		(layer "In15.Cu")
		(net "NIC2_MAIN_PWR_EN")
	)
	(segment
		(start 363.02188 -219.553282)
		(end 363.65815 -218.917012)
		(width 0.15494)
		(layer "In15.Cu")
		(net "NIC2_MAIN_PWR_EN")
	)
	(segment
		(start 333.710026 -180.23713)
		(end 333.275178 -180.671978)
		(width 0.15494)
		(layer "In15.Cu")
		(net "NIC2_MAIN_PWR_EN")
	)
	(segment
		(start 357.47833 -185.69813)
		(end 353.665028 -181.884828)
		(width 0.15494)
		(layer "In15.Cu")
		(net "NIC2_MAIN_PWR_EN")
	)
	(segment
		(start 219.5576 -179.46751)
		(end 219.180156 -179.090066)
		(width 0.15494)
		(layer "In15.Cu")
		(net "NIC2_MAIN_PWR_EN")
	)
	(segment
		(start 360.191812 -225.01987)
		(end 361.39374 -223.817942)
		(width 0.15494)
		(layer "In15.Cu")
		(net "NIC2_MAIN_PWR_EN")
	)
	(segment
		(start 282.78836 -180.671978)
		(end 282.06192 -179.945538)
		(width 0.15494)
		(layer "In15.Cu")
		(net "NIC2_MAIN_PWR_EN")
	)
	(segment
		(start 357.48087 -223.31934)
		(end 357.48087 -223.6724)
		(width 0.15494)
		(layer "In15.Cu")
		(net "NIC2_MAIN_PWR_EN")
	)
	(segment
		(start 358.82834 -225.01987)
		(end 360.191812 -225.01987)
		(width 0.15494)
		(layer "In15.Cu")
		(net "NIC2_MAIN_PWR_EN")
	)
	(segment
		(start 250.5964 -182.280814)
		(end 249.167904 -180.852318)
		(width 0.15494)
		(layer "In15.Cu")
		(net "NIC2_MAIN_PWR_EN")
	)
	(segment
		(start 213.933532 -178.79822)
		(end 211.05368 -178.79822)
		(width 0.15494)
		(layer "In15.Cu")
		(net "NIC2_MAIN_PWR_EN")
	)
	(segment
		(start 351.663 -223.1898)
		(end 354.52304 -223.1898)
		(width 0.15494)
		(layer "In15.Cu")
		(net "NIC2_MAIN_PWR_EN")
	)
	(segment
		(start 249.167904 -180.852318)
		(end 232.6005 -180.852318)
		(width 0.15494)
		(layer "In15.Cu")
		(net "NIC2_MAIN_PWR_EN")
	)
	(segment
		(start 363.65815 -218.917012)
		(end 363.65815 -200.268586)
		(width 0.15494)
		(layer "In15.Cu")
		(net "NIC2_MAIN_PWR_EN")
	)
	(segment
		(start 346.123006 -180.23713)
		(end 333.710026 -180.23713)
		(width 0.15494)
		(layer "In15.Cu")
		(net "NIC2_MAIN_PWR_EN")
	)
	(segment
		(start 228.534722 -180.668168)
		(end 227.334064 -179.46751)
		(width 0.15494)
		(layer "In15.Cu")
		(net "NIC2_MAIN_PWR_EN")
	)
	(segment
		(start 354.67671 -223.03613)
		(end 357.19766 -223.03613)
		(width 0.15494)
		(layer "In15.Cu")
		(net "NIC2_MAIN_PWR_EN")
	)
	(segment
		(start 357.48087 -223.6724)
		(end 358.82834 -225.01987)
		(width 0.15494)
		(layer "In15.Cu")
		(net "NIC2_MAIN_PWR_EN")
	)
	(segment
		(start 353.665028 -181.884828)
		(end 347.770704 -181.884828)
		(width 0.15494)
		(layer "In15.Cu")
		(net "NIC2_MAIN_PWR_EN")
	)
	(segment
		(start 384.242564 -232.126282)
		(end 384.355594 -232.239312)
		(width 0.13462)
		(layer "F.Cu")
		(net "USB2_FT4232_SDB_DP")
	)
	(segment
		(start 384.242564 -231.168448)
		(end 384.242564 -232.126282)
		(width 0.13462)
		(layer "F.Cu")
		(net "USB2_FT4232_SDB_DP")
	)
	(segment
		(start 233.871008 -84.162392)
		(end 233.284776 -84.748624)
		(width 0.13462)
		(layer "F.Cu")
		(net "USB2_FT4232_SDB_DP")
	)
	(segment
		(start 384.355594 -232.239312)
		(end 384.355594 -232.836212)
		(width 0.13462)
		(layer "F.Cu")
		(net "USB2_FT4232_SDB_DP")
	)
	(segment
		(start 233.871008 -83.718908)
		(end 233.871008 -84.162392)
		(width 0.13462)
		(layer "F.Cu")
		(net "USB2_FT4232_SDB_DP")
	)
	(segment
		(start 233.284776 -84.748624)
		(end 233.284776 -85.127592)
		(width 0.13462)
		(layer "F.Cu")
		(net "USB2_FT4232_SDB_DP")
	)
	(segment
		(start 384.537458 -230.873554)
		(end 384.242564 -231.168448)
		(width 0.13462)
		(layer "F.Cu")
		(net "USB2_FT4232_SDB_DP")
	)
	(segment
		(start 233.284776 -85.127592)
		(end 233.585766 -85.428582)
		(width 0.13462)
		(layer "F.Cu")
		(net "USB2_FT4232_SDB_DP")
	)
	(via
		(at 233.585766 -85.428582)
		(size 0.508)
		(drill 0.254)
		(layers "F.Cu" "B.Cu")
		(net "USB2_FT4232_SDB_DP")
	)
	(via
		(at 384.537458 -230.873554)
		(size 0.508)
		(drill 0.254)
		(layers "F.Cu" "B.Cu")
		(net "USB2_FT4232_SDB_DP")
	)
	(via
		(at 371.051328 -193.87439)
		(size 0.4064)
		(drill 0.2032)
		(layers "F.Cu" "B.Cu")
		(net "USB2_FT4232_SDB_DP")
	)
	(segment
		(start 296.753534 -137.8331)
		(end 321.42684 -137.8331)
		(width 0.13462)
		(layer "B.Cu")
		(net "USB2_FT4232_SDB_DP")
	)
	(segment
		(start 281.853132 -85.583268)
		(end 281.853132 -87.016844)
		(width 0.13462)
		(layer "B.Cu")
		(net "USB2_FT4232_SDB_DP")
	)
	(segment
		(start 238.22025 -86.58225)
		(end 241.350038 -86.58225)
		(width 0.13462)
		(layer "B.Cu")
		(net "USB2_FT4232_SDB_DP")
	)
	(segment
		(start 345.293188 -164.717476)
		(end 349.702628 -169.126916)
		(width 0.13462)
		(layer "B.Cu")
		(net "USB2_FT4232_SDB_DP")
	)
	(segment
		(start 233.284776 -85.992716)
		(end 233.39806 -86.106)
		(width 0.13462)
		(layer "B.Cu")
		(net "USB2_FT4232_SDB_DP")
	)
	(segment
		(start 241.350038 -86.58225)
		(end 243.00688 -84.925408)
		(width 0.13462)
		(layer "B.Cu")
		(net "USB2_FT4232_SDB_DP")
	)
	(segment
		(start 324.22846 -135.03148)
		(end 335.55813 -135.03148)
		(width 0.13462)
		(layer "B.Cu")
		(net "USB2_FT4232_SDB_DP")
	)
	(segment
		(start 383.887218 -229.49408)
		(end 384.249168 -229.85603)
		(width 0.13462)
		(layer "B.Cu")
		(net "USB2_FT4232_SDB_DP")
	)
	(segment
		(start 237.744 -86.106)
		(end 238.22025 -86.58225)
		(width 0.13462)
		(layer "B.Cu")
		(net "USB2_FT4232_SDB_DP")
	)
	(segment
		(start 273.998944 -77.72908)
		(end 281.853132 -85.583268)
		(width 0.13462)
		(layer "B.Cu")
		(net "USB2_FT4232_SDB_DP")
	)
	(segment
		(start 256.507996 -75.107292)
		(end 256.863088 -74.7522)
		(width 0.13462)
		(layer "B.Cu")
		(net "USB2_FT4232_SDB_DP")
	)
	(segment
		(start 233.585766 -85.428582)
		(end 233.284776 -85.729572)
		(width 0.13462)
		(layer "B.Cu")
		(net "USB2_FT4232_SDB_DP")
	)
	(segment
		(start 370.162582 -185.24347)
		(end 371.051328 -186.132216)
		(width 0.13462)
		(layer "B.Cu")
		(net "USB2_FT4232_SDB_DP")
	)
	(segment
		(start 256.863088 -74.7522)
		(end 261.239 -74.7522)
		(width 0.13462)
		(layer "B.Cu")
		(net "USB2_FT4232_SDB_DP")
	)
	(segment
		(start 349.702628 -169.126916)
		(end 363.97184 -169.126916)
		(width 0.13462)
		(layer "B.Cu")
		(net "USB2_FT4232_SDB_DP")
	)
	(segment
		(start 243.00688 -84.925408)
		(end 243.00688 -79.884778)
		(width 0.13462)
		(layer "B.Cu")
		(net "USB2_FT4232_SDB_DP")
	)
	(segment
		(start 281.853132 -87.016844)
		(end 291.33292 -96.496632)
		(width 0.13462)
		(layer "B.Cu")
		(net "USB2_FT4232_SDB_DP")
	)
	(segment
		(start 233.39806 -86.106)
		(end 237.744 -86.106)
		(width 0.13462)
		(layer "B.Cu")
		(net "USB2_FT4232_SDB_DP")
	)
	(segment
		(start 384.249168 -230.585264)
		(end 384.537458 -230.873554)
		(width 0.13462)
		(layer "B.Cu")
		(net "USB2_FT4232_SDB_DP")
	)
	(segment
		(start 261.239 -74.7522)
		(end 262.1534 -73.8378)
		(width 0.13462)
		(layer "B.Cu")
		(net "USB2_FT4232_SDB_DP")
	)
	(segment
		(start 371.051328 -186.132216)
		(end 371.051328 -193.87439)
		(width 0.13462)
		(layer "B.Cu")
		(net "USB2_FT4232_SDB_DP")
	)
	(segment
		(start 262.1534 -73.8378)
		(end 267.4366 -73.8378)
		(width 0.13462)
		(layer "B.Cu")
		(net "USB2_FT4232_SDB_DP")
	)
	(segment
		(start 267.4366 -73.8378)
		(end 271.32788 -77.72908)
		(width 0.13462)
		(layer "B.Cu")
		(net "USB2_FT4232_SDB_DP")
	)
	(segment
		(start 384.249168 -229.85603)
		(end 384.249168 -230.585264)
		(width 0.13462)
		(layer "B.Cu")
		(net "USB2_FT4232_SDB_DP")
	)
	(segment
		(start 370.162582 -175.317658)
		(end 370.162582 -185.24347)
		(width 0.13462)
		(layer "B.Cu")
		(net "USB2_FT4232_SDB_DP")
	)
	(segment
		(start 271.32788 -77.72908)
		(end 273.998944 -77.72908)
		(width 0.13462)
		(layer "B.Cu")
		(net "USB2_FT4232_SDB_DP")
	)
	(segment
		(start 247.784366 -75.107292)
		(end 256.507996 -75.107292)
		(width 0.13462)
		(layer "B.Cu")
		(net "USB2_FT4232_SDB_DP")
	)
	(segment
		(start 375.78411 -220.989144)
		(end 375.700544 -221.07271)
		(width 0.13462)
		(layer "B.Cu")
		(net "USB2_FT4232_SDB_DP")
	)
	(segment
		(start 345.293188 -144.766538)
		(end 345.293188 -164.717476)
		(width 0.13462)
		(layer "B.Cu")
		(net "USB2_FT4232_SDB_DP")
	)
	(segment
		(start 233.284776 -85.729572)
		(end 233.284776 -85.992716)
		(width 0.13462)
		(layer "B.Cu")
		(net "USB2_FT4232_SDB_DP")
	)
	(segment
		(start 375.590308 -224.164398)
		(end 375.590308 -225.76028)
		(width 0.13462)
		(layer "B.Cu")
		(net "USB2_FT4232_SDB_DP")
	)
	(segment
		(start 375.590308 -225.76028)
		(end 379.324108 -229.49408)
		(width 0.13462)
		(layer "B.Cu")
		(net "USB2_FT4232_SDB_DP")
	)
	(segment
		(start 375.78411 -213.859364)
		(end 375.78411 -220.989144)
		(width 0.13462)
		(layer "B.Cu")
		(net "USB2_FT4232_SDB_DP")
	)
	(segment
		(start 335.55813 -135.03148)
		(end 345.293188 -144.766538)
		(width 0.13462)
		(layer "B.Cu")
		(net "USB2_FT4232_SDB_DP")
	)
	(segment
		(start 375.700544 -223.897952)
		(end 375.590308 -224.164398)
		(width 0.13462)
		(layer "B.Cu")
		(net "USB2_FT4232_SDB_DP")
	)
	(segment
		(start 363.97184 -169.126916)
		(end 370.162582 -175.317658)
		(width 0.13462)
		(layer "B.Cu")
		(net "USB2_FT4232_SDB_DP")
	)
	(segment
		(start 371.051328 -193.87439)
		(end 371.051328 -209.126582)
		(width 0.13462)
		(layer "B.Cu")
		(net "USB2_FT4232_SDB_DP")
	)
	(segment
		(start 291.33292 -132.412486)
		(end 296.753534 -137.8331)
		(width 0.13462)
		(layer "B.Cu")
		(net "USB2_FT4232_SDB_DP")
	)
	(segment
		(start 379.324108 -229.49408)
		(end 383.887218 -229.49408)
		(width 0.13462)
		(layer "B.Cu")
		(net "USB2_FT4232_SDB_DP")
	)
	(segment
		(start 371.051328 -209.126582)
		(end 375.78411 -213.859364)
		(width 0.13462)
		(layer "B.Cu")
		(net "USB2_FT4232_SDB_DP")
	)
	(segment
		(start 291.33292 -96.496632)
		(end 291.33292 -132.412486)
		(width 0.13462)
		(layer "B.Cu")
		(net "USB2_FT4232_SDB_DP")
	)
	(segment
		(start 375.700544 -221.07271)
		(end 375.700544 -223.897952)
		(width 0.13462)
		(layer "B.Cu")
		(net "USB2_FT4232_SDB_DP")
	)
	(segment
		(start 321.42684 -137.8331)
		(end 324.22846 -135.03148)
		(width 0.13462)
		(layer "B.Cu")
		(net "USB2_FT4232_SDB_DP")
	)
	(segment
		(start 243.00688 -79.884778)
		(end 247.784366 -75.107292)
		(width 0.13462)
		(layer "B.Cu")
		(net "USB2_FT4232_SDB_DP")
	)
	(segment
		(start 136.642856 -170.999912)
		(end 136.26592 -171.376848)
		(width 0.13462)
		(layer "F.Cu")
		(net "CLK_100M_DB2000QL_NIC1_DN")
	)
	(segment
		(start 135.364474 -173.272704)
		(end 135.364474 -174.793656)
		(width 0.13462)
		(layer "F.Cu")
		(net "CLK_100M_DB2000QL_NIC1_DN")
	)
	(segment
		(start 136.26592 -171.376848)
		(end 136.26592 -172.371258)
		(width 0.13462)
		(layer "F.Cu")
		(net "CLK_100M_DB2000QL_NIC1_DN")
	)
	(segment
		(start 136.26592 -172.371258)
		(end 135.364474 -173.272704)
		(width 0.13462)
		(layer "F.Cu")
		(net "CLK_100M_DB2000QL_NIC1_DN")
	)
	(segment
		(start 135.364474 -174.793656)
		(end 135.471154 -174.900336)
		(width 0.13462)
		(layer "F.Cu")
		(net "CLK_100M_DB2000QL_NIC1_DN")
	)
	(segment
		(start 168.38549 -16.439388)
		(end 168.38549 -15.370302)
		(width 0.13208)
		(layer "F.Cu")
		(net "SMB_ISO_SSD5_SCL")
	)
	(segment
		(start 166.124382 -18.437098)
		(end 166.16807 -18.437098)
		(width 0.13208)
		(layer "F.Cu")
		(net "SMB_ISO_SSD5_SCL")
	)
	(segment
		(start 166.72179 -18.990818)
		(end 166.16807 -18.437098)
		(width 0.13208)
		(layer "F.Cu")
		(net "SMB_ISO_SSD5_SCL")
	)
	(segment
		(start 168.55948 -23.355554)
		(end 168.55948 -23.965154)
		(width 0.13208)
		(layer "F.Cu")
		(net "SMB_ISO_SSD5_SCL")
	)
	(segment
		(start 167.902382 -18.990818)
		(end 166.72179 -18.990818)
		(width 0.13208)
		(layer "F.Cu")
		(net "SMB_ISO_SSD5_SCL")
	)
	(segment
		(start 168.38549 -16.439388)
		(end 168.38549 -18.50771)
		(width 0.13208)
		(layer "F.Cu")
		(net "SMB_ISO_SSD5_SCL")
	)
	(segment
		(start 168.38549 -18.50771)
		(end 167.902382 -18.990818)
		(width 0.13208)
		(layer "F.Cu")
		(net "SMB_ISO_SSD5_SCL")
	)
	(segment
		(start 165.35654 -17.419574)
		(end 165.35654 -17.669256)
		(width 0.13208)
		(layer "F.Cu")
		(net "SMB_ISO_SSD5_SCL")
	)
	(segment
		(start 165.35654 -17.669256)
		(end 166.124382 -18.437098)
		(width 0.13208)
		(layer "F.Cu")
		(net "SMB_ISO_SSD5_SCL")
	)
	(via
		(at 168.38549 -15.370302)
		(size 0.508)
		(drill 0.254)
		(layers "F.Cu" "B.Cu")
		(net "SMB_ISO_SSD5_SCL")
	)
	(via
		(at 168.55948 -23.965154)
		(size 0.508)
		(drill 0.254)
		(layers "F.Cu" "B.Cu")
		(net "SMB_ISO_SSD5_SCL")
	)
	(segment
		(start 168.38549 -15.370302)
		(end 169.863516 -16.848328)
		(width 0.13208)
		(layer "B.Cu")
		(net "SMB_ISO_SSD5_SCL")
	)
	(segment
		(start 169.863516 -16.848328)
		(end 169.863516 -22.661118)
		(width 0.13208)
		(layer "B.Cu")
		(net "SMB_ISO_SSD5_SCL")
	)
	(segment
		(start 169.863516 -22.661118)
		(end 168.55948 -23.965154)
		(width 0.13208)
		(layer "B.Cu")
		(net "SMB_ISO_SSD5_SCL")
	)
	(segment
		(start 123.975114 -251.5997)
		(end 123.721114 -251.3457)
		(width 0.13208)
		(layer "F.Cu")
		(net "SMB_BIC_I2C6_MUX_VR_R_SDA")
	)
	(segment
		(start 398.345406 -88.952324)
		(end 398.345406 -86.321646)
		(width 0.13208)
		(layer "F.Cu")
		(net "SMB_BIC_I2C6_MUX_VR_R_SDA")
	)
	(segment
		(start 128.647952 -248.598182)
		(end 128.702308 -248.652538)
		(width 0.13208)
		(layer "F.Cu")
		(net "SMB_BIC_I2C6_MUX_VR_R_SDA")
	)
	(segment
		(start 129.71653 -246.362982)
		(end 129.599182 -246.362982)
		(width 0.13208)
		(layer "F.Cu")
		(net "SMB_BIC_I2C6_MUX_VR_R_SDA")
	)
	(segment
		(start 123.721114 -250.578112)
		(end 132.423662 -241.875564)
		(width 0.13208)
		(layer "F.Cu")
		(net "SMB_BIC_I2C6_MUX_VR_R_SDA")
	)
	(segment
		(start 127.274828 -251.359924)
		(end 126.921006 -251.006102)
		(width 0.13208)
		(layer "F.Cu")
		(net "SMB_BIC_I2C6_MUX_VR_R_SDA")
	)
	(segment
		(start 394.644372 -85.496654)
		(end 395.212824 -84.928202)
		(width 0.13208)
		(layer "F.Cu")
		(net "SMB_BIC_I2C6_MUX_VR_R_SDA")
	)
	(segment
		(start 129.599182 -246.362982)
		(end 129.053336 -246.908828)
		(width 0.13208)
		(layer "F.Cu")
		(net "SMB_BIC_I2C6_MUX_VR_R_SDA")
	)
	(segment
		(start 396.088616 -85.690456)
		(end 395.809216 -85.411056)
		(width 0.13208)
		(layer "F.Cu")
		(net "SMB_BIC_I2C6_MUX_VR_R_SDA")
	)
	(segment
		(start 123.721114 -251.3457)
		(end 123.721114 -250.578112)
		(width 0.13208)
		(layer "F.Cu")
		(net "SMB_BIC_I2C6_MUX_VR_R_SDA")
	)
	(segment
		(start 407.660602 -174.70247)
		(end 407.660602 -115.850924)
		(width 0.13208)
		(layer "F.Cu")
		(net "SMB_BIC_I2C6_MUX_VR_R_SDA")
	)
	(segment
		(start 409.53055 -176.572418)
		(end 407.660602 -174.70247)
		(width 0.13208)
		(layer "F.Cu")
		(net "SMB_BIC_I2C6_MUX_VR_R_SDA")
	)
	(segment
		(start 419.055042 -178.121056)
		(end 417.506404 -176.572418)
		(width 0.13208)
		(layer "F.Cu")
		(net "SMB_BIC_I2C6_MUX_VR_R_SDA")
	)
	(segment
		(start 129.053336 -246.908828)
		(end 129.053336 -248.30151)
		(width 0.13208)
		(layer "F.Cu")
		(net "SMB_BIC_I2C6_MUX_VR_R_SDA")
	)
	(segment
		(start 395.212824 -84.928202)
		(end 395.809216 -84.928202)
		(width 0.13208)
		(layer "F.Cu")
		(net "SMB_BIC_I2C6_MUX_VR_R_SDA")
	)
	(segment
		(start 423.98188 -211.173568)
		(end 419.055042 -206.24673)
		(width 0.13208)
		(layer "F.Cu")
		(net "SMB_BIC_I2C6_MUX_VR_R_SDA")
	)
	(segment
		(start 123.975114 -252.016514)
		(end 123.975114 -251.5997)
		(width 0.13208)
		(layer "F.Cu")
		(net "SMB_BIC_I2C6_MUX_VR_R_SDA")
	)
	(segment
		(start 395.809216 -85.411056)
		(end 395.809216 -84.928202)
		(width 0.13208)
		(layer "F.Cu")
		(net "SMB_BIC_I2C6_MUX_VR_R_SDA")
	)
	(segment
		(start 419.466522 -249.30481)
		(end 419.2778 -249.116088)
		(width 0.13208)
		(layer "F.Cu")
		(net "SMB_BIC_I2C6_MUX_VR_R_SDA")
	)
	(segment
		(start 419.2778 -249.116088)
		(end 419.2778 -247.732804)
		(width 0.13208)
		(layer "F.Cu")
		(net "SMB_BIC_I2C6_MUX_VR_R_SDA")
	)
	(segment
		(start 404.323804 -112.514126)
		(end 404.323804 -94.930722)
		(width 0.13208)
		(layer "F.Cu")
		(net "SMB_BIC_I2C6_MUX_VR_R_SDA")
	)
	(segment
		(start 407.660602 -115.850924)
		(end 404.323804 -112.514126)
		(width 0.13208)
		(layer "F.Cu")
		(net "SMB_BIC_I2C6_MUX_VR_R_SDA")
	)
	(segment
		(start 419.2778 -247.732804)
		(end 423.98188 -243.028724)
		(width 0.13208)
		(layer "F.Cu")
		(net "SMB_BIC_I2C6_MUX_VR_R_SDA")
	)
	(segment
		(start 394.613638 -85.496654)
		(end 394.637768 -85.496654)
		(width 0.13208)
		(layer "F.Cu")
		(net "SMB_BIC_I2C6_MUX_VR_R_SDA")
	)
	(segment
		(start 394.637768 -85.496654)
		(end 394.644372 -85.496654)
		(width 0.13208)
		(layer "F.Cu")
		(net "SMB_BIC_I2C6_MUX_VR_R_SDA")
	)
	(segment
		(start 356.17531 -252.016514)
		(end 356.17531 -251.57811)
		(width 0.13208)
		(layer "F.Cu")
		(net "SMB_BIC_I2C6_MUX_VR_R_SDA")
	)
	(segment
		(start 397.714216 -85.690456)
		(end 396.088616 -85.690456)
		(width 0.13208)
		(layer "F.Cu")
		(net "SMB_BIC_I2C6_MUX_VR_R_SDA")
	)
	(segment
		(start 394.637768 -85.496654)
		(end 394.069316 -84.928202)
		(width 0.13208)
		(layer "F.Cu")
		(net "SMB_BIC_I2C6_MUX_VR_R_SDA")
	)
	(segment
		(start 398.345406 -86.321646)
		(end 397.714216 -85.690456)
		(width 0.13208)
		(layer "F.Cu")
		(net "SMB_BIC_I2C6_MUX_VR_R_SDA")
	)
	(segment
		(start 127.697484 -248.598182)
		(end 128.647952 -248.598182)
		(width 0.13208)
		(layer "F.Cu")
		(net "SMB_BIC_I2C6_MUX_VR_R_SDA")
	)
	(segment
		(start 419.055042 -206.24673)
		(end 419.055042 -178.121056)
		(width 0.13208)
		(layer "F.Cu")
		(net "SMB_BIC_I2C6_MUX_VR_R_SDA")
	)
	(segment
		(start 423.98188 -243.028724)
		(end 423.98188 -211.173568)
		(width 0.13208)
		(layer "F.Cu")
		(net "SMB_BIC_I2C6_MUX_VR_R_SDA")
	)
	(segment
		(start 356.17531 -251.57811)
		(end 355.92131 -251.32411)
		(width 0.13208)
		(layer "F.Cu")
		(net "SMB_BIC_I2C6_MUX_VR_R_SDA")
	)
	(segment
		(start 126.921006 -251.006102)
		(end 126.921006 -249.37466)
		(width 0.13208)
		(layer "F.Cu")
		(net "SMB_BIC_I2C6_MUX_VR_R_SDA")
	)
	(segment
		(start 126.921006 -249.37466)
		(end 127.697484 -248.598182)
		(width 0.13208)
		(layer "F.Cu")
		(net "SMB_BIC_I2C6_MUX_VR_R_SDA")
	)
	(segment
		(start 404.323804 -94.930722)
		(end 398.345406 -88.952324)
		(width 0.13208)
		(layer "F.Cu")
		(net "SMB_BIC_I2C6_MUX_VR_R_SDA")
	)
	(segment
		(start 417.506404 -176.572418)
		(end 409.53055 -176.572418)
		(width 0.13208)
		(layer "F.Cu")
		(net "SMB_BIC_I2C6_MUX_VR_R_SDA")
	)
	(segment
		(start 129.053336 -248.30151)
		(end 128.702308 -248.652538)
		(width 0.13208)
		(layer "F.Cu")
		(net "SMB_BIC_I2C6_MUX_VR_R_SDA")
	)
	(via
		(at 128.702308 -248.652538)
		(size 0.508)
		(drill 0.254)
		(layers "F.Cu" "B.Cu")
		(net "SMB_BIC_I2C6_MUX_VR_R_SDA")
	)
	(via
		(at 355.92131 -251.32411)
		(size 0.508)
		(drill 0.254)
		(layers "F.Cu" "B.Cu")
		(net "SMB_BIC_I2C6_MUX_VR_R_SDA")
	)
	(via
		(at 419.466522 -249.30481)
		(size 0.508)
		(drill 0.254)
		(layers "F.Cu" "B.Cu")
		(net "SMB_BIC_I2C6_MUX_VR_R_SDA")
	)
	(via
		(at 394.613638 -85.496654)
		(size 0.508)
		(drill 0.254)
		(layers "F.Cu" "B.Cu")
		(net "SMB_BIC_I2C6_MUX_VR_R_SDA")
	)
	(via
		(at 132.423662 -241.875564)
		(size 0.508)
		(drill 0.254)
		(layers "F.Cu" "B.Cu")
		(net "SMB_BIC_I2C6_MUX_VR_R_SDA")
	)
	(via
		(at 123.721114 -251.3457)
		(size 0.508)
		(drill 0.254)
		(layers "F.Cu" "B.Cu")
		(net "SMB_BIC_I2C6_MUX_VR_R_SDA")
	)
	(via
		(at 305.668426 -256.834894)
		(size 0.508)
		(drill 0.254)
		(layers "F.Cu" "B.Cu")
		(net "SMB_BIC_I2C6_MUX_VR_R_SDA")
	)
	(segment
		(start 312.843672 -253.765304)
		(end 312.979054 -253.900686)
		(width 0.13208)
		(layer "B.Cu")
		(net "SMB_BIC_I2C6_MUX_VR_R_SDA")
	)
	(segment
		(start 340.25713 -253.765304)
		(end 344.851736 -249.170698)
		(width 0.13208)
		(layer "B.Cu")
		(net "SMB_BIC_I2C6_MUX_VR_R_SDA")
	)
	(segment
		(start 313.903614 -254.093218)
		(end 314.038996 -254.2286)
		(width 0.13208)
		(layer "B.Cu")
		(net "SMB_BIC_I2C6_MUX_VR_R_SDA")
	)
	(segment
		(start 314.365894 -254.093218)
		(end 314.365894 -253.900686)
		(width 0.13208)
		(layer "B.Cu")
		(net "SMB_BIC_I2C6_MUX_VR_R_SDA")
	)
	(segment
		(start 354.213668 -249.170698)
		(end 354.988368 -249.945398)
		(width 0.13208)
		(layer "B.Cu")
		(net "SMB_BIC_I2C6_MUX_VR_R_SDA")
	)
	(segment
		(start 313.441334 -253.900686)
		(end 313.576716 -253.765304)
		(width 0.13208)
		(layer "B.Cu")
		(net "SMB_BIC_I2C6_MUX_VR_R_SDA")
	)
	(segment
		(start 312.1152 -253.765304)
		(end 312.843672 -253.765304)
		(width 0.13208)
		(layer "B.Cu")
		(net "SMB_BIC_I2C6_MUX_VR_R_SDA")
	)
	(segment
		(start 344.851736 -249.170698)
		(end 354.213668 -249.170698)
		(width 0.13208)
		(layer "B.Cu")
		(net "SMB_BIC_I2C6_MUX_VR_R_SDA")
	)
	(segment
		(start 313.903614 -253.900686)
		(end 313.903614 -254.093218)
		(width 0.13208)
		(layer "B.Cu")
		(net "SMB_BIC_I2C6_MUX_VR_R_SDA")
	)
	(segment
		(start 314.038996 -254.2286)
		(end 314.230512 -254.2286)
		(width 0.13208)
		(layer "B.Cu")
		(net "SMB_BIC_I2C6_MUX_VR_R_SDA")
	)
	(segment
		(start 308.698392 -253.804928)
		(end 312.075576 -253.804928)
		(width 0.13208)
		(layer "B.Cu")
		(net "SMB_BIC_I2C6_MUX_VR_R_SDA")
	)
	(segment
		(start 314.501276 -253.765304)
		(end 340.25713 -253.765304)
		(width 0.13208)
		(layer "B.Cu")
		(net "SMB_BIC_I2C6_MUX_VR_R_SDA")
	)
	(segment
		(start 313.305952 -254.2286)
		(end 313.441334 -254.093218)
		(width 0.13208)
		(layer "B.Cu")
		(net "SMB_BIC_I2C6_MUX_VR_R_SDA")
	)
	(segment
		(start 314.365894 -253.900686)
		(end 314.501276 -253.765304)
		(width 0.13208)
		(layer "B.Cu")
		(net "SMB_BIC_I2C6_MUX_VR_R_SDA")
	)
	(segment
		(start 313.114436 -254.2286)
		(end 313.305952 -254.2286)
		(width 0.13208)
		(layer "B.Cu")
		(net "SMB_BIC_I2C6_MUX_VR_R_SDA")
	)
	(segment
		(start 312.979054 -253.900686)
		(end 312.979054 -254.093218)
		(width 0.13208)
		(layer "B.Cu")
		(net "SMB_BIC_I2C6_MUX_VR_R_SDA")
	)
	(segment
		(start 355.92131 -250.326652)
		(end 355.540056 -249.945398)
		(width 0.13208)
		(layer "B.Cu")
		(net "SMB_BIC_I2C6_MUX_VR_R_SDA")
	)
	(segment
		(start 314.230512 -254.2286)
		(end 314.365894 -254.093218)
		(width 0.13208)
		(layer "B.Cu")
		(net "SMB_BIC_I2C6_MUX_VR_R_SDA")
	)
	(segment
		(start 355.540056 -249.945398)
		(end 354.988368 -249.945398)
		(width 0.13208)
		(layer "B.Cu")
		(net "SMB_BIC_I2C6_MUX_VR_R_SDA")
	)
	(segment
		(start 305.668426 -256.834894)
		(end 308.698392 -253.804928)
		(width 0.13208)
		(layer "B.Cu")
		(net "SMB_BIC_I2C6_MUX_VR_R_SDA")
	)
	(segment
		(start 312.075576 -253.804928)
		(end 312.1152 -253.765304)
		(width 0.13208)
		(layer "B.Cu")
		(net "SMB_BIC_I2C6_MUX_VR_R_SDA")
	)
	(segment
		(start 313.768232 -253.765304)
		(end 313.903614 -253.900686)
		(width 0.13208)
		(layer "B.Cu")
		(net "SMB_BIC_I2C6_MUX_VR_R_SDA")
	)
	(segment
		(start 355.92131 -251.32411)
		(end 355.92131 -250.326652)
		(width 0.13208)
		(layer "B.Cu")
		(net "SMB_BIC_I2C6_MUX_VR_R_SDA")
	)
	(segment
		(start 313.576716 -253.765304)
		(end 313.768232 -253.765304)
		(width 0.13208)
		(layer "B.Cu")
		(net "SMB_BIC_I2C6_MUX_VR_R_SDA")
	)
	(segment
		(start 313.441334 -254.093218)
		(end 313.441334 -253.900686)
		(width 0.13208)
		(layer "B.Cu")
		(net "SMB_BIC_I2C6_MUX_VR_R_SDA")
	)
	(segment
		(start 312.979054 -254.093218)
		(end 313.114436 -254.2286)
		(width 0.13208)
		(layer "B.Cu")
		(net "SMB_BIC_I2C6_MUX_VR_R_SDA")
	)
	(segment
		(start 233.688636 -249.589036)
		(end 234.713272 -250.613672)
		(width 0.15494)
		(layer "In13.Cu")
		(net "SMB_BIC_I2C6_MUX_VR_R_SDA")
	)
	(segment
		(start 254.390906 -251.7902)
		(end 271.779746 -251.7902)
		(width 0.15494)
		(layer "In13.Cu")
		(net "SMB_BIC_I2C6_MUX_VR_R_SDA")
	)
	(segment
		(start 231.08285 -249.589036)
		(end 233.688636 -249.589036)
		(width 0.15494)
		(layer "In13.Cu")
		(net "SMB_BIC_I2C6_MUX_VR_R_SDA")
	)
	(segment
		(start 272.488406 -252.49886)
		(end 297.5483 -252.49886)
		(width 0.15494)
		(layer "In13.Cu")
		(net "SMB_BIC_I2C6_MUX_VR_R_SDA")
	)
	(segment
		(start 253.214378 -250.613672)
		(end 254.390906 -251.7902)
		(width 0.15494)
		(layer "In13.Cu")
		(net "SMB_BIC_I2C6_MUX_VR_R_SDA")
	)
	(segment
		(start 214.298276 -248.91746)
		(end 215.765634 -247.450102)
		(width 0.15494)
		(layer "In13.Cu")
		(net "SMB_BIC_I2C6_MUX_VR_R_SDA")
	)
	(segment
		(start 215.765634 -247.450102)
		(end 228.943916 -247.450102)
		(width 0.15494)
		(layer "In13.Cu")
		(net "SMB_BIC_I2C6_MUX_VR_R_SDA")
	)
	(segment
		(start 301.33544 -256.286)
		(end 305.119532 -256.286)
		(width 0.15494)
		(layer "In13.Cu")
		(net "SMB_BIC_I2C6_MUX_VR_R_SDA")
	)
	(segment
		(start 132.423662 -241.875564)
		(end 133.024626 -241.2746)
		(width 0.15494)
		(layer "In13.Cu")
		(net "SMB_BIC_I2C6_MUX_VR_R_SDA")
	)
	(segment
		(start 209.705448 -248.91746)
		(end 214.298276 -248.91746)
		(width 0.15494)
		(layer "In13.Cu")
		(net "SMB_BIC_I2C6_MUX_VR_R_SDA")
	)
	(segment
		(start 150.367746 -241.2746)
		(end 152.425146 -243.332)
		(width 0.15494)
		(layer "In13.Cu")
		(net "SMB_BIC_I2C6_MUX_VR_R_SDA")
	)
	(segment
		(start 271.779746 -251.7902)
		(end 272.488406 -252.49886)
		(width 0.15494)
		(layer "In13.Cu")
		(net "SMB_BIC_I2C6_MUX_VR_R_SDA")
	)
	(segment
		(start 234.713272 -250.613672)
		(end 253.214378 -250.613672)
		(width 0.15494)
		(layer "In13.Cu")
		(net "SMB_BIC_I2C6_MUX_VR_R_SDA")
	)
	(segment
		(start 126.414276 -248.652538)
		(end 123.721114 -251.3457)
		(width 0.15494)
		(layer "In13.Cu")
		(net "SMB_BIC_I2C6_MUX_VR_R_SDA")
	)
	(segment
		(start 208.138522 -247.350534)
		(end 209.705448 -248.91746)
		(width 0.15494)
		(layer "In13.Cu")
		(net "SMB_BIC_I2C6_MUX_VR_R_SDA")
	)
	(segment
		(start 177.779934 -247.350534)
		(end 208.138522 -247.350534)
		(width 0.15494)
		(layer "In13.Cu")
		(net "SMB_BIC_I2C6_MUX_VR_R_SDA")
	)
	(segment
		(start 173.7614 -243.332)
		(end 177.779934 -247.350534)
		(width 0.15494)
		(layer "In13.Cu")
		(net "SMB_BIC_I2C6_MUX_VR_R_SDA")
	)
	(segment
		(start 128.702308 -248.652538)
		(end 126.414276 -248.652538)
		(width 0.15494)
		(layer "In13.Cu")
		(net "SMB_BIC_I2C6_MUX_VR_R_SDA")
	)
	(segment
		(start 305.119532 -256.286)
		(end 305.668426 -256.834894)
		(width 0.15494)
		(layer "In13.Cu")
		(net "SMB_BIC_I2C6_MUX_VR_R_SDA")
	)
	(segment
		(start 133.024626 -241.2746)
		(end 150.367746 -241.2746)
		(width 0.15494)
		(layer "In13.Cu")
		(net "SMB_BIC_I2C6_MUX_VR_R_SDA")
	)
	(segment
		(start 297.5483 -252.49886)
		(end 301.33544 -256.286)
		(width 0.15494)
		(layer "In13.Cu")
		(net "SMB_BIC_I2C6_MUX_VR_R_SDA")
	)
	(segment
		(start 228.943916 -247.450102)
		(end 231.08285 -249.589036)
		(width 0.15494)
		(layer "In13.Cu")
		(net "SMB_BIC_I2C6_MUX_VR_R_SDA")
	)
	(segment
		(start 152.425146 -243.332)
		(end 173.7614 -243.332)
		(width 0.15494)
		(layer "In13.Cu")
		(net "SMB_BIC_I2C6_MUX_VR_R_SDA")
	)
	(segment
		(start 359.909618 -249.530108)
		(end 357.715312 -249.530108)
		(width 0.15494)
		(layer "In15.Cu")
		(net "SMB_BIC_I2C6_MUX_VR_R_SDA")
	)
	(segment
		(start 360.360468 -249.980958)
		(end 359.909618 -249.530108)
		(width 0.15494)
		(layer "In15.Cu")
		(net "SMB_BIC_I2C6_MUX_VR_R_SDA")
	)
	(segment
		(start 418.632132 -248.47042)
		(end 390.07542 -248.47042)
		(width 0.15494)
		(layer "In15.Cu")
		(net "SMB_BIC_I2C6_MUX_VR_R_SDA")
	)
	(segment
		(start 357.715312 -249.530108)
		(end 355.92131 -251.32411)
		(width 0.15494)
		(layer "In15.Cu")
		(net "SMB_BIC_I2C6_MUX_VR_R_SDA")
	)
	(segment
		(start 419.466522 -249.30481)
		(end 418.632132 -248.47042)
		(width 0.15494)
		(layer "In15.Cu")
		(net "SMB_BIC_I2C6_MUX_VR_R_SDA")
	)
	(segment
		(start 388.564882 -249.980958)
		(end 360.360468 -249.980958)
		(width 0.15494)
		(layer "In15.Cu")
		(net "SMB_BIC_I2C6_MUX_VR_R_SDA")
	)
	(segment
		(start 390.07542 -248.47042)
		(end 388.564882 -249.980958)
		(width 0.15494)
		(layer "In15.Cu")
		(net "SMB_BIC_I2C6_MUX_VR_R_SDA")
	)
	(via
		(at 98.924364 -380.37008)
		(size 0.6604)
		(drill 0.3302)
		(layers "F.Cu" "B.Cu")
		(net "SMB_GPU_1_SCL")
	)
	(segment
		(start 100.432362 -380.45009)
		(end 100.352352 -380.37008)
		(width 0.13208)
		(layer "B.Cu")
		(net "SMB_GPU_1_SCL")
	)
	(segment
		(start 98.924364 -380.37008)
		(end 92.030042 -380.37008)
		(width 0.13208)
		(layer "B.Cu")
		(net "SMB_GPU_1_SCL")
	)
	(segment
		(start 100.352352 -380.37008)
		(end 98.924364 -380.37008)
		(width 0.13208)
		(layer "B.Cu")
		(net "SMB_GPU_1_SCL")
	)
	(segment
		(start 92.030042 -380.37008)
		(end 91.710002 -380.69012)
		(width 0.13208)
		(layer "B.Cu")
		(net "SMB_GPU_1_SCL")
	)
	(segment
		(start 320.096134 -387.942836)
		(end 320.774314 -387.942836)
		(width 0.13208)
		(layer "F.Cu")
		(net "GPU_FPGA_OVERT_R_N")
	)
	(via
		(at 320.774314 -387.942836)
		(size 0.508)
		(drill 0.254)
		(layers "F.Cu" "B.Cu")
		(net "GPU_FPGA_OVERT_R_N")
	)
	(segment
		(start 321.694302 -392.712448)
		(end 319.7606 -390.778746)
		(width 0.15494)
		(layer "In9.Cu")
		(net "GPU_FPGA_OVERT_R_N")
	)
	(segment
		(start 344.689938 -412.090108)
		(end 343.014046 -413.766)
		(width 0.15494)
		(layer "In9.Cu")
		(net "GPU_FPGA_OVERT_R_N")
	)
	(segment
		(start 328.298048 -411.153102)
		(end 328.298048 -394.592302)
		(width 0.15494)
		(layer "In9.Cu")
		(net "GPU_FPGA_OVERT_R_N")
	)
	(segment
		(start 326.418194 -392.712448)
		(end 321.694302 -392.712448)
		(width 0.15494)
		(layer "In9.Cu")
		(net "GPU_FPGA_OVERT_R_N")
	)
	(segment
		(start 330.910946 -413.766)
		(end 328.298048 -411.153102)
		(width 0.15494)
		(layer "In9.Cu")
		(net "GPU_FPGA_OVERT_R_N")
	)
	(segment
		(start 328.298048 -394.592302)
		(end 326.418194 -392.712448)
		(width 0.15494)
		(layer "In9.Cu")
		(net "GPU_FPGA_OVERT_R_N")
	)
	(segment
		(start 319.7606 -390.778746)
		(end 319.7606 -389.47979)
		(width 0.15494)
		(layer "In9.Cu")
		(net "GPU_FPGA_OVERT_R_N")
	)
	(segment
		(start 343.014046 -413.766)
		(end 330.910946 -413.766)
		(width 0.15494)
		(layer "In9.Cu")
		(net "GPU_FPGA_OVERT_R_N")
	)
	(segment
		(start 319.7606 -389.47979)
		(end 320.774314 -388.466076)
		(width 0.15494)
		(layer "In9.Cu")
		(net "GPU_FPGA_OVERT_R_N")
	)
	(segment
		(start 320.774314 -388.466076)
		(end 320.774314 -387.942836)
		(width 0.15494)
		(layer "In9.Cu")
		(net "GPU_FPGA_OVERT_R_N")
	)
	(segment
		(start 357.61295 -225.552)
		(end 356.997 -225.552)
		(width 0.13208)
		(layer "F.Cu")
		(net "RST_NIC3_PERST_N")
	)
	(segment
		(start 347.693742 -221.58706)
		(end 348.093538 -221.986856)
		(width 0.13208)
		(layer "F.Cu")
		(net "RST_NIC3_PERST_N")
	)
	(via
		(at 348.093538 -221.986856)
		(size 0.4572)
		(drill 0.254)
		(layers "F.Cu" "B.Cu")
		(net "RST_NIC3_PERST_N")
	)
	(via
		(at 356.997 -225.552)
		(size 0.508)
		(drill 0.254)
		(layers "F.Cu" "B.Cu")
		(net "RST_NIC3_PERST_N")
	)
	(segment
		(start 348.093538 -221.986856)
		(end 348.493842 -222.38716)
		(width 0.0889)
		(layer "In7.Cu")
		(net "RST_NIC3_PERST_N")
	)
	(segment
		(start 352.707448 -222.38716)
		(end 355.872288 -225.552)
		(width 0.15494)
		(layer "In7.Cu")
		(net "RST_NIC3_PERST_N")
	)
	(segment
		(start 348.493842 -222.38716)
		(end 351.60204 -222.38716)
		(width 0.0889)
		(layer "In7.Cu")
		(net "RST_NIC3_PERST_N")
	)
	(segment
		(start 355.872288 -225.552)
		(end 356.997 -225.552)
		(width 0.15494)
		(layer "In7.Cu")
		(net "RST_NIC3_PERST_N")
	)
	(segment
		(start 351.60204 -222.38716)
		(end 352.707448 -222.38716)
		(width 0.15494)
		(layer "In7.Cu")
		(net "RST_NIC3_PERST_N")
	)
	(segment
		(start 234.021122 -89.52738)
		(end 234.021122 -89.854024)
		(width 0.13462)
		(layer "F.Cu")
		(net "USB2_FT4232_SDB_R_DP")
	)
	(segment
		(start 233.901742 -88.512142)
		(end 233.901742 -89.408)
		(width 0.13462)
		(layer "F.Cu")
		(net "USB2_FT4232_SDB_R_DP")
	)
	(segment
		(start 233.871008 -82.918808)
		(end 233.557572 -82.918808)
		(width 0.13462)
		(layer "F.Cu")
		(net "USB2_FT4232_SDB_R_DP")
	)
	(segment
		(start 233.901742 -89.408)
		(end 234.021122 -89.52738)
		(width 0.13462)
		(layer "F.Cu")
		(net "USB2_FT4232_SDB_R_DP")
	)
	(segment
		(start 233.249724 -87.860124)
		(end 233.901742 -88.512142)
		(width 0.13462)
		(layer "F.Cu")
		(net "USB2_FT4232_SDB_R_DP")
	)
	(segment
		(start 233.557572 -82.918808)
		(end 233.142028 -82.503264)
		(width 0.13462)
		(layer "F.Cu")
		(net "USB2_FT4232_SDB_R_DP")
	)
	(segment
		(start 233.515916 -87.4141)
		(end 233.249724 -87.680292)
		(width 0.13462)
		(layer "F.Cu")
		(net "USB2_FT4232_SDB_R_DP")
	)
	(segment
		(start 233.249724 -87.680292)
		(end 233.249724 -87.860124)
		(width 0.13462)
		(layer "F.Cu")
		(net "USB2_FT4232_SDB_R_DP")
	)
	(segment
		(start 235.849414 -82.77225)
		(end 236.63656 -82.77225)
		(width 0.1651)
		(layer "In15.Cu")
		(net "USB2_FT4232_SDB_R_DP")
	)
	(segment
		(start 233.411014 -82.77225)
		(end 233.906314 -82.77225)
		(width 0.1651)
		(layer "In15.Cu")
		(net "USB2_FT4232_SDB_R_DP")
	)
	(segment
		(start 229.8827 -82.7913)
		(end 229.8827 -83.2866)
		(width 0.1651)
		(layer "In15.Cu")
		(net "USB2_FT4232_SDB_R_DP")
	)
	(segment
		(start 232.2195 -86.44636)
		(end 232.3338 -86.56066)
		(width 0.1651)
		(layer "In15.Cu")
		(net "USB2_FT4232_SDB_R_DP")
	)
	(segment
		(start 234.817158 -80.8355)
		(end 234.702858 -80.9498)
		(width 0.1651)
		(layer "In15.Cu")
		(net "USB2_FT4232_SDB_R_DP")
	)
	(segment
		(start 233.221276 -86.866222)
		(end 233.221276 -87.11946)
		(width 0.1651)
		(layer "In15.Cu")
		(net "USB2_FT4232_SDB_R_DP")
	)
	(segment
		(start 231.654858 -80.8355)
		(end 231.159558 -80.8355)
		(width 0.1651)
		(layer "In15.Cu")
		(net "USB2_FT4232_SDB_R_DP")
	)
	(segment
		(start 229.8827 -85.725)
		(end 229.7684 -85.8393)
		(width 0.1651)
		(layer "In15.Cu")
		(net "USB2_FT4232_SDB_R_DP")
	)
	(segment
		(start 234.515914 -82.65795)
		(end 234.630214 -82.77225)
		(width 0.1651)
		(layer "In15.Cu")
		(net "USB2_FT4232_SDB_R_DP")
	)
	(segment
		(start 229.7684 -82.1817)
		(end 229.7684 -82.677)
		(width 0.1651)
		(layer "In15.Cu")
		(net "USB2_FT4232_SDB_R_DP")
	)
	(segment
		(start 232.264458 -80.9498)
		(end 231.769158 -80.9498)
		(width 0.1651)
		(layer "In15.Cu")
		(net "USB2_FT4232_SDB_R_DP")
	)
	(segment
		(start 230.3907 -86.56066)
		(end 230.505 -86.44636)
		(width 0.1651)
		(layer "In15.Cu")
		(net "USB2_FT4232_SDB_R_DP")
	)
	(segment
		(start 232.988358 -80.9498)
		(end 232.874058 -80.8355)
		(width 0.1651)
		(layer "In15.Cu")
		(net "USB2_FT4232_SDB_R_DP")
	)
	(segment
		(start 234.207558 -80.9498)
		(end 234.093258 -80.8355)
		(width 0.1651)
		(layer "In15.Cu")
		(net "USB2_FT4232_SDB_R_DP")
	)
	(segment
		(start 233.906314 -82.77225)
		(end 234.020614 -82.65795)
		(width 0.1651)
		(layer "In15.Cu")
		(net "USB2_FT4232_SDB_R_DP")
	)
	(segment
		(start 231.159558 -80.8355)
		(end 231.045258 -80.9498)
		(width 0.1651)
		(layer "In15.Cu")
		(net "USB2_FT4232_SDB_R_DP")
	)
	(segment
		(start 231.769158 -80.9498)
		(end 231.654858 -80.8355)
		(width 0.1651)
		(layer "In15.Cu")
		(net "USB2_FT4232_SDB_R_DP")
	)
	(segment
		(start 235.239814 -82.65795)
		(end 235.735114 -82.65795)
		(width 0.1651)
		(layer "In15.Cu")
		(net "USB2_FT4232_SDB_R_DP")
	)
	(segment
		(start 229.7684 -81.4578)
		(end 229.8827 -81.5721)
		(width 0.1651)
		(layer "In15.Cu")
		(net "USB2_FT4232_SDB_R_DP")
	)
	(segment
		(start 229.8954 -86.56066)
		(end 230.3907 -86.56066)
		(width 0.1651)
		(layer "In15.Cu")
		(net "USB2_FT4232_SDB_R_DP")
	)
	(segment
		(start 235.426758 -80.9498)
		(end 235.312458 -80.8355)
		(width 0.1651)
		(layer "In15.Cu")
		(net "USB2_FT4232_SDB_R_DP")
	)
	(segment
		(start 236.77626 -82.105754)
		(end 236.77626 -81.610454)
		(width 0.1651)
		(layer "In15.Cu")
		(net "USB2_FT4232_SDB_R_DP")
	)
	(segment
		(start 229.7684 -83.4009)
		(end 229.7684 -83.8962)
		(width 0.1651)
		(layer "In15.Cu")
		(net "USB2_FT4232_SDB_R_DP")
	)
	(segment
		(start 236.63656 -82.77225)
		(end 236.89056 -82.51825)
		(width 0.1651)
		(layer "In15.Cu")
		(net "USB2_FT4232_SDB_R_DP")
	)
	(segment
		(start 229.7684 -85.8393)
		(end 229.7684 -86.43366)
		(width 0.1651)
		(layer "In15.Cu")
		(net "USB2_FT4232_SDB_R_DP")
	)
	(segment
		(start 229.7684 -84.6201)
		(end 229.7684 -85.1154)
		(width 0.1651)
		(layer "In15.Cu")
		(net "USB2_FT4232_SDB_R_DP")
	)
	(segment
		(start 236.89056 -81.496154)
		(end 236.89056 -81.000854)
		(width 0.1651)
		(layer "In15.Cu")
		(net "USB2_FT4232_SDB_R_DP")
	)
	(segment
		(start 232.3338 -86.56066)
		(end 232.915714 -86.56066)
		(width 0.1651)
		(layer "In15.Cu")
		(net "USB2_FT4232_SDB_R_DP")
	)
	(segment
		(start 236.725206 -80.8355)
		(end 236.036358 -80.8355)
		(width 0.1651)
		(layer "In15.Cu")
		(net "USB2_FT4232_SDB_R_DP")
	)
	(segment
		(start 229.8954 -80.8355)
		(end 229.7684 -80.9625)
		(width 0.1651)
		(layer "In15.Cu")
		(net "USB2_FT4232_SDB_R_DP")
	)
	(segment
		(start 229.7684 -86.43366)
		(end 229.8954 -86.56066)
		(width 0.1651)
		(layer "In15.Cu")
		(net "USB2_FT4232_SDB_R_DP")
	)
	(segment
		(start 229.8827 -84.0105)
		(end 229.8827 -84.5058)
		(width 0.1651)
		(layer "In15.Cu")
		(net "USB2_FT4232_SDB_R_DP")
	)
	(segment
		(start 232.915714 -86.56066)
		(end 233.221276 -86.866222)
		(width 0.1651)
		(layer "In15.Cu")
		(net "USB2_FT4232_SDB_R_DP")
	)
	(segment
		(start 236.89056 -82.220054)
		(end 236.77626 -82.105754)
		(width 0.1651)
		(layer "In15.Cu")
		(net "USB2_FT4232_SDB_R_DP")
	)
	(segment
		(start 233.142028 -82.503264)
		(end 233.411014 -82.77225)
		(width 0.1651)
		(layer "In15.Cu")
		(net "USB2_FT4232_SDB_R_DP")
	)
	(segment
		(start 235.125514 -82.77225)
		(end 235.239814 -82.65795)
		(width 0.1651)
		(layer "In15.Cu")
		(net "USB2_FT4232_SDB_R_DP")
	)
	(segment
		(start 229.7684 -82.677)
		(end 229.8827 -82.7913)
		(width 0.1651)
		(layer "In15.Cu")
		(net "USB2_FT4232_SDB_R_DP")
	)
	(segment
		(start 230.505 -86.44636)
		(end 231.0003 -86.44636)
		(width 0.1651)
		(layer "In15.Cu")
		(net "USB2_FT4232_SDB_R_DP")
	)
	(segment
		(start 234.630214 -82.77225)
		(end 235.125514 -82.77225)
		(width 0.1651)
		(layer "In15.Cu")
		(net "USB2_FT4232_SDB_R_DP")
	)
	(segment
		(start 231.7242 -86.44636)
		(end 232.2195 -86.44636)
		(width 0.1651)
		(layer "In15.Cu")
		(net "USB2_FT4232_SDB_R_DP")
	)
	(segment
		(start 232.874058 -80.8355)
		(end 232.378758 -80.8355)
		(width 0.1651)
		(layer "In15.Cu")
		(net "USB2_FT4232_SDB_R_DP")
	)
	(segment
		(start 236.77626 -81.610454)
		(end 236.89056 -81.496154)
		(width 0.1651)
		(layer "In15.Cu")
		(net "USB2_FT4232_SDB_R_DP")
	)
	(segment
		(start 233.221276 -87.11946)
		(end 233.515916 -87.4141)
		(width 0.1651)
		(layer "In15.Cu")
		(net "USB2_FT4232_SDB_R_DP")
	)
	(segment
		(start 235.922058 -80.9498)
		(end 235.426758 -80.9498)
		(width 0.1651)
		(layer "In15.Cu")
		(net "USB2_FT4232_SDB_R_DP")
	)
	(segment
		(start 229.7684 -83.8962)
		(end 229.8827 -84.0105)
		(width 0.1651)
		(layer "In15.Cu")
		(net "USB2_FT4232_SDB_R_DP")
	)
	(segment
		(start 229.8827 -83.2866)
		(end 229.7684 -83.4009)
		(width 0.1651)
		(layer "In15.Cu")
		(net "USB2_FT4232_SDB_R_DP")
	)
	(segment
		(start 234.093258 -80.8355)
		(end 233.597958 -80.8355)
		(width 0.1651)
		(layer "In15.Cu")
		(net "USB2_FT4232_SDB_R_DP")
	)
	(segment
		(start 234.702858 -80.9498)
		(end 234.207558 -80.9498)
		(width 0.1651)
		(layer "In15.Cu")
		(net "USB2_FT4232_SDB_R_DP")
	)
	(segment
		(start 231.1146 -86.56066)
		(end 231.6099 -86.56066)
		(width 0.1651)
		(layer "In15.Cu")
		(net "USB2_FT4232_SDB_R_DP")
	)
	(segment
		(start 236.89056 -81.000854)
		(end 236.725206 -80.8355)
		(width 0.1651)
		(layer "In15.Cu")
		(net "USB2_FT4232_SDB_R_DP")
	)
	(segment
		(start 233.597958 -80.8355)
		(end 233.483658 -80.9498)
		(width 0.1651)
		(layer "In15.Cu")
		(net "USB2_FT4232_SDB_R_DP")
	)
	(segment
		(start 229.8827 -84.5058)
		(end 229.7684 -84.6201)
		(width 0.1651)
		(layer "In15.Cu")
		(net "USB2_FT4232_SDB_R_DP")
	)
	(segment
		(start 229.8827 -82.0674)
		(end 229.7684 -82.1817)
		(width 0.1651)
		(layer "In15.Cu")
		(net "USB2_FT4232_SDB_R_DP")
	)
	(segment
		(start 232.378758 -80.8355)
		(end 232.264458 -80.9498)
		(width 0.1651)
		(layer "In15.Cu")
		(net "USB2_FT4232_SDB_R_DP")
	)
	(segment
		(start 229.8827 -81.5721)
		(end 229.8827 -82.0674)
		(width 0.1651)
		(layer "In15.Cu")
		(net "USB2_FT4232_SDB_R_DP")
	)
	(segment
		(start 235.312458 -80.8355)
		(end 234.817158 -80.8355)
		(width 0.1651)
		(layer "In15.Cu")
		(net "USB2_FT4232_SDB_R_DP")
	)
	(segment
		(start 229.7684 -85.1154)
		(end 229.8827 -85.2297)
		(width 0.1651)
		(layer "In15.Cu")
		(net "USB2_FT4232_SDB_R_DP")
	)
	(segment
		(start 230.435658 -80.8355)
		(end 229.8954 -80.8355)
		(width 0.1651)
		(layer "In15.Cu")
		(net "USB2_FT4232_SDB_R_DP")
	)
	(segment
		(start 229.7684 -80.9625)
		(end 229.7684 -81.4578)
		(width 0.1651)
		(layer "In15.Cu")
		(net "USB2_FT4232_SDB_R_DP")
	)
	(segment
		(start 231.0003 -86.44636)
		(end 231.1146 -86.56066)
		(width 0.1651)
		(layer "In15.Cu")
		(net "USB2_FT4232_SDB_R_DP")
	)
	(segment
		(start 233.483658 -80.9498)
		(end 232.988358 -80.9498)
		(width 0.1651)
		(layer "In15.Cu")
		(net "USB2_FT4232_SDB_R_DP")
	)
	(segment
		(start 231.6099 -86.56066)
		(end 231.7242 -86.44636)
		(width 0.1651)
		(layer "In15.Cu")
		(net "USB2_FT4232_SDB_R_DP")
	)
	(segment
		(start 230.549958 -80.9498)
		(end 230.435658 -80.8355)
		(width 0.1651)
		(layer "In15.Cu")
		(net "USB2_FT4232_SDB_R_DP")
	)
	(segment
		(start 231.045258 -80.9498)
		(end 230.549958 -80.9498)
		(width 0.1651)
		(layer "In15.Cu")
		(net "USB2_FT4232_SDB_R_DP")
	)
	(segment
		(start 229.8827 -85.2297)
		(end 229.8827 -85.725)
		(width 0.1651)
		(layer "In15.Cu")
		(net "USB2_FT4232_SDB_R_DP")
	)
	(segment
		(start 235.735114 -82.65795)
		(end 235.849414 -82.77225)
		(width 0.1651)
		(layer "In15.Cu")
		(net "USB2_FT4232_SDB_R_DP")
	)
	(segment
		(start 234.020614 -82.65795)
		(end 234.515914 -82.65795)
		(width 0.1651)
		(layer "In15.Cu")
		(net "USB2_FT4232_SDB_R_DP")
	)
	(segment
		(start 236.036358 -80.8355)
		(end 235.922058 -80.9498)
		(width 0.1651)
		(layer "In15.Cu")
		(net "USB2_FT4232_SDB_R_DP")
	)
	(segment
		(start 236.89056 -82.51825)
		(end 236.89056 -82.220054)
		(width 0.1651)
		(layer "In15.Cu")
		(net "USB2_FT4232_SDB_R_DP")
	)
	(segment
		(start 388.24027 -84.186522)
		(end 388.932674 -84.186522)
		(width 0.13208)
		(layer "F.Cu")
		(net "SMB_BIC_I2C6_MUX_CLK_SCL")
	)
	(segment
		(start 391.870438 -83.785202)
		(end 393.269216 -83.785202)
		(width 0.13208)
		(layer "F.Cu")
		(net "SMB_BIC_I2C6_MUX_CLK_SCL")
	)
	(segment
		(start 391.583418 -84.072222)
		(end 391.870438 -83.785202)
		(width 0.13208)
		(layer "F.Cu")
		(net "SMB_BIC_I2C6_MUX_CLK_SCL")
	)
	(segment
		(start 389.046974 -84.072222)
		(end 391.583418 -84.072222)
		(width 0.13208)
		(layer "F.Cu")
		(net "SMB_BIC_I2C6_MUX_CLK_SCL")
	)
	(segment
		(start 388.932674 -84.186522)
		(end 389.046974 -84.072222)
		(width 0.13208)
		(layer "F.Cu")
		(net "SMB_BIC_I2C6_MUX_CLK_SCL")
	)
	(via
		(at 391.870438 -83.785202)
		(size 0.508)
		(drill 0.254)
		(layers "F.Cu" "B.Cu")
		(net "SMB_BIC_I2C6_MUX_CLK_SCL")
	)
	(segment
		(start 47.83709 -406.177242)
		(end 48.406812 -406.177242)
		(width 0.1651)
		(layer "In11.Cu")
		(net "P2E_GPU_FPGA_PEX_RX_DN<0>")
	)
	(segment
		(start 49.450752 -405.133302)
		(end 51.04511 -397.11884)
		(width 0.1651)
		(layer "In11.Cu")
		(net "P2E_GPU_FPGA_PEX_RX_DN<0>")
	)
	(segment
		(start 87.243158 -393.94003)
		(end 87.356696 -393.824968)
		(width 0.1651)
		(layer "In11.Cu")
		(net "P2E_GPU_FPGA_PEX_RX_DN<0>")
	)
	(segment
		(start 90.449146 -394.704062)
		(end 90.449146 -405.3332)
		(width 0.1651)
		(layer "In11.Cu")
		(net "P2E_GPU_FPGA_PEX_RX_DN<0>")
	)
	(segment
		(start 88.586564 -393.817856)
		(end 89.84107 -394.106908)
		(width 0.1651)
		(layer "In11.Cu")
		(net "P2E_GPU_FPGA_PEX_RX_DN<0>")
	)
	(segment
		(start 54.91988 -394.01369)
		(end 86.632542 -393.829286)
		(width 0.1651)
		(layer "In11.Cu")
		(net "P2E_GPU_FPGA_PEX_RX_DN<0>")
	)
	(segment
		(start 91.293188 -406.177242)
		(end 91.583002 -406.177242)
		(width 0.1651)
		(layer "In11.Cu")
		(net "P2E_GPU_FPGA_PEX_RX_DN<0>")
	)
	(segment
		(start 51.04511 -397.11884)
		(end 52.264056 -394.173456)
		(width 0.1651)
		(layer "In11.Cu")
		(net "P2E_GPU_FPGA_PEX_RX_DN<0>")
	)
	(segment
		(start 90.449146 -405.3332)
		(end 91.293188 -406.177242)
		(width 0.1651)
		(layer "In11.Cu")
		(net "P2E_GPU_FPGA_PEX_RX_DN<0>")
	)
	(segment
		(start 90.436954 -394.702792)
		(end 90.437462 -394.703046)
		(width 0.1651)
		(layer "In11.Cu")
		(net "P2E_GPU_FPGA_PEX_RX_DN<0>")
	)
	(segment
		(start 52.264056 -394.173456)
		(end 52.503324 -394.01369)
		(width 0.1651)
		(layer "In11.Cu")
		(net "P2E_GPU_FPGA_PEX_RX_DN<0>")
	)
	(segment
		(start 87.356696 -393.824968)
		(end 88.586564 -393.817856)
		(width 0.1651)
		(layer "In11.Cu")
		(net "P2E_GPU_FPGA_PEX_RX_DN<0>")
	)
	(segment
		(start 86.632542 -393.829286)
		(end 86.747604 -393.943078)
		(width 0.1651)
		(layer "In11.Cu")
		(net "P2E_GPU_FPGA_PEX_RX_DN<0>")
	)
	(segment
		(start 90.437462 -394.703046)
		(end 90.445844 -394.702792)
		(width 0.1651)
		(layer "In11.Cu")
		(net "P2E_GPU_FPGA_PEX_RX_DN<0>")
	)
	(segment
		(start 90.447876 -394.702792)
		(end 90.449146 -394.704062)
		(width 0.1651)
		(layer "In11.Cu")
		(net "P2E_GPU_FPGA_PEX_RX_DN<0>")
	)
	(segment
		(start 91.583002 -406.177242)
		(end 91.710002 -406.304242)
		(width 0.1651)
		(layer "In11.Cu")
		(net "P2E_GPU_FPGA_PEX_RX_DN<0>")
	)
	(segment
		(start 52.503324 -394.01369)
		(end 54.91988 -394.01369)
		(width 0.1651)
		(layer "In11.Cu")
		(net "P2E_GPU_FPGA_PEX_RX_DN<0>")
	)
	(segment
		(start 91.710002 -406.304242)
		(end 91.710002 -406.690068)
		(width 0.1651)
		(layer "In11.Cu")
		(net "P2E_GPU_FPGA_PEX_RX_DN<0>")
	)
	(segment
		(start 89.84107 -394.106908)
		(end 90.436954 -394.702792)
		(width 0.1651)
		(layer "In11.Cu")
		(net "P2E_GPU_FPGA_PEX_RX_DN<0>")
	)
	(segment
		(start 47.71009 -406.304242)
		(end 47.83709 -406.177242)
		(width 0.1651)
		(layer "In11.Cu")
		(net "P2E_GPU_FPGA_PEX_RX_DN<0>")
	)
	(segment
		(start 86.747604 -393.943078)
		(end 87.243158 -393.94003)
		(width 0.1651)
		(layer "In11.Cu")
		(net "P2E_GPU_FPGA_PEX_RX_DN<0>")
	)
	(segment
		(start 90.445844 -394.702792)
		(end 90.447876 -394.702792)
		(width 0.1651)
		(layer "In11.Cu")
		(net "P2E_GPU_FPGA_PEX_RX_DN<0>")
	)
	(segment
		(start 48.406812 -406.177242)
		(end 49.450752 -405.133302)
		(width 0.1651)
		(layer "In11.Cu")
		(net "P2E_GPU_FPGA_PEX_RX_DN<0>")
	)
	(segment
		(start 47.71009 -406.690068)
		(end 47.71009 -406.304242)
		(width 0.1651)
		(layer "In11.Cu")
		(net "P2E_GPU_FPGA_PEX_RX_DN<0>")
	)
	(segment
		(start 217.386408 -121.742962)
		(end 219.425266 -121.742962)
		(width 0.13208)
		(layer "F.Cu")
		(net "PWRGD_P3V3_NIC3_R")
	)
	(segment
		(start 216.583768 -120.940322)
		(end 217.386408 -121.742962)
		(width 0.13208)
		(layer "F.Cu")
		(net "PWRGD_P3V3_NIC3_R")
	)
	(segment
		(start 216.583768 -119.720868)
		(end 216.583768 -120.940322)
		(width 0.13208)
		(layer "F.Cu")
		(net "PWRGD_P3V3_NIC3_R")
	)
	(segment
		(start 216.085928 -119.223028)
		(end 216.583768 -119.720868)
		(width 0.13208)
		(layer "F.Cu")
		(net "PWRGD_P3V3_NIC3_R")
	)
	(segment
		(start 346.893896 -222.38716)
		(end 347.293692 -222.786956)
		(width 0.13208)
		(layer "F.Cu")
		(net "PWRGD_P3V3_NIC3_R")
	)
	(segment
		(start 216.085928 -119.223028)
		(end 215.475566 -119.223028)
		(width 0.13208)
		(layer "F.Cu")
		(net "PWRGD_P3V3_NIC3_R")
	)
	(via
		(at 216.085928 -119.223028)
		(size 0.508)
		(drill 0.254)
		(layers "F.Cu" "B.Cu")
		(net "PWRGD_P3V3_NIC3_R")
	)
	(via
		(at 209.394298 -184.466484)
		(size 0.508)
		(drill 0.254)
		(layers "F.Cu" "B.Cu")
		(net "PWRGD_P3V3_NIC3_R")
	)
	(via
		(at 347.293692 -222.786956)
		(size 0.4572)
		(drill 0.254)
		(layers "F.Cu" "B.Cu")
		(net "PWRGD_P3V3_NIC3_R")
	)
	(segment
		(start 216.626186 -119.763286)
		(end 216.085928 -119.223028)
		(width 0.15494)
		(layer "In5.Cu")
		(net "PWRGD_P3V3_NIC3_R")
	)
	(segment
		(start 210.2358 -179.961032)
		(end 210.2358 -176.437544)
		(width 0.15494)
		(layer "In5.Cu")
		(net "PWRGD_P3V3_NIC3_R")
	)
	(segment
		(start 210.312 -169.773346)
		(end 210.312 -138.445748)
		(width 0.15494)
		(layer "In5.Cu")
		(net "PWRGD_P3V3_NIC3_R")
	)
	(segment
		(start 211.4296 -170.890946)
		(end 210.312 -169.773346)
		(width 0.15494)
		(layer "In5.Cu")
		(net "PWRGD_P3V3_NIC3_R")
	)
	(segment
		(start 209.8548 -180.342032)
		(end 210.2358 -179.961032)
		(width 0.15494)
		(layer "In5.Cu")
		(net "PWRGD_P3V3_NIC3_R")
	)
	(segment
		(start 211.4296 -175.243744)
		(end 211.4296 -170.890946)
		(width 0.15494)
		(layer "In5.Cu")
		(net "PWRGD_P3V3_NIC3_R")
	)
	(segment
		(start 216.626186 -132.131562)
		(end 216.626186 -119.763286)
		(width 0.15494)
		(layer "In5.Cu")
		(net "PWRGD_P3V3_NIC3_R")
	)
	(segment
		(start 210.2358 -176.437544)
		(end 211.4296 -175.243744)
		(width 0.15494)
		(layer "In5.Cu")
		(net "PWRGD_P3V3_NIC3_R")
	)
	(segment
		(start 209.8548 -182.342536)
		(end 209.8548 -180.342032)
		(width 0.15494)
		(layer "In5.Cu")
		(net "PWRGD_P3V3_NIC3_R")
	)
	(segment
		(start 210.312 -138.445748)
		(end 216.626186 -132.131562)
		(width 0.15494)
		(layer "In5.Cu")
		(net "PWRGD_P3V3_NIC3_R")
	)
	(segment
		(start 209.394298 -182.803038)
		(end 209.8548 -182.342536)
		(width 0.15494)
		(layer "In5.Cu")
		(net "PWRGD_P3V3_NIC3_R")
	)
	(segment
		(start 209.394298 -184.466484)
		(end 209.394298 -182.803038)
		(width 0.15494)
		(layer "In5.Cu")
		(net "PWRGD_P3V3_NIC3_R")
	)
	(segment
		(start 251.402342 -190.585598)
		(end 241.3762 -190.585598)
		(width 0.15494)
		(layer "In15.Cu")
		(net "PWRGD_P3V3_NIC3_R")
	)
	(segment
		(start 314.100464 -189.032388)
		(end 273.94789 -189.032388)
		(width 0.15494)
		(layer "In15.Cu")
		(net "PWRGD_P3V3_NIC3_R")
	)
	(segment
		(start 224.28327 -185.954416)
		(end 223.470216 -185.141362)
		(width 0.15494)
		(layer "In15.Cu")
		(net "PWRGD_P3V3_NIC3_R")
	)
	(segment
		(start 353.489006 -218.990164)
		(end 354.866448 -217.612722)
		(width 0.15494)
		(layer "In15.Cu")
		(net "PWRGD_P3V3_NIC3_R")
	)
	(segment
		(start 330.538328 -193.085466)
		(end 326.114156 -188.661294)
		(width 0.15494)
		(layer "In15.Cu")
		(net "PWRGD_P3V3_NIC3_R")
	)
	(segment
		(start 223.470216 -185.141362)
		(end 210.069176 -185.141362)
		(width 0.15494)
		(layer "In15.Cu")
		(net "PWRGD_P3V3_NIC3_R")
	)
	(segment
		(start 254.254508 -187.733432)
		(end 251.402342 -190.585598)
		(width 0.15494)
		(layer "In15.Cu")
		(net "PWRGD_P3V3_NIC3_R")
	)
	(segment
		(start 347.286072 -200.811638)
		(end 343.20226 -196.727826)
		(width 0.15494)
		(layer "In15.Cu")
		(net "PWRGD_P3V3_NIC3_R")
	)
	(segment
		(start 351.875344 -219.528898)
		(end 352.057462 -219.34678)
		(width 0.15494)
		(layer "In15.Cu")
		(net "PWRGD_P3V3_NIC3_R")
	)
	(segment
		(start 352.582734 -218.990164)
		(end 353.489006 -218.990164)
		(width 0.15494)
		(layer "In15.Cu")
		(net "PWRGD_P3V3_NIC3_R")
	)
	(segment
		(start 339.843618 -193.085466)
		(end 330.538328 -193.085466)
		(width 0.15494)
		(layer "In15.Cu")
		(net "PWRGD_P3V3_NIC3_R")
	)
	(segment
		(start 355.71049 -206.532734)
		(end 355.71049 -204.434694)
		(width 0.15494)
		(layer "In15.Cu")
		(net "PWRGD_P3V3_NIC3_R")
	)
	(segment
		(start 352.087434 -200.811638)
		(end 347.286072 -200.811638)
		(width 0.15494)
		(layer "In15.Cu")
		(net "PWRGD_P3V3_NIC3_R")
	)
	(segment
		(start 273.94789 -189.032388)
		(end 272.648934 -187.733432)
		(width 0.15494)
		(layer "In15.Cu")
		(net "PWRGD_P3V3_NIC3_R")
	)
	(segment
		(start 346.896182 -220.222064)
		(end 346.896182 -220.20784)
		(width 0.15494)
		(layer "In15.Cu")
		(net "PWRGD_P3V3_NIC3_R")
	)
	(segment
		(start 347.575124 -219.528898)
		(end 351.875344 -219.528898)
		(width 0.15494)
		(layer "In15.Cu")
		(net "PWRGD_P3V3_NIC3_R")
	)
	(segment
		(start 355.41458 -210.717892)
		(end 355.133656 -210.436968)
		(width 0.15494)
		(layer "In15.Cu")
		(net "PWRGD_P3V3_NIC3_R")
	)
	(segment
		(start 346.896182 -220.20784)
		(end 347.575124 -219.528898)
		(width 0.15494)
		(layer "In15.Cu")
		(net "PWRGD_P3V3_NIC3_R")
	)
	(segment
		(start 355.133656 -210.436968)
		(end 355.133656 -207.109568)
		(width 0.15494)
		(layer "In15.Cu")
		(net "PWRGD_P3V3_NIC3_R")
	)
	(segment
		(start 346.896182 -222.389446)
		(end 346.896182 -220.222064)
		(width 0.0889)
		(layer "In15.Cu")
		(net "PWRGD_P3V3_NIC3_R")
	)
	(segment
		(start 210.069176 -185.141362)
		(end 209.394298 -184.466484)
		(width 0.15494)
		(layer "In15.Cu")
		(net "PWRGD_P3V3_NIC3_R")
	)
	(segment
		(start 314.471558 -188.661294)
		(end 314.100464 -189.032388)
		(width 0.15494)
		(layer "In15.Cu")
		(net "PWRGD_P3V3_NIC3_R")
	)
	(segment
		(start 354.866448 -213.214712)
		(end 355.41458 -212.66658)
		(width 0.15494)
		(layer "In15.Cu")
		(net "PWRGD_P3V3_NIC3_R")
	)
	(segment
		(start 343.20226 -196.727826)
		(end 343.20226 -196.444108)
		(width 0.15494)
		(layer "In15.Cu")
		(net "PWRGD_P3V3_NIC3_R")
	)
	(segment
		(start 355.133656 -207.109568)
		(end 355.71049 -206.532734)
		(width 0.15494)
		(layer "In15.Cu")
		(net "PWRGD_P3V3_NIC3_R")
	)
	(segment
		(start 347.293692 -222.786956)
		(end 346.896182 -222.389446)
		(width 0.0889)
		(layer "In15.Cu")
		(net "PWRGD_P3V3_NIC3_R")
	)
	(segment
		(start 343.20226 -196.444108)
		(end 339.843618 -193.085466)
		(width 0.15494)
		(layer "In15.Cu")
		(net "PWRGD_P3V3_NIC3_R")
	)
	(segment
		(start 272.648934 -187.733432)
		(end 254.254508 -187.733432)
		(width 0.15494)
		(layer "In15.Cu")
		(net "PWRGD_P3V3_NIC3_R")
	)
	(segment
		(start 241.3762 -190.585598)
		(end 236.745018 -185.954416)
		(width 0.15494)
		(layer "In15.Cu")
		(net "PWRGD_P3V3_NIC3_R")
	)
	(segment
		(start 236.745018 -185.954416)
		(end 224.28327 -185.954416)
		(width 0.15494)
		(layer "In15.Cu")
		(net "PWRGD_P3V3_NIC3_R")
	)
	(segment
		(start 352.057462 -219.34678)
		(end 352.226118 -219.34678)
		(width 0.15494)
		(layer "In15.Cu")
		(net "PWRGD_P3V3_NIC3_R")
	)
	(segment
		(start 355.41458 -212.66658)
		(end 355.41458 -210.717892)
		(width 0.15494)
		(layer "In15.Cu")
		(net "PWRGD_P3V3_NIC3_R")
	)
	(segment
		(start 354.866448 -217.612722)
		(end 354.866448 -213.214712)
		(width 0.15494)
		(layer "In15.Cu")
		(net "PWRGD_P3V3_NIC3_R")
	)
	(segment
		(start 355.71049 -204.434694)
		(end 352.087434 -200.811638)
		(width 0.15494)
		(layer "In15.Cu")
		(net "PWRGD_P3V3_NIC3_R")
	)
	(segment
		(start 326.114156 -188.661294)
		(end 314.471558 -188.661294)
		(width 0.15494)
		(layer "In15.Cu")
		(net "PWRGD_P3V3_NIC3_R")
	)
	(segment
		(start 352.226118 -219.34678)
		(end 352.582734 -218.990164)
		(width 0.15494)
		(layer "In15.Cu")
		(net "PWRGD_P3V3_NIC3_R")
	)
	(segment
		(start 138.806682 -199.864726)
		(end 138.909806 -199.761602)
		(width 0.13462)
		(layer "F.Cu")
		(net "USB2_FT4232_CLI_DN")
	)
	(segment
		(start 138.806682 -200.489058)
		(end 138.806682 -199.864726)
		(width 0.13462)
		(layer "F.Cu")
		(net "USB2_FT4232_CLI_DN")
	)
	(segment
		(start 238.86668 -87.691722)
		(end 238.86668 -86.664038)
		(width 0.13462)
		(layer "F.Cu")
		(net "USB2_FT4232_CLI_DN")
	)
	(segment
		(start 138.909806 -199.761602)
		(end 138.909806 -198.811134)
		(width 0.13462)
		(layer "F.Cu")
		(net "USB2_FT4232_CLI_DN")
	)
	(segment
		(start 138.909806 -198.811134)
		(end 138.625072 -198.5264)
		(width 0.13462)
		(layer "F.Cu")
		(net "USB2_FT4232_CLI_DN")
	)
	(segment
		(start 238.5822 -87.976202)
		(end 238.86668 -87.691722)
		(width 0.13462)
		(layer "F.Cu")
		(net "USB2_FT4232_CLI_DN")
	)
	(segment
		(start 238.324898 -86.122256)
		(end 238.324898 -85.551518)
		(width 0.13462)
		(layer "F.Cu")
		(net "USB2_FT4232_CLI_DN")
	)
	(segment
		(start 238.86668 -86.664038)
		(end 238.324898 -86.122256)
		(width 0.13462)
		(layer "F.Cu")
		(net "USB2_FT4232_CLI_DN")
	)
	(segment
		(start 207.645762 -89.40546)
		(end 202.249024 -91.64066)
		(width 0.1651)
		(layer "In9.Cu")
		(net "USB2_FT4232_CLI_DN")
	)
	(segment
		(start 238.66856 -88.94826)
		(end 236.73816 -88.94826)
		(width 0.1651)
		(layer "In9.Cu")
		(net "USB2_FT4232_CLI_DN")
	)
	(segment
		(start 238.87303 -88.267032)
		(end 238.87303 -88.74379)
		(width 0.1651)
		(layer "In9.Cu")
		(net "USB2_FT4232_CLI_DN")
	)
	(segment
		(start 121.61266 -141.18844)
		(end 121.61266 -161.40684)
		(width 0.1651)
		(layer "In9.Cu")
		(net "USB2_FT4232_CLI_DN")
	)
	(segment
		(start 129.77876 -108.04906)
		(end 121.63806 -116.18976)
		(width 0.1651)
		(layer "In9.Cu")
		(net "USB2_FT4232_CLI_DN")
	)
	(segment
		(start 140.30706 -191.55664)
		(end 141.22146 -192.47104)
		(width 0.1651)
		(layer "In9.Cu")
		(net "USB2_FT4232_CLI_DN")
	)
	(segment
		(start 141.22146 -192.47104)
		(end 141.22146 -195.28536)
		(width 0.1651)
		(layer "In9.Cu")
		(net "USB2_FT4232_CLI_DN")
	)
	(segment
		(start 121.20626 -140.78204)
		(end 121.61266 -141.18844)
		(width 0.1651)
		(layer "In9.Cu")
		(net "USB2_FT4232_CLI_DN")
	)
	(segment
		(start 136.644634 -165.00094)
		(end 137.75563 -165.743128)
		(width 0.1651)
		(layer "In9.Cu")
		(net "USB2_FT4232_CLI_DN")
	)
	(segment
		(start 224.49536 -86.86546)
		(end 222.36176 -88.99906)
		(width 0.1651)
		(layer "In9.Cu")
		(net "USB2_FT4232_CLI_DN")
	)
	(segment
		(start 235.79836 -89.88806)
		(end 233.21264 -89.88806)
		(width 0.1651)
		(layer "In9.Cu")
		(net "USB2_FT4232_CLI_DN")
	)
	(segment
		(start 138.915902 -198.23557)
		(end 138.625072 -198.5264)
		(width 0.1651)
		(layer "In9.Cu")
		(net "USB2_FT4232_CLI_DN")
	)
	(segment
		(start 138.915902 -197.590918)
		(end 138.915902 -198.23557)
		(width 0.1651)
		(layer "In9.Cu")
		(net "USB2_FT4232_CLI_DN")
	)
	(segment
		(start 222.36176 -88.99906)
		(end 211.92236 -88.99906)
		(width 0.1651)
		(layer "In9.Cu")
		(net "USB2_FT4232_CLI_DN")
	)
	(segment
		(start 140.30706 -171.902882)
		(end 140.30706 -191.55664)
		(width 0.1651)
		(layer "In9.Cu")
		(net "USB2_FT4232_CLI_DN")
	)
	(segment
		(start 238.5822 -87.976202)
		(end 238.87303 -88.267032)
		(width 0.1651)
		(layer "In9.Cu")
		(net "USB2_FT4232_CLI_DN")
	)
	(segment
		(start 121.20626 -132.47116)
		(end 121.20626 -140.78204)
		(width 0.1651)
		(layer "In9.Cu")
		(net "USB2_FT4232_CLI_DN")
	)
	(segment
		(start 137.75563 -165.743128)
		(end 140.30706 -171.902882)
		(width 0.1651)
		(layer "In9.Cu")
		(net "USB2_FT4232_CLI_DN")
	)
	(segment
		(start 121.63806 -116.18976)
		(end 121.63806 -132.03936)
		(width 0.1651)
		(layer "In9.Cu")
		(net "USB2_FT4232_CLI_DN")
	)
	(segment
		(start 141.22146 -195.28536)
		(end 138.915902 -197.590918)
		(width 0.1651)
		(layer "In9.Cu")
		(net "USB2_FT4232_CLI_DN")
	)
	(segment
		(start 233.21264 -89.88806)
		(end 230.19004 -86.86546)
		(width 0.1651)
		(layer "In9.Cu")
		(net "USB2_FT4232_CLI_DN")
	)
	(segment
		(start 134.42696 -108.04906)
		(end 129.77876 -108.04906)
		(width 0.1651)
		(layer "In9.Cu")
		(net "USB2_FT4232_CLI_DN")
	)
	(segment
		(start 121.61266 -161.40684)
		(end 125.20676 -165.00094)
		(width 0.1651)
		(layer "In9.Cu")
		(net "USB2_FT4232_CLI_DN")
	)
	(segment
		(start 236.73816 -88.94826)
		(end 235.79836 -89.88806)
		(width 0.1651)
		(layer "In9.Cu")
		(net "USB2_FT4232_CLI_DN")
	)
	(segment
		(start 211.92236 -88.99906)
		(end 211.51596 -89.40546)
		(width 0.1651)
		(layer "In9.Cu")
		(net "USB2_FT4232_CLI_DN")
	)
	(segment
		(start 238.87303 -88.74379)
		(end 238.66856 -88.94826)
		(width 0.1651)
		(layer "In9.Cu")
		(net "USB2_FT4232_CLI_DN")
	)
	(segment
		(start 125.20676 -165.00094)
		(end 136.644634 -165.00094)
		(width 0.1651)
		(layer "In9.Cu")
		(net "USB2_FT4232_CLI_DN")
	)
	(segment
		(start 121.63806 -132.03936)
		(end 121.20626 -132.47116)
		(width 0.1651)
		(layer "In9.Cu")
		(net "USB2_FT4232_CLI_DN")
	)
	(segment
		(start 230.19004 -86.86546)
		(end 224.49536 -86.86546)
		(width 0.1651)
		(layer "In9.Cu")
		(net "USB2_FT4232_CLI_DN")
	)
	(segment
		(start 211.51596 -89.40546)
		(end 207.645762 -89.40546)
		(width 0.1651)
		(layer "In9.Cu")
		(net "USB2_FT4232_CLI_DN")
	)
	(segment
		(start 150.83536 -91.64066)
		(end 134.42696 -108.04906)
		(width 0.1651)
		(layer "In9.Cu")
		(net "USB2_FT4232_CLI_DN")
	)
	(segment
		(start 202.249024 -91.64066)
		(end 150.83536 -91.64066)
		(width 0.1651)
		(layer "In9.Cu")
		(net "USB2_FT4232_CLI_DN")
	)
	(segment
		(start 135.9916 -172.257466)
		(end 135.9916 -171.364656)
		(width 0.13462)
		(layer "F.Cu")
		(net "CLK_100M_DB2000QL_NIC1_DP")
	)
	(segment
		(start 135.090154 -173.158912)
		(end 135.9916 -172.257466)
		(width 0.13462)
		(layer "F.Cu")
		(net "CLK_100M_DB2000QL_NIC1_DP")
	)
	(segment
		(start 134.971028 -174.900336)
		(end 135.090154 -174.78121)
		(width 0.13462)
		(layer "F.Cu")
		(net "CLK_100M_DB2000QL_NIC1_DP")
	)
	(segment
		(start 135.9916 -171.364656)
		(end 135.626856 -170.999912)
		(width 0.13462)
		(layer "F.Cu")
		(net "CLK_100M_DB2000QL_NIC1_DP")
	)
	(segment
		(start 135.090154 -174.78121)
		(end 135.090154 -173.158912)
		(width 0.13462)
		(layer "F.Cu")
		(net "CLK_100M_DB2000QL_NIC1_DP")
	)
	(segment
		(start 389.46455 -83.430872)
		(end 391.211562 -83.430872)
		(width 0.13208)
		(layer "F.Cu")
		(net "SMB_BIC_I2C6_MUX_CLK_SDA")
	)
	(segment
		(start 388.24027 -83.536536)
		(end 389.358886 -83.536536)
		(width 0.13208)
		(layer "F.Cu")
		(net "SMB_BIC_I2C6_MUX_CLK_SDA")
	)
	(segment
		(start 391.211562 -83.430872)
		(end 392.000232 -82.642202)
		(width 0.13208)
		(layer "F.Cu")
		(net "SMB_BIC_I2C6_MUX_CLK_SDA")
	)
	(segment
		(start 389.358886 -83.536536)
		(end 389.46455 -83.430872)
		(width 0.13208)
		(layer "F.Cu")
		(net "SMB_BIC_I2C6_MUX_CLK_SDA")
	)
	(segment
		(start 392.591544 -82.642202)
		(end 393.269216 -82.642202)
		(width 0.13208)
		(layer "F.Cu")
		(net "SMB_BIC_I2C6_MUX_CLK_SDA")
	)
	(segment
		(start 392.000232 -82.642202)
		(end 392.591544 -82.642202)
		(width 0.13208)
		(layer "F.Cu")
		(net "SMB_BIC_I2C6_MUX_CLK_SDA")
	)
	(via
		(at 392.591544 -82.642202)
		(size 0.508)
		(drill 0.254)
		(layers "F.Cu" "B.Cu")
		(net "SMB_BIC_I2C6_MUX_CLK_SDA")
	)
	(segment
		(start 320.096134 -388.958836)
		(end 321.902582 -388.958836)
		(width 0.13208)
		(layer "F.Cu")
		(net "GPU_3V3IO_RSVD5_FFU_R")
	)
	(via
		(at 321.902582 -388.958836)
		(size 0.508)
		(drill 0.254)
		(layers "F.Cu" "B.Cu")
		(net "GPU_3V3IO_RSVD5_FFU_R")
	)
	(segment
		(start 320.2178 -389.531098)
		(end 320.2178 -390.7028)
		(width 0.15494)
		(layer "In9.Cu")
		(net "GPU_3V3IO_RSVD5_FFU_R")
	)
	(segment
		(start 339.04428 -413.335978)
		(end 340.29015 -412.090108)
		(width 0.15494)
		(layer "In9.Cu")
		(net "GPU_3V3IO_RSVD5_FFU_R")
	)
	(segment
		(start 321.902582 -388.958836)
		(end 320.790062 -388.958836)
		(width 0.15494)
		(layer "In9.Cu")
		(net "GPU_3V3IO_RSVD5_FFU_R")
	)
	(segment
		(start 326.595232 -392.17092)
		(end 328.737468 -394.313156)
		(width 0.15494)
		(layer "In9.Cu")
		(net "GPU_3V3IO_RSVD5_FFU_R")
	)
	(segment
		(start 320.2178 -390.7028)
		(end 321.68592 -392.17092)
		(width 0.15494)
		(layer "In9.Cu")
		(net "GPU_3V3IO_RSVD5_FFU_R")
	)
	(segment
		(start 331.146658 -413.335978)
		(end 339.04428 -413.335978)
		(width 0.15494)
		(layer "In9.Cu")
		(net "GPU_3V3IO_RSVD5_FFU_R")
	)
	(segment
		(start 328.737468 -394.313156)
		(end 328.737468 -410.926788)
		(width 0.15494)
		(layer "In9.Cu")
		(net "GPU_3V3IO_RSVD5_FFU_R")
	)
	(segment
		(start 328.737468 -410.926788)
		(end 331.146658 -413.335978)
		(width 0.15494)
		(layer "In9.Cu")
		(net "GPU_3V3IO_RSVD5_FFU_R")
	)
	(segment
		(start 321.68592 -392.17092)
		(end 326.595232 -392.17092)
		(width 0.15494)
		(layer "In9.Cu")
		(net "GPU_3V3IO_RSVD5_FFU_R")
	)
	(segment
		(start 320.790062 -388.958836)
		(end 320.2178 -389.531098)
		(width 0.15494)
		(layer "In9.Cu")
		(net "GPU_3V3IO_RSVD5_FFU_R")
	)
	(segment
		(start 279.459182 -402.738082)
		(end 279.729946 -402.738082)
		(width 0.13208)
		(layer "F.Cu")
		(net "RST_MB_BIC_ISO_R_N")
	)
	(segment
		(start 279.8572 -402.19122)
		(end 280.110438 -401.937982)
		(width 0.13208)
		(layer "F.Cu")
		(net "RST_MB_BIC_ISO_R_N")
	)
	(segment
		(start 279.459182 -402.738082)
		(end 279.459182 -403.352)
		(width 0.13208)
		(layer "F.Cu")
		(net "RST_MB_BIC_ISO_R_N")
	)
	(segment
		(start 279.8572 -402.610828)
		(end 279.8572 -402.19122)
		(width 0.13208)
		(layer "F.Cu")
		(net "RST_MB_BIC_ISO_R_N")
	)
	(segment
		(start 279.729946 -402.738082)
		(end 279.8572 -402.610828)
		(width 0.13208)
		(layer "F.Cu")
		(net "RST_MB_BIC_ISO_R_N")
	)
	(segment
		(start 218.398852 -175.94834)
		(end 217.334084 -175.94834)
		(width 0.13208)
		(layer "F.Cu")
		(net "RST_MB_BIC_ISO_R_N")
	)
	(segment
		(start 346.093796 -216.786968)
		(end 346.493592 -216.387172)
		(width 0.13208)
		(layer "F.Cu")
		(net "RST_MB_BIC_ISO_R_N")
	)
	(segment
		(start 280.110438 -401.937982)
		(end 280.475182 -401.937982)
		(width 0.13208)
		(layer "F.Cu")
		(net "RST_MB_BIC_ISO_R_N")
	)
	(via
		(at 279.459182 -403.352)
		(size 0.508)
		(drill 0.254)
		(layers "F.Cu" "B.Cu")
		(net "RST_MB_BIC_ISO_R_N")
	)
	(via
		(at 222.032068 -190.224156)
		(size 0.508)
		(drill 0.254)
		(layers "F.Cu" "B.Cu")
		(net "RST_MB_BIC_ISO_R_N")
	)
	(via
		(at 248.466356 -208.590896)
		(size 0.508)
		(drill 0.254)
		(layers "F.Cu" "B.Cu")
		(net "RST_MB_BIC_ISO_R_N")
	)
	(via
		(at 217.303096 -228.22027)
		(size 0.508)
		(drill 0.254)
		(layers "F.Cu" "B.Cu")
		(net "RST_MB_BIC_ISO_R_N")
	)
	(via
		(at 240.857786 -329.17511)
		(size 0.508)
		(drill 0.254)
		(layers "F.Cu" "B.Cu")
		(net "RST_MB_BIC_ISO_R_N")
	)
	(via
		(at 217.334084 -175.94834)
		(size 0.508)
		(drill 0.254)
		(layers "F.Cu" "B.Cu")
		(net "RST_MB_BIC_ISO_R_N")
	)
	(via
		(at 346.493592 -216.387172)
		(size 0.4572)
		(drill 0.254)
		(layers "F.Cu" "B.Cu")
		(net "RST_MB_BIC_ISO_R_N")
	)
	(via
		(at 268.1478 -213.5886)
		(size 0.508)
		(drill 0.254)
		(layers "F.Cu" "B.Cu")
		(net "RST_MB_BIC_ISO_R_N")
	)
	(via
		(at 220.98889 -203.462128)
		(size 0.508)
		(drill 0.254)
		(layers "F.Cu" "B.Cu")
		(net "RST_MB_BIC_ISO_R_N")
	)
	(segment
		(start 210.924648 -209.676238)
		(end 207.78724 -212.813646)
		(width 0.13208)
		(layer "B.Cu")
		(net "RST_MB_BIC_ISO_R_N")
	)
	(segment
		(start 211.572856 -209.676238)
		(end 210.924648 -209.676238)
		(width 0.13208)
		(layer "B.Cu")
		(net "RST_MB_BIC_ISO_R_N")
	)
	(segment
		(start 205.424786 -215.832182)
		(end 205.424786 -226.791774)
		(width 0.13208)
		(layer "B.Cu")
		(net "RST_MB_BIC_ISO_R_N")
	)
	(segment
		(start 207.78724 -212.813646)
		(end 207.78724 -213.469728)
		(width 0.13208)
		(layer "B.Cu")
		(net "RST_MB_BIC_ISO_R_N")
	)
	(segment
		(start 208.529682 -229.14737)
		(end 210.056984 -229.14737)
		(width 0.13208)
		(layer "B.Cu")
		(net "RST_MB_BIC_ISO_R_N")
	)
	(segment
		(start 218.008962 -208.617312)
		(end 214.993474 -208.617312)
		(width 0.13208)
		(layer "B.Cu")
		(net "RST_MB_BIC_ISO_R_N")
	)
	(segment
		(start 210.417156 -228.787198)
		(end 216.736168 -228.787198)
		(width 0.13208)
		(layer "B.Cu")
		(net "RST_MB_BIC_ISO_R_N")
	)
	(segment
		(start 208.15681 -228.774498)
		(end 208.529682 -229.14737)
		(width 0.13208)
		(layer "B.Cu")
		(net "RST_MB_BIC_ISO_R_N")
	)
	(segment
		(start 220.98889 -203.462128)
		(end 220.98889 -205.637384)
		(width 0.13208)
		(layer "B.Cu")
		(net "RST_MB_BIC_ISO_R_N")
	)
	(segment
		(start 207.40751 -228.774498)
		(end 208.15681 -228.774498)
		(width 0.13208)
		(layer "B.Cu")
		(net "RST_MB_BIC_ISO_R_N")
	)
	(segment
		(start 216.736168 -228.787198)
		(end 217.303096 -228.22027)
		(width 0.13208)
		(layer "B.Cu")
		(net "RST_MB_BIC_ISO_R_N")
	)
	(segment
		(start 214.993474 -208.617312)
		(end 214.745316 -208.86547)
		(width 0.13208)
		(layer "B.Cu")
		(net "RST_MB_BIC_ISO_R_N")
	)
	(segment
		(start 205.424786 -226.791774)
		(end 207.40751 -228.774498)
		(width 0.13208)
		(layer "B.Cu")
		(net "RST_MB_BIC_ISO_R_N")
	)
	(segment
		(start 210.056984 -229.14737)
		(end 210.417156 -228.787198)
		(width 0.13208)
		(layer "B.Cu")
		(net "RST_MB_BIC_ISO_R_N")
	)
	(segment
		(start 207.78724 -213.469728)
		(end 205.424786 -215.832182)
		(width 0.13208)
		(layer "B.Cu")
		(net "RST_MB_BIC_ISO_R_N")
	)
	(segment
		(start 212.383624 -208.86547)
		(end 211.572856 -209.676238)
		(width 0.13208)
		(layer "B.Cu")
		(net "RST_MB_BIC_ISO_R_N")
	)
	(segment
		(start 214.745316 -208.86547)
		(end 212.383624 -208.86547)
		(width 0.13208)
		(layer "B.Cu")
		(net "RST_MB_BIC_ISO_R_N")
	)
	(segment
		(start 220.98889 -205.637384)
		(end 218.008962 -208.617312)
		(width 0.13208)
		(layer "B.Cu")
		(net "RST_MB_BIC_ISO_R_N")
	)
	(segment
		(start 248.971054 -206.3496)
		(end 248.040398 -206.3496)
		(width 0.15494)
		(layer "In5.Cu")
		(net "RST_MB_BIC_ISO_R_N")
	)
	(segment
		(start 241.215672 -210.616546)
		(end 241.215672 -208.220818)
		(width 0.15494)
		(layer "In5.Cu")
		(net "RST_MB_BIC_ISO_R_N")
	)
	(segment
		(start 249.258074 -208.145888)
		(end 249.366278 -208.037684)
		(width 0.15494)
		(layer "In5.Cu")
		(net "RST_MB_BIC_ISO_R_N")
	)
	(segment
		(start 221.234 -189.379606)
		(end 222.032068 -190.177674)
		(width 0.15494)
		(layer "In5.Cu")
		(net "RST_MB_BIC_ISO_R_N")
	)
	(segment
		(start 221.234 -187.749942)
		(end 221.234 -189.379606)
		(width 0.15494)
		(layer "In5.Cu")
		(net "RST_MB_BIC_ISO_R_N")
	)
	(segment
		(start 248.040398 -206.3496)
		(end 244.64645 -209.743548)
		(width 0.15494)
		(layer "In5.Cu")
		(net "RST_MB_BIC_ISO_R_N")
	)
	(segment
		(start 224.028 -192.151)
		(end 223.8502 -192.3288)
		(width 0.15494)
		(layer "In5.Cu")
		(net "RST_MB_BIC_ISO_R_N")
	)
	(segment
		(start 223.8502 -192.3288)
		(end 223.0882 -192.3288)
		(width 0.15494)
		(layer "In5.Cu")
		(net "RST_MB_BIC_ISO_R_N")
	)
	(segment
		(start 244.64645 -209.743548)
		(end 244.64645 -210.725004)
		(width 0.15494)
		(layer "In5.Cu")
		(net "RST_MB_BIC_ISO_R_N")
	)
	(segment
		(start 244.119654 -211.2518)
		(end 241.850926 -211.2518)
		(width 0.15494)
		(layer "In5.Cu")
		(net "RST_MB_BIC_ISO_R_N")
	)
	(segment
		(start 232.83799 -201.87539)
		(end 226.260914 -195.298314)
		(width 0.15494)
		(layer "In5.Cu")
		(net "RST_MB_BIC_ISO_R_N")
	)
	(segment
		(start 248.466356 -208.590896)
		(end 248.466356 -208.590388)
		(width 0.15494)
		(layer "In5.Cu")
		(net "RST_MB_BIC_ISO_R_N")
	)
	(segment
		(start 249.366278 -208.037684)
		(end 249.366278 -206.744824)
		(width 0.15494)
		(layer "In5.Cu")
		(net "RST_MB_BIC_ISO_R_N")
	)
	(segment
		(start 249.366278 -206.744824)
		(end 248.971054 -206.3496)
		(width 0.15494)
		(layer "In5.Cu")
		(net "RST_MB_BIC_ISO_R_N")
	)
	(segment
		(start 248.910856 -208.145888)
		(end 249.258074 -208.145888)
		(width 0.15494)
		(layer "In5.Cu")
		(net "RST_MB_BIC_ISO_R_N")
	)
	(segment
		(start 226.260914 -192.3542)
		(end 226.057714 -192.151)
		(width 0.15494)
		(layer "In5.Cu")
		(net "RST_MB_BIC_ISO_R_N")
	)
	(segment
		(start 241.850926 -211.2518)
		(end 241.215672 -210.616546)
		(width 0.15494)
		(layer "In5.Cu")
		(net "RST_MB_BIC_ISO_R_N")
	)
	(segment
		(start 217.334084 -183.850026)
		(end 221.234 -187.749942)
		(width 0.15494)
		(layer "In5.Cu")
		(net "RST_MB_BIC_ISO_R_N")
	)
	(segment
		(start 239.29467 -206.299816)
		(end 237.541816 -206.299816)
		(width 0.15494)
		(layer "In5.Cu")
		(net "RST_MB_BIC_ISO_R_N")
	)
	(segment
		(start 234.615736 -201.87539)
		(end 232.83799 -201.87539)
		(width 0.15494)
		(layer "In5.Cu")
		(net "RST_MB_BIC_ISO_R_N")
	)
	(segment
		(start 241.215672 -208.220818)
		(end 239.29467 -206.299816)
		(width 0.15494)
		(layer "In5.Cu")
		(net "RST_MB_BIC_ISO_R_N")
	)
	(segment
		(start 248.466356 -208.590388)
		(end 248.910856 -208.145888)
		(width 0.15494)
		(layer "In5.Cu")
		(net "RST_MB_BIC_ISO_R_N")
	)
	(segment
		(start 235.204508 -202.464162)
		(end 234.615736 -201.87539)
		(width 0.15494)
		(layer "In5.Cu")
		(net "RST_MB_BIC_ISO_R_N")
	)
	(segment
		(start 226.260914 -195.298314)
		(end 226.260914 -192.3542)
		(width 0.15494)
		(layer "In5.Cu")
		(net "RST_MB_BIC_ISO_R_N")
	)
	(segment
		(start 222.639382 -191.879982)
		(end 222.639382 -190.83147)
		(width 0.15494)
		(layer "In5.Cu")
		(net "RST_MB_BIC_ISO_R_N")
	)
	(segment
		(start 222.639382 -190.83147)
		(end 222.032068 -190.224156)
		(width 0.15494)
		(layer "In5.Cu")
		(net "RST_MB_BIC_ISO_R_N")
	)
	(segment
		(start 217.334084 -175.94834)
		(end 217.334084 -183.850026)
		(width 0.15494)
		(layer "In5.Cu")
		(net "RST_MB_BIC_ISO_R_N")
	)
	(segment
		(start 237.541816 -206.299816)
		(end 235.204508 -203.962508)
		(width 0.15494)
		(layer "In5.Cu")
		(net "RST_MB_BIC_ISO_R_N")
	)
	(segment
		(start 226.057714 -192.151)
		(end 224.028 -192.151)
		(width 0.15494)
		(layer "In5.Cu")
		(net "RST_MB_BIC_ISO_R_N")
	)
	(segment
		(start 235.204508 -203.962508)
		(end 235.204508 -202.464162)
		(width 0.15494)
		(layer "In5.Cu")
		(net "RST_MB_BIC_ISO_R_N")
	)
	(segment
		(start 244.64645 -210.725004)
		(end 244.119654 -211.2518)
		(width 0.15494)
		(layer "In5.Cu")
		(net "RST_MB_BIC_ISO_R_N")
	)
	(segment
		(start 223.0882 -192.3288)
		(end 222.639382 -191.879982)
		(width 0.15494)
		(layer "In5.Cu")
		(net "RST_MB_BIC_ISO_R_N")
	)
	(segment
		(start 222.032068 -190.177674)
		(end 222.032068 -190.224156)
		(width 0.15494)
		(layer "In5.Cu")
		(net "RST_MB_BIC_ISO_R_N")
	)
	(segment
		(start 265.98626 -375.7803)
		(end 267.71346 -374.0531)
		(width 0.15494)
		(layer "In7.Cu")
		(net "RST_MB_BIC_ISO_R_N")
	)
	(segment
		(start 249.992134 -332.5368)
		(end 246.630444 -329.17511)
		(width 0.15494)
		(layer "In7.Cu")
		(net "RST_MB_BIC_ISO_R_N")
	)
	(segment
		(start 221.64548 -201.177906)
		(end 221.64548 -199.932544)
		(width 0.15494)
		(layer "In7.Cu")
		(net "RST_MB_BIC_ISO_R_N")
	)
	(segment
		(start 251.694188 -332.5368)
		(end 249.992134 -332.5368)
		(width 0.15494)
		(layer "In7.Cu")
		(net "RST_MB_BIC_ISO_R_N")
	)
	(segment
		(start 267.71346 -374.0531)
		(end 267.71346 -360.8705)
		(width 0.15494)
		(layer "In7.Cu")
		(net "RST_MB_BIC_ISO_R_N")
	)
	(segment
		(start 278.4348 -402.327618)
		(end 278.4348 -399.211546)
		(width 0.15494)
		(layer "In7.Cu")
		(net "RST_MB_BIC_ISO_R_N")
	)
	(segment
		(start 264.53846 -357.6955)
		(end 264.53846 -346.0623)
		(width 0.15494)
		(layer "In7.Cu")
		(net "RST_MB_BIC_ISO_R_N")
	)
	(segment
		(start 279.459182 -403.352)
		(end 278.4348 -402.327618)
		(width 0.15494)
		(layer "In7.Cu")
		(net "RST_MB_BIC_ISO_R_N")
	)
	(segment
		(start 222.6564 -190.848488)
		(end 222.032068 -190.224156)
		(width 0.15494)
		(layer "In7.Cu")
		(net "RST_MB_BIC_ISO_R_N")
	)
	(segment
		(start 222.64878 -191.765428)
		(end 222.64878 -191.069468)
		(width 0.15494)
		(layer "In7.Cu")
		(net "RST_MB_BIC_ISO_R_N")
	)
	(segment
		(start 221.64548 -199.932544)
		(end 222.6564 -197.49008)
		(width 0.15494)
		(layer "In7.Cu")
		(net "RST_MB_BIC_ISO_R_N")
	)
	(segment
		(start 264.53846 -346.0623)
		(end 255.83388 -337.357974)
		(width 0.15494)
		(layer "In7.Cu")
		(net "RST_MB_BIC_ISO_R_N")
	)
	(segment
		(start 220.98889 -203.462128)
		(end 220.6244 -203.097638)
		(width 0.15494)
		(layer "In7.Cu")
		(net "RST_MB_BIC_ISO_R_N")
	)
	(segment
		(start 265.98626 -381.1397)
		(end 265.98626 -375.7803)
		(width 0.15494)
		(layer "In7.Cu")
		(net "RST_MB_BIC_ISO_R_N")
	)
	(segment
		(start 220.6244 -203.097638)
		(end 220.6244 -202.198986)
		(width 0.15494)
		(layer "In7.Cu")
		(net "RST_MB_BIC_ISO_R_N")
	)
	(segment
		(start 222.64878 -191.069468)
		(end 222.6564 -191.061848)
		(width 0.15494)
		(layer "In7.Cu")
		(net "RST_MB_BIC_ISO_R_N")
	)
	(segment
		(start 276.09546 -391.2489)
		(end 265.98626 -381.1397)
		(width 0.15494)
		(layer "In7.Cu")
		(net "RST_MB_BIC_ISO_R_N")
	)
	(segment
		(start 246.630444 -329.17511)
		(end 240.857786 -329.17511)
		(width 0.15494)
		(layer "In7.Cu")
		(net "RST_MB_BIC_ISO_R_N")
	)
	(segment
		(start 276.09546 -396.872206)
		(end 276.09546 -391.2489)
		(width 0.15494)
		(layer "In7.Cu")
		(net "RST_MB_BIC_ISO_R_N")
	)
	(segment
		(start 222.6564 -191.773048)
		(end 222.64878 -191.765428)
		(width 0.15494)
		(layer "In7.Cu")
		(net "RST_MB_BIC_ISO_R_N")
	)
	(segment
		(start 222.6564 -197.49008)
		(end 222.6564 -191.773048)
		(width 0.15494)
		(layer "In7.Cu")
		(net "RST_MB_BIC_ISO_R_N")
	)
	(segment
		(start 267.71346 -360.8705)
		(end 264.53846 -357.6955)
		(width 0.15494)
		(layer "In7.Cu")
		(net "RST_MB_BIC_ISO_R_N")
	)
	(segment
		(start 255.83388 -337.357974)
		(end 255.833626 -337.357466)
		(width 0.15494)
		(layer "In7.Cu")
		(net "RST_MB_BIC_ISO_R_N")
	)
	(segment
		(start 222.6564 -191.061848)
		(end 222.6564 -190.848488)
		(width 0.15494)
		(layer "In7.Cu")
		(net "RST_MB_BIC_ISO_R_N")
	)
	(segment
		(start 255.351788 -336.1944)
		(end 251.694188 -332.5368)
		(width 0.15494)
		(layer "In7.Cu")
		(net "RST_MB_BIC_ISO_R_N")
	)
	(segment
		(start 278.4348 -399.211546)
		(end 276.09546 -396.872206)
		(width 0.15494)
		(layer "In7.Cu")
		(net "RST_MB_BIC_ISO_R_N")
	)
	(segment
		(start 220.6244 -202.198986)
		(end 221.64548 -201.177906)
		(width 0.15494)
		(layer "In7.Cu")
		(net "RST_MB_BIC_ISO_R_N")
	)
	(segment
		(start 255.833626 -337.357466)
		(end 255.351788 -336.1944)
		(width 0.15494)
		(layer "In7.Cu")
		(net "RST_MB_BIC_ISO_R_N")
	)
	(segment
		(start 225.16973 -243.559076)
		(end 225.16973 -252.98273)
		(width 0.15494)
		(layer "In9.Cu")
		(net "RST_MB_BIC_ISO_R_N")
	)
	(segment
		(start 229.6414 -257.4544)
		(end 229.6414 -260.298946)
		(width 0.15494)
		(layer "In9.Cu")
		(net "RST_MB_BIC_ISO_R_N")
	)
	(segment
		(start 219.16898 -230.36022)
		(end 218.755468 -230.773732)
		(width 0.15494)
		(layer "In9.Cu")
		(net "RST_MB_BIC_ISO_R_N")
	)
	(segment
		(start 218.755468 -235.660184)
		(end 219.4814 -236.386116)
		(width 0.15494)
		(layer "In9.Cu")
		(net "RST_MB_BIC_ISO_R_N")
	)
	(segment
		(start 219.4814 -236.386116)
		(end 219.4814 -237.870746)
		(width 0.15494)
		(layer "In9.Cu")
		(net "RST_MB_BIC_ISO_R_N")
	)
	(segment
		(start 217.303096 -228.22027)
		(end 219.16898 -230.086154)
		(width 0.15494)
		(layer "In9.Cu")
		(net "RST_MB_BIC_ISO_R_N")
	)
	(segment
		(start 233.5022 -282.194254)
		(end 233.5022 -321.819524)
		(width 0.15494)
		(layer "In9.Cu")
		(net "RST_MB_BIC_ISO_R_N")
	)
	(segment
		(start 233.5022 -321.819524)
		(end 234.171744 -322.489068)
		(width 0.15494)
		(layer "In9.Cu")
		(net "RST_MB_BIC_ISO_R_N")
	)
	(segment
		(start 225.16973 -252.98273)
		(end 229.6414 -257.4544)
		(width 0.15494)
		(layer "In9.Cu")
		(net "RST_MB_BIC_ISO_R_N")
	)
	(segment
		(start 219.4814 -237.870746)
		(end 225.16973 -243.559076)
		(width 0.15494)
		(layer "In9.Cu")
		(net "RST_MB_BIC_ISO_R_N")
	)
	(segment
		(start 239.273842 -322.489068)
		(end 240.857786 -324.073012)
		(width 0.15494)
		(layer "In9.Cu")
		(net "RST_MB_BIC_ISO_R_N")
	)
	(segment
		(start 231.323896 -280.01595)
		(end 233.5022 -282.194254)
		(width 0.15494)
		(layer "In9.Cu")
		(net "RST_MB_BIC_ISO_R_N")
	)
	(segment
		(start 234.171744 -322.489068)
		(end 239.273842 -322.489068)
		(width 0.15494)
		(layer "In9.Cu")
		(net "RST_MB_BIC_ISO_R_N")
	)
	(segment
		(start 240.857786 -324.073012)
		(end 240.857786 -329.17511)
		(width 0.15494)
		(layer "In9.Cu")
		(net "RST_MB_BIC_ISO_R_N")
	)
	(segment
		(start 219.16898 -230.086154)
		(end 219.16898 -230.36022)
		(width 0.15494)
		(layer "In9.Cu")
		(net "RST_MB_BIC_ISO_R_N")
	)
	(segment
		(start 218.755468 -230.773732)
		(end 218.755468 -235.660184)
		(width 0.15494)
		(layer "In9.Cu")
		(net "RST_MB_BIC_ISO_R_N")
	)
	(segment
		(start 231.323896 -261.981442)
		(end 231.323896 -280.01595)
		(width 0.15494)
		(layer "In9.Cu")
		(net "RST_MB_BIC_ISO_R_N")
	)
	(segment
		(start 229.6414 -260.298946)
		(end 231.323896 -261.981442)
		(width 0.15494)
		(layer "In9.Cu")
		(net "RST_MB_BIC_ISO_R_N")
	)
	(segment
		(start 259.500116 -212.281516)
		(end 260.16966 -212.95106)
		(width 0.15494)
		(layer "In13.Cu")
		(net "RST_MB_BIC_ISO_R_N")
	)
	(segment
		(start 248.466356 -208.590896)
		(end 249.040396 -209.164936)
		(width 0.15494)
		(layer "In13.Cu")
		(net "RST_MB_BIC_ISO_R_N")
	)
	(segment
		(start 264.6807 -212.003132)
		(end 265.98245 -212.003132)
		(width 0.15494)
		(layer "In13.Cu")
		(net "RST_MB_BIC_ISO_R_N")
	)
	(segment
		(start 254.133096 -209.164936)
		(end 257.249676 -212.281516)
		(width 0.15494)
		(layer "In13.Cu")
		(net "RST_MB_BIC_ISO_R_N")
	)
	(segment
		(start 268.1986 -212.60054)
		(end 268.1986 -213.5378)
		(width 0.15494)
		(layer "In13.Cu")
		(net "RST_MB_BIC_ISO_R_N")
	)
	(segment
		(start 261.828788 -212.95106)
		(end 261.829042 -212.951314)
		(width 0.15494)
		(layer "In13.Cu")
		(net "RST_MB_BIC_ISO_R_N")
	)
	(segment
		(start 267.807694 -212.209634)
		(end 268.1986 -212.60054)
		(width 0.15494)
		(layer "In13.Cu")
		(net "RST_MB_BIC_ISO_R_N")
	)
	(segment
		(start 260.16966 -212.95106)
		(end 261.828788 -212.95106)
		(width 0.15494)
		(layer "In13.Cu")
		(net "RST_MB_BIC_ISO_R_N")
	)
	(segment
		(start 257.249676 -212.281516)
		(end 259.500116 -212.281516)
		(width 0.15494)
		(layer "In13.Cu")
		(net "RST_MB_BIC_ISO_R_N")
	)
	(segment
		(start 261.829042 -212.951314)
		(end 263.732518 -212.951314)
		(width 0.15494)
		(layer "In13.Cu")
		(net "RST_MB_BIC_ISO_R_N")
	)
	(segment
		(start 265.98245 -212.003132)
		(end 266.188952 -212.209634)
		(width 0.15494)
		(layer "In13.Cu")
		(net "RST_MB_BIC_ISO_R_N")
	)
	(segment
		(start 249.040396 -209.164936)
		(end 254.133096 -209.164936)
		(width 0.15494)
		(layer "In13.Cu")
		(net "RST_MB_BIC_ISO_R_N")
	)
	(segment
		(start 268.1986 -213.5378)
		(end 268.1478 -213.5886)
		(width 0.15494)
		(layer "In13.Cu")
		(net "RST_MB_BIC_ISO_R_N")
	)
	(segment
		(start 266.188952 -212.209634)
		(end 267.807694 -212.209634)
		(width 0.15494)
		(layer "In13.Cu")
		(net "RST_MB_BIC_ISO_R_N")
	)
	(segment
		(start 263.732518 -212.951314)
		(end 264.6807 -212.003132)
		(width 0.15494)
		(layer "In13.Cu")
		(net "RST_MB_BIC_ISO_R_N")
	)
	(segment
		(start 346.096082 -215.989662)
		(end 346.493592 -216.387172)
		(width 0.0889)
		(layer "In15.Cu")
		(net "RST_MB_BIC_ISO_R_N")
	)
	(segment
		(start 326.771 -206.9592)
		(end 328.484484 -208.672684)
		(width 0.15494)
		(layer "In15.Cu")
		(net "RST_MB_BIC_ISO_R_N")
	)
	(segment
		(start 328.484484 -208.672684)
		(end 330.973938 -208.672684)
		(width 0.15494)
		(layer "In15.Cu")
		(net "RST_MB_BIC_ISO_R_N")
	)
	(segment
		(start 299.009054 -208.788)
		(end 300.456854 -207.3402)
		(width 0.15494)
		(layer "In15.Cu")
		(net "RST_MB_BIC_ISO_R_N")
	)
	(segment
		(start 332.079854 -209.7786)
		(end 333.2988 -209.7786)
		(width 0.15494)
		(layer "In15.Cu")
		(net "RST_MB_BIC_ISO_R_N")
	)
	(segment
		(start 325.4248 -206.9592)
		(end 326.771 -206.9592)
		(width 0.15494)
		(layer "In15.Cu")
		(net "RST_MB_BIC_ISO_R_N")
	)
	(segment
		(start 341.189818 -210.379564)
		(end 342.704674 -211.89442)
		(width 0.15494)
		(layer "In15.Cu")
		(net "RST_MB_BIC_ISO_R_N")
	)
	(segment
		(start 333.2988 -209.7786)
		(end 333.7814 -210.2612)
		(width 0.15494)
		(layer "In15.Cu")
		(net "RST_MB_BIC_ISO_R_N")
	)
	(segment
		(start 342.704674 -211.89442)
		(end 342.704674 -215.560656)
		(width 0.15494)
		(layer "In15.Cu")
		(net "RST_MB_BIC_ISO_R_N")
	)
	(segment
		(start 333.7814 -210.2612)
		(end 338.188554 -210.2612)
		(width 0.15494)
		(layer "In15.Cu")
		(net "RST_MB_BIC_ISO_R_N")
	)
	(segment
		(start 338.188554 -210.2612)
		(end 338.306918 -210.379564)
		(width 0.15494)
		(layer "In15.Cu")
		(net "RST_MB_BIC_ISO_R_N")
	)
	(segment
		(start 338.306918 -210.379564)
		(end 341.189818 -210.379564)
		(width 0.15494)
		(layer "In15.Cu")
		(net "RST_MB_BIC_ISO_R_N")
	)
	(segment
		(start 268.1478 -213.5886)
		(end 282.981146 -213.5886)
		(width 0.15494)
		(layer "In15.Cu")
		(net "RST_MB_BIC_ISO_R_N")
	)
	(segment
		(start 342.704674 -215.755474)
		(end 342.938862 -215.989662)
		(width 0.0889)
		(layer "In15.Cu")
		(net "RST_MB_BIC_ISO_R_N")
	)
	(segment
		(start 287.781746 -208.788)
		(end 299.009054 -208.788)
		(width 0.15494)
		(layer "In15.Cu")
		(net "RST_MB_BIC_ISO_R_N")
	)
	(segment
		(start 325.0438 -207.3402)
		(end 325.4248 -206.9592)
		(width 0.15494)
		(layer "In15.Cu")
		(net "RST_MB_BIC_ISO_R_N")
	)
	(segment
		(start 300.456854 -207.3402)
		(end 325.0438 -207.3402)
		(width 0.15494)
		(layer "In15.Cu")
		(net "RST_MB_BIC_ISO_R_N")
	)
	(segment
		(start 342.938862 -215.989662)
		(end 346.096082 -215.989662)
		(width 0.0889)
		(layer "In15.Cu")
		(net "RST_MB_BIC_ISO_R_N")
	)
	(segment
		(start 342.704674 -215.560656)
		(end 342.704674 -215.755474)
		(width 0.0889)
		(layer "In15.Cu")
		(net "RST_MB_BIC_ISO_R_N")
	)
	(segment
		(start 330.973938 -208.672684)
		(end 332.079854 -209.7786)
		(width 0.15494)
		(layer "In15.Cu")
		(net "RST_MB_BIC_ISO_R_N")
	)
	(segment
		(start 282.981146 -213.5886)
		(end 287.781746 -208.788)
		(width 0.15494)
		(layer "In15.Cu")
		(net "RST_MB_BIC_ISO_R_N")
	)
	(segment
		(start 349.293942 -224.786952)
		(end 349.693738 -225.186748)
		(width 0.13208)
		(layer "F.Cu")
		(net "NIC1_AUX_PWR_EN")
	)
	(via
		(at 349.693738 -225.186748)
		(size 0.4572)
		(drill 0.254)
		(layers "F.Cu" "B.Cu")
		(net "NIC1_AUX_PWR_EN")
	)
	(via
		(at 90.984578 -212.461348)
		(size 0.508)
		(drill 0.254)
		(layers "F.Cu" "B.Cu")
		(net "NIC1_AUX_PWR_EN")
	)
	(via
		(at 70.191376 -118.711218)
		(size 0.508)
		(drill 0.254)
		(layers "F.Cu" "B.Cu")
		(net "NIC1_AUX_PWR_EN")
	)
	(segment
		(start 70.890638 -118.711218)
		(end 70.191376 -118.711218)
		(width 0.13208)
		(layer "B.Cu")
		(net "NIC1_AUX_PWR_EN")
	)
	(segment
		(start 70.88632 -117.66169)
		(end 70.88632 -118.7069)
		(width 0.13208)
		(layer "B.Cu")
		(net "NIC1_AUX_PWR_EN")
	)
	(segment
		(start 70.88632 -118.7069)
		(end 70.890638 -118.711218)
		(width 0.13208)
		(layer "B.Cu")
		(net "NIC1_AUX_PWR_EN")
	)
	(segment
		(start 91.567 -197.643242)
		(end 91.567 -145.121884)
		(width 0.15494)
		(layer "In5.Cu")
		(net "NIC1_AUX_PWR_EN")
	)
	(segment
		(start 70.198996 -118.718838)
		(end 70.191376 -118.711218)
		(width 0.15494)
		(layer "In5.Cu")
		(net "NIC1_AUX_PWR_EN")
	)
	(segment
		(start 88.500966 -135.419084)
		(end 86.988396 -130.921506)
		(width 0.15494)
		(layer "In5.Cu")
		(net "NIC1_AUX_PWR_EN")
	)
	(segment
		(start 74.785728 -118.718838)
		(end 70.198996 -118.718838)
		(width 0.15494)
		(layer "In5.Cu")
		(net "NIC1_AUX_PWR_EN")
	)
	(segment
		(start 91.567 -145.121884)
		(end 89.885012 -143.439896)
		(width 0.15494)
		(layer "In5.Cu")
		(net "NIC1_AUX_PWR_EN")
	)
	(segment
		(start 90.984578 -198.225664)
		(end 91.567 -197.643242)
		(width 0.15494)
		(layer "In5.Cu")
		(net "NIC1_AUX_PWR_EN")
	)
	(segment
		(start 86.988396 -130.921506)
		(end 74.785728 -118.718838)
		(width 0.15494)
		(layer "In5.Cu")
		(net "NIC1_AUX_PWR_EN")
	)
	(segment
		(start 90.984578 -212.461348)
		(end 90.984578 -198.225664)
		(width 0.15494)
		(layer "In5.Cu")
		(net "NIC1_AUX_PWR_EN")
	)
	(segment
		(start 89.885012 -143.439896)
		(end 88.500966 -135.419084)
		(width 0.15494)
		(layer "In5.Cu")
		(net "NIC1_AUX_PWR_EN")
	)
	(segment
		(start 239.988598 -241.0714)
		(end 239.341914 -240.424716)
		(width 0.15494)
		(layer "In13.Cu")
		(net "NIC1_AUX_PWR_EN")
	)
	(segment
		(start 349.631 -236.728)
		(end 348.5896 -237.7694)
		(width 0.15494)
		(layer "In13.Cu")
		(net "NIC1_AUX_PWR_EN")
	)
	(segment
		(start 232.074974 -241.0968)
		(end 222.453708 -241.0968)
		(width 0.15494)
		(layer "In13.Cu")
		(net "NIC1_AUX_PWR_EN")
	)
	(segment
		(start 172.003974 -235.83392)
		(end 132.53212 -235.83392)
		(width 0.15494)
		(layer "In13.Cu")
		(net "NIC1_AUX_PWR_EN")
	)
	(segment
		(start 350.091248 -227.790502)
		(end 350.24187 -227.941124)
		(width 0.15494)
		(layer "In13.Cu")
		(net "NIC1_AUX_PWR_EN")
	)
	(segment
		(start 274.809458 -241.574574)
		(end 262.580374 -241.574574)
		(width 0.15494)
		(layer "In13.Cu")
		(net "NIC1_AUX_PWR_EN")
	)
	(segment
		(start 348.5896 -237.7694)
		(end 347.061028 -237.7694)
		(width 0.15494)
		(layer "In13.Cu")
		(net "NIC1_AUX_PWR_EN")
	)
	(segment
		(start 255.092708 -241.5794)
		(end 254.584708 -241.0714)
		(width 0.15494)
		(layer "In13.Cu")
		(net "NIC1_AUX_PWR_EN")
	)
	(segment
		(start 350.091248 -225.584258)
		(end 350.091248 -227.3808)
		(width 0.0889)
		(layer "In13.Cu")
		(net "NIC1_AUX_PWR_EN")
	)
	(segment
		(start 341.057484 -243.205)
		(end 276.439884 -243.205)
		(width 0.15494)
		(layer "In13.Cu")
		(net "NIC1_AUX_PWR_EN")
	)
	(segment
		(start 262.580374 -241.574574)
		(end 262.397748 -241.7572)
		(width 0.15494)
		(layer "In13.Cu")
		(net "NIC1_AUX_PWR_EN")
	)
	(segment
		(start 345.120976 -239.709452)
		(end 344.553032 -239.709452)
		(width 0.15494)
		(layer "In13.Cu")
		(net "NIC1_AUX_PWR_EN")
	)
	(segment
		(start 349.693738 -225.186748)
		(end 350.091248 -225.584258)
		(width 0.0889)
		(layer "In13.Cu")
		(net "NIC1_AUX_PWR_EN")
	)
	(segment
		(start 132.53212 -235.83392)
		(end 119.344694 -222.646494)
		(width 0.15494)
		(layer "In13.Cu")
		(net "NIC1_AUX_PWR_EN")
	)
	(segment
		(start 222.453708 -241.0968)
		(end 221.945708 -240.5888)
		(width 0.15494)
		(layer "In13.Cu")
		(net "NIC1_AUX_PWR_EN")
	)
	(segment
		(start 97.653348 -212.461348)
		(end 90.984578 -212.461348)
		(width 0.15494)
		(layer "In13.Cu")
		(net "NIC1_AUX_PWR_EN")
	)
	(segment
		(start 350.24187 -227.941124)
		(end 350.24187 -233.778552)
		(width 0.15494)
		(layer "In13.Cu")
		(net "NIC1_AUX_PWR_EN")
	)
	(segment
		(start 262.137144 -241.7572)
		(end 262.130286 -241.764058)
		(width 0.15494)
		(layer "In13.Cu")
		(net "NIC1_AUX_PWR_EN")
	)
	(segment
		(start 208.13268 -240.5888)
		(end 205.866746 -242.854734)
		(width 0.15494)
		(layer "In13.Cu")
		(net "NIC1_AUX_PWR_EN")
	)
	(segment
		(start 349.631 -234.389422)
		(end 349.631 -236.728)
		(width 0.15494)
		(layer "In13.Cu")
		(net "NIC1_AUX_PWR_EN")
	)
	(segment
		(start 179.024788 -242.854734)
		(end 172.003974 -235.83392)
		(width 0.15494)
		(layer "In13.Cu")
		(net "NIC1_AUX_PWR_EN")
	)
	(segment
		(start 261.722108 -241.7572)
		(end 261.70636 -241.7572)
		(width 0.15494)
		(layer "In13.Cu")
		(net "NIC1_AUX_PWR_EN")
	)
	(segment
		(start 347.061028 -237.7694)
		(end 345.120976 -239.709452)
		(width 0.15494)
		(layer "In13.Cu")
		(net "NIC1_AUX_PWR_EN")
	)
	(segment
		(start 350.091248 -227.3808)
		(end 350.091248 -227.790502)
		(width 0.15494)
		(layer "In13.Cu")
		(net "NIC1_AUX_PWR_EN")
	)
	(segment
		(start 119.344694 -222.646494)
		(end 119.344694 -220.995494)
		(width 0.15494)
		(layer "In13.Cu")
		(net "NIC1_AUX_PWR_EN")
	)
	(segment
		(start 119.344694 -220.995494)
		(end 111.452914 -213.103714)
		(width 0.15494)
		(layer "In13.Cu")
		(net "NIC1_AUX_PWR_EN")
	)
	(segment
		(start 261.70636 -241.7572)
		(end 261.149592 -241.200432)
		(width 0.15494)
		(layer "In13.Cu")
		(net "NIC1_AUX_PWR_EN")
	)
	(segment
		(start 98.295714 -213.103714)
		(end 97.653348 -212.461348)
		(width 0.15494)
		(layer "In13.Cu")
		(net "NIC1_AUX_PWR_EN")
	)
	(segment
		(start 262.130286 -241.764058)
		(end 261.728966 -241.764058)
		(width 0.15494)
		(layer "In13.Cu")
		(net "NIC1_AUX_PWR_EN")
	)
	(segment
		(start 111.452914 -213.103714)
		(end 98.295714 -213.103714)
		(width 0.15494)
		(layer "In13.Cu")
		(net "NIC1_AUX_PWR_EN")
	)
	(segment
		(start 205.866746 -242.854734)
		(end 179.024788 -242.854734)
		(width 0.15494)
		(layer "In13.Cu")
		(net "NIC1_AUX_PWR_EN")
	)
	(segment
		(start 232.747058 -240.424716)
		(end 232.074974 -241.0968)
		(width 0.15494)
		(layer "In13.Cu")
		(net "NIC1_AUX_PWR_EN")
	)
	(segment
		(start 344.553032 -239.709452)
		(end 341.057484 -243.205)
		(width 0.15494)
		(layer "In13.Cu")
		(net "NIC1_AUX_PWR_EN")
	)
	(segment
		(start 254.584708 -241.0714)
		(end 239.988598 -241.0714)
		(width 0.15494)
		(layer "In13.Cu")
		(net "NIC1_AUX_PWR_EN")
	)
	(segment
		(start 239.341914 -240.424716)
		(end 232.747058 -240.424716)
		(width 0.15494)
		(layer "In13.Cu")
		(net "NIC1_AUX_PWR_EN")
	)
	(segment
		(start 261.149592 -241.200432)
		(end 257.544316 -241.200432)
		(width 0.15494)
		(layer "In13.Cu")
		(net "NIC1_AUX_PWR_EN")
	)
	(segment
		(start 257.165348 -241.5794)
		(end 255.092708 -241.5794)
		(width 0.15494)
		(layer "In13.Cu")
		(net "NIC1_AUX_PWR_EN")
	)
	(segment
		(start 262.397748 -241.7572)
		(end 262.137144 -241.7572)
		(width 0.15494)
		(layer "In13.Cu")
		(net "NIC1_AUX_PWR_EN")
	)
	(segment
		(start 221.945708 -240.5888)
		(end 208.13268 -240.5888)
		(width 0.15494)
		(layer "In13.Cu")
		(net "NIC1_AUX_PWR_EN")
	)
	(segment
		(start 350.24187 -233.778552)
		(end 349.631 -234.389422)
		(width 0.15494)
		(layer "In13.Cu")
		(net "NIC1_AUX_PWR_EN")
	)
	(segment
		(start 276.439884 -243.205)
		(end 274.809458 -241.574574)
		(width 0.15494)
		(layer "In13.Cu")
		(net "NIC1_AUX_PWR_EN")
	)
	(segment
		(start 261.728966 -241.764058)
		(end 261.722108 -241.7572)
		(width 0.15494)
		(layer "In13.Cu")
		(net "NIC1_AUX_PWR_EN")
	)
	(segment
		(start 257.544316 -241.200432)
		(end 257.165348 -241.5794)
		(width 0.15494)
		(layer "In13.Cu")
		(net "NIC1_AUX_PWR_EN")
	)
	(segment
		(start 175.203358 -59.171586)
		(end 175.044354 -59.012582)
		(width 0.13208)
		(layer "F.Cu")
		(net "P3V3_SSD6_OCP")
	)
	(segment
		(start 175.24095 -58.364628)
		(end 175.044354 -58.561224)
		(width 0.13208)
		(layer "F.Cu")
		(net "P3V3_SSD6_OCP")
	)
	(segment
		(start 175.044354 -59.012582)
		(end 175.044354 -58.561224)
		(width 0.13208)
		(layer "F.Cu")
		(net "P3V3_SSD6_OCP")
	)
	(segment
		(start 175.24095 -57.16397)
		(end 175.24095 -58.364628)
		(width 0.13208)
		(layer "F.Cu")
		(net "P3V3_SSD6_OCP")
	)
	(via
		(at 175.044354 -58.561224)
		(size 0.508)
		(drill 0.254)
		(layers "F.Cu" "B.Cu")
		(net "P3V3_SSD6_OCP")
	)
	(segment
		(start 383.968244 -231.168448)
		(end 383.968244 -232.126282)
		(width 0.13462)
		(layer "F.Cu")
		(net "USB2_FT4232_SDB_DN")
	)
	(segment
		(start 383.673858 -230.873554)
		(end 383.968498 -231.168194)
		(width 0.13462)
		(layer "F.Cu")
		(net "USB2_FT4232_SDB_DN")
	)
	(segment
		(start 233.010456 -85.140292)
		(end 233.010456 -84.757514)
		(width 0.13462)
		(layer "F.Cu")
		(net "USB2_FT4232_SDB_DN")
	)
	(segment
		(start 232.722166 -85.428582)
		(end 233.010456 -85.140292)
		(width 0.13462)
		(layer "F.Cu")
		(net "USB2_FT4232_SDB_DN")
	)
	(segment
		(start 233.010456 -84.757514)
		(end 232.46969 -84.216748)
		(width 0.13462)
		(layer "F.Cu")
		(net "USB2_FT4232_SDB_DN")
	)
	(segment
		(start 383.968498 -231.168194)
		(end 383.968244 -231.168448)
		(width 0.13462)
		(layer "F.Cu")
		(net "USB2_FT4232_SDB_DN")
	)
	(segment
		(start 383.855468 -232.239058)
		(end 383.855468 -232.836212)
		(width 0.13462)
		(layer "F.Cu")
		(net "USB2_FT4232_SDB_DN")
	)
	(segment
		(start 383.968244 -232.126282)
		(end 383.855468 -232.239058)
		(width 0.13462)
		(layer "F.Cu")
		(net "USB2_FT4232_SDB_DN")
	)
	(segment
		(start 232.46969 -84.216748)
		(end 232.46969 -83.718908)
		(width 0.13462)
		(layer "F.Cu")
		(net "USB2_FT4232_SDB_DN")
	)
	(via
		(at 383.673858 -230.873554)
		(size 0.508)
		(drill 0.254)
		(layers "F.Cu" "B.Cu")
		(net "USB2_FT4232_SDB_DN")
	)
	(via
		(at 370.777008 -204.947774)
		(size 0.4064)
		(drill 0.2032)
		(layers "F.Cu" "B.Cu")
		(net "USB2_FT4232_SDB_DN")
	)
	(via
		(at 232.722166 -85.428582)
		(size 0.508)
		(drill 0.254)
		(layers "F.Cu" "B.Cu")
		(net "USB2_FT4232_SDB_DN")
	)
	(segment
		(start 369.888262 -185.357262)
		(end 369.888262 -175.43145)
		(width 0.13462)
		(layer "B.Cu")
		(net "USB2_FT4232_SDB_DN")
	)
	(segment
		(start 247.898158 -75.381612)
		(end 243.2812 -79.99857)
		(width 0.13462)
		(layer "B.Cu")
		(net "USB2_FT4232_SDB_DN")
	)
	(segment
		(start 261.352792 -75.02652)
		(end 256.97688 -75.02652)
		(width 0.13462)
		(layer "B.Cu")
		(net "USB2_FT4232_SDB_DN")
	)
	(segment
		(start 241.46383 -86.85657)
		(end 238.106458 -86.85657)
		(width 0.13462)
		(layer "B.Cu")
		(net "USB2_FT4232_SDB_DN")
	)
	(segment
		(start 281.578812 -87.130636)
		(end 281.578812 -85.69706)
		(width 0.13462)
		(layer "B.Cu")
		(net "USB2_FT4232_SDB_DN")
	)
	(segment
		(start 233.010456 -85.716872)
		(end 232.722166 -85.428582)
		(width 0.13462)
		(layer "B.Cu")
		(net "USB2_FT4232_SDB_DN")
	)
	(segment
		(start 345.018868 -164.831268)
		(end 345.018868 -144.88033)
		(width 0.13462)
		(layer "B.Cu")
		(net "USB2_FT4232_SDB_DN")
	)
	(segment
		(start 267.322808 -74.11212)
		(end 262.267192 -74.11212)
		(width 0.13462)
		(layer "B.Cu")
		(net "USB2_FT4232_SDB_DN")
	)
	(segment
		(start 349.588836 -169.401236)
		(end 345.018868 -164.831268)
		(width 0.13462)
		(layer "B.Cu")
		(net "USB2_FT4232_SDB_DN")
	)
	(segment
		(start 375.426224 -223.843342)
		(end 375.315988 -224.109788)
		(width 0.13462)
		(layer "B.Cu")
		(net "USB2_FT4232_SDB_DN")
	)
	(segment
		(start 335.444338 -135.3058)
		(end 324.342252 -135.3058)
		(width 0.13462)
		(layer "B.Cu")
		(net "USB2_FT4232_SDB_DN")
	)
	(segment
		(start 363.858048 -169.401236)
		(end 349.588836 -169.401236)
		(width 0.13462)
		(layer "B.Cu")
		(net "USB2_FT4232_SDB_DN")
	)
	(segment
		(start 273.885152 -78.0034)
		(end 271.214088 -78.0034)
		(width 0.13462)
		(layer "B.Cu")
		(net "USB2_FT4232_SDB_DN")
	)
	(segment
		(start 383.974848 -229.969822)
		(end 383.974848 -230.572564)
		(width 0.13462)
		(layer "B.Cu")
		(net "USB2_FT4232_SDB_DN")
	)
	(segment
		(start 369.888262 -175.43145)
		(end 363.858048 -169.401236)
		(width 0.13462)
		(layer "B.Cu")
		(net "USB2_FT4232_SDB_DN")
	)
	(segment
		(start 291.0586 -96.610424)
		(end 281.578812 -87.130636)
		(width 0.13462)
		(layer "B.Cu")
		(net "USB2_FT4232_SDB_DN")
	)
	(segment
		(start 238.106458 -86.85657)
		(end 237.630208 -86.38032)
		(width 0.13462)
		(layer "B.Cu")
		(net "USB2_FT4232_SDB_DN")
	)
	(segment
		(start 370.777008 -204.947774)
		(end 370.777008 -209.240374)
		(width 0.13462)
		(layer "B.Cu")
		(net "USB2_FT4232_SDB_DN")
	)
	(segment
		(start 383.773426 -229.7684)
		(end 383.974848 -229.969822)
		(width 0.13462)
		(layer "B.Cu")
		(net "USB2_FT4232_SDB_DN")
	)
	(segment
		(start 375.50979 -220.875352)
		(end 375.426224 -220.958918)
		(width 0.13462)
		(layer "B.Cu")
		(net "USB2_FT4232_SDB_DN")
	)
	(segment
		(start 370.777008 -209.240374)
		(end 375.50979 -213.973156)
		(width 0.13462)
		(layer "B.Cu")
		(net "USB2_FT4232_SDB_DN")
	)
	(segment
		(start 243.2812 -79.99857)
		(end 243.2812 -85.0392)
		(width 0.13462)
		(layer "B.Cu")
		(net "USB2_FT4232_SDB_DN")
	)
	(segment
		(start 262.267192 -74.11212)
		(end 261.352792 -75.02652)
		(width 0.13462)
		(layer "B.Cu")
		(net "USB2_FT4232_SDB_DN")
	)
	(segment
		(start 271.214088 -78.0034)
		(end 267.322808 -74.11212)
		(width 0.13462)
		(layer "B.Cu")
		(net "USB2_FT4232_SDB_DN")
	)
	(segment
		(start 375.50979 -213.973156)
		(end 375.50979 -220.875352)
		(width 0.13462)
		(layer "B.Cu")
		(net "USB2_FT4232_SDB_DN")
	)
	(segment
		(start 324.342252 -135.3058)
		(end 321.540632 -138.10742)
		(width 0.13462)
		(layer "B.Cu")
		(net "USB2_FT4232_SDB_DN")
	)
	(segment
		(start 243.2812 -85.0392)
		(end 241.46383 -86.85657)
		(width 0.13462)
		(layer "B.Cu")
		(net "USB2_FT4232_SDB_DN")
	)
	(segment
		(start 375.315988 -224.109788)
		(end 375.315988 -225.874072)
		(width 0.13462)
		(layer "B.Cu")
		(net "USB2_FT4232_SDB_DN")
	)
	(segment
		(start 321.540632 -138.10742)
		(end 296.639742 -138.10742)
		(width 0.13462)
		(layer "B.Cu")
		(net "USB2_FT4232_SDB_DN")
	)
	(segment
		(start 375.315988 -225.874072)
		(end 379.210316 -229.7684)
		(width 0.13462)
		(layer "B.Cu")
		(net "USB2_FT4232_SDB_DN")
	)
	(segment
		(start 256.97688 -75.02652)
		(end 256.621788 -75.381612)
		(width 0.13462)
		(layer "B.Cu")
		(net "USB2_FT4232_SDB_DN")
	)
	(segment
		(start 256.621788 -75.381612)
		(end 247.898158 -75.381612)
		(width 0.13462)
		(layer "B.Cu")
		(net "USB2_FT4232_SDB_DN")
	)
	(segment
		(start 375.426224 -220.958918)
		(end 375.426224 -223.843342)
		(width 0.13462)
		(layer "B.Cu")
		(net "USB2_FT4232_SDB_DN")
	)
	(segment
		(start 296.639742 -138.10742)
		(end 291.0586 -132.526278)
		(width 0.13462)
		(layer "B.Cu")
		(net "USB2_FT4232_SDB_DN")
	)
	(segment
		(start 291.0586 -132.526278)
		(end 291.0586 -96.610424)
		(width 0.13462)
		(layer "B.Cu")
		(net "USB2_FT4232_SDB_DN")
	)
	(segment
		(start 281.578812 -85.69706)
		(end 273.885152 -78.0034)
		(width 0.13462)
		(layer "B.Cu")
		(net "USB2_FT4232_SDB_DN")
	)
	(segment
		(start 383.974848 -230.572564)
		(end 383.673858 -230.873554)
		(width 0.13462)
		(layer "B.Cu")
		(net "USB2_FT4232_SDB_DN")
	)
	(segment
		(start 233.284268 -86.38032)
		(end 233.010456 -86.106508)
		(width 0.13462)
		(layer "B.Cu")
		(net "USB2_FT4232_SDB_DN")
	)
	(segment
		(start 233.010456 -86.106508)
		(end 233.010456 -85.716872)
		(width 0.13462)
		(layer "B.Cu")
		(net "USB2_FT4232_SDB_DN")
	)
	(segment
		(start 345.018868 -144.88033)
		(end 335.444338 -135.3058)
		(width 0.13462)
		(layer "B.Cu")
		(net "USB2_FT4232_SDB_DN")
	)
	(segment
		(start 370.777008 -186.246008)
		(end 369.888262 -185.357262)
		(width 0.13462)
		(layer "B.Cu")
		(net "USB2_FT4232_SDB_DN")
	)
	(segment
		(start 370.777008 -204.947774)
		(end 370.777008 -186.246008)
		(width 0.13462)
		(layer "B.Cu")
		(net "USB2_FT4232_SDB_DN")
	)
	(segment
		(start 379.210316 -229.7684)
		(end 383.773426 -229.7684)
		(width 0.13462)
		(layer "B.Cu")
		(net "USB2_FT4232_SDB_DN")
	)
	(segment
		(start 237.630208 -86.38032)
		(end 233.284268 -86.38032)
		(width 0.13462)
		(layer "B.Cu")
		(net "USB2_FT4232_SDB_DN")
	)
	(segment
		(start 144.554956 -21.847048)
		(end 144.554956 -22.561296)
		(width 0.13208)
		(layer "F.Cu")
		(net "SMB_SSD4_ISO_EN")
	)
	(segment
		(start 143.760698 -20.789392)
		(end 143.760698 -21.05279)
		(width 0.13208)
		(layer "F.Cu")
		(net "SMB_SSD4_ISO_EN")
	)
	(segment
		(start 143.760698 -21.05279)
		(end 144.554956 -21.847048)
		(width 0.13208)
		(layer "F.Cu")
		(net "SMB_SSD4_ISO_EN")
	)
	(via
		(at 144.554956 -21.847048)
		(size 0.508)
		(drill 0.254)
		(layers "F.Cu" "B.Cu")
		(net "SMB_SSD4_ISO_EN")
	)
	(segment
		(start 254.858266 -19.453098)
		(end 255.467866 -19.453098)
		(width 0.13208)
		(layer "F.Cu")
		(net "SMB_ISO_SSD8_R_SDA")
	)
	(segment
		(start 242.864894 -22.990048)
		(end 243.909342 -22.990048)
		(width 0.13208)
		(layer "F.Cu")
		(net "SMB_ISO_SSD8_R_SDA")
	)
	(segment
		(start 243.909342 -22.990048)
		(end 243.944394 -23.0251)
		(width 0.13208)
		(layer "F.Cu")
		(net "SMB_ISO_SSD8_R_SDA")
	)
	(via
		(at 243.944394 -23.0251)
		(size 0.508)
		(drill 0.254)
		(layers "F.Cu" "B.Cu")
		(net "SMB_ISO_SSD8_R_SDA")
	)
	(via
		(at 254.858266 -19.453098)
		(size 0.508)
		(drill 0.254)
		(layers "F.Cu" "B.Cu")
		(net "SMB_ISO_SSD8_R_SDA")
	)
	(segment
		(start 244.437154 -22.53234)
		(end 243.944394 -23.0251)
		(width 0.15494)
		(layer "In5.Cu")
		(net "SMB_ISO_SSD8_R_SDA")
	)
	(segment
		(start 253.716282 -22.53234)
		(end 244.437154 -22.53234)
		(width 0.15494)
		(layer "In5.Cu")
		(net "SMB_ISO_SSD8_R_SDA")
	)
	(segment
		(start 254.858266 -19.453098)
		(end 254.858266 -21.390356)
		(width 0.15494)
		(layer "In5.Cu")
		(net "SMB_ISO_SSD8_R_SDA")
	)
	(segment
		(start 254.858266 -21.390356)
		(end 253.716282 -22.53234)
		(width 0.15494)
		(layer "In5.Cu")
		(net "SMB_ISO_SSD8_R_SDA")
	)
	(segment
		(start 394.69314 -83.956652)
		(end 394.52169 -83.785202)
		(width 0.13208)
		(layer "F.Cu")
		(net "SMB_BIC_I2C6_MUX_CLK_R_SCL")
	)
	(segment
		(start 394.69314 -84.276692)
		(end 394.69314 -83.956652)
		(width 0.13208)
		(layer "F.Cu")
		(net "SMB_BIC_I2C6_MUX_CLK_R_SCL")
	)
	(segment
		(start 401.938998 -85.930486)
		(end 400.91868 -85.930486)
		(width 0.13208)
		(layer "F.Cu")
		(net "SMB_BIC_I2C6_MUX_CLK_R_SCL")
	)
	(segment
		(start 394.52169 -83.785202)
		(end 394.069316 -83.785202)
		(width 0.13208)
		(layer "F.Cu")
		(net "SMB_BIC_I2C6_MUX_CLK_R_SCL")
	)
	(segment
		(start 395.809216 -83.785202)
		(end 395.18463 -83.785202)
		(width 0.13208)
		(layer "F.Cu")
		(net "SMB_BIC_I2C6_MUX_CLK_R_SCL")
	)
	(segment
		(start 395.18463 -83.785202)
		(end 394.69314 -84.276692)
		(width 0.13208)
		(layer "F.Cu")
		(net "SMB_BIC_I2C6_MUX_CLK_R_SCL")
	)
	(via
		(at 400.91868 -85.930486)
		(size 0.508)
		(drill 0.254)
		(layers "F.Cu" "B.Cu")
		(net "SMB_BIC_I2C6_MUX_CLK_R_SCL")
	)
	(via
		(at 394.69314 -84.276692)
		(size 0.508)
		(drill 0.254)
		(layers "F.Cu" "B.Cu")
		(net "SMB_BIC_I2C6_MUX_CLK_R_SCL")
	)
	(segment
		(start 402.70049 -85.797898)
		(end 401.873974 -85.797898)
		(width 0.13208)
		(layer "B.Cu")
		(net "SMB_BIC_I2C6_MUX_CLK_R_SCL")
	)
	(segment
		(start 401.741386 -85.930486)
		(end 400.91868 -85.930486)
		(width 0.13208)
		(layer "B.Cu")
		(net "SMB_BIC_I2C6_MUX_CLK_R_SCL")
	)
	(segment
		(start 401.873974 -85.797898)
		(end 401.741386 -85.930486)
		(width 0.13208)
		(layer "B.Cu")
		(net "SMB_BIC_I2C6_MUX_CLK_R_SCL")
	)
	(segment
		(start 395.060678 -84.924392)
		(end 394.69314 -84.556854)
		(width 0.15494)
		(layer "In13.Cu")
		(net "SMB_BIC_I2C6_MUX_CLK_R_SCL")
	)
	(segment
		(start 400.466814 -85.47862)
		(end 396.155418 -85.47862)
		(width 0.15494)
		(layer "In13.Cu")
		(net "SMB_BIC_I2C6_MUX_CLK_R_SCL")
	)
	(segment
		(start 395.60119 -84.924392)
		(end 395.060678 -84.924392)
		(width 0.15494)
		(layer "In13.Cu")
		(net "SMB_BIC_I2C6_MUX_CLK_R_SCL")
	)
	(segment
		(start 394.69314 -84.556854)
		(end 394.69314 -84.276692)
		(width 0.15494)
		(layer "In13.Cu")
		(net "SMB_BIC_I2C6_MUX_CLK_R_SCL")
	)
	(segment
		(start 396.155418 -85.47862)
		(end 395.60119 -84.924392)
		(width 0.15494)
		(layer "In13.Cu")
		(net "SMB_BIC_I2C6_MUX_CLK_R_SCL")
	)
	(segment
		(start 400.91868 -85.930486)
		(end 400.466814 -85.47862)
		(width 0.15494)
		(layer "In13.Cu")
		(net "SMB_BIC_I2C6_MUX_CLK_R_SCL")
	)
	(segment
		(start 93.57106 -397.461232)
		(end 92.651326 -398.380966)
		(width 0.1651)
		(layer "In15.Cu")
		(net "CLK_100M_GPU_FPGA_REF_DN")
	)
	(segment
		(start 92.651326 -398.380966)
		(end 91.786202 -398.380966)
		(width 0.1651)
		(layer "In15.Cu")
		(net "CLK_100M_GPU_FPGA_REF_DN")
	)
	(segment
		(start 90.99931 -393.7254)
		(end 91.698318 -393.957302)
		(width 0.1651)
		(layer "In15.Cu")
		(net "CLK_100M_GPU_FPGA_REF_DN")
	)
	(segment
		(start 47.709836 -394.517118)
		(end 51.75377 -392.842242)
		(width 0.1651)
		(layer "In15.Cu")
		(net "CLK_100M_GPU_FPGA_REF_DN")
	)
	(segment
		(start 93.208094 -395.467332)
		(end 93.57106 -396.343632)
		(width 0.1651)
		(layer "In15.Cu")
		(net "CLK_100M_GPU_FPGA_REF_DN")
	)
	(segment
		(start 51.75377 -392.842242)
		(end 88.32342 -393.7254)
		(width 0.1651)
		(layer "In15.Cu")
		(net "CLK_100M_GPU_FPGA_REF_DN")
	)
	(segment
		(start 93.57106 -396.343632)
		(end 93.57106 -397.461232)
		(width 0.1651)
		(layer "In15.Cu")
		(net "CLK_100M_GPU_FPGA_REF_DN")
	)
	(segment
		(start 91.786202 -398.380966)
		(end 91.710002 -398.457166)
		(width 0.1651)
		(layer "In15.Cu")
		(net "CLK_100M_GPU_FPGA_REF_DN")
	)
	(segment
		(start 88.32342 -393.7254)
		(end 90.99931 -393.7254)
		(width 0.1651)
		(layer "In15.Cu")
		(net "CLK_100M_GPU_FPGA_REF_DN")
	)
	(segment
		(start 47.58309 -398.38122)
		(end 46.914308 -398.38122)
		(width 0.1651)
		(layer "In15.Cu")
		(net "CLK_100M_GPU_FPGA_REF_DN")
	)
	(segment
		(start 46.5201 -395.706854)
		(end 47.709836 -394.517118)
		(width 0.1651)
		(layer "In15.Cu")
		(net "CLK_100M_GPU_FPGA_REF_DN")
	)
	(segment
		(start 46.914308 -398.38122)
		(end 46.5201 -397.987012)
		(width 0.1651)
		(layer "In15.Cu")
		(net "CLK_100M_GPU_FPGA_REF_DN")
	)
	(segment
		(start 91.698318 -393.957302)
		(end 93.208094 -395.467332)
		(width 0.1651)
		(layer "In15.Cu")
		(net "CLK_100M_GPU_FPGA_REF_DN")
	)
	(segment
		(start 47.71009 -398.50822)
		(end 47.58309 -398.38122)
		(width 0.1651)
		(layer "In15.Cu")
		(net "CLK_100M_GPU_FPGA_REF_DN")
	)
	(segment
		(start 47.71009 -398.890236)
		(end 47.71009 -398.50822)
		(width 0.1651)
		(layer "In15.Cu")
		(net "CLK_100M_GPU_FPGA_REF_DN")
	)
	(segment
		(start 91.710002 -398.457166)
		(end 91.710002 -398.890236)
		(width 0.1651)
		(layer "In15.Cu")
		(net "CLK_100M_GPU_FPGA_REF_DN")
	)
	(segment
		(start 46.5201 -397.987012)
		(end 46.5201 -395.706854)
		(width 0.1651)
		(layer "In15.Cu")
		(net "CLK_100M_GPU_FPGA_REF_DN")
	)
	(segment
		(start 232.46969 -82.918808)
		(end 232.693972 -82.918808)
		(width 0.13462)
		(layer "F.Cu")
		(net "USB2_FT4232_SDB_R_DN")
	)
	(segment
		(start 232.693972 -82.918808)
		(end 233.142028 -83.366864)
		(width 0.13462)
		(layer "F.Cu")
		(net "USB2_FT4232_SDB_R_DN")
	)
	(segment
		(start 233.627422 -89.42324)
		(end 233.520996 -89.529666)
		(width 0.13462)
		(layer "F.Cu")
		(net "USB2_FT4232_SDB_R_DN")
	)
	(segment
		(start 232.975404 -87.973916)
		(end 233.627422 -88.625934)
		(width 0.13462)
		(layer "F.Cu")
		(net "USB2_FT4232_SDB_R_DN")
	)
	(segment
		(start 233.627422 -88.625934)
		(end 233.627422 -89.42324)
		(width 0.13462)
		(layer "F.Cu")
		(net "USB2_FT4232_SDB_R_DN")
	)
	(segment
		(start 232.975404 -87.737188)
		(end 232.975404 -87.973916)
		(width 0.13462)
		(layer "F.Cu")
		(net "USB2_FT4232_SDB_R_DN")
	)
	(segment
		(start 233.520996 -89.529666)
		(end 233.520996 -89.85377)
		(width 0.13462)
		(layer "F.Cu")
		(net "USB2_FT4232_SDB_R_DN")
	)
	(segment
		(start 233.520996 -89.85377)
		(end 233.52125 -89.854024)
		(width 0.13462)
		(layer "F.Cu")
		(net "USB2_FT4232_SDB_R_DN")
	)
	(segment
		(start 232.652316 -87.4141)
		(end 232.975404 -87.737188)
		(width 0.13462)
		(layer "F.Cu")
		(net "USB2_FT4232_SDB_R_DN")
	)
	(segment
		(start 236.7534 -83.05419)
		(end 237.1725 -82.63509)
		(width 0.1651)
		(layer "In15.Cu")
		(net "USB2_FT4232_SDB_R_DN")
	)
	(segment
		(start 232.939336 -86.983062)
		(end 232.939336 -87.12708)
		(width 0.1651)
		(layer "In15.Cu")
		(net "USB2_FT4232_SDB_R_DN")
	)
	(segment
		(start 232.939336 -87.12708)
		(end 232.652316 -87.4141)
		(width 0.1651)
		(layer "In15.Cu")
		(net "USB2_FT4232_SDB_R_DN")
	)
	(segment
		(start 232.798874 -86.8426)
		(end 232.939336 -86.983062)
		(width 0.1651)
		(layer "In15.Cu")
		(net "USB2_FT4232_SDB_R_DN")
	)
	(segment
		(start 229.77856 -80.55356)
		(end 229.48646 -80.84566)
		(width 0.1651)
		(layer "In15.Cu")
		(net "USB2_FT4232_SDB_R_DN")
	)
	(segment
		(start 229.77856 -86.8426)
		(end 232.798874 -86.8426)
		(width 0.1651)
		(layer "In15.Cu")
		(net "USB2_FT4232_SDB_R_DN")
	)
	(segment
		(start 229.48646 -86.5505)
		(end 229.77856 -86.8426)
		(width 0.1651)
		(layer "In15.Cu")
		(net "USB2_FT4232_SDB_R_DN")
	)
	(segment
		(start 237.1725 -82.63509)
		(end 237.1725 -80.884014)
		(width 0.1651)
		(layer "In15.Cu")
		(net "USB2_FT4232_SDB_R_DN")
	)
	(segment
		(start 233.454702 -83.05419)
		(end 236.7534 -83.05419)
		(width 0.1651)
		(layer "In15.Cu")
		(net "USB2_FT4232_SDB_R_DN")
	)
	(segment
		(start 236.842046 -80.55356)
		(end 229.77856 -80.55356)
		(width 0.1651)
		(layer "In15.Cu")
		(net "USB2_FT4232_SDB_R_DN")
	)
	(segment
		(start 229.48646 -80.84566)
		(end 229.48646 -86.5505)
		(width 0.1651)
		(layer "In15.Cu")
		(net "USB2_FT4232_SDB_R_DN")
	)
	(segment
		(start 237.1725 -80.884014)
		(end 236.842046 -80.55356)
		(width 0.1651)
		(layer "In15.Cu")
		(net "USB2_FT4232_SDB_R_DN")
	)
	(segment
		(start 233.142028 -83.366864)
		(end 233.454702 -83.05419)
		(width 0.1651)
		(layer "In15.Cu")
		(net "USB2_FT4232_SDB_R_DN")
	)
	(segment
		(start 134.23392 -173.376082)
		(end 134.23392 -171.376848)
		(width 0.13462)
		(layer "F.Cu")
		(net "CLK_100M_DB2000QL_NIC0_DN")
	)
	(segment
		(start 134.23392 -171.376848)
		(end 134.610856 -170.999912)
		(width 0.13462)
		(layer "F.Cu")
		(net "CLK_100M_DB2000QL_NIC0_DN")
	)
	(segment
		(start 134.366 -174.79518)
		(end 134.366 -173.508162)
		(width 0.13462)
		(layer "F.Cu")
		(net "CLK_100M_DB2000QL_NIC0_DN")
	)
	(segment
		(start 134.471156 -174.900336)
		(end 134.366 -174.79518)
		(width 0.13462)
		(layer "F.Cu")
		(net "CLK_100M_DB2000QL_NIC0_DN")
	)
	(segment
		(start 134.366 -173.508162)
		(end 134.23392 -173.376082)
		(width 0.13462)
		(layer "F.Cu")
		(net "CLK_100M_DB2000QL_NIC0_DN")
	)
	(segment
		(start 23.30831 -259.295392)
		(end 23.224744 -259.378958)
		(width 0.13208)
		(layer "F.Cu")
		(net "PEX0_SYS_ERR_N_G")
	)
	(segment
		(start 23.128478 -259.475224)
		(end 23.128478 -260.407658)
		(width 0.13208)
		(layer "F.Cu")
		(net "PEX0_SYS_ERR_N_G")
	)
	(segment
		(start 23.875492 -257.73126)
		(end 23.875492 -257.22326)
		(width 0.13208)
		(layer "F.Cu")
		(net "PEX0_SYS_ERR_N_G")
	)
	(segment
		(start 23.224744 -259.378958)
		(end 23.128478 -259.475224)
		(width 0.13208)
		(layer "F.Cu")
		(net "PEX0_SYS_ERR_N_G")
	)
	(segment
		(start 23.754588 -257.852164)
		(end 23.875492 -257.73126)
		(width 0.13208)
		(layer "F.Cu")
		(net "PEX0_SYS_ERR_N_G")
	)
	(segment
		(start 23.30831 -257.852164)
		(end 23.754588 -257.852164)
		(width 0.13208)
		(layer "F.Cu")
		(net "PEX0_SYS_ERR_N_G")
	)
	(segment
		(start 23.875492 -257.22326)
		(end 23.754334 -257.102102)
		(width 0.13208)
		(layer "F.Cu")
		(net "PEX0_SYS_ERR_N_G")
	)
	(segment
		(start 23.30831 -258.649978)
		(end 23.30831 -259.295392)
		(width 0.13208)
		(layer "F.Cu")
		(net "PEX0_SYS_ERR_N_G")
	)
	(segment
		(start 23.30831 -257.852164)
		(end 23.30831 -258.649978)
		(width 0.13208)
		(layer "F.Cu")
		(net "PEX0_SYS_ERR_N_G")
	)
	(segment
		(start 23.754334 -257.102102)
		(end 23.30831 -257.102102)
		(width 0.13208)
		(layer "F.Cu")
		(net "PEX0_SYS_ERR_N_G")
	)
	(via
		(at 23.30831 -258.649978)
		(size 0.508)
		(drill 0.254)
		(layers "F.Cu" "B.Cu")
		(net "PEX0_SYS_ERR_N_G")
	)
	(segment
		(start 140.126466 -19.453098)
		(end 140.168122 -19.453098)
		(width 0.13208)
		(layer "F.Cu")
		(net "SMB_ISO_SSD4_SDA")
	)
	(segment
		(start 140.168122 -19.453098)
		(end 142.116302 -19.453098)
		(width 0.13208)
		(layer "F.Cu")
		(net "SMB_ISO_SSD4_SDA")
	)
	(segment
		(start 139.356592 -20.467574)
		(end 139.356592 -20.222972)
		(width 0.13208)
		(layer "F.Cu")
		(net "SMB_ISO_SSD4_SDA")
	)
	(segment
		(start 139.356592 -20.222972)
		(end 140.126466 -19.453098)
		(width 0.13208)
		(layer "F.Cu")
		(net "SMB_ISO_SSD4_SDA")
	)
	(segment
		(start 142.116302 -19.453098)
		(end 143.035782 -18.533618)
		(width 0.13208)
		(layer "F.Cu")
		(net "SMB_ISO_SSD4_SDA")
	)
	(segment
		(start 143.035782 -16.439388)
		(end 143.111982 -16.363188)
		(width 0.13208)
		(layer "F.Cu")
		(net "SMB_ISO_SSD4_SDA")
	)
	(segment
		(start 143.111982 -16.363188)
		(end 143.111982 -15.351252)
		(width 0.13208)
		(layer "F.Cu")
		(net "SMB_ISO_SSD4_SDA")
	)
	(segment
		(start 143.035782 -18.533618)
		(end 143.035782 -16.439388)
		(width 0.13208)
		(layer "F.Cu")
		(net "SMB_ISO_SSD4_SDA")
	)
	(segment
		(start 143.562578 -23.337266)
		(end 143.562578 -23.946866)
		(width 0.13208)
		(layer "F.Cu")
		(net "SMB_ISO_SSD4_SDA")
	)
	(via
		(at 143.111982 -15.351252)
		(size 0.508)
		(drill 0.254)
		(layers "F.Cu" "B.Cu")
		(net "SMB_ISO_SSD4_SDA")
	)
	(via
		(at 143.562578 -23.946866)
		(size 0.508)
		(drill 0.254)
		(layers "F.Cu" "B.Cu")
		(net "SMB_ISO_SSD4_SDA")
	)
	(segment
		(start 143.111982 -15.420594)
		(end 143.111982 -15.351252)
		(width 0.13208)
		(layer "B.Cu")
		(net "SMB_ISO_SSD4_SDA")
	)
	(segment
		(start 145.173954 -22.33549)
		(end 145.173954 -17.482566)
		(width 0.13208)
		(layer "B.Cu")
		(net "SMB_ISO_SSD4_SDA")
	)
	(segment
		(start 145.173954 -17.482566)
		(end 143.111982 -15.420594)
		(width 0.13208)
		(layer "B.Cu")
		(net "SMB_ISO_SSD4_SDA")
	)
	(segment
		(start 143.562578 -23.946866)
		(end 145.173954 -22.33549)
		(width 0.13208)
		(layer "B.Cu")
		(net "SMB_ISO_SSD4_SDA")
	)
	(segment
		(start 280.858214 -18.44421)
		(end 280.865326 -18.437098)
		(width 0.13208)
		(layer "F.Cu")
		(net "SMB_ISO_SSD9_R_SCL")
	)
	(segment
		(start 268.864842 -22.3901)
		(end 270.66748 -22.3901)
		(width 0.13208)
		(layer "F.Cu")
		(net "SMB_ISO_SSD9_R_SCL")
	)
	(segment
		(start 270.66748 -22.3901)
		(end 271.29359 -23.01621)
		(width 0.13208)
		(layer "F.Cu")
		(net "SMB_ISO_SSD9_R_SCL")
	)
	(segment
		(start 280.865326 -18.437098)
		(end 281.467814 -18.437098)
		(width 0.13208)
		(layer "F.Cu")
		(net "SMB_ISO_SSD9_R_SCL")
	)
	(via
		(at 280.858214 -18.44421)
		(size 0.508)
		(drill 0.254)
		(layers "F.Cu" "B.Cu")
		(net "SMB_ISO_SSD9_R_SCL")
	)
	(via
		(at 271.29359 -23.01621)
		(size 0.508)
		(drill 0.254)
		(layers "F.Cu" "B.Cu")
		(net "SMB_ISO_SSD9_R_SCL")
	)
	(segment
		(start 279.8826 -23.01621)
		(end 271.29359 -23.01621)
		(width 0.15494)
		(layer "In5.Cu")
		(net "SMB_ISO_SSD9_R_SCL")
	)
	(segment
		(start 280.858214 -18.44421)
		(end 281.42692 -19.012916)
		(width 0.15494)
		(layer "In5.Cu")
		(net "SMB_ISO_SSD9_R_SCL")
	)
	(segment
		(start 281.42692 -19.012916)
		(end 281.42692 -21.47189)
		(width 0.15494)
		(layer "In5.Cu")
		(net "SMB_ISO_SSD9_R_SCL")
	)
	(segment
		(start 281.42692 -21.47189)
		(end 279.8826 -23.01621)
		(width 0.15494)
		(layer "In5.Cu")
		(net "SMB_ISO_SSD9_R_SCL")
	)
	(segment
		(start 401.938998 -86.580726)
		(end 401.19427 -86.580726)
		(width 0.13208)
		(layer "F.Cu")
		(net "SMB_BIC_I2C6_MUX_CLK_R_SDA")
	)
	(segment
		(start 395.099032 -82.642202)
		(end 395.809216 -82.642202)
		(width 0.13208)
		(layer "F.Cu")
		(net "SMB_BIC_I2C6_MUX_CLK_R_SDA")
	)
	(segment
		(start 394.597636 -83.143598)
		(end 395.099032 -82.642202)
		(width 0.13208)
		(layer "F.Cu")
		(net "SMB_BIC_I2C6_MUX_CLK_R_SDA")
	)
	(segment
		(start 401.19427 -86.580726)
		(end 400.961098 -86.813898)
		(width 0.13208)
		(layer "F.Cu")
		(net "SMB_BIC_I2C6_MUX_CLK_R_SDA")
	)
	(segment
		(start 394.069316 -82.642202)
		(end 394.09624 -82.642202)
		(width 0.13208)
		(layer "F.Cu")
		(net "SMB_BIC_I2C6_MUX_CLK_R_SDA")
	)
	(segment
		(start 394.09624 -82.642202)
		(end 394.597636 -83.143598)
		(width 0.13208)
		(layer "F.Cu")
		(net "SMB_BIC_I2C6_MUX_CLK_R_SDA")
	)
	(via
		(at 394.597636 -83.143598)
		(size 0.508)
		(drill 0.254)
		(layers "F.Cu" "B.Cu")
		(net "SMB_BIC_I2C6_MUX_CLK_R_SDA")
	)
	(via
		(at 400.961098 -86.813898)
		(size 0.508)
		(drill 0.254)
		(layers "F.Cu" "B.Cu")
		(net "SMB_BIC_I2C6_MUX_CLK_R_SDA")
	)
	(segment
		(start 402.70049 -86.813898)
		(end 400.961098 -86.813898)
		(width 0.13208)
		(layer "B.Cu")
		(net "SMB_BIC_I2C6_MUX_CLK_R_SDA")
	)
	(segment
		(start 400.19986 -84.109306)
		(end 398.488408 -84.109306)
		(width 0.15494)
		(layer "In13.Cu")
		(net "SMB_BIC_I2C6_MUX_CLK_R_SDA")
	)
	(segment
		(start 398.488408 -84.109306)
		(end 398.220946 -84.376768)
		(width 0.15494)
		(layer "In13.Cu")
		(net "SMB_BIC_I2C6_MUX_CLK_R_SDA")
	)
	(segment
		(start 398.220946 -84.376768)
		(end 396.317724 -84.376768)
		(width 0.15494)
		(layer "In13.Cu")
		(net "SMB_BIC_I2C6_MUX_CLK_R_SDA")
	)
	(segment
		(start 401.413726 -86.36127)
		(end 401.413726 -85.323172)
		(width 0.15494)
		(layer "In13.Cu")
		(net "SMB_BIC_I2C6_MUX_CLK_R_SDA")
	)
	(segment
		(start 401.413726 -85.323172)
		(end 400.19986 -84.109306)
		(width 0.15494)
		(layer "In13.Cu")
		(net "SMB_BIC_I2C6_MUX_CLK_R_SDA")
	)
	(segment
		(start 394.871448 -83.789012)
		(end 394.597636 -83.5152)
		(width 0.15494)
		(layer "In13.Cu")
		(net "SMB_BIC_I2C6_MUX_CLK_R_SDA")
	)
	(segment
		(start 394.597636 -83.5152)
		(end 394.597636 -83.143598)
		(width 0.15494)
		(layer "In13.Cu")
		(net "SMB_BIC_I2C6_MUX_CLK_R_SDA")
	)
	(segment
		(start 396.317724 -84.376768)
		(end 395.729968 -83.789012)
		(width 0.15494)
		(layer "In13.Cu")
		(net "SMB_BIC_I2C6_MUX_CLK_R_SDA")
	)
	(segment
		(start 400.961098 -86.813898)
		(end 401.413726 -86.36127)
		(width 0.15494)
		(layer "In13.Cu")
		(net "SMB_BIC_I2C6_MUX_CLK_R_SDA")
	)
	(segment
		(start 395.729968 -83.789012)
		(end 394.871448 -83.789012)
		(width 0.15494)
		(layer "In13.Cu")
		(net "SMB_BIC_I2C6_MUX_CLK_R_SDA")
	)
	(segment
		(start 279.101042 -401.019772)
		(end 279.101042 -400.000978)
		(width 0.13208)
		(layer "F.Cu")
		(net "RST_MB_BIC_ISO_N")
	)
	(segment
		(start 279.520904 -401.42922)
		(end 279.520904 -401.146772)
		(width 0.13208)
		(layer "F.Cu")
		(net "RST_MB_BIC_ISO_N")
	)
	(segment
		(start 279.459182 -401.490942)
		(end 279.520904 -401.42922)
		(width 0.13208)
		(layer "F.Cu")
		(net "RST_MB_BIC_ISO_N")
	)
	(segment
		(start 279.459182 -401.937982)
		(end 279.459182 -401.490942)
		(width 0.13208)
		(layer "F.Cu")
		(net "RST_MB_BIC_ISO_N")
	)
	(segment
		(start 279.228042 -401.146772)
		(end 279.101042 -401.019772)
		(width 0.13208)
		(layer "F.Cu")
		(net "RST_MB_BIC_ISO_N")
	)
	(segment
		(start 279.520904 -401.146772)
		(end 279.228042 -401.146772)
		(width 0.13208)
		(layer "F.Cu")
		(net "RST_MB_BIC_ISO_N")
	)
	(via
		(at 279.520904 -401.146772)
		(size 0.508)
		(drill 0.254)
		(layers "F.Cu" "B.Cu")
		(net "RST_MB_BIC_ISO_N")
	)
	(segment
		(start 348.493842 -225.587052)
		(end 348.893892 -225.987102)
		(width 0.13208)
		(layer "F.Cu")
		(net "RST_NIC0_PERST_N")
	)
	(via
		(at 349.885 -229.616)
		(size 0.6604)
		(drill 0.3302)
		(layers "F.Cu" "B.Cu")
		(net "RST_NIC0_PERST_N")
	)
	(via
		(at 348.893892 -225.987102)
		(size 0.4572)
		(drill 0.254)
		(layers "F.Cu" "B.Cu")
		(net "RST_NIC0_PERST_N")
	)
	(segment
		(start 350.139 -228.473)
		(end 349.293688 -227.627688)
		(width 0.13208)
		(layer "B.Cu")
		(net "RST_NIC0_PERST_N")
	)
	(segment
		(start 350.139 -229.00259)
		(end 350.139 -228.473)
		(width 0.13208)
		(layer "B.Cu")
		(net "RST_NIC0_PERST_N")
	)
	(segment
		(start 349.885 -232.39095)
		(end 349.885 -229.616)
		(width 0.13208)
		(layer "B.Cu")
		(net "RST_NIC0_PERST_N")
	)
	(segment
		(start 349.293688 -227.627688)
		(end 349.293688 -227.2284)
		(width 0.13208)
		(layer "B.Cu")
		(net "RST_NIC0_PERST_N")
	)
	(segment
		(start 349.123 -233.15295)
		(end 349.885 -232.39095)
		(width 0.13208)
		(layer "B.Cu")
		(net "RST_NIC0_PERST_N")
	)
	(segment
		(start 349.293688 -226.386898)
		(end 348.893892 -225.987102)
		(width 0.0889)
		(layer "B.Cu")
		(net "RST_NIC0_PERST_N")
	)
	(segment
		(start 349.293688 -227.2284)
		(end 349.293688 -226.386898)
		(width 0.0889)
		(layer "B.Cu")
		(net "RST_NIC0_PERST_N")
	)
	(segment
		(start 349.885 -229.616)
		(end 350.139 -229.00259)
		(width 0.13208)
		(layer "B.Cu")
		(net "RST_NIC0_PERST_N")
	)
	(segment
		(start 139.306808 -199.86244)
		(end 139.171426 -199.727058)
		(width 0.13462)
		(layer "F.Cu")
		(net "USB2_FT4232_CLI_DP")
	)
	(segment
		(start 239.721898 -86.101682)
		(end 239.721898 -85.551518)
		(width 0.13462)
		(layer "F.Cu")
		(net "USB2_FT4232_CLI_DP")
	)
	(segment
		(start 139.306808 -200.489058)
		(end 139.306808 -199.86244)
		(width 0.13462)
		(layer "F.Cu")
		(net "USB2_FT4232_CLI_DP")
	)
	(segment
		(start 239.141 -87.671402)
		(end 239.141 -86.68258)
		(width 0.13462)
		(layer "F.Cu")
		(net "USB2_FT4232_CLI_DP")
	)
	(segment
		(start 139.171426 -199.727058)
		(end 139.171426 -198.843646)
		(width 0.13462)
		(layer "F.Cu")
		(net "USB2_FT4232_CLI_DP")
	)
	(segment
		(start 239.4458 -87.976202)
		(end 239.141 -87.671402)
		(width 0.13462)
		(layer "F.Cu")
		(net "USB2_FT4232_CLI_DP")
	)
	(segment
		(start 139.171426 -198.843646)
		(end 139.488672 -198.5264)
		(width 0.13462)
		(layer "F.Cu")
		(net "USB2_FT4232_CLI_DP")
	)
	(segment
		(start 239.141 -86.68258)
		(end 239.721898 -86.101682)
		(width 0.13462)
		(layer "F.Cu")
		(net "USB2_FT4232_CLI_DP")
	)
	(segment
		(start 230.0732 -87.1474)
		(end 224.6122 -87.1474)
		(width 0.1651)
		(layer "In9.Cu")
		(net "USB2_FT4232_CLI_DP")
	)
	(segment
		(start 137.983468 -165.556184)
		(end 140.589 -171.846748)
		(width 0.1651)
		(layer "In9.Cu")
		(net "USB2_FT4232_CLI_DP")
	)
	(segment
		(start 238.7854 -89.2302)
		(end 236.855 -89.2302)
		(width 0.1651)
		(layer "In9.Cu")
		(net "USB2_FT4232_CLI_DP")
	)
	(segment
		(start 239.15497 -88.86063)
		(end 238.7854 -89.2302)
		(width 0.1651)
		(layer "In9.Cu")
		(net "USB2_FT4232_CLI_DP")
	)
	(segment
		(start 129.8956 -108.331)
		(end 121.92 -116.3066)
		(width 0.1651)
		(layer "In9.Cu")
		(net "USB2_FT4232_CLI_DP")
	)
	(segment
		(start 202.305158 -91.9226)
		(end 150.9522 -91.9226)
		(width 0.1651)
		(layer "In9.Cu")
		(net "USB2_FT4232_CLI_DP")
	)
	(segment
		(start 121.4882 -132.588)
		(end 121.4882 -140.6652)
		(width 0.1651)
		(layer "In9.Cu")
		(net "USB2_FT4232_CLI_DP")
	)
	(segment
		(start 236.855 -89.2302)
		(end 235.9152 -90.17)
		(width 0.1651)
		(layer "In9.Cu")
		(net "USB2_FT4232_CLI_DP")
	)
	(segment
		(start 140.589 -191.4398)
		(end 141.5034 -192.3542)
		(width 0.1651)
		(layer "In9.Cu")
		(net "USB2_FT4232_CLI_DP")
	)
	(segment
		(start 207.701896 -89.6874)
		(end 202.305158 -91.9226)
		(width 0.1651)
		(layer "In9.Cu")
		(net "USB2_FT4232_CLI_DP")
	)
	(segment
		(start 139.197842 -197.707758)
		(end 139.197842 -198.23557)
		(width 0.1651)
		(layer "In9.Cu")
		(net "USB2_FT4232_CLI_DP")
	)
	(segment
		(start 235.9152 -90.17)
		(end 233.0958 -90.17)
		(width 0.1651)
		(layer "In9.Cu")
		(net "USB2_FT4232_CLI_DP")
	)
	(segment
		(start 139.197842 -198.23557)
		(end 139.488672 -198.5264)
		(width 0.1651)
		(layer "In9.Cu")
		(net "USB2_FT4232_CLI_DP")
	)
	(segment
		(start 222.4786 -89.281)
		(end 212.0392 -89.281)
		(width 0.1651)
		(layer "In9.Cu")
		(net "USB2_FT4232_CLI_DP")
	)
	(segment
		(start 150.9522 -91.9226)
		(end 134.5438 -108.331)
		(width 0.1651)
		(layer "In9.Cu")
		(net "USB2_FT4232_CLI_DP")
	)
	(segment
		(start 121.92 -132.1562)
		(end 121.4882 -132.588)
		(width 0.1651)
		(layer "In9.Cu")
		(net "USB2_FT4232_CLI_DP")
	)
	(segment
		(start 211.6328 -89.6874)
		(end 207.701896 -89.6874)
		(width 0.1651)
		(layer "In9.Cu")
		(net "USB2_FT4232_CLI_DP")
	)
	(segment
		(start 134.5438 -108.331)
		(end 129.8956 -108.331)
		(width 0.1651)
		(layer "In9.Cu")
		(net "USB2_FT4232_CLI_DP")
	)
	(segment
		(start 121.4882 -140.6652)
		(end 121.8946 -141.0716)
		(width 0.1651)
		(layer "In9.Cu")
		(net "USB2_FT4232_CLI_DP")
	)
	(segment
		(start 239.4458 -87.976202)
		(end 239.15497 -88.267032)
		(width 0.1651)
		(layer "In9.Cu")
		(net "USB2_FT4232_CLI_DP")
	)
	(segment
		(start 121.8946 -161.29)
		(end 125.3236 -164.719)
		(width 0.1651)
		(layer "In9.Cu")
		(net "USB2_FT4232_CLI_DP")
	)
	(segment
		(start 141.5034 -195.4022)
		(end 139.197842 -197.707758)
		(width 0.1651)
		(layer "In9.Cu")
		(net "USB2_FT4232_CLI_DP")
	)
	(segment
		(start 224.6122 -87.1474)
		(end 222.4786 -89.281)
		(width 0.1651)
		(layer "In9.Cu")
		(net "USB2_FT4232_CLI_DP")
	)
	(segment
		(start 141.5034 -192.3542)
		(end 141.5034 -195.4022)
		(width 0.1651)
		(layer "In9.Cu")
		(net "USB2_FT4232_CLI_DP")
	)
	(segment
		(start 140.589 -171.846748)
		(end 140.589 -191.4398)
		(width 0.1651)
		(layer "In9.Cu")
		(net "USB2_FT4232_CLI_DP")
	)
	(segment
		(start 121.92 -116.3066)
		(end 121.92 -132.1562)
		(width 0.1651)
		(layer "In9.Cu")
		(net "USB2_FT4232_CLI_DP")
	)
	(segment
		(start 239.15497 -88.267032)
		(end 239.15497 -88.86063)
		(width 0.1651)
		(layer "In9.Cu")
		(net "USB2_FT4232_CLI_DP")
	)
	(segment
		(start 125.3236 -164.719)
		(end 136.730232 -164.719)
		(width 0.1651)
		(layer "In9.Cu")
		(net "USB2_FT4232_CLI_DP")
	)
	(segment
		(start 233.0958 -90.17)
		(end 230.0732 -87.1474)
		(width 0.1651)
		(layer "In9.Cu")
		(net "USB2_FT4232_CLI_DP")
	)
	(segment
		(start 212.0392 -89.281)
		(end 211.6328 -89.6874)
		(width 0.1651)
		(layer "In9.Cu")
		(net "USB2_FT4232_CLI_DP")
	)
	(segment
		(start 121.8946 -141.0716)
		(end 121.8946 -161.29)
		(width 0.1651)
		(layer "In9.Cu")
		(net "USB2_FT4232_CLI_DP")
	)
	(segment
		(start 136.730232 -164.719)
		(end 137.983468 -165.556184)
		(width 0.1651)
		(layer "In9.Cu")
		(net "USB2_FT4232_CLI_DP")
	)
	(segment
		(start 22.492462 -254.850646)
		(end 22.258528 -255.08458)
		(width 0.13208)
		(layer "F.Cu")
		(net "PEX0_SYS_ERR_3V3_N")
	)
	(segment
		(start 23.027132 -254.850646)
		(end 22.492462 -254.850646)
		(width 0.13208)
		(layer "F.Cu")
		(net "PEX0_SYS_ERR_3V3_N")
	)
	(segment
		(start 21.909278 -256.259838)
		(end 21.600668 -256.259838)
		(width 0.13208)
		(layer "F.Cu")
		(net "PEX0_SYS_ERR_3V3_N")
	)
	(segment
		(start 22.258528 -255.910588)
		(end 21.909278 -256.259838)
		(width 0.13208)
		(layer "F.Cu")
		(net "PEX0_SYS_ERR_3V3_N")
	)
	(segment
		(start 22.258528 -255.08458)
		(end 22.258528 -255.910588)
		(width 0.13208)
		(layer "F.Cu")
		(net "PEX0_SYS_ERR_3V3_N")
	)
	(segment
		(start 21.600668 -256.259838)
		(end 21.508466 -256.35204)
		(width 0.13208)
		(layer "F.Cu")
		(net "PEX0_SYS_ERR_3V3_N")
	)
	(via
		(at 22.258528 -255.910588)
		(size 0.508)
		(drill 0.254)
		(layers "F.Cu" "B.Cu")
		(net "PEX0_SYS_ERR_3V3_N")
	)
	(segment
		(start 142.385542 -16.439388)
		(end 142.385542 -18.421858)
		(width 0.13208)
		(layer "F.Cu")
		(net "SMB_ISO_SSD4_SCL")
	)
	(segment
		(start 142.559532 -23.355554)
		(end 142.559532 -23.965154)
		(width 0.13208)
		(layer "F.Cu")
		(net "SMB_ISO_SSD4_SCL")
	)
	(segment
		(start 139.356592 -17.669256)
		(end 140.124434 -18.437098)
		(width 0.13208)
		(layer "F.Cu")
		(net "SMB_ISO_SSD4_SCL")
	)
	(segment
		(start 142.385542 -16.439388)
		(end 142.385542 -15.370302)
		(width 0.13208)
		(layer "F.Cu")
		(net "SMB_ISO_SSD4_SCL")
	)
	(segment
		(start 140.124434 -18.437098)
		(end 140.168122 -18.437098)
		(width 0.13208)
		(layer "F.Cu")
		(net "SMB_ISO_SSD4_SCL")
	)
	(segment
		(start 140.721842 -18.990818)
		(end 140.168122 -18.437098)
		(width 0.13208)
		(layer "F.Cu")
		(net "SMB_ISO_SSD4_SCL")
	)
	(segment
		(start 141.816582 -18.990818)
		(end 140.721842 -18.990818)
		(width 0.13208)
		(layer "F.Cu")
		(net "SMB_ISO_SSD4_SCL")
	)
	(segment
		(start 142.385542 -18.421858)
		(end 141.816582 -18.990818)
		(width 0.13208)
		(layer "F.Cu")
		(net "SMB_ISO_SSD4_SCL")
	)
	(segment
		(start 139.356592 -17.419574)
		(end 139.356592 -17.669256)
		(width 0.13208)
		(layer "F.Cu")
		(net "SMB_ISO_SSD4_SCL")
	)
	(via
		(at 142.385542 -15.370302)
		(size 0.508)
		(drill 0.254)
		(layers "F.Cu" "B.Cu")
		(net "SMB_ISO_SSD4_SCL")
	)
	(via
		(at 142.559532 -23.965154)
		(size 0.508)
		(drill 0.254)
		(layers "F.Cu" "B.Cu")
		(net "SMB_ISO_SSD4_SCL")
	)
	(segment
		(start 143.863568 -16.848328)
		(end 143.863568 -22.661118)
		(width 0.13208)
		(layer "B.Cu")
		(net "SMB_ISO_SSD4_SCL")
	)
	(segment
		(start 142.385542 -15.370302)
		(end 143.863568 -16.848328)
		(width 0.13208)
		(layer "B.Cu")
		(net "SMB_ISO_SSD4_SCL")
	)
	(segment
		(start 143.863568 -22.661118)
		(end 142.559532 -23.965154)
		(width 0.13208)
		(layer "B.Cu")
		(net "SMB_ISO_SSD4_SCL")
	)
	(segment
		(start 412.767526 -22.3901)
		(end 413.393636 -23.01621)
		(width 0.13208)
		(layer "F.Cu")
		(net "SMB_ISO_SSD14_R_SCL")
	)
	(segment
		(start 422.95826 -18.44421)
		(end 422.965372 -18.437098)
		(width 0.13208)
		(layer "F.Cu")
		(net "SMB_ISO_SSD14_R_SCL")
	)
	(segment
		(start 410.964888 -22.3901)
		(end 412.767526 -22.3901)
		(width 0.13208)
		(layer "F.Cu")
		(net "SMB_ISO_SSD14_R_SCL")
	)
	(segment
		(start 422.965372 -18.437098)
		(end 423.56786 -18.437098)
		(width 0.13208)
		(layer "F.Cu")
		(net "SMB_ISO_SSD14_R_SCL")
	)
	(via
		(at 422.95826 -18.44421)
		(size 0.508)
		(drill 0.254)
		(layers "F.Cu" "B.Cu")
		(net "SMB_ISO_SSD14_R_SCL")
	)
	(via
		(at 413.393636 -23.01621)
		(size 0.508)
		(drill 0.254)
		(layers "F.Cu" "B.Cu")
		(net "SMB_ISO_SSD14_R_SCL")
	)
	(segment
		(start 421.982646 -23.01621)
		(end 413.393636 -23.01621)
		(width 0.15494)
		(layer "In5.Cu")
		(net "SMB_ISO_SSD14_R_SCL")
	)
	(segment
		(start 423.526966 -19.012916)
		(end 423.526966 -21.47189)
		(width 0.15494)
		(layer "In5.Cu")
		(net "SMB_ISO_SSD14_R_SCL")
	)
	(segment
		(start 422.95826 -18.44421)
		(end 423.526966 -19.012916)
		(width 0.15494)
		(layer "In5.Cu")
		(net "SMB_ISO_SSD14_R_SCL")
	)
	(segment
		(start 423.526966 -21.47189)
		(end 421.982646 -23.01621)
		(width 0.15494)
		(layer "In5.Cu")
		(net "SMB_ISO_SSD14_R_SCL")
	)
	(segment
		(start 456.089258 -50.201068)
		(end 456.089258 -73.749916)
		(width 0.13208)
		(layer "F.Cu")
		(net "SMB_BIC_I2C6_MUX_SSD_8_15_ADC_SCL")
	)
	(segment
		(start 456.089258 -73.749916)
		(end 455.276712 -74.562462)
		(width 0.13208)
		(layer "F.Cu")
		(net "SMB_BIC_I2C6_MUX_SSD_8_15_ADC_SCL")
	)
	(segment
		(start 455.361802 -49.918874)
		(end 455.807064 -49.918874)
		(width 0.13208)
		(layer "F.Cu")
		(net "SMB_BIC_I2C6_MUX_SSD_8_15_ADC_SCL")
	)
	(segment
		(start 455.276712 -74.562462)
		(end 455.276712 -75.787504)
		(width 0.13208)
		(layer "F.Cu")
		(net "SMB_BIC_I2C6_MUX_SSD_8_15_ADC_SCL")
	)
	(segment
		(start 388.24027 -82.88655)
		(end 389.554212 -82.88655)
		(width 0.13208)
		(layer "F.Cu")
		(net "SMB_BIC_I2C6_MUX_SSD_8_15_ADC_SCL")
	)
	(segment
		(start 389.554212 -82.88655)
		(end 390.94156 -81.499202)
		(width 0.13208)
		(layer "F.Cu")
		(net "SMB_BIC_I2C6_MUX_SSD_8_15_ADC_SCL")
	)
	(segment
		(start 455.807064 -49.918874)
		(end 456.089258 -50.201068)
		(width 0.13208)
		(layer "F.Cu")
		(net "SMB_BIC_I2C6_MUX_SSD_8_15_ADC_SCL")
	)
	(segment
		(start 455.276712 -75.787504)
		(end 454.069196 -76.99502)
		(width 0.13208)
		(layer "F.Cu")
		(net "SMB_BIC_I2C6_MUX_SSD_8_15_ADC_SCL")
	)
	(via
		(at 454.069196 -76.99502)
		(size 0.508)
		(drill 0.254)
		(layers "F.Cu" "B.Cu")
		(net "SMB_BIC_I2C6_MUX_SSD_8_15_ADC_SCL")
	)
	(via
		(at 390.94156 -81.499202)
		(size 0.508)
		(drill 0.254)
		(layers "F.Cu" "B.Cu")
		(net "SMB_BIC_I2C6_MUX_SSD_8_15_ADC_SCL")
	)
	(segment
		(start 398.122648 -81.499202)
		(end 390.94156 -81.499202)
		(width 0.15494)
		(layer "In15.Cu")
		(net "SMB_BIC_I2C6_MUX_SSD_8_15_ADC_SCL")
	)
	(segment
		(start 431.851054 -78.016862)
		(end 428.528988 -78.016862)
		(width 0.15494)
		(layer "In15.Cu")
		(net "SMB_BIC_I2C6_MUX_SSD_8_15_ADC_SCL")
	)
	(segment
		(start 421.997632 -81.441798)
		(end 419.396418 -81.441798)
		(width 0.15494)
		(layer "In15.Cu")
		(net "SMB_BIC_I2C6_MUX_SSD_8_15_ADC_SCL")
	)
	(segment
		(start 432.872896 -76.99502)
		(end 431.851054 -78.016862)
		(width 0.15494)
		(layer "In15.Cu")
		(net "SMB_BIC_I2C6_MUX_SSD_8_15_ADC_SCL")
	)
	(segment
		(start 422.532302 -80.907128)
		(end 421.997632 -81.441798)
		(width 0.15494)
		(layer "In15.Cu")
		(net "SMB_BIC_I2C6_MUX_SSD_8_15_ADC_SCL")
	)
	(segment
		(start 418.735256 -80.780636)
		(end 398.841214 -80.780636)
		(width 0.15494)
		(layer "In15.Cu")
		(net "SMB_BIC_I2C6_MUX_SSD_8_15_ADC_SCL")
	)
	(segment
		(start 419.396418 -81.441798)
		(end 418.735256 -80.780636)
		(width 0.15494)
		(layer "In15.Cu")
		(net "SMB_BIC_I2C6_MUX_SSD_8_15_ADC_SCL")
	)
	(segment
		(start 428.528988 -78.016862)
		(end 425.638722 -80.907128)
		(width 0.15494)
		(layer "In15.Cu")
		(net "SMB_BIC_I2C6_MUX_SSD_8_15_ADC_SCL")
	)
	(segment
		(start 454.069196 -76.99502)
		(end 432.872896 -76.99502)
		(width 0.15494)
		(layer "In15.Cu")
		(net "SMB_BIC_I2C6_MUX_SSD_8_15_ADC_SCL")
	)
	(segment
		(start 425.638722 -80.907128)
		(end 422.532302 -80.907128)
		(width 0.15494)
		(layer "In15.Cu")
		(net "SMB_BIC_I2C6_MUX_SSD_8_15_ADC_SCL")
	)
	(segment
		(start 398.841214 -80.780636)
		(end 398.122648 -81.499202)
		(width 0.15494)
		(layer "In15.Cu")
		(net "SMB_BIC_I2C6_MUX_SSD_8_15_ADC_SCL")
	)
	(segment
		(start 276.516084 -402.145754)
		(end 276.30247 -401.93214)
		(width 0.13208)
		(layer "F.Cu")
		(net "MB_BMC_MON_ISO_R")
	)
	(segment
		(start 224.267776 -212.704172)
		(end 223.86798 -212.304376)
		(width 0.13208)
		(layer "F.Cu")
		(net "MB_BMC_MON_ISO_R")
	)
	(segment
		(start 276.30247 -401.93214)
		(end 275.963126 -401.93214)
		(width 0.13208)
		(layer "F.Cu")
		(net "MB_BMC_MON_ISO_R")
	)
	(segment
		(start 276.516084 -402.61286)
		(end 276.516084 -402.145754)
		(width 0.13208)
		(layer "F.Cu")
		(net "MB_BMC_MON_ISO_R")
	)
	(segment
		(start 276.979126 -403.46249)
		(end 276.979126 -402.73224)
		(width 0.13208)
		(layer "F.Cu")
		(net "MB_BMC_MON_ISO_R")
	)
	(segment
		(start 276.979126 -402.73224)
		(end 276.635464 -402.73224)
		(width 0.13208)
		(layer "F.Cu")
		(net "MB_BMC_MON_ISO_R")
	)
	(segment
		(start 276.635464 -402.73224)
		(end 276.516084 -402.61286)
		(width 0.13208)
		(layer "F.Cu")
		(net "MB_BMC_MON_ISO_R")
	)
	(via
		(at 223.86798 -212.304376)
		(size 0.4572)
		(drill 0.254)
		(layers "F.Cu" "B.Cu")
		(net "MB_BMC_MON_ISO_R")
	)
	(via
		(at 276.979126 -403.46249)
		(size 0.508)
		(drill 0.254)
		(layers "F.Cu" "B.Cu")
		(net "MB_BMC_MON_ISO_R")
	)
	(via
		(at 222.349314 -252.424184)
		(size 0.508)
		(drill 0.254)
		(layers "F.Cu" "B.Cu")
		(net "MB_BMC_MON_ISO_R")
	)
	(via
		(at 225.279204 -329.872848)
		(size 0.508)
		(drill 0.254)
		(layers "F.Cu" "B.Cu")
		(net "MB_BMC_MON_ISO_R")
	)
	(segment
		(start 215.028018 -255.451356)
		(end 218.701874 -251.7775)
		(width 0.13208)
		(layer "B.Cu")
		(net "MB_BMC_MON_ISO_R")
	)
	(segment
		(start 225.279204 -329.872848)
		(end 225.279204 -329.315572)
		(width 0.13208)
		(layer "B.Cu")
		(net "MB_BMC_MON_ISO_R")
	)
	(segment
		(start 218.701874 -251.7775)
		(end 221.70263 -251.7775)
		(width 0.13208)
		(layer "B.Cu")
		(net "MB_BMC_MON_ISO_R")
	)
	(segment
		(start 214.44585 -258.020058)
		(end 215.028018 -257.43789)
		(width 0.13208)
		(layer "B.Cu")
		(net "MB_BMC_MON_ISO_R")
	)
	(segment
		(start 211.981542 -316.01791)
		(end 211.981542 -284.614112)
		(width 0.13208)
		(layer "B.Cu")
		(net "MB_BMC_MON_ISO_R")
	)
	(segment
		(start 215.028018 -257.43789)
		(end 215.028018 -255.451356)
		(width 0.13208)
		(layer "B.Cu")
		(net "MB_BMC_MON_ISO_R")
	)
	(segment
		(start 214.44585 -282.149804)
		(end 214.44585 -258.020058)
		(width 0.13208)
		(layer "B.Cu")
		(net "MB_BMC_MON_ISO_R")
	)
	(segment
		(start 211.981542 -284.614112)
		(end 214.44585 -282.149804)
		(width 0.13208)
		(layer "B.Cu")
		(net "MB_BMC_MON_ISO_R")
	)
	(segment
		(start 225.279204 -329.315572)
		(end 211.981542 -316.01791)
		(width 0.13208)
		(layer "B.Cu")
		(net "MB_BMC_MON_ISO_R")
	)
	(segment
		(start 221.70263 -251.7775)
		(end 222.349314 -252.424184)
		(width 0.13208)
		(layer "B.Cu")
		(net "MB_BMC_MON_ISO_R")
	)
	(segment
		(start 222.218758 -252.293628)
		(end 223.09074 -251.421392)
		(width 0.15494)
		(layer "In5.Cu")
		(net "MB_BMC_MON_ISO_R")
	)
	(segment
		(start 221.454726 -217.280236)
		(end 220.3323 -216.15781)
		(width 0.15494)
		(layer "In5.Cu")
		(net "MB_BMC_MON_ISO_R")
	)
	(segment
		(start 223.110044 -237.32236)
		(end 222.131382 -236.343698)
		(width 0.15494)
		(layer "In5.Cu")
		(net "MB_BMC_MON_ISO_R")
	)
	(segment
		(start 222.131382 -236.343698)
		(end 222.131382 -228.300788)
		(width 0.15494)
		(layer "In5.Cu")
		(net "MB_BMC_MON_ISO_R")
	)
	(segment
		(start 221.454726 -219.736416)
		(end 221.454726 -217.280236)
		(width 0.15494)
		(layer "In5.Cu")
		(net "MB_BMC_MON_ISO_R")
	)
	(segment
		(start 222.131382 -228.300788)
		(end 221.27972 -227.449126)
		(width 0.15494)
		(layer "In5.Cu")
		(net "MB_BMC_MON_ISO_R")
	)
	(segment
		(start 222.76054 -247.196356)
		(end 222.76054 -246.64289)
		(width 0.15494)
		(layer "In5.Cu")
		(net "MB_BMC_MON_ISO_R")
	)
	(segment
		(start 223.09074 -247.526556)
		(end 222.76054 -247.196356)
		(width 0.15494)
		(layer "In5.Cu")
		(net "MB_BMC_MON_ISO_R")
	)
	(segment
		(start 220.81998 -223.536764)
		(end 220.819726 -223.53651)
		(width 0.15494)
		(layer "In5.Cu")
		(net "MB_BMC_MON_ISO_R")
	)
	(segment
		(start 222.76054 -246.64289)
		(end 223.110044 -246.293386)
		(width 0.15494)
		(layer "In5.Cu")
		(net "MB_BMC_MON_ISO_R")
	)
	(segment
		(start 223.110044 -246.293386)
		(end 223.110044 -237.32236)
		(width 0.15494)
		(layer "In5.Cu")
		(net "MB_BMC_MON_ISO_R")
	)
	(segment
		(start 222.89897 -211.896706)
		(end 223.46031 -211.896706)
		(width 0.15494)
		(layer "In5.Cu")
		(net "MB_BMC_MON_ISO_R")
	)
	(segment
		(start 223.09074 -251.421392)
		(end 223.09074 -247.526556)
		(width 0.15494)
		(layer "In5.Cu")
		(net "MB_BMC_MON_ISO_R")
	)
	(segment
		(start 220.819726 -223.53651)
		(end 220.819726 -220.371416)
		(width 0.15494)
		(layer "In5.Cu")
		(net "MB_BMC_MON_ISO_R")
	)
	(segment
		(start 220.81998 -225.517202)
		(end 220.81998 -223.536764)
		(width 0.15494)
		(layer "In5.Cu")
		(net "MB_BMC_MON_ISO_R")
	)
	(segment
		(start 222.349314 -252.424184)
		(end 222.218758 -252.293628)
		(width 0.15494)
		(layer "In5.Cu")
		(net "MB_BMC_MON_ISO_R")
	)
	(segment
		(start 221.27972 -225.976942)
		(end 220.81998 -225.517202)
		(width 0.15494)
		(layer "In5.Cu")
		(net "MB_BMC_MON_ISO_R")
	)
	(segment
		(start 220.819726 -220.371416)
		(end 221.454726 -219.736416)
		(width 0.15494)
		(layer "In5.Cu")
		(net "MB_BMC_MON_ISO_R")
	)
	(segment
		(start 221.27972 -227.449126)
		(end 221.27972 -225.976942)
		(width 0.15494)
		(layer "In5.Cu")
		(net "MB_BMC_MON_ISO_R")
	)
	(segment
		(start 220.3323 -216.15781)
		(end 220.3323 -214.463376)
		(width 0.15494)
		(layer "In5.Cu")
		(net "MB_BMC_MON_ISO_R")
	)
	(segment
		(start 220.3323 -214.463376)
		(end 222.89897 -211.896706)
		(width 0.15494)
		(layer "In5.Cu")
		(net "MB_BMC_MON_ISO_R")
	)
	(segment
		(start 223.46031 -211.896706)
		(end 223.86798 -212.304376)
		(width 0.15494)
		(layer "In5.Cu")
		(net "MB_BMC_MON_ISO_R")
	)
	(segment
		(start 281.9146 -371.246146)
		(end 266.2174 -355.548946)
		(width 0.15494)
		(layer "In9.Cu")
		(net "MB_BMC_MON_ISO_R")
	)
	(segment
		(start 224.8408 -334.263746)
		(end 224.8408 -330.311252)
		(width 0.15494)
		(layer "In9.Cu")
		(net "MB_BMC_MON_ISO_R")
	)
	(segment
		(start 266.2174 -345.8718)
		(end 263.9314 -343.5858)
		(width 0.15494)
		(layer "In9.Cu")
		(net "MB_BMC_MON_ISO_R")
	)
	(segment
		(start 278.22271 -403.46249)
		(end 281.9146 -399.7706)
		(width 0.15494)
		(layer "In9.Cu")
		(net "MB_BMC_MON_ISO_R")
	)
	(segment
		(start 263.9314 -343.5858)
		(end 236.093254 -343.5858)
		(width 0.15494)
		(layer "In9.Cu")
		(net "MB_BMC_MON_ISO_R")
	)
	(segment
		(start 266.2174 -355.548946)
		(end 266.2174 -345.8718)
		(width 0.15494)
		(layer "In9.Cu")
		(net "MB_BMC_MON_ISO_R")
	)
	(segment
		(start 236.093254 -343.5858)
		(end 227.665534 -335.15808)
		(width 0.15494)
		(layer "In9.Cu")
		(net "MB_BMC_MON_ISO_R")
	)
	(segment
		(start 224.8408 -330.311252)
		(end 225.279204 -329.872848)
		(width 0.15494)
		(layer "In9.Cu")
		(net "MB_BMC_MON_ISO_R")
	)
	(segment
		(start 281.9146 -399.7706)
		(end 281.9146 -371.246146)
		(width 0.15494)
		(layer "In9.Cu")
		(net "MB_BMC_MON_ISO_R")
	)
	(segment
		(start 276.979126 -403.46249)
		(end 278.22271 -403.46249)
		(width 0.15494)
		(layer "In9.Cu")
		(net "MB_BMC_MON_ISO_R")
	)
	(segment
		(start 225.735134 -335.15808)
		(end 224.8408 -334.263746)
		(width 0.15494)
		(layer "In9.Cu")
		(net "MB_BMC_MON_ISO_R")
	)
	(segment
		(start 227.665534 -335.15808)
		(end 225.735134 -335.15808)
		(width 0.15494)
		(layer "In9.Cu")
		(net "MB_BMC_MON_ISO_R")
	)
	(segment
		(start 87.194898 -58.453782)
		(end 87.194898 -59.177936)
		(width 0.2032)
		(layer "F.Cu")
		(net "P3V3_SSD3_SS")
	)
	(segment
		(start 87.190834 -58.449718)
		(end 87.194898 -58.453782)
		(width 0.2032)
		(layer "F.Cu")
		(net "P3V3_SSD3_SS")
	)
	(segment
		(start 87.073232 -58.166)
		(end 87.190834 -58.449718)
		(width 0.2032)
		(layer "F.Cu")
		(net "P3V3_SSD3_SS")
	)
	(segment
		(start 86.140798 -57.233566)
		(end 87.073232 -58.166)
		(width 0.2032)
		(layer "F.Cu")
		(net "P3V3_SSD3_SS")
	)
	(segment
		(start 86.140798 -57.16397)
		(end 86.140798 -57.233566)
		(width 0.2032)
		(layer "F.Cu")
		(net "P3V3_SSD3_SS")
	)
	(via
		(at 87.190834 -58.449718)
		(size 0.508)
		(drill 0.254)
		(layers "F.Cu" "B.Cu")
		(net "P3V3_SSD3_SS")
	)
	(segment
		(start 133.9596 -171.364656)
		(end 133.594856 -170.999912)
		(width 0.13462)
		(layer "F.Cu")
		(net "CLK_100M_DB2000QL_NIC0_DP")
	)
	(segment
		(start 133.97103 -174.900336)
		(end 134.09168 -174.779686)
		(width 0.13462)
		(layer "F.Cu")
		(net "CLK_100M_DB2000QL_NIC0_DP")
	)
	(segment
		(start 134.09168 -173.621954)
		(end 133.9596 -173.489874)
		(width 0.13462)
		(layer "F.Cu")
		(net "CLK_100M_DB2000QL_NIC0_DP")
	)
	(segment
		(start 133.9596 -173.489874)
		(end 133.9596 -171.364656)
		(width 0.13462)
		(layer "F.Cu")
		(net "CLK_100M_DB2000QL_NIC0_DP")
	)
	(segment
		(start 134.09168 -174.779686)
		(end 134.09168 -173.621954)
		(width 0.13462)
		(layer "F.Cu")
		(net "CLK_100M_DB2000QL_NIC0_DP")
	)
	(segment
		(start 23.977092 -255.688592)
		(end 23.977092 -254.850646)
		(width 0.13208)
		(layer "F.Cu")
		(net "LED_PEX0_SYS_ERR_N")
	)
	(segment
		(start 23.977092 -255.992376)
		(end 23.977092 -255.688592)
		(width 0.13208)
		(layer "F.Cu")
		(net "LED_PEX0_SYS_ERR_N")
	)
	(segment
		(start 24.792686 -256.748788)
		(end 24.733504 -256.748788)
		(width 0.13208)
		(layer "F.Cu")
		(net "LED_PEX0_SYS_ERR_N")
	)
	(segment
		(start 24.733504 -256.748788)
		(end 23.977092 -255.992376)
		(width 0.13208)
		(layer "F.Cu")
		(net "LED_PEX0_SYS_ERR_N")
	)
	(via
		(at 23.977092 -255.688592)
		(size 0.508)
		(drill 0.254)
		(layers "F.Cu" "B.Cu")
		(net "LED_PEX0_SYS_ERR_N")
	)
	(segment
		(start 306.865274 -18.437098)
		(end 307.467762 -18.437098)
		(width 0.13208)
		(layer "F.Cu")
		(net "SMB_ISO_SSD10_R_SCL")
	)
	(segment
		(start 296.667428 -22.3901)
		(end 297.293538 -23.01621)
		(width 0.13208)
		(layer "F.Cu")
		(net "SMB_ISO_SSD10_R_SCL")
	)
	(segment
		(start 306.858162 -18.44421)
		(end 306.865274 -18.437098)
		(width 0.13208)
		(layer "F.Cu")
		(net "SMB_ISO_SSD10_R_SCL")
	)
	(segment
		(start 294.86479 -22.3901)
		(end 296.667428 -22.3901)
		(width 0.13208)
		(layer "F.Cu")
		(net "SMB_ISO_SSD10_R_SCL")
	)
	(via
		(at 306.858162 -18.44421)
		(size 0.508)
		(drill 0.254)
		(layers "F.Cu" "B.Cu")
		(net "SMB_ISO_SSD10_R_SCL")
	)
	(via
		(at 297.293538 -23.01621)
		(size 0.508)
		(drill 0.254)
		(layers "F.Cu" "B.Cu")
		(net "SMB_ISO_SSD10_R_SCL")
	)
	(segment
		(start 305.882548 -23.01621)
		(end 297.293538 -23.01621)
		(width 0.15494)
		(layer "In5.Cu")
		(net "SMB_ISO_SSD10_R_SCL")
	)
	(segment
		(start 307.426868 -19.012916)
		(end 307.426868 -21.47189)
		(width 0.15494)
		(layer "In5.Cu")
		(net "SMB_ISO_SSD10_R_SCL")
	)
	(segment
		(start 307.426868 -21.47189)
		(end 305.882548 -23.01621)
		(width 0.15494)
		(layer "In5.Cu")
		(net "SMB_ISO_SSD10_R_SCL")
	)
	(segment
		(start 306.858162 -18.44421)
		(end 307.426868 -19.012916)
		(width 0.15494)
		(layer "In5.Cu")
		(net "SMB_ISO_SSD10_R_SCL")
	)
	(segment
		(start 388.24027 -82.236564)
		(end 389.317484 -82.236564)
		(width 0.13208)
		(layer "F.Cu")
		(net "SMB_BIC_I2C6_MUX_SSD_8_15_ADC_SDA")
	)
	(segment
		(start 391.197846 -80.356202)
		(end 392.578082 -80.356202)
		(width 0.13208)
		(layer "F.Cu")
		(net "SMB_BIC_I2C6_MUX_SSD_8_15_ADC_SDA")
	)
	(segment
		(start 392.578082 -80.356202)
		(end 393.269216 -80.356202)
		(width 0.13208)
		(layer "F.Cu")
		(net "SMB_BIC_I2C6_MUX_SSD_8_15_ADC_SDA")
	)
	(segment
		(start 389.317484 -82.236564)
		(end 391.197846 -80.356202)
		(width 0.13208)
		(layer "F.Cu")
		(net "SMB_BIC_I2C6_MUX_SSD_8_15_ADC_SDA")
	)
	(via
		(at 392.578082 -80.356202)
		(size 0.508)
		(drill 0.254)
		(layers "F.Cu" "B.Cu")
		(net "SMB_BIC_I2C6_MUX_SSD_8_15_ADC_SDA")
	)
	(segment
		(start 320.096134 -390.990836)
		(end 321.864482 -390.990836)
		(width 0.13208)
		(layer "F.Cu")
		(net "GPU_3V3IO_RSVD3_FFU_R")
	)
	(via
		(at 321.864482 -390.990836)
		(size 0.508)
		(drill 0.254)
		(layers "F.Cu" "B.Cu")
		(net "GPU_3V3IO_RSVD3_FFU_R")
	)
	(segment
		(start 326.881236 -390.990836)
		(end 321.864482 -390.990836)
		(width 0.15494)
		(layer "In9.Cu")
		(net "GPU_3V3IO_RSVD3_FFU_R")
	)
	(segment
		(start 329.616308 -393.725908)
		(end 326.881236 -390.990836)
		(width 0.15494)
		(layer "In9.Cu")
		(net "GPU_3V3IO_RSVD3_FFU_R")
	)
	(segment
		(start 331.490066 -412.090108)
		(end 329.616308 -410.21635)
		(width 0.15494)
		(layer "In9.Cu")
		(net "GPU_3V3IO_RSVD3_FFU_R")
	)
	(segment
		(start 329.616308 -410.21635)
		(end 329.616308 -393.725908)
		(width 0.15494)
		(layer "In9.Cu")
		(net "GPU_3V3IO_RSVD3_FFU_R")
	)
	(segment
		(start 355.322886 -221.488)
		(end 357.61295 -221.488)
		(width 0.13208)
		(layer "F.Cu")
		(net "RST_NIC5_PERST_N")
	)
	(segment
		(start 352.509582 -219.987114)
		(end 354.010468 -221.488)
		(width 0.13208)
		(layer "F.Cu")
		(net "RST_NIC5_PERST_N")
	)
	(segment
		(start 354.010468 -221.488)
		(end 355.322886 -221.488)
		(width 0.13208)
		(layer "F.Cu")
		(net "RST_NIC5_PERST_N")
	)
	(segment
		(start 350.893888 -219.987114)
		(end 352.509582 -219.987114)
		(width 0.13208)
		(layer "F.Cu")
		(net "RST_NIC5_PERST_N")
	)
	(via
		(at 355.322886 -221.488)
		(size 0.762)
		(drill 0.381)
		(layers "F.Cu" "B.Cu")
		(net "RST_NIC5_PERST_N")
	)
	(segment
		(start 336.843624 -49.95291)
		(end 337.514946 -49.95291)
		(width 0.13208)
		(layer "F.Cu")
		(net "SMB_BIC_I2C6_MUX_SSD_8_15_ADC_R_SCL")
	)
	(segment
		(start 423.498772 -50.502312)
		(end 423.498772 -50.451512)
		(width 0.13208)
		(layer "F.Cu")
		(net "SMB_BIC_I2C6_MUX_SSD_8_15_ADC_R_SCL")
	)
	(segment
		(start 452.943722 -49.95291)
		(end 453.615044 -49.95291)
		(width 0.13208)
		(layer "F.Cu")
		(net "SMB_BIC_I2C6_MUX_SSD_8_15_ADC_R_SCL")
	)
	(segment
		(start 454.555098 -50.981864)
		(end 454.561702 -50.97526)
		(width 0.13208)
		(layer "F.Cu")
		(net "SMB_BIC_I2C6_MUX_SSD_8_15_ADC_R_SCL")
	)
	(segment
		(start 374.943878 -49.95291)
		(end 375.6152 -49.95291)
		(width 0.13208)
		(layer "F.Cu")
		(net "SMB_BIC_I2C6_MUX_SSD_8_15_ADC_R_SCL")
	)
	(segment
		(start 453.64908 -49.918874)
		(end 453.615044 -49.95291)
		(width 0.13208)
		(layer "F.Cu")
		(net "SMB_BIC_I2C6_MUX_SSD_8_15_ADC_R_SCL")
	)
	(segment
		(start 307.408072 -50.462434)
		(end 307.929026 -49.94148)
		(width 0.13208)
		(layer "F.Cu")
		(net "SMB_BIC_I2C6_MUX_SSD_8_15_ADC_R_SCL")
	)
	(segment
		(start 423.498772 -50.451512)
		(end 424.008804 -49.94148)
		(width 0.13208)
		(layer "F.Cu")
		(net "SMB_BIC_I2C6_MUX_SSD_8_15_ADC_R_SCL")
	)
	(segment
		(start 424.008804 -49.94148)
		(end 424.283378 -49.94148)
		(width 0.13208)
		(layer "F.Cu")
		(net "SMB_BIC_I2C6_MUX_SSD_8_15_ADC_R_SCL")
	)
	(segment
		(start 284.843728 -49.95291)
		(end 285.51505 -49.95291)
		(width 0.13208)
		(layer "F.Cu")
		(net "SMB_BIC_I2C6_MUX_SSD_8_15_ADC_R_SCL")
	)
	(segment
		(start 258.84378 -49.95291)
		(end 259.515102 -49.95291)
		(width 0.13208)
		(layer "F.Cu")
		(net "SMB_BIC_I2C6_MUX_SSD_8_15_ADC_R_SCL")
	)
	(segment
		(start 454.561702 -50.97526)
		(end 454.561702 -49.918874)
		(width 0.13208)
		(layer "F.Cu")
		(net "SMB_BIC_I2C6_MUX_SSD_8_15_ADC_R_SCL")
	)
	(segment
		(start 307.929026 -49.94148)
		(end 308.18328 -49.94148)
		(width 0.13208)
		(layer "F.Cu")
		(net "SMB_BIC_I2C6_MUX_SSD_8_15_ADC_R_SCL")
	)
	(segment
		(start 454.561702 -49.918874)
		(end 453.64908 -49.918874)
		(width 0.13208)
		(layer "F.Cu")
		(net "SMB_BIC_I2C6_MUX_SSD_8_15_ADC_R_SCL")
	)
	(segment
		(start 400.943826 -49.95291)
		(end 401.615148 -49.95291)
		(width 0.13208)
		(layer "F.Cu")
		(net "SMB_BIC_I2C6_MUX_SSD_8_15_ADC_R_SCL")
	)
	(via
		(at 337.514946 -49.95291)
		(size 0.508)
		(drill 0.254)
		(layers "F.Cu" "B.Cu")
		(net "SMB_BIC_I2C6_MUX_SSD_8_15_ADC_R_SCL")
	)
	(via
		(at 375.6152 -49.95291)
		(size 0.508)
		(drill 0.254)
		(layers "F.Cu" "B.Cu")
		(net "SMB_BIC_I2C6_MUX_SSD_8_15_ADC_R_SCL")
	)
	(via
		(at 423.498772 -50.502312)
		(size 0.508)
		(drill 0.254)
		(layers "F.Cu" "B.Cu")
		(net "SMB_BIC_I2C6_MUX_SSD_8_15_ADC_R_SCL")
	)
	(via
		(at 307.408072 -50.462434)
		(size 0.508)
		(drill 0.254)
		(layers "F.Cu" "B.Cu")
		(net "SMB_BIC_I2C6_MUX_SSD_8_15_ADC_R_SCL")
	)
	(via
		(at 259.515102 -49.95291)
		(size 0.508)
		(drill 0.254)
		(layers "F.Cu" "B.Cu")
		(net "SMB_BIC_I2C6_MUX_SSD_8_15_ADC_R_SCL")
	)
	(via
		(at 285.51505 -49.95291)
		(size 0.508)
		(drill 0.254)
		(layers "F.Cu" "B.Cu")
		(net "SMB_BIC_I2C6_MUX_SSD_8_15_ADC_R_SCL")
	)
	(via
		(at 401.615148 -49.95291)
		(size 0.508)
		(drill 0.254)
		(layers "F.Cu" "B.Cu")
		(net "SMB_BIC_I2C6_MUX_SSD_8_15_ADC_R_SCL")
	)
	(via
		(at 453.615044 -49.95291)
		(size 0.508)
		(drill 0.254)
		(layers "F.Cu" "B.Cu")
		(net "SMB_BIC_I2C6_MUX_SSD_8_15_ADC_R_SCL")
	)
	(segment
		(start 259.515102 -49.95291)
		(end 260.691122 -48.77689)
		(width 0.13208)
		(layer "B.Cu")
		(net "SMB_BIC_I2C6_MUX_SSD_8_15_ADC_R_SCL")
	)
	(segment
		(start 325.572628 -48.76419)
		(end 327.142602 -50.334164)
		(width 0.13208)
		(layer "B.Cu")
		(net "SMB_BIC_I2C6_MUX_SSD_8_15_ADC_R_SCL")
	)
	(segment
		(start 365.26216 -50.353468)
		(end 375.214642 -50.353468)
		(width 0.13208)
		(layer "B.Cu")
		(net "SMB_BIC_I2C6_MUX_SSD_8_15_ADC_R_SCL")
	)
	(segment
		(start 363.672882 -48.76419)
		(end 365.26216 -50.353468)
		(width 0.13208)
		(layer "B.Cu")
		(net "SMB_BIC_I2C6_MUX_SSD_8_15_ADC_R_SCL")
	)
	(segment
		(start 399.073116 -50.5714)
		(end 399.691606 -49.95291)
		(width 0.13208)
		(layer "B.Cu")
		(net "SMB_BIC_I2C6_MUX_SSD_8_15_ADC_R_SCL")
	)
	(segment
		(start 401.615148 -49.95291)
		(end 402.803868 -48.76419)
		(width 0.13208)
		(layer "B.Cu")
		(net "SMB_BIC_I2C6_MUX_SSD_8_15_ADC_R_SCL")
	)
	(segment
		(start 286.71647 -48.75149)
		(end 301.147988 -48.75149)
		(width 0.13208)
		(layer "B.Cu")
		(net "SMB_BIC_I2C6_MUX_SSD_8_15_ADC_R_SCL")
	)
	(segment
		(start 283.624528 -49.95291)
		(end 285.51505 -49.95291)
		(width 0.13208)
		(layer "B.Cu")
		(net "SMB_BIC_I2C6_MUX_SSD_8_15_ADC_R_SCL")
	)
	(segment
		(start 302.858932 -50.462434)
		(end 307.408072 -50.462434)
		(width 0.13208)
		(layer "B.Cu")
		(net "SMB_BIC_I2C6_MUX_SSD_8_15_ADC_R_SCL")
	)
	(segment
		(start 417.223448 -50.31486)
		(end 423.31132 -50.31486)
		(width 0.13208)
		(layer "B.Cu")
		(net "SMB_BIC_I2C6_MUX_SSD_8_15_ADC_R_SCL")
	)
	(segment
		(start 415.672778 -48.76419)
		(end 417.223448 -50.31486)
		(width 0.13208)
		(layer "B.Cu")
		(net "SMB_BIC_I2C6_MUX_SSD_8_15_ADC_R_SCL")
	)
	(segment
		(start 337.133692 -50.334164)
		(end 337.514946 -49.95291)
		(width 0.13208)
		(layer "B.Cu")
		(net "SMB_BIC_I2C6_MUX_SSD_8_15_ADC_R_SCL")
	)
	(segment
		(start 275.176488 -48.77689)
		(end 276.872192 -50.472594)
		(width 0.13208)
		(layer "B.Cu")
		(net "SMB_BIC_I2C6_MUX_SSD_8_15_ADC_R_SCL")
	)
	(segment
		(start 423.31132 -50.31486)
		(end 423.498772 -50.502312)
		(width 0.13208)
		(layer "B.Cu")
		(net "SMB_BIC_I2C6_MUX_SSD_8_15_ADC_R_SCL")
	)
	(segment
		(start 337.514946 -49.95291)
		(end 338.703666 -48.76419)
		(width 0.13208)
		(layer "B.Cu")
		(net "SMB_BIC_I2C6_MUX_SSD_8_15_ADC_R_SCL")
	)
	(segment
		(start 375.6152 -49.95291)
		(end 376.694954 -48.873156)
		(width 0.13208)
		(layer "B.Cu")
		(net "SMB_BIC_I2C6_MUX_SSD_8_15_ADC_R_SCL")
	)
	(segment
		(start 285.51505 -49.95291)
		(end 286.71647 -48.75149)
		(width 0.13208)
		(layer "B.Cu")
		(net "SMB_BIC_I2C6_MUX_SSD_8_15_ADC_R_SCL")
	)
	(segment
		(start 301.147988 -48.75149)
		(end 302.858932 -50.462434)
		(width 0.13208)
		(layer "B.Cu")
		(net "SMB_BIC_I2C6_MUX_SSD_8_15_ADC_R_SCL")
	)
	(segment
		(start 307.408072 -50.462434)
		(end 311.005474 -50.462434)
		(width 0.13208)
		(layer "B.Cu")
		(net "SMB_BIC_I2C6_MUX_SSD_8_15_ADC_R_SCL")
	)
	(segment
		(start 327.142602 -50.334164)
		(end 337.133692 -50.334164)
		(width 0.13208)
		(layer "B.Cu")
		(net "SMB_BIC_I2C6_MUX_SSD_8_15_ADC_R_SCL")
	)
	(segment
		(start 428.803816 -48.76419)
		(end 441.672726 -48.76419)
		(width 0.13208)
		(layer "B.Cu")
		(net "SMB_BIC_I2C6_MUX_SSD_8_15_ADC_R_SCL")
	)
	(segment
		(start 338.703666 -48.76419)
		(end 363.672882 -48.76419)
		(width 0.13208)
		(layer "B.Cu")
		(net "SMB_BIC_I2C6_MUX_SSD_8_15_ADC_R_SCL")
	)
	(segment
		(start 427.253146 -50.31486)
		(end 428.803816 -48.76419)
		(width 0.13208)
		(layer "B.Cu")
		(net "SMB_BIC_I2C6_MUX_SSD_8_15_ADC_R_SCL")
	)
	(segment
		(start 276.872192 -50.472594)
		(end 283.104844 -50.472594)
		(width 0.13208)
		(layer "B.Cu")
		(net "SMB_BIC_I2C6_MUX_SSD_8_15_ADC_R_SCL")
	)
	(segment
		(start 423.498772 -50.502312)
		(end 423.686224 -50.31486)
		(width 0.13208)
		(layer "B.Cu")
		(net "SMB_BIC_I2C6_MUX_SSD_8_15_ADC_R_SCL")
	)
	(segment
		(start 399.691606 -49.95291)
		(end 401.615148 -49.95291)
		(width 0.13208)
		(layer "B.Cu")
		(net "SMB_BIC_I2C6_MUX_SSD_8_15_ADC_R_SCL")
	)
	(segment
		(start 389.146542 -50.5714)
		(end 399.073116 -50.5714)
		(width 0.13208)
		(layer "B.Cu")
		(net "SMB_BIC_I2C6_MUX_SSD_8_15_ADC_R_SCL")
	)
	(segment
		(start 441.672726 -48.76419)
		(end 443.252352 -50.343816)
		(width 0.13208)
		(layer "B.Cu")
		(net "SMB_BIC_I2C6_MUX_SSD_8_15_ADC_R_SCL")
	)
	(segment
		(start 375.214642 -50.353468)
		(end 375.6152 -49.95291)
		(width 0.13208)
		(layer "B.Cu")
		(net "SMB_BIC_I2C6_MUX_SSD_8_15_ADC_R_SCL")
	)
	(segment
		(start 387.448298 -48.873156)
		(end 389.146542 -50.5714)
		(width 0.13208)
		(layer "B.Cu")
		(net "SMB_BIC_I2C6_MUX_SSD_8_15_ADC_R_SCL")
	)
	(segment
		(start 260.691122 -48.77689)
		(end 275.176488 -48.77689)
		(width 0.13208)
		(layer "B.Cu")
		(net "SMB_BIC_I2C6_MUX_SSD_8_15_ADC_R_SCL")
	)
	(segment
		(start 311.005474 -50.462434)
		(end 312.703718 -48.76419)
		(width 0.13208)
		(layer "B.Cu")
		(net "SMB_BIC_I2C6_MUX_SSD_8_15_ADC_R_SCL")
	)
	(segment
		(start 402.803868 -48.76419)
		(end 415.672778 -48.76419)
		(width 0.13208)
		(layer "B.Cu")
		(net "SMB_BIC_I2C6_MUX_SSD_8_15_ADC_R_SCL")
	)
	(segment
		(start 443.252352 -50.343816)
		(end 453.224138 -50.343816)
		(width 0.13208)
		(layer "B.Cu")
		(net "SMB_BIC_I2C6_MUX_SSD_8_15_ADC_R_SCL")
	)
	(segment
		(start 423.686224 -50.31486)
		(end 427.253146 -50.31486)
		(width 0.13208)
		(layer "B.Cu")
		(net "SMB_BIC_I2C6_MUX_SSD_8_15_ADC_R_SCL")
	)
	(segment
		(start 453.224138 -50.343816)
		(end 453.615044 -49.95291)
		(width 0.13208)
		(layer "B.Cu")
		(net "SMB_BIC_I2C6_MUX_SSD_8_15_ADC_R_SCL")
	)
	(segment
		(start 312.703718 -48.76419)
		(end 325.572628 -48.76419)
		(width 0.13208)
		(layer "B.Cu")
		(net "SMB_BIC_I2C6_MUX_SSD_8_15_ADC_R_SCL")
	)
	(segment
		(start 376.694954 -48.873156)
		(end 387.448298 -48.873156)
		(width 0.13208)
		(layer "B.Cu")
		(net "SMB_BIC_I2C6_MUX_SSD_8_15_ADC_R_SCL")
	)
	(segment
		(start 283.104844 -50.472594)
		(end 283.624528 -49.95291)
		(width 0.13208)
		(layer "B.Cu")
		(net "SMB_BIC_I2C6_MUX_SSD_8_15_ADC_R_SCL")
	)
	(segment
		(start 276.979126 -401.331684)
		(end 277.137622 -401.173188)
		(width 0.13208)
		(layer "F.Cu")
		(net "MB_BMC_MON_ISO")
	)
	(segment
		(start 277.137622 -401.173188)
		(end 277.501858 -401.173188)
		(width 0.13208)
		(layer "F.Cu")
		(net "MB_BMC_MON_ISO")
	)
	(segment
		(start 277.80107 -400.873976)
		(end 277.80107 -400.000978)
		(width 0.13208)
		(layer "F.Cu")
		(net "MB_BMC_MON_ISO")
	)
	(segment
		(start 277.501858 -401.173188)
		(end 277.80107 -400.873976)
		(width 0.13208)
		(layer "F.Cu")
		(net "MB_BMC_MON_ISO")
	)
	(segment
		(start 276.979126 -401.93214)
		(end 276.979126 -401.331684)
		(width 0.13208)
		(layer "F.Cu")
		(net "MB_BMC_MON_ISO")
	)
	(via
		(at 277.501858 -401.173188)
		(size 0.508)
		(drill 0.254)
		(layers "F.Cu" "B.Cu")
		(net "MB_BMC_MON_ISO")
	)
	(segment
		(start 357.61295 -229.616)
		(end 356.997 -229.616)
		(width 0.13208)
		(layer "F.Cu")
		(net "RST_NIC1_PERST_N")
	)
	(segment
		(start 347.693742 -223.987106)
		(end 348.093538 -224.386902)
		(width 0.13208)
		(layer "F.Cu")
		(net "RST_NIC1_PERST_N")
	)
	(via
		(at 348.093538 -224.386902)
		(size 0.4572)
		(drill 0.254)
		(layers "F.Cu" "B.Cu")
		(net "RST_NIC1_PERST_N")
	)
	(via
		(at 356.997 -229.616)
		(size 0.508)
		(drill 0.254)
		(layers "F.Cu" "B.Cu")
		(net "RST_NIC1_PERST_N")
	)
	(segment
		(start 354.56368 -226.569778)
		(end 354.56368 -228.07168)
		(width 0.15494)
		(layer "In7.Cu")
		(net "RST_NIC1_PERST_N")
	)
	(segment
		(start 351.947226 -224.369884)
		(end 352.363786 -224.369884)
		(width 0.15494)
		(layer "In7.Cu")
		(net "RST_NIC1_PERST_N")
	)
	(segment
		(start 351.564194 -223.986852)
		(end 351.566734 -223.989392)
		(width 0.0889)
		(layer "In7.Cu")
		(net "RST_NIC1_PERST_N")
	)
	(segment
		(start 356.108 -229.616)
		(end 356.997 -229.616)
		(width 0.15494)
		(layer "In7.Cu")
		(net "RST_NIC1_PERST_N")
	)
	(segment
		(start 352.363786 -224.369884)
		(end 354.56368 -226.569778)
		(width 0.15494)
		(layer "In7.Cu")
		(net "RST_NIC1_PERST_N")
	)
	(segment
		(start 348.093538 -224.386902)
		(end 348.493588 -223.986852)
		(width 0.0889)
		(layer "In7.Cu")
		(net "RST_NIC1_PERST_N")
	)
	(segment
		(start 354.56368 -228.07168)
		(end 356.108 -229.616)
		(width 0.15494)
		(layer "In7.Cu")
		(net "RST_NIC1_PERST_N")
	)
	(segment
		(start 348.493588 -223.986852)
		(end 351.564194 -223.986852)
		(width 0.0889)
		(layer "In7.Cu")
		(net "RST_NIC1_PERST_N")
	)
	(segment
		(start 351.566734 -223.989392)
		(end 351.947226 -224.369884)
		(width 0.15494)
		(layer "In7.Cu")
		(net "RST_NIC1_PERST_N")
	)
	(segment
		(start 177.173382 -58.166)
		(end 177.290984 -58.449718)
		(width 0.2032)
		(layer "F.Cu")
		(net "P3V3_SSD6_SS")
	)
	(segment
		(start 177.290984 -58.449718)
		(end 177.295048 -58.453782)
		(width 0.2032)
		(layer "F.Cu")
		(net "P3V3_SSD6_SS")
	)
	(segment
		(start 177.295048 -58.453782)
		(end 177.295048 -59.177936)
		(width 0.2032)
		(layer "F.Cu")
		(net "P3V3_SSD6_SS")
	)
	(segment
		(start 176.240948 -57.16397)
		(end 176.240948 -57.233566)
		(width 0.2032)
		(layer "F.Cu")
		(net "P3V3_SSD6_SS")
	)
	(segment
		(start 176.240948 -57.233566)
		(end 177.173382 -58.166)
		(width 0.2032)
		(layer "F.Cu")
		(net "P3V3_SSD6_SS")
	)
	(via
		(at 177.290984 -58.449718)
		(size 0.508)
		(drill 0.254)
		(layers "F.Cu" "B.Cu")
		(net "P3V3_SSD6_SS")
	)
	(segment
		(start 145.53438 -171.92879)
		(end 145.24863 -171.642786)
		(width 0.1143)
		(layer "F.Cu")
		(net "CLK_100M_DB2000QL_PEX3_S1_R_DN")
	)
	(segment
		(start 146.299682 -172.694092)
		(end 146.013932 -172.408088)
		(width 0.1143)
		(layer "F.Cu")
		(net "CLK_100M_DB2000QL_PEX3_S1_R_DN")
	)
	(segment
		(start 241.253772 -173.241716)
		(end 239.005364 -170.993308)
		(width 0.1143)
		(layer "F.Cu")
		(net "CLK_100M_DB2000QL_PEX3_S1_R_DN")
	)
	(segment
		(start 146.013932 -172.408088)
		(end 146.013932 -172.214286)
		(width 0.1143)
		(layer "F.Cu")
		(net "CLK_100M_DB2000QL_PEX3_S1_R_DN")
	)
	(segment
		(start 143.718026 -170.112182)
		(end 143.718026 -169.91838)
		(width 0.1143)
		(layer "F.Cu")
		(net "CLK_100M_DB2000QL_PEX3_S1_R_DN")
	)
	(segment
		(start 142.187422 -168.387776)
		(end 141.901926 -168.10228)
		(width 0.1143)
		(layer "F.Cu")
		(net "CLK_100M_DB2000QL_PEX3_S1_R_DN")
	)
	(segment
		(start 145.24863 -171.642786)
		(end 145.24863 -171.448984)
		(width 0.1143)
		(layer "F.Cu")
		(net "CLK_100M_DB2000QL_PEX3_S1_R_DN")
	)
	(segment
		(start 385.149852 -297.79976)
		(end 385.149598 -297.79976)
		(width 0.1143)
		(layer "F.Cu")
		(net "CLK_100M_DB2000QL_PEX3_S1_R_DN")
	)
	(segment
		(start 142.952724 -169.34688)
		(end 142.952724 -169.153078)
		(width 0.1143)
		(layer "F.Cu")
		(net "CLK_100M_DB2000QL_PEX3_S1_R_DN")
	)
	(segment
		(start 144.483328 -170.877484)
		(end 144.483328 -170.683682)
		(width 0.1143)
		(layer "F.Cu")
		(net "CLK_100M_DB2000QL_PEX3_S1_R_DN")
	)
	(segment
		(start 142.473172 -168.867582)
		(end 142.187422 -168.581578)
		(width 0.1143)
		(layer "F.Cu")
		(net "CLK_100M_DB2000QL_PEX3_S1_R_DN")
	)
	(segment
		(start 141.70787 -168.10228)
		(end 141.42212 -167.81653)
		(width 0.1143)
		(layer "F.Cu")
		(net "CLK_100M_DB2000QL_PEX3_S1_R_DN")
	)
	(segment
		(start 183.0959 -184.404)
		(end 158.203646 -184.404)
		(width 0.1143)
		(layer "F.Cu")
		(net "CLK_100M_DB2000QL_PEX3_S1_R_DN")
	)
	(segment
		(start 208.187798 -174.010574)
		(end 183.0959 -184.404)
		(width 0.1143)
		(layer "F.Cu")
		(net "CLK_100M_DB2000QL_PEX3_S1_R_DN")
	)
	(segment
		(start 140.622528 -166.822882)
		(end 132.109718 -166.822882)
		(width 0.1143)
		(layer "F.Cu")
		(net "CLK_100M_DB2000QL_PEX3_S1_R_DN")
	)
	(segment
		(start 146.493738 -172.694092)
		(end 146.299682 -172.694092)
		(width 0.1143)
		(layer "F.Cu")
		(net "CLK_100M_DB2000QL_PEX3_S1_R_DN")
	)
	(segment
		(start 142.187422 -168.581578)
		(end 142.187422 -168.387776)
		(width 0.1143)
		(layer "F.Cu")
		(net "CLK_100M_DB2000QL_PEX3_S1_R_DN")
	)
	(segment
		(start 257.723386 -173.241716)
		(end 241.253772 -173.241716)
		(width 0.1143)
		(layer "F.Cu")
		(net "CLK_100M_DB2000QL_PEX3_S1_R_DN")
	)
	(segment
		(start 158.203646 -184.404)
		(end 146.493738 -172.694092)
		(width 0.1143)
		(layer "F.Cu")
		(net "CLK_100M_DB2000QL_PEX3_S1_R_DN")
	)
	(segment
		(start 145.728436 -171.92879)
		(end 145.53438 -171.92879)
		(width 0.1143)
		(layer "F.Cu")
		(net "CLK_100M_DB2000QL_PEX3_S1_R_DN")
	)
	(segment
		(start 141.42212 -167.81653)
		(end 141.42212 -167.622474)
		(width 0.1143)
		(layer "F.Cu")
		(net "CLK_100M_DB2000QL_PEX3_S1_R_DN")
	)
	(segment
		(start 143.718026 -169.91838)
		(end 143.43253 -169.632884)
		(width 0.1143)
		(layer "F.Cu")
		(net "CLK_100M_DB2000QL_PEX3_S1_R_DN")
	)
	(segment
		(start 144.769078 -171.163488)
		(end 144.483328 -170.877484)
		(width 0.1143)
		(layer "F.Cu")
		(net "CLK_100M_DB2000QL_PEX3_S1_R_DN")
	)
	(segment
		(start 132.109718 -166.822882)
		(end 131.1021 -167.8305)
		(width 0.1143)
		(layer "F.Cu")
		(net "CLK_100M_DB2000QL_PEX3_S1_R_DN")
	)
	(segment
		(start 144.963134 -171.163488)
		(end 144.769078 -171.163488)
		(width 0.1143)
		(layer "F.Cu")
		(net "CLK_100M_DB2000QL_PEX3_S1_R_DN")
	)
	(segment
		(start 141.901926 -168.10228)
		(end 141.70787 -168.10228)
		(width 0.1143)
		(layer "F.Cu")
		(net "CLK_100M_DB2000QL_PEX3_S1_R_DN")
	)
	(segment
		(start 145.24863 -171.448984)
		(end 144.963134 -171.163488)
		(width 0.1143)
		(layer "F.Cu")
		(net "CLK_100M_DB2000QL_PEX3_S1_R_DN")
	)
	(segment
		(start 142.952724 -169.153078)
		(end 142.667228 -168.867582)
		(width 0.1143)
		(layer "F.Cu")
		(net "CLK_100M_DB2000QL_PEX3_S1_R_DN")
	)
	(segment
		(start 146.013932 -172.214286)
		(end 145.728436 -171.92879)
		(width 0.1143)
		(layer "F.Cu")
		(net "CLK_100M_DB2000QL_PEX3_S1_R_DN")
	)
	(segment
		(start 239.005364 -170.993308)
		(end 215.137492 -170.993308)
		(width 0.1143)
		(layer "F.Cu")
		(net "CLK_100M_DB2000QL_PEX3_S1_R_DN")
	)
	(segment
		(start 212.120226 -174.010574)
		(end 208.187798 -174.010574)
		(width 0.1143)
		(layer "F.Cu")
		(net "CLK_100M_DB2000QL_PEX3_S1_R_DN")
	)
	(segment
		(start 385.149598 -297.79976)
		(end 384.674618 -297.32478)
		(width 0.1143)
		(layer "F.Cu")
		(net "CLK_100M_DB2000QL_PEX3_S1_R_DN")
	)
	(segment
		(start 143.238474 -169.632884)
		(end 142.952724 -169.34688)
		(width 0.1143)
		(layer "F.Cu")
		(net "CLK_100M_DB2000QL_PEX3_S1_R_DN")
	)
	(segment
		(start 215.137492 -170.993308)
		(end 212.120226 -174.010574)
		(width 0.1143)
		(layer "F.Cu")
		(net "CLK_100M_DB2000QL_PEX3_S1_R_DN")
	)
	(segment
		(start 142.667228 -168.867582)
		(end 142.473172 -168.867582)
		(width 0.1143)
		(layer "F.Cu")
		(net "CLK_100M_DB2000QL_PEX3_S1_R_DN")
	)
	(segment
		(start 144.003776 -170.398186)
		(end 143.718026 -170.112182)
		(width 0.1143)
		(layer "F.Cu")
		(net "CLK_100M_DB2000QL_PEX3_S1_R_DN")
	)
	(segment
		(start 144.483328 -170.683682)
		(end 144.197832 -170.398186)
		(width 0.1143)
		(layer "F.Cu")
		(net "CLK_100M_DB2000QL_PEX3_S1_R_DN")
	)
	(segment
		(start 141.42212 -167.622474)
		(end 140.622528 -166.822882)
		(width 0.1143)
		(layer "F.Cu")
		(net "CLK_100M_DB2000QL_PEX3_S1_R_DN")
	)
	(segment
		(start 143.43253 -169.632884)
		(end 143.238474 -169.632884)
		(width 0.1143)
		(layer "F.Cu")
		(net "CLK_100M_DB2000QL_PEX3_S1_R_DN")
	)
	(segment
		(start 257.977386 -173.495716)
		(end 257.723386 -173.241716)
		(width 0.1143)
		(layer "F.Cu")
		(net "CLK_100M_DB2000QL_PEX3_S1_R_DN")
	)
	(segment
		(start 144.197832 -170.398186)
		(end 144.003776 -170.398186)
		(width 0.1143)
		(layer "F.Cu")
		(net "CLK_100M_DB2000QL_PEX3_S1_R_DN")
	)
	(segment
		(start 131.1021 -167.8305)
		(end 131.1021 -169.866056)
		(width 0.1143)
		(layer "F.Cu")
		(net "CLK_100M_DB2000QL_PEX3_S1_R_DN")
	)
	(segment
		(start 131.1021 -169.866056)
		(end 131.435856 -170.199812)
		(width 0.1143)
		(layer "F.Cu")
		(net "CLK_100M_DB2000QL_PEX3_S1_R_DN")
	)
	(via
		(at 257.977386 -173.495716)
		(size 0.508)
		(drill 0.254)
		(layers "F.Cu" "B.Cu")
		(net "CLK_100M_DB2000QL_PEX3_S1_R_DN")
	)
	(via
		(at 384.674618 -297.32478)
		(size 0.4064)
		(drill 0.2032)
		(layers "F.Cu" "B.Cu")
		(net "CLK_100M_DB2000QL_PEX3_S1_R_DN")
	)
	(segment
		(start 378.886974 -279.230328)
		(end 376.872246 -277.2156)
		(width 0.1143)
		(layer "B.Cu")
		(net "CLK_100M_DB2000QL_PEX3_S1_R_DN")
	)
	(segment
		(start 385.054348 -297.11015)
		(end 384.895598 -296.9514)
		(width 0.0889)
		(layer "B.Cu")
		(net "CLK_100M_DB2000QL_PEX3_S1_R_DN")
	)
	(segment
		(start 385.054348 -297.23588)
		(end 385.054348 -297.11015)
		(width 0.0889)
		(layer "B.Cu")
		(net "CLK_100M_DB2000QL_PEX3_S1_R_DN")
	)
	(segment
		(start 378.886974 -294.56761)
		(end 378.886974 -279.230328)
		(width 0.1143)
		(layer "B.Cu")
		(net "CLK_100M_DB2000QL_PEX3_S1_R_DN")
	)
	(segment
		(start 293.801546 -211.1375)
		(end 263.908286 -181.24424)
		(width 0.1143)
		(layer "B.Cu")
		(net "CLK_100M_DB2000QL_PEX3_S1_R_DN")
	)
	(segment
		(start 368.5413 -245.161308)
		(end 364.667292 -241.2873)
		(width 0.1143)
		(layer "B.Cu")
		(net "CLK_100M_DB2000QL_PEX3_S1_R_DN")
	)
	(segment
		(start 261.727442 -176.202086)
		(end 261.727442 -175.950372)
		(width 0.1143)
		(layer "B.Cu")
		(net "CLK_100M_DB2000QL_PEX3_S1_R_DN")
	)
	(segment
		(start 302.043846 -211.1375)
		(end 293.801546 -211.1375)
		(width 0.1143)
		(layer "B.Cu")
		(net "CLK_100M_DB2000QL_PEX3_S1_R_DN")
	)
	(segment
		(start 259.018786 -173.241716)
		(end 258.231386 -173.241716)
		(width 0.1143)
		(layer "B.Cu")
		(net "CLK_100M_DB2000QL_PEX3_S1_R_DN")
	)
	(segment
		(start 321.982846 -240.4872)
		(end 315.7855 -234.289854)
		(width 0.1143)
		(layer "B.Cu")
		(net "CLK_100M_DB2000QL_PEX3_S1_R_DN")
	)
	(segment
		(start 315.7855 -224.879154)
		(end 302.043846 -211.1375)
		(width 0.1143)
		(layer "B.Cu")
		(net "CLK_100M_DB2000QL_PEX3_S1_R_DN")
	)
	(segment
		(start 352.742246 -241.2873)
		(end 352.2218 -241.807746)
		(width 0.1143)
		(layer "B.Cu")
		(net "CLK_100M_DB2000QL_PEX3_S1_R_DN")
	)
	(segment
		(start 383.80035 -296.9514)
		(end 383.7178 -297.03395)
		(width 0.0889)
		(layer "B.Cu")
		(net "CLK_100M_DB2000QL_PEX3_S1_R_DN")
	)
	(segment
		(start 384.965448 -297.32478)
		(end 385.054348 -297.23588)
		(width 0.0889)
		(layer "B.Cu")
		(net "CLK_100M_DB2000QL_PEX3_S1_R_DN")
	)
	(segment
		(start 379.492764 -295.1734)
		(end 378.886974 -294.56761)
		(width 0.1143)
		(layer "B.Cu")
		(net "CLK_100M_DB2000QL_PEX3_S1_R_DN")
	)
	(segment
		(start 328.205846 -240.4872)
		(end 321.982846 -240.4872)
		(width 0.1143)
		(layer "B.Cu")
		(net "CLK_100M_DB2000QL_PEX3_S1_R_DN")
	)
	(segment
		(start 329.526392 -241.807746)
		(end 328.205846 -240.4872)
		(width 0.1143)
		(layer "B.Cu")
		(net "CLK_100M_DB2000QL_PEX3_S1_R_DN")
	)
	(segment
		(start 376.582178 -277.2156)
		(end 368.5413 -269.174722)
		(width 0.1143)
		(layer "B.Cu")
		(net "CLK_100M_DB2000QL_PEX3_S1_R_DN")
	)
	(segment
		(start 383.38125 -297.03395)
		(end 381.5207 -295.1734)
		(width 0.1143)
		(layer "B.Cu")
		(net "CLK_100M_DB2000QL_PEX3_S1_R_DN")
	)
	(segment
		(start 384.895598 -296.9514)
		(end 383.80035 -296.9514)
		(width 0.0889)
		(layer "B.Cu")
		(net "CLK_100M_DB2000QL_PEX3_S1_R_DN")
	)
	(segment
		(start 383.7178 -297.03395)
		(end 383.695702 -297.03395)
		(width 0.0889)
		(layer "B.Cu")
		(net "CLK_100M_DB2000QL_PEX3_S1_R_DN")
	)
	(segment
		(start 261.727442 -175.950372)
		(end 259.018786 -173.241716)
		(width 0.1143)
		(layer "B.Cu")
		(net "CLK_100M_DB2000QL_PEX3_S1_R_DN")
	)
	(segment
		(start 383.695702 -297.03395)
		(end 383.38125 -297.03395)
		(width 0.1143)
		(layer "B.Cu")
		(net "CLK_100M_DB2000QL_PEX3_S1_R_DN")
	)
	(segment
		(start 262.194802 -176.417732)
		(end 261.943088 -176.417732)
		(width 0.1143)
		(layer "B.Cu")
		(net "CLK_100M_DB2000QL_PEX3_S1_R_DN")
	)
	(segment
		(start 384.674618 -297.32478)
		(end 384.965448 -297.32478)
		(width 0.0889)
		(layer "B.Cu")
		(net "CLK_100M_DB2000QL_PEX3_S1_R_DN")
	)
	(segment
		(start 368.5413 -269.174722)
		(end 368.5413 -245.161308)
		(width 0.1143)
		(layer "B.Cu")
		(net "CLK_100M_DB2000QL_PEX3_S1_R_DN")
	)
	(segment
		(start 364.667292 -241.2873)
		(end 352.742246 -241.2873)
		(width 0.1143)
		(layer "B.Cu")
		(net "CLK_100M_DB2000QL_PEX3_S1_R_DN")
	)
	(segment
		(start 315.7855 -234.289854)
		(end 315.7855 -224.879154)
		(width 0.1143)
		(layer "B.Cu")
		(net "CLK_100M_DB2000QL_PEX3_S1_R_DN")
	)
	(segment
		(start 263.908286 -178.131216)
		(end 262.194802 -176.417732)
		(width 0.1143)
		(layer "B.Cu")
		(net "CLK_100M_DB2000QL_PEX3_S1_R_DN")
	)
	(segment
		(start 352.2218 -241.807746)
		(end 329.526392 -241.807746)
		(width 0.1143)
		(layer "B.Cu")
		(net "CLK_100M_DB2000QL_PEX3_S1_R_DN")
	)
	(segment
		(start 258.231386 -173.241716)
		(end 257.977386 -173.495716)
		(width 0.1143)
		(layer "B.Cu")
		(net "CLK_100M_DB2000QL_PEX3_S1_R_DN")
	)
	(segment
		(start 263.908286 -181.24424)
		(end 263.908286 -178.131216)
		(width 0.1143)
		(layer "B.Cu")
		(net "CLK_100M_DB2000QL_PEX3_S1_R_DN")
	)
	(segment
		(start 381.5207 -295.1734)
		(end 379.492764 -295.1734)
		(width 0.1143)
		(layer "B.Cu")
		(net "CLK_100M_DB2000QL_PEX3_S1_R_DN")
	)
	(segment
		(start 376.872246 -277.2156)
		(end 376.582178 -277.2156)
		(width 0.1143)
		(layer "B.Cu")
		(net "CLK_100M_DB2000QL_PEX3_S1_R_DN")
	)
	(segment
		(start 261.943088 -176.417732)
		(end 261.727442 -176.202086)
		(width 0.1143)
		(layer "B.Cu")
		(net "CLK_100M_DB2000QL_PEX3_S1_R_DN")
	)
	(segment
		(start 104.340406 -5.747258)
		(end 105.898442 -5.747258)
		(width 0.13208)
		(layer "F.Cu")
		(net "SMB_SSD3_ISO_EN")
	)
	(segment
		(start 104.126538 -6.541516)
		(end 104.126538 -5.961126)
		(width 0.13208)
		(layer "F.Cu")
		(net "SMB_SSD3_ISO_EN")
	)
	(segment
		(start 104.126538 -5.961126)
		(end 104.340406 -5.747258)
		(width 0.13208)
		(layer "F.Cu")
		(net "SMB_SSD3_ISO_EN")
	)
	(via
		(at 104.340406 -5.747258)
		(size 0.508)
		(drill 0.254)
		(layers "F.Cu" "B.Cu")
		(net "SMB_SSD3_ISO_EN")
	)
	(segment
		(start 310.843676 -48.93691)
		(end 311.514998 -48.93691)
		(width 0.13208)
		(layer "F.Cu")
		(net "SMB_BIC_I2C6_MUX_SSD_8_15_ADC_R_SDA")
	)
	(segment
		(start 400.943826 -48.93691)
		(end 401.615148 -48.93691)
		(width 0.13208)
		(layer "F.Cu")
		(net "SMB_BIC_I2C6_MUX_SSD_8_15_ADC_R_SDA")
	)
	(segment
		(start 256.983484 -49.94148)
		(end 256.983484 -50.324258)
		(width 0.13208)
		(layer "F.Cu")
		(net "SMB_BIC_I2C6_MUX_SSD_8_15_ADC_R_SDA")
	)
	(segment
		(start 394.069316 -80.356202)
		(end 394.818362 -80.356202)
		(width 0.13208)
		(layer "F.Cu")
		(net "SMB_BIC_I2C6_MUX_SSD_8_15_ADC_R_SDA")
	)
	(segment
		(start 284.843728 -48.93691)
		(end 285.51505 -48.93691)
		(width 0.13208)
		(layer "F.Cu")
		(net "SMB_BIC_I2C6_MUX_SSD_8_15_ADC_R_SDA")
	)
	(segment
		(start 336.843624 -48.93691)
		(end 337.514946 -48.93691)
		(width 0.13208)
		(layer "F.Cu")
		(net "SMB_BIC_I2C6_MUX_SSD_8_15_ADC_R_SDA")
	)
	(segment
		(start 394.818362 -80.356202)
		(end 395.809216 -80.356202)
		(width 0.13208)
		(layer "F.Cu")
		(net "SMB_BIC_I2C6_MUX_SSD_8_15_ADC_R_SDA")
	)
	(segment
		(start 374.943878 -48.93691)
		(end 375.6152 -48.93691)
		(width 0.13208)
		(layer "F.Cu")
		(net "SMB_BIC_I2C6_MUX_SSD_8_15_ADC_R_SDA")
	)
	(segment
		(start 426.943774 -48.93691)
		(end 427.615096 -48.93691)
		(width 0.13208)
		(layer "F.Cu")
		(net "SMB_BIC_I2C6_MUX_SSD_8_15_ADC_R_SDA")
	)
	(segment
		(start 256.983484 -50.324258)
		(end 256.613914 -50.693828)
		(width 0.13208)
		(layer "F.Cu")
		(net "SMB_BIC_I2C6_MUX_SSD_8_15_ADC_R_SDA")
	)
	(segment
		(start 452.943722 -48.93691)
		(end 453.587866 -48.93691)
		(width 0.13208)
		(layer "F.Cu")
		(net "SMB_BIC_I2C6_MUX_SSD_8_15_ADC_R_SDA")
	)
	(via
		(at 453.587866 -48.93691)
		(size 0.508)
		(drill 0.254)
		(layers "F.Cu" "B.Cu")
		(net "SMB_BIC_I2C6_MUX_SSD_8_15_ADC_R_SDA")
	)
	(via
		(at 427.615096 -48.93691)
		(size 0.508)
		(drill 0.254)
		(layers "F.Cu" "B.Cu")
		(net "SMB_BIC_I2C6_MUX_SSD_8_15_ADC_R_SDA")
	)
	(via
		(at 337.514946 -48.93691)
		(size 0.508)
		(drill 0.254)
		(layers "F.Cu" "B.Cu")
		(net "SMB_BIC_I2C6_MUX_SSD_8_15_ADC_R_SDA")
	)
	(via
		(at 401.615148 -48.93691)
		(size 0.508)
		(drill 0.254)
		(layers "F.Cu" "B.Cu")
		(net "SMB_BIC_I2C6_MUX_SSD_8_15_ADC_R_SDA")
	)
	(via
		(at 285.51505 -48.93691)
		(size 0.508)
		(drill 0.254)
		(layers "F.Cu" "B.Cu")
		(net "SMB_BIC_I2C6_MUX_SSD_8_15_ADC_R_SDA")
	)
	(via
		(at 311.514998 -48.93691)
		(size 0.508)
		(drill 0.254)
		(layers "F.Cu" "B.Cu")
		(net "SMB_BIC_I2C6_MUX_SSD_8_15_ADC_R_SDA")
	)
	(via
		(at 256.613914 -50.693828)
		(size 0.508)
		(drill 0.254)
		(layers "F.Cu" "B.Cu")
		(net "SMB_BIC_I2C6_MUX_SSD_8_15_ADC_R_SDA")
	)
	(via
		(at 375.6152 -48.93691)
		(size 0.508)
		(drill 0.254)
		(layers "F.Cu" "B.Cu")
		(net "SMB_BIC_I2C6_MUX_SSD_8_15_ADC_R_SDA")
	)
	(via
		(at 455.555096 -77.049122)
		(size 0.508)
		(drill 0.254)
		(layers "F.Cu" "B.Cu")
		(net "SMB_BIC_I2C6_MUX_SSD_8_15_ADC_R_SDA")
	)
	(via
		(at 394.818362 -80.356202)
		(size 0.508)
		(drill 0.254)
		(layers "F.Cu" "B.Cu")
		(net "SMB_BIC_I2C6_MUX_SSD_8_15_ADC_R_SDA")
	)
	(segment
		(start 398.938242 -50.042064)
		(end 400.043396 -48.93691)
		(width 0.13208)
		(layer "B.Cu")
		(net "SMB_BIC_I2C6_MUX_SSD_8_15_ADC_R_SDA")
	)
	(segment
		(start 311.514998 -48.93691)
		(end 312.124598 -48.32731)
		(width 0.13208)
		(layer "B.Cu")
		(net "SMB_BIC_I2C6_MUX_SSD_8_15_ADC_R_SDA")
	)
	(segment
		(start 286.13735 -48.31461)
		(end 301.32909 -48.31461)
		(width 0.13208)
		(layer "B.Cu")
		(net "SMB_BIC_I2C6_MUX_SSD_8_15_ADC_R_SDA")
	)
	(segment
		(start 365.443262 -49.916588)
		(end 374.635522 -49.916588)
		(width 0.13208)
		(layer "B.Cu")
		(net "SMB_BIC_I2C6_MUX_SSD_8_15_ADC_R_SDA")
	)
	(segment
		(start 441.853828 -48.32731)
		(end 443.433454 -49.906936)
		(width 0.13208)
		(layer "B.Cu")
		(net "SMB_BIC_I2C6_MUX_SSD_8_15_ADC_R_SDA")
	)
	(segment
		(start 389.951214 -48.930814)
		(end 390.082532 -49.062132)
		(width 0.13208)
		(layer "B.Cu")
		(net "SMB_BIC_I2C6_MUX_SSD_8_15_ADC_R_SDA")
	)
	(segment
		(start 277.053294 -50.035714)
		(end 282.923742 -50.035714)
		(width 0.13208)
		(layer "B.Cu")
		(net "SMB_BIC_I2C6_MUX_SSD_8_15_ADC_R_SDA")
	)
	(segment
		(start 402.224748 -48.32731)
		(end 415.85388 -48.32731)
		(width 0.13208)
		(layer "B.Cu")
		(net "SMB_BIC_I2C6_MUX_SSD_8_15_ADC_R_SDA")
	)
	(segment
		(start 390.054084 -50.042064)
		(end 398.938242 -50.042064)
		(width 0.13208)
		(layer "B.Cu")
		(net "SMB_BIC_I2C6_MUX_SSD_8_15_ADC_R_SDA")
	)
	(segment
		(start 336.554572 -49.897284)
		(end 337.514946 -48.93691)
		(width 0.13208)
		(layer "B.Cu")
		(net "SMB_BIC_I2C6_MUX_SSD_8_15_ADC_R_SDA")
	)
	(segment
		(start 389.447024 -49.266348)
		(end 389.782558 -48.930814)
		(width 0.13208)
		(layer "B.Cu")
		(net "SMB_BIC_I2C6_MUX_SSD_8_15_ADC_R_SDA")
	)
	(segment
		(start 256.613914 -50.693828)
		(end 258.967732 -48.34001)
		(width 0.13208)
		(layer "B.Cu")
		(net "SMB_BIC_I2C6_MUX_SSD_8_15_ADC_R_SDA")
	)
	(segment
		(start 389.782558 -48.930814)
		(end 389.951214 -48.930814)
		(width 0.13208)
		(layer "B.Cu")
		(net "SMB_BIC_I2C6_MUX_SSD_8_15_ADC_R_SDA")
	)
	(segment
		(start 325.75373 -48.32731)
		(end 327.323704 -49.897284)
		(width 0.13208)
		(layer "B.Cu")
		(net "SMB_BIC_I2C6_MUX_SSD_8_15_ADC_R_SDA")
	)
	(segment
		(start 302.936148 -49.921668)
		(end 310.53024 -49.921668)
		(width 0.13208)
		(layer "B.Cu")
		(net "SMB_BIC_I2C6_MUX_SSD_8_15_ADC_R_SDA")
	)
	(segment
		(start 388.166864 -48.154844)
		(end 389.278368 -49.266348)
		(width 0.13208)
		(layer "B.Cu")
		(net "SMB_BIC_I2C6_MUX_SSD_8_15_ADC_R_SDA")
	)
	(segment
		(start 400.043396 -48.93691)
		(end 401.615148 -48.93691)
		(width 0.13208)
		(layer "B.Cu")
		(net "SMB_BIC_I2C6_MUX_SSD_8_15_ADC_R_SDA")
	)
	(segment
		(start 282.923742 -50.035714)
		(end 284.022546 -48.93691)
		(width 0.13208)
		(layer "B.Cu")
		(net "SMB_BIC_I2C6_MUX_SSD_8_15_ADC_R_SDA")
	)
	(segment
		(start 374.635522 -49.916588)
		(end 375.6152 -48.93691)
		(width 0.13208)
		(layer "B.Cu")
		(net "SMB_BIC_I2C6_MUX_SSD_8_15_ADC_R_SDA")
	)
	(segment
		(start 375.6152 -48.93691)
		(end 376.397266 -48.154844)
		(width 0.13208)
		(layer "B.Cu")
		(net "SMB_BIC_I2C6_MUX_SSD_8_15_ADC_R_SDA")
	)
	(segment
		(start 451.83044 -49.906936)
		(end 451.997826 -49.73955)
		(width 0.13208)
		(layer "B.Cu")
		(net "SMB_BIC_I2C6_MUX_SSD_8_15_ADC_R_SDA")
	)
	(segment
		(start 284.022546 -48.93691)
		(end 285.51505 -48.93691)
		(width 0.13208)
		(layer "B.Cu")
		(net "SMB_BIC_I2C6_MUX_SSD_8_15_ADC_R_SDA")
	)
	(segment
		(start 426.674026 -49.87798)
		(end 427.615096 -48.93691)
		(width 0.13208)
		(layer "B.Cu")
		(net "SMB_BIC_I2C6_MUX_SSD_8_15_ADC_R_SDA")
	)
	(segment
		(start 390.082532 -49.230788)
		(end 389.746998 -49.566322)
		(width 0.13208)
		(layer "B.Cu")
		(net "SMB_BIC_I2C6_MUX_SSD_8_15_ADC_R_SDA")
	)
	(segment
		(start 452.422006 -49.73955)
		(end 452.541386 -49.85893)
		(width 0.13208)
		(layer "B.Cu")
		(net "SMB_BIC_I2C6_MUX_SSD_8_15_ADC_R_SDA")
	)
	(segment
		(start 428.224696 -48.32731)
		(end 441.853828 -48.32731)
		(width 0.13208)
		(layer "B.Cu")
		(net "SMB_BIC_I2C6_MUX_SSD_8_15_ADC_R_SDA")
	)
	(segment
		(start 285.51505 -48.93691)
		(end 286.13735 -48.31461)
		(width 0.13208)
		(layer "B.Cu")
		(net "SMB_BIC_I2C6_MUX_SSD_8_15_ADC_R_SDA")
	)
	(segment
		(start 452.422006 -49.264316)
		(end 452.422006 -49.73955)
		(width 0.13208)
		(layer "B.Cu")
		(net "SMB_BIC_I2C6_MUX_SSD_8_15_ADC_R_SDA")
	)
	(segment
		(start 301.32909 -48.31461)
		(end 302.936148 -49.921668)
		(width 0.13208)
		(layer "B.Cu")
		(net "SMB_BIC_I2C6_MUX_SSD_8_15_ADC_R_SDA")
	)
	(segment
		(start 417.40455 -49.87798)
		(end 426.674026 -49.87798)
		(width 0.13208)
		(layer "B.Cu")
		(net "SMB_BIC_I2C6_MUX_SSD_8_15_ADC_R_SDA")
	)
	(segment
		(start 452.541386 -49.85893)
		(end 452.665846 -49.85893)
		(width 0.13208)
		(layer "B.Cu")
		(net "SMB_BIC_I2C6_MUX_SSD_8_15_ADC_R_SDA")
	)
	(segment
		(start 452.665846 -49.85893)
		(end 453.587866 -48.93691)
		(width 0.13208)
		(layer "B.Cu")
		(net "SMB_BIC_I2C6_MUX_SSD_8_15_ADC_R_SDA")
	)
	(segment
		(start 401.615148 -48.93691)
		(end 402.224748 -48.32731)
		(width 0.13208)
		(layer "B.Cu")
		(net "SMB_BIC_I2C6_MUX_SSD_8_15_ADC_R_SDA")
	)
	(segment
		(start 451.997826 -49.73955)
		(end 451.997826 -49.264316)
		(width 0.13208)
		(layer "B.Cu")
		(net "SMB_BIC_I2C6_MUX_SSD_8_15_ADC_R_SDA")
	)
	(segment
		(start 310.53024 -49.921668)
		(end 311.514998 -48.93691)
		(width 0.13208)
		(layer "B.Cu")
		(net "SMB_BIC_I2C6_MUX_SSD_8_15_ADC_R_SDA")
	)
	(segment
		(start 389.746998 -49.734978)
		(end 390.054084 -50.042064)
		(width 0.13208)
		(layer "B.Cu")
		(net "SMB_BIC_I2C6_MUX_SSD_8_15_ADC_R_SDA")
	)
	(segment
		(start 451.997826 -49.264316)
		(end 452.117206 -49.144936)
		(width 0.13208)
		(layer "B.Cu")
		(net "SMB_BIC_I2C6_MUX_SSD_8_15_ADC_R_SDA")
	)
	(segment
		(start 363.853984 -48.32731)
		(end 365.443262 -49.916588)
		(width 0.13208)
		(layer "B.Cu")
		(net "SMB_BIC_I2C6_MUX_SSD_8_15_ADC_R_SDA")
	)
	(segment
		(start 390.082532 -49.062132)
		(end 390.082532 -49.230788)
		(width 0.13208)
		(layer "B.Cu")
		(net "SMB_BIC_I2C6_MUX_SSD_8_15_ADC_R_SDA")
	)
	(segment
		(start 312.124598 -48.32731)
		(end 325.75373 -48.32731)
		(width 0.13208)
		(layer "B.Cu")
		(net "SMB_BIC_I2C6_MUX_SSD_8_15_ADC_R_SDA")
	)
	(segment
		(start 443.433454 -49.906936)
		(end 451.83044 -49.906936)
		(width 0.13208)
		(layer "B.Cu")
		(net "SMB_BIC_I2C6_MUX_SSD_8_15_ADC_R_SDA")
	)
	(segment
		(start 389.746998 -49.566322)
		(end 389.746998 -49.734978)
		(width 0.13208)
		(layer "B.Cu")
		(net "SMB_BIC_I2C6_MUX_SSD_8_15_ADC_R_SDA")
	)
	(segment
		(start 337.514946 -48.93691)
		(end 338.124546 -48.32731)
		(width 0.13208)
		(layer "B.Cu")
		(net "SMB_BIC_I2C6_MUX_SSD_8_15_ADC_R_SDA")
	)
	(segment
		(start 389.278368 -49.266348)
		(end 389.447024 -49.266348)
		(width 0.13208)
		(layer "B.Cu")
		(net "SMB_BIC_I2C6_MUX_SSD_8_15_ADC_R_SDA")
	)
	(segment
		(start 452.302626 -49.144936)
		(end 452.422006 -49.264316)
		(width 0.13208)
		(layer "B.Cu")
		(net "SMB_BIC_I2C6_MUX_SSD_8_15_ADC_R_SDA")
	)
	(segment
		(start 275.35759 -48.34001)
		(end 277.053294 -50.035714)
		(width 0.13208)
		(layer "B.Cu")
		(net "SMB_BIC_I2C6_MUX_SSD_8_15_ADC_R_SDA")
	)
	(segment
		(start 327.323704 -49.897284)
		(end 336.554572 -49.897284)
		(width 0.13208)
		(layer "B.Cu")
		(net "SMB_BIC_I2C6_MUX_SSD_8_15_ADC_R_SDA")
	)
	(segment
		(start 427.615096 -48.93691)
		(end 428.224696 -48.32731)
		(width 0.13208)
		(layer "B.Cu")
		(net "SMB_BIC_I2C6_MUX_SSD_8_15_ADC_R_SDA")
	)
	(segment
		(start 415.85388 -48.32731)
		(end 417.40455 -49.87798)
		(width 0.13208)
		(layer "B.Cu")
		(net "SMB_BIC_I2C6_MUX_SSD_8_15_ADC_R_SDA")
	)
	(segment
		(start 452.117206 -49.144936)
		(end 452.302626 -49.144936)
		(width 0.13208)
		(layer "B.Cu")
		(net "SMB_BIC_I2C6_MUX_SSD_8_15_ADC_R_SDA")
	)
	(segment
		(start 376.397266 -48.154844)
		(end 388.166864 -48.154844)
		(width 0.13208)
		(layer "B.Cu")
		(net "SMB_BIC_I2C6_MUX_SSD_8_15_ADC_R_SDA")
	)
	(segment
		(start 258.967732 -48.34001)
		(end 275.35759 -48.34001)
		(width 0.13208)
		(layer "B.Cu")
		(net "SMB_BIC_I2C6_MUX_SSD_8_15_ADC_R_SDA")
	)
	(segment
		(start 338.124546 -48.32731)
		(end 363.853984 -48.32731)
		(width 0.13208)
		(layer "B.Cu")
		(net "SMB_BIC_I2C6_MUX_SSD_8_15_ADC_R_SDA")
	)
	(segment
		(start 455.555096 -77.049122)
		(end 455.12355 -76.617576)
		(width 0.15494)
		(layer "In5.Cu")
		(net "SMB_BIC_I2C6_MUX_SSD_8_15_ADC_R_SDA")
	)
	(segment
		(start 455.12355 -50.472594)
		(end 453.587866 -48.93691)
		(width 0.15494)
		(layer "In5.Cu")
		(net "SMB_BIC_I2C6_MUX_SSD_8_15_ADC_R_SDA")
	)
	(segment
		(start 455.12355 -76.617576)
		(end 455.12355 -50.472594)
		(width 0.15494)
		(layer "In5.Cu")
		(net "SMB_BIC_I2C6_MUX_SSD_8_15_ADC_R_SDA")
	)
	(segment
		(start 396.401036 -80.356202)
		(end 394.818362 -80.356202)
		(width 0.15494)
		(layer "In15.Cu")
		(net "SMB_BIC_I2C6_MUX_SSD_8_15_ADC_R_SDA")
	)
	(segment
		(start 454.88098 -76.375006)
		(end 429.49876 -76.375006)
		(width 0.15494)
		(layer "In15.Cu")
		(net "SMB_BIC_I2C6_MUX_SSD_8_15_ADC_R_SDA")
	)
	(segment
		(start 422.335452 -80.431894)
		(end 421.800782 -80.966564)
		(width 0.15494)
		(layer "In15.Cu")
		(net "SMB_BIC_I2C6_MUX_SSD_8_15_ADC_R_SDA")
	)
	(segment
		(start 421.800782 -80.966564)
		(end 419.593268 -80.966564)
		(width 0.15494)
		(layer "In15.Cu")
		(net "SMB_BIC_I2C6_MUX_SSD_8_15_ADC_R_SDA")
	)
	(segment
		(start 425.441872 -80.431894)
		(end 422.335452 -80.431894)
		(width 0.15494)
		(layer "In15.Cu")
		(net "SMB_BIC_I2C6_MUX_SSD_8_15_ADC_R_SDA")
	)
	(segment
		(start 398.318228 -80.305402)
		(end 397.598138 -81.025492)
		(width 0.15494)
		(layer "In15.Cu")
		(net "SMB_BIC_I2C6_MUX_SSD_8_15_ADC_R_SDA")
	)
	(segment
		(start 455.555096 -77.049122)
		(end 454.88098 -76.375006)
		(width 0.15494)
		(layer "In15.Cu")
		(net "SMB_BIC_I2C6_MUX_SSD_8_15_ADC_R_SDA")
	)
	(segment
		(start 429.49876 -76.375006)
		(end 425.441872 -80.431894)
		(width 0.15494)
		(layer "In15.Cu")
		(net "SMB_BIC_I2C6_MUX_SSD_8_15_ADC_R_SDA")
	)
	(segment
		(start 397.598138 -81.025492)
		(end 397.070326 -81.025492)
		(width 0.15494)
		(layer "In15.Cu")
		(net "SMB_BIC_I2C6_MUX_SSD_8_15_ADC_R_SDA")
	)
	(segment
		(start 397.070326 -81.025492)
		(end 396.401036 -80.356202)
		(width 0.15494)
		(layer "In15.Cu")
		(net "SMB_BIC_I2C6_MUX_SSD_8_15_ADC_R_SDA")
	)
	(segment
		(start 418.932106 -80.305402)
		(end 398.318228 -80.305402)
		(width 0.15494)
		(layer "In15.Cu")
		(net "SMB_BIC_I2C6_MUX_SSD_8_15_ADC_R_SDA")
	)
	(segment
		(start 419.593268 -80.966564)
		(end 418.932106 -80.305402)
		(width 0.15494)
		(layer "In15.Cu")
		(net "SMB_BIC_I2C6_MUX_SSD_8_15_ADC_R_SDA")
	)
	(segment
		(start 319.30594 -386.958332)
		(end 319.30594 -387.93293)
		(width 0.13208)
		(layer "F.Cu")
		(net "GPU_FPGA_OVERT_N")
	)
	(segment
		(start 318.577214 -386.958332)
		(end 317.473076 -388.06247)
		(width 0.13208)
		(layer "F.Cu")
		(net "GPU_FPGA_OVERT_N")
	)
	(segment
		(start 319.30594 -387.93293)
		(end 319.296034 -387.942836)
		(width 0.13208)
		(layer "F.Cu")
		(net "GPU_FPGA_OVERT_N")
	)
	(segment
		(start 319.30594 -386.958332)
		(end 318.577214 -386.958332)
		(width 0.13208)
		(layer "F.Cu")
		(net "GPU_FPGA_OVERT_N")
	)
	(via
		(at 317.473076 -388.06247)
		(size 0.508)
		(drill 0.254)
		(layers "F.Cu" "B.Cu")
		(net "GPU_FPGA_OVERT_N")
	)
	(segment
		(start 314.72378 -389.668766)
		(end 315.86678 -389.668766)
		(width 0.15494)
		(layer "In9.Cu")
		(net "GPU_FPGA_OVERT_N")
	)
	(segment
		(start 307.554884 -412.794958)
		(end 310.886856 -409.462986)
		(width 0.15494)
		(layer "In9.Cu")
		(net "GPU_FPGA_OVERT_N")
	)
	(segment
		(start 315.86678 -389.668766)
		(end 317.473076 -388.06247)
		(width 0.15494)
		(layer "In9.Cu")
		(net "GPU_FPGA_OVERT_N")
	)
	(segment
		(start 301.394622 -412.794958)
		(end 307.554884 -412.794958)
		(width 0.15494)
		(layer "In9.Cu")
		(net "GPU_FPGA_OVERT_N")
	)
	(segment
		(start 300.689772 -412.090108)
		(end 301.394622 -412.794958)
		(width 0.15494)
		(layer "In9.Cu")
		(net "GPU_FPGA_OVERT_N")
	)
	(segment
		(start 310.886856 -409.462986)
		(end 310.886856 -393.50569)
		(width 0.15494)
		(layer "In9.Cu")
		(net "GPU_FPGA_OVERT_N")
	)
	(segment
		(start 310.886856 -393.50569)
		(end 314.72378 -389.668766)
		(width 0.15494)
		(layer "In9.Cu")
		(net "GPU_FPGA_OVERT_N")
	)
	(segment
		(start 279.101042 -397.178022)
		(end 279.240234 -397.03883)
		(width 0.13208)
		(layer "F.Cu")
		(net "RST_MB_BIC_N")
	)
	(segment
		(start 270.256 -360.1974)
		(end 278.4602 -360.1974)
		(width 0.13208)
		(layer "F.Cu")
		(net "RST_MB_BIC_N")
	)
	(segment
		(start 265.300968 -355.242368)
		(end 270.256 -360.1974)
		(width 0.13208)
		(layer "F.Cu")
		(net "RST_MB_BIC_N")
	)
	(segment
		(start 265.017758 -342.981788)
		(end 265.017758 -343.863168)
		(width 0.13208)
		(layer "F.Cu")
		(net "RST_MB_BIC_N")
	)
	(segment
		(start 365.252 -359.3084)
		(end 365.571532 -359.3084)
		(width 0.13208)
		(layer "F.Cu")
		(net "RST_MB_BIC_N")
	)
	(segment
		(start 279.101042 -398.000982)
		(end 279.101042 -397.178022)
		(width 0.13208)
		(layer "F.Cu")
		(net "RST_MB_BIC_N")
	)
	(segment
		(start 281.660092 -394.99794)
		(end 281.09545 -395.562582)
		(width 0.13208)
		(layer "F.Cu")
		(net "RST_MB_BIC_N")
	)
	(segment
		(start 278.987504 -395.836902)
		(end 278.987504 -395.562582)
		(width 0.13208)
		(layer "F.Cu")
		(net "RST_MB_BIC_N")
	)
	(segment
		(start 281.09545 -395.562582)
		(end 278.987504 -395.562582)
		(width 0.13208)
		(layer "F.Cu")
		(net "RST_MB_BIC_N")
	)
	(segment
		(start 279.240234 -396.532862)
		(end 279.240234 -396.089632)
		(width 0.13208)
		(layer "F.Cu")
		(net "RST_MB_BIC_N")
	)
	(segment
		(start 278.4602 -360.1974)
		(end 281.660092 -363.397292)
		(width 0.13208)
		(layer "F.Cu")
		(net "RST_MB_BIC_N")
	)
	(segment
		(start 266.61618 -342.255348)
		(end 265.744198 -342.255348)
		(width 0.13208)
		(layer "F.Cu")
		(net "RST_MB_BIC_N")
	)
	(segment
		(start 364.809532 -358.36606)
		(end 364.809532 -358.865932)
		(width 0.13208)
		(layer "F.Cu")
		(net "RST_MB_BIC_N")
	)
	(segment
		(start 281.660092 -363.397292)
		(end 281.660092 -394.99794)
		(width 0.13208)
		(layer "F.Cu")
		(net "RST_MB_BIC_N")
	)
	(segment
		(start 265.017758 -343.863168)
		(end 265.300968 -344.146378)
		(width 0.13208)
		(layer "F.Cu")
		(net "RST_MB_BIC_N")
	)
	(segment
		(start 265.744198 -342.255348)
		(end 265.017758 -342.981788)
		(width 0.13208)
		(layer "F.Cu")
		(net "RST_MB_BIC_N")
	)
	(segment
		(start 265.300968 -344.146378)
		(end 265.300968 -355.242368)
		(width 0.13208)
		(layer "F.Cu")
		(net "RST_MB_BIC_N")
	)
	(segment
		(start 279.240234 -396.089632)
		(end 278.987504 -395.836902)
		(width 0.13208)
		(layer "F.Cu")
		(net "RST_MB_BIC_N")
	)
	(segment
		(start 364.809532 -358.865932)
		(end 365.252 -359.3084)
		(width 0.13208)
		(layer "F.Cu")
		(net "RST_MB_BIC_N")
	)
	(segment
		(start 279.240234 -397.03883)
		(end 279.240234 -396.532862)
		(width 0.13208)
		(layer "F.Cu")
		(net "RST_MB_BIC_N")
	)
	(via
		(at 358.347518 -331.575918)
		(size 0.508)
		(drill 0.254)
		(layers "F.Cu" "B.Cu")
		(net "RST_MB_BIC_N")
	)
	(via
		(at 279.240234 -396.532862)
		(size 0.508)
		(drill 0.254)
		(layers "F.Cu" "B.Cu")
		(net "RST_MB_BIC_N")
	)
	(via
		(at 365.571532 -359.3084)
		(size 0.508)
		(drill 0.254)
		(layers "F.Cu" "B.Cu")
		(net "RST_MB_BIC_N")
	)
	(via
		(at 266.61618 -342.255348)
		(size 0.508)
		(drill 0.254)
		(layers "F.Cu" "B.Cu")
		(net "RST_MB_BIC_N")
	)
	(segment
		(start 346.7862 -341.2236)
		(end 267.1318 -341.2236)
		(width 0.13208)
		(layer "B.Cu")
		(net "RST_MB_BIC_N")
	)
	(segment
		(start 266.5984 -342.237568)
		(end 266.61618 -342.255348)
		(width 0.13208)
		(layer "B.Cu")
		(net "RST_MB_BIC_N")
	)
	(segment
		(start 364.0074 -342.9)
		(end 348.4626 -342.9)
		(width 0.13208)
		(layer "B.Cu")
		(net "RST_MB_BIC_N")
	)
	(segment
		(start 266.5984 -341.757)
		(end 266.5984 -342.237568)
		(width 0.13208)
		(layer "B.Cu")
		(net "RST_MB_BIC_N")
	)
	(segment
		(start 267.1318 -341.2236)
		(end 266.5984 -341.757)
		(width 0.13208)
		(layer "B.Cu")
		(net "RST_MB_BIC_N")
	)
	(segment
		(start 368.9096 -330.073)
		(end 369.2144 -330.3778)
		(width 0.13208)
		(layer "B.Cu")
		(net "RST_MB_BIC_N")
	)
	(segment
		(start 369.2144 -335.967578)
		(end 366.921034 -338.260944)
		(width 0.13208)
		(layer "B.Cu")
		(net "RST_MB_BIC_N")
	)
	(segment
		(start 366.921034 -338.260944)
		(end 366.921034 -339.986366)
		(width 0.13208)
		(layer "B.Cu")
		(net "RST_MB_BIC_N")
	)
	(segment
		(start 358.347518 -331.575918)
		(end 358.347518 -330.744322)
		(width 0.13208)
		(layer "B.Cu")
		(net "RST_MB_BIC_N")
	)
	(segment
		(start 358.347518 -330.744322)
		(end 359.01884 -330.073)
		(width 0.13208)
		(layer "B.Cu")
		(net "RST_MB_BIC_N")
	)
	(segment
		(start 359.01884 -330.073)
		(end 368.9096 -330.073)
		(width 0.13208)
		(layer "B.Cu")
		(net "RST_MB_BIC_N")
	)
	(segment
		(start 348.4626 -342.9)
		(end 346.7862 -341.2236)
		(width 0.13208)
		(layer "B.Cu")
		(net "RST_MB_BIC_N")
	)
	(segment
		(start 369.2144 -330.3778)
		(end 369.2144 -335.967578)
		(width 0.13208)
		(layer "B.Cu")
		(net "RST_MB_BIC_N")
	)
	(segment
		(start 366.921034 -339.986366)
		(end 364.0074 -342.9)
		(width 0.13208)
		(layer "B.Cu")
		(net "RST_MB_BIC_N")
	)
	(segment
		(start 359.295192 -331.575918)
		(end 363.321346 -335.602072)
		(width 0.15494)
		(layer "In9.Cu")
		(net "RST_MB_BIC_N")
	)
	(segment
		(start 358.347518 -331.575918)
		(end 359.295192 -331.575918)
		(width 0.15494)
		(layer "In9.Cu")
		(net "RST_MB_BIC_N")
	)
	(segment
		(start 363.321346 -336.18424)
		(end 365.38154 -338.244434)
		(width 0.15494)
		(layer "In9.Cu")
		(net "RST_MB_BIC_N")
	)
	(segment
		(start 374.19534 -361.388406)
		(end 379.354334 -366.5474)
		(width 0.15494)
		(layer "In9.Cu")
		(net "RST_MB_BIC_N")
	)
	(segment
		(start 367.651538 -361.388406)
		(end 374.19534 -361.388406)
		(width 0.15494)
		(layer "In9.Cu")
		(net "RST_MB_BIC_N")
	)
	(segment
		(start 363.321346 -335.602072)
		(end 363.321346 -336.18424)
		(width 0.15494)
		(layer "In9.Cu")
		(net "RST_MB_BIC_N")
	)
	(segment
		(start 384.047238 -366.5474)
		(end 386.489956 -368.990118)
		(width 0.15494)
		(layer "In9.Cu")
		(net "RST_MB_BIC_N")
	)
	(segment
		(start 365.38154 -338.244434)
		(end 365.38154 -359.118408)
		(width 0.15494)
		(layer "In9.Cu")
		(net "RST_MB_BIC_N")
	)
	(segment
		(start 365.38154 -359.118408)
		(end 365.571532 -359.3084)
		(width 0.15494)
		(layer "In9.Cu")
		(net "RST_MB_BIC_N")
	)
	(segment
		(start 379.354334 -366.5474)
		(end 384.047238 -366.5474)
		(width 0.15494)
		(layer "In9.Cu")
		(net "RST_MB_BIC_N")
	)
	(segment
		(start 365.571532 -359.3084)
		(end 367.651538 -361.388406)
		(width 0.15494)
		(layer "In9.Cu")
		(net "RST_MB_BIC_N")
	)
	(segment
		(start 357.61295 -223.52)
		(end 356.997 -223.52)
		(width 0.13208)
		(layer "F.Cu")
		(net "NIC3_CLK_EN_N")
	)
	(segment
		(start 348.493842 -221.58706)
		(end 348.893892 -221.98711)
		(width 0.13208)
		(layer "F.Cu")
		(net "NIC3_CLK_EN_N")
	)
	(via
		(at 348.893892 -221.98711)
		(size 0.4572)
		(drill 0.254)
		(layers "F.Cu" "B.Cu")
		(net "NIC3_CLK_EN_N")
	)
	(via
		(at 356.997 -223.52)
		(size 0.508)
		(drill 0.254)
		(layers "F.Cu" "B.Cu")
		(net "NIC3_CLK_EN_N")
	)
	(segment
		(start 351.61093 -222.389446)
		(end 349.296228 -222.389446)
		(width 0.0889)
		(layer "In5.Cu")
		(net "NIC3_CLK_EN_N")
	)
	(segment
		(start 349.296228 -222.389446)
		(end 348.893892 -221.98711)
		(width 0.0889)
		(layer "In5.Cu")
		(net "NIC3_CLK_EN_N")
	)
	(segment
		(start 352.741484 -223.52)
		(end 351.61093 -222.389446)
		(width 0.15494)
		(layer "In5.Cu")
		(net "NIC3_CLK_EN_N")
	)
	(segment
		(start 356.997 -223.52)
		(end 352.741484 -223.52)
		(width 0.15494)
		(layer "In5.Cu")
		(net "NIC3_CLK_EN_N")
	)
	(segment
		(start 35.073336 -58.166)
		(end 35.190938 -58.449718)
		(width 0.2032)
		(layer "F.Cu")
		(net "P3V3_SSD1_SS")
	)
	(segment
		(start 34.140902 -57.16397)
		(end 34.140902 -57.233566)
		(width 0.2032)
		(layer "F.Cu")
		(net "P3V3_SSD1_SS")
	)
	(segment
		(start 35.195002 -58.453782)
		(end 35.195002 -59.177936)
		(width 0.2032)
		(layer "F.Cu")
		(net "P3V3_SSD1_SS")
	)
	(segment
		(start 35.190938 -58.449718)
		(end 35.195002 -58.453782)
		(width 0.2032)
		(layer "F.Cu")
		(net "P3V3_SSD1_SS")
	)
	(segment
		(start 34.140902 -57.233566)
		(end 35.073336 -58.166)
		(width 0.2032)
		(layer "F.Cu")
		(net "P3V3_SSD1_SS")
	)
	(via
		(at 35.190938 -58.449718)
		(size 0.508)
		(drill 0.254)
		(layers "F.Cu" "B.Cu")
		(net "P3V3_SSD1_SS")
	)
	(segment
		(start 103.80472 -10.945622)
		(end 103.560118 -10.945622)
		(width 0.13208)
		(layer "F.Cu")
		(net "SMB_ISO_SSD3_SDA")
	)
	(segment
		(start 101.870764 -7.266432)
		(end 102.790244 -8.185912)
		(width 0.13208)
		(layer "F.Cu")
		(net "SMB_ISO_SSD3_SDA")
	)
	(segment
		(start 103.560118 -10.945622)
		(end 102.790244 -10.175748)
		(width 0.13208)
		(layer "F.Cu")
		(net "SMB_ISO_SSD3_SDA")
	)
	(segment
		(start 102.790244 -10.175748)
		(end 102.790244 -10.134092)
		(width 0.13208)
		(layer "F.Cu")
		(net "SMB_ISO_SSD3_SDA")
	)
	(segment
		(start 98.538792 -6.931152)
		(end 98.874072 -7.266432)
		(width 0.13208)
		(layer "F.Cu")
		(net "SMB_ISO_SSD3_SDA")
	)
	(segment
		(start 99.776534 -7.266432)
		(end 101.870764 -7.266432)
		(width 0.13208)
		(layer "F.Cu")
		(net "SMB_ISO_SSD3_SDA")
	)
	(segment
		(start 98.874072 -7.266432)
		(end 99.776534 -7.266432)
		(width 0.13208)
		(layer "F.Cu")
		(net "SMB_ISO_SSD3_SDA")
	)
	(segment
		(start 106.674412 -6.739636)
		(end 107.284012 -6.739636)
		(width 0.13208)
		(layer "F.Cu")
		(net "SMB_ISO_SSD3_SDA")
	)
	(segment
		(start 102.790244 -8.185912)
		(end 102.790244 -10.134092)
		(width 0.13208)
		(layer "F.Cu")
		(net "SMB_ISO_SSD3_SDA")
	)
	(via
		(at 98.538792 -6.931152)
		(size 0.508)
		(drill 0.254)
		(layers "F.Cu" "B.Cu")
		(net "SMB_ISO_SSD3_SDA")
	)
	(via
		(at 107.284012 -6.739636)
		(size 0.508)
		(drill 0.254)
		(layers "F.Cu" "B.Cu")
		(net "SMB_ISO_SSD3_SDA")
	)
	(segment
		(start 100.271326 -5.198618)
		(end 105.742994 -5.198618)
		(width 0.13208)
		(layer "B.Cu")
		(net "SMB_ISO_SSD3_SDA")
	)
	(segment
		(start 98.538792 -6.931152)
		(end 100.271326 -5.198618)
		(width 0.13208)
		(layer "B.Cu")
		(net "SMB_ISO_SSD3_SDA")
	)
	(segment
		(start 105.742994 -5.198618)
		(end 107.284012 -6.739636)
		(width 0.13208)
		(layer "B.Cu")
		(net "SMB_ISO_SSD3_SDA")
	)
	(segment
		(start 379.862334 -86.5378)
		(end 379.252734 -86.5378)
		(width 0.13208)
		(layer "F.Cu")
		(net "SMB_BIC_I2C6_MUX_PEX_ADC_SDA")
	)
	(segment
		(start 380.138686 -86.5378)
		(end 379.862334 -86.5378)
		(width 0.13208)
		(layer "F.Cu")
		(net "SMB_BIC_I2C6_MUX_PEX_ADC_SDA")
	)
	(segment
		(start 382.640078 -86.136734)
		(end 380.539752 -86.136734)
		(width 0.13208)
		(layer "F.Cu")
		(net "SMB_BIC_I2C6_MUX_PEX_ADC_SDA")
	)
	(segment
		(start 380.539752 -86.136734)
		(end 380.138686 -86.5378)
		(width 0.13208)
		(layer "F.Cu")
		(net "SMB_BIC_I2C6_MUX_PEX_ADC_SDA")
	)
	(via
		(at 379.862334 -86.5378)
		(size 0.508)
		(drill 0.254)
		(layers "F.Cu" "B.Cu")
		(net "SMB_BIC_I2C6_MUX_PEX_ADC_SDA")
	)
	(segment
		(start 331.978 -243.967)
		(end 331.978 -244.83695)
		(width 0.13208)
		(layer "F.Cu")
		(net "RST_MB_PERST_0_N")
	)
	(segment
		(start 331.842364 -243.450364)
		(end 331.978 -243.586)
		(width 0.13208)
		(layer "F.Cu")
		(net "RST_MB_PERST_0_N")
	)
	(segment
		(start 103.62438 -367.598198)
		(end 103.62438 -368.236754)
		(width 0.13208)
		(layer "F.Cu")
		(net "RST_MB_PERST_0_N")
	)
	(segment
		(start 103.55326 -366.507268)
		(end 103.55326 -367.450878)
		(width 0.13208)
		(layer "F.Cu")
		(net "RST_MB_PERST_0_N")
	)
	(segment
		(start 103.51516 -367.488978)
		(end 103.62438 -367.598198)
		(width 0.13208)
		(layer "F.Cu")
		(net "RST_MB_PERST_0_N")
	)
	(segment
		(start 331.978 -243.586)
		(end 331.978 -243.967)
		(width 0.13208)
		(layer "F.Cu")
		(net "RST_MB_PERST_0_N")
	)
	(segment
		(start 331.842364 -242.848892)
		(end 331.842364 -243.450364)
		(width 0.13208)
		(layer "F.Cu")
		(net "RST_MB_PERST_0_N")
	)
	(segment
		(start 103.55326 -367.450878)
		(end 103.51516 -367.488978)
		(width 0.13208)
		(layer "F.Cu")
		(net "RST_MB_PERST_0_N")
	)
	(via
		(at 103.62438 -368.236754)
		(size 0.508)
		(drill 0.254)
		(layers "F.Cu" "B.Cu")
		(net "RST_MB_PERST_0_N")
	)
	(via
		(at 331.978 -243.967)
		(size 0.508)
		(drill 0.254)
		(layers "F.Cu" "B.Cu")
		(net "RST_MB_PERST_0_N")
	)
	(via
		(at 199.001126 -361.86237)
		(size 0.508)
		(drill 0.254)
		(layers "F.Cu" "B.Cu")
		(net "RST_MB_PERST_0_N")
	)
	(via
		(at 231.340152 -330.061824)
		(size 0.508)
		(drill 0.254)
		(layers "F.Cu" "B.Cu")
		(net "RST_MB_PERST_0_N")
	)
	(via
		(at 237.838234 -241.676936)
		(size 0.508)
		(drill 0.254)
		(layers "F.Cu" "B.Cu")
		(net "RST_MB_PERST_0_N")
	)
	(segment
		(start 198.6153 -361.476544)
		(end 199.001126 -361.86237)
		(width 0.13208)
		(layer "B.Cu")
		(net "RST_MB_PERST_0_N")
	)
	(segment
		(start 245.322852 -327.42886)
		(end 235.826046 -327.42886)
		(width 0.13208)
		(layer "B.Cu")
		(net "RST_MB_PERST_0_N")
	)
	(segment
		(start 108.712762 -367.666524)
		(end 114.902742 -361.476544)
		(width 0.13208)
		(layer "B.Cu")
		(net "RST_MB_PERST_0_N")
	)
	(segment
		(start 237.838234 -241.676936)
		(end 238.907828 -242.74653)
		(width 0.13208)
		(layer "B.Cu")
		(net "RST_MB_PERST_0_N")
	)
	(segment
		(start 244.644164 -252.782578)
		(end 248.125234 -256.263648)
		(width 0.13208)
		(layer "B.Cu")
		(net "RST_MB_PERST_0_N")
	)
	(segment
		(start 240.755678 -252.782578)
		(end 244.644164 -252.782578)
		(width 0.13208)
		(layer "B.Cu")
		(net "RST_MB_PERST_0_N")
	)
	(segment
		(start 235.826046 -327.42886)
		(end 233.193082 -330.061824)
		(width 0.13208)
		(layer "B.Cu")
		(net "RST_MB_PERST_0_N")
	)
	(segment
		(start 103.62438 -368.236754)
		(end 104.19461 -367.666524)
		(width 0.13208)
		(layer "B.Cu")
		(net "RST_MB_PERST_0_N")
	)
	(segment
		(start 104.19461 -367.666524)
		(end 108.712762 -367.666524)
		(width 0.13208)
		(layer "B.Cu")
		(net "RST_MB_PERST_0_N")
	)
	(segment
		(start 248.125234 -256.263648)
		(end 248.125234 -264.818368)
		(width 0.13208)
		(layer "B.Cu")
		(net "RST_MB_PERST_0_N")
	)
	(segment
		(start 238.907828 -250.934728)
		(end 240.755678 -252.782578)
		(width 0.13208)
		(layer "B.Cu")
		(net "RST_MB_PERST_0_N")
	)
	(segment
		(start 256.668016 -285.444184)
		(end 256.668016 -305.622198)
		(width 0.13208)
		(layer "B.Cu")
		(net "RST_MB_PERST_0_N")
	)
	(segment
		(start 248.125234 -264.818368)
		(end 256.668016 -285.444184)
		(width 0.13208)
		(layer "B.Cu")
		(net "RST_MB_PERST_0_N")
	)
	(segment
		(start 249.270266 -323.481446)
		(end 245.322852 -327.42886)
		(width 0.13208)
		(layer "B.Cu")
		(net "RST_MB_PERST_0_N")
	)
	(segment
		(start 114.902742 -361.476544)
		(end 198.6153 -361.476544)
		(width 0.13208)
		(layer "B.Cu")
		(net "RST_MB_PERST_0_N")
	)
	(segment
		(start 238.907828 -242.74653)
		(end 238.907828 -250.934728)
		(width 0.13208)
		(layer "B.Cu")
		(net "RST_MB_PERST_0_N")
	)
	(segment
		(start 233.193082 -330.061824)
		(end 231.340152 -330.061824)
		(width 0.13208)
		(layer "B.Cu")
		(net "RST_MB_PERST_0_N")
	)
	(segment
		(start 256.668016 -305.622198)
		(end 249.270266 -323.481446)
		(width 0.13208)
		(layer "B.Cu")
		(net "RST_MB_PERST_0_N")
	)
	(segment
		(start 218.649296 -356.286308)
		(end 206.41437 -356.286308)
		(width 0.15494)
		(layer "In5.Cu")
		(net "RST_MB_PERST_0_N")
	)
	(segment
		(start 202.440286 -360.260392)
		(end 202.005184 -360.440732)
		(width 0.15494)
		(layer "In5.Cu")
		(net "RST_MB_PERST_0_N")
	)
	(segment
		(start 228.257608 -332.812898)
		(end 228.257608 -346.677996)
		(width 0.15494)
		(layer "In5.Cu")
		(net "RST_MB_PERST_0_N")
	)
	(segment
		(start 231.008682 -330.061824)
		(end 228.257608 -332.812898)
		(width 0.15494)
		(layer "In5.Cu")
		(net "RST_MB_PERST_0_N")
	)
	(segment
		(start 228.257608 -346.677996)
		(end 218.649296 -356.286308)
		(width 0.15494)
		(layer "In5.Cu")
		(net "RST_MB_PERST_0_N")
	)
	(segment
		(start 231.340152 -330.061824)
		(end 231.008682 -330.061824)
		(width 0.15494)
		(layer "In5.Cu")
		(net "RST_MB_PERST_0_N")
	)
	(segment
		(start 199.001126 -361.296458)
		(end 199.001126 -361.86237)
		(width 0.15494)
		(layer "In5.Cu")
		(net "RST_MB_PERST_0_N")
	)
	(segment
		(start 202.005184 -360.440732)
		(end 199.856852 -360.440732)
		(width 0.15494)
		(layer "In5.Cu")
		(net "RST_MB_PERST_0_N")
	)
	(segment
		(start 206.41437 -356.286308)
		(end 202.440286 -360.260392)
		(width 0.15494)
		(layer "In5.Cu")
		(net "RST_MB_PERST_0_N")
	)
	(segment
		(start 199.856852 -360.440732)
		(end 199.001126 -361.296458)
		(width 0.15494)
		(layer "In5.Cu")
		(net "RST_MB_PERST_0_N")
	)
	(segment
		(start 326.068436 -244.7544)
		(end 325.599552 -245.223284)
		(width 0.15494)
		(layer "In13.Cu")
		(net "RST_MB_PERST_0_N")
	)
	(segment
		(start 260.685026 -243.052346)
		(end 260.146292 -243.59108)
		(width 0.15494)
		(layer "In13.Cu")
		(net "RST_MB_PERST_0_N")
	)
	(segment
		(start 238.46917 -241.046)
		(end 237.838234 -241.676936)
		(width 0.15494)
		(layer "In13.Cu")
		(net "RST_MB_PERST_0_N")
	)
	(segment
		(start 329.9206 -244.3734)
		(end 329.5396 -244.7544)
		(width 0.15494)
		(layer "In13.Cu")
		(net "RST_MB_PERST_0_N")
	)
	(segment
		(start 329.5396 -244.7544)
		(end 326.068436 -244.7544)
		(width 0.15494)
		(layer "In13.Cu")
		(net "RST_MB_PERST_0_N")
	)
	(segment
		(start 301.204884 -245.223284)
		(end 300.349412 -244.367812)
		(width 0.15494)
		(layer "In13.Cu")
		(net "RST_MB_PERST_0_N")
	)
	(segment
		(start 262.268208 -243.650008)
		(end 261.670546 -243.052346)
		(width 0.15494)
		(layer "In13.Cu")
		(net "RST_MB_PERST_0_N")
	)
	(segment
		(start 275.478748 -243.650008)
		(end 262.268208 -243.650008)
		(width 0.15494)
		(layer "In13.Cu")
		(net "RST_MB_PERST_0_N")
	)
	(segment
		(start 255.19888 -243.59108)
		(end 253.7206 -242.1128)
		(width 0.15494)
		(layer "In13.Cu")
		(net "RST_MB_PERST_0_N")
	)
	(segment
		(start 331.978 -243.967)
		(end 331.5716 -244.3734)
		(width 0.15494)
		(layer "In13.Cu")
		(net "RST_MB_PERST_0_N")
	)
	(segment
		(start 253.7206 -242.1128)
		(end 240.106454 -242.1128)
		(width 0.15494)
		(layer "In13.Cu")
		(net "RST_MB_PERST_0_N")
	)
	(segment
		(start 239.039654 -241.046)
		(end 238.46917 -241.046)
		(width 0.15494)
		(layer "In13.Cu")
		(net "RST_MB_PERST_0_N")
	)
	(segment
		(start 240.106454 -242.1128)
		(end 239.039654 -241.046)
		(width 0.15494)
		(layer "In13.Cu")
		(net "RST_MB_PERST_0_N")
	)
	(segment
		(start 300.349412 -244.367812)
		(end 276.196552 -244.367812)
		(width 0.15494)
		(layer "In13.Cu")
		(net "RST_MB_PERST_0_N")
	)
	(segment
		(start 260.146292 -243.59108)
		(end 255.19888 -243.59108)
		(width 0.15494)
		(layer "In13.Cu")
		(net "RST_MB_PERST_0_N")
	)
	(segment
		(start 276.196552 -244.367812)
		(end 275.478748 -243.650008)
		(width 0.15494)
		(layer "In13.Cu")
		(net "RST_MB_PERST_0_N")
	)
	(segment
		(start 261.670546 -243.052346)
		(end 260.685026 -243.052346)
		(width 0.15494)
		(layer "In13.Cu")
		(net "RST_MB_PERST_0_N")
	)
	(segment
		(start 325.599552 -245.223284)
		(end 301.204884 -245.223284)
		(width 0.15494)
		(layer "In13.Cu")
		(net "RST_MB_PERST_0_N")
	)
	(segment
		(start 331.5716 -244.3734)
		(end 329.9206 -244.3734)
		(width 0.15494)
		(layer "In13.Cu")
		(net "RST_MB_PERST_0_N")
	)
	(segment
		(start 91.710002 -368.990118)
		(end 100.605336 -368.990118)
		(width 0.15494)
		(layer "In15.Cu")
		(net "RST_MB_PERST_0_N")
	)
	(segment
		(start 101.3587 -368.236754)
		(end 103.62438 -368.236754)
		(width 0.15494)
		(layer "In15.Cu")
		(net "RST_MB_PERST_0_N")
	)
	(segment
		(start 100.605336 -368.990118)
		(end 101.3587 -368.236754)
		(width 0.15494)
		(layer "In15.Cu")
		(net "RST_MB_PERST_0_N")
	)
	(segment
		(start 239.158018 -170.625008)
		(end 241.406426 -172.873416)
		(width 0.1143)
		(layer "F.Cu")
		(net "CLK_100M_DB2000QL_PEX3_S1_R_DP")
	)
	(segment
		(start 130.419856 -170.199812)
		(end 130.7338 -169.885868)
		(width 0.1143)
		(layer "F.Cu")
		(net "CLK_100M_DB2000QL_PEX3_S1_R_DP")
	)
	(segment
		(start 130.7338 -167.677846)
		(end 131.957064 -166.454582)
		(width 0.1143)
		(layer "F.Cu")
		(net "CLK_100M_DB2000QL_PEX3_S1_R_DP")
	)
	(segment
		(start 183.022494 -184.0357)
		(end 208.114392 -173.642274)
		(width 0.1143)
		(layer "F.Cu")
		(net "CLK_100M_DB2000QL_PEX3_S1_R_DP")
	)
	(segment
		(start 130.7338 -169.885868)
		(end 130.7338 -167.677846)
		(width 0.1143)
		(layer "F.Cu")
		(net "CLK_100M_DB2000QL_PEX3_S1_R_DP")
	)
	(segment
		(start 241.406426 -172.873416)
		(end 257.710686 -172.873416)
		(width 0.1143)
		(layer "F.Cu")
		(net "CLK_100M_DB2000QL_PEX3_S1_R_DP")
	)
	(segment
		(start 131.957064 -166.454582)
		(end 140.775182 -166.454582)
		(width 0.1143)
		(layer "F.Cu")
		(net "CLK_100M_DB2000QL_PEX3_S1_R_DP")
	)
	(segment
		(start 211.967572 -173.642274)
		(end 214.984838 -170.625008)
		(width 0.1143)
		(layer "F.Cu")
		(net "CLK_100M_DB2000QL_PEX3_S1_R_DP")
	)
	(segment
		(start 386.099812 -297.79976)
		(end 386.099558 -297.79976)
		(width 0.1143)
		(layer "F.Cu")
		(net "CLK_100M_DB2000QL_PEX3_S1_R_DP")
	)
	(segment
		(start 140.775182 -166.454582)
		(end 158.3563 -184.0357)
		(width 0.1143)
		(layer "F.Cu")
		(net "CLK_100M_DB2000QL_PEX3_S1_R_DP")
	)
	(segment
		(start 158.3563 -184.0357)
		(end 183.022494 -184.0357)
		(width 0.1143)
		(layer "F.Cu")
		(net "CLK_100M_DB2000QL_PEX3_S1_R_DP")
	)
	(segment
		(start 214.984838 -170.625008)
		(end 239.158018 -170.625008)
		(width 0.1143)
		(layer "F.Cu")
		(net "CLK_100M_DB2000QL_PEX3_S1_R_DP")
	)
	(segment
		(start 257.710686 -172.873416)
		(end 257.723386 -172.886116)
		(width 0.1143)
		(layer "F.Cu")
		(net "CLK_100M_DB2000QL_PEX3_S1_R_DP")
	)
	(segment
		(start 257.723386 -172.886116)
		(end 257.977386 -172.632116)
		(width 0.1143)
		(layer "F.Cu")
		(net "CLK_100M_DB2000QL_PEX3_S1_R_DP")
	)
	(segment
		(start 386.099558 -297.79976)
		(end 385.624578 -297.32478)
		(width 0.1143)
		(layer "F.Cu")
		(net "CLK_100M_DB2000QL_PEX3_S1_R_DP")
	)
	(segment
		(start 208.114392 -173.642274)
		(end 211.967572 -173.642274)
		(width 0.1143)
		(layer "F.Cu")
		(net "CLK_100M_DB2000QL_PEX3_S1_R_DP")
	)
	(via
		(at 257.977386 -172.632116)
		(size 0.508)
		(drill 0.254)
		(layers "F.Cu" "B.Cu")
		(net "CLK_100M_DB2000QL_PEX3_S1_R_DP")
	)
	(via
		(at 385.624578 -297.32478)
		(size 0.4064)
		(drill 0.2032)
		(layers "F.Cu" "B.Cu")
		(net "CLK_100M_DB2000QL_PEX3_S1_R_DP")
	)
	(segment
		(start 385.257548 -297.025822)
		(end 384.979926 -296.7482)
		(width 0.0889)
		(layer "B.Cu")
		(net "CLK_100M_DB2000QL_PEX3_S1_R_DP")
	)
	(segment
		(start 385.257548 -297.24858)
		(end 385.257548 -297.025822)
		(width 0.0889)
		(layer "B.Cu")
		(net "CLK_100M_DB2000QL_PEX3_S1_R_DP")
	)
	(segment
		(start 329.679046 -241.439446)
		(end 328.3585 -240.1189)
		(width 0.1143)
		(layer "B.Cu")
		(net "CLK_100M_DB2000QL_PEX3_S1_R_DP")
	)
	(segment
		(start 377.0249 -276.8473)
		(end 376.734832 -276.8473)
		(width 0.1143)
		(layer "B.Cu")
		(net "CLK_100M_DB2000QL_PEX3_S1_R_DP")
	)
	(segment
		(start 383.7178 -296.66565)
		(end 383.695702 -296.66565)
		(width 0.0889)
		(layer "B.Cu")
		(net "CLK_100M_DB2000QL_PEX3_S1_R_DP")
	)
	(segment
		(start 316.1538 -224.7265)
		(end 302.1965 -210.7692)
		(width 0.1143)
		(layer "B.Cu")
		(net "CLK_100M_DB2000QL_PEX3_S1_R_DP")
	)
	(segment
		(start 259.17144 -172.873416)
		(end 258.218686 -172.873416)
		(width 0.1143)
		(layer "B.Cu")
		(net "CLK_100M_DB2000QL_PEX3_S1_R_DP")
	)
	(segment
		(start 293.9542 -210.7692)
		(end 264.276586 -181.091586)
		(width 0.1143)
		(layer "B.Cu")
		(net "CLK_100M_DB2000QL_PEX3_S1_R_DP")
	)
	(segment
		(start 381.673354 -294.8051)
		(end 379.645418 -294.8051)
		(width 0.1143)
		(layer "B.Cu")
		(net "CLK_100M_DB2000QL_PEX3_S1_R_DP")
	)
	(segment
		(start 383.80035 -296.7482)
		(end 383.7178 -296.66565)
		(width 0.0889)
		(layer "B.Cu")
		(net "CLK_100M_DB2000QL_PEX3_S1_R_DP")
	)
	(segment
		(start 364.819946 -240.919)
		(end 352.589592 -240.919)
		(width 0.1143)
		(layer "B.Cu")
		(net "CLK_100M_DB2000QL_PEX3_S1_R_DP")
	)
	(segment
		(start 352.069146 -241.439446)
		(end 329.679046 -241.439446)
		(width 0.1143)
		(layer "B.Cu")
		(net "CLK_100M_DB2000QL_PEX3_S1_R_DP")
	)
	(segment
		(start 368.9096 -269.022068)
		(end 368.9096 -245.008654)
		(width 0.1143)
		(layer "B.Cu")
		(net "CLK_100M_DB2000QL_PEX3_S1_R_DP")
	)
	(segment
		(start 264.276586 -181.091586)
		(end 264.276586 -177.978562)
		(width 0.1143)
		(layer "B.Cu")
		(net "CLK_100M_DB2000QL_PEX3_S1_R_DP")
	)
	(segment
		(start 385.333748 -297.32478)
		(end 385.257548 -297.24858)
		(width 0.0889)
		(layer "B.Cu")
		(net "CLK_100M_DB2000QL_PEX3_S1_R_DP")
	)
	(segment
		(start 379.255274 -279.077674)
		(end 377.0249 -276.8473)
		(width 0.1143)
		(layer "B.Cu")
		(net "CLK_100M_DB2000QL_PEX3_S1_R_DP")
	)
	(segment
		(start 383.533904 -296.66565)
		(end 381.673354 -294.8051)
		(width 0.1143)
		(layer "B.Cu")
		(net "CLK_100M_DB2000QL_PEX3_S1_R_DP")
	)
	(segment
		(start 302.1965 -210.7692)
		(end 293.9542 -210.7692)
		(width 0.1143)
		(layer "B.Cu")
		(net "CLK_100M_DB2000QL_PEX3_S1_R_DP")
	)
	(segment
		(start 379.255274 -294.414956)
		(end 379.255274 -279.077674)
		(width 0.1143)
		(layer "B.Cu")
		(net "CLK_100M_DB2000QL_PEX3_S1_R_DP")
	)
	(segment
		(start 352.589592 -240.919)
		(end 352.069146 -241.439446)
		(width 0.1143)
		(layer "B.Cu")
		(net "CLK_100M_DB2000QL_PEX3_S1_R_DP")
	)
	(segment
		(start 368.9096 -245.008654)
		(end 364.819946 -240.919)
		(width 0.1143)
		(layer "B.Cu")
		(net "CLK_100M_DB2000QL_PEX3_S1_R_DP")
	)
	(segment
		(start 376.734832 -276.8473)
		(end 368.9096 -269.022068)
		(width 0.1143)
		(layer "B.Cu")
		(net "CLK_100M_DB2000QL_PEX3_S1_R_DP")
	)
	(segment
		(start 379.645418 -294.8051)
		(end 379.255274 -294.414956)
		(width 0.1143)
		(layer "B.Cu")
		(net "CLK_100M_DB2000QL_PEX3_S1_R_DP")
	)
	(segment
		(start 258.218686 -172.873416)
		(end 257.977386 -172.632116)
		(width 0.1143)
		(layer "B.Cu")
		(net "CLK_100M_DB2000QL_PEX3_S1_R_DP")
	)
	(segment
		(start 328.3585 -240.1189)
		(end 322.1355 -240.1189)
		(width 0.1143)
		(layer "B.Cu")
		(net "CLK_100M_DB2000QL_PEX3_S1_R_DP")
	)
	(segment
		(start 385.624578 -297.32478)
		(end 385.333748 -297.32478)
		(width 0.0889)
		(layer "B.Cu")
		(net "CLK_100M_DB2000QL_PEX3_S1_R_DP")
	)
	(segment
		(start 322.1355 -240.1189)
		(end 316.1538 -234.1372)
		(width 0.1143)
		(layer "B.Cu")
		(net "CLK_100M_DB2000QL_PEX3_S1_R_DP")
	)
	(segment
		(start 264.276586 -177.978562)
		(end 259.17144 -172.873416)
		(width 0.1143)
		(layer "B.Cu")
		(net "CLK_100M_DB2000QL_PEX3_S1_R_DP")
	)
	(segment
		(start 316.1538 -234.1372)
		(end 316.1538 -224.7265)
		(width 0.1143)
		(layer "B.Cu")
		(net "CLK_100M_DB2000QL_PEX3_S1_R_DP")
	)
	(segment
		(start 383.695702 -296.66565)
		(end 383.533904 -296.66565)
		(width 0.1143)
		(layer "B.Cu")
		(net "CLK_100M_DB2000QL_PEX3_S1_R_DP")
	)
	(segment
		(start 384.979926 -296.7482)
		(end 383.80035 -296.7482)
		(width 0.0889)
		(layer "B.Cu")
		(net "CLK_100M_DB2000QL_PEX3_S1_R_DP")
	)
	(segment
		(start 256.551938 -87.429086)
		(end 256.48158 -87.499444)
		(width 0.2032)
		(layer "F.Cu")
		(net "P3V3_CLK_GEN_VDDA25M_CK440")
	)
	(segment
		(start 256.551938 -86.806532)
		(end 256.551938 -87.429086)
		(width 0.2032)
		(layer "F.Cu")
		(net "P3V3_CLK_GEN_VDDA25M_CK440")
	)
	(via
		(at 257.659124 -87.53348)
		(size 0.6604)
		(drill 0.3302)
		(layers "F.Cu" "B.Cu")
		(net "P3V3_CLK_GEN_VDDA25M_CK440")
	)
	(via
		(at 256.48158 -87.499444)
		(size 0.508)
		(drill 0.254)
		(layers "F.Cu" "B.Cu")
		(net "P3V3_CLK_GEN_VDDA25M_CK440")
	)
	(segment
		(start 255.951482 -86.969346)
		(end 256.48158 -87.499444)
		(width 0.381)
		(layer "B.Cu")
		(net "P3V3_CLK_GEN_VDDA25M_CK440")
	)
	(segment
		(start 255.951482 -86.32952)
		(end 255.951482 -86.969346)
		(width 0.381)
		(layer "B.Cu")
		(net "P3V3_CLK_GEN_VDDA25M_CK440")
	)
	(segment
		(start 99.776534 -7.916672)
		(end 101.820472 -7.916672)
		(width 0.13208)
		(layer "F.Cu")
		(net "SMB_ISO_SSD3_SCL")
	)
	(segment
		(start 106.6927 -7.742682)
		(end 107.3023 -7.742682)
		(width 0.13208)
		(layer "F.Cu")
		(net "SMB_ISO_SSD3_SCL")
	)
	(segment
		(start 101.774244 -10.17778)
		(end 101.774244 -10.134092)
		(width 0.13208)
		(layer "F.Cu")
		(net "SMB_ISO_SSD3_SCL")
	)
	(segment
		(start 98.707448 -7.916672)
		(end 99.776534 -7.916672)
		(width 0.13208)
		(layer "F.Cu")
		(net "SMB_ISO_SSD3_SCL")
	)
	(segment
		(start 102.327964 -9.580372)
		(end 101.774244 -10.134092)
		(width 0.13208)
		(layer "F.Cu")
		(net "SMB_ISO_SSD3_SCL")
	)
	(segment
		(start 102.327964 -8.424164)
		(end 102.327964 -9.580372)
		(width 0.13208)
		(layer "F.Cu")
		(net "SMB_ISO_SSD3_SCL")
	)
	(segment
		(start 101.820472 -7.916672)
		(end 102.327964 -8.424164)
		(width 0.13208)
		(layer "F.Cu")
		(net "SMB_ISO_SSD3_SCL")
	)
	(segment
		(start 100.75672 -10.945622)
		(end 101.006402 -10.945622)
		(width 0.13208)
		(layer "F.Cu")
		(net "SMB_ISO_SSD3_SCL")
	)
	(segment
		(start 101.006402 -10.945622)
		(end 101.774244 -10.17778)
		(width 0.13208)
		(layer "F.Cu")
		(net "SMB_ISO_SSD3_SCL")
	)
	(via
		(at 98.707448 -7.916672)
		(size 0.508)
		(drill 0.254)
		(layers "F.Cu" "B.Cu")
		(net "SMB_ISO_SSD3_SCL")
	)
	(via
		(at 107.3023 -7.742682)
		(size 0.508)
		(drill 0.254)
		(layers "F.Cu" "B.Cu")
		(net "SMB_ISO_SSD3_SCL")
	)
	(segment
		(start 105.992422 -6.432804)
		(end 107.3023 -7.742682)
		(width 0.13208)
		(layer "B.Cu")
		(net "SMB_ISO_SSD3_SCL")
	)
	(segment
		(start 100.191316 -6.432804)
		(end 105.992422 -6.432804)
		(width 0.13208)
		(layer "B.Cu")
		(net "SMB_ISO_SSD3_SCL")
	)
	(segment
		(start 98.707448 -7.916672)
		(end 100.191316 -6.432804)
		(width 0.13208)
		(layer "B.Cu")
		(net "SMB_ISO_SSD3_SCL")
	)
	(segment
		(start 370.958364 -19.453098)
		(end 371.567964 -19.453098)
		(width 0.13208)
		(layer "F.Cu")
		(net "SMB_ISO_SSD12_R_SDA")
	)
	(segment
		(start 358.964992 -22.990048)
		(end 360.00944 -22.990048)
		(width 0.13208)
		(layer "F.Cu")
		(net "SMB_ISO_SSD12_R_SDA")
	)
	(segment
		(start 360.00944 -22.990048)
		(end 360.044492 -23.0251)
		(width 0.13208)
		(layer "F.Cu")
		(net "SMB_ISO_SSD12_R_SDA")
	)
	(via
		(at 360.044492 -23.0251)
		(size 0.508)
		(drill 0.254)
		(layers "F.Cu" "B.Cu")
		(net "SMB_ISO_SSD12_R_SDA")
	)
	(via
		(at 370.958364 -19.453098)
		(size 0.508)
		(drill 0.254)
		(layers "F.Cu" "B.Cu")
		(net "SMB_ISO_SSD12_R_SDA")
	)
	(segment
		(start 360.537252 -22.53234)
		(end 360.044492 -23.0251)
		(width 0.15494)
		(layer "In5.Cu")
		(net "SMB_ISO_SSD12_R_SDA")
	)
	(segment
		(start 369.81638 -22.53234)
		(end 360.537252 -22.53234)
		(width 0.15494)
		(layer "In5.Cu")
		(net "SMB_ISO_SSD12_R_SDA")
	)
	(segment
		(start 370.958364 -21.390356)
		(end 369.81638 -22.53234)
		(width 0.15494)
		(layer "In5.Cu")
		(net "SMB_ISO_SSD12_R_SDA")
	)
	(segment
		(start 370.958364 -19.453098)
		(end 370.958364 -21.390356)
		(width 0.15494)
		(layer "In5.Cu")
		(net "SMB_ISO_SSD12_R_SDA")
	)
	(segment
		(start 240.034572 -70.116954)
		(end 240.1316 -70.213982)
		(width 0.13208)
		(layer "F.Cu")
		(net "SMB_BIC_I2C6_MUX_SSD_0_7_ADC_SCL")
	)
	(segment
		(start 222.282258 -68.026026)
		(end 222.282258 -62.054994)
		(width 0.13208)
		(layer "F.Cu")
		(net "SMB_BIC_I2C6_MUX_SSD_0_7_ADC_SCL")
	)
	(segment
		(start 226.90455 -72.648318)
		(end 222.282258 -68.026026)
		(width 0.13208)
		(layer "F.Cu")
		(net "SMB_BIC_I2C6_MUX_SSD_0_7_ADC_SCL")
	)
	(segment
		(start 260.912864 -73.51776)
		(end 261.207504 -73.8124)
		(width 0.13208)
		(layer "F.Cu")
		(net "SMB_BIC_I2C6_MUX_SSD_0_7_ADC_SCL")
	)
	(segment
		(start 240.1316 -71.780146)
		(end 239.263428 -72.648318)
		(width 0.13208)
		(layer "F.Cu")
		(net "SMB_BIC_I2C6_MUX_SSD_0_7_ADC_SCL")
	)
	(segment
		(start 261.207504 -73.8124)
		(end 270.27632 -73.8124)
		(width 0.13208)
		(layer "F.Cu")
		(net "SMB_BIC_I2C6_MUX_SSD_0_7_ADC_SCL")
	)
	(segment
		(start 223.139 -61.198252)
		(end 223.139 -50.927)
		(width 0.13208)
		(layer "F.Cu")
		(net "SMB_BIC_I2C6_MUX_SSD_0_7_ADC_SCL")
	)
	(segment
		(start 380.80442 -82.066638)
		(end 380.80442 -82.498184)
		(width 0.13208)
		(layer "F.Cu")
		(net "SMB_BIC_I2C6_MUX_SSD_0_7_ADC_SCL")
	)
	(segment
		(start 379.560582 -80.8228)
		(end 380.80442 -82.066638)
		(width 0.13208)
		(layer "F.Cu")
		(net "SMB_BIC_I2C6_MUX_SSD_0_7_ADC_SCL")
	)
	(segment
		(start 270.27632 -73.8124)
		(end 280.271728 -83.807808)
		(width 0.13208)
		(layer "F.Cu")
		(net "SMB_BIC_I2C6_MUX_SSD_0_7_ADC_SCL")
	)
	(segment
		(start 239.263428 -72.648318)
		(end 226.90455 -72.648318)
		(width 0.13208)
		(layer "F.Cu")
		(net "SMB_BIC_I2C6_MUX_SSD_0_7_ADC_SCL")
	)
	(segment
		(start 377.778772 -80.8228)
		(end 379.560582 -80.8228)
		(width 0.13208)
		(layer "F.Cu")
		(net "SMB_BIC_I2C6_MUX_SSD_0_7_ADC_SCL")
	)
	(segment
		(start 380.80442 -82.498184)
		(end 381.192786 -82.88655)
		(width 0.13208)
		(layer "F.Cu")
		(net "SMB_BIC_I2C6_MUX_SSD_0_7_ADC_SCL")
	)
	(segment
		(start 240.1316 -70.213982)
		(end 240.1316 -71.780146)
		(width 0.13208)
		(layer "F.Cu")
		(net "SMB_BIC_I2C6_MUX_SSD_0_7_ADC_SCL")
	)
	(segment
		(start 222.282258 -62.054994)
		(end 223.139 -61.198252)
		(width 0.13208)
		(layer "F.Cu")
		(net "SMB_BIC_I2C6_MUX_SSD_0_7_ADC_SCL")
	)
	(segment
		(start 381.192786 -82.88655)
		(end 382.640078 -82.88655)
		(width 0.13208)
		(layer "F.Cu")
		(net "SMB_BIC_I2C6_MUX_SSD_0_7_ADC_SCL")
	)
	(segment
		(start 280.271728 -83.807808)
		(end 280.271728 -86.498176)
		(width 0.13208)
		(layer "F.Cu")
		(net "SMB_BIC_I2C6_MUX_SSD_0_7_ADC_SCL")
	)
	(via
		(at 280.271728 -86.498176)
		(size 0.508)
		(drill 0.254)
		(layers "F.Cu" "B.Cu")
		(net "SMB_BIC_I2C6_MUX_SSD_0_7_ADC_SCL")
	)
	(via
		(at 240.034572 -70.116954)
		(size 0.508)
		(drill 0.254)
		(layers "F.Cu" "B.Cu")
		(net "SMB_BIC_I2C6_MUX_SSD_0_7_ADC_SCL")
	)
	(via
		(at 377.778772 -80.8228)
		(size 0.508)
		(drill 0.254)
		(layers "F.Cu" "B.Cu")
		(net "SMB_BIC_I2C6_MUX_SSD_0_7_ADC_SCL")
	)
	(via
		(at 260.912864 -73.51776)
		(size 0.508)
		(drill 0.254)
		(layers "F.Cu" "B.Cu")
		(net "SMB_BIC_I2C6_MUX_SSD_0_7_ADC_SCL")
	)
	(segment
		(start 260.912864 -73.51776)
		(end 260.664706 -73.51776)
		(width 0.15494)
		(layer "In11.Cu")
		(net "SMB_BIC_I2C6_MUX_SSD_0_7_ADC_SCL")
	)
	(segment
		(start 240.628678 -69.522848)
		(end 240.034572 -70.116954)
		(width 0.15494)
		(layer "In11.Cu")
		(net "SMB_BIC_I2C6_MUX_SSD_0_7_ADC_SCL")
	)
	(segment
		(start 260.664706 -73.51776)
		(end 256.669794 -69.522848)
		(width 0.15494)
		(layer "In11.Cu")
		(net "SMB_BIC_I2C6_MUX_SSD_0_7_ADC_SCL")
	)
	(segment
		(start 256.669794 -69.522848)
		(end 240.628678 -69.522848)
		(width 0.15494)
		(layer "In11.Cu")
		(net "SMB_BIC_I2C6_MUX_SSD_0_7_ADC_SCL")
	)
	(segment
		(start 338.1502 -93.522546)
		(end 333.857854 -89.2302)
		(width 0.15494)
		(layer "In13.Cu")
		(net "SMB_BIC_I2C6_MUX_SSD_0_7_ADC_SCL")
	)
	(segment
		(start 369.469162 -82.574892)
		(end 368.374422 -82.574892)
		(width 0.15494)
		(layer "In13.Cu")
		(net "SMB_BIC_I2C6_MUX_SSD_0_7_ADC_SCL")
	)
	(segment
		(start 377.778772 -80.8228)
		(end 376.584972 -80.8228)
		(width 0.15494)
		(layer "In13.Cu")
		(net "SMB_BIC_I2C6_MUX_SSD_0_7_ADC_SCL")
	)
	(segment
		(start 371.024658 -82.147156)
		(end 369.896898 -82.147156)
		(width 0.15494)
		(layer "In13.Cu")
		(net "SMB_BIC_I2C6_MUX_SSD_0_7_ADC_SCL")
	)
	(segment
		(start 352.781616 -96.73336)
		(end 339.170518 -96.73336)
		(width 0.15494)
		(layer "In13.Cu")
		(net "SMB_BIC_I2C6_MUX_SSD_0_7_ADC_SCL")
	)
	(segment
		(start 331.140054 -88.3666)
		(end 330.1492 -88.3666)
		(width 0.15494)
		(layer "In13.Cu")
		(net "SMB_BIC_I2C6_MUX_SSD_0_7_ADC_SCL")
	)
	(segment
		(start 328.1426 -89.5096)
		(end 326.86371 -88.23071)
		(width 0.15494)
		(layer "In13.Cu")
		(net "SMB_BIC_I2C6_MUX_SSD_0_7_ADC_SCL")
	)
	(segment
		(start 371.780054 -81.39176)
		(end 371.024658 -82.147156)
		(width 0.15494)
		(layer "In13.Cu")
		(net "SMB_BIC_I2C6_MUX_SSD_0_7_ADC_SCL")
	)
	(segment
		(start 330.1492 -88.3666)
		(end 329.0062 -89.5096)
		(width 0.15494)
		(layer "In13.Cu")
		(net "SMB_BIC_I2C6_MUX_SSD_0_7_ADC_SCL")
	)
	(segment
		(start 376.016012 -81.39176)
		(end 371.780054 -81.39176)
		(width 0.15494)
		(layer "In13.Cu")
		(net "SMB_BIC_I2C6_MUX_SSD_0_7_ADC_SCL")
	)
	(segment
		(start 367.832132 -82.433922)
		(end 364.591854 -85.6742)
		(width 0.15494)
		(layer "In13.Cu")
		(net "SMB_BIC_I2C6_MUX_SSD_0_7_ADC_SCL")
	)
	(segment
		(start 280.828242 -87.05469)
		(end 280.271728 -86.498176)
		(width 0.15494)
		(layer "In13.Cu")
		(net "SMB_BIC_I2C6_MUX_SSD_0_7_ADC_SCL")
	)
	(segment
		(start 315.663834 -88.23071)
		(end 314.453524 -87.0204)
		(width 0.15494)
		(layer "In13.Cu")
		(net "SMB_BIC_I2C6_MUX_SSD_0_7_ADC_SCL")
	)
	(segment
		(start 310.5404 -86.4108)
		(end 309.499 -86.4108)
		(width 0.15494)
		(layer "In13.Cu")
		(net "SMB_BIC_I2C6_MUX_SSD_0_7_ADC_SCL")
	)
	(segment
		(start 339.170518 -96.73336)
		(end 338.1502 -95.713042)
		(width 0.15494)
		(layer "In13.Cu")
		(net "SMB_BIC_I2C6_MUX_SSD_0_7_ADC_SCL")
	)
	(segment
		(start 368.374422 -82.574892)
		(end 368.233452 -82.433922)
		(width 0.15494)
		(layer "In13.Cu")
		(net "SMB_BIC_I2C6_MUX_SSD_0_7_ADC_SCL")
	)
	(segment
		(start 308.85511 -87.05469)
		(end 280.828242 -87.05469)
		(width 0.15494)
		(layer "In13.Cu")
		(net "SMB_BIC_I2C6_MUX_SSD_0_7_ADC_SCL")
	)
	(segment
		(start 329.0062 -89.5096)
		(end 328.1426 -89.5096)
		(width 0.15494)
		(layer "In13.Cu")
		(net "SMB_BIC_I2C6_MUX_SSD_0_7_ADC_SCL")
	)
	(segment
		(start 332.003654 -89.2302)
		(end 331.140054 -88.3666)
		(width 0.15494)
		(layer "In13.Cu")
		(net "SMB_BIC_I2C6_MUX_SSD_0_7_ADC_SCL")
	)
	(segment
		(start 376.584972 -80.8228)
		(end 376.016012 -81.39176)
		(width 0.15494)
		(layer "In13.Cu")
		(net "SMB_BIC_I2C6_MUX_SSD_0_7_ADC_SCL")
	)
	(segment
		(start 368.233452 -82.433922)
		(end 367.832132 -82.433922)
		(width 0.15494)
		(layer "In13.Cu")
		(net "SMB_BIC_I2C6_MUX_SSD_0_7_ADC_SCL")
	)
	(segment
		(start 326.86371 -88.23071)
		(end 315.663834 -88.23071)
		(width 0.15494)
		(layer "In13.Cu")
		(net "SMB_BIC_I2C6_MUX_SSD_0_7_ADC_SCL")
	)
	(segment
		(start 333.857854 -89.2302)
		(end 332.003654 -89.2302)
		(width 0.15494)
		(layer "In13.Cu")
		(net "SMB_BIC_I2C6_MUX_SSD_0_7_ADC_SCL")
	)
	(segment
		(start 309.499 -86.4108)
		(end 308.85511 -87.05469)
		(width 0.15494)
		(layer "In13.Cu")
		(net "SMB_BIC_I2C6_MUX_SSD_0_7_ADC_SCL")
	)
	(segment
		(start 314.453524 -87.0204)
		(end 311.15 -87.0204)
		(width 0.15494)
		(layer "In13.Cu")
		(net "SMB_BIC_I2C6_MUX_SSD_0_7_ADC_SCL")
	)
	(segment
		(start 363.840776 -85.6742)
		(end 352.781616 -96.73336)
		(width 0.15494)
		(layer "In13.Cu")
		(net "SMB_BIC_I2C6_MUX_SSD_0_7_ADC_SCL")
	)
	(segment
		(start 369.896898 -82.147156)
		(end 369.469162 -82.574892)
		(width 0.15494)
		(layer "In13.Cu")
		(net "SMB_BIC_I2C6_MUX_SSD_0_7_ADC_SCL")
	)
	(segment
		(start 338.1502 -95.713042)
		(end 338.1502 -93.522546)
		(width 0.15494)
		(layer "In13.Cu")
		(net "SMB_BIC_I2C6_MUX_SSD_0_7_ADC_SCL")
	)
	(segment
		(start 364.591854 -85.6742)
		(end 363.840776 -85.6742)
		(width 0.15494)
		(layer "In13.Cu")
		(net "SMB_BIC_I2C6_MUX_SSD_0_7_ADC_SCL")
	)
	(segment
		(start 311.15 -87.0204)
		(end 310.5404 -86.4108)
		(width 0.15494)
		(layer "In13.Cu")
		(net "SMB_BIC_I2C6_MUX_SSD_0_7_ADC_SCL")
	)
	(segment
		(start 319.296034 -388.958836)
		(end 318.58585 -388.958836)
		(width 0.13208)
		(layer "F.Cu")
		(net "GPU_3V3IO_RSVD5_FFU")
	)
	(segment
		(start 318.583818 -388.960868)
		(end 317.67526 -388.960868)
		(width 0.13208)
		(layer "F.Cu")
		(net "GPU_3V3IO_RSVD5_FFU")
	)
	(segment
		(start 318.58585 -388.958836)
		(end 318.583818 -388.960868)
		(width 0.13208)
		(layer "F.Cu")
		(net "GPU_3V3IO_RSVD5_FFU")
	)
	(via
		(at 318.58585 -388.958836)
		(size 0.508)
		(drill 0.254)
		(layers "F.Cu" "B.Cu")
		(net "GPU_3V3IO_RSVD5_FFU")
	)
	(segment
		(start 311.326276 -409.70454)
		(end 311.326276 -393.83462)
		(width 0.15494)
		(layer "In9.Cu")
		(net "GPU_3V3IO_RSVD5_FFU")
	)
	(segment
		(start 297.459654 -413.259778)
		(end 307.771038 -413.259778)
		(width 0.15494)
		(layer "In9.Cu")
		(net "GPU_3V3IO_RSVD5_FFU")
	)
	(segment
		(start 311.326276 -393.83462)
		(end 315.010038 -390.150858)
		(width 0.15494)
		(layer "In9.Cu")
		(net "GPU_3V3IO_RSVD5_FFU")
	)
	(segment
		(start 307.771038 -413.259778)
		(end 311.326276 -409.70454)
		(width 0.15494)
		(layer "In9.Cu")
		(net "GPU_3V3IO_RSVD5_FFU")
	)
	(segment
		(start 317.246762 -388.958836)
		(end 318.58585 -388.958836)
		(width 0.15494)
		(layer "In9.Cu")
		(net "GPU_3V3IO_RSVD5_FFU")
	)
	(segment
		(start 296.289984 -412.090108)
		(end 297.459654 -413.259778)
		(width 0.15494)
		(layer "In9.Cu")
		(net "GPU_3V3IO_RSVD5_FFU")
	)
	(segment
		(start 316.05474 -390.150858)
		(end 317.246762 -388.958836)
		(width 0.15494)
		(layer "In9.Cu")
		(net "GPU_3V3IO_RSVD5_FFU")
	)
	(segment
		(start 315.010038 -390.150858)
		(end 316.05474 -390.150858)
		(width 0.15494)
		(layer "In9.Cu")
		(net "GPU_3V3IO_RSVD5_FFU")
	)
	(segment
		(start 149.044406 -58.561224)
		(end 149.044406 -59.012582)
		(width 0.13208)
		(layer "F.Cu")
		(net "P3V3_SSD5_OCP")
	)
	(segment
		(start 149.241002 -57.16397)
		(end 149.241002 -58.364628)
		(width 0.13208)
		(layer "F.Cu")
		(net "P3V3_SSD5_OCP")
	)
	(segment
		(start 149.241002 -58.364628)
		(end 149.044406 -58.561224)
		(width 0.13208)
		(layer "F.Cu")
		(net "P3V3_SSD5_OCP")
	)
	(segment
		(start 149.044406 -59.012582)
		(end 149.20341 -59.171586)
		(width 0.13208)
		(layer "F.Cu")
		(net "P3V3_SSD5_OCP")
	)
	(via
		(at 149.044406 -58.561224)
		(size 0.508)
		(drill 0.254)
		(layers "F.Cu" "B.Cu")
		(net "P3V3_SSD5_OCP")
	)
	(segment
		(start 255.560068 -82.056478)
		(end 255.498346 -82.1182)
		(width 0.1778)
		(layer "F.Cu")
		(net "P3V3_CLK_GEN_VDDXTAL_CK440")
	)
	(segment
		(start 254.869696 -82.1182)
		(end 254.807974 -82.056478)
		(width 0.1778)
		(layer "F.Cu")
		(net "P3V3_CLK_GEN_VDDXTAL_CK440")
	)
	(segment
		(start 255.801876 -82.056478)
		(end 255.560068 -82.056478)
		(width 0.1778)
		(layer "F.Cu")
		(net "P3V3_CLK_GEN_VDDXTAL_CK440")
	)
	(segment
		(start 255.498346 -82.1182)
		(end 254.869696 -82.1182)
		(width 0.1778)
		(layer "F.Cu")
		(net "P3V3_CLK_GEN_VDDXTAL_CK440")
	)
	(via
		(at 254.807974 -82.056478)
		(size 0.508)
		(drill 0.254)
		(layers "F.Cu" "B.Cu")
		(net "P3V3_CLK_GEN_VDDXTAL_CK440")
	)
	(via
		(at 254.10668 -89.904316)
		(size 0.508)
		(drill 0.254)
		(layers "F.Cu" "B.Cu")
		(net "P3V3_CLK_GEN_VDDXTAL_CK440")
	)
	(segment
		(start 254.89408 -89.904316)
		(end 254.10668 -89.904316)
		(width 0.508)
		(layer "B.Cu")
		(net "P3V3_CLK_GEN_VDDXTAL_CK440")
	)
	(segment
		(start 255.483868 -84.685886)
		(end 255.2192 -84.950554)
		(width 0.508)
		(layer "In5.Cu")
		(net "P3V3_CLK_GEN_VDDXTAL_CK440")
	)
	(segment
		(start 255.483868 -82.732372)
		(end 255.483868 -84.685886)
		(width 0.508)
		(layer "In5.Cu")
		(net "P3V3_CLK_GEN_VDDXTAL_CK440")
	)
	(segment
		(start 255.2192 -84.950554)
		(end 255.2192 -88.791796)
		(width 0.508)
		(layer "In5.Cu")
		(net "P3V3_CLK_GEN_VDDXTAL_CK440")
	)
	(segment
		(start 255.2192 -88.791796)
		(end 254.10668 -89.904316)
		(width 0.508)
		(layer "In5.Cu")
		(net "P3V3_CLK_GEN_VDDXTAL_CK440")
	)
	(segment
		(start 254.807974 -82.056478)
		(end 255.483868 -82.732372)
		(width 0.508)
		(layer "In5.Cu")
		(net "P3V3_CLK_GEN_VDDXTAL_CK440")
	)
	(segment
		(start 242.864894 -22.3901)
		(end 244.667532 -22.3901)
		(width 0.13208)
		(layer "F.Cu")
		(net "SMB_ISO_SSD8_R_SCL")
	)
	(segment
		(start 254.865378 -18.437098)
		(end 255.467866 -18.437098)
		(width 0.13208)
		(layer "F.Cu")
		(net "SMB_ISO_SSD8_R_SCL")
	)
	(segment
		(start 254.858266 -18.44421)
		(end 254.865378 -18.437098)
		(width 0.13208)
		(layer "F.Cu")
		(net "SMB_ISO_SSD8_R_SCL")
	)
	(segment
		(start 244.667532 -22.3901)
		(end 245.293642 -23.01621)
		(width 0.13208)
		(layer "F.Cu")
		(net "SMB_ISO_SSD8_R_SCL")
	)
	(via
		(at 245.293642 -23.01621)
		(size 0.508)
		(drill 0.254)
		(layers "F.Cu" "B.Cu")
		(net "SMB_ISO_SSD8_R_SCL")
	)
	(via
		(at 254.858266 -18.44421)
		(size 0.508)
		(drill 0.254)
		(layers "F.Cu" "B.Cu")
		(net "SMB_ISO_SSD8_R_SCL")
	)
	(segment
		(start 254.858266 -18.44421)
		(end 255.426972 -19.012916)
		(width 0.15494)
		(layer "In5.Cu")
		(net "SMB_ISO_SSD8_R_SCL")
	)
	(segment
		(start 253.882652 -23.01621)
		(end 245.293642 -23.01621)
		(width 0.15494)
		(layer "In5.Cu")
		(net "SMB_ISO_SSD8_R_SCL")
	)
	(segment
		(start 255.426972 -19.012916)
		(end 255.426972 -21.47189)
		(width 0.15494)
		(layer "In5.Cu")
		(net "SMB_ISO_SSD8_R_SCL")
	)
	(segment
		(start 255.426972 -21.47189)
		(end 253.882652 -23.01621)
		(width 0.15494)
		(layer "In5.Cu")
		(net "SMB_ISO_SSD8_R_SCL")
	)
	(segment
		(start 382.640078 -83.536536)
		(end 381.681482 -83.536536)
		(width 0.13208)
		(layer "F.Cu")
		(net "SMB_BIC_I2C6_MUX_SSD_0_7_ADC_SDA")
	)
	(segment
		(start 379.88367 -81.9658)
		(end 379.252734 -81.9658)
		(width 0.13208)
		(layer "F.Cu")
		(net "SMB_BIC_I2C6_MUX_SSD_0_7_ADC_SDA")
	)
	(segment
		(start 381.681482 -83.536536)
		(end 381.482346 -83.3374)
		(width 0.13208)
		(layer "F.Cu")
		(net "SMB_BIC_I2C6_MUX_SSD_0_7_ADC_SDA")
	)
	(segment
		(start 381.482346 -83.3374)
		(end 380.873762 -83.3374)
		(width 0.13208)
		(layer "F.Cu")
		(net "SMB_BIC_I2C6_MUX_SSD_0_7_ADC_SDA")
	)
	(segment
		(start 379.88367 -82.347308)
		(end 379.88367 -81.9658)
		(width 0.13208)
		(layer "F.Cu")
		(net "SMB_BIC_I2C6_MUX_SSD_0_7_ADC_SDA")
	)
	(segment
		(start 380.873762 -83.3374)
		(end 379.88367 -82.347308)
		(width 0.13208)
		(layer "F.Cu")
		(net "SMB_BIC_I2C6_MUX_SSD_0_7_ADC_SDA")
	)
	(via
		(at 379.88367 -81.9658)
		(size 0.508)
		(drill 0.254)
		(layers "F.Cu" "B.Cu")
		(net "SMB_BIC_I2C6_MUX_SSD_0_7_ADC_SDA")
	)
	(segment
		(start 246.176038 -170.409362)
		(end 245.770908 -170.814492)
		(width 0.1143)
		(layer "F.Cu")
		(net "CLK_100M_DB2000QL_PEX2_S1_R_DN")
	)
	(segment
		(start 182.678578 -183.3626)
		(end 160.274 -183.3626)
		(width 0.1143)
		(layer "F.Cu")
		(net "CLK_100M_DB2000QL_PEX2_S1_R_DN")
	)
	(segment
		(start 145.563082 -168.651682)
		(end 145.369026 -168.651682)
		(width 0.1143)
		(layer "F.Cu")
		(net "CLK_100M_DB2000QL_PEX2_S1_R_DN")
	)
	(segment
		(start 143.838422 -167.121078)
		(end 143.552672 -166.835074)
		(width 0.1143)
		(layer "F.Cu")
		(net "CLK_100M_DB2000QL_PEX2_S1_R_DN")
	)
	(segment
		(start 144.603724 -167.88638)
		(end 144.317974 -167.600376)
		(width 0.1143)
		(layer "F.Cu")
		(net "CLK_100M_DB2000QL_PEX2_S1_R_DN")
	)
	(segment
		(start 245.770908 -170.814492)
		(end 240.372138 -170.814492)
		(width 0.1143)
		(layer "F.Cu")
		(net "CLK_100M_DB2000QL_PEX2_S1_R_DN")
	)
	(segment
		(start 240.372138 -170.814492)
		(end 238.221774 -168.664128)
		(width 0.1143)
		(layer "F.Cu")
		(net "CLK_100M_DB2000QL_PEX2_S1_R_DN")
	)
	(segment
		(start 207.952086 -172.894244)
		(end 182.678578 -183.3626)
		(width 0.1143)
		(layer "F.Cu")
		(net "CLK_100M_DB2000QL_PEX2_S1_R_DN")
	)
	(segment
		(start 145.848578 -169.13098)
		(end 145.848578 -168.937178)
		(width 0.1143)
		(layer "F.Cu")
		(net "CLK_100M_DB2000QL_PEX2_S1_R_DN")
	)
	(segment
		(start 131.70662 -165.435534)
		(end 129.0828 -168.059354)
		(width 0.1143)
		(layer "F.Cu")
		(net "CLK_100M_DB2000QL_PEX2_S1_R_DN")
	)
	(segment
		(start 143.552672 -166.835074)
		(end 143.552672 -166.641272)
		(width 0.1143)
		(layer "F.Cu")
		(net "CLK_100M_DB2000QL_PEX2_S1_R_DN")
	)
	(segment
		(start 145.848578 -168.937178)
		(end 145.563082 -168.651682)
		(width 0.1143)
		(layer "F.Cu")
		(net "CLK_100M_DB2000QL_PEX2_S1_R_DN")
	)
	(segment
		(start 269.0495 -297.79976)
		(end 268.57452 -297.32478)
		(width 0.1143)
		(layer "F.Cu")
		(net "CLK_100M_DB2000QL_PEX2_S1_R_DN")
	)
	(segment
		(start 238.221774 -168.664128)
		(end 221.122748 -168.664128)
		(width 0.1143)
		(layer "F.Cu")
		(net "CLK_100M_DB2000QL_PEX2_S1_R_DN")
	)
	(segment
		(start 211.332064 -172.894244)
		(end 207.952086 -172.894244)
		(width 0.1143)
		(layer "F.Cu")
		(net "CLK_100M_DB2000QL_PEX2_S1_R_DN")
	)
	(segment
		(start 146.134328 -169.416984)
		(end 145.848578 -169.13098)
		(width 0.1143)
		(layer "F.Cu")
		(net "CLK_100M_DB2000QL_PEX2_S1_R_DN")
	)
	(segment
		(start 144.79778 -167.88638)
		(end 144.603724 -167.88638)
		(width 0.1143)
		(layer "F.Cu")
		(net "CLK_100M_DB2000QL_PEX2_S1_R_DN")
	)
	(segment
		(start 142.787624 -165.876224)
		(end 142.346934 -165.435534)
		(width 0.1143)
		(layer "F.Cu")
		(net "CLK_100M_DB2000QL_PEX2_S1_R_DN")
	)
	(segment
		(start 214.681308 -169.545)
		(end 211.332064 -172.894244)
		(width 0.1143)
		(layer "F.Cu")
		(net "CLK_100M_DB2000QL_PEX2_S1_R_DN")
	)
	(segment
		(start 142.346934 -165.435534)
		(end 131.70662 -165.435534)
		(width 0.1143)
		(layer "F.Cu")
		(net "CLK_100M_DB2000QL_PEX2_S1_R_DN")
	)
	(segment
		(start 160.274 -183.3626)
		(end 146.328384 -169.416984)
		(width 0.1143)
		(layer "F.Cu")
		(net "CLK_100M_DB2000QL_PEX2_S1_R_DN")
	)
	(segment
		(start 246.176038 -169.837862)
		(end 246.176038 -170.409362)
		(width 0.1143)
		(layer "F.Cu")
		(net "CLK_100M_DB2000QL_PEX2_S1_R_DN")
	)
	(segment
		(start 142.787624 -166.070026)
		(end 142.787624 -165.876224)
		(width 0.1143)
		(layer "F.Cu")
		(net "CLK_100M_DB2000QL_PEX2_S1_R_DN")
	)
	(segment
		(start 145.369026 -168.651682)
		(end 145.083276 -168.365678)
		(width 0.1143)
		(layer "F.Cu")
		(net "CLK_100M_DB2000QL_PEX2_S1_R_DN")
	)
	(segment
		(start 143.552672 -166.641272)
		(end 143.267176 -166.355776)
		(width 0.1143)
		(layer "F.Cu")
		(net "CLK_100M_DB2000QL_PEX2_S1_R_DN")
	)
	(segment
		(start 129.0828 -168.059354)
		(end 129.0828 -169.878756)
		(width 0.1143)
		(layer "F.Cu")
		(net "CLK_100M_DB2000QL_PEX2_S1_R_DN")
	)
	(segment
		(start 143.267176 -166.355776)
		(end 143.073374 -166.355776)
		(width 0.1143)
		(layer "F.Cu")
		(net "CLK_100M_DB2000QL_PEX2_S1_R_DN")
	)
	(segment
		(start 145.083276 -168.365678)
		(end 145.083276 -168.171876)
		(width 0.1143)
		(layer "F.Cu")
		(net "CLK_100M_DB2000QL_PEX2_S1_R_DN")
	)
	(segment
		(start 246.430038 -169.583862)
		(end 246.176038 -169.837862)
		(width 0.1143)
		(layer "F.Cu")
		(net "CLK_100M_DB2000QL_PEX2_S1_R_DN")
	)
	(segment
		(start 144.032478 -167.121078)
		(end 143.838422 -167.121078)
		(width 0.1143)
		(layer "F.Cu")
		(net "CLK_100M_DB2000QL_PEX2_S1_R_DN")
	)
	(segment
		(start 221.122748 -168.664128)
		(end 220.241876 -169.545)
		(width 0.1143)
		(layer "F.Cu")
		(net "CLK_100M_DB2000QL_PEX2_S1_R_DN")
	)
	(segment
		(start 269.049754 -297.79976)
		(end 269.0495 -297.79976)
		(width 0.1143)
		(layer "F.Cu")
		(net "CLK_100M_DB2000QL_PEX2_S1_R_DN")
	)
	(segment
		(start 146.328384 -169.416984)
		(end 146.134328 -169.416984)
		(width 0.1143)
		(layer "F.Cu")
		(net "CLK_100M_DB2000QL_PEX2_S1_R_DN")
	)
	(segment
		(start 220.241876 -169.545)
		(end 214.681308 -169.545)
		(width 0.1143)
		(layer "F.Cu")
		(net "CLK_100M_DB2000QL_PEX2_S1_R_DN")
	)
	(segment
		(start 144.317974 -167.406574)
		(end 144.032478 -167.121078)
		(width 0.1143)
		(layer "F.Cu")
		(net "CLK_100M_DB2000QL_PEX2_S1_R_DN")
	)
	(segment
		(start 144.317974 -167.600376)
		(end 144.317974 -167.406574)
		(width 0.1143)
		(layer "F.Cu")
		(net "CLK_100M_DB2000QL_PEX2_S1_R_DN")
	)
	(segment
		(start 129.0828 -169.878756)
		(end 129.403856 -170.199812)
		(width 0.1143)
		(layer "F.Cu")
		(net "CLK_100M_DB2000QL_PEX2_S1_R_DN")
	)
	(segment
		(start 143.073374 -166.355776)
		(end 142.787624 -166.070026)
		(width 0.1143)
		(layer "F.Cu")
		(net "CLK_100M_DB2000QL_PEX2_S1_R_DN")
	)
	(segment
		(start 145.083276 -168.171876)
		(end 144.79778 -167.88638)
		(width 0.1143)
		(layer "F.Cu")
		(net "CLK_100M_DB2000QL_PEX2_S1_R_DN")
	)
	(via
		(at 246.430038 -169.583862)
		(size 0.508)
		(drill 0.254)
		(layers "F.Cu" "B.Cu")
		(net "CLK_100M_DB2000QL_PEX2_S1_R_DN")
	)
	(via
		(at 268.57452 -297.32478)
		(size 0.4064)
		(drill 0.2032)
		(layers "F.Cu" "B.Cu")
		(net "CLK_100M_DB2000QL_PEX2_S1_R_DN")
	)
	(segment
		(start 267.558774 -297.491912)
		(end 267.201396 -297.134534)
		(width 0.1143)
		(layer "B.Cu")
		(net "CLK_100M_DB2000QL_PEX2_S1_R_DN")
	)
	(segment
		(start 263.342628 -292.07333)
		(end 263.342628 -291.66947)
		(width 0.1143)
		(layer "B.Cu")
		(net "CLK_100M_DB2000QL_PEX2_S1_R_DN")
	)
	(segment
		(start 245.119398 -219.162122)
		(end 245.741952 -218.539568)
		(width 0.1143)
		(layer "B.Cu")
		(net "CLK_100M_DB2000QL_PEX2_S1_R_DN")
	)
	(segment
		(start 268.9479 -297.53941)
		(end 268.795754 -297.691556)
		(width 0.0889)
		(layer "B.Cu")
		(net "CLK_100M_DB2000QL_PEX2_S1_R_DN")
	)
	(segment
		(start 268.57452 -297.32478)
		(end 268.859 -297.32478)
		(width 0.0889)
		(layer "B.Cu")
		(net "CLK_100M_DB2000QL_PEX2_S1_R_DN")
	)
	(segment
		(start 245.5418 -212.737954)
		(end 247.795034 -210.48472)
		(width 0.1143)
		(layer "B.Cu")
		(net "CLK_100M_DB2000QL_PEX2_S1_R_DN")
	)
	(segment
		(start 263.952228 -294.631618)
		(end 263.205468 -293.884858)
		(width 0.1143)
		(layer "B.Cu")
		(net "CLK_100M_DB2000QL_PEX2_S1_R_DN")
	)
	(segment
		(start 253.3396 -260.661912)
		(end 253.3396 -238.936022)
		(width 0.1143)
		(layer "B.Cu")
		(net "CLK_100M_DB2000QL_PEX2_S1_R_DN")
	)
	(segment
		(start 250.555506 -193.5099)
		(end 254.4318 -189.633606)
		(width 0.1143)
		(layer "B.Cu")
		(net "CLK_100M_DB2000QL_PEX2_S1_R_DN")
	)
	(segment
		(start 263.205468 -292.21049)
		(end 263.342628 -292.07333)
		(width 0.1143)
		(layer "B.Cu")
		(net "CLK_100M_DB2000QL_PEX2_S1_R_DN")
	)
	(segment
		(start 267.574268 -297.507406)
		(end 267.558774 -297.491912)
		(width 0.0889)
		(layer "B.Cu")
		(net "CLK_100M_DB2000QL_PEX2_S1_R_DN")
	)
	(segment
		(start 263.205468 -279.423368)
		(end 257.513074 -273.73072)
		(width 0.1143)
		(layer "B.Cu")
		(net "CLK_100M_DB2000QL_PEX2_S1_R_DN")
	)
	(segment
		(start 268.795754 -297.691556)
		(end 267.641578 -297.691556)
		(width 0.0889)
		(layer "B.Cu")
		(net "CLK_100M_DB2000QL_PEX2_S1_R_DN")
	)
	(segment
		(start 254.4318 -189.633606)
		(end 254.4318 -178.427126)
		(width 0.1143)
		(layer "B.Cu")
		(net "CLK_100M_DB2000QL_PEX2_S1_R_DN")
	)
	(segment
		(start 247.795034 -207.198976)
		(end 249.07113 -204.117956)
		(width 0.1143)
		(layer "B.Cu")
		(net "CLK_100M_DB2000QL_PEX2_S1_R_DN")
	)
	(segment
		(start 263.205468 -291.53231)
		(end 263.205468 -279.423368)
		(width 0.1143)
		(layer "B.Cu")
		(net "CLK_100M_DB2000QL_PEX2_S1_R_DN")
	)
	(segment
		(start 254.48514 -266.4206)
		(end 253.3396 -260.661912)
		(width 0.1143)
		(layer "B.Cu")
		(net "CLK_100M_DB2000QL_PEX2_S1_R_DN")
	)
	(segment
		(start 247.795034 -210.48472)
		(end 247.795034 -207.198976)
		(width 0.1143)
		(layer "B.Cu")
		(net "CLK_100M_DB2000QL_PEX2_S1_R_DN")
	)
	(segment
		(start 268.859 -297.32478)
		(end 268.9479 -297.41368)
		(width 0.0889)
		(layer "B.Cu")
		(net "CLK_100M_DB2000QL_PEX2_S1_R_DN")
	)
	(segment
		(start 266.51585 -295.693592)
		(end 263.952228 -294.631618)
		(width 0.1143)
		(layer "B.Cu")
		(net "CLK_100M_DB2000QL_PEX2_S1_R_DN")
	)
	(segment
		(start 249.07113 -204.117956)
		(end 249.07113 -194.222878)
		(width 0.1143)
		(layer "B.Cu")
		(net "CLK_100M_DB2000QL_PEX2_S1_R_DN")
	)
	(segment
		(start 267.574268 -297.624246)
		(end 267.574268 -297.507406)
		(width 0.0889)
		(layer "B.Cu")
		(net "CLK_100M_DB2000QL_PEX2_S1_R_DN")
	)
	(segment
		(start 263.205468 -293.884858)
		(end 263.205468 -292.21049)
		(width 0.1143)
		(layer "B.Cu")
		(net "CLK_100M_DB2000QL_PEX2_S1_R_DN")
	)
	(segment
		(start 263.342628 -291.66947)
		(end 263.205468 -291.53231)
		(width 0.1143)
		(layer "B.Cu")
		(net "CLK_100M_DB2000QL_PEX2_S1_R_DN")
	)
	(segment
		(start 267.201396 -296.379138)
		(end 266.51585 -295.693592)
		(width 0.1143)
		(layer "B.Cu")
		(net "CLK_100M_DB2000QL_PEX2_S1_R_DN")
	)
	(segment
		(start 267.641578 -297.691556)
		(end 267.574268 -297.624246)
		(width 0.0889)
		(layer "B.Cu")
		(net "CLK_100M_DB2000QL_PEX2_S1_R_DN")
	)
	(segment
		(start 257.513074 -273.73072)
		(end 254.48514 -266.4206)
		(width 0.1143)
		(layer "B.Cu")
		(net "CLK_100M_DB2000QL_PEX2_S1_R_DN")
	)
	(segment
		(start 245.741952 -215.006936)
		(end 245.5418 -214.806784)
		(width 0.1143)
		(layer "B.Cu")
		(net "CLK_100M_DB2000QL_PEX2_S1_R_DN")
	)
	(segment
		(start 246.1768 -170.172126)
		(end 246.1768 -169.8371)
		(width 0.1143)
		(layer "B.Cu")
		(net "CLK_100M_DB2000QL_PEX2_S1_R_DN")
	)
	(segment
		(start 249.07113 -194.222878)
		(end 249.784108 -193.5099)
		(width 0.1143)
		(layer "B.Cu")
		(net "CLK_100M_DB2000QL_PEX2_S1_R_DN")
	)
	(segment
		(start 249.784108 -193.5099)
		(end 250.555506 -193.5099)
		(width 0.1143)
		(layer "B.Cu")
		(net "CLK_100M_DB2000QL_PEX2_S1_R_DN")
	)
	(segment
		(start 244.634512 -222.215456)
		(end 245.119398 -221.044516)
		(width 0.1143)
		(layer "B.Cu")
		(net "CLK_100M_DB2000QL_PEX2_S1_R_DN")
	)
	(segment
		(start 245.5418 -214.806784)
		(end 245.5418 -212.737954)
		(width 0.1143)
		(layer "B.Cu")
		(net "CLK_100M_DB2000QL_PEX2_S1_R_DN")
	)
	(segment
		(start 245.119398 -221.044516)
		(end 245.119398 -219.162122)
		(width 0.1143)
		(layer "B.Cu")
		(net "CLK_100M_DB2000QL_PEX2_S1_R_DN")
	)
	(segment
		(start 267.201396 -297.134534)
		(end 267.201396 -296.379138)
		(width 0.1143)
		(layer "B.Cu")
		(net "CLK_100M_DB2000QL_PEX2_S1_R_DN")
	)
	(segment
		(start 268.9479 -297.41368)
		(end 268.9479 -297.53941)
		(width 0.0889)
		(layer "B.Cu")
		(net "CLK_100M_DB2000QL_PEX2_S1_R_DN")
	)
	(segment
		(start 244.634512 -230.230934)
		(end 244.634512 -222.215456)
		(width 0.1143)
		(layer "B.Cu")
		(net "CLK_100M_DB2000QL_PEX2_S1_R_DN")
	)
	(segment
		(start 254.4318 -178.427126)
		(end 246.1768 -170.172126)
		(width 0.1143)
		(layer "B.Cu")
		(net "CLK_100M_DB2000QL_PEX2_S1_R_DN")
	)
	(segment
		(start 253.3396 -238.936022)
		(end 244.634512 -230.230934)
		(width 0.1143)
		(layer "B.Cu")
		(net "CLK_100M_DB2000QL_PEX2_S1_R_DN")
	)
	(segment
		(start 245.741952 -218.539568)
		(end 245.741952 -215.006936)
		(width 0.1143)
		(layer "B.Cu")
		(net "CLK_100M_DB2000QL_PEX2_S1_R_DN")
	)
	(segment
		(start 246.1768 -169.8371)
		(end 246.430038 -169.583862)
		(width 0.1143)
		(layer "B.Cu")
		(net "CLK_100M_DB2000QL_PEX2_S1_R_DN")
	)
	(segment
		(start 146.967956 -311.613296)
		(end 146.644868 -311.290208)
		(width 0.13208)
		(layer "F.Cu")
		(net "PU_PEX1_PAD_TRI_L")
	)
	(segment
		(start 150.59279 -312.268108)
		(end 148.74621 -312.268108)
		(width 0.13208)
		(layer "F.Cu")
		(net "PU_PEX1_PAD_TRI_L")
	)
	(segment
		(start 148.091398 -311.613296)
		(end 146.967956 -311.613296)
		(width 0.13208)
		(layer "F.Cu")
		(net "PU_PEX1_PAD_TRI_L")
	)
	(segment
		(start 148.74621 -312.268108)
		(end 148.091398 -311.613296)
		(width 0.13208)
		(layer "F.Cu")
		(net "PU_PEX1_PAD_TRI_L")
	)
	(segment
		(start 167.200072 -309.199788)
		(end 166.725092 -308.724808)
		(width 0.13208)
		(layer "F.Cu")
		(net "PU_PEX1_PAD_TRI_L")
	)
	(via
		(at 166.725092 -308.724808)
		(size 0.4064)
		(drill 0.2032)
		(layers "F.Cu" "B.Cu")
		(net "PU_PEX1_PAD_TRI_L")
	)
	(via
		(at 150.59279 -312.268108)
		(size 0.508)
		(drill 0.254)
		(layers "F.Cu" "B.Cu")
		(net "PU_PEX1_PAD_TRI_L")
	)
	(segment
		(start 151.251412 -312.4708)
		(end 151.04872 -312.268108)
		(width 0.13208)
		(layer "B.Cu")
		(net "PU_PEX1_PAD_TRI_L")
	)
	(segment
		(start 166.725092 -308.724808)
		(end 166.725092 -312.140854)
		(width 0.13208)
		(layer "B.Cu")
		(net "PU_PEX1_PAD_TRI_L")
	)
	(segment
		(start 166.725092 -312.140854)
		(end 166.395146 -312.4708)
		(width 0.13208)
		(layer "B.Cu")
		(net "PU_PEX1_PAD_TRI_L")
	)
	(segment
		(start 151.04872 -312.268108)
		(end 150.59279 -312.268108)
		(width 0.13208)
		(layer "B.Cu")
		(net "PU_PEX1_PAD_TRI_L")
	)
	(segment
		(start 166.395146 -312.4708)
		(end 151.251412 -312.4708)
		(width 0.13208)
		(layer "B.Cu")
		(net "PU_PEX1_PAD_TRI_L")
	)
	(segment
		(start 168.150032 -309.199788)
		(end 167.675052 -308.724808)
		(width 0.127)
		(layer "F.Cu")
		(net "TP_PEX1_TDI")
	)
	(via
		(at 167.675052 -308.724808)
		(size 0.4064)
		(drill 0.2032)
		(layers "F.Cu" "B.Cu")
		(net "TP_PEX1_TDI")
	)
	(via
		(at 168.150032 -309.199788)
		(size 0.6604)
		(drill 0.3302)
		(layers "F.Cu" "B.Cu")
		(net "TP_PEX1_TDI")
	)
	(segment
		(start 168.150032 -309.199788)
		(end 167.675052 -308.724808)
		(width 0.13208)
		(layer "B.Cu")
		(net "TP_PEX1_TDI")
	)
	(segment
		(start 80.454754 -21.847048)
		(end 80.454754 -22.561296)
		(width 0.13208)
		(layer "F.Cu")
		(net "SMB_SSD2_ISO_EN")
	)
	(segment
		(start 79.660496 -20.789392)
		(end 79.660496 -21.05279)
		(width 0.13208)
		(layer "F.Cu")
		(net "SMB_SSD2_ISO_EN")
	)
	(segment
		(start 79.660496 -21.05279)
		(end 80.454754 -21.847048)
		(width 0.13208)
		(layer "F.Cu")
		(net "SMB_SSD2_ISO_EN")
	)
	(via
		(at 80.454754 -21.847048)
		(size 0.508)
		(drill 0.254)
		(layers "F.Cu" "B.Cu")
		(net "SMB_SSD2_ISO_EN")
	)
	(segment
		(start 211.17941 -172.525944)
		(end 214.528654 -169.1767)
		(width 0.1143)
		(layer "F.Cu")
		(net "CLK_100M_DB2000QL_PEX2_S1_R_DP")
	)
	(segment
		(start 182.605172 -182.9943)
		(end 207.87868 -172.525944)
		(width 0.1143)
		(layer "F.Cu")
		(net "CLK_100M_DB2000QL_PEX2_S1_R_DP")
	)
	(segment
		(start 238.374428 -168.295828)
		(end 240.524792 -170.446192)
		(width 0.1143)
		(layer "F.Cu")
		(net "CLK_100M_DB2000QL_PEX2_S1_R_DP")
	)
	(segment
		(start 269.99946 -297.79976)
		(end 269.52448 -297.32478)
		(width 0.1143)
		(layer "F.Cu")
		(net "CLK_100M_DB2000QL_PEX2_S1_R_DP")
	)
	(segment
		(start 245.807738 -170.256708)
		(end 245.807738 -169.825162)
		(width 0.1143)
		(layer "F.Cu")
		(net "CLK_100M_DB2000QL_PEX2_S1_R_DP")
	)
	(segment
		(start 220.089222 -169.1767)
		(end 220.970094 -168.295828)
		(width 0.1143)
		(layer "F.Cu")
		(net "CLK_100M_DB2000QL_PEX2_S1_R_DP")
	)
	(segment
		(start 160.426654 -182.9943)
		(end 182.605172 -182.9943)
		(width 0.1143)
		(layer "F.Cu")
		(net "CLK_100M_DB2000QL_PEX2_S1_R_DP")
	)
	(segment
		(start 269.999714 -297.79976)
		(end 269.99946 -297.79976)
		(width 0.1143)
		(layer "F.Cu")
		(net "CLK_100M_DB2000QL_PEX2_S1_R_DP")
	)
	(segment
		(start 131.553966 -165.067234)
		(end 142.499588 -165.067234)
		(width 0.1143)
		(layer "F.Cu")
		(net "CLK_100M_DB2000QL_PEX2_S1_R_DP")
	)
	(segment
		(start 245.807738 -169.825162)
		(end 245.566438 -169.583862)
		(width 0.1143)
		(layer "F.Cu")
		(net "CLK_100M_DB2000QL_PEX2_S1_R_DP")
	)
	(segment
		(start 128.7145 -167.9067)
		(end 131.553966 -165.067234)
		(width 0.1143)
		(layer "F.Cu")
		(net "CLK_100M_DB2000QL_PEX2_S1_R_DP")
	)
	(segment
		(start 214.528654 -169.1767)
		(end 220.089222 -169.1767)
		(width 0.1143)
		(layer "F.Cu")
		(net "CLK_100M_DB2000QL_PEX2_S1_R_DP")
	)
	(segment
		(start 245.618254 -170.446192)
		(end 245.807738 -170.256708)
		(width 0.1143)
		(layer "F.Cu")
		(net "CLK_100M_DB2000QL_PEX2_S1_R_DP")
	)
	(segment
		(start 128.7145 -169.873168)
		(end 128.7145 -167.9067)
		(width 0.1143)
		(layer "F.Cu")
		(net "CLK_100M_DB2000QL_PEX2_S1_R_DP")
	)
	(segment
		(start 240.524792 -170.446192)
		(end 245.618254 -170.446192)
		(width 0.1143)
		(layer "F.Cu")
		(net "CLK_100M_DB2000QL_PEX2_S1_R_DP")
	)
	(segment
		(start 207.87868 -172.525944)
		(end 211.17941 -172.525944)
		(width 0.1143)
		(layer "F.Cu")
		(net "CLK_100M_DB2000QL_PEX2_S1_R_DP")
	)
	(segment
		(start 220.970094 -168.295828)
		(end 238.374428 -168.295828)
		(width 0.1143)
		(layer "F.Cu")
		(net "CLK_100M_DB2000QL_PEX2_S1_R_DP")
	)
	(segment
		(start 142.499588 -165.067234)
		(end 160.426654 -182.9943)
		(width 0.1143)
		(layer "F.Cu")
		(net "CLK_100M_DB2000QL_PEX2_S1_R_DP")
	)
	(segment
		(start 128.387856 -170.199812)
		(end 128.7145 -169.873168)
		(width 0.1143)
		(layer "F.Cu")
		(net "CLK_100M_DB2000QL_PEX2_S1_R_DP")
	)
	(via
		(at 269.52448 -297.32478)
		(size 0.4064)
		(drill 0.2032)
		(layers "F.Cu" "B.Cu")
		(net "CLK_100M_DB2000QL_PEX2_S1_R_DP")
	)
	(via
		(at 245.566438 -169.583862)
		(size 0.508)
		(drill 0.254)
		(layers "F.Cu" "B.Cu")
		(net "CLK_100M_DB2000QL_PEX2_S1_R_DP")
	)
	(segment
		(start 252.9713 -239.088676)
		(end 244.266212 -230.383588)
		(width 0.1143)
		(layer "B.Cu")
		(net "CLK_100M_DB2000QL_PEX2_S1_R_DP")
	)
	(segment
		(start 245.1735 -214.959438)
		(end 245.1735 -212.5853)
		(width 0.1143)
		(layer "B.Cu")
		(net "CLK_100M_DB2000QL_PEX2_S1_R_DP")
	)
	(segment
		(start 266.833096 -297.287442)
		(end 266.833096 -296.531792)
		(width 0.1143)
		(layer "B.Cu")
		(net "CLK_100M_DB2000QL_PEX2_S1_R_DP")
	)
	(segment
		(start 267.29817 -297.752516)
		(end 266.833096 -297.287442)
		(width 0.1143)
		(layer "B.Cu")
		(net "CLK_100M_DB2000QL_PEX2_S1_R_DP")
	)
	(segment
		(start 245.1735 -212.5853)
		(end 247.426734 -210.332066)
		(width 0.1143)
		(layer "B.Cu")
		(net "CLK_100M_DB2000QL_PEX2_S1_R_DP")
	)
	(segment
		(start 269.52448 -297.32478)
		(end 269.24 -297.32478)
		(width 0.0889)
		(layer "B.Cu")
		(net "CLK_100M_DB2000QL_PEX2_S1_R_DP")
	)
	(segment
		(start 257.200654 -273.939508)
		(end 254.13081 -266.528042)
		(width 0.1143)
		(layer "B.Cu")
		(net "CLK_100M_DB2000QL_PEX2_S1_R_DP")
	)
	(segment
		(start 248.70283 -204.04455)
		(end 248.70283 -194.070224)
		(width 0.1143)
		(layer "B.Cu")
		(net "CLK_100M_DB2000QL_PEX2_S1_R_DP")
	)
	(segment
		(start 266.307062 -296.006012)
		(end 263.74344 -294.944038)
		(width 0.1143)
		(layer "B.Cu")
		(net "CLK_100M_DB2000QL_PEX2_S1_R_DP")
	)
	(segment
		(start 244.266212 -230.383588)
		(end 244.266212 -222.14205)
		(width 0.1143)
		(layer "B.Cu")
		(net "CLK_100M_DB2000QL_PEX2_S1_R_DP")
	)
	(segment
		(start 267.313664 -297.76801)
		(end 267.29817 -297.752516)
		(width 0.0889)
		(layer "B.Cu")
		(net "CLK_100M_DB2000QL_PEX2_S1_R_DP")
	)
	(segment
		(start 245.8085 -170.32478)
		(end 245.8085 -169.825924)
		(width 0.1143)
		(layer "B.Cu")
		(net "CLK_100M_DB2000QL_PEX2_S1_R_DP")
	)
	(segment
		(start 269.24 -297.32478)
		(end 269.1511 -297.41368)
		(width 0.0889)
		(layer "B.Cu")
		(net "CLK_100M_DB2000QL_PEX2_S1_R_DP")
	)
	(segment
		(start 245.8085 -169.825924)
		(end 245.566438 -169.583862)
		(width 0.1143)
		(layer "B.Cu")
		(net "CLK_100M_DB2000QL_PEX2_S1_R_DP")
	)
	(segment
		(start 244.266212 -222.14205)
		(end 244.751098 -220.97111)
		(width 0.1143)
		(layer "B.Cu")
		(net "CLK_100M_DB2000QL_PEX2_S1_R_DP")
	)
	(segment
		(start 250.402852 -193.1416)
		(end 254.0635 -189.480952)
		(width 0.1143)
		(layer "B.Cu")
		(net "CLK_100M_DB2000QL_PEX2_S1_R_DP")
	)
	(segment
		(start 254.0635 -189.480952)
		(end 254.0635 -178.57978)
		(width 0.1143)
		(layer "B.Cu")
		(net "CLK_100M_DB2000QL_PEX2_S1_R_DP")
	)
	(segment
		(start 269.1511 -297.623738)
		(end 268.880082 -297.894756)
		(width 0.0889)
		(layer "B.Cu")
		(net "CLK_100M_DB2000QL_PEX2_S1_R_DP")
	)
	(segment
		(start 269.1511 -297.41368)
		(end 269.1511 -297.623738)
		(width 0.0889)
		(layer "B.Cu")
		(net "CLK_100M_DB2000QL_PEX2_S1_R_DP")
	)
	(segment
		(start 252.9713 -260.698234)
		(end 252.9713 -239.088676)
		(width 0.1143)
		(layer "B.Cu")
		(net "CLK_100M_DB2000QL_PEX2_S1_R_DP")
	)
	(segment
		(start 262.837168 -279.576022)
		(end 257.200654 -273.939508)
		(width 0.1143)
		(layer "B.Cu")
		(net "CLK_100M_DB2000QL_PEX2_S1_R_DP")
	)
	(segment
		(start 245.373652 -215.15959)
		(end 245.1735 -214.959438)
		(width 0.1143)
		(layer "B.Cu")
		(net "CLK_100M_DB2000QL_PEX2_S1_R_DP")
	)
	(segment
		(start 247.426734 -207.12557)
		(end 248.70283 -204.04455)
		(width 0.1143)
		(layer "B.Cu")
		(net "CLK_100M_DB2000QL_PEX2_S1_R_DP")
	)
	(segment
		(start 266.833096 -296.531792)
		(end 266.307062 -296.006012)
		(width 0.1143)
		(layer "B.Cu")
		(net "CLK_100M_DB2000QL_PEX2_S1_R_DP")
	)
	(segment
		(start 244.751098 -220.97111)
		(end 244.751098 -219.009468)
		(width 0.1143)
		(layer "B.Cu")
		(net "CLK_100M_DB2000QL_PEX2_S1_R_DP")
	)
	(segment
		(start 249.631454 -193.1416)
		(end 250.402852 -193.1416)
		(width 0.1143)
		(layer "B.Cu")
		(net "CLK_100M_DB2000QL_PEX2_S1_R_DP")
	)
	(segment
		(start 262.837168 -294.037512)
		(end 262.837168 -279.576022)
		(width 0.1143)
		(layer "B.Cu")
		(net "CLK_100M_DB2000QL_PEX2_S1_R_DP")
	)
	(segment
		(start 267.430504 -297.76801)
		(end 267.313664 -297.76801)
		(width 0.0889)
		(layer "B.Cu")
		(net "CLK_100M_DB2000QL_PEX2_S1_R_DP")
	)
	(segment
		(start 244.751098 -219.009468)
		(end 245.373652 -218.386914)
		(width 0.1143)
		(layer "B.Cu")
		(net "CLK_100M_DB2000QL_PEX2_S1_R_DP")
	)
	(segment
		(start 267.55725 -297.894756)
		(end 267.430504 -297.76801)
		(width 0.0889)
		(layer "B.Cu")
		(net "CLK_100M_DB2000QL_PEX2_S1_R_DP")
	)
	(segment
		(start 245.373652 -218.386914)
		(end 245.373652 -215.15959)
		(width 0.1143)
		(layer "B.Cu")
		(net "CLK_100M_DB2000QL_PEX2_S1_R_DP")
	)
	(segment
		(start 268.880082 -297.894756)
		(end 267.55725 -297.894756)
		(width 0.0889)
		(layer "B.Cu")
		(net "CLK_100M_DB2000QL_PEX2_S1_R_DP")
	)
	(segment
		(start 254.13081 -266.528042)
		(end 252.9713 -260.698234)
		(width 0.1143)
		(layer "B.Cu")
		(net "CLK_100M_DB2000QL_PEX2_S1_R_DP")
	)
	(segment
		(start 248.70283 -194.070224)
		(end 249.631454 -193.1416)
		(width 0.1143)
		(layer "B.Cu")
		(net "CLK_100M_DB2000QL_PEX2_S1_R_DP")
	)
	(segment
		(start 247.426734 -210.332066)
		(end 247.426734 -207.12557)
		(width 0.1143)
		(layer "B.Cu")
		(net "CLK_100M_DB2000QL_PEX2_S1_R_DP")
	)
	(segment
		(start 254.0635 -178.57978)
		(end 245.8085 -170.32478)
		(width 0.1143)
		(layer "B.Cu")
		(net "CLK_100M_DB2000QL_PEX2_S1_R_DP")
	)
	(segment
		(start 263.74344 -294.944038)
		(end 262.837168 -294.037512)
		(width 0.1143)
		(layer "B.Cu")
		(net "CLK_100M_DB2000QL_PEX2_S1_R_DP")
	)
	(segment
		(start 145.925032 -305.931062)
		(end 145.20672 -306.649374)
		(width 0.13208)
		(layer "F.Cu")
		(net "PEX1_DFT_IDDT")
	)
	(segment
		(start 167.200072 -308.249828)
		(end 166.725092 -307.774848)
		(width 0.13208)
		(layer "F.Cu")
		(net "PEX1_DFT_IDDT")
	)
	(segment
		(start 145.854928 -307.11775)
		(end 146.20748 -306.765198)
		(width 0.13208)
		(layer "F.Cu")
		(net "PEX1_DFT_IDDT")
	)
	(segment
		(start 145.675096 -307.11775)
		(end 145.854928 -307.11775)
		(width 0.13208)
		(layer "F.Cu")
		(net "PEX1_DFT_IDDT")
	)
	(segment
		(start 145.20672 -306.649374)
		(end 145.675096 -307.11775)
		(width 0.13208)
		(layer "F.Cu")
		(net "PEX1_DFT_IDDT")
	)
	(via
		(at 146.20748 -306.765198)
		(size 0.508)
		(drill 0.254)
		(layers "F.Cu" "B.Cu")
		(net "PEX1_DFT_IDDT")
	)
	(via
		(at 166.725092 -307.774848)
		(size 0.4064)
		(drill 0.2032)
		(layers "F.Cu" "B.Cu")
		(net "PEX1_DFT_IDDT")
	)
	(segment
		(start 164.356288 -306.970684)
		(end 164.356288 -306.4002)
		(width 0.13208)
		(layer "B.Cu")
		(net "PEX1_DFT_IDDT")
	)
	(segment
		(start 164.229288 -306.2732)
		(end 162.432746 -306.2732)
		(width 0.13208)
		(layer "B.Cu")
		(net "PEX1_DFT_IDDT")
	)
	(segment
		(start 161.975546 -305.816)
		(end 147.156678 -305.816)
		(width 0.13208)
		(layer "B.Cu")
		(net "PEX1_DFT_IDDT")
	)
	(segment
		(start 162.432746 -306.2732)
		(end 161.975546 -305.816)
		(width 0.13208)
		(layer "B.Cu")
		(net "PEX1_DFT_IDDT")
	)
	(segment
		(start 166.216076 -307.265832)
		(end 164.651436 -307.265832)
		(width 0.13208)
		(layer "B.Cu")
		(net "PEX1_DFT_IDDT")
	)
	(segment
		(start 147.156678 -305.816)
		(end 146.20748 -306.765198)
		(width 0.13208)
		(layer "B.Cu")
		(net "PEX1_DFT_IDDT")
	)
	(segment
		(start 164.651436 -307.265832)
		(end 164.356288 -306.970684)
		(width 0.13208)
		(layer "B.Cu")
		(net "PEX1_DFT_IDDT")
	)
	(segment
		(start 166.725092 -307.774848)
		(end 166.216076 -307.265832)
		(width 0.13208)
		(layer "B.Cu")
		(net "PEX1_DFT_IDDT")
	)
	(segment
		(start 164.356288 -306.4002)
		(end 164.229288 -306.2732)
		(width 0.13208)
		(layer "B.Cu")
		(net "PEX1_DFT_IDDT")
	)
	(segment
		(start 78.28534 -16.439388)
		(end 78.28534 -18.463006)
		(width 0.13208)
		(layer "F.Cu")
		(net "SMB_ISO_SSD2_SCL")
	)
	(segment
		(start 75.25639 -17.669256)
		(end 76.024232 -18.437098)
		(width 0.13208)
		(layer "F.Cu")
		(net "SMB_ISO_SSD2_SCL")
	)
	(segment
		(start 75.25639 -17.419574)
		(end 75.25639 -17.669256)
		(width 0.13208)
		(layer "F.Cu")
		(net "SMB_ISO_SSD2_SCL")
	)
	(segment
		(start 78.45933 -23.355554)
		(end 78.45933 -23.965154)
		(width 0.13208)
		(layer "F.Cu")
		(net "SMB_ISO_SSD2_SCL")
	)
	(segment
		(start 78.28534 -18.463006)
		(end 77.757528 -18.990818)
		(width 0.13208)
		(layer "F.Cu")
		(net "SMB_ISO_SSD2_SCL")
	)
	(segment
		(start 78.210664 -16.364712)
		(end 78.28534 -16.439388)
		(width 0.13208)
		(layer "F.Cu")
		(net "SMB_ISO_SSD2_SCL")
	)
	(segment
		(start 78.210664 -15.374366)
		(end 78.210664 -16.364712)
		(width 0.13208)
		(layer "F.Cu")
		(net "SMB_ISO_SSD2_SCL")
	)
	(segment
		(start 76.62164 -18.990818)
		(end 76.06792 -18.437098)
		(width 0.13208)
		(layer "F.Cu")
		(net "SMB_ISO_SSD2_SCL")
	)
	(segment
		(start 77.757528 -18.990818)
		(end 76.62164 -18.990818)
		(width 0.13208)
		(layer "F.Cu")
		(net "SMB_ISO_SSD2_SCL")
	)
	(segment
		(start 76.024232 -18.437098)
		(end 76.06792 -18.437098)
		(width 0.13208)
		(layer "F.Cu")
		(net "SMB_ISO_SSD2_SCL")
	)
	(via
		(at 78.210664 -15.374366)
		(size 0.508)
		(drill 0.254)
		(layers "F.Cu" "B.Cu")
		(net "SMB_ISO_SSD2_SCL")
	)
	(via
		(at 78.45933 -23.965154)
		(size 0.508)
		(drill 0.254)
		(layers "F.Cu" "B.Cu")
		(net "SMB_ISO_SSD2_SCL")
	)
	(segment
		(start 78.468728 -15.92199)
		(end 78.468728 -15.63243)
		(width 0.13208)
		(layer "B.Cu")
		(net "SMB_ISO_SSD2_SCL")
	)
	(segment
		(start 78.468728 -15.63243)
		(end 78.210664 -15.374366)
		(width 0.13208)
		(layer "B.Cu")
		(net "SMB_ISO_SSD2_SCL")
	)
	(segment
		(start 79.705708 -17.15897)
		(end 78.468728 -15.92199)
		(width 0.13208)
		(layer "B.Cu")
		(net "SMB_ISO_SSD2_SCL")
	)
	(segment
		(start 78.45933 -23.965154)
		(end 79.705708 -22.718776)
		(width 0.13208)
		(layer "B.Cu")
		(net "SMB_ISO_SSD2_SCL")
	)
	(segment
		(start 79.705708 -22.718776)
		(end 79.705708 -17.15897)
		(width 0.13208)
		(layer "B.Cu")
		(net "SMB_ISO_SSD2_SCL")
	)
	(segment
		(start 396.958312 -19.453098)
		(end 397.567912 -19.453098)
		(width 0.13208)
		(layer "F.Cu")
		(net "SMB_ISO_SSD13_R_SDA")
	)
	(segment
		(start 384.96494 -22.990048)
		(end 386.009388 -22.990048)
		(width 0.13208)
		(layer "F.Cu")
		(net "SMB_ISO_SSD13_R_SDA")
	)
	(segment
		(start 386.009388 -22.990048)
		(end 386.04444 -23.0251)
		(width 0.13208)
		(layer "F.Cu")
		(net "SMB_ISO_SSD13_R_SDA")
	)
	(via
		(at 386.04444 -23.0251)
		(size 0.508)
		(drill 0.254)
		(layers "F.Cu" "B.Cu")
		(net "SMB_ISO_SSD13_R_SDA")
	)
	(via
		(at 396.958312 -19.453098)
		(size 0.508)
		(drill 0.254)
		(layers "F.Cu" "B.Cu")
		(net "SMB_ISO_SSD13_R_SDA")
	)
	(segment
		(start 395.816328 -22.53234)
		(end 386.5372 -22.53234)
		(width 0.15494)
		(layer "In5.Cu")
		(net "SMB_ISO_SSD13_R_SDA")
	)
	(segment
		(start 396.958312 -21.390356)
		(end 395.816328 -22.53234)
		(width 0.15494)
		(layer "In5.Cu")
		(net "SMB_ISO_SSD13_R_SDA")
	)
	(segment
		(start 386.5372 -22.53234)
		(end 386.04444 -23.0251)
		(width 0.15494)
		(layer "In5.Cu")
		(net "SMB_ISO_SSD13_R_SDA")
	)
	(segment
		(start 396.958312 -19.453098)
		(end 396.958312 -21.390356)
		(width 0.15494)
		(layer "In5.Cu")
		(net "SMB_ISO_SSD13_R_SDA")
	)
	(segment
		(start 381.527812 -84.186522)
		(end 382.640078 -84.186522)
		(width 0.13208)
		(layer "F.Cu")
		(net "SMB_BIC_I2C6_MUX_THERMAL_SCL")
	)
	(segment
		(start 381.167386 -83.826096)
		(end 381.527812 -84.186522)
		(width 0.13208)
		(layer "F.Cu")
		(net "SMB_BIC_I2C6_MUX_THERMAL_SCL")
	)
	(segment
		(start 379.912118 -83.1088)
		(end 380.629414 -83.826096)
		(width 0.13208)
		(layer "F.Cu")
		(net "SMB_BIC_I2C6_MUX_THERMAL_SCL")
	)
	(segment
		(start 379.252734 -83.1088)
		(end 379.912118 -83.1088)
		(width 0.13208)
		(layer "F.Cu")
		(net "SMB_BIC_I2C6_MUX_THERMAL_SCL")
	)
	(segment
		(start 380.629414 -83.826096)
		(end 381.167386 -83.826096)
		(width 0.13208)
		(layer "F.Cu")
		(net "SMB_BIC_I2C6_MUX_THERMAL_SCL")
	)
	(via
		(at 381.167386 -83.826096)
		(size 0.508)
		(drill 0.254)
		(layers "F.Cu" "B.Cu")
		(net "SMB_BIC_I2C6_MUX_THERMAL_SCL")
	)
	(segment
		(start 319.30594 -392.063732)
		(end 319.30594 -391.000742)
		(width 0.13208)
		(layer "F.Cu")
		(net "GPU_3V3IO_RSVD3_FFU")
	)
	(segment
		(start 319.30594 -391.000742)
		(end 319.296034 -390.990836)
		(width 0.13208)
		(layer "F.Cu")
		(net "GPU_3V3IO_RSVD3_FFU")
	)
	(segment
		(start 319.296034 -390.990836)
		(end 318.58585 -390.990836)
		(width 0.13208)
		(layer "F.Cu")
		(net "GPU_3V3IO_RSVD3_FFU")
	)
	(via
		(at 318.58585 -390.990836)
		(size 0.508)
		(drill 0.254)
		(layers "F.Cu" "B.Cu")
		(net "GPU_3V3IO_RSVD3_FFU")
	)
	(segment
		(start 315.510164 -390.990836)
		(end 312.22823 -394.27277)
		(width 0.15494)
		(layer "In9.Cu")
		(net "GPU_3V3IO_RSVD3_FFU")
	)
	(segment
		(start 312.22823 -394.27277)
		(end 312.22823 -410.24937)
		(width 0.15494)
		(layer "In9.Cu")
		(net "GPU_3V3IO_RSVD3_FFU")
	)
	(segment
		(start 289.673792 -414.274)
		(end 287.4899 -412.090108)
		(width 0.15494)
		(layer "In9.Cu")
		(net "GPU_3V3IO_RSVD3_FFU")
	)
	(segment
		(start 312.22823 -410.24937)
		(end 308.2036 -414.274)
		(width 0.15494)
		(layer "In9.Cu")
		(net "GPU_3V3IO_RSVD3_FFU")
	)
	(segment
		(start 318.58585 -390.990836)
		(end 315.510164 -390.990836)
		(width 0.15494)
		(layer "In9.Cu")
		(net "GPU_3V3IO_RSVD3_FFU")
	)
	(segment
		(start 308.2036 -414.274)
		(end 289.673792 -414.274)
		(width 0.15494)
		(layer "In9.Cu")
		(net "GPU_3V3IO_RSVD3_FFU")
	)
	(segment
		(start 346.71 -208.407)
		(end 346.71 -207.645)
		(width 0.13208)
		(layer "F.Cu")
		(net "PRSNT_SSD1_FPGA_N")
	)
	(segment
		(start 346.71 -207.645)
		(end 346.71 -205.63205)
		(width 0.13208)
		(layer "F.Cu")
		(net "PRSNT_SSD1_FPGA_N")
	)
	(segment
		(start 344.49385 -211.18703)
		(end 344.49385 -210.62315)
		(width 0.13208)
		(layer "F.Cu")
		(net "PRSNT_SSD1_FPGA_N")
	)
	(segment
		(start 344.49385 -210.62315)
		(end 346.71 -208.407)
		(width 0.13208)
		(layer "F.Cu")
		(net "PRSNT_SSD1_FPGA_N")
	)
	(via
		(at 346.71 -207.645)
		(size 0.762)
		(drill 0.381)
		(layers "F.Cu" "B.Cu")
		(net "PRSNT_SSD1_FPGA_N")
	)
	(segment
		(start 205.102206 -305.092354)
		(end 205.101698 -305.091846)
		(width 0.13208)
		(layer "F.Cu")
		(net "PEX1_SPARE4")
	)
	(segment
		(start 205.102206 -305.092354)
		(end 205.102206 -305.674522)
		(width 0.13208)
		(layer "F.Cu")
		(net "PEX1_SPARE4")
	)
	(segment
		(start 176.224946 -307.774848)
		(end 175.749966 -308.249828)
		(width 0.13462)
		(layer "F.Cu")
		(net "PEX1_SPARE4")
	)
	(segment
		(start 205.101698 -305.091846)
		(end 205.101698 -304.436526)
		(width 0.13208)
		(layer "F.Cu")
		(net "PEX1_SPARE4")
	)
	(segment
		(start 205.102206 -305.064922)
		(end 205.102206 -305.092354)
		(width 0.13208)
		(layer "F.Cu")
		(net "PEX1_SPARE4")
	)
	(via
		(at 205.102206 -305.064922)
		(size 0.508)
		(drill 0.254)
		(layers "F.Cu" "B.Cu")
		(net "PEX1_SPARE4")
	)
	(via
		(at 176.224946 -307.774848)
		(size 0.4064)
		(drill 0.2032)
		(layers "F.Cu" "B.Cu")
		(net "PEX1_SPARE4")
	)
	(via
		(at 200.204832 -306.835556)
		(size 0.6604)
		(drill 0.3302)
		(layers "F.Cu" "B.Cu")
		(net "PEX1_SPARE4")
	)
	(segment
		(start 188.099192 -307.527706)
		(end 188.337698 -307.2892)
		(width 0.13208)
		(layer "B.Cu")
		(net "PEX1_SPARE4")
	)
	(segment
		(start 188.337698 -307.2892)
		(end 189.153546 -307.2892)
		(width 0.13208)
		(layer "B.Cu")
		(net "PEX1_SPARE4")
	)
	(segment
		(start 188.099192 -307.967126)
		(end 188.099192 -307.527706)
		(width 0.13208)
		(layer "B.Cu")
		(net "PEX1_SPARE4")
	)
	(segment
		(start 205.102206 -305.064922)
		(end 205.102206 -304.159666)
		(width 0.13208)
		(layer "B.Cu")
		(net "PEX1_SPARE4")
	)
	(segment
		(start 176.686718 -308.23662)
		(end 187.829698 -308.23662)
		(width 0.13208)
		(layer "B.Cu")
		(net "PEX1_SPARE4")
	)
	(segment
		(start 205.102206 -304.159666)
		(end 204.975206 -304.032666)
		(width 0.13208)
		(layer "B.Cu")
		(net "PEX1_SPARE4")
	)
	(segment
		(start 189.60719 -306.835556)
		(end 200.204832 -306.835556)
		(width 0.13208)
		(layer "B.Cu")
		(net "PEX1_SPARE4")
	)
	(segment
		(start 203.735432 -304.032666)
		(end 201.446638 -306.32146)
		(width 0.13208)
		(layer "B.Cu")
		(net "PEX1_SPARE4")
	)
	(segment
		(start 189.153546 -307.2892)
		(end 189.60719 -306.835556)
		(width 0.13208)
		(layer "B.Cu")
		(net "PEX1_SPARE4")
	)
	(segment
		(start 201.446638 -306.32146)
		(end 200.204832 -306.835556)
		(width 0.13208)
		(layer "B.Cu")
		(net "PEX1_SPARE4")
	)
	(segment
		(start 176.224946 -307.774848)
		(end 176.686718 -308.23662)
		(width 0.13208)
		(layer "B.Cu")
		(net "PEX1_SPARE4")
	)
	(segment
		(start 187.829698 -308.23662)
		(end 188.099192 -307.967126)
		(width 0.13208)
		(layer "B.Cu")
		(net "PEX1_SPARE4")
	)
	(segment
		(start 204.975206 -304.032666)
		(end 203.735432 -304.032666)
		(width 0.13208)
		(layer "B.Cu")
		(net "PEX1_SPARE4")
	)
	(segment
		(start 79.462376 -23.337266)
		(end 79.462376 -23.946866)
		(width 0.13208)
		(layer "F.Cu")
		(net "SMB_ISO_SSD2_SDA")
	)
	(segment
		(start 78.93558 -16.439388)
		(end 78.93558 -18.533618)
		(width 0.13208)
		(layer "F.Cu")
		(net "SMB_ISO_SSD2_SDA")
	)
	(segment
		(start 76.026264 -19.453098)
		(end 76.06792 -19.453098)
		(width 0.13208)
		(layer "F.Cu")
		(net "SMB_ISO_SSD2_SDA")
	)
	(segment
		(start 78.93558 -18.533618)
		(end 78.0161 -19.453098)
		(width 0.13208)
		(layer "F.Cu")
		(net "SMB_ISO_SSD2_SDA")
	)
	(segment
		(start 78.947518 -15.339822)
		(end 78.93558 -15.35176)
		(width 0.13208)
		(layer "F.Cu")
		(net "SMB_ISO_SSD2_SDA")
	)
	(segment
		(start 78.0161 -19.453098)
		(end 76.06792 -19.453098)
		(width 0.13208)
		(layer "F.Cu")
		(net "SMB_ISO_SSD2_SDA")
	)
	(segment
		(start 78.93558 -15.35176)
		(end 78.93558 -16.439388)
		(width 0.13208)
		(layer "F.Cu")
		(net "SMB_ISO_SSD2_SDA")
	)
	(segment
		(start 75.25639 -20.222972)
		(end 76.026264 -19.453098)
		(width 0.13208)
		(layer "F.Cu")
		(net "SMB_ISO_SSD2_SDA")
	)
	(segment
		(start 75.25639 -20.467574)
		(end 75.25639 -20.222972)
		(width 0.13208)
		(layer "F.Cu")
		(net "SMB_ISO_SSD2_SDA")
	)
	(via
		(at 79.462376 -23.946866)
		(size 0.508)
		(drill 0.254)
		(layers "F.Cu" "B.Cu")
		(net "SMB_ISO_SSD2_SDA")
	)
	(via
		(at 78.947518 -15.339822)
		(size 0.508)
		(drill 0.254)
		(layers "F.Cu" "B.Cu")
		(net "SMB_ISO_SSD2_SDA")
	)
	(segment
		(start 79.462376 -23.946866)
		(end 81.016094 -22.393148)
		(width 0.13208)
		(layer "B.Cu")
		(net "SMB_ISO_SSD2_SDA")
	)
	(segment
		(start 81.016094 -22.393148)
		(end 81.016094 -17.70888)
		(width 0.13208)
		(layer "B.Cu")
		(net "SMB_ISO_SSD2_SDA")
	)
	(segment
		(start 78.947518 -15.640304)
		(end 78.947518 -15.339822)
		(width 0.13208)
		(layer "B.Cu")
		(net "SMB_ISO_SSD2_SDA")
	)
	(segment
		(start 81.016094 -17.70888)
		(end 78.947518 -15.640304)
		(width 0.13208)
		(layer "B.Cu")
		(net "SMB_ISO_SSD2_SDA")
	)
	(segment
		(start 333.981298 -11.543792)
		(end 333.974186 -11.53668)
		(width 0.13208)
		(layer "F.Cu")
		(net "SMB_ISO_SSD11_R_SCL")
	)
	(segment
		(start 333.974186 -11.53668)
		(end 333.974186 -10.934192)
		(width 0.13208)
		(layer "F.Cu")
		(net "SMB_ISO_SSD11_R_SCL")
	)
	(segment
		(start 322.667376 -22.3901)
		(end 323.293486 -23.01621)
		(width 0.13208)
		(layer "F.Cu")
		(net "SMB_ISO_SSD11_R_SCL")
	)
	(segment
		(start 320.864738 -22.3901)
		(end 322.667376 -22.3901)
		(width 0.13208)
		(layer "F.Cu")
		(net "SMB_ISO_SSD11_R_SCL")
	)
	(via
		(at 323.293486 -23.01621)
		(size 0.508)
		(drill 0.254)
		(layers "F.Cu" "B.Cu")
		(net "SMB_ISO_SSD11_R_SCL")
	)
	(via
		(at 333.981298 -11.543792)
		(size 0.508)
		(drill 0.254)
		(layers "F.Cu" "B.Cu")
		(net "SMB_ISO_SSD11_R_SCL")
	)
	(segment
		(start 333.426816 -21.47189)
		(end 333.426816 -12.098274)
		(width 0.15494)
		(layer "In5.Cu")
		(net "SMB_ISO_SSD11_R_SCL")
	)
	(segment
		(start 333.426816 -12.098274)
		(end 333.981298 -11.543792)
		(width 0.15494)
		(layer "In5.Cu")
		(net "SMB_ISO_SSD11_R_SCL")
	)
	(segment
		(start 331.882496 -23.01621)
		(end 333.426816 -21.47189)
		(width 0.15494)
		(layer "In5.Cu")
		(net "SMB_ISO_SSD11_R_SCL")
	)
	(segment
		(start 323.293486 -23.01621)
		(end 331.882496 -23.01621)
		(width 0.15494)
		(layer "In5.Cu")
		(net "SMB_ISO_SSD11_R_SCL")
	)
	(segment
		(start 379.69317 -84.2518)
		(end 379.252734 -84.2518)
		(width 0.13208)
		(layer "F.Cu")
		(net "SMB_BIC_I2C6_MUX_THERMAL_SDA")
	)
	(segment
		(start 382.640078 -84.836508)
		(end 380.277878 -84.836508)
		(width 0.13208)
		(layer "F.Cu")
		(net "SMB_BIC_I2C6_MUX_THERMAL_SDA")
	)
	(segment
		(start 380.277878 -84.836508)
		(end 379.905006 -84.463636)
		(width 0.13208)
		(layer "F.Cu")
		(net "SMB_BIC_I2C6_MUX_THERMAL_SDA")
	)
	(segment
		(start 379.905006 -84.463636)
		(end 379.69317 -84.2518)
		(width 0.13208)
		(layer "F.Cu")
		(net "SMB_BIC_I2C6_MUX_THERMAL_SDA")
	)
	(via
		(at 379.905006 -84.463636)
		(size 0.508)
		(drill 0.254)
		(layers "F.Cu" "B.Cu")
		(net "SMB_BIC_I2C6_MUX_THERMAL_SDA")
	)
	(segment
		(start 267.394944 -58.453782)
		(end 267.39088 -58.449718)
		(width 0.2032)
		(layer "F.Cu")
		(net "P3V3_SSD9_SS")
	)
	(segment
		(start 266.340844 -57.233566)
		(end 267.273278 -58.166)
		(width 0.2032)
		(layer "F.Cu")
		(net "P3V3_SSD9_SS")
	)
	(segment
		(start 266.340844 -57.16397)
		(end 266.340844 -57.233566)
		(width 0.2032)
		(layer "F.Cu")
		(net "P3V3_SSD9_SS")
	)
	(segment
		(start 267.394944 -59.177936)
		(end 267.394944 -58.453782)
		(width 0.2032)
		(layer "F.Cu")
		(net "P3V3_SSD9_SS")
	)
	(segment
		(start 267.273278 -58.166)
		(end 267.39088 -58.449718)
		(width 0.2032)
		(layer "F.Cu")
		(net "P3V3_SSD9_SS")
	)
	(via
		(at 267.39088 -58.449718)
		(size 0.508)
		(drill 0.254)
		(layers "F.Cu" "B.Cu")
		(net "P3V3_SSD9_SS")
	)
	(segment
		(start 152.182576 -236.221016)
		(end 132.830316 -236.221016)
		(width 0.1143)
		(layer "F.Cu")
		(net "CLK_100M_DB2000QL_PEX1_S1_R_DN")
	)
	(segment
		(start 153.856182 -239.048798)
		(end 154.1145 -238.79048)
		(width 0.1143)
		(layer "F.Cu")
		(net "CLK_100M_DB2000QL_PEX1_S1_R_DN")
	)
	(segment
		(start 126.3269 -207.905858)
		(end 126.3269 -190.8556)
		(width 0.1143)
		(layer "F.Cu")
		(net "CLK_100M_DB2000QL_PEX1_S1_R_DN")
	)
	(segment
		(start 122.929396 -211.303362)
		(end 126.3269 -207.905858)
		(width 0.1143)
		(layer "F.Cu")
		(net "CLK_100M_DB2000QL_PEX1_S1_R_DN")
	)
	(segment
		(start 152.94991 -297.79976)
		(end 152.949656 -297.79976)
		(width 0.1143)
		(layer "F.Cu")
		(net "CLK_100M_DB2000QL_PEX1_S1_R_DN")
	)
	(segment
		(start 121.058178 -176.299876)
		(end 123.037854 -174.3202)
		(width 0.1143)
		(layer "F.Cu")
		(net "CLK_100M_DB2000QL_PEX1_S1_R_DN")
	)
	(segment
		(start 132.830316 -236.221016)
		(end 122.929396 -226.320096)
		(width 0.1143)
		(layer "F.Cu")
		(net "CLK_100M_DB2000QL_PEX1_S1_R_DN")
	)
	(segment
		(start 152.949656 -297.79976)
		(end 152.474676 -297.32478)
		(width 0.1143)
		(layer "F.Cu")
		(net "CLK_100M_DB2000QL_PEX1_S1_R_DN")
	)
	(segment
		(start 126.3269 -190.8556)
		(end 121.058178 -185.586878)
		(width 0.1143)
		(layer "F.Cu")
		(net "CLK_100M_DB2000QL_PEX1_S1_R_DN")
	)
	(segment
		(start 121.058178 -185.586878)
		(end 121.058178 -176.299876)
		(width 0.1143)
		(layer "F.Cu")
		(net "CLK_100M_DB2000QL_PEX1_S1_R_DN")
	)
	(segment
		(start 154.1145 -238.15294)
		(end 152.182576 -236.221016)
		(width 0.1143)
		(layer "F.Cu")
		(net "CLK_100M_DB2000QL_PEX1_S1_R_DN")
	)
	(segment
		(start 125.49251 -174.3202)
		(end 125.821186 -173.991524)
		(width 0.1143)
		(layer "F.Cu")
		(net "CLK_100M_DB2000QL_PEX1_S1_R_DN")
	)
	(segment
		(start 154.1145 -238.79048)
		(end 154.1145 -238.15294)
		(width 0.1143)
		(layer "F.Cu")
		(net "CLK_100M_DB2000QL_PEX1_S1_R_DN")
	)
	(segment
		(start 122.929396 -226.320096)
		(end 122.929396 -211.303362)
		(width 0.1143)
		(layer "F.Cu")
		(net "CLK_100M_DB2000QL_PEX1_S1_R_DN")
	)
	(segment
		(start 123.037854 -174.3202)
		(end 125.49251 -174.3202)
		(width 0.1143)
		(layer "F.Cu")
		(net "CLK_100M_DB2000QL_PEX1_S1_R_DN")
	)
	(via
		(at 153.856182 -239.048798)
		(size 0.508)
		(drill 0.254)
		(layers "F.Cu" "B.Cu")
		(net "CLK_100M_DB2000QL_PEX1_S1_R_DN")
	)
	(via
		(at 152.474676 -297.32478)
		(size 0.4064)
		(drill 0.2032)
		(layers "F.Cu" "B.Cu")
		(net "CLK_100M_DB2000QL_PEX1_S1_R_DN")
	)
	(segment
		(start 154.110182 -239.302798)
		(end 153.856182 -239.048798)
		(width 0.1143)
		(layer "B.Cu")
		(net "CLK_100M_DB2000QL_PEX1_S1_R_DN")
	)
	(segment
		(start 152.420066 -296.6212)
		(end 151.99995 -296.6212)
		(width 0.0889)
		(layer "B.Cu")
		(net "CLK_100M_DB2000QL_PEX1_S1_R_DN")
	)
	(segment
		(start 147.789138 -295.102534)
		(end 146.574256 -293.887652)
		(width 0.1143)
		(layer "B.Cu")
		(net "CLK_100M_DB2000QL_PEX1_S1_R_DN")
	)
	(segment
		(start 152.854406 -297.23588)
		(end 152.854406 -297.05554)
		(width 0.0889)
		(layer "B.Cu")
		(net "CLK_100M_DB2000QL_PEX1_S1_R_DN")
	)
	(segment
		(start 146.574256 -278.832056)
		(end 144.081754 -276.339554)
		(width 0.1143)
		(layer "B.Cu")
		(net "CLK_100M_DB2000QL_PEX1_S1_R_DN")
	)
	(segment
		(start 151.54275 -296.70375)
		(end 149.941534 -295.102534)
		(width 0.1143)
		(layer "B.Cu")
		(net "CLK_100M_DB2000QL_PEX1_S1_R_DN")
	)
	(segment
		(start 151.99995 -296.6212)
		(end 151.9174 -296.70375)
		(width 0.0889)
		(layer "B.Cu")
		(net "CLK_100M_DB2000QL_PEX1_S1_R_DN")
	)
	(segment
		(start 144.081754 -276.339554)
		(end 143.509746 -276.339554)
		(width 0.1143)
		(layer "B.Cu")
		(net "CLK_100M_DB2000QL_PEX1_S1_R_DN")
	)
	(segment
		(start 151.895302 -296.70375)
		(end 151.54275 -296.70375)
		(width 0.1143)
		(layer "B.Cu")
		(net "CLK_100M_DB2000QL_PEX1_S1_R_DN")
	)
	(segment
		(start 148.183346 -246.177308)
		(end 154.110182 -240.250472)
		(width 0.1143)
		(layer "B.Cu")
		(net "CLK_100M_DB2000QL_PEX1_S1_R_DN")
	)
	(segment
		(start 136.74471 -269.574518)
		(end 136.74471 -252.257814)
		(width 0.1143)
		(layer "B.Cu")
		(net "CLK_100M_DB2000QL_PEX1_S1_R_DN")
	)
	(segment
		(start 154.110182 -240.250472)
		(end 154.110182 -239.302798)
		(width 0.1143)
		(layer "B.Cu")
		(net "CLK_100M_DB2000QL_PEX1_S1_R_DN")
	)
	(segment
		(start 152.854406 -297.05554)
		(end 152.420066 -296.6212)
		(width 0.0889)
		(layer "B.Cu")
		(net "CLK_100M_DB2000QL_PEX1_S1_R_DN")
	)
	(segment
		(start 136.74471 -252.257814)
		(end 142.825216 -246.177308)
		(width 0.1143)
		(layer "B.Cu")
		(net "CLK_100M_DB2000QL_PEX1_S1_R_DN")
	)
	(segment
		(start 142.825216 -246.177308)
		(end 148.183346 -246.177308)
		(width 0.1143)
		(layer "B.Cu")
		(net "CLK_100M_DB2000QL_PEX1_S1_R_DN")
	)
	(segment
		(start 146.574256 -293.887652)
		(end 146.574256 -278.832056)
		(width 0.1143)
		(layer "B.Cu")
		(net "CLK_100M_DB2000QL_PEX1_S1_R_DN")
	)
	(segment
		(start 152.474676 -297.32478)
		(end 152.765506 -297.32478)
		(width 0.0889)
		(layer "B.Cu")
		(net "CLK_100M_DB2000QL_PEX1_S1_R_DN")
	)
	(segment
		(start 149.941534 -295.102534)
		(end 147.789138 -295.102534)
		(width 0.1143)
		(layer "B.Cu")
		(net "CLK_100M_DB2000QL_PEX1_S1_R_DN")
	)
	(segment
		(start 151.9174 -296.70375)
		(end 151.895302 -296.70375)
		(width 0.0889)
		(layer "B.Cu")
		(net "CLK_100M_DB2000QL_PEX1_S1_R_DN")
	)
	(segment
		(start 143.509746 -276.339554)
		(end 136.74471 -269.574518)
		(width 0.1143)
		(layer "B.Cu")
		(net "CLK_100M_DB2000QL_PEX1_S1_R_DN")
	)
	(segment
		(start 152.765506 -297.32478)
		(end 152.854406 -297.23588)
		(width 0.0889)
		(layer "B.Cu")
		(net "CLK_100M_DB2000QL_PEX1_S1_R_DN")
	)
	(segment
		(start 273.967702 -81.401412)
		(end 274.255992 -81.113122)
		(width 0.13462)
		(layer "F.Cu")
		(net "CLK_100M_CK440Q_1_DB800ZL_R_DN")
	)
	(segment
		(start 105.461308 -86.578948)
		(end 105.402126 -86.63813)
		(width 0.13462)
		(layer "F.Cu")
		(net "CLK_100M_CK440Q_1_DB800ZL_R_DN")
	)
	(segment
		(start 104.181402 -86.248748)
		(end 100.601272 -86.248748)
		(width 0.13462)
		(layer "F.Cu")
		(net "CLK_100M_CK440Q_1_DB800ZL_R_DN")
	)
	(segment
		(start 269.24889 -81.401412)
		(end 273.967702 -81.401412)
		(width 0.13462)
		(layer "F.Cu")
		(net "CLK_100M_CK440Q_1_DB800ZL_R_DN")
	)
	(segment
		(start 100.601272 -86.248748)
		(end 100.300282 -85.947758)
		(width 0.13462)
		(layer "F.Cu")
		(net "CLK_100M_CK440Q_1_DB800ZL_R_DN")
	)
	(segment
		(start 105.889044 -86.578948)
		(end 105.461308 -86.578948)
		(width 0.13462)
		(layer "F.Cu")
		(net "CLK_100M_CK440Q_1_DB800ZL_R_DN")
	)
	(segment
		(start 105.402126 -86.63813)
		(end 104.570784 -86.63813)
		(width 0.13462)
		(layer "F.Cu")
		(net "CLK_100M_CK440Q_1_DB800ZL_R_DN")
	)
	(segment
		(start 104.570784 -86.63813)
		(end 104.181402 -86.248748)
		(width 0.13462)
		(layer "F.Cu")
		(net "CLK_100M_CK440Q_1_DB800ZL_R_DN")
	)
	(segment
		(start 268.9352 -81.087722)
		(end 269.24889 -81.401412)
		(width 0.13462)
		(layer "F.Cu")
		(net "CLK_100M_CK440Q_1_DB800ZL_R_DN")
	)
	(via
		(at 100.300282 -85.947758)
		(size 0.508)
		(drill 0.254)
		(layers "F.Cu" "B.Cu")
		(net "CLK_100M_CK440Q_1_DB800ZL_R_DN")
	)
	(via
		(at 274.255992 -81.113122)
		(size 0.508)
		(drill 0.254)
		(layers "F.Cu" "B.Cu")
		(net "CLK_100M_CK440Q_1_DB800ZL_R_DN")
	)
	(segment
		(start 242.6462 -76.8096)
		(end 240.3094 -74.4728)
		(width 0.1651)
		(layer "In9.Cu")
		(net "CLK_100M_CK440Q_1_DB800ZL_R_DN")
	)
	(segment
		(start 118.237 -81.534)
		(end 116.575078 -80.84566)
		(width 0.1651)
		(layer "In9.Cu")
		(net "CLK_100M_CK440Q_1_DB800ZL_R_DN")
	)
	(segment
		(start 105.17632 -81.5213)
		(end 103.444802 -83.252818)
		(width 0.1651)
		(layer "In9.Cu")
		(net "CLK_100M_CK440Q_1_DB800ZL_R_DN")
	)
	(segment
		(start 102.49281 -85.55101)
		(end 101.805232 -86.238588)
		(width 0.1651)
		(layer "In9.Cu")
		(net "CLK_100M_CK440Q_1_DB800ZL_R_DN")
	)
	(segment
		(start 103.444802 -83.252818)
		(end 102.49281 -85.55101)
		(width 0.1651)
		(layer "In9.Cu")
		(net "CLK_100M_CK440Q_1_DB800ZL_R_DN")
	)
	(segment
		(start 219.8624 -75.2348)
		(end 196.5706 -75.2348)
		(width 0.1651)
		(layer "In9.Cu")
		(net "CLK_100M_CK440Q_1_DB800ZL_R_DN")
	)
	(segment
		(start 223.8756 -73.6346)
		(end 221.4626 -73.6346)
		(width 0.1651)
		(layer "In9.Cu")
		(net "CLK_100M_CK440Q_1_DB800ZL_R_DN")
	)
	(segment
		(start 269.973552 -81.403952)
		(end 267.208 -78.6384)
		(width 0.1651)
		(layer "In9.Cu")
		(net "CLK_100M_CK440Q_1_DB800ZL_R_DN")
	)
	(segment
		(start 224.7138 -74.4728)
		(end 223.8756 -73.6346)
		(width 0.1651)
		(layer "In9.Cu")
		(net "CLK_100M_CK440Q_1_DB800ZL_R_DN")
	)
	(segment
		(start 267.208 -78.6384)
		(end 262.1534 -78.6384)
		(width 0.1651)
		(layer "In9.Cu")
		(net "CLK_100M_CK440Q_1_DB800ZL_R_DN")
	)
	(segment
		(start 262.1534 -78.6384)
		(end 260.7564 -77.2414)
		(width 0.1651)
		(layer "In9.Cu")
		(net "CLK_100M_CK440Q_1_DB800ZL_R_DN")
	)
	(segment
		(start 100.591112 -86.238588)
		(end 100.300282 -85.947758)
		(width 0.1651)
		(layer "In9.Cu")
		(net "CLK_100M_CK440Q_1_DB800ZL_R_DN")
	)
	(segment
		(start 240.3094 -74.4728)
		(end 224.7138 -74.4728)
		(width 0.1651)
		(layer "In9.Cu")
		(net "CLK_100M_CK440Q_1_DB800ZL_R_DN")
	)
	(segment
		(start 221.4626 -73.6346)
		(end 219.8624 -75.2348)
		(width 0.1651)
		(layer "In9.Cu")
		(net "CLK_100M_CK440Q_1_DB800ZL_R_DN")
	)
	(segment
		(start 190.2714 -81.534)
		(end 118.237 -81.534)
		(width 0.1651)
		(layer "In9.Cu")
		(net "CLK_100M_CK440Q_1_DB800ZL_R_DN")
	)
	(segment
		(start 260.7564 -77.2414)
		(end 251.944378 -77.2414)
		(width 0.1651)
		(layer "In9.Cu")
		(net "CLK_100M_CK440Q_1_DB800ZL_R_DN")
	)
	(segment
		(start 274.255992 -81.113122)
		(end 273.965162 -81.403952)
		(width 0.1651)
		(layer "In9.Cu")
		(net "CLK_100M_CK440Q_1_DB800ZL_R_DN")
	)
	(segment
		(start 196.5706 -75.2348)
		(end 190.2714 -81.534)
		(width 0.1651)
		(layer "In9.Cu")
		(net "CLK_100M_CK440Q_1_DB800ZL_R_DN")
	)
	(segment
		(start 116.575078 -80.84566)
		(end 108.573062 -80.84566)
		(width 0.1651)
		(layer "In9.Cu")
		(net "CLK_100M_CK440Q_1_DB800ZL_R_DN")
	)
	(segment
		(start 101.805232 -86.238588)
		(end 100.591112 -86.238588)
		(width 0.1651)
		(layer "In9.Cu")
		(net "CLK_100M_CK440Q_1_DB800ZL_R_DN")
	)
	(segment
		(start 273.965162 -81.403952)
		(end 269.973552 -81.403952)
		(width 0.1651)
		(layer "In9.Cu")
		(net "CLK_100M_CK440Q_1_DB800ZL_R_DN")
	)
	(segment
		(start 108.573062 -80.84566)
		(end 105.17632 -81.5213)
		(width 0.1651)
		(layer "In9.Cu")
		(net "CLK_100M_CK440Q_1_DB800ZL_R_DN")
	)
	(segment
		(start 251.944378 -77.2414)
		(end 250.901708 -76.8096)
		(width 0.1651)
		(layer "In9.Cu")
		(net "CLK_100M_CK440Q_1_DB800ZL_R_DN")
	)
	(segment
		(start 250.901708 -76.8096)
		(end 242.6462 -76.8096)
		(width 0.1651)
		(layer "In9.Cu")
		(net "CLK_100M_CK440Q_1_DB800ZL_R_DN")
	)
	(segment
		(start 254.7239 -85.208364)
		(end 255.375918 -84.556346)
		(width 0.13208)
		(layer "F.Cu")
		(net "TP_CLK_CK440_PFT_OUT_DN")
	)
	(segment
		(start 254.7239 -86.520782)
		(end 254.7239 -85.208364)
		(width 0.13208)
		(layer "F.Cu")
		(net "TP_CLK_CK440_PFT_OUT_DN")
	)
	(segment
		(start 254.187452 -87.05723)
		(end 254.7239 -86.520782)
		(width 0.13208)
		(layer "F.Cu")
		(net "TP_CLK_CK440_PFT_OUT_DN")
	)
	(segment
		(start 249.356626 -89.463118)
		(end 251.690124 -89.463118)
		(width 0.13208)
		(layer "F.Cu")
		(net "TP_CLK_CK440_PFT_OUT_DN")
	)
	(segment
		(start 254.187452 -87.467948)
		(end 254.187452 -87.05723)
		(width 0.13208)
		(layer "F.Cu")
		(net "TP_CLK_CK440_PFT_OUT_DN")
	)
	(segment
		(start 251.690124 -89.463118)
		(end 252.593856 -88.559386)
		(width 0.13208)
		(layer "F.Cu")
		(net "TP_CLK_CK440_PFT_OUT_DN")
	)
	(segment
		(start 252.593856 -88.559386)
		(end 253.096014 -88.559386)
		(width 0.13208)
		(layer "F.Cu")
		(net "TP_CLK_CK440_PFT_OUT_DN")
	)
	(segment
		(start 253.096014 -88.559386)
		(end 254.187452 -87.467948)
		(width 0.13208)
		(layer "F.Cu")
		(net "TP_CLK_CK440_PFT_OUT_DN")
	)
	(segment
		(start 255.375918 -84.556346)
		(end 255.801876 -84.556346)
		(width 0.13208)
		(layer "F.Cu")
		(net "TP_CLK_CK440_PFT_OUT_DN")
	)
	(via
		(at 249.356626 -89.463118)
		(size 0.508)
		(drill 0.254)
		(layers "F.Cu" "B.Cu")
		(net "TP_CLK_CK440_PFT_OUT_DN")
	)
	(segment
		(start 170.999912 -308.249828)
		(end 170.524932 -307.774848)
		(width 0.13208)
		(layer "F.Cu")
		(net "TP_PEX1_TMS")
	)
	(via
		(at 170.524932 -307.774848)
		(size 0.4064)
		(drill 0.2032)
		(layers "F.Cu" "B.Cu")
		(net "TP_PEX1_TMS")
	)
	(via
		(at 170.049952 -307.299868)
		(size 0.6604)
		(drill 0.3302)
		(layers "F.Cu" "B.Cu")
		(net "TP_PEX1_TMS")
	)
	(segment
		(start 170.524932 -307.774848)
		(end 170.049952 -307.299868)
		(width 0.13208)
		(layer "B.Cu")
		(net "TP_PEX1_TMS")
	)
	(segment
		(start 377.66244 -83.1088)
		(end 378.452634 -83.1088)
		(width 0.13208)
		(layer "F.Cu")
		(net "SMB_BIC_I2C6_MUX_THERMAL_R_SCL")
	)
	(segment
		(start 376.712734 -83.1088)
		(end 377.66244 -83.1088)
		(width 0.13208)
		(layer "F.Cu")
		(net "SMB_BIC_I2C6_MUX_THERMAL_R_SCL")
	)
	(via
		(at 377.66244 -83.1088)
		(size 0.508)
		(drill 0.254)
		(layers "F.Cu" "B.Cu")
		(net "SMB_BIC_I2C6_MUX_THERMAL_R_SCL")
	)
	(segment
		(start 378.833634 -80.887316)
		(end 378.94895 -80.772)
		(width 0.13208)
		(layer "B.Cu")
		(net "SMB_BIC_I2C6_MUX_THERMAL_R_SCL")
	)
	(segment
		(start 378.833634 -83.1088)
		(end 378.833634 -80.887316)
		(width 0.13208)
		(layer "B.Cu")
		(net "SMB_BIC_I2C6_MUX_THERMAL_R_SCL")
	)
	(segment
		(start 378.833634 -83.1088)
		(end 377.66244 -83.1088)
		(width 0.13208)
		(layer "B.Cu")
		(net "SMB_BIC_I2C6_MUX_THERMAL_R_SCL")
	)
	(segment
		(start 149.480778 -383.460498)
		(end 149.480778 -384.591814)
		(width 0.13208)
		(layer "F.Cu")
		(net "RST_GPU_FPGA_EROT_R_N")
	)
	(via
		(at 149.480778 -384.591814)
		(size 0.508)
		(drill 0.254)
		(layers "F.Cu" "B.Cu")
		(net "RST_GPU_FPGA_EROT_R_N")
	)
	(segment
		(start 156.746702 -366.222026)
		(end 176.941988 -366.222026)
		(width 0.15494)
		(layer "In15.Cu")
		(net "RST_GPU_FPGA_EROT_R_N")
	)
	(segment
		(start 149.480778 -384.591814)
		(end 149.480778 -384.04165)
		(width 0.15494)
		(layer "In15.Cu")
		(net "RST_GPU_FPGA_EROT_R_N")
	)
	(segment
		(start 149.480778 -384.04165)
		(end 146.4818 -381.042672)
		(width 0.15494)
		(layer "In15.Cu")
		(net "RST_GPU_FPGA_EROT_R_N")
	)
	(segment
		(start 146.4818 -381.042672)
		(end 146.4818 -376.486928)
		(width 0.15494)
		(layer "In15.Cu")
		(net "RST_GPU_FPGA_EROT_R_N")
	)
	(segment
		(start 146.4818 -376.486928)
		(end 156.746702 -366.222026)
		(width 0.15494)
		(layer "In15.Cu")
		(net "RST_GPU_FPGA_EROT_R_N")
	)
	(segment
		(start 176.941988 -366.222026)
		(end 179.71008 -368.990118)
		(width 0.15494)
		(layer "In15.Cu")
		(net "RST_GPU_FPGA_EROT_R_N")
	)
	(segment
		(start 344.49385 -211.98713)
		(end 344.893646 -211.587334)
		(width 0.13208)
		(layer "F.Cu")
		(net "SSD1_PEX_PWR_EN_R")
	)
	(segment
		(start 363.87405 -207.899)
		(end 363.87405 -206.883)
		(width 0.13208)
		(layer "F.Cu")
		(net "SSD1_PEX_PWR_EN_R")
	)
	(segment
		(start 364.49 -206.883)
		(end 365.10595 -206.883)
		(width 0.13208)
		(layer "F.Cu")
		(net "SSD1_PEX_PWR_EN_R")
	)
	(segment
		(start 363.87405 -206.883)
		(end 364.49 -206.883)
		(width 0.13208)
		(layer "F.Cu")
		(net "SSD1_PEX_PWR_EN_R")
	)
	(via
		(at 364.49 -206.883)
		(size 0.508)
		(drill 0.254)
		(layers "F.Cu" "B.Cu")
		(net "SSD1_PEX_PWR_EN_R")
	)
	(via
		(at 344.893646 -211.587334)
		(size 0.4572)
		(drill 0.254)
		(layers "F.Cu" "B.Cu")
		(net "SSD1_PEX_PWR_EN_R")
	)
	(segment
		(start 364.49 -206.883)
		(end 362.6866 -208.6864)
		(width 0.15494)
		(layer "In13.Cu")
		(net "SSD1_PEX_PWR_EN_R")
	)
	(segment
		(start 346.85478 -209.6262)
		(end 344.893646 -211.587334)
		(width 0.15494)
		(layer "In13.Cu")
		(net "SSD1_PEX_PWR_EN_R")
	)
	(segment
		(start 358.572054 -209.804)
		(end 358.394254 -209.6262)
		(width 0.15494)
		(layer "In13.Cu")
		(net "SSD1_PEX_PWR_EN_R")
	)
	(segment
		(start 358.394254 -209.6262)
		(end 346.85478 -209.6262)
		(width 0.15494)
		(layer "In13.Cu")
		(net "SSD1_PEX_PWR_EN_R")
	)
	(segment
		(start 360.934254 -208.6864)
		(end 359.816654 -209.804)
		(width 0.15494)
		(layer "In13.Cu")
		(net "SSD1_PEX_PWR_EN_R")
	)
	(segment
		(start 359.816654 -209.804)
		(end 358.572054 -209.804)
		(width 0.15494)
		(layer "In13.Cu")
		(net "SSD1_PEX_PWR_EN_R")
	)
	(segment
		(start 362.6866 -208.6864)
		(end 360.934254 -208.6864)
		(width 0.15494)
		(layer "In13.Cu")
		(net "SSD1_PEX_PWR_EN_R")
	)
	(segment
		(start 254.633984 -87.11819)
		(end 254.633984 -87.427816)
		(width 0.13208)
		(layer "F.Cu")
		(net "TP_CLK_CK440_PFT_OUT_DP")
	)
	(segment
		(start 252.228604 -89.360756)
		(end 252.228604 -89.868502)
		(width 0.13208)
		(layer "F.Cu")
		(net "TP_CLK_CK440_PFT_OUT_DP")
	)
	(segment
		(start 255.301242 -85.056472)
		(end 255.010412 -85.347302)
		(width 0.13208)
		(layer "F.Cu")
		(net "TP_CLK_CK440_PFT_OUT_DP")
	)
	(segment
		(start 255.010412 -86.741762)
		(end 254.633984 -87.11819)
		(width 0.13208)
		(layer "F.Cu")
		(net "TP_CLK_CK440_PFT_OUT_DP")
	)
	(segment
		(start 255.010412 -85.347302)
		(end 255.010412 -86.741762)
		(width 0.13208)
		(layer "F.Cu")
		(net "TP_CLK_CK440_PFT_OUT_DP")
	)
	(segment
		(start 252.71476 -88.8746)
		(end 252.228604 -89.360756)
		(width 0.13208)
		(layer "F.Cu")
		(net "TP_CLK_CK440_PFT_OUT_DP")
	)
	(segment
		(start 253.1872 -88.8746)
		(end 252.71476 -88.8746)
		(width 0.13208)
		(layer "F.Cu")
		(net "TP_CLK_CK440_PFT_OUT_DP")
	)
	(segment
		(start 255.801876 -85.056472)
		(end 255.301242 -85.056472)
		(width 0.13208)
		(layer "F.Cu")
		(net "TP_CLK_CK440_PFT_OUT_DP")
	)
	(segment
		(start 254.633984 -87.427816)
		(end 253.1872 -88.8746)
		(width 0.13208)
		(layer "F.Cu")
		(net "TP_CLK_CK440_PFT_OUT_DP")
	)
	(via
		(at 252.228604 -89.868502)
		(size 0.508)
		(drill 0.254)
		(layers "F.Cu" "B.Cu")
		(net "TP_CLK_CK440_PFT_OUT_DP")
	)
	(segment
		(start 168.625012 -307.774848)
		(end 169.099992 -308.249828)
		(width 0.13208)
		(layer "F.Cu")
		(net "TP_PEX1_TRST_L")
	)
	(via
		(at 168.625012 -307.774848)
		(size 0.4064)
		(drill 0.2032)
		(layers "F.Cu" "B.Cu")
		(net "TP_PEX1_TRST_L")
	)
	(via
		(at 170.999912 -308.249828)
		(size 0.6604)
		(drill 0.3302)
		(layers "F.Cu" "B.Cu")
		(net "TP_PEX1_TRST_L")
	)
	(segment
		(start 172.900086 -308.249828)
		(end 172.975016 -308.324758)
		(width 0.13208)
		(layer "B.Cu")
		(net "TP_PEX1_TRST_L")
	)
	(segment
		(start 168.625012 -307.774848)
		(end 169.099992 -308.249828)
		(width 0.13208)
		(layer "B.Cu")
		(net "TP_PEX1_TRST_L")
	)
	(segment
		(start 172.975016 -308.324758)
		(end 172.983906 -308.324758)
		(width 0.13208)
		(layer "B.Cu")
		(net "TP_PEX1_TRST_L")
	)
	(segment
		(start 169.099992 -308.249828)
		(end 170.999912 -308.249828)
		(width 0.13208)
		(layer "B.Cu")
		(net "TP_PEX1_TRST_L")
	)
	(segment
		(start 170.999912 -308.249828)
		(end 172.900086 -308.249828)
		(width 0.13208)
		(layer "B.Cu")
		(net "TP_PEX1_TRST_L")
	)
	(segment
		(start 59.581796 -362.646976)
		(end 59.750452 -362.646976)
		(width 0.13208)
		(layer "F.Cu")
		(net "SMB_BIC_I2C6_MUX_THERMAL_R_SDA")
	)
	(segment
		(start 59.450478 -362.94695)
		(end 59.450478 -362.778294)
		(width 0.13208)
		(layer "F.Cu")
		(net "SMB_BIC_I2C6_MUX_THERMAL_R_SDA")
	)
	(segment
		(start 22.613112 -398.995392)
		(end 22.613112 -398.733772)
		(width 0.13208)
		(layer "F.Cu")
		(net "SMB_BIC_I2C6_MUX_THERMAL_R_SDA")
	)
	(segment
		(start 72.940164 -8.662416)
		(end 72.940164 -8.112252)
		(width 0.13208)
		(layer "F.Cu")
		(net "SMB_BIC_I2C6_MUX_THERMAL_R_SDA")
	)
	(segment
		(start 59.484514 -364.02391)
		(end 59.921648 -363.586776)
		(width 0.13208)
		(layer "F.Cu")
		(net "SMB_BIC_I2C6_MUX_THERMAL_R_SDA")
	)
	(segment
		(start 60.050426 -362.347002)
		(end 60.050426 -362.178346)
		(width 0.13208)
		(layer "F.Cu")
		(net "SMB_BIC_I2C6_MUX_THERMAL_R_SDA")
	)
	(segment
		(start 22.613112 -399.734532)
		(end 22.493732 -399.615152)
		(width 0.13208)
		(layer "F.Cu")
		(net "SMB_BIC_I2C6_MUX_THERMAL_R_SDA")
	)
	(segment
		(start 59.484514 -365.162084)
		(end 59.484514 -364.02391)
		(width 0.13208)
		(layer "F.Cu")
		(net "SMB_BIC_I2C6_MUX_THERMAL_R_SDA")
	)
	(segment
		(start 72.940164 -8.112252)
		(end 72.083676 -7.255764)
		(width 0.13208)
		(layer "F.Cu")
		(net "SMB_BIC_I2C6_MUX_THERMAL_R_SDA")
	)
	(segment
		(start 22.493732 -399.114772)
		(end 22.613112 -398.995392)
		(width 0.13208)
		(layer "F.Cu")
		(net "SMB_BIC_I2C6_MUX_THERMAL_R_SDA")
	)
	(segment
		(start 72.083676 -7.255764)
		(end 72.083676 -6.897624)
		(width 0.13208)
		(layer "F.Cu")
		(net "SMB_BIC_I2C6_MUX_THERMAL_R_SDA")
	)
	(segment
		(start 368.68354 -8.34263)
		(end 368.990118 -8.649208)
		(width 0.13208)
		(layer "F.Cu")
		(net "SMB_BIC_I2C6_MUX_THERMAL_R_SDA")
	)
	(segment
		(start 22.613112 -400.914108)
		(end 22.613112 -399.734532)
		(width 0.13208)
		(layer "F.Cu")
		(net "SMB_BIC_I2C6_MUX_THERMAL_R_SDA")
	)
	(segment
		(start 21.557488 -398.114012)
		(end 22.493732 -398.114012)
		(width 0.13208)
		(layer "F.Cu")
		(net "SMB_BIC_I2C6_MUX_THERMAL_R_SDA")
	)
	(segment
		(start 378.452634 -84.2518)
		(end 378.343922 -84.143088)
		(width 0.13208)
		(layer "F.Cu")
		(net "SMB_BIC_I2C6_MUX_THERMAL_R_SDA")
	)
	(segment
		(start 60.990226 -362.518198)
		(end 61.064394 -362.44403)
		(width 0.13208)
		(layer "F.Cu")
		(net "SMB_BIC_I2C6_MUX_THERMAL_R_SDA")
	)
	(segment
		(start 21.438108 -398.495012)
		(end 21.438108 -398.233392)
		(width 0.13208)
		(layer "F.Cu")
		(net "SMB_BIC_I2C6_MUX_THERMAL_R_SDA")
	)
	(segment
		(start 22.613112 -397.994632)
		(end 22.613112 -363.746034)
		(width 0.13208)
		(layer "F.Cu")
		(net "SMB_BIC_I2C6_MUX_THERMAL_R_SDA")
	)
	(segment
		(start 60.221622 -363.118146)
		(end 60.390278 -363.118146)
		(width 0.13208)
		(layer "F.Cu")
		(net "SMB_BIC_I2C6_MUX_THERMAL_R_SDA")
	)
	(segment
		(start 54.243224 -366.583214)
		(end 58.063384 -366.583214)
		(width 0.13208)
		(layer "F.Cu")
		(net "SMB_BIC_I2C6_MUX_THERMAL_R_SDA")
	)
	(segment
		(start 20.50796 -403.01926)
		(end 22.613112 -400.914108)
		(width 0.13208)
		(layer "F.Cu")
		(net "SMB_BIC_I2C6_MUX_THERMAL_R_SDA")
	)
	(segment
		(start 73.608438 -9.33069)
		(end 72.940164 -8.662416)
		(width 0.13208)
		(layer "F.Cu")
		(net "SMB_BIC_I2C6_MUX_THERMAL_R_SDA")
	)
	(segment
		(start 53.523134 -363.624114)
		(end 53.523134 -365.863124)
		(width 0.13208)
		(layer "F.Cu")
		(net "SMB_BIC_I2C6_MUX_THERMAL_R_SDA")
	)
	(segment
		(start 22.493732 -398.614392)
		(end 21.557488 -398.614392)
		(width 0.13208)
		(layer "F.Cu")
		(net "SMB_BIC_I2C6_MUX_THERMAL_R_SDA")
	)
	(segment
		(start 377.736608 -84.143088)
		(end 376.821446 -84.143088)
		(width 0.13208)
		(layer "F.Cu")
		(net "SMB_BIC_I2C6_MUX_THERMAL_R_SDA")
	)
	(segment
		(start 59.921648 -363.41812)
		(end 59.450478 -362.94695)
		(width 0.13208)
		(layer "F.Cu")
		(net "SMB_BIC_I2C6_MUX_THERMAL_R_SDA")
	)
	(segment
		(start 60.181744 -362.047028)
		(end 60.3504 -362.047028)
		(width 0.13208)
		(layer "F.Cu")
		(net "SMB_BIC_I2C6_MUX_THERMAL_R_SDA")
	)
	(segment
		(start 21.438108 -399.234152)
		(end 21.557488 -399.114772)
		(width 0.13208)
		(layer "F.Cu")
		(net "SMB_BIC_I2C6_MUX_THERMAL_R_SDA")
	)
	(segment
		(start 376.821446 -84.143088)
		(end 376.712734 -84.2518)
		(width 0.13208)
		(layer "F.Cu")
		(net "SMB_BIC_I2C6_MUX_THERMAL_R_SDA")
	)
	(segment
		(start 21.438108 -398.233392)
		(end 21.557488 -398.114012)
		(width 0.13208)
		(layer "F.Cu")
		(net "SMB_BIC_I2C6_MUX_THERMAL_R_SDA")
	)
	(segment
		(start 21.557488 -399.615152)
		(end 21.438108 -399.495772)
		(width 0.13208)
		(layer "F.Cu")
		(net "SMB_BIC_I2C6_MUX_THERMAL_R_SDA")
	)
	(segment
		(start 22.613112 -398.733772)
		(end 22.493732 -398.614392)
		(width 0.13208)
		(layer "F.Cu")
		(net "SMB_BIC_I2C6_MUX_THERMAL_R_SDA")
	)
	(segment
		(start 21.557488 -399.114772)
		(end 22.493732 -399.114772)
		(width 0.13208)
		(layer "F.Cu")
		(net "SMB_BIC_I2C6_MUX_THERMAL_R_SDA")
	)
	(segment
		(start 58.063384 -366.583214)
		(end 59.484514 -365.162084)
		(width 0.13208)
		(layer "F.Cu")
		(net "SMB_BIC_I2C6_MUX_THERMAL_R_SDA")
	)
	(segment
		(start 22.493732 -399.615152)
		(end 21.557488 -399.615152)
		(width 0.13208)
		(layer "F.Cu")
		(net "SMB_BIC_I2C6_MUX_THERMAL_R_SDA")
	)
	(segment
		(start 93.991176 -362.44403)
		(end 99.200716 -367.65357)
		(width 0.13208)
		(layer "F.Cu")
		(net "SMB_BIC_I2C6_MUX_THERMAL_R_SDA")
	)
	(segment
		(start 59.921648 -363.586776)
		(end 59.921648 -363.41812)
		(width 0.13208)
		(layer "F.Cu")
		(net "SMB_BIC_I2C6_MUX_THERMAL_R_SDA")
	)
	(segment
		(start 378.343922 -84.143088)
		(end 377.736608 -84.143088)
		(width 0.13208)
		(layer "F.Cu")
		(net "SMB_BIC_I2C6_MUX_THERMAL_R_SDA")
	)
	(segment
		(start 23.570946 -362.7882)
		(end 52.68722 -362.7882)
		(width 0.13208)
		(layer "F.Cu")
		(net "SMB_BIC_I2C6_MUX_THERMAL_R_SDA")
	)
	(segment
		(start 60.390278 -363.118146)
		(end 60.521596 -362.986828)
		(width 0.13208)
		(layer "F.Cu")
		(net "SMB_BIC_I2C6_MUX_THERMAL_R_SDA")
	)
	(segment
		(start 21.557488 -398.614392)
		(end 21.438108 -398.495012)
		(width 0.13208)
		(layer "F.Cu")
		(net "SMB_BIC_I2C6_MUX_THERMAL_R_SDA")
	)
	(segment
		(start 60.521596 -362.818172)
		(end 60.050426 -362.347002)
		(width 0.13208)
		(layer "F.Cu")
		(net "SMB_BIC_I2C6_MUX_THERMAL_R_SDA")
	)
	(segment
		(start 60.050426 -362.178346)
		(end 60.181744 -362.047028)
		(width 0.13208)
		(layer "F.Cu")
		(net "SMB_BIC_I2C6_MUX_THERMAL_R_SDA")
	)
	(segment
		(start 368.68354 -7.719822)
		(end 368.68354 -8.34263)
		(width 0.13208)
		(layer "F.Cu")
		(net "SMB_BIC_I2C6_MUX_THERMAL_R_SDA")
	)
	(segment
		(start 59.750452 -362.646976)
		(end 60.221622 -363.118146)
		(width 0.13208)
		(layer "F.Cu")
		(net "SMB_BIC_I2C6_MUX_THERMAL_R_SDA")
	)
	(segment
		(start 447.312288 -404.670768)
		(end 447.312288 -404.042626)
		(width 0.13208)
		(layer "F.Cu")
		(net "SMB_BIC_I2C6_MUX_THERMAL_R_SDA")
	)
	(segment
		(start 18.019014 -403.01926)
		(end 20.50796 -403.01926)
		(width 0.13208)
		(layer "F.Cu")
		(net "SMB_BIC_I2C6_MUX_THERMAL_R_SDA")
	)
	(segment
		(start 22.613112 -363.746034)
		(end 23.570946 -362.7882)
		(width 0.13208)
		(layer "F.Cu")
		(net "SMB_BIC_I2C6_MUX_THERMAL_R_SDA")
	)
	(segment
		(start 99.200716 -367.65357)
		(end 100.063554 -367.65357)
		(width 0.13208)
		(layer "F.Cu")
		(net "SMB_BIC_I2C6_MUX_THERMAL_R_SDA")
	)
	(segment
		(start 22.493732 -398.114012)
		(end 22.613112 -397.994632)
		(width 0.13208)
		(layer "F.Cu")
		(net "SMB_BIC_I2C6_MUX_THERMAL_R_SDA")
	)
	(segment
		(start 60.3504 -362.047028)
		(end 60.82157 -362.518198)
		(width 0.13208)
		(layer "F.Cu")
		(net "SMB_BIC_I2C6_MUX_THERMAL_R_SDA")
	)
	(segment
		(start 59.450478 -362.778294)
		(end 59.581796 -362.646976)
		(width 0.13208)
		(layer "F.Cu")
		(net "SMB_BIC_I2C6_MUX_THERMAL_R_SDA")
	)
	(segment
		(start 60.82157 -362.518198)
		(end 60.990226 -362.518198)
		(width 0.13208)
		(layer "F.Cu")
		(net "SMB_BIC_I2C6_MUX_THERMAL_R_SDA")
	)
	(segment
		(start 52.68722 -362.7882)
		(end 53.523134 -363.624114)
		(width 0.13208)
		(layer "F.Cu")
		(net "SMB_BIC_I2C6_MUX_THERMAL_R_SDA")
	)
	(segment
		(start 21.438108 -399.495772)
		(end 21.438108 -399.234152)
		(width 0.13208)
		(layer "F.Cu")
		(net "SMB_BIC_I2C6_MUX_THERMAL_R_SDA")
	)
	(segment
		(start 53.523134 -365.863124)
		(end 54.243224 -366.583214)
		(width 0.13208)
		(layer "F.Cu")
		(net "SMB_BIC_I2C6_MUX_THERMAL_R_SDA")
	)
	(segment
		(start 61.064394 -362.44403)
		(end 93.991176 -362.44403)
		(width 0.13208)
		(layer "F.Cu")
		(net "SMB_BIC_I2C6_MUX_THERMAL_R_SDA")
	)
	(segment
		(start 60.521596 -362.986828)
		(end 60.521596 -362.818172)
		(width 0.13208)
		(layer "F.Cu")
		(net "SMB_BIC_I2C6_MUX_THERMAL_R_SDA")
	)
	(via
		(at 368.990118 -8.649208)
		(size 0.508)
		(drill 0.254)
		(layers "F.Cu" "B.Cu")
		(net "SMB_BIC_I2C6_MUX_THERMAL_R_SDA")
	)
	(via
		(at 447.312288 -404.042626)
		(size 0.508)
		(drill 0.254)
		(layers "F.Cu" "B.Cu")
		(net "SMB_BIC_I2C6_MUX_THERMAL_R_SDA")
	)
	(via
		(at 73.608438 -9.33069)
		(size 0.508)
		(drill 0.254)
		(layers "F.Cu" "B.Cu")
		(net "SMB_BIC_I2C6_MUX_THERMAL_R_SDA")
	)
	(via
		(at 454.936352 -19.633184)
		(size 0.508)
		(drill 0.254)
		(layers "F.Cu" "B.Cu")
		(net "SMB_BIC_I2C6_MUX_THERMAL_R_SDA")
	)
	(via
		(at 100.063554 -367.65357)
		(size 0.508)
		(drill 0.254)
		(layers "F.Cu" "B.Cu")
		(net "SMB_BIC_I2C6_MUX_THERMAL_R_SDA")
	)
	(via
		(at 377.736608 -84.143088)
		(size 0.508)
		(drill 0.254)
		(layers "F.Cu" "B.Cu")
		(net "SMB_BIC_I2C6_MUX_THERMAL_R_SDA")
	)
	(via
		(at 435.75986 -84.256626)
		(size 0.508)
		(drill 0.254)
		(layers "F.Cu" "B.Cu")
		(net "SMB_BIC_I2C6_MUX_THERMAL_R_SDA")
	)
	(segment
		(start 447.312288 -395.085824)
		(end 447.312288 -404.042626)
		(width 0.13208)
		(layer "B.Cu")
		(net "SMB_BIC_I2C6_MUX_THERMAL_R_SDA")
	)
	(segment
		(start 113.30559 -360.195114)
		(end 188.927232 -360.195114)
		(width 0.13208)
		(layer "B.Cu")
		(net "SMB_BIC_I2C6_MUX_THERMAL_R_SDA")
	)
	(segment
		(start 360.38028 -360.748072)
		(end 360.38028 -382.792224)
		(width 0.13208)
		(layer "B.Cu")
		(net "SMB_BIC_I2C6_MUX_THERMAL_R_SDA")
	)
	(segment
		(start 222.490538 -340.836758)
		(end 224.077022 -342.423242)
		(width 0.13208)
		(layer "B.Cu")
		(net "SMB_BIC_I2C6_MUX_THERMAL_R_SDA")
	)
	(segment
		(start 261.10184 -343.541604)
		(end 266.469368 -348.909132)
		(width 0.13208)
		(layer "B.Cu")
		(net "SMB_BIC_I2C6_MUX_THERMAL_R_SDA")
	)
	(segment
		(start 253.144782 -343.541604)
		(end 261.10184 -343.541604)
		(width 0.13208)
		(layer "B.Cu")
		(net "SMB_BIC_I2C6_MUX_THERMAL_R_SDA")
	)
	(segment
		(start 366.919002 -389.86079)
		(end 401.544282 -389.86079)
		(width 0.13208)
		(layer "B.Cu")
		(net "SMB_BIC_I2C6_MUX_THERMAL_R_SDA")
	)
	(segment
		(start 270.518636 -358.867964)
		(end 358.500172 -358.867964)
		(width 0.13208)
		(layer "B.Cu")
		(net "SMB_BIC_I2C6_MUX_THERMAL_R_SDA")
	)
	(segment
		(start 360.38028 -382.792224)
		(end 364.545626 -386.95757)
		(width 0.13208)
		(layer "B.Cu")
		(net "SMB_BIC_I2C6_MUX_THERMAL_R_SDA")
	)
	(segment
		(start 358.500172 -358.867964)
		(end 360.38028 -360.748072)
		(width 0.13208)
		(layer "B.Cu")
		(net "SMB_BIC_I2C6_MUX_THERMAL_R_SDA")
	)
	(segment
		(start 404.87346 -393.189968)
		(end 445.416432 -393.189968)
		(width 0.13208)
		(layer "B.Cu")
		(net "SMB_BIC_I2C6_MUX_THERMAL_R_SDA")
	)
	(segment
		(start 109.252258 -364.248446)
		(end 113.30559 -360.195114)
		(width 0.13208)
		(layer "B.Cu")
		(net "SMB_BIC_I2C6_MUX_THERMAL_R_SDA")
	)
	(segment
		(start 208.285588 -340.836758)
		(end 222.490538 -340.836758)
		(width 0.13208)
		(layer "B.Cu")
		(net "SMB_BIC_I2C6_MUX_THERMAL_R_SDA")
	)
	(segment
		(start 224.077022 -342.423242)
		(end 252.02642 -342.423242)
		(width 0.13208)
		(layer "B.Cu")
		(net "SMB_BIC_I2C6_MUX_THERMAL_R_SDA")
	)
	(segment
		(start 188.927232 -360.195114)
		(end 208.285588 -340.836758)
		(width 0.13208)
		(layer "B.Cu")
		(net "SMB_BIC_I2C6_MUX_THERMAL_R_SDA")
	)
	(segment
		(start 364.545626 -387.487414)
		(end 366.919002 -389.86079)
		(width 0.13208)
		(layer "B.Cu")
		(net "SMB_BIC_I2C6_MUX_THERMAL_R_SDA")
	)
	(segment
		(start 266.469368 -348.909132)
		(end 266.469368 -354.818696)
		(width 0.13208)
		(layer "B.Cu")
		(net "SMB_BIC_I2C6_MUX_THERMAL_R_SDA")
	)
	(segment
		(start 100.063554 -367.65357)
		(end 100.063554 -367.173764)
		(width 0.13208)
		(layer "B.Cu")
		(net "SMB_BIC_I2C6_MUX_THERMAL_R_SDA")
	)
	(segment
		(start 100.063554 -367.173764)
		(end 102.988872 -364.248446)
		(width 0.13208)
		(layer "B.Cu")
		(net "SMB_BIC_I2C6_MUX_THERMAL_R_SDA")
	)
	(segment
		(start 364.545626 -386.95757)
		(end 364.545626 -387.487414)
		(width 0.13208)
		(layer "B.Cu")
		(net "SMB_BIC_I2C6_MUX_THERMAL_R_SDA")
	)
	(segment
		(start 102.988872 -364.248446)
		(end 109.252258 -364.248446)
		(width 0.13208)
		(layer "B.Cu")
		(net "SMB_BIC_I2C6_MUX_THERMAL_R_SDA")
	)
	(segment
		(start 445.416432 -393.189968)
		(end 447.312288 -395.085824)
		(width 0.13208)
		(layer "B.Cu")
		(net "SMB_BIC_I2C6_MUX_THERMAL_R_SDA")
	)
	(segment
		(start 266.469368 -354.818696)
		(end 270.518636 -358.867964)
		(width 0.13208)
		(layer "B.Cu")
		(net "SMB_BIC_I2C6_MUX_THERMAL_R_SDA")
	)
	(segment
		(start 252.02642 -342.423242)
		(end 253.144782 -343.541604)
		(width 0.13208)
		(layer "B.Cu")
		(net "SMB_BIC_I2C6_MUX_THERMAL_R_SDA")
	)
	(segment
		(start 401.544282 -389.86079)
		(end 404.87346 -393.189968)
		(width 0.13208)
		(layer "B.Cu")
		(net "SMB_BIC_I2C6_MUX_THERMAL_R_SDA")
	)
	(segment
		(start 435.933342 -131.285742)
		(end 440.85256 -136.20496)
		(width 0.15494)
		(layer "In5.Cu")
		(net "SMB_BIC_I2C6_MUX_THERMAL_R_SDA")
	)
	(segment
		(start 434.8734 -128.726692)
		(end 435.933342 -131.285742)
		(width 0.15494)
		(layer "In5.Cu")
		(net "SMB_BIC_I2C6_MUX_THERMAL_R_SDA")
	)
	(segment
		(start 448.98818 -404.042626)
		(end 447.312288 -404.042626)
		(width 0.15494)
		(layer "In5.Cu")
		(net "SMB_BIC_I2C6_MUX_THERMAL_R_SDA")
	)
	(segment
		(start 432.3334 -117.5004)
		(end 434.8734 -120.0404)
		(width 0.15494)
		(layer "In5.Cu")
		(net "SMB_BIC_I2C6_MUX_THERMAL_R_SDA")
	)
	(segment
		(start 450.1896 -265.4046)
		(end 450.1896 -274.2184)
		(width 0.15494)
		(layer "In5.Cu")
		(net "SMB_BIC_I2C6_MUX_THERMAL_R_SDA")
	)
	(segment
		(start 444.119 -281.7114)
		(end 444.119 -305.5366)
		(width 0.15494)
		(layer "In5.Cu")
		(net "SMB_BIC_I2C6_MUX_THERMAL_R_SDA")
	)
	(segment
		(start 440.85256 -238.82096)
		(end 449.4276 -247.396)
		(width 0.15494)
		(layer "In5.Cu")
		(net "SMB_BIC_I2C6_MUX_THERMAL_R_SDA")
	)
	(segment
		(start 450.1896 -274.2184)
		(end 448.5386 -275.8694)
		(width 0.15494)
		(layer "In5.Cu")
		(net "SMB_BIC_I2C6_MUX_THERMAL_R_SDA")
	)
	(segment
		(start 434.36794 -85.648546)
		(end 434.36794 -94.15526)
		(width 0.15494)
		(layer "In5.Cu")
		(net "SMB_BIC_I2C6_MUX_THERMAL_R_SDA")
	)
	(segment
		(start 449.4276 -255.0668)
		(end 448.2592 -256.2352)
		(width 0.15494)
		(layer "In5.Cu")
		(net "SMB_BIC_I2C6_MUX_THERMAL_R_SDA")
	)
	(segment
		(start 449.453 -316.7126)
		(end 449.453 -403.577806)
		(width 0.15494)
		(layer "In5.Cu")
		(net "SMB_BIC_I2C6_MUX_THERMAL_R_SDA")
	)
	(segment
		(start 443.865 -311.1246)
		(end 449.453 -316.7126)
		(width 0.15494)
		(layer "In5.Cu")
		(net "SMB_BIC_I2C6_MUX_THERMAL_R_SDA")
	)
	(segment
		(start 428.498 -100.0252)
		(end 428.498 -108.8898)
		(width 0.15494)
		(layer "In5.Cu")
		(net "SMB_BIC_I2C6_MUX_THERMAL_R_SDA")
	)
	(segment
		(start 432.3334 -112.7252)
		(end 432.3334 -117.5004)
		(width 0.15494)
		(layer "In5.Cu")
		(net "SMB_BIC_I2C6_MUX_THERMAL_R_SDA")
	)
	(segment
		(start 448.2592 -263.4742)
		(end 450.1896 -265.4046)
		(width 0.15494)
		(layer "In5.Cu")
		(net "SMB_BIC_I2C6_MUX_THERMAL_R_SDA")
	)
	(segment
		(start 444.119 -305.5366)
		(end 443.865 -305.7906)
		(width 0.15494)
		(layer "In5.Cu")
		(net "SMB_BIC_I2C6_MUX_THERMAL_R_SDA")
	)
	(segment
		(start 449.4276 -247.396)
		(end 449.4276 -255.0668)
		(width 0.15494)
		(layer "In5.Cu")
		(net "SMB_BIC_I2C6_MUX_THERMAL_R_SDA")
	)
	(segment
		(start 434.36794 -94.15526)
		(end 428.498 -100.0252)
		(width 0.15494)
		(layer "In5.Cu")
		(net "SMB_BIC_I2C6_MUX_THERMAL_R_SDA")
	)
	(segment
		(start 434.8734 -120.0404)
		(end 434.8734 -128.726692)
		(width 0.15494)
		(layer "In5.Cu")
		(net "SMB_BIC_I2C6_MUX_THERMAL_R_SDA")
	)
	(segment
		(start 428.498 -108.8898)
		(end 432.3334 -112.7252)
		(width 0.15494)
		(layer "In5.Cu")
		(net "SMB_BIC_I2C6_MUX_THERMAL_R_SDA")
	)
	(segment
		(start 435.75986 -84.256626)
		(end 434.36794 -85.648546)
		(width 0.15494)
		(layer "In5.Cu")
		(net "SMB_BIC_I2C6_MUX_THERMAL_R_SDA")
	)
	(segment
		(start 449.453 -403.577806)
		(end 448.98818 -404.042626)
		(width 0.15494)
		(layer "In5.Cu")
		(net "SMB_BIC_I2C6_MUX_THERMAL_R_SDA")
	)
	(segment
		(start 448.2592 -256.2352)
		(end 448.2592 -263.4742)
		(width 0.15494)
		(layer "In5.Cu")
		(net "SMB_BIC_I2C6_MUX_THERMAL_R_SDA")
	)
	(segment
		(start 448.5386 -275.8694)
		(end 448.5386 -277.2918)
		(width 0.15494)
		(layer "In5.Cu")
		(net "SMB_BIC_I2C6_MUX_THERMAL_R_SDA")
	)
	(segment
		(start 443.865 -305.7906)
		(end 443.865 -311.1246)
		(width 0.15494)
		(layer "In5.Cu")
		(net "SMB_BIC_I2C6_MUX_THERMAL_R_SDA")
	)
	(segment
		(start 440.85256 -136.20496)
		(end 440.85256 -238.82096)
		(width 0.15494)
		(layer "In5.Cu")
		(net "SMB_BIC_I2C6_MUX_THERMAL_R_SDA")
	)
	(segment
		(start 448.5386 -277.2918)
		(end 444.119 -281.7114)
		(width 0.15494)
		(layer "In5.Cu")
		(net "SMB_BIC_I2C6_MUX_THERMAL_R_SDA")
	)
	(segment
		(start 453.37222 -29.758894)
		(end 458.986636 -35.37331)
		(width 0.15494)
		(layer "In13.Cu")
		(net "SMB_BIC_I2C6_MUX_THERMAL_R_SDA")
	)
	(segment
		(start 392.395202 -81.8896)
		(end 391.74928 -82.535522)
		(width 0.15494)
		(layer "In13.Cu")
		(net "SMB_BIC_I2C6_MUX_THERMAL_R_SDA")
	)
	(segment
		(start 391.74928 -82.535522)
		(end 391.013442 -82.535522)
		(width 0.15494)
		(layer "In13.Cu")
		(net "SMB_BIC_I2C6_MUX_THERMAL_R_SDA")
	)
	(segment
		(start 423.78122 -81.485486)
		(end 423.377106 -81.8896)
		(width 0.15494)
		(layer "In13.Cu")
		(net "SMB_BIC_I2C6_MUX_THERMAL_R_SDA")
	)
	(segment
		(start 384.194558 -82.164682)
		(end 383.058416 -83.300824)
		(width 0.15494)
		(layer "In13.Cu")
		(net "SMB_BIC_I2C6_MUX_THERMAL_R_SDA")
	)
	(segment
		(start 455.422 -24.272748)
		(end 453.37222 -26.322528)
		(width 0.15494)
		(layer "In13.Cu")
		(net "SMB_BIC_I2C6_MUX_THERMAL_R_SDA")
	)
	(segment
		(start 453.37222 -26.322528)
		(end 453.37222 -29.758894)
		(width 0.15494)
		(layer "In13.Cu")
		(net "SMB_BIC_I2C6_MUX_THERMAL_R_SDA")
	)
	(segment
		(start 455.422 -20.118832)
		(end 455.422 -24.272748)
		(width 0.15494)
		(layer "In13.Cu")
		(net "SMB_BIC_I2C6_MUX_THERMAL_R_SDA")
	)
	(segment
		(start 458.986636 -35.37331)
		(end 458.986636 -35.402012)
		(width 0.15494)
		(layer "In13.Cu")
		(net "SMB_BIC_I2C6_MUX_THERMAL_R_SDA")
	)
	(segment
		(start 391.013442 -82.535522)
		(end 390.642602 -82.164682)
		(width 0.15494)
		(layer "In13.Cu")
		(net "SMB_BIC_I2C6_MUX_THERMAL_R_SDA")
	)
	(segment
		(start 383.058416 -83.300824)
		(end 378.578872 -83.300824)
		(width 0.15494)
		(layer "In13.Cu")
		(net "SMB_BIC_I2C6_MUX_THERMAL_R_SDA")
	)
	(segment
		(start 423.809922 -81.485486)
		(end 423.78122 -81.485486)
		(width 0.15494)
		(layer "In13.Cu")
		(net "SMB_BIC_I2C6_MUX_THERMAL_R_SDA")
	)
	(segment
		(start 378.578872 -83.300824)
		(end 377.736608 -84.143088)
		(width 0.15494)
		(layer "In13.Cu")
		(net "SMB_BIC_I2C6_MUX_THERMAL_R_SDA")
	)
	(segment
		(start 458.986636 -35.402012)
		(end 458.997558 -35.412934)
		(width 0.15494)
		(layer "In13.Cu")
		(net "SMB_BIC_I2C6_MUX_THERMAL_R_SDA")
	)
	(segment
		(start 458.986382 -69.484494)
		(end 452.767192 -75.703684)
		(width 0.15494)
		(layer "In13.Cu")
		(net "SMB_BIC_I2C6_MUX_THERMAL_R_SDA")
	)
	(segment
		(start 458.986382 -69.455792)
		(end 458.986382 -69.484494)
		(width 0.15494)
		(layer "In13.Cu")
		(net "SMB_BIC_I2C6_MUX_THERMAL_R_SDA")
	)
	(segment
		(start 452.767192 -75.703684)
		(end 429.591724 -75.703684)
		(width 0.15494)
		(layer "In13.Cu")
		(net "SMB_BIC_I2C6_MUX_THERMAL_R_SDA")
	)
	(segment
		(start 458.997558 -35.412934)
		(end 458.997558 -69.444616)
		(width 0.15494)
		(layer "In13.Cu")
		(net "SMB_BIC_I2C6_MUX_THERMAL_R_SDA")
	)
	(segment
		(start 423.377106 -81.8896)
		(end 392.395202 -81.8896)
		(width 0.15494)
		(layer "In13.Cu")
		(net "SMB_BIC_I2C6_MUX_THERMAL_R_SDA")
	)
	(segment
		(start 429.591724 -75.703684)
		(end 423.809922 -81.485486)
		(width 0.15494)
		(layer "In13.Cu")
		(net "SMB_BIC_I2C6_MUX_THERMAL_R_SDA")
	)
	(segment
		(start 454.936352 -19.633184)
		(end 455.422 -20.118832)
		(width 0.15494)
		(layer "In13.Cu")
		(net "SMB_BIC_I2C6_MUX_THERMAL_R_SDA")
	)
	(segment
		(start 458.997558 -69.444616)
		(end 458.986382 -69.455792)
		(width 0.15494)
		(layer "In13.Cu")
		(net "SMB_BIC_I2C6_MUX_THERMAL_R_SDA")
	)
	(segment
		(start 390.642602 -82.164682)
		(end 384.194558 -82.164682)
		(width 0.15494)
		(layer "In13.Cu")
		(net "SMB_BIC_I2C6_MUX_THERMAL_R_SDA")
	)
	(segment
		(start 154.416506 -18.4658)
		(end 139.827 -18.4658)
		(width 0.15494)
		(layer "In15.Cu")
		(net "SMB_BIC_I2C6_MUX_THERMAL_R_SDA")
	)
	(segment
		(start 326.314054 -18.5674)
		(end 325.951342 -18.930112)
		(width 0.15494)
		(layer "In15.Cu")
		(net "SMB_BIC_I2C6_MUX_THERMAL_R_SDA")
	)
	(segment
		(start 412.693612 -18.462498)
		(end 398.149572 -18.462498)
		(width 0.15494)
		(layer "In15.Cu")
		(net "SMB_BIC_I2C6_MUX_THERMAL_R_SDA")
	)
	(segment
		(start 248.386854 -18.4912)
		(end 247.959372 -18.918682)
		(width 0.15494)
		(layer "In15.Cu")
		(net "SMB_BIC_I2C6_MUX_THERMAL_R_SDA")
	)
	(segment
		(start 380.136908 -83.09737)
		(end 380.278894 -83.239356)
		(width 0.15494)
		(layer "In15.Cu")
		(net "SMB_BIC_I2C6_MUX_THERMAL_R_SDA")
	)
	(segment
		(start 214.737696 -18.830544)
		(end 211.168234 -18.830544)
		(width 0.15494)
		(layer "In15.Cu")
		(net "SMB_BIC_I2C6_MUX_THERMAL_R_SDA")
	)
	(segment
		(start 391.755376 -84.3788)
		(end 393.435586 -84.3788)
		(width 0.15494)
		(layer "In15.Cu")
		(net "SMB_BIC_I2C6_MUX_THERMAL_R_SDA")
	)
	(segment
		(start 90.14079 -17.950434)
		(end 83.123024 -17.950434)
		(width 0.15494)
		(layer "In15.Cu")
		(net "SMB_BIC_I2C6_MUX_THERMAL_R_SDA")
	)
	(segment
		(start 413.070802 -18.839688)
		(end 412.693612 -18.462498)
		(width 0.15494)
		(layer "In15.Cu")
		(net "SMB_BIC_I2C6_MUX_THERMAL_R_SDA")
	)
	(segment
		(start 398.149572 -18.462498)
		(end 397.487902 -17.800828)
		(width 0.15494)
		(layer "In15.Cu")
		(net "SMB_BIC_I2C6_MUX_THERMAL_R_SDA")
	)
	(segment
		(start 347.788484 -24.240998)
		(end 332.694534 -24.240998)
		(width 0.15494)
		(layer "In15.Cu")
		(net "SMB_BIC_I2C6_MUX_THERMAL_R_SDA")
	)
	(segment
		(start 279.043384 -18.822416)
		(end 275.349208 -18.822416)
		(width 0.15494)
		(layer "In15.Cu")
		(net "SMB_BIC_I2C6_MUX_THERMAL_R_SDA")
	)
	(segment
		(start 386.470398 -18.550382)
		(end 385.234434 -18.550382)
		(width 0.15494)
		(layer "In15.Cu")
		(net "SMB_BIC_I2C6_MUX_THERMAL_R_SDA")
	)
	(segment
		(start 255.4986 -17.9578)
		(end 253.885446 -17.9578)
		(width 0.15494)
		(layer "In15.Cu")
		(net "SMB_BIC_I2C6_MUX_THERMAL_R_SDA")
	)
	(segment
		(start 380.278894 -83.239356)
		(end 390.615932 -83.239356)
		(width 0.15494)
		(layer "In15.Cu")
		(net "SMB_BIC_I2C6_MUX_THERMAL_R_SDA")
	)
	(segment
		(start 416.04565 -18.839688)
		(end 413.070802 -18.839688)
		(width 0.15494)
		(layer "In15.Cu")
		(net "SMB_BIC_I2C6_MUX_THERMAL_R_SDA")
	)
	(segment
		(start 133.318504 -18.918174)
		(end 132.898642 -18.498312)
		(width 0.15494)
		(layer "In15.Cu")
		(net "SMB_BIC_I2C6_MUX_THERMAL_R_SDA")
	)
	(segment
		(start 434.962808 -83.459574)
		(end 435.75986 -84.256626)
		(width 0.15494)
		(layer "In15.Cu")
		(net "SMB_BIC_I2C6_MUX_THERMAL_R_SDA")
	)
	(segment
		(start 422.913302 -81.826608)
		(end 428.030894 -81.826608)
		(width 0.15494)
		(layer "In15.Cu")
		(net "SMB_BIC_I2C6_MUX_THERMAL_R_SDA")
	)
	(segment
		(start 245.050056 -18.44802)
		(end 235.378498 -18.44802)
		(width 0.15494)
		(layer "In15.Cu")
		(net "SMB_BIC_I2C6_MUX_THERMAL_R_SDA")
	)
	(segment
		(start 365.06277 -18.4912)
		(end 364.560104 -18.4912)
		(width 0.15494)
		(layer "In15.Cu")
		(net "SMB_BIC_I2C6_MUX_THERMAL_R_SDA")
	)
	(segment
		(start 119.6721 -18.34642)
		(end 113.742978 -24.275542)
		(width 0.15494)
		(layer "In15.Cu")
		(net "SMB_BIC_I2C6_MUX_THERMAL_R_SDA")
	)
	(segment
		(start 158.115 -18.4658)
		(end 157.7086 -18.8722)
		(width 0.15494)
		(layer "In15.Cu")
		(net "SMB_BIC_I2C6_MUX_THERMAL_R_SDA")
	)
	(segment
		(start 113.742978 -24.275542)
		(end 100.653088 -24.275542)
		(width 0.15494)
		(layer "In15.Cu")
		(net "SMB_BIC_I2C6_MUX_THERMAL_R_SDA")
	)
	(segment
		(start 275.349208 -18.822416)
		(end 275.017992 -18.4912)
		(width 0.15494)
		(layer "In15.Cu")
		(net "SMB_BIC_I2C6_MUX_THERMAL_R_SDA")
	)
	(segment
		(start 128.284986 -18.34642)
		(end 119.6721 -18.34642)
		(width 0.15494)
		(layer "In15.Cu")
		(net "SMB_BIC_I2C6_MUX_THERMAL_R_SDA")
	)
	(segment
		(start 307.2892 -17.9578)
		(end 306.2732 -17.9578)
		(width 0.15494)
		(layer "In15.Cu")
		(net "SMB_BIC_I2C6_MUX_THERMAL_R_SDA")
	)
	(segment
		(start 139.319 -17.9578)
		(end 137.757408 -17.9578)
		(width 0.15494)
		(layer "In15.Cu")
		(net "SMB_BIC_I2C6_MUX_THERMAL_R_SDA")
	)
	(segment
		(start 378.64034 -83.239356)
		(end 379.509782 -83.239356)
		(width 0.15494)
		(layer "In15.Cu")
		(net "SMB_BIC_I2C6_MUX_THERMAL_R_SDA")
	)
	(segment
		(start 100.653088 -24.275542)
		(end 94.850458 -18.472912)
		(width 0.15494)
		(layer "In15.Cu")
		(net "SMB_BIC_I2C6_MUX_THERMAL_R_SDA")
	)
	(segment
		(start 418.354256 -81.700116)
		(end 419.015418 -82.361278)
		(width 0.15494)
		(layer "In15.Cu")
		(net "SMB_BIC_I2C6_MUX_THERMAL_R_SDA")
	)
	(segment
		(start 322.762372 -18.4404)
		(end 307.7718 -18.4404)
		(width 0.15494)
		(layer "In15.Cu")
		(net "SMB_BIC_I2C6_MUX_THERMAL_R_SDA")
	)
	(segment
		(start 393.882626 -84.82584)
		(end 395.79423 -84.82584)
		(width 0.15494)
		(layer "In15.Cu")
		(net "SMB_BIC_I2C6_MUX_THERMAL_R_SDA")
	)
	(segment
		(start 423.56278 -18.52422)
		(end 423.15892 -18.92808)
		(width 0.15494)
		(layer "In15.Cu")
		(net "SMB_BIC_I2C6_MUX_THERMAL_R_SDA")
	)
	(segment
		(start 419.015418 -82.361278)
		(end 422.378632 -82.361278)
		(width 0.15494)
		(layer "In15.Cu")
		(net "SMB_BIC_I2C6_MUX_THERMAL_R_SDA")
	)
	(segment
		(start 184.777126 -18.422112)
		(end 184.192164 -18.422112)
		(width 0.15494)
		(layer "In15.Cu")
		(net "SMB_BIC_I2C6_MUX_THERMAL_R_SDA")
	)
	(segment
		(start 128.91516 -18.976594)
		(end 128.284986 -18.34642)
		(width 0.15494)
		(layer "In15.Cu")
		(net "SMB_BIC_I2C6_MUX_THERMAL_R_SDA")
	)
	(segment
		(start 393.435586 -84.3788)
		(end 393.882626 -84.82584)
		(width 0.15494)
		(layer "In15.Cu")
		(net "SMB_BIC_I2C6_MUX_THERMAL_R_SDA")
	)
	(segment
		(start 273.770344 -18.96491)
		(end 271.245584 -18.96491)
		(width 0.15494)
		(layer "In15.Cu")
		(net "SMB_BIC_I2C6_MUX_THERMAL_R_SDA")
	)
	(segment
		(start 390.615932 -83.239356)
		(end 391.755376 -84.3788)
		(width 0.15494)
		(layer "In15.Cu")
		(net "SMB_BIC_I2C6_MUX_THERMAL_R_SDA")
	)
	(segment
		(start 390.515602 -18.562828)
		(end 386.482844 -18.562828)
		(width 0.15494)
		(layer "In15.Cu")
		(net "SMB_BIC_I2C6_MUX_THERMAL_R_SDA")
	)
	(segment
		(start 91.132152 -18.941796)
		(end 90.14079 -17.950434)
		(width 0.15494)
		(layer "In15.Cu")
		(net "SMB_BIC_I2C6_MUX_THERMAL_R_SDA")
	)
	(segment
		(start 305.501294 -18.729706)
		(end 301.211234 -18.729706)
		(width 0.15494)
		(layer "In15.Cu")
		(net "SMB_BIC_I2C6_MUX_THERMAL_R_SDA")
	)
	(segment
		(start 396.345156 -84.274914)
		(end 397.601694 -84.274914)
		(width 0.15494)
		(layer "In15.Cu")
		(net "SMB_BIC_I2C6_MUX_THERMAL_R_SDA")
	)
	(segment
		(start 300.375574 -18.4658)
		(end 299.911008 -18.930366)
		(width 0.15494)
		(layer "In15.Cu")
		(net "SMB_BIC_I2C6_MUX_THERMAL_R_SDA")
	)
	(segment
		(start 448.757548 -18.92808)
		(end 448.392296 -18.562828)
		(width 0.15494)
		(layer "In15.Cu")
		(net "SMB_BIC_I2C6_MUX_THERMAL_R_SDA")
	)
	(segment
		(start 165.567106 -17.942306)
		(end 163.681918 -17.942306)
		(width 0.15494)
		(layer "In15.Cu")
		(net "SMB_BIC_I2C6_MUX_THERMAL_R_SDA")
	)
	(segment
		(start 307.7718 -18.4404)
		(end 307.2892 -17.9578)
		(width 0.15494)
		(layer "In15.Cu")
		(net "SMB_BIC_I2C6_MUX_THERMAL_R_SDA")
	)
	(segment
		(start 271.245584 -18.96491)
		(end 270.695674 -18.415)
		(width 0.15494)
		(layer "In15.Cu")
		(net "SMB_BIC_I2C6_MUX_THERMAL_R_SDA")
	)
	(segment
		(start 210.343496 -18.4912)
		(end 209.930492 -18.904204)
		(width 0.15494)
		(layer "In15.Cu")
		(net "SMB_BIC_I2C6_MUX_THERMAL_R_SDA")
	)
	(segment
		(start 281.432 -17.9324)
		(end 279.9334 -17.9324)
		(width 0.15494)
		(layer "In15.Cu")
		(net "SMB_BIC_I2C6_MUX_THERMAL_R_SDA")
	)
	(segment
		(start 247.959372 -18.918682)
		(end 245.520718 -18.918682)
		(width 0.15494)
		(layer "In15.Cu")
		(net "SMB_BIC_I2C6_MUX_THERMAL_R_SDA")
	)
	(segment
		(start 386.482844 -18.562828)
		(end 386.470398 -18.550382)
		(width 0.15494)
		(layer "In15.Cu")
		(net "SMB_BIC_I2C6_MUX_THERMAL_R_SDA")
	)
	(segment
		(start 368.977926 -18.835878)
		(end 365.407448 -18.835878)
		(width 0.15494)
		(layer "In15.Cu")
		(net "SMB_BIC_I2C6_MUX_THERMAL_R_SDA")
	)
	(segment
		(start 379.651768 -82.641186)
		(end 379.793754 -82.4992)
		(width 0.15494)
		(layer "In15.Cu")
		(net "SMB_BIC_I2C6_MUX_THERMAL_R_SDA")
	)
	(segment
		(start 281.94 -18.4404)
		(end 281.432 -17.9324)
		(width 0.15494)
		(layer "In15.Cu")
		(net "SMB_BIC_I2C6_MUX_THERMAL_R_SDA")
	)
	(segment
		(start 379.994922 -82.4992)
		(end 380.136908 -82.641186)
		(width 0.15494)
		(layer "In15.Cu")
		(net "SMB_BIC_I2C6_MUX_THERMAL_R_SDA")
	)
	(segment
		(start 400.176492 -81.700116)
		(end 418.354256 -81.700116)
		(width 0.15494)
		(layer "In15.Cu")
		(net "SMB_BIC_I2C6_MUX_THERMAL_R_SDA")
	)
	(segment
		(start 206.954374 -18.47342)
		(end 191.98082 -18.47342)
		(width 0.15494)
		(layer "In15.Cu")
		(net "SMB_BIC_I2C6_MUX_THERMAL_R_SDA")
	)
	(segment
		(start 154.822906 -18.8722)
		(end 154.416506 -18.4658)
		(width 0.15494)
		(layer "In15.Cu")
		(net "SMB_BIC_I2C6_MUX_THERMAL_R_SDA")
	)
	(segment
		(start 211.168234 -18.830544)
		(end 210.82889 -18.4912)
		(width 0.15494)
		(layer "In15.Cu")
		(net "SMB_BIC_I2C6_MUX_THERMAL_R_SDA")
	)
	(segment
		(start 235.378498 -18.44802)
		(end 234.178602 -17.248124)
		(width 0.15494)
		(layer "In15.Cu")
		(net "SMB_BIC_I2C6_MUX_THERMAL_R_SDA")
	)
	(segment
		(start 428.030894 -81.826608)
		(end 429.66386 -83.459574)
		(width 0.15494)
		(layer "In15.Cu")
		(net "SMB_BIC_I2C6_MUX_THERMAL_R_SDA")
	)
	(segment
		(start 163.681918 -17.942306)
		(end 162.809936 -18.814288)
		(width 0.15494)
		(layer "In15.Cu")
		(net "SMB_BIC_I2C6_MUX_THERMAL_R_SDA")
	)
	(segment
		(start 375.33326 -8.649208)
		(end 368.990118 -8.649208)
		(width 0.15494)
		(layer "In15.Cu")
		(net "SMB_BIC_I2C6_MUX_THERMAL_R_SDA")
	)
	(segment
		(start 207.385158 -18.904204)
		(end 206.954374 -18.47342)
		(width 0.15494)
		(layer "In15.Cu")
		(net "SMB_BIC_I2C6_MUX_THERMAL_R_SDA")
	)
	(segment
		(start 306.2732 -17.9578)
		(end 305.501294 -18.729706)
		(width 0.15494)
		(layer "In15.Cu")
		(net "SMB_BIC_I2C6_MUX_THERMAL_R_SDA")
	)
	(segment
		(start 297.268646 -18.930366)
		(end 296.77868 -18.4404)
		(width 0.15494)
		(layer "In15.Cu")
		(net "SMB_BIC_I2C6_MUX_THERMAL_R_SDA")
	)
	(segment
		(start 299.911008 -18.930366)
		(end 297.268646 -18.930366)
		(width 0.15494)
		(layer "In15.Cu")
		(net "SMB_BIC_I2C6_MUX_THERMAL_R_SDA")
	)
	(segment
		(start 423.15892 -18.92808)
		(end 422.7576 -18.92808)
		(width 0.15494)
		(layer "In15.Cu")
		(net "SMB_BIC_I2C6_MUX_THERMAL_R_SDA")
	)
	(segment
		(start 245.520718 -18.918682)
		(end 245.050056 -18.44802)
		(width 0.15494)
		(layer "In15.Cu")
		(net "SMB_BIC_I2C6_MUX_THERMAL_R_SDA")
	)
	(segment
		(start 353.657662 -18.37182)
		(end 347.788484 -24.240998)
		(width 0.15494)
		(layer "In15.Cu")
		(net "SMB_BIC_I2C6_MUX_THERMAL_R_SDA")
	)
	(segment
		(start 296.77868 -18.4404)
		(end 281.94 -18.4404)
		(width 0.15494)
		(layer "In15.Cu")
		(net "SMB_BIC_I2C6_MUX_THERMAL_R_SDA")
	)
	(segment
		(start 215.63584 -17.9324)
		(end 214.737696 -18.830544)
		(width 0.15494)
		(layer "In15.Cu")
		(net "SMB_BIC_I2C6_MUX_THERMAL_R_SDA")
	)
	(segment
		(start 364.155736 -18.895568)
		(end 361.126786 -18.895568)
		(width 0.15494)
		(layer "In15.Cu")
		(net "SMB_BIC_I2C6_MUX_THERMAL_R_SDA")
	)
	(segment
		(start 191.4652 -17.9578)
		(end 189.655704 -17.9578)
		(width 0.15494)
		(layer "In15.Cu")
		(net "SMB_BIC_I2C6_MUX_THERMAL_R_SDA")
	)
	(segment
		(start 454.936352 -19.633184)
		(end 454.231248 -18.92808)
		(width 0.15494)
		(layer "In15.Cu")
		(net "SMB_BIC_I2C6_MUX_THERMAL_R_SDA")
	)
	(segment
		(start 370.70919 -17.104614)
		(end 368.977926 -18.835878)
		(width 0.15494)
		(layer "In15.Cu")
		(net "SMB_BIC_I2C6_MUX_THERMAL_R_SDA")
	)
	(segment
		(start 395.301978 -18.550382)
		(end 390.528048 -18.550382)
		(width 0.15494)
		(layer "In15.Cu")
		(net "SMB_BIC_I2C6_MUX_THERMAL_R_SDA")
	)
	(segment
		(start 368.990118 -8.649208)
		(end 370.70919 -10.36828)
		(width 0.15494)
		(layer "In15.Cu")
		(net "SMB_BIC_I2C6_MUX_THERMAL_R_SDA")
	)
	(segment
		(start 377.736608 -84.143088)
		(end 378.64034 -83.239356)
		(width 0.15494)
		(layer "In15.Cu")
		(net "SMB_BIC_I2C6_MUX_THERMAL_R_SDA")
	)
	(segment
		(start 139.827 -18.4658)
		(end 139.319 -17.9578)
		(width 0.15494)
		(layer "In15.Cu")
		(net "SMB_BIC_I2C6_MUX_THERMAL_R_SDA")
	)
	(segment
		(start 379.509782 -83.239356)
		(end 379.651768 -83.09737)
		(width 0.15494)
		(layer "In15.Cu")
		(net "SMB_BIC_I2C6_MUX_THERMAL_R_SDA")
	)
	(segment
		(start 396.051532 -17.800828)
		(end 395.301978 -18.550382)
		(width 0.15494)
		(layer "In15.Cu")
		(net "SMB_BIC_I2C6_MUX_THERMAL_R_SDA")
	)
	(segment
		(start 430.882806 -18.52422)
		(end 423.56278 -18.52422)
		(width 0.15494)
		(layer "In15.Cu")
		(net "SMB_BIC_I2C6_MUX_THERMAL_R_SDA")
	)
	(segment
		(start 158.745174 -18.4658)
		(end 158.115 -18.4658)
		(width 0.15494)
		(layer "In15.Cu")
		(net "SMB_BIC_I2C6_MUX_THERMAL_R_SDA")
	)
	(segment
		(start 422.378632 -82.361278)
		(end 422.913302 -81.826608)
		(width 0.15494)
		(layer "In15.Cu")
		(net "SMB_BIC_I2C6_MUX_THERMAL_R_SDA")
	)
	(segment
		(start 385.234434 -18.550382)
		(end 375.33326 -8.649208)
		(width 0.15494)
		(layer "In15.Cu")
		(net "SMB_BIC_I2C6_MUX_THERMAL_R_SDA")
	)
	(segment
		(start 180.372004 -18.496026)
		(end 166.120826 -18.496026)
		(width 0.15494)
		(layer "In15.Cu")
		(net "SMB_BIC_I2C6_MUX_THERMAL_R_SDA")
	)
	(segment
		(start 275.017992 -18.4912)
		(end 274.244054 -18.4912)
		(width 0.15494)
		(layer "In15.Cu")
		(net "SMB_BIC_I2C6_MUX_THERMAL_R_SDA")
	)
	(segment
		(start 132.210048 -18.498312)
		(end 131.731766 -18.976594)
		(width 0.15494)
		(layer "In15.Cu")
		(net "SMB_BIC_I2C6_MUX_THERMAL_R_SDA")
	)
	(segment
		(start 395.79423 -84.82584)
		(end 396.345156 -84.274914)
		(width 0.15494)
		(layer "In15.Cu")
		(net "SMB_BIC_I2C6_MUX_THERMAL_R_SDA")
	)
	(segment
		(start 270.695674 -18.415)
		(end 255.9558 -18.415)
		(width 0.15494)
		(layer "In15.Cu")
		(net "SMB_BIC_I2C6_MUX_THERMAL_R_SDA")
	)
	(segment
		(start 234.178602 -17.248124)
		(end 220.114622 -17.248124)
		(width 0.15494)
		(layer "In15.Cu")
		(net "SMB_BIC_I2C6_MUX_THERMAL_R_SDA")
	)
	(segment
		(start 397.487902 -17.800828)
		(end 396.051532 -17.800828)
		(width 0.15494)
		(layer "In15.Cu")
		(net "SMB_BIC_I2C6_MUX_THERMAL_R_SDA")
	)
	(segment
		(start 397.601694 -84.274914)
		(end 400.176492 -81.700116)
		(width 0.15494)
		(layer "In15.Cu")
		(net "SMB_BIC_I2C6_MUX_THERMAL_R_SDA")
	)
	(segment
		(start 132.898642 -18.498312)
		(end 132.210048 -18.498312)
		(width 0.15494)
		(layer "In15.Cu")
		(net "SMB_BIC_I2C6_MUX_THERMAL_R_SDA")
	)
	(segment
		(start 209.930492 -18.904204)
		(end 207.385158 -18.904204)
		(width 0.15494)
		(layer "In15.Cu")
		(net "SMB_BIC_I2C6_MUX_THERMAL_R_SDA")
	)
	(segment
		(start 252.897132 -18.946114)
		(end 249.316494 -18.946114)
		(width 0.15494)
		(layer "In15.Cu")
		(net "SMB_BIC_I2C6_MUX_THERMAL_R_SDA")
	)
	(segment
		(start 361.126786 -18.895568)
		(end 360.603038 -18.37182)
		(width 0.15494)
		(layer "In15.Cu")
		(net "SMB_BIC_I2C6_MUX_THERMAL_R_SDA")
	)
	(segment
		(start 279.9334 -17.9324)
		(end 279.043384 -18.822416)
		(width 0.15494)
		(layer "In15.Cu")
		(net "SMB_BIC_I2C6_MUX_THERMAL_R_SDA")
	)
	(segment
		(start 166.120826 -18.496026)
		(end 165.567106 -17.942306)
		(width 0.15494)
		(layer "In15.Cu")
		(net "SMB_BIC_I2C6_MUX_THERMAL_R_SDA")
	)
	(segment
		(start 94.850458 -18.472912)
		(end 94.050866 -18.472912)
		(width 0.15494)
		(layer "In15.Cu")
		(net "SMB_BIC_I2C6_MUX_THERMAL_R_SDA")
	)
	(segment
		(start 157.7086 -18.8722)
		(end 154.822906 -18.8722)
		(width 0.15494)
		(layer "In15.Cu")
		(net "SMB_BIC_I2C6_MUX_THERMAL_R_SDA")
	)
	(segment
		(start 365.407448 -18.835878)
		(end 365.06277 -18.4912)
		(width 0.15494)
		(layer "In15.Cu")
		(net "SMB_BIC_I2C6_MUX_THERMAL_R_SDA")
	)
	(segment
		(start 210.82889 -18.4912)
		(end 210.343496 -18.4912)
		(width 0.15494)
		(layer "In15.Cu")
		(net "SMB_BIC_I2C6_MUX_THERMAL_R_SDA")
	)
	(segment
		(start 219.430346 -17.9324)
		(end 215.63584 -17.9324)
		(width 0.15494)
		(layer "In15.Cu")
		(net "SMB_BIC_I2C6_MUX_THERMAL_R_SDA")
	)
	(segment
		(start 188.845444 -18.76806)
		(end 185.123074 -18.76806)
		(width 0.15494)
		(layer "In15.Cu")
		(net "SMB_BIC_I2C6_MUX_THERMAL_R_SDA")
	)
	(segment
		(start 325.951342 -18.930112)
		(end 323.252084 -18.930112)
		(width 0.15494)
		(layer "In15.Cu")
		(net "SMB_BIC_I2C6_MUX_THERMAL_R_SDA")
	)
	(segment
		(start 379.651768 -83.09737)
		(end 379.651768 -82.641186)
		(width 0.15494)
		(layer "In15.Cu")
		(net "SMB_BIC_I2C6_MUX_THERMAL_R_SDA")
	)
	(segment
		(start 131.731766 -18.976594)
		(end 128.91516 -18.976594)
		(width 0.15494)
		(layer "In15.Cu")
		(net "SMB_BIC_I2C6_MUX_THERMAL_R_SDA")
	)
	(segment
		(start 274.244054 -18.4912)
		(end 273.770344 -18.96491)
		(width 0.15494)
		(layer "In15.Cu")
		(net "SMB_BIC_I2C6_MUX_THERMAL_R_SDA")
	)
	(segment
		(start 159.093662 -18.814288)
		(end 158.745174 -18.4658)
		(width 0.15494)
		(layer "In15.Cu")
		(net "SMB_BIC_I2C6_MUX_THERMAL_R_SDA")
	)
	(segment
		(start 448.392296 -18.562828)
		(end 438.215786 -18.562828)
		(width 0.15494)
		(layer "In15.Cu")
		(net "SMB_BIC_I2C6_MUX_THERMAL_R_SDA")
	)
	(segment
		(start 332.694534 -24.240998)
		(end 327.020936 -18.5674)
		(width 0.15494)
		(layer "In15.Cu")
		(net "SMB_BIC_I2C6_MUX_THERMAL_R_SDA")
	)
	(segment
		(start 253.885446 -17.9578)
		(end 252.897132 -18.946114)
		(width 0.15494)
		(layer "In15.Cu")
		(net "SMB_BIC_I2C6_MUX_THERMAL_R_SDA")
	)
	(segment
		(start 93.581982 -18.941796)
		(end 91.132152 -18.941796)
		(width 0.15494)
		(layer "In15.Cu")
		(net "SMB_BIC_I2C6_MUX_THERMAL_R_SDA")
	)
	(segment
		(start 191.98082 -18.47342)
		(end 191.4652 -17.9578)
		(width 0.15494)
		(layer "In15.Cu")
		(net "SMB_BIC_I2C6_MUX_THERMAL_R_SDA")
	)
	(segment
		(start 83.123024 -17.950434)
		(end 74.50328 -9.33069)
		(width 0.15494)
		(layer "In15.Cu")
		(net "SMB_BIC_I2C6_MUX_THERMAL_R_SDA")
	)
	(segment
		(start 136.797034 -18.918174)
		(end 133.318504 -18.918174)
		(width 0.15494)
		(layer "In15.Cu")
		(net "SMB_BIC_I2C6_MUX_THERMAL_R_SDA")
	)
	(segment
		(start 220.114622 -17.248124)
		(end 219.430346 -17.9324)
		(width 0.15494)
		(layer "In15.Cu")
		(net "SMB_BIC_I2C6_MUX_THERMAL_R_SDA")
	)
	(segment
		(start 180.80101 -18.925032)
		(end 180.372004 -18.496026)
		(width 0.15494)
		(layer "In15.Cu")
		(net "SMB_BIC_I2C6_MUX_THERMAL_R_SDA")
	)
	(segment
		(start 379.793754 -82.4992)
		(end 379.994922 -82.4992)
		(width 0.15494)
		(layer "In15.Cu")
		(net "SMB_BIC_I2C6_MUX_THERMAL_R_SDA")
	)
	(segment
		(start 301.211234 -18.729706)
		(end 300.947328 -18.4658)
		(width 0.15494)
		(layer "In15.Cu")
		(net "SMB_BIC_I2C6_MUX_THERMAL_R_SDA")
	)
	(segment
		(start 364.560104 -18.4912)
		(end 364.155736 -18.895568)
		(width 0.15494)
		(layer "In15.Cu")
		(net "SMB_BIC_I2C6_MUX_THERMAL_R_SDA")
	)
	(segment
		(start 370.70919 -10.36828)
		(end 370.70919 -17.104614)
		(width 0.15494)
		(layer "In15.Cu")
		(net "SMB_BIC_I2C6_MUX_THERMAL_R_SDA")
	)
	(segment
		(start 94.050866 -18.472912)
		(end 93.581982 -18.941796)
		(width 0.15494)
		(layer "In15.Cu")
		(net "SMB_BIC_I2C6_MUX_THERMAL_R_SDA")
	)
	(segment
		(start 300.947328 -18.4658)
		(end 300.375574 -18.4658)
		(width 0.15494)
		(layer "In15.Cu")
		(net "SMB_BIC_I2C6_MUX_THERMAL_R_SDA")
	)
	(segment
		(start 189.655704 -17.9578)
		(end 188.845444 -18.76806)
		(width 0.15494)
		(layer "In15.Cu")
		(net "SMB_BIC_I2C6_MUX_THERMAL_R_SDA")
	)
	(segment
		(start 323.252084 -18.930112)
		(end 322.762372 -18.4404)
		(width 0.15494)
		(layer "In15.Cu")
		(net "SMB_BIC_I2C6_MUX_THERMAL_R_SDA")
	)
	(segment
		(start 454.231248 -18.92808)
		(end 448.757548 -18.92808)
		(width 0.15494)
		(layer "In15.Cu")
		(net "SMB_BIC_I2C6_MUX_THERMAL_R_SDA")
	)
	(segment
		(start 360.603038 -18.37182)
		(end 353.657662 -18.37182)
		(width 0.15494)
		(layer "In15.Cu")
		(net "SMB_BIC_I2C6_MUX_THERMAL_R_SDA")
	)
	(segment
		(start 137.757408 -17.9578)
		(end 136.797034 -18.918174)
		(width 0.15494)
		(layer "In15.Cu")
		(net "SMB_BIC_I2C6_MUX_THERMAL_R_SDA")
	)
	(segment
		(start 183.689244 -18.925032)
		(end 180.80101 -18.925032)
		(width 0.15494)
		(layer "In15.Cu")
		(net "SMB_BIC_I2C6_MUX_THERMAL_R_SDA")
	)
	(segment
		(start 74.50328 -9.33069)
		(end 73.608438 -9.33069)
		(width 0.15494)
		(layer "In15.Cu")
		(net "SMB_BIC_I2C6_MUX_THERMAL_R_SDA")
	)
	(segment
		(start 437.729376 -18.076418)
		(end 431.330608 -18.076418)
		(width 0.15494)
		(layer "In15.Cu")
		(net "SMB_BIC_I2C6_MUX_THERMAL_R_SDA")
	)
	(segment
		(start 390.528048 -18.550382)
		(end 390.515602 -18.562828)
		(width 0.15494)
		(layer "In15.Cu")
		(net "SMB_BIC_I2C6_MUX_THERMAL_R_SDA")
	)
	(segment
		(start 422.35374 -18.52422)
		(end 416.361118 -18.52422)
		(width 0.15494)
		(layer "In15.Cu")
		(net "SMB_BIC_I2C6_MUX_THERMAL_R_SDA")
	)
	(segment
		(start 431.330608 -18.076418)
		(end 430.882806 -18.52422)
		(width 0.15494)
		(layer "In15.Cu")
		(net "SMB_BIC_I2C6_MUX_THERMAL_R_SDA")
	)
	(segment
		(start 327.020936 -18.5674)
		(end 326.314054 -18.5674)
		(width 0.15494)
		(layer "In15.Cu")
		(net "SMB_BIC_I2C6_MUX_THERMAL_R_SDA")
	)
	(segment
		(start 429.66386 -83.459574)
		(end 434.962808 -83.459574)
		(width 0.15494)
		(layer "In15.Cu")
		(net "SMB_BIC_I2C6_MUX_THERMAL_R_SDA")
	)
	(segment
		(start 184.192164 -18.422112)
		(end 183.689244 -18.925032)
		(width 0.15494)
		(layer "In15.Cu")
		(net "SMB_BIC_I2C6_MUX_THERMAL_R_SDA")
	)
	(segment
		(start 249.316494 -18.946114)
		(end 248.86158 -18.4912)
		(width 0.15494)
		(layer "In15.Cu")
		(net "SMB_BIC_I2C6_MUX_THERMAL_R_SDA")
	)
	(segment
		(start 422.7576 -18.92808)
		(end 422.35374 -18.52422)
		(width 0.15494)
		(layer "In15.Cu")
		(net "SMB_BIC_I2C6_MUX_THERMAL_R_SDA")
	)
	(segment
		(start 416.361118 -18.52422)
		(end 416.04565 -18.839688)
		(width 0.15494)
		(layer "In15.Cu")
		(net "SMB_BIC_I2C6_MUX_THERMAL_R_SDA")
	)
	(segment
		(start 380.136908 -82.641186)
		(end 380.136908 -83.09737)
		(width 0.15494)
		(layer "In15.Cu")
		(net "SMB_BIC_I2C6_MUX_THERMAL_R_SDA")
	)
	(segment
		(start 438.215786 -18.562828)
		(end 437.729376 -18.076418)
		(width 0.15494)
		(layer "In15.Cu")
		(net "SMB_BIC_I2C6_MUX_THERMAL_R_SDA")
	)
	(segment
		(start 162.809936 -18.814288)
		(end 159.093662 -18.814288)
		(width 0.15494)
		(layer "In15.Cu")
		(net "SMB_BIC_I2C6_MUX_THERMAL_R_SDA")
	)
	(segment
		(start 185.123074 -18.76806)
		(end 184.777126 -18.422112)
		(width 0.15494)
		(layer "In15.Cu")
		(net "SMB_BIC_I2C6_MUX_THERMAL_R_SDA")
	)
	(segment
		(start 248.86158 -18.4912)
		(end 248.386854 -18.4912)
		(width 0.15494)
		(layer "In15.Cu")
		(net "SMB_BIC_I2C6_MUX_THERMAL_R_SDA")
	)
	(segment
		(start 255.9558 -18.415)
		(end 255.4986 -17.9578)
		(width 0.15494)
		(layer "In15.Cu")
		(net "SMB_BIC_I2C6_MUX_THERMAL_R_SDA")
	)
	(segment
		(start 343.69375 -212.786976)
		(end 344.093546 -212.38718)
		(width 0.13208)
		(layer "F.Cu")
		(net "SSD15_CLK_EN_N")
	)
	(via
		(at 345.44 -209.423)
		(size 0.6604)
		(drill 0.3302)
		(layers "F.Cu" "B.Cu")
		(net "SSD15_CLK_EN_N")
	)
	(via
		(at 344.093546 -212.38718)
		(size 0.4572)
		(drill 0.254)
		(layers "F.Cu" "B.Cu")
		(net "SSD15_CLK_EN_N")
	)
	(segment
		(start 344.093546 -212.38718)
		(end 344.093546 -211.582)
		(width 0.13208)
		(layer "B.Cu")
		(net "SSD15_CLK_EN_N")
	)
	(segment
		(start 344.093546 -211.582)
		(end 344.741246 -210.9343)
		(width 0.13208)
		(layer "B.Cu")
		(net "SSD15_CLK_EN_N")
	)
	(segment
		(start 344.741246 -210.121754)
		(end 345.44 -209.423)
		(width 0.13208)
		(layer "B.Cu")
		(net "SSD15_CLK_EN_N")
	)
	(segment
		(start 344.741246 -210.9343)
		(end 344.741246 -210.121754)
		(width 0.13208)
		(layer "B.Cu")
		(net "SSD15_CLK_EN_N")
	)
	(segment
		(start 345.44 -209.423)
		(end 345.44 -208.17205)
		(width 0.13208)
		(layer "B.Cu")
		(net "SSD15_CLK_EN_N")
	)
	(segment
		(start 293.273226 -58.166)
		(end 293.390828 -58.449718)
		(width 0.2032)
		(layer "F.Cu")
		(net "P3V3_SSD10_SS")
	)
	(segment
		(start 292.340792 -57.16397)
		(end 292.340792 -57.233566)
		(width 0.2032)
		(layer "F.Cu")
		(net "P3V3_SSD10_SS")
	)
	(segment
		(start 293.394892 -58.453782)
		(end 293.394892 -59.177936)
		(width 0.13208)
		(layer "F.Cu")
		(net "P3V3_SSD10_SS")
	)
	(segment
		(start 292.340792 -57.233566)
		(end 293.273226 -58.166)
		(width 0.2032)
		(layer "F.Cu")
		(net "P3V3_SSD10_SS")
	)
	(segment
		(start 293.390828 -58.449718)
		(end 293.394892 -58.453782)
		(width 0.13208)
		(layer "F.Cu")
		(net "P3V3_SSD10_SS")
	)
	(via
		(at 293.390828 -58.449718)
		(size 0.508)
		(drill 0.254)
		(layers "F.Cu" "B.Cu")
		(net "P3V3_SSD10_SS")
	)
	(segment
		(start 136.09193 -235.715556)
		(end 135.68807 -235.715556)
		(width 0.1143)
		(layer "F.Cu")
		(net "CLK_100M_DB2000QL_PEX1_S1_R_DP")
	)
	(segment
		(start 131.859528 -234.535472)
		(end 131.665726 -234.535472)
		(width 0.1143)
		(layer "F.Cu")
		(net "CLK_100M_DB2000QL_PEX1_S1_R_DP")
	)
	(segment
		(start 136.22909 -235.852716)
		(end 136.09193 -235.715556)
		(width 0.1143)
		(layer "F.Cu")
		(net "CLK_100M_DB2000QL_PEX1_S1_R_DP")
	)
	(segment
		(start 154.4828 -238.000286)
		(end 152.33523 -235.852716)
		(width 0.1143)
		(layer "F.Cu")
		(net "CLK_100M_DB2000QL_PEX1_S1_R_DP")
	)
	(segment
		(start 132.98297 -235.852716)
		(end 132.145532 -235.015278)
		(width 0.1143)
		(layer "F.Cu")
		(net "CLK_100M_DB2000QL_PEX1_S1_R_DP")
	)
	(segment
		(start 123.297696 -211.456016)
		(end 126.6952 -208.058512)
		(width 0.1143)
		(layer "F.Cu")
		(net "CLK_100M_DB2000QL_PEX1_S1_R_DP")
	)
	(segment
		(start 131.665726 -234.535472)
		(end 131.38023 -234.249976)
		(width 0.1143)
		(layer "F.Cu")
		(net "CLK_100M_DB2000QL_PEX1_S1_R_DP")
	)
	(segment
		(start 121.426478 -185.434224)
		(end 121.426478 -176.45253)
		(width 0.1143)
		(layer "F.Cu")
		(net "CLK_100M_DB2000QL_PEX1_S1_R_DP")
	)
	(segment
		(start 131.09448 -233.77017)
		(end 130.900424 -233.77017)
		(width 0.1143)
		(layer "F.Cu")
		(net "CLK_100M_DB2000QL_PEX1_S1_R_DP")
	)
	(segment
		(start 125.502162 -174.6885)
		(end 125.821186 -175.007524)
		(width 0.1143)
		(layer "F.Cu")
		(net "CLK_100M_DB2000QL_PEX1_S1_R_DP")
	)
	(segment
		(start 135.68807 -235.715556)
		(end 135.55091 -235.852716)
		(width 0.1143)
		(layer "F.Cu")
		(net "CLK_100M_DB2000QL_PEX1_S1_R_DP")
	)
	(segment
		(start 132.145532 -235.015278)
		(end 132.145532 -234.821222)
		(width 0.1143)
		(layer "F.Cu")
		(net "CLK_100M_DB2000QL_PEX1_S1_R_DP")
	)
	(segment
		(start 154.719782 -239.048798)
		(end 154.4828 -238.811816)
		(width 0.1143)
		(layer "F.Cu")
		(net "CLK_100M_DB2000QL_PEX1_S1_R_DP")
	)
	(segment
		(start 130.329178 -233.004868)
		(end 130.135122 -233.004868)
		(width 0.1143)
		(layer "F.Cu")
		(net "CLK_100M_DB2000QL_PEX1_S1_R_DP")
	)
	(segment
		(start 135.14705 -235.852716)
		(end 135.00989 -235.715556)
		(width 0.1143)
		(layer "F.Cu")
		(net "CLK_100M_DB2000QL_PEX1_S1_R_DP")
	)
	(segment
		(start 132.145532 -234.821222)
		(end 131.859528 -234.535472)
		(width 0.1143)
		(layer "F.Cu")
		(net "CLK_100M_DB2000QL_PEX1_S1_R_DP")
	)
	(segment
		(start 131.38023 -234.05592)
		(end 131.09448 -233.77017)
		(width 0.1143)
		(layer "F.Cu")
		(net "CLK_100M_DB2000QL_PEX1_S1_R_DP")
	)
	(segment
		(start 135.55091 -235.852716)
		(end 135.14705 -235.852716)
		(width 0.1143)
		(layer "F.Cu")
		(net "CLK_100M_DB2000QL_PEX1_S1_R_DP")
	)
	(segment
		(start 134.06501 -235.852716)
		(end 133.92785 -235.715556)
		(width 0.1143)
		(layer "F.Cu")
		(net "CLK_100M_DB2000QL_PEX1_S1_R_DP")
	)
	(segment
		(start 153.89987 -297.79976)
		(end 153.899616 -297.79976)
		(width 0.1143)
		(layer "F.Cu")
		(net "CLK_100M_DB2000QL_PEX1_S1_R_DP")
	)
	(segment
		(start 133.92785 -235.715556)
		(end 133.52399 -235.715556)
		(width 0.1143)
		(layer "F.Cu")
		(net "CLK_100M_DB2000QL_PEX1_S1_R_DP")
	)
	(segment
		(start 133.52399 -235.715556)
		(end 133.38683 -235.852716)
		(width 0.1143)
		(layer "F.Cu")
		(net "CLK_100M_DB2000QL_PEX1_S1_R_DP")
	)
	(segment
		(start 134.46887 -235.852716)
		(end 134.06501 -235.852716)
		(width 0.1143)
		(layer "F.Cu")
		(net "CLK_100M_DB2000QL_PEX1_S1_R_DP")
	)
	(segment
		(start 134.60603 -235.715556)
		(end 134.46887 -235.852716)
		(width 0.1143)
		(layer "F.Cu")
		(net "CLK_100M_DB2000QL_PEX1_S1_R_DP")
	)
	(segment
		(start 154.4828 -238.811816)
		(end 154.4828 -238.000286)
		(width 0.1143)
		(layer "F.Cu")
		(net "CLK_100M_DB2000QL_PEX1_S1_R_DP")
	)
	(segment
		(start 126.6952 -208.058512)
		(end 126.6952 -190.702946)
		(width 0.1143)
		(layer "F.Cu")
		(net "CLK_100M_DB2000QL_PEX1_S1_R_DP")
	)
	(segment
		(start 126.6952 -190.702946)
		(end 121.426478 -185.434224)
		(width 0.1143)
		(layer "F.Cu")
		(net "CLK_100M_DB2000QL_PEX1_S1_R_DP")
	)
	(segment
		(start 133.38683 -235.852716)
		(end 132.98297 -235.852716)
		(width 0.1143)
		(layer "F.Cu")
		(net "CLK_100M_DB2000QL_PEX1_S1_R_DP")
	)
	(segment
		(start 130.614928 -233.484674)
		(end 130.614928 -233.290872)
		(width 0.1143)
		(layer "F.Cu")
		(net "CLK_100M_DB2000QL_PEX1_S1_R_DP")
	)
	(segment
		(start 130.135122 -233.004868)
		(end 123.297696 -226.167442)
		(width 0.1143)
		(layer "F.Cu")
		(net "CLK_100M_DB2000QL_PEX1_S1_R_DP")
	)
	(segment
		(start 135.00989 -235.715556)
		(end 134.60603 -235.715556)
		(width 0.1143)
		(layer "F.Cu")
		(net "CLK_100M_DB2000QL_PEX1_S1_R_DP")
	)
	(segment
		(start 123.190508 -174.6885)
		(end 125.502162 -174.6885)
		(width 0.1143)
		(layer "F.Cu")
		(net "CLK_100M_DB2000QL_PEX1_S1_R_DP")
	)
	(segment
		(start 131.38023 -234.249976)
		(end 131.38023 -234.05592)
		(width 0.1143)
		(layer "F.Cu")
		(net "CLK_100M_DB2000QL_PEX1_S1_R_DP")
	)
	(segment
		(start 153.899616 -297.79976)
		(end 153.424636 -297.32478)
		(width 0.1143)
		(layer "F.Cu")
		(net "CLK_100M_DB2000QL_PEX1_S1_R_DP")
	)
	(segment
		(start 152.33523 -235.852716)
		(end 136.22909 -235.852716)
		(width 0.1143)
		(layer "F.Cu")
		(net "CLK_100M_DB2000QL_PEX1_S1_R_DP")
	)
	(segment
		(start 130.614928 -233.290872)
		(end 130.329178 -233.004868)
		(width 0.1143)
		(layer "F.Cu")
		(net "CLK_100M_DB2000QL_PEX1_S1_R_DP")
	)
	(segment
		(start 121.426478 -176.45253)
		(end 123.190508 -174.6885)
		(width 0.1143)
		(layer "F.Cu")
		(net "CLK_100M_DB2000QL_PEX1_S1_R_DP")
	)
	(segment
		(start 123.297696 -226.167442)
		(end 123.297696 -211.456016)
		(width 0.1143)
		(layer "F.Cu")
		(net "CLK_100M_DB2000QL_PEX1_S1_R_DP")
	)
	(segment
		(start 130.900424 -233.77017)
		(end 130.614928 -233.484674)
		(width 0.1143)
		(layer "F.Cu")
		(net "CLK_100M_DB2000QL_PEX1_S1_R_DP")
	)
	(via
		(at 153.424636 -297.32478)
		(size 0.4064)
		(drill 0.2032)
		(layers "F.Cu" "B.Cu")
		(net "CLK_100M_DB2000QL_PEX1_S1_R_DP")
	)
	(via
		(at 154.719782 -239.048798)
		(size 0.508)
		(drill 0.254)
		(layers "F.Cu" "B.Cu")
		(net "CLK_100M_DB2000QL_PEX1_S1_R_DP")
	)
	(segment
		(start 153.133806 -297.32478)
		(end 153.057606 -297.24858)
		(width 0.0889)
		(layer "B.Cu")
		(net "CLK_100M_DB2000QL_PEX1_S1_R_DP")
	)
	(segment
		(start 151.695404 -296.33545)
		(end 150.094188 -294.734234)
		(width 0.1143)
		(layer "B.Cu")
		(net "CLK_100M_DB2000QL_PEX1_S1_R_DP")
	)
	(segment
		(start 153.057606 -296.971212)
		(end 152.504394 -296.418)
		(width 0.0889)
		(layer "B.Cu")
		(net "CLK_100M_DB2000QL_PEX1_S1_R_DP")
	)
	(segment
		(start 137.11301 -252.410468)
		(end 142.97787 -246.545608)
		(width 0.1143)
		(layer "B.Cu")
		(net "CLK_100M_DB2000QL_PEX1_S1_R_DP")
	)
	(segment
		(start 147.079716 -291.06749)
		(end 147.079716 -290.66363)
		(width 0.1143)
		(layer "B.Cu")
		(net "CLK_100M_DB2000QL_PEX1_S1_R_DP")
	)
	(segment
		(start 153.057606 -297.24858)
		(end 153.057606 -296.971212)
		(width 0.0889)
		(layer "B.Cu")
		(net "CLK_100M_DB2000QL_PEX1_S1_R_DP")
	)
	(segment
		(start 148.336 -246.545608)
		(end 154.478482 -240.403126)
		(width 0.1143)
		(layer "B.Cu")
		(net "CLK_100M_DB2000QL_PEX1_S1_R_DP")
	)
	(segment
		(start 146.942556 -293.734998)
		(end 146.942556 -291.20465)
		(width 0.1143)
		(layer "B.Cu")
		(net "CLK_100M_DB2000QL_PEX1_S1_R_DP")
	)
	(segment
		(start 147.941792 -294.734234)
		(end 146.942556 -293.734998)
		(width 0.1143)
		(layer "B.Cu")
		(net "CLK_100M_DB2000QL_PEX1_S1_R_DP")
	)
	(segment
		(start 146.942556 -290.52647)
		(end 146.942556 -278.679402)
		(width 0.1143)
		(layer "B.Cu")
		(net "CLK_100M_DB2000QL_PEX1_S1_R_DP")
	)
	(segment
		(start 151.9174 -296.33545)
		(end 151.895302 -296.33545)
		(width 0.0889)
		(layer "B.Cu")
		(net "CLK_100M_DB2000QL_PEX1_S1_R_DP")
	)
	(segment
		(start 154.478482 -239.290098)
		(end 154.719782 -239.048798)
		(width 0.1143)
		(layer "B.Cu")
		(net "CLK_100M_DB2000QL_PEX1_S1_R_DP")
	)
	(segment
		(start 142.97787 -246.545608)
		(end 148.336 -246.545608)
		(width 0.1143)
		(layer "B.Cu")
		(net "CLK_100M_DB2000QL_PEX1_S1_R_DP")
	)
	(segment
		(start 150.094188 -294.734234)
		(end 147.941792 -294.734234)
		(width 0.1143)
		(layer "B.Cu")
		(net "CLK_100M_DB2000QL_PEX1_S1_R_DP")
	)
	(segment
		(start 146.942556 -278.679402)
		(end 144.234408 -275.971254)
		(width 0.1143)
		(layer "B.Cu")
		(net "CLK_100M_DB2000QL_PEX1_S1_R_DP")
	)
	(segment
		(start 147.079716 -290.66363)
		(end 146.942556 -290.52647)
		(width 0.1143)
		(layer "B.Cu")
		(net "CLK_100M_DB2000QL_PEX1_S1_R_DP")
	)
	(segment
		(start 151.99995 -296.418)
		(end 151.9174 -296.33545)
		(width 0.0889)
		(layer "B.Cu")
		(net "CLK_100M_DB2000QL_PEX1_S1_R_DP")
	)
	(segment
		(start 152.504394 -296.418)
		(end 151.99995 -296.418)
		(width 0.0889)
		(layer "B.Cu")
		(net "CLK_100M_DB2000QL_PEX1_S1_R_DP")
	)
	(segment
		(start 151.895302 -296.33545)
		(end 151.695404 -296.33545)
		(width 0.1143)
		(layer "B.Cu")
		(net "CLK_100M_DB2000QL_PEX1_S1_R_DP")
	)
	(segment
		(start 137.11301 -269.421864)
		(end 137.11301 -252.410468)
		(width 0.1143)
		(layer "B.Cu")
		(net "CLK_100M_DB2000QL_PEX1_S1_R_DP")
	)
	(segment
		(start 144.234408 -275.971254)
		(end 143.6624 -275.971254)
		(width 0.1143)
		(layer "B.Cu")
		(net "CLK_100M_DB2000QL_PEX1_S1_R_DP")
	)
	(segment
		(start 154.478482 -240.403126)
		(end 154.478482 -239.290098)
		(width 0.1143)
		(layer "B.Cu")
		(net "CLK_100M_DB2000QL_PEX1_S1_R_DP")
	)
	(segment
		(start 146.942556 -291.20465)
		(end 147.079716 -291.06749)
		(width 0.1143)
		(layer "B.Cu")
		(net "CLK_100M_DB2000QL_PEX1_S1_R_DP")
	)
	(segment
		(start 143.6624 -275.971254)
		(end 137.11301 -269.421864)
		(width 0.1143)
		(layer "B.Cu")
		(net "CLK_100M_DB2000QL_PEX1_S1_R_DP")
	)
	(segment
		(start 153.424636 -297.32478)
		(end 153.133806 -297.32478)
		(width 0.0889)
		(layer "B.Cu")
		(net "CLK_100M_DB2000QL_PEX1_S1_R_DP")
	)
	(segment
		(start 104.06761 -86.523068)
		(end 100.613972 -86.523068)
		(width 0.13462)
		(layer "F.Cu")
		(net "CLK_100M_CK440Q_1_DB800ZL_R_DP")
	)
	(segment
		(start 105.462578 -86.978998)
		(end 105.39603 -86.91245)
		(width 0.13462)
		(layer "F.Cu")
		(net "CLK_100M_CK440Q_1_DB800ZL_R_DP")
	)
	(segment
		(start 104.456992 -86.91245)
		(end 104.06761 -86.523068)
		(width 0.13462)
		(layer "F.Cu")
		(net "CLK_100M_CK440Q_1_DB800ZL_R_DP")
	)
	(segment
		(start 269.26159 -81.675732)
		(end 268.9352 -82.002122)
		(width 0.13462)
		(layer "F.Cu")
		(net "CLK_100M_CK440Q_1_DB800ZL_R_DP")
	)
	(segment
		(start 274.255992 -81.976722)
		(end 273.955002 -81.675732)
		(width 0.13462)
		(layer "F.Cu")
		(net "CLK_100M_CK440Q_1_DB800ZL_R_DP")
	)
	(segment
		(start 273.955002 -81.675732)
		(end 269.26159 -81.675732)
		(width 0.13462)
		(layer "F.Cu")
		(net "CLK_100M_CK440Q_1_DB800ZL_R_DP")
	)
	(segment
		(start 105.39603 -86.91245)
		(end 104.456992 -86.91245)
		(width 0.13462)
		(layer "F.Cu")
		(net "CLK_100M_CK440Q_1_DB800ZL_R_DP")
	)
	(segment
		(start 100.613972 -86.523068)
		(end 100.601272 -86.510368)
		(width 0.13462)
		(layer "F.Cu")
		(net "CLK_100M_CK440Q_1_DB800ZL_R_DP")
	)
	(segment
		(start 105.889044 -86.978998)
		(end 105.462578 -86.978998)
		(width 0.13462)
		(layer "F.Cu")
		(net "CLK_100M_CK440Q_1_DB800ZL_R_DP")
	)
	(segment
		(start 100.601272 -86.510368)
		(end 100.300282 -86.811358)
		(width 0.13462)
		(layer "F.Cu")
		(net "CLK_100M_CK440Q_1_DB800ZL_R_DP")
	)
	(via
		(at 274.255992 -81.976722)
		(size 0.508)
		(drill 0.254)
		(layers "F.Cu" "B.Cu")
		(net "CLK_100M_CK440Q_1_DB800ZL_R_DP")
	)
	(via
		(at 100.300282 -86.811358)
		(size 0.508)
		(drill 0.254)
		(layers "F.Cu" "B.Cu")
		(net "CLK_100M_CK440Q_1_DB800ZL_R_DP")
	)
	(segment
		(start 108.601002 -81.1276)
		(end 105.315258 -81.781142)
		(width 0.1651)
		(layer "In9.Cu")
		(net "CLK_100M_CK440Q_1_DB800ZL_R_DP")
	)
	(segment
		(start 102.731824 -85.710776)
		(end 101.922072 -86.520528)
		(width 0.1651)
		(layer "In9.Cu")
		(net "CLK_100M_CK440Q_1_DB800ZL_R_DP")
	)
	(segment
		(start 105.315258 -81.781142)
		(end 103.683816 -83.412584)
		(width 0.1651)
		(layer "In9.Cu")
		(net "CLK_100M_CK440Q_1_DB800ZL_R_DP")
	)
	(segment
		(start 269.856712 -81.685892)
		(end 267.09116 -78.92034)
		(width 0.1651)
		(layer "In9.Cu")
		(net "CLK_100M_CK440Q_1_DB800ZL_R_DP")
	)
	(segment
		(start 221.57944 -73.91654)
		(end 219.97924 -75.51674)
		(width 0.1651)
		(layer "In9.Cu")
		(net "CLK_100M_CK440Q_1_DB800ZL_R_DP")
	)
	(segment
		(start 224.59696 -74.75474)
		(end 223.75876 -73.91654)
		(width 0.1651)
		(layer "In9.Cu")
		(net "CLK_100M_CK440Q_1_DB800ZL_R_DP")
	)
	(segment
		(start 273.965162 -81.685892)
		(end 269.856712 -81.685892)
		(width 0.1651)
		(layer "In9.Cu")
		(net "CLK_100M_CK440Q_1_DB800ZL_R_DP")
	)
	(segment
		(start 190.38824 -81.81594)
		(end 118.180866 -81.81594)
		(width 0.1651)
		(layer "In9.Cu")
		(net "CLK_100M_CK440Q_1_DB800ZL_R_DP")
	)
	(segment
		(start 118.180866 -81.81594)
		(end 116.518944 -81.1276)
		(width 0.1651)
		(layer "In9.Cu")
		(net "CLK_100M_CK440Q_1_DB800ZL_R_DP")
	)
	(segment
		(start 101.922072 -86.520528)
		(end 100.591112 -86.520528)
		(width 0.1651)
		(layer "In9.Cu")
		(net "CLK_100M_CK440Q_1_DB800ZL_R_DP")
	)
	(segment
		(start 240.19256 -74.75474)
		(end 224.59696 -74.75474)
		(width 0.1651)
		(layer "In9.Cu")
		(net "CLK_100M_CK440Q_1_DB800ZL_R_DP")
	)
	(segment
		(start 251.888244 -77.52334)
		(end 250.845574 -77.09154)
		(width 0.1651)
		(layer "In9.Cu")
		(net "CLK_100M_CK440Q_1_DB800ZL_R_DP")
	)
	(segment
		(start 260.63956 -77.52334)
		(end 251.888244 -77.52334)
		(width 0.1651)
		(layer "In9.Cu")
		(net "CLK_100M_CK440Q_1_DB800ZL_R_DP")
	)
	(segment
		(start 100.591112 -86.520528)
		(end 100.300282 -86.811358)
		(width 0.1651)
		(layer "In9.Cu")
		(net "CLK_100M_CK440Q_1_DB800ZL_R_DP")
	)
	(segment
		(start 242.52936 -77.09154)
		(end 240.19256 -74.75474)
		(width 0.1651)
		(layer "In9.Cu")
		(net "CLK_100M_CK440Q_1_DB800ZL_R_DP")
	)
	(segment
		(start 196.68744 -75.51674)
		(end 190.38824 -81.81594)
		(width 0.1651)
		(layer "In9.Cu")
		(net "CLK_100M_CK440Q_1_DB800ZL_R_DP")
	)
	(segment
		(start 262.03656 -78.92034)
		(end 260.63956 -77.52334)
		(width 0.1651)
		(layer "In9.Cu")
		(net "CLK_100M_CK440Q_1_DB800ZL_R_DP")
	)
	(segment
		(start 267.09116 -78.92034)
		(end 262.03656 -78.92034)
		(width 0.1651)
		(layer "In9.Cu")
		(net "CLK_100M_CK440Q_1_DB800ZL_R_DP")
	)
	(segment
		(start 223.75876 -73.91654)
		(end 221.57944 -73.91654)
		(width 0.1651)
		(layer "In9.Cu")
		(net "CLK_100M_CK440Q_1_DB800ZL_R_DP")
	)
	(segment
		(start 219.97924 -75.51674)
		(end 196.68744 -75.51674)
		(width 0.1651)
		(layer "In9.Cu")
		(net "CLK_100M_CK440Q_1_DB800ZL_R_DP")
	)
	(segment
		(start 274.255992 -81.976722)
		(end 273.965162 -81.685892)
		(width 0.1651)
		(layer "In9.Cu")
		(net "CLK_100M_CK440Q_1_DB800ZL_R_DP")
	)
	(segment
		(start 250.845574 -77.09154)
		(end 242.52936 -77.09154)
		(width 0.1651)
		(layer "In9.Cu")
		(net "CLK_100M_CK440Q_1_DB800ZL_R_DP")
	)
	(segment
		(start 103.683816 -83.412584)
		(end 102.731824 -85.710776)
		(width 0.1651)
		(layer "In9.Cu")
		(net "CLK_100M_CK440Q_1_DB800ZL_R_DP")
	)
	(segment
		(start 116.518944 -81.1276)
		(end 108.601002 -81.1276)
		(width 0.1651)
		(layer "In9.Cu")
		(net "CLK_100M_CK440Q_1_DB800ZL_R_DP")
	)
	(segment
		(start 206.621888 -311.969404)
		(end 207.60944 -311.969404)
		(width 0.13208)
		(layer "F.Cu")
		(net "PEX1_SPARE5")
	)
	(segment
		(start 206.316072 -311.663588)
		(end 206.621888 -311.969404)
		(width 0.13208)
		(layer "F.Cu")
		(net "PEX1_SPARE5")
	)
	(segment
		(start 176.224946 -308.724808)
		(end 175.749966 -309.199788)
		(width 0.13462)
		(layer "F.Cu")
		(net "PEX1_SPARE5")
	)
	(segment
		(start 207.68056 -311.969404)
		(end 208.169764 -311.4802)
		(width 0.13208)
		(layer "F.Cu")
		(net "PEX1_SPARE5")
	)
	(segment
		(start 207.60944 -311.969404)
		(end 207.68056 -311.969404)
		(width 0.13208)
		(layer "F.Cu")
		(net "PEX1_SPARE5")
	)
	(via
		(at 176.224946 -308.724808)
		(size 0.4064)
		(drill 0.2032)
		(layers "F.Cu" "B.Cu")
		(net "PEX1_SPARE5")
	)
	(via
		(at 184.613042 -320.890646)
		(size 0.6604)
		(drill 0.3302)
		(layers "F.Cu" "B.Cu")
		(net "PEX1_SPARE5")
	)
	(via
		(at 207.60944 -311.969404)
		(size 0.508)
		(drill 0.254)
		(layers "F.Cu" "B.Cu")
		(net "PEX1_SPARE5")
	)
	(segment
		(start 176.224946 -308.724808)
		(end 176.224946 -320.605404)
		(width 0.13208)
		(layer "B.Cu")
		(net "PEX1_SPARE5")
	)
	(segment
		(start 206.300324 -313.27852)
		(end 205.64729 -313.27852)
		(width 0.13208)
		(layer "B.Cu")
		(net "PEX1_SPARE5")
	)
	(segment
		(start 176.510188 -320.890646)
		(end 184.613042 -320.890646)
		(width 0.13208)
		(layer "B.Cu")
		(net "PEX1_SPARE5")
	)
	(segment
		(start 207.60944 -311.969404)
		(end 206.300324 -313.27852)
		(width 0.13208)
		(layer "B.Cu")
		(net "PEX1_SPARE5")
	)
	(segment
		(start 198.035164 -320.890646)
		(end 184.613042 -320.890646)
		(width 0.13208)
		(layer "B.Cu")
		(net "PEX1_SPARE5")
	)
	(segment
		(start 205.64729 -313.27852)
		(end 198.035164 -320.890646)
		(width 0.13208)
		(layer "B.Cu")
		(net "PEX1_SPARE5")
	)
	(segment
		(start 176.224946 -320.605404)
		(end 176.510188 -320.890646)
		(width 0.13208)
		(layer "B.Cu")
		(net "PEX1_SPARE5")
	)
	(segment
		(start 50.026316 -19.453098)
		(end 50.067972 -19.453098)
		(width 0.13208)
		(layer "F.Cu")
		(net "SMB_ISO_SSD1_SDA")
	)
	(segment
		(start 49.256442 -20.467574)
		(end 49.256442 -20.222972)
		(width 0.13208)
		(layer "F.Cu")
		(net "SMB_ISO_SSD1_SDA")
	)
	(segment
		(start 52.935632 -18.533618)
		(end 52.935632 -16.439388)
		(width 0.13208)
		(layer "F.Cu")
		(net "SMB_ISO_SSD1_SDA")
	)
	(segment
		(start 50.067972 -19.453098)
		(end 52.016152 -19.453098)
		(width 0.13208)
		(layer "F.Cu")
		(net "SMB_ISO_SSD1_SDA")
	)
	(segment
		(start 52.016152 -19.453098)
		(end 52.935632 -18.533618)
		(width 0.13208)
		(layer "F.Cu")
		(net "SMB_ISO_SSD1_SDA")
	)
	(segment
		(start 49.256442 -20.222972)
		(end 50.026316 -19.453098)
		(width 0.13208)
		(layer "F.Cu")
		(net "SMB_ISO_SSD1_SDA")
	)
	(segment
		(start 53.462428 -23.337266)
		(end 53.462428 -23.946866)
		(width 0.13208)
		(layer "F.Cu")
		(net "SMB_ISO_SSD1_SDA")
	)
	(segment
		(start 52.99583 -16.37919)
		(end 52.99583 -15.333726)
		(width 0.13208)
		(layer "F.Cu")
		(net "SMB_ISO_SSD1_SDA")
	)
	(segment
		(start 52.935632 -16.439388)
		(end 52.99583 -16.37919)
		(width 0.13208)
		(layer "F.Cu")
		(net "SMB_ISO_SSD1_SDA")
	)
	(via
		(at 52.99583 -15.333726)
		(size 0.508)
		(drill 0.254)
		(layers "F.Cu" "B.Cu")
		(net "SMB_ISO_SSD1_SDA")
	)
	(via
		(at 53.462428 -23.946866)
		(size 0.508)
		(drill 0.254)
		(layers "F.Cu" "B.Cu")
		(net "SMB_ISO_SSD1_SDA")
	)
	(segment
		(start 52.99583 -15.333726)
		(end 52.99583 -15.836392)
		(width 0.13208)
		(layer "B.Cu")
		(net "SMB_ISO_SSD1_SDA")
	)
	(segment
		(start 52.99583 -15.836392)
		(end 55.03545 -17.876012)
		(width 0.13208)
		(layer "B.Cu")
		(net "SMB_ISO_SSD1_SDA")
	)
	(segment
		(start 55.03545 -17.876012)
		(end 55.03545 -22.373844)
		(width 0.13208)
		(layer "B.Cu")
		(net "SMB_ISO_SSD1_SDA")
	)
	(segment
		(start 55.03545 -22.373844)
		(end 53.462428 -23.946866)
		(width 0.13208)
		(layer "B.Cu")
		(net "SMB_ISO_SSD1_SDA")
	)
	(segment
		(start 381.427736 -85.486494)
		(end 382.640078 -85.486494)
		(width 0.13208)
		(layer "F.Cu")
		(net "SMB_BIC_I2C6_MUX_PEX_ADC_SCL")
	)
	(segment
		(start 464.381088 -279.135078)
		(end 464.381088 -278.375872)
		(width 0.13208)
		(layer "F.Cu")
		(net "SMB_BIC_I2C6_MUX_PEX_ADC_SCL")
	)
	(via
		(at 464.381088 -278.375872)
		(size 0.508)
		(drill 0.254)
		(layers "F.Cu" "B.Cu")
		(net "SMB_BIC_I2C6_MUX_PEX_ADC_SCL")
	)
	(via
		(at 381.427736 -85.486494)
		(size 0.508)
		(drill 0.254)
		(layers "F.Cu" "B.Cu")
		(net "SMB_BIC_I2C6_MUX_PEX_ADC_SCL")
	)
	(via
		(at 435.84622 -86.606126)
		(size 0.508)
		(drill 0.254)
		(layers "F.Cu" "B.Cu")
		(net "SMB_BIC_I2C6_MUX_PEX_ADC_SCL")
	)
	(segment
		(start 441.974986 -233.663744)
		(end 441.77204 -233.460798)
		(width 0.15494)
		(layer "In5.Cu")
		(net "SMB_BIC_I2C6_MUX_PEX_ADC_SCL")
	)
	(segment
		(start 433.30114 -117.162072)
		(end 433.30114 -112.319816)
		(width 0.15494)
		(layer "In5.Cu")
		(net "SMB_BIC_I2C6_MUX_PEX_ADC_SCL")
	)
	(segment
		(start 450.9262 -250.2408)
		(end 450.9262 -247.504712)
		(width 0.15494)
		(layer "In5.Cu")
		(net "SMB_BIC_I2C6_MUX_PEX_ADC_SCL")
	)
	(segment
		(start 435.810914 -86.641432)
		(end 435.84622 -86.606126)
		(width 0.15494)
		(layer "In5.Cu")
		(net "SMB_BIC_I2C6_MUX_PEX_ADC_SCL")
	)
	(segment
		(start 433.30114 -112.319816)
		(end 429.456088 -108.474764)
		(width 0.15494)
		(layer "In5.Cu")
		(net "SMB_BIC_I2C6_MUX_PEX_ADC_SCL")
	)
	(segment
		(start 429.456088 -100.485702)
		(end 435.810914 -94.130876)
		(width 0.15494)
		(layer "In5.Cu")
		(net "SMB_BIC_I2C6_MUX_PEX_ADC_SCL")
	)
	(segment
		(start 435.810914 -119.671846)
		(end 433.30114 -117.162072)
		(width 0.15494)
		(layer "In5.Cu")
		(net "SMB_BIC_I2C6_MUX_PEX_ADC_SCL")
	)
	(segment
		(start 465.68741 -253.624588)
		(end 464.790282 -252.72746)
		(width 0.15494)
		(layer "In5.Cu")
		(net "SMB_BIC_I2C6_MUX_PEX_ADC_SCL")
	)
	(segment
		(start 464.790282 -252.72746)
		(end 456.120246 -252.72746)
		(width 0.15494)
		(layer "In5.Cu")
		(net "SMB_BIC_I2C6_MUX_PEX_ADC_SCL")
	)
	(segment
		(start 456.120246 -252.72746)
		(end 454.428098 -251.035312)
		(width 0.15494)
		(layer "In5.Cu")
		(net "SMB_BIC_I2C6_MUX_PEX_ADC_SCL")
	)
	(segment
		(start 435.810914 -94.130876)
		(end 435.810914 -86.641432)
		(width 0.15494)
		(layer "In5.Cu")
		(net "SMB_BIC_I2C6_MUX_PEX_ADC_SCL")
	)
	(segment
		(start 465.68741 -277.06955)
		(end 465.68741 -253.624588)
		(width 0.15494)
		(layer "In5.Cu")
		(net "SMB_BIC_I2C6_MUX_PEX_ADC_SCL")
	)
	(segment
		(start 441.77204 -135.639556)
		(end 436.584852 -130.452368)
		(width 0.15494)
		(layer "In5.Cu")
		(net "SMB_BIC_I2C6_MUX_PEX_ADC_SCL")
	)
	(segment
		(start 441.974986 -238.553498)
		(end 441.974986 -233.663744)
		(width 0.15494)
		(layer "In5.Cu")
		(net "SMB_BIC_I2C6_MUX_PEX_ADC_SCL")
	)
	(segment
		(start 454.428098 -251.035312)
		(end 451.720712 -251.035312)
		(width 0.15494)
		(layer "In5.Cu")
		(net "SMB_BIC_I2C6_MUX_PEX_ADC_SCL")
	)
	(segment
		(start 450.9262 -247.504712)
		(end 441.974986 -238.553498)
		(width 0.15494)
		(layer "In5.Cu")
		(net "SMB_BIC_I2C6_MUX_PEX_ADC_SCL")
	)
	(segment
		(start 441.77204 -233.460798)
		(end 441.77204 -135.639556)
		(width 0.15494)
		(layer "In5.Cu")
		(net "SMB_BIC_I2C6_MUX_PEX_ADC_SCL")
	)
	(segment
		(start 464.381088 -278.375872)
		(end 465.68741 -277.06955)
		(width 0.15494)
		(layer "In5.Cu")
		(net "SMB_BIC_I2C6_MUX_PEX_ADC_SCL")
	)
	(segment
		(start 435.810914 -128.58496)
		(end 435.810914 -119.671846)
		(width 0.15494)
		(layer "In5.Cu")
		(net "SMB_BIC_I2C6_MUX_PEX_ADC_SCL")
	)
	(segment
		(start 436.584852 -130.452368)
		(end 435.810914 -128.58496)
		(width 0.15494)
		(layer "In5.Cu")
		(net "SMB_BIC_I2C6_MUX_PEX_ADC_SCL")
	)
	(segment
		(start 429.456088 -108.474764)
		(end 429.456088 -100.485702)
		(width 0.15494)
		(layer "In5.Cu")
		(net "SMB_BIC_I2C6_MUX_PEX_ADC_SCL")
	)
	(segment
		(start 451.720712 -251.035312)
		(end 450.9262 -250.2408)
		(width 0.15494)
		(layer "In5.Cu")
		(net "SMB_BIC_I2C6_MUX_PEX_ADC_SCL")
	)
	(segment
		(start 397.954246 -84.616036)
		(end 397.954246 -84.968842)
		(width 0.15494)
		(layer "In15.Cu")
		(net "SMB_BIC_I2C6_MUX_PEX_ADC_SCL")
	)
	(segment
		(start 434.65496 -85.894672)
		(end 433.751482 -86.79815)
		(width 0.15494)
		(layer "In15.Cu")
		(net "SMB_BIC_I2C6_MUX_PEX_ADC_SCL")
	)
	(segment
		(start 397.388334 -85.534754)
		(end 396.286736 -85.534754)
		(width 0.15494)
		(layer "In15.Cu")
		(net "SMB_BIC_I2C6_MUX_PEX_ADC_SCL")
	)
	(segment
		(start 433.751482 -86.79815)
		(end 428.055532 -86.79815)
		(width 0.15494)
		(layer "In15.Cu")
		(net "SMB_BIC_I2C6_MUX_PEX_ADC_SCL")
	)
	(segment
		(start 400.410426 -82.159856)
		(end 397.954246 -84.616036)
		(width 0.15494)
		(layer "In15.Cu")
		(net "SMB_BIC_I2C6_MUX_PEX_ADC_SCL")
	)
	(segment
		(start 395.717776 -86.103714)
		(end 392.811254 -86.103714)
		(width 0.15494)
		(layer "In15.Cu")
		(net "SMB_BIC_I2C6_MUX_PEX_ADC_SCL")
	)
	(segment
		(start 426.600874 -85.343492)
		(end 425.212256 -85.343492)
		(width 0.15494)
		(layer "In15.Cu")
		(net "SMB_BIC_I2C6_MUX_PEX_ADC_SCL")
	)
	(segment
		(start 396.286736 -85.534754)
		(end 395.717776 -86.103714)
		(width 0.15494)
		(layer "In15.Cu")
		(net "SMB_BIC_I2C6_MUX_PEX_ADC_SCL")
	)
	(segment
		(start 390.71804 -84.0105)
		(end 382.90373 -84.0105)
		(width 0.15494)
		(layer "In15.Cu")
		(net "SMB_BIC_I2C6_MUX_PEX_ADC_SCL")
	)
	(segment
		(start 419.747446 -83.911186)
		(end 417.996116 -82.159856)
		(width 0.15494)
		(layer "In15.Cu")
		(net "SMB_BIC_I2C6_MUX_PEX_ADC_SCL")
	)
	(segment
		(start 428.055532 -86.79815)
		(end 426.600874 -85.343492)
		(width 0.15494)
		(layer "In15.Cu")
		(net "SMB_BIC_I2C6_MUX_PEX_ADC_SCL")
	)
	(segment
		(start 435.84622 -86.606126)
		(end 435.134766 -85.894672)
		(width 0.15494)
		(layer "In15.Cu")
		(net "SMB_BIC_I2C6_MUX_PEX_ADC_SCL")
	)
	(segment
		(start 435.134766 -85.894672)
		(end 434.65496 -85.894672)
		(width 0.15494)
		(layer "In15.Cu")
		(net "SMB_BIC_I2C6_MUX_PEX_ADC_SCL")
	)
	(segment
		(start 425.212256 -85.343492)
		(end 423.77995 -83.911186)
		(width 0.15494)
		(layer "In15.Cu")
		(net "SMB_BIC_I2C6_MUX_PEX_ADC_SCL")
	)
	(segment
		(start 423.77995 -83.911186)
		(end 419.747446 -83.911186)
		(width 0.15494)
		(layer "In15.Cu")
		(net "SMB_BIC_I2C6_MUX_PEX_ADC_SCL")
	)
	(segment
		(start 397.954246 -84.968842)
		(end 397.388334 -85.534754)
		(width 0.15494)
		(layer "In15.Cu")
		(net "SMB_BIC_I2C6_MUX_PEX_ADC_SCL")
	)
	(segment
		(start 392.811254 -86.103714)
		(end 390.71804 -84.0105)
		(width 0.15494)
		(layer "In15.Cu")
		(net "SMB_BIC_I2C6_MUX_PEX_ADC_SCL")
	)
	(segment
		(start 382.90373 -84.0105)
		(end 381.427736 -85.486494)
		(width 0.15494)
		(layer "In15.Cu")
		(net "SMB_BIC_I2C6_MUX_PEX_ADC_SCL")
	)
	(segment
		(start 417.996116 -82.159856)
		(end 400.410426 -82.159856)
		(width 0.15494)
		(layer "In15.Cu")
		(net "SMB_BIC_I2C6_MUX_PEX_ADC_SCL")
	)
	(via
		(at 181.102508 -416.023298)
		(size 0.6604)
		(drill 0.3302)
		(layers "F.Cu" "B.Cu")
		(net "GPU_RSVD_PARTNER0")
	)
	(segment
		(start 180.66385 -402.087588)
		(end 180.066442 -401.49018)
		(width 0.13208)
		(layer "B.Cu")
		(net "GPU_RSVD_PARTNER0")
	)
	(segment
		(start 181.102508 -415.062162)
		(end 180.66385 -414.623504)
		(width 0.13208)
		(layer "B.Cu")
		(net "GPU_RSVD_PARTNER0")
	)
	(segment
		(start 181.102508 -416.023298)
		(end 181.102508 -415.062162)
		(width 0.13208)
		(layer "B.Cu")
		(net "GPU_RSVD_PARTNER0")
	)
	(segment
		(start 180.66385 -414.623504)
		(end 180.66385 -402.087588)
		(width 0.13208)
		(layer "B.Cu")
		(net "GPU_RSVD_PARTNER0")
	)
	(segment
		(start 180.066442 -401.49018)
		(end 179.71008 -401.49018)
		(width 0.13208)
		(layer "B.Cu")
		(net "GPU_RSVD_PARTNER0")
	)
	(segment
		(start 238.375952 -232.943908)
		(end 237.903512 -232.471468)
		(width 0.13208)
		(layer "F.Cu")
		(net "SSD5_PWRDIS_BIC_R")
	)
	(segment
		(start 346.093796 -215.187022)
		(end 346.493592 -214.787226)
		(width 0.13208)
		(layer "F.Cu")
		(net "SSD5_PWRDIS_BIC_R")
	)
	(segment
		(start 238.375952 -233.439716)
		(end 238.375952 -232.943908)
		(width 0.13208)
		(layer "F.Cu")
		(net "SSD5_PWRDIS_BIC_R")
	)
	(segment
		(start 237.903512 -234.327954)
		(end 237.903512 -233.912156)
		(width 0.13208)
		(layer "F.Cu")
		(net "SSD5_PWRDIS_BIC_R")
	)
	(segment
		(start 237.903512 -232.471468)
		(end 237.903512 -231.816656)
		(width 0.13208)
		(layer "F.Cu")
		(net "SSD5_PWRDIS_BIC_R")
	)
	(segment
		(start 237.903512 -233.912156)
		(end 238.375952 -233.439716)
		(width 0.13208)
		(layer "F.Cu")
		(net "SSD5_PWRDIS_BIC_R")
	)
	(via
		(at 265.02995 -211.0232)
		(size 0.508)
		(drill 0.254)
		(layers "F.Cu" "B.Cu")
		(net "SSD5_PWRDIS_BIC_R")
	)
	(via
		(at 237.903512 -232.471468)
		(size 0.508)
		(drill 0.254)
		(layers "F.Cu" "B.Cu")
		(net "SSD5_PWRDIS_BIC_R")
	)
	(via
		(at 346.493592 -214.787226)
		(size 0.4572)
		(drill 0.254)
		(layers "F.Cu" "B.Cu")
		(net "SSD5_PWRDIS_BIC_R")
	)
	(segment
		(start 252.63348 -219.520008)
		(end 252.63348 -214.77605)
		(width 0.15494)
		(layer "In7.Cu")
		(net "SSD5_PWRDIS_BIC_R")
	)
	(segment
		(start 256.3114 -213.2584)
		(end 257.048 -213.2584)
		(width 0.15494)
		(layer "In7.Cu")
		(net "SSD5_PWRDIS_BIC_R")
	)
	(segment
		(start 262.509 -211.0232)
		(end 265.02995 -211.0232)
		(width 0.15494)
		(layer "In7.Cu")
		(net "SSD5_PWRDIS_BIC_R")
	)
	(segment
		(start 257.048 -213.2584)
		(end 257.302 -213.5124)
		(width 0.15494)
		(layer "In7.Cu")
		(net "SSD5_PWRDIS_BIC_R")
	)
	(segment
		(start 257.302 -213.5124)
		(end 260.0198 -213.5124)
		(width 0.15494)
		(layer "In7.Cu")
		(net "SSD5_PWRDIS_BIC_R")
	)
	(segment
		(start 255.8796 -213.6902)
		(end 256.3114 -213.2584)
		(width 0.15494)
		(layer "In7.Cu")
		(net "SSD5_PWRDIS_BIC_R")
	)
	(segment
		(start 237.903512 -232.471468)
		(end 238.87938 -231.4956)
		(width 0.15494)
		(layer "In7.Cu")
		(net "SSD5_PWRDIS_BIC_R")
	)
	(segment
		(start 260.0198 -213.5124)
		(end 262.509 -211.0232)
		(width 0.15494)
		(layer "In7.Cu")
		(net "SSD5_PWRDIS_BIC_R")
	)
	(segment
		(start 253.71933 -213.6902)
		(end 255.8796 -213.6902)
		(width 0.15494)
		(layer "In7.Cu")
		(net "SSD5_PWRDIS_BIC_R")
	)
	(segment
		(start 241.9604 -231.4956)
		(end 243.6368 -229.8192)
		(width 0.15494)
		(layer "In7.Cu")
		(net "SSD5_PWRDIS_BIC_R")
	)
	(segment
		(start 250.103386 -223.556068)
		(end 250.103386 -222.050102)
		(width 0.15494)
		(layer "In7.Cu")
		(net "SSD5_PWRDIS_BIC_R")
	)
	(segment
		(start 247.424194 -226.23526)
		(end 250.103386 -223.556068)
		(width 0.15494)
		(layer "In7.Cu")
		(net "SSD5_PWRDIS_BIC_R")
	)
	(segment
		(start 250.103386 -222.050102)
		(end 252.63348 -219.520008)
		(width 0.15494)
		(layer "In7.Cu")
		(net "SSD5_PWRDIS_BIC_R")
	)
	(segment
		(start 252.63348 -214.77605)
		(end 253.71933 -213.6902)
		(width 0.15494)
		(layer "In7.Cu")
		(net "SSD5_PWRDIS_BIC_R")
	)
	(segment
		(start 238.87938 -231.4956)
		(end 241.9604 -231.4956)
		(width 0.15494)
		(layer "In7.Cu")
		(net "SSD5_PWRDIS_BIC_R")
	)
	(segment
		(start 246.218964 -226.23526)
		(end 247.424194 -226.23526)
		(width 0.15494)
		(layer "In7.Cu")
		(net "SSD5_PWRDIS_BIC_R")
	)
	(segment
		(start 243.6368 -229.8192)
		(end 243.6368 -228.817424)
		(width 0.15494)
		(layer "In7.Cu")
		(net "SSD5_PWRDIS_BIC_R")
	)
	(segment
		(start 243.6368 -228.817424)
		(end 246.218964 -226.23526)
		(width 0.15494)
		(layer "In7.Cu")
		(net "SSD5_PWRDIS_BIC_R")
	)
	(segment
		(start 298.243244 -207.250538)
		(end 299.861224 -205.632558)
		(width 0.15494)
		(layer "In15.Cu")
		(net "SSD5_PWRDIS_BIC_R")
	)
	(segment
		(start 345.296236 -211.413344)
		(end 345.301316 -211.418424)
		(width 0.15494)
		(layer "In15.Cu")
		(net "SSD5_PWRDIS_BIC_R")
	)
	(segment
		(start 343.14638 -208.268824)
		(end 343.1667 -208.289144)
		(width 0.15494)
		(layer "In15.Cu")
		(net "SSD5_PWRDIS_BIC_R")
	)
	(segment
		(start 328.318622 -203.858622)
		(end 328.318622 -206.274924)
		(width 0.15494)
		(layer "In15.Cu")
		(net "SSD5_PWRDIS_BIC_R")
	)
	(segment
		(start 346.096082 -214.389716)
		(end 346.493592 -214.787226)
		(width 0.0889)
		(layer "In15.Cu")
		(net "SSD5_PWRDIS_BIC_R")
	)
	(segment
		(start 283.818584 -210.462114)
		(end 287.03016 -207.250538)
		(width 0.15494)
		(layer "In15.Cu")
		(net "SSD5_PWRDIS_BIC_R")
	)
	(segment
		(start 345.296236 -211.828634)
		(end 345.296236 -214.151972)
		(width 0.0889)
		(layer "In15.Cu")
		(net "SSD5_PWRDIS_BIC_R")
	)
	(segment
		(start 328.318622 -206.274924)
		(end 329.147678 -207.10398)
		(width 0.15494)
		(layer "In15.Cu")
		(net "SSD5_PWRDIS_BIC_R")
	)
	(segment
		(start 299.861224 -205.632558)
		(end 324.414642 -205.632558)
		(width 0.15494)
		(layer "In15.Cu")
		(net "SSD5_PWRDIS_BIC_R")
	)
	(segment
		(start 344.449654 -209.572098)
		(end 344.469974 -209.592418)
		(width 0.15494)
		(layer "In15.Cu")
		(net "SSD5_PWRDIS_BIC_R")
	)
	(segment
		(start 344.449654 -209.359246)
		(end 344.449654 -209.572098)
		(width 0.15494)
		(layer "In15.Cu")
		(net "SSD5_PWRDIS_BIC_R")
	)
	(segment
		(start 343.379552 -208.289144)
		(end 344.449654 -209.359246)
		(width 0.15494)
		(layer "In15.Cu")
		(net "SSD5_PWRDIS_BIC_R")
	)
	(segment
		(start 332.064106 -206.413608)
		(end 332.079346 -206.407258)
		(width 0.15494)
		(layer "In15.Cu")
		(net "SSD5_PWRDIS_BIC_R")
	)
	(segment
		(start 265.591036 -210.462114)
		(end 283.818584 -210.462114)
		(width 0.15494)
		(layer "In15.Cu")
		(net "SSD5_PWRDIS_BIC_R")
	)
	(segment
		(start 334.540098 -206.011526)
		(end 334.540098 -206.651098)
		(width 0.15494)
		(layer "In15.Cu")
		(net "SSD5_PWRDIS_BIC_R")
	)
	(segment
		(start 345.301316 -211.756244)
		(end 345.296236 -211.761324)
		(width 0.15494)
		(layer "In15.Cu")
		(net "SSD5_PWRDIS_BIC_R")
	)
	(segment
		(start 331.373734 -207.10398)
		(end 332.064106 -206.413608)
		(width 0.15494)
		(layer "In15.Cu")
		(net "SSD5_PWRDIS_BIC_R")
	)
	(segment
		(start 326.644 -203.4032)
		(end 327.8632 -203.4032)
		(width 0.15494)
		(layer "In15.Cu")
		(net "SSD5_PWRDIS_BIC_R")
	)
	(segment
		(start 334.49387 -205.965298)
		(end 334.540098 -206.011526)
		(width 0.15494)
		(layer "In15.Cu")
		(net "SSD5_PWRDIS_BIC_R")
	)
	(segment
		(start 345.296236 -211.761324)
		(end 345.296236 -211.828634)
		(width 0.15494)
		(layer "In15.Cu")
		(net "SSD5_PWRDIS_BIC_R")
	)
	(segment
		(start 329.147678 -207.10398)
		(end 331.373734 -207.10398)
		(width 0.15494)
		(layer "In15.Cu")
		(net "SSD5_PWRDIS_BIC_R")
	)
	(segment
		(start 345.296236 -211.362036)
		(end 345.296236 -211.413344)
		(width 0.15494)
		(layer "In15.Cu")
		(net "SSD5_PWRDIS_BIC_R")
	)
	(segment
		(start 334.21066 -205.66761)
		(end 334.49387 -205.95082)
		(width 0.15494)
		(layer "In15.Cu")
		(net "SSD5_PWRDIS_BIC_R")
	)
	(segment
		(start 334.49387 -205.95082)
		(end 334.49387 -205.965298)
		(width 0.15494)
		(layer "In15.Cu")
		(net "SSD5_PWRDIS_BIC_R")
	)
	(segment
		(start 336.157824 -208.268824)
		(end 343.14638 -208.268824)
		(width 0.15494)
		(layer "In15.Cu")
		(net "SSD5_PWRDIS_BIC_R")
	)
	(segment
		(start 265.02995 -211.0232)
		(end 265.591036 -210.462114)
		(width 0.15494)
		(layer "In15.Cu")
		(net "SSD5_PWRDIS_BIC_R")
	)
	(segment
		(start 287.03016 -207.250538)
		(end 298.243244 -207.250538)
		(width 0.15494)
		(layer "In15.Cu")
		(net "SSD5_PWRDIS_BIC_R")
	)
	(segment
		(start 333.605124 -205.67777)
		(end 333.79918 -205.67777)
		(width 0.15494)
		(layer "In15.Cu")
		(net "SSD5_PWRDIS_BIC_R")
	)
	(segment
		(start 334.540098 -206.651098)
		(end 336.157824 -208.268824)
		(width 0.15494)
		(layer "In15.Cu")
		(net "SSD5_PWRDIS_BIC_R")
	)
	(segment
		(start 344.469974 -209.592418)
		(end 344.469974 -210.535774)
		(width 0.15494)
		(layer "In15.Cu")
		(net "SSD5_PWRDIS_BIC_R")
	)
	(segment
		(start 343.1667 -208.289144)
		(end 343.379552 -208.289144)
		(width 0.15494)
		(layer "In15.Cu")
		(net "SSD5_PWRDIS_BIC_R")
	)
	(segment
		(start 332.31709 -206.211424)
		(end 333.605124 -205.67777)
		(width 0.15494)
		(layer "In15.Cu")
		(net "SSD5_PWRDIS_BIC_R")
	)
	(segment
		(start 333.79918 -205.67777)
		(end 333.80934 -205.66761)
		(width 0.15494)
		(layer "In15.Cu")
		(net "SSD5_PWRDIS_BIC_R")
	)
	(segment
		(start 345.301316 -211.418424)
		(end 345.301316 -211.756244)
		(width 0.15494)
		(layer "In15.Cu")
		(net "SSD5_PWRDIS_BIC_R")
	)
	(segment
		(start 344.469974 -210.535774)
		(end 345.296236 -211.362036)
		(width 0.15494)
		(layer "In15.Cu")
		(net "SSD5_PWRDIS_BIC_R")
	)
	(segment
		(start 324.414642 -205.632558)
		(end 326.644 -203.4032)
		(width 0.15494)
		(layer "In15.Cu")
		(net "SSD5_PWRDIS_BIC_R")
	)
	(segment
		(start 332.27518 -206.211424)
		(end 332.31709 -206.211424)
		(width 0.15494)
		(layer "In15.Cu")
		(net "SSD5_PWRDIS_BIC_R")
	)
	(segment
		(start 327.8632 -203.4032)
		(end 328.318622 -203.858622)
		(width 0.15494)
		(layer "In15.Cu")
		(net "SSD5_PWRDIS_BIC_R")
	)
	(segment
		(start 332.079346 -206.407258)
		(end 332.27518 -206.211424)
		(width 0.15494)
		(layer "In15.Cu")
		(net "SSD5_PWRDIS_BIC_R")
	)
	(segment
		(start 333.80934 -205.66761)
		(end 334.21066 -205.66761)
		(width 0.15494)
		(layer "In15.Cu")
		(net "SSD5_PWRDIS_BIC_R")
	)
	(segment
		(start 345.296236 -214.151972)
		(end 345.53398 -214.389716)
		(width 0.0889)
		(layer "In15.Cu")
		(net "SSD5_PWRDIS_BIC_R")
	)
	(segment
		(start 345.53398 -214.389716)
		(end 346.096082 -214.389716)
		(width 0.0889)
		(layer "In15.Cu")
		(net "SSD5_PWRDIS_BIC_R")
	)
	(segment
		(start 66.299842 -282.599892)
		(end 66.774822 -283.074872)
		(width 0.13208)
		(layer "F.Cu")
		(net "PEX0_MODE_SEL12")
	)
	(segment
		(start 35.518344 -251.158502)
		(end 35.518344 -251.956824)
		(width 0.13208)
		(layer "F.Cu")
		(net "PEX0_MODE_SEL12")
	)
	(segment
		(start 35.518344 -250.470924)
		(end 35.518344 -251.158502)
		(width 0.13208)
		(layer "F.Cu")
		(net "PEX0_MODE_SEL12")
	)
	(via
		(at 35.518344 -251.158502)
		(size 0.508)
		(drill 0.254)
		(layers "F.Cu" "B.Cu")
		(net "PEX0_MODE_SEL12")
	)
	(via
		(at 63.54191 -268.169898)
		(size 0.6604)
		(drill 0.3302)
		(layers "F.Cu" "B.Cu")
		(net "PEX0_MODE_SEL12")
	)
	(via
		(at 66.774822 -283.074872)
		(size 0.4064)
		(drill 0.2032)
		(layers "F.Cu" "B.Cu")
		(net "PEX0_MODE_SEL12")
	)
	(segment
		(start 36.425378 -255.4224)
		(end 50.794412 -255.4224)
		(width 0.13208)
		(layer "B.Cu")
		(net "PEX0_MODE_SEL12")
	)
	(segment
		(start 67.078606 -271.706594)
		(end 63.54191 -268.169898)
		(width 0.13208)
		(layer "B.Cu")
		(net "PEX0_MODE_SEL12")
	)
	(segment
		(start 67.363594 -271.706594)
		(end 67.078606 -271.706594)
		(width 0.13208)
		(layer "B.Cu")
		(net "PEX0_MODE_SEL12")
	)
	(segment
		(start 50.794412 -255.4224)
		(end 63.54191 -268.169898)
		(width 0.13208)
		(layer "B.Cu")
		(net "PEX0_MODE_SEL12")
	)
	(segment
		(start 67.692524 -281.875738)
		(end 67.692524 -272.035524)
		(width 0.13208)
		(layer "B.Cu")
		(net "PEX0_MODE_SEL12")
	)
	(segment
		(start 67.692524 -272.035524)
		(end 67.363594 -271.706594)
		(width 0.13208)
		(layer "B.Cu")
		(net "PEX0_MODE_SEL12")
	)
	(segment
		(start 66.774822 -282.79344)
		(end 67.692524 -281.875738)
		(width 0.13208)
		(layer "B.Cu")
		(net "PEX0_MODE_SEL12")
	)
	(segment
		(start 35.518344 -251.158502)
		(end 35.008566 -251.66828)
		(width 0.13208)
		(layer "B.Cu")
		(net "PEX0_MODE_SEL12")
	)
	(segment
		(start 35.008566 -254.005588)
		(end 36.425378 -255.4224)
		(width 0.13208)
		(layer "B.Cu")
		(net "PEX0_MODE_SEL12")
	)
	(segment
		(start 66.774822 -283.074872)
		(end 66.774822 -282.79344)
		(width 0.13208)
		(layer "B.Cu")
		(net "PEX0_MODE_SEL12")
	)
	(segment
		(start 35.008566 -251.66828)
		(end 35.008566 -254.005588)
		(width 0.13208)
		(layer "B.Cu")
		(net "PEX0_MODE_SEL12")
	)
	(segment
		(start 206.732886 -310.277002)
		(end 206.732886 -310.043322)
		(width 0.13208)
		(layer "F.Cu")
		(net "PEX1_SPARE0")
	)
	(segment
		(start 177.174906 -308.724808)
		(end 176.699926 -308.249828)
		(width 0.13208)
		(layer "F.Cu")
		(net "PEX1_SPARE0")
	)
	(segment
		(start 206.064866 -310.945022)
		(end 206.324708 -310.68518)
		(width 0.13208)
		(layer "F.Cu")
		(net "PEX1_SPARE0")
	)
	(segment
		(start 205.597506 -310.945022)
		(end 206.064866 -310.945022)
		(width 0.13208)
		(layer "F.Cu")
		(net "PEX1_SPARE0")
	)
	(segment
		(start 206.324708 -310.68518)
		(end 206.732886 -310.277002)
		(width 0.13208)
		(layer "F.Cu")
		(net "PEX1_SPARE0")
	)
	(via
		(at 203.266548 -314.33389)
		(size 0.6604)
		(drill 0.3302)
		(layers "F.Cu" "B.Cu")
		(net "PEX1_SPARE0")
	)
	(via
		(at 206.324708 -310.68518)
		(size 0.508)
		(drill 0.254)
		(layers "F.Cu" "B.Cu")
		(net "PEX1_SPARE0")
	)
	(via
		(at 177.174906 -308.724808)
		(size 0.4064)
		(drill 0.2032)
		(layers "F.Cu" "B.Cu")
		(net "PEX1_SPARE0")
	)
	(segment
		(start 178.13782 -309.980584)
		(end 178.13782 -315.252862)
		(width 0.13208)
		(layer "B.Cu")
		(net "PEX1_SPARE0")
	)
	(segment
		(start 178.26482 -315.379862)
		(end 202.220576 -315.379862)
		(width 0.13208)
		(layer "B.Cu")
		(net "PEX1_SPARE0")
	)
	(segment
		(start 177.174906 -309.28818)
		(end 177.626772 -309.740046)
		(width 0.13208)
		(layer "B.Cu")
		(net "PEX1_SPARE0")
	)
	(segment
		(start 202.220576 -315.379862)
		(end 203.266548 -314.33389)
		(width 0.13208)
		(layer "B.Cu")
		(net "PEX1_SPARE0")
	)
	(segment
		(start 206.324708 -311.27573)
		(end 206.324708 -310.68518)
		(width 0.13208)
		(layer "B.Cu")
		(net "PEX1_SPARE0")
	)
	(segment
		(start 177.897282 -309.740046)
		(end 178.13782 -309.980584)
		(width 0.13208)
		(layer "B.Cu")
		(net "PEX1_SPARE0")
	)
	(segment
		(start 178.13782 -315.252862)
		(end 178.26482 -315.379862)
		(width 0.13208)
		(layer "B.Cu")
		(net "PEX1_SPARE0")
	)
	(segment
		(start 203.266548 -314.33389)
		(end 206.324708 -311.27573)
		(width 0.13208)
		(layer "B.Cu")
		(net "PEX1_SPARE0")
	)
	(segment
		(start 177.626772 -309.740046)
		(end 177.897282 -309.740046)
		(width 0.13208)
		(layer "B.Cu")
		(net "PEX1_SPARE0")
	)
	(segment
		(start 177.174906 -308.724808)
		(end 177.174906 -309.28818)
		(width 0.13208)
		(layer "B.Cu")
		(net "PEX1_SPARE0")
	)
	(segment
		(start 50.024284 -18.437098)
		(end 50.067972 -18.437098)
		(width 0.13208)
		(layer "F.Cu")
		(net "SMB_ISO_SSD1_SCL")
	)
	(segment
		(start 50.621692 -18.990818)
		(end 50.067972 -18.437098)
		(width 0.13208)
		(layer "F.Cu")
		(net "SMB_ISO_SSD1_SCL")
	)
	(segment
		(start 51.799236 -18.990818)
		(end 50.621692 -18.990818)
		(width 0.13208)
		(layer "F.Cu")
		(net "SMB_ISO_SSD1_SCL")
	)
	(segment
		(start 52.285392 -16.439388)
		(end 52.285392 -18.504662)
		(width 0.13208)
		(layer "F.Cu")
		(net "SMB_ISO_SSD1_SCL")
	)
	(segment
		(start 52.285392 -18.504662)
		(end 51.799236 -18.990818)
		(width 0.13208)
		(layer "F.Cu")
		(net "SMB_ISO_SSD1_SCL")
	)
	(segment
		(start 49.256442 -17.669256)
		(end 50.024284 -18.437098)
		(width 0.13208)
		(layer "F.Cu")
		(net "SMB_ISO_SSD1_SCL")
	)
	(segment
		(start 52.459382 -23.355554)
		(end 52.459382 -23.965154)
		(width 0.13208)
		(layer "F.Cu")
		(net "SMB_ISO_SSD1_SCL")
	)
	(segment
		(start 49.256442 -17.419574)
		(end 49.256442 -17.669256)
		(width 0.13208)
		(layer "F.Cu")
		(net "SMB_ISO_SSD1_SCL")
	)
	(segment
		(start 52.285392 -16.439388)
		(end 52.285392 -15.370302)
		(width 0.13208)
		(layer "F.Cu")
		(net "SMB_ISO_SSD1_SCL")
	)
	(via
		(at 52.459382 -23.965154)
		(size 0.508)
		(drill 0.254)
		(layers "F.Cu" "B.Cu")
		(net "SMB_ISO_SSD1_SCL")
	)
	(via
		(at 52.285392 -15.370302)
		(size 0.508)
		(drill 0.254)
		(layers "F.Cu" "B.Cu")
		(net "SMB_ISO_SSD1_SCL")
	)
	(segment
		(start 53.725064 -22.699472)
		(end 52.459382 -23.965154)
		(width 0.13208)
		(layer "B.Cu")
		(net "SMB_ISO_SSD1_SCL")
	)
	(segment
		(start 53.725064 -17.597374)
		(end 53.725064 -22.699472)
		(width 0.13208)
		(layer "B.Cu")
		(net "SMB_ISO_SSD1_SCL")
	)
	(segment
		(start 52.285392 -16.157702)
		(end 53.725064 -17.597374)
		(width 0.13208)
		(layer "B.Cu")
		(net "SMB_ISO_SSD1_SCL")
	)
	(segment
		(start 52.285392 -15.370302)
		(end 52.285392 -16.157702)
		(width 0.13208)
		(layer "B.Cu")
		(net "SMB_ISO_SSD1_SCL")
	)
	(segment
		(start 436.964836 -22.990048)
		(end 438.009284 -22.990048)
		(width 0.13208)
		(layer "F.Cu")
		(net "SMB_ISO_SSD15_R_SDA")
	)
	(segment
		(start 438.009284 -22.990048)
		(end 438.044336 -23.0251)
		(width 0.13208)
		(layer "F.Cu")
		(net "SMB_ISO_SSD15_R_SDA")
	)
	(segment
		(start 448.958208 -19.453098)
		(end 449.567808 -19.453098)
		(width 0.13208)
		(layer "F.Cu")
		(net "SMB_ISO_SSD15_R_SDA")
	)
	(via
		(at 448.958208 -19.453098)
		(size 0.508)
		(drill 0.254)
		(layers "F.Cu" "B.Cu")
		(net "SMB_ISO_SSD15_R_SDA")
	)
	(via
		(at 438.044336 -23.0251)
		(size 0.508)
		(drill 0.254)
		(layers "F.Cu" "B.Cu")
		(net "SMB_ISO_SSD15_R_SDA")
	)
	(segment
		(start 438.537096 -22.53234)
		(end 438.044336 -23.0251)
		(width 0.15494)
		(layer "In5.Cu")
		(net "SMB_ISO_SSD15_R_SDA")
	)
	(segment
		(start 447.816224 -22.53234)
		(end 438.537096 -22.53234)
		(width 0.15494)
		(layer "In5.Cu")
		(net "SMB_ISO_SSD15_R_SDA")
	)
	(segment
		(start 448.958208 -21.390356)
		(end 447.816224 -22.53234)
		(width 0.15494)
		(layer "In5.Cu")
		(net "SMB_ISO_SSD15_R_SDA")
	)
	(segment
		(start 448.958208 -19.453098)
		(end 448.958208 -21.390356)
		(width 0.15494)
		(layer "In5.Cu")
		(net "SMB_ISO_SSD15_R_SDA")
	)
	(segment
		(start 232.244646 -280.583386)
		(end 232.854246 -280.583386)
		(width 0.13208)
		(layer "F.Cu")
		(net "SMB_BIC_I2C6_MUX_PEX_ADC_R_SCL")
	)
	(segment
		(start 252.473206 -261.58063)
		(end 251.92228 -261.029704)
		(width 0.13208)
		(layer "F.Cu")
		(net "SMB_BIC_I2C6_MUX_PEX_ADC_R_SCL")
	)
	(segment
		(start 462.865724 -280.70683)
		(end 463.221324 -280.70683)
		(width 0.13208)
		(layer "F.Cu")
		(net "SMB_BIC_I2C6_MUX_PEX_ADC_R_SCL")
	)
	(segment
		(start 251.17806 -280.02865)
		(end 252.473206 -278.733504)
		(width 0.13208)
		(layer "F.Cu")
		(net "SMB_BIC_I2C6_MUX_PEX_ADC_R_SCL")
	)
	(segment
		(start 249.90044 -280.573988)
		(end 249.891042 -280.583386)
		(width 0.13208)
		(layer "F.Cu")
		(net "SMB_BIC_I2C6_MUX_PEX_ADC_R_SCL")
	)
	(segment
		(start 93.31325 -239.728248)
		(end 94.034356 -239.728248)
		(width 0.13208)
		(layer "F.Cu")
		(net "SMB_BIC_I2C6_MUX_PEX_ADC_R_SCL")
	)
	(segment
		(start 464.381088 -280.922984)
		(end 463.51317 -280.922984)
		(width 0.13208)
		(layer "F.Cu")
		(net "SMB_BIC_I2C6_MUX_PEX_ADC_R_SCL")
	)
	(segment
		(start 252.473206 -278.733504)
		(end 252.473206 -261.58063)
		(width 0.13208)
		(layer "F.Cu")
		(net "SMB_BIC_I2C6_MUX_PEX_ADC_R_SCL")
	)
	(segment
		(start 250.445778 -280.02865)
		(end 251.17806 -280.02865)
		(width 0.13208)
		(layer "F.Cu")
		(net "SMB_BIC_I2C6_MUX_PEX_ADC_R_SCL")
	)
	(segment
		(start 251.92228 -261.029704)
		(end 251.92228 -259.905754)
		(width 0.13208)
		(layer "F.Cu")
		(net "SMB_BIC_I2C6_MUX_PEX_ADC_R_SCL")
	)
	(segment
		(start 249.104404 -280.583386)
		(end 248.494804 -280.583386)
		(width 0.13208)
		(layer "F.Cu")
		(net "SMB_BIC_I2C6_MUX_PEX_ADC_R_SCL")
	)
	(segment
		(start 463.51317 -280.922984)
		(end 463.475324 -280.96083)
		(width 0.13208)
		(layer "F.Cu")
		(net "SMB_BIC_I2C6_MUX_PEX_ADC_R_SCL")
	)
	(segment
		(start 249.891042 -280.583386)
		(end 249.104404 -280.583386)
		(width 0.13208)
		(layer "F.Cu")
		(net "SMB_BIC_I2C6_MUX_PEX_ADC_R_SCL")
	)
	(segment
		(start 93.228922 -239.64392)
		(end 93.31325 -239.728248)
		(width 0.13208)
		(layer "F.Cu")
		(net "SMB_BIC_I2C6_MUX_PEX_ADC_R_SCL")
	)
	(segment
		(start 251.92228 -259.905754)
		(end 251.428504 -258.713986)
		(width 0.13208)
		(layer "F.Cu")
		(net "SMB_BIC_I2C6_MUX_PEX_ADC_R_SCL")
	)
	(segment
		(start 464.381088 -280.922984)
		(end 464.381088 -279.935178)
		(width 0.13208)
		(layer "F.Cu")
		(net "SMB_BIC_I2C6_MUX_PEX_ADC_R_SCL")
	)
	(segment
		(start 249.90044 -280.573988)
		(end 250.445778 -280.02865)
		(width 0.13208)
		(layer "F.Cu")
		(net "SMB_BIC_I2C6_MUX_PEX_ADC_R_SCL")
	)
	(segment
		(start 463.221324 -280.70683)
		(end 463.475324 -280.96083)
		(width 0.13208)
		(layer "F.Cu")
		(net "SMB_BIC_I2C6_MUX_PEX_ADC_R_SCL")
	)
	(segment
		(start 251.428504 -258.713986)
		(end 251.01296 -258.298442)
		(width 0.13208)
		(layer "F.Cu")
		(net "SMB_BIC_I2C6_MUX_PEX_ADC_R_SCL")
	)
	(segment
		(start 94.705678 -239.728248)
		(end 94.034356 -239.728248)
		(width 0.13208)
		(layer "F.Cu")
		(net "SMB_BIC_I2C6_MUX_PEX_ADC_R_SCL")
	)
	(via
		(at 232.854246 -280.583386)
		(size 0.508)
		(drill 0.254)
		(layers "F.Cu" "B.Cu")
		(net "SMB_BIC_I2C6_MUX_PEX_ADC_R_SCL")
	)
	(via
		(at 230.849424 -258.489958)
		(size 0.508)
		(drill 0.254)
		(layers "F.Cu" "B.Cu")
		(net "SMB_BIC_I2C6_MUX_PEX_ADC_R_SCL")
	)
	(via
		(at 463.475324 -280.96083)
		(size 0.508)
		(drill 0.254)
		(layers "F.Cu" "B.Cu")
		(net "SMB_BIC_I2C6_MUX_PEX_ADC_R_SCL")
	)
	(via
		(at 94.034356 -239.728248)
		(size 0.508)
		(drill 0.254)
		(layers "F.Cu" "B.Cu")
		(net "SMB_BIC_I2C6_MUX_PEX_ADC_R_SCL")
	)
	(via
		(at 249.104404 -280.583386)
		(size 0.508)
		(drill 0.254)
		(layers "F.Cu" "B.Cu")
		(net "SMB_BIC_I2C6_MUX_PEX_ADC_R_SCL")
	)
	(via
		(at 251.01296 -258.298442)
		(size 0.508)
		(drill 0.254)
		(layers "F.Cu" "B.Cu")
		(net "SMB_BIC_I2C6_MUX_PEX_ADC_R_SCL")
	)
	(via
		(at 114.67084 -247.57253)
		(size 0.508)
		(drill 0.254)
		(layers "F.Cu" "B.Cu")
		(net "SMB_BIC_I2C6_MUX_PEX_ADC_R_SCL")
	)
	(segment
		(start 92.55379 -241.683286)
		(end 92.92717 -241.309906)
		(width 0.13208)
		(layer "B.Cu")
		(net "SMB_BIC_I2C6_MUX_PEX_ADC_R_SCL")
	)
	(segment
		(start 93.311472 -239.728248)
		(end 94.034356 -239.728248)
		(width 0.13208)
		(layer "B.Cu")
		(net "SMB_BIC_I2C6_MUX_PEX_ADC_R_SCL")
	)
	(segment
		(start 110.20806 -251.1806)
		(end 96.646746 -251.1806)
		(width 0.13208)
		(layer "B.Cu")
		(net "SMB_BIC_I2C6_MUX_PEX_ADC_R_SCL")
	)
	(segment
		(start 113.81613 -247.57253)
		(end 110.20806 -251.1806)
		(width 0.13208)
		(layer "B.Cu")
		(net "SMB_BIC_I2C6_MUX_PEX_ADC_R_SCL")
	)
	(segment
		(start 92.55379 -247.087644)
		(end 92.55379 -241.683286)
		(width 0.13208)
		(layer "B.Cu")
		(net "SMB_BIC_I2C6_MUX_PEX_ADC_R_SCL")
	)
	(segment
		(start 92.92717 -241.309906)
		(end 92.92717 -240.11255)
		(width 0.13208)
		(layer "B.Cu")
		(net "SMB_BIC_I2C6_MUX_PEX_ADC_R_SCL")
	)
	(segment
		(start 96.646746 -251.1806)
		(end 92.55379 -247.087644)
		(width 0.13208)
		(layer "B.Cu")
		(net "SMB_BIC_I2C6_MUX_PEX_ADC_R_SCL")
	)
	(segment
		(start 92.92717 -240.11255)
		(end 93.311472 -239.728248)
		(width 0.13208)
		(layer "B.Cu")
		(net "SMB_BIC_I2C6_MUX_PEX_ADC_R_SCL")
	)
	(segment
		(start 114.67084 -247.57253)
		(end 113.81613 -247.57253)
		(width 0.13208)
		(layer "B.Cu")
		(net "SMB_BIC_I2C6_MUX_PEX_ADC_R_SCL")
	)
	(segment
		(start 231.8004 -272.059146)
		(end 231.8004 -279.52954)
		(width 0.15494)
		(layer "In9.Cu")
		(net "SMB_BIC_I2C6_MUX_PEX_ADC_R_SCL")
	)
	(segment
		(start 246.733314 -280.37409)
		(end 248.895108 -280.37409)
		(width 0.15494)
		(layer "In9.Cu")
		(net "SMB_BIC_I2C6_MUX_PEX_ADC_R_SCL")
	)
	(segment
		(start 231.8004 -279.52954)
		(end 232.854246 -280.583386)
		(width 0.15494)
		(layer "In9.Cu")
		(net "SMB_BIC_I2C6_MUX_PEX_ADC_R_SCL")
	)
	(segment
		(start 234.046268 -280.583386)
		(end 234.441238 -280.746962)
		(width 0.15494)
		(layer "In9.Cu")
		(net "SMB_BIC_I2C6_MUX_PEX_ADC_R_SCL")
	)
	(segment
		(start 232.085896 -262.032496)
		(end 232.085896 -271.77365)
		(width 0.15494)
		(layer "In9.Cu")
		(net "SMB_BIC_I2C6_MUX_PEX_ADC_R_SCL")
	)
	(segment
		(start 232.085896 -271.77365)
		(end 231.8004 -272.059146)
		(width 0.15494)
		(layer "In9.Cu")
		(net "SMB_BIC_I2C6_MUX_PEX_ADC_R_SCL")
	)
	(segment
		(start 246.130826 -279.771602)
		(end 246.733314 -280.37409)
		(width 0.15494)
		(layer "In9.Cu")
		(net "SMB_BIC_I2C6_MUX_PEX_ADC_R_SCL")
	)
	(segment
		(start 230.1748 -259.164582)
		(end 230.1748 -260.1214)
		(width 0.15494)
		(layer "In9.Cu")
		(net "SMB_BIC_I2C6_MUX_PEX_ADC_R_SCL")
	)
	(segment
		(start 248.895108 -280.37409)
		(end 249.104404 -280.583386)
		(width 0.15494)
		(layer "In9.Cu")
		(net "SMB_BIC_I2C6_MUX_PEX_ADC_R_SCL")
	)
	(segment
		(start 234.441238 -280.746962)
		(end 243.466112 -280.746962)
		(width 0.15494)
		(layer "In9.Cu")
		(net "SMB_BIC_I2C6_MUX_PEX_ADC_R_SCL")
	)
	(segment
		(start 244.441472 -279.771602)
		(end 246.130826 -279.771602)
		(width 0.15494)
		(layer "In9.Cu")
		(net "SMB_BIC_I2C6_MUX_PEX_ADC_R_SCL")
	)
	(segment
		(start 232.854246 -280.583386)
		(end 234.046268 -280.583386)
		(width 0.15494)
		(layer "In9.Cu")
		(net "SMB_BIC_I2C6_MUX_PEX_ADC_R_SCL")
	)
	(segment
		(start 230.849424 -258.489958)
		(end 230.1748 -259.164582)
		(width 0.15494)
		(layer "In9.Cu")
		(net "SMB_BIC_I2C6_MUX_PEX_ADC_R_SCL")
	)
	(segment
		(start 230.1748 -260.1214)
		(end 232.085896 -262.032496)
		(width 0.15494)
		(layer "In9.Cu")
		(net "SMB_BIC_I2C6_MUX_PEX_ADC_R_SCL")
	)
	(segment
		(start 243.466112 -280.746962)
		(end 244.441472 -279.771602)
		(width 0.15494)
		(layer "In9.Cu")
		(net "SMB_BIC_I2C6_MUX_PEX_ADC_R_SCL")
	)
	(segment
		(start 115.590574 -246.652796)
		(end 137.149586 -246.652796)
		(width 0.15494)
		(layer "In13.Cu")
		(net "SMB_BIC_I2C6_MUX_PEX_ADC_R_SCL")
	)
	(segment
		(start 384.89128 -237.236)
		(end 385.722114 -236.405166)
		(width 0.15494)
		(layer "In13.Cu")
		(net "SMB_BIC_I2C6_MUX_PEX_ADC_R_SCL")
	)
	(segment
		(start 339.014054 -255.66878)
		(end 342.5571 -252.125734)
		(width 0.15494)
		(layer "In13.Cu")
		(net "SMB_BIC_I2C6_MUX_PEX_ADC_R_SCL")
	)
	(segment
		(start 169.5704 -257.175)
		(end 210.184746 -257.175)
		(width 0.15494)
		(layer "In13.Cu")
		(net "SMB_BIC_I2C6_MUX_PEX_ADC_R_SCL")
	)
	(segment
		(start 374.075198 -243.078)
		(end 377.351036 -243.078)
		(width 0.15494)
		(layer "In13.Cu")
		(net "SMB_BIC_I2C6_MUX_PEX_ADC_R_SCL")
	)
	(segment
		(start 380.614428 -239.814608)
		(end 380.614428 -238.104172)
		(width 0.15494)
		(layer "In13.Cu")
		(net "SMB_BIC_I2C6_MUX_PEX_ADC_R_SCL")
	)
	(segment
		(start 424.3578 -239.4712)
		(end 456.3872 -239.4712)
		(width 0.15494)
		(layer "In13.Cu")
		(net "SMB_BIC_I2C6_MUX_PEX_ADC_R_SCL")
	)
	(segment
		(start 266.686792 -257.9116)
		(end 298.759626 -257.9116)
		(width 0.15494)
		(layer "In13.Cu")
		(net "SMB_BIC_I2C6_MUX_PEX_ADC_R_SCL")
	)
	(segment
		(start 298.759626 -257.9116)
		(end 301.332646 -260.48462)
		(width 0.15494)
		(layer "In13.Cu")
		(net "SMB_BIC_I2C6_MUX_PEX_ADC_R_SCL")
	)
	(segment
		(start 456.3872 -239.4712)
		(end 463.78495 -246.86895)
		(width 0.15494)
		(layer "In13.Cu")
		(net "SMB_BIC_I2C6_MUX_PEX_ADC_R_SCL")
	)
	(segment
		(start 419.5064 -234.6198)
		(end 424.3578 -239.4712)
		(width 0.15494)
		(layer "In13.Cu")
		(net "SMB_BIC_I2C6_MUX_PEX_ADC_R_SCL")
	)
	(segment
		(start 158.4706 -249.51817)
		(end 158.4706 -257.555492)
		(width 0.15494)
		(layer "In13.Cu")
		(net "SMB_BIC_I2C6_MUX_PEX_ADC_R_SCL")
	)
	(segment
		(start 385.722114 -236.405166)
		(end 388.871714 -236.405166)
		(width 0.15494)
		(layer "In13.Cu")
		(net "SMB_BIC_I2C6_MUX_PEX_ADC_R_SCL")
	)
	(segment
		(start 259.039614 -257.6576)
		(end 266.432792 -257.6576)
		(width 0.15494)
		(layer "In13.Cu")
		(net "SMB_BIC_I2C6_MUX_PEX_ADC_R_SCL")
	)
	(segment
		(start 342.5571 -252.125734)
		(end 342.5571 -251.65304)
		(width 0.15494)
		(layer "In13.Cu")
		(net "SMB_BIC_I2C6_MUX_PEX_ADC_R_SCL")
	)
	(segment
		(start 137.149586 -246.652796)
		(end 138.33348 -247.83669)
		(width 0.15494)
		(layer "In13.Cu")
		(net "SMB_BIC_I2C6_MUX_PEX_ADC_R_SCL")
	)
	(segment
		(start 463.78495 -246.86895)
		(end 463.78495 -257.058414)
		(width 0.15494)
		(layer "In13.Cu")
		(net "SMB_BIC_I2C6_MUX_PEX_ADC_R_SCL")
	)
	(segment
		(start 214.763858 -255.745742)
		(end 216.342976 -257.32486)
		(width 0.15494)
		(layer "In13.Cu")
		(net "SMB_BIC_I2C6_MUX_PEX_ADC_R_SCL")
	)
	(segment
		(start 390.65708 -234.6198)
		(end 419.5064 -234.6198)
		(width 0.15494)
		(layer "In13.Cu")
		(net "SMB_BIC_I2C6_MUX_PEX_ADC_R_SCL")
	)
	(segment
		(start 138.33348 -247.83669)
		(end 149.322282 -247.83669)
		(width 0.15494)
		(layer "In13.Cu")
		(net "SMB_BIC_I2C6_MUX_PEX_ADC_R_SCL")
	)
	(segment
		(start 463.78495 -257.058414)
		(end 465.4296 -258.703064)
		(width 0.15494)
		(layer "In13.Cu")
		(net "SMB_BIC_I2C6_MUX_PEX_ADC_R_SCL")
	)
	(segment
		(start 266.432792 -257.6576)
		(end 266.686792 -257.9116)
		(width 0.15494)
		(layer "In13.Cu")
		(net "SMB_BIC_I2C6_MUX_PEX_ADC_R_SCL")
	)
	(segment
		(start 158.4706 -257.555492)
		(end 156.684726 -259.341366)
		(width 0.15494)
		(layer "In13.Cu")
		(net "SMB_BIC_I2C6_MUX_PEX_ADC_R_SCL")
	)
	(segment
		(start 327.92289 -256.61239)
		(end 328.8665 -255.66878)
		(width 0.15494)
		(layer "In13.Cu")
		(net "SMB_BIC_I2C6_MUX_PEX_ADC_R_SCL")
	)
	(segment
		(start 380.614428 -238.104172)
		(end 381.4826 -237.236)
		(width 0.15494)
		(layer "In13.Cu")
		(net "SMB_BIC_I2C6_MUX_PEX_ADC_R_SCL")
	)
	(segment
		(start 252.08103 -259.366512)
		(end 257.330702 -259.366512)
		(width 0.15494)
		(layer "In13.Cu")
		(net "SMB_BIC_I2C6_MUX_PEX_ADC_R_SCL")
	)
	(segment
		(start 156.684726 -259.341366)
		(end 156.684726 -262.339582)
		(width 0.15494)
		(layer "In13.Cu")
		(net "SMB_BIC_I2C6_MUX_PEX_ADC_R_SCL")
	)
	(segment
		(start 309.059834 -260.48462)
		(end 312.932064 -256.61239)
		(width 0.15494)
		(layer "In13.Cu")
		(net "SMB_BIC_I2C6_MUX_PEX_ADC_R_SCL")
	)
	(segment
		(start 301.332646 -260.48462)
		(end 309.059834 -260.48462)
		(width 0.15494)
		(layer "In13.Cu")
		(net "SMB_BIC_I2C6_MUX_PEX_ADC_R_SCL")
	)
	(segment
		(start 312.932064 -256.61239)
		(end 327.92289 -256.61239)
		(width 0.15494)
		(layer "In13.Cu")
		(net "SMB_BIC_I2C6_MUX_PEX_ADC_R_SCL")
	)
	(segment
		(start 149.645624 -248.160032)
		(end 157.112462 -248.160032)
		(width 0.15494)
		(layer "In13.Cu")
		(net "SMB_BIC_I2C6_MUX_PEX_ADC_R_SCL")
	)
	(segment
		(start 257.330702 -259.366512)
		(end 259.039614 -257.6576)
		(width 0.15494)
		(layer "In13.Cu")
		(net "SMB_BIC_I2C6_MUX_PEX_ADC_R_SCL")
	)
	(segment
		(start 156.684726 -262.339582)
		(end 157.481016 -263.135872)
		(width 0.15494)
		(layer "In13.Cu")
		(net "SMB_BIC_I2C6_MUX_PEX_ADC_R_SCL")
	)
	(segment
		(start 229.684326 -257.32486)
		(end 230.849424 -258.489958)
		(width 0.15494)
		(layer "In13.Cu")
		(net "SMB_BIC_I2C6_MUX_PEX_ADC_R_SCL")
	)
	(segment
		(start 328.8665 -255.66878)
		(end 339.014054 -255.66878)
		(width 0.15494)
		(layer "In13.Cu")
		(net "SMB_BIC_I2C6_MUX_PEX_ADC_R_SCL")
	)
	(segment
		(start 377.351036 -243.078)
		(end 380.614428 -239.814608)
		(width 0.15494)
		(layer "In13.Cu")
		(net "SMB_BIC_I2C6_MUX_PEX_ADC_R_SCL")
	)
	(segment
		(start 465.4296 -279.006554)
		(end 463.475324 -280.96083)
		(width 0.15494)
		(layer "In13.Cu")
		(net "SMB_BIC_I2C6_MUX_PEX_ADC_R_SCL")
	)
	(segment
		(start 211.614004 -255.745742)
		(end 214.763858 -255.745742)
		(width 0.15494)
		(layer "In13.Cu")
		(net "SMB_BIC_I2C6_MUX_PEX_ADC_R_SCL")
	)
	(segment
		(start 465.4296 -258.703064)
		(end 465.4296 -279.006554)
		(width 0.15494)
		(layer "In13.Cu")
		(net "SMB_BIC_I2C6_MUX_PEX_ADC_R_SCL")
	)
	(segment
		(start 358.363774 -240.63706)
		(end 371.634258 -240.63706)
		(width 0.15494)
		(layer "In13.Cu")
		(net "SMB_BIC_I2C6_MUX_PEX_ADC_R_SCL")
	)
	(segment
		(start 114.67084 -247.57253)
		(end 115.590574 -246.652796)
		(width 0.15494)
		(layer "In13.Cu")
		(net "SMB_BIC_I2C6_MUX_PEX_ADC_R_SCL")
	)
	(segment
		(start 163.609528 -263.135872)
		(end 169.5704 -257.175)
		(width 0.15494)
		(layer "In13.Cu")
		(net "SMB_BIC_I2C6_MUX_PEX_ADC_R_SCL")
	)
	(segment
		(start 157.481016 -263.135872)
		(end 163.609528 -263.135872)
		(width 0.15494)
		(layer "In13.Cu")
		(net "SMB_BIC_I2C6_MUX_PEX_ADC_R_SCL")
	)
	(segment
		(start 251.01296 -258.298442)
		(end 252.08103 -259.366512)
		(width 0.15494)
		(layer "In13.Cu")
		(net "SMB_BIC_I2C6_MUX_PEX_ADC_R_SCL")
	)
	(segment
		(start 210.184746 -257.175)
		(end 211.614004 -255.745742)
		(width 0.15494)
		(layer "In13.Cu")
		(net "SMB_BIC_I2C6_MUX_PEX_ADC_R_SCL")
	)
	(segment
		(start 347.31452 -246.89562)
		(end 352.105214 -246.89562)
		(width 0.15494)
		(layer "In13.Cu")
		(net "SMB_BIC_I2C6_MUX_PEX_ADC_R_SCL")
	)
	(segment
		(start 371.634258 -240.63706)
		(end 374.075198 -243.078)
		(width 0.15494)
		(layer "In13.Cu")
		(net "SMB_BIC_I2C6_MUX_PEX_ADC_R_SCL")
	)
	(segment
		(start 388.871714 -236.405166)
		(end 390.65708 -234.6198)
		(width 0.15494)
		(layer "In13.Cu")
		(net "SMB_BIC_I2C6_MUX_PEX_ADC_R_SCL")
	)
	(segment
		(start 342.5571 -251.65304)
		(end 347.31452 -246.89562)
		(width 0.15494)
		(layer "In13.Cu")
		(net "SMB_BIC_I2C6_MUX_PEX_ADC_R_SCL")
	)
	(segment
		(start 352.105214 -246.89562)
		(end 358.363774 -240.63706)
		(width 0.15494)
		(layer "In13.Cu")
		(net "SMB_BIC_I2C6_MUX_PEX_ADC_R_SCL")
	)
	(segment
		(start 216.342976 -257.32486)
		(end 229.684326 -257.32486)
		(width 0.15494)
		(layer "In13.Cu")
		(net "SMB_BIC_I2C6_MUX_PEX_ADC_R_SCL")
	)
	(segment
		(start 157.112462 -248.160032)
		(end 158.4706 -249.51817)
		(width 0.15494)
		(layer "In13.Cu")
		(net "SMB_BIC_I2C6_MUX_PEX_ADC_R_SCL")
	)
	(segment
		(start 149.322282 -247.83669)
		(end 149.645624 -248.160032)
		(width 0.15494)
		(layer "In13.Cu")
		(net "SMB_BIC_I2C6_MUX_PEX_ADC_R_SCL")
	)
	(segment
		(start 381.4826 -237.236)
		(end 384.89128 -237.236)
		(width 0.15494)
		(layer "In13.Cu")
		(net "SMB_BIC_I2C6_MUX_PEX_ADC_R_SCL")
	)
	(segment
		(start 364.744 -209.931)
		(end 365.10595 -209.931)
		(width 0.13208)
		(layer "F.Cu")
		(net "RST_PEX_SSD0_PERST_R_N")
	)
	(segment
		(start 364.236 -209.931)
		(end 364.49 -209.677)
		(width 0.13208)
		(layer "F.Cu")
		(net "RST_PEX_SSD0_PERST_R_N")
	)
	(segment
		(start 363.87405 -209.931)
		(end 364.236 -209.931)
		(width 0.13208)
		(layer "F.Cu")
		(net "RST_PEX_SSD0_PERST_R_N")
	)
	(segment
		(start 364.49 -209.677)
		(end 364.744 -209.931)
		(width 0.13208)
		(layer "F.Cu")
		(net "RST_PEX_SSD0_PERST_R_N")
	)
	(segment
		(start 344.49385 -215.987122)
		(end 344.893646 -215.587326)
		(width 0.13208)
		(layer "F.Cu")
		(net "RST_PEX_SSD0_PERST_R_N")
	)
	(via
		(at 364.49 -209.677)
		(size 0.508)
		(drill 0.254)
		(layers "F.Cu" "B.Cu")
		(net "RST_PEX_SSD0_PERST_R_N")
	)
	(via
		(at 344.893646 -215.587326)
		(size 0.4572)
		(drill 0.254)
		(layers "F.Cu" "B.Cu")
		(net "RST_PEX_SSD0_PERST_R_N")
	)
	(segment
		(start 364.49 -209.677)
		(end 362.698792 -211.468208)
		(width 0.15494)
		(layer "In13.Cu")
		(net "RST_PEX_SSD0_PERST_R_N")
	)
	(segment
		(start 354.833428 -212.867494)
		(end 352.51263 -215.188292)
		(width 0.15494)
		(layer "In13.Cu")
		(net "RST_PEX_SSD0_PERST_R_N")
	)
	(segment
		(start 362.698792 -211.468208)
		(end 361.372404 -211.468208)
		(width 0.15494)
		(layer "In13.Cu")
		(net "RST_PEX_SSD0_PERST_R_N")
	)
	(segment
		(start 359.973118 -212.867494)
		(end 354.833428 -212.867494)
		(width 0.15494)
		(layer "In13.Cu")
		(net "RST_PEX_SSD0_PERST_R_N")
	)
	(segment
		(start 345.29268 -215.188292)
		(end 344.893646 -215.587326)
		(width 0.0889)
		(layer "In13.Cu")
		(net "RST_PEX_SSD0_PERST_R_N")
	)
	(segment
		(start 352.51263 -215.188292)
		(end 345.29268 -215.188292)
		(width 0.0889)
		(layer "In13.Cu")
		(net "RST_PEX_SSD0_PERST_R_N")
	)
	(segment
		(start 361.372404 -211.468208)
		(end 359.973118 -212.867494)
		(width 0.15494)
		(layer "In13.Cu")
		(net "RST_PEX_SSD0_PERST_R_N")
	)
	(segment
		(start 356.440994 -57.16397)
		(end 356.440994 -57.233566)
		(width 0.2032)
		(layer "F.Cu")
		(net "P3V3_SSD12_SS")
	)
	(segment
		(start 356.440994 -57.233566)
		(end 357.373428 -58.166)
		(width 0.2032)
		(layer "F.Cu")
		(net "P3V3_SSD12_SS")
	)
	(segment
		(start 357.495094 -58.453782)
		(end 357.495094 -59.177936)
		(width 0.2032)
		(layer "F.Cu")
		(net "P3V3_SSD12_SS")
	)
	(segment
		(start 357.373428 -58.166)
		(end 357.49103 -58.449718)
		(width 0.2032)
		(layer "F.Cu")
		(net "P3V3_SSD12_SS")
	)
	(segment
		(start 357.49103 -58.449718)
		(end 357.495094 -58.453782)
		(width 0.2032)
		(layer "F.Cu")
		(net "P3V3_SSD12_SS")
	)
	(via
		(at 357.49103 -58.449718)
		(size 0.508)
		(drill 0.254)
		(layers "F.Cu" "B.Cu")
		(net "P3V3_SSD12_SS")
	)
	(segment
		(start 123.055634 -176.3395)
		(end 125.50521 -176.3395)
		(width 0.1143)
		(layer "F.Cu")
		(net "CLK_100M_DB2000QL_PEX0_S1_R_DN")
	)
	(segment
		(start 125.50521 -176.3395)
		(end 125.821186 -176.023524)
		(width 0.1143)
		(layer "F.Cu")
		(net "CLK_100M_DB2000QL_PEX0_S1_R_DN")
	)
	(segment
		(start 127.6223 -190.081154)
		(end 122.17273 -184.631584)
		(width 0.1143)
		(layer "F.Cu")
		(net "CLK_100M_DB2000QL_PEX0_S1_R_DN")
	)
	(segment
		(start 36.849558 -297.79976)
		(end 36.374578 -297.32478)
		(width 0.1143)
		(layer "F.Cu")
		(net "CLK_100M_DB2000QL_PEX0_S1_R_DN")
	)
	(segment
		(start 122.17273 -184.631584)
		(end 122.17273 -177.222404)
		(width 0.1143)
		(layer "F.Cu")
		(net "CLK_100M_DB2000QL_PEX0_S1_R_DN")
	)
	(segment
		(start 127.37973 -195.696078)
		(end 127.6223 -195.453508)
		(width 0.1143)
		(layer "F.Cu")
		(net "CLK_100M_DB2000QL_PEX0_S1_R_DN")
	)
	(segment
		(start 122.17273 -177.222404)
		(end 123.055634 -176.3395)
		(width 0.1143)
		(layer "F.Cu")
		(net "CLK_100M_DB2000QL_PEX0_S1_R_DN")
	)
	(segment
		(start 127.6223 -195.453508)
		(end 127.6223 -190.081154)
		(width 0.1143)
		(layer "F.Cu")
		(net "CLK_100M_DB2000QL_PEX0_S1_R_DN")
	)
	(segment
		(start 36.849812 -297.79976)
		(end 36.849558 -297.79976)
		(width 0.1143)
		(layer "F.Cu")
		(net "CLK_100M_DB2000QL_PEX0_S1_R_DN")
	)
	(via
		(at 127.37973 -195.696078)
		(size 0.508)
		(drill 0.254)
		(layers "F.Cu" "B.Cu")
		(net "CLK_100M_DB2000QL_PEX0_S1_R_DN")
	)
	(via
		(at 36.374578 -297.32478)
		(size 0.4064)
		(drill 0.2032)
		(layers "F.Cu" "B.Cu")
		(net "CLK_100M_DB2000QL_PEX0_S1_R_DN")
	)
	(segment
		(start 35.258502 -296.93235)
		(end 34.90595 -296.93235)
		(width 0.1143)
		(layer "B.Cu")
		(net "CLK_100M_DB2000QL_PEX0_S1_R_DN")
	)
	(segment
		(start 75.39228 -222.0722)
		(end 100.25888 -197.2056)
		(width 0.1143)
		(layer "B.Cu")
		(net "CLK_100M_DB2000QL_PEX0_S1_R_DN")
	)
	(segment
		(start 127.630174 -196.421248)
		(end 127.630174 -195.946522)
		(width 0.1143)
		(layer "B.Cu")
		(net "CLK_100M_DB2000QL_PEX0_S1_R_DN")
	)
	(segment
		(start 127.630174 -195.946522)
		(end 127.37973 -195.696078)
		(width 0.1143)
		(layer "B.Cu")
		(net "CLK_100M_DB2000QL_PEX0_S1_R_DN")
	)
	(segment
		(start 35.36315 -296.8498)
		(end 35.2806 -296.93235)
		(width 0.0889)
		(layer "B.Cu")
		(net "CLK_100M_DB2000QL_PEX0_S1_R_DN")
	)
	(segment
		(start 50.16246 -222.0722)
		(end 75.39228 -222.0722)
		(width 0.1143)
		(layer "B.Cu")
		(net "CLK_100M_DB2000QL_PEX0_S1_R_DN")
	)
	(segment
		(start 36.491672 -296.8498)
		(end 35.36315 -296.8498)
		(width 0.0889)
		(layer "B.Cu")
		(net "CLK_100M_DB2000QL_PEX0_S1_R_DN")
	)
	(segment
		(start 20.6883 -251.54636)
		(end 50.16246 -222.0722)
		(width 0.1143)
		(layer "B.Cu")
		(net "CLK_100M_DB2000QL_PEX0_S1_R_DN")
	)
	(segment
		(start 36.741608 -297.24858)
		(end 36.741608 -297.099736)
		(width 0.0889)
		(layer "B.Cu")
		(net "CLK_100M_DB2000QL_PEX0_S1_R_DN")
	)
	(segment
		(start 29.551376 -293.241984)
		(end 29.551376 -280.020776)
		(width 0.1143)
		(layer "B.Cu")
		(net "CLK_100M_DB2000QL_PEX0_S1_R_DN")
	)
	(segment
		(start 118.051834 -200.5838)
		(end 127.296164 -196.755512)
		(width 0.1143)
		(layer "B.Cu")
		(net "CLK_100M_DB2000QL_PEX0_S1_R_DN")
	)
	(segment
		(start 31.1785 -294.869108)
		(end 29.551376 -293.241984)
		(width 0.1143)
		(layer "B.Cu")
		(net "CLK_100M_DB2000QL_PEX0_S1_R_DN")
	)
	(segment
		(start 100.25888 -197.2056)
		(end 107.688888 -197.2056)
		(width 0.1143)
		(layer "B.Cu")
		(net "CLK_100M_DB2000QL_PEX0_S1_R_DN")
	)
	(segment
		(start 23.603458 -267.532866)
		(end 20.6883 -260.494526)
		(width 0.1143)
		(layer "B.Cu")
		(net "CLK_100M_DB2000QL_PEX0_S1_R_DN")
	)
	(segment
		(start 115.844828 -200.5838)
		(end 118.051834 -200.5838)
		(width 0.1143)
		(layer "B.Cu")
		(net "CLK_100M_DB2000QL_PEX0_S1_R_DN")
	)
	(segment
		(start 32.842708 -294.869108)
		(end 31.1785 -294.869108)
		(width 0.1143)
		(layer "B.Cu")
		(net "CLK_100M_DB2000QL_PEX0_S1_R_DN")
	)
	(segment
		(start 35.2806 -296.93235)
		(end 35.258502 -296.93235)
		(width 0.0889)
		(layer "B.Cu")
		(net "CLK_100M_DB2000QL_PEX0_S1_R_DN")
	)
	(segment
		(start 34.90595 -296.93235)
		(end 32.842708 -294.869108)
		(width 0.1143)
		(layer "B.Cu")
		(net "CLK_100M_DB2000QL_PEX0_S1_R_DN")
	)
	(segment
		(start 29.551376 -280.020776)
		(end 23.603458 -274.072858)
		(width 0.1143)
		(layer "B.Cu")
		(net "CLK_100M_DB2000QL_PEX0_S1_R_DN")
	)
	(segment
		(start 107.688888 -197.2056)
		(end 115.844828 -200.5838)
		(width 0.1143)
		(layer "B.Cu")
		(net "CLK_100M_DB2000QL_PEX0_S1_R_DN")
	)
	(segment
		(start 23.603458 -274.072858)
		(end 23.603458 -267.532866)
		(width 0.1143)
		(layer "B.Cu")
		(net "CLK_100M_DB2000QL_PEX0_S1_R_DN")
	)
	(segment
		(start 36.665408 -297.32478)
		(end 36.741608 -297.24858)
		(width 0.0889)
		(layer "B.Cu")
		(net "CLK_100M_DB2000QL_PEX0_S1_R_DN")
	)
	(segment
		(start 20.6883 -260.494526)
		(end 20.6883 -251.54636)
		(width 0.1143)
		(layer "B.Cu")
		(net "CLK_100M_DB2000QL_PEX0_S1_R_DN")
	)
	(segment
		(start 36.374578 -297.32478)
		(end 36.665408 -297.32478)
		(width 0.0889)
		(layer "B.Cu")
		(net "CLK_100M_DB2000QL_PEX0_S1_R_DN")
	)
	(segment
		(start 36.741608 -297.099736)
		(end 36.491672 -296.8498)
		(width 0.0889)
		(layer "B.Cu")
		(net "CLK_100M_DB2000QL_PEX0_S1_R_DN")
	)
	(segment
		(start 127.296164 -196.755512)
		(end 127.630174 -196.421248)
		(width 0.1143)
		(layer "B.Cu")
		(net "CLK_100M_DB2000QL_PEX0_S1_R_DN")
	)
	(segment
		(start 128.149604 -178.7144)
		(end 129.570734 -177.293778)
		(width 0.13462)
		(layer "F.Cu")
		(net "CLK_100M_CK440Q_0_DB2000QL_R_DP")
	)
	(segment
		(start 274.11553 -83.947)
		(end 274.409154 -84.240624)
		(width 0.13462)
		(layer "F.Cu")
		(net "CLK_100M_CK440Q_0_DB2000QL_R_DP")
	)
	(segment
		(start 123.656598 -178.995324)
		(end 123.937522 -178.7144)
		(width 0.13462)
		(layer "F.Cu")
		(net "CLK_100M_CK440Q_0_DB2000QL_R_DP")
	)
	(segment
		(start 269.254224 -83.947)
		(end 274.11553 -83.947)
		(width 0.13462)
		(layer "F.Cu")
		(net "CLK_100M_CK440Q_0_DB2000QL_R_DP")
	)
	(segment
		(start 129.864358 -177.293778)
		(end 129.971038 -177.400458)
		(width 0.13462)
		(layer "F.Cu")
		(net "CLK_100M_CK440Q_0_DB2000QL_R_DP")
	)
	(segment
		(start 129.570734 -177.293778)
		(end 129.864358 -177.293778)
		(width 0.13462)
		(layer "F.Cu")
		(net "CLK_100M_CK440Q_0_DB2000QL_R_DP")
	)
	(segment
		(start 123.937522 -178.7144)
		(end 128.149604 -178.7144)
		(width 0.13462)
		(layer "F.Cu")
		(net "CLK_100M_CK440Q_0_DB2000QL_R_DP")
	)
	(segment
		(start 268.9352 -84.266024)
		(end 269.254224 -83.947)
		(width 0.13462)
		(layer "F.Cu")
		(net "CLK_100M_CK440Q_0_DB2000QL_R_DP")
	)
	(via
		(at 274.409154 -84.240624)
		(size 0.508)
		(drill 0.254)
		(layers "F.Cu" "B.Cu")
		(net "CLK_100M_CK440Q_0_DB2000QL_R_DP")
	)
	(via
		(at 123.656598 -178.995324)
		(size 0.508)
		(drill 0.254)
		(layers "F.Cu" "B.Cu")
		(net "CLK_100M_CK440Q_0_DB2000QL_R_DP")
	)
	(segment
		(start 268.037564 -115.220496)
		(end 268.438884 -115.220496)
		(width 0.13462)
		(layer "B.Cu")
		(net "CLK_100M_CK440Q_0_DB2000QL_R_DP")
	)
	(segment
		(start 123.497848 -181.683152)
		(end 123.69165 -181.683152)
		(width 0.13462)
		(layer "B.Cu")
		(net "CLK_100M_CK440Q_0_DB2000QL_R_DP")
	)
	(segment
		(start 270.453612 -113.205768)
		(end 270.73733 -112.92205)
		(width 0.13462)
		(layer "B.Cu")
		(net "CLK_100M_CK440Q_0_DB2000QL_R_DP")
	)
	(segment
		(start 123.21413 -181.205378)
		(end 123.21413 -181.399434)
		(width 0.13462)
		(layer "B.Cu")
		(net "CLK_100M_CK440Q_0_DB2000QL_R_DP")
	)
	(segment
		(start 125.215142 -183.206644)
		(end 125.499368 -183.490616)
		(width 0.13462)
		(layer "B.Cu")
		(net "CLK_100M_CK440Q_0_DB2000QL_R_DP")
	)
	(segment
		(start 141.451838 -184.63768)
		(end 142.14856 -183.940958)
		(width 0.13462)
		(layer "B.Cu")
		(net "CLK_100M_CK440Q_0_DB2000QL_R_DP")
	)
	(segment
		(start 123.355608 -178.694334)
		(end 122.660664 -178.694334)
		(width 0.13462)
		(layer "B.Cu")
		(net "CLK_100M_CK440Q_0_DB2000QL_R_DP")
	)
	(segment
		(start 269.975584 -113.683796)
		(end 269.975584 -113.48974)
		(width 0.13462)
		(layer "B.Cu")
		(net "CLK_100M_CK440Q_0_DB2000QL_R_DP")
	)
	(segment
		(start 122.452384 -178.902614)
		(end 122.452384 -180.637688)
		(width 0.13462)
		(layer "B.Cu")
		(net "CLK_100M_CK440Q_0_DB2000QL_R_DP")
	)
	(segment
		(start 122.736102 -180.921406)
		(end 122.929904 -180.921406)
		(width 0.13462)
		(layer "B.Cu")
		(net "CLK_100M_CK440Q_0_DB2000QL_R_DP")
	)
	(segment
		(start 128.606296 -184.63768)
		(end 141.451838 -184.63768)
		(width 0.13462)
		(layer "B.Cu")
		(net "CLK_100M_CK440Q_0_DB2000QL_R_DP")
	)
	(segment
		(start 122.929904 -180.921406)
		(end 123.21413 -181.205378)
		(width 0.13462)
		(layer "B.Cu")
		(net "CLK_100M_CK440Q_0_DB2000QL_R_DP")
	)
	(segment
		(start 262.756142 -114.45875)
		(end 263.040114 -114.742976)
		(width 0.13462)
		(layer "B.Cu")
		(net "CLK_100M_CK440Q_0_DB2000QL_R_DP")
	)
	(segment
		(start 263.040114 -114.742976)
		(end 263.040114 -114.936778)
		(width 0.13462)
		(layer "B.Cu")
		(net "CLK_100M_CK440Q_0_DB2000QL_R_DP")
	)
	(segment
		(start 123.21413 -181.399434)
		(end 123.497848 -181.683152)
		(width 0.13462)
		(layer "B.Cu")
		(net "CLK_100M_CK440Q_0_DB2000QL_R_DP")
	)
	(segment
		(start 127.392176 -184.50052)
		(end 127.529336 -184.63768)
		(width 0.13462)
		(layer "B.Cu")
		(net "CLK_100M_CK440Q_0_DB2000QL_R_DP")
	)
	(segment
		(start 123.656598 -178.995324)
		(end 123.355608 -178.694334)
		(width 0.13462)
		(layer "B.Cu")
		(net "CLK_100M_CK440Q_0_DB2000QL_R_DP")
	)
	(segment
		(start 126.990856 -184.50052)
		(end 127.392176 -184.50052)
		(width 0.13462)
		(layer "B.Cu")
		(net "CLK_100M_CK440Q_0_DB2000QL_R_DP")
	)
	(segment
		(start 266.960604 -115.220496)
		(end 267.361924 -115.220496)
		(width 0.13462)
		(layer "B.Cu")
		(net "CLK_100M_CK440Q_0_DB2000QL_R_DP")
	)
	(segment
		(start 271.977104 -111.682276)
		(end 272.711672 -110.947708)
		(width 0.13462)
		(layer "B.Cu")
		(net "CLK_100M_CK440Q_0_DB2000QL_R_DP")
	)
	(segment
		(start 268.438884 -115.220496)
		(end 269.174976 -114.484404)
		(width 0.13462)
		(layer "B.Cu")
		(net "CLK_100M_CK440Q_0_DB2000QL_R_DP")
	)
	(segment
		(start 276.46884 -90.163396)
		(end 276.46884 -85.237828)
		(width 0.13462)
		(layer "B.Cu")
		(net "CLK_100M_CK440Q_0_DB2000QL_R_DP")
	)
	(segment
		(start 258.207764 -110.104428)
		(end 261.80034 -113.697004)
		(width 0.13462)
		(layer "B.Cu")
		(net "CLK_100M_CK440Q_0_DB2000QL_R_DP")
	)
	(segment
		(start 239.8268 -115.546124)
		(end 245.268496 -110.104428)
		(width 0.13462)
		(layer "B.Cu")
		(net "CLK_100M_CK440Q_0_DB2000QL_R_DP")
	)
	(segment
		(start 267.499084 -115.083336)
		(end 267.900404 -115.083336)
		(width 0.13462)
		(layer "B.Cu")
		(net "CLK_100M_CK440Q_0_DB2000QL_R_DP")
	)
	(segment
		(start 269.458948 -114.006376)
		(end 269.653004 -114.006376)
		(width 0.13462)
		(layer "B.Cu")
		(net "CLK_100M_CK440Q_0_DB2000QL_R_DP")
	)
	(segment
		(start 264.268204 -115.083336)
		(end 264.669524 -115.083336)
		(width 0.13462)
		(layer "B.Cu")
		(net "CLK_100M_CK440Q_0_DB2000QL_R_DP")
	)
	(segment
		(start 264.131044 -115.220496)
		(end 264.268204 -115.083336)
		(width 0.13462)
		(layer "B.Cu")
		(net "CLK_100M_CK440Q_0_DB2000QL_R_DP")
	)
	(segment
		(start 266.823444 -115.083336)
		(end 266.960604 -115.220496)
		(width 0.13462)
		(layer "B.Cu")
		(net "CLK_100M_CK440Q_0_DB2000QL_R_DP")
	)
	(segment
		(start 265.883644 -115.220496)
		(end 266.284964 -115.220496)
		(width 0.13462)
		(layer "B.Cu")
		(net "CLK_100M_CK440Q_0_DB2000QL_R_DP")
	)
	(segment
		(start 128.067816 -184.50052)
		(end 128.469136 -184.50052)
		(width 0.13462)
		(layer "B.Cu")
		(net "CLK_100M_CK440Q_0_DB2000QL_R_DP")
	)
	(segment
		(start 124.737622 -182.922926)
		(end 125.02134 -183.206644)
		(width 0.13462)
		(layer "B.Cu")
		(net "CLK_100M_CK440Q_0_DB2000QL_R_DP")
	)
	(segment
		(start 261.994396 -113.697004)
		(end 262.278368 -113.98123)
		(width 0.13462)
		(layer "B.Cu")
		(net "CLK_100M_CK440Q_0_DB2000QL_R_DP")
	)
	(segment
		(start 124.737622 -182.72887)
		(end 124.737622 -182.922926)
		(width 0.13462)
		(layer "B.Cu")
		(net "CLK_100M_CK440Q_0_DB2000QL_R_DP")
	)
	(segment
		(start 142.14856 -183.940958)
		(end 180.922676 -183.940958)
		(width 0.13462)
		(layer "B.Cu")
		(net "CLK_100M_CK440Q_0_DB2000QL_R_DP")
	)
	(segment
		(start 122.452384 -180.637688)
		(end 122.736102 -180.921406)
		(width 0.13462)
		(layer "B.Cu")
		(net "CLK_100M_CK440Q_0_DB2000QL_R_DP")
	)
	(segment
		(start 205.373478 -152.942798)
		(end 239.8268 -118.489476)
		(width 0.13462)
		(layer "B.Cu")
		(net "CLK_100M_CK440Q_0_DB2000QL_R_DP")
	)
	(segment
		(start 122.660664 -178.694334)
		(end 122.452384 -178.902614)
		(width 0.13462)
		(layer "B.Cu")
		(net "CLK_100M_CK440Q_0_DB2000QL_R_DP")
	)
	(segment
		(start 123.69165 -181.683152)
		(end 123.975876 -181.967124)
		(width 0.13462)
		(layer "B.Cu")
		(net "CLK_100M_CK440Q_0_DB2000QL_R_DP")
	)
	(segment
		(start 262.278368 -114.175032)
		(end 262.562086 -114.45875)
		(width 0.13462)
		(layer "B.Cu")
		(net "CLK_100M_CK440Q_0_DB2000QL_R_DP")
	)
	(segment
		(start 269.174976 -114.290348)
		(end 269.458948 -114.006376)
		(width 0.13462)
		(layer "B.Cu")
		(net "CLK_100M_CK440Q_0_DB2000QL_R_DP")
	)
	(segment
		(start 124.453396 -182.444898)
		(end 124.737622 -182.72887)
		(width 0.13462)
		(layer "B.Cu")
		(net "CLK_100M_CK440Q_0_DB2000QL_R_DP")
	)
	(segment
		(start 126.452376 -184.63768)
		(end 126.853696 -184.63768)
		(width 0.13462)
		(layer "B.Cu")
		(net "CLK_100M_CK440Q_0_DB2000QL_R_DP")
	)
	(segment
		(start 271.215358 -112.444022)
		(end 271.499076 -112.160304)
		(width 0.13462)
		(layer "B.Cu")
		(net "CLK_100M_CK440Q_0_DB2000QL_R_DP")
	)
	(segment
		(start 263.040114 -114.936778)
		(end 263.323832 -115.220496)
		(width 0.13462)
		(layer "B.Cu")
		(net "CLK_100M_CK440Q_0_DB2000QL_R_DP")
	)
	(segment
		(start 271.499076 -111.966248)
		(end 271.783048 -111.682276)
		(width 0.13462)
		(layer "B.Cu")
		(net "CLK_100M_CK440Q_0_DB2000QL_R_DP")
	)
	(segment
		(start 271.783048 -111.682276)
		(end 271.977104 -111.682276)
		(width 0.13462)
		(layer "B.Cu")
		(net "CLK_100M_CK440Q_0_DB2000QL_R_DP")
	)
	(segment
		(start 265.208004 -115.220496)
		(end 265.345164 -115.083336)
		(width 0.13462)
		(layer "B.Cu")
		(net "CLK_100M_CK440Q_0_DB2000QL_R_DP")
	)
	(segment
		(start 261.80034 -113.697004)
		(end 261.994396 -113.697004)
		(width 0.13462)
		(layer "B.Cu")
		(net "CLK_100M_CK440Q_0_DB2000QL_R_DP")
	)
	(segment
		(start 276.46884 -85.237828)
		(end 275.178012 -83.947)
		(width 0.13462)
		(layer "B.Cu")
		(net "CLK_100M_CK440Q_0_DB2000QL_R_DP")
	)
	(segment
		(start 267.900404 -115.083336)
		(end 268.037564 -115.220496)
		(width 0.13462)
		(layer "B.Cu")
		(net "CLK_100M_CK440Q_0_DB2000QL_R_DP")
	)
	(segment
		(start 270.25981 -113.205768)
		(end 270.453612 -113.205768)
		(width 0.13462)
		(layer "B.Cu")
		(net "CLK_100M_CK440Q_0_DB2000QL_R_DP")
	)
	(segment
		(start 262.278368 -113.98123)
		(end 262.278368 -114.175032)
		(width 0.13462)
		(layer "B.Cu")
		(net "CLK_100M_CK440Q_0_DB2000QL_R_DP")
	)
	(segment
		(start 127.930656 -184.63768)
		(end 128.067816 -184.50052)
		(width 0.13462)
		(layer "B.Cu")
		(net "CLK_100M_CK440Q_0_DB2000QL_R_DP")
	)
	(segment
		(start 270.73733 -112.727994)
		(end 271.021556 -112.444022)
		(width 0.13462)
		(layer "B.Cu")
		(net "CLK_100M_CK440Q_0_DB2000QL_R_DP")
	)
	(segment
		(start 265.345164 -115.083336)
		(end 265.746484 -115.083336)
		(width 0.13462)
		(layer "B.Cu")
		(net "CLK_100M_CK440Q_0_DB2000QL_R_DP")
	)
	(segment
		(start 265.746484 -115.083336)
		(end 265.883644 -115.220496)
		(width 0.13462)
		(layer "B.Cu")
		(net "CLK_100M_CK440Q_0_DB2000QL_R_DP")
	)
	(segment
		(start 269.975584 -113.48974)
		(end 270.25981 -113.205768)
		(width 0.13462)
		(layer "B.Cu")
		(net "CLK_100M_CK440Q_0_DB2000QL_R_DP")
	)
	(segment
		(start 245.268496 -110.104428)
		(end 258.207764 -110.104428)
		(width 0.13462)
		(layer "B.Cu")
		(net "CLK_100M_CK440Q_0_DB2000QL_R_DP")
	)
	(segment
		(start 263.323832 -115.220496)
		(end 264.131044 -115.220496)
		(width 0.13462)
		(layer "B.Cu")
		(net "CLK_100M_CK440Q_0_DB2000QL_R_DP")
	)
	(segment
		(start 269.653004 -114.006376)
		(end 269.975584 -113.683796)
		(width 0.13462)
		(layer "B.Cu")
		(net "CLK_100M_CK440Q_0_DB2000QL_R_DP")
	)
	(segment
		(start 266.422124 -115.083336)
		(end 266.823444 -115.083336)
		(width 0.13462)
		(layer "B.Cu")
		(net "CLK_100M_CK440Q_0_DB2000QL_R_DP")
	)
	(segment
		(start 264.669524 -115.083336)
		(end 264.806684 -115.220496)
		(width 0.13462)
		(layer "B.Cu")
		(net "CLK_100M_CK440Q_0_DB2000QL_R_DP")
	)
	(segment
		(start 123.975876 -181.967124)
		(end 123.975876 -182.16118)
		(width 0.13462)
		(layer "B.Cu")
		(net "CLK_100M_CK440Q_0_DB2000QL_R_DP")
	)
	(segment
		(start 125.499368 -183.490616)
		(end 125.499368 -183.684672)
		(width 0.13462)
		(layer "B.Cu")
		(net "CLK_100M_CK440Q_0_DB2000QL_R_DP")
	)
	(segment
		(start 274.702778 -83.947)
		(end 274.409154 -84.240624)
		(width 0.13462)
		(layer "B.Cu")
		(net "CLK_100M_CK440Q_0_DB2000QL_R_DP")
	)
	(segment
		(start 272.711672 -93.920564)
		(end 276.46884 -90.163396)
		(width 0.13462)
		(layer "B.Cu")
		(net "CLK_100M_CK440Q_0_DB2000QL_R_DP")
	)
	(segment
		(start 126.853696 -184.63768)
		(end 126.990856 -184.50052)
		(width 0.13462)
		(layer "B.Cu")
		(net "CLK_100M_CK440Q_0_DB2000QL_R_DP")
	)
	(segment
		(start 125.02134 -183.206644)
		(end 125.215142 -183.206644)
		(width 0.13462)
		(layer "B.Cu")
		(net "CLK_100M_CK440Q_0_DB2000QL_R_DP")
	)
	(segment
		(start 262.562086 -114.45875)
		(end 262.756142 -114.45875)
		(width 0.13462)
		(layer "B.Cu")
		(net "CLK_100M_CK440Q_0_DB2000QL_R_DP")
	)
	(segment
		(start 239.8268 -118.489476)
		(end 239.8268 -115.546124)
		(width 0.13462)
		(layer "B.Cu")
		(net "CLK_100M_CK440Q_0_DB2000QL_R_DP")
	)
	(segment
		(start 269.174976 -114.484404)
		(end 269.174976 -114.290348)
		(width 0.13462)
		(layer "B.Cu")
		(net "CLK_100M_CK440Q_0_DB2000QL_R_DP")
	)
	(segment
		(start 127.529336 -184.63768)
		(end 127.930656 -184.63768)
		(width 0.13462)
		(layer "B.Cu")
		(net "CLK_100M_CK440Q_0_DB2000QL_R_DP")
	)
	(segment
		(start 271.499076 -112.160304)
		(end 271.499076 -111.966248)
		(width 0.13462)
		(layer "B.Cu")
		(net "CLK_100M_CK440Q_0_DB2000QL_R_DP")
	)
	(segment
		(start 270.73733 -112.92205)
		(end 270.73733 -112.727994)
		(width 0.13462)
		(layer "B.Cu")
		(net "CLK_100M_CK440Q_0_DB2000QL_R_DP")
	)
	(segment
		(start 124.259594 -182.444898)
		(end 124.453396 -182.444898)
		(width 0.13462)
		(layer "B.Cu")
		(net "CLK_100M_CK440Q_0_DB2000QL_R_DP")
	)
	(segment
		(start 125.499368 -183.684672)
		(end 126.452376 -184.63768)
		(width 0.13462)
		(layer "B.Cu")
		(net "CLK_100M_CK440Q_0_DB2000QL_R_DP")
	)
	(segment
		(start 123.975876 -182.16118)
		(end 124.259594 -182.444898)
		(width 0.13462)
		(layer "B.Cu")
		(net "CLK_100M_CK440Q_0_DB2000QL_R_DP")
	)
	(segment
		(start 205.373478 -159.490156)
		(end 205.373478 -152.942798)
		(width 0.13462)
		(layer "B.Cu")
		(net "CLK_100M_CK440Q_0_DB2000QL_R_DP")
	)
	(segment
		(start 180.922676 -183.940958)
		(end 205.373478 -159.490156)
		(width 0.13462)
		(layer "B.Cu")
		(net "CLK_100M_CK440Q_0_DB2000QL_R_DP")
	)
	(segment
		(start 267.361924 -115.220496)
		(end 267.499084 -115.083336)
		(width 0.13462)
		(layer "B.Cu")
		(net "CLK_100M_CK440Q_0_DB2000QL_R_DP")
	)
	(segment
		(start 266.284964 -115.220496)
		(end 266.422124 -115.083336)
		(width 0.13462)
		(layer "B.Cu")
		(net "CLK_100M_CK440Q_0_DB2000QL_R_DP")
	)
	(segment
		(start 275.178012 -83.947)
		(end 274.702778 -83.947)
		(width 0.13462)
		(layer "B.Cu")
		(net "CLK_100M_CK440Q_0_DB2000QL_R_DP")
	)
	(segment
		(start 271.021556 -112.444022)
		(end 271.215358 -112.444022)
		(width 0.13462)
		(layer "B.Cu")
		(net "CLK_100M_CK440Q_0_DB2000QL_R_DP")
	)
	(segment
		(start 128.469136 -184.50052)
		(end 128.606296 -184.63768)
		(width 0.13462)
		(layer "B.Cu")
		(net "CLK_100M_CK440Q_0_DB2000QL_R_DP")
	)
	(segment
		(start 264.806684 -115.220496)
		(end 265.208004 -115.220496)
		(width 0.13462)
		(layer "B.Cu")
		(net "CLK_100M_CK440Q_0_DB2000QL_R_DP")
	)
	(segment
		(start 272.711672 -110.947708)
		(end 272.711672 -93.920564)
		(width 0.13462)
		(layer "B.Cu")
		(net "CLK_100M_CK440Q_0_DB2000QL_R_DP")
	)
	(segment
		(start 206.11719 -305.064922)
		(end 206.117698 -305.064414)
		(width 0.13208)
		(layer "F.Cu")
		(net "PEX1_SPARE3")
	)
	(segment
		(start 206.118206 -305.674522)
		(end 206.118206 -305.065938)
		(width 0.13208)
		(layer "F.Cu")
		(net "PEX1_SPARE3")
	)
	(segment
		(start 206.117698 -305.064414)
		(end 206.117698 -304.436526)
		(width 0.13208)
		(layer "F.Cu")
		(net "PEX1_SPARE3")
	)
	(segment
		(start 206.118206 -305.065938)
		(end 206.11719 -305.064922)
		(width 0.13208)
		(layer "F.Cu")
		(net "PEX1_SPARE3")
	)
	(segment
		(start 182.39994 -309.199788)
		(end 182.87492 -308.724808)
		(width 0.13208)
		(layer "F.Cu")
		(net "PEX1_SPARE3")
	)
	(via
		(at 206.11719 -305.064922)
		(size 0.508)
		(drill 0.254)
		(layers "F.Cu" "B.Cu")
		(net "PEX1_SPARE3")
	)
	(via
		(at 200.235058 -310.149748)
		(size 0.6604)
		(drill 0.3302)
		(layers "F.Cu" "B.Cu")
		(net "PEX1_SPARE3")
	)
	(via
		(at 182.87492 -308.724808)
		(size 0.4064)
		(drill 0.2032)
		(layers "F.Cu" "B.Cu")
		(net "PEX1_SPARE3")
	)
	(segment
		(start 194.295014 -309.890414)
		(end 194.5005 -309.684928)
		(width 0.13208)
		(layer "B.Cu")
		(net "PEX1_SPARE3")
	)
	(segment
		(start 182.87492 -308.724808)
		(end 182.87492 -310.53024)
		(width 0.13208)
		(layer "B.Cu")
		(net "PEX1_SPARE3")
	)
	(segment
		(start 201.502264 -310.149748)
		(end 200.235058 -310.149748)
		(width 0.13208)
		(layer "B.Cu")
		(net "PEX1_SPARE3")
	)
	(segment
		(start 194.295014 -310.437022)
		(end 194.295014 -309.890414)
		(width 0.13208)
		(layer "B.Cu")
		(net "PEX1_SPARE3")
	)
	(segment
		(start 206.11719 -305.534822)
		(end 201.502264 -310.149748)
		(width 0.13208)
		(layer "B.Cu")
		(net "PEX1_SPARE3")
	)
	(segment
		(start 183.002174 -310.657494)
		(end 194.074542 -310.657494)
		(width 0.13208)
		(layer "B.Cu")
		(net "PEX1_SPARE3")
	)
	(segment
		(start 199.770238 -309.684928)
		(end 200.235058 -310.149748)
		(width 0.13208)
		(layer "B.Cu")
		(net "PEX1_SPARE3")
	)
	(segment
		(start 194.074542 -310.657494)
		(end 194.295014 -310.437022)
		(width 0.13208)
		(layer "B.Cu")
		(net "PEX1_SPARE3")
	)
	(segment
		(start 182.87492 -310.53024)
		(end 183.002174 -310.657494)
		(width 0.13208)
		(layer "B.Cu")
		(net "PEX1_SPARE3")
	)
	(segment
		(start 194.5005 -309.684928)
		(end 199.770238 -309.684928)
		(width 0.13208)
		(layer "B.Cu")
		(net "PEX1_SPARE3")
	)
	(segment
		(start 206.11719 -305.064922)
		(end 206.11719 -305.534822)
		(width 0.13208)
		(layer "B.Cu")
		(net "PEX1_SPARE3")
	)
	(segment
		(start 378.357892 -86.443058)
		(end 377.675902 -86.443058)
		(width 0.13208)
		(layer "F.Cu")
		(net "SMB_BIC_I2C6_MUX_PEX_ADC_R_SDA")
	)
	(segment
		(start 19.835622 -243.20754)
		(end 19.835622 -243.376196)
		(width 0.13208)
		(layer "F.Cu")
		(net "SMB_BIC_I2C6_MUX_PEX_ADC_R_SDA")
	)
	(segment
		(start 94.705678 -240.744248)
		(end 94.034356 -240.744248)
		(width 0.13208)
		(layer "F.Cu")
		(net "SMB_BIC_I2C6_MUX_PEX_ADC_R_SDA")
	)
	(segment
		(start 19.854418 -241.112294)
		(end 19.860768 -241.118644)
		(width 0.13208)
		(layer "F.Cu")
		(net "SMB_BIC_I2C6_MUX_PEX_ADC_R_SDA")
	)
	(segment
		(start 248.7168 -279.34539)
		(end 248.494804 -279.567386)
		(width 0.13208)
		(layer "F.Cu")
		(net "SMB_BIC_I2C6_MUX_PEX_ADC_R_SDA")
	)
	(segment
		(start 378.452634 -86.5378)
		(end 378.357892 -86.443058)
		(width 0.13208)
		(layer "F.Cu")
		(net "SMB_BIC_I2C6_MUX_PEX_ADC_R_SDA")
	)
	(segment
		(start 251.176536 -259.247386)
		(end 251.01296 -259.08381)
		(width 0.13208)
		(layer "F.Cu")
		(net "SMB_BIC_I2C6_MUX_PEX_ADC_R_SDA")
	)
	(segment
		(start 252.036326 -277.35022)
		(end 252.036326 -261.761986)
		(width 0.13208)
		(layer "F.Cu")
		(net "SMB_BIC_I2C6_MUX_PEX_ADC_R_SDA")
	)
	(segment
		(start 232.596182 -279.34539)
		(end 232.466642 -279.34539)
		(width 0.13208)
		(layer "F.Cu")
		(net "SMB_BIC_I2C6_MUX_PEX_ADC_R_SDA")
	)
	(segment
		(start 249.136408 -279.055322)
		(end 248.84634 -279.34539)
		(width 0.13208)
		(layer "F.Cu")
		(net "SMB_BIC_I2C6_MUX_PEX_ADC_R_SDA")
	)
	(segment
		(start 463.231484 -279.69083)
		(end 463.475324 -279.44699)
		(width 0.13208)
		(layer "F.Cu")
		(net "SMB_BIC_I2C6_MUX_PEX_ADC_R_SDA")
	)
	(segment
		(start 19.534378 -242.906296)
		(end 19.835622 -243.20754)
		(width 0.13208)
		(layer "F.Cu")
		(net "SMB_BIC_I2C6_MUX_PEX_ADC_R_SDA")
	)
	(segment
		(start 252.036326 -261.761986)
		(end 251.4854 -261.21106)
		(width 0.13208)
		(layer "F.Cu")
		(net "SMB_BIC_I2C6_MUX_PEX_ADC_R_SDA")
	)
	(segment
		(start 248.84634 -279.34539)
		(end 248.7168 -279.34539)
		(width 0.13208)
		(layer "F.Cu")
		(net "SMB_BIC_I2C6_MUX_PEX_ADC_R_SDA")
	)
	(segment
		(start 249.909838 -279.476708)
		(end 249.488452 -279.055322)
		(width 0.13208)
		(layer "F.Cu")
		(net "SMB_BIC_I2C6_MUX_PEX_ADC_R_SDA")
	)
	(segment
		(start 19.209766 -243.637816)
		(end 18.766028 -244.081554)
		(width 0.13208)
		(layer "F.Cu")
		(net "SMB_BIC_I2C6_MUX_PEX_ADC_R_SDA")
	)
	(segment
		(start 232.88625 -279.055322)
		(end 232.596182 -279.34539)
		(width 0.13208)
		(layer "F.Cu")
		(net "SMB_BIC_I2C6_MUX_PEX_ADC_R_SDA")
	)
	(segment
		(start 19.534378 -242.73764)
		(end 19.534378 -242.906296)
		(width 0.13208)
		(layer "F.Cu")
		(net "SMB_BIC_I2C6_MUX_PEX_ADC_R_SDA")
	)
	(segment
		(start 251.4854 -261.21106)
		(end 251.4854 -259.993384)
		(width 0.13208)
		(layer "F.Cu")
		(net "SMB_BIC_I2C6_MUX_PEX_ADC_R_SDA")
	)
	(segment
		(start 19.860768 -242.41125)
		(end 19.534378 -242.73764)
		(width 0.13208)
		(layer "F.Cu")
		(net "SMB_BIC_I2C6_MUX_PEX_ADC_R_SDA")
	)
	(segment
		(start 19.378422 -243.637816)
		(end 19.209766 -243.637816)
		(width 0.13208)
		(layer "F.Cu")
		(net "SMB_BIC_I2C6_MUX_PEX_ADC_R_SDA")
	)
	(segment
		(start 18.766028 -244.081554)
		(end 18.766028 -276.471888)
		(width 0.13208)
		(layer "F.Cu")
		(net "SMB_BIC_I2C6_MUX_PEX_ADC_R_SDA")
	)
	(segment
		(start 19.391884 -243.651278)
		(end 19.378422 -243.637816)
		(width 0.13208)
		(layer "F.Cu")
		(net "SMB_BIC_I2C6_MUX_PEX_ADC_R_SDA")
	)
	(segment
		(start 249.909838 -279.476708)
		(end 252.036326 -277.35022)
		(width 0.13208)
		(layer "F.Cu")
		(net "SMB_BIC_I2C6_MUX_PEX_ADC_R_SDA")
	)
	(segment
		(start 376.807476 -86.443058)
		(end 376.712734 -86.5378)
		(width 0.13208)
		(layer "F.Cu")
		(net "SMB_BIC_I2C6_MUX_PEX_ADC_R_SDA")
	)
	(segment
		(start 19.860768 -241.118644)
		(end 19.860768 -242.41125)
		(width 0.13208)
		(layer "F.Cu")
		(net "SMB_BIC_I2C6_MUX_PEX_ADC_R_SDA")
	)
	(segment
		(start 232.466642 -279.34539)
		(end 232.244646 -279.567386)
		(width 0.13208)
		(layer "F.Cu")
		(net "SMB_BIC_I2C6_MUX_PEX_ADC_R_SDA")
	)
	(segment
		(start 377.675902 -86.443058)
		(end 376.807476 -86.443058)
		(width 0.13208)
		(layer "F.Cu")
		(net "SMB_BIC_I2C6_MUX_PEX_ADC_R_SDA")
	)
	(segment
		(start 18.766028 -276.471888)
		(end 17.957292 -277.280624)
		(width 0.13208)
		(layer "F.Cu")
		(net "SMB_BIC_I2C6_MUX_PEX_ADC_R_SDA")
	)
	(segment
		(start 17.957292 -277.280624)
		(end 17.185386 -277.280624)
		(width 0.13208)
		(layer "F.Cu")
		(net "SMB_BIC_I2C6_MUX_PEX_ADC_R_SDA")
	)
	(segment
		(start 19.835622 -243.376196)
		(end 19.56054 -243.651278)
		(width 0.13208)
		(layer "F.Cu")
		(net "SMB_BIC_I2C6_MUX_PEX_ADC_R_SDA")
	)
	(segment
		(start 462.865724 -279.69083)
		(end 463.231484 -279.69083)
		(width 0.13208)
		(layer "F.Cu")
		(net "SMB_BIC_I2C6_MUX_PEX_ADC_R_SDA")
	)
	(segment
		(start 249.488452 -279.055322)
		(end 249.136408 -279.055322)
		(width 0.13208)
		(layer "F.Cu")
		(net "SMB_BIC_I2C6_MUX_PEX_ADC_R_SDA")
	)
	(segment
		(start 251.4854 -259.993384)
		(end 251.176536 -259.247386)
		(width 0.13208)
		(layer "F.Cu")
		(net "SMB_BIC_I2C6_MUX_PEX_ADC_R_SDA")
	)
	(segment
		(start 19.56054 -243.651278)
		(end 19.391884 -243.651278)
		(width 0.13208)
		(layer "F.Cu")
		(net "SMB_BIC_I2C6_MUX_PEX_ADC_R_SDA")
	)
	(via
		(at 94.034356 -240.744248)
		(size 0.508)
		(drill 0.254)
		(layers "F.Cu" "B.Cu")
		(net "SMB_BIC_I2C6_MUX_PEX_ADC_R_SDA")
	)
	(via
		(at 434.905404 -87.383112)
		(size 0.508)
		(drill 0.254)
		(layers "F.Cu" "B.Cu")
		(net "SMB_BIC_I2C6_MUX_PEX_ADC_R_SDA")
	)
	(via
		(at 232.88625 -279.055322)
		(size 0.508)
		(drill 0.254)
		(layers "F.Cu" "B.Cu")
		(net "SMB_BIC_I2C6_MUX_PEX_ADC_R_SDA")
	)
	(via
		(at 377.675902 -86.443058)
		(size 0.508)
		(drill 0.254)
		(layers "F.Cu" "B.Cu")
		(net "SMB_BIC_I2C6_MUX_PEX_ADC_R_SDA")
	)
	(via
		(at 463.475324 -279.44699)
		(size 0.508)
		(drill 0.254)
		(layers "F.Cu" "B.Cu")
		(net "SMB_BIC_I2C6_MUX_PEX_ADC_R_SDA")
	)
	(via
		(at 249.136408 -279.055322)
		(size 0.508)
		(drill 0.254)
		(layers "F.Cu" "B.Cu")
		(net "SMB_BIC_I2C6_MUX_PEX_ADC_R_SDA")
	)
	(via
		(at 230.739188 -259.868162)
		(size 0.508)
		(drill 0.254)
		(layers "F.Cu" "B.Cu")
		(net "SMB_BIC_I2C6_MUX_PEX_ADC_R_SDA")
	)
	(via
		(at 116.36248 -247.574054)
		(size 0.508)
		(drill 0.254)
		(layers "F.Cu" "B.Cu")
		(net "SMB_BIC_I2C6_MUX_PEX_ADC_R_SDA")
	)
	(via
		(at 251.01296 -259.08381)
		(size 0.508)
		(drill 0.254)
		(layers "F.Cu" "B.Cu")
		(net "SMB_BIC_I2C6_MUX_PEX_ADC_R_SDA")
	)
	(via
		(at 19.854418 -241.112294)
		(size 0.508)
		(drill 0.254)
		(layers "F.Cu" "B.Cu")
		(net "SMB_BIC_I2C6_MUX_PEX_ADC_R_SDA")
	)
	(segment
		(start 97.94621 -249.98045)
		(end 97.94621 -250.603258)
		(width 0.13208)
		(layer "B.Cu")
		(net "SMB_BIC_I2C6_MUX_PEX_ADC_R_SDA")
	)
	(segment
		(start 97.94621 -250.603258)
		(end 97.82683 -250.722638)
		(width 0.13208)
		(layer "B.Cu")
		(net "SMB_BIC_I2C6_MUX_PEX_ADC_R_SDA")
	)
	(segment
		(start 98.82759 -250.603258)
		(end 98.82759 -249.98045)
		(width 0.13208)
		(layer "B.Cu")
		(net "SMB_BIC_I2C6_MUX_PEX_ADC_R_SDA")
	)
	(segment
		(start 96.872044 -250.722638)
		(end 93.272102 -247.122696)
		(width 0.13208)
		(layer "B.Cu")
		(net "SMB_BIC_I2C6_MUX_PEX_ADC_R_SDA")
	)
	(segment
		(start 94.034356 -241.267488)
		(end 94.034356 -240.744248)
		(width 0.13208)
		(layer "B.Cu")
		(net "SMB_BIC_I2C6_MUX_PEX_ADC_R_SDA")
	)
	(segment
		(start 98.82759 -249.98045)
		(end 98.70821 -249.86107)
		(width 0.13208)
		(layer "B.Cu")
		(net "SMB_BIC_I2C6_MUX_PEX_ADC_R_SDA")
	)
	(segment
		(start 116.36248 -247.574054)
		(end 115.785392 -246.996966)
		(width 0.13208)
		(layer "B.Cu")
		(net "SMB_BIC_I2C6_MUX_PEX_ADC_R_SDA")
	)
	(segment
		(start 113.505234 -246.996966)
		(end 109.779562 -250.722638)
		(width 0.13208)
		(layer "B.Cu")
		(net "SMB_BIC_I2C6_MUX_PEX_ADC_R_SDA")
	)
	(segment
		(start 98.70821 -249.86107)
		(end 98.06559 -249.86107)
		(width 0.13208)
		(layer "B.Cu")
		(net "SMB_BIC_I2C6_MUX_PEX_ADC_R_SDA")
	)
	(segment
		(start 93.272102 -247.122696)
		(end 93.272102 -242.029742)
		(width 0.13208)
		(layer "B.Cu")
		(net "SMB_BIC_I2C6_MUX_PEX_ADC_R_SDA")
	)
	(segment
		(start 93.272102 -242.029742)
		(end 94.034356 -241.267488)
		(width 0.13208)
		(layer "B.Cu")
		(net "SMB_BIC_I2C6_MUX_PEX_ADC_R_SDA")
	)
	(segment
		(start 109.779562 -250.722638)
		(end 98.94697 -250.722638)
		(width 0.13208)
		(layer "B.Cu")
		(net "SMB_BIC_I2C6_MUX_PEX_ADC_R_SDA")
	)
	(segment
		(start 98.94697 -250.722638)
		(end 98.82759 -250.603258)
		(width 0.13208)
		(layer "B.Cu")
		(net "SMB_BIC_I2C6_MUX_PEX_ADC_R_SDA")
	)
	(segment
		(start 98.06559 -249.86107)
		(end 97.94621 -249.98045)
		(width 0.13208)
		(layer "B.Cu")
		(net "SMB_BIC_I2C6_MUX_PEX_ADC_R_SDA")
	)
	(segment
		(start 97.82683 -250.722638)
		(end 96.872044 -250.722638)
		(width 0.13208)
		(layer "B.Cu")
		(net "SMB_BIC_I2C6_MUX_PEX_ADC_R_SDA")
	)
	(segment
		(start 115.785392 -246.996966)
		(end 113.505234 -246.996966)
		(width 0.13208)
		(layer "B.Cu")
		(net "SMB_BIC_I2C6_MUX_PEX_ADC_R_SDA")
	)
	(segment
		(start 441.3123 -135.830056)
		(end 436.194708 -130.712464)
		(width 0.15494)
		(layer "In5.Cu")
		(net "SMB_BIC_I2C6_MUX_PEX_ADC_R_SDA")
	)
	(segment
		(start 441.3123 -233.651298)
		(end 441.3123 -135.830056)
		(width 0.15494)
		(layer "In5.Cu")
		(net "SMB_BIC_I2C6_MUX_PEX_ADC_R_SDA")
	)
	(segment
		(start 454.237598 -251.495052)
		(end 451.47484 -251.495052)
		(width 0.15494)
		(layer "In5.Cu")
		(net "SMB_BIC_I2C6_MUX_PEX_ADC_R_SDA")
	)
	(segment
		(start 463.475324 -279.44699)
		(end 463.214974 -279.18664)
		(width 0.15494)
		(layer "In5.Cu")
		(net "SMB_BIC_I2C6_MUX_PEX_ADC_R_SDA")
	)
	(segment
		(start 435.351174 -119.862346)
		(end 432.8414 -117.352572)
		(width 0.15494)
		(layer "In5.Cu")
		(net "SMB_BIC_I2C6_MUX_PEX_ADC_R_SDA")
	)
	(segment
		(start 455.929746 -253.1872)
		(end 454.237598 -251.495052)
		(width 0.15494)
		(layer "In5.Cu")
		(net "SMB_BIC_I2C6_MUX_PEX_ADC_R_SDA")
	)
	(segment
		(start 428.996348 -108.665264)
		(end 428.996348 -100.295202)
		(width 0.15494)
		(layer "In5.Cu")
		(net "SMB_BIC_I2C6_MUX_PEX_ADC_R_SDA")
	)
	(segment
		(start 451.47484 -251.495052)
		(end 450.19976 -250.219972)
		(width 0.15494)
		(layer "In5.Cu")
		(net "SMB_BIC_I2C6_MUX_PEX_ADC_R_SDA")
	)
	(segment
		(start 435.351174 -128.678686)
		(end 435.351174 -119.862346)
		(width 0.15494)
		(layer "In5.Cu")
		(net "SMB_BIC_I2C6_MUX_PEX_ADC_R_SDA")
	)
	(segment
		(start 441.515246 -238.743998)
		(end 441.515246 -233.854244)
		(width 0.15494)
		(layer "In5.Cu")
		(net "SMB_BIC_I2C6_MUX_PEX_ADC_R_SDA")
	)
	(segment
		(start 463.214974 -278.642318)
		(end 465.22767 -276.629622)
		(width 0.15494)
		(layer "In5.Cu")
		(net "SMB_BIC_I2C6_MUX_PEX_ADC_R_SDA")
	)
	(segment
		(start 436.194708 -130.712464)
		(end 435.351174 -128.678686)
		(width 0.15494)
		(layer "In5.Cu")
		(net "SMB_BIC_I2C6_MUX_PEX_ADC_R_SDA")
	)
	(segment
		(start 428.996348 -100.295202)
		(end 435.249574 -94.041976)
		(width 0.15494)
		(layer "In5.Cu")
		(net "SMB_BIC_I2C6_MUX_PEX_ADC_R_SDA")
	)
	(segment
		(start 435.249574 -87.727282)
		(end 434.905404 -87.383112)
		(width 0.15494)
		(layer "In5.Cu")
		(net "SMB_BIC_I2C6_MUX_PEX_ADC_R_SDA")
	)
	(segment
		(start 464.599782 -253.1872)
		(end 455.929746 -253.1872)
		(width 0.15494)
		(layer "In5.Cu")
		(net "SMB_BIC_I2C6_MUX_PEX_ADC_R_SDA")
	)
	(segment
		(start 432.8414 -112.510316)
		(end 428.996348 -108.665264)
		(width 0.15494)
		(layer "In5.Cu")
		(net "SMB_BIC_I2C6_MUX_PEX_ADC_R_SDA")
	)
	(segment
		(start 441.515246 -233.854244)
		(end 441.3123 -233.651298)
		(width 0.15494)
		(layer "In5.Cu")
		(net "SMB_BIC_I2C6_MUX_PEX_ADC_R_SDA")
	)
	(segment
		(start 432.8414 -117.352572)
		(end 432.8414 -112.510316)
		(width 0.15494)
		(layer "In5.Cu")
		(net "SMB_BIC_I2C6_MUX_PEX_ADC_R_SDA")
	)
	(segment
		(start 463.214974 -279.18664)
		(end 463.214974 -278.642318)
		(width 0.15494)
		(layer "In5.Cu")
		(net "SMB_BIC_I2C6_MUX_PEX_ADC_R_SDA")
	)
	(segment
		(start 465.22767 -276.629622)
		(end 465.22767 -253.815088)
		(width 0.15494)
		(layer "In5.Cu")
		(net "SMB_BIC_I2C6_MUX_PEX_ADC_R_SDA")
	)
	(segment
		(start 450.19976 -250.219972)
		(end 450.19976 -247.428512)
		(width 0.15494)
		(layer "In5.Cu")
		(net "SMB_BIC_I2C6_MUX_PEX_ADC_R_SDA")
	)
	(segment
		(start 465.22767 -253.815088)
		(end 464.599782 -253.1872)
		(width 0.15494)
		(layer "In5.Cu")
		(net "SMB_BIC_I2C6_MUX_PEX_ADC_R_SDA")
	)
	(segment
		(start 435.249574 -94.041976)
		(end 435.249574 -87.727282)
		(width 0.15494)
		(layer "In5.Cu")
		(net "SMB_BIC_I2C6_MUX_PEX_ADC_R_SDA")
	)
	(segment
		(start 450.19976 -247.428512)
		(end 441.515246 -238.743998)
		(width 0.15494)
		(layer "In5.Cu")
		(net "SMB_BIC_I2C6_MUX_PEX_ADC_R_SDA")
	)
	(segment
		(start 232.704386 -266.179554)
		(end 233.182414 -266.179554)
		(width 0.15494)
		(layer "In9.Cu")
		(net "SMB_BIC_I2C6_MUX_PEX_ADC_R_SDA")
	)
	(segment
		(start 232.5624 -266.522708)
		(end 232.5624 -266.32154)
		(width 0.15494)
		(layer "In9.Cu")
		(net "SMB_BIC_I2C6_MUX_PEX_ADC_R_SDA")
	)
	(segment
		(start 233.182414 -267.634974)
		(end 232.704386 -267.634974)
		(width 0.15494)
		(layer "In9.Cu")
		(net "SMB_BIC_I2C6_MUX_PEX_ADC_R_SDA")
	)
	(segment
		(start 233.182414 -268.605254)
		(end 232.704386 -268.605254)
		(width 0.15494)
		(layer "In9.Cu")
		(net "SMB_BIC_I2C6_MUX_PEX_ADC_R_SDA")
	)
	(segment
		(start 233.3244 -265.8364)
		(end 233.182414 -265.694414)
		(width 0.15494)
		(layer "In9.Cu")
		(net "SMB_BIC_I2C6_MUX_PEX_ADC_R_SDA")
	)
	(segment
		(start 233.182414 -266.664694)
		(end 232.704386 -266.664694)
		(width 0.15494)
		(layer "In9.Cu")
		(net "SMB_BIC_I2C6_MUX_PEX_ADC_R_SDA")
	)
	(segment
		(start 232.704386 -269.090394)
		(end 233.182414 -269.090394)
		(width 0.15494)
		(layer "In9.Cu")
		(net "SMB_BIC_I2C6_MUX_PEX_ADC_R_SDA")
	)
	(segment
		(start 232.88625 -279.055322)
		(end 233.35107 -279.520142)
		(width 0.15494)
		(layer "In9.Cu")
		(net "SMB_BIC_I2C6_MUX_PEX_ADC_R_SDA")
	)
	(segment
		(start 232.704386 -267.149834)
		(end 233.182414 -267.149834)
		(width 0.15494)
		(layer "In9.Cu")
		(net "SMB_BIC_I2C6_MUX_PEX_ADC_R_SDA")
	)
	(segment
		(start 232.5624 -272.205196)
		(end 232.5624 -269.23238)
		(width 0.15494)
		(layer "In9.Cu")
		(net "SMB_BIC_I2C6_MUX_PEX_ADC_R_SDA")
	)
	(segment
		(start 233.3244 -268.74724)
		(end 233.182414 -268.605254)
		(width 0.15494)
		(layer "In9.Cu")
		(net "SMB_BIC_I2C6_MUX_PEX_ADC_R_SDA")
	)
	(segment
		(start 246.329708 -279.024334)
		(end 246.888 -279.024334)
		(width 0.15494)
		(layer "In9.Cu")
		(net "SMB_BIC_I2C6_MUX_PEX_ADC_R_SDA")
	)
	(segment
		(start 232.5624 -267.492988)
		(end 232.5624 -267.29182)
		(width 0.15494)
		(layer "In9.Cu")
		(net "SMB_BIC_I2C6_MUX_PEX_ADC_R_SDA")
	)
	(segment
		(start 232.704386 -268.605254)
		(end 232.5624 -268.463268)
		(width 0.15494)
		(layer "In9.Cu")
		(net "SMB_BIC_I2C6_MUX_PEX_ADC_R_SDA")
	)
	(segment
		(start 232.5624 -266.32154)
		(end 232.704386 -266.179554)
		(width 0.15494)
		(layer "In9.Cu")
		(net "SMB_BIC_I2C6_MUX_PEX_ADC_R_SDA")
	)
	(segment
		(start 233.3244 -268.948408)
		(end 233.3244 -268.74724)
		(width 0.15494)
		(layer "In9.Cu")
		(net "SMB_BIC_I2C6_MUX_PEX_ADC_R_SDA")
	)
	(segment
		(start 232.5624 -268.463268)
		(end 232.5624 -268.2621)
		(width 0.15494)
		(layer "In9.Cu")
		(net "SMB_BIC_I2C6_MUX_PEX_ADC_R_SDA")
	)
	(segment
		(start 233.3244 -265.067288)
		(end 233.3244 -264.86612)
		(width 0.15494)
		(layer "In9.Cu")
		(net "SMB_BIC_I2C6_MUX_PEX_ADC_R_SDA")
	)
	(segment
		(start 233.3244 -267.007848)
		(end 233.3244 -266.80668)
		(width 0.15494)
		(layer "In9.Cu")
		(net "SMB_BIC_I2C6_MUX_PEX_ADC_R_SDA")
	)
	(segment
		(start 233.182414 -264.724134)
		(end 232.704386 -264.724134)
		(width 0.15494)
		(layer "In9.Cu")
		(net "SMB_BIC_I2C6_MUX_PEX_ADC_R_SDA")
	)
	(segment
		(start 233.182414 -266.179554)
		(end 233.3244 -266.037568)
		(width 0.15494)
		(layer "In9.Cu")
		(net "SMB_BIC_I2C6_MUX_PEX_ADC_R_SDA")
	)
	(segment
		(start 233.3244 -264.86612)
		(end 233.182414 -264.724134)
		(width 0.15494)
		(layer "In9.Cu")
		(net "SMB_BIC_I2C6_MUX_PEX_ADC_R_SDA")
	)
	(segment
		(start 232.283 -272.484596)
		(end 232.5624 -272.205196)
		(width 0.15494)
		(layer "In9.Cu")
		(net "SMB_BIC_I2C6_MUX_PEX_ADC_R_SDA")
	)
	(segment
		(start 233.3244 -266.037568)
		(end 233.3244 -265.8364)
		(width 0.15494)
		(layer "In9.Cu")
		(net "SMB_BIC_I2C6_MUX_PEX_ADC_R_SDA")
	)
	(segment
		(start 233.182414 -265.209274)
		(end 233.3244 -265.067288)
		(width 0.15494)
		(layer "In9.Cu")
		(net "SMB_BIC_I2C6_MUX_PEX_ADC_R_SDA")
	)
	(segment
		(start 232.5624 -264.582148)
		(end 232.5624 -261.691374)
		(width 0.15494)
		(layer "In9.Cu")
		(net "SMB_BIC_I2C6_MUX_PEX_ADC_R_SDA")
	)
	(segment
		(start 232.704386 -266.664694)
		(end 232.5624 -266.522708)
		(width 0.15494)
		(layer "In9.Cu")
		(net "SMB_BIC_I2C6_MUX_PEX_ADC_R_SDA")
	)
	(segment
		(start 232.5624 -265.552428)
		(end 232.5624 -265.35126)
		(width 0.15494)
		(layer "In9.Cu")
		(net "SMB_BIC_I2C6_MUX_PEX_ADC_R_SDA")
	)
	(segment
		(start 233.3244 -266.80668)
		(end 233.182414 -266.664694)
		(width 0.15494)
		(layer "In9.Cu")
		(net "SMB_BIC_I2C6_MUX_PEX_ADC_R_SDA")
	)
	(segment
		(start 241.963194 -279.6032)
		(end 242.264692 -279.301702)
		(width 0.15494)
		(layer "In9.Cu")
		(net "SMB_BIC_I2C6_MUX_PEX_ADC_R_SDA")
	)
	(segment
		(start 232.5624 -265.35126)
		(end 232.704386 -265.209274)
		(width 0.15494)
		(layer "In9.Cu")
		(net "SMB_BIC_I2C6_MUX_PEX_ADC_R_SDA")
	)
	(segment
		(start 246.05234 -279.301702)
		(end 246.329708 -279.024334)
		(width 0.15494)
		(layer "In9.Cu")
		(net "SMB_BIC_I2C6_MUX_PEX_ADC_R_SDA")
	)
	(segment
		(start 240.701322 -279.520142)
		(end 240.78438 -279.6032)
		(width 0.15494)
		(layer "In9.Cu")
		(net "SMB_BIC_I2C6_MUX_PEX_ADC_R_SDA")
	)
	(segment
		(start 232.5624 -268.2621)
		(end 232.704386 -268.120114)
		(width 0.15494)
		(layer "In9.Cu")
		(net "SMB_BIC_I2C6_MUX_PEX_ADC_R_SDA")
	)
	(segment
		(start 240.78438 -279.6032)
		(end 241.963194 -279.6032)
		(width 0.15494)
		(layer "In9.Cu")
		(net "SMB_BIC_I2C6_MUX_PEX_ADC_R_SDA")
	)
	(segment
		(start 232.704386 -264.724134)
		(end 232.5624 -264.582148)
		(width 0.15494)
		(layer "In9.Cu")
		(net "SMB_BIC_I2C6_MUX_PEX_ADC_R_SDA")
	)
	(segment
		(start 232.5624 -267.29182)
		(end 232.704386 -267.149834)
		(width 0.15494)
		(layer "In9.Cu")
		(net "SMB_BIC_I2C6_MUX_PEX_ADC_R_SDA")
	)
	(segment
		(start 242.264692 -279.301702)
		(end 246.05234 -279.301702)
		(width 0.15494)
		(layer "In9.Cu")
		(net "SMB_BIC_I2C6_MUX_PEX_ADC_R_SDA")
	)
	(segment
		(start 232.704386 -265.694414)
		(end 232.5624 -265.552428)
		(width 0.15494)
		(layer "In9.Cu")
		(net "SMB_BIC_I2C6_MUX_PEX_ADC_R_SDA")
	)
	(segment
		(start 232.704386 -268.120114)
		(end 233.182414 -268.120114)
		(width 0.15494)
		(layer "In9.Cu")
		(net "SMB_BIC_I2C6_MUX_PEX_ADC_R_SDA")
	)
	(segment
		(start 246.888 -279.024334)
		(end 246.918988 -279.055322)
		(width 0.15494)
		(layer "In9.Cu")
		(net "SMB_BIC_I2C6_MUX_PEX_ADC_R_SDA")
	)
	(segment
		(start 233.35107 -279.520142)
		(end 240.701322 -279.520142)
		(width 0.15494)
		(layer "In9.Cu")
		(net "SMB_BIC_I2C6_MUX_PEX_ADC_R_SDA")
	)
	(segment
		(start 232.5624 -261.691374)
		(end 230.739188 -259.868162)
		(width 0.15494)
		(layer "In9.Cu")
		(net "SMB_BIC_I2C6_MUX_PEX_ADC_R_SDA")
	)
	(segment
		(start 233.182414 -267.149834)
		(end 233.3244 -267.007848)
		(width 0.15494)
		(layer "In9.Cu")
		(net "SMB_BIC_I2C6_MUX_PEX_ADC_R_SDA")
	)
	(segment
		(start 233.3244 -267.978128)
		(end 233.3244 -267.77696)
		(width 0.15494)
		(layer "In9.Cu")
		(net "SMB_BIC_I2C6_MUX_PEX_ADC_R_SDA")
	)
	(segment
		(start 232.5624 -269.23238)
		(end 232.704386 -269.090394)
		(width 0.15494)
		(layer "In9.Cu")
		(net "SMB_BIC_I2C6_MUX_PEX_ADC_R_SDA")
	)
	(segment
		(start 246.918988 -279.055322)
		(end 249.136408 -279.055322)
		(width 0.15494)
		(layer "In9.Cu")
		(net "SMB_BIC_I2C6_MUX_PEX_ADC_R_SDA")
	)
	(segment
		(start 233.3244 -267.77696)
		(end 233.182414 -267.634974)
		(width 0.15494)
		(layer "In9.Cu")
		(net "SMB_BIC_I2C6_MUX_PEX_ADC_R_SDA")
	)
	(segment
		(start 233.182414 -265.694414)
		(end 232.704386 -265.694414)
		(width 0.15494)
		(layer "In9.Cu")
		(net "SMB_BIC_I2C6_MUX_PEX_ADC_R_SDA")
	)
	(segment
		(start 232.704386 -267.634974)
		(end 232.5624 -267.492988)
		(width 0.15494)
		(layer "In9.Cu")
		(net "SMB_BIC_I2C6_MUX_PEX_ADC_R_SDA")
	)
	(segment
		(start 232.704386 -265.209274)
		(end 233.182414 -265.209274)
		(width 0.15494)
		(layer "In9.Cu")
		(net "SMB_BIC_I2C6_MUX_PEX_ADC_R_SDA")
	)
	(segment
		(start 233.182414 -269.090394)
		(end 233.3244 -268.948408)
		(width 0.15494)
		(layer "In9.Cu")
		(net "SMB_BIC_I2C6_MUX_PEX_ADC_R_SDA")
	)
	(segment
		(start 232.283 -278.452072)
		(end 232.283 -272.484596)
		(width 0.15494)
		(layer "In9.Cu")
		(net "SMB_BIC_I2C6_MUX_PEX_ADC_R_SDA")
	)
	(segment
		(start 232.88625 -279.055322)
		(end 232.283 -278.452072)
		(width 0.15494)
		(layer "In9.Cu")
		(net "SMB_BIC_I2C6_MUX_PEX_ADC_R_SDA")
	)
	(segment
		(start 233.182414 -268.120114)
		(end 233.3244 -267.978128)
		(width 0.15494)
		(layer "In9.Cu")
		(net "SMB_BIC_I2C6_MUX_PEX_ADC_R_SDA")
	)
	(segment
		(start 257.0734 -260.075934)
		(end 257.548126 -260.075934)
		(width 0.15494)
		(layer "In13.Cu")
		(net "SMB_BIC_I2C6_MUX_PEX_ADC_R_SDA")
	)
	(segment
		(start 463.243676 -257.330702)
		(end 462.739486 -257.834892)
		(width 0.15494)
		(layer "In13.Cu")
		(net "SMB_BIC_I2C6_MUX_PEX_ADC_R_SDA")
	)
	(segment
		(start 156.921962 -248.619772)
		(end 157.804612 -249.502422)
		(width 0.15494)
		(layer "In13.Cu")
		(net "SMB_BIC_I2C6_MUX_PEX_ADC_R_SDA")
	)
	(segment
		(start 388.746746 -239.5728)
		(end 389.095488 -239.224058)
		(width 0.15494)
		(layer "In13.Cu")
		(net "SMB_BIC_I2C6_MUX_PEX_ADC_R_SDA")
	)
	(segment
		(start 461.971644 -256.05867)
		(end 461.467454 -256.56286)
		(width 0.15494)
		(layer "In13.Cu")
		(net "SMB_BIC_I2C6_MUX_PEX_ADC_R_SDA")
	)
	(segment
		(start 460.195422 -255.290828)
		(end 460.195422 -255.481328)
		(width 0.15494)
		(layer "In13.Cu")
		(net "SMB_BIC_I2C6_MUX_PEX_ADC_R_SDA")
	)
	(segment
		(start 461.467454 -256.75336)
		(end 461.91297 -257.198876)
		(width 0.15494)
		(layer "In13.Cu")
		(net "SMB_BIC_I2C6_MUX_PEX_ADC_R_SDA")
	)
	(segment
		(start 462.739486 -258.025392)
		(end 463.185002 -258.470908)
		(width 0.15494)
		(layer "In13.Cu")
		(net "SMB_BIC_I2C6_MUX_PEX_ADC_R_SDA")
	)
	(segment
		(start 257.548126 -260.075934)
		(end 258.64566 -258.9784)
		(width 0.15494)
		(layer "In13.Cu")
		(net "SMB_BIC_I2C6_MUX_PEX_ADC_R_SDA")
	)
	(segment
		(start 378.4092 -242.9002)
		(end 382.00457 -242.9002)
		(width 0.15494)
		(layer "In13.Cu")
		(net "SMB_BIC_I2C6_MUX_PEX_ADC_R_SDA")
	)
	(segment
		(start 228.655626 -257.7846)
		(end 230.739188 -259.868162)
		(width 0.15494)
		(layer "In13.Cu")
		(net "SMB_BIC_I2C6_MUX_PEX_ADC_R_SDA")
	)
	(segment
		(start 462.290414 -246.111014)
		(end 462.290414 -253.05258)
		(width 0.15494)
		(layer "In13.Cu")
		(net "SMB_BIC_I2C6_MUX_PEX_ADC_R_SDA")
	)
	(segment
		(start 384.748024 -242.386866)
		(end 385.846828 -241.288062)
		(width 0.15494)
		(layer "In13.Cu")
		(net "SMB_BIC_I2C6_MUX_PEX_ADC_R_SDA")
	)
	(segment
		(start 422.327324 -238.35487)
		(end 423.926254 -239.9538)
		(width 0.15494)
		(layer "In13.Cu")
		(net "SMB_BIC_I2C6_MUX_PEX_ADC_R_SDA")
	)
	(segment
		(start 389.095488 -239.224058)
		(end 415.918396 -239.224058)
		(width 0.15494)
		(layer "In13.Cu")
		(net "SMB_BIC_I2C6_MUX_PEX_ADC_R_SDA")
	)
	(segment
		(start 463.997294 -258.028948)
		(end 464.82 -258.851654)
		(width 0.15494)
		(layer "In13.Cu")
		(net "SMB_BIC_I2C6_MUX_PEX_ADC_R_SDA")
	)
	(segment
		(start 313.299348 -257.07213)
		(end 328.11339 -257.07213)
		(width 0.15494)
		(layer "In13.Cu")
		(net "SMB_BIC_I2C6_MUX_PEX_ADC_R_SDA")
	)
	(segment
		(start 463.185002 -258.470908)
		(end 463.375502 -258.470908)
		(width 0.15494)
		(layer "In13.Cu")
		(net "SMB_BIC_I2C6_MUX_PEX_ADC_R_SDA")
	)
	(segment
		(start 136.509252 -247.1928)
		(end 137.612882 -248.29643)
		(width 0.15494)
		(layer "In13.Cu")
		(net "SMB_BIC_I2C6_MUX_PEX_ADC_R_SDA")
	)
	(segment
		(start 462.290414 -253.05258)
		(end 462.000092 -253.342902)
		(width 0.15494)
		(layer "In13.Cu")
		(net "SMB_BIC_I2C6_MUX_PEX_ADC_R_SDA")
	)
	(segment
		(start 463.221832 -278.635714)
		(end 463.221832 -279.193498)
		(width 0.15494)
		(layer "In13.Cu")
		(net "SMB_BIC_I2C6_MUX_PEX_ADC_R_SDA")
	)
	(segment
		(start 461.91297 -257.198876)
		(end 462.10347 -257.198876)
		(width 0.15494)
		(layer "In13.Cu")
		(net "SMB_BIC_I2C6_MUX_PEX_ADC_R_SDA")
	)
	(segment
		(start 460.609442 -253.342902)
		(end 460.318866 -253.633478)
		(width 0.15494)
		(layer "In13.Cu")
		(net "SMB_BIC_I2C6_MUX_PEX_ADC_R_SDA")
	)
	(segment
		(start 386.36321 -239.5728)
		(end 388.746746 -239.5728)
		(width 0.15494)
		(layer "In13.Cu")
		(net "SMB_BIC_I2C6_MUX_PEX_ADC_R_SDA")
	)
	(segment
		(start 253.355348 -261.426198)
		(end 255.723136 -261.426198)
		(width 0.15494)
		(layer "In13.Cu")
		(net "SMB_BIC_I2C6_MUX_PEX_ADC_R_SDA")
	)
	(segment
		(start 357.979726 -241.7318)
		(end 370.857526 -241.7318)
		(width 0.15494)
		(layer "In13.Cu")
		(net "SMB_BIC_I2C6_MUX_PEX_ADC_R_SDA")
	)
	(segment
		(start 463.221832 -279.193498)
		(end 463.475324 -279.44699)
		(width 0.15494)
		(layer "In13.Cu")
		(net "SMB_BIC_I2C6_MUX_PEX_ADC_R_SDA")
	)
	(segment
		(start 339.204554 -256.12852)
		(end 343.01684 -252.316234)
		(width 0.15494)
		(layer "In13.Cu")
		(net "SMB_BIC_I2C6_MUX_PEX_ADC_R_SDA")
	)
	(segment
		(start 461.335628 -255.422654)
		(end 461.526128 -255.422654)
		(width 0.15494)
		(layer "In13.Cu")
		(net "SMB_BIC_I2C6_MUX_PEX_ADC_R_SDA")
	)
	(segment
		(start 267.4239 -258.37134)
		(end 298.569126 -258.37134)
		(width 0.15494)
		(layer "In13.Cu")
		(net "SMB_BIC_I2C6_MUX_PEX_ADC_R_SDA")
	)
	(segment
		(start 251.01296 -259.08381)
		(end 253.355348 -261.426198)
		(width 0.15494)
		(layer "In13.Cu")
		(net "SMB_BIC_I2C6_MUX_PEX_ADC_R_SDA")
	)
	(segment
		(start 382.517904 -242.386866)
		(end 384.748024 -242.386866)
		(width 0.15494)
		(layer "In13.Cu")
		(net "SMB_BIC_I2C6_MUX_PEX_ADC_R_SDA")
	)
	(segment
		(start 462.79816 -256.694686)
		(end 463.243676 -257.140202)
		(width 0.15494)
		(layer "In13.Cu")
		(net "SMB_BIC_I2C6_MUX_PEX_ADC_R_SDA")
	)
	(segment
		(start 415.918396 -239.224058)
		(end 416.787584 -238.35487)
		(width 0.15494)
		(layer "In13.Cu")
		(net "SMB_BIC_I2C6_MUX_PEX_ADC_R_SDA")
	)
	(segment
		(start 382.00457 -242.9002)
		(end 382.517904 -242.386866)
		(width 0.15494)
		(layer "In13.Cu")
		(net "SMB_BIC_I2C6_MUX_PEX_ADC_R_SDA")
	)
	(segment
		(start 460.640938 -255.926844)
		(end 460.831438 -255.926844)
		(width 0.15494)
		(layer "In13.Cu")
		(net "SMB_BIC_I2C6_MUX_PEX_ADC_R_SDA")
	)
	(segment
		(start 423.926254 -239.9538)
		(end 456.1332 -239.9538)
		(width 0.15494)
		(layer "In13.Cu")
		(net "SMB_BIC_I2C6_MUX_PEX_ADC_R_SDA")
	)
	(segment
		(start 298.569126 -258.37134)
		(end 301.142146 -260.94436)
		(width 0.15494)
		(layer "In13.Cu")
		(net "SMB_BIC_I2C6_MUX_PEX_ADC_R_SDA")
	)
	(segment
		(start 464.82 -277.037546)
		(end 463.221832 -278.635714)
		(width 0.15494)
		(layer "In13.Cu")
		(net "SMB_BIC_I2C6_MUX_PEX_ADC_R_SDA")
	)
	(segment
		(start 301.142146 -260.94436)
		(end 309.427118 -260.94436)
		(width 0.15494)
		(layer "In13.Cu")
		(net "SMB_BIC_I2C6_MUX_PEX_ADC_R_SDA")
	)
	(segment
		(start 460.699612 -254.596138)
		(end 460.699612 -254.786638)
		(width 0.15494)
		(layer "In13.Cu")
		(net "SMB_BIC_I2C6_MUX_PEX_ADC_R_SDA")
	)
	(segment
		(start 164.263324 -263.644126)
		(end 170.22445 -257.683)
		(width 0.15494)
		(layer "In13.Cu")
		(net "SMB_BIC_I2C6_MUX_PEX_ADC_R_SDA")
	)
	(segment
		(start 137.612882 -248.29643)
		(end 149.131782 -248.29643)
		(width 0.15494)
		(layer "In13.Cu")
		(net "SMB_BIC_I2C6_MUX_PEX_ADC_R_SDA")
	)
	(segment
		(start 463.243676 -257.140202)
		(end 463.243676 -257.330702)
		(width 0.15494)
		(layer "In13.Cu")
		(net "SMB_BIC_I2C6_MUX_PEX_ADC_R_SDA")
	)
	(segment
		(start 149.455124 -248.619772)
		(end 156.921962 -248.619772)
		(width 0.15494)
		(layer "In13.Cu")
		(net "SMB_BIC_I2C6_MUX_PEX_ADC_R_SDA")
	)
	(segment
		(start 462.739486 -257.834892)
		(end 462.739486 -258.025392)
		(width 0.15494)
		(layer "In13.Cu")
		(net "SMB_BIC_I2C6_MUX_PEX_ADC_R_SDA")
	)
	(segment
		(start 462.000092 -253.342902)
		(end 460.609442 -253.342902)
		(width 0.15494)
		(layer "In13.Cu")
		(net "SMB_BIC_I2C6_MUX_PEX_ADC_R_SDA")
	)
	(segment
		(start 116.36248 -247.574054)
		(end 116.743734 -247.1928)
		(width 0.15494)
		(layer "In13.Cu")
		(net "SMB_BIC_I2C6_MUX_PEX_ADC_R_SDA")
	)
	(segment
		(start 266.81684 -258.9784)
		(end 267.4239 -258.37134)
		(width 0.15494)
		(layer "In13.Cu")
		(net "SMB_BIC_I2C6_MUX_PEX_ADC_R_SDA")
	)
	(segment
		(start 157.804612 -249.502422)
		(end 157.804612 -255.616456)
		(width 0.15494)
		(layer "In13.Cu")
		(net "SMB_BIC_I2C6_MUX_PEX_ADC_R_SDA")
	)
	(segment
		(start 460.195422 -255.481328)
		(end 460.640938 -255.926844)
		(width 0.15494)
		(layer "In13.Cu")
		(net "SMB_BIC_I2C6_MUX_PEX_ADC_R_SDA")
	)
	(segment
		(start 462.60766 -256.694686)
		(end 462.79816 -256.694686)
		(width 0.15494)
		(layer "In13.Cu")
		(net "SMB_BIC_I2C6_MUX_PEX_ADC_R_SDA")
	)
	(segment
		(start 385.846828 -241.288062)
		(end 385.846828 -240.089182)
		(width 0.15494)
		(layer "In13.Cu")
		(net "SMB_BIC_I2C6_MUX_PEX_ADC_R_SDA")
	)
	(segment
		(start 456.1332 -239.9538)
		(end 462.290414 -246.111014)
		(width 0.15494)
		(layer "In13.Cu")
		(net "SMB_BIC_I2C6_MUX_PEX_ADC_R_SDA")
	)
	(segment
		(start 464.82 -258.851654)
		(end 464.82 -277.037546)
		(width 0.15494)
		(layer "In13.Cu")
		(net "SMB_BIC_I2C6_MUX_PEX_ADC_R_SDA")
	)
	(segment
		(start 343.01684 -251.84354)
		(end 347.50502 -247.35536)
		(width 0.15494)
		(layer "In13.Cu")
		(net "SMB_BIC_I2C6_MUX_PEX_ADC_R_SDA")
	)
	(segment
		(start 116.743734 -247.1928)
		(end 136.509252 -247.1928)
		(width 0.15494)
		(layer "In13.Cu")
		(net "SMB_BIC_I2C6_MUX_PEX_ADC_R_SDA")
	)
	(segment
		(start 372.041928 -242.222528)
		(end 373.4562 -243.6368)
		(width 0.15494)
		(layer "In13.Cu")
		(net "SMB_BIC_I2C6_MUX_PEX_ADC_R_SDA")
	)
	(segment
		(start 385.846828 -240.089182)
		(end 386.36321 -239.5728)
		(width 0.15494)
		(layer "In13.Cu")
		(net "SMB_BIC_I2C6_MUX_PEX_ADC_R_SDA")
	)
	(segment
		(start 156.082238 -262.666734)
		(end 157.05963 -263.644126)
		(width 0.15494)
		(layer "In13.Cu")
		(net "SMB_BIC_I2C6_MUX_PEX_ADC_R_SDA")
	)
	(segment
		(start 329.057 -256.12852)
		(end 339.204554 -256.12852)
		(width 0.15494)
		(layer "In13.Cu")
		(net "SMB_BIC_I2C6_MUX_PEX_ADC_R_SDA")
	)
	(segment
		(start 156.082238 -257.33883)
		(end 156.082238 -262.666734)
		(width 0.15494)
		(layer "In13.Cu")
		(net "SMB_BIC_I2C6_MUX_PEX_ADC_R_SDA")
	)
	(segment
		(start 463.375502 -258.470908)
		(end 463.817462 -258.028948)
		(width 0.15494)
		(layer "In13.Cu")
		(net "SMB_BIC_I2C6_MUX_PEX_ADC_R_SDA")
	)
	(segment
		(start 377.6726 -243.6368)
		(end 378.4092 -242.9002)
		(width 0.15494)
		(layer "In13.Cu")
		(net "SMB_BIC_I2C6_MUX_PEX_ADC_R_SDA")
	)
	(segment
		(start 461.467454 -256.56286)
		(end 461.467454 -256.75336)
		(width 0.15494)
		(layer "In13.Cu")
		(net "SMB_BIC_I2C6_MUX_PEX_ADC_R_SDA")
	)
	(segment
		(start 210.286854 -257.683)
		(end 210.388454 -257.7846)
		(width 0.15494)
		(layer "In13.Cu")
		(net "SMB_BIC_I2C6_MUX_PEX_ADC_R_SDA")
	)
	(segment
		(start 463.817462 -258.028948)
		(end 463.997294 -258.028948)
		(width 0.15494)
		(layer "In13.Cu")
		(net "SMB_BIC_I2C6_MUX_PEX_ADC_R_SDA")
	)
	(segment
		(start 462.10347 -257.198876)
		(end 462.60766 -256.694686)
		(width 0.15494)
		(layer "In13.Cu")
		(net "SMB_BIC_I2C6_MUX_PEX_ADC_R_SDA")
	)
	(segment
		(start 157.05963 -263.644126)
		(end 164.263324 -263.644126)
		(width 0.15494)
		(layer "In13.Cu")
		(net "SMB_BIC_I2C6_MUX_PEX_ADC_R_SDA")
	)
	(segment
		(start 309.427118 -260.94436)
		(end 313.299348 -257.07213)
		(width 0.15494)
		(layer "In13.Cu")
		(net "SMB_BIC_I2C6_MUX_PEX_ADC_R_SDA")
	)
	(segment
		(start 210.388454 -257.7846)
		(end 228.655626 -257.7846)
		(width 0.15494)
		(layer "In13.Cu")
		(net "SMB_BIC_I2C6_MUX_PEX_ADC_R_SDA")
	)
	(segment
		(start 255.723136 -261.426198)
		(end 257.0734 -260.075934)
		(width 0.15494)
		(layer "In13.Cu")
		(net "SMB_BIC_I2C6_MUX_PEX_ADC_R_SDA")
	)
	(segment
		(start 461.971644 -255.86817)
		(end 461.971644 -256.05867)
		(width 0.15494)
		(layer "In13.Cu")
		(net "SMB_BIC_I2C6_MUX_PEX_ADC_R_SDA")
	)
	(segment
		(start 460.831438 -255.926844)
		(end 461.335628 -255.422654)
		(width 0.15494)
		(layer "In13.Cu")
		(net "SMB_BIC_I2C6_MUX_PEX_ADC_R_SDA")
	)
	(segment
		(start 157.804612 -255.616456)
		(end 156.082238 -257.33883)
		(width 0.15494)
		(layer "In13.Cu")
		(net "SMB_BIC_I2C6_MUX_PEX_ADC_R_SDA")
	)
	(segment
		(start 170.22445 -257.683)
		(end 210.286854 -257.683)
		(width 0.15494)
		(layer "In13.Cu")
		(net "SMB_BIC_I2C6_MUX_PEX_ADC_R_SDA")
	)
	(segment
		(start 258.64566 -258.9784)
		(end 266.81684 -258.9784)
		(width 0.15494)
		(layer "In13.Cu")
		(net "SMB_BIC_I2C6_MUX_PEX_ADC_R_SDA")
	)
	(segment
		(start 373.4562 -243.6368)
		(end 377.6726 -243.6368)
		(width 0.15494)
		(layer "In13.Cu")
		(net "SMB_BIC_I2C6_MUX_PEX_ADC_R_SDA")
	)
	(segment
		(start 328.11339 -257.07213)
		(end 329.057 -256.12852)
		(width 0.15494)
		(layer "In13.Cu")
		(net "SMB_BIC_I2C6_MUX_PEX_ADC_R_SDA")
	)
	(segment
		(start 352.356166 -247.35536)
		(end 357.979726 -241.7318)
		(width 0.15494)
		(layer "In13.Cu")
		(net "SMB_BIC_I2C6_MUX_PEX_ADC_R_SDA")
	)
	(segment
		(start 370.857526 -241.7318)
		(end 372.041928 -242.222528)
		(width 0.15494)
		(layer "In13.Cu")
		(net "SMB_BIC_I2C6_MUX_PEX_ADC_R_SDA")
	)
	(segment
		(start 149.131782 -248.29643)
		(end 149.455124 -248.619772)
		(width 0.15494)
		(layer "In13.Cu")
		(net "SMB_BIC_I2C6_MUX_PEX_ADC_R_SDA")
	)
	(segment
		(start 343.01684 -252.316234)
		(end 343.01684 -251.84354)
		(width 0.15494)
		(layer "In13.Cu")
		(net "SMB_BIC_I2C6_MUX_PEX_ADC_R_SDA")
	)
	(segment
		(start 461.526128 -255.422654)
		(end 461.971644 -255.86817)
		(width 0.15494)
		(layer "In13.Cu")
		(net "SMB_BIC_I2C6_MUX_PEX_ADC_R_SDA")
	)
	(segment
		(start 460.699612 -254.786638)
		(end 460.195422 -255.290828)
		(width 0.15494)
		(layer "In13.Cu")
		(net "SMB_BIC_I2C6_MUX_PEX_ADC_R_SDA")
	)
	(segment
		(start 416.787584 -238.35487)
		(end 422.327324 -238.35487)
		(width 0.15494)
		(layer "In13.Cu")
		(net "SMB_BIC_I2C6_MUX_PEX_ADC_R_SDA")
	)
	(segment
		(start 460.318866 -253.633478)
		(end 460.318866 -254.215392)
		(width 0.15494)
		(layer "In13.Cu")
		(net "SMB_BIC_I2C6_MUX_PEX_ADC_R_SDA")
	)
	(segment
		(start 460.318866 -254.215392)
		(end 460.699612 -254.596138)
		(width 0.15494)
		(layer "In13.Cu")
		(net "SMB_BIC_I2C6_MUX_PEX_ADC_R_SDA")
	)
	(segment
		(start 347.50502 -247.35536)
		(end 352.356166 -247.35536)
		(width 0.15494)
		(layer "In13.Cu")
		(net "SMB_BIC_I2C6_MUX_PEX_ADC_R_SDA")
	)
	(segment
		(start 93.66631 -241.112294)
		(end 94.034356 -240.744248)
		(width 0.15494)
		(layer "In15.Cu")
		(net "SMB_BIC_I2C6_MUX_PEX_ADC_R_SDA")
	)
	(segment
		(start 417.76269 -82.723228)
		(end 419.51402 -84.474558)
		(width 0.15494)
		(layer "In15.Cu")
		(net "SMB_BIC_I2C6_MUX_PEX_ADC_R_SDA")
	)
	(segment
		(start 383.746502 -85.493352)
		(end 384.500628 -84.739226)
		(width 0.15494)
		(layer "In15.Cu")
		(net "SMB_BIC_I2C6_MUX_PEX_ADC_R_SDA")
	)
	(segment
		(start 397.4211 -86.544912)
		(end 398.68856 -85.277452)
		(width 0.15494)
		(layer "In15.Cu")
		(net "SMB_BIC_I2C6_MUX_PEX_ADC_R_SDA")
	)
	(segment
		(start 384.500628 -84.739226)
		(end 390.771888 -84.739226)
		(width 0.15494)
		(layer "In15.Cu")
		(net "SMB_BIC_I2C6_MUX_PEX_ADC_R_SDA")
	)
	(segment
		(start 426.651166 -86.244938)
		(end 427.78934 -87.383112)
		(width 0.15494)
		(layer "In15.Cu")
		(net "SMB_BIC_I2C6_MUX_PEX_ADC_R_SDA")
	)
	(segment
		(start 400.488404 -85.277452)
		(end 403.042628 -82.723228)
		(width 0.15494)
		(layer "In15.Cu")
		(net "SMB_BIC_I2C6_MUX_PEX_ADC_R_SDA")
	)
	(segment
		(start 424.81373 -85.741764)
		(end 425.316904 -86.244938)
		(width 0.15494)
		(layer "In15.Cu")
		(net "SMB_BIC_I2C6_MUX_PEX_ADC_R_SDA")
	)
	(segment
		(start 393.139168 -87.106506)
		(end 395.962378 -87.106506)
		(width 0.15494)
		(layer "In15.Cu")
		(net "SMB_BIC_I2C6_MUX_PEX_ADC_R_SDA")
	)
	(segment
		(start 403.042628 -82.723228)
		(end 417.76269 -82.723228)
		(width 0.15494)
		(layer "In15.Cu")
		(net "SMB_BIC_I2C6_MUX_PEX_ADC_R_SDA")
	)
	(segment
		(start 390.771888 -84.739226)
		(end 393.139168 -87.106506)
		(width 0.15494)
		(layer "In15.Cu")
		(net "SMB_BIC_I2C6_MUX_PEX_ADC_R_SDA")
	)
	(segment
		(start 377.675902 -86.443058)
		(end 378.755656 -86.443058)
		(width 0.15494)
		(layer "In15.Cu")
		(net "SMB_BIC_I2C6_MUX_PEX_ADC_R_SDA")
	)
	(segment
		(start 395.962378 -87.106506)
		(end 396.523972 -86.544912)
		(width 0.15494)
		(layer "In15.Cu")
		(net "SMB_BIC_I2C6_MUX_PEX_ADC_R_SDA")
	)
	(segment
		(start 398.68856 -85.277452)
		(end 400.488404 -85.277452)
		(width 0.15494)
		(layer "In15.Cu")
		(net "SMB_BIC_I2C6_MUX_PEX_ADC_R_SDA")
	)
	(segment
		(start 378.755656 -86.443058)
		(end 379.404372 -87.091774)
		(width 0.15494)
		(layer "In15.Cu")
		(net "SMB_BIC_I2C6_MUX_PEX_ADC_R_SDA")
	)
	(segment
		(start 427.78934 -87.383112)
		(end 434.905404 -87.383112)
		(width 0.15494)
		(layer "In15.Cu")
		(net "SMB_BIC_I2C6_MUX_PEX_ADC_R_SDA")
	)
	(segment
		(start 382.328166 -85.493352)
		(end 383.746502 -85.493352)
		(width 0.15494)
		(layer "In15.Cu")
		(net "SMB_BIC_I2C6_MUX_PEX_ADC_R_SDA")
	)
	(segment
		(start 19.854418 -241.112294)
		(end 93.66631 -241.112294)
		(width 0.15494)
		(layer "In15.Cu")
		(net "SMB_BIC_I2C6_MUX_PEX_ADC_R_SDA")
	)
	(segment
		(start 380.729744 -87.091774)
		(end 382.328166 -85.493352)
		(width 0.15494)
		(layer "In15.Cu")
		(net "SMB_BIC_I2C6_MUX_PEX_ADC_R_SDA")
	)
	(segment
		(start 425.316904 -86.244938)
		(end 426.651166 -86.244938)
		(width 0.15494)
		(layer "In15.Cu")
		(net "SMB_BIC_I2C6_MUX_PEX_ADC_R_SDA")
	)
	(segment
		(start 396.523972 -86.544912)
		(end 397.4211 -86.544912)
		(width 0.15494)
		(layer "In15.Cu")
		(net "SMB_BIC_I2C6_MUX_PEX_ADC_R_SDA")
	)
	(segment
		(start 379.404372 -87.091774)
		(end 380.729744 -87.091774)
		(width 0.15494)
		(layer "In15.Cu")
		(net "SMB_BIC_I2C6_MUX_PEX_ADC_R_SDA")
	)
	(segment
		(start 419.51402 -84.474558)
		(end 423.54627 -84.474558)
		(width 0.15494)
		(layer "In15.Cu")
		(net "SMB_BIC_I2C6_MUX_PEX_ADC_R_SDA")
	)
	(segment
		(start 424.81373 -85.742018)
		(end 424.81373 -85.741764)
		(width 0.15494)
		(layer "In15.Cu")
		(net "SMB_BIC_I2C6_MUX_PEX_ADC_R_SDA")
	)
	(segment
		(start 423.54627 -84.474558)
		(end 424.81373 -85.742018)
		(width 0.15494)
		(layer "In15.Cu")
		(net "SMB_BIC_I2C6_MUX_PEX_ADC_R_SDA")
	)
	(segment
		(start 146.255486 -389.998204)
		(end 146.255486 -389.359648)
		(width 0.13208)
		(layer "F.Cu")
		(net "GPU_FPGA_BOOT_EN_R")
	)
	(via
		(at 146.255486 -389.359648)
		(size 0.508)
		(drill 0.254)
		(layers "F.Cu" "B.Cu")
		(net "GPU_FPGA_BOOT_EN_R")
	)
	(segment
		(start 148.463254 -390.7282)
		(end 148.920454 -391.1854)
		(width 0.15494)
		(layer "In9.Cu")
		(net "GPU_FPGA_BOOT_EN_R")
	)
	(segment
		(start 151.5872 -391.1854)
		(end 154.8384 -394.4366)
		(width 0.15494)
		(layer "In9.Cu")
		(net "GPU_FPGA_BOOT_EN_R")
	)
	(segment
		(start 180.467 -412.1658)
		(end 180.467 -403.547072)
		(width 0.15494)
		(layer "In9.Cu")
		(net "GPU_FPGA_BOOT_EN_R")
	)
	(segment
		(start 177.7238 -414.909)
		(end 180.467 -412.1658)
		(width 0.15494)
		(layer "In9.Cu")
		(net "GPU_FPGA_BOOT_EN_R")
	)
	(segment
		(start 180.467 -403.547072)
		(end 179.71008 -402.790152)
		(width 0.15494)
		(layer "In9.Cu")
		(net "GPU_FPGA_BOOT_EN_R")
	)
	(segment
		(start 158.5468 -414.909)
		(end 177.7238 -414.909)
		(width 0.15494)
		(layer "In9.Cu")
		(net "GPU_FPGA_BOOT_EN_R")
	)
	(segment
		(start 154.8384 -394.4366)
		(end 154.8384 -411.2006)
		(width 0.15494)
		(layer "In9.Cu")
		(net "GPU_FPGA_BOOT_EN_R")
	)
	(segment
		(start 154.8384 -411.2006)
		(end 158.5468 -414.909)
		(width 0.15494)
		(layer "In9.Cu")
		(net "GPU_FPGA_BOOT_EN_R")
	)
	(segment
		(start 147.244054 -390.7282)
		(end 148.463254 -390.7282)
		(width 0.15494)
		(layer "In9.Cu")
		(net "GPU_FPGA_BOOT_EN_R")
	)
	(segment
		(start 146.255486 -389.359648)
		(end 146.255486 -389.739632)
		(width 0.15494)
		(layer "In9.Cu")
		(net "GPU_FPGA_BOOT_EN_R")
	)
	(segment
		(start 148.920454 -391.1854)
		(end 151.5872 -391.1854)
		(width 0.15494)
		(layer "In9.Cu")
		(net "GPU_FPGA_BOOT_EN_R")
	)
	(segment
		(start 146.255486 -389.739632)
		(end 147.244054 -390.7282)
		(width 0.15494)
		(layer "In9.Cu")
		(net "GPU_FPGA_BOOT_EN_R")
	)
	(segment
		(start 212.405722 -243.570506)
		(end 212.405722 -242.03787)
		(width 0.13208)
		(layer "F.Cu")
		(net "SMB_PEX_R_SDA")
	)
	(segment
		(start 212.405722 -242.03787)
		(end 212.405722 -241.07267)
		(width 0.13208)
		(layer "F.Cu")
		(net "SMB_PEX_R_SDA")
	)
	(segment
		(start 212.451442 -243.616226)
		(end 212.405722 -243.570506)
		(width 0.13208)
		(layer "F.Cu")
		(net "SMB_PEX_R_SDA")
	)
	(via
		(at 220.242384 -237.734602)
		(size 0.508)
		(drill 0.254)
		(layers "F.Cu" "B.Cu")
		(net "SMB_PEX_R_SDA")
	)
	(via
		(at 212.405722 -241.07267)
		(size 0.508)
		(drill 0.254)
		(layers "F.Cu" "B.Cu")
		(net "SMB_PEX_R_SDA")
	)
	(via
		(at 216.200736 -220.334586)
		(size 0.508)
		(drill 0.254)
		(layers "F.Cu" "B.Cu")
		(net "SMB_PEX_R_SDA")
	)
	(segment
		(start 220.242384 -237.734602)
		(end 219.060522 -238.916464)
		(width 0.13208)
		(layer "B.Cu")
		(net "SMB_PEX_R_SDA")
	)
	(segment
		(start 212.585808 -240.251742)
		(end 212.585808 -240.637822)
		(width 0.13208)
		(layer "B.Cu")
		(net "SMB_PEX_R_SDA")
	)
	(segment
		(start 216.200736 -220.334586)
		(end 215.68537 -219.81922)
		(width 0.13208)
		(layer "B.Cu")
		(net "SMB_PEX_R_SDA")
	)
	(segment
		(start 212.585808 -240.637822)
		(end 212.405722 -241.07267)
		(width 0.13208)
		(layer "B.Cu")
		(net "SMB_PEX_R_SDA")
	)
	(segment
		(start 214.512906 -219.81922)
		(end 214.201248 -220.130878)
		(width 0.13208)
		(layer "B.Cu")
		(net "SMB_PEX_R_SDA")
	)
	(segment
		(start 216.200736 -220.334586)
		(end 216.835736 -220.334586)
		(width 0.13208)
		(layer "B.Cu")
		(net "SMB_PEX_R_SDA")
	)
	(segment
		(start 214.201248 -220.130878)
		(end 214.201248 -220.322902)
		(width 0.13208)
		(layer "B.Cu")
		(net "SMB_PEX_R_SDA")
	)
	(segment
		(start 219.060522 -238.916464)
		(end 215.250268 -238.916464)
		(width 0.13208)
		(layer "B.Cu")
		(net "SMB_PEX_R_SDA")
	)
	(segment
		(start 215.250268 -238.916464)
		(end 213.094062 -241.07267)
		(width 0.13208)
		(layer "B.Cu")
		(net "SMB_PEX_R_SDA")
	)
	(segment
		(start 215.68537 -219.81922)
		(end 214.512906 -219.81922)
		(width 0.13208)
		(layer "B.Cu")
		(net "SMB_PEX_R_SDA")
	)
	(segment
		(start 213.094062 -241.07267)
		(end 212.405722 -241.07267)
		(width 0.13208)
		(layer "B.Cu")
		(net "SMB_PEX_R_SDA")
	)
	(segment
		(start 216.476326 -220.334586)
		(end 216.200736 -220.334586)
		(width 0.15494)
		(layer "In9.Cu")
		(net "SMB_PEX_R_SDA")
	)
	(segment
		(start 220.242384 -224.100644)
		(end 216.476326 -220.334586)
		(width 0.15494)
		(layer "In9.Cu")
		(net "SMB_PEX_R_SDA")
	)
	(segment
		(start 220.006164 -237.498382)
		(end 220.006164 -236.247686)
		(width 0.15494)
		(layer "In9.Cu")
		(net "SMB_PEX_R_SDA")
	)
	(segment
		(start 220.006164 -236.247686)
		(end 220.242384 -236.011466)
		(width 0.15494)
		(layer "In9.Cu")
		(net "SMB_PEX_R_SDA")
	)
	(segment
		(start 220.242384 -237.734602)
		(end 220.006164 -237.498382)
		(width 0.15494)
		(layer "In9.Cu")
		(net "SMB_PEX_R_SDA")
	)
	(segment
		(start 220.242384 -236.011466)
		(end 220.242384 -224.100644)
		(width 0.15494)
		(layer "In9.Cu")
		(net "SMB_PEX_R_SDA")
	)
	(segment
		(start 123.964954 -178.44008)
		(end 128.035812 -178.44008)
		(width 0.13462)
		(layer "F.Cu")
		(net "CLK_100M_CK440Q_0_DB2000QL_R_DN")
	)
	(segment
		(start 128.035812 -178.44008)
		(end 129.456942 -177.019458)
		(width 0.13462)
		(layer "F.Cu")
		(net "CLK_100M_CK440Q_0_DB2000QL_R_DN")
	)
	(segment
		(start 268.9352 -83.351624)
		(end 269.256256 -83.67268)
		(width 0.13462)
		(layer "F.Cu")
		(net "CLK_100M_CK440Q_0_DB2000QL_R_DN")
	)
	(segment
		(start 129.456942 -177.019458)
		(end 129.851912 -177.019458)
		(width 0.13462)
		(layer "F.Cu")
		(net "CLK_100M_CK440Q_0_DB2000QL_R_DN")
	)
	(segment
		(start 269.256256 -83.67268)
		(end 274.113498 -83.67268)
		(width 0.13462)
		(layer "F.Cu")
		(net "CLK_100M_CK440Q_0_DB2000QL_R_DN")
	)
	(segment
		(start 129.851912 -177.019458)
		(end 129.971038 -176.900332)
		(width 0.13462)
		(layer "F.Cu")
		(net "CLK_100M_CK440Q_0_DB2000QL_R_DN")
	)
	(segment
		(start 274.113498 -83.67268)
		(end 274.409154 -83.377024)
		(width 0.13462)
		(layer "F.Cu")
		(net "CLK_100M_CK440Q_0_DB2000QL_R_DN")
	)
	(segment
		(start 123.656598 -178.131724)
		(end 123.964954 -178.44008)
		(width 0.13462)
		(layer "F.Cu")
		(net "CLK_100M_CK440Q_0_DB2000QL_R_DN")
	)
	(via
		(at 274.409154 -83.377024)
		(size 0.508)
		(drill 0.254)
		(layers "F.Cu" "B.Cu")
		(net "CLK_100M_CK440Q_0_DB2000QL_R_DN")
	)
	(via
		(at 123.656598 -178.131724)
		(size 0.508)
		(drill 0.254)
		(layers "F.Cu" "B.Cu")
		(net "CLK_100M_CK440Q_0_DB2000QL_R_DN")
	)
	(segment
		(start 276.74316 -90.277188)
		(end 276.74316 -85.124036)
		(width 0.13462)
		(layer "B.Cu")
		(net "CLK_100M_CK440Q_0_DB2000QL_R_DN")
	)
	(segment
		(start 123.656598 -178.131724)
		(end 123.368308 -178.420014)
		(width 0.13462)
		(layer "B.Cu")
		(net "CLK_100M_CK440Q_0_DB2000QL_R_DN")
	)
	(segment
		(start 141.56563 -184.912)
		(end 142.262352 -184.215278)
		(width 0.13462)
		(layer "B.Cu")
		(net "CLK_100M_CK440Q_0_DB2000QL_R_DN")
	)
	(segment
		(start 276.74316 -85.124036)
		(end 275.291804 -83.67268)
		(width 0.13462)
		(layer "B.Cu")
		(net "CLK_100M_CK440Q_0_DB2000QL_R_DN")
	)
	(segment
		(start 181.036468 -184.215278)
		(end 205.647798 -159.603948)
		(width 0.13462)
		(layer "B.Cu")
		(net "CLK_100M_CK440Q_0_DB2000QL_R_DN")
	)
	(segment
		(start 258.093972 -110.378748)
		(end 263.21004 -115.494816)
		(width 0.13462)
		(layer "B.Cu")
		(net "CLK_100M_CK440Q_0_DB2000QL_R_DN")
	)
	(segment
		(start 142.262352 -184.215278)
		(end 181.036468 -184.215278)
		(width 0.13462)
		(layer "B.Cu")
		(net "CLK_100M_CK440Q_0_DB2000QL_R_DN")
	)
	(segment
		(start 245.382288 -110.378748)
		(end 258.093972 -110.378748)
		(width 0.13462)
		(layer "B.Cu")
		(net "CLK_100M_CK440Q_0_DB2000QL_R_DN")
	)
	(segment
		(start 122.178064 -178.788822)
		(end 122.178064 -180.75148)
		(width 0.13462)
		(layer "B.Cu")
		(net "CLK_100M_CK440Q_0_DB2000QL_R_DN")
	)
	(segment
		(start 122.546872 -178.420014)
		(end 122.178064 -178.788822)
		(width 0.13462)
		(layer "B.Cu")
		(net "CLK_100M_CK440Q_0_DB2000QL_R_DN")
	)
	(segment
		(start 275.291804 -83.67268)
		(end 274.70481 -83.67268)
		(width 0.13462)
		(layer "B.Cu")
		(net "CLK_100M_CK440Q_0_DB2000QL_R_DN")
	)
	(segment
		(start 240.10112 -115.659916)
		(end 245.382288 -110.378748)
		(width 0.13462)
		(layer "B.Cu")
		(net "CLK_100M_CK440Q_0_DB2000QL_R_DN")
	)
	(segment
		(start 205.647798 -153.05659)
		(end 240.10112 -118.603268)
		(width 0.13462)
		(layer "B.Cu")
		(net "CLK_100M_CK440Q_0_DB2000QL_R_DN")
	)
	(segment
		(start 272.985992 -94.034356)
		(end 276.74316 -90.277188)
		(width 0.13462)
		(layer "B.Cu")
		(net "CLK_100M_CK440Q_0_DB2000QL_R_DN")
	)
	(segment
		(start 122.178064 -180.75148)
		(end 126.338584 -184.912)
		(width 0.13462)
		(layer "B.Cu")
		(net "CLK_100M_CK440Q_0_DB2000QL_R_DN")
	)
	(segment
		(start 263.21004 -115.494816)
		(end 268.552676 -115.494816)
		(width 0.13462)
		(layer "B.Cu")
		(net "CLK_100M_CK440Q_0_DB2000QL_R_DN")
	)
	(segment
		(start 126.338584 -184.912)
		(end 141.56563 -184.912)
		(width 0.13462)
		(layer "B.Cu")
		(net "CLK_100M_CK440Q_0_DB2000QL_R_DN")
	)
	(segment
		(start 268.552676 -115.494816)
		(end 272.985992 -111.0615)
		(width 0.13462)
		(layer "B.Cu")
		(net "CLK_100M_CK440Q_0_DB2000QL_R_DN")
	)
	(segment
		(start 205.647798 -159.603948)
		(end 205.647798 -153.05659)
		(width 0.13462)
		(layer "B.Cu")
		(net "CLK_100M_CK440Q_0_DB2000QL_R_DN")
	)
	(segment
		(start 272.985992 -111.0615)
		(end 272.985992 -94.034356)
		(width 0.13462)
		(layer "B.Cu")
		(net "CLK_100M_CK440Q_0_DB2000QL_R_DN")
	)
	(segment
		(start 240.10112 -118.603268)
		(end 240.10112 -115.659916)
		(width 0.13462)
		(layer "B.Cu")
		(net "CLK_100M_CK440Q_0_DB2000QL_R_DN")
	)
	(segment
		(start 123.368308 -178.420014)
		(end 122.546872 -178.420014)
		(width 0.13462)
		(layer "B.Cu")
		(net "CLK_100M_CK440Q_0_DB2000QL_R_DN")
	)
	(segment
		(start 274.70481 -83.67268)
		(end 274.409154 -83.377024)
		(width 0.13462)
		(layer "B.Cu")
		(net "CLK_100M_CK440Q_0_DB2000QL_R_DN")
	)
	(segment
		(start 65.349882 -282.599892)
		(end 65.824862 -283.074872)
		(width 0.13208)
		(layer "F.Cu")
		(net "PEX0_MODE_SEL11")
	)
	(segment
		(start 34.502344 -250.470924)
		(end 34.502344 -251.158502)
		(width 0.13208)
		(layer "F.Cu")
		(net "PEX0_MODE_SEL11")
	)
	(segment
		(start 34.502344 -251.158502)
		(end 34.502344 -251.956824)
		(width 0.13208)
		(layer "F.Cu")
		(net "PEX0_MODE_SEL11")
	)
	(via
		(at 34.502344 -251.158502)
		(size 0.508)
		(drill 0.254)
		(layers "F.Cu" "B.Cu")
		(net "PEX0_MODE_SEL11")
	)
	(via
		(at 65.824862 -283.074872)
		(size 0.4064)
		(drill 0.2032)
		(layers "F.Cu" "B.Cu")
		(net "PEX0_MODE_SEL11")
	)
	(segment
		(start 66.775076 -282.124658)
		(end 66.775076 -272.170144)
		(width 0.13208)
		(layer "B.Cu")
		(net "PEX0_MODE_SEL11")
	)
	(segment
		(start 63.619634 -269.207234)
		(end 62.567566 -268.155166)
		(width 0.13208)
		(layer "B.Cu")
		(net "PEX0_MODE_SEL11")
	)
	(segment
		(start 66.775076 -272.170144)
		(end 63.812166 -269.207234)
		(width 0.13208)
		(layer "B.Cu")
		(net "PEX0_MODE_SEL11")
	)
	(segment
		(start 62.567566 -267.962634)
		(end 50.459132 -255.8542)
		(width 0.13208)
		(layer "B.Cu")
		(net "PEX0_MODE_SEL11")
	)
	(segment
		(start 33.959292 -253.973838)
		(end 33.959292 -251.701554)
		(width 0.13208)
		(layer "B.Cu")
		(net "PEX0_MODE_SEL11")
	)
	(segment
		(start 50.459132 -255.8542)
		(end 35.839654 -255.8542)
		(width 0.13208)
		(layer "B.Cu")
		(net "PEX0_MODE_SEL11")
	)
	(segment
		(start 65.824862 -283.074872)
		(end 66.775076 -282.124658)
		(width 0.13208)
		(layer "B.Cu")
		(net "PEX0_MODE_SEL11")
	)
	(segment
		(start 33.959292 -251.701554)
		(end 34.502344 -251.158502)
		(width 0.13208)
		(layer "B.Cu")
		(net "PEX0_MODE_SEL11")
	)
	(segment
		(start 63.812166 -269.207234)
		(end 63.619634 -269.207234)
		(width 0.13208)
		(layer "B.Cu")
		(net "PEX0_MODE_SEL11")
	)
	(segment
		(start 62.567566 -268.155166)
		(end 62.567566 -267.962634)
		(width 0.13208)
		(layer "B.Cu")
		(net "PEX0_MODE_SEL11")
	)
	(segment
		(start 35.839654 -255.8542)
		(end 33.959292 -253.973838)
		(width 0.13208)
		(layer "B.Cu")
		(net "PEX0_MODE_SEL11")
	)
	(segment
		(start 150.753826 -311.015888)
		(end 150.680928 -311.015888)
		(width 0.13208)
		(layer "F.Cu")
		(net "PU_PEX1_ATPG_MODE_L")
	)
	(segment
		(start 150.680928 -311.015888)
		(end 148.800058 -309.135018)
		(width 0.13208)
		(layer "F.Cu")
		(net "PU_PEX1_ATPG_MODE_L")
	)
	(segment
		(start 166.249858 -309.199788)
		(end 165.774878 -309.674768)
		(width 0.13208)
		(layer "F.Cu")
		(net "PU_PEX1_ATPG_MODE_L")
	)
	(via
		(at 151.644604 -311.015888)
		(size 0.6604)
		(drill 0.3302)
		(layers "F.Cu" "B.Cu")
		(net "PU_PEX1_ATPG_MODE_L")
	)
	(via
		(at 150.753826 -311.015888)
		(size 0.508)
		(drill 0.254)
		(layers "F.Cu" "B.Cu")
		(net "PU_PEX1_ATPG_MODE_L")
	)
	(via
		(at 165.774878 -309.674768)
		(size 0.4064)
		(drill 0.2032)
		(layers "F.Cu" "B.Cu")
		(net "PU_PEX1_ATPG_MODE_L")
	)
	(segment
		(start 165.774878 -309.674768)
		(end 165.774878 -310.399176)
		(width 0.13208)
		(layer "B.Cu")
		(net "PU_PEX1_ATPG_MODE_L")
	)
	(segment
		(start 151.644604 -310.698642)
		(end 151.644604 -311.015888)
		(width 0.13208)
		(layer "B.Cu")
		(net "PU_PEX1_ATPG_MODE_L")
	)
	(segment
		(start 165.582854 -310.5912)
		(end 151.752046 -310.5912)
		(width 0.13208)
		(layer "B.Cu")
		(net "PU_PEX1_ATPG_MODE_L")
	)
	(segment
		(start 151.752046 -310.5912)
		(end 151.644604 -310.698642)
		(width 0.13208)
		(layer "B.Cu")
		(net "PU_PEX1_ATPG_MODE_L")
	)
	(segment
		(start 151.644604 -311.015888)
		(end 150.753826 -311.015888)
		(width 0.13208)
		(layer "B.Cu")
		(net "PU_PEX1_ATPG_MODE_L")
	)
	(segment
		(start 165.774878 -310.399176)
		(end 165.582854 -310.5912)
		(width 0.13208)
		(layer "B.Cu")
		(net "PU_PEX1_ATPG_MODE_L")
	)
	(segment
		(start 396.958312 -18.44421)
		(end 396.965424 -18.437098)
		(width 0.13208)
		(layer "F.Cu")
		(net "SMB_ISO_SSD13_R_SCL")
	)
	(segment
		(start 384.96494 -22.3901)
		(end 386.767578 -22.3901)
		(width 0.13208)
		(layer "F.Cu")
		(net "SMB_ISO_SSD13_R_SCL")
	)
	(segment
		(start 396.965424 -18.437098)
		(end 397.567912 -18.437098)
		(width 0.13208)
		(layer "F.Cu")
		(net "SMB_ISO_SSD13_R_SCL")
	)
	(segment
		(start 386.767578 -22.3901)
		(end 387.393688 -23.01621)
		(width 0.13208)
		(layer "F.Cu")
		(net "SMB_ISO_SSD13_R_SCL")
	)
	(via
		(at 396.958312 -18.44421)
		(size 0.508)
		(drill 0.254)
		(layers "F.Cu" "B.Cu")
		(net "SMB_ISO_SSD13_R_SCL")
	)
	(via
		(at 387.393688 -23.01621)
		(size 0.508)
		(drill 0.254)
		(layers "F.Cu" "B.Cu")
		(net "SMB_ISO_SSD13_R_SCL")
	)
	(segment
		(start 395.982698 -23.01621)
		(end 387.393688 -23.01621)
		(width 0.15494)
		(layer "In5.Cu")
		(net "SMB_ISO_SSD13_R_SCL")
	)
	(segment
		(start 397.527018 -21.47189)
		(end 395.982698 -23.01621)
		(width 0.15494)
		(layer "In5.Cu")
		(net "SMB_ISO_SSD13_R_SCL")
	)
	(segment
		(start 397.527018 -19.012916)
		(end 397.527018 -21.47189)
		(width 0.15494)
		(layer "In5.Cu")
		(net "SMB_ISO_SSD13_R_SCL")
	)
	(segment
		(start 396.958312 -18.44421)
		(end 397.527018 -19.012916)
		(width 0.15494)
		(layer "In5.Cu")
		(net "SMB_ISO_SSD13_R_SCL")
	)
	(segment
		(start 380.725426 -87.539068)
		(end 381.098044 -87.539068)
		(width 0.13208)
		(layer "F.Cu")
		(net "SMB_BIC_I2C6_MUX_NIC_ADC_SCL")
	)
	(segment
		(start 381.425196 -86.78672)
		(end 382.640078 -86.78672)
		(width 0.13208)
		(layer "F.Cu")
		(net "SMB_BIC_I2C6_MUX_NIC_ADC_SCL")
	)
	(segment
		(start 381.098044 -87.113872)
		(end 381.425196 -86.78672)
		(width 0.13208)
		(layer "F.Cu")
		(net "SMB_BIC_I2C6_MUX_NIC_ADC_SCL")
	)
	(segment
		(start 379.252734 -87.6808)
		(end 380.583694 -87.6808)
		(width 0.13208)
		(layer "F.Cu")
		(net "SMB_BIC_I2C6_MUX_NIC_ADC_SCL")
	)
	(segment
		(start 380.583694 -87.6808)
		(end 380.725426 -87.539068)
		(width 0.13208)
		(layer "F.Cu")
		(net "SMB_BIC_I2C6_MUX_NIC_ADC_SCL")
	)
	(segment
		(start 381.098044 -87.539068)
		(end 381.098044 -87.113872)
		(width 0.13208)
		(layer "F.Cu")
		(net "SMB_BIC_I2C6_MUX_NIC_ADC_SCL")
	)
	(via
		(at 381.098044 -87.539068)
		(size 0.508)
		(drill 0.254)
		(layers "F.Cu" "B.Cu")
		(net "SMB_BIC_I2C6_MUX_NIC_ADC_SCL")
	)
	(segment
		(start 291.340794 -57.16397)
		(end 291.340794 -58.364628)
		(width 0.13208)
		(layer "F.Cu")
		(net "P3V3_SSD10_OCP")
	)
	(segment
		(start 291.144198 -59.012582)
		(end 291.144198 -58.561224)
		(width 0.13208)
		(layer "F.Cu")
		(net "P3V3_SSD10_OCP")
	)
	(segment
		(start 291.303202 -59.171586)
		(end 291.144198 -59.012582)
		(width 0.13208)
		(layer "F.Cu")
		(net "P3V3_SSD10_OCP")
	)
	(segment
		(start 291.340794 -58.364628)
		(end 291.144198 -58.561224)
		(width 0.13208)
		(layer "F.Cu")
		(net "P3V3_SSD10_OCP")
	)
	(via
		(at 291.144198 -58.561224)
		(size 0.508)
		(drill 0.254)
		(layers "F.Cu" "B.Cu")
		(net "P3V3_SSD10_OCP")
	)
	(segment
		(start 234.021122 -95.761556)
		(end 234.021122 -95.729552)
		(width 0.13208)
		(layer "F.Cu")
		(net "PEX_USB_HUB_TEST")
	)
	(segment
		(start 234.021122 -95.729552)
		(end 234.021122 -94.679008)
		(width 0.13208)
		(layer "F.Cu")
		(net "PEX_USB_HUB_TEST")
	)
	(segment
		(start 233.444288 -96.858328)
		(end 233.444288 -96.33839)
		(width 0.13208)
		(layer "F.Cu")
		(net "PEX_USB_HUB_TEST")
	)
	(segment
		(start 233.444288 -96.33839)
		(end 234.021122 -95.761556)
		(width 0.13208)
		(layer "F.Cu")
		(net "PEX_USB_HUB_TEST")
	)
	(via
		(at 234.021122 -95.729552)
		(size 0.508)
		(drill 0.254)
		(layers "F.Cu" "B.Cu")
		(net "PEX_USB_HUB_TEST")
	)
	(segment
		(start 122.54103 -177.375058)
		(end 123.208288 -176.7078)
		(width 0.1143)
		(layer "F.Cu")
		(net "CLK_100M_DB2000QL_PEX0_S1_R_DP")
	)
	(segment
		(start 122.54103 -184.47893)
		(end 122.54103 -177.375058)
		(width 0.1143)
		(layer "F.Cu")
		(net "CLK_100M_DB2000QL_PEX0_S1_R_DP")
	)
	(segment
		(start 37.799518 -297.79976)
		(end 37.324538 -297.32478)
		(width 0.1143)
		(layer "F.Cu")
		(net "CLK_100M_DB2000QL_PEX0_S1_R_DP")
	)
	(segment
		(start 128.24333 -195.696078)
		(end 127.9906 -195.443348)
		(width 0.1143)
		(layer "F.Cu")
		(net "CLK_100M_DB2000QL_PEX0_S1_R_DP")
	)
	(segment
		(start 127.9906 -189.9285)
		(end 122.54103 -184.47893)
		(width 0.1143)
		(layer "F.Cu")
		(net "CLK_100M_DB2000QL_PEX0_S1_R_DP")
	)
	(segment
		(start 127.9906 -195.443348)
		(end 127.9906 -189.9285)
		(width 0.1143)
		(layer "F.Cu")
		(net "CLK_100M_DB2000QL_PEX0_S1_R_DP")
	)
	(segment
		(start 125.489462 -176.7078)
		(end 125.821186 -177.039524)
		(width 0.1143)
		(layer "F.Cu")
		(net "CLK_100M_DB2000QL_PEX0_S1_R_DP")
	)
	(segment
		(start 123.208288 -176.7078)
		(end 125.489462 -176.7078)
		(width 0.1143)
		(layer "F.Cu")
		(net "CLK_100M_DB2000QL_PEX0_S1_R_DP")
	)
	(segment
		(start 37.799772 -297.79976)
		(end 37.799518 -297.79976)
		(width 0.1143)
		(layer "F.Cu")
		(net "CLK_100M_DB2000QL_PEX0_S1_R_DP")
	)
	(via
		(at 128.24333 -195.696078)
		(size 0.508)
		(drill 0.254)
		(layers "F.Cu" "B.Cu")
		(net "CLK_100M_DB2000QL_PEX0_S1_R_DP")
	)
	(via
		(at 37.324538 -297.32478)
		(size 0.4064)
		(drill 0.2032)
		(layers "F.Cu" "B.Cu")
		(net "CLK_100M_DB2000QL_PEX0_S1_R_DP")
	)
	(segment
		(start 30.056836 -288.89833)
		(end 29.919676 -288.76117)
		(width 0.1143)
		(layer "B.Cu")
		(net "CLK_100M_DB2000QL_PEX0_S1_R_DP")
	)
	(segment
		(start 36.576 -296.6466)
		(end 35.36315 -296.6466)
		(width 0.0889)
		(layer "B.Cu")
		(net "CLK_100M_DB2000QL_PEX0_S1_R_DP")
	)
	(segment
		(start 30.056836 -288.22015)
		(end 30.056836 -287.81629)
		(width 0.1143)
		(layer "B.Cu")
		(net "CLK_100M_DB2000QL_PEX0_S1_R_DP")
	)
	(segment
		(start 30.056836 -286.05607)
		(end 30.056836 -285.65221)
		(width 0.1143)
		(layer "B.Cu")
		(net "CLK_100M_DB2000QL_PEX0_S1_R_DP")
	)
	(segment
		(start 30.056836 -289.30219)
		(end 30.056836 -288.89833)
		(width 0.1143)
		(layer "B.Cu")
		(net "CLK_100M_DB2000QL_PEX0_S1_R_DP")
	)
	(segment
		(start 31.331154 -294.500808)
		(end 29.919676 -293.08933)
		(width 0.1143)
		(layer "B.Cu")
		(net "CLK_100M_DB2000QL_PEX0_S1_R_DP")
	)
	(segment
		(start 29.919676 -291.60343)
		(end 30.056836 -291.46627)
		(width 0.1143)
		(layer "B.Cu")
		(net "CLK_100M_DB2000QL_PEX0_S1_R_DP")
	)
	(segment
		(start 35.36315 -296.6466)
		(end 35.2806 -296.56405)
		(width 0.0889)
		(layer "B.Cu")
		(net "CLK_100M_DB2000QL_PEX0_S1_R_DP")
	)
	(segment
		(start 107.615482 -197.5739)
		(end 115.771422 -200.9521)
		(width 0.1143)
		(layer "B.Cu")
		(net "CLK_100M_DB2000QL_PEX0_S1_R_DP")
	)
	(segment
		(start 30.056836 -291.06241)
		(end 29.919676 -290.92525)
		(width 0.1143)
		(layer "B.Cu")
		(net "CLK_100M_DB2000QL_PEX0_S1_R_DP")
	)
	(segment
		(start 21.0566 -251.699014)
		(end 50.315114 -222.4405)
		(width 0.1143)
		(layer "B.Cu")
		(net "CLK_100M_DB2000QL_PEX0_S1_R_DP")
	)
	(segment
		(start 30.056836 -292.14445)
		(end 29.919676 -292.00729)
		(width 0.1143)
		(layer "B.Cu")
		(net "CLK_100M_DB2000QL_PEX0_S1_R_DP")
	)
	(segment
		(start 23.943818 -267.39215)
		(end 21.0566 -260.42112)
		(width 0.1143)
		(layer "B.Cu")
		(net "CLK_100M_DB2000QL_PEX0_S1_R_DP")
	)
	(segment
		(start 35.058604 -296.56405)
		(end 32.995362 -294.500808)
		(width 0.1143)
		(layer "B.Cu")
		(net "CLK_100M_DB2000QL_PEX0_S1_R_DP")
	)
	(segment
		(start 23.943818 -267.391896)
		(end 23.943818 -267.39215)
		(width 0.1143)
		(layer "B.Cu")
		(net "CLK_100M_DB2000QL_PEX0_S1_R_DP")
	)
	(segment
		(start 30.056836 -289.98037)
		(end 29.919676 -289.84321)
		(width 0.1143)
		(layer "B.Cu")
		(net "CLK_100M_DB2000QL_PEX0_S1_R_DP")
	)
	(segment
		(start 29.919676 -286.59709)
		(end 29.919676 -286.19323)
		(width 0.1143)
		(layer "B.Cu")
		(net "CLK_100M_DB2000QL_PEX0_S1_R_DP")
	)
	(segment
		(start 30.056836 -286.73425)
		(end 29.919676 -286.59709)
		(width 0.1143)
		(layer "B.Cu")
		(net "CLK_100M_DB2000QL_PEX0_S1_R_DP")
	)
	(segment
		(start 29.919676 -288.35731)
		(end 30.056836 -288.22015)
		(width 0.1143)
		(layer "B.Cu")
		(net "CLK_100M_DB2000QL_PEX0_S1_R_DP")
	)
	(segment
		(start 32.995362 -294.500808)
		(end 31.331154 -294.500808)
		(width 0.1143)
		(layer "B.Cu")
		(net "CLK_100M_DB2000QL_PEX0_S1_R_DP")
	)
	(segment
		(start 30.056836 -291.46627)
		(end 30.056836 -291.06241)
		(width 0.1143)
		(layer "B.Cu")
		(net "CLK_100M_DB2000QL_PEX0_S1_R_DP")
	)
	(segment
		(start 30.056836 -292.54831)
		(end 30.056836 -292.14445)
		(width 0.1143)
		(layer "B.Cu")
		(net "CLK_100M_DB2000QL_PEX0_S1_R_DP")
	)
	(segment
		(start 29.919676 -286.19323)
		(end 30.056836 -286.05607)
		(width 0.1143)
		(layer "B.Cu")
		(net "CLK_100M_DB2000QL_PEX0_S1_R_DP")
	)
	(segment
		(start 127.47371 -197.080632)
		(end 127.504952 -197.067678)
		(width 0.1143)
		(layer "B.Cu")
		(net "CLK_100M_DB2000QL_PEX0_S1_R_DP")
	)
	(segment
		(start 118.12524 -200.9521)
		(end 127.437642 -197.095618)
		(width 0.1143)
		(layer "B.Cu")
		(net "CLK_100M_DB2000QL_PEX0_S1_R_DP")
	)
	(segment
		(start 29.919676 -292.68547)
		(end 30.056836 -292.54831)
		(width 0.1143)
		(layer "B.Cu")
		(net "CLK_100M_DB2000QL_PEX0_S1_R_DP")
	)
	(segment
		(start 29.919676 -292.00729)
		(end 29.919676 -291.60343)
		(width 0.1143)
		(layer "B.Cu")
		(net "CLK_100M_DB2000QL_PEX0_S1_R_DP")
	)
	(segment
		(start 29.919676 -289.84321)
		(end 29.919676 -289.43935)
		(width 0.1143)
		(layer "B.Cu")
		(net "CLK_100M_DB2000QL_PEX0_S1_R_DP")
	)
	(segment
		(start 100.411534 -197.5739)
		(end 107.615482 -197.5739)
		(width 0.1143)
		(layer "B.Cu")
		(net "CLK_100M_DB2000QL_PEX0_S1_R_DP")
	)
	(segment
		(start 36.944808 -297.23588)
		(end 36.944808 -297.015408)
		(width 0.0889)
		(layer "B.Cu")
		(net "CLK_100M_DB2000QL_PEX0_S1_R_DP")
	)
	(segment
		(start 30.056836 -287.13811)
		(end 30.056836 -286.73425)
		(width 0.1143)
		(layer "B.Cu")
		(net "CLK_100M_DB2000QL_PEX0_S1_R_DP")
	)
	(segment
		(start 30.056836 -287.81629)
		(end 29.919676 -287.67913)
		(width 0.1143)
		(layer "B.Cu")
		(net "CLK_100M_DB2000QL_PEX0_S1_R_DP")
	)
	(segment
		(start 29.919676 -279.868122)
		(end 23.971758 -273.920204)
		(width 0.1143)
		(layer "B.Cu")
		(net "CLK_100M_DB2000QL_PEX0_S1_R_DP")
	)
	(segment
		(start 29.919676 -288.76117)
		(end 29.919676 -288.35731)
		(width 0.1143)
		(layer "B.Cu")
		(net "CLK_100M_DB2000QL_PEX0_S1_R_DP")
	)
	(segment
		(start 30.056836 -290.38423)
		(end 30.056836 -289.98037)
		(width 0.1143)
		(layer "B.Cu")
		(net "CLK_100M_DB2000QL_PEX0_S1_R_DP")
	)
	(segment
		(start 29.919676 -289.43935)
		(end 30.056836 -289.30219)
		(width 0.1143)
		(layer "B.Cu")
		(net "CLK_100M_DB2000QL_PEX0_S1_R_DP")
	)
	(segment
		(start 127.458724 -197.095618)
		(end 127.47371 -197.080632)
		(width 0.1143)
		(layer "B.Cu")
		(net "CLK_100M_DB2000QL_PEX0_S1_R_DP")
	)
	(segment
		(start 37.033708 -297.32478)
		(end 36.944808 -297.23588)
		(width 0.0889)
		(layer "B.Cu")
		(net "CLK_100M_DB2000QL_PEX0_S1_R_DP")
	)
	(segment
		(start 23.971758 -267.45946)
		(end 23.943818 -267.391896)
		(width 0.1143)
		(layer "B.Cu")
		(net "CLK_100M_DB2000QL_PEX0_S1_R_DP")
	)
	(segment
		(start 35.2806 -296.56405)
		(end 35.258502 -296.56405)
		(width 0.0889)
		(layer "B.Cu")
		(net "CLK_100M_DB2000QL_PEX0_S1_R_DP")
	)
	(segment
		(start 29.919676 -290.92525)
		(end 29.919676 -290.52139)
		(width 0.1143)
		(layer "B.Cu")
		(net "CLK_100M_DB2000QL_PEX0_S1_R_DP")
	)
	(segment
		(start 29.919676 -287.27527)
		(end 30.056836 -287.13811)
		(width 0.1143)
		(layer "B.Cu")
		(net "CLK_100M_DB2000QL_PEX0_S1_R_DP")
	)
	(segment
		(start 29.919676 -290.52139)
		(end 30.056836 -290.38423)
		(width 0.1143)
		(layer "B.Cu")
		(net "CLK_100M_DB2000QL_PEX0_S1_R_DP")
	)
	(segment
		(start 21.0566 -260.42112)
		(end 21.0566 -251.699014)
		(width 0.1143)
		(layer "B.Cu")
		(net "CLK_100M_DB2000QL_PEX0_S1_R_DP")
	)
	(segment
		(start 35.258502 -296.56405)
		(end 35.058604 -296.56405)
		(width 0.1143)
		(layer "B.Cu")
		(net "CLK_100M_DB2000QL_PEX0_S1_R_DP")
	)
	(segment
		(start 127.998474 -196.573902)
		(end 127.998474 -195.940934)
		(width 0.1143)
		(layer "B.Cu")
		(net "CLK_100M_DB2000QL_PEX0_S1_R_DP")
	)
	(segment
		(start 29.919676 -293.08933)
		(end 29.919676 -292.68547)
		(width 0.1143)
		(layer "B.Cu")
		(net "CLK_100M_DB2000QL_PEX0_S1_R_DP")
	)
	(segment
		(start 36.944808 -297.015408)
		(end 36.576 -296.6466)
		(width 0.0889)
		(layer "B.Cu")
		(net "CLK_100M_DB2000QL_PEX0_S1_R_DP")
	)
	(segment
		(start 127.437642 -197.095618)
		(end 127.458724 -197.095618)
		(width 0.1143)
		(layer "B.Cu")
		(net "CLK_100M_DB2000QL_PEX0_S1_R_DP")
	)
	(segment
		(start 29.919676 -287.67913)
		(end 29.919676 -287.27527)
		(width 0.1143)
		(layer "B.Cu")
		(net "CLK_100M_DB2000QL_PEX0_S1_R_DP")
	)
	(segment
		(start 127.504952 -197.067678)
		(end 127.998474 -196.573902)
		(width 0.1143)
		(layer "B.Cu")
		(net "CLK_100M_DB2000QL_PEX0_S1_R_DP")
	)
	(segment
		(start 23.971758 -273.920204)
		(end 23.971758 -267.45946)
		(width 0.1143)
		(layer "B.Cu")
		(net "CLK_100M_DB2000QL_PEX0_S1_R_DP")
	)
	(segment
		(start 115.771422 -200.9521)
		(end 118.12524 -200.9521)
		(width 0.1143)
		(layer "B.Cu")
		(net "CLK_100M_DB2000QL_PEX0_S1_R_DP")
	)
	(segment
		(start 30.056836 -285.65221)
		(end 29.919676 -285.51505)
		(width 0.1143)
		(layer "B.Cu")
		(net "CLK_100M_DB2000QL_PEX0_S1_R_DP")
	)
	(segment
		(start 75.544934 -222.4405)
		(end 100.411534 -197.5739)
		(width 0.1143)
		(layer "B.Cu")
		(net "CLK_100M_DB2000QL_PEX0_S1_R_DP")
	)
	(segment
		(start 37.324538 -297.32478)
		(end 37.033708 -297.32478)
		(width 0.0889)
		(layer "B.Cu")
		(net "CLK_100M_DB2000QL_PEX0_S1_R_DP")
	)
	(segment
		(start 127.998474 -195.940934)
		(end 128.24333 -195.696078)
		(width 0.1143)
		(layer "B.Cu")
		(net "CLK_100M_DB2000QL_PEX0_S1_R_DP")
	)
	(segment
		(start 29.919676 -285.51505)
		(end 29.919676 -279.868122)
		(width 0.1143)
		(layer "B.Cu")
		(net "CLK_100M_DB2000QL_PEX0_S1_R_DP")
	)
	(segment
		(start 50.315114 -222.4405)
		(end 75.544934 -222.4405)
		(width 0.1143)
		(layer "B.Cu")
		(net "CLK_100M_DB2000QL_PEX0_S1_R_DP")
	)
	(segment
		(start 205.119732 -310.226456)
		(end 205.492858 -309.85333)
		(width 0.13208)
		(layer "F.Cu")
		(net "PEX1_SPARE2")
	)
	(segment
		(start 206.01432 -309.331868)
		(end 206.01432 -309.324756)
		(width 0.13208)
		(layer "F.Cu")
		(net "PEX1_SPARE2")
	)
	(segment
		(start 205.492858 -309.85333)
		(end 206.01432 -309.331868)
		(width 0.13208)
		(layer "F.Cu")
		(net "PEX1_SPARE2")
	)
	(segment
		(start 204.87894 -310.226456)
		(end 205.119732 -310.226456)
		(width 0.13208)
		(layer "F.Cu")
		(net "PEX1_SPARE2")
	)
	(via
		(at 201.922634 -313.423554)
		(size 0.6604)
		(drill 0.3302)
		(layers "F.Cu" "B.Cu")
		(net "PEX1_SPARE2")
	)
	(via
		(at 205.492858 -309.85333)
		(size 0.508)
		(drill 0.254)
		(layers "F.Cu" "B.Cu")
		(net "PEX1_SPARE2")
	)
	(via
		(at 177.649886 -309.199788)
		(size 0.4064)
		(drill 0.2032)
		(layers "F.Cu" "B.Cu")
		(net "PEX1_SPARE2")
	)
	(segment
		(start 178.404266 -309.199788)
		(end 179.070254 -309.865776)
		(width 0.13208)
		(layer "B.Cu")
		(net "PEX1_SPARE2")
	)
	(segment
		(start 201.922634 -313.423554)
		(end 205.492858 -309.85333)
		(width 0.13208)
		(layer "B.Cu")
		(net "PEX1_SPARE2")
	)
	(segment
		(start 177.649886 -309.199788)
		(end 178.404266 -309.199788)
		(width 0.13208)
		(layer "B.Cu")
		(net "PEX1_SPARE2")
	)
	(segment
		(start 179.070254 -309.865776)
		(end 179.070254 -314.330334)
		(width 0.13208)
		(layer "B.Cu")
		(net "PEX1_SPARE2")
	)
	(segment
		(start 200.888854 -314.457334)
		(end 201.922634 -313.423554)
		(width 0.13208)
		(layer "B.Cu")
		(net "PEX1_SPARE2")
	)
	(segment
		(start 179.197254 -314.457334)
		(end 200.888854 -314.457334)
		(width 0.13208)
		(layer "B.Cu")
		(net "PEX1_SPARE2")
	)
	(segment
		(start 179.070254 -314.330334)
		(end 179.197254 -314.457334)
		(width 0.13208)
		(layer "B.Cu")
		(net "PEX1_SPARE2")
	)
	(segment
		(start 54.454806 -21.847048)
		(end 54.454806 -22.561296)
		(width 0.13208)
		(layer "F.Cu")
		(net "SMB_SSD1_ISO_EN")
	)
	(segment
		(start 53.660548 -21.05279)
		(end 54.454806 -21.847048)
		(width 0.13208)
		(layer "F.Cu")
		(net "SMB_SSD1_ISO_EN")
	)
	(segment
		(start 53.660548 -20.789392)
		(end 53.660548 -21.05279)
		(width 0.13208)
		(layer "F.Cu")
		(net "SMB_SSD1_ISO_EN")
	)
	(via
		(at 54.454806 -21.847048)
		(size 0.508)
		(drill 0.254)
		(layers "F.Cu" "B.Cu")
		(net "SMB_SSD1_ISO_EN")
	)
	(segment
		(start 410.964888 -22.990048)
		(end 412.009336 -22.990048)
		(width 0.13208)
		(layer "F.Cu")
		(net "SMB_ISO_SSD14_R_SDA")
	)
	(segment
		(start 422.95826 -19.453098)
		(end 423.56786 -19.453098)
		(width 0.13208)
		(layer "F.Cu")
		(net "SMB_ISO_SSD14_R_SDA")
	)
	(segment
		(start 412.009336 -22.990048)
		(end 412.044388 -23.0251)
		(width 0.13208)
		(layer "F.Cu")
		(net "SMB_ISO_SSD14_R_SDA")
	)
	(via
		(at 422.95826 -19.453098)
		(size 0.508)
		(drill 0.254)
		(layers "F.Cu" "B.Cu")
		(net "SMB_ISO_SSD14_R_SDA")
	)
	(via
		(at 412.044388 -23.0251)
		(size 0.508)
		(drill 0.254)
		(layers "F.Cu" "B.Cu")
		(net "SMB_ISO_SSD14_R_SDA")
	)
	(segment
		(start 412.537148 -22.53234)
		(end 412.044388 -23.0251)
		(width 0.15494)
		(layer "In5.Cu")
		(net "SMB_ISO_SSD14_R_SDA")
	)
	(segment
		(start 422.95826 -19.453098)
		(end 422.95826 -21.390356)
		(width 0.15494)
		(layer "In5.Cu")
		(net "SMB_ISO_SSD14_R_SDA")
	)
	(segment
		(start 421.816276 -22.53234)
		(end 412.537148 -22.53234)
		(width 0.15494)
		(layer "In5.Cu")
		(net "SMB_ISO_SSD14_R_SDA")
	)
	(segment
		(start 422.95826 -21.390356)
		(end 421.816276 -22.53234)
		(width 0.15494)
		(layer "In5.Cu")
		(net "SMB_ISO_SSD14_R_SDA")
	)
	(segment
		(start 379.862334 -88.818974)
		(end 379.827028 -88.818974)
		(width 0.13208)
		(layer "F.Cu")
		(net "SMB_BIC_I2C6_MUX_NIC_ADC_SDA")
	)
	(segment
		(start 379.827028 -88.818974)
		(end 379.822202 -88.8238)
		(width 0.13208)
		(layer "F.Cu")
		(net "SMB_BIC_I2C6_MUX_NIC_ADC_SDA")
	)
	(segment
		(start 381.929132 -87.436706)
		(end 380.546864 -88.818974)
		(width 0.13208)
		(layer "F.Cu")
		(net "SMB_BIC_I2C6_MUX_NIC_ADC_SDA")
	)
	(segment
		(start 380.546864 -88.818974)
		(end 379.862334 -88.818974)
		(width 0.13208)
		(layer "F.Cu")
		(net "SMB_BIC_I2C6_MUX_NIC_ADC_SDA")
	)
	(segment
		(start 382.640078 -87.436706)
		(end 381.929132 -87.436706)
		(width 0.13208)
		(layer "F.Cu")
		(net "SMB_BIC_I2C6_MUX_NIC_ADC_SDA")
	)
	(segment
		(start 379.822202 -88.8238)
		(end 379.252734 -88.8238)
		(width 0.13208)
		(layer "F.Cu")
		(net "SMB_BIC_I2C6_MUX_NIC_ADC_SDA")
	)
	(via
		(at 379.862334 -88.818974)
		(size 0.508)
		(drill 0.254)
		(layers "F.Cu" "B.Cu")
		(net "SMB_BIC_I2C6_MUX_NIC_ADC_SDA")
	)
	(via
		(at 179.702968 -414.912556)
		(size 0.6604)
		(drill 0.3302)
		(layers "F.Cu" "B.Cu")
		(net "GPU_RSVD_PARTNER1")
	)
	(segment
		(start 178.588416 -405.383492)
		(end 177.509932 -404.305008)
		(width 0.13208)
		(layer "B.Cu")
		(net "GPU_RSVD_PARTNER1")
	)
	(segment
		(start 178.588416 -413.798004)
		(end 178.588416 -405.383492)
		(width 0.13208)
		(layer "B.Cu")
		(net "GPU_RSVD_PARTNER1")
	)
	(segment
		(start 177.509932 -404.305008)
		(end 177.509932 -404.290022)
		(width 0.13208)
		(layer "B.Cu")
		(net "GPU_RSVD_PARTNER1")
	)
	(segment
		(start 179.702968 -414.912556)
		(end 178.588416 -413.798004)
		(width 0.13208)
		(layer "B.Cu")
		(net "GPU_RSVD_PARTNER1")
	)
	(segment
		(start 211.755482 -242.03787)
		(end 211.755482 -241.07267)
		(width 0.13208)
		(layer "F.Cu")
		(net "SMB_PEX_R_SCL")
	)
	(segment
		(start 211.435442 -243.616226)
		(end 211.755482 -243.296186)
		(width 0.13208)
		(layer "F.Cu")
		(net "SMB_PEX_R_SCL")
	)
	(segment
		(start 211.755482 -243.296186)
		(end 211.755482 -242.03787)
		(width 0.13208)
		(layer "F.Cu")
		(net "SMB_PEX_R_SCL")
	)
	(via
		(at 221.520004 -237.430564)
		(size 0.508)
		(drill 0.254)
		(layers "F.Cu" "B.Cu")
		(net "SMB_PEX_R_SCL")
	)
	(via
		(at 211.755482 -241.07267)
		(size 0.508)
		(drill 0.254)
		(layers "F.Cu" "B.Cu")
		(net "SMB_PEX_R_SCL")
	)
	(via
		(at 216.200736 -219.318586)
		(size 0.508)
		(drill 0.254)
		(layers "F.Cu" "B.Cu")
		(net "SMB_PEX_R_SCL")
	)
	(segment
		(start 212.165946 -241.706146)
		(end 211.755482 -241.295682)
		(width 0.13208)
		(layer "B.Cu")
		(net "SMB_PEX_R_SCL")
	)
	(segment
		(start 216.443814 -239.542574)
		(end 214.280242 -241.706146)
		(width 0.13208)
		(layer "B.Cu")
		(net "SMB_PEX_R_SCL")
	)
	(segment
		(start 211.569808 -240.62436)
		(end 211.569808 -240.251742)
		(width 0.13208)
		(layer "B.Cu")
		(net "SMB_PEX_R_SCL")
	)
	(segment
		(start 211.755482 -241.07267)
		(end 211.569808 -240.62436)
		(width 0.13208)
		(layer "B.Cu")
		(net "SMB_PEX_R_SCL")
	)
	(segment
		(start 214.201248 -219.150438)
		(end 214.201248 -219.306902)
		(width 0.13208)
		(layer "B.Cu")
		(net "SMB_PEX_R_SCL")
	)
	(segment
		(start 211.755482 -241.295682)
		(end 211.755482 -241.07267)
		(width 0.13208)
		(layer "B.Cu")
		(net "SMB_PEX_R_SCL")
	)
	(segment
		(start 215.704928 -218.822778)
		(end 214.528908 -218.822778)
		(width 0.13208)
		(layer "B.Cu")
		(net "SMB_PEX_R_SCL")
	)
	(segment
		(start 214.280242 -241.706146)
		(end 212.165946 -241.706146)
		(width 0.13208)
		(layer "B.Cu")
		(net "SMB_PEX_R_SCL")
	)
	(segment
		(start 214.528908 -218.822778)
		(end 214.201248 -219.150438)
		(width 0.13208)
		(layer "B.Cu")
		(net "SMB_PEX_R_SCL")
	)
	(segment
		(start 219.407994 -239.542574)
		(end 216.443814 -239.542574)
		(width 0.13208)
		(layer "B.Cu")
		(net "SMB_PEX_R_SCL")
	)
	(segment
		(start 221.520004 -237.430564)
		(end 219.407994 -239.542574)
		(width 0.13208)
		(layer "B.Cu")
		(net "SMB_PEX_R_SCL")
	)
	(segment
		(start 216.200736 -219.318586)
		(end 216.835736 -219.318586)
		(width 0.13208)
		(layer "B.Cu")
		(net "SMB_PEX_R_SCL")
	)
	(segment
		(start 216.200736 -219.318586)
		(end 215.704928 -218.822778)
		(width 0.13208)
		(layer "B.Cu")
		(net "SMB_PEX_R_SCL")
	)
	(segment
		(start 221.520004 -236.718856)
		(end 220.877384 -236.076236)
		(width 0.15494)
		(layer "In9.Cu")
		(net "SMB_PEX_R_SCL")
	)
	(segment
		(start 221.520004 -237.430564)
		(end 221.520004 -236.718856)
		(width 0.15494)
		(layer "In9.Cu")
		(net "SMB_PEX_R_SCL")
	)
	(segment
		(start 220.877384 -236.076236)
		(end 220.877384 -223.995234)
		(width 0.15494)
		(layer "In9.Cu")
		(net "SMB_PEX_R_SCL")
	)
	(segment
		(start 220.877384 -223.995234)
		(end 216.200736 -219.318586)
		(width 0.15494)
		(layer "In9.Cu")
		(net "SMB_PEX_R_SCL")
	)
	(segment
		(start 363.87405 -210.947)
		(end 364.48365 -210.947)
		(width 0.13208)
		(layer "F.Cu")
		(net "SSD0_PEX_PWR_EN_R")
	)
	(segment
		(start 343.69375 -215.987122)
		(end 344.093546 -215.587326)
		(width 0.13208)
		(layer "F.Cu")
		(net "SSD0_PEX_PWR_EN_R")
	)
	(segment
		(start 363.87405 -211.963)
		(end 363.87405 -210.947)
		(width 0.13208)
		(layer "F.Cu")
		(net "SSD0_PEX_PWR_EN_R")
	)
	(segment
		(start 364.48365 -210.947)
		(end 365.10595 -210.947)
		(width 0.13208)
		(layer "F.Cu")
		(net "SSD0_PEX_PWR_EN_R")
	)
	(via
		(at 364.48365 -210.947)
		(size 0.508)
		(drill 0.254)
		(layers "F.Cu" "B.Cu")
		(net "SSD0_PEX_PWR_EN_R")
	)
	(via
		(at 344.093546 -215.587326)
		(size 0.4572)
		(drill 0.254)
		(layers "F.Cu" "B.Cu")
		(net "SSD0_PEX_PWR_EN_R")
	)
	(segment
		(start 354.84181 -213.88959)
		(end 360.382058 -213.88959)
		(width 0.15494)
		(layer "In13.Cu")
		(net "SSD0_PEX_PWR_EN_R")
	)
	(segment
		(start 360.382058 -213.88959)
		(end 361.781344 -212.490304)
		(width 0.15494)
		(layer "In13.Cu")
		(net "SSD0_PEX_PWR_EN_R")
	)
	(segment
		(start 344.093546 -215.587326)
		(end 344.491056 -215.984836)
		(width 0.0889)
		(layer "In13.Cu")
		(net "SSD0_PEX_PWR_EN_R")
	)
	(segment
		(start 361.781344 -212.490304)
		(end 362.940346 -212.490304)
		(width 0.15494)
		(layer "In13.Cu")
		(net "SSD0_PEX_PWR_EN_R")
	)
	(segment
		(start 344.491056 -215.984836)
		(end 352.746564 -215.984836)
		(width 0.0889)
		(layer "In13.Cu")
		(net "SSD0_PEX_PWR_EN_R")
	)
	(segment
		(start 352.746564 -215.984836)
		(end 354.84181 -213.88959)
		(width 0.15494)
		(layer "In13.Cu")
		(net "SSD0_PEX_PWR_EN_R")
	)
	(segment
		(start 362.940346 -212.490304)
		(end 364.48365 -210.947)
		(width 0.15494)
		(layer "In13.Cu")
		(net "SSD0_PEX_PWR_EN_R")
	)
	(segment
		(start 37.550344 -251.158502)
		(end 37.550344 -250.470924)
		(width 0.13208)
		(layer "F.Cu")
		(net "PEX0_MODE_SEL10")
	)
	(segment
		(start 66.299842 -283.549852)
		(end 66.774822 -284.024832)
		(width 0.13208)
		(layer "F.Cu")
		(net "PEX0_MODE_SEL10")
	)
	(segment
		(start 37.550344 -251.956824)
		(end 37.550344 -251.158502)
		(width 0.13208)
		(layer "F.Cu")
		(net "PEX0_MODE_SEL10")
	)
	(via
		(at 37.550344 -251.158502)
		(size 0.508)
		(drill 0.254)
		(layers "F.Cu" "B.Cu")
		(net "PEX0_MODE_SEL10")
	)
	(via
		(at 67.496182 -270.410432)
		(size 0.6604)
		(drill 0.3302)
		(layers "F.Cu" "B.Cu")
		(net "PEX0_MODE_SEL10")
	)
	(via
		(at 66.774822 -284.024832)
		(size 0.4064)
		(drill 0.2032)
		(layers "F.Cu" "B.Cu")
		(net "PEX0_MODE_SEL10")
	)
	(segment
		(start 51.79695 -254.7112)
		(end 67.496182 -270.410432)
		(width 0.13208)
		(layer "B.Cu")
		(net "PEX0_MODE_SEL10")
	)
	(segment
		(start 67.909948 -270.824198)
		(end 67.496182 -270.410432)
		(width 0.13208)
		(layer "B.Cu")
		(net "PEX0_MODE_SEL10")
	)
	(segment
		(start 68.43141 -282.601416)
		(end 68.883784 -282.601416)
		(width 0.13208)
		(layer "B.Cu")
		(net "PEX0_MODE_SEL10")
	)
	(segment
		(start 68.640452 -270.824198)
		(end 67.909948 -270.824198)
		(width 0.13208)
		(layer "B.Cu")
		(net "PEX0_MODE_SEL10")
	)
	(segment
		(start 68.204588 -283.407104)
		(end 68.204588 -282.828238)
		(width 0.13208)
		(layer "B.Cu")
		(net "PEX0_MODE_SEL10")
	)
	(segment
		(start 66.774822 -284.024832)
		(end 67.07759 -284.024832)
		(width 0.13208)
		(layer "B.Cu")
		(net "PEX0_MODE_SEL10")
	)
	(segment
		(start 68.883784 -282.601416)
		(end 69.642736 -281.842464)
		(width 0.13208)
		(layer "B.Cu")
		(net "PEX0_MODE_SEL10")
	)
	(segment
		(start 67.549014 -283.553408)
		(end 68.058284 -283.553408)
		(width 0.13208)
		(layer "B.Cu")
		(net "PEX0_MODE_SEL10")
	)
	(segment
		(start 69.642736 -281.842464)
		(end 69.642736 -271.826482)
		(width 0.13208)
		(layer "B.Cu")
		(net "PEX0_MODE_SEL10")
	)
	(segment
		(start 68.204588 -282.828238)
		(end 68.43141 -282.601416)
		(width 0.13208)
		(layer "B.Cu")
		(net "PEX0_MODE_SEL10")
	)
	(segment
		(start 37.033708 -253.981458)
		(end 37.76345 -254.7112)
		(width 0.13208)
		(layer "B.Cu")
		(net "PEX0_MODE_SEL10")
	)
	(segment
		(start 68.058284 -283.553408)
		(end 68.204588 -283.407104)
		(width 0.13208)
		(layer "B.Cu")
		(net "PEX0_MODE_SEL10")
	)
	(segment
		(start 67.07759 -284.024832)
		(end 67.549014 -283.553408)
		(width 0.13208)
		(layer "B.Cu")
		(net "PEX0_MODE_SEL10")
	)
	(segment
		(start 37.550344 -251.158502)
		(end 37.033708 -251.675138)
		(width 0.13208)
		(layer "B.Cu")
		(net "PEX0_MODE_SEL10")
	)
	(segment
		(start 37.033708 -251.675138)
		(end 37.033708 -253.981458)
		(width 0.13208)
		(layer "B.Cu")
		(net "PEX0_MODE_SEL10")
	)
	(segment
		(start 69.642736 -271.826482)
		(end 68.640452 -270.824198)
		(width 0.13208)
		(layer "B.Cu")
		(net "PEX0_MODE_SEL10")
	)
	(segment
		(start 37.76345 -254.7112)
		(end 51.79695 -254.7112)
		(width 0.13208)
		(layer "B.Cu")
		(net "PEX0_MODE_SEL10")
	)
	(segment
		(start 166.249858 -308.249828)
		(end 165.774878 -308.724808)
		(width 0.13208)
		(layer "F.Cu")
		(net "TP_PEX1_TCK")
	)
	(via
		(at 165.299898 -309.199788)
		(size 0.6604)
		(drill 0.3302)
		(layers "F.Cu" "B.Cu")
		(net "TP_PEX1_TCK")
	)
	(via
		(at 165.774878 -308.724808)
		(size 0.4064)
		(drill 0.2032)
		(layers "F.Cu" "B.Cu")
		(net "TP_PEX1_TCK")
	)
	(segment
		(start 165.299898 -309.199788)
		(end 165.774878 -308.724808)
		(width 0.13208)
		(layer "B.Cu")
		(net "TP_PEX1_TCK")
	)
	(segment
		(start 269.90929 -22.990048)
		(end 269.944342 -23.0251)
		(width 0.13208)
		(layer "F.Cu")
		(net "SMB_ISO_SSD9_R_SDA")
	)
	(segment
		(start 268.864842 -22.990048)
		(end 269.90929 -22.990048)
		(width 0.13208)
		(layer "F.Cu")
		(net "SMB_ISO_SSD9_R_SDA")
	)
	(segment
		(start 280.858214 -19.453098)
		(end 281.467814 -19.453098)
		(width 0.13208)
		(layer "F.Cu")
		(net "SMB_ISO_SSD9_R_SDA")
	)
	(via
		(at 269.944342 -23.0251)
		(size 0.508)
		(drill 0.254)
		(layers "F.Cu" "B.Cu")
		(net "SMB_ISO_SSD9_R_SDA")
	)
	(via
		(at 280.858214 -19.453098)
		(size 0.508)
		(drill 0.254)
		(layers "F.Cu" "B.Cu")
		(net "SMB_ISO_SSD9_R_SDA")
	)
	(segment
		(start 279.72639 -22.52218)
		(end 270.447262 -22.52218)
		(width 0.15494)
		(layer "In5.Cu")
		(net "SMB_ISO_SSD9_R_SDA")
	)
	(segment
		(start 280.858214 -19.453098)
		(end 280.858214 -21.390356)
		(width 0.15494)
		(layer "In5.Cu")
		(net "SMB_ISO_SSD9_R_SDA")
	)
	(segment
		(start 280.858214 -21.390356)
		(end 279.72639 -22.52218)
		(width 0.15494)
		(layer "In5.Cu")
		(net "SMB_ISO_SSD9_R_SDA")
	)
	(segment
		(start 270.447262 -22.52218)
		(end 269.944342 -23.0251)
		(width 0.15494)
		(layer "In5.Cu")
		(net "SMB_ISO_SSD9_R_SDA")
	)
	(segment
		(start 377.53544 -87.6808)
		(end 378.452634 -87.6808)
		(width 0.13208)
		(layer "F.Cu")
		(net "SMB_BIC_I2C6_MUX_NIC_ADC_R_SCL")
	)
	(segment
		(start 94.103444 -96.411542)
		(end 94.103444 -95.801942)
		(width 0.13208)
		(layer "F.Cu")
		(net "SMB_BIC_I2C6_MUX_NIC_ADC_R_SCL")
	)
	(segment
		(start 94.103444 -93.442536)
		(end 94.103444 -95.801942)
		(width 0.13208)
		(layer "F.Cu")
		(net "SMB_BIC_I2C6_MUX_NIC_ADC_R_SCL")
	)
	(segment
		(start 247.359678 -153.1112)
		(end 247.359678 -153.782522)
		(width 0.13208)
		(layer "F.Cu")
		(net "SMB_BIC_I2C6_MUX_NIC_ADC_R_SCL")
	)
	(segment
		(start 363.459776 -153.1112)
		(end 363.459776 -153.782522)
		(width 0.13208)
		(layer "F.Cu")
		(net "SMB_BIC_I2C6_MUX_NIC_ADC_R_SCL")
	)
	(segment
		(start 326.303386 -96.411542)
		(end 326.303386 -95.801942)
		(width 0.13208)
		(layer "F.Cu")
		(net "SMB_BIC_I2C6_MUX_NIC_ADC_R_SCL")
	)
	(segment
		(start 94.216474 -93.329506)
		(end 94.103444 -93.442536)
		(width 0.13208)
		(layer "F.Cu")
		(net "SMB_BIC_I2C6_MUX_NIC_ADC_R_SCL")
	)
	(segment
		(start 376.712734 -87.6808)
		(end 377.53544 -87.6808)
		(width 0.13208)
		(layer "F.Cu")
		(net "SMB_BIC_I2C6_MUX_NIC_ADC_R_SCL")
	)
	(segment
		(start 131.25958 -153.1112)
		(end 131.25958 -153.782522)
		(width 0.13208)
		(layer "F.Cu")
		(net "SMB_BIC_I2C6_MUX_NIC_ADC_R_SCL")
	)
	(segment
		(start 220.493844 -94.9325)
		(end 220.493844 -95.73895)
		(width 0.13208)
		(layer "F.Cu")
		(net "SMB_BIC_I2C6_MUX_NIC_ADC_R_SCL")
	)
	(via
		(at 377.53544 -87.6808)
		(size 0.508)
		(drill 0.254)
		(layers "F.Cu" "B.Cu")
		(net "SMB_BIC_I2C6_MUX_NIC_ADC_R_SCL")
	)
	(via
		(at 247.359678 -153.782522)
		(size 0.508)
		(drill 0.254)
		(layers "F.Cu" "B.Cu")
		(net "SMB_BIC_I2C6_MUX_NIC_ADC_R_SCL")
	)
	(via
		(at 131.25958 -153.782522)
		(size 0.508)
		(drill 0.254)
		(layers "F.Cu" "B.Cu")
		(net "SMB_BIC_I2C6_MUX_NIC_ADC_R_SCL")
	)
	(via
		(at 326.303386 -95.801942)
		(size 0.508)
		(drill 0.254)
		(layers "F.Cu" "B.Cu")
		(net "SMB_BIC_I2C6_MUX_NIC_ADC_R_SCL")
	)
	(via
		(at 94.103444 -94.971362)
		(size 0.6604)
		(drill 0.3302)
		(layers "F.Cu" "B.Cu")
		(net "SMB_BIC_I2C6_MUX_NIC_ADC_R_SCL")
	)
	(via
		(at 115.79479 -93.396308)
		(size 0.508)
		(drill 0.254)
		(layers "F.Cu" "B.Cu")
		(net "SMB_BIC_I2C6_MUX_NIC_ADC_R_SCL")
	)
	(via
		(at 220.493844 -94.9325)
		(size 0.508)
		(drill 0.254)
		(layers "F.Cu" "B.Cu")
		(net "SMB_BIC_I2C6_MUX_NIC_ADC_R_SCL")
	)
	(via
		(at 363.459776 -153.782522)
		(size 0.508)
		(drill 0.254)
		(layers "F.Cu" "B.Cu")
		(net "SMB_BIC_I2C6_MUX_NIC_ADC_R_SCL")
	)
	(via
		(at 94.103444 -95.801942)
		(size 0.508)
		(drill 0.254)
		(layers "F.Cu" "B.Cu")
		(net "SMB_BIC_I2C6_MUX_NIC_ADC_R_SCL")
	)
	(segment
		(start 115.79479 -93.396308)
		(end 114.956082 -92.5576)
		(width 0.13208)
		(layer "B.Cu")
		(net "SMB_BIC_I2C6_MUX_NIC_ADC_R_SCL")
	)
	(segment
		(start 363.459776 -153.2382)
		(end 363.459776 -153.782522)
		(width 0.13208)
		(layer "B.Cu")
		(net "SMB_BIC_I2C6_MUX_NIC_ADC_R_SCL")
	)
	(segment
		(start 363.332776 -153.1112)
		(end 363.459776 -153.2382)
		(width 0.13208)
		(layer "B.Cu")
		(net "SMB_BIC_I2C6_MUX_NIC_ADC_R_SCL")
	)
	(segment
		(start 94.103444 -95.801942)
		(end 94.103444 -94.971362)
		(width 0.13208)
		(layer "B.Cu")
		(net "SMB_BIC_I2C6_MUX_NIC_ADC_R_SCL")
	)
	(segment
		(start 114.956082 -92.5576)
		(end 95.214694 -92.5576)
		(width 0.13208)
		(layer "B.Cu")
		(net "SMB_BIC_I2C6_MUX_NIC_ADC_R_SCL")
	)
	(segment
		(start 95.214694 -92.5576)
		(end 94.103444 -93.66885)
		(width 0.13208)
		(layer "B.Cu")
		(net "SMB_BIC_I2C6_MUX_NIC_ADC_R_SCL")
	)
	(segment
		(start 94.103444 -93.66885)
		(end 94.103444 -94.971362)
		(width 0.13208)
		(layer "B.Cu")
		(net "SMB_BIC_I2C6_MUX_NIC_ADC_R_SCL")
	)
	(segment
		(start 375.959624 -91.415616)
		(end 368.611658 -98.763582)
		(width 0.15494)
		(layer "In5.Cu")
		(net "SMB_BIC_I2C6_MUX_NIC_ADC_R_SCL")
	)
	(segment
		(start 370.055902 -104.373934)
		(end 370.055902 -110.841028)
		(width 0.15494)
		(layer "In5.Cu")
		(net "SMB_BIC_I2C6_MUX_NIC_ADC_R_SCL")
	)
	(segment
		(start 372.099332 -149.919182)
		(end 369.837208 -152.181306)
		(width 0.15494)
		(layer "In5.Cu")
		(net "SMB_BIC_I2C6_MUX_NIC_ADC_R_SCL")
	)
	(segment
		(start 377.53544 -87.6808)
		(end 375.959624 -89.256616)
		(width 0.15494)
		(layer "In5.Cu")
		(net "SMB_BIC_I2C6_MUX_NIC_ADC_R_SCL")
	)
	(segment
		(start 375.959624 -89.256616)
		(end 375.959624 -91.415616)
		(width 0.15494)
		(layer "In5.Cu")
		(net "SMB_BIC_I2C6_MUX_NIC_ADC_R_SCL")
	)
	(segment
		(start 368.611658 -102.92969)
		(end 370.055902 -104.373934)
		(width 0.15494)
		(layer "In5.Cu")
		(net "SMB_BIC_I2C6_MUX_NIC_ADC_R_SCL")
	)
	(segment
		(start 368.611658 -98.763582)
		(end 368.611658 -102.92969)
		(width 0.15494)
		(layer "In5.Cu")
		(net "SMB_BIC_I2C6_MUX_NIC_ADC_R_SCL")
	)
	(segment
		(start 372.099332 -112.884458)
		(end 372.099332 -149.919182)
		(width 0.15494)
		(layer "In5.Cu")
		(net "SMB_BIC_I2C6_MUX_NIC_ADC_R_SCL")
	)
	(segment
		(start 365.398304 -152.181306)
		(end 364.78845 -152.79116)
		(width 0.15494)
		(layer "In5.Cu")
		(net "SMB_BIC_I2C6_MUX_NIC_ADC_R_SCL")
	)
	(segment
		(start 364.78845 -152.79116)
		(end 364.451138 -152.79116)
		(width 0.15494)
		(layer "In5.Cu")
		(net "SMB_BIC_I2C6_MUX_NIC_ADC_R_SCL")
	)
	(segment
		(start 370.055902 -110.841028)
		(end 372.099332 -112.884458)
		(width 0.15494)
		(layer "In5.Cu")
		(net "SMB_BIC_I2C6_MUX_NIC_ADC_R_SCL")
	)
	(segment
		(start 364.451138 -152.79116)
		(end 363.459776 -153.782522)
		(width 0.15494)
		(layer "In5.Cu")
		(net "SMB_BIC_I2C6_MUX_NIC_ADC_R_SCL")
	)
	(segment
		(start 369.837208 -152.181306)
		(end 365.398304 -152.181306)
		(width 0.15494)
		(layer "In5.Cu")
		(net "SMB_BIC_I2C6_MUX_NIC_ADC_R_SCL")
	)
	(segment
		(start 122.9106 -147.3708)
		(end 122.9106 -150.333456)
		(width 0.15494)
		(layer "In7.Cu")
		(net "SMB_BIC_I2C6_MUX_NIC_ADC_R_SCL")
	)
	(segment
		(start 118.17604 -100.797868)
		(end 118.17604 -111.87684)
		(width 0.15494)
		(layer "In7.Cu")
		(net "SMB_BIC_I2C6_MUX_NIC_ADC_R_SCL")
	)
	(segment
		(start 128.749044 -151.271986)
		(end 131.25958 -153.782522)
		(width 0.15494)
		(layer "In7.Cu")
		(net "SMB_BIC_I2C6_MUX_NIC_ADC_R_SCL")
	)
	(segment
		(start 118.17604 -111.87684)
		(end 124.079 -117.7798)
		(width 0.15494)
		(layer "In7.Cu")
		(net "SMB_BIC_I2C6_MUX_NIC_ADC_R_SCL")
	)
	(segment
		(start 124.079 -117.7798)
		(end 124.079 -146.2024)
		(width 0.15494)
		(layer "In7.Cu")
		(net "SMB_BIC_I2C6_MUX_NIC_ADC_R_SCL")
	)
	(segment
		(start 115.79479 -93.396308)
		(end 115.79479 -98.416618)
		(width 0.15494)
		(layer "In7.Cu")
		(net "SMB_BIC_I2C6_MUX_NIC_ADC_R_SCL")
	)
	(segment
		(start 123.84913 -151.271986)
		(end 128.749044 -151.271986)
		(width 0.15494)
		(layer "In7.Cu")
		(net "SMB_BIC_I2C6_MUX_NIC_ADC_R_SCL")
	)
	(segment
		(start 115.79479 -98.416618)
		(end 118.17604 -100.797868)
		(width 0.15494)
		(layer "In7.Cu")
		(net "SMB_BIC_I2C6_MUX_NIC_ADC_R_SCL")
	)
	(segment
		(start 124.079 -146.2024)
		(end 122.9106 -147.3708)
		(width 0.15494)
		(layer "In7.Cu")
		(net "SMB_BIC_I2C6_MUX_NIC_ADC_R_SCL")
	)
	(segment
		(start 122.9106 -150.333456)
		(end 123.84913 -151.271986)
		(width 0.15494)
		(layer "In7.Cu")
		(net "SMB_BIC_I2C6_MUX_NIC_ADC_R_SCL")
	)
	(segment
		(start 229.695502 -97.479612)
		(end 231.47909 -99.2632)
		(width 0.15494)
		(layer "In9.Cu")
		(net "SMB_BIC_I2C6_MUX_NIC_ADC_R_SCL")
	)
	(segment
		(start 221.165928 -95.604584)
		(end 228.417374 -95.604584)
		(width 0.15494)
		(layer "In9.Cu")
		(net "SMB_BIC_I2C6_MUX_NIC_ADC_R_SCL")
	)
	(segment
		(start 238.89208 -146.766026)
		(end 238.89208 -150.093934)
		(width 0.15494)
		(layer "In9.Cu")
		(net "SMB_BIC_I2C6_MUX_NIC_ADC_R_SCL")
	)
	(segment
		(start 228.417374 -95.604584)
		(end 229.695502 -96.882712)
		(width 0.15494)
		(layer "In9.Cu")
		(net "SMB_BIC_I2C6_MUX_NIC_ADC_R_SCL")
	)
	(segment
		(start 237.212886 -139.62253)
		(end 239.625632 -142.035276)
		(width 0.15494)
		(layer "In9.Cu")
		(net "SMB_BIC_I2C6_MUX_NIC_ADC_R_SCL")
	)
	(segment
		(start 237.374684 -103.737156)
		(end 240.508028 -103.737156)
		(width 0.15494)
		(layer "In9.Cu")
		(net "SMB_BIC_I2C6_MUX_NIC_ADC_R_SCL")
	)
	(segment
		(start 231.47909 -99.2632)
		(end 232.900728 -99.2632)
		(width 0.15494)
		(layer "In9.Cu")
		(net "SMB_BIC_I2C6_MUX_NIC_ADC_R_SCL")
	)
	(segment
		(start 240.508028 -103.737156)
		(end 244.051582 -107.28071)
		(width 0.15494)
		(layer "In9.Cu")
		(net "SMB_BIC_I2C6_MUX_NIC_ADC_R_SCL")
	)
	(segment
		(start 244.051582 -118.271036)
		(end 242.951 -119.371618)
		(width 0.15494)
		(layer "In9.Cu")
		(net "SMB_BIC_I2C6_MUX_NIC_ADC_R_SCL")
	)
	(segment
		(start 242.15471 -119.371618)
		(end 239.625632 -121.900696)
		(width 0.15494)
		(layer "In9.Cu")
		(net "SMB_BIC_I2C6_MUX_NIC_ADC_R_SCL")
	)
	(segment
		(start 237.212886 -130.043428)
		(end 237.212886 -139.62253)
		(width 0.15494)
		(layer "In9.Cu")
		(net "SMB_BIC_I2C6_MUX_NIC_ADC_R_SCL")
	)
	(segment
		(start 238.89208 -150.093934)
		(end 242.580668 -153.782522)
		(width 0.15494)
		(layer "In9.Cu")
		(net "SMB_BIC_I2C6_MUX_NIC_ADC_R_SCL")
	)
	(segment
		(start 239.625632 -146.032474)
		(end 238.89208 -146.766026)
		(width 0.15494)
		(layer "In9.Cu")
		(net "SMB_BIC_I2C6_MUX_NIC_ADC_R_SCL")
	)
	(segment
		(start 239.625632 -142.035276)
		(end 239.625632 -146.032474)
		(width 0.15494)
		(layer "In9.Cu")
		(net "SMB_BIC_I2C6_MUX_NIC_ADC_R_SCL")
	)
	(segment
		(start 242.951 -119.371618)
		(end 242.15471 -119.371618)
		(width 0.15494)
		(layer "In9.Cu")
		(net "SMB_BIC_I2C6_MUX_NIC_ADC_R_SCL")
	)
	(segment
		(start 239.625632 -121.900696)
		(end 239.625632 -127.630682)
		(width 0.15494)
		(layer "In9.Cu")
		(net "SMB_BIC_I2C6_MUX_NIC_ADC_R_SCL")
	)
	(segment
		(start 220.493844 -94.9325)
		(end 221.165928 -95.604584)
		(width 0.15494)
		(layer "In9.Cu")
		(net "SMB_BIC_I2C6_MUX_NIC_ADC_R_SCL")
	)
	(segment
		(start 242.580668 -153.782522)
		(end 247.359678 -153.782522)
		(width 0.15494)
		(layer "In9.Cu")
		(net "SMB_BIC_I2C6_MUX_NIC_ADC_R_SCL")
	)
	(segment
		(start 229.695502 -96.882712)
		(end 229.695502 -97.479612)
		(width 0.15494)
		(layer "In9.Cu")
		(net "SMB_BIC_I2C6_MUX_NIC_ADC_R_SCL")
	)
	(segment
		(start 232.900728 -99.2632)
		(end 237.374684 -103.737156)
		(width 0.15494)
		(layer "In9.Cu")
		(net "SMB_BIC_I2C6_MUX_NIC_ADC_R_SCL")
	)
	(segment
		(start 239.625632 -127.630682)
		(end 237.212886 -130.043428)
		(width 0.15494)
		(layer "In9.Cu")
		(net "SMB_BIC_I2C6_MUX_NIC_ADC_R_SCL")
	)
	(segment
		(start 244.051582 -107.28071)
		(end 244.051582 -118.271036)
		(width 0.15494)
		(layer "In9.Cu")
		(net "SMB_BIC_I2C6_MUX_NIC_ADC_R_SCL")
	)
	(segment
		(start 333.403702 -92.237052)
		(end 334.35671 -93.19006)
		(width 0.15494)
		(layer "In13.Cu")
		(net "SMB_BIC_I2C6_MUX_NIC_ADC_R_SCL")
	)
	(segment
		(start 336.526124 -96.77527)
		(end 336.526124 -98.586544)
		(width 0.15494)
		(layer "In13.Cu")
		(net "SMB_BIC_I2C6_MUX_NIC_ADC_R_SCL")
	)
	(segment
		(start 368.666014 -88.529668)
		(end 369.834668 -88.529668)
		(width 0.15494)
		(layer "In13.Cu")
		(net "SMB_BIC_I2C6_MUX_NIC_ADC_R_SCL")
	)
	(segment
		(start 365.364014 -90.040714)
		(end 367.165128 -88.2396)
		(width 0.15494)
		(layer "In13.Cu")
		(net "SMB_BIC_I2C6_MUX_NIC_ADC_R_SCL")
	)
	(segment
		(start 327.618344 -92.237052)
		(end 333.403702 -92.237052)
		(width 0.15494)
		(layer "In13.Cu")
		(net "SMB_BIC_I2C6_MUX_NIC_ADC_R_SCL")
	)
	(segment
		(start 353.445318 -99.131628)
		(end 362.536232 -90.040714)
		(width 0.15494)
		(layer "In13.Cu")
		(net "SMB_BIC_I2C6_MUX_NIC_ADC_R_SCL")
	)
	(segment
		(start 367.165128 -88.2396)
		(end 368.375946 -88.2396)
		(width 0.15494)
		(layer "In13.Cu")
		(net "SMB_BIC_I2C6_MUX_NIC_ADC_R_SCL")
	)
	(segment
		(start 362.536232 -90.040714)
		(end 365.364014 -90.040714)
		(width 0.15494)
		(layer "In13.Cu")
		(net "SMB_BIC_I2C6_MUX_NIC_ADC_R_SCL")
	)
	(segment
		(start 334.35671 -94.605856)
		(end 336.526124 -96.77527)
		(width 0.15494)
		(layer "In13.Cu")
		(net "SMB_BIC_I2C6_MUX_NIC_ADC_R_SCL")
	)
	(segment
		(start 373.661686 -87.119206)
		(end 376.223022 -87.119206)
		(width 0.15494)
		(layer "In13.Cu")
		(net "SMB_BIC_I2C6_MUX_NIC_ADC_R_SCL")
	)
	(segment
		(start 326.303386 -95.801942)
		(end 326.303386 -93.55201)
		(width 0.15494)
		(layer "In13.Cu")
		(net "SMB_BIC_I2C6_MUX_NIC_ADC_R_SCL")
	)
	(segment
		(start 371.830092 -88.9508)
		(end 373.661686 -87.119206)
		(width 0.15494)
		(layer "In13.Cu")
		(net "SMB_BIC_I2C6_MUX_NIC_ADC_R_SCL")
	)
	(segment
		(start 376.784616 -87.6808)
		(end 377.53544 -87.6808)
		(width 0.15494)
		(layer "In13.Cu")
		(net "SMB_BIC_I2C6_MUX_NIC_ADC_R_SCL")
	)
	(segment
		(start 368.375946 -88.2396)
		(end 368.666014 -88.529668)
		(width 0.15494)
		(layer "In13.Cu")
		(net "SMB_BIC_I2C6_MUX_NIC_ADC_R_SCL")
	)
	(segment
		(start 376.223022 -87.119206)
		(end 376.784616 -87.6808)
		(width 0.15494)
		(layer "In13.Cu")
		(net "SMB_BIC_I2C6_MUX_NIC_ADC_R_SCL")
	)
	(segment
		(start 336.526124 -98.586544)
		(end 337.071208 -99.131628)
		(width 0.15494)
		(layer "In13.Cu")
		(net "SMB_BIC_I2C6_MUX_NIC_ADC_R_SCL")
	)
	(segment
		(start 370.2558 -88.9508)
		(end 371.830092 -88.9508)
		(width 0.15494)
		(layer "In13.Cu")
		(net "SMB_BIC_I2C6_MUX_NIC_ADC_R_SCL")
	)
	(segment
		(start 326.303386 -93.55201)
		(end 327.618344 -92.237052)
		(width 0.15494)
		(layer "In13.Cu")
		(net "SMB_BIC_I2C6_MUX_NIC_ADC_R_SCL")
	)
	(segment
		(start 334.35671 -93.19006)
		(end 334.35671 -94.605856)
		(width 0.15494)
		(layer "In13.Cu")
		(net "SMB_BIC_I2C6_MUX_NIC_ADC_R_SCL")
	)
	(segment
		(start 369.834668 -88.529668)
		(end 370.2558 -88.9508)
		(width 0.15494)
		(layer "In13.Cu")
		(net "SMB_BIC_I2C6_MUX_NIC_ADC_R_SCL")
	)
	(segment
		(start 337.071208 -99.131628)
		(end 353.445318 -99.131628)
		(width 0.15494)
		(layer "In13.Cu")
		(net "SMB_BIC_I2C6_MUX_NIC_ADC_R_SCL")
	)
	(segment
		(start 133.1468 -152.2476)
		(end 132.252466 -153.141934)
		(width 0.15494)
		(layer "In15.Cu")
		(net "SMB_BIC_I2C6_MUX_NIC_ADC_R_SCL")
	)
	(segment
		(start 244.446552 -150.771352)
		(end 239.569752 -150.771352)
		(width 0.15494)
		(layer "In15.Cu")
		(net "SMB_BIC_I2C6_MUX_NIC_ADC_R_SCL")
	)
	(segment
		(start 172.161454 -135.636)
		(end 169.977054 -137.8204)
		(width 0.15494)
		(layer "In15.Cu")
		(net "SMB_BIC_I2C6_MUX_NIC_ADC_R_SCL")
	)
	(segment
		(start 226.531678 -99.002342)
		(end 225.779584 -99.002342)
		(width 0.15494)
		(layer "In15.Cu")
		(net "SMB_BIC_I2C6_MUX_NIC_ADC_R_SCL")
	)
	(segment
		(start 178.282854 -135.636)
		(end 172.161454 -135.636)
		(width 0.15494)
		(layer "In15.Cu")
		(net "SMB_BIC_I2C6_MUX_NIC_ADC_R_SCL")
	)
	(segment
		(start 247.359678 -153.684478)
		(end 244.446552 -150.771352)
		(width 0.15494)
		(layer "In15.Cu")
		(net "SMB_BIC_I2C6_MUX_NIC_ADC_R_SCL")
	)
	(segment
		(start 322.634864 -91.51112)
		(end 316.86246 -91.51112)
		(width 0.15494)
		(layer "In15.Cu")
		(net "SMB_BIC_I2C6_MUX_NIC_ADC_R_SCL")
	)
	(segment
		(start 239.569752 -150.771352)
		(end 238.807752 -150.009352)
		(width 0.15494)
		(layer "In15.Cu")
		(net "SMB_BIC_I2C6_MUX_NIC_ADC_R_SCL")
	)
	(segment
		(start 311.416446 -92.392246)
		(end 310.417718 -91.393518)
		(width 0.15494)
		(layer "In15.Cu")
		(net "SMB_BIC_I2C6_MUX_NIC_ADC_R_SCL")
	)
	(segment
		(start 195.586604 -137.6172)
		(end 180.264054 -137.6172)
		(width 0.15494)
		(layer "In15.Cu")
		(net "SMB_BIC_I2C6_MUX_NIC_ADC_R_SCL")
	)
	(segment
		(start 131.900168 -153.141934)
		(end 131.25958 -153.782522)
		(width 0.15494)
		(layer "In15.Cu")
		(net "SMB_BIC_I2C6_MUX_NIC_ADC_R_SCL")
	)
	(segment
		(start 164.8714 -135.6614)
		(end 162.216338 -135.6614)
		(width 0.15494)
		(layer "In15.Cu")
		(net "SMB_BIC_I2C6_MUX_NIC_ADC_R_SCL")
	)
	(segment
		(start 238.807752 -150.009352)
		(end 238.807752 -146.810984)
		(width 0.15494)
		(layer "In15.Cu")
		(net "SMB_BIC_I2C6_MUX_NIC_ADC_R_SCL")
	)
	(segment
		(start 222.453454 -97.8408)
		(end 222.160338 -97.547684)
		(width 0.15494)
		(layer "In15.Cu")
		(net "SMB_BIC_I2C6_MUX_NIC_ADC_R_SCL")
	)
	(segment
		(start 196.907404 -138.938)
		(end 195.586604 -137.6172)
		(width 0.15494)
		(layer "In15.Cu")
		(net "SMB_BIC_I2C6_MUX_NIC_ADC_R_SCL")
	)
	(segment
		(start 238.139478 -146.14271)
		(end 238.139478 -135.676132)
		(width 0.15494)
		(layer "In15.Cu")
		(net "SMB_BIC_I2C6_MUX_NIC_ADC_R_SCL")
	)
	(segment
		(start 180.264054 -137.6172)
		(end 178.282854 -135.636)
		(width 0.15494)
		(layer "In15.Cu")
		(net "SMB_BIC_I2C6_MUX_NIC_ADC_R_SCL")
	)
	(segment
		(start 270.4338 -90.9828)
		(end 267.893546 -90.9828)
		(width 0.15494)
		(layer "In15.Cu")
		(net "SMB_BIC_I2C6_MUX_NIC_ADC_R_SCL")
	)
	(segment
		(start 315.981334 -92.392246)
		(end 311.416446 -92.392246)
		(width 0.15494)
		(layer "In15.Cu")
		(net "SMB_BIC_I2C6_MUX_NIC_ADC_R_SCL")
	)
	(segment
		(start 232.970324 -99.596448)
		(end 227.125784 -99.596448)
		(width 0.15494)
		(layer "In15.Cu")
		(net "SMB_BIC_I2C6_MUX_NIC_ADC_R_SCL")
	)
	(segment
		(start 248.712736 -100.3046)
		(end 233.678476 -100.3046)
		(width 0.15494)
		(layer "In15.Cu")
		(net "SMB_BIC_I2C6_MUX_NIC_ADC_R_SCL")
	)
	(segment
		(start 247.359678 -153.782522)
		(end 247.359678 -153.684478)
		(width 0.15494)
		(layer "In15.Cu")
		(net "SMB_BIC_I2C6_MUX_NIC_ADC_R_SCL")
	)
	(segment
		(start 222.160338 -96.598994)
		(end 220.493844 -94.9325)
		(width 0.15494)
		(layer "In15.Cu")
		(net "SMB_BIC_I2C6_MUX_NIC_ADC_R_SCL")
	)
	(segment
		(start 270.844518 -91.393518)
		(end 270.4338 -90.9828)
		(width 0.15494)
		(layer "In15.Cu")
		(net "SMB_BIC_I2C6_MUX_NIC_ADC_R_SCL")
	)
	(segment
		(start 225.329242 -98.552)
		(end 223.4946 -98.552)
		(width 0.15494)
		(layer "In15.Cu")
		(net "SMB_BIC_I2C6_MUX_NIC_ADC_R_SCL")
	)
	(segment
		(start 149.987 -142.113)
		(end 139.8524 -152.2476)
		(width 0.15494)
		(layer "In15.Cu")
		(net "SMB_BIC_I2C6_MUX_NIC_ADC_R_SCL")
	)
	(segment
		(start 316.86246 -91.51112)
		(end 315.981334 -92.392246)
		(width 0.15494)
		(layer "In15.Cu")
		(net "SMB_BIC_I2C6_MUX_NIC_ADC_R_SCL")
	)
	(segment
		(start 326.303386 -95.801942)
		(end 326.303386 -95.179642)
		(width 0.15494)
		(layer "In15.Cu")
		(net "SMB_BIC_I2C6_MUX_NIC_ADC_R_SCL")
	)
	(segment
		(start 238.139478 -135.676132)
		(end 235.483146 -133.0198)
		(width 0.15494)
		(layer "In15.Cu")
		(net "SMB_BIC_I2C6_MUX_NIC_ADC_R_SCL")
	)
	(segment
		(start 223.4946 -98.552)
		(end 222.7834 -97.8408)
		(width 0.15494)
		(layer "In15.Cu")
		(net "SMB_BIC_I2C6_MUX_NIC_ADC_R_SCL")
	)
	(segment
		(start 238.807752 -146.810984)
		(end 238.139478 -146.14271)
		(width 0.15494)
		(layer "In15.Cu")
		(net "SMB_BIC_I2C6_MUX_NIC_ADC_R_SCL")
	)
	(segment
		(start 160.913572 -134.848854)
		(end 160.126426 -135.636)
		(width 0.15494)
		(layer "In15.Cu")
		(net "SMB_BIC_I2C6_MUX_NIC_ADC_R_SCL")
	)
	(segment
		(start 151.7396 -142.113)
		(end 149.987 -142.113)
		(width 0.15494)
		(layer "In15.Cu")
		(net "SMB_BIC_I2C6_MUX_NIC_ADC_R_SCL")
	)
	(segment
		(start 211.4042 -138.938)
		(end 196.907404 -138.938)
		(width 0.15494)
		(layer "In15.Cu")
		(net "SMB_BIC_I2C6_MUX_NIC_ADC_R_SCL")
	)
	(segment
		(start 158.2166 -135.636)
		(end 151.7396 -142.113)
		(width 0.15494)
		(layer "In15.Cu")
		(net "SMB_BIC_I2C6_MUX_NIC_ADC_R_SCL")
	)
	(segment
		(start 266.521946 -92.3544)
		(end 256.662936 -92.3544)
		(width 0.15494)
		(layer "In15.Cu")
		(net "SMB_BIC_I2C6_MUX_NIC_ADC_R_SCL")
	)
	(segment
		(start 139.8524 -152.2476)
		(end 133.1468 -152.2476)
		(width 0.15494)
		(layer "In15.Cu")
		(net "SMB_BIC_I2C6_MUX_NIC_ADC_R_SCL")
	)
	(segment
		(start 160.126426 -135.636)
		(end 158.2166 -135.636)
		(width 0.15494)
		(layer "In15.Cu")
		(net "SMB_BIC_I2C6_MUX_NIC_ADC_R_SCL")
	)
	(segment
		(start 256.662936 -92.3544)
		(end 248.712736 -100.3046)
		(width 0.15494)
		(layer "In15.Cu")
		(net "SMB_BIC_I2C6_MUX_NIC_ADC_R_SCL")
	)
	(segment
		(start 169.977054 -137.8204)
		(end 167.0304 -137.8204)
		(width 0.15494)
		(layer "In15.Cu")
		(net "SMB_BIC_I2C6_MUX_NIC_ADC_R_SCL")
	)
	(segment
		(start 267.893546 -90.9828)
		(end 266.521946 -92.3544)
		(width 0.15494)
		(layer "In15.Cu")
		(net "SMB_BIC_I2C6_MUX_NIC_ADC_R_SCL")
	)
	(segment
		(start 310.417718 -91.393518)
		(end 270.844518 -91.393518)
		(width 0.15494)
		(layer "In15.Cu")
		(net "SMB_BIC_I2C6_MUX_NIC_ADC_R_SCL")
	)
	(segment
		(start 227.125784 -99.596448)
		(end 226.531678 -99.002342)
		(width 0.15494)
		(layer "In15.Cu")
		(net "SMB_BIC_I2C6_MUX_NIC_ADC_R_SCL")
	)
	(segment
		(start 167.0304 -137.8204)
		(end 164.8714 -135.6614)
		(width 0.15494)
		(layer "In15.Cu")
		(net "SMB_BIC_I2C6_MUX_NIC_ADC_R_SCL")
	)
	(segment
		(start 326.303386 -95.179642)
		(end 322.634864 -91.51112)
		(width 0.15494)
		(layer "In15.Cu")
		(net "SMB_BIC_I2C6_MUX_NIC_ADC_R_SCL")
	)
	(segment
		(start 233.678476 -100.3046)
		(end 232.970324 -99.596448)
		(width 0.15494)
		(layer "In15.Cu")
		(net "SMB_BIC_I2C6_MUX_NIC_ADC_R_SCL")
	)
	(segment
		(start 225.779584 -99.002342)
		(end 225.329242 -98.552)
		(width 0.15494)
		(layer "In15.Cu")
		(net "SMB_BIC_I2C6_MUX_NIC_ADC_R_SCL")
	)
	(segment
		(start 132.252466 -153.141934)
		(end 131.900168 -153.141934)
		(width 0.15494)
		(layer "In15.Cu")
		(net "SMB_BIC_I2C6_MUX_NIC_ADC_R_SCL")
	)
	(segment
		(start 162.216338 -135.6614)
		(end 161.403792 -134.848854)
		(width 0.15494)
		(layer "In15.Cu")
		(net "SMB_BIC_I2C6_MUX_NIC_ADC_R_SCL")
	)
	(segment
		(start 161.403792 -134.848854)
		(end 160.913572 -134.848854)
		(width 0.15494)
		(layer "In15.Cu")
		(net "SMB_BIC_I2C6_MUX_NIC_ADC_R_SCL")
	)
	(segment
		(start 217.3224 -133.0198)
		(end 211.4042 -138.938)
		(width 0.15494)
		(layer "In15.Cu")
		(net "SMB_BIC_I2C6_MUX_NIC_ADC_R_SCL")
	)
	(segment
		(start 222.7834 -97.8408)
		(end 222.453454 -97.8408)
		(width 0.15494)
		(layer "In15.Cu")
		(net "SMB_BIC_I2C6_MUX_NIC_ADC_R_SCL")
	)
	(segment
		(start 222.160338 -97.547684)
		(end 222.160338 -96.598994)
		(width 0.15494)
		(layer "In15.Cu")
		(net "SMB_BIC_I2C6_MUX_NIC_ADC_R_SCL")
	)
	(segment
		(start 235.483146 -133.0198)
		(end 217.3224 -133.0198)
		(width 0.15494)
		(layer "In15.Cu")
		(net "SMB_BIC_I2C6_MUX_NIC_ADC_R_SCL")
	)
	(segment
		(start 360.172 -176.784)
		(end 360.426 -177.038)
		(width 0.13208)
		(layer "F.Cu")
		(net "RST_PEX_SSD6_PERST_R_N")
	)
	(segment
		(start 359.918 -177.038)
		(end 360.172 -176.784)
		(width 0.13208)
		(layer "F.Cu")
		(net "RST_PEX_SSD6_PERST_R_N")
	)
	(segment
		(start 347.693742 -213.587076)
		(end 348.093538 -213.18728)
		(width 0.13208)
		(layer "F.Cu")
		(net "RST_PEX_SSD6_PERST_R_N")
	)
	(segment
		(start 359.55605 -177.038)
		(end 359.918 -177.038)
		(width 0.13208)
		(layer "F.Cu")
		(net "RST_PEX_SSD6_PERST_R_N")
	)
	(segment
		(start 360.426 -177.038)
		(end 360.78795 -177.038)
		(width 0.13208)
		(layer "F.Cu")
		(net "RST_PEX_SSD6_PERST_R_N")
	)
	(via
		(at 348.093538 -213.18728)
		(size 0.4572)
		(drill 0.254)
		(layers "F.Cu" "B.Cu")
		(net "RST_PEX_SSD6_PERST_R_N")
	)
	(via
		(at 360.172 -176.784)
		(size 0.508)
		(drill 0.254)
		(layers "F.Cu" "B.Cu")
		(net "RST_PEX_SSD6_PERST_R_N")
	)
	(segment
		(start 361.581192 -199.885808)
		(end 361.581192 -178.193192)
		(width 0.15494)
		(layer "In5.Cu")
		(net "RST_PEX_SSD6_PERST_R_N")
	)
	(segment
		(start 349.29318 -212.99424)
		(end 349.50146 -212.78596)
		(width 0.0889)
		(layer "In5.Cu")
		(net "RST_PEX_SSD6_PERST_R_N")
	)
	(segment
		(start 357.135938 -207.709262)
		(end 359.9053 -204.9399)
		(width 0.15494)
		(layer "In5.Cu")
		(net "RST_PEX_SSD6_PERST_R_N")
	)
	(segment
		(start 354.617782 -207.709262)
		(end 357.135938 -207.709262)
		(width 0.15494)
		(layer "In5.Cu")
		(net "RST_PEX_SSD6_PERST_R_N")
	)
	(segment
		(start 349.50146 -212.78596)
		(end 349.90024 -212.78596)
		(width 0.0889)
		(layer "In5.Cu")
		(net "RST_PEX_SSD6_PERST_R_N")
	)
	(segment
		(start 350.07042 -212.015832)
		(end 350.07042 -211.39658)
		(width 0.15494)
		(layer "In5.Cu")
		(net "RST_PEX_SSD6_PERST_R_N")
	)
	(segment
		(start 349.29318 -213.33714)
		(end 349.29318 -212.99424)
		(width 0.0889)
		(layer "In5.Cu")
		(net "RST_PEX_SSD6_PERST_R_N")
	)
	(segment
		(start 350.11614 -212.57006)
		(end 350.11614 -212.061552)
		(width 0.15494)
		(layer "In5.Cu")
		(net "RST_PEX_SSD6_PERST_R_N")
	)
	(segment
		(start 348.093538 -213.18728)
		(end 348.497398 -213.59114)
		(width 0.0889)
		(layer "In5.Cu")
		(net "RST_PEX_SSD6_PERST_R_N")
	)
	(segment
		(start 351.1423 -210.3247)
		(end 352.002344 -210.3247)
		(width 0.15494)
		(layer "In5.Cu")
		(net "RST_PEX_SSD6_PERST_R_N")
	)
	(segment
		(start 350.07042 -211.39658)
		(end 351.1423 -210.3247)
		(width 0.15494)
		(layer "In5.Cu")
		(net "RST_PEX_SSD6_PERST_R_N")
	)
	(segment
		(start 349.90024 -212.78596)
		(end 350.11614 -212.57006)
		(width 0.15494)
		(layer "In5.Cu")
		(net "RST_PEX_SSD6_PERST_R_N")
	)
	(segment
		(start 348.497398 -213.59114)
		(end 349.03918 -213.59114)
		(width 0.0889)
		(layer "In5.Cu")
		(net "RST_PEX_SSD6_PERST_R_N")
	)
	(segment
		(start 359.9053 -203.9493)
		(end 361.1626 -202.692)
		(width 0.15494)
		(layer "In5.Cu")
		(net "RST_PEX_SSD6_PERST_R_N")
	)
	(segment
		(start 349.03918 -213.59114)
		(end 349.29318 -213.33714)
		(width 0.0889)
		(layer "In5.Cu")
		(net "RST_PEX_SSD6_PERST_R_N")
	)
	(segment
		(start 359.9053 -204.9399)
		(end 359.9053 -203.9493)
		(width 0.15494)
		(layer "In5.Cu")
		(net "RST_PEX_SSD6_PERST_R_N")
	)
	(segment
		(start 361.581192 -178.193192)
		(end 360.172 -176.784)
		(width 0.15494)
		(layer "In5.Cu")
		(net "RST_PEX_SSD6_PERST_R_N")
	)
	(segment
		(start 361.1626 -202.692)
		(end 361.1626 -200.3044)
		(width 0.15494)
		(layer "In5.Cu")
		(net "RST_PEX_SSD6_PERST_R_N")
	)
	(segment
		(start 361.1626 -200.3044)
		(end 361.581192 -199.885808)
		(width 0.15494)
		(layer "In5.Cu")
		(net "RST_PEX_SSD6_PERST_R_N")
	)
	(segment
		(start 352.002344 -210.3247)
		(end 354.617782 -207.709262)
		(width 0.15494)
		(layer "In5.Cu")
		(net "RST_PEX_SSD6_PERST_R_N")
	)
	(segment
		(start 350.11614 -212.061552)
		(end 350.07042 -212.015832)
		(width 0.15494)
		(layer "In5.Cu")
		(net "RST_PEX_SSD6_PERST_R_N")
	)
	(segment
		(start 240.51006 -53.397404)
		(end 240.830608 -53.397404)
		(width 0.2032)
		(layer "F.Cu")
		(net "P3V3_SSD8_SS")
	)
	(segment
		(start 241.56416 -55.41137)
		(end 241.56416 -55.011828)
		(width 0.2032)
		(layer "F.Cu")
		(net "P3V3_SSD8_SS")
	)
	(segment
		(start 240.830608 -53.397404)
		(end 241.344958 -53.911754)
		(width 0.2032)
		(layer "F.Cu")
		(net "P3V3_SSD8_SS")
	)
	(segment
		(start 241.56416 -55.011828)
		(end 241.347752 -54.79542)
		(width 0.2032)
		(layer "F.Cu")
		(net "P3V3_SSD8_SS")
	)
	(segment
		(start 241.347752 -54.79542)
		(end 241.344958 -54.79542)
		(width 0.2032)
		(layer "F.Cu")
		(net "P3V3_SSD8_SS")
	)
	(segment
		(start 241.344958 -53.911754)
		(end 241.344958 -54.79542)
		(width 0.2032)
		(layer "F.Cu")
		(net "P3V3_SSD8_SS")
	)
	(via
		(at 241.344958 -54.79542)
		(size 0.508)
		(drill 0.254)
		(layers "F.Cu" "B.Cu")
		(net "P3V3_SSD8_SS")
	)
	(segment
		(start 207.134206 -305.674522)
		(end 207.134206 -305.073558)
		(width 0.13208)
		(layer "F.Cu")
		(net "PEX1_SPARE1")
	)
	(segment
		(start 207.12557 -305.064922)
		(end 207.133698 -305.056794)
		(width 0.13208)
		(layer "F.Cu")
		(net "PEX1_SPARE1")
	)
	(segment
		(start 207.134206 -305.073558)
		(end 207.12557 -305.064922)
		(width 0.13208)
		(layer "F.Cu")
		(net "PEX1_SPARE1")
	)
	(segment
		(start 180.50002 -309.199788)
		(end 180.975 -308.724808)
		(width 0.13208)
		(layer "F.Cu")
		(net "PEX1_SPARE1")
	)
	(segment
		(start 207.133698 -305.056794)
		(end 207.133698 -304.436526)
		(width 0.13208)
		(layer "F.Cu")
		(net "PEX1_SPARE1")
	)
	(via
		(at 207.12557 -305.064922)
		(size 0.508)
		(drill 0.254)
		(layers "F.Cu" "B.Cu")
		(net "PEX1_SPARE1")
	)
	(via
		(at 180.975 -308.724808)
		(size 0.4064)
		(drill 0.2032)
		(layers "F.Cu" "B.Cu")
		(net "PEX1_SPARE1")
	)
	(via
		(at 201.164444 -311.026048)
		(size 0.6604)
		(drill 0.3302)
		(layers "F.Cu" "B.Cu")
		(net "PEX1_SPARE1")
	)
	(segment
		(start 181.860698 -309.610506)
		(end 180.975 -308.724808)
		(width 0.13208)
		(layer "B.Cu")
		(net "PEX1_SPARE1")
	)
	(segment
		(start 200.650856 -311.539636)
		(end 182.114698 -311.539636)
		(width 0.13208)
		(layer "B.Cu")
		(net "PEX1_SPARE1")
	)
	(segment
		(start 201.164444 -311.026048)
		(end 200.650856 -311.539636)
		(width 0.13208)
		(layer "B.Cu")
		(net "PEX1_SPARE1")
	)
	(segment
		(start 201.164444 -311.026048)
		(end 207.12557 -305.064922)
		(width 0.13208)
		(layer "B.Cu")
		(net "PEX1_SPARE1")
	)
	(segment
		(start 182.114698 -311.539636)
		(end 181.860698 -311.285636)
		(width 0.13208)
		(layer "B.Cu")
		(net "PEX1_SPARE1")
	)
	(segment
		(start 181.860698 -311.285636)
		(end 181.860698 -309.610506)
		(width 0.13208)
		(layer "B.Cu")
		(net "PEX1_SPARE1")
	)
	(segment
		(start 248.375678 -153.1112)
		(end 248.375678 -153.782522)
		(width 0.13208)
		(layer "F.Cu")
		(net "SMB_BIC_I2C6_MUX_NIC_ADC_R_SDA")
	)
	(segment
		(start 220.366844 -98.40595)
		(end 220.366844 -97.79)
		(width 0.13208)
		(layer "F.Cu")
		(net "SMB_BIC_I2C6_MUX_NIC_ADC_R_SDA")
	)
	(segment
		(start 16.175736 -153.1112)
		(end 16.175736 -153.782522)
		(width 0.13208)
		(layer "F.Cu")
		(net "SMB_BIC_I2C6_MUX_NIC_ADC_R_SDA")
	)
	(segment
		(start 92.851986 -90.26144)
		(end 93.2688 -90.678254)
		(width 0.13208)
		(layer "F.Cu")
		(net "SMB_BIC_I2C6_MUX_NIC_ADC_R_SDA")
	)
	(segment
		(start 93.087444 -96.411542)
		(end 93.087444 -95.812102)
		(width 0.13208)
		(layer "F.Cu")
		(net "SMB_BIC_I2C6_MUX_NIC_ADC_R_SDA")
	)
	(segment
		(start 93.2688 -90.678254)
		(end 93.2688 -95.630746)
		(width 0.13208)
		(layer "F.Cu")
		(net "SMB_BIC_I2C6_MUX_NIC_ADC_R_SDA")
	)
	(segment
		(start 377.53544 -88.8238)
		(end 378.452634 -88.8238)
		(width 0.13208)
		(layer "F.Cu")
		(net "SMB_BIC_I2C6_MUX_NIC_ADC_R_SDA")
	)
	(segment
		(start 132.27558 -153.1112)
		(end 132.27558 -153.782522)
		(width 0.13208)
		(layer "F.Cu")
		(net "SMB_BIC_I2C6_MUX_NIC_ADC_R_SDA")
	)
	(segment
		(start 93.087444 -95.812102)
		(end 93.097604 -95.801942)
		(width 0.13208)
		(layer "F.Cu")
		(net "SMB_BIC_I2C6_MUX_NIC_ADC_R_SDA")
	)
	(segment
		(start 93.2688 -95.630746)
		(end 93.097604 -95.801942)
		(width 0.13208)
		(layer "F.Cu")
		(net "SMB_BIC_I2C6_MUX_NIC_ADC_R_SDA")
	)
	(segment
		(start 376.712734 -88.8238)
		(end 377.53544 -88.8238)
		(width 0.13208)
		(layer "F.Cu")
		(net "SMB_BIC_I2C6_MUX_NIC_ADC_R_SDA")
	)
	(segment
		(start 441.387484 -95.812102)
		(end 441.397644 -95.801942)
		(width 0.13208)
		(layer "F.Cu")
		(net "SMB_BIC_I2C6_MUX_NIC_ADC_R_SDA")
	)
	(segment
		(start 441.387484 -96.411542)
		(end 441.387484 -95.812102)
		(width 0.13208)
		(layer "F.Cu")
		(net "SMB_BIC_I2C6_MUX_NIC_ADC_R_SDA")
	)
	(segment
		(start 325.287386 -96.411542)
		(end 325.287386 -95.812102)
		(width 0.13208)
		(layer "F.Cu")
		(net "SMB_BIC_I2C6_MUX_NIC_ADC_R_SDA")
	)
	(segment
		(start 92.851986 -89.9922)
		(end 92.851986 -90.26144)
		(width 0.13208)
		(layer "F.Cu")
		(net "SMB_BIC_I2C6_MUX_NIC_ADC_R_SDA")
	)
	(segment
		(start 325.287386 -95.812102)
		(end 325.297546 -95.801942)
		(width 0.13208)
		(layer "F.Cu")
		(net "SMB_BIC_I2C6_MUX_NIC_ADC_R_SDA")
	)
	(segment
		(start 364.475776 -153.1112)
		(end 364.475776 -153.782522)
		(width 0.13208)
		(layer "F.Cu")
		(net "SMB_BIC_I2C6_MUX_NIC_ADC_R_SDA")
	)
	(via
		(at 364.475776 -153.782522)
		(size 0.508)
		(drill 0.254)
		(layers "F.Cu" "B.Cu")
		(net "SMB_BIC_I2C6_MUX_NIC_ADC_R_SDA")
	)
	(via
		(at 16.175736 -153.782522)
		(size 0.508)
		(drill 0.254)
		(layers "F.Cu" "B.Cu")
		(net "SMB_BIC_I2C6_MUX_NIC_ADC_R_SDA")
	)
	(via
		(at 377.53544 -88.8238)
		(size 0.508)
		(drill 0.254)
		(layers "F.Cu" "B.Cu")
		(net "SMB_BIC_I2C6_MUX_NIC_ADC_R_SDA")
	)
	(via
		(at 25.43048 -95.986092)
		(size 0.508)
		(drill 0.254)
		(layers "F.Cu" "B.Cu")
		(net "SMB_BIC_I2C6_MUX_NIC_ADC_R_SDA")
	)
	(via
		(at 93.097604 -95.801942)
		(size 0.508)
		(drill 0.254)
		(layers "F.Cu" "B.Cu")
		(net "SMB_BIC_I2C6_MUX_NIC_ADC_R_SDA")
	)
	(via
		(at 441.397644 -95.801942)
		(size 0.508)
		(drill 0.254)
		(layers "F.Cu" "B.Cu")
		(net "SMB_BIC_I2C6_MUX_NIC_ADC_R_SDA")
	)
	(via
		(at 248.375678 -153.782522)
		(size 0.508)
		(drill 0.254)
		(layers "F.Cu" "B.Cu")
		(net "SMB_BIC_I2C6_MUX_NIC_ADC_R_SDA")
	)
	(via
		(at 325.297546 -95.801942)
		(size 0.508)
		(drill 0.254)
		(layers "F.Cu" "B.Cu")
		(net "SMB_BIC_I2C6_MUX_NIC_ADC_R_SDA")
	)
	(via
		(at 132.27558 -153.782522)
		(size 0.508)
		(drill 0.254)
		(layers "F.Cu" "B.Cu")
		(net "SMB_BIC_I2C6_MUX_NIC_ADC_R_SDA")
	)
	(via
		(at 220.366844 -97.79)
		(size 0.508)
		(drill 0.254)
		(layers "F.Cu" "B.Cu")
		(net "SMB_BIC_I2C6_MUX_NIC_ADC_R_SDA")
	)
	(via
		(at 446.046606 -137.909808)
		(size 0.508)
		(drill 0.254)
		(layers "F.Cu" "B.Cu")
		(net "SMB_BIC_I2C6_MUX_NIC_ADC_R_SDA")
	)
	(via
		(at 92.851986 -89.9922)
		(size 0.508)
		(drill 0.254)
		(layers "F.Cu" "B.Cu")
		(net "SMB_BIC_I2C6_MUX_NIC_ADC_R_SDA")
	)
	(via
		(at 114.516408 -94.501716)
		(size 0.508)
		(drill 0.254)
		(layers "F.Cu" "B.Cu")
		(net "SMB_BIC_I2C6_MUX_NIC_ADC_R_SDA")
	)
	(segment
		(start 116.332 -93.218254)
		(end 116.332 -93.97619)
		(width 0.13208)
		(layer "B.Cu")
		(net "SMB_BIC_I2C6_MUX_NIC_ADC_R_SDA")
	)
	(segment
		(start 93.554296 -95.34525)
		(end 93.554296 -93.54185)
		(width 0.13208)
		(layer "B.Cu")
		(net "SMB_BIC_I2C6_MUX_NIC_ADC_R_SDA")
	)
	(segment
		(start 115.30076 -95.00743)
		(end 115.022122 -95.00743)
		(width 0.13208)
		(layer "B.Cu")
		(net "SMB_BIC_I2C6_MUX_NIC_ADC_R_SDA")
	)
	(segment
		(start 93.554296 -93.54185)
		(end 95.071946 -92.0242)
		(width 0.13208)
		(layer "B.Cu")
		(net "SMB_BIC_I2C6_MUX_NIC_ADC_R_SDA")
	)
	(segment
		(start 115.137946 -92.0242)
		(end 116.332 -93.218254)
		(width 0.13208)
		(layer "B.Cu")
		(net "SMB_BIC_I2C6_MUX_NIC_ADC_R_SDA")
	)
	(segment
		(start 115.022122 -95.00743)
		(end 114.516408 -94.501716)
		(width 0.13208)
		(layer "B.Cu")
		(net "SMB_BIC_I2C6_MUX_NIC_ADC_R_SDA")
	)
	(segment
		(start 95.071946 -92.0242)
		(end 115.137946 -92.0242)
		(width 0.13208)
		(layer "B.Cu")
		(net "SMB_BIC_I2C6_MUX_NIC_ADC_R_SDA")
	)
	(segment
		(start 93.097604 -95.801942)
		(end 93.554296 -95.34525)
		(width 0.13208)
		(layer "B.Cu")
		(net "SMB_BIC_I2C6_MUX_NIC_ADC_R_SDA")
	)
	(segment
		(start 116.332 -93.97619)
		(end 115.30076 -95.00743)
		(width 0.13208)
		(layer "B.Cu")
		(net "SMB_BIC_I2C6_MUX_NIC_ADC_R_SDA")
	)
	(segment
		(start 370.527326 -104.195118)
		(end 369.071398 -102.73919)
		(width 0.15494)
		(layer "In5.Cu")
		(net "SMB_BIC_I2C6_MUX_NIC_ADC_R_SDA")
	)
	(segment
		(start 369.071398 -102.73919)
		(end 369.071398 -98.954082)
		(width 0.15494)
		(layer "In5.Cu")
		(net "SMB_BIC_I2C6_MUX_NIC_ADC_R_SDA")
	)
	(segment
		(start 430.375568 -100.866702)
		(end 430.375568 -108.093764)
		(width 0.15494)
		(layer "In5.Cu")
		(net "SMB_BIC_I2C6_MUX_NIC_ADC_R_SDA")
	)
	(segment
		(start 436.427372 -94.814898)
		(end 430.375568 -100.866702)
		(width 0.15494)
		(layer "In5.Cu")
		(net "SMB_BIC_I2C6_MUX_NIC_ADC_R_SDA")
	)
	(segment
		(start 16.175736 -153.782522)
		(end 17.228058 -152.7302)
		(width 0.15494)
		(layer "In5.Cu")
		(net "SMB_BIC_I2C6_MUX_NIC_ADC_R_SDA")
	)
	(segment
		(start 437.383174 -129.949956)
		(end 444.433706 -137.000488)
		(width 0.15494)
		(layer "In5.Cu")
		(net "SMB_BIC_I2C6_MUX_NIC_ADC_R_SDA")
	)
	(segment
		(start 430.375568 -108.093764)
		(end 434.22062 -111.938816)
		(width 0.15494)
		(layer "In5.Cu")
		(net "SMB_BIC_I2C6_MUX_NIC_ADC_R_SDA")
	)
	(segment
		(start 434.22062 -116.781072)
		(end 436.730394 -119.290846)
		(width 0.15494)
		(layer "In5.Cu")
		(net "SMB_BIC_I2C6_MUX_NIC_ADC_R_SDA")
	)
	(segment
		(start 365.617252 -152.641046)
		(end 370.175028 -152.641046)
		(width 0.15494)
		(layer "In5.Cu")
		(net "SMB_BIC_I2C6_MUX_NIC_ADC_R_SDA")
	)
	(segment
		(start 434.22062 -111.938816)
		(end 434.22062 -116.781072)
		(width 0.15494)
		(layer "In5.Cu")
		(net "SMB_BIC_I2C6_MUX_NIC_ADC_R_SDA")
	)
	(segment
		(start 372.559072 -112.693958)
		(end 370.527326 -110.662212)
		(width 0.15494)
		(layer "In5.Cu")
		(net "SMB_BIC_I2C6_MUX_NIC_ADC_R_SDA")
	)
	(segment
		(start 441.755276 -94.814898)
		(end 436.427372 -94.814898)
		(width 0.15494)
		(layer "In5.Cu")
		(net "SMB_BIC_I2C6_MUX_NIC_ADC_R_SDA")
	)
	(segment
		(start 445.600836 -137.000488)
		(end 446.046606 -137.446258)
		(width 0.15494)
		(layer "In5.Cu")
		(net "SMB_BIC_I2C6_MUX_NIC_ADC_R_SDA")
	)
	(segment
		(start 442.016642 -95.076264)
		(end 441.755276 -94.814898)
		(width 0.15494)
		(layer "In5.Cu")
		(net "SMB_BIC_I2C6_MUX_NIC_ADC_R_SDA")
	)
	(segment
		(start 22.6822 -152.7302)
		(end 23.871428 -151.540972)
		(width 0.15494)
		(layer "In5.Cu")
		(net "SMB_BIC_I2C6_MUX_NIC_ADC_R_SDA")
	)
	(segment
		(start 370.175028 -152.641046)
		(end 372.559072 -150.257002)
		(width 0.15494)
		(layer "In5.Cu")
		(net "SMB_BIC_I2C6_MUX_NIC_ADC_R_SDA")
	)
	(segment
		(start 372.559072 -150.257002)
		(end 372.559072 -112.693958)
		(width 0.15494)
		(layer "In5.Cu")
		(net "SMB_BIC_I2C6_MUX_NIC_ADC_R_SDA")
	)
	(segment
		(start 442.016642 -95.477584)
		(end 442.016642 -95.076264)
		(width 0.15494)
		(layer "In5.Cu")
		(net "SMB_BIC_I2C6_MUX_NIC_ADC_R_SDA")
	)
	(segment
		(start 376.630438 -89.728802)
		(end 377.53544 -88.8238)
		(width 0.15494)
		(layer "In5.Cu")
		(net "SMB_BIC_I2C6_MUX_NIC_ADC_R_SDA")
	)
	(segment
		(start 446.046606 -137.446258)
		(end 446.046606 -137.909808)
		(width 0.15494)
		(layer "In5.Cu")
		(net "SMB_BIC_I2C6_MUX_NIC_ADC_R_SDA")
	)
	(segment
		(start 364.475776 -153.782522)
		(end 365.617252 -152.641046)
		(width 0.15494)
		(layer "In5.Cu")
		(net "SMB_BIC_I2C6_MUX_NIC_ADC_R_SDA")
	)
	(segment
		(start 436.730394 -119.290846)
		(end 436.730394 -128.375664)
		(width 0.15494)
		(layer "In5.Cu")
		(net "SMB_BIC_I2C6_MUX_NIC_ADC_R_SDA")
	)
	(segment
		(start 17.228058 -152.7302)
		(end 22.6822 -152.7302)
		(width 0.15494)
		(layer "In5.Cu")
		(net "SMB_BIC_I2C6_MUX_NIC_ADC_R_SDA")
	)
	(segment
		(start 23.871428 -151.540972)
		(end 23.871428 -97.545144)
		(width 0.15494)
		(layer "In5.Cu")
		(net "SMB_BIC_I2C6_MUX_NIC_ADC_R_SDA")
	)
	(segment
		(start 376.630438 -91.395042)
		(end 376.630438 -89.728802)
		(width 0.15494)
		(layer "In5.Cu")
		(net "SMB_BIC_I2C6_MUX_NIC_ADC_R_SDA")
	)
	(segment
		(start 23.871428 -97.545144)
		(end 25.43048 -95.986092)
		(width 0.15494)
		(layer "In5.Cu")
		(net "SMB_BIC_I2C6_MUX_NIC_ADC_R_SDA")
	)
	(segment
		(start 444.433706 -137.000488)
		(end 445.600836 -137.000488)
		(width 0.15494)
		(layer "In5.Cu")
		(net "SMB_BIC_I2C6_MUX_NIC_ADC_R_SDA")
	)
	(segment
		(start 370.527326 -110.662212)
		(end 370.527326 -104.195118)
		(width 0.15494)
		(layer "In5.Cu")
		(net "SMB_BIC_I2C6_MUX_NIC_ADC_R_SDA")
	)
	(segment
		(start 369.071398 -98.954082)
		(end 376.630438 -91.395042)
		(width 0.15494)
		(layer "In5.Cu")
		(net "SMB_BIC_I2C6_MUX_NIC_ADC_R_SDA")
	)
	(segment
		(start 441.692284 -95.801942)
		(end 442.016642 -95.477584)
		(width 0.15494)
		(layer "In5.Cu")
		(net "SMB_BIC_I2C6_MUX_NIC_ADC_R_SDA")
	)
	(segment
		(start 436.730394 -128.375664)
		(end 437.383174 -129.949956)
		(width 0.15494)
		(layer "In5.Cu")
		(net "SMB_BIC_I2C6_MUX_NIC_ADC_R_SDA")
	)
	(segment
		(start 441.397644 -95.801942)
		(end 441.692284 -95.801942)
		(width 0.15494)
		(layer "In5.Cu")
		(net "SMB_BIC_I2C6_MUX_NIC_ADC_R_SDA")
	)
	(segment
		(start 123.658376 -151.731726)
		(end 128.524254 -151.731726)
		(width 0.15494)
		(layer "In7.Cu")
		(net "SMB_BIC_I2C6_MUX_NIC_ADC_R_SDA")
	)
	(segment
		(start 115.062 -98.334322)
		(end 115.469416 -98.741738)
		(width 0.15494)
		(layer "In7.Cu")
		(net "SMB_BIC_I2C6_MUX_NIC_ADC_R_SDA")
	)
	(segment
		(start 123.61926 -146.0119)
		(end 122.45086 -147.1803)
		(width 0.15494)
		(layer "In7.Cu")
		(net "SMB_BIC_I2C6_MUX_NIC_ADC_R_SDA")
	)
	(segment
		(start 131.543044 -154.266392)
		(end 132.253482 -153.791666)
		(width 0.15494)
		(layer "In7.Cu")
		(net "SMB_BIC_I2C6_MUX_NIC_ADC_R_SDA")
	)
	(segment
		(start 123.61926 -117.9703)
		(end 123.61926 -146.0119)
		(width 0.15494)
		(layer "In7.Cu")
		(net "SMB_BIC_I2C6_MUX_NIC_ADC_R_SDA")
	)
	(segment
		(start 117.7163 -112.06734)
		(end 123.61926 -117.9703)
		(width 0.15494)
		(layer "In7.Cu")
		(net "SMB_BIC_I2C6_MUX_NIC_ADC_R_SDA")
	)
	(segment
		(start 131.05892 -154.266392)
		(end 131.543044 -154.266392)
		(width 0.15494)
		(layer "In7.Cu")
		(net "SMB_BIC_I2C6_MUX_NIC_ADC_R_SDA")
	)
	(segment
		(start 128.524254 -151.731726)
		(end 131.05892 -154.266392)
		(width 0.15494)
		(layer "In7.Cu")
		(net "SMB_BIC_I2C6_MUX_NIC_ADC_R_SDA")
	)
	(segment
		(start 115.469416 -98.741738)
		(end 115.46967 -98.741738)
		(width 0.15494)
		(layer "In7.Cu")
		(net "SMB_BIC_I2C6_MUX_NIC_ADC_R_SDA")
	)
	(segment
		(start 117.7163 -100.988368)
		(end 117.7163 -112.06734)
		(width 0.15494)
		(layer "In7.Cu")
		(net "SMB_BIC_I2C6_MUX_NIC_ADC_R_SDA")
	)
	(segment
		(start 114.516408 -94.501716)
		(end 115.062 -95.047308)
		(width 0.15494)
		(layer "In7.Cu")
		(net "SMB_BIC_I2C6_MUX_NIC_ADC_R_SDA")
	)
	(segment
		(start 115.062 -95.047308)
		(end 115.062 -98.334322)
		(width 0.15494)
		(layer "In7.Cu")
		(net "SMB_BIC_I2C6_MUX_NIC_ADC_R_SDA")
	)
	(segment
		(start 132.253482 -153.791666)
		(end 132.27558 -153.782522)
		(width 0.15494)
		(layer "In7.Cu")
		(net "SMB_BIC_I2C6_MUX_NIC_ADC_R_SDA")
	)
	(segment
		(start 122.45086 -150.52421)
		(end 123.658376 -151.731726)
		(width 0.15494)
		(layer "In7.Cu")
		(net "SMB_BIC_I2C6_MUX_NIC_ADC_R_SDA")
	)
	(segment
		(start 122.45086 -147.1803)
		(end 122.45086 -150.52421)
		(width 0.15494)
		(layer "In7.Cu")
		(net "SMB_BIC_I2C6_MUX_NIC_ADC_R_SDA")
	)
	(segment
		(start 115.46967 -98.741738)
		(end 117.7163 -100.988368)
		(width 0.15494)
		(layer "In7.Cu")
		(net "SMB_BIC_I2C6_MUX_NIC_ADC_R_SDA")
	)
	(segment
		(start 243.1796 -155.332938)
		(end 243.42852 -155.581858)
		(width 0.15494)
		(layer "In9.Cu")
		(net "SMB_BIC_I2C6_MUX_NIC_ADC_R_SDA")
	)
	(segment
		(start 239.141508 -142.235936)
		(end 239.141508 -145.831814)
		(width 0.15494)
		(layer "In9.Cu")
		(net "SMB_BIC_I2C6_MUX_NIC_ADC_R_SDA")
	)
	(segment
		(start 238.407956 -146.565366)
		(end 238.407956 -150.295102)
		(width 0.15494)
		(layer "In9.Cu")
		(net "SMB_BIC_I2C6_MUX_NIC_ADC_R_SDA")
	)
	(segment
		(start 239.141508 -121.703846)
		(end 239.141508 -127.430022)
		(width 0.15494)
		(layer "In9.Cu")
		(net "SMB_BIC_I2C6_MUX_NIC_ADC_R_SDA")
	)
	(segment
		(start 243.589048 -107.50296)
		(end 243.589048 -118.048786)
		(width 0.15494)
		(layer "In9.Cu")
		(net "SMB_BIC_I2C6_MUX_NIC_ADC_R_SDA")
	)
	(segment
		(start 232.68178 -99.729036)
		(end 237.174024 -104.22128)
		(width 0.15494)
		(layer "In9.Cu")
		(net "SMB_BIC_I2C6_MUX_NIC_ADC_R_SDA")
	)
	(segment
		(start 229.14483 -97.60204)
		(end 231.271826 -99.729036)
		(width 0.15494)
		(layer "In9.Cu")
		(net "SMB_BIC_I2C6_MUX_NIC_ADC_R_SDA")
	)
	(segment
		(start 229.14483 -97.004124)
		(end 229.14483 -97.60204)
		(width 0.15494)
		(layer "In9.Cu")
		(net "SMB_BIC_I2C6_MUX_NIC_ADC_R_SDA")
	)
	(segment
		(start 236.728762 -129.842768)
		(end 236.728762 -139.82319)
		(width 0.15494)
		(layer "In9.Cu")
		(net "SMB_BIC_I2C6_MUX_NIC_ADC_R_SDA")
	)
	(segment
		(start 242.731036 -118.906798)
		(end 241.938556 -118.906798)
		(width 0.15494)
		(layer "In9.Cu")
		(net "SMB_BIC_I2C6_MUX_NIC_ADC_R_SDA")
	)
	(segment
		(start 243.42852 -155.581858)
		(end 246.339614 -155.581858)
		(width 0.15494)
		(layer "In9.Cu")
		(net "SMB_BIC_I2C6_MUX_NIC_ADC_R_SDA")
	)
	(segment
		(start 247.923558 -153.997914)
		(end 248.160286 -153.997914)
		(width 0.15494)
		(layer "In9.Cu")
		(net "SMB_BIC_I2C6_MUX_NIC_ADC_R_SDA")
	)
	(segment
		(start 241.938556 -118.906798)
		(end 239.141508 -121.703846)
		(width 0.15494)
		(layer "In9.Cu")
		(net "SMB_BIC_I2C6_MUX_NIC_ADC_R_SDA")
	)
	(segment
		(start 246.339614 -155.581858)
		(end 247.923558 -153.997914)
		(width 0.15494)
		(layer "In9.Cu")
		(net "SMB_BIC_I2C6_MUX_NIC_ADC_R_SDA")
	)
	(segment
		(start 239.141508 -145.831814)
		(end 238.407956 -146.565366)
		(width 0.15494)
		(layer "In9.Cu")
		(net "SMB_BIC_I2C6_MUX_NIC_ADC_R_SDA")
	)
	(segment
		(start 248.160286 -153.997914)
		(end 248.375678 -153.782522)
		(width 0.15494)
		(layer "In9.Cu")
		(net "SMB_BIC_I2C6_MUX_NIC_ADC_R_SDA")
	)
	(segment
		(start 236.728762 -139.82319)
		(end 239.141508 -142.235936)
		(width 0.15494)
		(layer "In9.Cu")
		(net "SMB_BIC_I2C6_MUX_NIC_ADC_R_SDA")
	)
	(segment
		(start 243.1796 -155.066746)
		(end 243.1796 -155.332938)
		(width 0.15494)
		(layer "In9.Cu")
		(net "SMB_BIC_I2C6_MUX_NIC_ADC_R_SDA")
	)
	(segment
		(start 239.141508 -127.430022)
		(end 236.728762 -129.842768)
		(width 0.15494)
		(layer "In9.Cu")
		(net "SMB_BIC_I2C6_MUX_NIC_ADC_R_SDA")
	)
	(segment
		(start 238.407956 -150.295102)
		(end 243.1796 -155.066746)
		(width 0.15494)
		(layer "In9.Cu")
		(net "SMB_BIC_I2C6_MUX_NIC_ADC_R_SDA")
	)
	(segment
		(start 228.206808 -96.066102)
		(end 229.14483 -97.004124)
		(width 0.15494)
		(layer "In9.Cu")
		(net "SMB_BIC_I2C6_MUX_NIC_ADC_R_SDA")
	)
	(segment
		(start 240.307368 -104.22128)
		(end 243.589048 -107.50296)
		(width 0.15494)
		(layer "In9.Cu")
		(net "SMB_BIC_I2C6_MUX_NIC_ADC_R_SDA")
	)
	(segment
		(start 231.271826 -99.729036)
		(end 232.68178 -99.729036)
		(width 0.15494)
		(layer "In9.Cu")
		(net "SMB_BIC_I2C6_MUX_NIC_ADC_R_SDA")
	)
	(segment
		(start 243.589048 -118.048786)
		(end 242.731036 -118.906798)
		(width 0.15494)
		(layer "In9.Cu")
		(net "SMB_BIC_I2C6_MUX_NIC_ADC_R_SDA")
	)
	(segment
		(start 220.366844 -96.716596)
		(end 221.017338 -96.066102)
		(width 0.15494)
		(layer "In9.Cu")
		(net "SMB_BIC_I2C6_MUX_NIC_ADC_R_SDA")
	)
	(segment
		(start 220.366844 -97.79)
		(end 220.366844 -96.716596)
		(width 0.15494)
		(layer "In9.Cu")
		(net "SMB_BIC_I2C6_MUX_NIC_ADC_R_SDA")
	)
	(segment
		(start 221.017338 -96.066102)
		(end 228.206808 -96.066102)
		(width 0.15494)
		(layer "In9.Cu")
		(net "SMB_BIC_I2C6_MUX_NIC_ADC_R_SDA")
	)
	(segment
		(start 237.174024 -104.22128)
		(end 240.307368 -104.22128)
		(width 0.15494)
		(layer "In9.Cu")
		(net "SMB_BIC_I2C6_MUX_NIC_ADC_R_SDA")
	)
	(segment
		(start 412.191454 -140.826998)
		(end 412.326074 -140.692378)
		(width 0.15494)
		(layer "In13.Cu")
		(net "SMB_BIC_I2C6_MUX_NIC_ADC_R_SDA")
	)
	(segment
		(start 328.479658 -92.775024)
		(end 327.5076 -93.747082)
		(width 0.15494)
		(layer "In13.Cu")
		(net "SMB_BIC_I2C6_MUX_NIC_ADC_R_SDA")
	)
	(segment
		(start 404.335742 -136.24433)
		(end 407.181304 -136.24433)
		(width 0.15494)
		(layer "In13.Cu")
		(net "SMB_BIC_I2C6_MUX_NIC_ADC_R_SDA")
	)
	(segment
		(start 353.739196 -99.591368)
		(end 336.865722 -99.591368)
		(width 0.15494)
		(layer "In13.Cu")
		(net "SMB_BIC_I2C6_MUX_NIC_ADC_R_SDA")
	)
	(segment
		(start 365.451898 -152.8064)
		(end 372.8212 -152.8064)
		(width 0.15494)
		(layer "In13.Cu")
		(net "SMB_BIC_I2C6_MUX_NIC_ADC_R_SDA")
	)
	(segment
		(start 333.843122 -93.500956)
		(end 333.11719 -92.775024)
		(width 0.15494)
		(layer "In13.Cu")
		(net "SMB_BIC_I2C6_MUX_NIC_ADC_R_SDA")
	)
	(segment
		(start 387.0452 -138.5824)
		(end 389.534908 -138.5824)
		(width 0.15494)
		(layer "In13.Cu")
		(net "SMB_BIC_I2C6_MUX_NIC_ADC_R_SDA")
	)
	(segment
		(start 367.03762 -89.998042)
		(end 365.751364 -91.284298)
		(width 0.15494)
		(layer "In13.Cu")
		(net "SMB_BIC_I2C6_MUX_NIC_ADC_R_SDA")
	)
	(segment
		(start 414.253934 -140.692378)
		(end 414.607756 -141.0462)
		(width 0.15494)
		(layer "In13.Cu")
		(net "SMB_BIC_I2C6_MUX_NIC_ADC_R_SDA")
	)
	(segment
		(start 336.865722 -99.591368)
		(end 335.951576 -98.677222)
		(width 0.15494)
		(layer "In13.Cu")
		(net "SMB_BIC_I2C6_MUX_NIC_ADC_R_SDA")
	)
	(segment
		(start 389.534908 -138.5824)
		(end 392.001502 -136.115806)
		(width 0.15494)
		(layer "In13.Cu")
		(net "SMB_BIC_I2C6_MUX_NIC_ADC_R_SDA")
	)
	(segment
		(start 327.5076 -96.6978)
		(end 327.2028 -97.0026)
		(width 0.15494)
		(layer "In13.Cu")
		(net "SMB_BIC_I2C6_MUX_NIC_ADC_R_SDA")
	)
	(segment
		(start 413.611314 -140.692378)
		(end 413.611314 -138.5824)
		(width 0.15494)
		(layer "In13.Cu")
		(net "SMB_BIC_I2C6_MUX_NIC_ADC_R_SDA")
	)
	(segment
		(start 362.046266 -91.284298)
		(end 353.739196 -99.591368)
		(width 0.15494)
		(layer "In13.Cu")
		(net "SMB_BIC_I2C6_MUX_NIC_ADC_R_SDA")
	)
	(segment
		(start 407.181304 -136.24433)
		(end 411.763972 -140.826998)
		(width 0.15494)
		(layer "In13.Cu")
		(net "SMB_BIC_I2C6_MUX_NIC_ADC_R_SDA")
	)
	(segment
		(start 413.738314 -138.4554)
		(end 414.126934 -138.4554)
		(width 0.15494)
		(layer "In13.Cu")
		(net "SMB_BIC_I2C6_MUX_NIC_ADC_R_SDA")
	)
	(segment
		(start 326.498204 -97.0026)
		(end 325.297546 -95.801942)
		(width 0.15494)
		(layer "In13.Cu")
		(net "SMB_BIC_I2C6_MUX_NIC_ADC_R_SDA")
	)
	(segment
		(start 372.8212 -152.8064)
		(end 387.0452 -138.5824)
		(width 0.15494)
		(layer "In13.Cu")
		(net "SMB_BIC_I2C6_MUX_NIC_ADC_R_SDA")
	)
	(segment
		(start 392.001502 -136.115806)
		(end 395.008862 -136.115806)
		(width 0.15494)
		(layer "In13.Cu")
		(net "SMB_BIC_I2C6_MUX_NIC_ADC_R_SDA")
	)
	(segment
		(start 398.361662 -139.468606)
		(end 401.111466 -139.468606)
		(width 0.15494)
		(layer "In13.Cu")
		(net "SMB_BIC_I2C6_MUX_NIC_ADC_R_SDA")
	)
	(segment
		(start 365.751364 -91.284298)
		(end 362.046266 -91.284298)
		(width 0.15494)
		(layer "In13.Cu")
		(net "SMB_BIC_I2C6_MUX_NIC_ADC_R_SDA")
	)
	(segment
		(start 414.253934 -138.5824)
		(end 414.253934 -140.692378)
		(width 0.15494)
		(layer "In13.Cu")
		(net "SMB_BIC_I2C6_MUX_NIC_ADC_R_SDA")
	)
	(segment
		(start 327.2028 -97.0026)
		(end 326.498204 -97.0026)
		(width 0.15494)
		(layer "In13.Cu")
		(net "SMB_BIC_I2C6_MUX_NIC_ADC_R_SDA")
	)
	(segment
		(start 333.843122 -94.778322)
		(end 333.843122 -93.500956)
		(width 0.15494)
		(layer "In13.Cu")
		(net "SMB_BIC_I2C6_MUX_NIC_ADC_R_SDA")
	)
	(segment
		(start 413.476694 -140.826998)
		(end 413.611314 -140.692378)
		(width 0.15494)
		(layer "In13.Cu")
		(net "SMB_BIC_I2C6_MUX_NIC_ADC_R_SDA")
	)
	(segment
		(start 335.951576 -98.677222)
		(end 335.951576 -96.886776)
		(width 0.15494)
		(layer "In13.Cu")
		(net "SMB_BIC_I2C6_MUX_NIC_ADC_R_SDA")
	)
	(segment
		(start 412.326074 -138.557)
		(end 412.453074 -138.43)
		(width 0.15494)
		(layer "In13.Cu")
		(net "SMB_BIC_I2C6_MUX_NIC_ADC_R_SDA")
	)
	(segment
		(start 413.611314 -138.5824)
		(end 413.738314 -138.4554)
		(width 0.15494)
		(layer "In13.Cu")
		(net "SMB_BIC_I2C6_MUX_NIC_ADC_R_SDA")
	)
	(segment
		(start 335.951576 -96.886776)
		(end 333.843122 -94.778322)
		(width 0.15494)
		(layer "In13.Cu")
		(net "SMB_BIC_I2C6_MUX_NIC_ADC_R_SDA")
	)
	(segment
		(start 401.111466 -139.468606)
		(end 404.335742 -136.24433)
		(width 0.15494)
		(layer "In13.Cu")
		(net "SMB_BIC_I2C6_MUX_NIC_ADC_R_SDA")
	)
	(segment
		(start 411.763972 -140.826998)
		(end 412.191454 -140.826998)
		(width 0.15494)
		(layer "In13.Cu")
		(net "SMB_BIC_I2C6_MUX_NIC_ADC_R_SDA")
	)
	(segment
		(start 377.53544 -88.8238)
		(end 376.884438 -88.172798)
		(width 0.15494)
		(layer "In13.Cu")
		(net "SMB_BIC_I2C6_MUX_NIC_ADC_R_SDA")
	)
	(segment
		(start 412.968694 -138.557)
		(end 412.968694 -140.692378)
		(width 0.15494)
		(layer "In13.Cu")
		(net "SMB_BIC_I2C6_MUX_NIC_ADC_R_SDA")
	)
	(segment
		(start 414.126934 -138.4554)
		(end 414.253934 -138.5824)
		(width 0.15494)
		(layer "In13.Cu")
		(net "SMB_BIC_I2C6_MUX_NIC_ADC_R_SDA")
	)
	(segment
		(start 414.607756 -141.0462)
		(end 442.910214 -141.0462)
		(width 0.15494)
		(layer "In13.Cu")
		(net "SMB_BIC_I2C6_MUX_NIC_ADC_R_SDA")
	)
	(segment
		(start 413.103314 -140.826998)
		(end 413.476694 -140.826998)
		(width 0.15494)
		(layer "In13.Cu")
		(net "SMB_BIC_I2C6_MUX_NIC_ADC_R_SDA")
	)
	(segment
		(start 364.475776 -153.782522)
		(end 365.451898 -152.8064)
		(width 0.15494)
		(layer "In13.Cu")
		(net "SMB_BIC_I2C6_MUX_NIC_ADC_R_SDA")
	)
	(segment
		(start 376.884438 -88.172798)
		(end 375.242582 -88.172798)
		(width 0.15494)
		(layer "In13.Cu")
		(net "SMB_BIC_I2C6_MUX_NIC_ADC_R_SDA")
	)
	(segment
		(start 327.5076 -93.747082)
		(end 327.5076 -96.6978)
		(width 0.15494)
		(layer "In13.Cu")
		(net "SMB_BIC_I2C6_MUX_NIC_ADC_R_SDA")
	)
	(segment
		(start 412.453074 -138.43)
		(end 412.841694 -138.43)
		(width 0.15494)
		(layer "In13.Cu")
		(net "SMB_BIC_I2C6_MUX_NIC_ADC_R_SDA")
	)
	(segment
		(start 442.910214 -141.0462)
		(end 446.046606 -137.909808)
		(width 0.15494)
		(layer "In13.Cu")
		(net "SMB_BIC_I2C6_MUX_NIC_ADC_R_SDA")
	)
	(segment
		(start 373.417338 -89.998042)
		(end 367.03762 -89.998042)
		(width 0.15494)
		(layer "In13.Cu")
		(net "SMB_BIC_I2C6_MUX_NIC_ADC_R_SDA")
	)
	(segment
		(start 375.242582 -88.172798)
		(end 373.417338 -89.998042)
		(width 0.15494)
		(layer "In13.Cu")
		(net "SMB_BIC_I2C6_MUX_NIC_ADC_R_SDA")
	)
	(segment
		(start 412.968694 -140.692378)
		(end 413.103314 -140.826998)
		(width 0.15494)
		(layer "In13.Cu")
		(net "SMB_BIC_I2C6_MUX_NIC_ADC_R_SDA")
	)
	(segment
		(start 395.008862 -136.115806)
		(end 398.361662 -139.468606)
		(width 0.15494)
		(layer "In13.Cu")
		(net "SMB_BIC_I2C6_MUX_NIC_ADC_R_SDA")
	)
	(segment
		(start 412.841694 -138.43)
		(end 412.968694 -138.557)
		(width 0.15494)
		(layer "In13.Cu")
		(net "SMB_BIC_I2C6_MUX_NIC_ADC_R_SDA")
	)
	(segment
		(start 333.11719 -92.775024)
		(end 328.479658 -92.775024)
		(width 0.15494)
		(layer "In13.Cu")
		(net "SMB_BIC_I2C6_MUX_NIC_ADC_R_SDA")
	)
	(segment
		(start 412.326074 -140.692378)
		(end 412.326074 -138.557)
		(width 0.15494)
		(layer "In13.Cu")
		(net "SMB_BIC_I2C6_MUX_NIC_ADC_R_SDA")
	)
	(segment
		(start 317.932054 -91.97086)
		(end 317.803276 -92.099638)
		(width 0.15494)
		(layer "In15.Cu")
		(net "SMB_BIC_I2C6_MUX_NIC_ADC_R_SDA")
	)
	(segment
		(start 133.327902 -152.7302)
		(end 132.27558 -153.782522)
		(width 0.15494)
		(layer "In15.Cu")
		(net "SMB_BIC_I2C6_MUX_NIC_ADC_R_SDA")
	)
	(segment
		(start 178.0794 -136.1186)
		(end 172.412152 -136.1186)
		(width 0.15494)
		(layer "In15.Cu")
		(net "SMB_BIC_I2C6_MUX_NIC_ADC_R_SDA")
	)
	(segment
		(start 317.235078 -91.97086)
		(end 317.053214 -91.97086)
		(width 0.15494)
		(layer "In15.Cu")
		(net "SMB_BIC_I2C6_MUX_NIC_ADC_R_SDA")
	)
	(segment
		(start 248.375678 -153.782522)
		(end 248.071894 -153.782522)
		(width 0.15494)
		(layer "In15.Cu")
		(net "SMB_BIC_I2C6_MUX_NIC_ADC_R_SDA")
	)
	(segment
		(start 238.3028 -146.974306)
		(end 237.6678 -146.339306)
		(width 0.15494)
		(layer "In15.Cu")
		(net "SMB_BIC_I2C6_MUX_NIC_ADC_R_SDA")
	)
	(segment
		(start 84.131404 -93.594936)
		(end 87.73414 -89.9922)
		(width 0.15494)
		(layer "In15.Cu")
		(net "SMB_BIC_I2C6_MUX_NIC_ADC_R_SDA")
	)
	(segment
		(start 318.553338 -92.851986)
		(end 318.371474 -92.851986)
		(width 0.15494)
		(layer "In15.Cu")
		(net "SMB_BIC_I2C6_MUX_NIC_ADC_R_SDA")
	)
	(segment
		(start 238.3028 -150.240746)
		(end 238.3028 -146.974306)
		(width 0.15494)
		(layer "In15.Cu")
		(net "SMB_BIC_I2C6_MUX_NIC_ADC_R_SDA")
	)
	(segment
		(start 237.6678 -146.339306)
		(end 237.6678 -135.9662)
		(width 0.15494)
		(layer "In15.Cu")
		(net "SMB_BIC_I2C6_MUX_NIC_ADC_R_SDA")
	)
	(segment
		(start 232.769156 -100.082096)
		(end 224.262696 -100.082096)
		(width 0.15494)
		(layer "In15.Cu")
		(net "SMB_BIC_I2C6_MUX_NIC_ADC_R_SDA")
	)
	(segment
		(start 325.297546 -95.801942)
		(end 322.34759 -92.851986)
		(width 0.15494)
		(layer "In15.Cu")
		(net "SMB_BIC_I2C6_MUX_NIC_ADC_R_SDA")
	)
	(segment
		(start 248.071894 -153.782522)
		(end 247.503442 -154.350974)
		(width 0.15494)
		(layer "In15.Cu")
		(net "SMB_BIC_I2C6_MUX_NIC_ADC_R_SDA")
	)
	(segment
		(start 317.803276 -92.099638)
		(end 317.803276 -92.723208)
		(width 0.15494)
		(layer "In15.Cu")
		(net "SMB_BIC_I2C6_MUX_NIC_ADC_R_SDA")
	)
	(segment
		(start 267.1318 -92.837)
		(end 256.867152 -92.837)
		(width 0.15494)
		(layer "In15.Cu")
		(net "SMB_BIC_I2C6_MUX_NIC_ADC_R_SDA")
	)
	(segment
		(start 196.686678 -139.412472)
		(end 195.374006 -138.0998)
		(width 0.15494)
		(layer "In15.Cu")
		(net "SMB_BIC_I2C6_MUX_NIC_ADC_R_SDA")
	)
	(segment
		(start 318.242696 -92.099638)
		(end 318.113918 -91.97086)
		(width 0.15494)
		(layer "In15.Cu")
		(net "SMB_BIC_I2C6_MUX_NIC_ADC_R_SDA")
	)
	(segment
		(start 244.2972 -151.2824)
		(end 239.344454 -151.2824)
		(width 0.15494)
		(layer "In15.Cu")
		(net "SMB_BIC_I2C6_MUX_NIC_ADC_R_SDA")
	)
	(segment
		(start 318.992758 -91.97086)
		(end 318.810894 -91.97086)
		(width 0.15494)
		(layer "In15.Cu")
		(net "SMB_BIC_I2C6_MUX_NIC_ADC_R_SDA")
	)
	(segment
		(start 317.053214 -91.97086)
		(end 316.924436 -92.099638)
		(width 0.15494)
		(layer "In15.Cu")
		(net "SMB_BIC_I2C6_MUX_NIC_ADC_R_SDA")
	)
	(segment
		(start 311.164732 -92.851986)
		(end 310.33974 -92.026994)
		(width 0.15494)
		(layer "In15.Cu")
		(net "SMB_BIC_I2C6_MUX_NIC_ADC_R_SDA")
	)
	(segment
		(start 322.34759 -92.851986)
		(end 319.250314 -92.851986)
		(width 0.15494)
		(layer "In15.Cu")
		(net "SMB_BIC_I2C6_MUX_NIC_ADC_R_SDA")
	)
	(segment
		(start 87.73414 -89.9922)
		(end 92.851986 -89.9922)
		(width 0.15494)
		(layer "In15.Cu")
		(net "SMB_BIC_I2C6_MUX_NIC_ADC_R_SDA")
	)
	(segment
		(start 235.2548 -133.5532)
		(end 217.481404 -133.5532)
		(width 0.15494)
		(layer "In15.Cu")
		(net "SMB_BIC_I2C6_MUX_NIC_ADC_R_SDA")
	)
	(segment
		(start 246.8626 -153.8478)
		(end 244.2972 -151.2824)
		(width 0.15494)
		(layer "In15.Cu")
		(net "SMB_BIC_I2C6_MUX_NIC_ADC_R_SDA")
	)
	(segment
		(start 318.682116 -92.723208)
		(end 318.553338 -92.851986)
		(width 0.15494)
		(layer "In15.Cu")
		(net "SMB_BIC_I2C6_MUX_NIC_ADC_R_SDA")
	)
	(segment
		(start 317.803276 -92.723208)
		(end 317.674498 -92.851986)
		(width 0.15494)
		(layer "In15.Cu")
		(net "SMB_BIC_I2C6_MUX_NIC_ADC_R_SDA")
	)
	(segment
		(start 158.343854 -136.1948)
		(end 151.917654 -142.621)
		(width 0.15494)
		(layer "In15.Cu")
		(net "SMB_BIC_I2C6_MUX_NIC_ADC_R_SDA")
	)
	(segment
		(start 267.941806 -92.026994)
		(end 267.1318 -92.837)
		(width 0.15494)
		(layer "In15.Cu")
		(net "SMB_BIC_I2C6_MUX_NIC_ADC_R_SDA")
	)
	(segment
		(start 233.47426 -100.7872)
		(end 232.769156 -100.082096)
		(width 0.15494)
		(layer "In15.Cu")
		(net "SMB_BIC_I2C6_MUX_NIC_ADC_R_SDA")
	)
	(segment
		(start 220.94571 -98.368866)
		(end 220.366844 -97.79)
		(width 0.15494)
		(layer "In15.Cu")
		(net "SMB_BIC_I2C6_MUX_NIC_ADC_R_SDA")
	)
	(segment
		(start 317.363856 -92.723208)
		(end 317.363856 -92.099638)
		(width 0.15494)
		(layer "In15.Cu")
		(net "SMB_BIC_I2C6_MUX_NIC_ADC_R_SDA")
	)
	(segment
		(start 317.363856 -92.099638)
		(end 317.235078 -91.97086)
		(width 0.15494)
		(layer "In15.Cu")
		(net "SMB_BIC_I2C6_MUX_NIC_ADC_R_SDA")
	)
	(segment
		(start 224.262696 -100.082096)
		(end 222.549466 -98.368866)
		(width 0.15494)
		(layer "In15.Cu")
		(net "SMB_BIC_I2C6_MUX_NIC_ADC_R_SDA")
	)
	(segment
		(start 316.795658 -92.851986)
		(end 311.164732 -92.851986)
		(width 0.15494)
		(layer "In15.Cu")
		(net "SMB_BIC_I2C6_MUX_NIC_ADC_R_SDA")
	)
	(segment
		(start 256.867152 -92.837)
		(end 248.916952 -100.7872)
		(width 0.15494)
		(layer "In15.Cu")
		(net "SMB_BIC_I2C6_MUX_NIC_ADC_R_SDA")
	)
	(segment
		(start 140.081254 -152.7302)
		(end 133.327902 -152.7302)
		(width 0.15494)
		(layer "In15.Cu")
		(net "SMB_BIC_I2C6_MUX_NIC_ADC_R_SDA")
	)
	(segment
		(start 316.924436 -92.723208)
		(end 316.795658 -92.851986)
		(width 0.15494)
		(layer "In15.Cu")
		(net "SMB_BIC_I2C6_MUX_NIC_ADC_R_SDA")
	)
	(segment
		(start 237.6678 -135.9662)
		(end 235.2548 -133.5532)
		(width 0.15494)
		(layer "In15.Cu")
		(net "SMB_BIC_I2C6_MUX_NIC_ADC_R_SDA")
	)
	(segment
		(start 318.371474 -92.851986)
		(end 318.242696 -92.723208)
		(width 0.15494)
		(layer "In15.Cu")
		(net "SMB_BIC_I2C6_MUX_NIC_ADC_R_SDA")
	)
	(segment
		(start 318.810894 -91.97086)
		(end 318.682116 -92.099638)
		(width 0.15494)
		(layer "In15.Cu")
		(net "SMB_BIC_I2C6_MUX_NIC_ADC_R_SDA")
	)
	(segment
		(start 310.33974 -92.026994)
		(end 267.941806 -92.026994)
		(width 0.15494)
		(layer "In15.Cu")
		(net "SMB_BIC_I2C6_MUX_NIC_ADC_R_SDA")
	)
	(segment
		(start 217.481404 -133.5532)
		(end 211.622132 -139.412472)
		(width 0.15494)
		(layer "In15.Cu")
		(net "SMB_BIC_I2C6_MUX_NIC_ADC_R_SDA")
	)
	(segment
		(start 318.113918 -91.97086)
		(end 317.932054 -91.97086)
		(width 0.15494)
		(layer "In15.Cu")
		(net "SMB_BIC_I2C6_MUX_NIC_ADC_R_SDA")
	)
	(segment
		(start 166.87165 -138.3538)
		(end 164.71265 -136.1948)
		(width 0.15494)
		(layer "In15.Cu")
		(net "SMB_BIC_I2C6_MUX_NIC_ADC_R_SDA")
	)
	(segment
		(start 247.503442 -154.350974)
		(end 247.187466 -154.350974)
		(width 0.15494)
		(layer "In15.Cu")
		(net "SMB_BIC_I2C6_MUX_NIC_ADC_R_SDA")
	)
	(segment
		(start 25.43048 -95.986092)
		(end 31.126938 -90.289634)
		(width 0.15494)
		(layer "In15.Cu")
		(net "SMB_BIC_I2C6_MUX_NIC_ADC_R_SDA")
	)
	(segment
		(start 78.316582 -93.594936)
		(end 84.131404 -93.594936)
		(width 0.15494)
		(layer "In15.Cu")
		(net "SMB_BIC_I2C6_MUX_NIC_ADC_R_SDA")
	)
	(segment
		(start 248.916952 -100.7872)
		(end 233.47426 -100.7872)
		(width 0.15494)
		(layer "In15.Cu")
		(net "SMB_BIC_I2C6_MUX_NIC_ADC_R_SDA")
	)
	(segment
		(start 170.176952 -138.3538)
		(end 166.87165 -138.3538)
		(width 0.15494)
		(layer "In15.Cu")
		(net "SMB_BIC_I2C6_MUX_NIC_ADC_R_SDA")
	)
	(segment
		(start 31.126938 -90.289634)
		(end 75.01128 -90.289634)
		(width 0.15494)
		(layer "In15.Cu")
		(net "SMB_BIC_I2C6_MUX_NIC_ADC_R_SDA")
	)
	(segment
		(start 239.344454 -151.2824)
		(end 238.3028 -150.240746)
		(width 0.15494)
		(layer "In15.Cu")
		(net "SMB_BIC_I2C6_MUX_NIC_ADC_R_SDA")
	)
	(segment
		(start 317.492634 -92.851986)
		(end 317.363856 -92.723208)
		(width 0.15494)
		(layer "In15.Cu")
		(net "SMB_BIC_I2C6_MUX_NIC_ADC_R_SDA")
	)
	(segment
		(start 75.01128 -90.289634)
		(end 78.316582 -93.594936)
		(width 0.15494)
		(layer "In15.Cu")
		(net "SMB_BIC_I2C6_MUX_NIC_ADC_R_SDA")
	)
	(segment
		(start 317.674498 -92.851986)
		(end 317.492634 -92.851986)
		(width 0.15494)
		(layer "In15.Cu")
		(net "SMB_BIC_I2C6_MUX_NIC_ADC_R_SDA")
	)
	(segment
		(start 319.121536 -92.723208)
		(end 319.121536 -92.099638)
		(width 0.15494)
		(layer "In15.Cu")
		(net "SMB_BIC_I2C6_MUX_NIC_ADC_R_SDA")
	)
	(segment
		(start 164.71265 -136.1948)
		(end 158.343854 -136.1948)
		(width 0.15494)
		(layer "In15.Cu")
		(net "SMB_BIC_I2C6_MUX_NIC_ADC_R_SDA")
	)
	(segment
		(start 211.622132 -139.412472)
		(end 196.686678 -139.412472)
		(width 0.15494)
		(layer "In15.Cu")
		(net "SMB_BIC_I2C6_MUX_NIC_ADC_R_SDA")
	)
	(segment
		(start 319.121536 -92.099638)
		(end 318.992758 -91.97086)
		(width 0.15494)
		(layer "In15.Cu")
		(net "SMB_BIC_I2C6_MUX_NIC_ADC_R_SDA")
	)
	(segment
		(start 195.374006 -138.0998)
		(end 180.0606 -138.0998)
		(width 0.15494)
		(layer "In15.Cu")
		(net "SMB_BIC_I2C6_MUX_NIC_ADC_R_SDA")
	)
	(segment
		(start 319.250314 -92.851986)
		(end 319.121536 -92.723208)
		(width 0.15494)
		(layer "In15.Cu")
		(net "SMB_BIC_I2C6_MUX_NIC_ADC_R_SDA")
	)
	(segment
		(start 316.924436 -92.099638)
		(end 316.924436 -92.723208)
		(width 0.15494)
		(layer "In15.Cu")
		(net "SMB_BIC_I2C6_MUX_NIC_ADC_R_SDA")
	)
	(segment
		(start 247.187466 -154.350974)
		(end 246.8626 -154.026108)
		(width 0.15494)
		(layer "In15.Cu")
		(net "SMB_BIC_I2C6_MUX_NIC_ADC_R_SDA")
	)
	(segment
		(start 318.242696 -92.723208)
		(end 318.242696 -92.099638)
		(width 0.15494)
		(layer "In15.Cu")
		(net "SMB_BIC_I2C6_MUX_NIC_ADC_R_SDA")
	)
	(segment
		(start 150.190454 -142.621)
		(end 140.081254 -152.7302)
		(width 0.15494)
		(layer "In15.Cu")
		(net "SMB_BIC_I2C6_MUX_NIC_ADC_R_SDA")
	)
	(segment
		(start 151.917654 -142.621)
		(end 150.190454 -142.621)
		(width 0.15494)
		(layer "In15.Cu")
		(net "SMB_BIC_I2C6_MUX_NIC_ADC_R_SDA")
	)
	(segment
		(start 318.682116 -92.099638)
		(end 318.682116 -92.723208)
		(width 0.15494)
		(layer "In15.Cu")
		(net "SMB_BIC_I2C6_MUX_NIC_ADC_R_SDA")
	)
	(segment
		(start 172.412152 -136.1186)
		(end 170.176952 -138.3538)
		(width 0.15494)
		(layer "In15.Cu")
		(net "SMB_BIC_I2C6_MUX_NIC_ADC_R_SDA")
	)
	(segment
		(start 180.0606 -138.0998)
		(end 178.0794 -136.1186)
		(width 0.15494)
		(layer "In15.Cu")
		(net "SMB_BIC_I2C6_MUX_NIC_ADC_R_SDA")
	)
	(segment
		(start 222.549466 -98.368866)
		(end 220.94571 -98.368866)
		(width 0.15494)
		(layer "In15.Cu")
		(net "SMB_BIC_I2C6_MUX_NIC_ADC_R_SDA")
	)
	(segment
		(start 246.8626 -154.026108)
		(end 246.8626 -153.8478)
		(width 0.15494)
		(layer "In15.Cu")
		(net "SMB_BIC_I2C6_MUX_NIC_ADC_R_SDA")
	)
	(segment
		(start 145.239486 -389.998204)
		(end 145.239486 -389.388096)
		(width 0.13208)
		(layer "F.Cu")
		(net "SMB_GPU1_ALERT_N")
	)
	(segment
		(start 145.230342 -389.98906)
		(end 145.239486 -389.998204)
		(width 0.13208)
		(layer "F.Cu")
		(net "SMB_GPU1_ALERT_N")
	)
	(segment
		(start 144.982184 -389.130794)
		(end 144.982184 -388.698486)
		(width 0.13208)
		(layer "F.Cu")
		(net "SMB_GPU1_ALERT_N")
	)
	(segment
		(start 145.239486 -389.388096)
		(end 144.982184 -389.130794)
		(width 0.13208)
		(layer "F.Cu")
		(net "SMB_GPU1_ALERT_N")
	)
	(segment
		(start 144.261332 -389.98906)
		(end 145.230342 -389.98906)
		(width 0.13208)
		(layer "F.Cu")
		(net "SMB_GPU1_ALERT_N")
	)
	(via
		(at 144.982184 -388.698486)
		(size 0.508)
		(drill 0.254)
		(layers "F.Cu" "B.Cu")
		(net "SMB_GPU1_ALERT_N")
	)
	(segment
		(start 158.621984 -414.476438)
		(end 176.810416 -414.476438)
		(width 0.15494)
		(layer "In9.Cu")
		(net "SMB_GPU1_ALERT_N")
	)
	(segment
		(start 145.44167 -388.239)
		(end 146.386042 -388.239)
		(width 0.15494)
		(layer "In9.Cu")
		(net "SMB_GPU1_ALERT_N")
	)
	(segment
		(start 146.386042 -388.239)
		(end 146.746468 -388.599426)
		(width 0.15494)
		(layer "In9.Cu")
		(net "SMB_GPU1_ALERT_N")
	)
	(segment
		(start 178.062382 -405.589994)
		(end 177.509932 -405.589994)
		(width 0.15494)
		(layer "In9.Cu")
		(net "SMB_GPU1_ALERT_N")
	)
	(segment
		(start 147.670012 -390.2964)
		(end 148.6154 -390.2964)
		(width 0.15494)
		(layer "In9.Cu")
		(net "SMB_GPU1_ALERT_N")
	)
	(segment
		(start 176.810416 -414.476438)
		(end 178.7906 -412.496254)
		(width 0.15494)
		(layer "In9.Cu")
		(net "SMB_GPU1_ALERT_N")
	)
	(segment
		(start 178.7906 -406.318212)
		(end 178.062382 -405.589994)
		(width 0.15494)
		(layer "In9.Cu")
		(net "SMB_GPU1_ALERT_N")
	)
	(segment
		(start 151.714454 -390.7282)
		(end 155.2702 -394.283946)
		(width 0.15494)
		(layer "In9.Cu")
		(net "SMB_GPU1_ALERT_N")
	)
	(segment
		(start 148.6154 -390.2964)
		(end 149.0472 -390.7282)
		(width 0.15494)
		(layer "In9.Cu")
		(net "SMB_GPU1_ALERT_N")
	)
	(segment
		(start 144.982184 -388.698486)
		(end 145.44167 -388.239)
		(width 0.15494)
		(layer "In9.Cu")
		(net "SMB_GPU1_ALERT_N")
	)
	(segment
		(start 155.2702 -394.283946)
		(end 155.2702 -411.124654)
		(width 0.15494)
		(layer "In9.Cu")
		(net "SMB_GPU1_ALERT_N")
	)
	(segment
		(start 178.7906 -412.496254)
		(end 178.7906 -406.318212)
		(width 0.15494)
		(layer "In9.Cu")
		(net "SMB_GPU1_ALERT_N")
	)
	(segment
		(start 155.2702 -411.124654)
		(end 158.621984 -414.476438)
		(width 0.15494)
		(layer "In9.Cu")
		(net "SMB_GPU1_ALERT_N")
	)
	(segment
		(start 146.746468 -388.599426)
		(end 146.746468 -389.372856)
		(width 0.15494)
		(layer "In9.Cu")
		(net "SMB_GPU1_ALERT_N")
	)
	(segment
		(start 149.0472 -390.7282)
		(end 151.714454 -390.7282)
		(width 0.15494)
		(layer "In9.Cu")
		(net "SMB_GPU1_ALERT_N")
	)
	(segment
		(start 146.746468 -389.372856)
		(end 147.670012 -390.2964)
		(width 0.15494)
		(layer "In9.Cu")
		(net "SMB_GPU1_ALERT_N")
	)
	(segment
		(start 224.267776 -219.904056)
		(end 223.86798 -220.303852)
		(width 0.13208)
		(layer "F.Cu")
		(net "SMB_PEX_SDA")
	)
	(via
		(at 223.86798 -220.303852)
		(size 0.4572)
		(drill 0.254)
		(layers "F.Cu" "B.Cu")
		(net "SMB_PEX_SDA")
	)
	(via
		(at 219.254324 -219.495116)
		(size 0.6604)
		(drill 0.3302)
		(layers "F.Cu" "B.Cu")
		(net "SMB_PEX_SDA")
	)
	(segment
		(start 222.261176 -220.17609)
		(end 220.18244 -220.17609)
		(width 0.13208)
		(layer "B.Cu")
		(net "SMB_PEX_SDA")
	)
	(segment
		(start 218.435682 -220.542866)
		(end 217.844116 -220.542866)
		(width 0.13208)
		(layer "B.Cu")
		(net "SMB_PEX_SDA")
	)
	(segment
		(start 219.501466 -219.495116)
		(end 219.254324 -219.495116)
		(width 0.13208)
		(layer "B.Cu")
		(net "SMB_PEX_SDA")
	)
	(segment
		(start 219.254324 -219.495116)
		(end 219.254324 -219.724224)
		(width 0.13208)
		(layer "B.Cu")
		(net "SMB_PEX_SDA")
	)
	(segment
		(start 219.254324 -219.724224)
		(end 218.435682 -220.542866)
		(width 0.13208)
		(layer "B.Cu")
		(net "SMB_PEX_SDA")
	)
	(segment
		(start 217.844116 -220.542866)
		(end 217.635836 -220.334586)
		(width 0.13208)
		(layer "B.Cu")
		(net "SMB_PEX_SDA")
	)
	(segment
		(start 223.86798 -220.303852)
		(end 222.388938 -220.303852)
		(width 0.13208)
		(layer "B.Cu")
		(net "SMB_PEX_SDA")
	)
	(segment
		(start 220.18244 -220.17609)
		(end 219.501466 -219.495116)
		(width 0.13208)
		(layer "B.Cu")
		(net "SMB_PEX_SDA")
	)
	(segment
		(start 222.388938 -220.303852)
		(end 222.261176 -220.17609)
		(width 0.13208)
		(layer "B.Cu")
		(net "SMB_PEX_SDA")
	)
	(segment
		(start 423.470832 -35.876738)
		(end 422.727882 -35.876738)
		(width 0.13208)
		(layer "F.Cu")
		(net "PWRGD_P3V3_SSD15_R")
	)
	(segment
		(start 423.470832 -35.876738)
		(end 424.182032 -35.876738)
		(width 0.13208)
		(layer "F.Cu")
		(net "PWRGD_P3V3_SSD15_R")
	)
	(segment
		(start 424.182032 -35.876738)
		(end 424.39717 -35.6616)
		(width 0.13208)
		(layer "F.Cu")
		(net "PWRGD_P3V3_SSD15_R")
	)
	(segment
		(start 424.39717 -35.6616)
		(end 426.937678 -35.6616)
		(width 0.13208)
		(layer "F.Cu")
		(net "PWRGD_P3V3_SSD15_R")
	)
	(segment
		(start 427.50867 -36.232592)
		(end 427.895258 -36.232592)
		(width 0.13208)
		(layer "F.Cu")
		(net "PWRGD_P3V3_SSD15_R")
	)
	(segment
		(start 343.69375 -214.387176)
		(end 344.093546 -213.98738)
		(width 0.13208)
		(layer "F.Cu")
		(net "PWRGD_P3V3_SSD15_R")
	)
	(segment
		(start 426.937678 -35.6616)
		(end 427.50867 -36.232592)
		(width 0.13208)
		(layer "F.Cu")
		(net "PWRGD_P3V3_SSD15_R")
	)
	(segment
		(start 434.910992 -61.386974)
		(end 434.910992 -62.051438)
		(width 0.13208)
		(layer "F.Cu")
		(net "PWRGD_P3V3_SSD15_R")
	)
	(via
		(at 344.093546 -213.98738)
		(size 0.4572)
		(drill 0.254)
		(layers "F.Cu" "B.Cu")
		(net "PWRGD_P3V3_SSD15_R")
	)
	(via
		(at 416.56762 -85.2297)
		(size 0.508)
		(drill 0.254)
		(layers "F.Cu" "B.Cu")
		(net "PWRGD_P3V3_SSD15_R")
	)
	(via
		(at 423.470832 -35.876738)
		(size 0.508)
		(drill 0.254)
		(layers "F.Cu" "B.Cu")
		(net "PWRGD_P3V3_SSD15_R")
	)
	(via
		(at 434.910992 -62.051438)
		(size 0.508)
		(drill 0.254)
		(layers "F.Cu" "B.Cu")
		(net "PWRGD_P3V3_SSD15_R")
	)
	(via
		(at 365.447072 -94.40037)
		(size 0.508)
		(drill 0.254)
		(layers "F.Cu" "B.Cu")
		(net "PWRGD_P3V3_SSD15_R")
	)
	(segment
		(start 349.443548 -128.471676)
		(end 353.376992 -124.538232)
		(width 0.15494)
		(layer "In5.Cu")
		(net "PWRGD_P3V3_SSD15_R")
	)
	(segment
		(start 357.043482 -174.056548)
		(end 349.412814 -166.42588)
		(width 0.15494)
		(layer "In5.Cu")
		(net "PWRGD_P3V3_SSD15_R")
	)
	(segment
		(start 359.25887 -199.221344)
		(end 359.25887 -181.307486)
		(width 0.15494)
		(layer "In5.Cu")
		(net "PWRGD_P3V3_SSD15_R")
	)
	(segment
		(start 350.104456 -204.7494)
		(end 351.1296 -204.7494)
		(width 0.15494)
		(layer "In5.Cu")
		(net "PWRGD_P3V3_SSD15_R")
	)
	(segment
		(start 353.376992 -116.753386)
		(end 361.671362 -108.459016)
		(width 0.15494)
		(layer "In5.Cu")
		(net "PWRGD_P3V3_SSD15_R")
	)
	(segment
		(start 350.058736 -204.70368)
		(end 350.104456 -204.7494)
		(width 0.15494)
		(layer "In5.Cu")
		(net "PWRGD_P3V3_SSD15_R")
	)
	(segment
		(start 345.7194 -207.996028)
		(end 346.722446 -206.992982)
		(width 0.15494)
		(layer "In5.Cu")
		(net "PWRGD_P3V3_SSD15_R")
	)
	(segment
		(start 346.722446 -205.84287)
		(end 347.861636 -204.70368)
		(width 0.15494)
		(layer "In5.Cu")
		(net "PWRGD_P3V3_SSD15_R")
	)
	(segment
		(start 351.85604 -203.64196)
		(end 353.810316 -203.64196)
		(width 0.15494)
		(layer "In5.Cu")
		(net "PWRGD_P3V3_SSD15_R")
	)
	(segment
		(start 351.409 -204.089)
		(end 351.85604 -203.64196)
		(width 0.15494)
		(layer "In5.Cu")
		(net "PWRGD_P3V3_SSD15_R")
	)
	(segment
		(start 360.463592 -178.585368)
		(end 360.0069 -178.585368)
		(width 0.15494)
		(layer "In5.Cu")
		(net "PWRGD_P3V3_SSD15_R")
	)
	(segment
		(start 344.093546 -213.98738)
		(end 344.491056 -213.58987)
		(width 0.0889)
		(layer "In5.Cu")
		(net "PWRGD_P3V3_SSD15_R")
	)
	(segment
		(start 345.7194 -210.7692)
		(end 345.7194 -207.996028)
		(width 0.15494)
		(layer "In5.Cu")
		(net "PWRGD_P3V3_SSD15_R")
	)
	(segment
		(start 360.0069 -178.585368)
		(end 358.642158 -177.220626)
		(width 0.15494)
		(layer "In5.Cu")
		(net "PWRGD_P3V3_SSD15_R")
	)
	(segment
		(start 360.712512 -178.834288)
		(end 360.463592 -178.585368)
		(width 0.15494)
		(layer "In5.Cu")
		(net "PWRGD_P3V3_SSD15_R")
	)
	(segment
		(start 347.861636 -204.70368)
		(end 350.058736 -204.70368)
		(width 0.15494)
		(layer "In5.Cu")
		(net "PWRGD_P3V3_SSD15_R")
	)
	(segment
		(start 344.491056 -212.05444)
		(end 344.491056 -211.918296)
		(width 0.15494)
		(layer "In5.Cu")
		(net "PWRGD_P3V3_SSD15_R")
	)
	(segment
		(start 435.420008 -62.051438)
		(end 436.130954 -61.340492)
		(width 0.15494)
		(layer "In5.Cu")
		(net "PWRGD_P3V3_SSD15_R")
	)
	(segment
		(start 357.871014 -200.6092)
		(end 359.25887 -199.221344)
		(width 0.15494)
		(layer "In5.Cu")
		(net "PWRGD_P3V3_SSD15_R")
	)
	(segment
		(start 344.491056 -211.918296)
		(end 344.40368 -211.83092)
		(width 0.15494)
		(layer "In5.Cu")
		(net "PWRGD_P3V3_SSD15_R")
	)
	(segment
		(start 344.40368 -211.3915)
		(end 344.77198 -211.0232)
		(width 0.15494)
		(layer "In5.Cu")
		(net "PWRGD_P3V3_SSD15_R")
	)
	(segment
		(start 434.910992 -68.864734)
		(end 418.546026 -85.2297)
		(width 0.15494)
		(layer "In5.Cu")
		(net "PWRGD_P3V3_SSD15_R")
	)
	(segment
		(start 356.843076 -200.6092)
		(end 357.871014 -200.6092)
		(width 0.15494)
		(layer "In5.Cu")
		(net "PWRGD_P3V3_SSD15_R")
	)
	(segment
		(start 434.910992 -62.051438)
		(end 435.420008 -62.051438)
		(width 0.15494)
		(layer "In5.Cu")
		(net "PWRGD_P3V3_SSD15_R")
	)
	(segment
		(start 358.642158 -176.228756)
		(end 357.043482 -174.63008)
		(width 0.15494)
		(layer "In5.Cu")
		(net "PWRGD_P3V3_SSD15_R")
	)
	(segment
		(start 358.642158 -177.220626)
		(end 358.642158 -176.228756)
		(width 0.15494)
		(layer "In5.Cu")
		(net "PWRGD_P3V3_SSD15_R")
	)
	(segment
		(start 436.130954 -61.340492)
		(end 436.130954 -45.845222)
		(width 0.15494)
		(layer "In5.Cu")
		(net "PWRGD_P3V3_SSD15_R")
	)
	(segment
		(start 346.722446 -206.992982)
		(end 346.722446 -205.84287)
		(width 0.15494)
		(layer "In5.Cu")
		(net "PWRGD_P3V3_SSD15_R")
	)
	(segment
		(start 360.712512 -179.853844)
		(end 360.712512 -178.834288)
		(width 0.15494)
		(layer "In5.Cu")
		(net "PWRGD_P3V3_SSD15_R")
	)
	(segment
		(start 349.443548 -158.168594)
		(end 349.443548 -128.471676)
		(width 0.15494)
		(layer "In5.Cu")
		(net "PWRGD_P3V3_SSD15_R")
	)
	(segment
		(start 344.40368 -211.83092)
		(end 344.40368 -211.3915)
		(width 0.15494)
		(layer "In5.Cu")
		(net "PWRGD_P3V3_SSD15_R")
	)
	(segment
		(start 351.1296 -204.7494)
		(end 351.409 -204.47)
		(width 0.15494)
		(layer "In5.Cu")
		(net "PWRGD_P3V3_SSD15_R")
	)
	(segment
		(start 361.671362 -108.459016)
		(end 361.671362 -98.17608)
		(width 0.15494)
		(layer "In5.Cu")
		(net "PWRGD_P3V3_SSD15_R")
	)
	(segment
		(start 436.130954 -45.845222)
		(end 426.16247 -35.876738)
		(width 0.15494)
		(layer "In5.Cu")
		(net "PWRGD_P3V3_SSD15_R")
	)
	(segment
		(start 418.546026 -85.2297)
		(end 416.56762 -85.2297)
		(width 0.15494)
		(layer "In5.Cu")
		(net "PWRGD_P3V3_SSD15_R")
	)
	(segment
		(start 426.16247 -35.876738)
		(end 423.470832 -35.876738)
		(width 0.15494)
		(layer "In5.Cu")
		(net "PWRGD_P3V3_SSD15_R")
	)
	(segment
		(start 349.412814 -166.42588)
		(end 349.412814 -158.199328)
		(width 0.15494)
		(layer "In5.Cu")
		(net "PWRGD_P3V3_SSD15_R")
	)
	(segment
		(start 353.810316 -203.64196)
		(end 356.843076 -200.6092)
		(width 0.15494)
		(layer "In5.Cu")
		(net "PWRGD_P3V3_SSD15_R")
	)
	(segment
		(start 434.910992 -62.051438)
		(end 434.910992 -68.864734)
		(width 0.15494)
		(layer "In5.Cu")
		(net "PWRGD_P3V3_SSD15_R")
	)
	(segment
		(start 357.043482 -174.63008)
		(end 357.043482 -174.056548)
		(width 0.15494)
		(layer "In5.Cu")
		(net "PWRGD_P3V3_SSD15_R")
	)
	(segment
		(start 344.77198 -211.0232)
		(end 345.4654 -211.0232)
		(width 0.15494)
		(layer "In5.Cu")
		(net "PWRGD_P3V3_SSD15_R")
	)
	(segment
		(start 359.25887 -181.307486)
		(end 360.712512 -179.853844)
		(width 0.15494)
		(layer "In5.Cu")
		(net "PWRGD_P3V3_SSD15_R")
	)
	(segment
		(start 351.409 -204.47)
		(end 351.409 -204.089)
		(width 0.15494)
		(layer "In5.Cu")
		(net "PWRGD_P3V3_SSD15_R")
	)
	(segment
		(start 361.671362 -98.17608)
		(end 365.447072 -94.40037)
		(width 0.15494)
		(layer "In5.Cu")
		(net "PWRGD_P3V3_SSD15_R")
	)
	(segment
		(start 344.491056 -213.58987)
		(end 344.491056 -212.05444)
		(width 0.0889)
		(layer "In5.Cu")
		(net "PWRGD_P3V3_SSD15_R")
	)
	(segment
		(start 345.4654 -211.0232)
		(end 345.7194 -210.7692)
		(width 0.15494)
		(layer "In5.Cu")
		(net "PWRGD_P3V3_SSD15_R")
	)
	(segment
		(start 353.376992 -124.538232)
		(end 353.376992 -116.753386)
		(width 0.15494)
		(layer "In5.Cu")
		(net "PWRGD_P3V3_SSD15_R")
	)
	(segment
		(start 349.412814 -158.199328)
		(end 349.443548 -158.168594)
		(width 0.15494)
		(layer "In5.Cu")
		(net "PWRGD_P3V3_SSD15_R")
	)
	(segment
		(start 365.447072 -94.40037)
		(end 365.966502 -94.9198)
		(width 0.15494)
		(layer "In15.Cu")
		(net "PWRGD_P3V3_SSD15_R")
	)
	(segment
		(start 403.659594 -85.13318)
		(end 405.751284 -85.13318)
		(width 0.15494)
		(layer "In15.Cu")
		(net "PWRGD_P3V3_SSD15_R")
	)
	(segment
		(start 391.3632 -91.4654)
		(end 394.0048 -88.8238)
		(width 0.15494)
		(layer "In15.Cu")
		(net "PWRGD_P3V3_SSD15_R")
	)
	(segment
		(start 405.751284 -85.13318)
		(end 406.632918 -86.014814)
		(width 0.15494)
		(layer "In15.Cu")
		(net "PWRGD_P3V3_SSD15_R")
	)
	(segment
		(start 406.632918 -86.014814)
		(end 415.782506 -86.014814)
		(width 0.15494)
		(layer "In15.Cu")
		(net "PWRGD_P3V3_SSD15_R")
	)
	(segment
		(start 378.408946 -94.9198)
		(end 381.863346 -91.4654)
		(width 0.15494)
		(layer "In15.Cu")
		(net "PWRGD_P3V3_SSD15_R")
	)
	(segment
		(start 394.0048 -88.8238)
		(end 399.968974 -88.8238)
		(width 0.15494)
		(layer "In15.Cu")
		(net "PWRGD_P3V3_SSD15_R")
	)
	(segment
		(start 399.968974 -88.8238)
		(end 403.659594 -85.13318)
		(width 0.15494)
		(layer "In15.Cu")
		(net "PWRGD_P3V3_SSD15_R")
	)
	(segment
		(start 365.966502 -94.9198)
		(end 378.408946 -94.9198)
		(width 0.15494)
		(layer "In15.Cu")
		(net "PWRGD_P3V3_SSD15_R")
	)
	(segment
		(start 381.863346 -91.4654)
		(end 391.3632 -91.4654)
		(width 0.15494)
		(layer "In15.Cu")
		(net "PWRGD_P3V3_SSD15_R")
	)
	(segment
		(start 415.782506 -86.014814)
		(end 416.56762 -85.2297)
		(width 0.15494)
		(layer "In15.Cu")
		(net "PWRGD_P3V3_SSD15_R")
	)
	(segment
		(start 45.738542 -43.941492)
		(end 46.389798 -43.941492)
		(width 0.254)
		(layer "F.Cu")
		(net "P12V_SSD1_VIN_P")
	)
	(segment
		(start 45.725334 -43.928284)
		(end 45.725334 -42.849038)
		(width 0.254)
		(layer "F.Cu")
		(net "P12V_SSD1_VIN_P")
	)
	(segment
		(start 47.297086 -43.73626)
		(end 48.095916 -44.53509)
		(width 0.254)
		(layer "F.Cu")
		(net "P12V_SSD1_VIN_P")
	)
	(segment
		(start 48.095916 -44.53509)
		(end 48.095916 -45.043852)
		(width 0.254)
		(layer "F.Cu")
		(net "P12V_SSD1_VIN_P")
	)
	(segment
		(start 46.389798 -43.941492)
		(end 46.59503 -43.73626)
		(width 0.254)
		(layer "F.Cu")
		(net "P12V_SSD1_VIN_P")
	)
	(segment
		(start 45.738542 -43.941492)
		(end 45.725334 -43.928284)
		(width 0.254)
		(layer "F.Cu")
		(net "P12V_SSD1_VIN_P")
	)
	(segment
		(start 46.59503 -43.73626)
		(end 47.297086 -43.73626)
		(width 0.254)
		(layer "F.Cu")
		(net "P12V_SSD1_VIN_P")
	)
	(via
		(at 46.59503 -43.73626)
		(size 0.508)
		(drill 0.254)
		(layers "F.Cu" "B.Cu")
		(net "P12V_SSD1_VIN_P")
	)
	(segment
		(start 46.074584 -44.741592)
		(end 46.447456 -45.114464)
		(width 0.254)
		(layer "F.Cu")
		(net "P12V_SSD1_VIN_N")
	)
	(segment
		(start 47.02683 -45.693838)
		(end 47.44593 -45.693838)
		(width 0.254)
		(layer "F.Cu")
		(net "P12V_SSD1_VIN_N")
	)
	(segment
		(start 44.722542 -44.741592)
		(end 45.738542 -44.741592)
		(width 0.254)
		(layer "F.Cu")
		(net "P12V_SSD1_VIN_N")
	)
	(segment
		(start 45.738542 -44.741592)
		(end 46.074584 -44.741592)
		(width 0.254)
		(layer "F.Cu")
		(net "P12V_SSD1_VIN_N")
	)
	(segment
		(start 46.447456 -45.114464)
		(end 47.02683 -45.693838)
		(width 0.254)
		(layer "F.Cu")
		(net "P12V_SSD1_VIN_N")
	)
	(via
		(at 46.447456 -45.114464)
		(size 0.508)
		(drill 0.254)
		(layers "F.Cu" "B.Cu")
		(net "P12V_SSD1_VIN_N")
	)
	(segment
		(start 50.246026 -47.193962)
		(end 50.246026 -48.076612)
		(width 0.13208)
		(layer "F.Cu")
		(net "SMB_SSD1_ADC_SDA")
	)
	(segment
		(start 51.17338 -48.93691)
		(end 51.843686 -48.93691)
		(width 0.13208)
		(layer "F.Cu")
		(net "SMB_SSD1_ADC_SDA")
	)
	(segment
		(start 50.93589 -48.69942)
		(end 51.17338 -48.93691)
		(width 0.13208)
		(layer "F.Cu")
		(net "SMB_SSD1_ADC_SDA")
	)
	(segment
		(start 50.93589 -48.30699)
		(end 50.93589 -48.69942)
		(width 0.13208)
		(layer "F.Cu")
		(net "SMB_SSD1_ADC_SDA")
	)
	(segment
		(start 50.476404 -48.30699)
		(end 50.93589 -48.30699)
		(width 0.13208)
		(layer "F.Cu")
		(net "SMB_SSD1_ADC_SDA")
	)
	(segment
		(start 50.246026 -48.076612)
		(end 50.476404 -48.30699)
		(width 0.13208)
		(layer "F.Cu")
		(net "SMB_SSD1_ADC_SDA")
	)
	(via
		(at 50.93589 -48.30699)
		(size 0.508)
		(drill 0.254)
		(layers "F.Cu" "B.Cu")
		(net "SMB_SSD1_ADC_SDA")
	)
	(segment
		(start 77.843634 -42.84091)
		(end 77.843634 -43.85691)
		(width 0.13208)
		(layer "F.Cu")
		(net "SSD2_ADC_A1")
	)
	(segment
		(start 76.245974 -44.712636)
		(end 77.1017 -43.85691)
		(width 0.13208)
		(layer "F.Cu")
		(net "SSD2_ADC_A1")
	)
	(segment
		(start 76.245974 -45.693838)
		(end 76.245974 -44.712636)
		(width 0.13208)
		(layer "F.Cu")
		(net "SSD2_ADC_A1")
	)
	(segment
		(start 77.1017 -43.85691)
		(end 77.843634 -43.85691)
		(width 0.13208)
		(layer "F.Cu")
		(net "SSD2_ADC_A1")
	)
	(via
		(at 77.1017 -43.85691)
		(size 0.508)
		(drill 0.254)
		(layers "F.Cu" "B.Cu")
		(net "SSD2_ADC_A1")
	)
	(segment
		(start 300.738286 -82.032856)
		(end 300.738286 -82.332068)
		(width 0.13208)
		(layer "F.Cu")
		(net "SMB_BMC_FRU_SDA")
	)
	(segment
		(start 299.799248 -81.093818)
		(end 300.738286 -82.032856)
		(width 0.13208)
		(layer "F.Cu")
		(net "SMB_BMC_FRU_SDA")
	)
	(segment
		(start 298.559474 -82.333592)
		(end 299.799248 -81.093818)
		(width 0.13208)
		(layer "F.Cu")
		(net "SMB_BMC_FRU_SDA")
	)
	(segment
		(start 297.614848 -82.333592)
		(end 298.559474 -82.333592)
		(width 0.13208)
		(layer "F.Cu")
		(net "SMB_BMC_FRU_SDA")
	)
	(via
		(at 299.799248 -81.093818)
		(size 0.762)
		(drill 0.381)
		(layers "F.Cu" "B.Cu")
		(net "SMB_BMC_FRU_SDA")
	)
	(segment
		(start 299.418756 -83.744562)
		(end 300.01337 -83.744562)
		(width 0.13208)
		(layer "F.Cu")
		(net "SMB_BMC_FRU_SCL")
	)
	(segment
		(start 300.973236 -83.744562)
		(end 301.050706 -83.667092)
		(width 0.13208)
		(layer "F.Cu")
		(net "SMB_BMC_FRU_SCL")
	)
	(segment
		(start 297.614848 -83.603592)
		(end 299.277786 -83.603592)
		(width 0.13208)
		(layer "F.Cu")
		(net "SMB_BMC_FRU_SCL")
	)
	(segment
		(start 301.050706 -83.667092)
		(end 301.977806 -83.667092)
		(width 0.13208)
		(layer "F.Cu")
		(net "SMB_BMC_FRU_SCL")
	)
	(segment
		(start 300.01337 -83.744562)
		(end 300.973236 -83.744562)
		(width 0.13208)
		(layer "F.Cu")
		(net "SMB_BMC_FRU_SCL")
	)
	(segment
		(start 299.277786 -83.603592)
		(end 299.418756 -83.744562)
		(width 0.13208)
		(layer "F.Cu")
		(net "SMB_BMC_FRU_SCL")
	)
	(via
		(at 300.01337 -83.744562)
		(size 0.762)
		(drill 0.381)
		(layers "F.Cu" "B.Cu")
		(net "SMB_BMC_FRU_SCL")
	)
	(segment
		(start 333.320136 -225.587052)
		(end 333.009494 -225.897694)
		(width 0.13208)
		(layer "F.Cu")
		(net "PWRGD_P1V25_PEX3_R")
	)
	(segment
		(start 334.09382 -225.587052)
		(end 333.320136 -225.587052)
		(width 0.13208)
		(layer "F.Cu")
		(net "PWRGD_P1V25_PEX3_R")
	)
	(via
		(at 466.00491 -308.162706)
		(size 0.508)
		(drill 0.254)
		(layers "F.Cu" "B.Cu")
		(net "PWRGD_P1V25_PEX3_R")
	)
	(via
		(at 354.804726 -243.511578)
		(size 0.508)
		(drill 0.254)
		(layers "F.Cu" "B.Cu")
		(net "PWRGD_P1V25_PEX3_R")
	)
	(via
		(at 333.009494 -225.897694)
		(size 0.508)
		(drill 0.254)
		(layers "F.Cu" "B.Cu")
		(net "PWRGD_P1V25_PEX3_R")
	)
	(segment
		(start 462.083658 -307.989478)
		(end 461.729328 -307.989478)
		(width 0.13208)
		(layer "B.Cu")
		(net "PWRGD_P1V25_PEX3_R")
	)
	(segment
		(start 462.256124 -308.161944)
		(end 462.083658 -307.989478)
		(width 0.13208)
		(layer "B.Cu")
		(net "PWRGD_P1V25_PEX3_R")
	)
	(segment
		(start 466.00491 -308.162706)
		(end 466.004148 -308.161944)
		(width 0.13208)
		(layer "B.Cu")
		(net "PWRGD_P1V25_PEX3_R")
	)
	(segment
		(start 466.004148 -308.161944)
		(end 462.256124 -308.161944)
		(width 0.13208)
		(layer "B.Cu")
		(net "PWRGD_P1V25_PEX3_R")
	)
	(segment
		(start 333.009494 -225.897694)
		(end 333.121 -226.0092)
		(width 0.15494)
		(layer "In7.Cu")
		(net "PWRGD_P1V25_PEX3_R")
	)
	(segment
		(start 337.371182 -243.2304)
		(end 341.465154 -243.2304)
		(width 0.15494)
		(layer "In7.Cu")
		(net "PWRGD_P1V25_PEX3_R")
	)
	(segment
		(start 333.121 -226.0092)
		(end 333.121 -235.281216)
		(width 0.15494)
		(layer "In7.Cu")
		(net "PWRGD_P1V25_PEX3_R")
	)
	(segment
		(start 334.53578 -237.689136)
		(end 336.237326 -239.390682)
		(width 0.15494)
		(layer "In7.Cu")
		(net "PWRGD_P1V25_PEX3_R")
	)
	(segment
		(start 336.237326 -242.096544)
		(end 337.371182 -243.2304)
		(width 0.15494)
		(layer "In7.Cu")
		(net "PWRGD_P1V25_PEX3_R")
	)
	(segment
		(start 336.237326 -239.390682)
		(end 336.237326 -242.096544)
		(width 0.15494)
		(layer "In7.Cu")
		(net "PWRGD_P1V25_PEX3_R")
	)
	(segment
		(start 341.465154 -243.2304)
		(end 341.746332 -243.511578)
		(width 0.15494)
		(layer "In7.Cu")
		(net "PWRGD_P1V25_PEX3_R")
	)
	(segment
		(start 334.53578 -236.695996)
		(end 334.53578 -237.689136)
		(width 0.15494)
		(layer "In7.Cu")
		(net "PWRGD_P1V25_PEX3_R")
	)
	(segment
		(start 333.121 -235.281216)
		(end 334.53578 -236.695996)
		(width 0.15494)
		(layer "In7.Cu")
		(net "PWRGD_P1V25_PEX3_R")
	)
	(segment
		(start 341.746332 -243.511578)
		(end 354.804726 -243.511578)
		(width 0.15494)
		(layer "In7.Cu")
		(net "PWRGD_P1V25_PEX3_R")
	)
	(segment
		(start 374.222264 -242.5446)
		(end 371.835172 -240.157508)
		(width 0.15494)
		(layer "In13.Cu")
		(net "PWRGD_P1V25_PEX3_R")
	)
	(segment
		(start 376.141996 -242.5446)
		(end 374.222264 -242.5446)
		(width 0.15494)
		(layer "In13.Cu")
		(net "PWRGD_P1V25_PEX3_R")
	)
	(segment
		(start 378.429012 -241.31905)
		(end 377.367546 -241.31905)
		(width 0.15494)
		(layer "In13.Cu")
		(net "PWRGD_P1V25_PEX3_R")
	)
	(segment
		(start 381.338582 -235.20654)
		(end 378.825506 -237.719616)
		(width 0.15494)
		(layer "In13.Cu")
		(net "PWRGD_P1V25_PEX3_R")
	)
	(segment
		(start 377.367546 -241.31905)
		(end 376.141996 -242.5446)
		(width 0.15494)
		(layer "In13.Cu")
		(net "PWRGD_P1V25_PEX3_R")
	)
	(segment
		(start 371.835172 -240.157508)
		(end 358.158796 -240.157508)
		(width 0.15494)
		(layer "In13.Cu")
		(net "PWRGD_P1V25_PEX3_R")
	)
	(segment
		(start 387.652514 -235.20654)
		(end 381.338582 -235.20654)
		(width 0.15494)
		(layer "In13.Cu")
		(net "PWRGD_P1V25_PEX3_R")
	)
	(segment
		(start 464.365594 -246.713248)
		(end 456.590146 -238.9378)
		(width 0.15494)
		(layer "In13.Cu")
		(net "PWRGD_P1V25_PEX3_R")
	)
	(segment
		(start 466.00491 -308.162706)
		(end 466.00491 -258.179062)
		(width 0.15494)
		(layer "In13.Cu")
		(net "PWRGD_P1V25_PEX3_R")
	)
	(segment
		(start 456.590146 -238.9378)
		(end 424.5356 -238.9378)
		(width 0.15494)
		(layer "In13.Cu")
		(net "PWRGD_P1V25_PEX3_R")
	)
	(segment
		(start 358.158796 -240.157508)
		(end 354.804726 -243.511578)
		(width 0.15494)
		(layer "In13.Cu")
		(net "PWRGD_P1V25_PEX3_R")
	)
	(segment
		(start 466.00491 -258.179062)
		(end 464.365594 -256.539746)
		(width 0.15494)
		(layer "In13.Cu")
		(net "PWRGD_P1V25_PEX3_R")
	)
	(segment
		(start 424.5356 -238.9378)
		(end 419.735 -234.1372)
		(width 0.15494)
		(layer "In13.Cu")
		(net "PWRGD_P1V25_PEX3_R")
	)
	(segment
		(start 378.825506 -237.719616)
		(end 378.825506 -240.922556)
		(width 0.15494)
		(layer "In13.Cu")
		(net "PWRGD_P1V25_PEX3_R")
	)
	(segment
		(start 464.365594 -256.539746)
		(end 464.365594 -246.713248)
		(width 0.15494)
		(layer "In13.Cu")
		(net "PWRGD_P1V25_PEX3_R")
	)
	(segment
		(start 378.825506 -240.922556)
		(end 378.429012 -241.31905)
		(width 0.15494)
		(layer "In13.Cu")
		(net "PWRGD_P1V25_PEX3_R")
	)
	(segment
		(start 419.735 -234.1372)
		(end 388.721854 -234.1372)
		(width 0.15494)
		(layer "In13.Cu")
		(net "PWRGD_P1V25_PEX3_R")
	)
	(segment
		(start 388.721854 -234.1372)
		(end 387.652514 -235.20654)
		(width 0.15494)
		(layer "In13.Cu")
		(net "PWRGD_P1V25_PEX3_R")
	)
	(segment
		(start 96.23425 -244.312948)
		(end 96.23425 -243.876068)
		(width 0.13208)
		(layer "F.Cu")
		(net "PEX_P1V8_ADC_A0")
	)
	(segment
		(start 95.946468 -244.025166)
		(end 96.23425 -244.312948)
		(width 0.13208)
		(layer "F.Cu")
		(net "PEX_P1V8_ADC_A0")
	)
	(segment
		(start 96.623124 -243.487194)
		(end 97.103438 -243.487194)
		(width 0.13208)
		(layer "F.Cu")
		(net "PEX_P1V8_ADC_A0")
	)
	(segment
		(start 95.878904 -243.792248)
		(end 95.946468 -243.859812)
		(width 0.13208)
		(layer "F.Cu")
		(net "PEX_P1V8_ADC_A0")
	)
	(segment
		(start 95.505778 -244.808248)
		(end 95.505778 -243.792248)
		(width 0.13208)
		(layer "F.Cu")
		(net "PEX_P1V8_ADC_A0")
	)
	(segment
		(start 95.946468 -243.859812)
		(end 95.946468 -244.025166)
		(width 0.13208)
		(layer "F.Cu")
		(net "PEX_P1V8_ADC_A0")
	)
	(segment
		(start 95.505778 -243.792248)
		(end 95.878904 -243.792248)
		(width 0.13208)
		(layer "F.Cu")
		(net "PEX_P1V8_ADC_A0")
	)
	(segment
		(start 96.23425 -243.876068)
		(end 96.623124 -243.487194)
		(width 0.13208)
		(layer "F.Cu")
		(net "PEX_P1V8_ADC_A0")
	)
	(via
		(at 96.23425 -244.312948)
		(size 0.508)
		(drill 0.254)
		(layers "F.Cu" "B.Cu")
		(net "PEX_P1V8_ADC_A0")
	)
	(segment
		(start 286.822642 -83.603592)
		(end 286.78505 -83.566)
		(width 0.13208)
		(layer "F.Cu")
		(net "BB_FRU_A2")
	)
	(segment
		(start 285.26105 -82.931)
		(end 284.62605 -83.566)
		(width 0.13208)
		(layer "F.Cu")
		(net "BB_FRU_A2")
	)
	(segment
		(start 286.78505 -83.143852)
		(end 286.572198 -82.931)
		(width 0.13208)
		(layer "F.Cu")
		(net "BB_FRU_A2")
	)
	(segment
		(start 289.197034 -83.603592)
		(end 286.822642 -83.603592)
		(width 0.13208)
		(layer "F.Cu")
		(net "BB_FRU_A2")
	)
	(segment
		(start 292.331648 -83.603592)
		(end 289.197034 -83.603592)
		(width 0.13208)
		(layer "F.Cu")
		(net "BB_FRU_A2")
	)
	(segment
		(start 286.572198 -82.931)
		(end 285.26105 -82.931)
		(width 0.13208)
		(layer "F.Cu")
		(net "BB_FRU_A2")
	)
	(segment
		(start 286.78505 -83.566)
		(end 286.78505 -83.143852)
		(width 0.13208)
		(layer "F.Cu")
		(net "BB_FRU_A2")
	)
	(via
		(at 289.197034 -83.603592)
		(size 0.762)
		(drill 0.381)
		(layers "F.Cu" "B.Cu")
		(net "BB_FRU_A2")
	)
	(segment
		(start 101.27488 -244.939566)
		(end 100.902008 -244.566694)
		(width 0.254)
		(layer "F.Cu")
		(net "P12V_PEX_P1V8_VIN_N")
	)
	(segment
		(start 100.902008 -244.566694)
		(end 100.322634 -243.98732)
		(width 0.254)
		(layer "F.Cu")
		(net "P12V_PEX_P1V8_VIN_N")
	)
	(segment
		(start 100.322634 -243.98732)
		(end 99.903534 -243.98732)
		(width 0.254)
		(layer "F.Cu")
		(net "P12V_PEX_P1V8_VIN_N")
	)
	(segment
		(start 101.610922 -244.939566)
		(end 101.27488 -244.939566)
		(width 0.254)
		(layer "F.Cu")
		(net "P12V_PEX_P1V8_VIN_N")
	)
	(segment
		(start 102.626922 -244.939566)
		(end 101.610922 -244.939566)
		(width 0.254)
		(layer "F.Cu")
		(net "P12V_PEX_P1V8_VIN_N")
	)
	(via
		(at 100.902008 -244.566694)
		(size 0.508)
		(drill 0.254)
		(layers "F.Cu" "B.Cu")
		(net "P12V_PEX_P1V8_VIN_N")
	)
	(segment
		(start 284.62605 -86.613746)
		(end 284.62605 -86.106)
		(width 0.13208)
		(layer "F.Cu")
		(net "BB_FRU_A0")
	)
	(segment
		(start 287.804098 -86.143592)
		(end 290.979098 -86.143592)
		(width 0.13208)
		(layer "F.Cu")
		(net "BB_FRU_A0")
	)
	(segment
		(start 287.766506 -86.106)
		(end 287.804098 -86.143592)
		(width 0.13208)
		(layer "F.Cu")
		(net "BB_FRU_A0")
	)
	(segment
		(start 286.78505 -86.106)
		(end 287.766506 -86.106)
		(width 0.13208)
		(layer "F.Cu")
		(net "BB_FRU_A0")
	)
	(segment
		(start 284.753304 -86.741)
		(end 284.62605 -86.613746)
		(width 0.13208)
		(layer "F.Cu")
		(net "BB_FRU_A0")
	)
	(segment
		(start 286.78505 -86.614)
		(end 286.65805 -86.741)
		(width 0.13208)
		(layer "F.Cu")
		(net "BB_FRU_A0")
	)
	(segment
		(start 290.979098 -86.143592)
		(end 292.331648 -86.143592)
		(width 0.13208)
		(layer "F.Cu")
		(net "BB_FRU_A0")
	)
	(segment
		(start 286.78505 -86.106)
		(end 286.78505 -86.614)
		(width 0.13208)
		(layer "F.Cu")
		(net "BB_FRU_A0")
	)
	(segment
		(start 286.65805 -86.741)
		(end 284.753304 -86.741)
		(width 0.13208)
		(layer "F.Cu")
		(net "BB_FRU_A0")
	)
	(via
		(at 290.979098 -86.143592)
		(size 0.508)
		(drill 0.254)
		(layers "F.Cu" "B.Cu")
		(net "BB_FRU_A0")
	)
	(segment
		(start 95.505778 -242.776248)
		(end 95.716852 -242.987322)
		(width 0.13208)
		(layer "F.Cu")
		(net "PEX_P1V8_ADC_ALERT_N")
	)
	(segment
		(start 95.716852 -242.987322)
		(end 96.32823 -242.987322)
		(width 0.13208)
		(layer "F.Cu")
		(net "PEX_P1V8_ADC_ALERT_N")
	)
	(segment
		(start 96.32823 -242.987322)
		(end 97.103438 -242.987322)
		(width 0.13208)
		(layer "F.Cu")
		(net "PEX_P1V8_ADC_ALERT_N")
	)
	(via
		(at 96.32823 -242.987322)
		(size 0.508)
		(drill 0.254)
		(layers "F.Cu" "B.Cu")
		(net "PEX_P1V8_ADC_ALERT_N")
	)
	(segment
		(start 91.896184 -238.942372)
		(end 92.084652 -238.753904)
		(width 0.13208)
		(layer "F.Cu")
		(net "PEX_P1V8_ADC_A1")
	)
	(segment
		(start 91.896184 -240.749836)
		(end 91.896184 -238.942372)
		(width 0.13208)
		(layer "F.Cu")
		(net "PEX_P1V8_ADC_A1")
	)
	(segment
		(start 92.084652 -238.753904)
		(end 94.705678 -238.753904)
		(width 0.13208)
		(layer "F.Cu")
		(net "PEX_P1V8_ADC_A1")
	)
	(segment
		(start 93.03639 -246.5959)
		(end 93.03639 -241.890042)
		(width 0.13208)
		(layer "F.Cu")
		(net "PEX_P1V8_ADC_A1")
	)
	(segment
		(start 95.505778 -246.840248)
		(end 95.505778 -245.824248)
		(width 0.13208)
		(layer "F.Cu")
		(net "PEX_P1V8_ADC_A1")
	)
	(segment
		(start 95.505778 -245.824248)
		(end 96.247712 -245.824248)
		(width 0.13208)
		(layer "F.Cu")
		(net "PEX_P1V8_ADC_A1")
	)
	(segment
		(start 93.860874 -247.420384)
		(end 93.03639 -246.5959)
		(width 0.13208)
		(layer "F.Cu")
		(net "PEX_P1V8_ADC_A1")
	)
	(segment
		(start 95.505778 -247.293384)
		(end 95.378778 -247.420384)
		(width 0.13208)
		(layer "F.Cu")
		(net "PEX_P1V8_ADC_A1")
	)
	(segment
		(start 97.103438 -244.968522)
		(end 97.103438 -243.98732)
		(width 0.13208)
		(layer "F.Cu")
		(net "PEX_P1V8_ADC_A1")
	)
	(segment
		(start 95.378778 -247.420384)
		(end 93.860874 -247.420384)
		(width 0.13208)
		(layer "F.Cu")
		(net "PEX_P1V8_ADC_A1")
	)
	(segment
		(start 95.505778 -246.840248)
		(end 95.505778 -247.293384)
		(width 0.13208)
		(layer "F.Cu")
		(net "PEX_P1V8_ADC_A1")
	)
	(segment
		(start 96.247712 -245.824248)
		(end 97.103438 -244.968522)
		(width 0.13208)
		(layer "F.Cu")
		(net "PEX_P1V8_ADC_A1")
	)
	(segment
		(start 93.03639 -241.890042)
		(end 91.896184 -240.749836)
		(width 0.13208)
		(layer "F.Cu")
		(net "PEX_P1V8_ADC_A1")
	)
	(via
		(at 96.247712 -245.824248)
		(size 0.508)
		(drill 0.254)
		(layers "F.Cu" "B.Cu")
		(net "PEX_P1V8_ADC_A1")
	)
	(segment
		(start 96.501712 -241.242596)
		(end 96.501712 -241.917474)
		(width 0.13208)
		(layer "F.Cu")
		(net "SMB_PEX_P1V8_ADC_SDA")
	)
	(segment
		(start 96.755966 -242.487196)
		(end 97.103438 -242.487196)
		(width 0.13208)
		(layer "F.Cu")
		(net "SMB_PEX_P1V8_ADC_SDA")
	)
	(segment
		(start 96.501712 -241.917474)
		(end 96.618044 -242.033806)
		(width 0.13208)
		(layer "F.Cu")
		(net "SMB_PEX_P1V8_ADC_SDA")
	)
	(segment
		(start 96.003364 -240.744248)
		(end 96.501712 -241.242596)
		(width 0.13208)
		(layer "F.Cu")
		(net "SMB_PEX_P1V8_ADC_SDA")
	)
	(segment
		(start 95.505778 -240.744248)
		(end 96.003364 -240.744248)
		(width 0.13208)
		(layer "F.Cu")
		(net "SMB_PEX_P1V8_ADC_SDA")
	)
	(segment
		(start 96.618044 -242.033806)
		(end 96.618044 -242.349274)
		(width 0.13208)
		(layer "F.Cu")
		(net "SMB_PEX_P1V8_ADC_SDA")
	)
	(segment
		(start 96.618044 -242.349274)
		(end 96.755966 -242.487196)
		(width 0.13208)
		(layer "F.Cu")
		(net "SMB_PEX_P1V8_ADC_SDA")
	)
	(via
		(at 96.501712 -241.242596)
		(size 0.508)
		(drill 0.254)
		(layers "F.Cu" "B.Cu")
		(net "SMB_PEX_P1V8_ADC_SDA")
	)
	(segment
		(start 459.218284 -274.8915)
		(end 459.827884 -274.8915)
		(width 0.4572)
		(layer "F.Cu")
		(net "P1V25_PEX3_R")
	)
	(via
		(at 459.827884 -274.8915)
		(size 0.508)
		(drill 0.254)
		(layers "F.Cu" "B.Cu")
		(net "P1V25_PEX3_R")
	)
	(via
		(at 454.131934 -284.764988)
		(size 0.508)
		(drill 0.254)
		(layers "F.Cu" "B.Cu")
		(net "P1V25_PEX3_R")
	)
	(via
		(at 452.288148 -281.536902)
		(size 0.508)
		(drill 0.254)
		(layers "F.Cu" "B.Cu")
		(net "P1V25_PEX3_R")
	)
	(via
		(at 456.769724 -283.105606)
		(size 0.508)
		(drill 0.254)
		(layers "F.Cu" "B.Cu")
		(net "P1V25_PEX3_R")
	)
	(via
		(at 458.191108 -285.579312)
		(size 0.508)
		(drill 0.254)
		(layers "F.Cu" "B.Cu")
		(net "P1V25_PEX3_R")
	)
	(via
		(at 452.263764 -282.203652)
		(size 0.508)
		(drill 0.254)
		(layers "F.Cu" "B.Cu")
		(net "P1V25_PEX3_R")
	)
	(via
		(at 457.430124 -283.105606)
		(size 0.508)
		(drill 0.254)
		(layers "F.Cu" "B.Cu")
		(net "P1V25_PEX3_R")
	)
	(via
		(at 455.478134 -287.228788)
		(size 0.508)
		(drill 0.254)
		(layers "F.Cu" "B.Cu")
		(net "P1V25_PEX3_R")
	)
	(via
		(at 459.62189 -290.807648)
		(size 0.508)
		(drill 0.254)
		(layers "F.Cu" "B.Cu")
		(net "P1V25_PEX3_R")
	)
	(via
		(at 455.478134 -284.764988)
		(size 0.508)
		(drill 0.254)
		(layers "F.Cu" "B.Cu")
		(net "P1V25_PEX3_R")
	)
	(via
		(at 451.627748 -281.536902)
		(size 0.508)
		(drill 0.254)
		(layers "F.Cu" "B.Cu")
		(net "P1V25_PEX3_R")
	)
	(via
		(at 458.351128 -287.872424)
		(size 0.508)
		(drill 0.254)
		(layers "F.Cu" "B.Cu")
		(net "P1V25_PEX3_R")
	)
	(via
		(at 450.967348 -281.536902)
		(size 0.508)
		(drill 0.254)
		(layers "F.Cu" "B.Cu")
		(net "P1V25_PEX3_R")
	)
	(via
		(at 450.942964 -282.203652)
		(size 0.508)
		(drill 0.254)
		(layers "F.Cu" "B.Cu")
		(net "P1V25_PEX3_R")
	)
	(via
		(at 452.948548 -281.536902)
		(size 0.508)
		(drill 0.254)
		(layers "F.Cu" "B.Cu")
		(net "P1V25_PEX3_R")
	)
	(via
		(at 458.876908 -285.579312)
		(size 0.508)
		(drill 0.254)
		(layers "F.Cu" "B.Cu")
		(net "P1V25_PEX3_R")
	)
	(via
		(at 454.792334 -287.228788)
		(size 0.508)
		(drill 0.254)
		(layers "F.Cu" "B.Cu")
		(net "P1V25_PEX3_R")
	)
	(via
		(at 458.98689 -290.807648)
		(size 0.508)
		(drill 0.254)
		(layers "F.Cu" "B.Cu")
		(net "P1V25_PEX3_R")
	)
	(via
		(at 453.471534 -284.764988)
		(size 0.508)
		(drill 0.254)
		(layers "F.Cu" "B.Cu")
		(net "P1V25_PEX3_R")
	)
	(via
		(at 458.776324 -283.105606)
		(size 0.508)
		(drill 0.254)
		(layers "F.Cu" "B.Cu")
		(net "P1V25_PEX3_R")
	)
	(via
		(at 458.090524 -283.105606)
		(size 0.508)
		(drill 0.254)
		(layers "F.Cu" "B.Cu")
		(net "P1V25_PEX3_R")
	)
	(via
		(at 454.792334 -284.764988)
		(size 0.508)
		(drill 0.254)
		(layers "F.Cu" "B.Cu")
		(net "P1V25_PEX3_R")
	)
	(via
		(at 452.577708 -291.546788)
		(size 0.508)
		(drill 0.254)
		(layers "F.Cu" "B.Cu")
		(net "P1V25_PEX3_R")
	)
	(via
		(at 453.212708 -291.546788)
		(size 0.508)
		(drill 0.254)
		(layers "F.Cu" "B.Cu")
		(net "P1V25_PEX3_R")
	)
	(via
		(at 459.62189 -288.775648)
		(size 0.508)
		(drill 0.254)
		(layers "F.Cu" "B.Cu")
		(net "P1V25_PEX3_R")
	)
	(via
		(at 457.530708 -285.579312)
		(size 0.508)
		(drill 0.254)
		(layers "F.Cu" "B.Cu")
		(net "P1V25_PEX3_R")
	)
	(via
		(at 456.43546 -288.179256)
		(size 0.6604)
		(drill 0.3302)
		(layers "F.Cu" "B.Cu")
		(net "P1V25_PEX3_R")
	)
	(via
		(at 456.672696 -291.67582)
		(size 0.6604)
		(drill 0.3302)
		(layers "F.Cu" "B.Cu")
		(net "P1V25_PEX3_R")
	)
	(via
		(at 451.603364 -282.203652)
		(size 0.508)
		(drill 0.254)
		(layers "F.Cu" "B.Cu")
		(net "P1V25_PEX3_R")
	)
	(via
		(at 454.131934 -287.228788)
		(size 0.508)
		(drill 0.254)
		(layers "F.Cu" "B.Cu")
		(net "P1V25_PEX3_R")
	)
	(via
		(at 459.036928 -287.872424)
		(size 0.508)
		(drill 0.254)
		(layers "F.Cu" "B.Cu")
		(net "P1V25_PEX3_R")
	)
	(via
		(at 458.98689 -288.775648)
		(size 0.508)
		(drill 0.254)
		(layers "F.Cu" "B.Cu")
		(net "P1V25_PEX3_R")
	)
	(via
		(at 453.471534 -287.228788)
		(size 0.508)
		(drill 0.254)
		(layers "F.Cu" "B.Cu")
		(net "P1V25_PEX3_R")
	)
	(via
		(at 452.924164 -282.203652)
		(size 0.508)
		(drill 0.254)
		(layers "F.Cu" "B.Cu")
		(net "P1V25_PEX3_R")
	)
	(via
		(at 452.595996 -289.514788)
		(size 0.508)
		(drill 0.254)
		(layers "F.Cu" "B.Cu")
		(net "P1V25_PEX3_R")
	)
	(via
		(at 456.870308 -285.579312)
		(size 0.508)
		(drill 0.254)
		(layers "F.Cu" "B.Cu")
		(net "P1V25_PEX3_R")
	)
	(via
		(at 453.230996 -289.514788)
		(size 0.508)
		(drill 0.254)
		(layers "F.Cu" "B.Cu")
		(net "P1V25_PEX3_R")
	)
	(segment
		(start 101.62413 -245.752874)
		(end 101.610922 -245.739666)
		(width 0.254)
		(layer "F.Cu")
		(net "P12V_PEX_P1V8_VIN_P")
	)
	(segment
		(start 100.959666 -245.739666)
		(end 101.610922 -245.739666)
		(width 0.254)
		(layer "F.Cu")
		(net "P12V_PEX_P1V8_VIN_P")
	)
	(segment
		(start 99.934522 -244.637306)
		(end 100.217224 -244.920008)
		(width 0.254)
		(layer "F.Cu")
		(net "P12V_PEX_P1V8_VIN_P")
	)
	(segment
		(start 99.253548 -244.637306)
		(end 99.934522 -244.637306)
		(width 0.254)
		(layer "F.Cu")
		(net "P12V_PEX_P1V8_VIN_P")
	)
	(segment
		(start 100.217224 -245.407688)
		(end 100.754434 -245.944898)
		(width 0.254)
		(layer "F.Cu")
		(net "P12V_PEX_P1V8_VIN_P")
	)
	(segment
		(start 101.62413 -246.83212)
		(end 101.62413 -245.752874)
		(width 0.254)
		(layer "F.Cu")
		(net "P12V_PEX_P1V8_VIN_P")
	)
	(segment
		(start 100.217224 -244.920008)
		(end 100.217224 -245.407688)
		(width 0.254)
		(layer "F.Cu")
		(net "P12V_PEX_P1V8_VIN_P")
	)
	(segment
		(start 100.754434 -245.944898)
		(end 100.959666 -245.739666)
		(width 0.254)
		(layer "F.Cu")
		(net "P12V_PEX_P1V8_VIN_P")
	)
	(via
		(at 100.754434 -245.944898)
		(size 0.508)
		(drill 0.254)
		(layers "F.Cu" "B.Cu")
		(net "P12V_PEX_P1V8_VIN_P")
	)
	(segment
		(start 292.331648 -84.873592)
		(end 289.537648 -84.873592)
		(width 0.13208)
		(layer "F.Cu")
		(net "BB_FRU_A1")
	)
	(segment
		(start 289.00882 -85.40242)
		(end 288.479992 -84.873592)
		(width 0.13208)
		(layer "F.Cu")
		(net "BB_FRU_A1")
	)
	(segment
		(start 285.26105 -84.201)
		(end 284.62605 -84.836)
		(width 0.13208)
		(layer "F.Cu")
		(net "BB_FRU_A1")
	)
	(segment
		(start 289.537648 -84.873592)
		(end 289.00882 -85.40242)
		(width 0.13208)
		(layer "F.Cu")
		(net "BB_FRU_A1")
	)
	(segment
		(start 286.822642 -84.873592)
		(end 286.78505 -84.836)
		(width 0.13208)
		(layer "F.Cu")
		(net "BB_FRU_A1")
	)
	(segment
		(start 286.569912 -84.201)
		(end 285.26105 -84.201)
		(width 0.13208)
		(layer "F.Cu")
		(net "BB_FRU_A1")
	)
	(segment
		(start 286.78505 -84.836)
		(end 286.78505 -84.416138)
		(width 0.13208)
		(layer "F.Cu")
		(net "BB_FRU_A1")
	)
	(segment
		(start 286.78505 -84.416138)
		(end 286.569912 -84.201)
		(width 0.13208)
		(layer "F.Cu")
		(net "BB_FRU_A1")
	)
	(segment
		(start 288.479992 -84.873592)
		(end 286.822642 -84.873592)
		(width 0.13208)
		(layer "F.Cu")
		(net "BB_FRU_A1")
	)
	(via
		(at 289.00882 -85.40242)
		(size 0.508)
		(drill 0.254)
		(layers "F.Cu" "B.Cu")
		(net "BB_FRU_A1")
	)
	(segment
		(start 231.444546 -273.471386)
		(end 231.444546 -274.487386)
		(width 0.13208)
		(layer "F.Cu")
		(net "PEX1_P1V25_ADC_A1")
	)
	(segment
		(start 230.111554 -277.041864)
		(end 230.332534 -276.820884)
		(width 0.13208)
		(layer "F.Cu")
		(net "PEX1_P1V25_ADC_A1")
	)
	(segment
		(start 231.420162 -274.487386)
		(end 230.702612 -275.204936)
		(width 0.13208)
		(layer "F.Cu")
		(net "PEX1_P1V25_ADC_A1")
	)
	(segment
		(start 229.846886 -277.041864)
		(end 230.111554 -277.041864)
		(width 0.13208)
		(layer "F.Cu")
		(net "PEX1_P1V25_ADC_A1")
	)
	(segment
		(start 230.332534 -275.575014)
		(end 230.702612 -275.204936)
		(width 0.13208)
		(layer "F.Cu")
		(net "PEX1_P1V25_ADC_A1")
	)
	(segment
		(start 230.332534 -276.820884)
		(end 230.332534 -275.575014)
		(width 0.13208)
		(layer "F.Cu")
		(net "PEX1_P1V25_ADC_A1")
	)
	(segment
		(start 231.444546 -274.487386)
		(end 231.420162 -274.487386)
		(width 0.13208)
		(layer "F.Cu")
		(net "PEX1_P1V25_ADC_A1")
	)
	(via
		(at 230.702612 -275.204936)
		(size 0.508)
		(drill 0.254)
		(layers "F.Cu" "B.Cu")
		(net "PEX1_P1V25_ADC_A1")
	)
	(segment
		(start 461.456024 -279.69083)
		(end 461.08112 -279.69083)
		(width 0.13208)
		(layer "F.Cu")
		(net "SMB_PEX3_P1V25_ADC_SDA")
	)
	(segment
		(start 460.82712 -278.665432)
		(end 460.467964 -278.665432)
		(width 0.13208)
		(layer "F.Cu")
		(net "SMB_PEX3_P1V25_ADC_SDA")
	)
	(segment
		(start 460.95412 -279.56383)
		(end 460.95412 -278.792432)
		(width 0.13208)
		(layer "F.Cu")
		(net "SMB_PEX3_P1V25_ADC_SDA")
	)
	(segment
		(start 461.08112 -279.69083)
		(end 460.95412 -279.56383)
		(width 0.13208)
		(layer "F.Cu")
		(net "SMB_PEX3_P1V25_ADC_SDA")
	)
	(segment
		(start 460.95412 -278.792432)
		(end 460.82712 -278.665432)
		(width 0.13208)
		(layer "F.Cu")
		(net "SMB_PEX3_P1V25_ADC_SDA")
	)
	(segment
		(start 462.065624 -279.69083)
		(end 461.456024 -279.69083)
		(width 0.13208)
		(layer "F.Cu")
		(net "SMB_PEX3_P1V25_ADC_SDA")
	)
	(via
		(at 461.456024 -279.69083)
		(size 0.508)
		(drill 0.254)
		(layers "F.Cu" "B.Cu")
		(net "SMB_PEX3_P1V25_ADC_SDA")
	)
	(segment
		(start 2.47523 -64.102234)
		(end 2.47523 -64.540384)
		(width 0.381)
		(layer "F.Cu")
		(net "P12V_SSD0_R")
	)
	(segment
		(start 20.525486 -42.849038)
		(end 21.274024 -42.849038)
		(width 0.381)
		(layer "F.Cu")
		(net "P12V_SSD0_R")
	)
	(segment
		(start 2.47523 -64.540384)
		(end 2.27838 -64.737234)
		(width 0.381)
		(layer "F.Cu")
		(net "P12V_SSD0_R")
	)
	(via
		(at 17.718024 -68.586604)
		(size 0.508)
		(drill 0.254)
		(layers "F.Cu" "B.Cu")
		(net "P12V_SSD0_R")
	)
	(via
		(at 17.592294 -53.77053)
		(size 0.508)
		(drill 0.254)
		(layers "F.Cu" "B.Cu")
		(net "P12V_SSD0_R")
	)
	(via
		(at 17.718024 -67.951604)
		(size 0.508)
		(drill 0.254)
		(layers "F.Cu" "B.Cu")
		(net "P12V_SSD0_R")
	)
	(via
		(at 18.303494 -53.00853)
		(size 0.508)
		(drill 0.254)
		(layers "F.Cu" "B.Cu")
		(net "P12V_SSD0_R")
	)
	(via
		(at 13.902182 -54.096412)
		(size 0.508)
		(drill 0.254)
		(layers "F.Cu" "B.Cu")
		(net "P12V_SSD0_R")
	)
	(via
		(at 17.006824 -67.951604)
		(size 0.508)
		(drill 0.254)
		(layers "F.Cu" "B.Cu")
		(net "P12V_SSD0_R")
	)
	(via
		(at 18.353024 -68.586604)
		(size 0.508)
		(drill 0.254)
		(layers "F.Cu" "B.Cu")
		(net "P12V_SSD0_R")
	)
	(via
		(at 2.27838 -64.737234)
		(size 0.508)
		(drill 0.254)
		(layers "F.Cu" "B.Cu")
		(net "P12V_SSD0_R")
	)
	(via
		(at 19.249644 -46.066964)
		(size 0.508)
		(drill 0.254)
		(layers "F.Cu" "B.Cu")
		(net "P12V_SSD0_R")
	)
	(via
		(at 21.274024 -42.849038)
		(size 0.508)
		(drill 0.254)
		(layers "F.Cu" "B.Cu")
		(net "P12V_SSD0_R")
	)
	(via
		(at 19.512026 -53.685186)
		(size 0.508)
		(drill 0.254)
		(layers "F.Cu" "B.Cu")
		(net "P12V_SSD0_R")
	)
	(via
		(at 17.592294 -53.00853)
		(size 0.508)
		(drill 0.254)
		(layers "F.Cu" "B.Cu")
		(net "P12V_SSD0_R")
	)
	(via
		(at 18.227294 -53.77053)
		(size 0.508)
		(drill 0.254)
		(layers "F.Cu" "B.Cu")
		(net "P12V_SSD0_R")
	)
	(via
		(at 20.452588 -54.770528)
		(size 0.508)
		(drill 0.254)
		(layers "F.Cu" "B.Cu")
		(net "P12V_SSD0_R")
	)
	(via
		(at 14.747748 -67.10172)
		(size 0.508)
		(drill 0.254)
		(layers "F.Cu" "B.Cu")
		(net "P12V_SSD0_R")
	)
	(via
		(at 13.902182 -54.731412)
		(size 0.508)
		(drill 0.254)
		(layers "F.Cu" "B.Cu")
		(net "P12V_SSD0_R")
	)
	(via
		(at 20.452588 -54.135528)
		(size 0.508)
		(drill 0.254)
		(layers "F.Cu" "B.Cu")
		(net "P12V_SSD0_R")
	)
	(via
		(at 16.558006 -54.156102)
		(size 0.508)
		(drill 0.254)
		(layers "F.Cu" "B.Cu")
		(net "P12V_SSD0_R")
	)
	(via
		(at 16.558006 -54.791102)
		(size 0.508)
		(drill 0.254)
		(layers "F.Cu" "B.Cu")
		(net "P12V_SSD0_R")
	)
	(via
		(at 16.558006 -53.521102)
		(size 0.508)
		(drill 0.254)
		(layers "F.Cu" "B.Cu")
		(net "P12V_SSD0_R")
	)
	(via
		(at 19.959574 -45.976286)
		(size 0.508)
		(drill 0.254)
		(layers "F.Cu" "B.Cu")
		(net "P12V_SSD0_R")
	)
	(via
		(at 16.558006 -52.886102)
		(size 0.508)
		(drill 0.254)
		(layers "F.Cu" "B.Cu")
		(net "P12V_SSD0_R")
	)
	(via
		(at 18.353024 -67.951604)
		(size 0.508)
		(drill 0.254)
		(layers "F.Cu" "B.Cu")
		(net "P12V_SSD0_R")
	)
	(via
		(at 15.382748 -67.10172)
		(size 0.508)
		(drill 0.254)
		(layers "F.Cu" "B.Cu")
		(net "P12V_SSD0_R")
	)
	(via
		(at 18.486882 -46.792134)
		(size 0.508)
		(drill 0.254)
		(layers "F.Cu" "B.Cu")
		(net "P12V_SSD0_R")
	)
	(via
		(at 13.902182 -52.826412)
		(size 0.508)
		(drill 0.254)
		(layers "F.Cu" "B.Cu")
		(net "P12V_SSD0_R")
	)
	(via
		(at 13.902182 -53.461412)
		(size 0.508)
		(drill 0.254)
		(layers "F.Cu" "B.Cu")
		(net "P12V_SSD0_R")
	)
	(via
		(at 19.512026 -54.320186)
		(size 0.508)
		(drill 0.254)
		(layers "F.Cu" "B.Cu")
		(net "P12V_SSD0_R")
	)
	(via
		(at 19.1516 -46.739048)
		(size 0.508)
		(drill 0.254)
		(layers "F.Cu" "B.Cu")
		(net "P12V_SSD0_R")
	)
	(via
		(at 18.43405 -46.082204)
		(size 0.508)
		(drill 0.254)
		(layers "F.Cu" "B.Cu")
		(net "P12V_SSD0_R")
	)
	(via
		(at 17.006824 -68.586604)
		(size 0.508)
		(drill 0.254)
		(layers "F.Cu" "B.Cu")
		(net "P12V_SSD0_R")
	)
	(segment
		(start 7.918958 -65.908682)
		(end 9.111996 -67.10172)
		(width 0.508)
		(layer "B.Cu")
		(net "P12V_SSD0_R")
	)
	(segment
		(start 2.27838 -64.737234)
		(end 3.29311 -64.737234)
		(width 0.508)
		(layer "B.Cu")
		(net "P12V_SSD0_R")
	)
	(segment
		(start 6.960362 -65.907412)
		(end 6.961632 -65.908682)
		(width 0.508)
		(layer "B.Cu")
		(net "P12V_SSD0_R")
	)
	(segment
		(start 6.961632 -65.908682)
		(end 7.918958 -65.908682)
		(width 0.508)
		(layer "B.Cu")
		(net "P12V_SSD0_R")
	)
	(segment
		(start 3.29311 -64.737234)
		(end 4.464558 -65.908682)
		(width 0.508)
		(layer "B.Cu")
		(net "P12V_SSD0_R")
	)
	(segment
		(start 6.411468 -65.908682)
		(end 6.412738 -65.907412)
		(width 0.508)
		(layer "B.Cu")
		(net "P12V_SSD0_R")
	)
	(segment
		(start 9.111996 -67.10172)
		(end 14.747748 -67.10172)
		(width 0.508)
		(layer "B.Cu")
		(net "P12V_SSD0_R")
	)
	(segment
		(start 4.464558 -65.908682)
		(end 6.411468 -65.908682)
		(width 0.508)
		(layer "B.Cu")
		(net "P12V_SSD0_R")
	)
	(segment
		(start 6.412738 -65.907412)
		(end 6.960362 -65.907412)
		(width 0.508)
		(layer "B.Cu")
		(net "P12V_SSD0_R")
	)
	(segment
		(start 245.447058 -279.191974)
		(end 245.447058 -280.49982)
		(width 0.13208)
		(layer "F.Cu")
		(net "SMB_PEX2_P1V25_ADC_SCL")
	)
	(segment
		(start 245.44782 -280.500582)
		(end 246.270018 -280.500582)
		(width 0.13208)
		(layer "F.Cu")
		(net "SMB_PEX2_P1V25_ADC_SCL")
	)
	(segment
		(start 246.270018 -280.500582)
		(end 246.352822 -280.583386)
		(width 0.13208)
		(layer "F.Cu")
		(net "SMB_PEX2_P1V25_ADC_SCL")
	)
	(segment
		(start 245.447058 -280.49982)
		(end 245.44782 -280.500582)
		(width 0.13208)
		(layer "F.Cu")
		(net "SMB_PEX2_P1V25_ADC_SCL")
	)
	(segment
		(start 246.352822 -280.583386)
		(end 247.694704 -280.583386)
		(width 0.13208)
		(layer "F.Cu")
		(net "SMB_PEX2_P1V25_ADC_SCL")
	)
	(via
		(at 245.44782 -280.500582)
		(size 0.508)
		(drill 0.254)
		(layers "F.Cu" "B.Cu")
		(net "SMB_PEX2_P1V25_ADC_SCL")
	)
	(segment
		(start 230.102664 -280.583386)
		(end 231.444546 -280.583386)
		(width 0.13208)
		(layer "F.Cu")
		(net "SMB_PEX1_P1V25_ADC_SCL")
	)
	(segment
		(start 230.01986 -280.500582)
		(end 230.102664 -280.583386)
		(width 0.13208)
		(layer "F.Cu")
		(net "SMB_PEX1_P1V25_ADC_SCL")
	)
	(segment
		(start 229.1969 -280.49982)
		(end 229.197662 -280.500582)
		(width 0.13208)
		(layer "F.Cu")
		(net "SMB_PEX1_P1V25_ADC_SCL")
	)
	(segment
		(start 229.1969 -279.191974)
		(end 229.1969 -280.49982)
		(width 0.13208)
		(layer "F.Cu")
		(net "SMB_PEX1_P1V25_ADC_SCL")
	)
	(segment
		(start 229.197662 -280.500582)
		(end 230.01986 -280.500582)
		(width 0.13208)
		(layer "F.Cu")
		(net "SMB_PEX1_P1V25_ADC_SCL")
	)
	(via
		(at 229.197662 -280.500582)
		(size 0.508)
		(drill 0.254)
		(layers "F.Cu" "B.Cu")
		(net "SMB_PEX1_P1V25_ADC_SCL")
	)
	(via
		(at 12.017756 -272.345912)
		(size 0.508)
		(drill 0.254)
		(layers "F.Cu" "B.Cu")
		(net "P12V_PEX0_P1V25_VIN_P")
	)
	(segment
		(start 462.065624 -273.59483)
		(end 462.065624 -274.61083)
		(width 0.13208)
		(layer "F.Cu")
		(net "PEX3_P1V25_ADC_A1")
	)
	(segment
		(start 460.732632 -277.165308)
		(end 460.467964 -277.165308)
		(width 0.13208)
		(layer "F.Cu")
		(net "PEX3_P1V25_ADC_A1")
	)
	(segment
		(start 460.953612 -275.698458)
		(end 460.953612 -276.944328)
		(width 0.13208)
		(layer "F.Cu")
		(net "PEX3_P1V25_ADC_A1")
	)
	(segment
		(start 462.065624 -274.61083)
		(end 462.04124 -274.61083)
		(width 0.13208)
		(layer "F.Cu")
		(net "PEX3_P1V25_ADC_A1")
	)
	(segment
		(start 460.953612 -276.944328)
		(end 460.732632 -277.165308)
		(width 0.13208)
		(layer "F.Cu")
		(net "PEX3_P1V25_ADC_A1")
	)
	(segment
		(start 461.32369 -275.32838)
		(end 460.953612 -275.698458)
		(width 0.13208)
		(layer "F.Cu")
		(net "PEX3_P1V25_ADC_A1")
	)
	(segment
		(start 462.04124 -274.61083)
		(end 461.32369 -275.32838)
		(width 0.13208)
		(layer "F.Cu")
		(net "PEX3_P1V25_ADC_A1")
	)
	(via
		(at 461.32369 -275.32838)
		(size 0.508)
		(drill 0.254)
		(layers "F.Cu" "B.Cu")
		(net "PEX3_P1V25_ADC_A1")
	)
	(via
		(at 241.767106 -276.369018)
		(size 0.508)
		(drill 0.254)
		(layers "F.Cu" "B.Cu")
		(net "P12V_PEX2_P1V25_VIN_N")
	)
	(via
		(at 243.327174 -274.632674)
		(size 0.508)
		(drill 0.254)
		(layers "F.Cu" "B.Cu")
		(net "P12V_PEX2_P1V25_VIN_P")
	)
	(segment
		(start 230.333042 -278.668988)
		(end 230.333042 -279.440386)
		(width 0.13208)
		(layer "F.Cu")
		(net "SMB_PEX1_P1V25_ADC_SDA")
	)
	(segment
		(start 229.846886 -278.541988)
		(end 230.206042 -278.541988)
		(width 0.13208)
		(layer "F.Cu")
		(net "SMB_PEX1_P1V25_ADC_SDA")
	)
	(segment
		(start 230.834946 -279.567386)
		(end 231.444546 -279.567386)
		(width 0.13208)
		(layer "F.Cu")
		(net "SMB_PEX1_P1V25_ADC_SDA")
	)
	(segment
		(start 230.333042 -279.440386)
		(end 230.460042 -279.567386)
		(width 0.13208)
		(layer "F.Cu")
		(net "SMB_PEX1_P1V25_ADC_SDA")
	)
	(segment
		(start 230.460042 -279.567386)
		(end 230.834946 -279.567386)
		(width 0.13208)
		(layer "F.Cu")
		(net "SMB_PEX1_P1V25_ADC_SDA")
	)
	(segment
		(start 230.206042 -278.541988)
		(end 230.333042 -278.668988)
		(width 0.13208)
		(layer "F.Cu")
		(net "SMB_PEX1_P1V25_ADC_SDA")
	)
	(via
		(at 230.834946 -279.567386)
		(size 0.508)
		(drill 0.254)
		(layers "F.Cu" "B.Cu")
		(net "SMB_PEX1_P1V25_ADC_SDA")
	)
	(segment
		(start 461.203548 -278.165306)
		(end 461.456024 -277.91283)
		(width 0.13208)
		(layer "F.Cu")
		(net "PEX3_P1V25_ADC_ALERT_N")
	)
	(segment
		(start 460.467964 -278.165306)
		(end 461.203548 -278.165306)
		(width 0.13208)
		(layer "F.Cu")
		(net "PEX3_P1V25_ADC_ALERT_N")
	)
	(segment
		(start 461.456024 -277.91283)
		(end 461.710024 -277.65883)
		(width 0.13208)
		(layer "F.Cu")
		(net "PEX3_P1V25_ADC_ALERT_N")
	)
	(segment
		(start 461.710024 -277.65883)
		(end 462.065624 -277.65883)
		(width 0.13208)
		(layer "F.Cu")
		(net "PEX3_P1V25_ADC_ALERT_N")
	)
	(via
		(at 461.456024 -277.91283)
		(size 0.508)
		(drill 0.254)
		(layers "F.Cu" "B.Cu")
		(net "PEX3_P1V25_ADC_ALERT_N")
	)
	(segment
		(start 16.385286 -277.280624)
		(end 15.775686 -277.280624)
		(width 0.13208)
		(layer "F.Cu")
		(net "SMB_PEX0_P1V25_ADC_SDA")
	)
	(segment
		(start 15.273782 -276.382226)
		(end 15.146782 -276.255226)
		(width 0.13208)
		(layer "F.Cu")
		(net "SMB_PEX0_P1V25_ADC_SDA")
	)
	(segment
		(start 15.400782 -277.280624)
		(end 15.273782 -277.153624)
		(width 0.13208)
		(layer "F.Cu")
		(net "SMB_PEX0_P1V25_ADC_SDA")
	)
	(segment
		(start 15.273782 -277.153624)
		(end 15.273782 -276.382226)
		(width 0.13208)
		(layer "F.Cu")
		(net "SMB_PEX0_P1V25_ADC_SDA")
	)
	(segment
		(start 15.775686 -277.280624)
		(end 15.400782 -277.280624)
		(width 0.13208)
		(layer "F.Cu")
		(net "SMB_PEX0_P1V25_ADC_SDA")
	)
	(segment
		(start 15.146782 -276.255226)
		(end 14.787626 -276.255226)
		(width 0.13208)
		(layer "F.Cu")
		(net "SMB_PEX0_P1V25_ADC_SDA")
	)
	(via
		(at 15.775686 -277.280624)
		(size 0.508)
		(drill 0.254)
		(layers "F.Cu" "B.Cu")
		(net "SMB_PEX0_P1V25_ADC_SDA")
	)
	(segment
		(start 16.385286 -273.216624)
		(end 16.385286 -274.232624)
		(width 0.13208)
		(layer "F.Cu")
		(net "PEX0_P1V25_ADC_A0")
	)
	(segment
		(start 15.775686 -274.232624)
		(end 16.385286 -274.232624)
		(width 0.13208)
		(layer "F.Cu")
		(net "PEX0_P1V25_ADC_A0")
	)
	(segment
		(start 15.152116 -275.255228)
		(end 15.775686 -274.631658)
		(width 0.13208)
		(layer "F.Cu")
		(net "PEX0_P1V25_ADC_A0")
	)
	(segment
		(start 14.787626 -275.255228)
		(end 15.152116 -275.255228)
		(width 0.13208)
		(layer "F.Cu")
		(net "PEX0_P1V25_ADC_A0")
	)
	(segment
		(start 15.775686 -274.631658)
		(end 15.775686 -274.232624)
		(width 0.13208)
		(layer "F.Cu")
		(net "PEX0_P1V25_ADC_A0")
	)
	(via
		(at 15.775686 -274.232624)
		(size 0.508)
		(drill 0.254)
		(layers "F.Cu" "B.Cu")
		(net "PEX0_P1V25_ADC_A0")
	)
	(via
		(at 227.077016 -274.632674)
		(size 0.508)
		(drill 0.254)
		(layers "F.Cu" "B.Cu")
		(net "P12V_PEX1_P1V25_VIN_P")
	)
	(segment
		(start 460.832454 -277.665434)
		(end 461.456024 -277.041864)
		(width 0.13208)
		(layer "F.Cu")
		(net "PEX3_P1V25_ADC_A0")
	)
	(segment
		(start 462.065624 -276.64283)
		(end 461.456024 -276.64283)
		(width 0.13208)
		(layer "F.Cu")
		(net "PEX3_P1V25_ADC_A0")
	)
	(segment
		(start 461.456024 -277.041864)
		(end 461.456024 -276.64283)
		(width 0.13208)
		(layer "F.Cu")
		(net "PEX3_P1V25_ADC_A0")
	)
	(segment
		(start 460.467964 -277.665434)
		(end 460.832454 -277.665434)
		(width 0.13208)
		(layer "F.Cu")
		(net "PEX3_P1V25_ADC_A0")
	)
	(segment
		(start 462.065624 -275.62683)
		(end 462.065624 -276.64283)
		(width 0.13208)
		(layer "F.Cu")
		(net "PEX3_P1V25_ADC_A0")
	)
	(via
		(at 461.456024 -276.64283)
		(size 0.508)
		(drill 0.254)
		(layers "F.Cu" "B.Cu")
		(net "PEX3_P1V25_ADC_A0")
	)
	(via
		(at 10.457688 -274.082256)
		(size 0.508)
		(drill 0.254)
		(layers "F.Cu" "B.Cu")
		(net "P12V_PEX0_P1V25_VIN_N")
	)
	(segment
		(start 375.6533 -239.647984)
		(end 374.649238 -238.643922)
		(width 0.13208)
		(layer "F.Cu")
		(net "PWRGD_P3V3_AUX_R")
	)
	(segment
		(start 120.28424 -165.9001)
		(end 120.28424 -163.35883)
		(width 0.13208)
		(layer "F.Cu")
		(net "PWRGD_P3V3_AUX_R")
	)
	(segment
		(start 122.696986 -168.312846)
		(end 120.28424 -165.9001)
		(width 0.13208)
		(layer "F.Cu")
		(net "PWRGD_P3V3_AUX_R")
	)
	(segment
		(start 120.28424 -163.35883)
		(end 120.142762 -163.217352)
		(width 0.13208)
		(layer "F.Cu")
		(net "PWRGD_P3V3_AUX_R")
	)
	(segment
		(start 120.142762 -163.217352)
		(end 115.200938 -163.217352)
		(width 0.13208)
		(layer "F.Cu")
		(net "PWRGD_P3V3_AUX_R")
	)
	(segment
		(start 375.947686 -239.647984)
		(end 375.6533 -239.647984)
		(width 0.13208)
		(layer "F.Cu")
		(net "PWRGD_P3V3_AUX_R")
	)
	(segment
		(start 374.649238 -238.643922)
		(end 373.32285 -238.643922)
		(width 0.13208)
		(layer "F.Cu")
		(net "PWRGD_P3V3_AUX_R")
	)
	(via
		(at 121.779792 -210.462876)
		(size 0.508)
		(drill 0.254)
		(layers "F.Cu" "B.Cu")
		(net "PWRGD_P3V3_AUX_R")
	)
	(via
		(at 325.4756 -238.825024)
		(size 0.508)
		(drill 0.254)
		(layers "F.Cu" "B.Cu")
		(net "PWRGD_P3V3_AUX_R")
	)
	(via
		(at 122.696986 -168.312846)
		(size 0.508)
		(drill 0.254)
		(layers "F.Cu" "B.Cu")
		(net "PWRGD_P3V3_AUX_R")
	)
	(via
		(at 375.947686 -239.647984)
		(size 0.508)
		(drill 0.254)
		(layers "F.Cu" "B.Cu")
		(net "PWRGD_P3V3_AUX_R")
	)
	(via
		(at 329.403964 -227.328222)
		(size 0.508)
		(drill 0.254)
		(layers "F.Cu" "B.Cu")
		(net "PWRGD_P3V3_AUX_R")
	)
	(segment
		(start 329.889358 -238.38789)
		(end 330.282042 -238.780574)
		(width 0.13208)
		(layer "B.Cu")
		(net "PWRGD_P3V3_AUX_R")
	)
	(segment
		(start 329.403964 -226.629214)
		(end 329.29195 -226.5172)
		(width 0.13208)
		(layer "B.Cu")
		(net "PWRGD_P3V3_AUX_R")
	)
	(segment
		(start 325.4756 -238.825024)
		(end 325.4756 -238.374174)
		(width 0.13208)
		(layer "B.Cu")
		(net "PWRGD_P3V3_AUX_R")
	)
	(segment
		(start 341.117936 -239.8522)
		(end 341.71636 -240.450624)
		(width 0.13208)
		(layer "B.Cu")
		(net "PWRGD_P3V3_AUX_R")
	)
	(segment
		(start 335.79181 -239.1156)
		(end 336.181954 -239.505744)
		(width 0.13208)
		(layer "B.Cu")
		(net "PWRGD_P3V3_AUX_R")
	)
	(segment
		(start 336.181954 -239.986566)
		(end 336.606388 -240.411)
		(width 0.13208)
		(layer "B.Cu")
		(net "PWRGD_P3V3_AUX_R")
	)
	(segment
		(start 331.362558 -239.1156)
		(end 335.79181 -239.1156)
		(width 0.13208)
		(layer "B.Cu")
		(net "PWRGD_P3V3_AUX_R")
	)
	(segment
		(start 358.542844 -239.944656)
		(end 375.651014 -239.944656)
		(width 0.13208)
		(layer "B.Cu")
		(net "PWRGD_P3V3_AUX_R")
	)
	(segment
		(start 330.564998 -239.15497)
		(end 331.323188 -239.15497)
		(width 0.13208)
		(layer "B.Cu")
		(net "PWRGD_P3V3_AUX_R")
	)
	(segment
		(start 336.181954 -239.505744)
		(end 336.181954 -239.986566)
		(width 0.13208)
		(layer "B.Cu")
		(net "PWRGD_P3V3_AUX_R")
	)
	(segment
		(start 330.282042 -238.872014)
		(end 330.564998 -239.15497)
		(width 0.13208)
		(layer "B.Cu")
		(net "PWRGD_P3V3_AUX_R")
	)
	(segment
		(start 339.6996 -240.411)
		(end 340.2584 -239.8522)
		(width 0.13208)
		(layer "B.Cu")
		(net "PWRGD_P3V3_AUX_R")
	)
	(segment
		(start 357.806752 -239.208564)
		(end 358.542844 -239.944656)
		(width 0.13208)
		(layer "B.Cu")
		(net "PWRGD_P3V3_AUX_R")
	)
	(segment
		(start 330.282042 -238.780574)
		(end 330.282042 -238.872014)
		(width 0.13208)
		(layer "B.Cu")
		(net "PWRGD_P3V3_AUX_R")
	)
	(segment
		(start 352.80854 -239.208564)
		(end 357.806752 -239.208564)
		(width 0.13208)
		(layer "B.Cu")
		(net "PWRGD_P3V3_AUX_R")
	)
	(segment
		(start 351.56648 -240.450624)
		(end 352.80854 -239.208564)
		(width 0.13208)
		(layer "B.Cu")
		(net "PWRGD_P3V3_AUX_R")
	)
	(segment
		(start 325.4756 -238.374174)
		(end 325.655178 -238.194596)
		(width 0.13208)
		(layer "B.Cu")
		(net "PWRGD_P3V3_AUX_R")
	)
	(segment
		(start 341.71636 -240.450624)
		(end 351.56648 -240.450624)
		(width 0.13208)
		(layer "B.Cu")
		(net "PWRGD_P3V3_AUX_R")
	)
	(segment
		(start 324.116446 -238.825024)
		(end 325.4756 -238.825024)
		(width 0.13208)
		(layer "B.Cu")
		(net "PWRGD_P3V3_AUX_R")
	)
	(segment
		(start 340.2584 -239.8522)
		(end 341.117936 -239.8522)
		(width 0.13208)
		(layer "B.Cu")
		(net "PWRGD_P3V3_AUX_R")
	)
	(segment
		(start 328.749406 -238.38789)
		(end 329.889358 -238.38789)
		(width 0.13208)
		(layer "B.Cu")
		(net "PWRGD_P3V3_AUX_R")
	)
	(segment
		(start 325.655178 -238.194596)
		(end 328.556112 -238.194596)
		(width 0.13208)
		(layer "B.Cu")
		(net "PWRGD_P3V3_AUX_R")
	)
	(segment
		(start 336.606388 -240.411)
		(end 339.6996 -240.411)
		(width 0.13208)
		(layer "B.Cu")
		(net "PWRGD_P3V3_AUX_R")
	)
	(segment
		(start 328.556112 -238.194596)
		(end 328.749406 -238.38789)
		(width 0.13208)
		(layer "B.Cu")
		(net "PWRGD_P3V3_AUX_R")
	)
	(segment
		(start 329.403964 -227.328222)
		(end 329.403964 -226.629214)
		(width 0.13208)
		(layer "B.Cu")
		(net "PWRGD_P3V3_AUX_R")
	)
	(segment
		(start 375.651014 -239.944656)
		(end 375.947686 -239.647984)
		(width 0.13208)
		(layer "B.Cu")
		(net "PWRGD_P3V3_AUX_R")
	)
	(segment
		(start 331.323188 -239.15497)
		(end 331.362558 -239.1156)
		(width 0.13208)
		(layer "B.Cu")
		(net "PWRGD_P3V3_AUX_R")
	)
	(segment
		(start 323.187314 -233.524298)
		(end 323.187314 -231.93629)
		(width 0.15494)
		(layer "In5.Cu")
		(net "PWRGD_P3V3_AUX_R")
	)
	(segment
		(start 325.449946 -234.92206)
		(end 324.331076 -234.92206)
		(width 0.15494)
		(layer "In5.Cu")
		(net "PWRGD_P3V3_AUX_R")
	)
	(segment
		(start 324.331076 -234.92206)
		(end 323.366892 -233.957876)
		(width 0.15494)
		(layer "In5.Cu")
		(net "PWRGD_P3V3_AUX_R")
	)
	(segment
		(start 323.187314 -231.93629)
		(end 327.795382 -227.328222)
		(width 0.15494)
		(layer "In5.Cu")
		(net "PWRGD_P3V3_AUX_R")
	)
	(segment
		(start 126.2126 -199.949054)
		(end 126.2126 -185.0898)
		(width 0.15494)
		(layer "In5.Cu")
		(net "PWRGD_P3V3_AUX_R")
	)
	(segment
		(start 121.779792 -204.381862)
		(end 126.2126 -199.949054)
		(width 0.15494)
		(layer "In5.Cu")
		(net "PWRGD_P3V3_AUX_R")
	)
	(segment
		(start 323.366892 -233.957876)
		(end 323.187314 -233.524298)
		(width 0.15494)
		(layer "In5.Cu")
		(net "PWRGD_P3V3_AUX_R")
	)
	(segment
		(start 122.5042 -168.505632)
		(end 122.696986 -168.312846)
		(width 0.15494)
		(layer "In5.Cu")
		(net "PWRGD_P3V3_AUX_R")
	)
	(segment
		(start 126.2126 -185.0898)
		(end 122.5042 -181.3814)
		(width 0.15494)
		(layer "In5.Cu")
		(net "PWRGD_P3V3_AUX_R")
	)
	(segment
		(start 122.5042 -181.3814)
		(end 122.5042 -168.505632)
		(width 0.15494)
		(layer "In5.Cu")
		(net "PWRGD_P3V3_AUX_R")
	)
	(segment
		(start 326.495918 -237.544102)
		(end 326.495918 -235.968032)
		(width 0.15494)
		(layer "In5.Cu")
		(net "PWRGD_P3V3_AUX_R")
	)
	(segment
		(start 121.779792 -210.462876)
		(end 121.779792 -204.381862)
		(width 0.15494)
		(layer "In5.Cu")
		(net "PWRGD_P3V3_AUX_R")
	)
	(segment
		(start 326.495918 -235.968032)
		(end 325.449946 -234.92206)
		(width 0.15494)
		(layer "In5.Cu")
		(net "PWRGD_P3V3_AUX_R")
	)
	(segment
		(start 325.4756 -238.56442)
		(end 326.495918 -237.544102)
		(width 0.15494)
		(layer "In5.Cu")
		(net "PWRGD_P3V3_AUX_R")
	)
	(segment
		(start 325.4756 -238.825024)
		(end 325.4756 -238.56442)
		(width 0.15494)
		(layer "In5.Cu")
		(net "PWRGD_P3V3_AUX_R")
	)
	(segment
		(start 327.795382 -227.328222)
		(end 329.403964 -227.328222)
		(width 0.15494)
		(layer "In5.Cu")
		(net "PWRGD_P3V3_AUX_R")
	)
	(segment
		(start 279.941528 -227.749354)
		(end 301.094394 -227.749354)
		(width 0.15494)
		(layer "In13.Cu")
		(net "PWRGD_P3V3_AUX_R")
	)
	(segment
		(start 135.5598 -212.979)
		(end 136.0424 -212.4964)
		(width 0.15494)
		(layer "In13.Cu")
		(net "PWRGD_P3V3_AUX_R")
	)
	(segment
		(start 324.2818 -228.1428)
		(end 324.2818 -228.4984)
		(width 0.15494)
		(layer "In13.Cu")
		(net "PWRGD_P3V3_AUX_R")
	)
	(segment
		(start 261.585202 -216.779602)
		(end 268.971776 -216.779602)
		(width 0.15494)
		(layer "In13.Cu")
		(net "PWRGD_P3V3_AUX_R")
	)
	(segment
		(start 121.779792 -210.462876)
		(end 124.08789 -212.770974)
		(width 0.15494)
		(layer "In13.Cu")
		(net "PWRGD_P3V3_AUX_R")
	)
	(segment
		(start 212.861652 -208.225136)
		(end 213.225126 -208.58861)
		(width 0.15494)
		(layer "In13.Cu")
		(net "PWRGD_P3V3_AUX_R")
	)
	(segment
		(start 216.5096 -208.58861)
		(end 217.83421 -207.264)
		(width 0.15494)
		(layer "In13.Cu")
		(net "PWRGD_P3V3_AUX_R")
	)
	(segment
		(start 324.2818 -228.4984)
		(end 324.612 -228.8286)
		(width 0.15494)
		(layer "In13.Cu")
		(net "PWRGD_P3V3_AUX_R")
	)
	(segment
		(start 132.956554 -212.979)
		(end 135.5598 -212.979)
		(width 0.15494)
		(layer "In13.Cu")
		(net "PWRGD_P3V3_AUX_R")
	)
	(segment
		(start 230.983536 -206.75346)
		(end 232.094024 -207.2132)
		(width 0.15494)
		(layer "In13.Cu")
		(net "PWRGD_P3V3_AUX_R")
	)
	(segment
		(start 302.156622 -226.687126)
		(end 317.970916 -226.687126)
		(width 0.15494)
		(layer "In13.Cu")
		(net "PWRGD_P3V3_AUX_R")
	)
	(segment
		(start 245.4148 -207.645)
		(end 245.4148 -209.041492)
		(width 0.15494)
		(layer "In13.Cu")
		(net "PWRGD_P3V3_AUX_R")
	)
	(segment
		(start 132.016754 -213.9188)
		(end 132.956554 -212.979)
		(width 0.15494)
		(layer "In13.Cu")
		(net "PWRGD_P3V3_AUX_R")
	)
	(segment
		(start 323.5452 -227.6602)
		(end 323.7992 -227.6602)
		(width 0.15494)
		(layer "In13.Cu")
		(net "PWRGD_P3V3_AUX_R")
	)
	(segment
		(start 245.479316 -211.11591)
		(end 252.989334 -211.11591)
		(width 0.15494)
		(layer "In13.Cu")
		(net "PWRGD_P3V3_AUX_R")
	)
	(segment
		(start 162.444938 -212.4964)
		(end 166.460424 -208.480914)
		(width 0.15494)
		(layer "In13.Cu")
		(net "PWRGD_P3V3_AUX_R")
	)
	(segment
		(start 222.210884 -206.4766)
		(end 222.487744 -206.75346)
		(width 0.15494)
		(layer "In13.Cu")
		(net "PWRGD_P3V3_AUX_R")
	)
	(segment
		(start 328.478896 -228.25329)
		(end 329.403964 -227.328222)
		(width 0.15494)
		(layer "In13.Cu")
		(net "PWRGD_P3V3_AUX_R")
	)
	(segment
		(start 236.58576 -206.923132)
		(end 237.852458 -207.447134)
		(width 0.15494)
		(layer "In13.Cu")
		(net "PWRGD_P3V3_AUX_R")
	)
	(segment
		(start 259.800344 -214.994744)
		(end 261.585202 -216.779602)
		(width 0.15494)
		(layer "In13.Cu")
		(net "PWRGD_P3V3_AUX_R")
	)
	(segment
		(start 253.287276 -211.413852)
		(end 253.287276 -212.084412)
		(width 0.15494)
		(layer "In13.Cu")
		(net "PWRGD_P3V3_AUX_R")
	)
	(segment
		(start 221.0308 -206.4766)
		(end 222.210884 -206.4766)
		(width 0.15494)
		(layer "In13.Cu")
		(net "PWRGD_P3V3_AUX_R")
	)
	(segment
		(start 268.971776 -216.779602)
		(end 279.941528 -227.749354)
		(width 0.15494)
		(layer "In13.Cu")
		(net "PWRGD_P3V3_AUX_R")
	)
	(segment
		(start 256.197608 -214.994744)
		(end 259.800344 -214.994744)
		(width 0.15494)
		(layer "In13.Cu")
		(net "PWRGD_P3V3_AUX_R")
	)
	(segment
		(start 217.83421 -207.264)
		(end 220.2434 -207.264)
		(width 0.15494)
		(layer "In13.Cu")
		(net "PWRGD_P3V3_AUX_R")
	)
	(segment
		(start 245.1862 -209.270092)
		(end 245.1862 -210.822794)
		(width 0.15494)
		(layer "In13.Cu")
		(net "PWRGD_P3V3_AUX_R")
	)
	(segment
		(start 206.133192 -207.899)
		(end 206.303626 -207.728566)
		(width 0.15494)
		(layer "In13.Cu")
		(net "PWRGD_P3V3_AUX_R")
	)
	(segment
		(start 222.487744 -206.75346)
		(end 230.983536 -206.75346)
		(width 0.15494)
		(layer "In13.Cu")
		(net "PWRGD_P3V3_AUX_R")
	)
	(segment
		(start 206.303626 -207.728566)
		(end 206.87919 -207.728566)
		(width 0.15494)
		(layer "In13.Cu")
		(net "PWRGD_P3V3_AUX_R")
	)
	(segment
		(start 236.088428 -206.4258)
		(end 236.58576 -206.923132)
		(width 0.15494)
		(layer "In13.Cu")
		(net "PWRGD_P3V3_AUX_R")
	)
	(segment
		(start 233.7562 -207.2132)
		(end 234.5436 -206.4258)
		(width 0.15494)
		(layer "In13.Cu")
		(net "PWRGD_P3V3_AUX_R")
	)
	(segment
		(start 237.852458 -207.447134)
		(end 245.216934 -207.447134)
		(width 0.15494)
		(layer "In13.Cu")
		(net "PWRGD_P3V3_AUX_R")
	)
	(segment
		(start 245.1862 -210.822794)
		(end 245.479316 -211.11591)
		(width 0.15494)
		(layer "In13.Cu")
		(net "PWRGD_P3V3_AUX_R")
	)
	(segment
		(start 136.0424 -212.4964)
		(end 162.444938 -212.4964)
		(width 0.15494)
		(layer "In13.Cu")
		(net "PWRGD_P3V3_AUX_R")
	)
	(segment
		(start 326.955658 -228.25329)
		(end 328.478896 -228.25329)
		(width 0.15494)
		(layer "In13.Cu")
		(net "PWRGD_P3V3_AUX_R")
	)
	(segment
		(start 232.094024 -207.2132)
		(end 233.7562 -207.2132)
		(width 0.15494)
		(layer "In13.Cu")
		(net "PWRGD_P3V3_AUX_R")
	)
	(segment
		(start 326.380348 -228.8286)
		(end 326.955658 -228.25329)
		(width 0.15494)
		(layer "In13.Cu")
		(net "PWRGD_P3V3_AUX_R")
	)
	(segment
		(start 128.183386 -213.9188)
		(end 132.016754 -213.9188)
		(width 0.15494)
		(layer "In13.Cu")
		(net "PWRGD_P3V3_AUX_R")
	)
	(segment
		(start 245.4148 -209.041492)
		(end 245.1862 -209.270092)
		(width 0.15494)
		(layer "In13.Cu")
		(net "PWRGD_P3V3_AUX_R")
	)
	(segment
		(start 206.87919 -207.728566)
		(end 207.37576 -208.225136)
		(width 0.15494)
		(layer "In13.Cu")
		(net "PWRGD_P3V3_AUX_R")
	)
	(segment
		(start 324.612 -228.8286)
		(end 326.380348 -228.8286)
		(width 0.15494)
		(layer "In13.Cu")
		(net "PWRGD_P3V3_AUX_R")
	)
	(segment
		(start 166.460424 -208.480914)
		(end 178.4604 -208.480914)
		(width 0.15494)
		(layer "In13.Cu")
		(net "PWRGD_P3V3_AUX_R")
	)
	(segment
		(start 245.216934 -207.447134)
		(end 245.4148 -207.645)
		(width 0.15494)
		(layer "In13.Cu")
		(net "PWRGD_P3V3_AUX_R")
	)
	(segment
		(start 207.37576 -208.225136)
		(end 212.861652 -208.225136)
		(width 0.15494)
		(layer "In13.Cu")
		(net "PWRGD_P3V3_AUX_R")
	)
	(segment
		(start 220.2434 -207.264)
		(end 221.0308 -206.4766)
		(width 0.15494)
		(layer "In13.Cu")
		(net "PWRGD_P3V3_AUX_R")
	)
	(segment
		(start 301.094394 -227.749354)
		(end 302.156622 -226.687126)
		(width 0.15494)
		(layer "In13.Cu")
		(net "PWRGD_P3V3_AUX_R")
	)
	(segment
		(start 213.225126 -208.58861)
		(end 216.5096 -208.58861)
		(width 0.15494)
		(layer "In13.Cu")
		(net "PWRGD_P3V3_AUX_R")
	)
	(segment
		(start 252.989334 -211.11591)
		(end 253.287276 -211.413852)
		(width 0.15494)
		(layer "In13.Cu")
		(net "PWRGD_P3V3_AUX_R")
	)
	(segment
		(start 124.08789 -212.770974)
		(end 127.03556 -212.770974)
		(width 0.15494)
		(layer "In13.Cu")
		(net "PWRGD_P3V3_AUX_R")
	)
	(segment
		(start 319.65519 -228.3714)
		(end 322.834 -228.3714)
		(width 0.15494)
		(layer "In13.Cu")
		(net "PWRGD_P3V3_AUX_R")
	)
	(segment
		(start 253.287276 -212.084412)
		(end 256.197608 -214.994744)
		(width 0.15494)
		(layer "In13.Cu")
		(net "PWRGD_P3V3_AUX_R")
	)
	(segment
		(start 322.834 -228.3714)
		(end 323.5452 -227.6602)
		(width 0.15494)
		(layer "In13.Cu")
		(net "PWRGD_P3V3_AUX_R")
	)
	(segment
		(start 317.970916 -226.687126)
		(end 319.65519 -228.3714)
		(width 0.15494)
		(layer "In13.Cu")
		(net "PWRGD_P3V3_AUX_R")
	)
	(segment
		(start 234.5436 -206.4258)
		(end 236.088428 -206.4258)
		(width 0.15494)
		(layer "In13.Cu")
		(net "PWRGD_P3V3_AUX_R")
	)
	(segment
		(start 127.03556 -212.770974)
		(end 128.183386 -213.9188)
		(width 0.15494)
		(layer "In13.Cu")
		(net "PWRGD_P3V3_AUX_R")
	)
	(segment
		(start 178.4604 -208.480914)
		(end 179.042314 -207.899)
		(width 0.15494)
		(layer "In13.Cu")
		(net "PWRGD_P3V3_AUX_R")
	)
	(segment
		(start 323.7992 -227.6602)
		(end 324.2818 -228.1428)
		(width 0.15494)
		(layer "In13.Cu")
		(net "PWRGD_P3V3_AUX_R")
	)
	(segment
		(start 179.042314 -207.899)
		(end 206.133192 -207.899)
		(width 0.15494)
		(layer "In13.Cu")
		(net "PWRGD_P3V3_AUX_R")
	)
	(via
		(at 456.138026 -276.492462)
		(size 0.508)
		(drill 0.254)
		(layers "F.Cu" "B.Cu")
		(net "P12V_PEX3_P1V25_VIN_N")
	)
	(segment
		(start 230.211376 -277.54199)
		(end 230.834946 -276.91842)
		(width 0.13208)
		(layer "F.Cu")
		(net "PEX1_P1V25_ADC_A0")
	)
	(segment
		(start 231.444546 -275.503386)
		(end 231.444546 -276.519386)
		(width 0.13208)
		(layer "F.Cu")
		(net "PEX1_P1V25_ADC_A0")
	)
	(segment
		(start 230.834946 -276.519386)
		(end 231.444546 -276.519386)
		(width 0.13208)
		(layer "F.Cu")
		(net "PEX1_P1V25_ADC_A0")
	)
	(segment
		(start 230.834946 -276.91842)
		(end 230.834946 -276.519386)
		(width 0.13208)
		(layer "F.Cu")
		(net "PEX1_P1V25_ADC_A0")
	)
	(segment
		(start 229.846886 -277.54199)
		(end 230.211376 -277.54199)
		(width 0.13208)
		(layer "F.Cu")
		(net "PEX1_P1V25_ADC_A0")
	)
	(via
		(at 230.834946 -276.519386)
		(size 0.508)
		(drill 0.254)
		(layers "F.Cu" "B.Cu")
		(net "PEX1_P1V25_ADC_A0")
	)
	(segment
		(start 230.834946 -277.789386)
		(end 231.088946 -277.535386)
		(width 0.13208)
		(layer "F.Cu")
		(net "PEX1_P1V25_ADC_ALERT_N")
	)
	(segment
		(start 229.846886 -278.041862)
		(end 230.58247 -278.041862)
		(width 0.13208)
		(layer "F.Cu")
		(net "PEX1_P1V25_ADC_ALERT_N")
	)
	(segment
		(start 231.088946 -277.535386)
		(end 231.444546 -277.535386)
		(width 0.13208)
		(layer "F.Cu")
		(net "PEX1_P1V25_ADC_ALERT_N")
	)
	(segment
		(start 230.58247 -278.041862)
		(end 230.834946 -277.789386)
		(width 0.13208)
		(layer "F.Cu")
		(net "PEX1_P1V25_ADC_ALERT_N")
	)
	(via
		(at 230.834946 -277.789386)
		(size 0.508)
		(drill 0.254)
		(layers "F.Cu" "B.Cu")
		(net "PEX1_P1V25_ADC_ALERT_N")
	)
	(segment
		(start 246.097044 -277.54199)
		(end 246.461534 -277.54199)
		(width 0.13208)
		(layer "F.Cu")
		(net "PEX2_P1V25_ADC_A0")
	)
	(segment
		(start 247.694704 -275.503386)
		(end 247.694704 -276.519386)
		(width 0.13208)
		(layer "F.Cu")
		(net "PEX2_P1V25_ADC_A0")
	)
	(segment
		(start 246.461534 -277.54199)
		(end 247.085104 -276.91842)
		(width 0.13208)
		(layer "F.Cu")
		(net "PEX2_P1V25_ADC_A0")
	)
	(segment
		(start 247.085104 -276.519386)
		(end 247.694704 -276.519386)
		(width 0.13208)
		(layer "F.Cu")
		(net "PEX2_P1V25_ADC_A0")
	)
	(segment
		(start 247.085104 -276.91842)
		(end 247.085104 -276.519386)
		(width 0.13208)
		(layer "F.Cu")
		(net "PEX2_P1V25_ADC_A0")
	)
	(via
		(at 247.085104 -276.519386)
		(size 0.508)
		(drill 0.254)
		(layers "F.Cu" "B.Cu")
		(net "PEX2_P1V25_ADC_A0")
	)
	(segment
		(start 246.582692 -275.575014)
		(end 246.95277 -275.204936)
		(width 0.13208)
		(layer "F.Cu")
		(net "PEX2_P1V25_ADC_A1")
	)
	(segment
		(start 246.582692 -276.820884)
		(end 246.582692 -275.575014)
		(width 0.13208)
		(layer "F.Cu")
		(net "PEX2_P1V25_ADC_A1")
	)
	(segment
		(start 246.361712 -277.041864)
		(end 246.582692 -276.820884)
		(width 0.13208)
		(layer "F.Cu")
		(net "PEX2_P1V25_ADC_A1")
	)
	(segment
		(start 246.95277 -275.204936)
		(end 247.67032 -274.487386)
		(width 0.13208)
		(layer "F.Cu")
		(net "PEX2_P1V25_ADC_A1")
	)
	(segment
		(start 247.67032 -274.487386)
		(end 247.694704 -274.487386)
		(width 0.13208)
		(layer "F.Cu")
		(net "PEX2_P1V25_ADC_A1")
	)
	(segment
		(start 246.097044 -277.041864)
		(end 246.361712 -277.041864)
		(width 0.13208)
		(layer "F.Cu")
		(net "PEX2_P1V25_ADC_A1")
	)
	(segment
		(start 247.694704 -273.471386)
		(end 247.694704 -274.487386)
		(width 0.13208)
		(layer "F.Cu")
		(net "PEX2_P1V25_ADC_A1")
	)
	(via
		(at 246.95277 -275.204936)
		(size 0.508)
		(drill 0.254)
		(layers "F.Cu" "B.Cu")
		(net "PEX2_P1V25_ADC_A1")
	)
	(segment
		(start 16.385286 -275.248624)
		(end 16.029686 -275.248624)
		(width 0.13208)
		(layer "F.Cu")
		(net "PEX0_P1V25_ADC_ALERT_N")
	)
	(segment
		(start 15.52321 -275.7551)
		(end 14.787626 -275.7551)
		(width 0.13208)
		(layer "F.Cu")
		(net "PEX0_P1V25_ADC_ALERT_N")
	)
	(segment
		(start 15.775686 -275.502624)
		(end 15.52321 -275.7551)
		(width 0.13208)
		(layer "F.Cu")
		(net "PEX0_P1V25_ADC_ALERT_N")
	)
	(segment
		(start 16.029686 -275.248624)
		(end 15.775686 -275.502624)
		(width 0.13208)
		(layer "F.Cu")
		(net "PEX0_P1V25_ADC_ALERT_N")
	)
	(via
		(at 15.775686 -275.502624)
		(size 0.508)
		(drill 0.254)
		(layers "F.Cu" "B.Cu")
		(net "PEX0_P1V25_ADC_ALERT_N")
	)
	(segment
		(start 14.13764 -277.379938)
		(end 14.13764 -276.905212)
		(width 0.13208)
		(layer "F.Cu")
		(net "SMB_PEX0_P1V25_ADC_SCL")
	)
	(segment
		(start 92.428822 -239.64392)
		(end 92.428822 -240.503202)
		(width 0.13208)
		(layer "F.Cu")
		(net "SMB_PEX0_P1V25_ADC_SCL")
	)
	(segment
		(start 20.470622 -240.304828)
		(end 20.470622 -244.070378)
		(width 0.13208)
		(layer "F.Cu")
		(net "SMB_PEX0_P1V25_ADC_SCL")
	)
	(segment
		(start 20.470622 -244.070378)
		(end 19.2278 -245.3132)
		(width 0.13208)
		(layer "F.Cu")
		(net "SMB_PEX0_P1V25_ADC_SCL")
	)
	(segment
		(start 14.53388 -277.776178)
		(end 14.13764 -277.379938)
		(width 0.13208)
		(layer "F.Cu")
		(net "SMB_PEX0_P1V25_ADC_SCL")
	)
	(segment
		(start 18.464022 -277.776178)
		(end 14.53388 -277.776178)
		(width 0.13208)
		(layer "F.Cu")
		(net "SMB_PEX0_P1V25_ADC_SCL")
	)
	(segment
		(start 19.2278 -245.3132)
		(end 19.2278 -277.0124)
		(width 0.13208)
		(layer "F.Cu")
		(net "SMB_PEX0_P1V25_ADC_SCL")
	)
	(segment
		(start 19.2278 -277.0124)
		(end 18.464022 -277.776178)
		(width 0.13208)
		(layer "F.Cu")
		(net "SMB_PEX0_P1V25_ADC_SCL")
	)
	(via
		(at 92.428822 -240.503202)
		(size 0.508)
		(drill 0.254)
		(layers "F.Cu" "B.Cu")
		(net "SMB_PEX0_P1V25_ADC_SCL")
	)
	(via
		(at 20.470622 -240.304828)
		(size 0.508)
		(drill 0.254)
		(layers "F.Cu" "B.Cu")
		(net "SMB_PEX0_P1V25_ADC_SCL")
	)
	(segment
		(start 21.047202 -239.728248)
		(end 91.653868 -239.728248)
		(width 0.15494)
		(layer "In15.Cu")
		(net "SMB_PEX0_P1V25_ADC_SCL")
	)
	(segment
		(start 20.470622 -240.304828)
		(end 21.047202 -239.728248)
		(width 0.15494)
		(layer "In15.Cu")
		(net "SMB_PEX0_P1V25_ADC_SCL")
	)
	(segment
		(start 91.653868 -239.728248)
		(end 92.428822 -240.503202)
		(width 0.15494)
		(layer "In15.Cu")
		(net "SMB_PEX0_P1V25_ADC_SCL")
	)
	(segment
		(start 15.643352 -272.918174)
		(end 16.360902 -272.200624)
		(width 0.13208)
		(layer "F.Cu")
		(net "PEX0_P1V25_ADC_A1")
	)
	(segment
		(start 15.052294 -274.755102)
		(end 15.273274 -274.534122)
		(width 0.13208)
		(layer "F.Cu")
		(net "PEX0_P1V25_ADC_A1")
	)
	(segment
		(start 15.273274 -273.288252)
		(end 15.643352 -272.918174)
		(width 0.13208)
		(layer "F.Cu")
		(net "PEX0_P1V25_ADC_A1")
	)
	(segment
		(start 16.360902 -272.200624)
		(end 16.385286 -272.200624)
		(width 0.13208)
		(layer "F.Cu")
		(net "PEX0_P1V25_ADC_A1")
	)
	(segment
		(start 15.273274 -274.534122)
		(end 15.273274 -273.288252)
		(width 0.13208)
		(layer "F.Cu")
		(net "PEX0_P1V25_ADC_A1")
	)
	(segment
		(start 14.787626 -274.755102)
		(end 15.052294 -274.755102)
		(width 0.13208)
		(layer "F.Cu")
		(net "PEX0_P1V25_ADC_A1")
	)
	(segment
		(start 16.385286 -271.184624)
		(end 16.385286 -272.200624)
		(width 0.13208)
		(layer "F.Cu")
		(net "PEX0_P1V25_ADC_A1")
	)
	(via
		(at 15.643352 -272.918174)
		(size 0.508)
		(drill 0.254)
		(layers "F.Cu" "B.Cu")
		(net "PEX0_P1V25_ADC_A1")
	)
	(segment
		(start 441.387484 -97.821242)
		(end 441.387484 -98.196146)
		(width 0.13208)
		(layer "F.Cu")
		(net "SMB_NIC7_ADC_SDA")
	)
	(segment
		(start 441.387484 -97.211642)
		(end 441.387484 -97.821242)
		(width 0.13208)
		(layer "F.Cu")
		(net "SMB_NIC7_ADC_SDA")
	)
	(segment
		(start 441.260484 -98.323146)
		(end 440.489086 -98.323146)
		(width 0.13208)
		(layer "F.Cu")
		(net "SMB_NIC7_ADC_SDA")
	)
	(segment
		(start 441.387484 -98.196146)
		(end 441.260484 -98.323146)
		(width 0.13208)
		(layer "F.Cu")
		(net "SMB_NIC7_ADC_SDA")
	)
	(segment
		(start 440.489086 -98.323146)
		(end 440.362086 -98.450146)
		(width 0.13208)
		(layer "F.Cu")
		(net "SMB_NIC7_ADC_SDA")
	)
	(segment
		(start 440.362086 -98.450146)
		(end 440.362086 -98.809302)
		(width 0.13208)
		(layer "F.Cu")
		(net "SMB_NIC7_ADC_SDA")
	)
	(via
		(at 441.387484 -97.821242)
		(size 0.508)
		(drill 0.254)
		(layers "F.Cu" "B.Cu")
		(net "SMB_NIC7_ADC_SDA")
	)
	(via
		(at 225.516948 -276.369018)
		(size 0.508)
		(drill 0.254)
		(layers "F.Cu" "B.Cu")
		(net "P12V_PEX1_P1V25_VIN_N")
	)
	(segment
		(start 363.459776 -152.3111)
		(end 363.459776 -151.123904)
		(width 0.13208)
		(layer "F.Cu")
		(net "SMB_NIC6_ADC_SCL")
	)
	(segment
		(start 363.459776 -151.123904)
		(end 364.520226 -150.063454)
		(width 0.13208)
		(layer "F.Cu")
		(net "SMB_NIC6_ADC_SCL")
	)
	(segment
		(start 364.520226 -150.063454)
		(end 365.568738 -150.063454)
		(width 0.13208)
		(layer "F.Cu")
		(net "SMB_NIC6_ADC_SCL")
	)
	(via
		(at 364.520226 -150.063454)
		(size 0.508)
		(drill 0.254)
		(layers "F.Cu" "B.Cu")
		(net "SMB_NIC6_ADC_SCL")
	)
	(segment
		(start 246.097044 -278.041862)
		(end 246.832628 -278.041862)
		(width 0.13208)
		(layer "F.Cu")
		(net "PEX2_P1V25_ADC_ALERT_N")
	)
	(segment
		(start 246.832628 -278.041862)
		(end 247.085104 -277.789386)
		(width 0.13208)
		(layer "F.Cu")
		(net "PEX2_P1V25_ADC_ALERT_N")
	)
	(segment
		(start 247.339104 -277.535386)
		(end 247.085104 -277.789386)
		(width 0.13208)
		(layer "F.Cu")
		(net "PEX2_P1V25_ADC_ALERT_N")
	)
	(segment
		(start 247.694704 -277.535386)
		(end 247.339104 -277.535386)
		(width 0.13208)
		(layer "F.Cu")
		(net "PEX2_P1V25_ADC_ALERT_N")
	)
	(via
		(at 247.085104 -277.789386)
		(size 0.508)
		(drill 0.254)
		(layers "F.Cu" "B.Cu")
		(net "PEX2_P1V25_ADC_ALERT_N")
	)
	(segment
		(start 250.618752 -152.100026)
		(end 250.618752 -151.406606)
		(width 0.13208)
		(layer "F.Cu")
		(net "NIC4_ADC_ALERT_N")
	)
	(segment
		(start 250.407678 -152.3111)
		(end 250.618752 -152.100026)
		(width 0.13208)
		(layer "F.Cu")
		(net "NIC4_ADC_ALERT_N")
	)
	(segment
		(start 250.618752 -151.406606)
		(end 250.618752 -150.71344)
		(width 0.13208)
		(layer "F.Cu")
		(net "NIC4_ADC_ALERT_N")
	)
	(via
		(at 250.618752 -151.406606)
		(size 0.508)
		(drill 0.254)
		(layers "F.Cu" "B.Cu")
		(net "NIC4_ADC_ALERT_N")
	)
	(via
		(at 457.698094 -274.756118)
		(size 0.508)
		(drill 0.254)
		(layers "F.Cu" "B.Cu")
		(net "P12V_PEX3_P1V25_VIN_P")
	)
	(segment
		(start 370.571776 -152.3111)
		(end 369.555776 -152.3111)
		(width 0.13208)
		(layer "F.Cu")
		(net "NIC6_ADC_A1")
	)
	(segment
		(start 368.70005 -150.71344)
		(end 369.555776 -151.569166)
		(width 0.13208)
		(layer "F.Cu")
		(net "NIC6_ADC_A1")
	)
	(segment
		(start 367.718848 -150.71344)
		(end 368.70005 -150.71344)
		(width 0.13208)
		(layer "F.Cu")
		(net "NIC6_ADC_A1")
	)
	(segment
		(start 369.555776 -151.569166)
		(end 369.555776 -152.3111)
		(width 0.13208)
		(layer "F.Cu")
		(net "NIC6_ADC_A1")
	)
	(via
		(at 369.555776 -151.569166)
		(size 0.508)
		(drill 0.254)
		(layers "F.Cu" "B.Cu")
		(net "NIC6_ADC_A1")
	)
	(segment
		(start 249.930158 -151.0919)
		(end 248.954798 -151.0919)
		(width 0.13208)
		(layer "F.Cu")
		(net "SMB_NIC4_ADC_SDA")
	)
	(segment
		(start 248.375678 -151.67102)
		(end 248.375678 -152.3111)
		(width 0.13208)
		(layer "F.Cu")
		(net "SMB_NIC4_ADC_SDA")
	)
	(segment
		(start 250.118626 -150.71344)
		(end 250.118626 -150.903432)
		(width 0.13208)
		(layer "F.Cu")
		(net "SMB_NIC4_ADC_SDA")
	)
	(segment
		(start 248.954798 -151.0919)
		(end 248.375678 -151.67102)
		(width 0.13208)
		(layer "F.Cu")
		(net "SMB_NIC4_ADC_SDA")
	)
	(segment
		(start 250.118626 -150.903432)
		(end 249.930158 -151.0919)
		(width 0.13208)
		(layer "F.Cu")
		(net "SMB_NIC4_ADC_SDA")
	)
	(via
		(at 248.375678 -151.67102)
		(size 0.508)
		(drill 0.254)
		(layers "F.Cu" "B.Cu")
		(net "SMB_NIC4_ADC_SDA")
	)
	(segment
		(start 254.46355 -146.192748)
		(end 253.384304 -146.192748)
		(width 0.254)
		(layer "F.Cu")
		(net "P12V_NIC4_VIN_P")
	)
	(segment
		(start 253.384304 -146.192748)
		(end 253.371096 -146.205956)
		(width 0.254)
		(layer "F.Cu")
		(net "P12V_NIC4_VIN_P")
	)
	(segment
		(start 253.576328 -147.062444)
		(end 253.371096 -146.857212)
		(width 0.254)
		(layer "F.Cu")
		(net "P12V_NIC4_VIN_P")
	)
	(segment
		(start 253.371096 -146.857212)
		(end 253.371096 -146.205956)
		(width 0.254)
		(layer "F.Cu")
		(net "P12V_NIC4_VIN_P")
	)
	(segment
		(start 252.268736 -148.56333)
		(end 252.742954 -148.56333)
		(width 0.254)
		(layer "F.Cu")
		(net "P12V_NIC4_VIN_P")
	)
	(segment
		(start 252.742954 -148.56333)
		(end 253.576328 -147.729956)
		(width 0.254)
		(layer "F.Cu")
		(net "P12V_NIC4_VIN_P")
	)
	(segment
		(start 253.576328 -147.729956)
		(end 253.576328 -147.062444)
		(width 0.254)
		(layer "F.Cu")
		(net "P12V_NIC4_VIN_P")
	)
	(via
		(at 253.576328 -147.062444)
		(size 0.508)
		(drill 0.254)
		(layers "F.Cu" "B.Cu")
		(net "P12V_NIC4_VIN_P")
	)
	(segment
		(start 253.455678 -151.569166)
		(end 252.599952 -150.71344)
		(width 0.13208)
		(layer "F.Cu")
		(net "NIC4_ADC_A1")
	)
	(segment
		(start 254.471678 -152.3111)
		(end 253.455678 -152.3111)
		(width 0.13208)
		(layer "F.Cu")
		(net "NIC4_ADC_A1")
	)
	(segment
		(start 252.599952 -150.71344)
		(end 251.61875 -150.71344)
		(width 0.13208)
		(layer "F.Cu")
		(net "NIC4_ADC_A1")
	)
	(segment
		(start 253.455678 -151.569166)
		(end 253.455678 -152.3111)
		(width 0.13208)
		(layer "F.Cu")
		(net "NIC4_ADC_A1")
	)
	(via
		(at 253.455678 -151.569166)
		(size 0.508)
		(drill 0.254)
		(layers "F.Cu" "B.Cu")
		(net "NIC4_ADC_A1")
	)
	(segment
		(start 367.218722 -150.71344)
		(end 367.218722 -151.193754)
		(width 0.13208)
		(layer "F.Cu")
		(net "NIC6_ADC_A0")
	)
	(segment
		(start 367.218722 -151.193754)
		(end 367.607596 -151.582628)
		(width 0.13208)
		(layer "F.Cu")
		(net "NIC6_ADC_A0")
	)
	(segment
		(start 367.523776 -152.3111)
		(end 368.539776 -152.3111)
		(width 0.13208)
		(layer "F.Cu")
		(net "NIC6_ADC_A0")
	)
	(segment
		(start 368.044476 -151.582628)
		(end 368.412776 -151.582628)
		(width 0.13208)
		(layer "F.Cu")
		(net "NIC6_ADC_A0")
	)
	(segment
		(start 368.412776 -151.582628)
		(end 368.539776 -151.709628)
		(width 0.13208)
		(layer "F.Cu")
		(net "NIC6_ADC_A0")
	)
	(segment
		(start 367.607596 -151.582628)
		(end 368.044476 -151.582628)
		(width 0.13208)
		(layer "F.Cu")
		(net "NIC6_ADC_A0")
	)
	(segment
		(start 368.539776 -151.709628)
		(end 368.539776 -152.3111)
		(width 0.13208)
		(layer "F.Cu")
		(net "NIC6_ADC_A0")
	)
	(via
		(at 368.044476 -151.582628)
		(size 0.508)
		(drill 0.254)
		(layers "F.Cu" "B.Cu")
		(net "NIC6_ADC_A0")
	)
	(segment
		(start 368.044476 -151.582628)
		(end 367.057432 -152.569672)
		(width 0.13208)
		(layer "B.Cu")
		(net "NIC6_ADC_A0")
	)
	(segment
		(start 367.057432 -152.569672)
		(end 367.057432 -152.674066)
		(width 0.13208)
		(layer "B.Cu")
		(net "NIC6_ADC_A0")
	)
	(segment
		(start 439.355484 -97.567242)
		(end 439.609484 -97.821242)
		(width 0.13208)
		(layer "F.Cu")
		(net "NIC7_ADC_ALERT_N")
	)
	(segment
		(start 439.86196 -98.073718)
		(end 439.86196 -98.809302)
		(width 0.13208)
		(layer "F.Cu")
		(net "NIC7_ADC_ALERT_N")
	)
	(segment
		(start 439.609484 -97.821242)
		(end 439.86196 -98.073718)
		(width 0.13208)
		(layer "F.Cu")
		(net "NIC7_ADC_ALERT_N")
	)
	(segment
		(start 439.355484 -97.211642)
		(end 439.355484 -97.567242)
		(width 0.13208)
		(layer "F.Cu")
		(net "NIC7_ADC_ALERT_N")
	)
	(via
		(at 439.609484 -97.821242)
		(size 0.508)
		(drill 0.254)
		(layers "F.Cu" "B.Cu")
		(net "NIC7_ADC_ALERT_N")
	)
	(segment
		(start 328.973688 -227.941632)
		(end 328.700892 -228.214428)
		(width 0.13208)
		(layer "F.Cu")
		(net "PWRGD_P1V25_PEX0_R")
	)
	(segment
		(start 24.468582 -280.22931)
		(end 19.73072 -275.491448)
		(width 0.13208)
		(layer "F.Cu")
		(net "PWRGD_P1V25_PEX0_R")
	)
	(segment
		(start 11.736832 -233.99115)
		(end 11.532616 -233.786934)
		(width 0.13208)
		(layer "F.Cu")
		(net "PWRGD_P1V25_PEX0_R")
	)
	(segment
		(start 11.532616 -233.786934)
		(end 11.532616 -233.086402)
		(width 0.13208)
		(layer "F.Cu")
		(net "PWRGD_P1V25_PEX0_R")
	)
	(segment
		(start 11.532616 -233.086402)
		(end 11.845798 -232.77322)
		(width 0.13208)
		(layer "F.Cu")
		(net "PWRGD_P1V25_PEX0_R")
	)
	(segment
		(start 333.02956 -226.72294)
		(end 331.277722 -226.72294)
		(width 0.13208)
		(layer "F.Cu")
		(net "PWRGD_P1V25_PEX0_R")
	)
	(segment
		(start 17.33423 -307.861716)
		(end 18.80743 -307.861716)
		(width 0.13208)
		(layer "F.Cu")
		(net "PWRGD_P1V25_PEX0_R")
	)
	(segment
		(start 21.139912 -240.08588)
		(end 17.384522 -236.33049)
		(width 0.13208)
		(layer "F.Cu")
		(net "PWRGD_P1V25_PEX0_R")
	)
	(segment
		(start 19.73072 -245.54688)
		(end 21.139912 -244.137688)
		(width 0.13208)
		(layer "F.Cu")
		(net "PWRGD_P1V25_PEX0_R")
	)
	(segment
		(start 24.468582 -302.200564)
		(end 24.468582 -280.22931)
		(width 0.13208)
		(layer "F.Cu")
		(net "PWRGD_P1V25_PEX0_R")
	)
	(segment
		(start 333.769208 -225.983292)
		(end 333.02956 -226.72294)
		(width 0.13208)
		(layer "F.Cu")
		(net "PWRGD_P1V25_PEX0_R")
	)
	(segment
		(start 328.700892 -229.978966)
		(end 328.743056 -230.02113)
		(width 0.13208)
		(layer "F.Cu")
		(net "PWRGD_P1V25_PEX0_R")
	)
	(segment
		(start 331.277722 -226.72294)
		(end 330.05903 -227.941632)
		(width 0.13208)
		(layer "F.Cu")
		(net "PWRGD_P1V25_PEX0_R")
	)
	(segment
		(start 334.89392 -225.587052)
		(end 334.49768 -225.983292)
		(width 0.13208)
		(layer "F.Cu")
		(net "PWRGD_P1V25_PEX0_R")
	)
	(segment
		(start 330.05903 -227.941632)
		(end 328.973688 -227.941632)
		(width 0.13208)
		(layer "F.Cu")
		(net "PWRGD_P1V25_PEX0_R")
	)
	(segment
		(start 19.73072 -275.491448)
		(end 19.73072 -245.54688)
		(width 0.13208)
		(layer "F.Cu")
		(net "PWRGD_P1V25_PEX0_R")
	)
	(segment
		(start 17.384522 -236.33049)
		(end 11.736832 -233.99115)
		(width 0.13208)
		(layer "F.Cu")
		(net "PWRGD_P1V25_PEX0_R")
	)
	(segment
		(start 21.139912 -244.137688)
		(end 21.139912 -240.08588)
		(width 0.13208)
		(layer "F.Cu")
		(net "PWRGD_P1V25_PEX0_R")
	)
	(segment
		(start 328.700892 -228.214428)
		(end 328.700892 -229.978966)
		(width 0.13208)
		(layer "F.Cu")
		(net "PWRGD_P1V25_PEX0_R")
	)
	(segment
		(start 334.49768 -225.983292)
		(end 333.769208 -225.983292)
		(width 0.13208)
		(layer "F.Cu")
		(net "PWRGD_P1V25_PEX0_R")
	)
	(segment
		(start 11.845798 -232.77322)
		(end 12.300966 -232.77322)
		(width 0.13208)
		(layer "F.Cu")
		(net "PWRGD_P1V25_PEX0_R")
	)
	(segment
		(start 18.80743 -307.861716)
		(end 24.468582 -302.200564)
		(width 0.13208)
		(layer "F.Cu")
		(net "PWRGD_P1V25_PEX0_R")
	)
	(via
		(at 328.743056 -230.02113)
		(size 0.508)
		(drill 0.254)
		(layers "F.Cu" "B.Cu")
		(net "PWRGD_P1V25_PEX0_R")
	)
	(via
		(at 129.486914 -224.010728)
		(size 0.508)
		(drill 0.254)
		(layers "F.Cu" "B.Cu")
		(net "PWRGD_P1V25_PEX0_R")
	)
	(via
		(at 12.300966 -232.77322)
		(size 0.508)
		(drill 0.254)
		(layers "F.Cu" "B.Cu")
		(net "PWRGD_P1V25_PEX0_R")
	)
	(via
		(at 17.33423 -307.861716)
		(size 0.508)
		(drill 0.254)
		(layers "F.Cu" "B.Cu")
		(net "PWRGD_P1V25_PEX0_R")
	)
	(segment
		(start 17.42948 -307.956966)
		(end 17.42948 -310.135016)
		(width 0.13208)
		(layer "B.Cu")
		(net "PWRGD_P1V25_PEX0_R")
	)
	(segment
		(start 17.01038 -310.554116)
		(end 16.257778 -310.554116)
		(width 0.13208)
		(layer "B.Cu")
		(net "PWRGD_P1V25_PEX0_R")
	)
	(segment
		(start 17.42948 -310.135016)
		(end 17.01038 -310.554116)
		(width 0.13208)
		(layer "B.Cu")
		(net "PWRGD_P1V25_PEX0_R")
	)
	(segment
		(start 17.33423 -307.861716)
		(end 17.42948 -307.956966)
		(width 0.13208)
		(layer "B.Cu")
		(net "PWRGD_P1V25_PEX0_R")
	)
	(segment
		(start 62.624716 -211.39785)
		(end 63.237618 -212.010752)
		(width 0.15494)
		(layer "In13.Cu")
		(net "PWRGD_P1V25_PEX0_R")
	)
	(segment
		(start 12.300966 -232.77322)
		(end 13.716254 -232.77322)
		(width 0.15494)
		(layer "In13.Cu")
		(net "PWRGD_P1V25_PEX0_R")
	)
	(segment
		(start 63.237618 -212.010752)
		(end 71.01586 -212.010752)
		(width 0.15494)
		(layer "In13.Cu")
		(net "PWRGD_P1V25_PEX0_R")
	)
	(segment
		(start 124.518674 -224.010728)
		(end 129.486914 -224.010728)
		(width 0.15494)
		(layer "In13.Cu")
		(net "PWRGD_P1V25_PEX0_R")
	)
	(segment
		(start 98.425 -212.6742)
		(end 113.182146 -212.6742)
		(width 0.15494)
		(layer "In13.Cu")
		(net "PWRGD_P1V25_PEX0_R")
	)
	(segment
		(start 24.355806 -226.916488)
		(end 32.009588 -219.262706)
		(width 0.15494)
		(layer "In13.Cu")
		(net "PWRGD_P1V25_PEX0_R")
	)
	(segment
		(start 32.009588 -219.262706)
		(end 33.6296 -219.262706)
		(width 0.15494)
		(layer "In13.Cu")
		(net "PWRGD_P1V25_PEX0_R")
	)
	(segment
		(start 18.64487 -233.095038)
		(end 24.355806 -227.384102)
		(width 0.15494)
		(layer "In13.Cu")
		(net "PWRGD_P1V25_PEX0_R")
	)
	(segment
		(start 13.716254 -232.77322)
		(end 14.038072 -233.095038)
		(width 0.15494)
		(layer "In13.Cu")
		(net "PWRGD_P1V25_PEX0_R")
	)
	(segment
		(start 14.038072 -233.095038)
		(end 18.64487 -233.095038)
		(width 0.15494)
		(layer "In13.Cu")
		(net "PWRGD_P1V25_PEX0_R")
	)
	(segment
		(start 33.6296 -219.262706)
		(end 52.617116 -211.39785)
		(width 0.15494)
		(layer "In13.Cu")
		(net "PWRGD_P1V25_PEX0_R")
	)
	(segment
		(start 71.114412 -211.9122)
		(end 97.663 -211.9122)
		(width 0.15494)
		(layer "In13.Cu")
		(net "PWRGD_P1V25_PEX0_R")
	)
	(segment
		(start 97.663 -211.9122)
		(end 98.425 -212.6742)
		(width 0.15494)
		(layer "In13.Cu")
		(net "PWRGD_P1V25_PEX0_R")
	)
	(segment
		(start 71.01586 -212.010752)
		(end 71.114412 -211.9122)
		(width 0.15494)
		(layer "In13.Cu")
		(net "PWRGD_P1V25_PEX0_R")
	)
	(segment
		(start 52.617116 -211.39785)
		(end 62.624716 -211.39785)
		(width 0.15494)
		(layer "In13.Cu")
		(net "PWRGD_P1V25_PEX0_R")
	)
	(segment
		(start 113.182146 -212.6742)
		(end 124.518674 -224.010728)
		(width 0.15494)
		(layer "In13.Cu")
		(net "PWRGD_P1V25_PEX0_R")
	)
	(segment
		(start 24.355806 -227.384102)
		(end 24.355806 -226.916488)
		(width 0.15494)
		(layer "In13.Cu")
		(net "PWRGD_P1V25_PEX0_R")
	)
	(segment
		(start 240.497868 -229.69347)
		(end 245.932198 -224.25914)
		(width 0.15494)
		(layer "In15.Cu")
		(net "PWRGD_P1V25_PEX0_R")
	)
	(segment
		(start 326.29856 -229.266496)
		(end 327.053194 -230.02113)
		(width 0.15494)
		(layer "In15.Cu")
		(net "PWRGD_P1V25_PEX0_R")
	)
	(segment
		(start 266.483084 -224.597722)
		(end 267.310362 -225.425)
		(width 0.15494)
		(layer "In15.Cu")
		(net "PWRGD_P1V25_PEX0_R")
	)
	(segment
		(start 250.084336 -223.649794)
		(end 260.73354 -223.649794)
		(width 0.15494)
		(layer "In15.Cu")
		(net "PWRGD_P1V25_PEX0_R")
	)
	(segment
		(start 129.486914 -224.010728)
		(end 129.636774 -224.010728)
		(width 0.15494)
		(layer "In15.Cu")
		(net "PWRGD_P1V25_PEX0_R")
	)
	(segment
		(start 261.332472 -224.248726)
		(end 262.17499 -224.597722)
		(width 0.15494)
		(layer "In15.Cu")
		(net "PWRGD_P1V25_PEX0_R")
	)
	(segment
		(start 222.025972 -229.299008)
		(end 229.317296 -229.299008)
		(width 0.15494)
		(layer "In15.Cu")
		(net "PWRGD_P1V25_PEX0_R")
	)
	(segment
		(start 145.06194 -220.908118)
		(end 156.342588 -220.908118)
		(width 0.15494)
		(layer "In15.Cu")
		(net "PWRGD_P1V25_PEX0_R")
	)
	(segment
		(start 137.70102 -222.39097)
		(end 138.118342 -222.808292)
		(width 0.15494)
		(layer "In15.Cu")
		(net "PWRGD_P1V25_PEX0_R")
	)
	(segment
		(start 138.118342 -222.961454)
		(end 138.975084 -223.818196)
		(width 0.15494)
		(layer "In15.Cu")
		(net "PWRGD_P1V25_PEX0_R")
	)
	(segment
		(start 301.726346 -227.988876)
		(end 304.529998 -227.988876)
		(width 0.15494)
		(layer "In15.Cu")
		(net "PWRGD_P1V25_PEX0_R")
	)
	(segment
		(start 249.47499 -224.25914)
		(end 250.084336 -223.649794)
		(width 0.15494)
		(layer "In15.Cu")
		(net "PWRGD_P1V25_PEX0_R")
	)
	(segment
		(start 214.441024 -229.80142)
		(end 214.623904 -229.9843)
		(width 0.15494)
		(layer "In15.Cu")
		(net "PWRGD_P1V25_PEX0_R")
	)
	(segment
		(start 238.20247 -229.69347)
		(end 240.497868 -229.69347)
		(width 0.15494)
		(layer "In15.Cu")
		(net "PWRGD_P1V25_PEX0_R")
	)
	(segment
		(start 290.3474 -230.124)
		(end 291.47389 -228.99751)
		(width 0.15494)
		(layer "In15.Cu")
		(net "PWRGD_P1V25_PEX0_R")
	)
	(segment
		(start 186.5376 -226.949)
		(end 190.83909 -226.949)
		(width 0.15494)
		(layer "In15.Cu")
		(net "PWRGD_P1V25_PEX0_R")
	)
	(segment
		(start 185.039 -225.8822)
		(end 185.4708 -225.8822)
		(width 0.15494)
		(layer "In15.Cu")
		(net "PWRGD_P1V25_PEX0_R")
	)
	(segment
		(start 300.717712 -228.99751)
		(end 301.726346 -227.988876)
		(width 0.15494)
		(layer "In15.Cu")
		(net "PWRGD_P1V25_PEX0_R")
	)
	(segment
		(start 185.4708 -225.8822)
		(end 186.5376 -226.949)
		(width 0.15494)
		(layer "In15.Cu")
		(net "PWRGD_P1V25_PEX0_R")
	)
	(segment
		(start 160.567624 -225.133154)
		(end 184.289954 -225.133154)
		(width 0.15494)
		(layer "In15.Cu")
		(net "PWRGD_P1V25_PEX0_R")
	)
	(segment
		(start 193.69151 -229.80142)
		(end 214.441024 -229.80142)
		(width 0.15494)
		(layer "In15.Cu")
		(net "PWRGD_P1V25_PEX0_R")
	)
	(segment
		(start 305.642518 -229.101396)
		(end 323.232526 -229.101396)
		(width 0.15494)
		(layer "In15.Cu")
		(net "PWRGD_P1V25_PEX0_R")
	)
	(segment
		(start 129.636774 -224.010728)
		(end 130.594354 -223.053148)
		(width 0.15494)
		(layer "In15.Cu")
		(net "PWRGD_P1V25_PEX0_R")
	)
	(segment
		(start 130.594354 -223.053148)
		(end 134.587488 -223.053148)
		(width 0.15494)
		(layer "In15.Cu")
		(net "PWRGD_P1V25_PEX0_R")
	)
	(segment
		(start 142.653258 -223.3168)
		(end 145.06194 -220.908118)
		(width 0.15494)
		(layer "In15.Cu")
		(net "PWRGD_P1V25_PEX0_R")
	)
	(segment
		(start 141.096746 -223.3168)
		(end 142.653258 -223.3168)
		(width 0.15494)
		(layer "In15.Cu")
		(net "PWRGD_P1V25_PEX0_R")
	)
	(segment
		(start 245.932198 -224.25914)
		(end 249.47499 -224.25914)
		(width 0.15494)
		(layer "In15.Cu")
		(net "PWRGD_P1V25_PEX0_R")
	)
	(segment
		(start 134.587488 -223.053148)
		(end 135.249666 -222.39097)
		(width 0.15494)
		(layer "In15.Cu")
		(net "PWRGD_P1V25_PEX0_R")
	)
	(segment
		(start 221.34068 -229.9843)
		(end 222.025972 -229.299008)
		(width 0.15494)
		(layer "In15.Cu")
		(net "PWRGD_P1V25_PEX0_R")
	)
	(segment
		(start 156.342588 -220.908118)
		(end 160.567624 -225.133154)
		(width 0.15494)
		(layer "In15.Cu")
		(net "PWRGD_P1V25_PEX0_R")
	)
	(segment
		(start 235.2167 -229.253796)
		(end 237.762796 -229.253796)
		(width 0.15494)
		(layer "In15.Cu")
		(net "PWRGD_P1V25_PEX0_R")
	)
	(segment
		(start 229.961948 -228.654356)
		(end 234.61726 -228.654356)
		(width 0.15494)
		(layer "In15.Cu")
		(net "PWRGD_P1V25_PEX0_R")
	)
	(segment
		(start 214.623904 -229.9843)
		(end 221.34068 -229.9843)
		(width 0.15494)
		(layer "In15.Cu")
		(net "PWRGD_P1V25_PEX0_R")
	)
	(segment
		(start 323.397626 -229.266496)
		(end 326.29856 -229.266496)
		(width 0.15494)
		(layer "In15.Cu")
		(net "PWRGD_P1V25_PEX0_R")
	)
	(segment
		(start 237.762796 -229.253796)
		(end 238.20247 -229.69347)
		(width 0.15494)
		(layer "In15.Cu")
		(net "PWRGD_P1V25_PEX0_R")
	)
	(segment
		(start 184.289954 -225.133154)
		(end 185.039 -225.8822)
		(width 0.15494)
		(layer "In15.Cu")
		(net "PWRGD_P1V25_PEX0_R")
	)
	(segment
		(start 138.118342 -222.808292)
		(end 138.118342 -222.961454)
		(width 0.15494)
		(layer "In15.Cu")
		(net "PWRGD_P1V25_PEX0_R")
	)
	(segment
		(start 138.975084 -223.818196)
		(end 140.59535 -223.818196)
		(width 0.15494)
		(layer "In15.Cu")
		(net "PWRGD_P1V25_PEX0_R")
	)
	(segment
		(start 327.053194 -230.02113)
		(end 328.743056 -230.02113)
		(width 0.15494)
		(layer "In15.Cu")
		(net "PWRGD_P1V25_PEX0_R")
	)
	(segment
		(start 267.310362 -225.425)
		(end 267.54582 -225.425)
		(width 0.15494)
		(layer "In15.Cu")
		(net "PWRGD_P1V25_PEX0_R")
	)
	(segment
		(start 291.47389 -228.99751)
		(end 300.717712 -228.99751)
		(width 0.15494)
		(layer "In15.Cu")
		(net "PWRGD_P1V25_PEX0_R")
	)
	(segment
		(start 260.73354 -223.649794)
		(end 261.332472 -224.248726)
		(width 0.15494)
		(layer "In15.Cu")
		(net "PWRGD_P1V25_PEX0_R")
	)
	(segment
		(start 190.83909 -226.949)
		(end 193.69151 -229.80142)
		(width 0.15494)
		(layer "In15.Cu")
		(net "PWRGD_P1V25_PEX0_R")
	)
	(segment
		(start 323.232526 -229.101396)
		(end 323.397626 -229.266496)
		(width 0.15494)
		(layer "In15.Cu")
		(net "PWRGD_P1V25_PEX0_R")
	)
	(segment
		(start 267.54582 -225.425)
		(end 272.24482 -230.124)
		(width 0.15494)
		(layer "In15.Cu")
		(net "PWRGD_P1V25_PEX0_R")
	)
	(segment
		(start 135.249666 -222.39097)
		(end 137.70102 -222.39097)
		(width 0.15494)
		(layer "In15.Cu")
		(net "PWRGD_P1V25_PEX0_R")
	)
	(segment
		(start 262.17499 -224.597722)
		(end 266.483084 -224.597722)
		(width 0.15494)
		(layer "In15.Cu")
		(net "PWRGD_P1V25_PEX0_R")
	)
	(segment
		(start 304.529998 -227.988876)
		(end 305.642518 -229.101396)
		(width 0.15494)
		(layer "In15.Cu")
		(net "PWRGD_P1V25_PEX0_R")
	)
	(segment
		(start 234.61726 -228.654356)
		(end 235.2167 -229.253796)
		(width 0.15494)
		(layer "In15.Cu")
		(net "PWRGD_P1V25_PEX0_R")
	)
	(segment
		(start 272.24482 -230.124)
		(end 290.3474 -230.124)
		(width 0.15494)
		(layer "In15.Cu")
		(net "PWRGD_P1V25_PEX0_R")
	)
	(segment
		(start 229.317296 -229.299008)
		(end 229.961948 -228.654356)
		(width 0.15494)
		(layer "In15.Cu")
		(net "PWRGD_P1V25_PEX0_R")
	)
	(segment
		(start 140.59535 -223.818196)
		(end 141.096746 -223.3168)
		(width 0.15494)
		(layer "In15.Cu")
		(net "PWRGD_P1V25_PEX0_R")
	)
	(segment
		(start 323.26199 -98.809302)
		(end 323.26199 -98.444812)
		(width 0.13208)
		(layer "F.Cu")
		(net "NIC5_ADC_A0")
	)
	(segment
		(start 323.26199 -98.444812)
		(end 322.63842 -97.821242)
		(width 0.13208)
		(layer "F.Cu")
		(net "NIC5_ADC_A0")
	)
	(segment
		(start 321.223386 -97.211642)
		(end 322.239386 -97.211642)
		(width 0.13208)
		(layer "F.Cu")
		(net "NIC5_ADC_A0")
	)
	(segment
		(start 322.239386 -97.821242)
		(end 322.239386 -97.211642)
		(width 0.13208)
		(layer "F.Cu")
		(net "NIC5_ADC_A0")
	)
	(segment
		(start 322.63842 -97.821242)
		(end 322.239386 -97.821242)
		(width 0.13208)
		(layer "F.Cu")
		(net "NIC5_ADC_A0")
	)
	(via
		(at 322.239386 -97.821242)
		(size 0.508)
		(drill 0.254)
		(layers "F.Cu" "B.Cu")
		(net "NIC5_ADC_A0")
	)
	(via
		(at 438.189116 -103.13924)
		(size 0.508)
		(drill 0.254)
		(layers "F.Cu" "B.Cu")
		(net "P12V_NIC7_VIN_N")
	)
	(segment
		(start 13.537946 -272.481294)
		(end 14.147546 -272.481294)
		(width 0.4572)
		(layer "F.Cu")
		(net "P1V25_PEX0_R")
	)
	(via
		(at 6.736334 -279.73909)
		(size 0.508)
		(drill 0.254)
		(layers "F.Cu" "B.Cu")
		(net "P1V25_PEX0_R")
	)
	(via
		(at 6.267196 -284.818582)
		(size 0.508)
		(drill 0.254)
		(layers "F.Cu" "B.Cu")
		(net "P1V25_PEX0_R")
	)
	(via
		(at 7.396734 -279.73909)
		(size 0.508)
		(drill 0.254)
		(layers "F.Cu" "B.Cu")
		(net "P1V25_PEX0_R")
	)
	(via
		(at 5.415534 -279.73909)
		(size 0.508)
		(drill 0.254)
		(layers "F.Cu" "B.Cu")
		(net "P1V25_PEX0_R")
	)
	(via
		(at 11.394186 -283.1592)
		(size 0.508)
		(drill 0.254)
		(layers "F.Cu" "B.Cu")
		(net "P1V25_PEX0_R")
	)
	(via
		(at 12.34059 -285.462218)
		(size 0.508)
		(drill 0.254)
		(layers "F.Cu" "B.Cu")
		(net "P1V25_PEX0_R")
	)
	(via
		(at 14.147546 -272.481294)
		(size 0.508)
		(drill 0.254)
		(layers "F.Cu" "B.Cu")
		(net "P1V25_PEX0_R")
	)
	(via
		(at 5.387086 -289.23107)
		(size 0.508)
		(drill 0.254)
		(layers "F.Cu" "B.Cu")
		(net "P1V25_PEX0_R")
	)
	(via
		(at 7.587996 -284.818582)
		(size 0.508)
		(drill 0.254)
		(layers "F.Cu" "B.Cu")
		(net "P1V25_PEX0_R")
	)
	(via
		(at 6.267196 -282.354782)
		(size 0.508)
		(drill 0.254)
		(layers "F.Cu" "B.Cu")
		(net "P1V25_PEX0_R")
	)
	(via
		(at 6.075934 -279.73909)
		(size 0.508)
		(drill 0.254)
		(layers "F.Cu" "B.Cu")
		(net "P1V25_PEX0_R")
	)
	(via
		(at 6.736334 -279.087326)
		(size 0.508)
		(drill 0.254)
		(layers "F.Cu" "B.Cu")
		(net "P1V25_PEX0_R")
	)
	(via
		(at 12.079986 -283.1592)
		(size 0.508)
		(drill 0.254)
		(layers "F.Cu" "B.Cu")
		(net "P1V25_PEX0_R")
	)
	(via
		(at 5.581396 -287.104582)
		(size 0.508)
		(drill 0.254)
		(layers "F.Cu" "B.Cu")
		(net "P1V25_PEX0_R")
	)
	(via
		(at 12.079986 -280.6954)
		(size 0.508)
		(drill 0.254)
		(layers "F.Cu" "B.Cu")
		(net "P1V25_PEX0_R")
	)
	(via
		(at 10.073386 -283.1592)
		(size 0.508)
		(drill 0.254)
		(layers "F.Cu" "B.Cu")
		(net "P1V25_PEX0_R")
	)
	(via
		(at 6.927596 -284.818582)
		(size 0.508)
		(drill 0.254)
		(layers "F.Cu" "B.Cu")
		(net "P1V25_PEX0_R")
	)
	(via
		(at 6.927596 -282.354782)
		(size 0.508)
		(drill 0.254)
		(layers "F.Cu" "B.Cu")
		(net "P1V25_PEX0_R")
	)
	(via
		(at 7.587996 -282.354782)
		(size 0.508)
		(drill 0.254)
		(layers "F.Cu" "B.Cu")
		(net "P1V25_PEX0_R")
	)
	(via
		(at 8.273796 -282.354782)
		(size 0.508)
		(drill 0.254)
		(layers "F.Cu" "B.Cu")
		(net "P1V25_PEX0_R")
	)
	(via
		(at 10.073386 -280.6954)
		(size 0.508)
		(drill 0.254)
		(layers "F.Cu" "B.Cu")
		(net "P1V25_PEX0_R")
	)
	(via
		(at 12.965938 -287.956752)
		(size 0.508)
		(drill 0.254)
		(layers "F.Cu" "B.Cu")
		(net "P1V25_PEX0_R")
	)
	(via
		(at 8.273796 -284.818582)
		(size 0.508)
		(drill 0.254)
		(layers "F.Cu" "B.Cu")
		(net "P1V25_PEX0_R")
	)
	(via
		(at 6.022086 -289.23107)
		(size 0.508)
		(drill 0.254)
		(layers "F.Cu" "B.Cu")
		(net "P1V25_PEX0_R")
	)
	(via
		(at 11.394186 -280.6954)
		(size 0.508)
		(drill 0.254)
		(layers "F.Cu" "B.Cu")
		(net "P1V25_PEX0_R")
	)
	(via
		(at 12.330938 -287.956752)
		(size 0.508)
		(drill 0.254)
		(layers "F.Cu" "B.Cu")
		(net "P1V25_PEX0_R")
	)
	(via
		(at 6.267196 -287.104582)
		(size 0.508)
		(drill 0.254)
		(layers "F.Cu" "B.Cu")
		(net "P1V25_PEX0_R")
	)
	(via
		(at 5.415534 -279.087326)
		(size 0.508)
		(drill 0.254)
		(layers "F.Cu" "B.Cu")
		(net "P1V25_PEX0_R")
	)
	(via
		(at 10.733786 -283.1592)
		(size 0.508)
		(drill 0.254)
		(layers "F.Cu" "B.Cu")
		(net "P1V25_PEX0_R")
	)
	(via
		(at 10.733786 -280.6954)
		(size 0.508)
		(drill 0.254)
		(layers "F.Cu" "B.Cu")
		(net "P1V25_PEX0_R")
	)
	(via
		(at 6.075934 -279.087326)
		(size 0.508)
		(drill 0.254)
		(layers "F.Cu" "B.Cu")
		(net "P1V25_PEX0_R")
	)
	(via
		(at 7.396734 -279.087326)
		(size 0.508)
		(drill 0.254)
		(layers "F.Cu" "B.Cu")
		(net "P1V25_PEX0_R")
	)
	(segment
		(start 438.738518 -97.821242)
		(end 439.362088 -98.444812)
		(width 0.13208)
		(layer "F.Cu")
		(net "NIC7_ADC_A0")
	)
	(segment
		(start 438.339484 -97.821242)
		(end 438.738518 -97.821242)
		(width 0.13208)
		(layer "F.Cu")
		(net "NIC7_ADC_A0")
	)
	(segment
		(start 437.323484 -97.211642)
		(end 438.339484 -97.211642)
		(width 0.13208)
		(layer "F.Cu")
		(net "NIC7_ADC_A0")
	)
	(segment
		(start 442.403484 -96.411542)
		(end 442.403484 -95.801942)
		(width 0.13208)
		(layer "F.Cu")
		(net "NIC7_ADC_A0")
	)
	(segment
		(start 438.339484 -97.211642)
		(end 438.339484 -97.821242)
		(width 0.13208)
		(layer "F.Cu")
		(net "NIC7_ADC_A0")
	)
	(segment
		(start 439.362088 -98.444812)
		(end 439.362088 -98.809302)
		(width 0.13208)
		(layer "F.Cu")
		(net "NIC7_ADC_A0")
	)
	(via
		(at 442.403484 -95.801942)
		(size 0.508)
		(drill 0.254)
		(layers "F.Cu" "B.Cu")
		(net "NIC7_ADC_A0")
	)
	(via
		(at 438.339484 -97.821242)
		(size 0.508)
		(drill 0.254)
		(layers "F.Cu" "B.Cu")
		(net "NIC7_ADC_A0")
	)
	(segment
		(start 441.433458 -96.771968)
		(end 442.403484 -95.801942)
		(width 0.13208)
		(layer "B.Cu")
		(net "NIC7_ADC_A0")
	)
	(segment
		(start 439.388758 -96.771968)
		(end 441.433458 -96.771968)
		(width 0.13208)
		(layer "B.Cu")
		(net "NIC7_ADC_A0")
	)
	(segment
		(start 438.339484 -97.821242)
		(end 439.388758 -96.771968)
		(width 0.13208)
		(layer "B.Cu")
		(net "NIC7_ADC_A0")
	)
	(segment
		(start 241.508026 -210.889596)
		(end 241.514376 -210.895946)
		(width 0.2032)
		(layer "F.Cu")
		(net "P3V3_SCALED")
	)
	(segment
		(start 235.71073 -213.903052)
		(end 236.549438 -213.064344)
		(width 0.2032)
		(layer "F.Cu")
		(net "P3V3_SCALED")
	)
	(segment
		(start 235.068618 -213.903052)
		(end 235.71073 -213.903052)
		(width 0.127)
		(layer "F.Cu")
		(net "P3V3_SCALED")
	)
	(segment
		(start 240.03889 -210.866228)
		(end 239.577372 -210.866228)
		(width 0.2032)
		(layer "F.Cu")
		(net "P3V3_SCALED")
	)
	(segment
		(start 237.959138 -213.064344)
		(end 238.46028 -212.563202)
		(width 0.2032)
		(layer "F.Cu")
		(net "P3V3_SCALED")
	)
	(segment
		(start 236.549438 -213.064344)
		(end 237.959138 -213.064344)
		(width 0.2032)
		(layer "F.Cu")
		(net "P3V3_SCALED")
	)
	(segment
		(start 240.03889 -210.866228)
		(end 241.02949 -210.866228)
		(width 0.2032)
		(layer "F.Cu")
		(net "P3V3_SCALED")
	)
	(segment
		(start 239.268 -211.1756)
		(end 239.268 -211.755482)
		(width 0.2032)
		(layer "F.Cu")
		(net "P3V3_SCALED")
	)
	(segment
		(start 241.514376 -210.895946)
		(end 241.983768 -210.895946)
		(width 0.2032)
		(layer "F.Cu")
		(net "P3V3_SCALED")
	)
	(segment
		(start 239.577372 -210.866228)
		(end 239.268 -211.1756)
		(width 0.2032)
		(layer "F.Cu")
		(net "P3V3_SCALED")
	)
	(segment
		(start 239.268 -211.755482)
		(end 238.46028 -212.563202)
		(width 0.2032)
		(layer "F.Cu")
		(net "P3V3_SCALED")
	)
	(segment
		(start 234.667552 -214.304118)
		(end 235.068618 -213.903052)
		(width 0.2032)
		(layer "F.Cu")
		(net "P3V3_SCALED")
	)
	(segment
		(start 241.02949 -210.866228)
		(end 241.052858 -210.889596)
		(width 0.2032)
		(layer "F.Cu")
		(net "P3V3_SCALED")
	)
	(segment
		(start 241.052858 -210.889596)
		(end 241.508026 -210.889596)
		(width 0.2032)
		(layer "F.Cu")
		(net "P3V3_SCALED")
	)
	(segment
		(start 241.983768 -210.895946)
		(end 242.006882 -210.872832)
		(width 0.2032)
		(layer "F.Cu")
		(net "P3V3_SCALED")
	)
	(via
		(at 238.46028 -212.563202)
		(size 0.762)
		(drill 0.381)
		(layers "F.Cu" "B.Cu")
		(net "P3V3_SCALED")
	)
	(segment
		(start 326.303386 -97.678494)
		(end 326.303386 -97.211642)
		(width 0.13208)
		(layer "F.Cu")
		(net "SMB_NIC5_ADC_SCL")
	)
	(segment
		(start 324.911974 -99.459288)
		(end 326.21982 -99.459288)
		(width 0.13208)
		(layer "F.Cu")
		(net "SMB_NIC5_ADC_SCL")
	)
	(segment
		(start 326.220582 -99.458526)
		(end 326.220582 -97.761298)
		(width 0.13208)
		(layer "F.Cu")
		(net "SMB_NIC5_ADC_SCL")
	)
	(segment
		(start 326.21982 -99.459288)
		(end 326.220582 -99.458526)
		(width 0.13208)
		(layer "F.Cu")
		(net "SMB_NIC5_ADC_SCL")
	)
	(segment
		(start 326.220582 -97.761298)
		(end 326.303386 -97.678494)
		(width 0.13208)
		(layer "F.Cu")
		(net "SMB_NIC5_ADC_SCL")
	)
	(via
		(at 326.220582 -99.458526)
		(size 0.508)
		(drill 0.254)
		(layers "F.Cu" "B.Cu")
		(net "SMB_NIC5_ADC_SCL")
	)
	(segment
		(start 240.317528 -209.964528)
		(end 239.14989 -209.964528)
		(width 0.2032)
		(layer "F.Cu")
		(net "P5V_AUX_SCALED")
	)
	(segment
		(start 238.7854 -210.9978)
		(end 238.0234 -211.7598)
		(width 0.2032)
		(layer "F.Cu")
		(net "P5V_AUX_SCALED")
	)
	(segment
		(start 241.38509 -209.913728)
		(end 241.139218 -210.1596)
		(width 0.2032)
		(layer "F.Cu")
		(net "P5V_AUX_SCALED")
	)
	(segment
		(start 238.0234 -211.7598)
		(end 237.212124 -211.7598)
		(width 0.2032)
		(layer "F.Cu")
		(net "P5V_AUX_SCALED")
	)
	(segment
		(start 240.5126 -210.1596)
		(end 240.317528 -209.964528)
		(width 0.2032)
		(layer "F.Cu")
		(net "P5V_AUX_SCALED")
	)
	(segment
		(start 238.15929 -209.964528)
		(end 239.14989 -209.964528)
		(width 0.2032)
		(layer "F.Cu")
		(net "P5V_AUX_SCALED")
	)
	(segment
		(start 238.7854 -210.9978)
		(end 238.15929 -210.37169)
		(width 0.2032)
		(layer "F.Cu")
		(net "P5V_AUX_SCALED")
	)
	(segment
		(start 237.212124 -211.7598)
		(end 235.467652 -213.504272)
		(width 0.2032)
		(layer "F.Cu")
		(net "P5V_AUX_SCALED")
	)
	(segment
		(start 241.139218 -210.1596)
		(end 240.5126 -210.1596)
		(width 0.2032)
		(layer "F.Cu")
		(net "P5V_AUX_SCALED")
	)
	(segment
		(start 238.15929 -210.37169)
		(end 238.15929 -209.964528)
		(width 0.2032)
		(layer "F.Cu")
		(net "P5V_AUX_SCALED")
	)
	(via
		(at 238.7854 -210.9978)
		(size 0.508)
		(drill 0.254)
		(layers "F.Cu" "B.Cu")
		(net "P5V_AUX_SCALED")
	)
	(segment
		(start 252.439678 -151.709628)
		(end 252.312678 -151.582628)
		(width 0.13208)
		(layer "F.Cu")
		(net "NIC4_ADC_A0")
	)
	(segment
		(start 252.439678 -152.3111)
		(end 252.439678 -151.709628)
		(width 0.13208)
		(layer "F.Cu")
		(net "NIC4_ADC_A0")
	)
	(segment
		(start 251.944378 -151.582628)
		(end 251.507498 -151.582628)
		(width 0.13208)
		(layer "F.Cu")
		(net "NIC4_ADC_A0")
	)
	(segment
		(start 251.507498 -151.582628)
		(end 251.118624 -151.193754)
		(width 0.13208)
		(layer "F.Cu")
		(net "NIC4_ADC_A0")
	)
	(segment
		(start 251.423678 -152.3111)
		(end 252.439678 -152.3111)
		(width 0.13208)
		(layer "F.Cu")
		(net "NIC4_ADC_A0")
	)
	(segment
		(start 251.118624 -151.193754)
		(end 251.118624 -150.71344)
		(width 0.13208)
		(layer "F.Cu")
		(net "NIC4_ADC_A0")
	)
	(segment
		(start 252.312678 -151.582628)
		(end 251.944378 -151.582628)
		(width 0.13208)
		(layer "F.Cu")
		(net "NIC4_ADC_A0")
	)
	(via
		(at 251.944378 -151.582628)
		(size 0.508)
		(drill 0.254)
		(layers "F.Cu" "B.Cu")
		(net "NIC4_ADC_A0")
	)
	(segment
		(start 240.96091 -214.523828)
		(end 241.482372 -215.04529)
		(width 0.2032)
		(layer "F.Cu")
		(net "P3V3_AUX_SCALED")
	)
	(segment
		(start 235.467652 -214.304118)
		(end 236.224572 -214.304118)
		(width 0.2032)
		(layer "F.Cu")
		(net "P3V3_AUX_SCALED")
	)
	(segment
		(start 241.482372 -215.04529)
		(end 242.430808 -215.04529)
		(width 0.2032)
		(layer "F.Cu")
		(net "P3V3_AUX_SCALED")
	)
	(segment
		(start 237.363 -214.9094)
		(end 237.748572 -214.523828)
		(width 0.2032)
		(layer "F.Cu")
		(net "P3V3_AUX_SCALED")
	)
	(segment
		(start 237.748572 -214.523828)
		(end 238.469932 -214.523828)
		(width 0.2032)
		(layer "F.Cu")
		(net "P3V3_AUX_SCALED")
	)
	(segment
		(start 239.70869 -214.523828)
		(end 240.96091 -214.523828)
		(width 0.2032)
		(layer "F.Cu")
		(net "P3V3_AUX_SCALED")
	)
	(segment
		(start 238.469932 -214.523828)
		(end 239.70869 -214.523828)
		(width 0.2032)
		(layer "F.Cu")
		(net "P3V3_AUX_SCALED")
	)
	(segment
		(start 236.224572 -214.304118)
		(end 236.829854 -214.9094)
		(width 0.2032)
		(layer "F.Cu")
		(net "P3V3_AUX_SCALED")
	)
	(segment
		(start 236.829854 -214.9094)
		(end 237.363 -214.9094)
		(width 0.2032)
		(layer "F.Cu")
		(net "P3V3_AUX_SCALED")
	)
	(segment
		(start 242.430808 -215.04529)
		(end 242.438428 -215.05291)
		(width 0.2032)
		(layer "F.Cu")
		(net "P3V3_AUX_SCALED")
	)
	(via
		(at 238.469932 -214.523828)
		(size 0.762)
		(drill 0.381)
		(layers "F.Cu" "B.Cu")
		(net "P3V3_AUX_SCALED")
	)
	(segment
		(start 436.307484 -97.236026)
		(end 436.307484 -97.211642)
		(width 0.13208)
		(layer "F.Cu")
		(net "NIC7_ADC_A1")
	)
	(segment
		(start 438.861962 -98.578162)
		(end 438.607454 -98.323654)
		(width 0.13208)
		(layer "F.Cu")
		(net "NIC7_ADC_A1")
	)
	(segment
		(start 437.025034 -97.953576)
		(end 436.307484 -97.236026)
		(width 0.13208)
		(layer "F.Cu")
		(net "NIC7_ADC_A1")
	)
	(segment
		(start 438.861962 -98.809302)
		(end 438.861962 -98.578162)
		(width 0.13208)
		(layer "F.Cu")
		(net "NIC7_ADC_A1")
	)
	(segment
		(start 437.395112 -98.323654)
		(end 437.025034 -97.953576)
		(width 0.13208)
		(layer "F.Cu")
		(net "NIC7_ADC_A1")
	)
	(segment
		(start 435.291484 -97.211642)
		(end 436.307484 -97.211642)
		(width 0.13208)
		(layer "F.Cu")
		(net "NIC7_ADC_A1")
	)
	(segment
		(start 438.607454 -98.323654)
		(end 437.395112 -98.323654)
		(width 0.13208)
		(layer "F.Cu")
		(net "NIC7_ADC_A1")
	)
	(via
		(at 437.025034 -97.953576)
		(size 0.508)
		(drill 0.254)
		(layers "F.Cu" "B.Cu")
		(net "NIC7_ADC_A1")
	)
	(segment
		(start 244.847364 -274.768056)
		(end 245.456964 -274.768056)
		(width 0.4572)
		(layer "F.Cu")
		(net "P1V25_PEX2_R")
	)
	(via
		(at 242.043204 -285.445962)
		(size 0.508)
		(drill 0.254)
		(layers "F.Cu" "B.Cu")
		(net "P1V25_PEX2_R")
	)
	(via
		(at 241.382804 -285.445962)
		(size 0.508)
		(drill 0.254)
		(layers "F.Cu" "B.Cu")
		(net "P1V25_PEX2_R")
	)
	(via
		(at 239.583214 -287.105344)
		(size 0.508)
		(drill 0.254)
		(layers "F.Cu" "B.Cu")
		(net "P1V25_PEX2_R")
	)
	(via
		(at 243.650008 -287.74898)
		(size 0.508)
		(drill 0.254)
		(layers "F.Cu" "B.Cu")
		(net "P1V25_PEX2_R")
	)
	(via
		(at 236.728 -291.517832)
		(size 0.508)
		(drill 0.254)
		(layers "F.Cu" "B.Cu")
		(net "P1V25_PEX2_R")
	)
	(via
		(at 238.237014 -287.105344)
		(size 0.508)
		(drill 0.254)
		(layers "F.Cu" "B.Cu")
		(net "P1V25_PEX2_R")
	)
	(via
		(at 243.719096 -290.872926)
		(size 0.508)
		(drill 0.254)
		(layers "F.Cu" "B.Cu")
		(net "P1V25_PEX2_R")
	)
	(via
		(at 238.897414 -287.105344)
		(size 0.508)
		(drill 0.254)
		(layers "F.Cu" "B.Cu")
		(net "P1V25_PEX2_R")
	)
	(via
		(at 242.06454 -288.055812)
		(size 0.6604)
		(drill 0.3302)
		(layers "F.Cu" "B.Cu")
		(net "P1V25_PEX2_R")
	)
	(via
		(at 242.964208 -287.74898)
		(size 0.508)
		(drill 0.254)
		(layers "F.Cu" "B.Cu")
		(net "P1V25_PEX2_R")
	)
	(via
		(at 238.237014 -284.641544)
		(size 0.508)
		(drill 0.254)
		(layers "F.Cu" "B.Cu")
		(net "P1V25_PEX2_R")
	)
	(via
		(at 241.382804 -282.982162)
		(size 0.508)
		(drill 0.254)
		(layers "F.Cu" "B.Cu")
		(net "P1V25_PEX2_R")
	)
	(via
		(at 245.456964 -274.768056)
		(size 0.508)
		(drill 0.254)
		(layers "F.Cu" "B.Cu")
		(net "P1V25_PEX2_R")
	)
	(via
		(at 237.576614 -289.391344)
		(size 0.508)
		(drill 0.254)
		(layers "F.Cu" "B.Cu")
		(net "P1V25_PEX2_R")
	)
	(via
		(at 243.389404 -282.982162)
		(size 0.508)
		(drill 0.254)
		(layers "F.Cu" "B.Cu")
		(net "P1V25_PEX2_R")
	)
	(via
		(at 237.363 -291.517832)
		(size 0.508)
		(drill 0.254)
		(layers "F.Cu" "B.Cu")
		(net "P1V25_PEX2_R")
	)
	(via
		(at 236.890814 -289.391344)
		(size 0.508)
		(drill 0.254)
		(layers "F.Cu" "B.Cu")
		(net "P1V25_PEX2_R")
	)
	(via
		(at 242.043204 -282.982162)
		(size 0.508)
		(drill 0.254)
		(layers "F.Cu" "B.Cu")
		(net "P1V25_PEX2_R")
	)
	(via
		(at 244.354096 -290.872926)
		(size 0.508)
		(drill 0.254)
		(layers "F.Cu" "B.Cu")
		(net "P1V25_PEX2_R")
	)
	(via
		(at 242.703604 -282.982162)
		(size 0.508)
		(drill 0.254)
		(layers "F.Cu" "B.Cu")
		(net "P1V25_PEX2_R")
	)
	(via
		(at 242.703604 -285.445962)
		(size 0.508)
		(drill 0.254)
		(layers "F.Cu" "B.Cu")
		(net "P1V25_PEX2_R")
	)
	(via
		(at 237.576614 -284.641544)
		(size 0.508)
		(drill 0.254)
		(layers "F.Cu" "B.Cu")
		(net "P1V25_PEX2_R")
	)
	(via
		(at 237.576614 -287.105344)
		(size 0.508)
		(drill 0.254)
		(layers "F.Cu" "B.Cu")
		(net "P1V25_PEX2_R")
	)
	(via
		(at 238.897414 -284.641544)
		(size 0.508)
		(drill 0.254)
		(layers "F.Cu" "B.Cu")
		(net "P1V25_PEX2_R")
	)
	(via
		(at 244.41277 -288.652204)
		(size 0.508)
		(drill 0.254)
		(layers "F.Cu" "B.Cu")
		(net "P1V25_PEX2_R")
	)
	(via
		(at 239.583214 -284.641544)
		(size 0.508)
		(drill 0.254)
		(layers "F.Cu" "B.Cu")
		(net "P1V25_PEX2_R")
	)
	(via
		(at 243.389404 -285.445962)
		(size 0.508)
		(drill 0.254)
		(layers "F.Cu" "B.Cu")
		(net "P1V25_PEX2_R")
	)
	(via
		(at 242.301776 -291.552376)
		(size 0.6604)
		(drill 0.3302)
		(layers "F.Cu" "B.Cu")
		(net "P1V25_PEX2_R")
	)
	(via
		(at 320.352674 -101.579172)
		(size 0.508)
		(drill 0.254)
		(layers "F.Cu" "B.Cu")
		(net "P12V_NIC5_VIN_P")
	)
	(segment
		(start 252.570996 -146.541998)
		(end 252.570996 -146.205956)
		(width 0.254)
		(layer "F.Cu")
		(net "P12V_NIC4_VIN_N")
	)
	(segment
		(start 251.61875 -147.494244)
		(end 252.198124 -146.91487)
		(width 0.254)
		(layer "F.Cu")
		(net "P12V_NIC4_VIN_N")
	)
	(segment
		(start 251.61875 -147.913344)
		(end 251.61875 -147.494244)
		(width 0.254)
		(layer "F.Cu")
		(net "P12V_NIC4_VIN_N")
	)
	(segment
		(start 252.570996 -145.189956)
		(end 252.570996 -146.205956)
		(width 0.254)
		(layer "F.Cu")
		(net "P12V_NIC4_VIN_N")
	)
	(segment
		(start 252.198124 -146.91487)
		(end 252.570996 -146.541998)
		(width 0.254)
		(layer "F.Cu")
		(net "P12V_NIC4_VIN_N")
	)
	(via
		(at 252.198124 -146.91487)
		(size 0.508)
		(drill 0.254)
		(layers "F.Cu" "B.Cu")
		(net "P12V_NIC4_VIN_N")
	)
	(segment
		(start 233.867706 -215.104218)
		(end 234.267502 -214.704422)
		(width 0.2032)
		(layer "F.Cu")
		(net "P1V2_AUX_SCALED")
	)
	(via
		(at 234.267502 -214.704422)
		(size 0.4572)
		(drill 0.254)
		(layers "F.Cu" "B.Cu")
		(net "P1V2_AUX_SCALED")
	)
	(via
		(at 234.968288 -213.875874)
		(size 0.6604)
		(drill 0.3302)
		(layers "F.Cu" "B.Cu")
		(net "P1V2_AUX_SCALED")
	)
	(segment
		(start 235.756958 -212.949282)
		(end 235.54055 -212.732874)
		(width 0.2032)
		(layer "B.Cu")
		(net "P1V2_AUX_SCALED")
	)
	(segment
		(start 235.14177 -213.702392)
		(end 234.968288 -213.875874)
		(width 0.2032)
		(layer "B.Cu")
		(net "P1V2_AUX_SCALED")
	)
	(segment
		(start 234.802426 -214.169498)
		(end 234.267502 -214.704422)
		(width 0.2032)
		(layer "B.Cu")
		(net "P1V2_AUX_SCALED")
	)
	(segment
		(start 235.14177 -212.732874)
		(end 235.14177 -213.702392)
		(width 0.2032)
		(layer "B.Cu")
		(net "P1V2_AUX_SCALED")
	)
	(segment
		(start 234.802426 -214.041736)
		(end 234.802426 -214.169498)
		(width 0.2032)
		(layer "B.Cu")
		(net "P1V2_AUX_SCALED")
	)
	(segment
		(start 236.289088 -212.949282)
		(end 235.756958 -212.949282)
		(width 0.2032)
		(layer "B.Cu")
		(net "P1V2_AUX_SCALED")
	)
	(segment
		(start 237.521496 -212.732874)
		(end 236.505496 -212.732874)
		(width 0.2032)
		(layer "B.Cu")
		(net "P1V2_AUX_SCALED")
	)
	(segment
		(start 235.54055 -212.732874)
		(end 235.14177 -212.732874)
		(width 0.2032)
		(layer "B.Cu")
		(net "P1V2_AUX_SCALED")
	)
	(segment
		(start 234.968288 -213.875874)
		(end 234.802426 -214.041736)
		(width 0.2032)
		(layer "B.Cu")
		(net "P1V2_AUX_SCALED")
	)
	(segment
		(start 236.505496 -212.732874)
		(end 236.289088 -212.949282)
		(width 0.2032)
		(layer "B.Cu")
		(net "P1V2_AUX_SCALED")
	)
	(segment
		(start 338.093812 -222.38716)
		(end 337.694016 -222.786956)
		(width 0.13208)
		(layer "F.Cu")
		(net "PWRGD_P1V25_PEX2_R")
	)
	(via
		(at 248.454926 -310.202072)
		(size 0.508)
		(drill 0.254)
		(layers "F.Cu" "B.Cu")
		(net "PWRGD_P1V25_PEX2_R")
	)
	(via
		(at 234.938824 -252.557534)
		(size 0.508)
		(drill 0.254)
		(layers "F.Cu" "B.Cu")
		(net "PWRGD_P1V25_PEX2_R")
	)
	(via
		(at 265.5062 -221.577408)
		(size 0.508)
		(drill 0.254)
		(layers "F.Cu" "B.Cu")
		(net "PWRGD_P1V25_PEX2_R")
	)
	(via
		(at 337.694016 -222.786956)
		(size 0.4572)
		(drill 0.254)
		(layers "F.Cu" "B.Cu")
		(net "PWRGD_P1V25_PEX2_R")
	)
	(segment
		(start 248.163588 -312.834528)
		(end 246.804688 -312.834528)
		(width 0.13208)
		(layer "B.Cu")
		(net "PWRGD_P1V25_PEX2_R")
	)
	(segment
		(start 248.323862 -312.674254)
		(end 248.163588 -312.834528)
		(width 0.13208)
		(layer "B.Cu")
		(net "PWRGD_P1V25_PEX2_R")
	)
	(segment
		(start 248.323862 -310.333136)
		(end 248.323862 -312.674254)
		(width 0.13208)
		(layer "B.Cu")
		(net "PWRGD_P1V25_PEX2_R")
	)
	(segment
		(start 248.454926 -310.202072)
		(end 248.323862 -310.333136)
		(width 0.13208)
		(layer "B.Cu")
		(net "PWRGD_P1V25_PEX2_R")
	)
	(segment
		(start 248.43867 -261.15518)
		(end 255.805686 -268.522196)
		(width 0.15494)
		(layer "In5.Cu")
		(net "PWRGD_P1V25_PEX2_R")
	)
	(segment
		(start 255.805686 -298.057824)
		(end 253.91237 -302.628554)
		(width 0.15494)
		(layer "In5.Cu")
		(net "PWRGD_P1V25_PEX2_R")
	)
	(segment
		(start 250.179332 -308.477666)
		(end 248.454926 -310.202072)
		(width 0.15494)
		(layer "In5.Cu")
		(net "PWRGD_P1V25_PEX2_R")
	)
	(segment
		(start 245.885462 -253.073916)
		(end 248.43867 -255.627124)
		(width 0.15494)
		(layer "In5.Cu")
		(net "PWRGD_P1V25_PEX2_R")
	)
	(segment
		(start 235.455206 -253.073916)
		(end 245.885462 -253.073916)
		(width 0.15494)
		(layer "In5.Cu")
		(net "PWRGD_P1V25_PEX2_R")
	)
	(segment
		(start 253.91237 -302.628554)
		(end 251.6759 -304.865024)
		(width 0.15494)
		(layer "In5.Cu")
		(net "PWRGD_P1V25_PEX2_R")
	)
	(segment
		(start 251.6759 -304.865024)
		(end 250.179332 -308.477666)
		(width 0.15494)
		(layer "In5.Cu")
		(net "PWRGD_P1V25_PEX2_R")
	)
	(segment
		(start 248.43867 -255.627124)
		(end 248.43867 -261.15518)
		(width 0.15494)
		(layer "In5.Cu")
		(net "PWRGD_P1V25_PEX2_R")
	)
	(segment
		(start 255.805686 -268.522196)
		(end 255.805686 -298.057824)
		(width 0.15494)
		(layer "In5.Cu")
		(net "PWRGD_P1V25_PEX2_R")
	)
	(segment
		(start 234.938824 -252.557534)
		(end 235.455206 -253.073916)
		(width 0.15494)
		(layer "In5.Cu")
		(net "PWRGD_P1V25_PEX2_R")
	)
	(segment
		(start 247.456198 -239.88268)
		(end 247.45823 -239.88268)
		(width 0.15494)
		(layer "In7.Cu")
		(net "PWRGD_P1V25_PEX2_R")
	)
	(segment
		(start 257.56108 -228.620066)
		(end 258.725162 -227.455984)
		(width 0.15494)
		(layer "In7.Cu")
		(net "PWRGD_P1V25_PEX2_R")
	)
	(segment
		(start 262.6106 -223.7486)
		(end 262.6106 -221.831408)
		(width 0.15494)
		(layer "In7.Cu")
		(net "PWRGD_P1V25_PEX2_R")
	)
	(segment
		(start 258.725162 -227.036884)
		(end 260.337046 -225.425)
		(width 0.15494)
		(layer "In7.Cu")
		(net "PWRGD_P1V25_PEX2_R")
	)
	(segment
		(start 235.45419 -252.042168)
		(end 235.45419 -251.884688)
		(width 0.15494)
		(layer "In7.Cu")
		(net "PWRGD_P1V25_PEX2_R")
	)
	(segment
		(start 258.725162 -227.455984)
		(end 258.725162 -227.036884)
		(width 0.15494)
		(layer "In7.Cu")
		(net "PWRGD_P1V25_PEX2_R")
	)
	(segment
		(start 265.3792 -221.704408)
		(end 265.5062 -221.577408)
		(width 0.15494)
		(layer "In7.Cu")
		(net "PWRGD_P1V25_PEX2_R")
	)
	(segment
		(start 235.45419 -251.884688)
		(end 247.456198 -239.88268)
		(width 0.15494)
		(layer "In7.Cu")
		(net "PWRGD_P1V25_PEX2_R")
	)
	(segment
		(start 260.337046 -225.425)
		(end 260.9342 -225.425)
		(width 0.15494)
		(layer "In7.Cu")
		(net "PWRGD_P1V25_PEX2_R")
	)
	(segment
		(start 234.938824 -252.557534)
		(end 235.45419 -252.042168)
		(width 0.15494)
		(layer "In7.Cu")
		(net "PWRGD_P1V25_PEX2_R")
	)
	(segment
		(start 260.9342 -225.425)
		(end 262.6106 -223.7486)
		(width 0.15494)
		(layer "In7.Cu")
		(net "PWRGD_P1V25_PEX2_R")
	)
	(segment
		(start 257.56108 -229.77983)
		(end 257.56108 -228.620066)
		(width 0.15494)
		(layer "In7.Cu")
		(net "PWRGD_P1V25_PEX2_R")
	)
	(segment
		(start 262.6106 -221.831408)
		(end 262.7376 -221.704408)
		(width 0.15494)
		(layer "In7.Cu")
		(net "PWRGD_P1V25_PEX2_R")
	)
	(segment
		(start 247.45823 -239.88268)
		(end 257.56108 -229.77983)
		(width 0.15494)
		(layer "In7.Cu")
		(net "PWRGD_P1V25_PEX2_R")
	)
	(segment
		(start 262.7376 -221.704408)
		(end 265.3792 -221.704408)
		(width 0.15494)
		(layer "In7.Cu")
		(net "PWRGD_P1V25_PEX2_R")
	)
	(segment
		(start 328.74966 -221.92107)
		(end 328.75093 -221.9198)
		(width 0.15494)
		(layer "In15.Cu")
		(net "PWRGD_P1V25_PEX2_R")
	)
	(segment
		(start 334.6704 -222.631)
		(end 334.899 -222.4024)
		(width 0.0889)
		(layer "In15.Cu")
		(net "PWRGD_P1V25_PEX2_R")
	)
	(segment
		(start 304.135536 -221.704408)
		(end 304.478182 -221.361762)
		(width 0.15494)
		(layer "In15.Cu")
		(net "PWRGD_P1V25_PEX2_R")
	)
	(segment
		(start 325.095362 -222.691198)
		(end 325.422768 -223.018604)
		(width 0.15494)
		(layer "In15.Cu")
		(net "PWRGD_P1V25_PEX2_R")
	)
	(segment
		(start 330.70546 -223.56826)
		(end 332.8162 -223.56826)
		(width 0.15494)
		(layer "In15.Cu")
		(net "PWRGD_P1V25_PEX2_R")
	)
	(segment
		(start 298.7294 -221.704408)
		(end 304.135536 -221.704408)
		(width 0.15494)
		(layer "In15.Cu")
		(net "PWRGD_P1V25_PEX2_R")
	)
	(segment
		(start 298.6024 -221.577408)
		(end 298.7294 -221.704408)
		(width 0.15494)
		(layer "In15.Cu")
		(net "PWRGD_P1V25_PEX2_R")
	)
	(segment
		(start 304.478182 -221.361762)
		(end 322.091304 -221.361762)
		(width 0.15494)
		(layer "In15.Cu")
		(net "PWRGD_P1V25_PEX2_R")
	)
	(segment
		(start 323.42074 -222.691198)
		(end 325.095362 -222.691198)
		(width 0.15494)
		(layer "In15.Cu")
		(net "PWRGD_P1V25_PEX2_R")
	)
	(segment
		(start 325.865744 -223.018604)
		(end 326.164194 -223.317054)
		(width 0.15494)
		(layer "In15.Cu")
		(net "PWRGD_P1V25_PEX2_R")
	)
	(segment
		(start 328.75093 -221.9198)
		(end 329.057 -221.9198)
		(width 0.15494)
		(layer "In15.Cu")
		(net "PWRGD_P1V25_PEX2_R")
	)
	(segment
		(start 326.164194 -223.317054)
		(end 326.99325 -223.317054)
		(width 0.15494)
		(layer "In15.Cu")
		(net "PWRGD_P1V25_PEX2_R")
	)
	(segment
		(start 326.99325 -223.317054)
		(end 328.389234 -221.92107)
		(width 0.15494)
		(layer "In15.Cu")
		(net "PWRGD_P1V25_PEX2_R")
	)
	(segment
		(start 328.389234 -221.92107)
		(end 328.74966 -221.92107)
		(width 0.15494)
		(layer "In15.Cu")
		(net "PWRGD_P1V25_PEX2_R")
	)
	(segment
		(start 325.422768 -223.018604)
		(end 325.865744 -223.018604)
		(width 0.15494)
		(layer "In15.Cu")
		(net "PWRGD_P1V25_PEX2_R")
	)
	(segment
		(start 334.899 -222.4024)
		(end 337.30946 -222.4024)
		(width 0.0889)
		(layer "In15.Cu")
		(net "PWRGD_P1V25_PEX2_R")
	)
	(segment
		(start 333.75346 -222.631)
		(end 334.3656 -222.631)
		(width 0.15494)
		(layer "In15.Cu")
		(net "PWRGD_P1V25_PEX2_R")
	)
	(segment
		(start 329.057 -221.9198)
		(end 330.70546 -223.56826)
		(width 0.15494)
		(layer "In15.Cu")
		(net "PWRGD_P1V25_PEX2_R")
	)
	(segment
		(start 334.3656 -222.631)
		(end 334.6704 -222.631)
		(width 0.0889)
		(layer "In15.Cu")
		(net "PWRGD_P1V25_PEX2_R")
	)
	(segment
		(start 332.8162 -223.56826)
		(end 333.75346 -222.631)
		(width 0.15494)
		(layer "In15.Cu")
		(net "PWRGD_P1V25_PEX2_R")
	)
	(segment
		(start 265.5062 -221.577408)
		(end 298.6024 -221.577408)
		(width 0.15494)
		(layer "In15.Cu")
		(net "PWRGD_P1V25_PEX2_R")
	)
	(segment
		(start 337.30946 -222.4024)
		(end 337.694016 -222.786956)
		(width 0.0889)
		(layer "In15.Cu")
		(net "PWRGD_P1V25_PEX2_R")
	)
	(segment
		(start 322.091304 -221.361762)
		(end 323.42074 -222.691198)
		(width 0.15494)
		(layer "In15.Cu")
		(net "PWRGD_P1V25_PEX2_R")
	)
	(segment
		(start 319.191386 -97.211642)
		(end 320.207386 -97.211642)
		(width 0.13208)
		(layer "F.Cu")
		(net "NIC5_ADC_A1")
	)
	(segment
		(start 321.295014 -98.323654)
		(end 320.924936 -97.953576)
		(width 0.13208)
		(layer "F.Cu")
		(net "NIC5_ADC_A1")
	)
	(segment
		(start 322.761864 -98.544634)
		(end 322.540884 -98.323654)
		(width 0.13208)
		(layer "F.Cu")
		(net "NIC5_ADC_A1")
	)
	(segment
		(start 320.207386 -97.236026)
		(end 320.924936 -97.953576)
		(width 0.13208)
		(layer "F.Cu")
		(net "NIC5_ADC_A1")
	)
	(segment
		(start 320.207386 -97.211642)
		(end 320.207386 -97.236026)
		(width 0.13208)
		(layer "F.Cu")
		(net "NIC5_ADC_A1")
	)
	(segment
		(start 322.761864 -98.809302)
		(end 322.761864 -98.544634)
		(width 0.13208)
		(layer "F.Cu")
		(net "NIC5_ADC_A1")
	)
	(segment
		(start 322.540884 -98.323654)
		(end 321.295014 -98.323654)
		(width 0.13208)
		(layer "F.Cu")
		(net "NIC5_ADC_A1")
	)
	(via
		(at 320.924936 -97.953576)
		(size 0.508)
		(drill 0.254)
		(layers "F.Cu" "B.Cu")
		(net "NIC5_ADC_A1")
	)
	(via
		(at 436.452772 -101.579172)
		(size 0.508)
		(drill 0.254)
		(layers "F.Cu" "B.Cu")
		(net "P12V_NIC7_VIN_P")
	)
	(via
		(at 322.089018 -103.13924)
		(size 0.508)
		(drill 0.254)
		(layers "F.Cu" "B.Cu")
		(net "P12V_NIC5_VIN_N")
	)
	(segment
		(start 19.223736 -152.3111)
		(end 20.239736 -152.3111)
		(width 0.13208)
		(layer "F.Cu")
		(net "NIC0_ADC_A0")
	)
	(segment
		(start 19.307556 -151.582628)
		(end 18.918682 -151.193754)
		(width 0.13208)
		(layer "F.Cu")
		(net "NIC0_ADC_A0")
	)
	(segment
		(start 19.744436 -151.582628)
		(end 19.307556 -151.582628)
		(width 0.13208)
		(layer "F.Cu")
		(net "NIC0_ADC_A0")
	)
	(segment
		(start 20.112736 -151.582628)
		(end 19.744436 -151.582628)
		(width 0.13208)
		(layer "F.Cu")
		(net "NIC0_ADC_A0")
	)
	(segment
		(start 20.239736 -152.3111)
		(end 20.239736 -151.709628)
		(width 0.13208)
		(layer "F.Cu")
		(net "NIC0_ADC_A0")
	)
	(segment
		(start 20.239736 -151.709628)
		(end 20.112736 -151.582628)
		(width 0.13208)
		(layer "F.Cu")
		(net "NIC0_ADC_A0")
	)
	(segment
		(start 18.918682 -151.193754)
		(end 18.918682 -150.71344)
		(width 0.13208)
		(layer "F.Cu")
		(net "NIC0_ADC_A0")
	)
	(via
		(at 19.744436 -151.582628)
		(size 0.508)
		(drill 0.254)
		(layers "F.Cu" "B.Cu")
		(net "NIC0_ADC_A0")
	)
	(segment
		(start 325.287386 -97.211642)
		(end 325.287386 -97.821242)
		(width 0.13208)
		(layer "F.Cu")
		(net "SMB_NIC5_ADC_SDA")
	)
	(segment
		(start 324.261988 -98.450146)
		(end 324.261988 -98.809302)
		(width 0.13208)
		(layer "F.Cu")
		(net "SMB_NIC5_ADC_SDA")
	)
	(segment
		(start 325.287386 -97.821242)
		(end 325.287386 -98.196146)
		(width 0.13208)
		(layer "F.Cu")
		(net "SMB_NIC5_ADC_SDA")
	)
	(segment
		(start 325.160386 -98.323146)
		(end 324.388988 -98.323146)
		(width 0.13208)
		(layer "F.Cu")
		(net "SMB_NIC5_ADC_SDA")
	)
	(segment
		(start 324.388988 -98.323146)
		(end 324.261988 -98.450146)
		(width 0.13208)
		(layer "F.Cu")
		(net "SMB_NIC5_ADC_SDA")
	)
	(segment
		(start 325.287386 -98.196146)
		(end 325.160386 -98.323146)
		(width 0.13208)
		(layer "F.Cu")
		(net "SMB_NIC5_ADC_SDA")
	)
	(via
		(at 325.287386 -97.821242)
		(size 0.508)
		(drill 0.254)
		(layers "F.Cu" "B.Cu")
		(net "SMB_NIC5_ADC_SDA")
	)
	(segment
		(start 216.937844 -99.20605)
		(end 216.937844 -99.821746)
		(width 0.13208)
		(layer "F.Cu")
		(net "NIC3_ADC_A1")
	)
	(segment
		(start 216.937844 -99.821746)
		(end 217.753692 -100.637594)
		(width 0.13208)
		(layer "F.Cu")
		(net "NIC3_ADC_A1")
	)
	(segment
		(start 216.937844 -97.028)
		(end 216.937844 -96.53905)
		(width 0.13208)
		(layer "F.Cu")
		(net "NIC3_ADC_A1")
	)
	(segment
		(start 217.445844 -99.047554)
		(end 217.445844 -97.536)
		(width 0.13208)
		(layer "F.Cu")
		(net "NIC3_ADC_A1")
	)
	(segment
		(start 217.445844 -97.536)
		(end 216.937844 -97.028)
		(width 0.13208)
		(layer "F.Cu")
		(net "NIC3_ADC_A1")
	)
	(segment
		(start 217.753692 -100.637594)
		(end 217.753692 -100.841556)
		(width 0.13208)
		(layer "F.Cu")
		(net "NIC3_ADC_A1")
	)
	(segment
		(start 216.937844 -99.20605)
		(end 217.287348 -99.20605)
		(width 0.13208)
		(layer "F.Cu")
		(net "NIC3_ADC_A1")
	)
	(segment
		(start 217.287348 -99.20605)
		(end 217.445844 -99.047554)
		(width 0.13208)
		(layer "F.Cu")
		(net "NIC3_ADC_A1")
	)
	(via
		(at 216.937844 -99.821746)
		(size 0.508)
		(drill 0.254)
		(layers "F.Cu" "B.Cu")
		(net "NIC3_ADC_A1")
	)
	(segment
		(start 368.298222 -146.91487)
		(end 368.671094 -146.541998)
		(width 0.254)
		(layer "F.Cu")
		(net "P12V_NIC6_VIN_N")
	)
	(segment
		(start 367.718848 -147.913344)
		(end 367.718848 -147.494244)
		(width 0.254)
		(layer "F.Cu")
		(net "P12V_NIC6_VIN_N")
	)
	(segment
		(start 367.718848 -147.494244)
		(end 368.298222 -146.91487)
		(width 0.254)
		(layer "F.Cu")
		(net "P12V_NIC6_VIN_N")
	)
	(segment
		(start 368.671094 -145.189956)
		(end 368.671094 -146.205956)
		(width 0.254)
		(layer "F.Cu")
		(net "P12V_NIC6_VIN_N")
	)
	(segment
		(start 368.671094 -146.541998)
		(end 368.671094 -146.205956)
		(width 0.254)
		(layer "F.Cu")
		(net "P12V_NIC6_VIN_N")
	)
	(via
		(at 368.298222 -146.91487)
		(size 0.508)
		(drill 0.254)
		(layers "F.Cu" "B.Cu")
		(net "P12V_NIC6_VIN_N")
	)
	(segment
		(start 368.843052 -148.56333)
		(end 368.368834 -148.56333)
		(width 0.254)
		(layer "F.Cu")
		(net "P12V_NIC6_VIN_P")
	)
	(segment
		(start 369.676426 -147.729956)
		(end 368.843052 -148.56333)
		(width 0.254)
		(layer "F.Cu")
		(net "P12V_NIC6_VIN_P")
	)
	(segment
		(start 369.484402 -146.192748)
		(end 370.563648 -146.192748)
		(width 0.254)
		(layer "F.Cu")
		(net "P12V_NIC6_VIN_P")
	)
	(segment
		(start 369.471194 -146.205956)
		(end 369.471194 -146.857212)
		(width 0.254)
		(layer "F.Cu")
		(net "P12V_NIC6_VIN_P")
	)
	(segment
		(start 369.471194 -146.205956)
		(end 369.484402 -146.192748)
		(width 0.254)
		(layer "F.Cu")
		(net "P12V_NIC6_VIN_P")
	)
	(segment
		(start 369.676426 -147.062444)
		(end 369.676426 -147.729956)
		(width 0.254)
		(layer "F.Cu")
		(net "P12V_NIC6_VIN_P")
	)
	(segment
		(start 369.471194 -146.857212)
		(end 369.676426 -147.062444)
		(width 0.254)
		(layer "F.Cu")
		(net "P12V_NIC6_VIN_P")
	)
	(via
		(at 369.676426 -147.062444)
		(size 0.508)
		(drill 0.254)
		(layers "F.Cu" "B.Cu")
		(net "P12V_NIC6_VIN_P")
	)
	(segment
		(start 21.376386 -147.729956)
		(end 20.543012 -148.56333)
		(width 0.254)
		(layer "F.Cu")
		(net "P12V_NIC0_VIN_P")
	)
	(segment
		(start 20.543012 -148.56333)
		(end 20.068794 -148.56333)
		(width 0.254)
		(layer "F.Cu")
		(net "P12V_NIC0_VIN_P")
	)
	(segment
		(start 21.171154 -146.857212)
		(end 21.376386 -147.062444)
		(width 0.254)
		(layer "F.Cu")
		(net "P12V_NIC0_VIN_P")
	)
	(segment
		(start 21.184362 -146.192748)
		(end 22.263608 -146.192748)
		(width 0.254)
		(layer "F.Cu")
		(net "P12V_NIC0_VIN_P")
	)
	(segment
		(start 21.171154 -146.205956)
		(end 21.171154 -146.857212)
		(width 0.254)
		(layer "F.Cu")
		(net "P12V_NIC0_VIN_P")
	)
	(segment
		(start 21.171154 -146.205956)
		(end 21.184362 -146.192748)
		(width 0.254)
		(layer "F.Cu")
		(net "P12V_NIC0_VIN_P")
	)
	(segment
		(start 21.376386 -147.062444)
		(end 21.376386 -147.729956)
		(width 0.254)
		(layer "F.Cu")
		(net "P12V_NIC0_VIN_P")
	)
	(via
		(at 21.376386 -147.062444)
		(size 0.508)
		(drill 0.254)
		(layers "F.Cu" "B.Cu")
		(net "P12V_NIC0_VIN_P")
	)
	(segment
		(start 247.359678 -152.3111)
		(end 247.359678 -151.123904)
		(width 0.13208)
		(layer "F.Cu")
		(net "SMB_NIC4_ADC_SCL")
	)
	(segment
		(start 247.359678 -151.123904)
		(end 248.420128 -150.063454)
		(width 0.13208)
		(layer "F.Cu")
		(net "SMB_NIC4_ADC_SCL")
	)
	(segment
		(start 248.420128 -150.063454)
		(end 249.46864 -150.063454)
		(width 0.13208)
		(layer "F.Cu")
		(net "SMB_NIC4_ADC_SCL")
	)
	(via
		(at 248.420128 -150.063454)
		(size 0.508)
		(drill 0.254)
		(layers "F.Cu" "B.Cu")
		(net "SMB_NIC4_ADC_SCL")
	)
	(via
		(at 89.889076 -103.13924)
		(size 0.508)
		(drill 0.254)
		(layers "F.Cu" "B.Cu")
		(net "P12V_NIC1_VIN_N")
	)
	(segment
		(start 323.255386 -97.567242)
		(end 323.509386 -97.821242)
		(width 0.13208)
		(layer "F.Cu")
		(net "NIC5_ADC_ALERT_N")
	)
	(segment
		(start 323.761862 -98.073718)
		(end 323.761862 -98.809302)
		(width 0.13208)
		(layer "F.Cu")
		(net "NIC5_ADC_ALERT_N")
	)
	(segment
		(start 323.509386 -97.821242)
		(end 323.761862 -98.073718)
		(width 0.13208)
		(layer "F.Cu")
		(net "NIC5_ADC_ALERT_N")
	)
	(segment
		(start 323.255386 -97.211642)
		(end 323.255386 -97.567242)
		(width 0.13208)
		(layer "F.Cu")
		(net "NIC5_ADC_ALERT_N")
	)
	(via
		(at 323.509386 -97.821242)
		(size 0.508)
		(drill 0.254)
		(layers "F.Cu" "B.Cu")
		(net "NIC5_ADC_ALERT_N")
	)
	(segment
		(start 136.168638 -148.56333)
		(end 136.642856 -148.56333)
		(width 0.254)
		(layer "F.Cu")
		(net "P12V_NIC2_VIN_P")
	)
	(segment
		(start 136.642856 -148.56333)
		(end 137.47623 -147.729956)
		(width 0.254)
		(layer "F.Cu")
		(net "P12V_NIC2_VIN_P")
	)
	(segment
		(start 137.47623 -147.062444)
		(end 137.270998 -146.857212)
		(width 0.254)
		(layer "F.Cu")
		(net "P12V_NIC2_VIN_P")
	)
	(segment
		(start 137.284206 -146.192748)
		(end 137.270998 -146.205956)
		(width 0.254)
		(layer "F.Cu")
		(net "P12V_NIC2_VIN_P")
	)
	(segment
		(start 137.47623 -147.729956)
		(end 137.47623 -147.062444)
		(width 0.254)
		(layer "F.Cu")
		(net "P12V_NIC2_VIN_P")
	)
	(segment
		(start 138.363452 -146.192748)
		(end 137.284206 -146.192748)
		(width 0.254)
		(layer "F.Cu")
		(net "P12V_NIC2_VIN_P")
	)
	(segment
		(start 137.270998 -146.857212)
		(end 137.270998 -146.205956)
		(width 0.254)
		(layer "F.Cu")
		(net "P12V_NIC2_VIN_P")
	)
	(via
		(at 137.47623 -147.062444)
		(size 0.508)
		(drill 0.254)
		(layers "F.Cu" "B.Cu")
		(net "P12V_NIC2_VIN_P")
	)
	(segment
		(start 366.507776 -152.3111)
		(end 366.71885 -152.100026)
		(width 0.13208)
		(layer "F.Cu")
		(net "NIC6_ADC_ALERT_N")
	)
	(segment
		(start 366.71885 -152.100026)
		(end 366.71885 -151.406606)
		(width 0.13208)
		(layer "F.Cu")
		(net "NIC6_ADC_ALERT_N")
	)
	(segment
		(start 366.71885 -151.406606)
		(end 366.71885 -150.71344)
		(width 0.13208)
		(layer "F.Cu")
		(net "NIC6_ADC_ALERT_N")
	)
	(via
		(at 366.71885 -151.406606)
		(size 0.508)
		(drill 0.254)
		(layers "F.Cu" "B.Cu")
		(net "NIC6_ADC_ALERT_N")
	)
	(segment
		(start 333.304896 -112.856518)
		(end 333.304896 -117.28196)
		(width 0.254)
		(layer "F.Cu")
		(net "P12V_NIC5_R")
	)
	(segment
		(start 320.488056 -100.058982)
		(end 320.488056 -99.449382)
		(width 0.4572)
		(layer "F.Cu")
		(net "P12V_NIC5_R")
	)
	(segment
		(start 333.304896 -117.28196)
		(end 333.65059 -117.627654)
		(width 0.254)
		(layer "F.Cu")
		(net "P12V_NIC5_R")
	)
	(segment
		(start 333.65059 -117.627654)
		(end 338.396834 -117.627654)
		(width 0.254)
		(layer "F.Cu")
		(net "P12V_NIC5_R")
	)
	(segment
		(start 333.32547 -112.835944)
		(end 333.304896 -112.856518)
		(width 0.254)
		(layer "F.Cu")
		(net "P12V_NIC5_R")
	)
	(via
		(at 323.044312 -107.718606)
		(size 0.508)
		(drill 0.254)
		(layers "F.Cu" "B.Cu")
		(net "P12V_NIC5_R")
	)
	(via
		(at 320.488056 -99.449382)
		(size 0.508)
		(drill 0.254)
		(layers "F.Cu" "B.Cu")
		(net "P12V_NIC5_R")
	)
	(via
		(at 336.879438 -112.705134)
		(size 0.508)
		(drill 0.254)
		(layers "F.Cu" "B.Cu")
		(net "P12V_NIC5_R")
	)
	(via
		(at 329.594972 -105.057194)
		(size 0.508)
		(drill 0.254)
		(layers "F.Cu" "B.Cu")
		(net "P12V_NIC5_R")
	)
	(via
		(at 337.590638 -112.705134)
		(size 0.508)
		(drill 0.254)
		(layers "F.Cu" "B.Cu")
		(net "P12V_NIC5_R")
	)
	(via
		(at 330.170282 -107.713018)
		(size 0.508)
		(drill 0.254)
		(layers "F.Cu" "B.Cu")
		(net "P12V_NIC5_R")
	)
	(via
		(at 323.044312 -107.058206)
		(size 0.508)
		(drill 0.254)
		(layers "F.Cu" "B.Cu")
		(net "P12V_NIC5_R")
	)
	(via
		(at 325.651368 -112.297972)
		(size 0.508)
		(drill 0.254)
		(layers "F.Cu" "B.Cu")
		(net "P12V_NIC5_R")
	)
	(via
		(at 337.590638 -110.571534)
		(size 0.508)
		(drill 0.254)
		(layers "F.Cu" "B.Cu")
		(net "P12V_NIC5_R")
	)
	(via
		(at 329.759056 -102.103174)
		(size 0.508)
		(drill 0.254)
		(layers "F.Cu" "B.Cu")
		(net "P12V_NIC5_R")
	)
	(via
		(at 323.044312 -104.416606)
		(size 0.508)
		(drill 0.254)
		(layers "F.Cu" "B.Cu")
		(net "P12V_NIC5_R")
	)
	(via
		(at 328.4474 -104.022906)
		(size 0.508)
		(drill 0.254)
		(layers "F.Cu" "B.Cu")
		(net "P12V_NIC5_R")
	)
	(via
		(at 330.229972 -105.057194)
		(size 0.508)
		(drill 0.254)
		(layers "F.Cu" "B.Cu")
		(net "P12V_NIC5_R")
	)
	(via
		(at 332.6765 -112.037622)
		(size 0.508)
		(drill 0.254)
		(layers "F.Cu" "B.Cu")
		(net "P12V_NIC5_R")
	)
	(via
		(at 336.879438 -110.571534)
		(size 0.508)
		(drill 0.254)
		(layers "F.Cu" "B.Cu")
		(net "P12V_NIC5_R")
	)
	(via
		(at 323.044312 -105.077006)
		(size 0.508)
		(drill 0.254)
		(layers "F.Cu" "B.Cu")
		(net "P12V_NIC5_R")
	)
	(via
		(at 337.590638 -111.282734)
		(size 0.508)
		(drill 0.254)
		(layers "F.Cu" "B.Cu")
		(net "P12V_NIC5_R")
	)
	(via
		(at 323.044312 -103.095806)
		(size 0.508)
		(drill 0.254)
		(layers "F.Cu" "B.Cu")
		(net "P12V_NIC5_R")
	)
	(via
		(at 336.879438 -111.282734)
		(size 0.508)
		(drill 0.254)
		(layers "F.Cu" "B.Cu")
		(net "P12V_NIC5_R")
	)
	(via
		(at 325.651368 -111.586772)
		(size 0.508)
		(drill 0.254)
		(layers "F.Cu" "B.Cu")
		(net "P12V_NIC5_R")
	)
	(via
		(at 330.138278 -112.748822)
		(size 0.508)
		(drill 0.254)
		(layers "F.Cu" "B.Cu")
		(net "P12V_NIC5_R")
	)
	(via
		(at 332.6765 -112.748822)
		(size 0.508)
		(drill 0.254)
		(layers "F.Cu" "B.Cu")
		(net "P12V_NIC5_R")
	)
	(via
		(at 328.900282 -107.713018)
		(size 0.508)
		(drill 0.254)
		(layers "F.Cu" "B.Cu")
		(net "P12V_NIC5_R")
	)
	(via
		(at 323.044312 -105.737406)
		(size 0.508)
		(drill 0.254)
		(layers "F.Cu" "B.Cu")
		(net "P12V_NIC5_R")
	)
	(via
		(at 330.138278 -111.326422)
		(size 0.508)
		(drill 0.254)
		(layers "F.Cu" "B.Cu")
		(net "P12V_NIC5_R")
	)
	(via
		(at 329.535282 -107.713018)
		(size 0.508)
		(drill 0.254)
		(layers "F.Cu" "B.Cu")
		(net "P12V_NIC5_R")
	)
	(via
		(at 329.124056 -102.103174)
		(size 0.508)
		(drill 0.254)
		(layers "F.Cu" "B.Cu")
		(net "P12V_NIC5_R")
	)
	(via
		(at 328.4474 -103.311706)
		(size 0.508)
		(drill 0.254)
		(layers "F.Cu" "B.Cu")
		(net "P12V_NIC5_R")
	)
	(via
		(at 327.683368 -112.297972)
		(size 0.508)
		(drill 0.254)
		(layers "F.Cu" "B.Cu")
		(net "P12V_NIC5_R")
	)
	(via
		(at 332.6765 -111.326422)
		(size 0.508)
		(drill 0.254)
		(layers "F.Cu" "B.Cu")
		(net "P12V_NIC5_R")
	)
	(via
		(at 329.2094 -104.022906)
		(size 0.508)
		(drill 0.254)
		(layers "F.Cu" "B.Cu")
		(net "P12V_NIC5_R")
	)
	(via
		(at 330.209398 -101.162612)
		(size 0.508)
		(drill 0.254)
		(layers "F.Cu" "B.Cu")
		(net "P12V_NIC5_R")
	)
	(via
		(at 323.14261 -110.621572)
		(size 0.508)
		(drill 0.254)
		(layers "F.Cu" "B.Cu")
		(net "P12V_NIC5_R")
	)
	(via
		(at 329.2094 -103.387906)
		(size 0.508)
		(drill 0.254)
		(layers "F.Cu" "B.Cu")
		(net "P12V_NIC5_R")
	)
	(via
		(at 323.14261 -109.910372)
		(size 0.508)
		(drill 0.254)
		(layers "F.Cu" "B.Cu")
		(net "P12V_NIC5_R")
	)
	(via
		(at 330.138278 -112.037622)
		(size 0.508)
		(drill 0.254)
		(layers "F.Cu" "B.Cu")
		(net "P12V_NIC5_R")
	)
	(via
		(at 328.324972 -105.057194)
		(size 0.508)
		(drill 0.254)
		(layers "F.Cu" "B.Cu")
		(net "P12V_NIC5_R")
	)
	(via
		(at 328.265282 -107.713018)
		(size 0.508)
		(drill 0.254)
		(layers "F.Cu" "B.Cu")
		(net "P12V_NIC5_R")
	)
	(via
		(at 329.574398 -101.162612)
		(size 0.508)
		(drill 0.254)
		(layers "F.Cu" "B.Cu")
		(net "P12V_NIC5_R")
	)
	(via
		(at 327.683368 -111.586772)
		(size 0.508)
		(drill 0.254)
		(layers "F.Cu" "B.Cu")
		(net "P12V_NIC5_R")
	)
	(via
		(at 323.194934 -102.4382)
		(size 0.508)
		(drill 0.254)
		(layers "F.Cu" "B.Cu")
		(net "P12V_NIC5_R")
	)
	(via
		(at 323.044312 -108.379006)
		(size 0.508)
		(drill 0.254)
		(layers "F.Cu" "B.Cu")
		(net "P12V_NIC5_R")
	)
	(via
		(at 323.044312 -106.397806)
		(size 0.508)
		(drill 0.254)
		(layers "F.Cu" "B.Cu")
		(net "P12V_NIC5_R")
	)
	(via
		(at 323.044312 -103.756206)
		(size 0.508)
		(drill 0.254)
		(layers "F.Cu" "B.Cu")
		(net "P12V_NIC5_R")
	)
	(via
		(at 328.959972 -105.057194)
		(size 0.508)
		(drill 0.254)
		(layers "F.Cu" "B.Cu")
		(net "P12V_NIC5_R")
	)
	(via
		(at 337.590638 -111.993934)
		(size 0.508)
		(drill 0.254)
		(layers "F.Cu" "B.Cu")
		(net "P12V_NIC5_R")
	)
	(via
		(at 336.879438 -111.993934)
		(size 0.508)
		(drill 0.254)
		(layers "F.Cu" "B.Cu")
		(net "P12V_NIC5_R")
	)
	(segment
		(start 16.175736 -151.67102)
		(end 16.175736 -152.3111)
		(width 0.13208)
		(layer "F.Cu")
		(net "SMB_NIC0_ADC_SDA")
	)
	(segment
		(start 17.730216 -151.0919)
		(end 16.754856 -151.0919)
		(width 0.13208)
		(layer "F.Cu")
		(net "SMB_NIC0_ADC_SDA")
	)
	(segment
		(start 16.754856 -151.0919)
		(end 16.175736 -151.67102)
		(width 0.13208)
		(layer "F.Cu")
		(net "SMB_NIC0_ADC_SDA")
	)
	(segment
		(start 17.918684 -150.71344)
		(end 17.918684 -150.903432)
		(width 0.13208)
		(layer "F.Cu")
		(net "SMB_NIC0_ADC_SDA")
	)
	(segment
		(start 17.918684 -150.903432)
		(end 17.730216 -151.0919)
		(width 0.13208)
		(layer "F.Cu")
		(net "SMB_NIC0_ADC_SDA")
	)
	(via
		(at 16.175736 -151.67102)
		(size 0.508)
		(drill 0.254)
		(layers "F.Cu" "B.Cu")
		(net "SMB_NIC0_ADC_SDA")
	)
	(segment
		(start 131.25958 -152.3111)
		(end 131.25958 -151.123904)
		(width 0.13208)
		(layer "F.Cu")
		(net "SMB_NIC2_ADC_SCL")
	)
	(segment
		(start 131.25958 -151.123904)
		(end 132.32003 -150.063454)
		(width 0.13208)
		(layer "F.Cu")
		(net "SMB_NIC2_ADC_SCL")
	)
	(segment
		(start 132.32003 -150.063454)
		(end 133.368542 -150.063454)
		(width 0.13208)
		(layer "F.Cu")
		(net "SMB_NIC2_ADC_SCL")
	)
	(via
		(at 132.32003 -150.063454)
		(size 0.508)
		(drill 0.254)
		(layers "F.Cu" "B.Cu")
		(net "SMB_NIC2_ADC_SCL")
	)
	(segment
		(start 18.41881 -151.406606)
		(end 18.41881 -150.71344)
		(width 0.13208)
		(layer "F.Cu")
		(net "NIC0_ADC_ALERT_N")
	)
	(segment
		(start 18.207736 -152.3111)
		(end 18.41881 -152.100026)
		(width 0.13208)
		(layer "F.Cu")
		(net "NIC0_ADC_ALERT_N")
	)
	(segment
		(start 18.41881 -152.100026)
		(end 18.41881 -151.406606)
		(width 0.13208)
		(layer "F.Cu")
		(net "NIC0_ADC_ALERT_N")
	)
	(via
		(at 18.41881 -151.406606)
		(size 0.508)
		(drill 0.254)
		(layers "F.Cu" "B.Cu")
		(net "NIC0_ADC_ALERT_N")
	)
	(segment
		(start 20.371054 -146.541998)
		(end 20.371054 -146.205956)
		(width 0.254)
		(layer "F.Cu")
		(net "P12V_NIC0_VIN_N")
	)
	(segment
		(start 20.371054 -145.189956)
		(end 20.371054 -146.205956)
		(width 0.254)
		(layer "F.Cu")
		(net "P12V_NIC0_VIN_N")
	)
	(segment
		(start 19.418808 -147.913344)
		(end 19.418808 -147.494244)
		(width 0.254)
		(layer "F.Cu")
		(net "P12V_NIC0_VIN_N")
	)
	(segment
		(start 19.418808 -147.494244)
		(end 19.998182 -146.91487)
		(width 0.254)
		(layer "F.Cu")
		(net "P12V_NIC0_VIN_N")
	)
	(segment
		(start 19.998182 -146.91487)
		(end 20.371054 -146.541998)
		(width 0.254)
		(layer "F.Cu")
		(net "P12V_NIC0_VIN_N")
	)
	(via
		(at 19.998182 -146.91487)
		(size 0.508)
		(drill 0.254)
		(layers "F.Cu" "B.Cu")
		(net "P12V_NIC0_VIN_N")
	)
	(segment
		(start 21.255736 -151.569166)
		(end 20.40001 -150.71344)
		(width 0.13208)
		(layer "F.Cu")
		(net "NIC0_ADC_A1")
	)
	(segment
		(start 21.255736 -152.3111)
		(end 21.255736 -151.569166)
		(width 0.13208)
		(layer "F.Cu")
		(net "NIC0_ADC_A1")
	)
	(segment
		(start 20.40001 -150.71344)
		(end 19.418808 -150.71344)
		(width 0.13208)
		(layer "F.Cu")
		(net "NIC0_ADC_A1")
	)
	(segment
		(start 22.271736 -152.3111)
		(end 21.255736 -152.3111)
		(width 0.13208)
		(layer "F.Cu")
		(net "NIC0_ADC_A1")
	)
	(via
		(at 21.255736 -151.569166)
		(size 0.508)
		(drill 0.254)
		(layers "F.Cu" "B.Cu")
		(net "NIC0_ADC_A1")
	)
	(segment
		(start 134.518654 -152.100026)
		(end 134.518654 -151.406606)
		(width 0.13208)
		(layer "F.Cu")
		(net "NIC2_ADC_ALERT_N")
	)
	(segment
		(start 134.30758 -152.3111)
		(end 134.518654 -152.100026)
		(width 0.13208)
		(layer "F.Cu")
		(net "NIC2_ADC_ALERT_N")
	)
	(segment
		(start 134.518654 -151.406606)
		(end 134.518654 -150.71344)
		(width 0.13208)
		(layer "F.Cu")
		(net "NIC2_ADC_ALERT_N")
	)
	(via
		(at 134.518654 -151.406606)
		(size 0.508)
		(drill 0.254)
		(layers "F.Cu" "B.Cu")
		(net "NIC2_ADC_ALERT_N")
	)
	(segment
		(start 219.253816 -100.841556)
		(end 219.253816 -100.681028)
		(width 0.13208)
		(layer "F.Cu")
		(net "SMB_NIC3_ADC_SDA")
	)
	(segment
		(start 219.253816 -100.681028)
		(end 219.604844 -100.33)
		(width 0.13208)
		(layer "F.Cu")
		(net "SMB_NIC3_ADC_SDA")
	)
	(segment
		(start 220.366844 -100.203)
		(end 220.366844 -99.822)
		(width 0.13208)
		(layer "F.Cu")
		(net "SMB_NIC3_ADC_SDA")
	)
	(segment
		(start 220.239844 -100.33)
		(end 220.366844 -100.203)
		(width 0.13208)
		(layer "F.Cu")
		(net "SMB_NIC3_ADC_SDA")
	)
	(segment
		(start 219.604844 -100.33)
		(end 220.239844 -100.33)
		(width 0.13208)
		(layer "F.Cu")
		(net "SMB_NIC3_ADC_SDA")
	)
	(segment
		(start 220.366844 -99.822)
		(end 220.366844 -99.20605)
		(width 0.13208)
		(layer "F.Cu")
		(net "SMB_NIC3_ADC_SDA")
	)
	(via
		(at 220.366844 -99.822)
		(size 0.508)
		(drill 0.254)
		(layers "F.Cu" "B.Cu")
		(net "SMB_NIC3_ADC_SDA")
	)
	(segment
		(start 89.023444 -97.211642)
		(end 90.039444 -97.211642)
		(width 0.13208)
		(layer "F.Cu")
		(net "NIC1_ADC_A0")
	)
	(segment
		(start 90.438478 -97.821242)
		(end 91.062048 -98.444812)
		(width 0.13208)
		(layer "F.Cu")
		(net "NIC1_ADC_A0")
	)
	(segment
		(start 91.062048 -98.444812)
		(end 91.062048 -98.809302)
		(width 0.13208)
		(layer "F.Cu")
		(net "NIC1_ADC_A0")
	)
	(segment
		(start 90.039444 -97.821242)
		(end 90.438478 -97.821242)
		(width 0.13208)
		(layer "F.Cu")
		(net "NIC1_ADC_A0")
	)
	(segment
		(start 90.039444 -97.211642)
		(end 90.039444 -97.821242)
		(width 0.13208)
		(layer "F.Cu")
		(net "NIC1_ADC_A0")
	)
	(via
		(at 90.039444 -97.821242)
		(size 0.508)
		(drill 0.254)
		(layers "F.Cu" "B.Cu")
		(net "NIC1_ADC_A0")
	)
	(segment
		(start 254.46355 -147.741386)
		(end 254.46355 -146.992848)
		(width 0.4064)
		(layer "F.Cu")
		(net "P12V_NIC4_R")
	)
	(segment
		(start 239.198404 -150.797006)
		(end 243.623846 -150.797006)
		(width 0.254)
		(layer "F.Cu")
		(net "P12V_NIC4_R")
	)
	(segment
		(start 243.623846 -150.797006)
		(end 243.64442 -150.81758)
		(width 0.254)
		(layer "F.Cu")
		(net "P12V_NIC4_R")
	)
	(segment
		(start 238.85271 -155.888944)
		(end 238.85271 -151.1427)
		(width 0.254)
		(layer "F.Cu")
		(net "P12V_NIC4_R")
	)
	(segment
		(start 238.85271 -151.1427)
		(end 239.198404 -150.797006)
		(width 0.254)
		(layer "F.Cu")
		(net "P12V_NIC4_R")
	)
	(via
		(at 251.336302 -146.426936)
		(size 0.508)
		(drill 0.254)
		(layers "F.Cu" "B.Cu")
		(net "P12V_NIC4_R")
	)
	(via
		(at 243.731542 -147.630388)
		(size 0.508)
		(drill 0.254)
		(layers "F.Cu" "B.Cu")
		(net "P12V_NIC4_R")
	)
	(via
		(at 243.77523 -154.371548)
		(size 0.508)
		(drill 0.254)
		(layers "F.Cu" "B.Cu")
		(net "P12V_NIC4_R")
	)
	(via
		(at 243.336064 -141.019276)
		(size 0.508)
		(drill 0.254)
		(layers "F.Cu" "B.Cu")
		(net "P12V_NIC4_R")
	)
	(via
		(at 245.153942 -150.16861)
		(size 0.508)
		(drill 0.254)
		(layers "F.Cu" "B.Cu")
		(net "P12V_NIC4_R")
	)
	(via
		(at 244.48643 -154.371548)
		(size 0.508)
		(drill 0.254)
		(layers "F.Cu" "B.Cu")
		(net "P12V_NIC4_R")
	)
	(via
		(at 244.442742 -150.16861)
		(size 0.508)
		(drill 0.254)
		(layers "F.Cu" "B.Cu")
		(net "P12V_NIC4_R")
	)
	(via
		(at 249.52325 -136.620758)
		(size 0.508)
		(drill 0.254)
		(layers "F.Cu" "B.Cu")
		(net "P12V_NIC4_R")
	)
	(via
		(at 245.90883 -154.371548)
		(size 0.508)
		(drill 0.254)
		(layers "F.Cu" "B.Cu")
		(net "P12V_NIC4_R")
	)
	(via
		(at 250.57354 -145.618962)
		(size 0.508)
		(drill 0.254)
		(layers "F.Cu" "B.Cu")
		(net "P12V_NIC4_R")
	)
	(via
		(at 247.853962 -137.64133)
		(size 0.508)
		(drill 0.254)
		(layers "F.Cu" "B.Cu")
		(net "P12V_NIC4_R")
	)
	(via
		(at 245.153942 -147.630388)
		(size 0.508)
		(drill 0.254)
		(layers "F.Cu" "B.Cu")
		(net "P12V_NIC4_R")
	)
	(via
		(at 250.161552 -139.284964)
		(size 0.508)
		(drill 0.254)
		(layers "F.Cu" "B.Cu")
		(net "P12V_NIC4_R")
	)
	(via
		(at 249.52325 -138.525758)
		(size 0.508)
		(drill 0.254)
		(layers "F.Cu" "B.Cu")
		(net "P12V_NIC4_R")
	)
	(via
		(at 249.52325 -137.255758)
		(size 0.508)
		(drill 0.254)
		(layers "F.Cu" "B.Cu")
		(net "P12V_NIC4_R")
	)
	(via
		(at 245.90883 -155.082748)
		(size 0.508)
		(drill 0.254)
		(layers "F.Cu" "B.Cu")
		(net "P12V_NIC4_R")
	)
	(via
		(at 248.488962 -137.64133)
		(size 0.508)
		(drill 0.254)
		(layers "F.Cu" "B.Cu")
		(net "P12V_NIC4_R")
	)
	(via
		(at 244.48643 -155.082748)
		(size 0.508)
		(drill 0.254)
		(layers "F.Cu" "B.Cu")
		(net "P12V_NIC4_R")
	)
	(via
		(at 243.336064 -143.051276)
		(size 0.508)
		(drill 0.254)
		(layers "F.Cu" "B.Cu")
		(net "P12V_NIC4_R")
	)
	(via
		(at 247.777762 -138.40333)
		(size 0.508)
		(drill 0.254)
		(layers "F.Cu" "B.Cu")
		(net "P12V_NIC4_R")
	)
	(via
		(at 243.731542 -150.16861)
		(size 0.508)
		(drill 0.254)
		(layers "F.Cu" "B.Cu")
		(net "P12V_NIC4_R")
	)
	(via
		(at 250.520454 -144.954244)
		(size 0.508)
		(drill 0.254)
		(layers "F.Cu" "B.Cu")
		(net "P12V_NIC4_R")
	)
	(via
		(at 244.047264 -143.051276)
		(size 0.508)
		(drill 0.254)
		(layers "F.Cu" "B.Cu")
		(net "P12V_NIC4_R")
	)
	(via
		(at 254.46355 -147.741386)
		(size 0.508)
		(drill 0.254)
		(layers "F.Cu" "B.Cu")
		(net "P12V_NIC4_R")
	)
	(via
		(at 245.19763 -155.082748)
		(size 0.508)
		(drill 0.254)
		(layers "F.Cu" "B.Cu")
		(net "P12V_NIC4_R")
	)
	(via
		(at 243.77523 -155.082748)
		(size 0.508)
		(drill 0.254)
		(layers "F.Cu" "B.Cu")
		(net "P12V_NIC4_R")
	)
	(via
		(at 250.796552 -139.284964)
		(size 0.508)
		(drill 0.254)
		(layers "F.Cu" "B.Cu")
		(net "P12V_NIC4_R")
	)
	(via
		(at 249.52325 -137.890758)
		(size 0.508)
		(drill 0.254)
		(layers "F.Cu" "B.Cu")
		(net "P12V_NIC4_R")
	)
	(via
		(at 244.442742 -147.630388)
		(size 0.508)
		(drill 0.254)
		(layers "F.Cu" "B.Cu")
		(net "P12V_NIC4_R")
	)
	(via
		(at 243.336064 -145.083276)
		(size 0.508)
		(drill 0.254)
		(layers "F.Cu" "B.Cu")
		(net "P12V_NIC4_R")
	)
	(via
		(at 251.245624 -145.717006)
		(size 0.508)
		(drill 0.254)
		(layers "F.Cu" "B.Cu")
		(net "P12V_NIC4_R")
	)
	(via
		(at 246.56923 -137.091674)
		(size 0.508)
		(drill 0.254)
		(layers "F.Cu" "B.Cu")
		(net "P12V_NIC4_R")
	)
	(via
		(at 246.56923 -137.726674)
		(size 0.508)
		(drill 0.254)
		(layers "F.Cu" "B.Cu")
		(net "P12V_NIC4_R")
	)
	(via
		(at 244.047264 -145.083276)
		(size 0.508)
		(drill 0.254)
		(layers "F.Cu" "B.Cu")
		(net "P12V_NIC4_R")
	)
	(via
		(at 244.047264 -141.019276)
		(size 0.508)
		(drill 0.254)
		(layers "F.Cu" "B.Cu")
		(net "P12V_NIC4_R")
	)
	(via
		(at 249.526552 -139.284964)
		(size 0.508)
		(drill 0.254)
		(layers "F.Cu" "B.Cu")
		(net "P12V_NIC4_R")
	)
	(via
		(at 251.431552 -139.284964)
		(size 0.508)
		(drill 0.254)
		(layers "F.Cu" "B.Cu")
		(net "P12V_NIC4_R")
	)
	(via
		(at 245.628668 -136.565132)
		(size 0.508)
		(drill 0.254)
		(layers "F.Cu" "B.Cu")
		(net "P12V_NIC4_R")
	)
	(via
		(at 245.19763 -154.371548)
		(size 0.508)
		(drill 0.254)
		(layers "F.Cu" "B.Cu")
		(net "P12V_NIC4_R")
	)
	(via
		(at 248.488962 -138.40333)
		(size 0.508)
		(drill 0.254)
		(layers "F.Cu" "B.Cu")
		(net "P12V_NIC4_R")
	)
	(via
		(at 245.628668 -137.276332)
		(size 0.508)
		(drill 0.254)
		(layers "F.Cu" "B.Cu")
		(net "P12V_NIC4_R")
	)
	(via
		(at 251.230384 -144.901412)
		(size 0.508)
		(drill 0.254)
		(layers "F.Cu" "B.Cu")
		(net "P12V_NIC4_R")
	)
	(segment
		(start 251.336302 -147.094956)
		(end 251.336302 -146.426936)
		(width 0.508)
		(layer "B.Cu")
		(net "P12V_NIC4_R")
	)
	(segment
		(start 254.46355 -147.741386)
		(end 254.405892 -147.799044)
		(width 0.508)
		(layer "B.Cu")
		(net "P12V_NIC4_R")
	)
	(segment
		(start 252.04039 -147.799044)
		(end 251.336302 -147.094956)
		(width 0.508)
		(layer "B.Cu")
		(net "P12V_NIC4_R")
	)
	(segment
		(start 254.405892 -147.799044)
		(end 252.04039 -147.799044)
		(width 0.508)
		(layer "B.Cu")
		(net "P12V_NIC4_R")
	)
	(segment
		(start 135.518652 -150.71344)
		(end 136.499854 -150.71344)
		(width 0.13208)
		(layer "F.Cu")
		(net "NIC2_ADC_A1")
	)
	(segment
		(start 138.37158 -152.3111)
		(end 137.35558 -152.3111)
		(width 0.13208)
		(layer "F.Cu")
		(net "NIC2_ADC_A1")
	)
	(segment
		(start 136.499854 -150.71344)
		(end 137.35558 -151.569166)
		(width 0.13208)
		(layer "F.Cu")
		(net "NIC2_ADC_A1")
	)
	(segment
		(start 137.35558 -151.569166)
		(end 137.35558 -152.3111)
		(width 0.13208)
		(layer "F.Cu")
		(net "NIC2_ADC_A1")
	)
	(via
		(at 137.35558 -151.569166)
		(size 0.508)
		(drill 0.254)
		(layers "F.Cu" "B.Cu")
		(net "NIC2_ADC_A1")
	)
	(segment
		(start 218.75369 -100.841556)
		(end 218.75369 -100.076)
		(width 0.13208)
		(layer "F.Cu")
		(net "NIC3_ADC_ALERT_N")
	)
	(segment
		(start 218.75369 -100.076)
		(end 218.75369 -99.676204)
		(width 0.13208)
		(layer "F.Cu")
		(net "NIC3_ADC_ALERT_N")
	)
	(segment
		(start 218.75369 -99.676204)
		(end 219.223844 -99.20605)
		(width 0.13208)
		(layer "F.Cu")
		(net "NIC3_ADC_ALERT_N")
	)
	(via
		(at 218.75369 -100.076)
		(size 0.508)
		(drill 0.254)
		(layers "F.Cu" "B.Cu")
		(net "NIC3_ADC_ALERT_N")
	)
	(segment
		(start 15.159736 -153.782522)
		(end 15.159736 -151.123904)
		(width 0.13208)
		(layer "F.Cu")
		(net "SMB_NIC0_ADC_SCL")
	)
	(segment
		(start 15.159736 -151.123904)
		(end 16.220186 -150.063454)
		(width 0.13208)
		(layer "F.Cu")
		(net "SMB_NIC0_ADC_SCL")
	)
	(segment
		(start 94.339918 -89.87028)
		(end 93.853 -90.357198)
		(width 0.13208)
		(layer "F.Cu")
		(net "SMB_NIC0_ADC_SCL")
	)
	(segment
		(start 94.216474 -92.191586)
		(end 94.216474 -92.529406)
		(width 0.13208)
		(layer "F.Cu")
		(net "SMB_NIC0_ADC_SCL")
	)
	(segment
		(start 16.220186 -150.063454)
		(end 17.268698 -150.063454)
		(width 0.13208)
		(layer "F.Cu")
		(net "SMB_NIC0_ADC_SCL")
	)
	(segment
		(start 93.853 -91.828112)
		(end 94.216474 -92.191586)
		(width 0.13208)
		(layer "F.Cu")
		(net "SMB_NIC0_ADC_SCL")
	)
	(segment
		(start 93.853 -90.357198)
		(end 93.853 -91.828112)
		(width 0.13208)
		(layer "F.Cu")
		(net "SMB_NIC0_ADC_SCL")
	)
	(via
		(at 94.339918 -89.87028)
		(size 0.508)
		(drill 0.254)
		(layers "F.Cu" "B.Cu")
		(net "SMB_NIC0_ADC_SCL")
	)
	(via
		(at 24.95677 -95.12554)
		(size 0.508)
		(drill 0.254)
		(layers "F.Cu" "B.Cu")
		(net "SMB_NIC0_ADC_SCL")
	)
	(via
		(at 16.220186 -150.063454)
		(size 0.508)
		(drill 0.254)
		(layers "F.Cu" "B.Cu")
		(net "SMB_NIC0_ADC_SCL")
	)
	(via
		(at 15.159736 -153.782522)
		(size 0.508)
		(drill 0.254)
		(layers "F.Cu" "B.Cu")
		(net "SMB_NIC0_ADC_SCL")
	)
	(segment
		(start 22.429978 -152.27046)
		(end 23.411688 -151.28875)
		(width 0.15494)
		(layer "In5.Cu")
		(net "SMB_NIC0_ADC_SCL")
	)
	(segment
		(start 16.677894 -152.272238)
		(end 16.679672 -152.27046)
		(width 0.15494)
		(layer "In5.Cu")
		(net "SMB_NIC0_ADC_SCL")
	)
	(segment
		(start 23.411688 -151.28875)
		(end 23.411688 -95.980504)
		(width 0.15494)
		(layer "In5.Cu")
		(net "SMB_NIC0_ADC_SCL")
	)
	(segment
		(start 23.411688 -95.980504)
		(end 24.266652 -95.12554)
		(width 0.15494)
		(layer "In5.Cu")
		(net "SMB_NIC0_ADC_SCL")
	)
	(segment
		(start 24.266652 -95.12554)
		(end 24.95677 -95.12554)
		(width 0.15494)
		(layer "In5.Cu")
		(net "SMB_NIC0_ADC_SCL")
	)
	(segment
		(start 15.159736 -153.782522)
		(end 16.67002 -152.272238)
		(width 0.15494)
		(layer "In5.Cu")
		(net "SMB_NIC0_ADC_SCL")
	)
	(segment
		(start 16.67002 -152.272238)
		(end 16.677894 -152.272238)
		(width 0.15494)
		(layer "In5.Cu")
		(net "SMB_NIC0_ADC_SCL")
	)
	(segment
		(start 16.679672 -152.27046)
		(end 22.429978 -152.27046)
		(width 0.15494)
		(layer "In5.Cu")
		(net "SMB_NIC0_ADC_SCL")
	)
	(segment
		(start 93.792802 -89.323164)
		(end 94.339918 -89.87028)
		(width 0.15494)
		(layer "In15.Cu")
		(net "SMB_NIC0_ADC_SCL")
	)
	(segment
		(start 24.95677 -95.12554)
		(end 30.25267 -89.82964)
		(width 0.15494)
		(layer "In15.Cu")
		(net "SMB_NIC0_ADC_SCL")
	)
	(segment
		(start 87.752936 -89.323164)
		(end 93.792802 -89.323164)
		(width 0.15494)
		(layer "In15.Cu")
		(net "SMB_NIC0_ADC_SCL")
	)
	(segment
		(start 75.201526 -89.82964)
		(end 78.507082 -93.135196)
		(width 0.15494)
		(layer "In15.Cu")
		(net "SMB_NIC0_ADC_SCL")
	)
	(segment
		(start 83.940904 -93.135196)
		(end 87.752936 -89.323164)
		(width 0.15494)
		(layer "In15.Cu")
		(net "SMB_NIC0_ADC_SCL")
	)
	(segment
		(start 30.25267 -89.82964)
		(end 75.201526 -89.82964)
		(width 0.15494)
		(layer "In15.Cu")
		(net "SMB_NIC0_ADC_SCL")
	)
	(segment
		(start 78.507082 -93.135196)
		(end 83.940904 -93.135196)
		(width 0.15494)
		(layer "In15.Cu")
		(net "SMB_NIC0_ADC_SCL")
	)
	(segment
		(start 98.965258 -224.753424)
		(end 98.965258 -223.96704)
		(width 0.254)
		(layer "F.Cu")
		(net "P1V8_PEX_R")
	)
	(segment
		(start 100.82403 -246.83212)
		(end 100.075492 -246.83212)
		(width 0.381)
		(layer "F.Cu")
		(net "P1V8_PEX_R")
	)
	(segment
		(start 98.650552 -236.339888)
		(end 98.43135 -236.120686)
		(width 0.254)
		(layer "F.Cu")
		(net "P1V8_PEX_R")
	)
	(segment
		(start 99.41814 -236.339888)
		(end 98.650552 -236.339888)
		(width 0.254)
		(layer "F.Cu")
		(net "P1V8_PEX_R")
	)
	(segment
		(start 99.41814 -236.339888)
		(end 99.469956 -236.391704)
		(width 0.254)
		(layer "F.Cu")
		(net "P1V8_PEX_R")
	)
	(segment
		(start 98.43135 -236.120686)
		(end 98.43135 -225.287332)
		(width 0.254)
		(layer "F.Cu")
		(net "P1V8_PEX_R")
	)
	(segment
		(start 98.43135 -225.287332)
		(end 98.965258 -224.753424)
		(width 0.254)
		(layer "F.Cu")
		(net "P1V8_PEX_R")
	)
	(via
		(at 101.389942 -243.704872)
		(size 0.508)
		(drill 0.254)
		(layers "F.Cu" "B.Cu")
		(net "P1V8_PEX_R")
	)
	(via
		(at 102.862634 -242.889024)
		(size 0.508)
		(drill 0.254)
		(layers "F.Cu" "B.Cu")
		(net "P1V8_PEX_R")
	)
	(via
		(at 101.884734 -236.140244)
		(size 0.508)
		(drill 0.254)
		(layers "F.Cu" "B.Cu")
		(net "P1V8_PEX_R")
	)
	(via
		(at 102.915466 -243.598954)
		(size 0.508)
		(drill 0.254)
		(layers "F.Cu" "B.Cu")
		(net "P1V8_PEX_R")
	)
	(via
		(at 103.916734 -236.140244)
		(size 0.508)
		(drill 0.254)
		(layers "F.Cu" "B.Cu")
		(net "P1V8_PEX_R")
	)
	(via
		(at 100.075492 -246.83212)
		(size 0.508)
		(drill 0.254)
		(layers "F.Cu" "B.Cu")
		(net "P1V8_PEX_R")
	)
	(via
		(at 103.916734 -236.775244)
		(size 0.508)
		(drill 0.254)
		(layers "F.Cu" "B.Cu")
		(net "P1V8_PEX_R")
	)
	(via
		(at 107.980734 -236.140244)
		(size 0.508)
		(drill 0.254)
		(layers "F.Cu" "B.Cu")
		(net "P1V8_PEX_R")
	)
	(via
		(at 99.469956 -236.391704)
		(size 0.508)
		(drill 0.254)
		(layers "F.Cu" "B.Cu")
		(net "P1V8_PEX_R")
	)
	(via
		(at 102.197916 -242.94211)
		(size 0.508)
		(drill 0.254)
		(layers "F.Cu" "B.Cu")
		(net "P1V8_PEX_R")
	)
	(via
		(at 105.948734 -236.775244)
		(size 0.508)
		(drill 0.254)
		(layers "F.Cu" "B.Cu")
		(net "P1V8_PEX_R")
	)
	(via
		(at 107.980734 -236.775244)
		(size 0.508)
		(drill 0.254)
		(layers "F.Cu" "B.Cu")
		(net "P1V8_PEX_R")
	)
	(via
		(at 101.884734 -236.775244)
		(size 0.508)
		(drill 0.254)
		(layers "F.Cu" "B.Cu")
		(net "P1V8_PEX_R")
	)
	(via
		(at 105.948734 -236.140244)
		(size 0.508)
		(drill 0.254)
		(layers "F.Cu" "B.Cu")
		(net "P1V8_PEX_R")
	)
	(via
		(at 102.099872 -243.614194)
		(size 0.508)
		(drill 0.254)
		(layers "F.Cu" "B.Cu")
		(net "P1V8_PEX_R")
	)
	(segment
		(start 94.02064 -98.636328)
		(end 94.02064 -99.458526)
		(width 0.13208)
		(layer "F.Cu")
		(net "SMB_NIC1_ADC_SCL")
	)
	(segment
		(start 94.02064 -99.458526)
		(end 94.019878 -99.459288)
		(width 0.13208)
		(layer "F.Cu")
		(net "SMB_NIC1_ADC_SCL")
	)
	(segment
		(start 94.103444 -97.211642)
		(end 94.103444 -98.553524)
		(width 0.13208)
		(layer "F.Cu")
		(net "SMB_NIC1_ADC_SCL")
	)
	(segment
		(start 94.103444 -98.553524)
		(end 94.02064 -98.636328)
		(width 0.13208)
		(layer "F.Cu")
		(net "SMB_NIC1_ADC_SCL")
	)
	(segment
		(start 94.019878 -99.459288)
		(end 92.712032 -99.459288)
		(width 0.13208)
		(layer "F.Cu")
		(net "SMB_NIC1_ADC_SCL")
	)
	(via
		(at 94.02064 -99.458526)
		(size 0.508)
		(drill 0.254)
		(layers "F.Cu" "B.Cu")
		(net "SMB_NIC1_ADC_SCL")
	)
	(segment
		(start 22.263608 -147.52193)
		(end 22.044152 -147.741386)
		(width 0.4064)
		(layer "F.Cu")
		(net "P12V_NIC0_R")
	)
	(segment
		(start 22.263608 -146.992848)
		(end 22.263608 -147.52193)
		(width 0.4064)
		(layer "F.Cu")
		(net "P12V_NIC0_R")
	)
	(segment
		(start 11.423904 -150.797006)
		(end 6.998462 -150.797006)
		(width 0.254)
		(layer "F.Cu")
		(net "P12V_NIC0_R")
	)
	(segment
		(start 6.652768 -151.1427)
		(end 6.652768 -155.888944)
		(width 0.254)
		(layer "F.Cu")
		(net "P12V_NIC0_R")
	)
	(segment
		(start 11.444478 -150.81758)
		(end 11.423904 -150.797006)
		(width 0.254)
		(layer "F.Cu")
		(net "P12V_NIC0_R")
	)
	(segment
		(start 6.998462 -150.797006)
		(end 6.652768 -151.1427)
		(width 0.254)
		(layer "F.Cu")
		(net "P12V_NIC0_R")
	)
	(via
		(at 17.323308 -138.525758)
		(size 0.508)
		(drill 0.254)
		(layers "F.Cu" "B.Cu")
		(net "P12V_NIC0_R")
	)
	(via
		(at 11.847322 -145.083276)
		(size 0.508)
		(drill 0.254)
		(layers "F.Cu" "B.Cu")
		(net "P12V_NIC0_R")
	)
	(via
		(at 11.847322 -143.051276)
		(size 0.508)
		(drill 0.254)
		(layers "F.Cu" "B.Cu")
		(net "P12V_NIC0_R")
	)
	(via
		(at 18.320512 -144.954244)
		(size 0.508)
		(drill 0.254)
		(layers "F.Cu" "B.Cu")
		(net "P12V_NIC0_R")
	)
	(via
		(at 17.323308 -137.255758)
		(size 0.508)
		(drill 0.254)
		(layers "F.Cu" "B.Cu")
		(net "P12V_NIC0_R")
	)
	(via
		(at 11.5316 -150.16861)
		(size 0.508)
		(drill 0.254)
		(layers "F.Cu" "B.Cu")
		(net "P12V_NIC0_R")
	)
	(via
		(at 22.044152 -147.741386)
		(size 0.508)
		(drill 0.254)
		(layers "F.Cu" "B.Cu")
		(net "P12V_NIC0_R")
	)
	(via
		(at 18.589752 -139.282932)
		(size 0.508)
		(drill 0.254)
		(layers "F.Cu" "B.Cu")
		(net "P12V_NIC0_R")
	)
	(via
		(at 11.575288 -154.371548)
		(size 0.508)
		(drill 0.254)
		(layers "F.Cu" "B.Cu")
		(net "P12V_NIC0_R")
	)
	(via
		(at 13.708888 -154.371548)
		(size 0.508)
		(drill 0.254)
		(layers "F.Cu" "B.Cu")
		(net "P12V_NIC0_R")
	)
	(via
		(at 19.030442 -144.901412)
		(size 0.508)
		(drill 0.254)
		(layers "F.Cu" "B.Cu")
		(net "P12V_NIC0_R")
	)
	(via
		(at 14.369288 -137.091674)
		(size 0.508)
		(drill 0.254)
		(layers "F.Cu" "B.Cu")
		(net "P12V_NIC0_R")
	)
	(via
		(at 12.954 -150.16861)
		(size 0.508)
		(drill 0.254)
		(layers "F.Cu" "B.Cu")
		(net "P12V_NIC0_R")
	)
	(via
		(at 17.954752 -139.282932)
		(size 0.508)
		(drill 0.254)
		(layers "F.Cu" "B.Cu")
		(net "P12V_NIC0_R")
	)
	(via
		(at 17.323308 -136.620758)
		(size 0.508)
		(drill 0.254)
		(layers "F.Cu" "B.Cu")
		(net "P12V_NIC0_R")
	)
	(via
		(at 12.286488 -155.082748)
		(size 0.508)
		(drill 0.254)
		(layers "F.Cu" "B.Cu")
		(net "P12V_NIC0_R")
	)
	(via
		(at 19.13636 -146.426936)
		(size 0.508)
		(drill 0.254)
		(layers "F.Cu" "B.Cu")
		(net "P12V_NIC0_R")
	)
	(via
		(at 19.045682 -145.717006)
		(size 0.508)
		(drill 0.254)
		(layers "F.Cu" "B.Cu")
		(net "P12V_NIC0_R")
	)
	(via
		(at 19.224752 -139.282932)
		(size 0.508)
		(drill 0.254)
		(layers "F.Cu" "B.Cu")
		(net "P12V_NIC0_R")
	)
	(via
		(at 13.428726 -136.641332)
		(size 0.508)
		(drill 0.254)
		(layers "F.Cu" "B.Cu")
		(net "P12V_NIC0_R")
	)
	(via
		(at 17.319752 -139.282932)
		(size 0.508)
		(drill 0.254)
		(layers "F.Cu" "B.Cu")
		(net "P12V_NIC0_R")
	)
	(via
		(at 18.373598 -145.618962)
		(size 0.508)
		(drill 0.254)
		(layers "F.Cu" "B.Cu")
		(net "P12V_NIC0_R")
	)
	(via
		(at 12.2428 -150.16861)
		(size 0.508)
		(drill 0.254)
		(layers "F.Cu" "B.Cu")
		(net "P12V_NIC0_R")
	)
	(via
		(at 16.28902 -137.64133)
		(size 0.508)
		(drill 0.254)
		(layers "F.Cu" "B.Cu")
		(net "P12V_NIC0_R")
	)
	(via
		(at 11.847322 -141.019276)
		(size 0.508)
		(drill 0.254)
		(layers "F.Cu" "B.Cu")
		(net "P12V_NIC0_R")
	)
	(via
		(at 11.575288 -155.082748)
		(size 0.508)
		(drill 0.254)
		(layers "F.Cu" "B.Cu")
		(net "P12V_NIC0_R")
	)
	(via
		(at 11.5316 -147.630388)
		(size 0.508)
		(drill 0.254)
		(layers "F.Cu" "B.Cu")
		(net "P12V_NIC0_R")
	)
	(via
		(at 12.997688 -155.082748)
		(size 0.508)
		(drill 0.254)
		(layers "F.Cu" "B.Cu")
		(net "P12V_NIC0_R")
	)
	(via
		(at 17.323308 -137.890758)
		(size 0.508)
		(drill 0.254)
		(layers "F.Cu" "B.Cu")
		(net "P12V_NIC0_R")
	)
	(via
		(at 11.136122 -141.019276)
		(size 0.508)
		(drill 0.254)
		(layers "F.Cu" "B.Cu")
		(net "P12V_NIC0_R")
	)
	(via
		(at 14.369288 -137.726674)
		(size 0.508)
		(drill 0.254)
		(layers "F.Cu" "B.Cu")
		(net "P12V_NIC0_R")
	)
	(via
		(at 12.286488 -154.371548)
		(size 0.508)
		(drill 0.254)
		(layers "F.Cu" "B.Cu")
		(net "P12V_NIC0_R")
	)
	(via
		(at 12.997688 -154.371548)
		(size 0.508)
		(drill 0.254)
		(layers "F.Cu" "B.Cu")
		(net "P12V_NIC0_R")
	)
	(via
		(at 12.2428 -147.630388)
		(size 0.508)
		(drill 0.254)
		(layers "F.Cu" "B.Cu")
		(net "P12V_NIC0_R")
	)
	(via
		(at 15.57782 -138.40333)
		(size 0.508)
		(drill 0.254)
		(layers "F.Cu" "B.Cu")
		(net "P12V_NIC0_R")
	)
	(via
		(at 13.428726 -137.276332)
		(size 0.508)
		(drill 0.254)
		(layers "F.Cu" "B.Cu")
		(net "P12V_NIC0_R")
	)
	(via
		(at 11.136122 -145.083276)
		(size 0.508)
		(drill 0.254)
		(layers "F.Cu" "B.Cu")
		(net "P12V_NIC0_R")
	)
	(via
		(at 15.65402 -137.64133)
		(size 0.508)
		(drill 0.254)
		(layers "F.Cu" "B.Cu")
		(net "P12V_NIC0_R")
	)
	(via
		(at 16.28902 -138.40333)
		(size 0.508)
		(drill 0.254)
		(layers "F.Cu" "B.Cu")
		(net "P12V_NIC0_R")
	)
	(via
		(at 12.954 -147.630388)
		(size 0.508)
		(drill 0.254)
		(layers "F.Cu" "B.Cu")
		(net "P12V_NIC0_R")
	)
	(via
		(at 11.136122 -143.051276)
		(size 0.508)
		(drill 0.254)
		(layers "F.Cu" "B.Cu")
		(net "P12V_NIC0_R")
	)
	(via
		(at 13.708888 -155.082748)
		(size 0.508)
		(drill 0.254)
		(layers "F.Cu" "B.Cu")
		(net "P12V_NIC0_R")
	)
	(segment
		(start 218.635834 -99.03206)
		(end 218.635834 -97.32899)
		(width 0.13208)
		(layer "F.Cu")
		(net "NIC3_ADC_A0")
	)
	(segment
		(start 218.080844 -99.20605)
		(end 218.461844 -99.20605)
		(width 0.13208)
		(layer "F.Cu")
		(net "NIC3_ADC_A0")
	)
	(segment
		(start 218.253818 -99.994974)
		(end 218.253818 -100.841556)
		(width 0.13208)
		(layer "F.Cu")
		(net "NIC3_ADC_A0")
	)
	(segment
		(start 218.461844 -99.20605)
		(end 218.635834 -99.03206)
		(width 0.13208)
		(layer "F.Cu")
		(net "NIC3_ADC_A0")
	)
	(segment
		(start 218.080844 -97.155)
		(end 218.080844 -96.53905)
		(width 0.13208)
		(layer "F.Cu")
		(net "NIC3_ADC_A0")
	)
	(segment
		(start 218.588844 -97.282)
		(end 218.207844 -97.282)
		(width 0.13208)
		(layer "F.Cu")
		(net "NIC3_ADC_A0")
	)
	(segment
		(start 218.080844 -99.20605)
		(end 218.080844 -99.822)
		(width 0.13208)
		(layer "F.Cu")
		(net "NIC3_ADC_A0")
	)
	(segment
		(start 218.207844 -97.282)
		(end 218.080844 -97.155)
		(width 0.13208)
		(layer "F.Cu")
		(net "NIC3_ADC_A0")
	)
	(segment
		(start 218.080844 -99.822)
		(end 218.253818 -99.994974)
		(width 0.13208)
		(layer "F.Cu")
		(net "NIC3_ADC_A0")
	)
	(segment
		(start 218.635834 -97.32899)
		(end 218.588844 -97.282)
		(width 0.13208)
		(layer "F.Cu")
		(net "NIC3_ADC_A0")
	)
	(via
		(at 218.588844 -97.282)
		(size 0.508)
		(drill 0.254)
		(layers "F.Cu" "B.Cu")
		(net "NIC3_ADC_A0")
	)
	(segment
		(start 218.901264 -98.61423)
		(end 218.901264 -97.59442)
		(width 0.13208)
		(layer "B.Cu")
		(net "NIC3_ADC_A0")
	)
	(segment
		(start 218.901264 -97.59442)
		(end 218.588844 -97.282)
		(width 0.13208)
		(layer "B.Cu")
		(net "NIC3_ADC_A0")
	)
	(segment
		(start 93.087444 -97.821242)
		(end 93.087444 -97.211642)
		(width 0.13208)
		(layer "F.Cu")
		(net "SMB_NIC1_ADC_SDA")
	)
	(segment
		(start 92.189046 -98.323146)
		(end 92.960444 -98.323146)
		(width 0.13208)
		(layer "F.Cu")
		(net "SMB_NIC1_ADC_SDA")
	)
	(segment
		(start 92.062046 -98.450146)
		(end 92.189046 -98.323146)
		(width 0.13208)
		(layer "F.Cu")
		(net "SMB_NIC1_ADC_SDA")
	)
	(segment
		(start 93.087444 -98.196146)
		(end 93.087444 -97.821242)
		(width 0.13208)
		(layer "F.Cu")
		(net "SMB_NIC1_ADC_SDA")
	)
	(segment
		(start 92.960444 -98.323146)
		(end 93.087444 -98.196146)
		(width 0.13208)
		(layer "F.Cu")
		(net "SMB_NIC1_ADC_SDA")
	)
	(segment
		(start 92.062046 -98.809302)
		(end 92.062046 -98.450146)
		(width 0.13208)
		(layer "F.Cu")
		(net "SMB_NIC1_ADC_SDA")
	)
	(via
		(at 93.087444 -97.821242)
		(size 0.508)
		(drill 0.254)
		(layers "F.Cu" "B.Cu")
		(net "SMB_NIC1_ADC_SDA")
	)
	(segment
		(start 394.038582 -44.741592)
		(end 394.374624 -44.741592)
		(width 0.254)
		(layer "F.Cu")
		(net "P12V_SSD13_VIN_N")
	)
	(segment
		(start 394.747496 -45.114464)
		(end 395.32687 -45.693838)
		(width 0.254)
		(layer "F.Cu")
		(net "P12V_SSD13_VIN_N")
	)
	(segment
		(start 395.32687 -45.693838)
		(end 395.74597 -45.693838)
		(width 0.254)
		(layer "F.Cu")
		(net "P12V_SSD13_VIN_N")
	)
	(segment
		(start 393.022582 -44.741592)
		(end 394.038582 -44.741592)
		(width 0.254)
		(layer "F.Cu")
		(net "P12V_SSD13_VIN_N")
	)
	(segment
		(start 394.374624 -44.741592)
		(end 394.747496 -45.114464)
		(width 0.254)
		(layer "F.Cu")
		(net "P12V_SSD13_VIN_N")
	)
	(via
		(at 394.747496 -45.114464)
		(size 0.508)
		(drill 0.254)
		(layers "F.Cu" "B.Cu")
		(net "P12V_SSD13_VIN_N")
	)
	(segment
		(start 136.470898 -145.189956)
		(end 136.470898 -146.205956)
		(width 0.254)
		(layer "F.Cu")
		(net "P12V_NIC2_VIN_N")
	)
	(segment
		(start 136.470898 -146.541998)
		(end 136.470898 -146.205956)
		(width 0.254)
		(layer "F.Cu")
		(net "P12V_NIC2_VIN_N")
	)
	(segment
		(start 136.098026 -146.91487)
		(end 136.470898 -146.541998)
		(width 0.254)
		(layer "F.Cu")
		(net "P12V_NIC2_VIN_N")
	)
	(segment
		(start 135.518652 -147.494244)
		(end 136.098026 -146.91487)
		(width 0.254)
		(layer "F.Cu")
		(net "P12V_NIC2_VIN_N")
	)
	(segment
		(start 135.518652 -147.913344)
		(end 135.518652 -147.494244)
		(width 0.254)
		(layer "F.Cu")
		(net "P12V_NIC2_VIN_N")
	)
	(via
		(at 136.098026 -146.91487)
		(size 0.508)
		(drill 0.254)
		(layers "F.Cu" "B.Cu")
		(net "P12V_NIC2_VIN_N")
	)
	(segment
		(start 398.963642 -46.193964)
		(end 398.546066 -46.193964)
		(width 0.13208)
		(layer "F.Cu")
		(net "SSD13_ADC_A0")
	)
	(segment
		(start 399.38579 -45.35424)
		(end 399.38579 -45.695616)
		(width 0.13208)
		(layer "F.Cu")
		(net "SSD13_ADC_A0")
	)
	(segment
		(start 399.38579 -45.695616)
		(end 399.38579 -45.771816)
		(width 0.13208)
		(layer "F.Cu")
		(net "SSD13_ADC_A0")
	)
	(segment
		(start 400.143726 -45.88891)
		(end 399.579084 -45.88891)
		(width 0.13208)
		(layer "F.Cu")
		(net "SSD13_ADC_A0")
	)
	(segment
		(start 399.579084 -45.88891)
		(end 399.38579 -45.695616)
		(width 0.13208)
		(layer "F.Cu")
		(net "SSD13_ADC_A0")
	)
	(segment
		(start 400.143726 -44.87291)
		(end 400.143726 -45.88891)
		(width 0.13208)
		(layer "F.Cu")
		(net "SSD13_ADC_A0")
	)
	(segment
		(start 399.38579 -45.771816)
		(end 398.963642 -46.193964)
		(width 0.13208)
		(layer "F.Cu")
		(net "SSD13_ADC_A0")
	)
	(via
		(at 399.38579 -45.35424)
		(size 0.508)
		(drill 0.254)
		(layers "F.Cu" "B.Cu")
		(net "SSD13_ADC_A0")
	)
	(segment
		(start 216.816432 -102.991666)
		(end 217.103706 -102.991666)
		(width 0.249936)
		(layer "F.Cu")
		(net "P12V_NIC3_VIN_P")
	)
	(segment
		(start 216.001346 -105.34904)
		(end 216.001346 -104.697784)
		(width 0.249936)
		(layer "F.Cu")
		(net "P12V_NIC3_VIN_P")
	)
	(segment
		(start 216.001346 -104.697784)
		(end 215.796114 -104.492552)
		(width 0.249936)
		(layer "F.Cu")
		(net "P12V_NIC3_VIN_P")
	)
	(segment
		(start 215.796114 -104.011984)
		(end 216.816432 -102.991666)
		(width 0.249936)
		(layer "F.Cu")
		(net "P12V_NIC3_VIN_P")
	)
	(segment
		(start 215.796114 -104.492552)
		(end 215.796114 -104.011984)
		(width 0.249936)
		(layer "F.Cu")
		(net "P12V_NIC3_VIN_P")
	)
	(segment
		(start 216.001346 -105.34904)
		(end 214.9221 -105.34904)
		(width 0.254)
		(layer "F.Cu")
		(net "P12V_NIC3_VIN_P")
	)
	(segment
		(start 214.9221 -105.34904)
		(end 214.908892 -105.362248)
		(width 0.254)
		(layer "F.Cu")
		(net "P12V_NIC3_VIN_P")
	)
	(via
		(at 215.796114 -104.492552)
		(size 0.508)
		(drill 0.254)
		(layers "F.Cu" "B.Cu")
		(net "P12V_NIC3_VIN_P")
	)
	(segment
		(start 211.336382 -253.85268)
		(end 202.210162 -253.85268)
		(width 0.13208)
		(layer "F.Cu")
		(net "PWRGD_P1V8_PEX_R")
	)
	(segment
		(start 213.197186 -244.686582)
		(end 213.197186 -251.991876)
		(width 0.13208)
		(layer "F.Cu")
		(net "PWRGD_P1V8_PEX_R")
	)
	(segment
		(start 334.89392 -224.786952)
		(end 334.49768 -225.183192)
		(width 0.13208)
		(layer "F.Cu")
		(net "PWRGD_P1V8_PEX_R")
	)
	(segment
		(start 318.62395 -288.830766)
		(end 319.003934 -288.830766)
		(width 0.13208)
		(layer "F.Cu")
		(net "PWRGD_P1V8_PEX_R")
	)
	(segment
		(start 213.197186 -251.991876)
		(end 211.336382 -253.85268)
		(width 0.13208)
		(layer "F.Cu")
		(net "PWRGD_P1V8_PEX_R")
	)
	(segment
		(start 334.49768 -225.183192)
		(end 333.095092 -225.183192)
		(width 0.13208)
		(layer "F.Cu")
		(net "PWRGD_P1V8_PEX_R")
	)
	(segment
		(start 333.095092 -225.183192)
		(end 332.907386 -225.370898)
		(width 0.13208)
		(layer "F.Cu")
		(net "PWRGD_P1V8_PEX_R")
	)
	(segment
		(start 86.424008 -288.830766)
		(end 86.803992 -288.830766)
		(width 0.13208)
		(layer "F.Cu")
		(net "PWRGD_P1V8_PEX_R")
	)
	(segment
		(start 86.169754 -289.08502)
		(end 86.424008 -288.830766)
		(width 0.13208)
		(layer "F.Cu")
		(net "PWRGD_P1V8_PEX_R")
	)
	(segment
		(start 434.469794 -289.08502)
		(end 434.724048 -288.830766)
		(width 0.13208)
		(layer "F.Cu")
		(net "PWRGD_P1V8_PEX_R")
	)
	(segment
		(start 202.524106 -288.830766)
		(end 202.269852 -289.08502)
		(width 0.13208)
		(layer "F.Cu")
		(net "PWRGD_P1V8_PEX_R")
	)
	(segment
		(start 318.369696 -289.08502)
		(end 318.62395 -288.830766)
		(width 0.13208)
		(layer "F.Cu")
		(net "PWRGD_P1V8_PEX_R")
	)
	(segment
		(start 434.724048 -288.830766)
		(end 435.104032 -288.830766)
		(width 0.13208)
		(layer "F.Cu")
		(net "PWRGD_P1V8_PEX_R")
	)
	(segment
		(start 332.787244 -225.370898)
		(end 332.28788 -225.870262)
		(width 0.13208)
		(layer "F.Cu")
		(net "PWRGD_P1V8_PEX_R")
	)
	(segment
		(start 202.210162 -253.85268)
		(end 200.3044 -255.758442)
		(width 0.13208)
		(layer "F.Cu")
		(net "PWRGD_P1V8_PEX_R")
	)
	(segment
		(start 202.90409 -288.830766)
		(end 202.524106 -288.830766)
		(width 0.13208)
		(layer "F.Cu")
		(net "PWRGD_P1V8_PEX_R")
	)
	(segment
		(start 332.907386 -225.370898)
		(end 332.787244 -225.370898)
		(width 0.13208)
		(layer "F.Cu")
		(net "PWRGD_P1V8_PEX_R")
	)
	(segment
		(start 101.303836 -218.57589)
		(end 97.399348 -218.57589)
		(width 0.13208)
		(layer "F.Cu")
		(net "PWRGD_P1V8_PEX_R")
	)
	(segment
		(start 213.467442 -244.416326)
		(end 213.197186 -244.686582)
		(width 0.13208)
		(layer "F.Cu")
		(net "PWRGD_P1V8_PEX_R")
	)
	(via
		(at 97.399348 -218.57589)
		(size 0.508)
		(drill 0.254)
		(layers "F.Cu" "B.Cu")
		(net "PWRGD_P1V8_PEX_R")
	)
	(via
		(at 98.541332 -206.6798)
		(size 0.508)
		(drill 0.254)
		(layers "F.Cu" "B.Cu")
		(net "PWRGD_P1V8_PEX_R")
	)
	(via
		(at 434.469794 -289.08502)
		(size 0.508)
		(drill 0.254)
		(layers "F.Cu" "B.Cu")
		(net "PWRGD_P1V8_PEX_R")
	)
	(via
		(at 332.28788 -225.870262)
		(size 0.508)
		(drill 0.254)
		(layers "F.Cu" "B.Cu")
		(net "PWRGD_P1V8_PEX_R")
	)
	(via
		(at 86.169754 -289.08502)
		(size 0.508)
		(drill 0.254)
		(layers "F.Cu" "B.Cu")
		(net "PWRGD_P1V8_PEX_R")
	)
	(via
		(at 318.369696 -289.08502)
		(size 0.508)
		(drill 0.254)
		(layers "F.Cu" "B.Cu")
		(net "PWRGD_P1V8_PEX_R")
	)
	(via
		(at 200.3044 -255.758442)
		(size 0.508)
		(drill 0.254)
		(layers "F.Cu" "B.Cu")
		(net "PWRGD_P1V8_PEX_R")
	)
	(via
		(at 186.182 -207.264)
		(size 0.508)
		(drill 0.254)
		(layers "F.Cu" "B.Cu")
		(net "PWRGD_P1V8_PEX_R")
	)
	(via
		(at 316.484 -257.7592)
		(size 0.508)
		(drill 0.254)
		(layers "F.Cu" "B.Cu")
		(net "PWRGD_P1V8_PEX_R")
	)
	(via
		(at 202.269852 -289.08502)
		(size 0.508)
		(drill 0.254)
		(layers "F.Cu" "B.Cu")
		(net "PWRGD_P1V8_PEX_R")
	)
	(via
		(at 444.970916 -251.789438)
		(size 0.508)
		(drill 0.254)
		(layers "F.Cu" "B.Cu")
		(net "PWRGD_P1V8_PEX_R")
	)
	(segment
		(start 196.00164 -253.420372)
		(end 196.00164 -229.530148)
		(width 0.13208)
		(layer "B.Cu")
		(net "PWRGD_P1V8_PEX_R")
	)
	(segment
		(start 318.98463 -263.769094)
		(end 318.98463 -260.00583)
		(width 0.13208)
		(layer "B.Cu")
		(net "PWRGD_P1V8_PEX_R")
	)
	(segment
		(start 431.640488 -264.21461)
		(end 444.06566 -251.789438)
		(width 0.13208)
		(layer "B.Cu")
		(net "PWRGD_P1V8_PEX_R")
	)
	(segment
		(start 199.473312 -254.927354)
		(end 197.508622 -254.927354)
		(width 0.13208)
		(layer "B.Cu")
		(net "PWRGD_P1V8_PEX_R")
	)
	(segment
		(start 200.3044 -255.758442)
		(end 199.473312 -254.927354)
		(width 0.13208)
		(layer "B.Cu")
		(net "PWRGD_P1V8_PEX_R")
	)
	(segment
		(start 195.941442 -268.603984)
		(end 195.941442 -258.976876)
		(width 0.13208)
		(layer "B.Cu")
		(net "PWRGD_P1V8_PEX_R")
	)
	(segment
		(start 199.747886 -272.410428)
		(end 195.941442 -268.603984)
		(width 0.13208)
		(layer "B.Cu")
		(net "PWRGD_P1V8_PEX_R")
	)
	(segment
		(start 316.738 -257.7592)
		(end 316.484 -257.7592)
		(width 0.13208)
		(layer "B.Cu")
		(net "PWRGD_P1V8_PEX_R")
	)
	(segment
		(start 202.269852 -289.08502)
		(end 202.269852 -276.289262)
		(width 0.13208)
		(layer "B.Cu")
		(net "PWRGD_P1V8_PEX_R")
	)
	(segment
		(start 199.82688 -220.90888)
		(end 186.182 -207.264)
		(width 0.13208)
		(layer "B.Cu")
		(net "PWRGD_P1V8_PEX_R")
	)
	(segment
		(start 315.73978 -273.626834)
		(end 315.73978 -267.013944)
		(width 0.13208)
		(layer "B.Cu")
		(net "PWRGD_P1V8_PEX_R")
	)
	(segment
		(start 444.06566 -251.789438)
		(end 444.970916 -251.789438)
		(width 0.13208)
		(layer "B.Cu")
		(net "PWRGD_P1V8_PEX_R")
	)
	(segment
		(start 199.353678 -256.709164)
		(end 200.3044 -255.758442)
		(width 0.13208)
		(layer "B.Cu")
		(net "PWRGD_P1V8_PEX_R")
	)
	(segment
		(start 198.209154 -256.709164)
		(end 199.353678 -256.709164)
		(width 0.13208)
		(layer "B.Cu")
		(net "PWRGD_P1V8_PEX_R")
	)
	(segment
		(start 434.469794 -289.08502)
		(end 434.469794 -276.55647)
		(width 0.13208)
		(layer "B.Cu")
		(net "PWRGD_P1V8_PEX_R")
	)
	(segment
		(start 318.369696 -276.25675)
		(end 315.73978 -273.626834)
		(width 0.13208)
		(layer "B.Cu")
		(net "PWRGD_P1V8_PEX_R")
	)
	(segment
		(start 431.640488 -273.727164)
		(end 431.640488 -264.21461)
		(width 0.13208)
		(layer "B.Cu")
		(net "PWRGD_P1V8_PEX_R")
	)
	(segment
		(start 434.469794 -276.55647)
		(end 431.640488 -273.727164)
		(width 0.13208)
		(layer "B.Cu")
		(net "PWRGD_P1V8_PEX_R")
	)
	(segment
		(start 197.508622 -254.927354)
		(end 196.00164 -253.420372)
		(width 0.13208)
		(layer "B.Cu")
		(net "PWRGD_P1V8_PEX_R")
	)
	(segment
		(start 315.73978 -267.013944)
		(end 318.98463 -263.769094)
		(width 0.13208)
		(layer "B.Cu")
		(net "PWRGD_P1V8_PEX_R")
	)
	(segment
		(start 196.00164 -229.530148)
		(end 199.82688 -225.704908)
		(width 0.13208)
		(layer "B.Cu")
		(net "PWRGD_P1V8_PEX_R")
	)
	(segment
		(start 318.369696 -289.08502)
		(end 318.369696 -276.25675)
		(width 0.13208)
		(layer "B.Cu")
		(net "PWRGD_P1V8_PEX_R")
	)
	(segment
		(start 318.98463 -260.00583)
		(end 316.738 -257.7592)
		(width 0.13208)
		(layer "B.Cu")
		(net "PWRGD_P1V8_PEX_R")
	)
	(segment
		(start 195.941442 -258.976876)
		(end 198.209154 -256.709164)
		(width 0.13208)
		(layer "B.Cu")
		(net "PWRGD_P1V8_PEX_R")
	)
	(segment
		(start 202.269852 -276.289262)
		(end 199.747886 -273.767296)
		(width 0.13208)
		(layer "B.Cu")
		(net "PWRGD_P1V8_PEX_R")
	)
	(segment
		(start 199.82688 -225.704908)
		(end 199.82688 -220.90888)
		(width 0.13208)
		(layer "B.Cu")
		(net "PWRGD_P1V8_PEX_R")
	)
	(segment
		(start 199.747886 -273.767296)
		(end 199.747886 -272.410428)
		(width 0.13208)
		(layer "B.Cu")
		(net "PWRGD_P1V8_PEX_R")
	)
	(segment
		(start 98.541332 -206.6798)
		(end 98.679 -206.817468)
		(width 0.15494)
		(layer "In5.Cu")
		(net "PWRGD_P1V8_PEX_R")
	)
	(segment
		(start 100.8888 -273.255486)
		(end 100.51288 -274.163028)
		(width 0.15494)
		(layer "In5.Cu")
		(net "PWRGD_P1V8_PEX_R")
	)
	(segment
		(start 92.3798 -284.4546)
		(end 92.3798 -288.417)
		(width 0.15494)
		(layer "In5.Cu")
		(net "PWRGD_P1V8_PEX_R")
	)
	(segment
		(start 91.71178 -289.08502)
		(end 86.169754 -289.08502)
		(width 0.15494)
		(layer "In5.Cu")
		(net "PWRGD_P1V8_PEX_R")
	)
	(segment
		(start 98.034094 -278.800306)
		(end 92.3798 -284.4546)
		(width 0.15494)
		(layer "In5.Cu")
		(net "PWRGD_P1V8_PEX_R")
	)
	(segment
		(start 96.2152 -219.760038)
		(end 96.2152 -240.8428)
		(width 0.15494)
		(layer "In5.Cu")
		(net "PWRGD_P1V8_PEX_R")
	)
	(segment
		(start 92.3798 -288.417)
		(end 91.71178 -289.08502)
		(width 0.15494)
		(layer "In5.Cu")
		(net "PWRGD_P1V8_PEX_R")
	)
	(segment
		(start 95.0976 -248.835164)
		(end 98.357182 -256.704846)
		(width 0.15494)
		(layer "In5.Cu")
		(net "PWRGD_P1V8_PEX_R")
	)
	(segment
		(start 97.399348 -218.57589)
		(end 96.2152 -219.760038)
		(width 0.15494)
		(layer "In5.Cu")
		(net "PWRGD_P1V8_PEX_R")
	)
	(segment
		(start 100.51288 -274.163028)
		(end 98.034094 -278.800306)
		(width 0.15494)
		(layer "In5.Cu")
		(net "PWRGD_P1V8_PEX_R")
	)
	(segment
		(start 96.2152 -240.8428)
		(end 95.0976 -241.9604)
		(width 0.15494)
		(layer "In5.Cu")
		(net "PWRGD_P1V8_PEX_R")
	)
	(segment
		(start 98.357182 -256.704846)
		(end 100.8888 -269.432024)
		(width 0.15494)
		(layer "In5.Cu")
		(net "PWRGD_P1V8_PEX_R")
	)
	(segment
		(start 98.679 -208.824322)
		(end 97.399348 -210.103974)
		(width 0.15494)
		(layer "In5.Cu")
		(net "PWRGD_P1V8_PEX_R")
	)
	(segment
		(start 95.0976 -241.9604)
		(end 95.0976 -248.835164)
		(width 0.15494)
		(layer "In5.Cu")
		(net "PWRGD_P1V8_PEX_R")
	)
	(segment
		(start 97.399348 -210.103974)
		(end 97.399348 -218.57589)
		(width 0.15494)
		(layer "In5.Cu")
		(net "PWRGD_P1V8_PEX_R")
	)
	(segment
		(start 100.8888 -269.432024)
		(end 100.8888 -273.255486)
		(width 0.15494)
		(layer "In5.Cu")
		(net "PWRGD_P1V8_PEX_R")
	)
	(segment
		(start 98.679 -206.817468)
		(end 98.679 -208.824322)
		(width 0.15494)
		(layer "In5.Cu")
		(net "PWRGD_P1V8_PEX_R")
	)
	(segment
		(start 332.756002 -249.987816)
		(end 332.756002 -259.457698)
		(width 0.15494)
		(layer "In7.Cu")
		(net "PWRGD_P1V8_PEX_R")
	)
	(segment
		(start 332.33741 -239.350296)
		(end 332.33741 -239.76965)
		(width 0.15494)
		(layer "In7.Cu")
		(net "PWRGD_P1V8_PEX_R")
	)
	(segment
		(start 334.6958 -248.048018)
		(end 332.756002 -249.987816)
		(width 0.15494)
		(layer "In7.Cu")
		(net "PWRGD_P1V8_PEX_R")
	)
	(segment
		(start 329.262232 -261.112)
		(end 326.366632 -258.2164)
		(width 0.15494)
		(layer "In7.Cu")
		(net "PWRGD_P1V8_PEX_R")
	)
	(segment
		(start 332.28788 -227.499926)
		(end 332.1812 -227.606606)
		(width 0.15494)
		(layer "In7.Cu")
		(net "PWRGD_P1V8_PEX_R")
	)
	(segment
		(start 332.756002 -259.457698)
		(end 331.1017 -261.112)
		(width 0.15494)
		(layer "In7.Cu")
		(net "PWRGD_P1V8_PEX_R")
	)
	(segment
		(start 326.366632 -258.2164)
		(end 316.9412 -258.2164)
		(width 0.15494)
		(layer "In7.Cu")
		(net "PWRGD_P1V8_PEX_R")
	)
	(segment
		(start 330.983336 -237.996222)
		(end 332.33741 -239.350296)
		(width 0.15494)
		(layer "In7.Cu")
		(net "PWRGD_P1V8_PEX_R")
	)
	(segment
		(start 331.9526 -232.343452)
		(end 331.9526 -236.7026)
		(width 0.15494)
		(layer "In7.Cu")
		(net "PWRGD_P1V8_PEX_R")
	)
	(segment
		(start 332.1812 -232.114852)
		(end 331.9526 -232.343452)
		(width 0.15494)
		(layer "In7.Cu")
		(net "PWRGD_P1V8_PEX_R")
	)
	(segment
		(start 332.28788 -225.870262)
		(end 332.28788 -227.499926)
		(width 0.15494)
		(layer "In7.Cu")
		(net "PWRGD_P1V8_PEX_R")
	)
	(segment
		(start 330.983336 -237.671864)
		(end 330.983336 -237.996222)
		(width 0.15494)
		(layer "In7.Cu")
		(net "PWRGD_P1V8_PEX_R")
	)
	(segment
		(start 332.33741 -239.76965)
		(end 334.6958 -242.12804)
		(width 0.15494)
		(layer "In7.Cu")
		(net "PWRGD_P1V8_PEX_R")
	)
	(segment
		(start 316.9412 -258.2164)
		(end 316.484 -257.7592)
		(width 0.15494)
		(layer "In7.Cu")
		(net "PWRGD_P1V8_PEX_R")
	)
	(segment
		(start 331.1017 -261.112)
		(end 329.262232 -261.112)
		(width 0.15494)
		(layer "In7.Cu")
		(net "PWRGD_P1V8_PEX_R")
	)
	(segment
		(start 332.1812 -227.606606)
		(end 332.1812 -232.114852)
		(width 0.15494)
		(layer "In7.Cu")
		(net "PWRGD_P1V8_PEX_R")
	)
	(segment
		(start 334.6958 -242.12804)
		(end 334.6958 -248.048018)
		(width 0.15494)
		(layer "In7.Cu")
		(net "PWRGD_P1V8_PEX_R")
	)
	(segment
		(start 331.9526 -236.7026)
		(end 330.983336 -237.671864)
		(width 0.15494)
		(layer "In7.Cu")
		(net "PWRGD_P1V8_PEX_R")
	)
	(segment
		(start 265.664442 -211.50707)
		(end 266.21359 -210.957922)
		(width 0.15494)
		(layer "In13.Cu")
		(net "PWRGD_P1V8_PEX_R")
	)
	(segment
		(start 249.452892 -206.120492)
		(end 250.7361 -207.4037)
		(width 0.15494)
		(layer "In13.Cu")
		(net "PWRGD_P1V8_PEX_R")
	)
	(segment
		(start 160.882838 -212.03666)
		(end 164.957252 -207.962246)
		(width 0.15494)
		(layer "In13.Cu")
		(net "PWRGD_P1V8_PEX_R")
	)
	(segment
		(start 247.206008 -206.120492)
		(end 249.452892 -206.120492)
		(width 0.15494)
		(layer "In13.Cu")
		(net "PWRGD_P1V8_PEX_R")
	)
	(segment
		(start 236.781848 -206.46898)
		(end 238.034322 -206.987394)
		(width 0.15494)
		(layer "In13.Cu")
		(net "PWRGD_P1V8_PEX_R")
	)
	(segment
		(start 98.541332 -206.6798)
		(end 122.973846 -206.6798)
		(width 0.15494)
		(layer "In13.Cu")
		(net "PWRGD_P1V8_PEX_R")
	)
	(segment
		(start 178.897788 -207.264)
		(end 186.182 -207.264)
		(width 0.15494)
		(layer "In13.Cu")
		(net "PWRGD_P1V8_PEX_R")
	)
	(segment
		(start 327.348596 -224.96907)
		(end 328.643488 -224.96907)
		(width 0.15494)
		(layer "In13.Cu")
		(net "PWRGD_P1V8_PEX_R")
	)
	(segment
		(start 324.93204 -226.60864)
		(end 325.155306 -226.60864)
		(width 0.15494)
		(layer "In13.Cu")
		(net "PWRGD_P1V8_PEX_R")
	)
	(segment
		(start 321.80784 -223.48444)
		(end 324.93204 -226.60864)
		(width 0.15494)
		(layer "In13.Cu")
		(net "PWRGD_P1V8_PEX_R")
	)
	(segment
		(start 266.21359 -210.957922)
		(end 267.930376 -210.957922)
		(width 0.15494)
		(layer "In13.Cu")
		(net "PWRGD_P1V8_PEX_R")
	)
	(segment
		(start 220.601286 -206.248)
		(end 220.832426 -206.01686)
		(width 0.15494)
		(layer "In13.Cu")
		(net "PWRGD_P1V8_PEX_R")
	)
	(segment
		(start 251.9553 -207.4037)
		(end 253.185422 -208.633822)
		(width 0.15494)
		(layer "In13.Cu")
		(net "PWRGD_P1V8_PEX_R")
	)
	(segment
		(start 135.657844 -212.230716)
		(end 135.8519 -212.03666)
		(width 0.15494)
		(layer "In13.Cu")
		(net "PWRGD_P1V8_PEX_R")
	)
	(segment
		(start 220.832426 -206.01686)
		(end 222.401384 -206.01686)
		(width 0.15494)
		(layer "In13.Cu")
		(net "PWRGD_P1V8_PEX_R")
	)
	(segment
		(start 250.7361 -207.4037)
		(end 251.9553 -207.4037)
		(width 0.15494)
		(layer "In13.Cu")
		(net "PWRGD_P1V8_PEX_R")
	)
	(segment
		(start 229.55123 -205.2574)
		(end 235.570268 -205.2574)
		(width 0.15494)
		(layer "In13.Cu")
		(net "PWRGD_P1V8_PEX_R")
	)
	(segment
		(start 228.61143 -206.1972)
		(end 229.55123 -205.2574)
		(width 0.15494)
		(layer "In13.Cu")
		(net "PWRGD_P1V8_PEX_R")
	)
	(segment
		(start 213.541864 -208.12887)
		(end 215.97366 -208.12887)
		(width 0.15494)
		(layer "In13.Cu")
		(net "PWRGD_P1V8_PEX_R")
	)
	(segment
		(start 133.77037 -212.230716)
		(end 135.657844 -212.230716)
		(width 0.15494)
		(layer "In13.Cu")
		(net "PWRGD_P1V8_PEX_R")
	)
	(segment
		(start 325.155306 -226.60864)
		(end 326.237346 -225.5266)
		(width 0.15494)
		(layer "In13.Cu")
		(net "PWRGD_P1V8_PEX_R")
	)
	(segment
		(start 213.057994 -207.645)
		(end 213.541864 -208.12887)
		(width 0.15494)
		(layer "In13.Cu")
		(net "PWRGD_P1V8_PEX_R")
	)
	(segment
		(start 186.182 -207.264)
		(end 186.188604 -207.257396)
		(width 0.15494)
		(layer "In13.Cu")
		(net "PWRGD_P1V8_PEX_R")
	)
	(segment
		(start 186.188604 -207.257396)
		(end 208.781396 -207.257396)
		(width 0.15494)
		(layer "In13.Cu")
		(net "PWRGD_P1V8_PEX_R")
	)
	(segment
		(start 208.781396 -207.257396)
		(end 209.169 -207.645)
		(width 0.15494)
		(layer "In13.Cu")
		(net "PWRGD_P1V8_PEX_R")
	)
	(segment
		(start 259.435346 -211.1248)
		(end 260.248146 -211.9376)
		(width 0.15494)
		(layer "In13.Cu")
		(net "PWRGD_P1V8_PEX_R")
	)
	(segment
		(start 209.169 -207.645)
		(end 213.057994 -207.645)
		(width 0.15494)
		(layer "In13.Cu")
		(net "PWRGD_P1V8_PEX_R")
	)
	(segment
		(start 258.774946 -211.1248)
		(end 259.435346 -211.1248)
		(width 0.15494)
		(layer "In13.Cu")
		(net "PWRGD_P1V8_PEX_R")
	)
	(segment
		(start 235.570268 -205.2574)
		(end 236.781848 -206.46898)
		(width 0.15494)
		(layer "In13.Cu")
		(net "PWRGD_P1V8_PEX_R")
	)
	(segment
		(start 328.972418 -225.298)
		(end 331.715618 -225.298)
		(width 0.15494)
		(layer "In13.Cu")
		(net "PWRGD_P1V8_PEX_R")
	)
	(segment
		(start 326.791066 -225.5266)
		(end 327.348596 -224.96907)
		(width 0.15494)
		(layer "In13.Cu")
		(net "PWRGD_P1V8_PEX_R")
	)
	(segment
		(start 217.85453 -206.248)
		(end 220.601286 -206.248)
		(width 0.15494)
		(layer "In13.Cu")
		(net "PWRGD_P1V8_PEX_R")
	)
	(segment
		(start 127.66421 -211.36102)
		(end 132.900674 -211.36102)
		(width 0.15494)
		(layer "In13.Cu")
		(net "PWRGD_P1V8_PEX_R")
	)
	(segment
		(start 271.4244 -218.581986)
		(end 276.326854 -223.48444)
		(width 0.15494)
		(layer "In13.Cu")
		(net "PWRGD_P1V8_PEX_R")
	)
	(segment
		(start 328.643488 -224.96907)
		(end 328.972418 -225.298)
		(width 0.15494)
		(layer "In13.Cu")
		(net "PWRGD_P1V8_PEX_R")
	)
	(segment
		(start 127.652526 -211.35848)
		(end 127.66167 -211.35848)
		(width 0.15494)
		(layer "In13.Cu")
		(net "PWRGD_P1V8_PEX_R")
	)
	(segment
		(start 253.185422 -208.633822)
		(end 254.252222 -208.633822)
		(width 0.15494)
		(layer "In13.Cu")
		(net "PWRGD_P1V8_PEX_R")
	)
	(segment
		(start 135.8519 -212.03666)
		(end 160.882838 -212.03666)
		(width 0.15494)
		(layer "In13.Cu")
		(net "PWRGD_P1V8_PEX_R")
	)
	(segment
		(start 215.97366 -208.12887)
		(end 217.85453 -206.248)
		(width 0.15494)
		(layer "In13.Cu")
		(net "PWRGD_P1V8_PEX_R")
	)
	(segment
		(start 260.248146 -211.9376)
		(end 263.1948 -211.9376)
		(width 0.15494)
		(layer "In13.Cu")
		(net "PWRGD_P1V8_PEX_R")
	)
	(segment
		(start 257.259074 -211.640674)
		(end 258.259072 -211.640674)
		(width 0.15494)
		(layer "In13.Cu")
		(net "PWRGD_P1V8_PEX_R")
	)
	(segment
		(start 127.66167 -211.35848)
		(end 127.66421 -211.36102)
		(width 0.15494)
		(layer "In13.Cu")
		(net "PWRGD_P1V8_PEX_R")
	)
	(segment
		(start 331.715618 -225.298)
		(end 332.28788 -225.870262)
		(width 0.15494)
		(layer "In13.Cu")
		(net "PWRGD_P1V8_PEX_R")
	)
	(segment
		(start 246.339106 -206.987394)
		(end 247.206008 -206.120492)
		(width 0.15494)
		(layer "In13.Cu")
		(net "PWRGD_P1V8_PEX_R")
	)
	(segment
		(start 258.259072 -211.640674)
		(end 258.774946 -211.1248)
		(width 0.15494)
		(layer "In13.Cu")
		(net "PWRGD_P1V8_PEX_R")
	)
	(segment
		(start 254.252222 -208.633822)
		(end 257.259074 -211.640674)
		(width 0.15494)
		(layer "In13.Cu")
		(net "PWRGD_P1V8_PEX_R")
	)
	(segment
		(start 263.62533 -211.50707)
		(end 265.664442 -211.50707)
		(width 0.15494)
		(layer "In13.Cu")
		(net "PWRGD_P1V8_PEX_R")
	)
	(segment
		(start 178.199542 -207.962246)
		(end 178.897788 -207.264)
		(width 0.15494)
		(layer "In13.Cu")
		(net "PWRGD_P1V8_PEX_R")
	)
	(segment
		(start 276.326854 -223.48444)
		(end 321.80784 -223.48444)
		(width 0.15494)
		(layer "In13.Cu")
		(net "PWRGD_P1V8_PEX_R")
	)
	(segment
		(start 238.034322 -206.987394)
		(end 246.339106 -206.987394)
		(width 0.15494)
		(layer "In13.Cu")
		(net "PWRGD_P1V8_PEX_R")
	)
	(segment
		(start 132.900674 -211.36102)
		(end 133.77037 -212.230716)
		(width 0.15494)
		(layer "In13.Cu")
		(net "PWRGD_P1V8_PEX_R")
	)
	(segment
		(start 326.237346 -225.5266)
		(end 326.791066 -225.5266)
		(width 0.15494)
		(layer "In13.Cu")
		(net "PWRGD_P1V8_PEX_R")
	)
	(segment
		(start 222.581724 -206.1972)
		(end 228.61143 -206.1972)
		(width 0.15494)
		(layer "In13.Cu")
		(net "PWRGD_P1V8_PEX_R")
	)
	(segment
		(start 164.957252 -207.962246)
		(end 178.199542 -207.962246)
		(width 0.15494)
		(layer "In13.Cu")
		(net "PWRGD_P1V8_PEX_R")
	)
	(segment
		(start 222.401384 -206.01686)
		(end 222.581724 -206.1972)
		(width 0.15494)
		(layer "In13.Cu")
		(net "PWRGD_P1V8_PEX_R")
	)
	(segment
		(start 267.930376 -210.957922)
		(end 271.4244 -214.451946)
		(width 0.15494)
		(layer "In13.Cu")
		(net "PWRGD_P1V8_PEX_R")
	)
	(segment
		(start 263.1948 -211.9376)
		(end 263.62533 -211.50707)
		(width 0.15494)
		(layer "In13.Cu")
		(net "PWRGD_P1V8_PEX_R")
	)
	(segment
		(start 271.4244 -214.451946)
		(end 271.4244 -218.581986)
		(width 0.15494)
		(layer "In13.Cu")
		(net "PWRGD_P1V8_PEX_R")
	)
	(segment
		(start 122.973846 -206.6798)
		(end 127.652526 -211.35848)
		(width 0.15494)
		(layer "In13.Cu")
		(net "PWRGD_P1V8_PEX_R")
	)
	(segment
		(start 440.713368 -245.39829)
		(end 392.288522 -245.39829)
		(width 0.15494)
		(layer "In15.Cu")
		(net "PWRGD_P1V8_PEX_R")
	)
	(segment
		(start 329.920092 -258.21132)
		(end 316.93612 -258.21132)
		(width 0.15494)
		(layer "In15.Cu")
		(net "PWRGD_P1V8_PEX_R")
	)
	(segment
		(start 376.912886 -243.805964)
		(end 373.410734 -243.805964)
		(width 0.15494)
		(layer "In15.Cu")
		(net "PWRGD_P1V8_PEX_R")
	)
	(segment
		(start 316.93612 -258.21132)
		(end 316.484 -257.7592)
		(width 0.15494)
		(layer "In15.Cu")
		(net "PWRGD_P1V8_PEX_R")
	)
	(segment
		(start 444.970916 -251.789438)
		(end 444.970916 -249.655838)
		(width 0.15494)
		(layer "In15.Cu")
		(net "PWRGD_P1V8_PEX_R")
	)
	(segment
		(start 350.573594 -244.185186)
		(end 336.928206 -257.830574)
		(width 0.15494)
		(layer "In15.Cu")
		(net "PWRGD_P1V8_PEX_R")
	)
	(segment
		(start 363.704378 -244.185186)
		(end 350.573594 -244.185186)
		(width 0.15494)
		(layer "In15.Cu")
		(net "PWRGD_P1V8_PEX_R")
	)
	(segment
		(start 377.684792 -244.57787)
		(end 376.912886 -243.805964)
		(width 0.15494)
		(layer "In15.Cu")
		(net "PWRGD_P1V8_PEX_R")
	)
	(segment
		(start 392.288522 -245.39829)
		(end 390.659874 -243.769642)
		(width 0.15494)
		(layer "In15.Cu")
		(net "PWRGD_P1V8_PEX_R")
	)
	(segment
		(start 336.928206 -257.830574)
		(end 330.300838 -257.830574)
		(width 0.15494)
		(layer "In15.Cu")
		(net "PWRGD_P1V8_PEX_R")
	)
	(segment
		(start 367.803938 -244.446552)
		(end 363.965744 -244.446552)
		(width 0.15494)
		(layer "In15.Cu")
		(net "PWRGD_P1V8_PEX_R")
	)
	(segment
		(start 444.970916 -249.655838)
		(end 440.713368 -245.39829)
		(width 0.15494)
		(layer "In15.Cu")
		(net "PWRGD_P1V8_PEX_R")
	)
	(segment
		(start 370.1161 -242.13439)
		(end 367.803938 -244.446552)
		(width 0.15494)
		(layer "In15.Cu")
		(net "PWRGD_P1V8_PEX_R")
	)
	(segment
		(start 363.965744 -244.446552)
		(end 363.704378 -244.185186)
		(width 0.15494)
		(layer "In15.Cu")
		(net "PWRGD_P1V8_PEX_R")
	)
	(segment
		(start 371.73916 -242.13439)
		(end 370.1161 -242.13439)
		(width 0.15494)
		(layer "In15.Cu")
		(net "PWRGD_P1V8_PEX_R")
	)
	(segment
		(start 373.410734 -243.805964)
		(end 371.73916 -242.13439)
		(width 0.15494)
		(layer "In15.Cu")
		(net "PWRGD_P1V8_PEX_R")
	)
	(segment
		(start 390.659874 -243.769642)
		(end 384.237484 -243.769642)
		(width 0.15494)
		(layer "In15.Cu")
		(net "PWRGD_P1V8_PEX_R")
	)
	(segment
		(start 384.237484 -243.769642)
		(end 383.429256 -244.57787)
		(width 0.15494)
		(layer "In15.Cu")
		(net "PWRGD_P1V8_PEX_R")
	)
	(segment
		(start 383.429256 -244.57787)
		(end 377.684792 -244.57787)
		(width 0.15494)
		(layer "In15.Cu")
		(net "PWRGD_P1V8_PEX_R")
	)
	(segment
		(start 330.300838 -257.830574)
		(end 329.920092 -258.21132)
		(width 0.15494)
		(layer "In15.Cu")
		(net "PWRGD_P1V8_PEX_R")
	)
	(segment
		(start 449.404994 -117.28196)
		(end 449.750688 -117.627654)
		(width 0.254)
		(layer "F.Cu")
		(net "P12V_NIC7_R")
	)
	(segment
		(start 449.404994 -112.856518)
		(end 449.404994 -117.28196)
		(width 0.254)
		(layer "F.Cu")
		(net "P12V_NIC7_R")
	)
	(segment
		(start 436.588154 -100.058982)
		(end 436.588154 -99.449382)
		(width 0.4572)
		(layer "F.Cu")
		(net "P12V_NIC7_R")
	)
	(segment
		(start 449.750688 -117.627654)
		(end 454.496932 -117.627654)
		(width 0.254)
		(layer "F.Cu")
		(net "P12V_NIC7_R")
	)
	(segment
		(start 449.425568 -112.835944)
		(end 449.404994 -112.856518)
		(width 0.254)
		(layer "F.Cu")
		(net "P12V_NIC7_R")
	)
	(via
		(at 452.979536 -111.993934)
		(size 0.508)
		(drill 0.254)
		(layers "F.Cu" "B.Cu")
		(net "P12V_NIC7_R")
	)
	(via
		(at 439.14441 -103.095806)
		(size 0.508)
		(drill 0.254)
		(layers "F.Cu" "B.Cu")
		(net "P12V_NIC7_R")
	)
	(via
		(at 452.979536 -112.705134)
		(size 0.508)
		(drill 0.254)
		(layers "F.Cu" "B.Cu")
		(net "P12V_NIC7_R")
	)
	(via
		(at 439.14441 -106.397806)
		(size 0.508)
		(drill 0.254)
		(layers "F.Cu" "B.Cu")
		(net "P12V_NIC7_R")
	)
	(via
		(at 446.33007 -105.057194)
		(size 0.508)
		(drill 0.254)
		(layers "F.Cu" "B.Cu")
		(net "P12V_NIC7_R")
	)
	(via
		(at 453.690736 -110.571534)
		(size 0.508)
		(drill 0.254)
		(layers "F.Cu" "B.Cu")
		(net "P12V_NIC7_R")
	)
	(via
		(at 445.674496 -101.162612)
		(size 0.508)
		(drill 0.254)
		(layers "F.Cu" "B.Cu")
		(net "P12V_NIC7_R")
	)
	(via
		(at 443.783466 -111.586772)
		(size 0.508)
		(drill 0.254)
		(layers "F.Cu" "B.Cu")
		(net "P12V_NIC7_R")
	)
	(via
		(at 445.63538 -107.713018)
		(size 0.508)
		(drill 0.254)
		(layers "F.Cu" "B.Cu")
		(net "P12V_NIC7_R")
	)
	(via
		(at 446.238376 -111.326422)
		(size 0.508)
		(drill 0.254)
		(layers "F.Cu" "B.Cu")
		(net "P12V_NIC7_R")
	)
	(via
		(at 448.776598 -111.326422)
		(size 0.508)
		(drill 0.254)
		(layers "F.Cu" "B.Cu")
		(net "P12V_NIC7_R")
	)
	(via
		(at 439.14441 -108.379006)
		(size 0.508)
		(drill 0.254)
		(layers "F.Cu" "B.Cu")
		(net "P12V_NIC7_R")
	)
	(via
		(at 439.242708 -110.621572)
		(size 0.508)
		(drill 0.254)
		(layers "F.Cu" "B.Cu")
		(net "P12V_NIC7_R")
	)
	(via
		(at 445.224154 -102.103174)
		(size 0.508)
		(drill 0.254)
		(layers "F.Cu" "B.Cu")
		(net "P12V_NIC7_R")
	)
	(via
		(at 443.783466 -112.297972)
		(size 0.508)
		(drill 0.254)
		(layers "F.Cu" "B.Cu")
		(net "P12V_NIC7_R")
	)
	(via
		(at 446.309496 -101.162612)
		(size 0.508)
		(drill 0.254)
		(layers "F.Cu" "B.Cu")
		(net "P12V_NIC7_R")
	)
	(via
		(at 448.776598 -112.748822)
		(size 0.508)
		(drill 0.254)
		(layers "F.Cu" "B.Cu")
		(net "P12V_NIC7_R")
	)
	(via
		(at 446.238376 -112.748822)
		(size 0.508)
		(drill 0.254)
		(layers "F.Cu" "B.Cu")
		(net "P12V_NIC7_R")
	)
	(via
		(at 445.00038 -107.713018)
		(size 0.508)
		(drill 0.254)
		(layers "F.Cu" "B.Cu")
		(net "P12V_NIC7_R")
	)
	(via
		(at 445.309498 -104.022906)
		(size 0.508)
		(drill 0.254)
		(layers "F.Cu" "B.Cu")
		(net "P12V_NIC7_R")
	)
	(via
		(at 453.690736 -111.282734)
		(size 0.508)
		(drill 0.254)
		(layers "F.Cu" "B.Cu")
		(net "P12V_NIC7_R")
	)
	(via
		(at 439.14441 -104.416606)
		(size 0.508)
		(drill 0.254)
		(layers "F.Cu" "B.Cu")
		(net "P12V_NIC7_R")
	)
	(via
		(at 444.36538 -107.713018)
		(size 0.508)
		(drill 0.254)
		(layers "F.Cu" "B.Cu")
		(net "P12V_NIC7_R")
	)
	(via
		(at 445.859154 -102.103174)
		(size 0.508)
		(drill 0.254)
		(layers "F.Cu" "B.Cu")
		(net "P12V_NIC7_R")
	)
	(via
		(at 448.776598 -112.037622)
		(size 0.508)
		(drill 0.254)
		(layers "F.Cu" "B.Cu")
		(net "P12V_NIC7_R")
	)
	(via
		(at 452.979536 -111.282734)
		(size 0.508)
		(drill 0.254)
		(layers "F.Cu" "B.Cu")
		(net "P12V_NIC7_R")
	)
	(via
		(at 439.14441 -105.737406)
		(size 0.508)
		(drill 0.254)
		(layers "F.Cu" "B.Cu")
		(net "P12V_NIC7_R")
	)
	(via
		(at 445.06007 -105.057194)
		(size 0.508)
		(drill 0.254)
		(layers "F.Cu" "B.Cu")
		(net "P12V_NIC7_R")
	)
	(via
		(at 453.690736 -112.705134)
		(size 0.508)
		(drill 0.254)
		(layers "F.Cu" "B.Cu")
		(net "P12V_NIC7_R")
	)
	(via
		(at 441.751466 -111.586772)
		(size 0.508)
		(drill 0.254)
		(layers "F.Cu" "B.Cu")
		(net "P12V_NIC7_R")
	)
	(via
		(at 439.242708 -109.910372)
		(size 0.508)
		(drill 0.254)
		(layers "F.Cu" "B.Cu")
		(net "P12V_NIC7_R")
	)
	(via
		(at 444.547498 -104.022906)
		(size 0.508)
		(drill 0.254)
		(layers "F.Cu" "B.Cu")
		(net "P12V_NIC7_R")
	)
	(via
		(at 446.27038 -107.713018)
		(size 0.508)
		(drill 0.254)
		(layers "F.Cu" "B.Cu")
		(net "P12V_NIC7_R")
	)
	(via
		(at 453.690736 -111.993934)
		(size 0.508)
		(drill 0.254)
		(layers "F.Cu" "B.Cu")
		(net "P12V_NIC7_R")
	)
	(via
		(at 445.69507 -105.057194)
		(size 0.508)
		(drill 0.254)
		(layers "F.Cu" "B.Cu")
		(net "P12V_NIC7_R")
	)
	(via
		(at 439.295032 -102.4382)
		(size 0.508)
		(drill 0.254)
		(layers "F.Cu" "B.Cu")
		(net "P12V_NIC7_R")
	)
	(via
		(at 439.14441 -107.058206)
		(size 0.508)
		(drill 0.254)
		(layers "F.Cu" "B.Cu")
		(net "P12V_NIC7_R")
	)
	(via
		(at 446.238376 -112.037622)
		(size 0.508)
		(drill 0.254)
		(layers "F.Cu" "B.Cu")
		(net "P12V_NIC7_R")
	)
	(via
		(at 452.979536 -110.571534)
		(size 0.508)
		(drill 0.254)
		(layers "F.Cu" "B.Cu")
		(net "P12V_NIC7_R")
	)
	(via
		(at 439.14441 -105.077006)
		(size 0.508)
		(drill 0.254)
		(layers "F.Cu" "B.Cu")
		(net "P12V_NIC7_R")
	)
	(via
		(at 439.14441 -103.756206)
		(size 0.508)
		(drill 0.254)
		(layers "F.Cu" "B.Cu")
		(net "P12V_NIC7_R")
	)
	(via
		(at 445.309498 -103.387906)
		(size 0.508)
		(drill 0.254)
		(layers "F.Cu" "B.Cu")
		(net "P12V_NIC7_R")
	)
	(via
		(at 444.42507 -105.057194)
		(size 0.508)
		(drill 0.254)
		(layers "F.Cu" "B.Cu")
		(net "P12V_NIC7_R")
	)
	(via
		(at 444.547498 -103.311706)
		(size 0.508)
		(drill 0.254)
		(layers "F.Cu" "B.Cu")
		(net "P12V_NIC7_R")
	)
	(via
		(at 439.14441 -107.718606)
		(size 0.508)
		(drill 0.254)
		(layers "F.Cu" "B.Cu")
		(net "P12V_NIC7_R")
	)
	(via
		(at 441.751466 -112.297972)
		(size 0.508)
		(drill 0.254)
		(layers "F.Cu" "B.Cu")
		(net "P12V_NIC7_R")
	)
	(via
		(at 436.588154 -99.449382)
		(size 0.508)
		(drill 0.254)
		(layers "F.Cu" "B.Cu")
		(net "P12V_NIC7_R")
	)
	(segment
		(start 425.083478 -49.572164)
		(end 425.083478 -49.94148)
		(width 0.13208)
		(layer "F.Cu")
		(net "SMB_SSD14_ADC_SCL")
	)
	(segment
		(start 424.86961 -49.358296)
		(end 425.083478 -49.572164)
		(width 0.13208)
		(layer "F.Cu")
		(net "SMB_SSD14_ADC_SCL")
	)
	(segment
		(start 424.361864 -49.358296)
		(end 424.86961 -49.358296)
		(width 0.13208)
		(layer "F.Cu")
		(net "SMB_SSD14_ADC_SCL")
	)
	(segment
		(start 424.015408 -42.853102)
		(end 424.015408 -43.566842)
		(width 0.13208)
		(layer "F.Cu")
		(net "SMB_SSD14_ADC_SCL")
	)
	(segment
		(start 423.896028 -48.89246)
		(end 424.361864 -49.358296)
		(width 0.13208)
		(layer "F.Cu")
		(net "SMB_SSD14_ADC_SCL")
	)
	(segment
		(start 423.896028 -47.843948)
		(end 423.896028 -48.89246)
		(width 0.13208)
		(layer "F.Cu")
		(net "SMB_SSD14_ADC_SCL")
	)
	(via
		(at 423.896028 -48.89246)
		(size 0.508)
		(drill 0.254)
		(layers "F.Cu" "B.Cu")
		(net "SMB_SSD14_ADC_SCL")
	)
	(via
		(at 424.015408 -43.566842)
		(size 0.508)
		(drill 0.254)
		(layers "F.Cu" "B.Cu")
		(net "SMB_SSD14_ADC_SCL")
	)
	(segment
		(start 424.68927 -44.240704)
		(end 424.68927 -48.099218)
		(width 0.15494)
		(layer "In5.Cu")
		(net "SMB_SSD14_ADC_SCL")
	)
	(segment
		(start 424.015408 -43.566842)
		(end 424.68927 -44.240704)
		(width 0.15494)
		(layer "In5.Cu")
		(net "SMB_SSD14_ADC_SCL")
	)
	(segment
		(start 424.68927 -48.099218)
		(end 423.896028 -48.89246)
		(width 0.15494)
		(layer "In5.Cu")
		(net "SMB_SSD14_ADC_SCL")
	)
	(segment
		(start 395.43228 -44.76115)
		(end 395.714982 -45.043852)
		(width 0.254)
		(layer "F.Cu")
		(net "P12V_SSD13_VIN_P")
	)
	(segment
		(start 395.43228 -44.27347)
		(end 395.43228 -44.76115)
		(width 0.254)
		(layer "F.Cu")
		(net "P12V_SSD13_VIN_P")
	)
	(segment
		(start 394.89507 -43.73626)
		(end 395.43228 -44.27347)
		(width 0.254)
		(layer "F.Cu")
		(net "P12V_SSD13_VIN_P")
	)
	(segment
		(start 394.038582 -43.941492)
		(end 394.689838 -43.941492)
		(width 0.254)
		(layer "F.Cu")
		(net "P12V_SSD13_VIN_P")
	)
	(segment
		(start 394.025374 -43.928284)
		(end 394.025374 -42.849038)
		(width 0.254)
		(layer "F.Cu")
		(net "P12V_SSD13_VIN_P")
	)
	(segment
		(start 395.714982 -45.043852)
		(end 396.395956 -45.043852)
		(width 0.254)
		(layer "F.Cu")
		(net "P12V_SSD13_VIN_P")
	)
	(segment
		(start 394.038582 -43.941492)
		(end 394.025374 -43.928284)
		(width 0.254)
		(layer "F.Cu")
		(net "P12V_SSD13_VIN_P")
	)
	(segment
		(start 394.689838 -43.941492)
		(end 394.89507 -43.73626)
		(width 0.254)
		(layer "F.Cu")
		(net "P12V_SSD13_VIN_P")
	)
	(via
		(at 394.89507 -43.73626)
		(size 0.508)
		(drill 0.254)
		(layers "F.Cu" "B.Cu")
		(net "P12V_SSD13_VIN_P")
	)
	(via
		(at 88.152732 -101.579172)
		(size 0.508)
		(drill 0.254)
		(layers "F.Cu" "B.Cu")
		(net "P12V_NIC1_VIN_P")
	)
	(segment
		(start 421.432228 -44.76115)
		(end 421.71493 -45.043852)
		(width 0.254)
		(layer "F.Cu")
		(net "P12V_SSD14_VIN_P")
	)
	(segment
		(start 420.03853 -43.941492)
		(end 420.689786 -43.941492)
		(width 0.254)
		(layer "F.Cu")
		(net "P12V_SSD14_VIN_P")
	)
	(segment
		(start 420.03853 -43.941492)
		(end 420.025322 -43.928284)
		(width 0.254)
		(layer "F.Cu")
		(net "P12V_SSD14_VIN_P")
	)
	(segment
		(start 421.432228 -44.27347)
		(end 421.432228 -44.76115)
		(width 0.254)
		(layer "F.Cu")
		(net "P12V_SSD14_VIN_P")
	)
	(segment
		(start 420.025322 -43.928284)
		(end 420.025322 -42.849038)
		(width 0.254)
		(layer "F.Cu")
		(net "P12V_SSD14_VIN_P")
	)
	(segment
		(start 420.689786 -43.941492)
		(end 420.895018 -43.73626)
		(width 0.254)
		(layer "F.Cu")
		(net "P12V_SSD14_VIN_P")
	)
	(segment
		(start 421.71493 -45.043852)
		(end 422.395904 -45.043852)
		(width 0.254)
		(layer "F.Cu")
		(net "P12V_SSD14_VIN_P")
	)
	(segment
		(start 420.895018 -43.73626)
		(end 421.432228 -44.27347)
		(width 0.254)
		(layer "F.Cu")
		(net "P12V_SSD14_VIN_P")
	)
	(via
		(at 420.895018 -43.73626)
		(size 0.508)
		(drill 0.254)
		(layers "F.Cu" "B.Cu")
		(net "P12V_SSD14_VIN_P")
	)
	(segment
		(start 90.561922 -98.809302)
		(end 90.561922 -98.544634)
		(width 0.13208)
		(layer "F.Cu")
		(net "NIC1_ADC_A1")
	)
	(segment
		(start 88.724994 -97.953576)
		(end 88.007444 -97.236026)
		(width 0.13208)
		(layer "F.Cu")
		(net "NIC1_ADC_A1")
	)
	(segment
		(start 90.340942 -98.323654)
		(end 89.095072 -98.323654)
		(width 0.13208)
		(layer "F.Cu")
		(net "NIC1_ADC_A1")
	)
	(segment
		(start 86.991444 -97.211642)
		(end 88.007444 -97.211642)
		(width 0.13208)
		(layer "F.Cu")
		(net "NIC1_ADC_A1")
	)
	(segment
		(start 88.007444 -97.236026)
		(end 88.007444 -97.211642)
		(width 0.13208)
		(layer "F.Cu")
		(net "NIC1_ADC_A1")
	)
	(segment
		(start 90.561922 -98.544634)
		(end 90.340942 -98.323654)
		(width 0.13208)
		(layer "F.Cu")
		(net "NIC1_ADC_A1")
	)
	(segment
		(start 89.095072 -98.323654)
		(end 88.724994 -97.953576)
		(width 0.13208)
		(layer "F.Cu")
		(net "NIC1_ADC_A1")
	)
	(via
		(at 88.724994 -97.953576)
		(size 0.508)
		(drill 0.254)
		(layers "F.Cu" "B.Cu")
		(net "NIC1_ADC_A1")
	)
	(segment
		(start 425.235878 -48.30699)
		(end 425.235878 -48.69942)
		(width 0.13208)
		(layer "F.Cu")
		(net "SMB_SSD14_ADC_SDA")
	)
	(segment
		(start 424.546014 -48.076612)
		(end 424.776392 -48.30699)
		(width 0.13208)
		(layer "F.Cu")
		(net "SMB_SSD14_ADC_SDA")
	)
	(segment
		(start 424.776392 -48.30699)
		(end 425.235878 -48.30699)
		(width 0.13208)
		(layer "F.Cu")
		(net "SMB_SSD14_ADC_SDA")
	)
	(segment
		(start 426.143674 -49.95291)
		(end 426.143674 -48.93691)
		(width 0.13208)
		(layer "F.Cu")
		(net "SMB_SSD14_ADC_SDA")
	)
	(segment
		(start 425.235878 -48.69942)
		(end 425.473368 -48.93691)
		(width 0.13208)
		(layer "F.Cu")
		(net "SMB_SSD14_ADC_SDA")
	)
	(segment
		(start 425.473368 -48.93691)
		(end 426.143674 -48.93691)
		(width 0.13208)
		(layer "F.Cu")
		(net "SMB_SSD14_ADC_SDA")
	)
	(segment
		(start 424.546014 -47.193962)
		(end 424.546014 -48.076612)
		(width 0.13208)
		(layer "F.Cu")
		(net "SMB_SSD14_ADC_SDA")
	)
	(via
		(at 425.235878 -48.30699)
		(size 0.508)
		(drill 0.254)
		(layers "F.Cu" "B.Cu")
		(net "SMB_SSD14_ADC_SDA")
	)
	(segment
		(start 216.801446 -105.34904)
		(end 216.801446 -105.012998)
		(width 0.249936)
		(layer "F.Cu")
		(net "P12V_NIC3_VIN_N")
	)
	(segment
		(start 217.753692 -104.060752)
		(end 217.753692 -103.641652)
		(width 0.249936)
		(layer "F.Cu")
		(net "P12V_NIC3_VIN_N")
	)
	(segment
		(start 216.801446 -105.012998)
		(end 217.174318 -104.640126)
		(width 0.249936)
		(layer "F.Cu")
		(net "P12V_NIC3_VIN_N")
	)
	(segment
		(start 217.174318 -104.640126)
		(end 217.753692 -104.060752)
		(width 0.249936)
		(layer "F.Cu")
		(net "P12V_NIC3_VIN_N")
	)
	(segment
		(start 216.801446 -106.36504)
		(end 216.801446 -105.34904)
		(width 0.249936)
		(layer "F.Cu")
		(net "P12V_NIC3_VIN_N")
	)
	(via
		(at 217.174318 -104.640126)
		(size 0.508)
		(drill 0.254)
		(layers "F.Cu" "B.Cu")
		(net "P12V_NIC3_VIN_N")
	)
	(segment
		(start 376.775218 -63.086234)
		(end 376.069606 -63.086234)
		(width 0.4572)
		(layer "F.Cu")
		(net "P12V_SSD13_R")
	)
	(segment
		(start 394.825474 -42.849038)
		(end 395.574012 -42.849038)
		(width 0.381)
		(layer "F.Cu")
		(net "P12V_SSD13_R")
	)
	(via
		(at 394.752576 -54.135528)
		(size 0.508)
		(drill 0.254)
		(layers "F.Cu" "B.Cu")
		(net "P12V_SSD13_R")
	)
	(via
		(at 393.549632 -46.066964)
		(size 0.508)
		(drill 0.254)
		(layers "F.Cu" "B.Cu")
		(net "P12V_SSD13_R")
	)
	(via
		(at 393.812014 -54.320186)
		(size 0.508)
		(drill 0.254)
		(layers "F.Cu" "B.Cu")
		(net "P12V_SSD13_R")
	)
	(via
		(at 391.306812 -67.951604)
		(size 0.508)
		(drill 0.254)
		(layers "F.Cu" "B.Cu")
		(net "P12V_SSD13_R")
	)
	(via
		(at 392.734038 -46.082204)
		(size 0.508)
		(drill 0.254)
		(layers "F.Cu" "B.Cu")
		(net "P12V_SSD13_R")
	)
	(via
		(at 390.857994 -53.521102)
		(size 0.508)
		(drill 0.254)
		(layers "F.Cu" "B.Cu")
		(net "P12V_SSD13_R")
	)
	(via
		(at 392.78687 -46.792134)
		(size 0.508)
		(drill 0.254)
		(layers "F.Cu" "B.Cu")
		(net "P12V_SSD13_R")
	)
	(via
		(at 390.857994 -54.156102)
		(size 0.508)
		(drill 0.254)
		(layers "F.Cu" "B.Cu")
		(net "P12V_SSD13_R")
	)
	(via
		(at 388.20217 -54.731412)
		(size 0.508)
		(drill 0.254)
		(layers "F.Cu" "B.Cu")
		(net "P12V_SSD13_R")
	)
	(via
		(at 394.259562 -45.976286)
		(size 0.508)
		(drill 0.254)
		(layers "F.Cu" "B.Cu")
		(net "P12V_SSD13_R")
	)
	(via
		(at 376.069606 -63.086234)
		(size 0.508)
		(drill 0.254)
		(layers "F.Cu" "B.Cu")
		(net "P12V_SSD13_R")
	)
	(via
		(at 392.653012 -67.951604)
		(size 0.508)
		(drill 0.254)
		(layers "F.Cu" "B.Cu")
		(net "P12V_SSD13_R")
	)
	(via
		(at 393.812014 -53.685186)
		(size 0.508)
		(drill 0.254)
		(layers "F.Cu" "B.Cu")
		(net "P12V_SSD13_R")
	)
	(via
		(at 390.857994 -52.886102)
		(size 0.508)
		(drill 0.254)
		(layers "F.Cu" "B.Cu")
		(net "P12V_SSD13_R")
	)
	(via
		(at 392.603482 -53.00853)
		(size 0.508)
		(drill 0.254)
		(layers "F.Cu" "B.Cu")
		(net "P12V_SSD13_R")
	)
	(via
		(at 394.752576 -54.770528)
		(size 0.508)
		(drill 0.254)
		(layers "F.Cu" "B.Cu")
		(net "P12V_SSD13_R")
	)
	(via
		(at 392.018012 -68.586604)
		(size 0.508)
		(drill 0.254)
		(layers "F.Cu" "B.Cu")
		(net "P12V_SSD13_R")
	)
	(via
		(at 391.892282 -53.00853)
		(size 0.508)
		(drill 0.254)
		(layers "F.Cu" "B.Cu")
		(net "P12V_SSD13_R")
	)
	(via
		(at 391.892282 -53.77053)
		(size 0.508)
		(drill 0.254)
		(layers "F.Cu" "B.Cu")
		(net "P12V_SSD13_R")
	)
	(via
		(at 392.018012 -67.951604)
		(size 0.508)
		(drill 0.254)
		(layers "F.Cu" "B.Cu")
		(net "P12V_SSD13_R")
	)
	(via
		(at 388.20217 -53.461412)
		(size 0.508)
		(drill 0.254)
		(layers "F.Cu" "B.Cu")
		(net "P12V_SSD13_R")
	)
	(via
		(at 389.047736 -67.10172)
		(size 0.508)
		(drill 0.254)
		(layers "F.Cu" "B.Cu")
		(net "P12V_SSD13_R")
	)
	(via
		(at 388.20217 -54.096412)
		(size 0.508)
		(drill 0.254)
		(layers "F.Cu" "B.Cu")
		(net "P12V_SSD13_R")
	)
	(via
		(at 391.306812 -68.586604)
		(size 0.508)
		(drill 0.254)
		(layers "F.Cu" "B.Cu")
		(net "P12V_SSD13_R")
	)
	(via
		(at 393.451588 -46.739048)
		(size 0.508)
		(drill 0.254)
		(layers "F.Cu" "B.Cu")
		(net "P12V_SSD13_R")
	)
	(via
		(at 392.527282 -53.77053)
		(size 0.508)
		(drill 0.254)
		(layers "F.Cu" "B.Cu")
		(net "P12V_SSD13_R")
	)
	(via
		(at 395.574012 -42.849038)
		(size 0.508)
		(drill 0.254)
		(layers "F.Cu" "B.Cu")
		(net "P12V_SSD13_R")
	)
	(via
		(at 390.857994 -54.791102)
		(size 0.508)
		(drill 0.254)
		(layers "F.Cu" "B.Cu")
		(net "P12V_SSD13_R")
	)
	(via
		(at 392.653012 -68.586604)
		(size 0.508)
		(drill 0.254)
		(layers "F.Cu" "B.Cu")
		(net "P12V_SSD13_R")
	)
	(via
		(at 388.20217 -52.826412)
		(size 0.508)
		(drill 0.254)
		(layers "F.Cu" "B.Cu")
		(net "P12V_SSD13_R")
	)
	(via
		(at 389.682736 -67.10172)
		(size 0.508)
		(drill 0.254)
		(layers "F.Cu" "B.Cu")
		(net "P12V_SSD13_R")
	)
	(segment
		(start 91.055444 -97.211642)
		(end 91.055444 -97.567242)
		(width 0.13208)
		(layer "F.Cu")
		(net "NIC1_ADC_ALERT_N")
	)
	(segment
		(start 91.56192 -98.809302)
		(end 91.56192 -98.073718)
		(width 0.13208)
		(layer "F.Cu")
		(net "NIC1_ADC_ALERT_N")
	)
	(segment
		(start 91.055444 -97.567242)
		(end 91.309444 -97.821242)
		(width 0.13208)
		(layer "F.Cu")
		(net "NIC1_ADC_ALERT_N")
	)
	(segment
		(start 91.56192 -98.073718)
		(end 91.309444 -97.821242)
		(width 0.13208)
		(layer "F.Cu")
		(net "NIC1_ADC_ALERT_N")
	)
	(via
		(at 91.309444 -97.821242)
		(size 0.508)
		(drill 0.254)
		(layers "F.Cu" "B.Cu")
		(net "NIC1_ADC_ALERT_N")
	)
	(segment
		(start 446.82537 -42.849038)
		(end 447.573908 -42.849038)
		(width 0.381)
		(layer "F.Cu")
		(net "P12V_SSD15_R")
	)
	(segment
		(start 428.775114 -63.086234)
		(end 428.069502 -63.086234)
		(width 0.4572)
		(layer "F.Cu")
		(net "P12V_SSD15_R")
	)
	(via
		(at 445.81191 -54.320186)
		(size 0.508)
		(drill 0.254)
		(layers "F.Cu" "B.Cu")
		(net "P12V_SSD15_R")
	)
	(via
		(at 444.017908 -67.951604)
		(size 0.508)
		(drill 0.254)
		(layers "F.Cu" "B.Cu")
		(net "P12V_SSD15_R")
	)
	(via
		(at 445.81191 -53.685186)
		(size 0.508)
		(drill 0.254)
		(layers "F.Cu" "B.Cu")
		(net "P12V_SSD15_R")
	)
	(via
		(at 442.85789 -52.886102)
		(size 0.508)
		(drill 0.254)
		(layers "F.Cu" "B.Cu")
		(net "P12V_SSD15_R")
	)
	(via
		(at 440.202066 -54.096412)
		(size 0.508)
		(drill 0.254)
		(layers "F.Cu" "B.Cu")
		(net "P12V_SSD15_R")
	)
	(via
		(at 446.752472 -54.135528)
		(size 0.508)
		(drill 0.254)
		(layers "F.Cu" "B.Cu")
		(net "P12V_SSD15_R")
	)
	(via
		(at 444.017908 -68.586604)
		(size 0.508)
		(drill 0.254)
		(layers "F.Cu" "B.Cu")
		(net "P12V_SSD15_R")
	)
	(via
		(at 447.573908 -42.849038)
		(size 0.508)
		(drill 0.254)
		(layers "F.Cu" "B.Cu")
		(net "P12V_SSD15_R")
	)
	(via
		(at 443.306708 -67.951604)
		(size 0.508)
		(drill 0.254)
		(layers "F.Cu" "B.Cu")
		(net "P12V_SSD15_R")
	)
	(via
		(at 440.202066 -54.731412)
		(size 0.508)
		(drill 0.254)
		(layers "F.Cu" "B.Cu")
		(net "P12V_SSD15_R")
	)
	(via
		(at 444.786766 -46.792134)
		(size 0.508)
		(drill 0.254)
		(layers "F.Cu" "B.Cu")
		(net "P12V_SSD15_R")
	)
	(via
		(at 446.752472 -54.770528)
		(size 0.508)
		(drill 0.254)
		(layers "F.Cu" "B.Cu")
		(net "P12V_SSD15_R")
	)
	(via
		(at 440.202066 -53.461412)
		(size 0.508)
		(drill 0.254)
		(layers "F.Cu" "B.Cu")
		(net "P12V_SSD15_R")
	)
	(via
		(at 442.85789 -54.156102)
		(size 0.508)
		(drill 0.254)
		(layers "F.Cu" "B.Cu")
		(net "P12V_SSD15_R")
	)
	(via
		(at 446.259458 -45.976286)
		(size 0.508)
		(drill 0.254)
		(layers "F.Cu" "B.Cu")
		(net "P12V_SSD15_R")
	)
	(via
		(at 428.069502 -63.086234)
		(size 0.508)
		(drill 0.254)
		(layers "F.Cu" "B.Cu")
		(net "P12V_SSD15_R")
	)
	(via
		(at 441.047632 -67.10172)
		(size 0.508)
		(drill 0.254)
		(layers "F.Cu" "B.Cu")
		(net "P12V_SSD15_R")
	)
	(via
		(at 443.892178 -53.77053)
		(size 0.508)
		(drill 0.254)
		(layers "F.Cu" "B.Cu")
		(net "P12V_SSD15_R")
	)
	(via
		(at 441.682632 -67.10172)
		(size 0.508)
		(drill 0.254)
		(layers "F.Cu" "B.Cu")
		(net "P12V_SSD15_R")
	)
	(via
		(at 445.451484 -46.739048)
		(size 0.508)
		(drill 0.254)
		(layers "F.Cu" "B.Cu")
		(net "P12V_SSD15_R")
	)
	(via
		(at 444.603378 -53.00853)
		(size 0.508)
		(drill 0.254)
		(layers "F.Cu" "B.Cu")
		(net "P12V_SSD15_R")
	)
	(via
		(at 444.652908 -67.951604)
		(size 0.508)
		(drill 0.254)
		(layers "F.Cu" "B.Cu")
		(net "P12V_SSD15_R")
	)
	(via
		(at 444.652908 -68.586604)
		(size 0.508)
		(drill 0.254)
		(layers "F.Cu" "B.Cu")
		(net "P12V_SSD15_R")
	)
	(via
		(at 443.306708 -68.586604)
		(size 0.508)
		(drill 0.254)
		(layers "F.Cu" "B.Cu")
		(net "P12V_SSD15_R")
	)
	(via
		(at 445.549528 -46.066964)
		(size 0.508)
		(drill 0.254)
		(layers "F.Cu" "B.Cu")
		(net "P12V_SSD15_R")
	)
	(via
		(at 442.85789 -54.791102)
		(size 0.508)
		(drill 0.254)
		(layers "F.Cu" "B.Cu")
		(net "P12V_SSD15_R")
	)
	(via
		(at 444.527178 -53.77053)
		(size 0.508)
		(drill 0.254)
		(layers "F.Cu" "B.Cu")
		(net "P12V_SSD15_R")
	)
	(via
		(at 442.85789 -53.521102)
		(size 0.508)
		(drill 0.254)
		(layers "F.Cu" "B.Cu")
		(net "P12V_SSD15_R")
	)
	(via
		(at 443.892178 -53.00853)
		(size 0.508)
		(drill 0.254)
		(layers "F.Cu" "B.Cu")
		(net "P12V_SSD15_R")
	)
	(via
		(at 444.733934 -46.082204)
		(size 0.508)
		(drill 0.254)
		(layers "F.Cu" "B.Cu")
		(net "P12V_SSD15_R")
	)
	(via
		(at 440.202066 -52.826412)
		(size 0.508)
		(drill 0.254)
		(layers "F.Cu" "B.Cu")
		(net "P12V_SSD15_R")
	)
	(segment
		(start 135.32358 -152.3111)
		(end 136.33958 -152.3111)
		(width 0.13208)
		(layer "F.Cu")
		(net "NIC2_ADC_A0")
	)
	(segment
		(start 135.018526 -151.193754)
		(end 135.018526 -150.71344)
		(width 0.13208)
		(layer "F.Cu")
		(net "NIC2_ADC_A0")
	)
	(segment
		(start 136.33958 -152.3111)
		(end 136.33958 -151.709628)
		(width 0.13208)
		(layer "F.Cu")
		(net "NIC2_ADC_A0")
	)
	(segment
		(start 136.21258 -151.582628)
		(end 135.84428 -151.582628)
		(width 0.13208)
		(layer "F.Cu")
		(net "NIC2_ADC_A0")
	)
	(segment
		(start 135.4074 -151.582628)
		(end 135.018526 -151.193754)
		(width 0.13208)
		(layer "F.Cu")
		(net "NIC2_ADC_A0")
	)
	(segment
		(start 136.33958 -151.709628)
		(end 136.21258 -151.582628)
		(width 0.13208)
		(layer "F.Cu")
		(net "NIC2_ADC_A0")
	)
	(segment
		(start 135.84428 -151.582628)
		(end 135.4074 -151.582628)
		(width 0.13208)
		(layer "F.Cu")
		(net "NIC2_ADC_A0")
	)
	(via
		(at 135.84428 -151.582628)
		(size 0.508)
		(drill 0.254)
		(layers "F.Cu" "B.Cu")
		(net "NIC2_ADC_A0")
	)
	(segment
		(start 134.826248 -152.60066)
		(end 134.380732 -152.60066)
		(width 0.13208)
		(layer "B.Cu")
		(net "NIC2_ADC_A0")
	)
	(segment
		(start 135.84428 -151.582628)
		(end 134.826248 -152.60066)
		(width 0.13208)
		(layer "B.Cu")
		(net "NIC2_ADC_A0")
	)
	(segment
		(start 210.53552 -221.797626)
		(end 210.53552 -221.091506)
		(width 0.13208)
		(layer "F.Cu")
		(net "BUF_UART_MB_BIC_TX_EN")
	)
	(segment
		(start 210.008216 -223.140016)
		(end 210.008216 -222.32493)
		(width 0.13208)
		(layer "F.Cu")
		(net "BUF_UART_MB_BIC_TX_EN")
	)
	(segment
		(start 210.309968 -222.023178)
		(end 210.53552 -221.797626)
		(width 0.13208)
		(layer "F.Cu")
		(net "BUF_UART_MB_BIC_TX_EN")
	)
	(segment
		(start 210.008216 -222.32493)
		(end 210.309968 -222.023178)
		(width 0.13208)
		(layer "F.Cu")
		(net "BUF_UART_MB_BIC_TX_EN")
	)
	(via
		(at 210.309968 -222.023178)
		(size 0.508)
		(drill 0.254)
		(layers "F.Cu" "B.Cu")
		(net "BUF_UART_MB_BIC_TX_EN")
	)
	(segment
		(start 372.597934 -49.95291)
		(end 374.143778 -49.95291)
		(width 0.13208)
		(layer "F.Cu")
		(net "SMB_SSD12_ADC_SCL")
	)
	(segment
		(start 371.896132 -47.843948)
		(end 371.896132 -48.89246)
		(width 0.13208)
		(layer "F.Cu")
		(net "SMB_SSD12_ADC_SCL")
	)
	(segment
		(start 371.896132 -48.89246)
		(end 371.896132 -49.251108)
		(width 0.13208)
		(layer "F.Cu")
		(net "SMB_SSD12_ADC_SCL")
	)
	(segment
		(start 372.015512 -42.853102)
		(end 372.015512 -43.566842)
		(width 0.13208)
		(layer "F.Cu")
		(net "SMB_SSD12_ADC_SCL")
	)
	(segment
		(start 371.896132 -49.251108)
		(end 372.597934 -49.95291)
		(width 0.13208)
		(layer "F.Cu")
		(net "SMB_SSD12_ADC_SCL")
	)
	(via
		(at 371.896132 -48.89246)
		(size 0.508)
		(drill 0.254)
		(layers "F.Cu" "B.Cu")
		(net "SMB_SSD12_ADC_SCL")
	)
	(via
		(at 372.015512 -43.566842)
		(size 0.508)
		(drill 0.254)
		(layers "F.Cu" "B.Cu")
		(net "SMB_SSD12_ADC_SCL")
	)
	(segment
		(start 372.015512 -43.566842)
		(end 372.689374 -44.240704)
		(width 0.15494)
		(layer "In5.Cu")
		(net "SMB_SSD12_ADC_SCL")
	)
	(segment
		(start 372.689374 -48.099218)
		(end 371.896132 -48.89246)
		(width 0.15494)
		(layer "In5.Cu")
		(net "SMB_SSD12_ADC_SCL")
	)
	(segment
		(start 372.689374 -44.240704)
		(end 372.689374 -48.099218)
		(width 0.15494)
		(layer "In5.Cu")
		(net "SMB_SSD12_ADC_SCL")
	)
	(segment
		(start 398.01546 -42.853102)
		(end 398.01546 -43.566842)
		(width 0.13208)
		(layer "F.Cu")
		(net "SMB_SSD13_ADC_SCL")
	)
	(segment
		(start 397.89608 -49.261268)
		(end 397.89608 -48.89246)
		(width 0.13208)
		(layer "F.Cu")
		(net "SMB_SSD13_ADC_SCL")
	)
	(segment
		(start 397.89608 -48.89246)
		(end 397.89608 -47.843948)
		(width 0.13208)
		(layer "F.Cu")
		(net "SMB_SSD13_ADC_SCL")
	)
	(segment
		(start 400.143726 -49.95291)
		(end 398.587722 -49.95291)
		(width 0.13208)
		(layer "F.Cu")
		(net "SMB_SSD13_ADC_SCL")
	)
	(segment
		(start 398.587722 -49.95291)
		(end 397.89608 -49.261268)
		(width 0.13208)
		(layer "F.Cu")
		(net "SMB_SSD13_ADC_SCL")
	)
	(via
		(at 397.89608 -48.89246)
		(size 0.508)
		(drill 0.254)
		(layers "F.Cu" "B.Cu")
		(net "SMB_SSD13_ADC_SCL")
	)
	(via
		(at 398.01546 -43.566842)
		(size 0.508)
		(drill 0.254)
		(layers "F.Cu" "B.Cu")
		(net "SMB_SSD13_ADC_SCL")
	)
	(segment
		(start 398.01546 -43.566842)
		(end 398.689322 -44.240704)
		(width 0.15494)
		(layer "In5.Cu")
		(net "SMB_SSD13_ADC_SCL")
	)
	(segment
		(start 398.689322 -44.240704)
		(end 398.689322 -48.099218)
		(width 0.15494)
		(layer "In5.Cu")
		(net "SMB_SSD13_ADC_SCL")
	)
	(segment
		(start 398.689322 -48.099218)
		(end 397.89608 -48.89246)
		(width 0.15494)
		(layer "In5.Cu")
		(net "SMB_SSD13_ADC_SCL")
	)
	(segment
		(start 368.025426 -43.928284)
		(end 368.025426 -42.849038)
		(width 0.254)
		(layer "F.Cu")
		(net "P12V_SSD12_VIN_P")
	)
	(segment
		(start 369.432332 -44.27347)
		(end 369.432332 -44.76115)
		(width 0.254)
		(layer "F.Cu")
		(net "P12V_SSD12_VIN_P")
	)
	(segment
		(start 368.038634 -43.941492)
		(end 368.025426 -43.928284)
		(width 0.254)
		(layer "F.Cu")
		(net "P12V_SSD12_VIN_P")
	)
	(segment
		(start 368.68989 -43.941492)
		(end 368.895122 -43.73626)
		(width 0.254)
		(layer "F.Cu")
		(net "P12V_SSD12_VIN_P")
	)
	(segment
		(start 369.432332 -44.76115)
		(end 369.715034 -45.043852)
		(width 0.254)
		(layer "F.Cu")
		(net "P12V_SSD12_VIN_P")
	)
	(segment
		(start 369.715034 -45.043852)
		(end 370.396008 -45.043852)
		(width 0.254)
		(layer "F.Cu")
		(net "P12V_SSD12_VIN_P")
	)
	(segment
		(start 368.895122 -43.73626)
		(end 369.432332 -44.27347)
		(width 0.254)
		(layer "F.Cu")
		(net "P12V_SSD12_VIN_P")
	)
	(segment
		(start 368.038634 -43.941492)
		(end 368.68989 -43.941492)
		(width 0.254)
		(layer "F.Cu")
		(net "P12V_SSD12_VIN_P")
	)
	(via
		(at 368.895122 -43.73626)
		(size 0.508)
		(drill 0.254)
		(layers "F.Cu" "B.Cu")
		(net "P12V_SSD12_VIN_P")
	)
	(segment
		(start 210.836002 -222.366078)
		(end 210.787996 -222.366078)
		(width 0.13208)
		(layer "F.Cu")
		(net "UART_MB_BIC_R_TX")
	)
	(segment
		(start 211.631276 -221.884494)
		(end 211.631276 -221.171262)
		(width 0.13208)
		(layer "F.Cu")
		(net "UART_MB_BIC_R_TX")
	)
	(segment
		(start 210.658202 -222.495872)
		(end 210.658202 -223.140016)
		(width 0.13208)
		(layer "F.Cu")
		(net "UART_MB_BIC_R_TX")
	)
	(segment
		(start 211.631276 -221.884494)
		(end 211.317586 -221.884494)
		(width 0.13208)
		(layer "F.Cu")
		(net "UART_MB_BIC_R_TX")
	)
	(segment
		(start 211.317586 -221.884494)
		(end 210.836002 -222.366078)
		(width 0.13208)
		(layer "F.Cu")
		(net "UART_MB_BIC_R_TX")
	)
	(segment
		(start 211.631276 -221.171262)
		(end 211.55152 -221.091506)
		(width 0.13208)
		(layer "F.Cu")
		(net "UART_MB_BIC_R_TX")
	)
	(segment
		(start 210.787996 -222.366078)
		(end 210.658202 -222.495872)
		(width 0.13208)
		(layer "F.Cu")
		(net "UART_MB_BIC_R_TX")
	)
	(via
		(at 211.631276 -221.884494)
		(size 0.508)
		(drill 0.254)
		(layers "F.Cu" "B.Cu")
		(net "UART_MB_BIC_R_TX")
	)
	(segment
		(start 420.825422 -42.849038)
		(end 421.57396 -42.849038)
		(width 0.381)
		(layer "F.Cu")
		(net "P12V_SSD14_R")
	)
	(segment
		(start 402.775166 -63.086234)
		(end 402.069554 -63.086234)
		(width 0.4572)
		(layer "F.Cu")
		(net "P12V_SSD14_R")
	)
	(via
		(at 417.30676 -68.586604)
		(size 0.508)
		(drill 0.254)
		(layers "F.Cu" "B.Cu")
		(net "P12V_SSD14_R")
	)
	(via
		(at 414.202118 -52.826412)
		(size 0.508)
		(drill 0.254)
		(layers "F.Cu" "B.Cu")
		(net "P12V_SSD14_R")
	)
	(via
		(at 417.89223 -53.00853)
		(size 0.508)
		(drill 0.254)
		(layers "F.Cu" "B.Cu")
		(net "P12V_SSD14_R")
	)
	(via
		(at 418.65296 -67.951604)
		(size 0.508)
		(drill 0.254)
		(layers "F.Cu" "B.Cu")
		(net "P12V_SSD14_R")
	)
	(via
		(at 416.857942 -54.791102)
		(size 0.508)
		(drill 0.254)
		(layers "F.Cu" "B.Cu")
		(net "P12V_SSD14_R")
	)
	(via
		(at 417.89223 -53.77053)
		(size 0.508)
		(drill 0.254)
		(layers "F.Cu" "B.Cu")
		(net "P12V_SSD14_R")
	)
	(via
		(at 418.65296 -68.586604)
		(size 0.508)
		(drill 0.254)
		(layers "F.Cu" "B.Cu")
		(net "P12V_SSD14_R")
	)
	(via
		(at 418.786818 -46.792134)
		(size 0.508)
		(drill 0.254)
		(layers "F.Cu" "B.Cu")
		(net "P12V_SSD14_R")
	)
	(via
		(at 402.069554 -63.086234)
		(size 0.508)
		(drill 0.254)
		(layers "F.Cu" "B.Cu")
		(net "P12V_SSD14_R")
	)
	(via
		(at 419.811962 -54.320186)
		(size 0.508)
		(drill 0.254)
		(layers "F.Cu" "B.Cu")
		(net "P12V_SSD14_R")
	)
	(via
		(at 415.682684 -67.10172)
		(size 0.508)
		(drill 0.254)
		(layers "F.Cu" "B.Cu")
		(net "P12V_SSD14_R")
	)
	(via
		(at 416.857942 -52.886102)
		(size 0.508)
		(drill 0.254)
		(layers "F.Cu" "B.Cu")
		(net "P12V_SSD14_R")
	)
	(via
		(at 418.01796 -67.951604)
		(size 0.508)
		(drill 0.254)
		(layers "F.Cu" "B.Cu")
		(net "P12V_SSD14_R")
	)
	(via
		(at 416.857942 -53.521102)
		(size 0.508)
		(drill 0.254)
		(layers "F.Cu" "B.Cu")
		(net "P12V_SSD14_R")
	)
	(via
		(at 414.202118 -54.731412)
		(size 0.508)
		(drill 0.254)
		(layers "F.Cu" "B.Cu")
		(net "P12V_SSD14_R")
	)
	(via
		(at 414.202118 -53.461412)
		(size 0.508)
		(drill 0.254)
		(layers "F.Cu" "B.Cu")
		(net "P12V_SSD14_R")
	)
	(via
		(at 419.811962 -53.685186)
		(size 0.508)
		(drill 0.254)
		(layers "F.Cu" "B.Cu")
		(net "P12V_SSD14_R")
	)
	(via
		(at 420.25951 -45.976286)
		(size 0.508)
		(drill 0.254)
		(layers "F.Cu" "B.Cu")
		(net "P12V_SSD14_R")
	)
	(via
		(at 420.752524 -54.770528)
		(size 0.508)
		(drill 0.254)
		(layers "F.Cu" "B.Cu")
		(net "P12V_SSD14_R")
	)
	(via
		(at 417.30676 -67.951604)
		(size 0.508)
		(drill 0.254)
		(layers "F.Cu" "B.Cu")
		(net "P12V_SSD14_R")
	)
	(via
		(at 419.451536 -46.739048)
		(size 0.508)
		(drill 0.254)
		(layers "F.Cu" "B.Cu")
		(net "P12V_SSD14_R")
	)
	(via
		(at 416.857942 -54.156102)
		(size 0.508)
		(drill 0.254)
		(layers "F.Cu" "B.Cu")
		(net "P12V_SSD14_R")
	)
	(via
		(at 418.60343 -53.00853)
		(size 0.508)
		(drill 0.254)
		(layers "F.Cu" "B.Cu")
		(net "P12V_SSD14_R")
	)
	(via
		(at 418.52723 -53.77053)
		(size 0.508)
		(drill 0.254)
		(layers "F.Cu" "B.Cu")
		(net "P12V_SSD14_R")
	)
	(via
		(at 420.752524 -54.135528)
		(size 0.508)
		(drill 0.254)
		(layers "F.Cu" "B.Cu")
		(net "P12V_SSD14_R")
	)
	(via
		(at 414.202118 -54.096412)
		(size 0.508)
		(drill 0.254)
		(layers "F.Cu" "B.Cu")
		(net "P12V_SSD14_R")
	)
	(via
		(at 419.54958 -46.066964)
		(size 0.508)
		(drill 0.254)
		(layers "F.Cu" "B.Cu")
		(net "P12V_SSD14_R")
	)
	(via
		(at 415.047684 -67.10172)
		(size 0.508)
		(drill 0.254)
		(layers "F.Cu" "B.Cu")
		(net "P12V_SSD14_R")
	)
	(via
		(at 421.57396 -42.849038)
		(size 0.508)
		(drill 0.254)
		(layers "F.Cu" "B.Cu")
		(net "P12V_SSD14_R")
	)
	(via
		(at 418.01796 -68.586604)
		(size 0.508)
		(drill 0.254)
		(layers "F.Cu" "B.Cu")
		(net "P12V_SSD14_R")
	)
	(via
		(at 418.733986 -46.082204)
		(size 0.508)
		(drill 0.254)
		(layers "F.Cu" "B.Cu")
		(net "P12V_SSD14_R")
	)
	(segment
		(start 451.357746 -46.693836)
		(end 450.545962 -46.693836)
		(width 0.13208)
		(layer "F.Cu")
		(net "SSD15_ADC_ALERT_N")
	)
	(segment
		(start 452.143622 -46.90491)
		(end 451.932548 -46.693836)
		(width 0.13208)
		(layer "F.Cu")
		(net "SSD15_ADC_ALERT_N")
	)
	(segment
		(start 451.932548 -46.693836)
		(end 451.357746 -46.693836)
		(width 0.13208)
		(layer "F.Cu")
		(net "SSD15_ADC_ALERT_N")
	)
	(via
		(at 451.357746 -46.693836)
		(size 0.508)
		(drill 0.254)
		(layers "F.Cu" "B.Cu")
		(net "SSD15_ADC_ALERT_N")
	)
	(segment
		(start 212.067648 -226.825556)
		(end 211.491322 -226.825556)
		(width 0.13208)
		(layer "F.Cu")
		(net "UART_MB_BIC_TX_BUF")
	)
	(segment
		(start 211.308188 -225.340164)
		(end 211.308188 -225.593656)
		(width 0.13208)
		(layer "F.Cu")
		(net "UART_MB_BIC_TX_BUF")
	)
	(segment
		(start 212.177884 -226.71532)
		(end 212.067648 -226.825556)
		(width 0.13208)
		(layer "F.Cu")
		(net "UART_MB_BIC_TX_BUF")
	)
	(segment
		(start 211.821522 -226.045522)
		(end 212.177884 -226.401884)
		(width 0.13208)
		(layer "F.Cu")
		(net "UART_MB_BIC_TX_BUF")
	)
	(segment
		(start 211.760054 -226.045522)
		(end 211.821522 -226.045522)
		(width 0.13208)
		(layer "F.Cu")
		(net "UART_MB_BIC_TX_BUF")
	)
	(segment
		(start 212.177884 -226.401884)
		(end 212.177884 -226.71532)
		(width 0.13208)
		(layer "F.Cu")
		(net "UART_MB_BIC_TX_BUF")
	)
	(segment
		(start 211.308188 -225.593656)
		(end 211.760054 -226.045522)
		(width 0.13208)
		(layer "F.Cu")
		(net "UART_MB_BIC_TX_BUF")
	)
	(via
		(at 212.177884 -226.401884)
		(size 0.508)
		(drill 0.254)
		(layers "F.Cu" "B.Cu")
		(net "UART_MB_BIC_TX_BUF")
	)
	(segment
		(start 450.545962 -48.076612)
		(end 450.545962 -47.193962)
		(width 0.13208)
		(layer "F.Cu")
		(net "SMB_SSD15_ADC_SDA")
	)
	(segment
		(start 452.143622 -48.93691)
		(end 451.473316 -48.93691)
		(width 0.13208)
		(layer "F.Cu")
		(net "SMB_SSD15_ADC_SDA")
	)
	(segment
		(start 450.77634 -48.30699)
		(end 450.545962 -48.076612)
		(width 0.13208)
		(layer "F.Cu")
		(net "SMB_SSD15_ADC_SDA")
	)
	(segment
		(start 451.235826 -48.69942)
		(end 451.235826 -48.30699)
		(width 0.13208)
		(layer "F.Cu")
		(net "SMB_SSD15_ADC_SDA")
	)
	(segment
		(start 451.235826 -48.30699)
		(end 450.77634 -48.30699)
		(width 0.13208)
		(layer "F.Cu")
		(net "SMB_SSD15_ADC_SDA")
	)
	(segment
		(start 451.473316 -48.93691)
		(end 451.235826 -48.69942)
		(width 0.13208)
		(layer "F.Cu")
		(net "SMB_SSD15_ADC_SDA")
	)
	(via
		(at 451.235826 -48.30699)
		(size 0.508)
		(drill 0.254)
		(layers "F.Cu" "B.Cu")
		(net "SMB_SSD15_ADC_SDA")
	)
	(segment
		(start 368.825526 -42.849038)
		(end 369.574064 -42.849038)
		(width 0.381)
		(layer "F.Cu")
		(net "P12V_SSD12_R")
	)
	(segment
		(start 350.77527 -63.086234)
		(end 350.069658 -63.086234)
		(width 0.4572)
		(layer "F.Cu")
		(net "P12V_SSD12_R")
	)
	(via
		(at 366.603534 -53.00853)
		(size 0.508)
		(drill 0.254)
		(layers "F.Cu" "B.Cu")
		(net "P12V_SSD12_R")
	)
	(via
		(at 365.306864 -68.586604)
		(size 0.508)
		(drill 0.254)
		(layers "F.Cu" "B.Cu")
		(net "P12V_SSD12_R")
	)
	(via
		(at 362.202222 -52.826412)
		(size 0.508)
		(drill 0.254)
		(layers "F.Cu" "B.Cu")
		(net "P12V_SSD12_R")
	)
	(via
		(at 366.653064 -67.951604)
		(size 0.508)
		(drill 0.254)
		(layers "F.Cu" "B.Cu")
		(net "P12V_SSD12_R")
	)
	(via
		(at 368.752628 -54.135528)
		(size 0.508)
		(drill 0.254)
		(layers "F.Cu" "B.Cu")
		(net "P12V_SSD12_R")
	)
	(via
		(at 367.812066 -54.320186)
		(size 0.508)
		(drill 0.254)
		(layers "F.Cu" "B.Cu")
		(net "P12V_SSD12_R")
	)
	(via
		(at 367.549684 -46.066964)
		(size 0.508)
		(drill 0.254)
		(layers "F.Cu" "B.Cu")
		(net "P12V_SSD12_R")
	)
	(via
		(at 362.202222 -54.096412)
		(size 0.508)
		(drill 0.254)
		(layers "F.Cu" "B.Cu")
		(net "P12V_SSD12_R")
	)
	(via
		(at 366.018064 -68.586604)
		(size 0.508)
		(drill 0.254)
		(layers "F.Cu" "B.Cu")
		(net "P12V_SSD12_R")
	)
	(via
		(at 365.306864 -67.951604)
		(size 0.508)
		(drill 0.254)
		(layers "F.Cu" "B.Cu")
		(net "P12V_SSD12_R")
	)
	(via
		(at 364.858046 -52.886102)
		(size 0.508)
		(drill 0.254)
		(layers "F.Cu" "B.Cu")
		(net "P12V_SSD12_R")
	)
	(via
		(at 365.892334 -53.77053)
		(size 0.508)
		(drill 0.254)
		(layers "F.Cu" "B.Cu")
		(net "P12V_SSD12_R")
	)
	(via
		(at 365.892334 -53.00853)
		(size 0.508)
		(drill 0.254)
		(layers "F.Cu" "B.Cu")
		(net "P12V_SSD12_R")
	)
	(via
		(at 366.786922 -46.792134)
		(size 0.508)
		(drill 0.254)
		(layers "F.Cu" "B.Cu")
		(net "P12V_SSD12_R")
	)
	(via
		(at 364.858046 -54.791102)
		(size 0.508)
		(drill 0.254)
		(layers "F.Cu" "B.Cu")
		(net "P12V_SSD12_R")
	)
	(via
		(at 363.047788 -67.10172)
		(size 0.508)
		(drill 0.254)
		(layers "F.Cu" "B.Cu")
		(net "P12V_SSD12_R")
	)
	(via
		(at 366.527334 -53.77053)
		(size 0.508)
		(drill 0.254)
		(layers "F.Cu" "B.Cu")
		(net "P12V_SSD12_R")
	)
	(via
		(at 366.653064 -68.586604)
		(size 0.508)
		(drill 0.254)
		(layers "F.Cu" "B.Cu")
		(net "P12V_SSD12_R")
	)
	(via
		(at 366.73409 -46.082204)
		(size 0.508)
		(drill 0.254)
		(layers "F.Cu" "B.Cu")
		(net "P12V_SSD12_R")
	)
	(via
		(at 369.574064 -42.849038)
		(size 0.508)
		(drill 0.254)
		(layers "F.Cu" "B.Cu")
		(net "P12V_SSD12_R")
	)
	(via
		(at 363.682788 -67.10172)
		(size 0.508)
		(drill 0.254)
		(layers "F.Cu" "B.Cu")
		(net "P12V_SSD12_R")
	)
	(via
		(at 367.812066 -53.685186)
		(size 0.508)
		(drill 0.254)
		(layers "F.Cu" "B.Cu")
		(net "P12V_SSD12_R")
	)
	(via
		(at 366.018064 -67.951604)
		(size 0.508)
		(drill 0.254)
		(layers "F.Cu" "B.Cu")
		(net "P12V_SSD12_R")
	)
	(via
		(at 362.202222 -54.731412)
		(size 0.508)
		(drill 0.254)
		(layers "F.Cu" "B.Cu")
		(net "P12V_SSD12_R")
	)
	(via
		(at 368.752628 -54.770528)
		(size 0.508)
		(drill 0.254)
		(layers "F.Cu" "B.Cu")
		(net "P12V_SSD12_R")
	)
	(via
		(at 367.45164 -46.739048)
		(size 0.508)
		(drill 0.254)
		(layers "F.Cu" "B.Cu")
		(net "P12V_SSD12_R")
	)
	(via
		(at 364.858046 -54.156102)
		(size 0.508)
		(drill 0.254)
		(layers "F.Cu" "B.Cu")
		(net "P12V_SSD12_R")
	)
	(via
		(at 350.069658 -63.086234)
		(size 0.508)
		(drill 0.254)
		(layers "F.Cu" "B.Cu")
		(net "P12V_SSD12_R")
	)
	(via
		(at 368.259614 -45.976286)
		(size 0.508)
		(drill 0.254)
		(layers "F.Cu" "B.Cu")
		(net "P12V_SSD12_R")
	)
	(via
		(at 362.202222 -53.461412)
		(size 0.508)
		(drill 0.254)
		(layers "F.Cu" "B.Cu")
		(net "P12V_SSD12_R")
	)
	(via
		(at 364.858046 -53.521102)
		(size 0.508)
		(drill 0.254)
		(layers "F.Cu" "B.Cu")
		(net "P12V_SSD12_R")
	)
	(segment
		(start 373.579136 -45.88891)
		(end 374.143778 -45.88891)
		(width 0.13208)
		(layer "F.Cu")
		(net "SSD12_ADC_A0")
	)
	(segment
		(start 373.385842 -45.695616)
		(end 373.579136 -45.88891)
		(width 0.13208)
		(layer "F.Cu")
		(net "SSD12_ADC_A0")
	)
	(segment
		(start 373.385842 -45.771816)
		(end 372.963694 -46.193964)
		(width 0.13208)
		(layer "F.Cu")
		(net "SSD12_ADC_A0")
	)
	(segment
		(start 373.385842 -45.695616)
		(end 373.385842 -45.771816)
		(width 0.13208)
		(layer "F.Cu")
		(net "SSD12_ADC_A0")
	)
	(segment
		(start 374.143778 -44.87291)
		(end 374.143778 -45.88891)
		(width 0.13208)
		(layer "F.Cu")
		(net "SSD12_ADC_A0")
	)
	(segment
		(start 373.385842 -45.35424)
		(end 373.385842 -45.695616)
		(width 0.13208)
		(layer "F.Cu")
		(net "SSD12_ADC_A0")
	)
	(segment
		(start 372.963694 -46.193964)
		(end 372.546118 -46.193964)
		(width 0.13208)
		(layer "F.Cu")
		(net "SSD12_ADC_A0")
	)
	(via
		(at 373.385842 -45.35424)
		(size 0.508)
		(drill 0.254)
		(layers "F.Cu" "B.Cu")
		(net "SSD12_ADC_A0")
	)
	(segment
		(start 398.546066 -48.076612)
		(end 398.546066 -47.193962)
		(width 0.13208)
		(layer "F.Cu")
		(net "SMB_SSD13_ADC_SDA")
	)
	(segment
		(start 399.23593 -48.30699)
		(end 398.776444 -48.30699)
		(width 0.13208)
		(layer "F.Cu")
		(net "SMB_SSD13_ADC_SDA")
	)
	(segment
		(start 399.23593 -48.69942)
		(end 399.23593 -48.30699)
		(width 0.13208)
		(layer "F.Cu")
		(net "SMB_SSD13_ADC_SDA")
	)
	(segment
		(start 400.143726 -48.93691)
		(end 399.47342 -48.93691)
		(width 0.13208)
		(layer "F.Cu")
		(net "SMB_SSD13_ADC_SDA")
	)
	(segment
		(start 399.47342 -48.93691)
		(end 399.23593 -48.69942)
		(width 0.13208)
		(layer "F.Cu")
		(net "SMB_SSD13_ADC_SDA")
	)
	(segment
		(start 398.776444 -48.30699)
		(end 398.546066 -48.076612)
		(width 0.13208)
		(layer "F.Cu")
		(net "SMB_SSD13_ADC_SDA")
	)
	(via
		(at 399.23593 -48.30699)
		(size 0.508)
		(drill 0.254)
		(layers "F.Cu" "B.Cu")
		(net "SMB_SSD13_ADC_SDA")
	)
	(segment
		(start 227.263452 -121.778268)
		(end 232.009696 -121.778268)
		(width 0.254)
		(layer "F.Cu")
		(net "P12V_NIC3_R")
	)
	(segment
		(start 226.938332 -116.986558)
		(end 226.917758 -117.007132)
		(width 0.254)
		(layer "F.Cu")
		(net "P12V_NIC3_R")
	)
	(segment
		(start 226.917758 -121.432574)
		(end 227.263452 -121.778268)
		(width 0.254)
		(layer "F.Cu")
		(net "P12V_NIC3_R")
	)
	(segment
		(start 214.908892 -104.562148)
		(end 214.908892 -103.81361)
		(width 0.4064)
		(layer "F.Cu")
		(net "P12V_NIC3_R")
	)
	(segment
		(start 226.917758 -117.007132)
		(end 226.917758 -121.432574)
		(width 0.254)
		(layer "F.Cu")
		(net "P12V_NIC3_R")
	)
	(via
		(at 230.4923 -116.144548)
		(size 0.508)
		(drill 0.254)
		(layers "F.Cu" "B.Cu")
		(net "P12V_NIC3_R")
	)
	(via
		(at 219.172028 -117.294914)
		(size 0.508)
		(drill 0.254)
		(layers "F.Cu" "B.Cu")
		(net "P12V_NIC3_R")
	)
	(via
		(at 222.060262 -107.41152)
		(size 0.508)
		(drill 0.254)
		(layers "F.Cu" "B.Cu")
		(net "P12V_NIC3_R")
	)
	(via
		(at 217.140028 -116.583714)
		(size 0.508)
		(drill 0.254)
		(layers "F.Cu" "B.Cu")
		(net "P12V_NIC3_R")
	)
	(via
		(at 230.4923 -115.433348)
		(size 0.508)
		(drill 0.254)
		(layers "F.Cu" "B.Cu")
		(net "P12V_NIC3_R")
	)
	(via
		(at 221.204028 -116.583714)
		(size 0.508)
		(drill 0.254)
		(layers "F.Cu" "B.Cu")
		(net "P12V_NIC3_R")
	)
	(via
		(at 226.289362 -115.477036)
		(size 0.508)
		(drill 0.254)
		(layers "F.Cu" "B.Cu")
		(net "P12V_NIC3_R")
	)
	(via
		(at 218.798902 -105.936034)
		(size 0.508)
		(drill 0.254)
		(layers "F.Cu" "B.Cu")
		(net "P12V_NIC3_R")
	)
	(via
		(at 219.172028 -116.583714)
		(size 0.508)
		(drill 0.254)
		(layers "F.Cu" "B.Cu")
		(net "P12V_NIC3_R")
	)
	(via
		(at 222.822262 -106.77652)
		(size 0.508)
		(drill 0.254)
		(layers "F.Cu" "B.Cu")
		(net "P12V_NIC3_R")
	)
	(via
		(at 222.513144 -111.101632)
		(size 0.508)
		(drill 0.254)
		(layers "F.Cu" "B.Cu")
		(net "P12V_NIC3_R")
	)
	(via
		(at 223.75114 -116.188236)
		(size 0.508)
		(drill 0.254)
		(layers "F.Cu" "B.Cu")
		(net "P12V_NIC3_R")
	)
	(via
		(at 230.4923 -114.722148)
		(size 0.508)
		(drill 0.254)
		(layers "F.Cu" "B.Cu")
		(net "P12V_NIC3_R")
	)
	(via
		(at 223.783144 -111.101632)
		(size 0.508)
		(drill 0.254)
		(layers "F.Cu" "B.Cu")
		(net "P12V_NIC3_R")
	)
	(via
		(at 223.75114 -115.477036)
		(size 0.508)
		(drill 0.254)
		(layers "F.Cu" "B.Cu")
		(net "P12V_NIC3_R")
	)
	(via
		(at 231.2035 -116.855748)
		(size 0.508)
		(drill 0.254)
		(layers "F.Cu" "B.Cu")
		(net "P12V_NIC3_R")
	)
	(via
		(at 231.2035 -115.433348)
		(size 0.508)
		(drill 0.254)
		(layers "F.Cu" "B.Cu")
		(net "P12V_NIC3_R")
	)
	(via
		(at 223.842834 -108.445808)
		(size 0.508)
		(drill 0.254)
		(layers "F.Cu" "B.Cu")
		(net "P12V_NIC3_R")
	)
	(via
		(at 223.82226 -104.551226)
		(size 0.508)
		(drill 0.254)
		(layers "F.Cu" "B.Cu")
		(net "P12V_NIC3_R")
	)
	(via
		(at 214.908892 -103.81361)
		(size 0.508)
		(drill 0.254)
		(layers "F.Cu" "B.Cu")
		(net "P12V_NIC3_R")
	)
	(via
		(at 221.937834 -108.445808)
		(size 0.508)
		(drill 0.254)
		(layers "F.Cu" "B.Cu")
		(net "P12V_NIC3_R")
	)
	(via
		(at 226.289362 -116.188236)
		(size 0.508)
		(drill 0.254)
		(layers "F.Cu" "B.Cu")
		(net "P12V_NIC3_R")
	)
	(via
		(at 222.736918 -105.491788)
		(size 0.508)
		(drill 0.254)
		(layers "F.Cu" "B.Cu")
		(net "P12V_NIC3_R")
	)
	(via
		(at 222.060262 -106.70032)
		(size 0.508)
		(drill 0.254)
		(layers "F.Cu" "B.Cu")
		(net "P12V_NIC3_R")
	)
	(via
		(at 231.2035 -116.144548)
		(size 0.508)
		(drill 0.254)
		(layers "F.Cu" "B.Cu")
		(net "P12V_NIC3_R")
	)
	(via
		(at 226.289362 -116.899436)
		(size 0.508)
		(drill 0.254)
		(layers "F.Cu" "B.Cu")
		(net "P12V_NIC3_R")
	)
	(via
		(at 218.851988 -106.600752)
		(size 0.508)
		(drill 0.254)
		(layers "F.Cu" "B.Cu")
		(net "P12V_NIC3_R")
	)
	(via
		(at 218.03614 -105.12806)
		(size 0.508)
		(drill 0.254)
		(layers "F.Cu" "B.Cu")
		(net "P12V_NIC3_R")
	)
	(via
		(at 223.207834 -108.445808)
		(size 0.508)
		(drill 0.254)
		(layers "F.Cu" "B.Cu")
		(net "P12V_NIC3_R")
	)
	(via
		(at 221.204028 -117.294914)
		(size 0.508)
		(drill 0.254)
		(layers "F.Cu" "B.Cu")
		(net "P12V_NIC3_R")
	)
	(via
		(at 222.572834 -108.445808)
		(size 0.508)
		(drill 0.254)
		(layers "F.Cu" "B.Cu")
		(net "P12V_NIC3_R")
	)
	(via
		(at 221.878144 -111.101632)
		(size 0.508)
		(drill 0.254)
		(layers "F.Cu" "B.Cu")
		(net "P12V_NIC3_R")
	)
	(via
		(at 218.126818 -105.83799)
		(size 0.508)
		(drill 0.254)
		(layers "F.Cu" "B.Cu")
		(net "P12V_NIC3_R")
	)
	(via
		(at 223.148144 -111.101632)
		(size 0.508)
		(drill 0.254)
		(layers "F.Cu" "B.Cu")
		(net "P12V_NIC3_R")
	)
	(via
		(at 223.18726 -104.551226)
		(size 0.508)
		(drill 0.254)
		(layers "F.Cu" "B.Cu")
		(net "P12V_NIC3_R")
	)
	(via
		(at 223.371918 -105.491788)
		(size 0.508)
		(drill 0.254)
		(layers "F.Cu" "B.Cu")
		(net "P12V_NIC3_R")
	)
	(via
		(at 230.4923 -116.855748)
		(size 0.508)
		(drill 0.254)
		(layers "F.Cu" "B.Cu")
		(net "P12V_NIC3_R")
	)
	(via
		(at 218.142058 -106.653584)
		(size 0.508)
		(drill 0.254)
		(layers "F.Cu" "B.Cu")
		(net "P12V_NIC3_R")
	)
	(via
		(at 223.75114 -116.899436)
		(size 0.508)
		(drill 0.254)
		(layers "F.Cu" "B.Cu")
		(net "P12V_NIC3_R")
	)
	(via
		(at 231.2035 -114.722148)
		(size 0.508)
		(drill 0.254)
		(layers "F.Cu" "B.Cu")
		(net "P12V_NIC3_R")
	)
	(via
		(at 222.822262 -107.41152)
		(size 0.508)
		(drill 0.254)
		(layers "F.Cu" "B.Cu")
		(net "P12V_NIC3_R")
	)
	(via
		(at 217.140028 -117.294914)
		(size 0.508)
		(drill 0.254)
		(layers "F.Cu" "B.Cu")
		(net "P12V_NIC3_R")
	)
	(segment
		(start 426.143674 -46.90491)
		(end 425.9326 -46.693836)
		(width 0.13208)
		(layer "F.Cu")
		(net "SSD14_ADC_ALERT_N")
	)
	(segment
		(start 425.357798 -46.693836)
		(end 424.546014 -46.693836)
		(width 0.13208)
		(layer "F.Cu")
		(net "SSD14_ADC_ALERT_N")
	)
	(segment
		(start 425.9326 -46.693836)
		(end 425.357798 -46.693836)
		(width 0.13208)
		(layer "F.Cu")
		(net "SSD14_ADC_ALERT_N")
	)
	(via
		(at 425.357798 -46.693836)
		(size 0.508)
		(drill 0.254)
		(layers "F.Cu" "B.Cu")
		(net "SSD14_ADC_ALERT_N")
	)
	(segment
		(start 449.895976 -47.843948)
		(end 449.895976 -48.89246)
		(width 0.13208)
		(layer "F.Cu")
		(net "SMB_SSD15_ADC_SCL")
	)
	(segment
		(start 450.903848 -49.355756)
		(end 451.083426 -49.535334)
		(width 0.13208)
		(layer "F.Cu")
		(net "SMB_SSD15_ADC_SCL")
	)
	(segment
		(start 450.015356 -42.853102)
		(end 450.015356 -43.566842)
		(width 0.13208)
		(layer "F.Cu")
		(net "SMB_SSD15_ADC_SCL")
	)
	(segment
		(start 449.895976 -48.89246)
		(end 450.359272 -49.355756)
		(width 0.13208)
		(layer "F.Cu")
		(net "SMB_SSD15_ADC_SCL")
	)
	(segment
		(start 450.359272 -49.355756)
		(end 450.903848 -49.355756)
		(width 0.13208)
		(layer "F.Cu")
		(net "SMB_SSD15_ADC_SCL")
	)
	(segment
		(start 452.143622 -49.95291)
		(end 451.094856 -49.95291)
		(width 0.13208)
		(layer "F.Cu")
		(net "SMB_SSD15_ADC_SCL")
	)
	(segment
		(start 451.094856 -49.95291)
		(end 451.083426 -49.94148)
		(width 0.13208)
		(layer "F.Cu")
		(net "SMB_SSD15_ADC_SCL")
	)
	(segment
		(start 451.083426 -49.535334)
		(end 451.083426 -49.94148)
		(width 0.13208)
		(layer "F.Cu")
		(net "SMB_SSD15_ADC_SCL")
	)
	(via
		(at 450.015356 -43.566842)
		(size 0.508)
		(drill 0.254)
		(layers "F.Cu" "B.Cu")
		(net "SMB_SSD15_ADC_SCL")
	)
	(via
		(at 449.895976 -48.89246)
		(size 0.508)
		(drill 0.254)
		(layers "F.Cu" "B.Cu")
		(net "SMB_SSD15_ADC_SCL")
	)
	(segment
		(start 450.015356 -43.566842)
		(end 450.689218 -44.240704)
		(width 0.15494)
		(layer "In5.Cu")
		(net "SMB_SSD15_ADC_SCL")
	)
	(segment
		(start 450.689218 -48.099218)
		(end 449.895976 -48.89246)
		(width 0.15494)
		(layer "In5.Cu")
		(net "SMB_SSD15_ADC_SCL")
	)
	(segment
		(start 450.689218 -44.240704)
		(end 450.689218 -48.099218)
		(width 0.15494)
		(layer "In5.Cu")
		(net "SMB_SSD15_ADC_SCL")
	)
	(segment
		(start 447.432176 -44.27347)
		(end 447.432176 -44.76115)
		(width 0.254)
		(layer "F.Cu")
		(net "P12V_SSD15_VIN_P")
	)
	(segment
		(start 446.038478 -43.941492)
		(end 446.689734 -43.941492)
		(width 0.254)
		(layer "F.Cu")
		(net "P12V_SSD15_VIN_P")
	)
	(segment
		(start 446.894966 -43.73626)
		(end 447.432176 -44.27347)
		(width 0.254)
		(layer "F.Cu")
		(net "P12V_SSD15_VIN_P")
	)
	(segment
		(start 446.02527 -43.928284)
		(end 446.02527 -42.849038)
		(width 0.254)
		(layer "F.Cu")
		(net "P12V_SSD15_VIN_P")
	)
	(segment
		(start 446.689734 -43.941492)
		(end 446.894966 -43.73626)
		(width 0.254)
		(layer "F.Cu")
		(net "P12V_SSD15_VIN_P")
	)
	(segment
		(start 447.432176 -44.76115)
		(end 447.714878 -45.043852)
		(width 0.254)
		(layer "F.Cu")
		(net "P12V_SSD15_VIN_P")
	)
	(segment
		(start 447.714878 -45.043852)
		(end 448.395852 -45.043852)
		(width 0.254)
		(layer "F.Cu")
		(net "P12V_SSD15_VIN_P")
	)
	(segment
		(start 446.038478 -43.941492)
		(end 446.02527 -43.928284)
		(width 0.254)
		(layer "F.Cu")
		(net "P12V_SSD15_VIN_P")
	)
	(via
		(at 446.894966 -43.73626)
		(size 0.508)
		(drill 0.254)
		(layers "F.Cu" "B.Cu")
		(net "P12V_SSD15_VIN_P")
	)
	(segment
		(start 122.752612 -151.1427)
		(end 123.098306 -150.797006)
		(width 0.254)
		(layer "F.Cu")
		(net "P12V_NIC2_R")
	)
	(segment
		(start 123.098306 -150.797006)
		(end 127.523748 -150.797006)
		(width 0.254)
		(layer "F.Cu")
		(net "P12V_NIC2_R")
	)
	(segment
		(start 127.523748 -150.797006)
		(end 127.544322 -150.81758)
		(width 0.254)
		(layer "F.Cu")
		(net "P12V_NIC2_R")
	)
	(segment
		(start 122.752612 -155.888944)
		(end 122.752612 -151.1427)
		(width 0.254)
		(layer "F.Cu")
		(net "P12V_NIC2_R")
	)
	(segment
		(start 138.363452 -147.741386)
		(end 138.363452 -146.992848)
		(width 0.4064)
		(layer "F.Cu")
		(net "P12V_NIC2_R")
	)
	(via
		(at 127.675132 -154.371548)
		(size 0.508)
		(drill 0.254)
		(layers "F.Cu" "B.Cu")
		(net "P12V_NIC2_R")
	)
	(via
		(at 127.947166 -143.051276)
		(size 0.508)
		(drill 0.254)
		(layers "F.Cu" "B.Cu")
		(net "P12V_NIC2_R")
	)
	(via
		(at 129.52857 -137.276332)
		(size 0.508)
		(drill 0.254)
		(layers "F.Cu" "B.Cu")
		(net "P12V_NIC2_R")
	)
	(via
		(at 134.420356 -144.954244)
		(size 0.508)
		(drill 0.254)
		(layers "F.Cu" "B.Cu")
		(net "P12V_NIC2_R")
	)
	(via
		(at 131.677664 -138.40333)
		(size 0.508)
		(drill 0.254)
		(layers "F.Cu" "B.Cu")
		(net "P12V_NIC2_R")
	)
	(via
		(at 133.423152 -138.525758)
		(size 0.508)
		(drill 0.254)
		(layers "F.Cu" "B.Cu")
		(net "P12V_NIC2_R")
	)
	(via
		(at 129.053844 -147.630388)
		(size 0.508)
		(drill 0.254)
		(layers "F.Cu" "B.Cu")
		(net "P12V_NIC2_R")
	)
	(via
		(at 129.808732 -154.371548)
		(size 0.508)
		(drill 0.254)
		(layers "F.Cu" "B.Cu")
		(net "P12V_NIC2_R")
	)
	(via
		(at 129.097532 -154.371548)
		(size 0.508)
		(drill 0.254)
		(layers "F.Cu" "B.Cu")
		(net "P12V_NIC2_R")
	)
	(via
		(at 129.808732 -155.082748)
		(size 0.508)
		(drill 0.254)
		(layers "F.Cu" "B.Cu")
		(net "P12V_NIC2_R")
	)
	(via
		(at 127.631444 -150.16861)
		(size 0.508)
		(drill 0.254)
		(layers "F.Cu" "B.Cu")
		(net "P12V_NIC2_R")
	)
	(via
		(at 132.388864 -137.64133)
		(size 0.508)
		(drill 0.254)
		(layers "F.Cu" "B.Cu")
		(net "P12V_NIC2_R")
	)
	(via
		(at 128.386332 -155.082748)
		(size 0.508)
		(drill 0.254)
		(layers "F.Cu" "B.Cu")
		(net "P12V_NIC2_R")
	)
	(via
		(at 138.363452 -147.741386)
		(size 0.508)
		(drill 0.254)
		(layers "F.Cu" "B.Cu")
		(net "P12V_NIC2_R")
	)
	(via
		(at 128.342644 -147.630388)
		(size 0.508)
		(drill 0.254)
		(layers "F.Cu" "B.Cu")
		(net "P12V_NIC2_R")
	)
	(via
		(at 135.236204 -146.426936)
		(size 0.508)
		(drill 0.254)
		(layers "F.Cu" "B.Cu")
		(net "P12V_NIC2_R")
	)
	(via
		(at 134.473442 -145.618962)
		(size 0.508)
		(drill 0.254)
		(layers "F.Cu" "B.Cu")
		(net "P12V_NIC2_R")
	)
	(via
		(at 129.52857 -136.641332)
		(size 0.508)
		(drill 0.254)
		(layers "F.Cu" "B.Cu")
		(net "P12V_NIC2_R")
	)
	(via
		(at 133.423152 -137.255758)
		(size 0.508)
		(drill 0.254)
		(layers "F.Cu" "B.Cu")
		(net "P12V_NIC2_R")
	)
	(via
		(at 127.947166 -145.083276)
		(size 0.508)
		(drill 0.254)
		(layers "F.Cu" "B.Cu")
		(net "P12V_NIC2_R")
	)
	(via
		(at 135.505952 -139.279376)
		(size 0.508)
		(drill 0.254)
		(layers "F.Cu" "B.Cu")
		(net "P12V_NIC2_R")
	)
	(via
		(at 127.235966 -141.019276)
		(size 0.508)
		(drill 0.254)
		(layers "F.Cu" "B.Cu")
		(net "P12V_NIC2_R")
	)
	(via
		(at 135.130286 -144.901412)
		(size 0.508)
		(drill 0.254)
		(layers "F.Cu" "B.Cu")
		(net "P12V_NIC2_R")
	)
	(via
		(at 133.423152 -136.620758)
		(size 0.508)
		(drill 0.254)
		(layers "F.Cu" "B.Cu")
		(net "P12V_NIC2_R")
	)
	(via
		(at 127.235966 -145.083276)
		(size 0.508)
		(drill 0.254)
		(layers "F.Cu" "B.Cu")
		(net "P12V_NIC2_R")
	)
	(via
		(at 133.423152 -137.890758)
		(size 0.508)
		(drill 0.254)
		(layers "F.Cu" "B.Cu")
		(net "P12V_NIC2_R")
	)
	(via
		(at 133.600952 -139.279376)
		(size 0.508)
		(drill 0.254)
		(layers "F.Cu" "B.Cu")
		(net "P12V_NIC2_R")
	)
	(via
		(at 135.145526 -145.717006)
		(size 0.508)
		(drill 0.254)
		(layers "F.Cu" "B.Cu")
		(net "P12V_NIC2_R")
	)
	(via
		(at 128.342644 -150.16861)
		(size 0.508)
		(drill 0.254)
		(layers "F.Cu" "B.Cu")
		(net "P12V_NIC2_R")
	)
	(via
		(at 127.235966 -143.051276)
		(size 0.508)
		(drill 0.254)
		(layers "F.Cu" "B.Cu")
		(net "P12V_NIC2_R")
	)
	(via
		(at 134.870952 -139.279376)
		(size 0.508)
		(drill 0.254)
		(layers "F.Cu" "B.Cu")
		(net "P12V_NIC2_R")
	)
	(via
		(at 130.469132 -137.091674)
		(size 0.508)
		(drill 0.254)
		(layers "F.Cu" "B.Cu")
		(net "P12V_NIC2_R")
	)
	(via
		(at 127.947166 -141.019276)
		(size 0.508)
		(drill 0.254)
		(layers "F.Cu" "B.Cu")
		(net "P12V_NIC2_R")
	)
	(via
		(at 130.469132 -137.726674)
		(size 0.508)
		(drill 0.254)
		(layers "F.Cu" "B.Cu")
		(net "P12V_NIC2_R")
	)
	(via
		(at 134.235952 -139.279376)
		(size 0.508)
		(drill 0.254)
		(layers "F.Cu" "B.Cu")
		(net "P12V_NIC2_R")
	)
	(via
		(at 131.753864 -137.64133)
		(size 0.508)
		(drill 0.254)
		(layers "F.Cu" "B.Cu")
		(net "P12V_NIC2_R")
	)
	(via
		(at 127.675132 -155.082748)
		(size 0.508)
		(drill 0.254)
		(layers "F.Cu" "B.Cu")
		(net "P12V_NIC2_R")
	)
	(via
		(at 132.388864 -138.40333)
		(size 0.508)
		(drill 0.254)
		(layers "F.Cu" "B.Cu")
		(net "P12V_NIC2_R")
	)
	(via
		(at 129.097532 -155.082748)
		(size 0.508)
		(drill 0.254)
		(layers "F.Cu" "B.Cu")
		(net "P12V_NIC2_R")
	)
	(via
		(at 128.386332 -154.371548)
		(size 0.508)
		(drill 0.254)
		(layers "F.Cu" "B.Cu")
		(net "P12V_NIC2_R")
	)
	(via
		(at 129.053844 -150.16861)
		(size 0.508)
		(drill 0.254)
		(layers "F.Cu" "B.Cu")
		(net "P12V_NIC2_R")
	)
	(via
		(at 127.631444 -147.630388)
		(size 0.508)
		(drill 0.254)
		(layers "F.Cu" "B.Cu")
		(net "P12V_NIC2_R")
	)
	(segment
		(start 135.940292 -147.799044)
		(end 138.305794 -147.799044)
		(width 0.508)
		(layer "B.Cu")
		(net "P12V_NIC2_R")
	)
	(segment
		(start 135.236204 -147.094956)
		(end 135.940292 -147.799044)
		(width 0.508)
		(layer "B.Cu")
		(net "P12V_NIC2_R")
	)
	(segment
		(start 138.305794 -147.799044)
		(end 138.363452 -147.741386)
		(width 0.508)
		(layer "B.Cu")
		(net "P12V_NIC2_R")
	)
	(segment
		(start 135.236204 -146.426936)
		(end 135.236204 -147.094956)
		(width 0.508)
		(layer "B.Cu")
		(net "P12V_NIC2_R")
	)
	(segment
		(start 368.374676 -44.741592)
		(end 368.038634 -44.741592)
		(width 0.254)
		(layer "F.Cu")
		(net "P12V_SSD12_VIN_N")
	)
	(segment
		(start 368.747548 -45.114464)
		(end 368.374676 -44.741592)
		(width 0.254)
		(layer "F.Cu")
		(net "P12V_SSD12_VIN_N")
	)
	(segment
		(start 369.326922 -45.693838)
		(end 368.747548 -45.114464)
		(width 0.254)
		(layer "F.Cu")
		(net "P12V_SSD12_VIN_N")
	)
	(segment
		(start 367.022634 -44.741592)
		(end 368.038634 -44.741592)
		(width 0.254)
		(layer "F.Cu")
		(net "P12V_SSD12_VIN_N")
	)
	(segment
		(start 369.746022 -45.693838)
		(end 369.326922 -45.693838)
		(width 0.254)
		(layer "F.Cu")
		(net "P12V_SSD12_VIN_N")
	)
	(via
		(at 368.747548 -45.114464)
		(size 0.508)
		(drill 0.254)
		(layers "F.Cu" "B.Cu")
		(net "P12V_SSD12_VIN_N")
	)
	(segment
		(start 337.89493 -189.192408)
		(end 337.89493 -189.567312)
		(width 0.13208)
		(layer "F.Cu")
		(net "USB_DEBUG_PWR_BTN_N")
	)
	(segment
		(start 337.321398 -189.567312)
		(end 336.144362 -190.744348)
		(width 0.13208)
		(layer "F.Cu")
		(net "USB_DEBUG_PWR_BTN_N")
	)
	(segment
		(start 340.161372 -188.38545)
		(end 338.701888 -188.38545)
		(width 0.13208)
		(layer "F.Cu")
		(net "USB_DEBUG_PWR_BTN_N")
	)
	(segment
		(start 336.144362 -190.744348)
		(end 335.604612 -190.744348)
		(width 0.13208)
		(layer "F.Cu")
		(net "USB_DEBUG_PWR_BTN_N")
	)
	(segment
		(start 337.89493 -189.567312)
		(end 337.321398 -189.567312)
		(width 0.13208)
		(layer "F.Cu")
		(net "USB_DEBUG_PWR_BTN_N")
	)
	(segment
		(start 338.701888 -188.38545)
		(end 337.89493 -189.192408)
		(width 0.13208)
		(layer "F.Cu")
		(net "USB_DEBUG_PWR_BTN_N")
	)
	(via
		(at 337.89493 -189.567312)
		(size 0.508)
		(drill 0.254)
		(layers "F.Cu" "B.Cu")
		(net "USB_DEBUG_PWR_BTN_N")
	)
	(segment
		(start 333.982314 -49.487328)
		(end 333.795878 -49.300892)
		(width 0.13208)
		(layer "F.Cu")
		(net "SMB_SSD11_ADC_SCL")
	)
	(segment
		(start 334.994758 -49.95291)
		(end 334.983328 -49.94148)
		(width 0.13208)
		(layer "F.Cu")
		(net "SMB_SSD11_ADC_SCL")
	)
	(segment
		(start 333.795878 -49.300892)
		(end 333.795878 -48.89246)
		(width 0.13208)
		(layer "F.Cu")
		(net "SMB_SSD11_ADC_SCL")
	)
	(segment
		(start 334.839056 -49.487328)
		(end 333.982314 -49.487328)
		(width 0.13208)
		(layer "F.Cu")
		(net "SMB_SSD11_ADC_SCL")
	)
	(segment
		(start 334.983328 -49.94148)
		(end 334.983328 -49.6316)
		(width 0.13208)
		(layer "F.Cu")
		(net "SMB_SSD11_ADC_SCL")
	)
	(segment
		(start 333.795878 -48.89246)
		(end 333.795878 -47.843948)
		(width 0.13208)
		(layer "F.Cu")
		(net "SMB_SSD11_ADC_SCL")
	)
	(segment
		(start 336.043524 -49.95291)
		(end 334.994758 -49.95291)
		(width 0.13208)
		(layer "F.Cu")
		(net "SMB_SSD11_ADC_SCL")
	)
	(segment
		(start 334.983328 -49.6316)
		(end 334.839056 -49.487328)
		(width 0.13208)
		(layer "F.Cu")
		(net "SMB_SSD11_ADC_SCL")
	)
	(via
		(at 333.795878 -48.89246)
		(size 0.508)
		(drill 0.254)
		(layers "F.Cu" "B.Cu")
		(net "SMB_SSD11_ADC_SCL")
	)
	(segment
		(start 399.932652 -46.693836)
		(end 399.35785 -46.693836)
		(width 0.13208)
		(layer "F.Cu")
		(net "SSD13_ADC_ALERT_N")
	)
	(segment
		(start 400.143726 -46.90491)
		(end 399.932652 -46.693836)
		(width 0.13208)
		(layer "F.Cu")
		(net "SSD13_ADC_ALERT_N")
	)
	(segment
		(start 399.35785 -46.693836)
		(end 398.546066 -46.693836)
		(width 0.13208)
		(layer "F.Cu")
		(net "SSD13_ADC_ALERT_N")
	)
	(via
		(at 399.35785 -46.693836)
		(size 0.508)
		(drill 0.254)
		(layers "F.Cu" "B.Cu")
		(net "SSD13_ADC_ALERT_N")
	)
	(segment
		(start 334.445864 -47.193962)
		(end 334.445864 -48.076612)
		(width 0.13208)
		(layer "F.Cu")
		(net "SMB_SSD11_ADC_SDA")
	)
	(segment
		(start 335.373218 -48.93691)
		(end 336.043524 -48.93691)
		(width 0.13208)
		(layer "F.Cu")
		(net "SMB_SSD11_ADC_SDA")
	)
	(segment
		(start 334.676242 -48.30699)
		(end 335.135728 -48.30699)
		(width 0.13208)
		(layer "F.Cu")
		(net "SMB_SSD11_ADC_SDA")
	)
	(segment
		(start 333.915258 -42.853102)
		(end 333.915258 -43.566842)
		(width 0.13208)
		(layer "F.Cu")
		(net "SMB_SSD11_ADC_SDA")
	)
	(segment
		(start 334.445864 -48.076612)
		(end 334.676242 -48.30699)
		(width 0.13208)
		(layer "F.Cu")
		(net "SMB_SSD11_ADC_SDA")
	)
	(segment
		(start 335.135728 -48.30699)
		(end 335.135728 -48.69942)
		(width 0.13208)
		(layer "F.Cu")
		(net "SMB_SSD11_ADC_SDA")
	)
	(segment
		(start 335.135728 -48.69942)
		(end 335.373218 -48.93691)
		(width 0.13208)
		(layer "F.Cu")
		(net "SMB_SSD11_ADC_SDA")
	)
	(via
		(at 335.135728 -48.30699)
		(size 0.508)
		(drill 0.254)
		(layers "F.Cu" "B.Cu")
		(net "SMB_SSD11_ADC_SDA")
	)
	(via
		(at 333.915258 -43.566842)
		(size 0.508)
		(drill 0.254)
		(layers "F.Cu" "B.Cu")
		(net "SMB_SSD11_ADC_SDA")
	)
	(segment
		(start 334.58912 -47.760382)
		(end 334.58912 -44.240704)
		(width 0.15494)
		(layer "In5.Cu")
		(net "SMB_SSD11_ADC_SDA")
	)
	(segment
		(start 335.135728 -48.30699)
		(end 334.58912 -47.760382)
		(width 0.15494)
		(layer "In5.Cu")
		(net "SMB_SSD11_ADC_SDA")
	)
	(segment
		(start 334.58912 -44.240704)
		(end 333.915258 -43.566842)
		(width 0.15494)
		(layer "In5.Cu")
		(net "SMB_SSD11_ADC_SDA")
	)
	(segment
		(start 420.03853 -44.741592)
		(end 420.374572 -44.741592)
		(width 0.254)
		(layer "F.Cu")
		(net "P12V_SSD14_VIN_N")
	)
	(segment
		(start 419.02253 -44.741592)
		(end 420.03853 -44.741592)
		(width 0.254)
		(layer "F.Cu")
		(net "P12V_SSD14_VIN_N")
	)
	(segment
		(start 421.326818 -45.693838)
		(end 421.745918 -45.693838)
		(width 0.254)
		(layer "F.Cu")
		(net "P12V_SSD14_VIN_N")
	)
	(segment
		(start 420.374572 -44.741592)
		(end 420.747444 -45.114464)
		(width 0.254)
		(layer "F.Cu")
		(net "P12V_SSD14_VIN_N")
	)
	(segment
		(start 420.747444 -45.114464)
		(end 421.326818 -45.693838)
		(width 0.254)
		(layer "F.Cu")
		(net "P12V_SSD14_VIN_N")
	)
	(via
		(at 420.747444 -45.114464)
		(size 0.508)
		(drill 0.254)
		(layers "F.Cu" "B.Cu")
		(net "P12V_SSD14_VIN_N")
	)
	(segment
		(start 256.44602 -46.693836)
		(end 257.257804 -46.693836)
		(width 0.13208)
		(layer "F.Cu")
		(net "SSD8_ADC_ALERT_N")
	)
	(segment
		(start 257.832606 -46.693836)
		(end 258.04368 -46.90491)
		(width 0.13208)
		(layer "F.Cu")
		(net "SSD8_ADC_ALERT_N")
	)
	(segment
		(start 257.257804 -46.693836)
		(end 257.832606 -46.693836)
		(width 0.13208)
		(layer "F.Cu")
		(net "SSD8_ADC_ALERT_N")
	)
	(via
		(at 257.257804 -46.693836)
		(size 0.508)
		(drill 0.254)
		(layers "F.Cu" "B.Cu")
		(net "SSD8_ADC_ALERT_N")
	)
	(segment
		(start 373.932704 -46.693836)
		(end 373.357902 -46.693836)
		(width 0.13208)
		(layer "F.Cu")
		(net "SSD12_ADC_ALERT_N")
	)
	(segment
		(start 374.143778 -46.90491)
		(end 373.932704 -46.693836)
		(width 0.13208)
		(layer "F.Cu")
		(net "SSD12_ADC_ALERT_N")
	)
	(segment
		(start 373.357902 -46.693836)
		(end 372.546118 -46.693836)
		(width 0.13208)
		(layer "F.Cu")
		(net "SSD12_ADC_ALERT_N")
	)
	(via
		(at 373.357902 -46.693836)
		(size 0.508)
		(drill 0.254)
		(layers "F.Cu" "B.Cu")
		(net "SSD12_ADC_ALERT_N")
	)
	(segment
		(start 101.450648 -117.627654)
		(end 106.196892 -117.627654)
		(width 0.254)
		(layer "F.Cu")
		(net "P12V_NIC1_R")
	)
	(segment
		(start 88.288114 -100.058982)
		(end 88.288114 -99.449382)
		(width 0.4572)
		(layer "F.Cu")
		(net "P12V_NIC1_R")
	)
	(segment
		(start 101.104954 -117.28196)
		(end 101.450648 -117.627654)
		(width 0.254)
		(layer "F.Cu")
		(net "P12V_NIC1_R")
	)
	(segment
		(start 101.125528 -112.835944)
		(end 101.104954 -112.856518)
		(width 0.254)
		(layer "F.Cu")
		(net "P12V_NIC1_R")
	)
	(segment
		(start 101.104954 -112.856518)
		(end 101.104954 -117.28196)
		(width 0.254)
		(layer "F.Cu")
		(net "P12V_NIC1_R")
	)
	(via
		(at 105.390696 -111.282734)
		(size 0.508)
		(drill 0.254)
		(layers "F.Cu" "B.Cu")
		(net "P12V_NIC1_R")
	)
	(via
		(at 90.84437 -107.718606)
		(size 0.508)
		(drill 0.254)
		(layers "F.Cu" "B.Cu")
		(net "P12V_NIC1_R")
	)
	(via
		(at 93.451426 -112.297972)
		(size 0.508)
		(drill 0.254)
		(layers "F.Cu" "B.Cu")
		(net "P12V_NIC1_R")
	)
	(via
		(at 97.938336 -112.037622)
		(size 0.508)
		(drill 0.254)
		(layers "F.Cu" "B.Cu")
		(net "P12V_NIC1_R")
	)
	(via
		(at 96.247458 -104.022906)
		(size 0.508)
		(drill 0.254)
		(layers "F.Cu" "B.Cu")
		(net "P12V_NIC1_R")
	)
	(via
		(at 88.288114 -99.449382)
		(size 0.508)
		(drill 0.254)
		(layers "F.Cu" "B.Cu")
		(net "P12V_NIC1_R")
	)
	(via
		(at 105.390696 -110.571534)
		(size 0.508)
		(drill 0.254)
		(layers "F.Cu" "B.Cu")
		(net "P12V_NIC1_R")
	)
	(via
		(at 104.679496 -111.993934)
		(size 0.508)
		(drill 0.254)
		(layers "F.Cu" "B.Cu")
		(net "P12V_NIC1_R")
	)
	(via
		(at 105.390696 -111.993934)
		(size 0.508)
		(drill 0.254)
		(layers "F.Cu" "B.Cu")
		(net "P12V_NIC1_R")
	)
	(via
		(at 97.009458 -104.022906)
		(size 0.508)
		(drill 0.254)
		(layers "F.Cu" "B.Cu")
		(net "P12V_NIC1_R")
	)
	(via
		(at 97.938336 -112.748822)
		(size 0.508)
		(drill 0.254)
		(layers "F.Cu" "B.Cu")
		(net "P12V_NIC1_R")
	)
	(via
		(at 90.84437 -103.095806)
		(size 0.508)
		(drill 0.254)
		(layers "F.Cu" "B.Cu")
		(net "P12V_NIC1_R")
	)
	(via
		(at 96.12503 -105.057194)
		(size 0.508)
		(drill 0.254)
		(layers "F.Cu" "B.Cu")
		(net "P12V_NIC1_R")
	)
	(via
		(at 95.483426 -112.297972)
		(size 0.508)
		(drill 0.254)
		(layers "F.Cu" "B.Cu")
		(net "P12V_NIC1_R")
	)
	(via
		(at 90.84437 -104.416606)
		(size 0.508)
		(drill 0.254)
		(layers "F.Cu" "B.Cu")
		(net "P12V_NIC1_R")
	)
	(via
		(at 90.84437 -105.737406)
		(size 0.508)
		(drill 0.254)
		(layers "F.Cu" "B.Cu")
		(net "P12V_NIC1_R")
	)
	(via
		(at 90.84437 -103.756206)
		(size 0.508)
		(drill 0.254)
		(layers "F.Cu" "B.Cu")
		(net "P12V_NIC1_R")
	)
	(via
		(at 104.679496 -110.571534)
		(size 0.508)
		(drill 0.254)
		(layers "F.Cu" "B.Cu")
		(net "P12V_NIC1_R")
	)
	(via
		(at 90.84437 -107.058206)
		(size 0.508)
		(drill 0.254)
		(layers "F.Cu" "B.Cu")
		(net "P12V_NIC1_R")
	)
	(via
		(at 90.942668 -110.621572)
		(size 0.508)
		(drill 0.254)
		(layers "F.Cu" "B.Cu")
		(net "P12V_NIC1_R")
	)
	(via
		(at 100.476558 -112.037622)
		(size 0.508)
		(drill 0.254)
		(layers "F.Cu" "B.Cu")
		(net "P12V_NIC1_R")
	)
	(via
		(at 97.559114 -102.103174)
		(size 0.508)
		(drill 0.254)
		(layers "F.Cu" "B.Cu")
		(net "P12V_NIC1_R")
	)
	(via
		(at 100.476558 -112.748822)
		(size 0.508)
		(drill 0.254)
		(layers "F.Cu" "B.Cu")
		(net "P12V_NIC1_R")
	)
	(via
		(at 96.70034 -107.713018)
		(size 0.508)
		(drill 0.254)
		(layers "F.Cu" "B.Cu")
		(net "P12V_NIC1_R")
	)
	(via
		(at 96.06534 -107.713018)
		(size 0.508)
		(drill 0.254)
		(layers "F.Cu" "B.Cu")
		(net "P12V_NIC1_R")
	)
	(via
		(at 90.942668 -109.910372)
		(size 0.508)
		(drill 0.254)
		(layers "F.Cu" "B.Cu")
		(net "P12V_NIC1_R")
	)
	(via
		(at 93.451426 -111.586772)
		(size 0.508)
		(drill 0.254)
		(layers "F.Cu" "B.Cu")
		(net "P12V_NIC1_R")
	)
	(via
		(at 104.679496 -111.282734)
		(size 0.508)
		(drill 0.254)
		(layers "F.Cu" "B.Cu")
		(net "P12V_NIC1_R")
	)
	(via
		(at 95.483426 -111.586772)
		(size 0.508)
		(drill 0.254)
		(layers "F.Cu" "B.Cu")
		(net "P12V_NIC1_R")
	)
	(via
		(at 96.924114 -102.103174)
		(size 0.508)
		(drill 0.254)
		(layers "F.Cu" "B.Cu")
		(net "P12V_NIC1_R")
	)
	(via
		(at 97.374456 -101.162612)
		(size 0.508)
		(drill 0.254)
		(layers "F.Cu" "B.Cu")
		(net "P12V_NIC1_R")
	)
	(via
		(at 97.97034 -107.713018)
		(size 0.508)
		(drill 0.254)
		(layers "F.Cu" "B.Cu")
		(net "P12V_NIC1_R")
	)
	(via
		(at 97.938336 -111.326422)
		(size 0.508)
		(drill 0.254)
		(layers "F.Cu" "B.Cu")
		(net "P12V_NIC1_R")
	)
	(via
		(at 96.247458 -103.311706)
		(size 0.508)
		(drill 0.254)
		(layers "F.Cu" "B.Cu")
		(net "P12V_NIC1_R")
	)
	(via
		(at 97.009458 -103.387906)
		(size 0.508)
		(drill 0.254)
		(layers "F.Cu" "B.Cu")
		(net "P12V_NIC1_R")
	)
	(via
		(at 90.84437 -105.077006)
		(size 0.508)
		(drill 0.254)
		(layers "F.Cu" "B.Cu")
		(net "P12V_NIC1_R")
	)
	(via
		(at 97.33534 -107.713018)
		(size 0.508)
		(drill 0.254)
		(layers "F.Cu" "B.Cu")
		(net "P12V_NIC1_R")
	)
	(via
		(at 90.994992 -102.4382)
		(size 0.508)
		(drill 0.254)
		(layers "F.Cu" "B.Cu")
		(net "P12V_NIC1_R")
	)
	(via
		(at 90.84437 -106.397806)
		(size 0.508)
		(drill 0.254)
		(layers "F.Cu" "B.Cu")
		(net "P12V_NIC1_R")
	)
	(via
		(at 105.390696 -112.705134)
		(size 0.508)
		(drill 0.254)
		(layers "F.Cu" "B.Cu")
		(net "P12V_NIC1_R")
	)
	(via
		(at 98.009456 -101.162612)
		(size 0.508)
		(drill 0.254)
		(layers "F.Cu" "B.Cu")
		(net "P12V_NIC1_R")
	)
	(via
		(at 97.39503 -105.057194)
		(size 0.508)
		(drill 0.254)
		(layers "F.Cu" "B.Cu")
		(net "P12V_NIC1_R")
	)
	(via
		(at 100.476558 -111.326422)
		(size 0.508)
		(drill 0.254)
		(layers "F.Cu" "B.Cu")
		(net "P12V_NIC1_R")
	)
	(via
		(at 90.84437 -108.379006)
		(size 0.508)
		(drill 0.254)
		(layers "F.Cu" "B.Cu")
		(net "P12V_NIC1_R")
	)
	(via
		(at 98.03003 -105.057194)
		(size 0.508)
		(drill 0.254)
		(layers "F.Cu" "B.Cu")
		(net "P12V_NIC1_R")
	)
	(via
		(at 104.679496 -112.705134)
		(size 0.508)
		(drill 0.254)
		(layers "F.Cu" "B.Cu")
		(net "P12V_NIC1_R")
	)
	(via
		(at 96.76003 -105.057194)
		(size 0.508)
		(drill 0.254)
		(layers "F.Cu" "B.Cu")
		(net "P12V_NIC1_R")
	)
	(segment
		(start 309.2577 -46.693836)
		(end 308.445916 -46.693836)
		(width 0.13208)
		(layer "F.Cu")
		(net "SSD10_ADC_ALERT_N")
	)
	(segment
		(start 310.043576 -46.90491)
		(end 309.832502 -46.693836)
		(width 0.13208)
		(layer "F.Cu")
		(net "SSD10_ADC_ALERT_N")
	)
	(segment
		(start 309.832502 -46.693836)
		(end 309.2577 -46.693836)
		(width 0.13208)
		(layer "F.Cu")
		(net "SSD10_ADC_ALERT_N")
	)
	(via
		(at 309.2577 -46.693836)
		(size 0.508)
		(drill 0.254)
		(layers "F.Cu" "B.Cu")
		(net "SSD10_ADC_ALERT_N")
	)
	(segment
		(start 373.235982 -48.69942)
		(end 373.473472 -48.93691)
		(width 0.13208)
		(layer "F.Cu")
		(net "SMB_SSD12_ADC_SDA")
	)
	(segment
		(start 373.473472 -48.93691)
		(end 374.143778 -48.93691)
		(width 0.13208)
		(layer "F.Cu")
		(net "SMB_SSD12_ADC_SDA")
	)
	(segment
		(start 372.546118 -47.193962)
		(end 372.546118 -48.076612)
		(width 0.13208)
		(layer "F.Cu")
		(net "SMB_SSD12_ADC_SDA")
	)
	(segment
		(start 373.235982 -48.30699)
		(end 373.235982 -48.69942)
		(width 0.13208)
		(layer "F.Cu")
		(net "SMB_SSD12_ADC_SDA")
	)
	(segment
		(start 372.546118 -48.076612)
		(end 372.776496 -48.30699)
		(width 0.13208)
		(layer "F.Cu")
		(net "SMB_SSD12_ADC_SDA")
	)
	(segment
		(start 372.776496 -48.30699)
		(end 373.235982 -48.30699)
		(width 0.13208)
		(layer "F.Cu")
		(net "SMB_SSD12_ADC_SDA")
	)
	(via
		(at 373.235982 -48.30699)
		(size 0.508)
		(drill 0.254)
		(layers "F.Cu" "B.Cu")
		(net "SMB_SSD12_ADC_SDA")
	)
	(segment
		(start 240.212372 -60.163964)
		(end 240.212372 -59.172094)
		(width 0.381)
		(layer "F.Cu")
		(net "P12V_SSD8_R")
	)
	(segment
		(start 237.084362 -58.164222)
		(end 237.084362 -62.358778)
		(width 0.381)
		(layer "F.Cu")
		(net "P12V_SSD8_R")
	)
	(segment
		(start 252.725428 -42.849038)
		(end 253.473966 -42.849038)
		(width 0.381)
		(layer "F.Cu")
		(net "P12V_SSD8_R")
	)
	(segment
		(start 240.212372 -59.172094)
		(end 238.936784 -57.896506)
		(width 0.381)
		(layer "F.Cu")
		(net "P12V_SSD8_R")
	)
	(segment
		(start 237.352078 -57.896506)
		(end 237.084362 -58.164222)
		(width 0.381)
		(layer "F.Cu")
		(net "P12V_SSD8_R")
	)
	(segment
		(start 238.936784 -57.896506)
		(end 237.352078 -57.896506)
		(width 0.381)
		(layer "F.Cu")
		(net "P12V_SSD8_R")
	)
	(via
		(at 251.711968 -53.685186)
		(size 0.508)
		(drill 0.254)
		(layers "F.Cu" "B.Cu")
		(net "P12V_SSD8_R")
	)
	(via
		(at 248.757948 -53.521102)
		(size 0.508)
		(drill 0.254)
		(layers "F.Cu" "B.Cu")
		(net "P12V_SSD8_R")
	)
	(via
		(at 249.792236 -53.77053)
		(size 0.508)
		(drill 0.254)
		(layers "F.Cu" "B.Cu")
		(net "P12V_SSD8_R")
	)
	(via
		(at 237.084362 -62.358778)
		(size 0.508)
		(drill 0.254)
		(layers "F.Cu" "B.Cu")
		(net "P12V_SSD8_R")
	)
	(via
		(at 248.757948 -54.791102)
		(size 0.508)
		(drill 0.254)
		(layers "F.Cu" "B.Cu")
		(net "P12V_SSD8_R")
	)
	(via
		(at 250.503436 -53.00853)
		(size 0.508)
		(drill 0.254)
		(layers "F.Cu" "B.Cu")
		(net "P12V_SSD8_R")
	)
	(via
		(at 253.473966 -42.849038)
		(size 0.508)
		(drill 0.254)
		(layers "F.Cu" "B.Cu")
		(net "P12V_SSD8_R")
	)
	(via
		(at 249.917966 -68.586604)
		(size 0.508)
		(drill 0.254)
		(layers "F.Cu" "B.Cu")
		(net "P12V_SSD8_R")
	)
	(via
		(at 250.686824 -46.792134)
		(size 0.508)
		(drill 0.254)
		(layers "F.Cu" "B.Cu")
		(net "P12V_SSD8_R")
	)
	(via
		(at 249.206766 -68.586604)
		(size 0.508)
		(drill 0.254)
		(layers "F.Cu" "B.Cu")
		(net "P12V_SSD8_R")
	)
	(via
		(at 251.449586 -46.066964)
		(size 0.508)
		(drill 0.254)
		(layers "F.Cu" "B.Cu")
		(net "P12V_SSD8_R")
	)
	(via
		(at 250.552966 -68.586604)
		(size 0.508)
		(drill 0.254)
		(layers "F.Cu" "B.Cu")
		(net "P12V_SSD8_R")
	)
	(via
		(at 247.23471 -67.073272)
		(size 0.508)
		(drill 0.254)
		(layers "F.Cu" "B.Cu")
		(net "P12V_SSD8_R")
	)
	(via
		(at 246.102124 -52.826412)
		(size 0.508)
		(drill 0.254)
		(layers "F.Cu" "B.Cu")
		(net "P12V_SSD8_R")
	)
	(via
		(at 250.427236 -53.77053)
		(size 0.508)
		(drill 0.254)
		(layers "F.Cu" "B.Cu")
		(net "P12V_SSD8_R")
	)
	(via
		(at 248.757948 -54.156102)
		(size 0.508)
		(drill 0.254)
		(layers "F.Cu" "B.Cu")
		(net "P12V_SSD8_R")
	)
	(via
		(at 252.65253 -54.135528)
		(size 0.508)
		(drill 0.254)
		(layers "F.Cu" "B.Cu")
		(net "P12V_SSD8_R")
	)
	(via
		(at 252.65253 -54.770528)
		(size 0.508)
		(drill 0.254)
		(layers "F.Cu" "B.Cu")
		(net "P12V_SSD8_R")
	)
	(via
		(at 248.757948 -52.886102)
		(size 0.508)
		(drill 0.254)
		(layers "F.Cu" "B.Cu")
		(net "P12V_SSD8_R")
	)
	(via
		(at 246.59971 -67.073272)
		(size 0.508)
		(drill 0.254)
		(layers "F.Cu" "B.Cu")
		(net "P12V_SSD8_R")
	)
	(via
		(at 249.917966 -67.951604)
		(size 0.508)
		(drill 0.254)
		(layers "F.Cu" "B.Cu")
		(net "P12V_SSD8_R")
	)
	(via
		(at 250.633992 -46.082204)
		(size 0.508)
		(drill 0.254)
		(layers "F.Cu" "B.Cu")
		(net "P12V_SSD8_R")
	)
	(via
		(at 251.711968 -54.320186)
		(size 0.508)
		(drill 0.254)
		(layers "F.Cu" "B.Cu")
		(net "P12V_SSD8_R")
	)
	(via
		(at 246.102124 -53.461412)
		(size 0.508)
		(drill 0.254)
		(layers "F.Cu" "B.Cu")
		(net "P12V_SSD8_R")
	)
	(via
		(at 249.206766 -67.951604)
		(size 0.508)
		(drill 0.254)
		(layers "F.Cu" "B.Cu")
		(net "P12V_SSD8_R")
	)
	(via
		(at 250.552966 -67.951604)
		(size 0.508)
		(drill 0.254)
		(layers "F.Cu" "B.Cu")
		(net "P12V_SSD8_R")
	)
	(via
		(at 246.102124 -54.731412)
		(size 0.508)
		(drill 0.254)
		(layers "F.Cu" "B.Cu")
		(net "P12V_SSD8_R")
	)
	(via
		(at 252.159516 -45.976286)
		(size 0.508)
		(drill 0.254)
		(layers "F.Cu" "B.Cu")
		(net "P12V_SSD8_R")
	)
	(via
		(at 251.351542 -46.739048)
		(size 0.508)
		(drill 0.254)
		(layers "F.Cu" "B.Cu")
		(net "P12V_SSD8_R")
	)
	(via
		(at 246.102124 -54.096412)
		(size 0.508)
		(drill 0.254)
		(layers "F.Cu" "B.Cu")
		(net "P12V_SSD8_R")
	)
	(via
		(at 249.792236 -53.00853)
		(size 0.508)
		(drill 0.254)
		(layers "F.Cu" "B.Cu")
		(net "P12V_SSD8_R")
	)
	(segment
		(start 446.37452 -44.741592)
		(end 446.747392 -45.114464)
		(width 0.254)
		(layer "F.Cu")
		(net "P12V_SSD15_VIN_N")
	)
	(segment
		(start 445.022478 -44.741592)
		(end 446.038478 -44.741592)
		(width 0.254)
		(layer "F.Cu")
		(net "P12V_SSD15_VIN_N")
	)
	(segment
		(start 447.326766 -45.693838)
		(end 447.745866 -45.693838)
		(width 0.254)
		(layer "F.Cu")
		(net "P12V_SSD15_VIN_N")
	)
	(segment
		(start 446.038478 -44.741592)
		(end 446.37452 -44.741592)
		(width 0.254)
		(layer "F.Cu")
		(net "P12V_SSD15_VIN_N")
	)
	(segment
		(start 446.747392 -45.114464)
		(end 447.326766 -45.693838)
		(width 0.254)
		(layer "F.Cu")
		(net "P12V_SSD15_VIN_N")
	)
	(via
		(at 446.747392 -45.114464)
		(size 0.508)
		(drill 0.254)
		(layers "F.Cu" "B.Cu")
		(net "P12V_SSD15_VIN_N")
	)
	(segment
		(start 354.952808 -155.888944)
		(end 354.952808 -151.1427)
		(width 0.254)
		(layer "F.Cu")
		(net "P12V_NIC6_R")
	)
	(segment
		(start 370.563648 -147.741386)
		(end 370.563648 -146.992848)
		(width 0.4064)
		(layer "F.Cu")
		(net "P12V_NIC6_R")
	)
	(segment
		(start 359.723944 -150.797006)
		(end 359.744518 -150.81758)
		(width 0.254)
		(layer "F.Cu")
		(net "P12V_NIC6_R")
	)
	(segment
		(start 354.952808 -151.1427)
		(end 355.298502 -150.797006)
		(width 0.254)
		(layer "F.Cu")
		(net "P12V_NIC6_R")
	)
	(segment
		(start 355.298502 -150.797006)
		(end 359.723944 -150.797006)
		(width 0.254)
		(layer "F.Cu")
		(net "P12V_NIC6_R")
	)
	(via
		(at 361.25404 -147.630388)
		(size 0.508)
		(drill 0.254)
		(layers "F.Cu" "B.Cu")
		(net "P12V_NIC6_R")
	)
	(via
		(at 361.728766 -137.276332)
		(size 0.508)
		(drill 0.254)
		(layers "F.Cu" "B.Cu")
		(net "P12V_NIC6_R")
	)
	(via
		(at 360.54284 -147.630388)
		(size 0.508)
		(drill 0.254)
		(layers "F.Cu" "B.Cu")
		(net "P12V_NIC6_R")
	)
	(via
		(at 366.673638 -145.618962)
		(size 0.508)
		(drill 0.254)
		(layers "F.Cu" "B.Cu")
		(net "P12V_NIC6_R")
	)
	(via
		(at 365.623348 -136.620758)
		(size 0.508)
		(drill 0.254)
		(layers "F.Cu" "B.Cu")
		(net "P12V_NIC6_R")
	)
	(via
		(at 360.147362 -141.019276)
		(size 0.508)
		(drill 0.254)
		(layers "F.Cu" "B.Cu")
		(net "P12V_NIC6_R")
	)
	(via
		(at 359.436162 -141.019276)
		(size 0.508)
		(drill 0.254)
		(layers "F.Cu" "B.Cu")
		(net "P12V_NIC6_R")
	)
	(via
		(at 363.87786 -138.40333)
		(size 0.508)
		(drill 0.254)
		(layers "F.Cu" "B.Cu")
		(net "P12V_NIC6_R")
	)
	(via
		(at 361.297728 -154.371548)
		(size 0.508)
		(drill 0.254)
		(layers "F.Cu" "B.Cu")
		(net "P12V_NIC6_R")
	)
	(via
		(at 364.58906 -138.40333)
		(size 0.508)
		(drill 0.254)
		(layers "F.Cu" "B.Cu")
		(net "P12V_NIC6_R")
	)
	(via
		(at 360.54284 -150.16861)
		(size 0.508)
		(drill 0.254)
		(layers "F.Cu" "B.Cu")
		(net "P12V_NIC6_R")
	)
	(via
		(at 367.330482 -144.901412)
		(size 0.508)
		(drill 0.254)
		(layers "F.Cu" "B.Cu")
		(net "P12V_NIC6_R")
	)
	(via
		(at 359.436162 -145.083276)
		(size 0.508)
		(drill 0.254)
		(layers "F.Cu" "B.Cu")
		(net "P12V_NIC6_R")
	)
	(via
		(at 360.586528 -155.082748)
		(size 0.508)
		(drill 0.254)
		(layers "F.Cu" "B.Cu")
		(net "P12V_NIC6_R")
	)
	(via
		(at 361.297728 -155.082748)
		(size 0.508)
		(drill 0.254)
		(layers "F.Cu" "B.Cu")
		(net "P12V_NIC6_R")
	)
	(via
		(at 361.25404 -150.16861)
		(size 0.508)
		(drill 0.254)
		(layers "F.Cu" "B.Cu")
		(net "P12V_NIC6_R")
	)
	(via
		(at 366.264952 -139.298172)
		(size 0.508)
		(drill 0.254)
		(layers "F.Cu" "B.Cu")
		(net "P12V_NIC6_R")
	)
	(via
		(at 367.345722 -145.717006)
		(size 0.508)
		(drill 0.254)
		(layers "F.Cu" "B.Cu")
		(net "P12V_NIC6_R")
	)
	(via
		(at 360.147362 -143.051276)
		(size 0.508)
		(drill 0.254)
		(layers "F.Cu" "B.Cu")
		(net "P12V_NIC6_R")
	)
	(via
		(at 359.436162 -143.051276)
		(size 0.508)
		(drill 0.254)
		(layers "F.Cu" "B.Cu")
		(net "P12V_NIC6_R")
	)
	(via
		(at 365.623348 -137.890758)
		(size 0.508)
		(drill 0.254)
		(layers "F.Cu" "B.Cu")
		(net "P12V_NIC6_R")
	)
	(via
		(at 362.008928 -155.082748)
		(size 0.508)
		(drill 0.254)
		(layers "F.Cu" "B.Cu")
		(net "P12V_NIC6_R")
	)
	(via
		(at 363.95406 -137.64133)
		(size 0.508)
		(drill 0.254)
		(layers "F.Cu" "B.Cu")
		(net "P12V_NIC6_R")
	)
	(via
		(at 362.669328 -137.091674)
		(size 0.508)
		(drill 0.254)
		(layers "F.Cu" "B.Cu")
		(net "P12V_NIC6_R")
	)
	(via
		(at 364.58906 -137.64133)
		(size 0.508)
		(drill 0.254)
		(layers "F.Cu" "B.Cu")
		(net "P12V_NIC6_R")
	)
	(via
		(at 362.669328 -137.726674)
		(size 0.508)
		(drill 0.254)
		(layers "F.Cu" "B.Cu")
		(net "P12V_NIC6_R")
	)
	(via
		(at 360.147362 -145.083276)
		(size 0.508)
		(drill 0.254)
		(layers "F.Cu" "B.Cu")
		(net "P12V_NIC6_R")
	)
	(via
		(at 370.563648 -147.741386)
		(size 0.508)
		(drill 0.254)
		(layers "F.Cu" "B.Cu")
		(net "P12V_NIC6_R")
	)
	(via
		(at 359.83164 -150.16861)
		(size 0.508)
		(drill 0.254)
		(layers "F.Cu" "B.Cu")
		(net "P12V_NIC6_R")
	)
	(via
		(at 367.534952 -139.298172)
		(size 0.508)
		(drill 0.254)
		(layers "F.Cu" "B.Cu")
		(net "P12V_NIC6_R")
	)
	(via
		(at 362.008928 -154.371548)
		(size 0.508)
		(drill 0.254)
		(layers "F.Cu" "B.Cu")
		(net "P12V_NIC6_R")
	)
	(via
		(at 365.623348 -138.525758)
		(size 0.508)
		(drill 0.254)
		(layers "F.Cu" "B.Cu")
		(net "P12V_NIC6_R")
	)
	(via
		(at 367.4364 -146.426936)
		(size 0.508)
		(drill 0.254)
		(layers "F.Cu" "B.Cu")
		(net "P12V_NIC6_R")
	)
	(via
		(at 359.83164 -147.630388)
		(size 0.508)
		(drill 0.254)
		(layers "F.Cu" "B.Cu")
		(net "P12V_NIC6_R")
	)
	(via
		(at 360.586528 -154.371548)
		(size 0.508)
		(drill 0.254)
		(layers "F.Cu" "B.Cu")
		(net "P12V_NIC6_R")
	)
	(via
		(at 366.899952 -139.298172)
		(size 0.508)
		(drill 0.254)
		(layers "F.Cu" "B.Cu")
		(net "P12V_NIC6_R")
	)
	(via
		(at 361.728766 -136.565132)
		(size 0.508)
		(drill 0.254)
		(layers "F.Cu" "B.Cu")
		(net "P12V_NIC6_R")
	)
	(via
		(at 359.875328 -155.082748)
		(size 0.508)
		(drill 0.254)
		(layers "F.Cu" "B.Cu")
		(net "P12V_NIC6_R")
	)
	(via
		(at 365.623348 -137.255758)
		(size 0.508)
		(drill 0.254)
		(layers "F.Cu" "B.Cu")
		(net "P12V_NIC6_R")
	)
	(via
		(at 366.620552 -144.954244)
		(size 0.508)
		(drill 0.254)
		(layers "F.Cu" "B.Cu")
		(net "P12V_NIC6_R")
	)
	(via
		(at 359.875328 -154.371548)
		(size 0.508)
		(drill 0.254)
		(layers "F.Cu" "B.Cu")
		(net "P12V_NIC6_R")
	)
	(via
		(at 365.629952 -139.298172)
		(size 0.508)
		(drill 0.254)
		(layers "F.Cu" "B.Cu")
		(net "P12V_NIC6_R")
	)
	(segment
		(start 368.573812 -144.901412)
		(end 370.563648 -146.891248)
		(width 0.508)
		(layer "In15.Cu")
		(net "P12V_NIC6_R")
	)
	(segment
		(start 367.330482 -144.901412)
		(end 368.573812 -144.901412)
		(width 0.508)
		(layer "In15.Cu")
		(net "P12V_NIC6_R")
	)
	(segment
		(start 370.563648 -146.891248)
		(end 370.563648 -147.741386)
		(width 0.508)
		(layer "In15.Cu")
		(net "P12V_NIC6_R")
	)
	(segment
		(start 256.286762 -49.383188)
		(end 257.072892 -49.383188)
		(width 0.13208)
		(layer "F.Cu")
		(net "SMB_SSD8_ADC_SCL")
	)
	(segment
		(start 257.184144 -49.49444)
		(end 257.58521 -49.49444)
		(width 0.13208)
		(layer "F.Cu")
		(net "SMB_SSD8_ADC_SCL")
	)
	(segment
		(start 257.58521 -49.49444)
		(end 258.04368 -49.95291)
		(width 0.13208)
		(layer "F.Cu")
		(net "SMB_SSD8_ADC_SCL")
	)
	(segment
		(start 255.796034 -48.89246)
		(end 256.286762 -49.383188)
		(width 0.13208)
		(layer "F.Cu")
		(net "SMB_SSD8_ADC_SCL")
	)
	(segment
		(start 255.796034 -47.843948)
		(end 255.796034 -48.89246)
		(width 0.13208)
		(layer "F.Cu")
		(net "SMB_SSD8_ADC_SCL")
	)
	(segment
		(start 257.072892 -49.383188)
		(end 257.184144 -49.49444)
		(width 0.13208)
		(layer "F.Cu")
		(net "SMB_SSD8_ADC_SCL")
	)
	(via
		(at 255.796034 -48.89246)
		(size 0.508)
		(drill 0.254)
		(layers "F.Cu" "B.Cu")
		(net "SMB_SSD8_ADC_SCL")
	)
	(segment
		(start 211.754974 -218.257374)
		(end 211.346034 -218.257374)
		(width 0.13208)
		(layer "F.Cu")
		(net "TP_FSA3357K8X_B2_TX")
	)
	(segment
		(start 212.14461 -217.867738)
		(end 211.754974 -218.257374)
		(width 0.13208)
		(layer "F.Cu")
		(net "TP_FSA3357K8X_B2_TX")
	)
	(segment
		(start 212.14461 -215.320626)
		(end 212.14461 -217.867738)
		(width 0.13208)
		(layer "F.Cu")
		(net "TP_FSA3357K8X_B2_TX")
	)
	(via
		(at 212.14461 -215.320626)
		(size 0.508)
		(drill 0.254)
		(layers "F.Cu" "B.Cu")
		(net "TP_FSA3357K8X_B2_TX")
	)
	(segment
		(start 335.83245 -46.693836)
		(end 336.043524 -46.90491)
		(width 0.13208)
		(layer "F.Cu")
		(net "SSD11_ADC_ALERT_N")
	)
	(segment
		(start 335.257648 -46.693836)
		(end 335.83245 -46.693836)
		(width 0.13208)
		(layer "F.Cu")
		(net "SSD11_ADC_ALERT_N")
	)
	(segment
		(start 334.445864 -46.693836)
		(end 335.257648 -46.693836)
		(width 0.13208)
		(layer "F.Cu")
		(net "SSD11_ADC_ALERT_N")
	)
	(via
		(at 335.257648 -46.693836)
		(size 0.508)
		(drill 0.254)
		(layers "F.Cu" "B.Cu")
		(net "SSD11_ADC_ALERT_N")
	)
	(segment
		(start 303.938432 -44.741592)
		(end 304.274474 -44.741592)
		(width 0.254)
		(layer "F.Cu")
		(net "P12V_SSD10_VIN_N")
	)
	(segment
		(start 304.647346 -45.114464)
		(end 305.22672 -45.693838)
		(width 0.254)
		(layer "F.Cu")
		(net "P12V_SSD10_VIN_N")
	)
	(segment
		(start 302.922432 -44.741592)
		(end 303.938432 -44.741592)
		(width 0.254)
		(layer "F.Cu")
		(net "P12V_SSD10_VIN_N")
	)
	(segment
		(start 304.274474 -44.741592)
		(end 304.647346 -45.114464)
		(width 0.254)
		(layer "F.Cu")
		(net "P12V_SSD10_VIN_N")
	)
	(segment
		(start 305.22672 -45.693838)
		(end 305.64582 -45.693838)
		(width 0.254)
		(layer "F.Cu")
		(net "P12V_SSD10_VIN_N")
	)
	(via
		(at 304.647346 -45.114464)
		(size 0.508)
		(drill 0.254)
		(layers "F.Cu" "B.Cu")
		(net "P12V_SSD10_VIN_N")
	)
	(segment
		(start 286.675068 -63.086234)
		(end 285.969456 -63.086234)
		(width 0.4572)
		(layer "F.Cu")
		(net "P12V_SSD10_R")
	)
	(segment
		(start 304.725324 -42.849038)
		(end 305.473862 -42.849038)
		(width 0.381)
		(layer "F.Cu")
		(net "P12V_SSD10_R")
	)
	(via
		(at 304.159412 -45.976286)
		(size 0.508)
		(drill 0.254)
		(layers "F.Cu" "B.Cu")
		(net "P12V_SSD10_R")
	)
	(via
		(at 302.552862 -68.586604)
		(size 0.508)
		(drill 0.254)
		(layers "F.Cu" "B.Cu")
		(net "P12V_SSD10_R")
	)
	(via
		(at 298.10202 -54.731412)
		(size 0.508)
		(drill 0.254)
		(layers "F.Cu" "B.Cu")
		(net "P12V_SSD10_R")
	)
	(via
		(at 300.757844 -54.156102)
		(size 0.508)
		(drill 0.254)
		(layers "F.Cu" "B.Cu")
		(net "P12V_SSD10_R")
	)
	(via
		(at 302.68672 -46.792134)
		(size 0.508)
		(drill 0.254)
		(layers "F.Cu" "B.Cu")
		(net "P12V_SSD10_R")
	)
	(via
		(at 301.206662 -68.586604)
		(size 0.508)
		(drill 0.254)
		(layers "F.Cu" "B.Cu")
		(net "P12V_SSD10_R")
	)
	(via
		(at 285.969456 -63.086234)
		(size 0.508)
		(drill 0.254)
		(layers "F.Cu" "B.Cu")
		(net "P12V_SSD10_R")
	)
	(via
		(at 300.757844 -53.521102)
		(size 0.508)
		(drill 0.254)
		(layers "F.Cu" "B.Cu")
		(net "P12V_SSD10_R")
	)
	(via
		(at 302.503332 -53.00853)
		(size 0.508)
		(drill 0.254)
		(layers "F.Cu" "B.Cu")
		(net "P12V_SSD10_R")
	)
	(via
		(at 302.633888 -46.082204)
		(size 0.508)
		(drill 0.254)
		(layers "F.Cu" "B.Cu")
		(net "P12V_SSD10_R")
	)
	(via
		(at 303.711864 -53.685186)
		(size 0.508)
		(drill 0.254)
		(layers "F.Cu" "B.Cu")
		(net "P12V_SSD10_R")
	)
	(via
		(at 301.792132 -53.00853)
		(size 0.508)
		(drill 0.254)
		(layers "F.Cu" "B.Cu")
		(net "P12V_SSD10_R")
	)
	(via
		(at 302.427132 -53.77053)
		(size 0.508)
		(drill 0.254)
		(layers "F.Cu" "B.Cu")
		(net "P12V_SSD10_R")
	)
	(via
		(at 301.917862 -67.951604)
		(size 0.508)
		(drill 0.254)
		(layers "F.Cu" "B.Cu")
		(net "P12V_SSD10_R")
	)
	(via
		(at 301.792132 -53.77053)
		(size 0.508)
		(drill 0.254)
		(layers "F.Cu" "B.Cu")
		(net "P12V_SSD10_R")
	)
	(via
		(at 304.652426 -54.770528)
		(size 0.508)
		(drill 0.254)
		(layers "F.Cu" "B.Cu")
		(net "P12V_SSD10_R")
	)
	(via
		(at 298.10202 -54.096412)
		(size 0.508)
		(drill 0.254)
		(layers "F.Cu" "B.Cu")
		(net "P12V_SSD10_R")
	)
	(via
		(at 298.10202 -52.826412)
		(size 0.508)
		(drill 0.254)
		(layers "F.Cu" "B.Cu")
		(net "P12V_SSD10_R")
	)
	(via
		(at 305.473862 -42.849038)
		(size 0.508)
		(drill 0.254)
		(layers "F.Cu" "B.Cu")
		(net "P12V_SSD10_R")
	)
	(via
		(at 301.206662 -67.951604)
		(size 0.508)
		(drill 0.254)
		(layers "F.Cu" "B.Cu")
		(net "P12V_SSD10_R")
	)
	(via
		(at 304.652426 -54.135528)
		(size 0.508)
		(drill 0.254)
		(layers "F.Cu" "B.Cu")
		(net "P12V_SSD10_R")
	)
	(via
		(at 303.449482 -46.066964)
		(size 0.508)
		(drill 0.254)
		(layers "F.Cu" "B.Cu")
		(net "P12V_SSD10_R")
	)
	(via
		(at 303.711864 -54.320186)
		(size 0.508)
		(drill 0.254)
		(layers "F.Cu" "B.Cu")
		(net "P12V_SSD10_R")
	)
	(via
		(at 300.757844 -54.791102)
		(size 0.508)
		(drill 0.254)
		(layers "F.Cu" "B.Cu")
		(net "P12V_SSD10_R")
	)
	(via
		(at 303.351438 -46.739048)
		(size 0.508)
		(drill 0.254)
		(layers "F.Cu" "B.Cu")
		(net "P12V_SSD10_R")
	)
	(via
		(at 299.582586 -67.10172)
		(size 0.508)
		(drill 0.254)
		(layers "F.Cu" "B.Cu")
		(net "P12V_SSD10_R")
	)
	(via
		(at 302.552862 -67.951604)
		(size 0.508)
		(drill 0.254)
		(layers "F.Cu" "B.Cu")
		(net "P12V_SSD10_R")
	)
	(via
		(at 300.757844 -52.886102)
		(size 0.508)
		(drill 0.254)
		(layers "F.Cu" "B.Cu")
		(net "P12V_SSD10_R")
	)
	(via
		(at 301.917862 -68.586604)
		(size 0.508)
		(drill 0.254)
		(layers "F.Cu" "B.Cu")
		(net "P12V_SSD10_R")
	)
	(via
		(at 298.10202 -53.461412)
		(size 0.508)
		(drill 0.254)
		(layers "F.Cu" "B.Cu")
		(net "P12V_SSD10_R")
	)
	(via
		(at 298.947586 -67.10172)
		(size 0.508)
		(drill 0.254)
		(layers "F.Cu" "B.Cu")
		(net "P12V_SSD10_R")
	)
	(segment
		(start 208.27365 -218.236546)
		(end 208.863438 -218.236546)
		(width 0.13208)
		(layer "F.Cu")
		(net "TP_FSA3357K8X_B2_RX")
	)
	(segment
		(start 208.863438 -218.236546)
		(end 209.17916 -217.920824)
		(width 0.13208)
		(layer "F.Cu")
		(net "TP_FSA3357K8X_B2_RX")
	)
	(via
		(at 209.17916 -217.920824)
		(size 0.508)
		(drill 0.254)
		(layers "F.Cu" "B.Cu")
		(net "TP_FSA3357K8X_B2_RX")
	)
	(segment
		(start 256.183384 -49.94148)
		(end 255.866646 -49.94148)
		(width 0.13208)
		(layer "F.Cu")
		(net "SMB_SSD8_ADC_SDA")
	)
	(segment
		(start 256.676398 -48.30699)
		(end 257.135884 -48.30699)
		(width 0.13208)
		(layer "F.Cu")
		(net "SMB_SSD8_ADC_SDA")
	)
	(segment
		(start 257.373374 -48.93691)
		(end 258.04368 -48.93691)
		(width 0.13208)
		(layer "F.Cu")
		(net "SMB_SSD8_ADC_SDA")
	)
	(segment
		(start 257.135884 -48.69942)
		(end 257.373374 -48.93691)
		(width 0.13208)
		(layer "F.Cu")
		(net "SMB_SSD8_ADC_SDA")
	)
	(segment
		(start 256.44602 -48.076612)
		(end 256.676398 -48.30699)
		(width 0.13208)
		(layer "F.Cu")
		(net "SMB_SSD8_ADC_SDA")
	)
	(segment
		(start 256.44602 -47.193962)
		(end 256.44602 -48.076612)
		(width 0.13208)
		(layer "F.Cu")
		(net "SMB_SSD8_ADC_SDA")
	)
	(segment
		(start 255.866646 -49.94148)
		(end 254.769366 -48.8442)
		(width 0.13208)
		(layer "F.Cu")
		(net "SMB_SSD8_ADC_SDA")
	)
	(segment
		(start 257.135884 -48.30699)
		(end 257.135884 -48.69942)
		(width 0.13208)
		(layer "F.Cu")
		(net "SMB_SSD8_ADC_SDA")
	)
	(via
		(at 257.135884 -48.30699)
		(size 0.508)
		(drill 0.254)
		(layers "F.Cu" "B.Cu")
		(net "SMB_SSD8_ADC_SDA")
	)
	(via
		(at 254.769366 -48.8442)
		(size 0.508)
		(drill 0.254)
		(layers "F.Cu" "B.Cu")
		(net "SMB_SSD8_ADC_SDA")
	)
	(segment
		(start 254.769366 -48.8442)
		(end 255.306576 -48.30699)
		(width 0.13208)
		(layer "B.Cu")
		(net "SMB_SSD8_ADC_SDA")
	)
	(segment
		(start 255.306576 -48.30699)
		(end 257.135884 -48.30699)
		(width 0.13208)
		(layer "B.Cu")
		(net "SMB_SSD8_ADC_SDA")
	)
	(segment
		(start 206.773526 -214.975694)
		(end 206.222346 -214.424514)
		(width 0.13208)
		(layer "F.Cu")
		(net "BIC_UART_SEL2")
	)
	(segment
		(start 206.222346 -214.424514)
		(end 206.222346 -213.593426)
		(width 0.13208)
		(layer "F.Cu")
		(net "BIC_UART_SEL2")
	)
	(segment
		(start 206.773526 -215.536526)
		(end 206.773526 -214.975694)
		(width 0.13208)
		(layer "F.Cu")
		(net "BIC_UART_SEL2")
	)
	(segment
		(start 209.550508 -216.554304)
		(end 209.84591 -216.258902)
		(width 0.13208)
		(layer "F.Cu")
		(net "BIC_UART_SEL2")
	)
	(segment
		(start 207.200246 -216.554304)
		(end 209.020664 -216.554304)
		(width 0.13208)
		(layer "F.Cu")
		(net "BIC_UART_SEL2")
	)
	(segment
		(start 206.773526 -215.536526)
		(end 206.773526 -216.127584)
		(width 0.13208)
		(layer "F.Cu")
		(net "BIC_UART_SEL2")
	)
	(segment
		(start 209.020664 -216.554304)
		(end 209.550508 -216.554304)
		(width 0.13208)
		(layer "F.Cu")
		(net "BIC_UART_SEL2")
	)
	(segment
		(start 206.222346 -212.577426)
		(end 206.222346 -213.593426)
		(width 0.13208)
		(layer "F.Cu")
		(net "BIC_UART_SEL2")
	)
	(segment
		(start 209.84591 -216.258902)
		(end 209.84591 -215.557354)
		(width 0.13208)
		(layer "F.Cu")
		(net "BIC_UART_SEL2")
	)
	(segment
		(start 206.773526 -216.127584)
		(end 207.200246 -216.554304)
		(width 0.13208)
		(layer "F.Cu")
		(net "BIC_UART_SEL2")
	)
	(via
		(at 209.020664 -216.554304)
		(size 0.508)
		(drill 0.254)
		(layers "F.Cu" "B.Cu")
		(net "BIC_UART_SEL2")
	)
	(segment
		(start 312.675016 -63.086234)
		(end 311.969404 -63.086234)
		(width 0.4572)
		(layer "F.Cu")
		(net "P12V_SSD11_R")
	)
	(segment
		(start 330.725272 -42.849038)
		(end 331.47381 -42.849038)
		(width 0.381)
		(layer "F.Cu")
		(net "P12V_SSD11_R")
	)
	(via
		(at 328.50328 -53.00853)
		(size 0.508)
		(drill 0.254)
		(layers "F.Cu" "B.Cu")
		(net "P12V_SSD11_R")
	)
	(via
		(at 329.351386 -46.739048)
		(size 0.508)
		(drill 0.254)
		(layers "F.Cu" "B.Cu")
		(net "P12V_SSD11_R")
	)
	(via
		(at 327.79208 -53.77053)
		(size 0.508)
		(drill 0.254)
		(layers "F.Cu" "B.Cu")
		(net "P12V_SSD11_R")
	)
	(via
		(at 329.44943 -46.066964)
		(size 0.508)
		(drill 0.254)
		(layers "F.Cu" "B.Cu")
		(net "P12V_SSD11_R")
	)
	(via
		(at 326.757792 -52.886102)
		(size 0.508)
		(drill 0.254)
		(layers "F.Cu" "B.Cu")
		(net "P12V_SSD11_R")
	)
	(via
		(at 327.91781 -67.951604)
		(size 0.508)
		(drill 0.254)
		(layers "F.Cu" "B.Cu")
		(net "P12V_SSD11_R")
	)
	(via
		(at 327.79208 -53.00853)
		(size 0.508)
		(drill 0.254)
		(layers "F.Cu" "B.Cu")
		(net "P12V_SSD11_R")
	)
	(via
		(at 311.969404 -63.086234)
		(size 0.508)
		(drill 0.254)
		(layers "F.Cu" "B.Cu")
		(net "P12V_SSD11_R")
	)
	(via
		(at 327.20661 -67.951604)
		(size 0.508)
		(drill 0.254)
		(layers "F.Cu" "B.Cu")
		(net "P12V_SSD11_R")
	)
	(via
		(at 324.101968 -54.731412)
		(size 0.508)
		(drill 0.254)
		(layers "F.Cu" "B.Cu")
		(net "P12V_SSD11_R")
	)
	(via
		(at 327.20661 -68.586604)
		(size 0.508)
		(drill 0.254)
		(layers "F.Cu" "B.Cu")
		(net "P12V_SSD11_R")
	)
	(via
		(at 330.652374 -54.770528)
		(size 0.508)
		(drill 0.254)
		(layers "F.Cu" "B.Cu")
		(net "P12V_SSD11_R")
	)
	(via
		(at 327.91781 -68.586604)
		(size 0.508)
		(drill 0.254)
		(layers "F.Cu" "B.Cu")
		(net "P12V_SSD11_R")
	)
	(via
		(at 329.711812 -53.685186)
		(size 0.508)
		(drill 0.254)
		(layers "F.Cu" "B.Cu")
		(net "P12V_SSD11_R")
	)
	(via
		(at 326.757792 -54.791102)
		(size 0.508)
		(drill 0.254)
		(layers "F.Cu" "B.Cu")
		(net "P12V_SSD11_R")
	)
	(via
		(at 326.757792 -54.156102)
		(size 0.508)
		(drill 0.254)
		(layers "F.Cu" "B.Cu")
		(net "P12V_SSD11_R")
	)
	(via
		(at 328.686668 -46.792134)
		(size 0.508)
		(drill 0.254)
		(layers "F.Cu" "B.Cu")
		(net "P12V_SSD11_R")
	)
	(via
		(at 330.15936 -45.976286)
		(size 0.508)
		(drill 0.254)
		(layers "F.Cu" "B.Cu")
		(net "P12V_SSD11_R")
	)
	(via
		(at 326.757792 -53.521102)
		(size 0.508)
		(drill 0.254)
		(layers "F.Cu" "B.Cu")
		(net "P12V_SSD11_R")
	)
	(via
		(at 324.101968 -54.096412)
		(size 0.508)
		(drill 0.254)
		(layers "F.Cu" "B.Cu")
		(net "P12V_SSD11_R")
	)
	(via
		(at 329.711812 -54.320186)
		(size 0.508)
		(drill 0.254)
		(layers "F.Cu" "B.Cu")
		(net "P12V_SSD11_R")
	)
	(via
		(at 328.633836 -46.082204)
		(size 0.508)
		(drill 0.254)
		(layers "F.Cu" "B.Cu")
		(net "P12V_SSD11_R")
	)
	(via
		(at 328.55281 -68.586604)
		(size 0.508)
		(drill 0.254)
		(layers "F.Cu" "B.Cu")
		(net "P12V_SSD11_R")
	)
	(via
		(at 328.42708 -53.77053)
		(size 0.508)
		(drill 0.254)
		(layers "F.Cu" "B.Cu")
		(net "P12V_SSD11_R")
	)
	(via
		(at 331.47381 -42.849038)
		(size 0.508)
		(drill 0.254)
		(layers "F.Cu" "B.Cu")
		(net "P12V_SSD11_R")
	)
	(via
		(at 324.101968 -52.826412)
		(size 0.508)
		(drill 0.254)
		(layers "F.Cu" "B.Cu")
		(net "P12V_SSD11_R")
	)
	(via
		(at 325.582534 -67.10172)
		(size 0.508)
		(drill 0.254)
		(layers "F.Cu" "B.Cu")
		(net "P12V_SSD11_R")
	)
	(via
		(at 324.101968 -53.461412)
		(size 0.508)
		(drill 0.254)
		(layers "F.Cu" "B.Cu")
		(net "P12V_SSD11_R")
	)
	(via
		(at 330.652374 -54.135528)
		(size 0.508)
		(drill 0.254)
		(layers "F.Cu" "B.Cu")
		(net "P12V_SSD11_R")
	)
	(via
		(at 324.947534 -67.10172)
		(size 0.508)
		(drill 0.254)
		(layers "F.Cu" "B.Cu")
		(net "P12V_SSD11_R")
	)
	(via
		(at 328.55281 -67.951604)
		(size 0.508)
		(drill 0.254)
		(layers "F.Cu" "B.Cu")
		(net "P12V_SSD11_R")
	)
	(segment
		(start 304.589688 -43.941492)
		(end 303.938432 -43.941492)
		(width 0.254)
		(layer "F.Cu")
		(net "P12V_SSD10_VIN_P")
	)
	(segment
		(start 304.79492 -43.73626)
		(end 304.589688 -43.941492)
		(width 0.254)
		(layer "F.Cu")
		(net "P12V_SSD10_VIN_P")
	)
	(segment
		(start 303.925224 -42.849038)
		(end 303.925224 -43.928284)
		(width 0.254)
		(layer "F.Cu")
		(net "P12V_SSD10_VIN_P")
	)
	(segment
		(start 305.33213 -44.76115)
		(end 305.33213 -44.27347)
		(width 0.254)
		(layer "F.Cu")
		(net "P12V_SSD10_VIN_P")
	)
	(segment
		(start 305.33213 -44.27347)
		(end 304.79492 -43.73626)
		(width 0.254)
		(layer "F.Cu")
		(net "P12V_SSD10_VIN_P")
	)
	(segment
		(start 305.614832 -45.043852)
		(end 305.33213 -44.76115)
		(width 0.254)
		(layer "F.Cu")
		(net "P12V_SSD10_VIN_P")
	)
	(segment
		(start 303.925224 -43.928284)
		(end 303.938432 -43.941492)
		(width 0.254)
		(layer "F.Cu")
		(net "P12V_SSD10_VIN_P")
	)
	(segment
		(start 306.295806 -45.043852)
		(end 305.614832 -45.043852)
		(width 0.254)
		(layer "F.Cu")
		(net "P12V_SSD10_VIN_P")
	)
	(via
		(at 304.79492 -43.73626)
		(size 0.508)
		(drill 0.254)
		(layers "F.Cu" "B.Cu")
		(net "P12V_SSD10_VIN_P")
	)
	(segment
		(start 218.34602 -47.193962)
		(end 218.34602 -48.076612)
		(width 0.13208)
		(layer "F.Cu")
		(net "SMB_SSD7_ADC_SDA")
	)
	(segment
		(start 218.576398 -48.30699)
		(end 219.035884 -48.30699)
		(width 0.13208)
		(layer "F.Cu")
		(net "SMB_SSD7_ADC_SDA")
	)
	(segment
		(start 219.273374 -48.93691)
		(end 219.94368 -48.93691)
		(width 0.13208)
		(layer "F.Cu")
		(net "SMB_SSD7_ADC_SDA")
	)
	(segment
		(start 219.035884 -48.30699)
		(end 219.035884 -48.69942)
		(width 0.13208)
		(layer "F.Cu")
		(net "SMB_SSD7_ADC_SDA")
	)
	(segment
		(start 219.035884 -48.69942)
		(end 219.273374 -48.93691)
		(width 0.13208)
		(layer "F.Cu")
		(net "SMB_SSD7_ADC_SDA")
	)
	(segment
		(start 218.34602 -48.076612)
		(end 218.576398 -48.30699)
		(width 0.13208)
		(layer "F.Cu")
		(net "SMB_SSD7_ADC_SDA")
	)
	(via
		(at 219.035884 -48.30699)
		(size 0.508)
		(drill 0.254)
		(layers "F.Cu" "B.Cu")
		(net "SMB_SSD7_ADC_SDA")
	)
	(segment
		(start 329.925172 -42.849038)
		(end 329.925172 -43.928284)
		(width 0.254)
		(layer "F.Cu")
		(net "P12V_SSD11_VIN_P")
	)
	(segment
		(start 330.589636 -43.941492)
		(end 329.93838 -43.941492)
		(width 0.254)
		(layer "F.Cu")
		(net "P12V_SSD11_VIN_P")
	)
	(segment
		(start 331.332078 -44.76115)
		(end 331.332078 -44.27347)
		(width 0.254)
		(layer "F.Cu")
		(net "P12V_SSD11_VIN_P")
	)
	(segment
		(start 332.295754 -45.043852)
		(end 331.61478 -45.043852)
		(width 0.254)
		(layer "F.Cu")
		(net "P12V_SSD11_VIN_P")
	)
	(segment
		(start 331.61478 -45.043852)
		(end 331.332078 -44.76115)
		(width 0.254)
		(layer "F.Cu")
		(net "P12V_SSD11_VIN_P")
	)
	(segment
		(start 330.794868 -43.73626)
		(end 330.589636 -43.941492)
		(width 0.254)
		(layer "F.Cu")
		(net "P12V_SSD11_VIN_P")
	)
	(segment
		(start 331.332078 -44.27347)
		(end 330.794868 -43.73626)
		(width 0.254)
		(layer "F.Cu")
		(net "P12V_SSD11_VIN_P")
	)
	(segment
		(start 329.925172 -43.928284)
		(end 329.93838 -43.941492)
		(width 0.254)
		(layer "F.Cu")
		(net "P12V_SSD11_VIN_P")
	)
	(via
		(at 330.794868 -43.73626)
		(size 0.508)
		(drill 0.254)
		(layers "F.Cu" "B.Cu")
		(net "P12V_SSD11_VIN_P")
	)
	(segment
		(start 189.126876 -45.693838)
		(end 189.545976 -45.693838)
		(width 0.254)
		(layer "F.Cu")
		(net "P12V_SSD6_VIN_N")
	)
	(segment
		(start 187.838588 -44.741592)
		(end 188.17463 -44.741592)
		(width 0.254)
		(layer "F.Cu")
		(net "P12V_SSD6_VIN_N")
	)
	(segment
		(start 186.822588 -44.741592)
		(end 187.838588 -44.741592)
		(width 0.254)
		(layer "F.Cu")
		(net "P12V_SSD6_VIN_N")
	)
	(segment
		(start 188.17463 -44.741592)
		(end 188.547502 -45.114464)
		(width 0.254)
		(layer "F.Cu")
		(net "P12V_SSD6_VIN_N")
	)
	(segment
		(start 188.547502 -45.114464)
		(end 189.126876 -45.693838)
		(width 0.254)
		(layer "F.Cu")
		(net "P12V_SSD6_VIN_N")
	)
	(via
		(at 188.547502 -45.114464)
		(size 0.508)
		(drill 0.254)
		(layers "F.Cu" "B.Cu")
		(net "P12V_SSD6_VIN_N")
	)
	(segment
		(start 252.64745 -45.114464)
		(end 253.226824 -45.693838)
		(width 0.254)
		(layer "F.Cu")
		(net "P12V_SSD8_VIN_N")
	)
	(segment
		(start 252.274578 -44.741592)
		(end 252.64745 -45.114464)
		(width 0.254)
		(layer "F.Cu")
		(net "P12V_SSD8_VIN_N")
	)
	(segment
		(start 253.226824 -45.693838)
		(end 253.645924 -45.693838)
		(width 0.254)
		(layer "F.Cu")
		(net "P12V_SSD8_VIN_N")
	)
	(segment
		(start 250.922536 -44.741592)
		(end 251.938536 -44.741592)
		(width 0.254)
		(layer "F.Cu")
		(net "P12V_SSD8_VIN_N")
	)
	(segment
		(start 251.938536 -44.741592)
		(end 252.274578 -44.741592)
		(width 0.254)
		(layer "F.Cu")
		(net "P12V_SSD8_VIN_N")
	)
	(via
		(at 252.64745 -45.114464)
		(size 0.508)
		(drill 0.254)
		(layers "F.Cu" "B.Cu")
		(net "P12V_SSD8_VIN_N")
	)
	(segment
		(start 219.201746 -43.85691)
		(end 219.94368 -43.85691)
		(width 0.13208)
		(layer "F.Cu")
		(net "SSD7_ADC_A1")
	)
	(segment
		(start 218.34602 -44.712636)
		(end 219.201746 -43.85691)
		(width 0.13208)
		(layer "F.Cu")
		(net "SSD7_ADC_A1")
	)
	(segment
		(start 219.94368 -42.84091)
		(end 219.94368 -43.85691)
		(width 0.13208)
		(layer "F.Cu")
		(net "SSD7_ADC_A1")
	)
	(segment
		(start 218.34602 -45.693838)
		(end 218.34602 -44.712636)
		(width 0.13208)
		(layer "F.Cu")
		(net "SSD7_ADC_A1")
	)
	(via
		(at 219.201746 -43.85691)
		(size 0.508)
		(drill 0.254)
		(layers "F.Cu" "B.Cu")
		(net "SSD7_ADC_A1")
	)
	(segment
		(start 307.79593 -48.89246)
		(end 308.2798 -49.37633)
		(width 0.13208)
		(layer "F.Cu")
		(net "SMB_SSD10_ADC_SCL")
	)
	(segment
		(start 308.98338 -49.603152)
		(end 308.98338 -49.94148)
		(width 0.13208)
		(layer "F.Cu")
		(net "SMB_SSD10_ADC_SCL")
	)
	(segment
		(start 307.79593 -47.843948)
		(end 307.79593 -48.89246)
		(width 0.13208)
		(layer "F.Cu")
		(net "SMB_SSD10_ADC_SCL")
	)
	(segment
		(start 308.756558 -49.37633)
		(end 308.98338 -49.603152)
		(width 0.13208)
		(layer "F.Cu")
		(net "SMB_SSD10_ADC_SCL")
	)
	(segment
		(start 308.2798 -49.37633)
		(end 308.756558 -49.37633)
		(width 0.13208)
		(layer "F.Cu")
		(net "SMB_SSD10_ADC_SCL")
	)
	(via
		(at 307.79593 -48.89246)
		(size 0.508)
		(drill 0.254)
		(layers "F.Cu" "B.Cu")
		(net "SMB_SSD10_ADC_SCL")
	)
	(segment
		(start 166.346124 -46.693836)
		(end 167.157908 -46.693836)
		(width 0.13208)
		(layer "F.Cu")
		(net "SSD5_ADC_ALERT_N")
	)
	(segment
		(start 167.73271 -46.693836)
		(end 167.943784 -46.90491)
		(width 0.13208)
		(layer "F.Cu")
		(net "SSD5_ADC_ALERT_N")
	)
	(segment
		(start 167.157908 -46.693836)
		(end 167.73271 -46.693836)
		(width 0.13208)
		(layer "F.Cu")
		(net "SSD5_ADC_ALERT_N")
	)
	(via
		(at 167.157908 -46.693836)
		(size 0.508)
		(drill 0.254)
		(layers "F.Cu" "B.Cu")
		(net "SSD5_ADC_ALERT_N")
	)
	(segment
		(start 134.822692 -44.741592)
		(end 135.838692 -44.741592)
		(width 0.254)
		(layer "F.Cu")
		(net "P12V_SSD4_VIN_N")
	)
	(segment
		(start 136.547606 -45.114464)
		(end 137.12698 -45.693838)
		(width 0.254)
		(layer "F.Cu")
		(net "P12V_SSD4_VIN_N")
	)
	(segment
		(start 136.174734 -44.741592)
		(end 136.547606 -45.114464)
		(width 0.254)
		(layer "F.Cu")
		(net "P12V_SSD4_VIN_N")
	)
	(segment
		(start 135.838692 -44.741592)
		(end 136.174734 -44.741592)
		(width 0.254)
		(layer "F.Cu")
		(net "P12V_SSD4_VIN_N")
	)
	(segment
		(start 137.12698 -45.693838)
		(end 137.54608 -45.693838)
		(width 0.254)
		(layer "F.Cu")
		(net "P12V_SSD4_VIN_N")
	)
	(via
		(at 136.547606 -45.114464)
		(size 0.508)
		(drill 0.254)
		(layers "F.Cu" "B.Cu")
		(net "P12V_SSD4_VIN_N")
	)
	(segment
		(start 257.285744 -45.695616)
		(end 257.285744 -45.771816)
		(width 0.13208)
		(layer "F.Cu")
		(net "SSD8_ADC_A0")
	)
	(segment
		(start 256.863596 -46.193964)
		(end 256.44602 -46.193964)
		(width 0.13208)
		(layer "F.Cu")
		(net "SSD8_ADC_A0")
	)
	(segment
		(start 257.285744 -45.771816)
		(end 256.863596 -46.193964)
		(width 0.13208)
		(layer "F.Cu")
		(net "SSD8_ADC_A0")
	)
	(segment
		(start 257.479038 -45.88891)
		(end 258.04368 -45.88891)
		(width 0.13208)
		(layer "F.Cu")
		(net "SSD8_ADC_A0")
	)
	(segment
		(start 257.285744 -45.695616)
		(end 257.479038 -45.88891)
		(width 0.13208)
		(layer "F.Cu")
		(net "SSD8_ADC_A0")
	)
	(segment
		(start 257.285744 -45.35424)
		(end 257.285744 -45.695616)
		(width 0.13208)
		(layer "F.Cu")
		(net "SSD8_ADC_A0")
	)
	(segment
		(start 258.04368 -44.87291)
		(end 258.04368 -45.88891)
		(width 0.13208)
		(layer "F.Cu")
		(net "SSD8_ADC_A0")
	)
	(via
		(at 257.285744 -45.35424)
		(size 0.508)
		(drill 0.254)
		(layers "F.Cu" "B.Cu")
		(net "SSD8_ADC_A0")
	)
	(segment
		(start 162.625532 -42.849038)
		(end 163.37407 -42.849038)
		(width 0.381)
		(layer "F.Cu")
		(net "P12V_SSD5_R")
	)
	(segment
		(start 144.575276 -63.086234)
		(end 143.869664 -63.086234)
		(width 0.4572)
		(layer "F.Cu")
		(net "P12V_SSD5_R")
	)
	(via
		(at 156.002228 -54.731412)
		(size 0.508)
		(drill 0.254)
		(layers "F.Cu" "B.Cu")
		(net "P12V_SSD5_R")
	)
	(via
		(at 161.612072 -53.685186)
		(size 0.508)
		(drill 0.254)
		(layers "F.Cu" "B.Cu")
		(net "P12V_SSD5_R")
	)
	(via
		(at 161.34969 -46.066964)
		(size 0.508)
		(drill 0.254)
		(layers "F.Cu" "B.Cu")
		(net "P12V_SSD5_R")
	)
	(via
		(at 156.002228 -52.826412)
		(size 0.508)
		(drill 0.254)
		(layers "F.Cu" "B.Cu")
		(net "P12V_SSD5_R")
	)
	(via
		(at 158.658052 -54.156102)
		(size 0.508)
		(drill 0.254)
		(layers "F.Cu" "B.Cu")
		(net "P12V_SSD5_R")
	)
	(via
		(at 162.552634 -54.135528)
		(size 0.508)
		(drill 0.254)
		(layers "F.Cu" "B.Cu")
		(net "P12V_SSD5_R")
	)
	(via
		(at 160.40354 -53.00853)
		(size 0.508)
		(drill 0.254)
		(layers "F.Cu" "B.Cu")
		(net "P12V_SSD5_R")
	)
	(via
		(at 159.81807 -67.951604)
		(size 0.508)
		(drill 0.254)
		(layers "F.Cu" "B.Cu")
		(net "P12V_SSD5_R")
	)
	(via
		(at 159.10687 -67.951604)
		(size 0.508)
		(drill 0.254)
		(layers "F.Cu" "B.Cu")
		(net "P12V_SSD5_R")
	)
	(via
		(at 156.002228 -53.461412)
		(size 0.508)
		(drill 0.254)
		(layers "F.Cu" "B.Cu")
		(net "P12V_SSD5_R")
	)
	(via
		(at 157.482794 -67.10172)
		(size 0.508)
		(drill 0.254)
		(layers "F.Cu" "B.Cu")
		(net "P12V_SSD5_R")
	)
	(via
		(at 143.869664 -63.086234)
		(size 0.508)
		(drill 0.254)
		(layers "F.Cu" "B.Cu")
		(net "P12V_SSD5_R")
	)
	(via
		(at 156.002228 -54.096412)
		(size 0.508)
		(drill 0.254)
		(layers "F.Cu" "B.Cu")
		(net "P12V_SSD5_R")
	)
	(via
		(at 159.81807 -68.586604)
		(size 0.508)
		(drill 0.254)
		(layers "F.Cu" "B.Cu")
		(net "P12V_SSD5_R")
	)
	(via
		(at 160.534096 -46.082204)
		(size 0.508)
		(drill 0.254)
		(layers "F.Cu" "B.Cu")
		(net "P12V_SSD5_R")
	)
	(via
		(at 159.10687 -68.586604)
		(size 0.508)
		(drill 0.254)
		(layers "F.Cu" "B.Cu")
		(net "P12V_SSD5_R")
	)
	(via
		(at 159.69234 -53.00853)
		(size 0.508)
		(drill 0.254)
		(layers "F.Cu" "B.Cu")
		(net "P12V_SSD5_R")
	)
	(via
		(at 159.69234 -53.77053)
		(size 0.508)
		(drill 0.254)
		(layers "F.Cu" "B.Cu")
		(net "P12V_SSD5_R")
	)
	(via
		(at 160.45307 -67.951604)
		(size 0.508)
		(drill 0.254)
		(layers "F.Cu" "B.Cu")
		(net "P12V_SSD5_R")
	)
	(via
		(at 162.552634 -54.770528)
		(size 0.508)
		(drill 0.254)
		(layers "F.Cu" "B.Cu")
		(net "P12V_SSD5_R")
	)
	(via
		(at 162.05962 -45.976286)
		(size 0.508)
		(drill 0.254)
		(layers "F.Cu" "B.Cu")
		(net "P12V_SSD5_R")
	)
	(via
		(at 160.32734 -53.77053)
		(size 0.508)
		(drill 0.254)
		(layers "F.Cu" "B.Cu")
		(net "P12V_SSD5_R")
	)
	(via
		(at 158.658052 -53.521102)
		(size 0.508)
		(drill 0.254)
		(layers "F.Cu" "B.Cu")
		(net "P12V_SSD5_R")
	)
	(via
		(at 160.586928 -46.792134)
		(size 0.508)
		(drill 0.254)
		(layers "F.Cu" "B.Cu")
		(net "P12V_SSD5_R")
	)
	(via
		(at 156.847794 -67.10172)
		(size 0.508)
		(drill 0.254)
		(layers "F.Cu" "B.Cu")
		(net "P12V_SSD5_R")
	)
	(via
		(at 161.251646 -46.739048)
		(size 0.508)
		(drill 0.254)
		(layers "F.Cu" "B.Cu")
		(net "P12V_SSD5_R")
	)
	(via
		(at 158.658052 -52.886102)
		(size 0.508)
		(drill 0.254)
		(layers "F.Cu" "B.Cu")
		(net "P12V_SSD5_R")
	)
	(via
		(at 160.45307 -68.586604)
		(size 0.508)
		(drill 0.254)
		(layers "F.Cu" "B.Cu")
		(net "P12V_SSD5_R")
	)
	(via
		(at 158.658052 -54.791102)
		(size 0.508)
		(drill 0.254)
		(layers "F.Cu" "B.Cu")
		(net "P12V_SSD5_R")
	)
	(via
		(at 163.37407 -42.849038)
		(size 0.508)
		(drill 0.254)
		(layers "F.Cu" "B.Cu")
		(net "P12V_SSD5_R")
	)
	(via
		(at 161.612072 -54.320186)
		(size 0.508)
		(drill 0.254)
		(layers "F.Cu" "B.Cu")
		(net "P12V_SSD5_R")
	)
	(segment
		(start 331.226668 -45.693838)
		(end 331.645768 -45.693838)
		(width 0.254)
		(layer "F.Cu")
		(net "P12V_SSD11_VIN_N")
	)
	(segment
		(start 328.92238 -44.741592)
		(end 329.93838 -44.741592)
		(width 0.254)
		(layer "F.Cu")
		(net "P12V_SSD11_VIN_N")
	)
	(segment
		(start 329.93838 -44.741592)
		(end 330.274422 -44.741592)
		(width 0.254)
		(layer "F.Cu")
		(net "P12V_SSD11_VIN_N")
	)
	(segment
		(start 330.647294 -45.114464)
		(end 331.226668 -45.693838)
		(width 0.254)
		(layer "F.Cu")
		(net "P12V_SSD11_VIN_N")
	)
	(segment
		(start 330.274422 -44.741592)
		(end 330.647294 -45.114464)
		(width 0.254)
		(layer "F.Cu")
		(net "P12V_SSD11_VIN_N")
	)
	(via
		(at 330.647294 -45.114464)
		(size 0.508)
		(drill 0.254)
		(layers "F.Cu" "B.Cu")
		(net "P12V_SSD11_VIN_N")
	)
	(segment
		(start 166.437564 -49.95291)
		(end 167.943784 -49.95291)
		(width 0.13208)
		(layer "F.Cu")
		(net "SMB_SSD5_ADC_SCL")
	)
	(segment
		(start 165.696138 -47.843948)
		(end 165.696138 -48.89246)
		(width 0.13208)
		(layer "F.Cu")
		(net "SMB_SSD5_ADC_SCL")
	)
	(segment
		(start 165.696138 -49.211484)
		(end 166.437564 -49.95291)
		(width 0.13208)
		(layer "F.Cu")
		(net "SMB_SSD5_ADC_SCL")
	)
	(segment
		(start 165.696138 -48.89246)
		(end 165.696138 -49.211484)
		(width 0.13208)
		(layer "F.Cu")
		(net "SMB_SSD5_ADC_SCL")
	)
	(via
		(at 165.696138 -48.89246)
		(size 0.508)
		(drill 0.254)
		(layers "F.Cu" "B.Cu")
		(net "SMB_SSD5_ADC_SCL")
	)
	(segment
		(start 251.938536 -43.941492)
		(end 251.925328 -43.928284)
		(width 0.254)
		(layer "F.Cu")
		(net "P12V_SSD8_VIN_P")
	)
	(segment
		(start 252.589792 -43.941492)
		(end 252.795024 -43.73626)
		(width 0.254)
		(layer "F.Cu")
		(net "P12V_SSD8_VIN_P")
	)
	(segment
		(start 252.795024 -43.73626)
		(end 253.49708 -43.73626)
		(width 0.254)
		(layer "F.Cu")
		(net "P12V_SSD8_VIN_P")
	)
	(segment
		(start 251.938536 -43.941492)
		(end 252.589792 -43.941492)
		(width 0.254)
		(layer "F.Cu")
		(net "P12V_SSD8_VIN_P")
	)
	(segment
		(start 254.29591 -44.53509)
		(end 254.29591 -45.043852)
		(width 0.254)
		(layer "F.Cu")
		(net "P12V_SSD8_VIN_P")
	)
	(segment
		(start 251.925328 -43.928284)
		(end 251.925328 -42.849038)
		(width 0.254)
		(layer "F.Cu")
		(net "P12V_SSD8_VIN_P")
	)
	(segment
		(start 253.49708 -43.73626)
		(end 254.29591 -44.53509)
		(width 0.254)
		(layer "F.Cu")
		(net "P12V_SSD8_VIN_P")
	)
	(via
		(at 252.795024 -43.73626)
		(size 0.508)
		(drill 0.254)
		(layers "F.Cu" "B.Cu")
		(net "P12V_SSD8_VIN_P")
	)
	(segment
		(start 215.39708 -43.73626)
		(end 214.695024 -43.73626)
		(width 0.254)
		(layer "F.Cu")
		(net "P12V_SSD7_VIN_P")
	)
	(segment
		(start 213.838536 -43.941492)
		(end 213.825328 -43.928284)
		(width 0.254)
		(layer "F.Cu")
		(net "P12V_SSD7_VIN_P")
	)
	(segment
		(start 214.489792 -43.941492)
		(end 213.838536 -43.941492)
		(width 0.254)
		(layer "F.Cu")
		(net "P12V_SSD7_VIN_P")
	)
	(segment
		(start 216.19591 -44.53509)
		(end 215.39708 -43.73626)
		(width 0.254)
		(layer "F.Cu")
		(net "P12V_SSD7_VIN_P")
	)
	(segment
		(start 216.19591 -45.043852)
		(end 216.19591 -44.53509)
		(width 0.254)
		(layer "F.Cu")
		(net "P12V_SSD7_VIN_P")
	)
	(segment
		(start 213.825328 -43.928284)
		(end 213.825328 -42.849038)
		(width 0.254)
		(layer "F.Cu")
		(net "P12V_SSD7_VIN_P")
	)
	(segment
		(start 214.695024 -43.73626)
		(end 214.489792 -43.941492)
		(width 0.254)
		(layer "F.Cu")
		(net "P12V_SSD7_VIN_P")
	)
	(via
		(at 214.695024 -43.73626)
		(size 0.508)
		(drill 0.254)
		(layers "F.Cu" "B.Cu")
		(net "P12V_SSD7_VIN_P")
	)
	(segment
		(start 188.695076 -43.73626)
		(end 189.397132 -43.73626)
		(width 0.254)
		(layer "F.Cu")
		(net "P12V_SSD6_VIN_P")
	)
	(segment
		(start 188.489844 -43.941492)
		(end 188.695076 -43.73626)
		(width 0.254)
		(layer "F.Cu")
		(net "P12V_SSD6_VIN_P")
	)
	(segment
		(start 189.397132 -43.73626)
		(end 190.195962 -44.53509)
		(width 0.254)
		(layer "F.Cu")
		(net "P12V_SSD6_VIN_P")
	)
	(segment
		(start 190.195962 -44.53509)
		(end 190.195962 -45.043852)
		(width 0.254)
		(layer "F.Cu")
		(net "P12V_SSD6_VIN_P")
	)
	(segment
		(start 187.82538 -43.928284)
		(end 187.82538 -42.849038)
		(width 0.254)
		(layer "F.Cu")
		(net "P12V_SSD6_VIN_P")
	)
	(segment
		(start 187.838588 -43.941492)
		(end 187.82538 -43.928284)
		(width 0.254)
		(layer "F.Cu")
		(net "P12V_SSD6_VIN_P")
	)
	(segment
		(start 187.838588 -43.941492)
		(end 188.489844 -43.941492)
		(width 0.254)
		(layer "F.Cu")
		(net "P12V_SSD6_VIN_P")
	)
	(via
		(at 188.695076 -43.73626)
		(size 0.508)
		(drill 0.254)
		(layers "F.Cu" "B.Cu")
		(net "P12V_SSD6_VIN_P")
	)
	(segment
		(start 141.732762 -46.693836)
		(end 141.943836 -46.90491)
		(width 0.13208)
		(layer "F.Cu")
		(net "SSD4_ADC_ALERT_N")
	)
	(segment
		(start 140.346176 -46.693836)
		(end 141.15796 -46.693836)
		(width 0.13208)
		(layer "F.Cu")
		(net "SSD4_ADC_ALERT_N")
	)
	(segment
		(start 141.15796 -46.693836)
		(end 141.732762 -46.693836)
		(width 0.13208)
		(layer "F.Cu")
		(net "SSD4_ADC_ALERT_N")
	)
	(via
		(at 141.15796 -46.693836)
		(size 0.508)
		(drill 0.254)
		(layers "F.Cu" "B.Cu")
		(net "SSD4_ADC_ALERT_N")
	)
	(segment
		(start 139.69619 -49.452276)
		(end 139.69619 -48.89246)
		(width 0.13208)
		(layer "F.Cu")
		(net "SMB_SSD4_ADC_SCL")
	)
	(segment
		(start 139.69619 -48.89246)
		(end 139.69619 -47.843948)
		(width 0.13208)
		(layer "F.Cu")
		(net "SMB_SSD4_ADC_SCL")
	)
	(segment
		(start 140.196824 -49.95291)
		(end 139.69619 -49.452276)
		(width 0.13208)
		(layer "F.Cu")
		(net "SMB_SSD4_ADC_SCL")
	)
	(segment
		(start 141.943836 -49.95291)
		(end 140.196824 -49.95291)
		(width 0.13208)
		(layer "F.Cu")
		(net "SMB_SSD4_ADC_SCL")
	)
	(via
		(at 139.69619 -48.89246)
		(size 0.508)
		(drill 0.254)
		(layers "F.Cu" "B.Cu")
		(net "SMB_SSD4_ADC_SCL")
	)
	(segment
		(start 166.346124 -46.193964)
		(end 166.7637 -46.193964)
		(width 0.13208)
		(layer "F.Cu")
		(net "SSD5_ADC_A0")
	)
	(segment
		(start 167.185848 -45.771816)
		(end 167.185848 -45.695616)
		(width 0.13208)
		(layer "F.Cu")
		(net "SSD5_ADC_A0")
	)
	(segment
		(start 167.185848 -45.35424)
		(end 167.185848 -45.695616)
		(width 0.13208)
		(layer "F.Cu")
		(net "SSD5_ADC_A0")
	)
	(segment
		(start 166.7637 -46.193964)
		(end 167.185848 -45.771816)
		(width 0.13208)
		(layer "F.Cu")
		(net "SSD5_ADC_A0")
	)
	(segment
		(start 167.379142 -45.88891)
		(end 167.185848 -45.695616)
		(width 0.13208)
		(layer "F.Cu")
		(net "SSD5_ADC_A0")
	)
	(segment
		(start 167.943784 -45.88891)
		(end 167.379142 -45.88891)
		(width 0.13208)
		(layer "F.Cu")
		(net "SSD5_ADC_A0")
	)
	(segment
		(start 167.943784 -44.87291)
		(end 167.943784 -45.88891)
		(width 0.13208)
		(layer "F.Cu")
		(net "SSD5_ADC_A0")
	)
	(via
		(at 167.185848 -45.35424)
		(size 0.508)
		(drill 0.254)
		(layers "F.Cu" "B.Cu")
		(net "SSD5_ADC_A0")
	)
	(segment
		(start 219.732606 -46.693836)
		(end 219.157804 -46.693836)
		(width 0.13208)
		(layer "F.Cu")
		(net "SSD7_ADC_ALERT_N")
	)
	(segment
		(start 219.157804 -46.693836)
		(end 218.34602 -46.693836)
		(width 0.13208)
		(layer "F.Cu")
		(net "SSD7_ADC_ALERT_N")
	)
	(segment
		(start 219.94368 -46.90491)
		(end 219.732606 -46.693836)
		(width 0.13208)
		(layer "F.Cu")
		(net "SSD7_ADC_ALERT_N")
	)
	(via
		(at 219.157804 -46.693836)
		(size 0.508)
		(drill 0.254)
		(layers "F.Cu" "B.Cu")
		(net "SSD7_ADC_ALERT_N")
	)
	(segment
		(start 214.54745 -45.114464)
		(end 215.126824 -45.693838)
		(width 0.254)
		(layer "F.Cu")
		(net "P12V_SSD7_VIN_N")
	)
	(segment
		(start 215.126824 -45.693838)
		(end 215.545924 -45.693838)
		(width 0.254)
		(layer "F.Cu")
		(net "P12V_SSD7_VIN_N")
	)
	(segment
		(start 212.822536 -44.741592)
		(end 213.838536 -44.741592)
		(width 0.254)
		(layer "F.Cu")
		(net "P12V_SSD7_VIN_N")
	)
	(segment
		(start 214.174578 -44.741592)
		(end 214.54745 -45.114464)
		(width 0.254)
		(layer "F.Cu")
		(net "P12V_SSD7_VIN_N")
	)
	(segment
		(start 213.838536 -44.741592)
		(end 214.174578 -44.741592)
		(width 0.254)
		(layer "F.Cu")
		(net "P12V_SSD7_VIN_N")
	)
	(via
		(at 214.54745 -45.114464)
		(size 0.508)
		(drill 0.254)
		(layers "F.Cu" "B.Cu")
		(net "P12V_SSD7_VIN_N")
	)
	(segment
		(start 214.625428 -42.849038)
		(end 215.373966 -42.849038)
		(width 0.381)
		(layer "F.Cu")
		(net "P12V_SSD7_R")
	)
	(segment
		(start 196.575172 -63.086234)
		(end 195.86956 -63.086234)
		(width 0.4572)
		(layer "F.Cu")
		(net "P12V_SSD7_R")
	)
	(via
		(at 215.373966 -42.849038)
		(size 0.508)
		(drill 0.254)
		(layers "F.Cu" "B.Cu")
		(net "P12V_SSD7_R")
	)
	(via
		(at 211.692236 -53.00853)
		(size 0.508)
		(drill 0.254)
		(layers "F.Cu" "B.Cu")
		(net "P12V_SSD7_R")
	)
	(via
		(at 211.106766 -68.586604)
		(size 0.508)
		(drill 0.254)
		(layers "F.Cu" "B.Cu")
		(net "P12V_SSD7_R")
	)
	(via
		(at 212.452966 -67.951604)
		(size 0.508)
		(drill 0.254)
		(layers "F.Cu" "B.Cu")
		(net "P12V_SSD7_R")
	)
	(via
		(at 214.55253 -54.135528)
		(size 0.508)
		(drill 0.254)
		(layers "F.Cu" "B.Cu")
		(net "P12V_SSD7_R")
	)
	(via
		(at 211.692236 -53.77053)
		(size 0.508)
		(drill 0.254)
		(layers "F.Cu" "B.Cu")
		(net "P12V_SSD7_R")
	)
	(via
		(at 213.611968 -53.685186)
		(size 0.508)
		(drill 0.254)
		(layers "F.Cu" "B.Cu")
		(net "P12V_SSD7_R")
	)
	(via
		(at 213.349586 -46.066964)
		(size 0.508)
		(drill 0.254)
		(layers "F.Cu" "B.Cu")
		(net "P12V_SSD7_R")
	)
	(via
		(at 214.55253 -54.770528)
		(size 0.508)
		(drill 0.254)
		(layers "F.Cu" "B.Cu")
		(net "P12V_SSD7_R")
	)
	(via
		(at 211.817966 -67.951604)
		(size 0.508)
		(drill 0.254)
		(layers "F.Cu" "B.Cu")
		(net "P12V_SSD7_R")
	)
	(via
		(at 212.533992 -46.082204)
		(size 0.508)
		(drill 0.254)
		(layers "F.Cu" "B.Cu")
		(net "P12V_SSD7_R")
	)
	(via
		(at 214.059516 -45.976286)
		(size 0.508)
		(drill 0.254)
		(layers "F.Cu" "B.Cu")
		(net "P12V_SSD7_R")
	)
	(via
		(at 195.86956 -63.086234)
		(size 0.508)
		(drill 0.254)
		(layers "F.Cu" "B.Cu")
		(net "P12V_SSD7_R")
	)
	(via
		(at 210.657948 -53.521102)
		(size 0.508)
		(drill 0.254)
		(layers "F.Cu" "B.Cu")
		(net "P12V_SSD7_R")
	)
	(via
		(at 211.106766 -67.951604)
		(size 0.508)
		(drill 0.254)
		(layers "F.Cu" "B.Cu")
		(net "P12V_SSD7_R")
	)
	(via
		(at 210.657948 -52.886102)
		(size 0.508)
		(drill 0.254)
		(layers "F.Cu" "B.Cu")
		(net "P12V_SSD7_R")
	)
	(via
		(at 208.84769 -67.10172)
		(size 0.508)
		(drill 0.254)
		(layers "F.Cu" "B.Cu")
		(net "P12V_SSD7_R")
	)
	(via
		(at 208.002124 -52.826412)
		(size 0.508)
		(drill 0.254)
		(layers "F.Cu" "B.Cu")
		(net "P12V_SSD7_R")
	)
	(via
		(at 209.48269 -67.10172)
		(size 0.508)
		(drill 0.254)
		(layers "F.Cu" "B.Cu")
		(net "P12V_SSD7_R")
	)
	(via
		(at 212.403436 -53.00853)
		(size 0.508)
		(drill 0.254)
		(layers "F.Cu" "B.Cu")
		(net "P12V_SSD7_R")
	)
	(via
		(at 208.002124 -54.731412)
		(size 0.508)
		(drill 0.254)
		(layers "F.Cu" "B.Cu")
		(net "P12V_SSD7_R")
	)
	(via
		(at 210.657948 -54.156102)
		(size 0.508)
		(drill 0.254)
		(layers "F.Cu" "B.Cu")
		(net "P12V_SSD7_R")
	)
	(via
		(at 208.002124 -54.096412)
		(size 0.508)
		(drill 0.254)
		(layers "F.Cu" "B.Cu")
		(net "P12V_SSD7_R")
	)
	(via
		(at 213.251542 -46.739048)
		(size 0.508)
		(drill 0.254)
		(layers "F.Cu" "B.Cu")
		(net "P12V_SSD7_R")
	)
	(via
		(at 212.327236 -53.77053)
		(size 0.508)
		(drill 0.254)
		(layers "F.Cu" "B.Cu")
		(net "P12V_SSD7_R")
	)
	(via
		(at 212.586824 -46.792134)
		(size 0.508)
		(drill 0.254)
		(layers "F.Cu" "B.Cu")
		(net "P12V_SSD7_R")
	)
	(via
		(at 210.657948 -54.791102)
		(size 0.508)
		(drill 0.254)
		(layers "F.Cu" "B.Cu")
		(net "P12V_SSD7_R")
	)
	(via
		(at 211.817966 -68.586604)
		(size 0.508)
		(drill 0.254)
		(layers "F.Cu" "B.Cu")
		(net "P12V_SSD7_R")
	)
	(via
		(at 208.002124 -53.461412)
		(size 0.508)
		(drill 0.254)
		(layers "F.Cu" "B.Cu")
		(net "P12V_SSD7_R")
	)
	(via
		(at 212.452966 -68.586604)
		(size 0.508)
		(drill 0.254)
		(layers "F.Cu" "B.Cu")
		(net "P12V_SSD7_R")
	)
	(via
		(at 213.611968 -54.320186)
		(size 0.508)
		(drill 0.254)
		(layers "F.Cu" "B.Cu")
		(net "P12V_SSD7_R")
	)
	(segment
		(start 140.346176 -45.693838)
		(end 140.346176 -44.712636)
		(width 0.13208)
		(layer "F.Cu")
		(net "SSD4_ADC_A1")
	)
	(segment
		(start 141.201902 -43.85691)
		(end 141.943836 -43.85691)
		(width 0.13208)
		(layer "F.Cu")
		(net "SSD4_ADC_A1")
	)
	(segment
		(start 141.943836 -42.84091)
		(end 141.943836 -43.85691)
		(width 0.13208)
		(layer "F.Cu")
		(net "SSD4_ADC_A1")
	)
	(segment
		(start 140.346176 -44.712636)
		(end 141.201902 -43.85691)
		(width 0.13208)
		(layer "F.Cu")
		(net "SSD4_ADC_A1")
	)
	(via
		(at 141.201902 -43.85691)
		(size 0.508)
		(drill 0.254)
		(layers "F.Cu" "B.Cu")
		(net "SSD4_ADC_A1")
	)
	(segment
		(start 141.1859 -45.771816)
		(end 140.763752 -46.193964)
		(width 0.13208)
		(layer "F.Cu")
		(net "SSD4_ADC_A0")
	)
	(segment
		(start 141.379194 -45.88891)
		(end 141.1859 -45.695616)
		(width 0.13208)
		(layer "F.Cu")
		(net "SSD4_ADC_A0")
	)
	(segment
		(start 141.1859 -45.35424)
		(end 141.1859 -45.695616)
		(width 0.13208)
		(layer "F.Cu")
		(net "SSD4_ADC_A0")
	)
	(segment
		(start 140.763752 -46.193964)
		(end 140.346176 -46.193964)
		(width 0.13208)
		(layer "F.Cu")
		(net "SSD4_ADC_A0")
	)
	(segment
		(start 141.943836 -45.88891)
		(end 141.379194 -45.88891)
		(width 0.13208)
		(layer "F.Cu")
		(net "SSD4_ADC_A0")
	)
	(segment
		(start 141.1859 -45.695616)
		(end 141.1859 -45.771816)
		(width 0.13208)
		(layer "F.Cu")
		(net "SSD4_ADC_A0")
	)
	(segment
		(start 141.943836 -44.87291)
		(end 141.943836 -45.88891)
		(width 0.13208)
		(layer "F.Cu")
		(net "SSD4_ADC_A0")
	)
	(via
		(at 141.1859 -45.35424)
		(size 0.508)
		(drill 0.254)
		(layers "F.Cu" "B.Cu")
		(net "SSD4_ADC_A0")
	)
	(segment
		(start 360.207306 -238.298228)
		(end 359.867708 -237.95863)
		(width 0.13208)
		(layer "F.Cu")
		(net "PWRGD_P5V_AUX_R")
	)
	(segment
		(start 360.207306 -238.580168)
		(end 360.207306 -238.298228)
		(width 0.13208)
		(layer "F.Cu")
		(net "PWRGD_P5V_AUX_R")
	)
	(segment
		(start 115.943126 -162.128708)
		(end 115.440714 -162.63112)
		(width 0.13208)
		(layer "F.Cu")
		(net "PWRGD_P5V_AUX_R")
	)
	(segment
		(start 115.440714 -162.63112)
		(end 113.968784 -162.63112)
		(width 0.13208)
		(layer "F.Cu")
		(net "PWRGD_P5V_AUX_R")
	)
	(segment
		(start 113.8174 -162.782504)
		(end 113.432082 -162.782504)
		(width 0.13208)
		(layer "F.Cu")
		(net "PWRGD_P5V_AUX_R")
	)
	(segment
		(start 113.968784 -162.63112)
		(end 113.8174 -162.782504)
		(width 0.13208)
		(layer "F.Cu")
		(net "PWRGD_P5V_AUX_R")
	)
	(via
		(at 107.948222 -184.985914)
		(size 0.508)
		(drill 0.254)
		(layers "F.Cu" "B.Cu")
		(net "PWRGD_P5V_AUX_R")
	)
	(via
		(at 359.867708 -237.95863)
		(size 0.508)
		(drill 0.254)
		(layers "F.Cu" "B.Cu")
		(net "PWRGD_P5V_AUX_R")
	)
	(via
		(at 322.650104 -227.853748)
		(size 0.508)
		(drill 0.254)
		(layers "F.Cu" "B.Cu")
		(net "PWRGD_P5V_AUX_R")
	)
	(via
		(at 115.943126 -162.128708)
		(size 0.508)
		(drill 0.254)
		(layers "F.Cu" "B.Cu")
		(net "PWRGD_P5V_AUX_R")
	)
	(via
		(at 28.446222 -180.365908)
		(size 0.508)
		(drill 0.254)
		(layers "F.Cu" "B.Cu")
		(net "PWRGD_P5V_AUX_R")
	)
	(via
		(at 119.989346 -213.249764)
		(size 0.508)
		(drill 0.254)
		(layers "F.Cu" "B.Cu")
		(net "PWRGD_P5V_AUX_R")
	)
	(segment
		(start 343.241122 -238.596678)
		(end 343.986866 -237.850934)
		(width 0.13208)
		(layer "B.Cu")
		(net "PWRGD_P5V_AUX_R")
	)
	(segment
		(start 326.254618 -235.081826)
		(end 326.624696 -234.711748)
		(width 0.13208)
		(layer "B.Cu")
		(net "PWRGD_P5V_AUX_R")
	)
	(segment
		(start 358.801924 -237.826296)
		(end 359.735374 -237.826296)
		(width 0.13208)
		(layer "B.Cu")
		(net "PWRGD_P5V_AUX_R")
	)
	(segment
		(start 359.735374 -237.826296)
		(end 359.867708 -237.95863)
		(width 0.13208)
		(layer "B.Cu")
		(net "PWRGD_P5V_AUX_R")
	)
	(segment
		(start 28.446222 -180.365908)
		(end 28.446222 -178.71567)
		(width 0.13208)
		(layer "B.Cu")
		(net "PWRGD_P5V_AUX_R")
	)
	(segment
		(start 28.446222 -178.71567)
		(end 22.907752 -173.1772)
		(width 0.13208)
		(layer "B.Cu")
		(net "PWRGD_P5V_AUX_R")
	)
	(segment
		(start 333.70647 -237.218728)
		(end 334.785462 -238.29772)
		(width 0.13208)
		(layer "B.Cu")
		(net "PWRGD_P5V_AUX_R")
	)
	(segment
		(start 322.829682 -235.081826)
		(end 326.254618 -235.081826)
		(width 0.13208)
		(layer "B.Cu")
		(net "PWRGD_P5V_AUX_R")
	)
	(segment
		(start 331.40523 -237.218728)
		(end 333.70647 -237.218728)
		(width 0.13208)
		(layer "B.Cu")
		(net "PWRGD_P5V_AUX_R")
	)
	(segment
		(start 336.77352 -238.29772)
		(end 337.072478 -238.596678)
		(width 0.13208)
		(layer "B.Cu")
		(net "PWRGD_P5V_AUX_R")
	)
	(segment
		(start 326.624696 -234.711748)
		(end 329.674474 -234.711748)
		(width 0.13208)
		(layer "B.Cu")
		(net "PWRGD_P5V_AUX_R")
	)
	(segment
		(start 358.777286 -237.850934)
		(end 358.801924 -237.826296)
		(width 0.13208)
		(layer "B.Cu")
		(net "PWRGD_P5V_AUX_R")
	)
	(segment
		(start 343.986866 -237.850934)
		(end 358.777286 -237.850934)
		(width 0.13208)
		(layer "B.Cu")
		(net "PWRGD_P5V_AUX_R")
	)
	(segment
		(start 330.081128 -235.894626)
		(end 331.40523 -237.218728)
		(width 0.13208)
		(layer "B.Cu")
		(net "PWRGD_P5V_AUX_R")
	)
	(segment
		(start 322.650104 -227.853748)
		(end 321.801744 -227.853748)
		(width 0.13208)
		(layer "B.Cu")
		(net "PWRGD_P5V_AUX_R")
	)
	(segment
		(start 321.801744 -227.853748)
		(end 321.295268 -228.360224)
		(width 0.13208)
		(layer "B.Cu")
		(net "PWRGD_P5V_AUX_R")
	)
	(segment
		(start 329.674474 -234.711748)
		(end 330.081128 -235.118402)
		(width 0.13208)
		(layer "B.Cu")
		(net "PWRGD_P5V_AUX_R")
	)
	(segment
		(start 321.295268 -233.547412)
		(end 322.829682 -235.081826)
		(width 0.13208)
		(layer "B.Cu")
		(net "PWRGD_P5V_AUX_R")
	)
	(segment
		(start 334.785462 -238.29772)
		(end 336.77352 -238.29772)
		(width 0.13208)
		(layer "B.Cu")
		(net "PWRGD_P5V_AUX_R")
	)
	(segment
		(start 337.072478 -238.596678)
		(end 343.241122 -238.596678)
		(width 0.13208)
		(layer "B.Cu")
		(net "PWRGD_P5V_AUX_R")
	)
	(segment
		(start 321.295268 -228.360224)
		(end 321.295268 -233.547412)
		(width 0.13208)
		(layer "B.Cu")
		(net "PWRGD_P5V_AUX_R")
	)
	(segment
		(start 330.081128 -235.118402)
		(end 330.081128 -235.894626)
		(width 0.13208)
		(layer "B.Cu")
		(net "PWRGD_P5V_AUX_R")
	)
	(segment
		(start 111.376206 -188.661802)
		(end 107.948222 -185.233818)
		(width 0.15494)
		(layer "In7.Cu")
		(net "PWRGD_P5V_AUX_R")
	)
	(segment
		(start 117.361208 -206.704438)
		(end 111.376206 -200.719436)
		(width 0.15494)
		(layer "In7.Cu")
		(net "PWRGD_P5V_AUX_R")
	)
	(segment
		(start 117.147086 -184.985914)
		(end 120.03913 -182.09387)
		(width 0.15494)
		(layer "In7.Cu")
		(net "PWRGD_P5V_AUX_R")
	)
	(segment
		(start 115.943126 -164.711126)
		(end 115.943126 -162.128708)
		(width 0.15494)
		(layer "In7.Cu")
		(net "PWRGD_P5V_AUX_R")
	)
	(segment
		(start 117.361208 -210.621626)
		(end 117.361208 -206.704438)
		(width 0.15494)
		(layer "In7.Cu")
		(net "PWRGD_P5V_AUX_R")
	)
	(segment
		(start 120.03913 -168.80713)
		(end 115.943126 -164.711126)
		(width 0.15494)
		(layer "In7.Cu")
		(net "PWRGD_P5V_AUX_R")
	)
	(segment
		(start 119.989346 -213.249764)
		(end 117.361208 -210.621626)
		(width 0.15494)
		(layer "In7.Cu")
		(net "PWRGD_P5V_AUX_R")
	)
	(segment
		(start 107.948222 -184.985914)
		(end 117.147086 -184.985914)
		(width 0.15494)
		(layer "In7.Cu")
		(net "PWRGD_P5V_AUX_R")
	)
	(segment
		(start 111.376206 -200.719436)
		(end 111.376206 -188.661802)
		(width 0.15494)
		(layer "In7.Cu")
		(net "PWRGD_P5V_AUX_R")
	)
	(segment
		(start 107.948222 -185.233818)
		(end 107.948222 -184.985914)
		(width 0.15494)
		(layer "In7.Cu")
		(net "PWRGD_P5V_AUX_R")
	)
	(segment
		(start 120.03913 -182.09387)
		(end 120.03913 -168.80713)
		(width 0.15494)
		(layer "In7.Cu")
		(net "PWRGD_P5V_AUX_R")
	)
	(segment
		(start 107.436158 -184.47385)
		(end 32.554164 -184.47385)
		(width 0.15494)
		(layer "In13.Cu")
		(net "PWRGD_P5V_AUX_R")
	)
	(segment
		(start 107.948222 -184.985914)
		(end 107.436158 -184.47385)
		(width 0.15494)
		(layer "In13.Cu")
		(net "PWRGD_P5V_AUX_R")
	)
	(segment
		(start 32.554164 -184.47385)
		(end 28.446222 -180.365908)
		(width 0.15494)
		(layer "In13.Cu")
		(net "PWRGD_P5V_AUX_R")
	)
	(segment
		(start 322.650104 -227.853748)
		(end 307.024024 -227.853748)
		(width 0.15494)
		(layer "In15.Cu")
		(net "PWRGD_P5V_AUX_R")
	)
	(segment
		(start 129.110232 -220.620336)
		(end 128.72085 -221.009718)
		(width 0.15494)
		(layer "In15.Cu")
		(net "PWRGD_P5V_AUX_R")
	)
	(segment
		(start 221.0435 -229.26802)
		(end 214.921084 -229.26802)
		(width 0.15494)
		(layer "In15.Cu")
		(net "PWRGD_P5V_AUX_R")
	)
	(segment
		(start 260.521196 -221.30512)
		(end 258.077462 -221.30512)
		(width 0.15494)
		(layer "In15.Cu")
		(net "PWRGD_P5V_AUX_R")
	)
	(segment
		(start 273.042888 -228.841808)
		(end 268.86916 -224.671128)
		(width 0.15494)
		(layer "In15.Cu")
		(net "PWRGD_P5V_AUX_R")
	)
	(segment
		(start 235.51388 -228.537516)
		(end 234.91444 -227.938076)
		(width 0.15494)
		(layer "In15.Cu")
		(net "PWRGD_P5V_AUX_R")
	)
	(segment
		(start 193.98869 -229.08514)
		(end 189.178184 -224.274634)
		(width 0.15494)
		(layer "In15.Cu")
		(net "PWRGD_P5V_AUX_R")
	)
	(segment
		(start 128.72085 -221.009718)
		(end 126.122938 -221.009718)
		(width 0.15494)
		(layer "In15.Cu")
		(net "PWRGD_P5V_AUX_R")
	)
	(segment
		(start 214.921084 -229.26802)
		(end 214.738204 -229.08514)
		(width 0.15494)
		(layer "In15.Cu")
		(net "PWRGD_P5V_AUX_R")
	)
	(segment
		(start 256.853182 -220.08084)
		(end 254.087884 -220.08084)
		(width 0.15494)
		(layer "In15.Cu")
		(net "PWRGD_P5V_AUX_R")
	)
	(segment
		(start 237.117128 -228.537516)
		(end 235.51388 -228.537516)
		(width 0.15494)
		(layer "In15.Cu")
		(net "PWRGD_P5V_AUX_R")
	)
	(segment
		(start 266.780264 -223.881442)
		(end 263.097518 -223.881442)
		(width 0.15494)
		(layer "In15.Cu")
		(net "PWRGD_P5V_AUX_R")
	)
	(segment
		(start 221.728792 -228.582728)
		(end 221.0435 -229.26802)
		(width 0.15494)
		(layer "In15.Cu")
		(net "PWRGD_P5V_AUX_R")
	)
	(segment
		(start 126.122938 -221.009718)
		(end 119.989346 -214.876126)
		(width 0.15494)
		(layer "In15.Cu")
		(net "PWRGD_P5V_AUX_R")
	)
	(segment
		(start 268.86916 -224.671128)
		(end 267.56995 -224.671128)
		(width 0.15494)
		(layer "In15.Cu")
		(net "PWRGD_P5V_AUX_R")
	)
	(segment
		(start 119.989346 -214.876126)
		(end 119.989346 -213.249764)
		(width 0.15494)
		(layer "In15.Cu")
		(net "PWRGD_P5V_AUX_R")
	)
	(segment
		(start 252.135386 -222.033338)
		(end 250.687332 -222.033338)
		(width 0.15494)
		(layer "In15.Cu")
		(net "PWRGD_P5V_AUX_R")
	)
	(segment
		(start 141.65707 -220.620336)
		(end 129.110232 -220.620336)
		(width 0.15494)
		(layer "In15.Cu")
		(net "PWRGD_P5V_AUX_R")
	)
	(segment
		(start 189.178184 -224.274634)
		(end 160.75914 -224.274634)
		(width 0.15494)
		(layer "In15.Cu")
		(net "PWRGD_P5V_AUX_R")
	)
	(segment
		(start 234.91444 -227.938076)
		(end 229.664514 -227.938076)
		(width 0.15494)
		(layer "In15.Cu")
		(net "PWRGD_P5V_AUX_R")
	)
	(segment
		(start 229.019862 -228.582728)
		(end 221.728792 -228.582728)
		(width 0.15494)
		(layer "In15.Cu")
		(net "PWRGD_P5V_AUX_R")
	)
	(segment
		(start 229.664514 -227.938076)
		(end 229.019862 -228.582728)
		(width 0.15494)
		(layer "In15.Cu")
		(net "PWRGD_P5V_AUX_R")
	)
	(segment
		(start 263.097518 -223.881442)
		(end 260.521196 -221.30512)
		(width 0.15494)
		(layer "In15.Cu")
		(net "PWRGD_P5V_AUX_R")
	)
	(segment
		(start 142.189962 -220.087444)
		(end 141.65707 -220.620336)
		(width 0.15494)
		(layer "In15.Cu")
		(net "PWRGD_P5V_AUX_R")
	)
	(segment
		(start 305.636422 -226.466146)
		(end 289.124898 -226.466146)
		(width 0.15494)
		(layer "In15.Cu")
		(net "PWRGD_P5V_AUX_R")
	)
	(segment
		(start 307.024024 -227.853748)
		(end 305.636422 -226.466146)
		(width 0.15494)
		(layer "In15.Cu")
		(net "PWRGD_P5V_AUX_R")
	)
	(segment
		(start 247.008142 -222.169736)
		(end 241.563398 -227.61448)
		(width 0.15494)
		(layer "In15.Cu")
		(net "PWRGD_P5V_AUX_R")
	)
	(segment
		(start 214.738204 -229.08514)
		(end 193.98869 -229.08514)
		(width 0.15494)
		(layer "In15.Cu")
		(net "PWRGD_P5V_AUX_R")
	)
	(segment
		(start 267.56995 -224.671128)
		(end 266.780264 -223.881442)
		(width 0.15494)
		(layer "In15.Cu")
		(net "PWRGD_P5V_AUX_R")
	)
	(segment
		(start 258.077462 -221.30512)
		(end 256.853182 -220.08084)
		(width 0.15494)
		(layer "In15.Cu")
		(net "PWRGD_P5V_AUX_R")
	)
	(segment
		(start 254.087884 -220.08084)
		(end 252.135386 -222.033338)
		(width 0.15494)
		(layer "In15.Cu")
		(net "PWRGD_P5V_AUX_R")
	)
	(segment
		(start 286.749236 -228.841808)
		(end 273.042888 -228.841808)
		(width 0.15494)
		(layer "In15.Cu")
		(net "PWRGD_P5V_AUX_R")
	)
	(segment
		(start 289.124898 -226.466146)
		(end 286.749236 -228.841808)
		(width 0.15494)
		(layer "In15.Cu")
		(net "PWRGD_P5V_AUX_R")
	)
	(segment
		(start 250.550934 -222.169736)
		(end 247.008142 -222.169736)
		(width 0.15494)
		(layer "In15.Cu")
		(net "PWRGD_P5V_AUX_R")
	)
	(segment
		(start 238.040164 -227.61448)
		(end 237.117128 -228.537516)
		(width 0.15494)
		(layer "In15.Cu")
		(net "PWRGD_P5V_AUX_R")
	)
	(segment
		(start 241.563398 -227.61448)
		(end 238.040164 -227.61448)
		(width 0.15494)
		(layer "In15.Cu")
		(net "PWRGD_P5V_AUX_R")
	)
	(segment
		(start 156.57195 -220.087444)
		(end 142.189962 -220.087444)
		(width 0.15494)
		(layer "In15.Cu")
		(net "PWRGD_P5V_AUX_R")
	)
	(segment
		(start 160.75914 -224.274634)
		(end 156.57195 -220.087444)
		(width 0.15494)
		(layer "In15.Cu")
		(net "PWRGD_P5V_AUX_R")
	)
	(segment
		(start 250.687332 -222.033338)
		(end 250.550934 -222.169736)
		(width 0.15494)
		(layer "In15.Cu")
		(net "PWRGD_P5V_AUX_R")
	)
	(segment
		(start 170.575224 -63.086234)
		(end 169.897044 -63.086234)
		(width 0.4572)
		(layer "F.Cu")
		(net "P12V_SSD6_R")
	)
	(segment
		(start 188.62548 -42.849038)
		(end 189.374018 -42.849038)
		(width 0.381)
		(layer "F.Cu")
		(net "P12V_SSD6_R")
	)
	(via
		(at 187.251594 -46.739048)
		(size 0.508)
		(drill 0.254)
		(layers "F.Cu" "B.Cu")
		(net "P12V_SSD6_R")
	)
	(via
		(at 183.482742 -67.10172)
		(size 0.508)
		(drill 0.254)
		(layers "F.Cu" "B.Cu")
		(net "P12V_SSD6_R")
	)
	(via
		(at 186.403488 -53.00853)
		(size 0.508)
		(drill 0.254)
		(layers "F.Cu" "B.Cu")
		(net "P12V_SSD6_R")
	)
	(via
		(at 186.534044 -46.082204)
		(size 0.508)
		(drill 0.254)
		(layers "F.Cu" "B.Cu")
		(net "P12V_SSD6_R")
	)
	(via
		(at 182.002176 -54.731412)
		(size 0.508)
		(drill 0.254)
		(layers "F.Cu" "B.Cu")
		(net "P12V_SSD6_R")
	)
	(via
		(at 187.349638 -46.066964)
		(size 0.508)
		(drill 0.254)
		(layers "F.Cu" "B.Cu")
		(net "P12V_SSD6_R")
	)
	(via
		(at 185.106818 -68.586604)
		(size 0.508)
		(drill 0.254)
		(layers "F.Cu" "B.Cu")
		(net "P12V_SSD6_R")
	)
	(via
		(at 185.818018 -68.586604)
		(size 0.508)
		(drill 0.254)
		(layers "F.Cu" "B.Cu")
		(net "P12V_SSD6_R")
	)
	(via
		(at 188.059568 -45.976286)
		(size 0.508)
		(drill 0.254)
		(layers "F.Cu" "B.Cu")
		(net "P12V_SSD6_R")
	)
	(via
		(at 188.552582 -54.770528)
		(size 0.508)
		(drill 0.254)
		(layers "F.Cu" "B.Cu")
		(net "P12V_SSD6_R")
	)
	(via
		(at 182.002176 -54.096412)
		(size 0.508)
		(drill 0.254)
		(layers "F.Cu" "B.Cu")
		(net "P12V_SSD6_R")
	)
	(via
		(at 187.61202 -54.320186)
		(size 0.508)
		(drill 0.254)
		(layers "F.Cu" "B.Cu")
		(net "P12V_SSD6_R")
	)
	(via
		(at 184.658 -53.521102)
		(size 0.508)
		(drill 0.254)
		(layers "F.Cu" "B.Cu")
		(net "P12V_SSD6_R")
	)
	(via
		(at 184.658 -54.156102)
		(size 0.508)
		(drill 0.254)
		(layers "F.Cu" "B.Cu")
		(net "P12V_SSD6_R")
	)
	(via
		(at 188.552582 -54.135528)
		(size 0.508)
		(drill 0.254)
		(layers "F.Cu" "B.Cu")
		(net "P12V_SSD6_R")
	)
	(via
		(at 186.586876 -46.792134)
		(size 0.508)
		(drill 0.254)
		(layers "F.Cu" "B.Cu")
		(net "P12V_SSD6_R")
	)
	(via
		(at 185.692288 -53.00853)
		(size 0.508)
		(drill 0.254)
		(layers "F.Cu" "B.Cu")
		(net "P12V_SSD6_R")
	)
	(via
		(at 186.453018 -67.951604)
		(size 0.508)
		(drill 0.254)
		(layers "F.Cu" "B.Cu")
		(net "P12V_SSD6_R")
	)
	(via
		(at 185.692288 -53.77053)
		(size 0.508)
		(drill 0.254)
		(layers "F.Cu" "B.Cu")
		(net "P12V_SSD6_R")
	)
	(via
		(at 185.106818 -67.951604)
		(size 0.508)
		(drill 0.254)
		(layers "F.Cu" "B.Cu")
		(net "P12V_SSD6_R")
	)
	(via
		(at 187.61202 -53.685186)
		(size 0.508)
		(drill 0.254)
		(layers "F.Cu" "B.Cu")
		(net "P12V_SSD6_R")
	)
	(via
		(at 184.658 -52.886102)
		(size 0.508)
		(drill 0.254)
		(layers "F.Cu" "B.Cu")
		(net "P12V_SSD6_R")
	)
	(via
		(at 185.818018 -67.951604)
		(size 0.508)
		(drill 0.254)
		(layers "F.Cu" "B.Cu")
		(net "P12V_SSD6_R")
	)
	(via
		(at 189.374018 -42.849038)
		(size 0.508)
		(drill 0.254)
		(layers "F.Cu" "B.Cu")
		(net "P12V_SSD6_R")
	)
	(via
		(at 182.002176 -52.826412)
		(size 0.508)
		(drill 0.254)
		(layers "F.Cu" "B.Cu")
		(net "P12V_SSD6_R")
	)
	(via
		(at 186.453018 -68.586604)
		(size 0.508)
		(drill 0.254)
		(layers "F.Cu" "B.Cu")
		(net "P12V_SSD6_R")
	)
	(via
		(at 182.002176 -53.461412)
		(size 0.508)
		(drill 0.254)
		(layers "F.Cu" "B.Cu")
		(net "P12V_SSD6_R")
	)
	(via
		(at 169.897044 -63.086234)
		(size 0.508)
		(drill 0.254)
		(layers "F.Cu" "B.Cu")
		(net "P12V_SSD6_R")
	)
	(via
		(at 182.847742 -67.10172)
		(size 0.508)
		(drill 0.254)
		(layers "F.Cu" "B.Cu")
		(net "P12V_SSD6_R")
	)
	(via
		(at 186.327288 -53.77053)
		(size 0.508)
		(drill 0.254)
		(layers "F.Cu" "B.Cu")
		(net "P12V_SSD6_R")
	)
	(via
		(at 184.658 -54.791102)
		(size 0.508)
		(drill 0.254)
		(layers "F.Cu" "B.Cu")
		(net "P12V_SSD6_R")
	)
	(segment
		(start 193.943732 -46.90491)
		(end 193.732658 -46.693836)
		(width 0.13208)
		(layer "F.Cu")
		(net "SSD6_ADC_ALERT_N")
	)
	(segment
		(start 193.157856 -46.693836)
		(end 192.346072 -46.693836)
		(width 0.13208)
		(layer "F.Cu")
		(net "SSD6_ADC_ALERT_N")
	)
	(segment
		(start 193.732658 -46.693836)
		(end 193.157856 -46.693836)
		(width 0.13208)
		(layer "F.Cu")
		(net "SSD6_ADC_ALERT_N")
	)
	(via
		(at 193.157856 -46.693836)
		(size 0.508)
		(drill 0.254)
		(layers "F.Cu" "B.Cu")
		(net "SSD6_ADC_ALERT_N")
	)
	(segment
		(start 192.346072 -44.712636)
		(end 193.201798 -43.85691)
		(width 0.13208)
		(layer "F.Cu")
		(net "SSD6_ADC_A1")
	)
	(segment
		(start 193.201798 -43.85691)
		(end 193.943732 -43.85691)
		(width 0.13208)
		(layer "F.Cu")
		(net "SSD6_ADC_A1")
	)
	(segment
		(start 193.943732 -42.84091)
		(end 193.943732 -43.85691)
		(width 0.13208)
		(layer "F.Cu")
		(net "SSD6_ADC_A1")
	)
	(segment
		(start 192.346072 -45.693838)
		(end 192.346072 -44.712636)
		(width 0.13208)
		(layer "F.Cu")
		(net "SSD6_ADC_A1")
	)
	(via
		(at 193.201798 -43.85691)
		(size 0.508)
		(drill 0.254)
		(layers "F.Cu" "B.Cu")
		(net "SSD6_ADC_A1")
	)
	(segment
		(start 218.883484 -49.644046)
		(end 218.883484 -49.94148)
		(width 0.13208)
		(layer "F.Cu")
		(net "SMB_SSD7_ADC_SCL")
	)
	(segment
		(start 218.894914 -49.95291)
		(end 218.883484 -49.94148)
		(width 0.13208)
		(layer "F.Cu")
		(net "SMB_SSD7_ADC_SCL")
	)
	(segment
		(start 217.696034 -47.843948)
		(end 217.696034 -48.89246)
		(width 0.13208)
		(layer "F.Cu")
		(net "SMB_SSD7_ADC_SCL")
	)
	(segment
		(start 218.671902 -49.432464)
		(end 218.883484 -49.644046)
		(width 0.13208)
		(layer "F.Cu")
		(net "SMB_SSD7_ADC_SCL")
	)
	(segment
		(start 219.94368 -49.95291)
		(end 218.894914 -49.95291)
		(width 0.13208)
		(layer "F.Cu")
		(net "SMB_SSD7_ADC_SCL")
	)
	(segment
		(start 217.696034 -48.89246)
		(end 218.236038 -49.432464)
		(width 0.13208)
		(layer "F.Cu")
		(net "SMB_SSD7_ADC_SCL")
	)
	(segment
		(start 218.236038 -49.432464)
		(end 218.671902 -49.432464)
		(width 0.13208)
		(layer "F.Cu")
		(net "SMB_SSD7_ADC_SCL")
	)
	(via
		(at 217.696034 -48.89246)
		(size 0.508)
		(drill 0.254)
		(layers "F.Cu" "B.Cu")
		(net "SMB_SSD7_ADC_SCL")
	)
	(segment
		(start 167.273478 -48.93691)
		(end 167.035988 -48.69942)
		(width 0.13208)
		(layer "F.Cu")
		(net "SMB_SSD5_ADC_SDA")
	)
	(segment
		(start 166.576502 -48.30699)
		(end 166.346124 -48.076612)
		(width 0.13208)
		(layer "F.Cu")
		(net "SMB_SSD5_ADC_SDA")
	)
	(segment
		(start 167.035988 -48.69942)
		(end 167.035988 -48.30699)
		(width 0.13208)
		(layer "F.Cu")
		(net "SMB_SSD5_ADC_SDA")
	)
	(segment
		(start 166.346124 -48.076612)
		(end 166.346124 -47.193962)
		(width 0.13208)
		(layer "F.Cu")
		(net "SMB_SSD5_ADC_SDA")
	)
	(segment
		(start 167.035988 -48.30699)
		(end 166.576502 -48.30699)
		(width 0.13208)
		(layer "F.Cu")
		(net "SMB_SSD5_ADC_SDA")
	)
	(segment
		(start 167.943784 -48.93691)
		(end 167.273478 -48.93691)
		(width 0.13208)
		(layer "F.Cu")
		(net "SMB_SSD5_ADC_SDA")
	)
	(via
		(at 167.035988 -48.30699)
		(size 0.508)
		(drill 0.254)
		(layers "F.Cu" "B.Cu")
		(net "SMB_SSD5_ADC_SDA")
	)
	(segment
		(start 161.825432 -43.928284)
		(end 161.825432 -42.849038)
		(width 0.254)
		(layer "F.Cu")
		(net "P12V_SSD5_VIN_P")
	)
	(segment
		(start 162.695128 -43.73626)
		(end 162.489896 -43.941492)
		(width 0.254)
		(layer "F.Cu")
		(net "P12V_SSD5_VIN_P")
	)
	(segment
		(start 162.489896 -43.941492)
		(end 161.83864 -43.941492)
		(width 0.254)
		(layer "F.Cu")
		(net "P12V_SSD5_VIN_P")
	)
	(segment
		(start 161.83864 -43.941492)
		(end 161.825432 -43.928284)
		(width 0.254)
		(layer "F.Cu")
		(net "P12V_SSD5_VIN_P")
	)
	(segment
		(start 164.196014 -45.043852)
		(end 164.196014 -44.53509)
		(width 0.254)
		(layer "F.Cu")
		(net "P12V_SSD5_VIN_P")
	)
	(segment
		(start 163.397184 -43.73626)
		(end 162.695128 -43.73626)
		(width 0.254)
		(layer "F.Cu")
		(net "P12V_SSD5_VIN_P")
	)
	(segment
		(start 164.196014 -44.53509)
		(end 163.397184 -43.73626)
		(width 0.254)
		(layer "F.Cu")
		(net "P12V_SSD5_VIN_P")
	)
	(via
		(at 162.695128 -43.73626)
		(size 0.508)
		(drill 0.254)
		(layers "F.Cu" "B.Cu")
		(net "P12V_SSD5_VIN_P")
	)
	(segment
		(start 193.943732 -49.95291)
		(end 193.943732 -48.93691)
		(width 0.13208)
		(layer "F.Cu")
		(net "SMB_SSD6_ADC_SDA")
	)
	(segment
		(start 192.57645 -48.30699)
		(end 193.035936 -48.30699)
		(width 0.13208)
		(layer "F.Cu")
		(net "SMB_SSD6_ADC_SDA")
	)
	(segment
		(start 192.346072 -48.076612)
		(end 192.57645 -48.30699)
		(width 0.13208)
		(layer "F.Cu")
		(net "SMB_SSD6_ADC_SDA")
	)
	(segment
		(start 193.035936 -48.69942)
		(end 193.273426 -48.93691)
		(width 0.13208)
		(layer "F.Cu")
		(net "SMB_SSD6_ADC_SDA")
	)
	(segment
		(start 193.035936 -48.30699)
		(end 193.035936 -48.69942)
		(width 0.13208)
		(layer "F.Cu")
		(net "SMB_SSD6_ADC_SDA")
	)
	(segment
		(start 193.273426 -48.93691)
		(end 193.943732 -48.93691)
		(width 0.13208)
		(layer "F.Cu")
		(net "SMB_SSD6_ADC_SDA")
	)
	(segment
		(start 192.346072 -47.193962)
		(end 192.346072 -48.076612)
		(width 0.13208)
		(layer "F.Cu")
		(net "SMB_SSD6_ADC_SDA")
	)
	(via
		(at 193.035936 -48.30699)
		(size 0.508)
		(drill 0.254)
		(layers "F.Cu" "B.Cu")
		(net "SMB_SSD6_ADC_SDA")
	)
	(segment
		(start 118.575328 -63.086234)
		(end 117.869716 -63.086234)
		(width 0.4572)
		(layer "F.Cu")
		(net "P12V_SSD4_R")
	)
	(segment
		(start 136.625584 -42.849038)
		(end 137.374122 -42.849038)
		(width 0.381)
		(layer "F.Cu")
		(net "P12V_SSD4_R")
	)
	(via
		(at 135.349742 -46.066964)
		(size 0.508)
		(drill 0.254)
		(layers "F.Cu" "B.Cu")
		(net "P12V_SSD4_R")
	)
	(via
		(at 135.251698 -46.739048)
		(size 0.508)
		(drill 0.254)
		(layers "F.Cu" "B.Cu")
		(net "P12V_SSD4_R")
	)
	(via
		(at 136.552686 -54.135528)
		(size 0.508)
		(drill 0.254)
		(layers "F.Cu" "B.Cu")
		(net "P12V_SSD4_R")
	)
	(via
		(at 133.106922 -67.951604)
		(size 0.508)
		(drill 0.254)
		(layers "F.Cu" "B.Cu")
		(net "P12V_SSD4_R")
	)
	(via
		(at 134.403592 -53.00853)
		(size 0.508)
		(drill 0.254)
		(layers "F.Cu" "B.Cu")
		(net "P12V_SSD4_R")
	)
	(via
		(at 131.482846 -67.10172)
		(size 0.508)
		(drill 0.254)
		(layers "F.Cu" "B.Cu")
		(net "P12V_SSD4_R")
	)
	(via
		(at 134.453122 -67.951604)
		(size 0.508)
		(drill 0.254)
		(layers "F.Cu" "B.Cu")
		(net "P12V_SSD4_R")
	)
	(via
		(at 132.658104 -53.521102)
		(size 0.508)
		(drill 0.254)
		(layers "F.Cu" "B.Cu")
		(net "P12V_SSD4_R")
	)
	(via
		(at 130.00228 -54.096412)
		(size 0.508)
		(drill 0.254)
		(layers "F.Cu" "B.Cu")
		(net "P12V_SSD4_R")
	)
	(via
		(at 117.869716 -63.086234)
		(size 0.508)
		(drill 0.254)
		(layers "F.Cu" "B.Cu")
		(net "P12V_SSD4_R")
	)
	(via
		(at 130.847846 -67.10172)
		(size 0.508)
		(drill 0.254)
		(layers "F.Cu" "B.Cu")
		(net "P12V_SSD4_R")
	)
	(via
		(at 133.106922 -68.586604)
		(size 0.508)
		(drill 0.254)
		(layers "F.Cu" "B.Cu")
		(net "P12V_SSD4_R")
	)
	(via
		(at 130.00228 -54.731412)
		(size 0.508)
		(drill 0.254)
		(layers "F.Cu" "B.Cu")
		(net "P12V_SSD4_R")
	)
	(via
		(at 132.658104 -54.791102)
		(size 0.508)
		(drill 0.254)
		(layers "F.Cu" "B.Cu")
		(net "P12V_SSD4_R")
	)
	(via
		(at 136.059672 -45.976286)
		(size 0.508)
		(drill 0.254)
		(layers "F.Cu" "B.Cu")
		(net "P12V_SSD4_R")
	)
	(via
		(at 137.374122 -42.849038)
		(size 0.508)
		(drill 0.254)
		(layers "F.Cu" "B.Cu")
		(net "P12V_SSD4_R")
	)
	(via
		(at 134.327392 -53.77053)
		(size 0.508)
		(drill 0.254)
		(layers "F.Cu" "B.Cu")
		(net "P12V_SSD4_R")
	)
	(via
		(at 134.58698 -46.792134)
		(size 0.508)
		(drill 0.254)
		(layers "F.Cu" "B.Cu")
		(net "P12V_SSD4_R")
	)
	(via
		(at 133.692392 -53.00853)
		(size 0.508)
		(drill 0.254)
		(layers "F.Cu" "B.Cu")
		(net "P12V_SSD4_R")
	)
	(via
		(at 133.692392 -53.77053)
		(size 0.508)
		(drill 0.254)
		(layers "F.Cu" "B.Cu")
		(net "P12V_SSD4_R")
	)
	(via
		(at 130.00228 -52.826412)
		(size 0.508)
		(drill 0.254)
		(layers "F.Cu" "B.Cu")
		(net "P12V_SSD4_R")
	)
	(via
		(at 132.658104 -52.886102)
		(size 0.508)
		(drill 0.254)
		(layers "F.Cu" "B.Cu")
		(net "P12V_SSD4_R")
	)
	(via
		(at 135.612124 -53.685186)
		(size 0.508)
		(drill 0.254)
		(layers "F.Cu" "B.Cu")
		(net "P12V_SSD4_R")
	)
	(via
		(at 136.552686 -54.770528)
		(size 0.508)
		(drill 0.254)
		(layers "F.Cu" "B.Cu")
		(net "P12V_SSD4_R")
	)
	(via
		(at 135.612124 -54.320186)
		(size 0.508)
		(drill 0.254)
		(layers "F.Cu" "B.Cu")
		(net "P12V_SSD4_R")
	)
	(via
		(at 130.00228 -53.461412)
		(size 0.508)
		(drill 0.254)
		(layers "F.Cu" "B.Cu")
		(net "P12V_SSD4_R")
	)
	(via
		(at 133.818122 -67.951604)
		(size 0.508)
		(drill 0.254)
		(layers "F.Cu" "B.Cu")
		(net "P12V_SSD4_R")
	)
	(via
		(at 134.534148 -46.082204)
		(size 0.508)
		(drill 0.254)
		(layers "F.Cu" "B.Cu")
		(net "P12V_SSD4_R")
	)
	(via
		(at 134.453122 -68.586604)
		(size 0.508)
		(drill 0.254)
		(layers "F.Cu" "B.Cu")
		(net "P12V_SSD4_R")
	)
	(via
		(at 132.658104 -54.156102)
		(size 0.508)
		(drill 0.254)
		(layers "F.Cu" "B.Cu")
		(net "P12V_SSD4_R")
	)
	(via
		(at 133.818122 -68.586604)
		(size 0.508)
		(drill 0.254)
		(layers "F.Cu" "B.Cu")
		(net "P12V_SSD4_R")
	)
	(segment
		(start 102.245922 -47.193962)
		(end 102.245922 -48.076612)
		(width 0.13208)
		(layer "F.Cu")
		(net "SMB_SSD3_ADC_SDA")
	)
	(segment
		(start 102.4763 -48.30699)
		(end 102.935786 -48.30699)
		(width 0.13208)
		(layer "F.Cu")
		(net "SMB_SSD3_ADC_SDA")
	)
	(segment
		(start 102.935786 -48.69942)
		(end 103.173276 -48.93691)
		(width 0.13208)
		(layer "F.Cu")
		(net "SMB_SSD3_ADC_SDA")
	)
	(segment
		(start 102.245922 -48.076612)
		(end 102.4763 -48.30699)
		(width 0.13208)
		(layer "F.Cu")
		(net "SMB_SSD3_ADC_SDA")
	)
	(segment
		(start 102.935786 -48.30699)
		(end 102.935786 -48.69942)
		(width 0.13208)
		(layer "F.Cu")
		(net "SMB_SSD3_ADC_SDA")
	)
	(segment
		(start 103.173276 -48.93691)
		(end 103.843582 -48.93691)
		(width 0.13208)
		(layer "F.Cu")
		(net "SMB_SSD3_ADC_SDA")
	)
	(via
		(at 102.935786 -48.30699)
		(size 0.508)
		(drill 0.254)
		(layers "F.Cu" "B.Cu")
		(net "SMB_SSD3_ADC_SDA")
	)
	(segment
		(start 76.245974 -47.617126)
		(end 76.245974 -47.193962)
		(width 0.13208)
		(layer "F.Cu")
		(net "SMB_SSD2_ADC_SDA")
	)
	(segment
		(start 76.935838 -48.30699)
		(end 76.245974 -47.617126)
		(width 0.13208)
		(layer "F.Cu")
		(net "SMB_SSD2_ADC_SDA")
	)
	(segment
		(start 76.877164 -49.856644)
		(end 76.9239 -49.856644)
		(width 0.13208)
		(layer "F.Cu")
		(net "SMB_SSD2_ADC_SDA")
	)
	(segment
		(start 77.843634 -48.93691)
		(end 77.173328 -48.93691)
		(width 0.13208)
		(layer "F.Cu")
		(net "SMB_SSD2_ADC_SDA")
	)
	(segment
		(start 76.9239 -49.856644)
		(end 77.843634 -48.93691)
		(width 0.13208)
		(layer "F.Cu")
		(net "SMB_SSD2_ADC_SDA")
	)
	(segment
		(start 76.935838 -48.69942)
		(end 76.935838 -48.30699)
		(width 0.13208)
		(layer "F.Cu")
		(net "SMB_SSD2_ADC_SDA")
	)
	(segment
		(start 77.173328 -48.93691)
		(end 76.935838 -48.69942)
		(width 0.13208)
		(layer "F.Cu")
		(net "SMB_SSD2_ADC_SDA")
	)
	(via
		(at 76.935838 -48.30699)
		(size 0.508)
		(drill 0.254)
		(layers "F.Cu" "B.Cu")
		(net "SMB_SSD2_ADC_SDA")
	)
	(segment
		(start 191.696086 -48.89246)
		(end 192.168018 -49.364392)
		(width 0.13208)
		(layer "F.Cu")
		(net "SMB_SSD6_ADC_SCL")
	)
	(segment
		(start 191.696086 -47.843948)
		(end 191.696086 -48.89246)
		(width 0.13208)
		(layer "F.Cu")
		(net "SMB_SSD6_ADC_SCL")
	)
	(segment
		(start 192.883536 -49.530508)
		(end 192.883536 -49.94148)
		(width 0.13208)
		(layer "F.Cu")
		(net "SMB_SSD6_ADC_SCL")
	)
	(segment
		(start 192.71742 -49.364392)
		(end 192.883536 -49.530508)
		(width 0.13208)
		(layer "F.Cu")
		(net "SMB_SSD6_ADC_SCL")
	)
	(segment
		(start 192.168018 -49.364392)
		(end 192.71742 -49.364392)
		(width 0.13208)
		(layer "F.Cu")
		(net "SMB_SSD6_ADC_SCL")
	)
	(via
		(at 191.696086 -48.89246)
		(size 0.508)
		(drill 0.254)
		(layers "F.Cu" "B.Cu")
		(net "SMB_SSD6_ADC_SCL")
	)
	(segment
		(start 24.246078 -46.693836)
		(end 25.057862 -46.693836)
		(width 0.13208)
		(layer "F.Cu")
		(net "SSD0_ADC_ALERT_N")
	)
	(segment
		(start 25.632664 -46.693836)
		(end 25.843738 -46.90491)
		(width 0.13208)
		(layer "F.Cu")
		(net "SSD0_ADC_ALERT_N")
	)
	(segment
		(start 25.057862 -46.693836)
		(end 25.632664 -46.693836)
		(width 0.13208)
		(layer "F.Cu")
		(net "SSD0_ADC_ALERT_N")
	)
	(via
		(at 25.057862 -46.693836)
		(size 0.508)
		(drill 0.254)
		(layers "F.Cu" "B.Cu")
		(net "SSD0_ADC_ALERT_N")
	)
	(segment
		(start 135.838692 -43.941492)
		(end 135.825484 -43.928284)
		(width 0.254)
		(layer "F.Cu")
		(net "P12V_SSD4_VIN_P")
	)
	(segment
		(start 137.397236 -43.73626)
		(end 136.69518 -43.73626)
		(width 0.254)
		(layer "F.Cu")
		(net "P12V_SSD4_VIN_P")
	)
	(segment
		(start 135.825484 -43.928284)
		(end 135.825484 -42.849038)
		(width 0.254)
		(layer "F.Cu")
		(net "P12V_SSD4_VIN_P")
	)
	(segment
		(start 136.489948 -43.941492)
		(end 135.838692 -43.941492)
		(width 0.254)
		(layer "F.Cu")
		(net "P12V_SSD4_VIN_P")
	)
	(segment
		(start 138.196066 -45.043852)
		(end 138.196066 -44.53509)
		(width 0.254)
		(layer "F.Cu")
		(net "P12V_SSD4_VIN_P")
	)
	(segment
		(start 136.69518 -43.73626)
		(end 136.489948 -43.941492)
		(width 0.254)
		(layer "F.Cu")
		(net "P12V_SSD4_VIN_P")
	)
	(segment
		(start 138.196066 -44.53509)
		(end 137.397236 -43.73626)
		(width 0.254)
		(layer "F.Cu")
		(net "P12V_SSD4_VIN_P")
	)
	(via
		(at 136.69518 -43.73626)
		(size 0.508)
		(drill 0.254)
		(layers "F.Cu" "B.Cu")
		(net "P12V_SSD4_VIN_P")
	)
	(segment
		(start 73.026778 -45.693838)
		(end 72.447404 -45.114464)
		(width 0.254)
		(layer "F.Cu")
		(net "P12V_SSD2_VIN_N")
	)
	(segment
		(start 72.447404 -45.114464)
		(end 72.074532 -44.741592)
		(width 0.254)
		(layer "F.Cu")
		(net "P12V_SSD2_VIN_N")
	)
	(segment
		(start 73.445878 -45.693838)
		(end 73.026778 -45.693838)
		(width 0.254)
		(layer "F.Cu")
		(net "P12V_SSD2_VIN_N")
	)
	(segment
		(start 70.72249 -44.741592)
		(end 71.73849 -44.741592)
		(width 0.254)
		(layer "F.Cu")
		(net "P12V_SSD2_VIN_N")
	)
	(segment
		(start 72.074532 -44.741592)
		(end 71.73849 -44.741592)
		(width 0.254)
		(layer "F.Cu")
		(net "P12V_SSD2_VIN_N")
	)
	(via
		(at 72.447404 -45.114464)
		(size 0.508)
		(drill 0.254)
		(layers "F.Cu" "B.Cu")
		(net "P12V_SSD2_VIN_N")
	)
	(segment
		(start 160.82264 -44.741592)
		(end 161.83864 -44.741592)
		(width 0.254)
		(layer "F.Cu")
		(net "P12V_SSD5_VIN_N")
	)
	(segment
		(start 162.174682 -44.741592)
		(end 162.547554 -45.114464)
		(width 0.254)
		(layer "F.Cu")
		(net "P12V_SSD5_VIN_N")
	)
	(segment
		(start 162.547554 -45.114464)
		(end 163.126928 -45.693838)
		(width 0.254)
		(layer "F.Cu")
		(net "P12V_SSD5_VIN_N")
	)
	(segment
		(start 161.83864 -44.741592)
		(end 162.174682 -44.741592)
		(width 0.254)
		(layer "F.Cu")
		(net "P12V_SSD5_VIN_N")
	)
	(segment
		(start 163.126928 -45.693838)
		(end 163.546028 -45.693838)
		(width 0.254)
		(layer "F.Cu")
		(net "P12V_SSD5_VIN_N")
	)
	(via
		(at 162.547554 -45.114464)
		(size 0.508)
		(drill 0.254)
		(layers "F.Cu" "B.Cu")
		(net "P12V_SSD5_VIN_N")
	)
	(segment
		(start 102.072186 -49.36871)
		(end 102.606094 -49.36871)
		(width 0.13208)
		(layer "F.Cu")
		(net "SMB_SSD3_ADC_SCL")
	)
	(segment
		(start 101.595936 -48.89246)
		(end 102.072186 -49.36871)
		(width 0.13208)
		(layer "F.Cu")
		(net "SMB_SSD3_ADC_SCL")
	)
	(segment
		(start 103.843582 -49.95291)
		(end 102.794816 -49.95291)
		(width 0.13208)
		(layer "F.Cu")
		(net "SMB_SSD3_ADC_SCL")
	)
	(segment
		(start 102.794816 -49.95291)
		(end 102.783386 -49.94148)
		(width 0.13208)
		(layer "F.Cu")
		(net "SMB_SSD3_ADC_SCL")
	)
	(segment
		(start 102.783386 -49.546002)
		(end 102.783386 -49.94148)
		(width 0.13208)
		(layer "F.Cu")
		(net "SMB_SSD3_ADC_SCL")
	)
	(segment
		(start 101.595936 -47.843948)
		(end 101.595936 -48.89246)
		(width 0.13208)
		(layer "F.Cu")
		(net "SMB_SSD3_ADC_SCL")
	)
	(segment
		(start 102.606094 -49.36871)
		(end 102.783386 -49.546002)
		(width 0.13208)
		(layer "F.Cu")
		(net "SMB_SSD3_ADC_SCL")
	)
	(via
		(at 101.595936 -48.89246)
		(size 0.508)
		(drill 0.254)
		(layers "F.Cu" "B.Cu")
		(net "SMB_SSD3_ADC_SCL")
	)
	(segment
		(start 166.346124 -45.693838)
		(end 166.346124 -44.712636)
		(width 0.13208)
		(layer "F.Cu")
		(net "SSD5_ADC_A1")
	)
	(segment
		(start 167.943784 -42.84091)
		(end 167.943784 -43.85691)
		(width 0.13208)
		(layer "F.Cu")
		(net "SSD5_ADC_A1")
	)
	(segment
		(start 167.20185 -43.85691)
		(end 167.943784 -43.85691)
		(width 0.13208)
		(layer "F.Cu")
		(net "SSD5_ADC_A1")
	)
	(segment
		(start 166.346124 -44.712636)
		(end 167.20185 -43.85691)
		(width 0.13208)
		(layer "F.Cu")
		(net "SSD5_ADC_A1")
	)
	(via
		(at 167.20185 -43.85691)
		(size 0.508)
		(drill 0.254)
		(layers "F.Cu" "B.Cu")
		(net "SSD5_ADC_A1")
	)
	(segment
		(start 141.03604 -48.759872)
		(end 141.213078 -48.93691)
		(width 0.13208)
		(layer "F.Cu")
		(net "SMB_SSD4_ADC_SDA")
	)
	(segment
		(start 140.576554 -48.30699)
		(end 141.03604 -48.30699)
		(width 0.13208)
		(layer "F.Cu")
		(net "SMB_SSD4_ADC_SDA")
	)
	(segment
		(start 140.346176 -47.193962)
		(end 140.346176 -48.076612)
		(width 0.13208)
		(layer "F.Cu")
		(net "SMB_SSD4_ADC_SDA")
	)
	(segment
		(start 141.03604 -48.30699)
		(end 141.03604 -48.759872)
		(width 0.13208)
		(layer "F.Cu")
		(net "SMB_SSD4_ADC_SDA")
	)
	(segment
		(start 140.346176 -48.076612)
		(end 140.576554 -48.30699)
		(width 0.13208)
		(layer "F.Cu")
		(net "SMB_SSD4_ADC_SDA")
	)
	(segment
		(start 141.213078 -48.93691)
		(end 141.943836 -48.93691)
		(width 0.13208)
		(layer "F.Cu")
		(net "SMB_SSD4_ADC_SDA")
	)
	(via
		(at 141.03604 -48.30699)
		(size 0.508)
		(drill 0.254)
		(layers "F.Cu" "B.Cu")
		(net "SMB_SSD4_ADC_SDA")
	)
	(segment
		(start 51.843686 -49.95291)
		(end 50.65649 -49.95291)
		(width 0.13208)
		(layer "F.Cu")
		(net "SMB_SSD1_ADC_SCL")
	)
	(segment
		(start 49.59604 -48.89246)
		(end 49.59604 -47.843948)
		(width 0.13208)
		(layer "F.Cu")
		(net "SMB_SSD1_ADC_SCL")
	)
	(segment
		(start 50.65649 -49.95291)
		(end 49.59604 -48.89246)
		(width 0.13208)
		(layer "F.Cu")
		(net "SMB_SSD1_ADC_SCL")
	)
	(via
		(at 49.59604 -48.89246)
		(size 0.508)
		(drill 0.254)
		(layers "F.Cu" "B.Cu")
		(net "SMB_SSD1_ADC_SCL")
	)
	(segment
		(start 103.057706 -46.693836)
		(end 103.632508 -46.693836)
		(width 0.13208)
		(layer "F.Cu")
		(net "SSD3_ADC_ALERT_N")
	)
	(segment
		(start 103.632508 -46.693836)
		(end 103.843582 -46.90491)
		(width 0.13208)
		(layer "F.Cu")
		(net "SSD3_ADC_ALERT_N")
	)
	(segment
		(start 102.245922 -46.693836)
		(end 103.057706 -46.693836)
		(width 0.13208)
		(layer "F.Cu")
		(net "SSD3_ADC_ALERT_N")
	)
	(via
		(at 103.057706 -46.693836)
		(size 0.508)
		(drill 0.254)
		(layers "F.Cu" "B.Cu")
		(net "SSD3_ADC_ALERT_N")
	)
	(segment
		(start 24.246078 -48.076612)
		(end 24.246078 -47.193962)
		(width 0.13208)
		(layer "F.Cu")
		(net "SMB_SSD0_ADC_SDA")
	)
	(segment
		(start 25.843738 -48.93691)
		(end 25.173432 -48.93691)
		(width 0.13208)
		(layer "F.Cu")
		(net "SMB_SSD0_ADC_SDA")
	)
	(segment
		(start 24.476456 -48.30699)
		(end 24.246078 -48.076612)
		(width 0.13208)
		(layer "F.Cu")
		(net "SMB_SSD0_ADC_SDA")
	)
	(segment
		(start 24.935942 -48.30699)
		(end 24.476456 -48.30699)
		(width 0.13208)
		(layer "F.Cu")
		(net "SMB_SSD0_ADC_SDA")
	)
	(segment
		(start 24.935942 -48.69942)
		(end 24.935942 -48.30699)
		(width 0.13208)
		(layer "F.Cu")
		(net "SMB_SSD0_ADC_SDA")
	)
	(segment
		(start 25.173432 -48.93691)
		(end 24.935942 -48.69942)
		(width 0.13208)
		(layer "F.Cu")
		(net "SMB_SSD0_ADC_SDA")
	)
	(via
		(at 24.935942 -48.30699)
		(size 0.508)
		(drill 0.254)
		(layers "F.Cu" "B.Cu")
		(net "SMB_SSD0_ADC_SDA")
	)
	(segment
		(start 77.057758 -46.693836)
		(end 77.63256 -46.693836)
		(width 0.13208)
		(layer "F.Cu")
		(net "SSD2_ADC_ALERT_N")
	)
	(segment
		(start 76.245974 -46.693836)
		(end 77.057758 -46.693836)
		(width 0.13208)
		(layer "F.Cu")
		(net "SSD2_ADC_ALERT_N")
	)
	(segment
		(start 77.63256 -46.693836)
		(end 77.843634 -46.90491)
		(width 0.13208)
		(layer "F.Cu")
		(net "SSD2_ADC_ALERT_N")
	)
	(via
		(at 77.057758 -46.693836)
		(size 0.508)
		(drill 0.254)
		(layers "F.Cu" "B.Cu")
		(net "SSD2_ADC_ALERT_N")
	)
	(segment
		(start 20.38985 -43.941492)
		(end 19.738594 -43.941492)
		(width 0.254)
		(layer "F.Cu")
		(net "P12V_SSD0_VIN_P")
	)
	(segment
		(start 19.725386 -43.928284)
		(end 19.725386 -42.849038)
		(width 0.254)
		(layer "F.Cu")
		(net "P12V_SSD0_VIN_P")
	)
	(segment
		(start 20.595082 -43.73626)
		(end 20.38985 -43.941492)
		(width 0.254)
		(layer "F.Cu")
		(net "P12V_SSD0_VIN_P")
	)
	(segment
		(start 22.095968 -45.043852)
		(end 22.095968 -44.53509)
		(width 0.254)
		(layer "F.Cu")
		(net "P12V_SSD0_VIN_P")
	)
	(segment
		(start 21.297138 -43.73626)
		(end 20.595082 -43.73626)
		(width 0.254)
		(layer "F.Cu")
		(net "P12V_SSD0_VIN_P")
	)
	(segment
		(start 22.095968 -44.53509)
		(end 21.297138 -43.73626)
		(width 0.254)
		(layer "F.Cu")
		(net "P12V_SSD0_VIN_P")
	)
	(segment
		(start 19.738594 -43.941492)
		(end 19.725386 -43.928284)
		(width 0.254)
		(layer "F.Cu")
		(net "P12V_SSD0_VIN_P")
	)
	(via
		(at 20.595082 -43.73626)
		(size 0.508)
		(drill 0.254)
		(layers "F.Cu" "B.Cu")
		(net "P12V_SSD0_VIN_P")
	)
	(segment
		(start 25.279096 -45.88891)
		(end 25.085802 -45.695616)
		(width 0.13208)
		(layer "F.Cu")
		(net "SSD0_ADC_A0")
	)
	(segment
		(start 25.085802 -45.695616)
		(end 25.085802 -45.771816)
		(width 0.13208)
		(layer "F.Cu")
		(net "SSD0_ADC_A0")
	)
	(segment
		(start 25.843738 -44.87291)
		(end 25.843738 -45.88891)
		(width 0.13208)
		(layer "F.Cu")
		(net "SSD0_ADC_A0")
	)
	(segment
		(start 24.663654 -46.193964)
		(end 24.246078 -46.193964)
		(width 0.13208)
		(layer "F.Cu")
		(net "SSD0_ADC_A0")
	)
	(segment
		(start 25.085802 -45.771816)
		(end 24.663654 -46.193964)
		(width 0.13208)
		(layer "F.Cu")
		(net "SSD0_ADC_A0")
	)
	(segment
		(start 25.843738 -45.88891)
		(end 25.279096 -45.88891)
		(width 0.13208)
		(layer "F.Cu")
		(net "SSD0_ADC_A0")
	)
	(segment
		(start 25.085802 -45.35424)
		(end 25.085802 -45.695616)
		(width 0.13208)
		(layer "F.Cu")
		(net "SSD0_ADC_A0")
	)
	(via
		(at 25.085802 -45.35424)
		(size 0.508)
		(drill 0.254)
		(layers "F.Cu" "B.Cu")
		(net "SSD0_ADC_A0")
	)
	(segment
		(start 24.246078 -45.693838)
		(end 24.246078 -44.712636)
		(width 0.13208)
		(layer "F.Cu")
		(net "SSD0_ADC_A1")
	)
	(segment
		(start 25.843738 -42.84091)
		(end 25.843738 -43.85691)
		(width 0.13208)
		(layer "F.Cu")
		(net "SSD0_ADC_A1")
	)
	(segment
		(start 24.246078 -44.712636)
		(end 25.101804 -43.85691)
		(width 0.13208)
		(layer "F.Cu")
		(net "SSD0_ADC_A1")
	)
	(segment
		(start 25.101804 -43.85691)
		(end 25.843738 -43.85691)
		(width 0.13208)
		(layer "F.Cu")
		(net "SSD0_ADC_A1")
	)
	(via
		(at 25.101804 -43.85691)
		(size 0.508)
		(drill 0.254)
		(layers "F.Cu" "B.Cu")
		(net "SSD0_ADC_A1")
	)
	(segment
		(start 50.246026 -44.712636)
		(end 51.101752 -43.85691)
		(width 0.13208)
		(layer "F.Cu")
		(net "SSD1_ADC_A1")
	)
	(segment
		(start 51.101752 -43.85691)
		(end 51.843686 -43.85691)
		(width 0.13208)
		(layer "F.Cu")
		(net "SSD1_ADC_A1")
	)
	(segment
		(start 51.843686 -42.84091)
		(end 51.843686 -43.85691)
		(width 0.13208)
		(layer "F.Cu")
		(net "SSD1_ADC_A1")
	)
	(segment
		(start 50.246026 -45.693838)
		(end 50.246026 -44.712636)
		(width 0.13208)
		(layer "F.Cu")
		(net "SSD1_ADC_A1")
	)
	(via
		(at 51.101752 -43.85691)
		(size 0.508)
		(drill 0.254)
		(layers "F.Cu" "B.Cu")
		(net "SSD1_ADC_A1")
	)
	(segment
		(start 99.296982 -43.73626)
		(end 98.594926 -43.73626)
		(width 0.254)
		(layer "F.Cu")
		(net "P12V_SSD3_VIN_P")
	)
	(segment
		(start 98.389694 -43.941492)
		(end 97.738438 -43.941492)
		(width 0.254)
		(layer "F.Cu")
		(net "P12V_SSD3_VIN_P")
	)
	(segment
		(start 98.594926 -43.73626)
		(end 98.389694 -43.941492)
		(width 0.254)
		(layer "F.Cu")
		(net "P12V_SSD3_VIN_P")
	)
	(segment
		(start 100.095812 -44.53509)
		(end 99.296982 -43.73626)
		(width 0.254)
		(layer "F.Cu")
		(net "P12V_SSD3_VIN_P")
	)
	(segment
		(start 100.095812 -45.043852)
		(end 100.095812 -44.53509)
		(width 0.254)
		(layer "F.Cu")
		(net "P12V_SSD3_VIN_P")
	)
	(segment
		(start 97.738438 -43.941492)
		(end 97.72523 -43.928284)
		(width 0.254)
		(layer "F.Cu")
		(net "P12V_SSD3_VIN_P")
	)
	(segment
		(start 97.72523 -43.928284)
		(end 97.72523 -42.849038)
		(width 0.254)
		(layer "F.Cu")
		(net "P12V_SSD3_VIN_P")
	)
	(via
		(at 98.594926 -43.73626)
		(size 0.508)
		(drill 0.254)
		(layers "F.Cu" "B.Cu")
		(net "P12V_SSD3_VIN_P")
	)
	(segment
		(start 20.074636 -44.741592)
		(end 19.738594 -44.741592)
		(width 0.254)
		(layer "F.Cu")
		(net "P12V_SSD0_VIN_N")
	)
	(segment
		(start 21.445982 -45.693838)
		(end 21.026882 -45.693838)
		(width 0.254)
		(layer "F.Cu")
		(net "P12V_SSD0_VIN_N")
	)
	(segment
		(start 20.447508 -45.114464)
		(end 20.074636 -44.741592)
		(width 0.254)
		(layer "F.Cu")
		(net "P12V_SSD0_VIN_N")
	)
	(segment
		(start 21.026882 -45.693838)
		(end 20.447508 -45.114464)
		(width 0.254)
		(layer "F.Cu")
		(net "P12V_SSD0_VIN_N")
	)
	(segment
		(start 18.722594 -44.741592)
		(end 19.738594 -44.741592)
		(width 0.254)
		(layer "F.Cu")
		(net "P12V_SSD0_VIN_N")
	)
	(via
		(at 20.447508 -45.114464)
		(size 0.508)
		(drill 0.254)
		(layers "F.Cu" "B.Cu")
		(net "P12V_SSD0_VIN_N")
	)
	(segment
		(start 98.52533 -42.849038)
		(end 99.273868 -42.849038)
		(width 0.381)
		(layer "F.Cu")
		(net "P12V_SSD3_R")
	)
	(segment
		(start 80.475074 -63.086234)
		(end 79.769462 -63.086234)
		(width 0.4572)
		(layer "F.Cu")
		(net "P12V_SSD3_R")
	)
	(via
		(at 96.352868 -67.951604)
		(size 0.508)
		(drill 0.254)
		(layers "F.Cu" "B.Cu")
		(net "P12V_SSD3_R")
	)
	(via
		(at 96.303338 -53.00853)
		(size 0.508)
		(drill 0.254)
		(layers "F.Cu" "B.Cu")
		(net "P12V_SSD3_R")
	)
	(via
		(at 79.769462 -63.086234)
		(size 0.508)
		(drill 0.254)
		(layers "F.Cu" "B.Cu")
		(net "P12V_SSD3_R")
	)
	(via
		(at 95.717868 -68.586604)
		(size 0.508)
		(drill 0.254)
		(layers "F.Cu" "B.Cu")
		(net "P12V_SSD3_R")
	)
	(via
		(at 97.959418 -45.976286)
		(size 0.508)
		(drill 0.254)
		(layers "F.Cu" "B.Cu")
		(net "P12V_SSD3_R")
	)
	(via
		(at 96.227138 -53.77053)
		(size 0.508)
		(drill 0.254)
		(layers "F.Cu" "B.Cu")
		(net "P12V_SSD3_R")
	)
	(via
		(at 91.902026 -53.461412)
		(size 0.508)
		(drill 0.254)
		(layers "F.Cu" "B.Cu")
		(net "P12V_SSD3_R")
	)
	(via
		(at 91.902026 -54.096412)
		(size 0.508)
		(drill 0.254)
		(layers "F.Cu" "B.Cu")
		(net "P12V_SSD3_R")
	)
	(via
		(at 96.352868 -68.586604)
		(size 0.508)
		(drill 0.254)
		(layers "F.Cu" "B.Cu")
		(net "P12V_SSD3_R")
	)
	(via
		(at 97.51187 -54.320186)
		(size 0.508)
		(drill 0.254)
		(layers "F.Cu" "B.Cu")
		(net "P12V_SSD3_R")
	)
	(via
		(at 94.55785 -54.791102)
		(size 0.508)
		(drill 0.254)
		(layers "F.Cu" "B.Cu")
		(net "P12V_SSD3_R")
	)
	(via
		(at 94.55785 -52.886102)
		(size 0.508)
		(drill 0.254)
		(layers "F.Cu" "B.Cu")
		(net "P12V_SSD3_R")
	)
	(via
		(at 94.55785 -54.156102)
		(size 0.508)
		(drill 0.254)
		(layers "F.Cu" "B.Cu")
		(net "P12V_SSD3_R")
	)
	(via
		(at 95.006668 -68.586604)
		(size 0.508)
		(drill 0.254)
		(layers "F.Cu" "B.Cu")
		(net "P12V_SSD3_R")
	)
	(via
		(at 98.452432 -54.135528)
		(size 0.508)
		(drill 0.254)
		(layers "F.Cu" "B.Cu")
		(net "P12V_SSD3_R")
	)
	(via
		(at 97.51187 -53.685186)
		(size 0.508)
		(drill 0.254)
		(layers "F.Cu" "B.Cu")
		(net "P12V_SSD3_R")
	)
	(via
		(at 95.592138 -53.00853)
		(size 0.508)
		(drill 0.254)
		(layers "F.Cu" "B.Cu")
		(net "P12V_SSD3_R")
	)
	(via
		(at 95.006668 -67.951604)
		(size 0.508)
		(drill 0.254)
		(layers "F.Cu" "B.Cu")
		(net "P12V_SSD3_R")
	)
	(via
		(at 91.902026 -52.826412)
		(size 0.508)
		(drill 0.254)
		(layers "F.Cu" "B.Cu")
		(net "P12V_SSD3_R")
	)
	(via
		(at 99.273868 -42.849038)
		(size 0.508)
		(drill 0.254)
		(layers "F.Cu" "B.Cu")
		(net "P12V_SSD3_R")
	)
	(via
		(at 97.249488 -46.066964)
		(size 0.508)
		(drill 0.254)
		(layers "F.Cu" "B.Cu")
		(net "P12V_SSD3_R")
	)
	(via
		(at 93.382592 -67.10172)
		(size 0.508)
		(drill 0.254)
		(layers "F.Cu" "B.Cu")
		(net "P12V_SSD3_R")
	)
	(via
		(at 94.55785 -53.521102)
		(size 0.508)
		(drill 0.254)
		(layers "F.Cu" "B.Cu")
		(net "P12V_SSD3_R")
	)
	(via
		(at 98.452432 -54.770528)
		(size 0.508)
		(drill 0.254)
		(layers "F.Cu" "B.Cu")
		(net "P12V_SSD3_R")
	)
	(via
		(at 95.717868 -67.951604)
		(size 0.508)
		(drill 0.254)
		(layers "F.Cu" "B.Cu")
		(net "P12V_SSD3_R")
	)
	(via
		(at 96.486726 -46.792134)
		(size 0.508)
		(drill 0.254)
		(layers "F.Cu" "B.Cu")
		(net "P12V_SSD3_R")
	)
	(via
		(at 97.151444 -46.739048)
		(size 0.508)
		(drill 0.254)
		(layers "F.Cu" "B.Cu")
		(net "P12V_SSD3_R")
	)
	(via
		(at 92.747592 -67.10172)
		(size 0.508)
		(drill 0.254)
		(layers "F.Cu" "B.Cu")
		(net "P12V_SSD3_R")
	)
	(via
		(at 91.902026 -54.731412)
		(size 0.508)
		(drill 0.254)
		(layers "F.Cu" "B.Cu")
		(net "P12V_SSD3_R")
	)
	(via
		(at 95.592138 -53.77053)
		(size 0.508)
		(drill 0.254)
		(layers "F.Cu" "B.Cu")
		(net "P12V_SSD3_R")
	)
	(via
		(at 96.433894 -46.082204)
		(size 0.508)
		(drill 0.254)
		(layers "F.Cu" "B.Cu")
		(net "P12V_SSD3_R")
	)
	(segment
		(start 46.525434 -42.849038)
		(end 47.273972 -42.849038)
		(width 0.381)
		(layer "F.Cu")
		(net "P12V_SSD1_R")
	)
	(segment
		(start 28.475178 -63.086234)
		(end 27.769566 -63.086234)
		(width 0.381)
		(layer "F.Cu")
		(net "P12V_SSD1_R")
	)
	(via
		(at 45.511974 -54.320186)
		(size 0.508)
		(drill 0.254)
		(layers "F.Cu" "B.Cu")
		(net "P12V_SSD1_R")
	)
	(via
		(at 42.557954 -54.791102)
		(size 0.508)
		(drill 0.254)
		(layers "F.Cu" "B.Cu")
		(net "P12V_SSD1_R")
	)
	(via
		(at 44.48683 -46.792134)
		(size 0.508)
		(drill 0.254)
		(layers "F.Cu" "B.Cu")
		(net "P12V_SSD1_R")
	)
	(via
		(at 46.452536 -54.135528)
		(size 0.508)
		(drill 0.254)
		(layers "F.Cu" "B.Cu")
		(net "P12V_SSD1_R")
	)
	(via
		(at 45.151548 -46.739048)
		(size 0.508)
		(drill 0.254)
		(layers "F.Cu" "B.Cu")
		(net "P12V_SSD1_R")
	)
	(via
		(at 39.90213 -52.826412)
		(size 0.508)
		(drill 0.254)
		(layers "F.Cu" "B.Cu")
		(net "P12V_SSD1_R")
	)
	(via
		(at 47.273972 -42.849038)
		(size 0.508)
		(drill 0.254)
		(layers "F.Cu" "B.Cu")
		(net "P12V_SSD1_R")
	)
	(via
		(at 46.452536 -54.770528)
		(size 0.508)
		(drill 0.254)
		(layers "F.Cu" "B.Cu")
		(net "P12V_SSD1_R")
	)
	(via
		(at 41.382696 -67.10172)
		(size 0.508)
		(drill 0.254)
		(layers "F.Cu" "B.Cu")
		(net "P12V_SSD1_R")
	)
	(via
		(at 44.352972 -68.586604)
		(size 0.508)
		(drill 0.254)
		(layers "F.Cu" "B.Cu")
		(net "P12V_SSD1_R")
	)
	(via
		(at 39.90213 -54.096412)
		(size 0.508)
		(drill 0.254)
		(layers "F.Cu" "B.Cu")
		(net "P12V_SSD1_R")
	)
	(via
		(at 43.717972 -67.951604)
		(size 0.508)
		(drill 0.254)
		(layers "F.Cu" "B.Cu")
		(net "P12V_SSD1_R")
	)
	(via
		(at 43.006772 -68.586604)
		(size 0.508)
		(drill 0.254)
		(layers "F.Cu" "B.Cu")
		(net "P12V_SSD1_R")
	)
	(via
		(at 44.303442 -53.00853)
		(size 0.508)
		(drill 0.254)
		(layers "F.Cu" "B.Cu")
		(net "P12V_SSD1_R")
	)
	(via
		(at 44.433998 -46.082204)
		(size 0.508)
		(drill 0.254)
		(layers "F.Cu" "B.Cu")
		(net "P12V_SSD1_R")
	)
	(via
		(at 42.557954 -53.521102)
		(size 0.508)
		(drill 0.254)
		(layers "F.Cu" "B.Cu")
		(net "P12V_SSD1_R")
	)
	(via
		(at 45.511974 -53.685186)
		(size 0.508)
		(drill 0.254)
		(layers "F.Cu" "B.Cu")
		(net "P12V_SSD1_R")
	)
	(via
		(at 27.769566 -63.086234)
		(size 0.508)
		(drill 0.254)
		(layers "F.Cu" "B.Cu")
		(net "P12V_SSD1_R")
	)
	(via
		(at 45.249592 -46.066964)
		(size 0.508)
		(drill 0.254)
		(layers "F.Cu" "B.Cu")
		(net "P12V_SSD1_R")
	)
	(via
		(at 43.592242 -53.00853)
		(size 0.508)
		(drill 0.254)
		(layers "F.Cu" "B.Cu")
		(net "P12V_SSD1_R")
	)
	(via
		(at 39.90213 -53.461412)
		(size 0.508)
		(drill 0.254)
		(layers "F.Cu" "B.Cu")
		(net "P12V_SSD1_R")
	)
	(via
		(at 42.557954 -52.886102)
		(size 0.508)
		(drill 0.254)
		(layers "F.Cu" "B.Cu")
		(net "P12V_SSD1_R")
	)
	(via
		(at 45.959522 -45.976286)
		(size 0.508)
		(drill 0.254)
		(layers "F.Cu" "B.Cu")
		(net "P12V_SSD1_R")
	)
	(via
		(at 44.227242 -53.77053)
		(size 0.508)
		(drill 0.254)
		(layers "F.Cu" "B.Cu")
		(net "P12V_SSD1_R")
	)
	(via
		(at 43.006772 -67.951604)
		(size 0.508)
		(drill 0.254)
		(layers "F.Cu" "B.Cu")
		(net "P12V_SSD1_R")
	)
	(via
		(at 42.557954 -54.156102)
		(size 0.508)
		(drill 0.254)
		(layers "F.Cu" "B.Cu")
		(net "P12V_SSD1_R")
	)
	(via
		(at 44.352972 -67.951604)
		(size 0.508)
		(drill 0.254)
		(layers "F.Cu" "B.Cu")
		(net "P12V_SSD1_R")
	)
	(via
		(at 43.592242 -53.77053)
		(size 0.508)
		(drill 0.254)
		(layers "F.Cu" "B.Cu")
		(net "P12V_SSD1_R")
	)
	(via
		(at 40.747696 -67.10172)
		(size 0.508)
		(drill 0.254)
		(layers "F.Cu" "B.Cu")
		(net "P12V_SSD1_R")
	)
	(via
		(at 43.717972 -68.586604)
		(size 0.508)
		(drill 0.254)
		(layers "F.Cu" "B.Cu")
		(net "P12V_SSD1_R")
	)
	(via
		(at 39.90213 -54.731412)
		(size 0.508)
		(drill 0.254)
		(layers "F.Cu" "B.Cu")
		(net "P12V_SSD1_R")
	)
	(segment
		(start 51.08575 -45.695616)
		(end 51.08575 -45.771816)
		(width 0.13208)
		(layer "F.Cu")
		(net "SSD1_ADC_A0")
	)
	(segment
		(start 50.663602 -46.193964)
		(end 50.246026 -46.193964)
		(width 0.13208)
		(layer "F.Cu")
		(net "SSD1_ADC_A0")
	)
	(segment
		(start 51.279044 -45.88891)
		(end 51.08575 -45.695616)
		(width 0.13208)
		(layer "F.Cu")
		(net "SSD1_ADC_A0")
	)
	(segment
		(start 51.843686 -44.87291)
		(end 51.843686 -45.88891)
		(width 0.13208)
		(layer "F.Cu")
		(net "SSD1_ADC_A0")
	)
	(segment
		(start 51.08575 -45.35424)
		(end 51.08575 -45.695616)
		(width 0.13208)
		(layer "F.Cu")
		(net "SSD1_ADC_A0")
	)
	(segment
		(start 51.843686 -45.88891)
		(end 51.279044 -45.88891)
		(width 0.13208)
		(layer "F.Cu")
		(net "SSD1_ADC_A0")
	)
	(segment
		(start 51.08575 -45.771816)
		(end 50.663602 -46.193964)
		(width 0.13208)
		(layer "F.Cu")
		(net "SSD1_ADC_A0")
	)
	(via
		(at 51.08575 -45.35424)
		(size 0.508)
		(drill 0.254)
		(layers "F.Cu" "B.Cu")
		(net "SSD1_ADC_A0")
	)
	(segment
		(start 77.843634 -49.982882)
		(end 77.401674 -50.424842)
		(width 0.13208)
		(layer "F.Cu")
		(net "SMB_SSD2_ADC_SCL")
	)
	(segment
		(start 77.401674 -50.424842)
		(end 75.426316 -50.424842)
		(width 0.13208)
		(layer "F.Cu")
		(net "SMB_SSD2_ADC_SCL")
	)
	(segment
		(start 77.843634 -49.95291)
		(end 77.843634 -49.982882)
		(width 0.13208)
		(layer "F.Cu")
		(net "SMB_SSD2_ADC_SCL")
	)
	(segment
		(start 75.426316 -50.424842)
		(end 75.141328 -50.139854)
		(width 0.13208)
		(layer "F.Cu")
		(net "SMB_SSD2_ADC_SCL")
	)
	(segment
		(start 75.141328 -49.34712)
		(end 75.595988 -48.89246)
		(width 0.13208)
		(layer "F.Cu")
		(net "SMB_SSD2_ADC_SCL")
	)
	(segment
		(start 75.141328 -50.139854)
		(end 75.141328 -49.34712)
		(width 0.13208)
		(layer "F.Cu")
		(net "SMB_SSD2_ADC_SCL")
	)
	(segment
		(start 75.595988 -48.89246)
		(end 75.595988 -47.843948)
		(width 0.13208)
		(layer "F.Cu")
		(net "SMB_SSD2_ADC_SCL")
	)
	(via
		(at 75.595988 -48.89246)
		(size 0.508)
		(drill 0.254)
		(layers "F.Cu" "B.Cu")
		(net "SMB_SSD2_ADC_SCL")
	)
	(segment
		(start 337.293966 -223.187006)
		(end 336.89417 -223.586802)
		(width 0.13208)
		(layer "F.Cu")
		(net "PWRGD_P1V25_PEX1_R")
	)
	(segment
		(start 231.832404 -310.41721)
		(end 232.101136 -310.148478)
		(width 0.13208)
		(layer "F.Cu")
		(net "PWRGD_P1V25_PEX1_R")
	)
	(segment
		(start 231.832404 -311.132982)
		(end 231.832404 -310.41721)
		(width 0.13208)
		(layer "F.Cu")
		(net "PWRGD_P1V25_PEX1_R")
	)
	(via
		(at 232.101136 -310.148478)
		(size 0.508)
		(drill 0.254)
		(layers "F.Cu" "B.Cu")
		(net "PWRGD_P1V25_PEX1_R")
	)
	(via
		(at 336.89417 -223.586802)
		(size 0.4572)
		(drill 0.254)
		(layers "F.Cu" "B.Cu")
		(net "PWRGD_P1V25_PEX1_R")
	)
	(via
		(at 232.900728 -252.57887)
		(size 0.508)
		(drill 0.254)
		(layers "F.Cu" "B.Cu")
		(net "PWRGD_P1V25_PEX1_R")
	)
	(via
		(at 263.744202 -222.323152)
		(size 0.508)
		(drill 0.254)
		(layers "F.Cu" "B.Cu")
		(net "PWRGD_P1V25_PEX1_R")
	)
	(segment
		(start 260.19633 -226.6696)
		(end 263.017 -223.84893)
		(width 0.15494)
		(layer "In7.Cu")
		(net "PWRGD_P1V25_PEX1_R")
	)
	(segment
		(start 232.900728 -252.57887)
		(end 233.407458 -253.0856)
		(width 0.15494)
		(layer "In7.Cu")
		(net "PWRGD_P1V25_PEX1_R")
	)
	(segment
		(start 235.81233 -252.14707)
		(end 239.070896 -248.888504)
		(width 0.15494)
		(layer "In7.Cu")
		(net "PWRGD_P1V25_PEX1_R")
	)
	(segment
		(start 235.532168 -253.0856)
		(end 235.81233 -252.805438)
		(width 0.15494)
		(layer "In7.Cu")
		(net "PWRGD_P1V25_PEX1_R")
	)
	(segment
		(start 263.017 -223.84893)
		(end 263.017 -222.97263)
		(width 0.15494)
		(layer "In7.Cu")
		(net "PWRGD_P1V25_PEX1_R")
	)
	(segment
		(start 243.218716 -244.672612)
		(end 260.19633 -227.694998)
		(width 0.15494)
		(layer "In7.Cu")
		(net "PWRGD_P1V25_PEX1_R")
	)
	(segment
		(start 263.017 -222.97263)
		(end 263.666478 -222.323152)
		(width 0.15494)
		(layer "In7.Cu")
		(net "PWRGD_P1V25_PEX1_R")
	)
	(segment
		(start 233.407458 -253.0856)
		(end 235.532168 -253.0856)
		(width 0.15494)
		(layer "In7.Cu")
		(net "PWRGD_P1V25_PEX1_R")
	)
	(segment
		(start 239.070896 -248.774712)
		(end 243.172996 -244.672612)
		(width 0.15494)
		(layer "In7.Cu")
		(net "PWRGD_P1V25_PEX1_R")
	)
	(segment
		(start 235.81233 -252.805438)
		(end 235.81233 -252.14707)
		(width 0.15494)
		(layer "In7.Cu")
		(net "PWRGD_P1V25_PEX1_R")
	)
	(segment
		(start 263.666478 -222.323152)
		(end 263.744202 -222.323152)
		(width 0.15494)
		(layer "In7.Cu")
		(net "PWRGD_P1V25_PEX1_R")
	)
	(segment
		(start 239.070896 -248.888504)
		(end 239.070896 -248.774712)
		(width 0.15494)
		(layer "In7.Cu")
		(net "PWRGD_P1V25_PEX1_R")
	)
	(segment
		(start 260.19633 -227.694998)
		(end 260.19633 -226.6696)
		(width 0.15494)
		(layer "In7.Cu")
		(net "PWRGD_P1V25_PEX1_R")
	)
	(segment
		(start 243.172996 -244.672612)
		(end 243.218716 -244.672612)
		(width 0.15494)
		(layer "In7.Cu")
		(net "PWRGD_P1V25_PEX1_R")
	)
	(segment
		(start 231.536494 -281.373834)
		(end 233.04881 -282.88615)
		(width 0.15494)
		(layer "In11.Cu")
		(net "PWRGD_P1V25_PEX1_R")
	)
	(segment
		(start 232.588816 -310.148478)
		(end 232.101136 -310.148478)
		(width 0.15494)
		(layer "In11.Cu")
		(net "PWRGD_P1V25_PEX1_R")
	)
	(segment
		(start 229.415848 -252.412754)
		(end 229.415848 -255.044194)
		(width 0.15494)
		(layer "In11.Cu")
		(net "PWRGD_P1V25_PEX1_R")
	)
	(segment
		(start 232.900728 -252.56109)
		(end 232.333038 -251.9934)
		(width 0.15494)
		(layer "In11.Cu")
		(net "PWRGD_P1V25_PEX1_R")
	)
	(segment
		(start 232.333038 -251.9934)
		(end 229.835202 -251.9934)
		(width 0.15494)
		(layer "In11.Cu")
		(net "PWRGD_P1V25_PEX1_R")
	)
	(segment
		(start 233.04881 -282.88615)
		(end 233.04881 -309.688484)
		(width 0.15494)
		(layer "In11.Cu")
		(net "PWRGD_P1V25_PEX1_R")
	)
	(segment
		(start 233.04881 -309.688484)
		(end 232.588816 -310.148478)
		(width 0.15494)
		(layer "In11.Cu")
		(net "PWRGD_P1V25_PEX1_R")
	)
	(segment
		(start 231.536494 -257.16484)
		(end 231.536494 -281.373834)
		(width 0.15494)
		(layer "In11.Cu")
		(net "PWRGD_P1V25_PEX1_R")
	)
	(segment
		(start 229.835202 -251.9934)
		(end 229.415848 -252.412754)
		(width 0.15494)
		(layer "In11.Cu")
		(net "PWRGD_P1V25_PEX1_R")
	)
	(segment
		(start 232.900728 -252.57887)
		(end 232.900728 -252.56109)
		(width 0.15494)
		(layer "In11.Cu")
		(net "PWRGD_P1V25_PEX1_R")
	)
	(segment
		(start 229.415848 -255.044194)
		(end 231.536494 -257.16484)
		(width 0.15494)
		(layer "In11.Cu")
		(net "PWRGD_P1V25_PEX1_R")
	)
	(segment
		(start 334.7974 -223.7486)
		(end 334.5434 -223.7486)
		(width 0.0889)
		(layer "In15.Cu")
		(net "PWRGD_P1V25_PEX1_R")
	)
	(segment
		(start 326.876918 -225.472752)
		(end 325.888858 -225.472752)
		(width 0.15494)
		(layer "In15.Cu")
		(net "PWRGD_P1V25_PEX1_R")
	)
	(segment
		(start 324.228714 -225.261932)
		(end 321.38747 -222.420688)
		(width 0.15494)
		(layer "In15.Cu")
		(net "PWRGD_P1V25_PEX1_R")
	)
	(segment
		(start 335.010252 -223.961452)
		(end 334.7974 -223.7486)
		(width 0.0889)
		(layer "In15.Cu")
		(net "PWRGD_P1V25_PEX1_R")
	)
	(segment
		(start 325.678038 -225.261932)
		(end 324.228714 -225.261932)
		(width 0.15494)
		(layer "In15.Cu")
		(net "PWRGD_P1V25_PEX1_R")
	)
	(segment
		(start 325.888858 -225.472752)
		(end 325.678038 -225.261932)
		(width 0.15494)
		(layer "In15.Cu")
		(net "PWRGD_P1V25_PEX1_R")
	)
	(segment
		(start 328.74966 -224.00133)
		(end 328.34834 -224.00133)
		(width 0.15494)
		(layer "In15.Cu")
		(net "PWRGD_P1V25_PEX1_R")
	)
	(segment
		(start 334.5434 -223.7486)
		(end 334.00746 -224.28454)
		(width 0.15494)
		(layer "In15.Cu")
		(net "PWRGD_P1V25_PEX1_R")
	)
	(segment
		(start 329.03287 -224.28454)
		(end 328.74966 -224.00133)
		(width 0.15494)
		(layer "In15.Cu")
		(net "PWRGD_P1V25_PEX1_R")
	)
	(segment
		(start 263.841738 -222.420688)
		(end 263.744202 -222.323152)
		(width 0.15494)
		(layer "In15.Cu")
		(net "PWRGD_P1V25_PEX1_R")
	)
	(segment
		(start 336.89417 -223.586802)
		(end 336.51952 -223.961452)
		(width 0.0889)
		(layer "In15.Cu")
		(net "PWRGD_P1V25_PEX1_R")
	)
	(segment
		(start 321.38747 -222.420688)
		(end 263.841738 -222.420688)
		(width 0.15494)
		(layer "In15.Cu")
		(net "PWRGD_P1V25_PEX1_R")
	)
	(segment
		(start 336.51952 -223.961452)
		(end 335.010252 -223.961452)
		(width 0.0889)
		(layer "In15.Cu")
		(net "PWRGD_P1V25_PEX1_R")
	)
	(segment
		(start 328.34834 -224.00133)
		(end 326.876918 -225.472752)
		(width 0.15494)
		(layer "In15.Cu")
		(net "PWRGD_P1V25_PEX1_R")
	)
	(segment
		(start 334.00746 -224.28454)
		(end 329.03287 -224.28454)
		(width 0.15494)
		(layer "In15.Cu")
		(net "PWRGD_P1V25_PEX1_R")
	)
	(segment
		(start 51.632612 -46.693836)
		(end 51.843686 -46.90491)
		(width 0.13208)
		(layer "F.Cu")
		(net "SSD1_ADC_ALERT_N")
	)
	(segment
		(start 50.246026 -46.693836)
		(end 51.05781 -46.693836)
		(width 0.13208)
		(layer "F.Cu")
		(net "SSD1_ADC_ALERT_N")
	)
	(segment
		(start 51.05781 -46.693836)
		(end 51.632612 -46.693836)
		(width 0.13208)
		(layer "F.Cu")
		(net "SSD1_ADC_ALERT_N")
	)
	(via
		(at 51.05781 -46.693836)
		(size 0.508)
		(drill 0.254)
		(layers "F.Cu" "B.Cu")
		(net "SSD1_ADC_ALERT_N")
	)
	(segment
		(start 228.597206 -274.768056)
		(end 229.206806 -274.768056)
		(width 0.4572)
		(layer "F.Cu")
		(net "P1V25_PEX1_R")
	)
	(via
		(at 223.333056 -287.105344)
		(size 0.508)
		(drill 0.254)
		(layers "F.Cu" "B.Cu")
		(net "P1V25_PEX1_R")
	)
	(via
		(at 228.103938 -290.872926)
		(size 0.508)
		(drill 0.254)
		(layers "F.Cu" "B.Cu")
		(net "P1V25_PEX1_R")
	)
	(via
		(at 220.99905 -281.342338)
		(size 0.508)
		(drill 0.254)
		(layers "F.Cu" "B.Cu")
		(net "P1V25_PEX1_R")
	)
	(via
		(at 225.132646 -282.982162)
		(size 0.508)
		(drill 0.254)
		(layers "F.Cu" "B.Cu")
		(net "P1V25_PEX1_R")
	)
	(via
		(at 222.647256 -284.641544)
		(size 0.508)
		(drill 0.254)
		(layers "F.Cu" "B.Cu")
		(net "P1V25_PEX1_R")
	)
	(via
		(at 222.647256 -287.105344)
		(size 0.508)
		(drill 0.254)
		(layers "F.Cu" "B.Cu")
		(net "P1V25_PEX1_R")
	)
	(via
		(at 220.640656 -289.391344)
		(size 0.508)
		(drill 0.254)
		(layers "F.Cu" "B.Cu")
		(net "P1V25_PEX1_R")
	)
	(via
		(at 221.326456 -287.105344)
		(size 0.508)
		(drill 0.254)
		(layers "F.Cu" "B.Cu")
		(net "P1V25_PEX1_R")
	)
	(via
		(at 226.71405 -287.74898)
		(size 0.508)
		(drill 0.254)
		(layers "F.Cu" "B.Cu")
		(net "P1V25_PEX1_R")
	)
	(via
		(at 227.139246 -282.982162)
		(size 0.508)
		(drill 0.254)
		(layers "F.Cu" "B.Cu")
		(net "P1V25_PEX1_R")
	)
	(via
		(at 225.793046 -282.982162)
		(size 0.508)
		(drill 0.254)
		(layers "F.Cu" "B.Cu")
		(net "P1V25_PEX1_R")
	)
	(via
		(at 221.659704 -281.98445)
		(size 0.508)
		(drill 0.254)
		(layers "F.Cu" "B.Cu")
		(net "P1V25_PEX1_R")
	)
	(via
		(at 220.999304 -281.98445)
		(size 0.508)
		(drill 0.254)
		(layers "F.Cu" "B.Cu")
		(net "P1V25_PEX1_R")
	)
	(via
		(at 226.051618 -291.552376)
		(size 0.6604)
		(drill 0.3302)
		(layers "F.Cu" "B.Cu")
		(net "P1V25_PEX1_R")
	)
	(via
		(at 226.453446 -285.445962)
		(size 0.508)
		(drill 0.254)
		(layers "F.Cu" "B.Cu")
		(net "P1V25_PEX1_R")
	)
	(via
		(at 221.65945 -281.342338)
		(size 0.508)
		(drill 0.254)
		(layers "F.Cu" "B.Cu")
		(net "P1V25_PEX1_R")
	)
	(via
		(at 227.39985 -287.74898)
		(size 0.508)
		(drill 0.254)
		(layers "F.Cu" "B.Cu")
		(net "P1V25_PEX1_R")
	)
	(via
		(at 221.986856 -284.641544)
		(size 0.508)
		(drill 0.254)
		(layers "F.Cu" "B.Cu")
		(net "P1V25_PEX1_R")
	)
	(via
		(at 222.345504 -281.98445)
		(size 0.508)
		(drill 0.254)
		(layers "F.Cu" "B.Cu")
		(net "P1V25_PEX1_R")
	)
	(via
		(at 223.333056 -284.641544)
		(size 0.508)
		(drill 0.254)
		(layers "F.Cu" "B.Cu")
		(net "P1V25_PEX1_R")
	)
	(via
		(at 221.986856 -287.105344)
		(size 0.508)
		(drill 0.254)
		(layers "F.Cu" "B.Cu")
		(net "P1V25_PEX1_R")
	)
	(via
		(at 225.793046 -285.445962)
		(size 0.508)
		(drill 0.254)
		(layers "F.Cu" "B.Cu")
		(net "P1V25_PEX1_R")
	)
	(via
		(at 225.814382 -288.055812)
		(size 0.6604)
		(drill 0.3302)
		(layers "F.Cu" "B.Cu")
		(net "P1V25_PEX1_R")
	)
	(via
		(at 228.162612 -288.652204)
		(size 0.508)
		(drill 0.254)
		(layers "F.Cu" "B.Cu")
		(net "P1V25_PEX1_R")
	)
	(via
		(at 227.139246 -285.445962)
		(size 0.508)
		(drill 0.254)
		(layers "F.Cu" "B.Cu")
		(net "P1V25_PEX1_R")
	)
	(via
		(at 220.477588 -291.61232)
		(size 0.508)
		(drill 0.254)
		(layers "F.Cu" "B.Cu")
		(net "P1V25_PEX1_R")
	)
	(via
		(at 221.112588 -291.61232)
		(size 0.508)
		(drill 0.254)
		(layers "F.Cu" "B.Cu")
		(net "P1V25_PEX1_R")
	)
	(via
		(at 225.132646 -285.445962)
		(size 0.508)
		(drill 0.254)
		(layers "F.Cu" "B.Cu")
		(net "P1V25_PEX1_R")
	)
	(via
		(at 220.338904 -281.98445)
		(size 0.508)
		(drill 0.254)
		(layers "F.Cu" "B.Cu")
		(net "P1V25_PEX1_R")
	)
	(via
		(at 226.453446 -282.982162)
		(size 0.508)
		(drill 0.254)
		(layers "F.Cu" "B.Cu")
		(net "P1V25_PEX1_R")
	)
	(via
		(at 229.206806 -274.768056)
		(size 0.508)
		(drill 0.254)
		(layers "F.Cu" "B.Cu")
		(net "P1V25_PEX1_R")
	)
	(via
		(at 221.326456 -284.641544)
		(size 0.508)
		(drill 0.254)
		(layers "F.Cu" "B.Cu")
		(net "P1V25_PEX1_R")
	)
	(via
		(at 220.33865 -281.342338)
		(size 0.508)
		(drill 0.254)
		(layers "F.Cu" "B.Cu")
		(net "P1V25_PEX1_R")
	)
	(via
		(at 221.326456 -289.391344)
		(size 0.508)
		(drill 0.254)
		(layers "F.Cu" "B.Cu")
		(net "P1V25_PEX1_R")
	)
	(via
		(at 222.34525 -281.342338)
		(size 0.508)
		(drill 0.254)
		(layers "F.Cu" "B.Cu")
		(net "P1V25_PEX1_R")
	)
	(via
		(at 227.468938 -290.872926)
		(size 0.508)
		(drill 0.254)
		(layers "F.Cu" "B.Cu")
		(net "P1V25_PEX1_R")
	)
	(segment
		(start 72.525382 -42.849038)
		(end 73.27392 -42.849038)
		(width 0.381)
		(layer "F.Cu")
		(net "P12V_SSD2_R")
	)
	(segment
		(start 54.475126 -63.086234)
		(end 53.769514 -63.086234)
		(width 0.13208)
		(layer "F.Cu")
		(net "P12V_SSD2_R")
	)
	(via
		(at 68.557902 -52.886102)
		(size 0.508)
		(drill 0.254)
		(layers "F.Cu" "B.Cu")
		(net "P12V_SSD2_R")
	)
	(via
		(at 70.433946 -46.082204)
		(size 0.508)
		(drill 0.254)
		(layers "F.Cu" "B.Cu")
		(net "P12V_SSD2_R")
	)
	(via
		(at 69.00672 -67.951604)
		(size 0.508)
		(drill 0.254)
		(layers "F.Cu" "B.Cu")
		(net "P12V_SSD2_R")
	)
	(via
		(at 71.511922 -54.320186)
		(size 0.508)
		(drill 0.254)
		(layers "F.Cu" "B.Cu")
		(net "P12V_SSD2_R")
	)
	(via
		(at 69.71792 -67.951604)
		(size 0.508)
		(drill 0.254)
		(layers "F.Cu" "B.Cu")
		(net "P12V_SSD2_R")
	)
	(via
		(at 72.452484 -54.135528)
		(size 0.508)
		(drill 0.254)
		(layers "F.Cu" "B.Cu")
		(net "P12V_SSD2_R")
	)
	(via
		(at 53.769514 -63.086234)
		(size 0.508)
		(drill 0.254)
		(layers "F.Cu" "B.Cu")
		(net "P12V_SSD2_R")
	)
	(via
		(at 68.557902 -54.791102)
		(size 0.508)
		(drill 0.254)
		(layers "F.Cu" "B.Cu")
		(net "P12V_SSD2_R")
	)
	(via
		(at 65.902078 -54.096412)
		(size 0.508)
		(drill 0.254)
		(layers "F.Cu" "B.Cu")
		(net "P12V_SSD2_R")
	)
	(via
		(at 71.24954 -46.066964)
		(size 0.508)
		(drill 0.254)
		(layers "F.Cu" "B.Cu")
		(net "P12V_SSD2_R")
	)
	(via
		(at 65.902078 -54.731412)
		(size 0.508)
		(drill 0.254)
		(layers "F.Cu" "B.Cu")
		(net "P12V_SSD2_R")
	)
	(via
		(at 71.95947 -45.976286)
		(size 0.508)
		(drill 0.254)
		(layers "F.Cu" "B.Cu")
		(net "P12V_SSD2_R")
	)
	(via
		(at 71.151496 -46.739048)
		(size 0.508)
		(drill 0.254)
		(layers "F.Cu" "B.Cu")
		(net "P12V_SSD2_R")
	)
	(via
		(at 65.902078 -52.826412)
		(size 0.508)
		(drill 0.254)
		(layers "F.Cu" "B.Cu")
		(net "P12V_SSD2_R")
	)
	(via
		(at 69.59219 -53.77053)
		(size 0.508)
		(drill 0.254)
		(layers "F.Cu" "B.Cu")
		(net "P12V_SSD2_R")
	)
	(via
		(at 71.511922 -53.685186)
		(size 0.508)
		(drill 0.254)
		(layers "F.Cu" "B.Cu")
		(net "P12V_SSD2_R")
	)
	(via
		(at 70.22719 -53.77053)
		(size 0.508)
		(drill 0.254)
		(layers "F.Cu" "B.Cu")
		(net "P12V_SSD2_R")
	)
	(via
		(at 66.747644 -67.10172)
		(size 0.508)
		(drill 0.254)
		(layers "F.Cu" "B.Cu")
		(net "P12V_SSD2_R")
	)
	(via
		(at 65.902078 -53.461412)
		(size 0.508)
		(drill 0.254)
		(layers "F.Cu" "B.Cu")
		(net "P12V_SSD2_R")
	)
	(via
		(at 70.35292 -67.951604)
		(size 0.508)
		(drill 0.254)
		(layers "F.Cu" "B.Cu")
		(net "P12V_SSD2_R")
	)
	(via
		(at 68.557902 -53.521102)
		(size 0.508)
		(drill 0.254)
		(layers "F.Cu" "B.Cu")
		(net "P12V_SSD2_R")
	)
	(via
		(at 69.00672 -68.586604)
		(size 0.508)
		(drill 0.254)
		(layers "F.Cu" "B.Cu")
		(net "P12V_SSD2_R")
	)
	(via
		(at 67.382644 -67.10172)
		(size 0.508)
		(drill 0.254)
		(layers "F.Cu" "B.Cu")
		(net "P12V_SSD2_R")
	)
	(via
		(at 73.27392 -42.849038)
		(size 0.508)
		(drill 0.254)
		(layers "F.Cu" "B.Cu")
		(net "P12V_SSD2_R")
	)
	(via
		(at 70.486778 -46.792134)
		(size 0.508)
		(drill 0.254)
		(layers "F.Cu" "B.Cu")
		(net "P12V_SSD2_R")
	)
	(via
		(at 68.557902 -54.156102)
		(size 0.508)
		(drill 0.254)
		(layers "F.Cu" "B.Cu")
		(net "P12V_SSD2_R")
	)
	(via
		(at 69.59219 -53.00853)
		(size 0.508)
		(drill 0.254)
		(layers "F.Cu" "B.Cu")
		(net "P12V_SSD2_R")
	)
	(via
		(at 70.30339 -53.00853)
		(size 0.508)
		(drill 0.254)
		(layers "F.Cu" "B.Cu")
		(net "P12V_SSD2_R")
	)
	(via
		(at 69.71792 -68.586604)
		(size 0.508)
		(drill 0.254)
		(layers "F.Cu" "B.Cu")
		(net "P12V_SSD2_R")
	)
	(via
		(at 70.35292 -68.586604)
		(size 0.508)
		(drill 0.254)
		(layers "F.Cu" "B.Cu")
		(net "P12V_SSD2_R")
	)
	(via
		(at 72.452484 -54.770528)
		(size 0.508)
		(drill 0.254)
		(layers "F.Cu" "B.Cu")
		(net "P12V_SSD2_R")
	)
	(segment
		(start 102.245922 -44.712636)
		(end 103.101648 -43.85691)
		(width 0.13208)
		(layer "F.Cu")
		(net "SSD3_ADC_A1")
	)
	(segment
		(start 102.245922 -45.693838)
		(end 102.245922 -44.712636)
		(width 0.13208)
		(layer "F.Cu")
		(net "SSD3_ADC_A1")
	)
	(segment
		(start 103.843582 -42.84091)
		(end 103.843582 -43.85691)
		(width 0.13208)
		(layer "F.Cu")
		(net "SSD3_ADC_A1")
	)
	(segment
		(start 103.101648 -43.85691)
		(end 103.843582 -43.85691)
		(width 0.13208)
		(layer "F.Cu")
		(net "SSD3_ADC_A1")
	)
	(via
		(at 103.101648 -43.85691)
		(size 0.508)
		(drill 0.254)
		(layers "F.Cu" "B.Cu")
		(net "SSD3_ADC_A1")
	)
	(segment
		(start 96.722438 -44.741592)
		(end 97.738438 -44.741592)
		(width 0.254)
		(layer "F.Cu")
		(net "P12V_SSD3_VIN_N")
	)
	(segment
		(start 97.738438 -44.741592)
		(end 98.07448 -44.741592)
		(width 0.254)
		(layer "F.Cu")
		(net "P12V_SSD3_VIN_N")
	)
	(segment
		(start 98.447352 -45.114464)
		(end 99.026726 -45.693838)
		(width 0.254)
		(layer "F.Cu")
		(net "P12V_SSD3_VIN_N")
	)
	(segment
		(start 99.026726 -45.693838)
		(end 99.445826 -45.693838)
		(width 0.254)
		(layer "F.Cu")
		(net "P12V_SSD3_VIN_N")
	)
	(segment
		(start 98.07448 -44.741592)
		(end 98.447352 -45.114464)
		(width 0.254)
		(layer "F.Cu")
		(net "P12V_SSD3_VIN_N")
	)
	(via
		(at 98.447352 -45.114464)
		(size 0.508)
		(drill 0.254)
		(layers "F.Cu" "B.Cu")
		(net "P12V_SSD3_VIN_N")
	)
	(segment
		(start 24.656542 -49.95291)
		(end 23.596092 -48.89246)
		(width 0.13208)
		(layer "F.Cu")
		(net "SMB_SSD0_ADC_SCL")
	)
	(segment
		(start 23.596092 -48.89246)
		(end 23.596092 -47.843948)
		(width 0.13208)
		(layer "F.Cu")
		(net "SMB_SSD0_ADC_SCL")
	)
	(segment
		(start 25.843738 -49.95291)
		(end 24.656542 -49.95291)
		(width 0.13208)
		(layer "F.Cu")
		(net "SMB_SSD0_ADC_SCL")
	)
	(via
		(at 23.596092 -48.89246)
		(size 0.508)
		(drill 0.254)
		(layers "F.Cu" "B.Cu")
		(net "SMB_SSD0_ADC_SCL")
	)
	(segment
		(start 74.095864 -44.53509)
		(end 73.297034 -43.73626)
		(width 0.254)
		(layer "F.Cu")
		(net "P12V_SSD2_VIN_P")
	)
	(segment
		(start 72.389746 -43.941492)
		(end 71.73849 -43.941492)
		(width 0.254)
		(layer "F.Cu")
		(net "P12V_SSD2_VIN_P")
	)
	(segment
		(start 73.297034 -43.73626)
		(end 72.594978 -43.73626)
		(width 0.254)
		(layer "F.Cu")
		(net "P12V_SSD2_VIN_P")
	)
	(segment
		(start 72.594978 -43.73626)
		(end 72.389746 -43.941492)
		(width 0.254)
		(layer "F.Cu")
		(net "P12V_SSD2_VIN_P")
	)
	(segment
		(start 71.73849 -43.941492)
		(end 71.725282 -43.928284)
		(width 0.254)
		(layer "F.Cu")
		(net "P12V_SSD2_VIN_P")
	)
	(segment
		(start 71.725282 -43.928284)
		(end 71.725282 -42.849038)
		(width 0.254)
		(layer "F.Cu")
		(net "P12V_SSD2_VIN_P")
	)
	(segment
		(start 74.095864 -45.043852)
		(end 74.095864 -44.53509)
		(width 0.254)
		(layer "F.Cu")
		(net "P12V_SSD2_VIN_P")
	)
	(via
		(at 72.594978 -43.73626)
		(size 0.508)
		(drill 0.254)
		(layers "F.Cu" "B.Cu")
		(net "P12V_SSD2_VIN_P")
	)
	(segment
		(start 46.167802 -33.631886)
		(end 45.847508 -33.95218)
		(width 0.13462)
		(layer "F.Cu")
		(net "P5E_PEX0_STN2_TX_C_DN<43>")
	)
	(segment
		(start 41.771824 -33.790128)
		(end 41.26484 -33.790128)
		(width 0.13462)
		(layer "F.Cu")
		(net "P5E_PEX0_STN2_TX_C_DN<43>")
	)
	(segment
		(start 41.933876 -33.95218)
		(end 41.771824 -33.790128)
		(width 0.13462)
		(layer "F.Cu")
		(net "P5E_PEX0_STN2_TX_C_DN<43>")
	)
	(segment
		(start 45.847508 -33.95218)
		(end 41.933876 -33.95218)
		(width 0.13462)
		(layer "F.Cu")
		(net "P5E_PEX0_STN2_TX_C_DN<43>")
	)
	(segment
		(start 15.93596 -30.35808)
		(end 15.768066 -30.190186)
		(width 0.13462)
		(layer "F.Cu")
		(net "P5E_PEX0_STN2_TX_C_DN<45>")
	)
	(segment
		(start 19.841464 -30.35808)
		(end 15.93596 -30.35808)
		(width 0.13462)
		(layer "F.Cu")
		(net "P5E_PEX0_STN2_TX_C_DN<45>")
	)
	(segment
		(start 20.167854 -30.03169)
		(end 19.841464 -30.35808)
		(width 0.13462)
		(layer "F.Cu")
		(net "P5E_PEX0_STN2_TX_C_DN<45>")
	)
	(segment
		(start 15.768066 -30.190186)
		(end 15.264892 -30.190186)
		(width 0.13462)
		(layer "F.Cu")
		(net "P5E_PEX0_STN2_TX_C_DN<45>")
	)
	(segment
		(start 20.167854 -30.94609)
		(end 19.854164 -30.6324)
		(width 0.13462)
		(layer "F.Cu")
		(net "P5E_PEX0_STN2_TX_C_DP<45>")
	)
	(segment
		(start 19.854164 -30.6324)
		(end 15.92326 -30.6324)
		(width 0.13462)
		(layer "F.Cu")
		(net "P5E_PEX0_STN2_TX_C_DP<45>")
	)
	(segment
		(start 15.92326 -30.6324)
		(end 15.765526 -30.790134)
		(width 0.13462)
		(layer "F.Cu")
		(net "P5E_PEX0_STN2_TX_C_DP<45>")
	)
	(segment
		(start 15.765526 -30.790134)
		(end 15.264892 -30.790134)
		(width 0.13462)
		(layer "F.Cu")
		(net "P5E_PEX0_STN2_TX_C_DP<45>")
	)
	(segment
		(start 41.925494 -28.829)
		(end 41.764458 -28.990036)
		(width 0.13462)
		(layer "F.Cu")
		(net "P5E_PEX0_STN2_TX_C_DP<40>")
	)
	(segment
		(start 41.764458 -28.990036)
		(end 41.26484 -28.990036)
		(width 0.13462)
		(layer "F.Cu")
		(net "P5E_PEX0_STN2_TX_C_DP<40>")
	)
	(segment
		(start 43.215052 -28.829)
		(end 41.925494 -28.829)
		(width 0.13462)
		(layer "F.Cu")
		(net "P5E_PEX0_STN2_TX_C_DP<40>")
	)
	(segment
		(start 43.525694 -29.139642)
		(end 43.215052 -28.829)
		(width 0.13462)
		(layer "F.Cu")
		(net "P5E_PEX0_STN2_TX_C_DP<40>")
	)
	(via
		(at 94.224856 -41.241472)
		(size 0.508)
		(drill 0.254)
		(layers "F.Cu" "B.Cu")
		(net "P12V_SSD3")
	)
	(via
		(at 96.688656 -42.009822)
		(size 0.508)
		(drill 0.254)
		(layers "F.Cu" "B.Cu")
		(net "P12V_SSD3")
	)
	(via
		(at 97.962466 -37.523166)
		(size 0.6604)
		(drill 0.3302)
		(layers "F.Cu" "B.Cu")
		(net "P12V_SSD3")
	)
	(via
		(at 94.455234 -21.639022)
		(size 0.508)
		(drill 0.254)
		(layers "F.Cu" "B.Cu")
		(net "P12V_SSD3")
	)
	(via
		(at 94.885256 -41.241472)
		(size 0.508)
		(drill 0.254)
		(layers "F.Cu" "B.Cu")
		(net "P12V_SSD3")
	)
	(via
		(at 94.455234 -20.978622)
		(size 0.508)
		(drill 0.254)
		(layers "F.Cu" "B.Cu")
		(net "P12V_SSD3")
	)
	(via
		(at 96.688656 -41.349422)
		(size 0.508)
		(drill 0.254)
		(layers "F.Cu" "B.Cu")
		(net "P12V_SSD3")
	)
	(via
		(at 96.688656 -42.670222)
		(size 0.508)
		(drill 0.254)
		(layers "F.Cu" "B.Cu")
		(net "P12V_SSD3")
	)
	(via
		(at 94.961964 -43.041316)
		(size 0.6604)
		(drill 0.3302)
		(layers "F.Cu" "B.Cu")
		(net "P12V_SSD3")
	)
	(via
		(at 94.455234 -20.318222)
		(size 0.508)
		(drill 0.254)
		(layers "F.Cu" "B.Cu")
		(net "P12V_SSD3")
	)
	(via
		(at 94.455234 -19.657822)
		(size 0.508)
		(drill 0.254)
		(layers "F.Cu" "B.Cu")
		(net "P12V_SSD3")
	)
	(via
		(at 93.056964 -43.041316)
		(size 0.6604)
		(drill 0.3302)
		(layers "F.Cu" "B.Cu")
		(net "P12V_SSD3")
	)
	(via
		(at 96.688656 -43.305222)
		(size 0.508)
		(drill 0.254)
		(layers "F.Cu" "B.Cu")
		(net "P12V_SSD3")
	)
	(via
		(at 94.455234 -18.997422)
		(size 0.508)
		(drill 0.254)
		(layers "F.Cu" "B.Cu")
		(net "P12V_SSD3")
	)
	(via
		(at 96.421702 -19.14779)
		(size 0.6604)
		(drill 0.3302)
		(layers "F.Cu" "B.Cu")
		(net "P12V_SSD3")
	)
	(via
		(at 68.962016 -43.041316)
		(size 0.6604)
		(drill 0.3302)
		(layers "F.Cu" "B.Cu")
		(net "P12V_SSD2")
	)
	(via
		(at 67.057016 -43.041316)
		(size 0.6604)
		(drill 0.3302)
		(layers "F.Cu" "B.Cu")
		(net "P12V_SSD2")
	)
	(via
		(at 68.455286 -20.318222)
		(size 0.508)
		(drill 0.254)
		(layers "F.Cu" "B.Cu")
		(net "P12V_SSD2")
	)
	(via
		(at 68.455286 -20.978622)
		(size 0.508)
		(drill 0.254)
		(layers "F.Cu" "B.Cu")
		(net "P12V_SSD2")
	)
	(via
		(at 68.455286 -18.997422)
		(size 0.508)
		(drill 0.254)
		(layers "F.Cu" "B.Cu")
		(net "P12V_SSD2")
	)
	(via
		(at 70.688708 -42.009822)
		(size 0.508)
		(drill 0.254)
		(layers "F.Cu" "B.Cu")
		(net "P12V_SSD2")
	)
	(via
		(at 68.885308 -41.241472)
		(size 0.508)
		(drill 0.254)
		(layers "F.Cu" "B.Cu")
		(net "P12V_SSD2")
	)
	(via
		(at 70.688708 -41.349422)
		(size 0.508)
		(drill 0.254)
		(layers "F.Cu" "B.Cu")
		(net "P12V_SSD2")
	)
	(via
		(at 68.224908 -41.241472)
		(size 0.508)
		(drill 0.254)
		(layers "F.Cu" "B.Cu")
		(net "P12V_SSD2")
	)
	(via
		(at 70.00621 -19.14779)
		(size 0.6604)
		(drill 0.3302)
		(layers "F.Cu" "B.Cu")
		(net "P12V_SSD2")
	)
	(via
		(at 68.455286 -21.639022)
		(size 0.508)
		(drill 0.254)
		(layers "F.Cu" "B.Cu")
		(net "P12V_SSD2")
	)
	(via
		(at 70.688708 -43.305222)
		(size 0.508)
		(drill 0.254)
		(layers "F.Cu" "B.Cu")
		(net "P12V_SSD2")
	)
	(via
		(at 70.688708 -42.670222)
		(size 0.508)
		(drill 0.254)
		(layers "F.Cu" "B.Cu")
		(net "P12V_SSD2")
	)
	(via
		(at 69.751702 -33.76168)
		(size 0.6604)
		(drill 0.3302)
		(layers "F.Cu" "B.Cu")
		(net "P12V_SSD2")
	)
	(via
		(at 68.455286 -19.657822)
		(size 0.508)
		(drill 0.254)
		(layers "F.Cu" "B.Cu")
		(net "P12V_SSD2")
	)
	(via
		(at 42.88536 -41.241472)
		(size 0.508)
		(drill 0.254)
		(layers "F.Cu" "B.Cu")
		(net "P12V_SSD1")
	)
	(via
		(at 44.68876 -42.670222)
		(size 0.508)
		(drill 0.254)
		(layers "F.Cu" "B.Cu")
		(net "P12V_SSD1")
	)
	(via
		(at 42.962068 -43.041316)
		(size 0.6604)
		(drill 0.3302)
		(layers "F.Cu" "B.Cu")
		(net "P12V_SSD1")
	)
	(via
		(at 44.68876 -43.305222)
		(size 0.508)
		(drill 0.254)
		(layers "F.Cu" "B.Cu")
		(net "P12V_SSD1")
	)
	(via
		(at 42.455338 -20.978622)
		(size 0.508)
		(drill 0.254)
		(layers "F.Cu" "B.Cu")
		(net "P12V_SSD1")
	)
	(via
		(at 44.68876 -41.349422)
		(size 0.508)
		(drill 0.254)
		(layers "F.Cu" "B.Cu")
		(net "P12V_SSD1")
	)
	(via
		(at 42.455338 -20.318222)
		(size 0.508)
		(drill 0.254)
		(layers "F.Cu" "B.Cu")
		(net "P12V_SSD1")
	)
	(via
		(at 42.455338 -19.657822)
		(size 0.508)
		(drill 0.254)
		(layers "F.Cu" "B.Cu")
		(net "P12V_SSD1")
	)
	(via
		(at 43.250612 -30.598618)
		(size 0.6604)
		(drill 0.3302)
		(layers "F.Cu" "B.Cu")
		(net "P12V_SSD1")
	)
	(via
		(at 43.536108 -39.750238)
		(size 0.6604)
		(drill 0.3302)
		(layers "F.Cu" "B.Cu")
		(net "P12V_SSD1")
	)
	(via
		(at 44.68876 -42.009822)
		(size 0.508)
		(drill 0.254)
		(layers "F.Cu" "B.Cu")
		(net "P12V_SSD1")
	)
	(via
		(at 42.455338 -21.639022)
		(size 0.508)
		(drill 0.254)
		(layers "F.Cu" "B.Cu")
		(net "P12V_SSD1")
	)
	(via
		(at 41.057068 -43.041316)
		(size 0.6604)
		(drill 0.3302)
		(layers "F.Cu" "B.Cu")
		(net "P12V_SSD1")
	)
	(via
		(at 42.455338 -18.997422)
		(size 0.508)
		(drill 0.254)
		(layers "F.Cu" "B.Cu")
		(net "P12V_SSD1")
	)
	(via
		(at 42.22496 -41.241472)
		(size 0.508)
		(drill 0.254)
		(layers "F.Cu" "B.Cu")
		(net "P12V_SSD1")
	)
	(segment
		(start 130.6957 -249.644916)
		(end 130.106928 -250.233688)
		(width 0.13208)
		(layer "F.Cu")
		(net "SMB_PJP1_SCL")
	)
	(segment
		(start 132.428488 -249.644916)
		(end 130.6957 -249.644916)
		(width 0.13208)
		(layer "F.Cu")
		(net "SMB_PJP1_SCL")
	)
	(segment
		(start 130.106928 -250.233688)
		(end 129.074926 -251.26569)
		(width 0.13208)
		(layer "F.Cu")
		(net "SMB_PJP1_SCL")
	)
	(via
		(at 130.106928 -250.233688)
		(size 0.508)
		(drill 0.254)
		(layers "F.Cu" "B.Cu")
		(net "SMB_PJP1_SCL")
	)
	(segment
		(start 31.968694 -32.512762)
		(end 31.968694 -30.971236)
		(width 0.381)
		(layer "F.Cu")
		(net "P3V3_SSD1")
	)
	(segment
		(start 42.233342 -24.790146)
		(end 42.47515 -25.031954)
		(width 0.381)
		(layer "F.Cu")
		(net "P3V3_SSD1")
	)
	(segment
		(start 42.47515 -25.031954)
		(end 43.926506 -25.031954)
		(width 0.381)
		(layer "F.Cu")
		(net "P3V3_SSD1")
	)
	(segment
		(start 31.69412 -34.248852)
		(end 31.69412 -32.787336)
		(width 0.381)
		(layer "F.Cu")
		(net "P3V3_SSD1")
	)
	(segment
		(start 51.624992 -14.735302)
		(end 51.560476 -14.799818)
		(width 0.381)
		(layer "F.Cu")
		(net "P3V3_SSD1")
	)
	(segment
		(start 18.8468 -37.47516)
		(end 18.141188 -37.47516)
		(width 0.4572)
		(layer "F.Cu")
		(net "P3V3_SSD1")
	)
	(segment
		(start 50.056542 -17.419574)
		(end 50.666142 -17.419574)
		(width 0.508)
		(layer "F.Cu")
		(net "P3V3_SSD1")
	)
	(segment
		(start 47.754032 -27.492198)
		(end 47.233078 -26.971244)
		(width 0.381)
		(layer "F.Cu")
		(net "P3V3_SSD1")
	)
	(segment
		(start 41.26484 -24.790146)
		(end 42.233342 -24.790146)
		(width 0.381)
		(layer "F.Cu")
		(net "P3V3_SSD1")
	)
	(segment
		(start 34.179002 -59.978036)
		(end 34.179002 -60.633356)
		(width 0.381)
		(layer "F.Cu")
		(net "P3V3_SSD1")
	)
	(segment
		(start 44.569888 -25.031954)
		(end 43.926506 -25.031954)
		(width 0.4572)
		(layer "F.Cu")
		(net "P3V3_SSD1")
	)
	(segment
		(start 33.37179 -24.807418)
		(end 32.7533 -24.807418)
		(width 0.4572)
		(layer "F.Cu")
		(net "P3V3_SSD1")
	)
	(segment
		(start 47.885604 -27.492198)
		(end 47.754032 -27.492198)
		(width 0.381)
		(layer "F.Cu")
		(net "P3V3_SSD1")
	)
	(segment
		(start 51.560476 -14.799818)
		(end 51.560476 -16.439388)
		(width 0.381)
		(layer "F.Cu")
		(net "P3V3_SSD1")
	)
	(segment
		(start 51.624992 -14.100302)
		(end 51.624992 -14.735302)
		(width 0.381)
		(layer "F.Cu")
		(net "P3V3_SSD1")
	)
	(segment
		(start 31.968694 -30.971236)
		(end 31.394146 -30.396688)
		(width 0.381)
		(layer "F.Cu")
		(net "P3V3_SSD1")
	)
	(segment
		(start 45.471588 -25.742392)
		(end 45.471588 -26.360882)
		(width 0.4572)
		(layer "F.Cu")
		(net "P3V3_SSD1")
	)
	(segment
		(start 31.69412 -32.787336)
		(end 31.968694 -32.512762)
		(width 0.381)
		(layer "F.Cu")
		(net "P3V3_SSD1")
	)
	(segment
		(start 50.669444 -20.467574)
		(end 50.056542 -20.467574)
		(width 0.508)
		(layer "F.Cu")
		(net "P3V3_SSD1")
	)
	(via
		(at 32.493966 -49.574704)
		(size 0.508)
		(drill 0.254)
		(layers "F.Cu" "B.Cu")
		(net "P3V3_SSD1")
	)
	(via
		(at 30.310582 -30.376876)
		(size 0.508)
		(drill 0.254)
		(layers "F.Cu" "B.Cu")
		(net "P3V3_SSD1")
	)
	(via
		(at 51.624992 -14.100302)
		(size 0.508)
		(drill 0.254)
		(layers "F.Cu" "B.Cu")
		(net "P3V3_SSD1")
	)
	(via
		(at 33.763966 -49.574704)
		(size 0.508)
		(drill 0.254)
		(layers "F.Cu" "B.Cu")
		(net "P3V3_SSD1")
	)
	(via
		(at 32.51454 -53.469286)
		(size 0.508)
		(drill 0.254)
		(layers "F.Cu" "B.Cu")
		(net "P3V3_SSD1")
	)
	(via
		(at 32.7533 -24.807418)
		(size 0.508)
		(drill 0.254)
		(layers "F.Cu" "B.Cu")
		(net "P3V3_SSD1")
	)
	(via
		(at 44.569888 -25.031954)
		(size 0.508)
		(drill 0.254)
		(layers "F.Cu" "B.Cu")
		(net "P3V3_SSD1")
	)
	(via
		(at 32.964882 -52.528724)
		(size 0.508)
		(drill 0.254)
		(layers "F.Cu" "B.Cu")
		(net "P3V3_SSD1")
	)
	(via
		(at 34.179002 -60.633356)
		(size 0.508)
		(drill 0.254)
		(layers "F.Cu" "B.Cu")
		(net "P3V3_SSD1")
	)
	(via
		(at 34.276538 -51.320192)
		(size 0.508)
		(drill 0.254)
		(layers "F.Cu" "B.Cu")
		(net "P3V3_SSD1")
	)
	(via
		(at 50.669444 -20.467574)
		(size 0.508)
		(drill 0.254)
		(layers "F.Cu" "B.Cu")
		(net "P3V3_SSD1")
	)
	(via
		(at 18.141188 -37.47516)
		(size 0.508)
		(drill 0.254)
		(layers "F.Cu" "B.Cu")
		(net "P3V3_SSD1")
	)
	(via
		(at 30.310582 -29.614876)
		(size 0.508)
		(drill 0.254)
		(layers "F.Cu" "B.Cu")
		(net "P3V3_SSD1")
	)
	(via
		(at 33.514538 -51.243992)
		(size 0.508)
		(drill 0.254)
		(layers "F.Cu" "B.Cu")
		(net "P3V3_SSD1")
	)
	(via
		(at 34.398966 -49.574704)
		(size 0.508)
		(drill 0.254)
		(layers "F.Cu" "B.Cu")
		(net "P3V3_SSD1")
	)
	(via
		(at 33.599882 -52.528724)
		(size 0.508)
		(drill 0.254)
		(layers "F.Cu" "B.Cu")
		(net "P3V3_SSD1")
	)
	(via
		(at 45.471588 -26.360882)
		(size 0.508)
		(drill 0.254)
		(layers "F.Cu" "B.Cu")
		(net "P3V3_SSD1")
	)
	(via
		(at 47.233078 -26.971244)
		(size 0.508)
		(drill 0.254)
		(layers "F.Cu" "B.Cu")
		(net "P3V3_SSD1")
	)
	(via
		(at 50.666142 -17.419574)
		(size 0.508)
		(drill 0.254)
		(layers "F.Cu" "B.Cu")
		(net "P3V3_SSD1")
	)
	(via
		(at 33.128966 -49.574704)
		(size 0.508)
		(drill 0.254)
		(layers "F.Cu" "B.Cu")
		(net "P3V3_SSD1")
	)
	(via
		(at 33.14954 -53.469286)
		(size 0.508)
		(drill 0.254)
		(layers "F.Cu" "B.Cu")
		(net "P3V3_SSD1")
	)
	(via
		(at 33.514538 -50.608992)
		(size 0.508)
		(drill 0.254)
		(layers "F.Cu" "B.Cu")
		(net "P3V3_SSD1")
	)
	(via
		(at 34.276538 -50.608992)
		(size 0.508)
		(drill 0.254)
		(layers "F.Cu" "B.Cu")
		(net "P3V3_SSD1")
	)
	(segment
		(start 20.604226 -38.322758)
		(end 18.988786 -38.322758)
		(width 0.508)
		(layer "In9.Cu")
		(net "P3V3_SSD1")
	)
	(segment
		(start 21.05406 -37.872924)
		(end 20.604226 -38.322758)
		(width 0.508)
		(layer "In9.Cu")
		(net "P3V3_SSD1")
	)
	(segment
		(start 27.763724 -37.872924)
		(end 21.05406 -37.872924)
		(width 0.508)
		(layer "In9.Cu")
		(net "P3V3_SSD1")
	)
	(segment
		(start 18.988786 -38.322758)
		(end 18.141188 -37.47516)
		(width 0.508)
		(layer "In9.Cu")
		(net "P3V3_SSD1")
	)
	(segment
		(start 35.019488 -24.790146)
		(end 35.002216 -24.807418)
		(width 0.13208)
		(layer "F.Cu")
		(net "PU_CLKREQ1")
	)
	(segment
		(start 36.6649 -24.790146)
		(end 35.019488 -24.790146)
		(width 0.13208)
		(layer "F.Cu")
		(net "PU_CLKREQ1")
	)
	(segment
		(start 34.17189 -24.807418)
		(end 35.002216 -24.807418)
		(width 0.13208)
		(layer "F.Cu")
		(net "PU_CLKREQ1")
	)
	(via
		(at 35.002216 -24.807418)
		(size 0.508)
		(drill 0.254)
		(layers "F.Cu" "B.Cu")
		(net "PU_CLKREQ1")
	)
	(segment
		(start 127.735076 -252.160024)
		(end 129.30251 -252.160024)
		(width 0.13208)
		(layer "F.Cu")
		(net "SMB_PJP1_SDA")
	)
	(segment
		(start 135.348472 -252.184916)
		(end 132.726176 -252.184916)
		(width 0.13208)
		(layer "F.Cu")
		(net "SMB_PJP1_SDA")
	)
	(segment
		(start 129.30251 -252.160024)
		(end 129.327402 -252.184916)
		(width 0.13208)
		(layer "F.Cu")
		(net "SMB_PJP1_SDA")
	)
	(segment
		(start 127.711708 -252.136656)
		(end 127.735076 -252.160024)
		(width 0.13208)
		(layer "F.Cu")
		(net "SMB_PJP1_SDA")
	)
	(segment
		(start 129.327402 -252.184916)
		(end 132.726176 -252.184916)
		(width 0.13208)
		(layer "F.Cu")
		(net "SMB_PJP1_SDA")
	)
	(segment
		(start 127.298196 -252.136656)
		(end 127.711708 -252.136656)
		(width 0.13208)
		(layer "F.Cu")
		(net "SMB_PJP1_SDA")
	)
	(segment
		(start 127.274828 -252.160024)
		(end 127.298196 -252.136656)
		(width 0.13208)
		(layer "F.Cu")
		(net "SMB_PJP1_SDA")
	)
	(via
		(at 132.726176 -252.184916)
		(size 0.508)
		(drill 0.254)
		(layers "F.Cu" "B.Cu")
		(net "SMB_PJP1_SDA")
	)
	(segment
		(start 88.664796 -24.790146)
		(end 87.019384 -24.790146)
		(width 0.13208)
		(layer "F.Cu")
		(net "PU_CLKREQ3")
	)
	(segment
		(start 86.171786 -24.807418)
		(end 87.002112 -24.807418)
		(width 0.13208)
		(layer "F.Cu")
		(net "PU_CLKREQ3")
	)
	(segment
		(start 87.019384 -24.790146)
		(end 87.002112 -24.807418)
		(width 0.13208)
		(layer "F.Cu")
		(net "PU_CLKREQ3")
	)
	(via
		(at 87.002112 -24.807418)
		(size 0.508)
		(drill 0.254)
		(layers "F.Cu" "B.Cu")
		(net "PU_CLKREQ3")
	)
	(segment
		(start 62.664848 -24.790146)
		(end 61.019436 -24.790146)
		(width 0.13208)
		(layer "F.Cu")
		(net "PU_CLKREQ2")
	)
	(segment
		(start 61.002164 -24.807418)
		(end 60.171838 -24.807418)
		(width 0.13208)
		(layer "F.Cu")
		(net "PU_CLKREQ2")
	)
	(segment
		(start 61.019436 -24.790146)
		(end 61.002164 -24.807418)
		(width 0.13208)
		(layer "F.Cu")
		(net "PU_CLKREQ2")
	)
	(via
		(at 61.002164 -24.807418)
		(size 0.508)
		(drill 0.254)
		(layers "F.Cu" "B.Cu")
		(net "PU_CLKREQ2")
	)
	(segment
		(start 94.46641 -23.589996)
		(end 94.46641 -24.134572)
		(width 0.13208)
		(layer "F.Cu")
		(net "DUALPORT_N_SSD3")
	)
	(segment
		(start 97.471484 -24.910542)
		(end 97.471484 -24.942292)
		(width 0.13208)
		(layer "F.Cu")
		(net "DUALPORT_N_SSD3")
	)
	(segment
		(start 97.04959 -24.488648)
		(end 97.471484 -24.910542)
		(width 0.13208)
		(layer "F.Cu")
		(net "DUALPORT_N_SSD3")
	)
	(segment
		(start 98.487484 -24.942292)
		(end 97.471484 -24.942292)
		(width 0.13208)
		(layer "F.Cu")
		(net "DUALPORT_N_SSD3")
	)
	(segment
		(start 94.46641 -24.134572)
		(end 94.820486 -24.488648)
		(width 0.13208)
		(layer "F.Cu")
		(net "DUALPORT_N_SSD3")
	)
	(segment
		(start 93.264736 -23.589996)
		(end 94.46641 -23.589996)
		(width 0.13208)
		(layer "F.Cu")
		(net "DUALPORT_N_SSD3")
	)
	(segment
		(start 94.820486 -24.488648)
		(end 97.04959 -24.488648)
		(width 0.13208)
		(layer "F.Cu")
		(net "DUALPORT_N_SSD3")
	)
	(via
		(at 94.46641 -23.589996)
		(size 0.508)
		(drill 0.254)
		(layers "F.Cu" "B.Cu")
		(net "DUALPORT_N_SSD3")
	)
	(segment
		(start 68.466462 -23.589996)
		(end 68.466462 -24.134572)
		(width 0.13208)
		(layer "F.Cu")
		(net "DUALPORT_N_SSD2")
	)
	(segment
		(start 71.049642 -24.488648)
		(end 71.471536 -24.910542)
		(width 0.13208)
		(layer "F.Cu")
		(net "DUALPORT_N_SSD2")
	)
	(segment
		(start 71.471536 -24.910542)
		(end 71.471536 -24.942292)
		(width 0.13208)
		(layer "F.Cu")
		(net "DUALPORT_N_SSD2")
	)
	(segment
		(start 68.466462 -24.134572)
		(end 68.820538 -24.488648)
		(width 0.13208)
		(layer "F.Cu")
		(net "DUALPORT_N_SSD2")
	)
	(segment
		(start 67.264788 -23.589996)
		(end 68.466462 -23.589996)
		(width 0.13208)
		(layer "F.Cu")
		(net "DUALPORT_N_SSD2")
	)
	(segment
		(start 72.487536 -24.942292)
		(end 71.471536 -24.942292)
		(width 0.13208)
		(layer "F.Cu")
		(net "DUALPORT_N_SSD2")
	)
	(segment
		(start 68.820538 -24.488648)
		(end 71.049642 -24.488648)
		(width 0.13208)
		(layer "F.Cu")
		(net "DUALPORT_N_SSD2")
	)
	(via
		(at 68.466462 -23.589996)
		(size 0.508)
		(drill 0.254)
		(layers "F.Cu" "B.Cu")
		(net "DUALPORT_N_SSD2")
	)
	(segment
		(start 62.664848 -25.390094)
		(end 61.451998 -25.390094)
		(width 0.13208)
		(layer "F.Cu")
		(net "PRSNT_SSD2_N")
	)
	(segment
		(start 60.902088 -26.266394)
		(end 60.12053 -26.266394)
		(width 0.13208)
		(layer "F.Cu")
		(net "PRSNT_SSD2_N")
	)
	(segment
		(start 61.451998 -25.390094)
		(end 60.902088 -25.940004)
		(width 0.13208)
		(layer "F.Cu")
		(net "PRSNT_SSD2_N")
	)
	(segment
		(start 60.902088 -25.940004)
		(end 60.902088 -26.266394)
		(width 0.13208)
		(layer "F.Cu")
		(net "PRSNT_SSD2_N")
	)
	(via
		(at 60.902088 -26.266394)
		(size 0.508)
		(drill 0.254)
		(layers "F.Cu" "B.Cu")
		(net "PRSNT_SSD2_N")
	)
	(segment
		(start 86.902036 -25.940004)
		(end 86.902036 -26.266394)
		(width 0.13208)
		(layer "F.Cu")
		(net "PRSNT_SSD3_N")
	)
	(segment
		(start 88.664796 -25.390094)
		(end 87.451946 -25.390094)
		(width 0.13208)
		(layer "F.Cu")
		(net "PRSNT_SSD3_N")
	)
	(segment
		(start 86.902036 -26.266394)
		(end 86.120478 -26.266394)
		(width 0.13208)
		(layer "F.Cu")
		(net "PRSNT_SSD3_N")
	)
	(segment
		(start 87.451946 -25.390094)
		(end 86.902036 -25.940004)
		(width 0.13208)
		(layer "F.Cu")
		(net "PRSNT_SSD3_N")
	)
	(via
		(at 86.902036 -26.266394)
		(size 0.508)
		(drill 0.254)
		(layers "F.Cu" "B.Cu")
		(net "PRSNT_SSD3_N")
	)
	(segment
		(start 41.764458 -32.589978)
		(end 41.26484 -32.589978)
		(width 0.13462)
		(layer "F.Cu")
		(net "P5E_PEX0_STN2_TX_C_DP<42>")
	)
	(segment
		(start 43.525694 -32.739584)
		(end 43.19651 -32.4104)
		(width 0.13462)
		(layer "F.Cu")
		(net "P5E_PEX0_STN2_TX_C_DP<42>")
	)
	(segment
		(start 41.944036 -32.4104)
		(end 41.764458 -32.589978)
		(width 0.13462)
		(layer "F.Cu")
		(net "P5E_PEX0_STN2_TX_C_DP<42>")
	)
	(segment
		(start 43.19651 -32.4104)
		(end 41.944036 -32.4104)
		(width 0.13462)
		(layer "F.Cu")
		(net "P5E_PEX0_STN2_TX_C_DP<42>")
	)
	(segment
		(start 98.167698 -34.546286)
		(end 97.847912 -34.2265)
		(width 0.13462)
		(layer "F.Cu")
		(net "P5E_PEX0_STN2_TX_C_DP<35>")
	)
	(segment
		(start 93.767656 -34.390076)
		(end 93.264736 -34.390076)
		(width 0.13462)
		(layer "F.Cu")
		(net "P5E_PEX0_STN2_TX_C_DP<35>")
	)
	(segment
		(start 97.847912 -34.2265)
		(end 93.931232 -34.2265)
		(width 0.13462)
		(layer "F.Cu")
		(net "P5E_PEX0_STN2_TX_C_DP<35>")
	)
	(segment
		(start 93.931232 -34.2265)
		(end 93.767656 -34.390076)
		(width 0.13462)
		(layer "F.Cu")
		(net "P5E_PEX0_STN2_TX_C_DP<35>")
	)
	(segment
		(start 67.765422 -30.790134)
		(end 67.264788 -30.790134)
		(width 0.13462)
		(layer "F.Cu")
		(net "P5E_PEX0_STN2_TX_C_DP<37>")
	)
	(segment
		(start 67.923156 -30.6324)
		(end 67.765422 -30.790134)
		(width 0.13462)
		(layer "F.Cu")
		(net "P5E_PEX0_STN2_TX_C_DP<37>")
	)
	(segment
		(start 72.16775 -30.94609)
		(end 71.85406 -30.6324)
		(width 0.13462)
		(layer "F.Cu")
		(net "P5E_PEX0_STN2_TX_C_DP<37>")
	)
	(segment
		(start 71.85406 -30.6324)
		(end 67.923156 -30.6324)
		(width 0.13462)
		(layer "F.Cu")
		(net "P5E_PEX0_STN2_TX_C_DP<37>")
	)
	(segment
		(start 69.525642 -31.825184)
		(end 69.214746 -32.13608)
		(width 0.13462)
		(layer "F.Cu")
		(net "P5E_PEX0_STN2_TX_C_DN<38>")
	)
	(segment
		(start 67.767962 -31.99003)
		(end 67.264788 -31.99003)
		(width 0.13462)
		(layer "F.Cu")
		(net "P5E_PEX0_STN2_TX_C_DN<38>")
	)
	(segment
		(start 67.914012 -32.13608)
		(end 67.767962 -31.99003)
		(width 0.13462)
		(layer "F.Cu")
		(net "P5E_PEX0_STN2_TX_C_DN<38>")
	)
	(segment
		(start 69.214746 -32.13608)
		(end 67.914012 -32.13608)
		(width 0.13462)
		(layer "F.Cu")
		(net "P5E_PEX0_STN2_TX_C_DN<38>")
	)
	(segment
		(start 17.196308 -28.55468)
		(end 15.932658 -28.55468)
		(width 0.13462)
		(layer "F.Cu")
		(net "P5E_PEX0_STN2_TX_C_DN<44>")
	)
	(segment
		(start 15.768066 -28.390088)
		(end 15.264892 -28.390088)
		(width 0.13462)
		(layer "F.Cu")
		(net "P5E_PEX0_STN2_TX_C_DN<44>")
	)
	(segment
		(start 17.525746 -28.225242)
		(end 17.196308 -28.55468)
		(width 0.13462)
		(layer "F.Cu")
		(net "P5E_PEX0_STN2_TX_C_DN<44>")
	)
	(segment
		(start 15.932658 -28.55468)
		(end 15.768066 -28.390088)
		(width 0.13462)
		(layer "F.Cu")
		(net "P5E_PEX0_STN2_TX_C_DN<44>")
	)
	(segment
		(start 67.925442 -28.829)
		(end 67.764406 -28.990036)
		(width 0.13462)
		(layer "F.Cu")
		(net "P5E_PEX0_STN2_TX_C_DP<36>")
	)
	(segment
		(start 69.525642 -29.139642)
		(end 69.215 -28.829)
		(width 0.13462)
		(layer "F.Cu")
		(net "P5E_PEX0_STN2_TX_C_DP<36>")
	)
	(segment
		(start 67.764406 -28.990036)
		(end 67.264788 -28.990036)
		(width 0.13462)
		(layer "F.Cu")
		(net "P5E_PEX0_STN2_TX_C_DP<36>")
	)
	(segment
		(start 69.215 -28.829)
		(end 67.925442 -28.829)
		(width 0.13462)
		(layer "F.Cu")
		(net "P5E_PEX0_STN2_TX_C_DP<36>")
	)
	(segment
		(start 34.90214 -26.266394)
		(end 34.120582 -26.266394)
		(width 0.13208)
		(layer "F.Cu")
		(net "PRSNT_SSD1_N")
	)
	(segment
		(start 36.6649 -25.390094)
		(end 35.45205 -25.390094)
		(width 0.13208)
		(layer "F.Cu")
		(net "PRSNT_SSD1_N")
	)
	(segment
		(start 35.45205 -25.390094)
		(end 34.90214 -25.940004)
		(width 0.13208)
		(layer "F.Cu")
		(net "PRSNT_SSD1_N")
	)
	(segment
		(start 34.90214 -25.940004)
		(end 34.90214 -26.266394)
		(width 0.13208)
		(layer "F.Cu")
		(net "PRSNT_SSD1_N")
	)
	(via
		(at 34.90214 -26.266394)
		(size 0.508)
		(drill 0.254)
		(layers "F.Cu" "B.Cu")
		(net "PRSNT_SSD1_N")
	)
	(segment
		(start 17.525746 -31.825184)
		(end 17.21485 -32.13608)
		(width 0.13462)
		(layer "F.Cu")
		(net "P5E_PEX0_STN2_TX_C_DN<46>")
	)
	(segment
		(start 15.768066 -31.99003)
		(end 15.264892 -31.99003)
		(width 0.13462)
		(layer "F.Cu")
		(net "P5E_PEX0_STN2_TX_C_DN<46>")
	)
	(segment
		(start 15.914116 -32.13608)
		(end 15.768066 -31.99003)
		(width 0.13462)
		(layer "F.Cu")
		(net "P5E_PEX0_STN2_TX_C_DN<46>")
	)
	(segment
		(start 17.21485 -32.13608)
		(end 15.914116 -32.13608)
		(width 0.13462)
		(layer "F.Cu")
		(net "P5E_PEX0_STN2_TX_C_DN<46>")
	)
	(segment
		(start 67.767962 -28.390088)
		(end 67.264788 -28.390088)
		(width 0.13462)
		(layer "F.Cu")
		(net "P5E_PEX0_STN2_TX_C_DN<36>")
	)
	(segment
		(start 67.932554 -28.55468)
		(end 67.767962 -28.390088)
		(width 0.13462)
		(layer "F.Cu")
		(net "P5E_PEX0_STN2_TX_C_DN<36>")
	)
	(segment
		(start 69.196204 -28.55468)
		(end 67.932554 -28.55468)
		(width 0.13462)
		(layer "F.Cu")
		(net "P5E_PEX0_STN2_TX_C_DN<36>")
	)
	(segment
		(start 69.525642 -28.225242)
		(end 69.196204 -28.55468)
		(width 0.13462)
		(layer "F.Cu")
		(net "P5E_PEX0_STN2_TX_C_DN<36>")
	)
	(segment
		(start 41.26484 -23.589996)
		(end 42.466514 -23.589996)
		(width 0.13208)
		(layer "F.Cu")
		(net "DUALPORT_N_SSD1")
	)
	(segment
		(start 45.049694 -24.488648)
		(end 45.471588 -24.910542)
		(width 0.13208)
		(layer "F.Cu")
		(net "DUALPORT_N_SSD1")
	)
	(segment
		(start 45.471588 -24.910542)
		(end 45.471588 -24.942292)
		(width 0.13208)
		(layer "F.Cu")
		(net "DUALPORT_N_SSD1")
	)
	(segment
		(start 42.466514 -24.134572)
		(end 42.82059 -24.488648)
		(width 0.13208)
		(layer "F.Cu")
		(net "DUALPORT_N_SSD1")
	)
	(segment
		(start 46.487588 -24.942292)
		(end 45.471588 -24.942292)
		(width 0.13208)
		(layer "F.Cu")
		(net "DUALPORT_N_SSD1")
	)
	(segment
		(start 42.82059 -24.488648)
		(end 45.049694 -24.488648)
		(width 0.13208)
		(layer "F.Cu")
		(net "DUALPORT_N_SSD1")
	)
	(segment
		(start 42.466514 -23.589996)
		(end 42.466514 -24.134572)
		(width 0.13208)
		(layer "F.Cu")
		(net "DUALPORT_N_SSD1")
	)
	(via
		(at 42.466514 -23.589996)
		(size 0.508)
		(drill 0.254)
		(layers "F.Cu" "B.Cu")
		(net "DUALPORT_N_SSD1")
	)
	(segment
		(start 17.196562 -32.4104)
		(end 15.944088 -32.4104)
		(width 0.13462)
		(layer "F.Cu")
		(net "P5E_PEX0_STN2_TX_C_DP<46>")
	)
	(segment
		(start 15.76451 -32.589978)
		(end 15.264892 -32.589978)
		(width 0.13462)
		(layer "F.Cu")
		(net "P5E_PEX0_STN2_TX_C_DP<46>")
	)
	(segment
		(start 15.944088 -32.4104)
		(end 15.76451 -32.589978)
		(width 0.13462)
		(layer "F.Cu")
		(net "P5E_PEX0_STN2_TX_C_DP<46>")
	)
	(segment
		(start 17.525746 -32.739584)
		(end 17.196562 -32.4104)
		(width 0.13462)
		(layer "F.Cu")
		(net "P5E_PEX0_STN2_TX_C_DP<46>")
	)
	(segment
		(start 45.854112 -30.6324)
		(end 41.923208 -30.6324)
		(width 0.13462)
		(layer "F.Cu")
		(net "P5E_PEX0_STN2_TX_C_DP<41>")
	)
	(segment
		(start 46.167802 -30.94609)
		(end 45.854112 -30.6324)
		(width 0.13462)
		(layer "F.Cu")
		(net "P5E_PEX0_STN2_TX_C_DP<41>")
	)
	(segment
		(start 41.923208 -30.6324)
		(end 41.765474 -30.790134)
		(width 0.13462)
		(layer "F.Cu")
		(net "P5E_PEX0_STN2_TX_C_DP<41>")
	)
	(segment
		(start 41.765474 -30.790134)
		(end 41.26484 -30.790134)
		(width 0.13462)
		(layer "F.Cu")
		(net "P5E_PEX0_STN2_TX_C_DP<41>")
	)
	(segment
		(start 45.841412 -30.35808)
		(end 41.935908 -30.35808)
		(width 0.13462)
		(layer "F.Cu")
		(net "P5E_PEX0_STN2_TX_C_DN<41>")
	)
	(segment
		(start 46.167802 -30.03169)
		(end 45.841412 -30.35808)
		(width 0.13462)
		(layer "F.Cu")
		(net "P5E_PEX0_STN2_TX_C_DN<41>")
	)
	(segment
		(start 41.768014 -30.190186)
		(end 41.26484 -30.190186)
		(width 0.13462)
		(layer "F.Cu")
		(net "P5E_PEX0_STN2_TX_C_DN<41>")
	)
	(segment
		(start 41.935908 -30.35808)
		(end 41.768014 -30.190186)
		(width 0.13462)
		(layer "F.Cu")
		(net "P5E_PEX0_STN2_TX_C_DN<41>")
	)
	(segment
		(start 95.52559 -28.225242)
		(end 95.196152 -28.55468)
		(width 0.13462)
		(layer "F.Cu")
		(net "P5E_PEX0_STN2_TX_C_DN<32>")
	)
	(segment
		(start 93.76791 -28.390088)
		(end 93.264736 -28.390088)
		(width 0.13462)
		(layer "F.Cu")
		(net "P5E_PEX0_STN2_TX_C_DN<32>")
	)
	(segment
		(start 93.932502 -28.55468)
		(end 93.76791 -28.390088)
		(width 0.13462)
		(layer "F.Cu")
		(net "P5E_PEX0_STN2_TX_C_DN<32>")
	)
	(segment
		(start 95.196152 -28.55468)
		(end 93.932502 -28.55468)
		(width 0.13462)
		(layer "F.Cu")
		(net "P5E_PEX0_STN2_TX_C_DN<32>")
	)
	(segment
		(start 69.525642 -32.739584)
		(end 69.196458 -32.4104)
		(width 0.13462)
		(layer "F.Cu")
		(net "P5E_PEX0_STN2_TX_C_DP<38>")
	)
	(segment
		(start 67.943984 -32.4104)
		(end 67.764406 -32.589978)
		(width 0.13462)
		(layer "F.Cu")
		(net "P5E_PEX0_STN2_TX_C_DP<38>")
	)
	(segment
		(start 69.196458 -32.4104)
		(end 67.943984 -32.4104)
		(width 0.13462)
		(layer "F.Cu")
		(net "P5E_PEX0_STN2_TX_C_DP<38>")
	)
	(segment
		(start 67.764406 -32.589978)
		(end 67.264788 -32.589978)
		(width 0.13462)
		(layer "F.Cu")
		(net "P5E_PEX0_STN2_TX_C_DP<38>")
	)
	(segment
		(start 71.84136 -30.35808)
		(end 67.935856 -30.35808)
		(width 0.13462)
		(layer "F.Cu")
		(net "P5E_PEX0_STN2_TX_C_DN<37>")
	)
	(segment
		(start 72.16775 -30.03169)
		(end 71.84136 -30.35808)
		(width 0.13462)
		(layer "F.Cu")
		(net "P5E_PEX0_STN2_TX_C_DN<37>")
	)
	(segment
		(start 67.767962 -30.190186)
		(end 67.264788 -30.190186)
		(width 0.13462)
		(layer "F.Cu")
		(net "P5E_PEX0_STN2_TX_C_DN<37>")
	)
	(segment
		(start 67.935856 -30.35808)
		(end 67.767962 -30.190186)
		(width 0.13462)
		(layer "F.Cu")
		(net "P5E_PEX0_STN2_TX_C_DN<37>")
	)
	(segment
		(start 41.914064 -32.13608)
		(end 41.768014 -31.99003)
		(width 0.13462)
		(layer "F.Cu")
		(net "P5E_PEX0_STN2_TX_C_DN<42>")
	)
	(segment
		(start 41.768014 -31.99003)
		(end 41.26484 -31.99003)
		(width 0.13462)
		(layer "F.Cu")
		(net "P5E_PEX0_STN2_TX_C_DN<42>")
	)
	(segment
		(start 43.214798 -32.13608)
		(end 41.914064 -32.13608)
		(width 0.13462)
		(layer "F.Cu")
		(net "P5E_PEX0_STN2_TX_C_DN<42>")
	)
	(segment
		(start 43.525694 -31.825184)
		(end 43.214798 -32.13608)
		(width 0.13462)
		(layer "F.Cu")
		(net "P5E_PEX0_STN2_TX_C_DN<42>")
	)
	(segment
		(start 95.214694 -32.13608)
		(end 93.91396 -32.13608)
		(width 0.13462)
		(layer "F.Cu")
		(net "P5E_PEX0_STN2_TX_C_DN<34>")
	)
	(segment
		(start 93.76791 -31.99003)
		(end 93.264736 -31.99003)
		(width 0.13462)
		(layer "F.Cu")
		(net "P5E_PEX0_STN2_TX_C_DN<34>")
	)
	(segment
		(start 93.91396 -32.13608)
		(end 93.76791 -31.99003)
		(width 0.13462)
		(layer "F.Cu")
		(net "P5E_PEX0_STN2_TX_C_DN<34>")
	)
	(segment
		(start 95.52559 -31.825184)
		(end 95.214694 -32.13608)
		(width 0.13462)
		(layer "F.Cu")
		(net "P5E_PEX0_STN2_TX_C_DN<34>")
	)
	(segment
		(start 18.980912 -24.488648)
		(end 16.820642 -24.488648)
		(width 0.13208)
		(layer "F.Cu")
		(net "DUALPORT_N_SSD0")
	)
	(segment
		(start 19.47164 -24.942292)
		(end 20.48764 -24.942292)
		(width 0.13208)
		(layer "F.Cu")
		(net "DUALPORT_N_SSD0")
	)
	(segment
		(start 16.466566 -23.589996)
		(end 15.264892 -23.589996)
		(width 0.13208)
		(layer "F.Cu")
		(net "DUALPORT_N_SSD0")
	)
	(segment
		(start 16.466566 -24.134572)
		(end 16.466566 -23.589996)
		(width 0.13208)
		(layer "F.Cu")
		(net "DUALPORT_N_SSD0")
	)
	(segment
		(start 19.47164 -24.942292)
		(end 19.191732 -24.662384)
		(width 0.13208)
		(layer "F.Cu")
		(net "DUALPORT_N_SSD0")
	)
	(segment
		(start 19.191732 -24.662384)
		(end 19.154648 -24.662384)
		(width 0.13208)
		(layer "F.Cu")
		(net "DUALPORT_N_SSD0")
	)
	(segment
		(start 16.820642 -24.488648)
		(end 16.466566 -24.134572)
		(width 0.13208)
		(layer "F.Cu")
		(net "DUALPORT_N_SSD0")
	)
	(segment
		(start 19.154648 -24.662384)
		(end 18.980912 -24.488648)
		(width 0.13208)
		(layer "F.Cu")
		(net "DUALPORT_N_SSD0")
	)
	(via
		(at 16.466566 -23.589996)
		(size 0.508)
		(drill 0.254)
		(layers "F.Cu" "B.Cu")
		(net "DUALPORT_N_SSD0")
	)
	(segment
		(start 97.854008 -30.6324)
		(end 93.923104 -30.6324)
		(width 0.13462)
		(layer "F.Cu")
		(net "P5E_PEX0_STN2_TX_C_DP<33>")
	)
	(segment
		(start 98.167698 -30.94609)
		(end 97.854008 -30.6324)
		(width 0.13462)
		(layer "F.Cu")
		(net "P5E_PEX0_STN2_TX_C_DP<33>")
	)
	(segment
		(start 93.76537 -30.790134)
		(end 93.264736 -30.790134)
		(width 0.13462)
		(layer "F.Cu")
		(net "P5E_PEX0_STN2_TX_C_DP<33>")
	)
	(segment
		(start 93.923104 -30.6324)
		(end 93.76537 -30.790134)
		(width 0.13462)
		(layer "F.Cu")
		(net "P5E_PEX0_STN2_TX_C_DP<33>")
	)
	(segment
		(start 10.664952 -25.390094)
		(end 9.452102 -25.390094)
		(width 0.13208)
		(layer "F.Cu")
		(net "PRSNT_SSD0_N")
	)
	(segment
		(start 8.902192 -25.940004)
		(end 8.902192 -26.266394)
		(width 0.13208)
		(layer "F.Cu")
		(net "PRSNT_SSD0_N")
	)
	(segment
		(start 8.120634 -26.266394)
		(end 8.902192 -26.266394)
		(width 0.13208)
		(layer "F.Cu")
		(net "PRSNT_SSD0_N")
	)
	(segment
		(start 9.452102 -25.390094)
		(end 8.902192 -25.940004)
		(width 0.13208)
		(layer "F.Cu")
		(net "PRSNT_SSD0_N")
	)
	(via
		(at 8.902192 -26.266394)
		(size 0.508)
		(drill 0.254)
		(layers "F.Cu" "B.Cu")
		(net "PRSNT_SSD0_N")
	)
	(segment
		(start 15.771876 -33.790128)
		(end 15.264892 -33.790128)
		(width 0.13462)
		(layer "F.Cu")
		(net "P5E_PEX0_STN2_TX_C_DN<47>")
	)
	(segment
		(start 15.933928 -33.95218)
		(end 15.771876 -33.790128)
		(width 0.13462)
		(layer "F.Cu")
		(net "P5E_PEX0_STN2_TX_C_DN<47>")
	)
	(segment
		(start 19.84756 -33.95218)
		(end 15.933928 -33.95218)
		(width 0.13462)
		(layer "F.Cu")
		(net "P5E_PEX0_STN2_TX_C_DN<47>")
	)
	(segment
		(start 20.167854 -33.631886)
		(end 19.84756 -33.95218)
		(width 0.13462)
		(layer "F.Cu")
		(net "P5E_PEX0_STN2_TX_C_DN<47>")
	)
	(segment
		(start 97.841308 -30.35808)
		(end 93.935804 -30.35808)
		(width 0.13462)
		(layer "F.Cu")
		(net "P5E_PEX0_STN2_TX_C_DN<33>")
	)
	(segment
		(start 93.76791 -30.190186)
		(end 93.264736 -30.190186)
		(width 0.13462)
		(layer "F.Cu")
		(net "P5E_PEX0_STN2_TX_C_DN<33>")
	)
	(segment
		(start 98.167698 -30.03169)
		(end 97.841308 -30.35808)
		(width 0.13462)
		(layer "F.Cu")
		(net "P5E_PEX0_STN2_TX_C_DN<33>")
	)
	(segment
		(start 93.935804 -30.35808)
		(end 93.76791 -30.190186)
		(width 0.13462)
		(layer "F.Cu")
		(net "P5E_PEX0_STN2_TX_C_DN<33>")
	)
	(segment
		(start 41.76776 -34.390076)
		(end 41.26484 -34.390076)
		(width 0.13462)
		(layer "F.Cu")
		(net "P5E_PEX0_STN2_TX_C_DP<43>")
	)
	(segment
		(start 45.848016 -34.2265)
		(end 41.931336 -34.2265)
		(width 0.13462)
		(layer "F.Cu")
		(net "P5E_PEX0_STN2_TX_C_DP<43>")
	)
	(segment
		(start 41.931336 -34.2265)
		(end 41.76776 -34.390076)
		(width 0.13462)
		(layer "F.Cu")
		(net "P5E_PEX0_STN2_TX_C_DP<43>")
	)
	(segment
		(start 46.167802 -34.546286)
		(end 45.848016 -34.2265)
		(width 0.13462)
		(layer "F.Cu")
		(net "P5E_PEX0_STN2_TX_C_DP<43>")
	)
	(segment
		(start 10.664952 -24.790146)
		(end 9.01954 -24.790146)
		(width 0.13208)
		(layer "F.Cu")
		(net "PU_CLKREQ0")
	)
	(segment
		(start 9.002268 -24.807418)
		(end 8.171942 -24.807418)
		(width 0.13208)
		(layer "F.Cu")
		(net "PU_CLKREQ0")
	)
	(segment
		(start 9.01954 -24.790146)
		(end 9.002268 -24.807418)
		(width 0.13208)
		(layer "F.Cu")
		(net "PU_CLKREQ0")
	)
	(via
		(at 9.002268 -24.807418)
		(size 0.508)
		(drill 0.254)
		(layers "F.Cu" "B.Cu")
		(net "PU_CLKREQ0")
	)
	(segment
		(start 95.214948 -28.829)
		(end 93.92539 -28.829)
		(width 0.13462)
		(layer "F.Cu")
		(net "P5E_PEX0_STN2_TX_C_DP<32>")
	)
	(segment
		(start 95.52559 -29.139642)
		(end 95.214948 -28.829)
		(width 0.13462)
		(layer "F.Cu")
		(net "P5E_PEX0_STN2_TX_C_DP<32>")
	)
	(segment
		(start 93.92539 -28.829)
		(end 93.764354 -28.990036)
		(width 0.13462)
		(layer "F.Cu")
		(net "P5E_PEX0_STN2_TX_C_DP<32>")
	)
	(segment
		(start 93.764354 -28.990036)
		(end 93.264736 -28.990036)
		(width 0.13462)
		(layer "F.Cu")
		(net "P5E_PEX0_STN2_TX_C_DP<32>")
	)
	(segment
		(start 15.925546 -28.829)
		(end 15.76451 -28.990036)
		(width 0.13462)
		(layer "F.Cu")
		(net "P5E_PEX0_STN2_TX_C_DP<44>")
	)
	(segment
		(start 17.215104 -28.829)
		(end 15.925546 -28.829)
		(width 0.13462)
		(layer "F.Cu")
		(net "P5E_PEX0_STN2_TX_C_DP<44>")
	)
	(segment
		(start 17.525746 -29.139642)
		(end 17.215104 -28.829)
		(width 0.13462)
		(layer "F.Cu")
		(net "P5E_PEX0_STN2_TX_C_DP<44>")
	)
	(segment
		(start 15.76451 -28.990036)
		(end 15.264892 -28.990036)
		(width 0.13462)
		(layer "F.Cu")
		(net "P5E_PEX0_STN2_TX_C_DP<44>")
	)
	(segment
		(start 67.931284 -34.2265)
		(end 67.767708 -34.390076)
		(width 0.13462)
		(layer "F.Cu")
		(net "P5E_PEX0_STN2_TX_C_DP<39>")
	)
	(segment
		(start 72.16775 -34.546286)
		(end 71.847964 -34.2265)
		(width 0.13462)
		(layer "F.Cu")
		(net "P5E_PEX0_STN2_TX_C_DP<39>")
	)
	(segment
		(start 67.767708 -34.390076)
		(end 67.264788 -34.390076)
		(width 0.13462)
		(layer "F.Cu")
		(net "P5E_PEX0_STN2_TX_C_DP<39>")
	)
	(segment
		(start 71.847964 -34.2265)
		(end 67.931284 -34.2265)
		(width 0.13462)
		(layer "F.Cu")
		(net "P5E_PEX0_STN2_TX_C_DP<39>")
	)
	(segment
		(start 43.525694 -28.225242)
		(end 43.196256 -28.55468)
		(width 0.13462)
		(layer "F.Cu")
		(net "P5E_PEX0_STN2_TX_C_DN<40>")
	)
	(segment
		(start 41.768014 -28.390088)
		(end 41.26484 -28.390088)
		(width 0.13462)
		(layer "F.Cu")
		(net "P5E_PEX0_STN2_TX_C_DN<40>")
	)
	(segment
		(start 41.932606 -28.55468)
		(end 41.768014 -28.390088)
		(width 0.13462)
		(layer "F.Cu")
		(net "P5E_PEX0_STN2_TX_C_DN<40>")
	)
	(segment
		(start 43.196256 -28.55468)
		(end 41.932606 -28.55468)
		(width 0.13462)
		(layer "F.Cu")
		(net "P5E_PEX0_STN2_TX_C_DN<40>")
	)
	(segment
		(start 67.771772 -33.790128)
		(end 67.264788 -33.790128)
		(width 0.13462)
		(layer "F.Cu")
		(net "P5E_PEX0_STN2_TX_C_DN<39>")
	)
	(segment
		(start 72.16775 -33.631886)
		(end 71.847456 -33.95218)
		(width 0.13462)
		(layer "F.Cu")
		(net "P5E_PEX0_STN2_TX_C_DN<39>")
	)
	(segment
		(start 67.933824 -33.95218)
		(end 67.771772 -33.790128)
		(width 0.13462)
		(layer "F.Cu")
		(net "P5E_PEX0_STN2_TX_C_DN<39>")
	)
	(segment
		(start 71.847456 -33.95218)
		(end 67.933824 -33.95218)
		(width 0.13462)
		(layer "F.Cu")
		(net "P5E_PEX0_STN2_TX_C_DN<39>")
	)
	(segment
		(start 95.196406 -32.4104)
		(end 93.943932 -32.4104)
		(width 0.13462)
		(layer "F.Cu")
		(net "P5E_PEX0_STN2_TX_C_DP<34>")
	)
	(segment
		(start 93.764354 -32.589978)
		(end 93.264736 -32.589978)
		(width 0.13462)
		(layer "F.Cu")
		(net "P5E_PEX0_STN2_TX_C_DP<34>")
	)
	(segment
		(start 93.943932 -32.4104)
		(end 93.764354 -32.589978)
		(width 0.13462)
		(layer "F.Cu")
		(net "P5E_PEX0_STN2_TX_C_DP<34>")
	)
	(segment
		(start 95.52559 -32.739584)
		(end 95.196406 -32.4104)
		(width 0.13462)
		(layer "F.Cu")
		(net "P5E_PEX0_STN2_TX_C_DP<34>")
	)
	(segment
		(start 93.77172 -33.790128)
		(end 93.264736 -33.790128)
		(width 0.13462)
		(layer "F.Cu")
		(net "P5E_PEX0_STN2_TX_C_DN<35>")
	)
	(segment
		(start 93.933772 -33.95218)
		(end 93.77172 -33.790128)
		(width 0.13462)
		(layer "F.Cu")
		(net "P5E_PEX0_STN2_TX_C_DN<35>")
	)
	(segment
		(start 98.167698 -33.631886)
		(end 97.847404 -33.95218)
		(width 0.13462)
		(layer "F.Cu")
		(net "P5E_PEX0_STN2_TX_C_DN<35>")
	)
	(segment
		(start 97.847404 -33.95218)
		(end 93.933772 -33.95218)
		(width 0.13462)
		(layer "F.Cu")
		(net "P5E_PEX0_STN2_TX_C_DN<35>")
	)
	(segment
		(start 20.167854 -34.546286)
		(end 19.848068 -34.2265)
		(width 0.13462)
		(layer "F.Cu")
		(net "P5E_PEX0_STN2_TX_C_DP<47>")
	)
	(segment
		(start 15.931388 -34.2265)
		(end 15.767812 -34.390076)
		(width 0.13462)
		(layer "F.Cu")
		(net "P5E_PEX0_STN2_TX_C_DP<47>")
	)
	(segment
		(start 15.767812 -34.390076)
		(end 15.264892 -34.390076)
		(width 0.13462)
		(layer "F.Cu")
		(net "P5E_PEX0_STN2_TX_C_DP<47>")
	)
	(segment
		(start 19.848068 -34.2265)
		(end 15.931388 -34.2265)
		(width 0.13462)
		(layer "F.Cu")
		(net "P5E_PEX0_STN2_TX_C_DP<47>")
	)
	(segment
		(start 445.683132 -96.469962)
		(end 445.879982 -96.273112)
		(width 0.13208)
		(layer "F.Cu")
		(net "P12V_NIC7_OCP")
	)
	(segment
		(start 445.683132 -97.467928)
		(end 445.683132 -96.469962)
		(width 0.13208)
		(layer "F.Cu")
		(net "P12V_NIC7_OCP")
	)
	(segment
		(start 446.150238 -96.002856)
		(end 446.150238 -95.663766)
		(width 0.13208)
		(layer "F.Cu")
		(net "P12V_NIC7_OCP")
	)
	(segment
		(start 445.879982 -96.273112)
		(end 446.150238 -96.002856)
		(width 0.13208)
		(layer "F.Cu")
		(net "P12V_NIC7_OCP")
	)
	(via
		(at 445.879982 -96.273112)
		(size 0.508)
		(drill 0.254)
		(layers "F.Cu" "B.Cu")
		(net "P12V_NIC7_OCP")
	)
	(segment
		(start 357.701342 -139.740894)
		(end 357.049832 -140.392404)
		(width 0.13208)
		(layer "F.Cu")
		(net "P12V_NIC6_SS")
	)
	(segment
		(start 358.034082 -138.267694)
		(end 357.850694 -138.267694)
		(width 0.13208)
		(layer "F.Cu")
		(net "P12V_NIC6_SS")
	)
	(segment
		(start 356.313486 -140.392404)
		(end 357.049832 -140.392404)
		(width 0.13208)
		(layer "F.Cu")
		(net "P12V_NIC6_SS")
	)
	(segment
		(start 357.701342 -138.417046)
		(end 357.701342 -139.740894)
		(width 0.13208)
		(layer "F.Cu")
		(net "P12V_NIC6_SS")
	)
	(segment
		(start 357.850694 -138.267694)
		(end 357.701342 -138.417046)
		(width 0.13208)
		(layer "F.Cu")
		(net "P12V_NIC6_SS")
	)
	(via
		(at 357.049832 -140.392404)
		(size 0.508)
		(drill 0.254)
		(layers "F.Cu" "B.Cu")
		(net "P12V_NIC6_SS")
	)
	(segment
		(start 224.195894 -100.856542)
		(end 224.195894 -100.555552)
		(width 0.13208)
		(layer "F.Cu")
		(net "P12V_NIC3_EN_R")
	)
	(segment
		(start 225.469704 -100.30841)
		(end 226.200462 -99.577652)
		(width 0.13208)
		(layer "F.Cu")
		(net "P12V_NIC3_EN_R")
	)
	(segment
		(start 224.195894 -100.555552)
		(end 224.443036 -100.30841)
		(width 0.13208)
		(layer "F.Cu")
		(net "P12V_NIC3_EN_R")
	)
	(segment
		(start 224.443036 -100.30841)
		(end 225.469704 -100.30841)
		(width 0.13208)
		(layer "F.Cu")
		(net "P12V_NIC3_EN_R")
	)
	(segment
		(start 226.200462 -99.577652)
		(end 227.008944 -98.76917)
		(width 0.13208)
		(layer "F.Cu")
		(net "P12V_NIC3_EN_R")
	)
	(segment
		(start 228.024944 -98.76917)
		(end 227.008944 -98.76917)
		(width 0.13208)
		(layer "F.Cu")
		(net "P12V_NIC3_EN_R")
	)
	(via
		(at 226.200462 -99.577652)
		(size 0.508)
		(drill 0.254)
		(layers "F.Cu" "B.Cu")
		(net "P12V_NIC3_EN_R")
	)
	(via
		(at 135.945626 -143.179038)
		(size 0.508)
		(drill 0.254)
		(layers "F.Cu" "B.Cu")
		(net "P12V_NIC2")
	)
	(via
		(at 135.945626 -141.858238)
		(size 0.508)
		(drill 0.254)
		(layers "F.Cu" "B.Cu")
		(net "P12V_NIC2")
	)
	(via
		(at 161.08299 -144.634204)
		(size 0.508)
		(drill 0.254)
		(layers "F.Cu" "B.Cu")
		(net "P12V_NIC2")
	)
	(via
		(at 135.945626 -142.518638)
		(size 0.508)
		(drill 0.254)
		(layers "F.Cu" "B.Cu")
		(net "P12V_NIC2")
	)
	(via
		(at 160.492948 -144.39265)
		(size 0.508)
		(drill 0.254)
		(layers "F.Cu" "B.Cu")
		(net "P12V_NIC2")
	)
	(via
		(at 159.962088 -144.761712)
		(size 0.508)
		(drill 0.254)
		(layers "F.Cu" "B.Cu")
		(net "P12V_NIC2")
	)
	(via
		(at 135.945626 -141.197838)
		(size 0.508)
		(drill 0.254)
		(layers "F.Cu" "B.Cu")
		(net "P12V_NIC2")
	)
	(via
		(at 160.558226 -145.024348)
		(size 0.508)
		(drill 0.254)
		(layers "F.Cu" "B.Cu")
		(net "P12V_NIC2")
	)
	(via
		(at 159.61995 -145.30578)
		(size 0.508)
		(drill 0.254)
		(layers "F.Cu" "B.Cu")
		(net "P12V_NIC2")
	)
	(via
		(at 138.11504 -143.763238)
		(size 0.6604)
		(drill 0.3302)
		(layers "F.Cu" "B.Cu")
		(net "P12V_NIC2")
	)
	(via
		(at 161.155634 -143.999966)
		(size 0.508)
		(drill 0.254)
		(layers "F.Cu" "B.Cu")
		(net "P12V_NIC2")
	)
	(via
		(at 135.945626 -143.966438)
		(size 0.508)
		(drill 0.254)
		(layers "F.Cu" "B.Cu")
		(net "P12V_NIC2")
	)
	(via
		(at 137.559288 -141.412468)
		(size 0.6604)
		(drill 0.3302)
		(layers "F.Cu" "B.Cu")
		(net "P12V_NIC2")
	)
	(via
		(at 135.945626 -140.537438)
		(size 0.508)
		(drill 0.254)
		(layers "F.Cu" "B.Cu")
		(net "P12V_NIC2")
	)
	(segment
		(start 241.933984 -137.267696)
		(end 241.473736 -137.267696)
		(width 0.13208)
		(layer "F.Cu")
		(net "P12V_NIC4_OCP")
	)
	(segment
		(start 240.213388 -137.344404)
		(end 240.509044 -137.344404)
		(width 0.13208)
		(layer "F.Cu")
		(net "P12V_NIC4_OCP")
	)
	(segment
		(start 241.473736 -137.267696)
		(end 241.293142 -137.44829)
		(width 0.13208)
		(layer "F.Cu")
		(net "P12V_NIC4_OCP")
	)
	(segment
		(start 240.509044 -137.344404)
		(end 240.61293 -137.44829)
		(width 0.13208)
		(layer "F.Cu")
		(net "P12V_NIC4_OCP")
	)
	(segment
		(start 240.61293 -137.44829)
		(end 240.927128 -137.44829)
		(width 0.13208)
		(layer "F.Cu")
		(net "P12V_NIC4_OCP")
	)
	(segment
		(start 241.293142 -137.44829)
		(end 240.927128 -137.44829)
		(width 0.13208)
		(layer "F.Cu")
		(net "P12V_NIC4_OCP")
	)
	(via
		(at 240.927128 -137.44829)
		(size 0.508)
		(drill 0.254)
		(layers "F.Cu" "B.Cu")
		(net "P12V_NIC4_OCP")
	)
	(segment
		(start 222.195898 -100.02647)
		(end 221.674944 -99.505516)
		(width 0.13208)
		(layer "F.Cu")
		(net "P12V_NIC3_SS")
	)
	(segment
		(start 221.674944 -99.505516)
		(end 221.674944 -98.76917)
		(width 0.13208)
		(layer "F.Cu")
		(net "P12V_NIC3_SS")
	)
	(segment
		(start 222.195898 -100.856542)
		(end 222.195898 -100.02647)
		(width 0.13208)
		(layer "F.Cu")
		(net "P12V_NIC3_SS")
	)
	(via
		(at 221.674944 -99.505516)
		(size 0.508)
		(drill 0.254)
		(layers "F.Cu" "B.Cu")
		(net "P12V_NIC3_SS")
	)
	(via
		(at 254.489204 -143.740632)
		(size 0.6604)
		(drill 0.3302)
		(layers "F.Cu" "B.Cu")
		(net "P12V_NIC4")
	)
	(via
		(at 276.062186 -144.761712)
		(size 0.508)
		(drill 0.254)
		(layers "F.Cu" "B.Cu")
		(net "P12V_NIC4")
	)
	(via
		(at 277.183088 -144.634204)
		(size 0.508)
		(drill 0.254)
		(layers "F.Cu" "B.Cu")
		(net "P12V_NIC4")
	)
	(via
		(at 275.720048 -145.30578)
		(size 0.508)
		(drill 0.254)
		(layers "F.Cu" "B.Cu")
		(net "P12V_NIC4")
	)
	(via
		(at 252.045724 -143.966438)
		(size 0.508)
		(drill 0.254)
		(layers "F.Cu" "B.Cu")
		(net "P12V_NIC4")
	)
	(via
		(at 252.045724 -141.197838)
		(size 0.508)
		(drill 0.254)
		(layers "F.Cu" "B.Cu")
		(net "P12V_NIC4")
	)
	(via
		(at 252.045724 -142.518638)
		(size 0.508)
		(drill 0.254)
		(layers "F.Cu" "B.Cu")
		(net "P12V_NIC4")
	)
	(via
		(at 277.255732 -143.999966)
		(size 0.508)
		(drill 0.254)
		(layers "F.Cu" "B.Cu")
		(net "P12V_NIC4")
	)
	(via
		(at 252.045724 -141.858238)
		(size 0.508)
		(drill 0.254)
		(layers "F.Cu" "B.Cu")
		(net "P12V_NIC4")
	)
	(via
		(at 252.045724 -143.179038)
		(size 0.508)
		(drill 0.254)
		(layers "F.Cu" "B.Cu")
		(net "P12V_NIC4")
	)
	(via
		(at 254.104394 -141.047724)
		(size 0.6604)
		(drill 0.3302)
		(layers "F.Cu" "B.Cu")
		(net "P12V_NIC4")
	)
	(via
		(at 252.045724 -140.537438)
		(size 0.508)
		(drill 0.254)
		(layers "F.Cu" "B.Cu")
		(net "P12V_NIC4")
	)
	(via
		(at 276.593046 -144.39265)
		(size 0.508)
		(drill 0.254)
		(layers "F.Cu" "B.Cu")
		(net "P12V_NIC4")
	)
	(via
		(at 276.658324 -145.024348)
		(size 0.508)
		(drill 0.254)
		(layers "F.Cu" "B.Cu")
		(net "P12V_NIC4")
	)
	(segment
		(start 224.722944 -99.212146)
		(end 224.595944 -99.339146)
		(width 0.13208)
		(layer "F.Cu")
		(net "P12V_NIC3_OCP")
	)
	(segment
		(start 224.722944 -98.76917)
		(end 224.722944 -99.212146)
		(width 0.13208)
		(layer "F.Cu")
		(net "P12V_NIC3_OCP")
	)
	(segment
		(start 223.949514 -99.339146)
		(end 224.26295 -99.339146)
		(width 0.13208)
		(layer "F.Cu")
		(net "P12V_NIC3_OCP")
	)
	(segment
		(start 223.195896 -100.092764)
		(end 223.949514 -99.339146)
		(width 0.13208)
		(layer "F.Cu")
		(net "P12V_NIC3_OCP")
	)
	(segment
		(start 223.195896 -100.856542)
		(end 223.195896 -100.092764)
		(width 0.13208)
		(layer "F.Cu")
		(net "P12V_NIC3_OCP")
	)
	(segment
		(start 224.595944 -99.339146)
		(end 224.26295 -99.339146)
		(width 0.13208)
		(layer "F.Cu")
		(net "P12V_NIC3_OCP")
	)
	(via
		(at 224.26295 -99.339146)
		(size 0.508)
		(drill 0.254)
		(layers "F.Cu" "B.Cu")
		(net "P12V_NIC3_OCP")
	)
	(segment
		(start 329.583034 -96.469962)
		(end 329.779884 -96.273112)
		(width 0.13208)
		(layer "F.Cu")
		(net "P12V_NIC5_OCP")
	)
	(segment
		(start 329.583034 -97.467928)
		(end 329.583034 -96.469962)
		(width 0.13208)
		(layer "F.Cu")
		(net "P12V_NIC5_OCP")
	)
	(segment
		(start 330.05014 -96.002856)
		(end 330.05014 -95.663766)
		(width 0.13208)
		(layer "F.Cu")
		(net "P12V_NIC5_OCP")
	)
	(segment
		(start 329.779884 -96.273112)
		(end 330.05014 -96.002856)
		(width 0.13208)
		(layer "F.Cu")
		(net "P12V_NIC5_OCP")
	)
	(via
		(at 329.779884 -96.273112)
		(size 0.508)
		(drill 0.254)
		(layers "F.Cu" "B.Cu")
		(net "P12V_NIC5_OCP")
	)
	(segment
		(start 356.591362 -137.344404)
		(end 356.695248 -137.44829)
		(width 0.13208)
		(layer "F.Cu")
		(net "P12V_NIC6_OCP")
	)
	(segment
		(start 356.313486 -137.344404)
		(end 356.591362 -137.344404)
		(width 0.13208)
		(layer "F.Cu")
		(net "P12V_NIC6_OCP")
	)
	(segment
		(start 356.695248 -137.44829)
		(end 357.027226 -137.44829)
		(width 0.13208)
		(layer "F.Cu")
		(net "P12V_NIC6_OCP")
	)
	(segment
		(start 357.52151 -137.267696)
		(end 357.340916 -137.44829)
		(width 0.13208)
		(layer "F.Cu")
		(net "P12V_NIC6_OCP")
	)
	(segment
		(start 358.034082 -137.267696)
		(end 357.52151 -137.267696)
		(width 0.13208)
		(layer "F.Cu")
		(net "P12V_NIC6_OCP")
	)
	(segment
		(start 357.340916 -137.44829)
		(end 357.027226 -137.44829)
		(width 0.13208)
		(layer "F.Cu")
		(net "P12V_NIC6_OCP")
	)
	(via
		(at 357.027226 -137.44829)
		(size 0.508)
		(drill 0.254)
		(layers "F.Cu" "B.Cu")
		(net "P12V_NIC6_OCP")
	)
	(via
		(at 306.483004 -109.339126)
		(size 0.508)
		(drill 0.254)
		(layers "F.Cu" "B.Cu")
		(net "P12V_NIC5")
	)
	(via
		(at 307.194204 -109.339126)
		(size 0.508)
		(drill 0.254)
		(layers "F.Cu" "B.Cu")
		(net "P12V_NIC5")
	)
	(via
		(at 321.141344 -104.674924)
		(size 0.508)
		(drill 0.254)
		(layers "F.Cu" "B.Cu")
		(net "P12V_NIC5")
	)
	(via
		(at 306.483004 -109.999526)
		(size 0.508)
		(drill 0.254)
		(layers "F.Cu" "B.Cu")
		(net "P12V_NIC5")
	)
	(via
		(at 320.183002 -109.65942)
		(size 0.6604)
		(drill 0.3302)
		(layers "F.Cu" "B.Cu")
		(net "P12V_NIC5")
	)
	(via
		(at 318.32423 -106.549952)
		(size 0.508)
		(drill 0.254)
		(layers "F.Cu" "B.Cu")
		(net "P12V_NIC5")
	)
	(via
		(at 322.155312 -105.737406)
		(size 0.508)
		(drill 0.254)
		(layers "F.Cu" "B.Cu")
		(net "P12V_NIC5")
	)
	(via
		(at 311.698386 -109.759496)
		(size 0.6604)
		(drill 0.3302)
		(layers "F.Cu" "B.Cu")
		(net "P12V_NIC5")
	)
	(via
		(at 306.483004 -111.980726)
		(size 0.508)
		(drill 0.254)
		(layers "F.Cu" "B.Cu")
		(net "P12V_NIC5")
	)
	(via
		(at 318.32423 -107.210352)
		(size 0.508)
		(drill 0.254)
		(layers "F.Cu" "B.Cu")
		(net "P12V_NIC5")
	)
	(via
		(at 322.155312 -106.397806)
		(size 0.508)
		(drill 0.254)
		(layers "F.Cu" "B.Cu")
		(net "P12V_NIC5")
	)
	(via
		(at 322.155312 -107.058206)
		(size 0.508)
		(drill 0.254)
		(layers "F.Cu" "B.Cu")
		(net "P12V_NIC5")
	)
	(via
		(at 306.483004 -111.320326)
		(size 0.508)
		(drill 0.254)
		(layers "F.Cu" "B.Cu")
		(net "P12V_NIC5")
	)
	(via
		(at 307.194204 -111.320326)
		(size 0.508)
		(drill 0.254)
		(layers "F.Cu" "B.Cu")
		(net "P12V_NIC5")
	)
	(via
		(at 307.194204 -109.999526)
		(size 0.508)
		(drill 0.254)
		(layers "F.Cu" "B.Cu")
		(net "P12V_NIC5")
	)
	(via
		(at 306.483004 -110.659926)
		(size 0.508)
		(drill 0.254)
		(layers "F.Cu" "B.Cu")
		(net "P12V_NIC5")
	)
	(via
		(at 320.247772 -106.424984)
		(size 0.6604)
		(drill 0.3302)
		(layers "F.Cu" "B.Cu")
		(net "P12V_NIC5")
	)
	(via
		(at 318.32423 -105.889552)
		(size 0.508)
		(drill 0.254)
		(layers "F.Cu" "B.Cu")
		(net "P12V_NIC5")
	)
	(via
		(at 307.194204 -111.980726)
		(size 0.508)
		(drill 0.254)
		(layers "F.Cu" "B.Cu")
		(net "P12V_NIC5")
	)
	(via
		(at 307.194204 -110.659926)
		(size 0.508)
		(drill 0.254)
		(layers "F.Cu" "B.Cu")
		(net "P12V_NIC5")
	)
	(segment
		(start 448.436238 -95.664274)
		(end 448.436238 -96.416114)
		(width 0.13208)
		(layer "F.Cu")
		(net "P12V_NIC7_EN_R")
	)
	(segment
		(start 448.022726 -96.829626)
		(end 448.436238 -96.416114)
		(width 0.13208)
		(layer "F.Cu")
		(net "P12V_NIC7_EN_R")
	)
	(segment
		(start 448.436238 -95.664274)
		(end 449.452238 -95.664274)
		(width 0.13208)
		(layer "F.Cu")
		(net "P12V_NIC7_EN_R")
	)
	(segment
		(start 446.68313 -97.216468)
		(end 447.069972 -96.829626)
		(width 0.13208)
		(layer "F.Cu")
		(net "P12V_NIC7_EN_R")
	)
	(segment
		(start 446.68313 -97.467928)
		(end 446.68313 -97.216468)
		(width 0.13208)
		(layer "F.Cu")
		(net "P12V_NIC7_EN_R")
	)
	(segment
		(start 447.069972 -96.829626)
		(end 448.022726 -96.829626)
		(width 0.13208)
		(layer "F.Cu")
		(net "P12V_NIC7_EN_R")
	)
	(via
		(at 448.436238 -96.416114)
		(size 0.508)
		(drill 0.254)
		(layers "F.Cu" "B.Cu")
		(net "P12V_NIC7_EN_R")
	)
	(segment
		(start 241.02187 -135.866886)
		(end 240.213388 -135.058404)
		(width 0.13208)
		(layer "F.Cu")
		(net "P12V_NIC4_EN_R")
	)
	(segment
		(start 240.213388 -134.042404)
		(end 240.213388 -135.058404)
		(width 0.13208)
		(layer "F.Cu")
		(net "P12V_NIC4_EN_R")
	)
	(segment
		(start 241.422682 -136.267698)
		(end 241.02187 -135.866886)
		(width 0.13208)
		(layer "F.Cu")
		(net "P12V_NIC4_EN_R")
	)
	(segment
		(start 241.933984 -136.267698)
		(end 241.422682 -136.267698)
		(width 0.13208)
		(layer "F.Cu")
		(net "P12V_NIC4_EN_R")
	)
	(via
		(at 241.02187 -135.866886)
		(size 0.508)
		(drill 0.254)
		(layers "F.Cu" "B.Cu")
		(net "P12V_NIC4_EN_R")
	)
	(segment
		(start 193.7512 -82.168746)
		(end 193.7512 -82.628232)
		(width 0.13208)
		(layer "F.Cu")
		(net "PWRGD_P12V_NIC3_R")
	)
	(segment
		(start 234.949746 -120.781318)
		(end 234.949746 -121.398792)
		(width 0.13208)
		(layer "F.Cu")
		(net "PWRGD_P12V_NIC3_R")
	)
	(segment
		(start 347.693742 -222.38716)
		(end 348.093538 -222.786956)
		(width 0.13208)
		(layer "F.Cu")
		(net "PWRGD_P12V_NIC3_R")
	)
	(segment
		(start 191.12738 -83.924902)
		(end 191.12738 -88.484964)
		(width 0.13208)
		(layer "F.Cu")
		(net "PWRGD_P12V_NIC3_R")
	)
	(segment
		(start 192.54851 -89.906094)
		(end 192.944496 -89.906094)
		(width 0.13208)
		(layer "F.Cu")
		(net "PWRGD_P12V_NIC3_R")
	)
	(segment
		(start 223.706944 -97.96907)
		(end 223.706944 -97.31375)
		(width 0.13208)
		(layer "F.Cu")
		(net "PWRGD_P12V_NIC3_R")
	)
	(segment
		(start 191.12738 -88.484964)
		(end 192.54851 -89.906094)
		(width 0.13208)
		(layer "F.Cu")
		(net "PWRGD_P12V_NIC3_R")
	)
	(segment
		(start 193.7512 -82.628232)
		(end 193.321432 -83.058)
		(width 0.13208)
		(layer "F.Cu")
		(net "PWRGD_P12V_NIC3_R")
	)
	(segment
		(start 193.57975 -81.21904)
		(end 193.57975 -81.997296)
		(width 0.13208)
		(layer "F.Cu")
		(net "PWRGD_P12V_NIC3_R")
	)
	(segment
		(start 193.57975 -81.997296)
		(end 193.7512 -82.168746)
		(width 0.13208)
		(layer "F.Cu")
		(net "PWRGD_P12V_NIC3_R")
	)
	(segment
		(start 193.69913 -81.09966)
		(end 193.57975 -81.21904)
		(width 0.13208)
		(layer "F.Cu")
		(net "PWRGD_P12V_NIC3_R")
	)
	(segment
		(start 191.994282 -83.058)
		(end 191.12738 -83.924902)
		(width 0.13208)
		(layer "F.Cu")
		(net "PWRGD_P12V_NIC3_R")
	)
	(segment
		(start 193.321432 -83.058)
		(end 191.994282 -83.058)
		(width 0.13208)
		(layer "F.Cu")
		(net "PWRGD_P12V_NIC3_R")
	)
	(segment
		(start 194.157346 -81.09966)
		(end 193.69913 -81.09966)
		(width 0.13208)
		(layer "F.Cu")
		(net "PWRGD_P12V_NIC3_R")
	)
	(via
		(at 234.949746 -121.398792)
		(size 0.508)
		(drill 0.254)
		(layers "F.Cu" "B.Cu")
		(net "PWRGD_P12V_NIC3_R")
	)
	(via
		(at 212.340698 -181.29123)
		(size 0.508)
		(drill 0.254)
		(layers "F.Cu" "B.Cu")
		(net "PWRGD_P12V_NIC3_R")
	)
	(via
		(at 192.944496 -89.906094)
		(size 0.508)
		(drill 0.254)
		(layers "F.Cu" "B.Cu")
		(net "PWRGD_P12V_NIC3_R")
	)
	(via
		(at 217.974926 -125.738128)
		(size 0.508)
		(drill 0.254)
		(layers "F.Cu" "B.Cu")
		(net "PWRGD_P12V_NIC3_R")
	)
	(via
		(at 348.093538 -222.786956)
		(size 0.4572)
		(drill 0.254)
		(layers "F.Cu" "B.Cu")
		(net "PWRGD_P12V_NIC3_R")
	)
	(via
		(at 223.706944 -97.31375)
		(size 0.508)
		(drill 0.254)
		(layers "F.Cu" "B.Cu")
		(net "PWRGD_P12V_NIC3_R")
	)
	(segment
		(start 239.8268 -119.253)
		(end 238.720122 -120.359678)
		(width 0.15494)
		(layer "In5.Cu")
		(net "PWRGD_P12V_NIC3_R")
	)
	(segment
		(start 212.416898 -170.837352)
		(end 212.416898 -176.887124)
		(width 0.15494)
		(layer "In5.Cu")
		(net "PWRGD_P12V_NIC3_R")
	)
	(segment
		(start 211.0994 -169.519854)
		(end 212.416898 -170.837352)
		(width 0.15494)
		(layer "In5.Cu")
		(net "PWRGD_P12V_NIC3_R")
	)
	(segment
		(start 239.8268 -113.673382)
		(end 239.8268 -119.253)
		(width 0.15494)
		(layer "In5.Cu")
		(net "PWRGD_P12V_NIC3_R")
	)
	(segment
		(start 217.7288 -132.0419)
		(end 211.0994 -138.672316)
		(width 0.15494)
		(layer "In5.Cu")
		(net "PWRGD_P12V_NIC3_R")
	)
	(segment
		(start 237.130336 -98.942906)
		(end 243.608606 -105.421176)
		(width 0.15494)
		(layer "In5.Cu")
		(net "PWRGD_P12V_NIC3_R")
	)
	(segment
		(start 217.7288 -125.984254)
		(end 217.7288 -132.0419)
		(width 0.15494)
		(layer "In5.Cu")
		(net "PWRGD_P12V_NIC3_R")
	)
	(segment
		(start 238.720122 -120.359678)
		(end 235.98886 -120.359678)
		(width 0.15494)
		(layer "In5.Cu")
		(net "PWRGD_P12V_NIC3_R")
	)
	(segment
		(start 212.416898 -176.887124)
		(end 211.879942 -177.42408)
		(width 0.15494)
		(layer "In5.Cu")
		(net "PWRGD_P12V_NIC3_R")
	)
	(segment
		(start 211.0994 -138.672316)
		(end 211.0994 -169.519854)
		(width 0.15494)
		(layer "In5.Cu")
		(net "PWRGD_P12V_NIC3_R")
	)
	(segment
		(start 225.3361 -98.942906)
		(end 237.130336 -98.942906)
		(width 0.15494)
		(layer "In5.Cu")
		(net "PWRGD_P12V_NIC3_R")
	)
	(segment
		(start 211.879942 -177.42408)
		(end 211.879942 -180.830474)
		(width 0.15494)
		(layer "In5.Cu")
		(net "PWRGD_P12V_NIC3_R")
	)
	(segment
		(start 235.98886 -120.359678)
		(end 234.949746 -121.398792)
		(width 0.15494)
		(layer "In5.Cu")
		(net "PWRGD_P12V_NIC3_R")
	)
	(segment
		(start 243.608606 -109.891576)
		(end 239.8268 -113.673382)
		(width 0.15494)
		(layer "In5.Cu")
		(net "PWRGD_P12V_NIC3_R")
	)
	(segment
		(start 243.608606 -105.421176)
		(end 243.608606 -109.891576)
		(width 0.15494)
		(layer "In5.Cu")
		(net "PWRGD_P12V_NIC3_R")
	)
	(segment
		(start 211.879942 -180.830474)
		(end 212.340698 -181.29123)
		(width 0.15494)
		(layer "In5.Cu")
		(net "PWRGD_P12V_NIC3_R")
	)
	(segment
		(start 223.706944 -97.31375)
		(end 225.3361 -98.942906)
		(width 0.15494)
		(layer "In5.Cu")
		(net "PWRGD_P12V_NIC3_R")
	)
	(segment
		(start 217.974926 -125.738128)
		(end 217.7288 -125.984254)
		(width 0.15494)
		(layer "In5.Cu")
		(net "PWRGD_P12V_NIC3_R")
	)
	(segment
		(start 217.974926 -125.738128)
		(end 225.527362 -125.738128)
		(width 0.15494)
		(layer "In13.Cu")
		(net "PWRGD_P12V_NIC3_R")
	)
	(segment
		(start 234.050332 -122.298206)
		(end 234.949746 -121.398792)
		(width 0.15494)
		(layer "In13.Cu")
		(net "PWRGD_P12V_NIC3_R")
	)
	(segment
		(start 228.967284 -122.298206)
		(end 234.050332 -122.298206)
		(width 0.15494)
		(layer "In13.Cu")
		(net "PWRGD_P12V_NIC3_R")
	)
	(segment
		(start 225.527362 -125.738128)
		(end 228.967284 -122.298206)
		(width 0.15494)
		(layer "In13.Cu")
		(net "PWRGD_P12V_NIC3_R")
	)
	(segment
		(start 359.614724 -222.98787)
		(end 360.227118 -222.375476)
		(width 0.15494)
		(layer "In15.Cu")
		(net "PWRGD_P12V_NIC3_R")
	)
	(segment
		(start 359.173272 -197.810628)
		(end 359.173272 -190.594742)
		(width 0.15494)
		(layer "In15.Cu")
		(net "PWRGD_P12V_NIC3_R")
	)
	(segment
		(start 284.79877 -184.544462)
		(end 282.105862 -181.851554)
		(width 0.15494)
		(layer "In15.Cu")
		(net "PWRGD_P12V_NIC3_R")
	)
	(segment
		(start 360.227118 -222.375476)
		(end 361.50677 -219.285566)
		(width 0.15494)
		(layer "In15.Cu")
		(net "PWRGD_P12V_NIC3_R")
	)
	(segment
		(start 348.288356 -186.672728)
		(end 346.668598 -185.05297)
		(width 0.15494)
		(layer "In15.Cu")
		(net "PWRGD_P12V_NIC3_R")
	)
	(segment
		(start 353.313746 -222.377)
		(end 354.028756 -221.66199)
		(width 0.15494)
		(layer "In15.Cu")
		(net "PWRGD_P12V_NIC3_R")
	)
	(segment
		(start 227.585524 -182.497476)
		(end 213.546944 -182.497476)
		(width 0.15494)
		(layer "In15.Cu")
		(net "PWRGD_P12V_NIC3_R")
	)
	(segment
		(start 235.633514 -182.236364)
		(end 234.107228 -183.76265)
		(width 0.15494)
		(layer "In15.Cu")
		(net "PWRGD_P12V_NIC3_R")
	)
	(segment
		(start 228.850698 -183.76265)
		(end 227.585524 -182.497476)
		(width 0.15494)
		(layer "In15.Cu")
		(net "PWRGD_P12V_NIC3_R")
	)
	(segment
		(start 282.105862 -181.851554)
		(end 253.451614 -181.851554)
		(width 0.15494)
		(layer "In15.Cu")
		(net "PWRGD_P12V_NIC3_R")
	)
	(segment
		(start 358.296464 -189.717934)
		(end 357.475282 -189.717934)
		(width 0.15494)
		(layer "In15.Cu")
		(net "PWRGD_P12V_NIC3_R")
	)
	(segment
		(start 346.668598 -185.05297)
		(end 341.831168 -185.05297)
		(width 0.15494)
		(layer "In15.Cu")
		(net "PWRGD_P12V_NIC3_R")
	)
	(segment
		(start 361.50677 -219.285566)
		(end 361.50677 -200.144126)
		(width 0.15494)
		(layer "In15.Cu")
		(net "PWRGD_P12V_NIC3_R")
	)
	(segment
		(start 220.840046 -93.078046)
		(end 213.601046 -93.078046)
		(width 0.15494)
		(layer "In15.Cu")
		(net "PWRGD_P12V_NIC3_R")
	)
	(segment
		(start 354.430076 -186.672728)
		(end 348.288356 -186.672728)
		(width 0.15494)
		(layer "In15.Cu")
		(net "PWRGD_P12V_NIC3_R")
	)
	(segment
		(start 361.50677 -200.144126)
		(end 359.173272 -197.810628)
		(width 0.15494)
		(layer "In15.Cu")
		(net "PWRGD_P12V_NIC3_R")
	)
	(segment
		(start 348.503494 -222.377)
		(end 351.79 -222.377)
		(width 0.0889)
		(layer "In15.Cu")
		(net "PWRGD_P12V_NIC3_R")
	)
	(segment
		(start 234.107228 -183.76265)
		(end 228.850698 -183.76265)
		(width 0.15494)
		(layer "In15.Cu")
		(net "PWRGD_P12V_NIC3_R")
	)
	(segment
		(start 213.546944 -182.497476)
		(end 212.340698 -181.29123)
		(width 0.15494)
		(layer "In15.Cu")
		(net "PWRGD_P12V_NIC3_R")
	)
	(segment
		(start 212.3948 -91.8718)
		(end 194.910202 -91.8718)
		(width 0.15494)
		(layer "In15.Cu")
		(net "PWRGD_P12V_NIC3_R")
	)
	(segment
		(start 222.38081 -94.61881)
		(end 220.840046 -93.078046)
		(width 0.15494)
		(layer "In15.Cu")
		(net "PWRGD_P12V_NIC3_R")
	)
	(segment
		(start 194.910202 -91.8718)
		(end 192.944496 -89.906094)
		(width 0.15494)
		(layer "In15.Cu")
		(net "PWRGD_P12V_NIC3_R")
	)
	(segment
		(start 223.706944 -96.796606)
		(end 222.38081 -95.470472)
		(width 0.15494)
		(layer "In15.Cu")
		(net "PWRGD_P12V_NIC3_R")
	)
	(segment
		(start 358.52227 -222.98787)
		(end 359.614724 -222.98787)
		(width 0.15494)
		(layer "In15.Cu")
		(net "PWRGD_P12V_NIC3_R")
	)
	(segment
		(start 351.79 -222.377)
		(end 353.313746 -222.377)
		(width 0.15494)
		(layer "In15.Cu")
		(net "PWRGD_P12V_NIC3_R")
	)
	(segment
		(start 223.706944 -97.31375)
		(end 223.706944 -96.796606)
		(width 0.15494)
		(layer "In15.Cu")
		(net "PWRGD_P12V_NIC3_R")
	)
	(segment
		(start 357.19639 -221.66199)
		(end 358.52227 -222.98787)
		(width 0.15494)
		(layer "In15.Cu")
		(net "PWRGD_P12V_NIC3_R")
	)
	(segment
		(start 213.601046 -93.078046)
		(end 212.3948 -91.8718)
		(width 0.15494)
		(layer "In15.Cu")
		(net "PWRGD_P12V_NIC3_R")
	)
	(segment
		(start 348.093538 -222.786956)
		(end 348.503494 -222.377)
		(width 0.0889)
		(layer "In15.Cu")
		(net "PWRGD_P12V_NIC3_R")
	)
	(segment
		(start 341.831168 -185.05297)
		(end 341.32266 -184.544462)
		(width 0.15494)
		(layer "In15.Cu")
		(net "PWRGD_P12V_NIC3_R")
	)
	(segment
		(start 253.451614 -181.851554)
		(end 251.056902 -184.246266)
		(width 0.15494)
		(layer "In15.Cu")
		(net "PWRGD_P12V_NIC3_R")
	)
	(segment
		(start 341.32266 -184.544462)
		(end 284.79877 -184.544462)
		(width 0.15494)
		(layer "In15.Cu")
		(net "PWRGD_P12V_NIC3_R")
	)
	(segment
		(start 222.38081 -95.470472)
		(end 222.38081 -94.61881)
		(width 0.15494)
		(layer "In15.Cu")
		(net "PWRGD_P12V_NIC3_R")
	)
	(segment
		(start 354.028756 -221.66199)
		(end 357.19639 -221.66199)
		(width 0.15494)
		(layer "In15.Cu")
		(net "PWRGD_P12V_NIC3_R")
	)
	(segment
		(start 248.901712 -184.246266)
		(end 246.89181 -182.236364)
		(width 0.15494)
		(layer "In15.Cu")
		(net "PWRGD_P12V_NIC3_R")
	)
	(segment
		(start 251.056902 -184.246266)
		(end 248.901712 -184.246266)
		(width 0.15494)
		(layer "In15.Cu")
		(net "PWRGD_P12V_NIC3_R")
	)
	(segment
		(start 246.89181 -182.236364)
		(end 235.633514 -182.236364)
		(width 0.15494)
		(layer "In15.Cu")
		(net "PWRGD_P12V_NIC3_R")
	)
	(segment
		(start 359.173272 -190.594742)
		(end 358.296464 -189.717934)
		(width 0.15494)
		(layer "In15.Cu")
		(net "PWRGD_P12V_NIC3_R")
	)
	(segment
		(start 357.475282 -189.717934)
		(end 354.430076 -186.672728)
		(width 0.15494)
		(layer "In15.Cu")
		(net "PWRGD_P12V_NIC3_R")
	)
	(segment
		(start 96.834198 -95.663766)
		(end 95.818198 -95.663766)
		(width 0.13208)
		(layer "F.Cu")
		(net "PWRGD_P12V_NIC1")
	)
	(segment
		(start 96.23425 -96.288352)
		(end 95.911162 -96.288352)
		(width 0.13208)
		(layer "F.Cu")
		(net "PWRGD_P12V_NIC1")
	)
	(segment
		(start 96.882966 -96.937068)
		(end 96.23425 -96.288352)
		(width 0.13208)
		(layer "F.Cu")
		(net "PWRGD_P12V_NIC1")
	)
	(segment
		(start 95.911162 -96.288352)
		(end 95.818198 -96.195388)
		(width 0.13208)
		(layer "F.Cu")
		(net "PWRGD_P12V_NIC1")
	)
	(segment
		(start 96.882966 -97.467928)
		(end 96.882966 -96.937068)
		(width 0.13208)
		(layer "F.Cu")
		(net "PWRGD_P12V_NIC1")
	)
	(segment
		(start 95.818198 -95.663766)
		(end 95.818198 -95.71482)
		(width 0.13208)
		(layer "F.Cu")
		(net "PWRGD_P12V_NIC1")
	)
	(segment
		(start 95.818198 -96.195388)
		(end 95.818198 -95.71482)
		(width 0.13208)
		(layer "F.Cu")
		(net "PWRGD_P12V_NIC1")
	)
	(via
		(at 96.23425 -96.288352)
		(size 0.508)
		(drill 0.254)
		(layers "F.Cu" "B.Cu")
		(net "PWRGD_P12V_NIC1")
	)
	(segment
		(start 125.210316 -137.44829)
		(end 124.82703 -137.44829)
		(width 0.13208)
		(layer "F.Cu")
		(net "P12V_NIC2_OCP")
	)
	(segment
		(start 124.217176 -137.44829)
		(end 124.82703 -137.44829)
		(width 0.13208)
		(layer "F.Cu")
		(net "P12V_NIC2_OCP")
	)
	(segment
		(start 125.833886 -137.267696)
		(end 125.39091 -137.267696)
		(width 0.13208)
		(layer "F.Cu")
		(net "P12V_NIC2_OCP")
	)
	(segment
		(start 124.11329 -137.344404)
		(end 124.217176 -137.44829)
		(width 0.13208)
		(layer "F.Cu")
		(net "P12V_NIC2_OCP")
	)
	(segment
		(start 125.39091 -137.267696)
		(end 125.210316 -137.44829)
		(width 0.13208)
		(layer "F.Cu")
		(net "P12V_NIC2_OCP")
	)
	(via
		(at 124.82703 -137.44829)
		(size 0.508)
		(drill 0.254)
		(layers "F.Cu" "B.Cu")
		(net "P12V_NIC2_OCP")
	)
	(segment
		(start 356.313486 -134.042404)
		(end 356.313486 -135.058404)
		(width 0.13208)
		(layer "F.Cu")
		(net "P12V_NIC6_EN_R")
	)
	(segment
		(start 357.121968 -135.866886)
		(end 356.313486 -135.058404)
		(width 0.13208)
		(layer "F.Cu")
		(net "P12V_NIC6_EN_R")
	)
	(segment
		(start 357.52278 -136.267698)
		(end 357.121968 -135.866886)
		(width 0.13208)
		(layer "F.Cu")
		(net "P12V_NIC6_EN_R")
	)
	(segment
		(start 358.034082 -136.267698)
		(end 357.52278 -136.267698)
		(width 0.13208)
		(layer "F.Cu")
		(net "P12V_NIC6_EN_R")
	)
	(via
		(at 357.121968 -135.866886)
		(size 0.508)
		(drill 0.254)
		(layers "F.Cu" "B.Cu")
		(net "P12V_NIC6_EN_R")
	)
	(segment
		(start 241.601244 -138.417046)
		(end 241.601244 -139.740894)
		(width 0.13208)
		(layer "F.Cu")
		(net "P12V_NIC4_SS")
	)
	(segment
		(start 241.933984 -138.267694)
		(end 241.750596 -138.267694)
		(width 0.13208)
		(layer "F.Cu")
		(net "P12V_NIC4_SS")
	)
	(segment
		(start 241.601244 -139.740894)
		(end 240.949734 -140.392404)
		(width 0.13208)
		(layer "F.Cu")
		(net "P12V_NIC4_SS")
	)
	(segment
		(start 240.213388 -140.392404)
		(end 240.949734 -140.392404)
		(width 0.13208)
		(layer "F.Cu")
		(net "P12V_NIC4_SS")
	)
	(segment
		(start 241.750596 -138.267694)
		(end 241.601244 -138.417046)
		(width 0.13208)
		(layer "F.Cu")
		(net "P12V_NIC4_SS")
	)
	(via
		(at 240.949734 -140.392404)
		(size 0.508)
		(drill 0.254)
		(layers "F.Cu" "B.Cu")
		(net "P12V_NIC4_SS")
	)
	(segment
		(start 124.11329 -139.376404)
		(end 124.681996 -139.376404)
		(width 0.13208)
		(layer "F.Cu")
		(net "PWRGD_P12V_NIC2")
	)
	(segment
		(start 124.843794 -138.388852)
		(end 124.843794 -138.824462)
		(width 0.13208)
		(layer "F.Cu")
		(net "PWRGD_P12V_NIC2")
	)
	(segment
		(start 125.833886 -137.767822)
		(end 125.464824 -137.767822)
		(width 0.13208)
		(layer "F.Cu")
		(net "PWRGD_P12V_NIC2")
	)
	(segment
		(start 124.843794 -139.214606)
		(end 124.843794 -138.824462)
		(width 0.13208)
		(layer "F.Cu")
		(net "PWRGD_P12V_NIC2")
	)
	(segment
		(start 124.11329 -138.360404)
		(end 124.11329 -139.376404)
		(width 0.13208)
		(layer "F.Cu")
		(net "PWRGD_P12V_NIC2")
	)
	(segment
		(start 125.464824 -137.767822)
		(end 124.843794 -138.388852)
		(width 0.13208)
		(layer "F.Cu")
		(net "PWRGD_P12V_NIC2")
	)
	(segment
		(start 124.681996 -139.376404)
		(end 124.843794 -139.214606)
		(width 0.13208)
		(layer "F.Cu")
		(net "PWRGD_P12V_NIC2")
	)
	(via
		(at 124.843794 -138.824462)
		(size 0.508)
		(drill 0.254)
		(layers "F.Cu" "B.Cu")
		(net "PWRGD_P12V_NIC2")
	)
	(segment
		(start 216.001346 -106.36504)
		(end 213.265766 -106.36504)
		(width 0.254)
		(layer "F.Cu")
		(net "P12V_NIC3")
	)
	(segment
		(start 213.138766 -106.49204)
		(end 213.138766 -109.058202)
		(width 0.254)
		(layer "F.Cu")
		(net "P12V_NIC3")
	)
	(segment
		(start 213.265766 -106.36504)
		(end 213.138766 -106.49204)
		(width 0.254)
		(layer "F.Cu")
		(net "P12V_NIC3")
	)
	(via
		(at 199.340216 -108.044234)
		(size 0.508)
		(drill 0.254)
		(layers "F.Cu" "B.Cu")
		(net "P12V_NIC3")
	)
	(via
		(at 190.382906 -109.339126)
		(size 0.508)
		(drill 0.254)
		(layers "F.Cu" "B.Cu")
		(net "P12V_NIC3")
	)
	(via
		(at 199.365108 -108.877862)
		(size 0.508)
		(drill 0.254)
		(layers "F.Cu" "B.Cu")
		(net "P12V_NIC3")
	)
	(via
		(at 190.382906 -111.320326)
		(size 0.508)
		(drill 0.254)
		(layers "F.Cu" "B.Cu")
		(net "P12V_NIC3")
	)
	(via
		(at 209.576162 -110.631732)
		(size 0.508)
		(drill 0.254)
		(layers "F.Cu" "B.Cu")
		(net "P12V_NIC3")
	)
	(via
		(at 209.576162 -109.310932)
		(size 0.508)
		(drill 0.254)
		(layers "F.Cu" "B.Cu")
		(net "P12V_NIC3")
	)
	(via
		(at 191.094106 -109.999526)
		(size 0.508)
		(drill 0.254)
		(layers "F.Cu" "B.Cu")
		(net "P12V_NIC3")
	)
	(via
		(at 194.96659 -110.151164)
		(size 0.6604)
		(drill 0.3302)
		(layers "F.Cu" "B.Cu")
		(net "P12V_NIC3")
	)
	(via
		(at 190.382906 -110.659926)
		(size 0.508)
		(drill 0.254)
		(layers "F.Cu" "B.Cu")
		(net "P12V_NIC3")
	)
	(via
		(at 190.382906 -109.999526)
		(size 0.508)
		(drill 0.254)
		(layers "F.Cu" "B.Cu")
		(net "P12V_NIC3")
	)
	(via
		(at 191.094106 -109.339126)
		(size 0.508)
		(drill 0.254)
		(layers "F.Cu" "B.Cu")
		(net "P12V_NIC3")
	)
	(via
		(at 209.576162 -109.971332)
		(size 0.508)
		(drill 0.254)
		(layers "F.Cu" "B.Cu")
		(net "P12V_NIC3")
	)
	(via
		(at 191.094106 -111.980726)
		(size 0.508)
		(drill 0.254)
		(layers "F.Cu" "B.Cu")
		(net "P12V_NIC3")
	)
	(via
		(at 191.094106 -111.320326)
		(size 0.508)
		(drill 0.254)
		(layers "F.Cu" "B.Cu")
		(net "P12V_NIC3")
	)
	(via
		(at 211.170012 -110.664244)
		(size 0.508)
		(drill 0.254)
		(layers "F.Cu" "B.Cu")
		(net "P12V_NIC3")
	)
	(via
		(at 191.094106 -110.659926)
		(size 0.508)
		(drill 0.254)
		(layers "F.Cu" "B.Cu")
		(net "P12V_NIC3")
	)
	(via
		(at 211.170012 -110.003844)
		(size 0.508)
		(drill 0.254)
		(layers "F.Cu" "B.Cu")
		(net "P12V_NIC3")
	)
	(via
		(at 190.382906 -111.980726)
		(size 0.508)
		(drill 0.254)
		(layers "F.Cu" "B.Cu")
		(net "P12V_NIC3")
	)
	(via
		(at 198.318628 -110.09376)
		(size 0.6604)
		(drill 0.3302)
		(layers "F.Cu" "B.Cu")
		(net "P12V_NIC3")
	)
	(via
		(at 211.170012 -109.343444)
		(size 0.508)
		(drill 0.254)
		(layers "F.Cu" "B.Cu")
		(net "P12V_NIC3")
	)
	(segment
		(start 327.008998 -96.374966)
		(end 327.008998 -95.441516)
		(width 0.13208)
		(layer "F.Cu")
		(net "P12V_NIC5_SS")
	)
	(segment
		(start 328.583036 -97.467928)
		(end 328.583036 -97.403412)
		(width 0.13208)
		(layer "F.Cu")
		(net "P12V_NIC5_SS")
	)
	(segment
		(start 328.492358 -97.312734)
		(end 327.946766 -97.312734)
		(width 0.13208)
		(layer "F.Cu")
		(net "P12V_NIC5_SS")
	)
	(segment
		(start 328.583036 -97.403412)
		(end 328.492358 -97.312734)
		(width 0.13208)
		(layer "F.Cu")
		(net "P12V_NIC5_SS")
	)
	(segment
		(start 327.946766 -97.312734)
		(end 327.008998 -96.374966)
		(width 0.13208)
		(layer "F.Cu")
		(net "P12V_NIC5_SS")
	)
	(via
		(at 327.008998 -96.374966)
		(size 0.508)
		(drill 0.254)
		(layers "F.Cu" "B.Cu")
		(net "P12V_NIC5_SS")
	)
	(segment
		(start 332.33614 -96.416114)
		(end 331.922628 -96.829626)
		(width 0.13208)
		(layer "F.Cu")
		(net "P12V_NIC5_EN_R")
	)
	(segment
		(start 332.33614 -96.416114)
		(end 332.33614 -95.664274)
		(width 0.13208)
		(layer "F.Cu")
		(net "P12V_NIC5_EN_R")
	)
	(segment
		(start 330.969874 -96.829626)
		(end 330.583032 -97.216468)
		(width 0.13208)
		(layer "F.Cu")
		(net "P12V_NIC5_EN_R")
	)
	(segment
		(start 330.583032 -97.216468)
		(end 330.583032 -97.467928)
		(width 0.13208)
		(layer "F.Cu")
		(net "P12V_NIC5_EN_R")
	)
	(segment
		(start 331.922628 -96.829626)
		(end 330.969874 -96.829626)
		(width 0.13208)
		(layer "F.Cu")
		(net "P12V_NIC5_EN_R")
	)
	(segment
		(start 333.35214 -95.664274)
		(end 332.33614 -95.664274)
		(width 0.13208)
		(layer "F.Cu")
		(net "P12V_NIC5_EN_R")
	)
	(via
		(at 332.33614 -96.416114)
		(size 0.508)
		(drill 0.254)
		(layers "F.Cu" "B.Cu")
		(net "P12V_NIC5_EN_R")
	)
	(segment
		(start 98.38309 -97.216468)
		(end 98.769932 -96.829626)
		(width 0.13208)
		(layer "F.Cu")
		(net "P12V_NIC1_EN_R")
	)
	(segment
		(start 101.152198 -95.664274)
		(end 100.136198 -95.664274)
		(width 0.13208)
		(layer "F.Cu")
		(net "P12V_NIC1_EN_R")
	)
	(segment
		(start 100.136198 -96.416114)
		(end 100.136198 -95.664274)
		(width 0.13208)
		(layer "F.Cu")
		(net "P12V_NIC1_EN_R")
	)
	(segment
		(start 98.769932 -96.829626)
		(end 99.722686 -96.829626)
		(width 0.13208)
		(layer "F.Cu")
		(net "P12V_NIC1_EN_R")
	)
	(segment
		(start 99.722686 -96.829626)
		(end 100.136198 -96.416114)
		(width 0.13208)
		(layer "F.Cu")
		(net "P12V_NIC1_EN_R")
	)
	(segment
		(start 98.38309 -97.467928)
		(end 98.38309 -97.216468)
		(width 0.13208)
		(layer "F.Cu")
		(net "P12V_NIC1_EN_R")
	)
	(via
		(at 100.136198 -96.416114)
		(size 0.508)
		(drill 0.254)
		(layers "F.Cu" "B.Cu")
		(net "P12V_NIC1_EN_R")
	)
	(segment
		(start 240.943892 -138.824462)
		(end 240.943892 -139.206478)
		(width 0.13208)
		(layer "F.Cu")
		(net "PWRGD_P12V_NIC4")
	)
	(segment
		(start 240.773966 -139.376404)
		(end 240.213388 -139.376404)
		(width 0.13208)
		(layer "F.Cu")
		(net "PWRGD_P12V_NIC4")
	)
	(segment
		(start 241.564922 -137.767822)
		(end 240.943892 -138.388852)
		(width 0.13208)
		(layer "F.Cu")
		(net "PWRGD_P12V_NIC4")
	)
	(segment
		(start 240.943892 -139.206478)
		(end 240.773966 -139.376404)
		(width 0.13208)
		(layer "F.Cu")
		(net "PWRGD_P12V_NIC4")
	)
	(segment
		(start 240.213388 -138.360404)
		(end 240.213388 -139.376404)
		(width 0.13208)
		(layer "F.Cu")
		(net "PWRGD_P12V_NIC4")
	)
	(segment
		(start 240.943892 -138.388852)
		(end 240.943892 -138.824462)
		(width 0.13208)
		(layer "F.Cu")
		(net "PWRGD_P12V_NIC4")
	)
	(segment
		(start 241.933984 -137.767822)
		(end 241.564922 -137.767822)
		(width 0.13208)
		(layer "F.Cu")
		(net "PWRGD_P12V_NIC4")
	)
	(via
		(at 240.943892 -138.824462)
		(size 0.508)
		(drill 0.254)
		(layers "F.Cu" "B.Cu")
		(net "PWRGD_P12V_NIC4")
	)
	(segment
		(start 444.211202 -96.288352)
		(end 444.53429 -96.288352)
		(width 0.13208)
		(layer "F.Cu")
		(net "PWRGD_P12V_NIC7")
	)
	(segment
		(start 445.183006 -97.467928)
		(end 445.183006 -96.937068)
		(width 0.13208)
		(layer "F.Cu")
		(net "PWRGD_P12V_NIC7")
	)
	(segment
		(start 444.118238 -96.195388)
		(end 444.211202 -96.288352)
		(width 0.13208)
		(layer "F.Cu")
		(net "PWRGD_P12V_NIC7")
	)
	(segment
		(start 445.183006 -96.937068)
		(end 444.53429 -96.288352)
		(width 0.13208)
		(layer "F.Cu")
		(net "PWRGD_P12V_NIC7")
	)
	(segment
		(start 444.118238 -95.663766)
		(end 444.118238 -95.71482)
		(width 0.13208)
		(layer "F.Cu")
		(net "PWRGD_P12V_NIC7")
	)
	(segment
		(start 445.134238 -95.663766)
		(end 444.118238 -95.663766)
		(width 0.13208)
		(layer "F.Cu")
		(net "PWRGD_P12V_NIC7")
	)
	(segment
		(start 444.118238 -95.71482)
		(end 444.118238 -96.195388)
		(width 0.13208)
		(layer "F.Cu")
		(net "PWRGD_P12V_NIC7")
	)
	(via
		(at 444.53429 -96.288352)
		(size 0.508)
		(drill 0.254)
		(layers "F.Cu" "B.Cu")
		(net "PWRGD_P12V_NIC7")
	)
	(segment
		(start 125.501146 -138.417046)
		(end 125.501146 -139.740894)
		(width 0.13208)
		(layer "F.Cu")
		(net "P12V_NIC2_SS")
	)
	(segment
		(start 125.650498 -138.267694)
		(end 125.501146 -138.417046)
		(width 0.13208)
		(layer "F.Cu")
		(net "P12V_NIC2_SS")
	)
	(segment
		(start 125.501146 -139.740894)
		(end 124.849636 -140.392404)
		(width 0.13208)
		(layer "F.Cu")
		(net "P12V_NIC2_SS")
	)
	(segment
		(start 125.833886 -138.267694)
		(end 125.650498 -138.267694)
		(width 0.13208)
		(layer "F.Cu")
		(net "P12V_NIC2_SS")
	)
	(segment
		(start 124.11329 -140.392404)
		(end 124.849636 -140.392404)
		(width 0.13208)
		(layer "F.Cu")
		(net "P12V_NIC2_SS")
	)
	(via
		(at 124.849636 -140.392404)
		(size 0.508)
		(drill 0.254)
		(layers "F.Cu" "B.Cu")
		(net "P12V_NIC2_SS")
	)
	(segment
		(start 354.01758 -162.18789)
		(end 354.01758 -160.143698)
		(width 0.13208)
		(layer "F.Cu")
		(net "PWRGD_P12V_NIC6_R")
	)
	(segment
		(start 397.554958 -175.050958)
		(end 387.61162 -165.10762)
		(width 0.13208)
		(layer "F.Cu")
		(net "PWRGD_P12V_NIC6_R")
	)
	(segment
		(start 387.61162 -165.10762)
		(end 356.93731 -165.10762)
		(width 0.13208)
		(layer "F.Cu")
		(net "PWRGD_P12V_NIC6_R")
	)
	(segment
		(start 354.01123 -139.20724)
		(end 354.01123 -157.50794)
		(width 0.13208)
		(layer "F.Cu")
		(net "PWRGD_P12V_NIC6_R")
	)
	(segment
		(start 399.639282 -176.478438)
		(end 399.639282 -175.273716)
		(width 0.13208)
		(layer "F.Cu")
		(net "PWRGD_P12V_NIC6_R")
	)
	(segment
		(start 399.639282 -175.273716)
		(end 399.416524 -175.050958)
		(width 0.13208)
		(layer "F.Cu")
		(net "PWRGD_P12V_NIC6_R")
	)
	(segment
		(start 356.93731 -165.10762)
		(end 354.01758 -162.18789)
		(width 0.13208)
		(layer "F.Cu")
		(net "PWRGD_P12V_NIC6_R")
	)
	(segment
		(start 354.01123 -157.50794)
		(end 355.332284 -158.828994)
		(width 0.13208)
		(layer "F.Cu")
		(net "PWRGD_P12V_NIC6_R")
	)
	(segment
		(start 350.093788 -219.187014)
		(end 350.493584 -218.787218)
		(width 0.13208)
		(layer "F.Cu")
		(net "PWRGD_P12V_NIC6_R")
	)
	(segment
		(start 354.858066 -138.360404)
		(end 354.01123 -139.20724)
		(width 0.13208)
		(layer "F.Cu")
		(net "PWRGD_P12V_NIC6_R")
	)
	(segment
		(start 399.416524 -175.050958)
		(end 397.554958 -175.050958)
		(width 0.13208)
		(layer "F.Cu")
		(net "PWRGD_P12V_NIC6_R")
	)
	(segment
		(start 354.01758 -160.143698)
		(end 355.332284 -158.828994)
		(width 0.13208)
		(layer "F.Cu")
		(net "PWRGD_P12V_NIC6_R")
	)
	(segment
		(start 355.949758 -158.828994)
		(end 355.332284 -158.828994)
		(width 0.13208)
		(layer "F.Cu")
		(net "PWRGD_P12V_NIC6_R")
	)
	(segment
		(start 355.513386 -138.360404)
		(end 354.858066 -138.360404)
		(width 0.13208)
		(layer "F.Cu")
		(net "PWRGD_P12V_NIC6_R")
	)
	(via
		(at 350.493584 -218.787218)
		(size 0.4572)
		(drill 0.254)
		(layers "F.Cu" "B.Cu")
		(net "PWRGD_P12V_NIC6_R")
	)
	(via
		(at 354.858066 -138.360404)
		(size 0.508)
		(drill 0.254)
		(layers "F.Cu" "B.Cu")
		(net "PWRGD_P12V_NIC6_R")
	)
	(via
		(at 355.332284 -158.828994)
		(size 0.508)
		(drill 0.254)
		(layers "F.Cu" "B.Cu")
		(net "PWRGD_P12V_NIC6_R")
	)
	(segment
		(start 355.058218 -218.143582)
		(end 356.531418 -218.143582)
		(width 0.15494)
		(layer "In5.Cu")
		(net "PWRGD_P12V_NIC6_R")
	)
	(segment
		(start 369.470432 -213.342474)
		(end 372.443248 -210.369658)
		(width 0.15494)
		(layer "In5.Cu")
		(net "PWRGD_P12V_NIC6_R")
	)
	(segment
		(start 371.597174 -181.120542)
		(end 370.384324 -179.907692)
		(width 0.15494)
		(layer "In5.Cu")
		(net "PWRGD_P12V_NIC6_R")
	)
	(segment
		(start 372.494302 -208.15046)
		(end 372.494302 -192.065148)
		(width 0.15494)
		(layer "In5.Cu")
		(net "PWRGD_P12V_NIC6_R")
	)
	(segment
		(start 359.524554 -166.234618)
		(end 354.362258 -161.072322)
		(width 0.15494)
		(layer "In5.Cu")
		(net "PWRGD_P12V_NIC6_R")
	)
	(segment
		(start 350.493584 -218.787218)
		(end 350.933004 -219.226638)
		(width 0.15494)
		(layer "In5.Cu")
		(net "PWRGD_P12V_NIC6_R")
	)
	(segment
		(start 350.933004 -219.226638)
		(end 353.975162 -219.226638)
		(width 0.15494)
		(layer "In5.Cu")
		(net "PWRGD_P12V_NIC6_R")
	)
	(segment
		(start 371.597174 -191.16802)
		(end 371.597174 -181.120542)
		(width 0.15494)
		(layer "In5.Cu")
		(net "PWRGD_P12V_NIC6_R")
	)
	(segment
		(start 366.928146 -214.498428)
		(end 368.0841 -213.342474)
		(width 0.15494)
		(layer "In5.Cu")
		(net "PWRGD_P12V_NIC6_R")
	)
	(segment
		(start 368.0841 -213.342474)
		(end 369.470432 -213.342474)
		(width 0.15494)
		(layer "In5.Cu")
		(net "PWRGD_P12V_NIC6_R")
	)
	(segment
		(start 372.443248 -208.201514)
		(end 372.494302 -208.15046)
		(width 0.15494)
		(layer "In5.Cu")
		(net "PWRGD_P12V_NIC6_R")
	)
	(segment
		(start 356.743 -217.932)
		(end 360.8832 -217.932)
		(width 0.15494)
		(layer "In5.Cu")
		(net "PWRGD_P12V_NIC6_R")
	)
	(segment
		(start 372.443248 -210.369658)
		(end 372.443248 -208.201514)
		(width 0.15494)
		(layer "In5.Cu")
		(net "PWRGD_P12V_NIC6_R")
	)
	(segment
		(start 372.494302 -192.065148)
		(end 371.597174 -191.16802)
		(width 0.15494)
		(layer "In5.Cu")
		(net "PWRGD_P12V_NIC6_R")
	)
	(segment
		(start 355.341936 -138.844274)
		(end 354.858066 -138.360404)
		(width 0.15494)
		(layer "In5.Cu")
		(net "PWRGD_P12V_NIC6_R")
	)
	(segment
		(start 365.00689 -166.234618)
		(end 359.524554 -166.234618)
		(width 0.15494)
		(layer "In5.Cu")
		(net "PWRGD_P12V_NIC6_R")
	)
	(segment
		(start 360.8832 -217.932)
		(end 364.316772 -214.498428)
		(width 0.15494)
		(layer "In5.Cu")
		(net "PWRGD_P12V_NIC6_R")
	)
	(segment
		(start 370.384324 -171.612052)
		(end 365.00689 -166.234618)
		(width 0.15494)
		(layer "In5.Cu")
		(net "PWRGD_P12V_NIC6_R")
	)
	(segment
		(start 370.384324 -179.907692)
		(end 370.384324 -171.612052)
		(width 0.15494)
		(layer "In5.Cu")
		(net "PWRGD_P12V_NIC6_R")
	)
	(segment
		(start 354.362258 -143.902938)
		(end 355.341936 -142.92326)
		(width 0.15494)
		(layer "In5.Cu")
		(net "PWRGD_P12V_NIC6_R")
	)
	(segment
		(start 353.975162 -219.226638)
		(end 355.058218 -218.143582)
		(width 0.15494)
		(layer "In5.Cu")
		(net "PWRGD_P12V_NIC6_R")
	)
	(segment
		(start 364.316772 -214.498428)
		(end 366.928146 -214.498428)
		(width 0.15494)
		(layer "In5.Cu")
		(net "PWRGD_P12V_NIC6_R")
	)
	(segment
		(start 356.531418 -218.143582)
		(end 356.743 -217.932)
		(width 0.15494)
		(layer "In5.Cu")
		(net "PWRGD_P12V_NIC6_R")
	)
	(segment
		(start 355.341936 -142.92326)
		(end 355.341936 -138.844274)
		(width 0.15494)
		(layer "In5.Cu")
		(net "PWRGD_P12V_NIC6_R")
	)
	(segment
		(start 354.362258 -161.072322)
		(end 354.362258 -143.902938)
		(width 0.15494)
		(layer "In5.Cu")
		(net "PWRGD_P12V_NIC6_R")
	)
	(segment
		(start 80.461104 -76.444856)
		(end 85.54593 -76.444856)
		(width 0.13208)
		(layer "F.Cu")
		(net "PWRGD_P12V_NIC1_R")
	)
	(segment
		(start 88.67648 -85.3694)
		(end 90.01379 -86.70671)
		(width 0.13208)
		(layer "F.Cu")
		(net "PWRGD_P12V_NIC1_R")
	)
	(segment
		(start 90.01379 -86.70671)
		(end 93.928438 -86.70671)
		(width 0.13208)
		(layer "F.Cu")
		(net "PWRGD_P12V_NIC1_R")
	)
	(segment
		(start 77.366114 -79.539846)
		(end 80.461104 -76.444856)
		(width 0.13208)
		(layer "F.Cu")
		(net "PWRGD_P12V_NIC1_R")
	)
	(segment
		(start 96.227392 -89.005664)
		(end 96.227392 -93.646498)
		(width 0.13208)
		(layer "F.Cu")
		(net "PWRGD_P12V_NIC1_R")
	)
	(segment
		(start 85.54593 -76.444856)
		(end 86.264496 -77.163422)
		(width 0.13208)
		(layer "F.Cu")
		(net "PWRGD_P12V_NIC1_R")
	)
	(segment
		(start 93.928438 -86.70671)
		(end 96.227392 -89.005664)
		(width 0.13208)
		(layer "F.Cu")
		(net "PWRGD_P12V_NIC1_R")
	)
	(segment
		(start 96.227392 -93.646498)
		(end 96.834198 -94.253304)
		(width 0.13208)
		(layer "F.Cu")
		(net "PWRGD_P12V_NIC1_R")
	)
	(segment
		(start 350.093788 -224.786952)
		(end 350.493584 -225.186748)
		(width 0.13208)
		(layer "F.Cu")
		(net "PWRGD_P12V_NIC1_R")
	)
	(segment
		(start 78.057502 -81.09966)
		(end 77.54366 -81.09966)
		(width 0.13208)
		(layer "F.Cu")
		(net "PWRGD_P12V_NIC1_R")
	)
	(segment
		(start 77.54366 -81.09966)
		(end 77.366114 -80.922114)
		(width 0.13208)
		(layer "F.Cu")
		(net "PWRGD_P12V_NIC1_R")
	)
	(segment
		(start 96.834198 -94.253304)
		(end 96.834198 -94.863666)
		(width 0.13208)
		(layer "F.Cu")
		(net "PWRGD_P12V_NIC1_R")
	)
	(segment
		(start 86.264496 -82.957416)
		(end 88.67648 -85.3694)
		(width 0.13208)
		(layer "F.Cu")
		(net "PWRGD_P12V_NIC1_R")
	)
	(segment
		(start 77.366114 -80.922114)
		(end 77.366114 -79.539846)
		(width 0.13208)
		(layer "F.Cu")
		(net "PWRGD_P12V_NIC1_R")
	)
	(segment
		(start 86.264496 -77.163422)
		(end 86.264496 -82.957416)
		(width 0.13208)
		(layer "F.Cu")
		(net "PWRGD_P12V_NIC1_R")
	)
	(segment
		(start 109.136942 -116.630704)
		(end 109.136942 -117.248178)
		(width 0.13208)
		(layer "F.Cu")
		(net "PWRGD_P12V_NIC1_R")
	)
	(via
		(at 109.136942 -117.248178)
		(size 0.508)
		(drill 0.254)
		(layers "F.Cu" "B.Cu")
		(net "PWRGD_P12V_NIC1_R")
	)
	(via
		(at 350.493584 -225.186748)
		(size 0.4572)
		(drill 0.254)
		(layers "F.Cu" "B.Cu")
		(net "PWRGD_P12V_NIC1_R")
	)
	(via
		(at 96.834198 -94.253304)
		(size 0.508)
		(drill 0.254)
		(layers "F.Cu" "B.Cu")
		(net "PWRGD_P12V_NIC1_R")
	)
	(via
		(at 99.43338 -186.14771)
		(size 0.508)
		(drill 0.254)
		(layers "F.Cu" "B.Cu")
		(net "PWRGD_P12V_NIC1_R")
	)
	(via
		(at 88.67648 -85.3694)
		(size 0.508)
		(drill 0.254)
		(layers "F.Cu" "B.Cu")
		(net "PWRGD_P12V_NIC1_R")
	)
	(segment
		(start 81.606644 -114.945922)
		(end 84.475574 -114.945922)
		(width 0.15494)
		(layer "In5.Cu")
		(net "PWRGD_P12V_NIC1_R")
	)
	(segment
		(start 96.487488 -178.906678)
		(end 96.487488 -183.201818)
		(width 0.15494)
		(layer "In5.Cu")
		(net "PWRGD_P12V_NIC1_R")
	)
	(segment
		(start 82.103722 -108.14431)
		(end 80.831436 -109.416596)
		(width 0.15494)
		(layer "In5.Cu")
		(net "PWRGD_P12V_NIC1_R")
	)
	(segment
		(start 88.46058 -126.93777)
		(end 91.63558 -130.11277)
		(width 0.15494)
		(layer "In5.Cu")
		(net "PWRGD_P12V_NIC1_R")
	)
	(segment
		(start 80.831436 -109.416596)
		(end 80.831436 -114.170714)
		(width 0.15494)
		(layer "In5.Cu")
		(net "PWRGD_P12V_NIC1_R")
	)
	(segment
		(start 94.99346 -177.41265)
		(end 96.487488 -178.906678)
		(width 0.15494)
		(layer "In5.Cu")
		(net "PWRGD_P12V_NIC1_R")
	)
	(segment
		(start 84.475574 -114.945922)
		(end 88.46058 -118.930928)
		(width 0.15494)
		(layer "In5.Cu")
		(net "PWRGD_P12V_NIC1_R")
	)
	(segment
		(start 80.831436 -114.170714)
		(end 81.606644 -114.945922)
		(width 0.15494)
		(layer "In5.Cu")
		(net "PWRGD_P12V_NIC1_R")
	)
	(segment
		(start 91.63558 -130.11277)
		(end 91.63558 -133.758432)
		(width 0.15494)
		(layer "In5.Cu")
		(net "PWRGD_P12V_NIC1_R")
	)
	(segment
		(start 94.99346 -141.865096)
		(end 94.99346 -177.41265)
		(width 0.15494)
		(layer "In5.Cu")
		(net "PWRGD_P12V_NIC1_R")
	)
	(segment
		(start 96.487488 -183.201818)
		(end 99.43338 -186.14771)
		(width 0.15494)
		(layer "In5.Cu")
		(net "PWRGD_P12V_NIC1_R")
	)
	(segment
		(start 88.46058 -118.930928)
		(end 88.46058 -126.93777)
		(width 0.15494)
		(layer "In5.Cu")
		(net "PWRGD_P12V_NIC1_R")
	)
	(segment
		(start 82.103722 -91.942158)
		(end 82.103722 -108.14431)
		(width 0.15494)
		(layer "In5.Cu")
		(net "PWRGD_P12V_NIC1_R")
	)
	(segment
		(start 91.63558 -133.758432)
		(end 94.99346 -141.865096)
		(width 0.15494)
		(layer "In5.Cu")
		(net "PWRGD_P12V_NIC1_R")
	)
	(segment
		(start 88.67648 -85.3694)
		(end 82.103722 -91.942158)
		(width 0.15494)
		(layer "In5.Cu")
		(net "PWRGD_P12V_NIC1_R")
	)
	(segment
		(start 109.94517 -116.43995)
		(end 109.136942 -117.248178)
		(width 0.15494)
		(layer "In7.Cu")
		(net "PWRGD_P12V_NIC1_R")
	)
	(segment
		(start 115.246404 -102.013004)
		(end 115.246404 -114.09934)
		(width 0.15494)
		(layer "In7.Cu")
		(net "PWRGD_P12V_NIC1_R")
	)
	(segment
		(start 109.307376 -96.073976)
		(end 115.246404 -102.013004)
		(width 0.15494)
		(layer "In7.Cu")
		(net "PWRGD_P12V_NIC1_R")
	)
	(segment
		(start 112.905794 -116.43995)
		(end 109.94517 -116.43995)
		(width 0.15494)
		(layer "In7.Cu")
		(net "PWRGD_P12V_NIC1_R")
	)
	(segment
		(start 96.834198 -94.253304)
		(end 97.533714 -93.553788)
		(width 0.15494)
		(layer "In7.Cu")
		(net "PWRGD_P12V_NIC1_R")
	)
	(segment
		(start 115.246404 -114.09934)
		(end 112.905794 -116.43995)
		(width 0.15494)
		(layer "In7.Cu")
		(net "PWRGD_P12V_NIC1_R")
	)
	(segment
		(start 104.719628 -96.073976)
		(end 109.307376 -96.073976)
		(width 0.15494)
		(layer "In7.Cu")
		(net "PWRGD_P12V_NIC1_R")
	)
	(segment
		(start 102.19944 -93.553788)
		(end 104.719628 -96.073976)
		(width 0.15494)
		(layer "In7.Cu")
		(net "PWRGD_P12V_NIC1_R")
	)
	(segment
		(start 97.533714 -93.553788)
		(end 102.19944 -93.553788)
		(width 0.15494)
		(layer "In7.Cu")
		(net "PWRGD_P12V_NIC1_R")
	)
	(segment
		(start 120.523 -188.308488)
		(end 124.06249 -191.847978)
		(width 0.15494)
		(layer "In15.Cu")
		(net "PWRGD_P12V_NIC1_R")
	)
	(segment
		(start 357.74884 -175.94961)
		(end 358.615742 -175.94961)
		(width 0.15494)
		(layer "In15.Cu")
		(net "PWRGD_P12V_NIC1_R")
	)
	(segment
		(start 350.890332 -224.79)
		(end 350.493584 -225.186748)
		(width 0.0889)
		(layer "In15.Cu")
		(net "PWRGD_P12V_NIC1_R")
	)
	(segment
		(start 360.164634 -177.498502)
		(end 360.456226 -177.498502)
		(width 0.15494)
		(layer "In15.Cu")
		(net "PWRGD_P12V_NIC1_R")
	)
	(segment
		(start 370.345462 -186.974734)
		(end 370.345462 -212.741256)
		(width 0.15494)
		(layer "In15.Cu")
		(net "PWRGD_P12V_NIC1_R")
	)
	(segment
		(start 358.615742 -175.94961)
		(end 360.164634 -177.498502)
		(width 0.15494)
		(layer "In15.Cu")
		(net "PWRGD_P12V_NIC1_R")
	)
	(segment
		(start 261.129272 -173.63313)
		(end 343.921334 -173.63313)
		(width 0.15494)
		(layer "In15.Cu")
		(net "PWRGD_P12V_NIC1_R")
	)
	(segment
		(start 99.43338 -186.14771)
		(end 102.97287 -189.6872)
		(width 0.15494)
		(layer "In15.Cu")
		(net "PWRGD_P12V_NIC1_R")
	)
	(segment
		(start 124.06249 -191.847978)
		(end 124.06249 -193.27876)
		(width 0.15494)
		(layer "In15.Cu")
		(net "PWRGD_P12V_NIC1_R")
	)
	(segment
		(start 179.19827 -178.562508)
		(end 179.19827 -177.974244)
		(width 0.15494)
		(layer "In15.Cu")
		(net "PWRGD_P12V_NIC1_R")
	)
	(segment
		(start 231.56799 -175.274478)
		(end 259.487924 -175.274478)
		(width 0.15494)
		(layer "In15.Cu")
		(net "PWRGD_P12V_NIC1_R")
	)
	(segment
		(start 366.904778 -182.099712)
		(end 366.904778 -183.53405)
		(width 0.15494)
		(layer "In15.Cu")
		(net "PWRGD_P12V_NIC1_R")
	)
	(segment
		(start 369.62207 -221.80296)
		(end 362.26623 -229.1588)
		(width 0.15494)
		(layer "In15.Cu")
		(net "PWRGD_P12V_NIC1_R")
	)
	(segment
		(start 136.761728 -197.078854)
		(end 137.68197 -196.6976)
		(width 0.15494)
		(layer "In15.Cu")
		(net "PWRGD_P12V_NIC1_R")
	)
	(segment
		(start 361.783122 -178.825398)
		(end 363.630464 -178.825398)
		(width 0.15494)
		(layer "In15.Cu")
		(net "PWRGD_P12V_NIC1_R")
	)
	(segment
		(start 230.300022 -174.00651)
		(end 231.56799 -175.274478)
		(width 0.15494)
		(layer "In15.Cu")
		(net "PWRGD_P12V_NIC1_R")
	)
	(segment
		(start 362.26623 -229.1588)
		(end 361.527344 -229.1588)
		(width 0.15494)
		(layer "In15.Cu")
		(net "PWRGD_P12V_NIC1_R")
	)
	(segment
		(start 218.80195 -174.00651)
		(end 230.300022 -174.00651)
		(width 0.15494)
		(layer "In15.Cu")
		(net "PWRGD_P12V_NIC1_R")
	)
	(segment
		(start 112.547146 -189.6872)
		(end 113.925858 -188.308488)
		(width 0.15494)
		(layer "In15.Cu")
		(net "PWRGD_P12V_NIC1_R")
	)
	(segment
		(start 127.862584 -197.078854)
		(end 136.761728 -197.078854)
		(width 0.15494)
		(layer "In15.Cu")
		(net "PWRGD_P12V_NIC1_R")
	)
	(segment
		(start 360.456226 -177.498502)
		(end 361.783122 -178.825398)
		(width 0.15494)
		(layer "In15.Cu")
		(net "PWRGD_P12V_NIC1_R")
	)
	(segment
		(start 343.921334 -173.63313)
		(end 346.198698 -175.910494)
		(width 0.15494)
		(layer "In15.Cu")
		(net "PWRGD_P12V_NIC1_R")
	)
	(segment
		(start 181.66334 -176.126648)
		(end 182.703724 -175.086264)
		(width 0.15494)
		(layer "In15.Cu")
		(net "PWRGD_P12V_NIC1_R")
	)
	(segment
		(start 361.527344 -229.1588)
		(end 361.500674 -229.13213)
		(width 0.15494)
		(layer "In15.Cu")
		(net "PWRGD_P12V_NIC1_R")
	)
	(segment
		(start 361.500674 -229.13213)
		(end 357.454454 -229.13213)
		(width 0.15494)
		(layer "In15.Cu")
		(net "PWRGD_P12V_NIC1_R")
	)
	(segment
		(start 166.696898 -191.06388)
		(end 179.19827 -178.562508)
		(width 0.15494)
		(layer "In15.Cu")
		(net "PWRGD_P12V_NIC1_R")
	)
	(segment
		(start 137.68197 -196.6976)
		(end 140.590778 -196.6976)
		(width 0.15494)
		(layer "In15.Cu")
		(net "PWRGD_P12V_NIC1_R")
	)
	(segment
		(start 217.722196 -175.086264)
		(end 218.80195 -174.00651)
		(width 0.15494)
		(layer "In15.Cu")
		(net "PWRGD_P12V_NIC1_R")
	)
	(segment
		(start 182.703724 -175.086264)
		(end 217.722196 -175.086264)
		(width 0.15494)
		(layer "In15.Cu")
		(net "PWRGD_P12V_NIC1_R")
	)
	(segment
		(start 351.7138 -224.79)
		(end 350.890332 -224.79)
		(width 0.0889)
		(layer "In15.Cu")
		(net "PWRGD_P12V_NIC1_R")
	)
	(segment
		(start 259.487924 -175.274478)
		(end 261.129272 -173.63313)
		(width 0.15494)
		(layer "In15.Cu")
		(net "PWRGD_P12V_NIC1_R")
	)
	(segment
		(start 146.224498 -191.06388)
		(end 166.696898 -191.06388)
		(width 0.15494)
		(layer "In15.Cu")
		(net "PWRGD_P12V_NIC1_R")
	)
	(segment
		(start 179.19827 -177.974244)
		(end 180.60924 -176.563274)
		(width 0.15494)
		(layer "In15.Cu")
		(net "PWRGD_P12V_NIC1_R")
	)
	(segment
		(start 124.06249 -193.27876)
		(end 127.862584 -197.078854)
		(width 0.15494)
		(layer "In15.Cu")
		(net "PWRGD_P12V_NIC1_R")
	)
	(segment
		(start 353.112324 -224.79)
		(end 351.7138 -224.79)
		(width 0.15494)
		(layer "In15.Cu")
		(net "PWRGD_P12V_NIC1_R")
	)
	(segment
		(start 113.925858 -188.308488)
		(end 120.523 -188.308488)
		(width 0.15494)
		(layer "In15.Cu")
		(net "PWRGD_P12V_NIC1_R")
	)
	(segment
		(start 346.198698 -175.910494)
		(end 357.709724 -175.910494)
		(width 0.15494)
		(layer "In15.Cu")
		(net "PWRGD_P12V_NIC1_R")
	)
	(segment
		(start 370.345462 -212.741256)
		(end 369.62207 -213.464648)
		(width 0.15494)
		(layer "In15.Cu")
		(net "PWRGD_P12V_NIC1_R")
	)
	(segment
		(start 366.904778 -183.53405)
		(end 370.345462 -186.974734)
		(width 0.15494)
		(layer "In15.Cu")
		(net "PWRGD_P12V_NIC1_R")
	)
	(segment
		(start 102.97287 -189.6872)
		(end 112.547146 -189.6872)
		(width 0.15494)
		(layer "In15.Cu")
		(net "PWRGD_P12V_NIC1_R")
	)
	(segment
		(start 140.590778 -196.6976)
		(end 146.224498 -191.06388)
		(width 0.15494)
		(layer "In15.Cu")
		(net "PWRGD_P12V_NIC1_R")
	)
	(segment
		(start 363.630464 -178.825398)
		(end 366.904778 -182.099712)
		(width 0.15494)
		(layer "In15.Cu")
		(net "PWRGD_P12V_NIC1_R")
	)
	(segment
		(start 357.454454 -229.13213)
		(end 353.112324 -224.79)
		(width 0.15494)
		(layer "In15.Cu")
		(net "PWRGD_P12V_NIC1_R")
	)
	(segment
		(start 180.60924 -176.563274)
		(end 181.66334 -176.126648)
		(width 0.15494)
		(layer "In15.Cu")
		(net "PWRGD_P12V_NIC1_R")
	)
	(segment
		(start 369.62207 -213.464648)
		(end 369.62207 -221.80296)
		(width 0.15494)
		(layer "In15.Cu")
		(net "PWRGD_P12V_NIC1_R")
	)
	(segment
		(start 357.709724 -175.910494)
		(end 357.74884 -175.94961)
		(width 0.15494)
		(layer "In15.Cu")
		(net "PWRGD_P12V_NIC1_R")
	)
	(segment
		(start 444.046864 -97.312734)
		(end 443.109096 -96.374966)
		(width 0.13208)
		(layer "F.Cu")
		(net "P12V_NIC7_SS")
	)
	(segment
		(start 444.592456 -97.312734)
		(end 444.046864 -97.312734)
		(width 0.13208)
		(layer "F.Cu")
		(net "P12V_NIC7_SS")
	)
	(segment
		(start 444.683134 -97.467928)
		(end 444.683134 -97.403412)
		(width 0.13208)
		(layer "F.Cu")
		(net "P12V_NIC7_SS")
	)
	(segment
		(start 444.683134 -97.403412)
		(end 444.592456 -97.312734)
		(width 0.13208)
		(layer "F.Cu")
		(net "P12V_NIC7_SS")
	)
	(segment
		(start 443.109096 -96.374966)
		(end 443.109096 -95.441516)
		(width 0.13208)
		(layer "F.Cu")
		(net "P12V_NIC7_SS")
	)
	(via
		(at 443.109096 -96.374966)
		(size 0.508)
		(drill 0.254)
		(layers "F.Cu" "B.Cu")
		(net "P12V_NIC7_SS")
	)
	(segment
		(start 97.383092 -97.467928)
		(end 97.383092 -96.469962)
		(width 0.13208)
		(layer "F.Cu")
		(net "P12V_NIC1_OCP")
	)
	(segment
		(start 97.850198 -96.002856)
		(end 97.850198 -95.663766)
		(width 0.13208)
		(layer "F.Cu")
		(net "P12V_NIC1_OCP")
	)
	(segment
		(start 97.383092 -96.469962)
		(end 97.579942 -96.273112)
		(width 0.13208)
		(layer "F.Cu")
		(net "P12V_NIC1_OCP")
	)
	(segment
		(start 97.579942 -96.273112)
		(end 97.850198 -96.002856)
		(width 0.13208)
		(layer "F.Cu")
		(net "P12V_NIC1_OCP")
	)
	(via
		(at 97.579942 -96.273112)
		(size 0.508)
		(drill 0.254)
		(layers "F.Cu" "B.Cu")
		(net "P12V_NIC1_OCP")
	)
	(via
		(at 368.145822 -142.518638)
		(size 0.508)
		(drill 0.254)
		(layers "F.Cu" "B.Cu")
		(net "P12V_NIC6")
	)
	(via
		(at 370.623084 -143.655542)
		(size 0.6604)
		(drill 0.3302)
		(layers "F.Cu" "B.Cu")
		(net "P12V_NIC6")
	)
	(via
		(at 368.145822 -143.966438)
		(size 0.508)
		(drill 0.254)
		(layers "F.Cu" "B.Cu")
		(net "P12V_NIC6")
	)
	(via
		(at 392.758422 -145.024348)
		(size 0.508)
		(drill 0.254)
		(layers "F.Cu" "B.Cu")
		(net "P12V_NIC6")
	)
	(via
		(at 368.145822 -141.858238)
		(size 0.508)
		(drill 0.254)
		(layers "F.Cu" "B.Cu")
		(net "P12V_NIC6")
	)
	(via
		(at 393.283186 -144.634204)
		(size 0.508)
		(drill 0.254)
		(layers "F.Cu" "B.Cu")
		(net "P12V_NIC6")
	)
	(via
		(at 391.846816 -145.329148)
		(size 0.508)
		(drill 0.254)
		(layers "F.Cu" "B.Cu")
		(net "P12V_NIC6")
	)
	(via
		(at 368.145822 -143.179038)
		(size 0.508)
		(drill 0.254)
		(layers "F.Cu" "B.Cu")
		(net "P12V_NIC6")
	)
	(via
		(at 393.35583 -143.999966)
		(size 0.508)
		(drill 0.254)
		(layers "F.Cu" "B.Cu")
		(net "P12V_NIC6")
	)
	(via
		(at 368.145822 -141.197838)
		(size 0.508)
		(drill 0.254)
		(layers "F.Cu" "B.Cu")
		(net "P12V_NIC6")
	)
	(via
		(at 370.067332 -141.304518)
		(size 0.6604)
		(drill 0.3302)
		(layers "F.Cu" "B.Cu")
		(net "P12V_NIC6")
	)
	(via
		(at 368.145822 -140.537438)
		(size 0.508)
		(drill 0.254)
		(layers "F.Cu" "B.Cu")
		(net "P12V_NIC6")
	)
	(via
		(at 392.162284 -144.761712)
		(size 0.508)
		(drill 0.254)
		(layers "F.Cu" "B.Cu")
		(net "P12V_NIC6")
	)
	(via
		(at 392.693144 -144.39265)
		(size 0.508)
		(drill 0.254)
		(layers "F.Cu" "B.Cu")
		(net "P12V_NIC6")
	)
	(segment
		(start 123.31319 -138.360404)
		(end 122.65787 -138.360404)
		(width 0.13208)
		(layer "F.Cu")
		(net "PWRGD_P12V_NIC2_R")
	)
	(segment
		(start 349.293942 -223.187006)
		(end 349.693738 -223.586802)
		(width 0.13208)
		(layer "F.Cu")
		(net "PWRGD_P12V_NIC2_R")
	)
	(segment
		(start 123.749562 -158.828994)
		(end 123.132088 -158.828994)
		(width 0.13208)
		(layer "F.Cu")
		(net "PWRGD_P12V_NIC2_R")
	)
	(segment
		(start 167.439086 -176.478438)
		(end 167.439086 -175.730154)
		(width 0.13208)
		(layer "F.Cu")
		(net "PWRGD_P12V_NIC2_R")
	)
	(via
		(at 132.117084 -238.567214)
		(size 0.508)
		(drill 0.254)
		(layers "F.Cu" "B.Cu")
		(net "PWRGD_P12V_NIC2_R")
	)
	(via
		(at 137.947654 -177.488088)
		(size 0.508)
		(drill 0.254)
		(layers "F.Cu" "B.Cu")
		(net "PWRGD_P12V_NIC2_R")
	)
	(via
		(at 167.439086 -175.730154)
		(size 0.508)
		(drill 0.254)
		(layers "F.Cu" "B.Cu")
		(net "PWRGD_P12V_NIC2_R")
	)
	(via
		(at 123.132088 -158.828994)
		(size 0.508)
		(drill 0.254)
		(layers "F.Cu" "B.Cu")
		(net "PWRGD_P12V_NIC2_R")
	)
	(via
		(at 349.693738 -223.586802)
		(size 0.4572)
		(drill 0.254)
		(layers "F.Cu" "B.Cu")
		(net "PWRGD_P12V_NIC2_R")
	)
	(via
		(at 122.65787 -138.360404)
		(size 0.508)
		(drill 0.254)
		(layers "F.Cu" "B.Cu")
		(net "PWRGD_P12V_NIC2_R")
	)
	(segment
		(start 122.47499 -138.543284)
		(end 122.65787 -138.360404)
		(width 0.15494)
		(layer "In5.Cu")
		(net "PWRGD_P12V_NIC2_R")
	)
	(segment
		(start 136.026652 -164.236654)
		(end 138.018012 -166.228014)
		(width 0.15494)
		(layer "In5.Cu")
		(net "PWRGD_P12V_NIC2_R")
	)
	(segment
		(start 129.887218 -213.960964)
		(end 129.887218 -211.53628)
		(width 0.15494)
		(layer "In5.Cu")
		(net "PWRGD_P12V_NIC2_R")
	)
	(segment
		(start 129.887218 -211.53628)
		(end 130.255518 -211.16798)
		(width 0.15494)
		(layer "In5.Cu")
		(net "PWRGD_P12V_NIC2_R")
	)
	(segment
		(start 122.174 -157.870906)
		(end 122.174 -139.270232)
		(width 0.15494)
		(layer "In5.Cu")
		(net "PWRGD_P12V_NIC2_R")
	)
	(segment
		(start 132.117084 -238.567214)
		(end 132.117084 -230.999284)
		(width 0.15494)
		(layer "In5.Cu")
		(net "PWRGD_P12V_NIC2_R")
	)
	(segment
		(start 132.051298 -200.841102)
		(end 132.051298 -200.120504)
		(width 0.15494)
		(layer "In5.Cu")
		(net "PWRGD_P12V_NIC2_R")
	)
	(segment
		(start 132.117084 -230.999284)
		(end 130.633724 -229.515924)
		(width 0.15494)
		(layer "In5.Cu")
		(net "PWRGD_P12V_NIC2_R")
	)
	(segment
		(start 123.132088 -158.828994)
		(end 122.174 -157.870906)
		(width 0.15494)
		(layer "In5.Cu")
		(net "PWRGD_P12V_NIC2_R")
	)
	(segment
		(start 138.018012 -166.228014)
		(end 138.018012 -173.372018)
		(width 0.15494)
		(layer "In5.Cu")
		(net "PWRGD_P12V_NIC2_R")
	)
	(segment
		(start 138.018012 -173.372018)
		(end 138.507216 -173.861222)
		(width 0.15494)
		(layer "In5.Cu")
		(net "PWRGD_P12V_NIC2_R")
	)
	(segment
		(start 134.192518 -197.979284)
		(end 134.192518 -192.574418)
		(width 0.15494)
		(layer "In5.Cu")
		(net "PWRGD_P12V_NIC2_R")
	)
	(segment
		(start 138.5062 -178.046634)
		(end 137.947654 -177.488088)
		(width 0.15494)
		(layer "In5.Cu")
		(net "PWRGD_P12V_NIC2_R")
	)
	(segment
		(start 122.555 -161.438082)
		(end 125.353572 -164.236654)
		(width 0.15494)
		(layer "In5.Cu")
		(net "PWRGD_P12V_NIC2_R")
	)
	(segment
		(start 130.255518 -211.16798)
		(end 130.255518 -202.636882)
		(width 0.15494)
		(layer "In5.Cu")
		(net "PWRGD_P12V_NIC2_R")
	)
	(segment
		(start 125.353572 -164.236654)
		(end 136.026652 -164.236654)
		(width 0.15494)
		(layer "In5.Cu")
		(net "PWRGD_P12V_NIC2_R")
	)
	(segment
		(start 130.255518 -202.636882)
		(end 132.051298 -200.841102)
		(width 0.15494)
		(layer "In5.Cu")
		(net "PWRGD_P12V_NIC2_R")
	)
	(segment
		(start 134.192518 -192.574418)
		(end 138.5062 -188.260736)
		(width 0.15494)
		(layer "In5.Cu")
		(net "PWRGD_P12V_NIC2_R")
	)
	(segment
		(start 123.132088 -158.828994)
		(end 122.682 -158.828994)
		(width 0.15494)
		(layer "In5.Cu")
		(net "PWRGD_P12V_NIC2_R")
	)
	(segment
		(start 122.174 -139.270232)
		(end 122.47499 -138.543284)
		(width 0.15494)
		(layer "In5.Cu")
		(net "PWRGD_P12V_NIC2_R")
	)
	(segment
		(start 122.555 -158.955994)
		(end 122.555 -161.438082)
		(width 0.15494)
		(layer "In5.Cu")
		(net "PWRGD_P12V_NIC2_R")
	)
	(segment
		(start 138.507216 -176.928526)
		(end 137.947654 -177.488088)
		(width 0.15494)
		(layer "In5.Cu")
		(net "PWRGD_P12V_NIC2_R")
	)
	(segment
		(start 130.633724 -229.515924)
		(end 130.633724 -214.70747)
		(width 0.15494)
		(layer "In5.Cu")
		(net "PWRGD_P12V_NIC2_R")
	)
	(segment
		(start 132.051298 -200.120504)
		(end 134.192518 -197.979284)
		(width 0.15494)
		(layer "In5.Cu")
		(net "PWRGD_P12V_NIC2_R")
	)
	(segment
		(start 138.507216 -173.861222)
		(end 138.507216 -176.928526)
		(width 0.15494)
		(layer "In5.Cu")
		(net "PWRGD_P12V_NIC2_R")
	)
	(segment
		(start 130.633724 -214.70747)
		(end 129.887218 -213.960964)
		(width 0.15494)
		(layer "In5.Cu")
		(net "PWRGD_P12V_NIC2_R")
	)
	(segment
		(start 138.5062 -188.260736)
		(end 138.5062 -178.046634)
		(width 0.15494)
		(layer "In5.Cu")
		(net "PWRGD_P12V_NIC2_R")
	)
	(segment
		(start 122.682 -158.828994)
		(end 122.555 -158.955994)
		(width 0.15494)
		(layer "In5.Cu")
		(net "PWRGD_P12V_NIC2_R")
	)
	(segment
		(start 301.179992 -249.3645)
		(end 299.500544 -247.685052)
		(width 0.15494)
		(layer "In13.Cu")
		(net "PWRGD_P12V_NIC2_R")
	)
	(segment
		(start 133.783578 -239.1156)
		(end 132.66547 -239.1156)
		(width 0.15494)
		(layer "In13.Cu")
		(net "PWRGD_P12V_NIC2_R")
	)
	(segment
		(start 141.172692 -238.443008)
		(end 134.45617 -238.443008)
		(width 0.15494)
		(layer "In13.Cu")
		(net "PWRGD_P12V_NIC2_R")
	)
	(segment
		(start 350.091248 -223.189292)
		(end 351.50933 -223.189292)
		(width 0.0889)
		(layer "In13.Cu")
		(net "PWRGD_P12V_NIC2_R")
	)
	(segment
		(start 354.661216 -231.72547)
		(end 354.93706 -232.001314)
		(width 0.15494)
		(layer "In13.Cu")
		(net "PWRGD_P12V_NIC2_R")
	)
	(segment
		(start 166.86784 -176.3014)
		(end 167.439086 -175.730154)
		(width 0.15494)
		(layer "In13.Cu")
		(net "PWRGD_P12V_NIC2_R")
	)
	(segment
		(start 349.693738 -223.586802)
		(end 350.091248 -223.189292)
		(width 0.0889)
		(layer "In13.Cu")
		(net "PWRGD_P12V_NIC2_R")
	)
	(segment
		(start 234.844844 -242.769644)
		(end 208.820004 -242.769644)
		(width 0.15494)
		(layer "In13.Cu")
		(net "PWRGD_P12V_NIC2_R")
	)
	(segment
		(start 348.332552 -241.68354)
		(end 345.15425 -241.68354)
		(width 0.15494)
		(layer "In13.Cu")
		(net "PWRGD_P12V_NIC2_R")
	)
	(segment
		(start 331.611986 -247.62968)
		(end 329.877166 -249.3645)
		(width 0.15494)
		(layer "In13.Cu")
		(net "PWRGD_P12V_NIC2_R")
	)
	(segment
		(start 237.1598 -245.0846)
		(end 234.844844 -242.769644)
		(width 0.15494)
		(layer "In13.Cu")
		(net "PWRGD_P12V_NIC2_R")
	)
	(segment
		(start 141.78788 -171.651168)
		(end 145.330164 -171.651168)
		(width 0.15494)
		(layer "In13.Cu")
		(net "PWRGD_P12V_NIC2_R")
	)
	(segment
		(start 345.15425 -241.68354)
		(end 339.00237 -247.83542)
		(width 0.15494)
		(layer "In13.Cu")
		(net "PWRGD_P12V_NIC2_R")
	)
	(segment
		(start 334.851756 -247.62968)
		(end 331.611986 -247.62968)
		(width 0.15494)
		(layer "In13.Cu")
		(net "PWRGD_P12V_NIC2_R")
	)
	(segment
		(start 353.69754 -236.318552)
		(end 348.332552 -241.68354)
		(width 0.15494)
		(layer "In13.Cu")
		(net "PWRGD_P12V_NIC2_R")
	)
	(segment
		(start 143.0655 -236.5502)
		(end 141.172692 -238.443008)
		(width 0.15494)
		(layer "In13.Cu")
		(net "PWRGD_P12V_NIC2_R")
	)
	(segment
		(start 335.057496 -247.83542)
		(end 334.851756 -247.62968)
		(width 0.15494)
		(layer "In13.Cu")
		(net "PWRGD_P12V_NIC2_R")
	)
	(segment
		(start 149.980396 -176.3014)
		(end 166.86784 -176.3014)
		(width 0.15494)
		(layer "In13.Cu")
		(net "PWRGD_P12V_NIC2_R")
	)
	(segment
		(start 353.69754 -234.33786)
		(end 353.69754 -236.318552)
		(width 0.15494)
		(layer "In13.Cu")
		(net "PWRGD_P12V_NIC2_R")
	)
	(segment
		(start 354.93706 -232.001314)
		(end 354.93706 -233.09834)
		(width 0.15494)
		(layer "In13.Cu")
		(net "PWRGD_P12V_NIC2_R")
	)
	(segment
		(start 137.947654 -175.491394)
		(end 141.78788 -171.651168)
		(width 0.15494)
		(layer "In13.Cu")
		(net "PWRGD_P12V_NIC2_R")
	)
	(segment
		(start 351.50933 -223.189292)
		(end 354.661216 -226.341178)
		(width 0.15494)
		(layer "In13.Cu")
		(net "PWRGD_P12V_NIC2_R")
	)
	(segment
		(start 208.820004 -242.769644)
		(end 207.078834 -244.510814)
		(width 0.15494)
		(layer "In13.Cu")
		(net "PWRGD_P12V_NIC2_R")
	)
	(segment
		(start 134.45617 -238.443008)
		(end 133.783578 -239.1156)
		(width 0.15494)
		(layer "In13.Cu")
		(net "PWRGD_P12V_NIC2_R")
	)
	(segment
		(start 179.233068 -244.510814)
		(end 171.272454 -236.5502)
		(width 0.15494)
		(layer "In13.Cu")
		(net "PWRGD_P12V_NIC2_R")
	)
	(segment
		(start 137.947654 -177.488088)
		(end 137.947654 -175.491394)
		(width 0.15494)
		(layer "In13.Cu")
		(net "PWRGD_P12V_NIC2_R")
	)
	(segment
		(start 207.078834 -244.510814)
		(end 179.233068 -244.510814)
		(width 0.15494)
		(layer "In13.Cu")
		(net "PWRGD_P12V_NIC2_R")
	)
	(segment
		(start 339.00237 -247.83542)
		(end 335.057496 -247.83542)
		(width 0.15494)
		(layer "In13.Cu")
		(net "PWRGD_P12V_NIC2_R")
	)
	(segment
		(start 237.91291 -245.0846)
		(end 237.1598 -245.0846)
		(width 0.15494)
		(layer "In13.Cu")
		(net "PWRGD_P12V_NIC2_R")
	)
	(segment
		(start 275.498052 -247.685052)
		(end 273.815048 -246.002048)
		(width 0.15494)
		(layer "In13.Cu")
		(net "PWRGD_P12V_NIC2_R")
	)
	(segment
		(start 354.661216 -226.341178)
		(end 354.661216 -231.72547)
		(width 0.15494)
		(layer "In13.Cu")
		(net "PWRGD_P12V_NIC2_R")
	)
	(segment
		(start 299.500544 -247.685052)
		(end 275.498052 -247.685052)
		(width 0.15494)
		(layer "In13.Cu")
		(net "PWRGD_P12V_NIC2_R")
	)
	(segment
		(start 273.815048 -246.002048)
		(end 252.224794 -246.002048)
		(width 0.15494)
		(layer "In13.Cu")
		(net "PWRGD_P12V_NIC2_R")
	)
	(segment
		(start 238.50854 -244.5131)
		(end 237.91291 -245.0846)
		(width 0.15494)
		(layer "In13.Cu")
		(net "PWRGD_P12V_NIC2_R")
	)
	(segment
		(start 329.877166 -249.3645)
		(end 301.179992 -249.3645)
		(width 0.15494)
		(layer "In13.Cu")
		(net "PWRGD_P12V_NIC2_R")
	)
	(segment
		(start 145.330164 -171.651168)
		(end 149.980396 -176.3014)
		(width 0.15494)
		(layer "In13.Cu")
		(net "PWRGD_P12V_NIC2_R")
	)
	(segment
		(start 171.272454 -236.5502)
		(end 143.0655 -236.5502)
		(width 0.15494)
		(layer "In13.Cu")
		(net "PWRGD_P12V_NIC2_R")
	)
	(segment
		(start 252.224794 -246.002048)
		(end 250.735846 -244.5131)
		(width 0.15494)
		(layer "In13.Cu")
		(net "PWRGD_P12V_NIC2_R")
	)
	(segment
		(start 132.66547 -239.1156)
		(end 132.117084 -238.567214)
		(width 0.15494)
		(layer "In13.Cu")
		(net "PWRGD_P12V_NIC2_R")
	)
	(segment
		(start 354.93706 -233.09834)
		(end 353.69754 -234.33786)
		(width 0.15494)
		(layer "In13.Cu")
		(net "PWRGD_P12V_NIC2_R")
	)
	(segment
		(start 250.735846 -244.5131)
		(end 238.50854 -244.5131)
		(width 0.15494)
		(layer "In13.Cu")
		(net "PWRGD_P12V_NIC2_R")
	)
	(segment
		(start 283.539184 -176.478438)
		(end 283.539184 -175.730154)
		(width 0.13208)
		(layer "F.Cu")
		(net "PWRGD_P12V_NIC4_R")
	)
	(segment
		(start 239.84966 -158.828994)
		(end 239.232186 -158.828994)
		(width 0.13208)
		(layer "F.Cu")
		(net "PWRGD_P12V_NIC4_R")
	)
	(segment
		(start 239.413288 -138.360404)
		(end 238.757968 -138.360404)
		(width 0.13208)
		(layer "F.Cu")
		(net "PWRGD_P12V_NIC4_R")
	)
	(segment
		(start 350.893888 -221.58706)
		(end 351.293684 -221.986856)
		(width 0.13208)
		(layer "F.Cu")
		(net "PWRGD_P12V_NIC4_R")
	)
	(via
		(at 283.539184 -175.730154)
		(size 0.508)
		(drill 0.254)
		(layers "F.Cu" "B.Cu")
		(net "PWRGD_P12V_NIC4_R")
	)
	(via
		(at 351.293684 -221.986856)
		(size 0.4572)
		(drill 0.254)
		(layers "F.Cu" "B.Cu")
		(net "PWRGD_P12V_NIC4_R")
	)
	(via
		(at 286.885634 -186.073034)
		(size 0.508)
		(drill 0.254)
		(layers "F.Cu" "B.Cu")
		(net "PWRGD_P12V_NIC4_R")
	)
	(via
		(at 237.229396 -182.720234)
		(size 0.508)
		(drill 0.254)
		(layers "F.Cu" "B.Cu")
		(net "PWRGD_P12V_NIC4_R")
	)
	(via
		(at 238.757968 -138.360404)
		(size 0.508)
		(drill 0.254)
		(layers "F.Cu" "B.Cu")
		(net "PWRGD_P12V_NIC4_R")
	)
	(via
		(at 236.14126 -169.314622)
		(size 0.508)
		(drill 0.254)
		(layers "F.Cu" "B.Cu")
		(net "PWRGD_P12V_NIC4_R")
	)
	(via
		(at 239.232186 -158.828994)
		(size 0.508)
		(drill 0.254)
		(layers "F.Cu" "B.Cu")
		(net "PWRGD_P12V_NIC4_R")
	)
	(segment
		(start 236.294422 -181.78526)
		(end 236.294422 -177.874676)
		(width 0.15494)
		(layer "In5.Cu")
		(net "PWRGD_P12V_NIC4_R")
	)
	(segment
		(start 284.835854 -179.087526)
		(end 284.269434 -177.71999)
		(width 0.15494)
		(layer "In5.Cu")
		(net "PWRGD_P12V_NIC4_R")
	)
	(segment
		(start 285.777686 -184.965086)
		(end 284.835854 -182.691278)
		(width 0.15494)
		(layer "In5.Cu")
		(net "PWRGD_P12V_NIC4_R")
	)
	(segment
		(start 234.566206 -176.14646)
		(end 234.566206 -170.889676)
		(width 0.15494)
		(layer "In5.Cu")
		(net "PWRGD_P12V_NIC4_R")
	)
	(segment
		(start 284.269434 -177.71999)
		(end 283.539184 -176.98974)
		(width 0.15494)
		(layer "In5.Cu")
		(net "PWRGD_P12V_NIC4_R")
	)
	(segment
		(start 283.539184 -176.98974)
		(end 283.539184 -175.730154)
		(width 0.15494)
		(layer "In5.Cu")
		(net "PWRGD_P12V_NIC4_R")
	)
	(segment
		(start 286.885634 -186.073034)
		(end 285.777686 -184.965086)
		(width 0.15494)
		(layer "In5.Cu")
		(net "PWRGD_P12V_NIC4_R")
	)
	(segment
		(start 236.294422 -177.874676)
		(end 234.566206 -176.14646)
		(width 0.15494)
		(layer "In5.Cu")
		(net "PWRGD_P12V_NIC4_R")
	)
	(segment
		(start 237.229396 -182.720234)
		(end 236.294422 -181.78526)
		(width 0.15494)
		(layer "In5.Cu")
		(net "PWRGD_P12V_NIC4_R")
	)
	(segment
		(start 234.566206 -170.889676)
		(end 236.14126 -169.314622)
		(width 0.15494)
		(layer "In5.Cu")
		(net "PWRGD_P12V_NIC4_R")
	)
	(segment
		(start 284.835854 -182.691278)
		(end 284.835854 -179.087526)
		(width 0.15494)
		(layer "In5.Cu")
		(net "PWRGD_P12V_NIC4_R")
	)
	(segment
		(start 237.89767 -139.241276)
		(end 238.757968 -138.380978)
		(width 0.15494)
		(layer "In7.Cu")
		(net "PWRGD_P12V_NIC4_R")
	)
	(segment
		(start 236.14126 -161.91992)
		(end 239.232186 -158.828994)
		(width 0.15494)
		(layer "In7.Cu")
		(net "PWRGD_P12V_NIC4_R")
	)
	(segment
		(start 236.14126 -169.314622)
		(end 236.14126 -161.91992)
		(width 0.15494)
		(layer "In7.Cu")
		(net "PWRGD_P12V_NIC4_R")
	)
	(segment
		(start 239.232186 -158.828994)
		(end 237.89767 -157.494478)
		(width 0.15494)
		(layer "In7.Cu")
		(net "PWRGD_P12V_NIC4_R")
	)
	(segment
		(start 237.89767 -157.494478)
		(end 237.89767 -139.241276)
		(width 0.15494)
		(layer "In7.Cu")
		(net "PWRGD_P12V_NIC4_R")
	)
	(segment
		(start 238.757968 -138.380978)
		(end 238.757968 -138.360404)
		(width 0.15494)
		(layer "In7.Cu")
		(net "PWRGD_P12V_NIC4_R")
	)
	(segment
		(start 351.570544 -221.986856)
		(end 351.293684 -221.986856)
		(width 0.0889)
		(layer "In15.Cu")
		(net "PWRGD_P12V_NIC4_R")
	)
	(segment
		(start 356.73919 -191.626998)
		(end 356.73919 -196.677026)
		(width 0.15494)
		(layer "In15.Cu")
		(net "PWRGD_P12V_NIC4_R")
	)
	(segment
		(start 360.58729 -219.10167)
		(end 359.528364 -221.658688)
		(width 0.15494)
		(layer "In15.Cu")
		(net "PWRGD_P12V_NIC4_R")
	)
	(segment
		(start 352.7044 -187.592208)
		(end 356.73919 -191.626998)
		(width 0.15494)
		(layer "In15.Cu")
		(net "PWRGD_P12V_NIC4_R")
	)
	(segment
		(start 333.020924 -186.53887)
		(end 339.29066 -186.53887)
		(width 0.15494)
		(layer "In15.Cu")
		(net "PWRGD_P12V_NIC4_R")
	)
	(segment
		(start 359.51287 -221.674182)
		(end 359.51287 -221.68866)
		(width 0.15494)
		(layer "In15.Cu")
		(net "PWRGD_P12V_NIC4_R")
	)
	(segment
		(start 244.622066 -184.648348)
		(end 260.031738 -184.648348)
		(width 0.15494)
		(layer "In15.Cu")
		(net "PWRGD_P12V_NIC4_R")
	)
	(segment
		(start 339.29066 -186.53887)
		(end 339.30209 -186.52744)
		(width 0.15494)
		(layer "In15.Cu")
		(net "PWRGD_P12V_NIC4_R")
	)
	(segment
		(start 352.171 -221.3864)
		(end 351.570544 -221.986856)
		(width 0.0889)
		(layer "In15.Cu")
		(net "PWRGD_P12V_NIC4_R")
	)
	(segment
		(start 359.191052 -221.996)
		(end 358.593136 -221.996)
		(width 0.15494)
		(layer "In15.Cu")
		(net "PWRGD_P12V_NIC4_R")
	)
	(segment
		(start 260.031738 -184.648348)
		(end 260.744716 -183.93537)
		(width 0.15494)
		(layer "In15.Cu")
		(net "PWRGD_P12V_NIC4_R")
	)
	(segment
		(start 347.907356 -187.592208)
		(end 352.7044 -187.592208)
		(width 0.15494)
		(layer "In15.Cu")
		(net "PWRGD_P12V_NIC4_R")
	)
	(segment
		(start 360.58729 -200.525126)
		(end 360.58729 -219.10167)
		(width 0.15494)
		(layer "In15.Cu")
		(net "PWRGD_P12V_NIC4_R")
	)
	(segment
		(start 359.215182 -221.97187)
		(end 359.191052 -221.996)
		(width 0.15494)
		(layer "In15.Cu")
		(net "PWRGD_P12V_NIC4_R")
	)
	(segment
		(start 244.338856 -184.111138)
		(end 244.338856 -184.365138)
		(width 0.15494)
		(layer "In15.Cu")
		(net "PWRGD_P12V_NIC4_R")
	)
	(segment
		(start 352.40595 -221.15145)
		(end 352.171 -221.3864)
		(width 0.15494)
		(layer "In15.Cu")
		(net "PWRGD_P12V_NIC4_R")
	)
	(segment
		(start 356.73919 -196.677026)
		(end 360.58729 -200.525126)
		(width 0.15494)
		(layer "In15.Cu")
		(net "PWRGD_P12V_NIC4_R")
	)
	(segment
		(start 244.338856 -184.365138)
		(end 244.622066 -184.648348)
		(width 0.15494)
		(layer "In15.Cu")
		(net "PWRGD_P12V_NIC4_R")
	)
	(segment
		(start 260.744716 -183.93537)
		(end 283.682948 -183.93537)
		(width 0.15494)
		(layer "In15.Cu")
		(net "PWRGD_P12V_NIC4_R")
	)
	(segment
		(start 286.885634 -186.073034)
		(end 287.241488 -185.71718)
		(width 0.15494)
		(layer "In15.Cu")
		(net "PWRGD_P12V_NIC4_R")
	)
	(segment
		(start 285.820612 -186.073034)
		(end 286.885634 -186.073034)
		(width 0.15494)
		(layer "In15.Cu")
		(net "PWRGD_P12V_NIC4_R")
	)
	(segment
		(start 359.51287 -221.68866)
		(end 359.22966 -221.97187)
		(width 0.15494)
		(layer "In15.Cu")
		(net "PWRGD_P12V_NIC4_R")
	)
	(segment
		(start 237.229396 -182.720234)
		(end 242.947952 -182.720234)
		(width 0.15494)
		(layer "In15.Cu")
		(net "PWRGD_P12V_NIC4_R")
	)
	(segment
		(start 287.241488 -185.71718)
		(end 332.199234 -185.71718)
		(width 0.15494)
		(layer "In15.Cu")
		(net "PWRGD_P12V_NIC4_R")
	)
	(segment
		(start 357.748586 -221.15145)
		(end 352.40595 -221.15145)
		(width 0.15494)
		(layer "In15.Cu")
		(net "PWRGD_P12V_NIC4_R")
	)
	(segment
		(start 358.593136 -221.996)
		(end 357.748586 -221.15145)
		(width 0.15494)
		(layer "In15.Cu")
		(net "PWRGD_P12V_NIC4_R")
	)
	(segment
		(start 346.842588 -186.52744)
		(end 347.907356 -187.592208)
		(width 0.15494)
		(layer "In15.Cu")
		(net "PWRGD_P12V_NIC4_R")
	)
	(segment
		(start 283.682948 -183.93537)
		(end 285.820612 -186.073034)
		(width 0.15494)
		(layer "In15.Cu")
		(net "PWRGD_P12V_NIC4_R")
	)
	(segment
		(start 359.528364 -221.658688)
		(end 359.51287 -221.674182)
		(width 0.15494)
		(layer "In15.Cu")
		(net "PWRGD_P12V_NIC4_R")
	)
	(segment
		(start 242.947952 -182.720234)
		(end 244.338856 -184.111138)
		(width 0.15494)
		(layer "In15.Cu")
		(net "PWRGD_P12V_NIC4_R")
	)
	(segment
		(start 332.199234 -185.71718)
		(end 333.020924 -186.53887)
		(width 0.15494)
		(layer "In15.Cu")
		(net "PWRGD_P12V_NIC4_R")
	)
	(segment
		(start 339.30209 -186.52744)
		(end 346.842588 -186.52744)
		(width 0.15494)
		(layer "In15.Cu")
		(net "PWRGD_P12V_NIC4_R")
	)
	(segment
		(start 359.22966 -221.97187)
		(end 359.215182 -221.97187)
		(width 0.15494)
		(layer "In15.Cu")
		(net "PWRGD_P12V_NIC4_R")
	)
	(segment
		(start 223.706944 -98.76917)
		(end 222.690944 -98.76917)
		(width 0.13208)
		(layer "F.Cu")
		(net "PWRGD_P12V_NIC3")
	)
	(segment
		(start 222.690944 -99.201732)
		(end 222.690944 -98.76917)
		(width 0.13208)
		(layer "F.Cu")
		(net "PWRGD_P12V_NIC3")
	)
	(segment
		(start 222.69577 -99.79279)
		(end 222.988886 -99.499674)
		(width 0.13208)
		(layer "F.Cu")
		(net "PWRGD_P12V_NIC3")
	)
	(segment
		(start 222.69577 -100.856542)
		(end 222.69577 -99.79279)
		(width 0.13208)
		(layer "F.Cu")
		(net "PWRGD_P12V_NIC3")
	)
	(segment
		(start 222.988886 -99.499674)
		(end 222.690944 -99.201732)
		(width 0.13208)
		(layer "F.Cu")
		(net "PWRGD_P12V_NIC3")
	)
	(via
		(at 222.988886 -99.499674)
		(size 0.508)
		(drill 0.254)
		(layers "F.Cu" "B.Cu")
		(net "PWRGD_P12V_NIC3")
	)
	(segment
		(start 357.04399 -138.388852)
		(end 357.04399 -138.824462)
		(width 0.13208)
		(layer "F.Cu")
		(net "PWRGD_P12V_NIC6")
	)
	(segment
		(start 356.91699 -139.376404)
		(end 356.313486 -139.376404)
		(width 0.13208)
		(layer "F.Cu")
		(net "PWRGD_P12V_NIC6")
	)
	(segment
		(start 356.313486 -138.360404)
		(end 356.313486 -139.376404)
		(width 0.13208)
		(layer "F.Cu")
		(net "PWRGD_P12V_NIC6")
	)
	(segment
		(start 358.034082 -137.767822)
		(end 357.66502 -137.767822)
		(width 0.13208)
		(layer "F.Cu")
		(net "PWRGD_P12V_NIC6")
	)
	(segment
		(start 357.04399 -138.824462)
		(end 357.04399 -139.249404)
		(width 0.13208)
		(layer "F.Cu")
		(net "PWRGD_P12V_NIC6")
	)
	(segment
		(start 357.66502 -137.767822)
		(end 357.04399 -138.388852)
		(width 0.13208)
		(layer "F.Cu")
		(net "PWRGD_P12V_NIC6")
	)
	(segment
		(start 357.04399 -139.249404)
		(end 356.91699 -139.376404)
		(width 0.13208)
		(layer "F.Cu")
		(net "PWRGD_P12V_NIC6")
	)
	(via
		(at 357.04399 -138.824462)
		(size 0.508)
		(drill 0.254)
		(layers "F.Cu" "B.Cu")
		(net "PWRGD_P12V_NIC6")
	)
	(segment
		(start 94.809056 -96.374966)
		(end 94.809056 -95.441516)
		(width 0.13208)
		(layer "F.Cu")
		(net "P12V_NIC1_SS")
	)
	(segment
		(start 95.746824 -97.312734)
		(end 94.809056 -96.374966)
		(width 0.13208)
		(layer "F.Cu")
		(net "P12V_NIC1_SS")
	)
	(segment
		(start 96.383094 -97.467928)
		(end 96.383094 -97.403412)
		(width 0.13208)
		(layer "F.Cu")
		(net "P12V_NIC1_SS")
	)
	(segment
		(start 96.292416 -97.312734)
		(end 95.746824 -97.312734)
		(width 0.13208)
		(layer "F.Cu")
		(net "P12V_NIC1_SS")
	)
	(segment
		(start 96.383094 -97.403412)
		(end 96.292416 -97.312734)
		(width 0.13208)
		(layer "F.Cu")
		(net "P12V_NIC1_SS")
	)
	(via
		(at 94.809056 -96.374966)
		(size 0.508)
		(drill 0.254)
		(layers "F.Cu" "B.Cu")
		(net "P12V_NIC1_SS")
	)
	(segment
		(start 328.434192 -96.288352)
		(end 328.111104 -96.288352)
		(width 0.13208)
		(layer "F.Cu")
		(net "PWRGD_P12V_NIC5")
	)
	(segment
		(start 329.03414 -95.663766)
		(end 328.01814 -95.663766)
		(width 0.13208)
		(layer "F.Cu")
		(net "PWRGD_P12V_NIC5")
	)
	(segment
		(start 328.01814 -96.195388)
		(end 328.01814 -95.71482)
		(width 0.13208)
		(layer "F.Cu")
		(net "PWRGD_P12V_NIC5")
	)
	(segment
		(start 329.082908 -97.467928)
		(end 329.082908 -96.937068)
		(width 0.13208)
		(layer "F.Cu")
		(net "PWRGD_P12V_NIC5")
	)
	(segment
		(start 328.111104 -96.288352)
		(end 328.01814 -96.195388)
		(width 0.13208)
		(layer "F.Cu")
		(net "PWRGD_P12V_NIC5")
	)
	(segment
		(start 328.01814 -95.663766)
		(end 328.01814 -95.71482)
		(width 0.13208)
		(layer "F.Cu")
		(net "PWRGD_P12V_NIC5")
	)
	(segment
		(start 329.082908 -96.937068)
		(end 328.434192 -96.288352)
		(width 0.13208)
		(layer "F.Cu")
		(net "PWRGD_P12V_NIC5")
	)
	(via
		(at 328.434192 -96.288352)
		(size 0.508)
		(drill 0.254)
		(layers "F.Cu" "B.Cu")
		(net "PWRGD_P12V_NIC5")
	)
	(segment
		(start 124.11329 -134.042404)
		(end 124.11329 -135.058404)
		(width 0.13208)
		(layer "F.Cu")
		(net "P12V_NIC2_EN_R")
	)
	(segment
		(start 124.11329 -135.058404)
		(end 124.921772 -135.866886)
		(width 0.13208)
		(layer "F.Cu")
		(net "P12V_NIC2_EN_R")
	)
	(segment
		(start 125.833886 -136.267698)
		(end 125.322584 -136.267698)
		(width 0.13208)
		(layer "F.Cu")
		(net "P12V_NIC2_EN_R")
	)
	(segment
		(start 125.322584 -136.267698)
		(end 124.921772 -135.866886)
		(width 0.13208)
		(layer "F.Cu")
		(net "P12V_NIC2_EN_R")
	)
	(via
		(at 124.921772 -135.866886)
		(size 0.508)
		(drill 0.254)
		(layers "F.Cu" "B.Cu")
		(net "P12V_NIC2_EN_R")
	)
	(segment
		(start 425.779946 -81.21904)
		(end 425.899326 -81.09966)
		(width 0.13208)
		(layer "F.Cu")
		(net "PWRGD_P12V_NIC7_R")
	)
	(segment
		(start 426.16374 -82.414364)
		(end 425.779946 -82.03057)
		(width 0.13208)
		(layer "F.Cu")
		(net "PWRGD_P12V_NIC7_R")
	)
	(segment
		(start 350.493584 -217.187272)
		(end 350.093788 -217.587068)
		(width 0.13208)
		(layer "F.Cu")
		(net "PWRGD_P12V_NIC7_R")
	)
	(segment
		(start 445.134238 -94.863666)
		(end 445.134238 -94.253304)
		(width 0.13208)
		(layer "F.Cu")
		(net "PWRGD_P12V_NIC7_R")
	)
	(segment
		(start 425.779946 -82.03057)
		(end 425.779946 -81.21904)
		(width 0.13208)
		(layer "F.Cu")
		(net "PWRGD_P12V_NIC7_R")
	)
	(segment
		(start 457.436982 -116.630704)
		(end 457.436982 -117.248178)
		(width 0.13208)
		(layer "F.Cu")
		(net "PWRGD_P12V_NIC7_R")
	)
	(segment
		(start 425.899326 -81.09966)
		(end 426.357542 -81.09966)
		(width 0.13208)
		(layer "F.Cu")
		(net "PWRGD_P12V_NIC7_R")
	)
	(via
		(at 457.436982 -117.248178)
		(size 0.508)
		(drill 0.254)
		(layers "F.Cu" "B.Cu")
		(net "PWRGD_P12V_NIC7_R")
	)
	(via
		(at 354.061776 -128.995424)
		(size 0.508)
		(drill 0.254)
		(layers "F.Cu" "B.Cu")
		(net "PWRGD_P12V_NIC7_R")
	)
	(via
		(at 445.134238 -94.253304)
		(size 0.508)
		(drill 0.254)
		(layers "F.Cu" "B.Cu")
		(net "PWRGD_P12V_NIC7_R")
	)
	(via
		(at 350.493584 -217.187272)
		(size 0.4572)
		(drill 0.254)
		(layers "F.Cu" "B.Cu")
		(net "PWRGD_P12V_NIC7_R")
	)
	(via
		(at 426.16374 -82.414364)
		(size 0.508)
		(drill 0.254)
		(layers "F.Cu" "B.Cu")
		(net "PWRGD_P12V_NIC7_R")
	)
	(segment
		(start 352.406204 -159.638746)
		(end 352.406204 -130.650996)
		(width 0.15494)
		(layer "In5.Cu")
		(net "PWRGD_P12V_NIC7_R")
	)
	(segment
		(start 369.024408 -191.128904)
		(end 369.024408 -181.486302)
		(width 0.15494)
		(layer "In5.Cu")
		(net "PWRGD_P12V_NIC7_R")
	)
	(segment
		(start 356.37089 -165.468554)
		(end 353.092004 -162.189668)
		(width 0.15494)
		(layer "In5.Cu")
		(net "PWRGD_P12V_NIC7_R")
	)
	(segment
		(start 370.703602 -203.305156)
		(end 370.703602 -192.808098)
		(width 0.15494)
		(layer "In5.Cu")
		(net "PWRGD_P12V_NIC7_R")
	)
	(segment
		(start 353.092004 -160.324546)
		(end 352.406204 -159.638746)
		(width 0.15494)
		(layer "In5.Cu")
		(net "PWRGD_P12V_NIC7_R")
	)
	(segment
		(start 366.05337 -178.515264)
		(end 366.05337 -173.71949)
		(width 0.15494)
		(layer "In5.Cu")
		(net "PWRGD_P12V_NIC7_R")
	)
	(segment
		(start 367.413032 -205.303628)
		(end 368.70513 -205.303628)
		(width 0.15494)
		(layer "In5.Cu")
		(net "PWRGD_P12V_NIC7_R")
	)
	(segment
		(start 362.966 -211.1756)
		(end 362.966 -210.1215)
		(width 0.15494)
		(layer "In5.Cu")
		(net "PWRGD_P12V_NIC7_R")
	)
	(segment
		(start 352.406204 -130.650996)
		(end 354.061776 -128.995424)
		(width 0.15494)
		(layer "In5.Cu")
		(net "PWRGD_P12V_NIC7_R")
	)
	(segment
		(start 366.398048 -206.318612)
		(end 367.413032 -205.303628)
		(width 0.15494)
		(layer "In5.Cu")
		(net "PWRGD_P12V_NIC7_R")
	)
	(segment
		(start 369.024408 -181.486302)
		(end 366.05337 -178.515264)
		(width 0.15494)
		(layer "In5.Cu")
		(net "PWRGD_P12V_NIC7_R")
	)
	(segment
		(start 358.095804 -167.155368)
		(end 356.674928 -167.155368)
		(width 0.15494)
		(layer "In5.Cu")
		(net "PWRGD_P12V_NIC7_R")
	)
	(segment
		(start 351.429574 -217.187272)
		(end 354.576126 -214.04072)
		(width 0.15494)
		(layer "In5.Cu")
		(net "PWRGD_P12V_NIC7_R")
	)
	(segment
		(start 370.703602 -192.808098)
		(end 369.024408 -191.128904)
		(width 0.15494)
		(layer "In5.Cu")
		(net "PWRGD_P12V_NIC7_R")
	)
	(segment
		(start 366.05337 -173.71949)
		(end 360.599228 -168.265348)
		(width 0.15494)
		(layer "In5.Cu")
		(net "PWRGD_P12V_NIC7_R")
	)
	(segment
		(start 366.398048 -206.689452)
		(end 366.398048 -206.318612)
		(width 0.15494)
		(layer "In5.Cu")
		(net "PWRGD_P12V_NIC7_R")
	)
	(segment
		(start 350.493584 -217.187272)
		(end 351.429574 -217.187272)
		(width 0.15494)
		(layer "In5.Cu")
		(net "PWRGD_P12V_NIC7_R")
	)
	(segment
		(start 353.092004 -162.189668)
		(end 353.092004 -160.324546)
		(width 0.15494)
		(layer "In5.Cu")
		(net "PWRGD_P12V_NIC7_R")
	)
	(segment
		(start 357.3526 -212.852)
		(end 359.791 -212.852)
		(width 0.15494)
		(layer "In5.Cu")
		(net "PWRGD_P12V_NIC7_R")
	)
	(segment
		(start 354.576126 -214.04072)
		(end 356.16388 -214.04072)
		(width 0.15494)
		(layer "In5.Cu")
		(net "PWRGD_P12V_NIC7_R")
	)
	(segment
		(start 356.37089 -166.85133)
		(end 356.37089 -165.468554)
		(width 0.15494)
		(layer "In5.Cu")
		(net "PWRGD_P12V_NIC7_R")
	)
	(segment
		(start 359.205784 -168.265348)
		(end 358.095804 -167.155368)
		(width 0.15494)
		(layer "In5.Cu")
		(net "PWRGD_P12V_NIC7_R")
	)
	(segment
		(start 362.66628 -211.47532)
		(end 362.966 -211.1756)
		(width 0.15494)
		(layer "In5.Cu")
		(net "PWRGD_P12V_NIC7_R")
	)
	(segment
		(start 360.599228 -168.265348)
		(end 359.205784 -168.265348)
		(width 0.15494)
		(layer "In5.Cu")
		(net "PWRGD_P12V_NIC7_R")
	)
	(segment
		(start 359.791 -212.852)
		(end 361.16768 -211.47532)
		(width 0.15494)
		(layer "In5.Cu")
		(net "PWRGD_P12V_NIC7_R")
	)
	(segment
		(start 356.674928 -167.155368)
		(end 356.37089 -166.85133)
		(width 0.15494)
		(layer "In5.Cu")
		(net "PWRGD_P12V_NIC7_R")
	)
	(segment
		(start 361.16768 -211.47532)
		(end 362.66628 -211.47532)
		(width 0.15494)
		(layer "In5.Cu")
		(net "PWRGD_P12V_NIC7_R")
	)
	(segment
		(start 362.966 -210.1215)
		(end 366.398048 -206.689452)
		(width 0.15494)
		(layer "In5.Cu")
		(net "PWRGD_P12V_NIC7_R")
	)
	(segment
		(start 356.16388 -214.04072)
		(end 357.3526 -212.852)
		(width 0.15494)
		(layer "In5.Cu")
		(net "PWRGD_P12V_NIC7_R")
	)
	(segment
		(start 368.70513 -205.303628)
		(end 370.703602 -203.305156)
		(width 0.15494)
		(layer "In5.Cu")
		(net "PWRGD_P12V_NIC7_R")
	)
	(segment
		(start 417.53536 -128.50876)
		(end 416.305492 -127.278892)
		(width 0.15494)
		(layer "In13.Cu")
		(net "PWRGD_P12V_NIC7_R")
	)
	(segment
		(start 370.403882 -126.54534)
		(end 367.560352 -129.38887)
		(width 0.15494)
		(layer "In13.Cu")
		(net "PWRGD_P12V_NIC7_R")
	)
	(segment
		(start 421.144446 -128.50876)
		(end 417.53536 -128.50876)
		(width 0.15494)
		(layer "In13.Cu")
		(net "PWRGD_P12V_NIC7_R")
	)
	(segment
		(start 422.412668 -127.240538)
		(end 421.144446 -128.50876)
		(width 0.15494)
		(layer "In13.Cu")
		(net "PWRGD_P12V_NIC7_R")
	)
	(segment
		(start 458.007974 -117.81917)
		(end 457.436982 -117.248178)
		(width 0.15494)
		(layer "In13.Cu")
		(net "PWRGD_P12V_NIC7_R")
	)
	(segment
		(start 357.147368 -129.38887)
		(end 356.753922 -128.995424)
		(width 0.15494)
		(layer "In13.Cu")
		(net "PWRGD_P12V_NIC7_R")
	)
	(segment
		(start 460.288132 -102.764082)
		(end 452.326502 -94.802452)
		(width 0.15494)
		(layer "In13.Cu")
		(net "PWRGD_P12V_NIC7_R")
	)
	(segment
		(start 384.013964 -126.54534)
		(end 370.403882 -126.54534)
		(width 0.15494)
		(layer "In13.Cu")
		(net "PWRGD_P12V_NIC7_R")
	)
	(segment
		(start 446.251584 -127.240538)
		(end 422.412668 -127.240538)
		(width 0.15494)
		(layer "In13.Cu")
		(net "PWRGD_P12V_NIC7_R")
	)
	(segment
		(start 449.451984 -124.040138)
		(end 446.251584 -127.240538)
		(width 0.15494)
		(layer "In13.Cu")
		(net "PWRGD_P12V_NIC7_R")
	)
	(segment
		(start 458.007974 -117.81917)
		(end 458.007974 -119.916194)
		(width 0.15494)
		(layer "In13.Cu")
		(net "PWRGD_P12V_NIC7_R")
	)
	(segment
		(start 460.288132 -116.582698)
		(end 460.288132 -102.764082)
		(width 0.15494)
		(layer "In13.Cu")
		(net "PWRGD_P12V_NIC7_R")
	)
	(segment
		(start 458.007974 -119.916194)
		(end 453.447404 -124.476764)
		(width 0.15494)
		(layer "In13.Cu")
		(net "PWRGD_P12V_NIC7_R")
	)
	(segment
		(start 400.24939 -127.278892)
		(end 398.469358 -129.058924)
		(width 0.15494)
		(layer "In13.Cu")
		(net "PWRGD_P12V_NIC7_R")
	)
	(segment
		(start 356.753922 -128.995424)
		(end 354.061776 -128.995424)
		(width 0.15494)
		(layer "In13.Cu")
		(net "PWRGD_P12V_NIC7_R")
	)
	(segment
		(start 445.683386 -94.802452)
		(end 445.134238 -94.253304)
		(width 0.15494)
		(layer "In13.Cu")
		(net "PWRGD_P12V_NIC7_R")
	)
	(segment
		(start 453.447404 -124.476764)
		(end 451.10908 -124.476764)
		(width 0.15494)
		(layer "In13.Cu")
		(net "PWRGD_P12V_NIC7_R")
	)
	(segment
		(start 459.05166 -117.81917)
		(end 460.288132 -116.582698)
		(width 0.15494)
		(layer "In13.Cu")
		(net "PWRGD_P12V_NIC7_R")
	)
	(segment
		(start 398.469358 -129.058924)
		(end 386.527548 -129.058924)
		(width 0.15494)
		(layer "In13.Cu")
		(net "PWRGD_P12V_NIC7_R")
	)
	(segment
		(start 458.007974 -117.81917)
		(end 459.05166 -117.81917)
		(width 0.15494)
		(layer "In13.Cu")
		(net "PWRGD_P12V_NIC7_R")
	)
	(segment
		(start 416.305492 -127.278892)
		(end 400.24939 -127.278892)
		(width 0.15494)
		(layer "In13.Cu")
		(net "PWRGD_P12V_NIC7_R")
	)
	(segment
		(start 452.326502 -94.802452)
		(end 445.683386 -94.802452)
		(width 0.15494)
		(layer "In13.Cu")
		(net "PWRGD_P12V_NIC7_R")
	)
	(segment
		(start 367.560352 -129.38887)
		(end 357.147368 -129.38887)
		(width 0.15494)
		(layer "In13.Cu")
		(net "PWRGD_P12V_NIC7_R")
	)
	(segment
		(start 450.672454 -124.040138)
		(end 449.451984 -124.040138)
		(width 0.15494)
		(layer "In13.Cu")
		(net "PWRGD_P12V_NIC7_R")
	)
	(segment
		(start 386.527548 -129.058924)
		(end 384.013964 -126.54534)
		(width 0.15494)
		(layer "In13.Cu")
		(net "PWRGD_P12V_NIC7_R")
	)
	(segment
		(start 451.10908 -124.476764)
		(end 450.672454 -124.040138)
		(width 0.15494)
		(layer "In13.Cu")
		(net "PWRGD_P12V_NIC7_R")
	)
	(segment
		(start 444.527432 -92.920312)
		(end 444.527432 -93.646498)
		(width 0.15494)
		(layer "In15.Cu")
		(net "PWRGD_P12V_NIC7_R")
	)
	(segment
		(start 426.672248 -82.922872)
		(end 428.377604 -82.922872)
		(width 0.15494)
		(layer "In15.Cu")
		(net "PWRGD_P12V_NIC7_R")
	)
	(segment
		(start 434.893974 -84.328762)
		(end 435.364636 -84.799424)
		(width 0.15494)
		(layer "In15.Cu")
		(net "PWRGD_P12V_NIC7_R")
	)
	(segment
		(start 444.527432 -93.646498)
		(end 445.134238 -94.253304)
		(width 0.15494)
		(layer "In15.Cu")
		(net "PWRGD_P12V_NIC7_R")
	)
	(segment
		(start 429.783494 -84.328762)
		(end 434.893974 -84.328762)
		(width 0.15494)
		(layer "In15.Cu")
		(net "PWRGD_P12V_NIC7_R")
	)
	(segment
		(start 426.16374 -82.414364)
		(end 426.672248 -82.922872)
		(width 0.15494)
		(layer "In15.Cu")
		(net "PWRGD_P12V_NIC7_R")
	)
	(segment
		(start 428.377604 -82.922872)
		(end 429.783494 -84.328762)
		(width 0.15494)
		(layer "In15.Cu")
		(net "PWRGD_P12V_NIC7_R")
	)
	(segment
		(start 436.406544 -84.799424)
		(end 444.527432 -92.920312)
		(width 0.15494)
		(layer "In15.Cu")
		(net "PWRGD_P12V_NIC7_R")
	)
	(segment
		(start 435.364636 -84.799424)
		(end 436.406544 -84.799424)
		(width 0.15494)
		(layer "In15.Cu")
		(net "PWRGD_P12V_NIC7_R")
	)
	(segment
		(start 309.799228 -81.09966)
		(end 309.679848 -81.21904)
		(width 0.13208)
		(layer "F.Cu")
		(net "PWRGD_P12V_NIC5_R")
	)
	(segment
		(start 310.257444 -81.09966)
		(end 309.799228 -81.09966)
		(width 0.13208)
		(layer "F.Cu")
		(net "PWRGD_P12V_NIC5_R")
	)
	(segment
		(start 309.679848 -81.21904)
		(end 309.679848 -82.03057)
		(width 0.13208)
		(layer "F.Cu")
		(net "PWRGD_P12V_NIC5_R")
	)
	(segment
		(start 341.336884 -116.630704)
		(end 341.336884 -117.248178)
		(width 0.13208)
		(layer "F.Cu")
		(net "PWRGD_P12V_NIC5_R")
	)
	(segment
		(start 346.093796 -219.987114)
		(end 346.493592 -220.38691)
		(width 0.13208)
		(layer "F.Cu")
		(net "PWRGD_P12V_NIC5_R")
	)
	(segment
		(start 309.679848 -82.03057)
		(end 310.063642 -82.414364)
		(width 0.13208)
		(layer "F.Cu")
		(net "PWRGD_P12V_NIC5_R")
	)
	(segment
		(start 329.03414 -94.863666)
		(end 329.03414 -94.253304)
		(width 0.13208)
		(layer "F.Cu")
		(net "PWRGD_P12V_NIC5_R")
	)
	(via
		(at 329.03414 -94.253304)
		(size 0.508)
		(drill 0.254)
		(layers "F.Cu" "B.Cu")
		(net "PWRGD_P12V_NIC5_R")
	)
	(via
		(at 310.063642 -82.414364)
		(size 0.508)
		(drill 0.254)
		(layers "F.Cu" "B.Cu")
		(net "PWRGD_P12V_NIC5_R")
	)
	(via
		(at 341.336884 -117.248178)
		(size 0.508)
		(drill 0.254)
		(layers "F.Cu" "B.Cu")
		(net "PWRGD_P12V_NIC5_R")
	)
	(via
		(at 356.38359 -116.98351)
		(size 0.508)
		(drill 0.254)
		(layers "F.Cu" "B.Cu")
		(net "PWRGD_P12V_NIC5_R")
	)
	(via
		(at 346.493592 -220.38691)
		(size 0.4572)
		(drill 0.254)
		(layers "F.Cu" "B.Cu")
		(net "PWRGD_P12V_NIC5_R")
	)
	(segment
		(start 349.249746 -141.354302)
		(end 349.249746 -132.298948)
		(width 0.15494)
		(layer "In7.Cu")
		(net "PWRGD_P12V_NIC5_R")
	)
	(segment
		(start 356.362 -212.6742)
		(end 356.362 -211.81441)
		(width 0.15494)
		(layer "In7.Cu")
		(net "PWRGD_P12V_NIC5_R")
	)
	(segment
		(start 346.493592 -220.38691)
		(end 347.618304 -219.262198)
		(width 0.15494)
		(layer "In7.Cu")
		(net "PWRGD_P12V_NIC5_R")
	)
	(segment
		(start 368.75466 -202.022202)
		(end 369.03787 -201.738992)
		(width 0.15494)
		(layer "In7.Cu")
		(net "PWRGD_P12V_NIC5_R")
	)
	(segment
		(start 358.394 -168.6052)
		(end 354.3808 -168.6052)
		(width 0.15494)
		(layer "In7.Cu")
		(net "PWRGD_P12V_NIC5_R")
	)
	(segment
		(start 371.59946 -184.770776)
		(end 371.531134 -184.70245)
		(width 0.15494)
		(layer "In7.Cu")
		(net "PWRGD_P12V_NIC5_R")
	)
	(segment
		(start 353.101402 -219.262198)
		(end 356.6668 -215.6968)
		(width 0.15494)
		(layer "In7.Cu")
		(net "PWRGD_P12V_NIC5_R")
	)
	(segment
		(start 356.6668 -215.1126)
		(end 356.489 -214.9348)
		(width 0.15494)
		(layer "In7.Cu")
		(net "PWRGD_P12V_NIC5_R")
	)
	(segment
		(start 351.890584 -129.65811)
		(end 351.890584 -124.179076)
		(width 0.15494)
		(layer "In7.Cu")
		(net "PWRGD_P12V_NIC5_R")
	)
	(segment
		(start 356.6414 -213.7664)
		(end 356.6414 -212.9536)
		(width 0.15494)
		(layer "In7.Cu")
		(net "PWRGD_P12V_NIC5_R")
	)
	(segment
		(start 371.396768 -199.365616)
		(end 371.396768 -191.767968)
		(width 0.15494)
		(layer "In7.Cu")
		(net "PWRGD_P12V_NIC5_R")
	)
	(segment
		(start 363.9058 -205.2828)
		(end 365.129826 -204.058774)
		(width 0.15494)
		(layer "In7.Cu")
		(net "PWRGD_P12V_NIC5_R")
	)
	(segment
		(start 371.396768 -191.767968)
		(end 371.1448 -191.516)
		(width 0.15494)
		(layer "In7.Cu")
		(net "PWRGD_P12V_NIC5_R")
	)
	(segment
		(start 351.79 -166.0144)
		(end 351.79 -164.6682)
		(width 0.15494)
		(layer "In7.Cu")
		(net "PWRGD_P12V_NIC5_R")
	)
	(segment
		(start 361.745784 -205.2828)
		(end 363.9058 -205.2828)
		(width 0.15494)
		(layer "In7.Cu")
		(net "PWRGD_P12V_NIC5_R")
	)
	(segment
		(start 365.129826 -204.058774)
		(end 365.129826 -203.398374)
		(width 0.15494)
		(layer "In7.Cu")
		(net "PWRGD_P12V_NIC5_R")
	)
	(segment
		(start 360.819192 -206.209392)
		(end 361.745784 -205.2828)
		(width 0.15494)
		(layer "In7.Cu")
		(net "PWRGD_P12V_NIC5_R")
	)
	(segment
		(start 369.644422 -201.117962)
		(end 369.652042 -201.117962)
		(width 0.15494)
		(layer "In7.Cu")
		(net "PWRGD_P12V_NIC5_R")
	)
	(segment
		(start 356.362 -211.81441)
		(end 357.01732 -211.15909)
		(width 0.15494)
		(layer "In7.Cu")
		(net "PWRGD_P12V_NIC5_R")
	)
	(segment
		(start 356.38359 -119.68607)
		(end 356.38359 -116.98351)
		(width 0.15494)
		(layer "In7.Cu")
		(net "PWRGD_P12V_NIC5_R")
	)
	(segment
		(start 369.652042 -201.117962)
		(end 369.935252 -200.834752)
		(width 0.15494)
		(layer "In7.Cu")
		(net "PWRGD_P12V_NIC5_R")
	)
	(segment
		(start 368.740182 -202.022202)
		(end 368.75466 -202.022202)
		(width 0.15494)
		(layer "In7.Cu")
		(net "PWRGD_P12V_NIC5_R")
	)
	(segment
		(start 369.03787 -201.738992)
		(end 369.03787 -201.724514)
		(width 0.15494)
		(layer "In7.Cu")
		(net "PWRGD_P12V_NIC5_R")
	)
	(segment
		(start 371.1448 -191.516)
		(end 371.1448 -185.59018)
		(width 0.15494)
		(layer "In7.Cu")
		(net "PWRGD_P12V_NIC5_R")
	)
	(segment
		(start 360.3752 -166.624)
		(end 358.394 -168.6052)
		(width 0.15494)
		(layer "In7.Cu")
		(net "PWRGD_P12V_NIC5_R")
	)
	(segment
		(start 356.489 -213.9188)
		(end 356.6414 -213.7664)
		(width 0.15494)
		(layer "In7.Cu")
		(net "PWRGD_P12V_NIC5_R")
	)
	(segment
		(start 369.935252 -200.827132)
		(end 371.396768 -199.365616)
		(width 0.15494)
		(layer "In7.Cu")
		(net "PWRGD_P12V_NIC5_R")
	)
	(segment
		(start 371.531134 -184.702196)
		(end 370.591842 -183.762904)
		(width 0.15494)
		(layer "In7.Cu")
		(net "PWRGD_P12V_NIC5_R")
	)
	(segment
		(start 349.229426 -141.374622)
		(end 349.249746 -141.354302)
		(width 0.15494)
		(layer "In7.Cu")
		(net "PWRGD_P12V_NIC5_R")
	)
	(segment
		(start 349.229426 -162.107626)
		(end 349.229426 -141.374622)
		(width 0.15494)
		(layer "In7.Cu")
		(net "PWRGD_P12V_NIC5_R")
	)
	(segment
		(start 371.59946 -185.13552)
		(end 371.59946 -184.770776)
		(width 0.15494)
		(layer "In7.Cu")
		(net "PWRGD_P12V_NIC5_R")
	)
	(segment
		(start 360.235754 -206.209392)
		(end 360.819192 -206.209392)
		(width 0.15494)
		(layer "In7.Cu")
		(net "PWRGD_P12V_NIC5_R")
	)
	(segment
		(start 347.618304 -219.262198)
		(end 353.101402 -219.262198)
		(width 0.15494)
		(layer "In7.Cu")
		(net "PWRGD_P12V_NIC5_R")
	)
	(segment
		(start 366.241584 -202.286616)
		(end 366.321086 -202.286616)
		(width 0.15494)
		(layer "In7.Cu")
		(net "PWRGD_P12V_NIC5_R")
	)
	(segment
		(start 365.961168 -171.346368)
		(end 365.961168 -168.705022)
		(width 0.15494)
		(layer "In7.Cu")
		(net "PWRGD_P12V_NIC5_R")
	)
	(segment
		(start 366.32134 -202.28687)
		(end 366.72266 -202.28687)
		(width 0.15494)
		(layer "In7.Cu")
		(net "PWRGD_P12V_NIC5_R")
	)
	(segment
		(start 349.249746 -132.298948)
		(end 351.890584 -129.65811)
		(width 0.15494)
		(layer "In7.Cu")
		(net "PWRGD_P12V_NIC5_R")
	)
	(segment
		(start 371.531134 -184.70245)
		(end 371.531134 -184.702196)
		(width 0.15494)
		(layer "In7.Cu")
		(net "PWRGD_P12V_NIC5_R")
	)
	(segment
		(start 370.591842 -183.762904)
		(end 370.591842 -175.977042)
		(width 0.15494)
		(layer "In7.Cu")
		(net "PWRGD_P12V_NIC5_R")
	)
	(segment
		(start 351.890584 -124.179076)
		(end 356.38359 -119.68607)
		(width 0.15494)
		(layer "In7.Cu")
		(net "PWRGD_P12V_NIC5_R")
	)
	(segment
		(start 365.961168 -168.705022)
		(end 363.880146 -166.624)
		(width 0.15494)
		(layer "In7.Cu")
		(net "PWRGD_P12V_NIC5_R")
	)
	(segment
		(start 351.79 -164.6682)
		(end 349.229426 -162.107626)
		(width 0.15494)
		(layer "In7.Cu")
		(net "PWRGD_P12V_NIC5_R")
	)
	(segment
		(start 371.1448 -185.59018)
		(end 371.59946 -185.13552)
		(width 0.15494)
		(layer "In7.Cu")
		(net "PWRGD_P12V_NIC5_R")
	)
	(segment
		(start 357.01732 -211.15909)
		(end 357.01732 -209.427826)
		(width 0.15494)
		(layer "In7.Cu")
		(net "PWRGD_P12V_NIC5_R")
	)
	(segment
		(start 356.489 -214.9348)
		(end 356.489 -213.9188)
		(width 0.15494)
		(layer "In7.Cu")
		(net "PWRGD_P12V_NIC5_R")
	)
	(segment
		(start 366.321086 -202.286616)
		(end 366.32134 -202.28687)
		(width 0.15494)
		(layer "In7.Cu")
		(net "PWRGD_P12V_NIC5_R")
	)
	(segment
		(start 363.880146 -166.624)
		(end 360.3752 -166.624)
		(width 0.15494)
		(layer "In7.Cu")
		(net "PWRGD_P12V_NIC5_R")
	)
	(segment
		(start 356.6668 -215.6968)
		(end 356.6668 -215.1126)
		(width 0.15494)
		(layer "In7.Cu")
		(net "PWRGD_P12V_NIC5_R")
	)
	(segment
		(start 368.475768 -202.286616)
		(end 368.740182 -202.022202)
		(width 0.15494)
		(layer "In7.Cu")
		(net "PWRGD_P12V_NIC5_R")
	)
	(segment
		(start 354.3808 -168.6052)
		(end 351.79 -166.0144)
		(width 0.15494)
		(layer "In7.Cu")
		(net "PWRGD_P12V_NIC5_R")
	)
	(segment
		(start 366.72266 -202.28687)
		(end 366.722914 -202.286616)
		(width 0.15494)
		(layer "In7.Cu")
		(net "PWRGD_P12V_NIC5_R")
	)
	(segment
		(start 356.6414 -212.9536)
		(end 356.362 -212.6742)
		(width 0.15494)
		(layer "In7.Cu")
		(net "PWRGD_P12V_NIC5_R")
	)
	(segment
		(start 369.03787 -201.724514)
		(end 369.644422 -201.117962)
		(width 0.15494)
		(layer "In7.Cu")
		(net "PWRGD_P12V_NIC5_R")
	)
	(segment
		(start 365.129826 -203.398374)
		(end 366.241584 -202.286616)
		(width 0.15494)
		(layer "In7.Cu")
		(net "PWRGD_P12V_NIC5_R")
	)
	(segment
		(start 357.01732 -209.427826)
		(end 360.235754 -206.209392)
		(width 0.15494)
		(layer "In7.Cu")
		(net "PWRGD_P12V_NIC5_R")
	)
	(segment
		(start 366.722914 -202.286616)
		(end 368.475768 -202.286616)
		(width 0.15494)
		(layer "In7.Cu")
		(net "PWRGD_P12V_NIC5_R")
	)
	(segment
		(start 370.591842 -175.977042)
		(end 365.961168 -171.346368)
		(width 0.15494)
		(layer "In7.Cu")
		(net "PWRGD_P12V_NIC5_R")
	)
	(segment
		(start 369.935252 -200.834752)
		(end 369.935252 -200.827132)
		(width 0.15494)
		(layer "In7.Cu")
		(net "PWRGD_P12V_NIC5_R")
	)
	(segment
		(start 310.063642 -82.414364)
		(end 310.736742 -82.414364)
		(width 0.15494)
		(layer "In9.Cu")
		(net "PWRGD_P12V_NIC5_R")
	)
	(segment
		(start 343.634822 -100.734876)
		(end 343.634822 -105.99547)
		(width 0.15494)
		(layer "In9.Cu")
		(net "PWRGD_P12V_NIC5_R")
	)
	(segment
		(start 327.979024 -91.656154)
		(end 327.979024 -93.198188)
		(width 0.15494)
		(layer "In9.Cu")
		(net "PWRGD_P12V_NIC5_R")
	)
	(segment
		(start 327.979024 -93.198188)
		(end 329.03414 -94.253304)
		(width 0.15494)
		(layer "In9.Cu")
		(net "PWRGD_P12V_NIC5_R")
	)
	(segment
		(start 341.959184 -116.625878)
		(end 341.336884 -117.248178)
		(width 0.15494)
		(layer "In9.Cu")
		(net "PWRGD_P12V_NIC5_R")
	)
	(segment
		(start 333.305658 -95.155512)
		(end 333.627984 -95.477838)
		(width 0.15494)
		(layer "In9.Cu")
		(net "PWRGD_P12V_NIC5_R")
	)
	(segment
		(start 311.998868 -83.059524)
		(end 319.119504 -90.18016)
		(width 0.15494)
		(layer "In9.Cu")
		(net "PWRGD_P12V_NIC5_R")
	)
	(segment
		(start 343.634822 -105.99547)
		(end 344.902028 -107.262676)
		(width 0.15494)
		(layer "In9.Cu")
		(net "PWRGD_P12V_NIC5_R")
	)
	(segment
		(start 344.902028 -115.28806)
		(end 343.56421 -116.625878)
		(width 0.15494)
		(layer "In9.Cu")
		(net "PWRGD_P12V_NIC5_R")
	)
	(segment
		(start 311.381902 -83.059524)
		(end 311.998868 -83.059524)
		(width 0.15494)
		(layer "In9.Cu")
		(net "PWRGD_P12V_NIC5_R")
	)
	(segment
		(start 343.56421 -116.625878)
		(end 341.959184 -116.625878)
		(width 0.15494)
		(layer "In9.Cu")
		(net "PWRGD_P12V_NIC5_R")
	)
	(segment
		(start 319.119504 -90.18016)
		(end 326.50303 -90.18016)
		(width 0.15494)
		(layer "In9.Cu")
		(net "PWRGD_P12V_NIC5_R")
	)
	(segment
		(start 338.377784 -95.477838)
		(end 343.634822 -100.734876)
		(width 0.15494)
		(layer "In9.Cu")
		(net "PWRGD_P12V_NIC5_R")
	)
	(segment
		(start 344.902028 -107.262676)
		(end 344.902028 -115.28806)
		(width 0.15494)
		(layer "In9.Cu")
		(net "PWRGD_P12V_NIC5_R")
	)
	(segment
		(start 333.627984 -95.477838)
		(end 338.377784 -95.477838)
		(width 0.15494)
		(layer "In9.Cu")
		(net "PWRGD_P12V_NIC5_R")
	)
	(segment
		(start 329.03414 -94.253304)
		(end 329.936348 -95.155512)
		(width 0.15494)
		(layer "In9.Cu")
		(net "PWRGD_P12V_NIC5_R")
	)
	(segment
		(start 326.50303 -90.18016)
		(end 327.979024 -91.656154)
		(width 0.15494)
		(layer "In9.Cu")
		(net "PWRGD_P12V_NIC5_R")
	)
	(segment
		(start 329.936348 -95.155512)
		(end 333.305658 -95.155512)
		(width 0.15494)
		(layer "In9.Cu")
		(net "PWRGD_P12V_NIC5_R")
	)
	(segment
		(start 310.736742 -82.414364)
		(end 311.381902 -83.059524)
		(width 0.15494)
		(layer "In9.Cu")
		(net "PWRGD_P12V_NIC5_R")
	)
	(segment
		(start 356.38359 -116.98351)
		(end 355.960172 -116.560092)
		(width 0.15494)
		(layer "In13.Cu")
		(net "PWRGD_P12V_NIC5_R")
	)
	(segment
		(start 342.02497 -116.560092)
		(end 341.336884 -117.248178)
		(width 0.15494)
		(layer "In13.Cu")
		(net "PWRGD_P12V_NIC5_R")
	)
	(segment
		(start 355.960172 -116.560092)
		(end 342.02497 -116.560092)
		(width 0.15494)
		(layer "In13.Cu")
		(net "PWRGD_P12V_NIC5_R")
	)
	(via
		(at 74.994262 -109.339126)
		(size 0.508)
		(drill 0.254)
		(layers "F.Cu" "B.Cu")
		(net "P12V_NIC1")
	)
	(via
		(at 87.98306 -109.65942)
		(size 0.6604)
		(drill 0.3302)
		(layers "F.Cu" "B.Cu")
		(net "P12V_NIC1")
	)
	(via
		(at 89.95537 -107.058206)
		(size 0.508)
		(drill 0.254)
		(layers "F.Cu" "B.Cu")
		(net "P12V_NIC1")
	)
	(via
		(at 74.283062 -110.659926)
		(size 0.508)
		(drill 0.254)
		(layers "F.Cu" "B.Cu")
		(net "P12V_NIC1")
	)
	(via
		(at 74.283062 -109.999526)
		(size 0.508)
		(drill 0.254)
		(layers "F.Cu" "B.Cu")
		(net "P12V_NIC1")
	)
	(via
		(at 74.994262 -110.659926)
		(size 0.508)
		(drill 0.254)
		(layers "F.Cu" "B.Cu")
		(net "P12V_NIC1")
	)
	(via
		(at 74.283062 -111.320326)
		(size 0.508)
		(drill 0.254)
		(layers "F.Cu" "B.Cu")
		(net "P12V_NIC1")
	)
	(via
		(at 89.95537 -105.737406)
		(size 0.508)
		(drill 0.254)
		(layers "F.Cu" "B.Cu")
		(net "P12V_NIC1")
	)
	(via
		(at 86.124288 -107.210352)
		(size 0.508)
		(drill 0.254)
		(layers "F.Cu" "B.Cu")
		(net "P12V_NIC1")
	)
	(via
		(at 74.994262 -109.999526)
		(size 0.508)
		(drill 0.254)
		(layers "F.Cu" "B.Cu")
		(net "P12V_NIC1")
	)
	(via
		(at 89.95537 -106.397806)
		(size 0.508)
		(drill 0.254)
		(layers "F.Cu" "B.Cu")
		(net "P12V_NIC1")
	)
	(via
		(at 88.941402 -104.674924)
		(size 0.508)
		(drill 0.254)
		(layers "F.Cu" "B.Cu")
		(net "P12V_NIC1")
	)
	(via
		(at 86.124288 -106.549952)
		(size 0.508)
		(drill 0.254)
		(layers "F.Cu" "B.Cu")
		(net "P12V_NIC1")
	)
	(via
		(at 74.994262 -111.320326)
		(size 0.508)
		(drill 0.254)
		(layers "F.Cu" "B.Cu")
		(net "P12V_NIC1")
	)
	(via
		(at 74.283062 -111.980726)
		(size 0.508)
		(drill 0.254)
		(layers "F.Cu" "B.Cu")
		(net "P12V_NIC1")
	)
	(via
		(at 74.994262 -111.980726)
		(size 0.508)
		(drill 0.254)
		(layers "F.Cu" "B.Cu")
		(net "P12V_NIC1")
	)
	(via
		(at 88.04783 -106.424984)
		(size 0.6604)
		(drill 0.3302)
		(layers "F.Cu" "B.Cu")
		(net "P12V_NIC1")
	)
	(via
		(at 86.124288 -105.889552)
		(size 0.508)
		(drill 0.254)
		(layers "F.Cu" "B.Cu")
		(net "P12V_NIC1")
	)
	(via
		(at 74.283062 -109.339126)
		(size 0.508)
		(drill 0.254)
		(layers "F.Cu" "B.Cu")
		(net "P12V_NIC1")
	)
	(via
		(at 433.05603 -112.28832)
		(size 0.6604)
		(drill 0.3302)
		(layers "F.Cu" "B.Cu")
		(net "P12V_NIC7")
	)
	(via
		(at 422.583102 -109.999526)
		(size 0.508)
		(drill 0.254)
		(layers "F.Cu" "B.Cu")
		(net "P12V_NIC7")
	)
	(via
		(at 423.294302 -109.339126)
		(size 0.508)
		(drill 0.254)
		(layers "F.Cu" "B.Cu")
		(net "P12V_NIC7")
	)
	(via
		(at 423.294302 -110.659926)
		(size 0.508)
		(drill 0.254)
		(layers "F.Cu" "B.Cu")
		(net "P12V_NIC7")
	)
	(via
		(at 423.294302 -109.999526)
		(size 0.508)
		(drill 0.254)
		(layers "F.Cu" "B.Cu")
		(net "P12V_NIC7")
	)
	(via
		(at 436.2831 -109.65942)
		(size 0.6604)
		(drill 0.3302)
		(layers "F.Cu" "B.Cu")
		(net "P12V_NIC7")
	)
	(via
		(at 438.25541 -107.058206)
		(size 0.508)
		(drill 0.254)
		(layers "F.Cu" "B.Cu")
		(net "P12V_NIC7")
	)
	(via
		(at 423.294302 -111.320326)
		(size 0.508)
		(drill 0.254)
		(layers "F.Cu" "B.Cu")
		(net "P12V_NIC7")
	)
	(via
		(at 436.34787 -106.424984)
		(size 0.6604)
		(drill 0.3302)
		(layers "F.Cu" "B.Cu")
		(net "P12V_NIC7")
	)
	(via
		(at 437.241442 -104.674924)
		(size 0.508)
		(drill 0.254)
		(layers "F.Cu" "B.Cu")
		(net "P12V_NIC7")
	)
	(via
		(at 422.583102 -109.339126)
		(size 0.508)
		(drill 0.254)
		(layers "F.Cu" "B.Cu")
		(net "P12V_NIC7")
	)
	(via
		(at 422.583102 -110.659926)
		(size 0.508)
		(drill 0.254)
		(layers "F.Cu" "B.Cu")
		(net "P12V_NIC7")
	)
	(via
		(at 422.583102 -111.980726)
		(size 0.508)
		(drill 0.254)
		(layers "F.Cu" "B.Cu")
		(net "P12V_NIC7")
	)
	(via
		(at 438.25541 -106.397806)
		(size 0.508)
		(drill 0.254)
		(layers "F.Cu" "B.Cu")
		(net "P12V_NIC7")
	)
	(via
		(at 431.645314 -110.193836)
		(size 0.6604)
		(drill 0.3302)
		(layers "F.Cu" "B.Cu")
		(net "P12V_NIC7")
	)
	(via
		(at 423.294302 -111.980726)
		(size 0.508)
		(drill 0.254)
		(layers "F.Cu" "B.Cu")
		(net "P12V_NIC7")
	)
	(via
		(at 438.25541 -105.737406)
		(size 0.508)
		(drill 0.254)
		(layers "F.Cu" "B.Cu")
		(net "P12V_NIC7")
	)
	(via
		(at 422.583102 -111.320326)
		(size 0.508)
		(drill 0.254)
		(layers "F.Cu" "B.Cu")
		(net "P12V_NIC7")
	)
	(segment
		(start 184.517792 -356.80777)
		(end 184.837832 -356.48773)
		(width 0.13462)
		(layer "F.Cu")
		(net "P5E_PEX1_STN4_TX_C_DN<68>")
	)
	(segment
		(start 184.517792 -357.439214)
		(end 184.517792 -356.80777)
		(width 0.13462)
		(layer "F.Cu")
		(net "P5E_PEX1_STN4_TX_C_DN<68>")
	)
	(segment
		(start 184.812432 -357.733854)
		(end 184.517792 -357.439214)
		(width 0.13462)
		(layer "F.Cu")
		(net "P5E_PEX1_STN4_TX_C_DN<68>")
	)
	(segment
		(start 166.509954 -372.508018)
		(end 166.637208 -372.380764)
		(width 0.1651)
		(layer "In7.Cu")
		(net "P5E_PEX1_STN4_TX_C_DN<68>")
	)
	(segment
		(start 166.509954 -372.890034)
		(end 166.509954 -372.508018)
		(width 0.1651)
		(layer "In7.Cu")
		(net "P5E_PEX1_STN4_TX_C_DN<68>")
	)
	(segment
		(start 166.98595 -372.380764)
		(end 167.569388 -371.797326)
		(width 0.1651)
		(layer "In7.Cu")
		(net "P5E_PEX1_STN4_TX_C_DN<68>")
	)
	(segment
		(start 166.637208 -372.380764)
		(end 166.98595 -372.380764)
		(width 0.1651)
		(layer "In7.Cu")
		(net "P5E_PEX1_STN4_TX_C_DN<68>")
	)
	(segment
		(start 168.741344 -367.873026)
		(end 169.954448 -367.314734)
		(width 0.1651)
		(layer "In7.Cu")
		(net "P5E_PEX1_STN4_TX_C_DN<68>")
	)
	(segment
		(start 180.465222 -362.804964)
		(end 184.521602 -358.9909)
		(width 0.1651)
		(layer "In7.Cu")
		(net "P5E_PEX1_STN4_TX_C_DN<68>")
	)
	(segment
		(start 167.569388 -371.797326)
		(end 167.569388 -369.122706)
		(width 0.1651)
		(layer "In7.Cu")
		(net "P5E_PEX1_STN4_TX_C_DN<68>")
	)
	(segment
		(start 167.569388 -369.122706)
		(end 168.741344 -367.873026)
		(width 0.1651)
		(layer "In7.Cu")
		(net "P5E_PEX1_STN4_TX_C_DN<68>")
	)
	(segment
		(start 184.521602 -358.9909)
		(end 184.521602 -358.024684)
		(width 0.1651)
		(layer "In7.Cu")
		(net "P5E_PEX1_STN4_TX_C_DN<68>")
	)
	(segment
		(start 169.954448 -367.314734)
		(end 180.465222 -362.804964)
		(width 0.1651)
		(layer "In7.Cu")
		(net "P5E_PEX1_STN4_TX_C_DN<68>")
	)
	(segment
		(start 184.521602 -358.024684)
		(end 184.812432 -357.733854)
		(width 0.1651)
		(layer "In7.Cu")
		(net "P5E_PEX1_STN4_TX_C_DN<68>")
	)
	(segment
		(start 202.433428 -350.034606)
		(end 202.586336 -349.982028)
		(width 0.1651)
		(layer "In5.Cu")
		(net "P5E_PEX1_STN4_RX_DP<64>")
	)
	(segment
		(start 211.138262 -312.916062)
		(end 210.976464 -312.916062)
		(width 0.1651)
		(layer "In5.Cu")
		(net "P5E_PEX1_STN4_RX_DP<64>")
	)
	(segment
		(start 213.227158 -315.004958)
		(end 211.138262 -312.916062)
		(width 0.1651)
		(layer "In5.Cu")
		(net "P5E_PEX1_STN4_RX_DP<64>")
	)
	(segment
		(start 197.353936 -358.356916)
		(end 200.368408 -354.52558)
		(width 0.1651)
		(layer "In5.Cu")
		(net "P5E_PEX1_STN4_RX_DP<64>")
	)
	(segment
		(start 201.733658 -351.728532)
		(end 201.68108 -351.575624)
		(width 0.1651)
		(layer "In5.Cu")
		(net "P5E_PEX1_STN4_RX_DP<64>")
	)
	(segment
		(start 199.7202 -305.065684)
		(end 199.67448 -305.019964)
		(width 0.1143)
		(layer "In5.Cu")
		(net "P5E_PEX1_STN4_RX_DP<64>")
	)
	(segment
		(start 199.67448 -305.019964)
		(end 198.205598 -305.019964)
		(width 0.1143)
		(layer "In5.Cu")
		(net "P5E_PEX1_STN4_RX_DP<64>")
	)
	(segment
		(start 199.748648 -305.065684)
		(end 199.7202 -305.065684)
		(width 0.1143)
		(layer "In5.Cu")
		(net "P5E_PEX1_STN4_RX_DP<64>")
	)
	(segment
		(start 210.275932 -312.053732)
		(end 210.114388 -312.053732)
		(width 0.1651)
		(layer "In5.Cu")
		(net "P5E_PEX1_STN4_RX_DP<64>")
	)
	(segment
		(start 176.087532 -379.681486)
		(end 176.087532 -369.199668)
		(width 0.1651)
		(layer "In5.Cu")
		(net "P5E_PEX1_STN4_RX_DP<64>")
	)
	(segment
		(start 202.051412 -351.077784)
		(end 202.268582 -350.632776)
		(width 0.1651)
		(layer "In5.Cu")
		(net "P5E_PEX1_STN4_RX_DP<64>")
	)
	(segment
		(start 214.95766 -319.232026)
		(end 213.227158 -315.004958)
		(width 0.1651)
		(layer "In5.Cu")
		(net "P5E_PEX1_STN4_RX_DP<64>")
	)
	(segment
		(start 209.763868 -311.541668)
		(end 204.66685 -306.44465)
		(width 0.1651)
		(layer "In5.Cu")
		(net "P5E_PEX1_STN4_RX_DP<64>")
	)
	(segment
		(start 200.368408 -354.52558)
		(end 201.733658 -351.728532)
		(width 0.1651)
		(layer "In5.Cu")
		(net "P5E_PEX1_STN4_RX_DP<64>")
	)
	(segment
		(start 210.625944 -312.565542)
		(end 210.625944 -312.403744)
		(width 0.1651)
		(layer "In5.Cu")
		(net "P5E_PEX1_STN4_RX_DP<64>")
	)
	(segment
		(start 197.979792 -304.564034)
		(end 197.865492 -304.449734)
		(width 0.1143)
		(layer "In5.Cu")
		(net "P5E_PEX1_STN4_RX_DP<64>")
	)
	(segment
		(start 202.268582 -350.632776)
		(end 202.216004 -350.479868)
		(width 0.1651)
		(layer "In5.Cu")
		(net "P5E_PEX1_STN4_RX_DP<64>")
	)
	(segment
		(start 202.750928 -349.384112)
		(end 202.968352 -348.93885)
		(width 0.1651)
		(layer "In5.Cu")
		(net "P5E_PEX1_STN4_RX_DP<64>")
	)
	(segment
		(start 204.66685 -306.44465)
		(end 201.337926 -305.065684)
		(width 0.1651)
		(layer "In5.Cu")
		(net "P5E_PEX1_STN4_RX_DP<64>")
	)
	(segment
		(start 175.310038 -379.390148)
		(end 175.310038 -379.772164)
		(width 0.1651)
		(layer "In5.Cu")
		(net "P5E_PEX1_STN4_RX_DP<64>")
	)
	(segment
		(start 201.337926 -305.065684)
		(end 199.748648 -305.065684)
		(width 0.1651)
		(layer "In5.Cu")
		(net "P5E_PEX1_STN4_RX_DP<64>")
	)
	(segment
		(start 214.061548 -326.473566)
		(end 214.95766 -321.99326)
		(width 0.1651)
		(layer "In5.Cu")
		(net "P5E_PEX1_STN4_RX_DP<64>")
	)
	(segment
		(start 210.625944 -312.403744)
		(end 210.275932 -312.053732)
		(width 0.1651)
		(layer "In5.Cu")
		(net "P5E_PEX1_STN4_RX_DP<64>")
	)
	(segment
		(start 202.968352 -348.93885)
		(end 203.12126 -348.886272)
		(width 0.1651)
		(layer "In5.Cu")
		(net "P5E_PEX1_STN4_RX_DP<64>")
	)
	(segment
		(start 191.400684 -364.38205)
		(end 197.353936 -358.356916)
		(width 0.1651)
		(layer "In5.Cu")
		(net "P5E_PEX1_STN4_RX_DP<64>")
	)
	(segment
		(start 197.865492 -304.449734)
		(end 197.600062 -304.449734)
		(width 0.1143)
		(layer "In5.Cu")
		(net "P5E_PEX1_STN4_RX_DP<64>")
	)
	(segment
		(start 202.216004 -350.479868)
		(end 202.433428 -350.034606)
		(width 0.1651)
		(layer "In5.Cu")
		(net "P5E_PEX1_STN4_RX_DP<64>")
	)
	(segment
		(start 214.95766 -321.99326)
		(end 214.95766 -319.232026)
		(width 0.1651)
		(layer "In5.Cu")
		(net "P5E_PEX1_STN4_RX_DP<64>")
	)
	(segment
		(start 209.763868 -311.703212)
		(end 209.763868 -311.541668)
		(width 0.1651)
		(layer "In5.Cu")
		(net "P5E_PEX1_STN4_RX_DP<64>")
	)
	(segment
		(start 203.121006 -348.886272)
		(end 214.061548 -326.473566)
		(width 0.1651)
		(layer "In5.Cu")
		(net "P5E_PEX1_STN4_RX_DP<64>")
	)
	(segment
		(start 201.898504 -351.130362)
		(end 202.051412 -351.077784)
		(width 0.1651)
		(layer "In5.Cu")
		(net "P5E_PEX1_STN4_RX_DP<64>")
	)
	(segment
		(start 176.947322 -368.339878)
		(end 188.11621 -366.080802)
		(width 0.1651)
		(layer "In5.Cu")
		(net "P5E_PEX1_STN4_RX_DP<64>")
	)
	(segment
		(start 175.869854 -379.899164)
		(end 176.087532 -379.681486)
		(width 0.1651)
		(layer "In5.Cu")
		(net "P5E_PEX1_STN4_RX_DP<64>")
	)
	(segment
		(start 175.437038 -379.899164)
		(end 175.869854 -379.899164)
		(width 0.1651)
		(layer "In5.Cu")
		(net "P5E_PEX1_STN4_RX_DP<64>")
	)
	(segment
		(start 188.11621 -366.080802)
		(end 191.400684 -364.38205)
		(width 0.1651)
		(layer "In5.Cu")
		(net "P5E_PEX1_STN4_RX_DP<64>")
	)
	(segment
		(start 176.087532 -369.199668)
		(end 176.947322 -368.339878)
		(width 0.1651)
		(layer "In5.Cu")
		(net "P5E_PEX1_STN4_RX_DP<64>")
	)
	(segment
		(start 198.205598 -305.019964)
		(end 197.979792 -304.794158)
		(width 0.1143)
		(layer "In5.Cu")
		(net "P5E_PEX1_STN4_RX_DP<64>")
	)
	(segment
		(start 210.114388 -312.053732)
		(end 209.763868 -311.703212)
		(width 0.1651)
		(layer "In5.Cu")
		(net "P5E_PEX1_STN4_RX_DP<64>")
	)
	(segment
		(start 202.586336 -349.982028)
		(end 202.803506 -349.53702)
		(width 0.1651)
		(layer "In5.Cu")
		(net "P5E_PEX1_STN4_RX_DP<64>")
	)
	(segment
		(start 202.803506 -349.53702)
		(end 202.750928 -349.384112)
		(width 0.1651)
		(layer "In5.Cu")
		(net "P5E_PEX1_STN4_RX_DP<64>")
	)
	(segment
		(start 203.12126 -348.886272)
		(end 203.121006 -348.886272)
		(width 0.1651)
		(layer "In5.Cu")
		(net "P5E_PEX1_STN4_RX_DP<64>")
	)
	(segment
		(start 201.68108 -351.575624)
		(end 201.898504 -351.130362)
		(width 0.1651)
		(layer "In5.Cu")
		(net "P5E_PEX1_STN4_RX_DP<64>")
	)
	(segment
		(start 197.979792 -304.794158)
		(end 197.979792 -304.564034)
		(width 0.1143)
		(layer "In5.Cu")
		(net "P5E_PEX1_STN4_RX_DP<64>")
	)
	(segment
		(start 210.976464 -312.916062)
		(end 210.625944 -312.565542)
		(width 0.1651)
		(layer "In5.Cu")
		(net "P5E_PEX1_STN4_RX_DP<64>")
	)
	(segment
		(start 175.310038 -379.772164)
		(end 175.437038 -379.899164)
		(width 0.1651)
		(layer "In5.Cu")
		(net "P5E_PEX1_STN4_RX_DP<64>")
	)
	(segment
		(start 178.594512 -357.75773)
		(end 178.299872 -357.46309)
		(width 0.13462)
		(layer "F.Cu")
		(net "P5E_PEX1_STN4_TX_C_DN<71>")
	)
	(segment
		(start 178.299872 -357.46309)
		(end 178.299872 -356.831646)
		(width 0.13462)
		(layer "F.Cu")
		(net "P5E_PEX1_STN4_TX_C_DN<71>")
	)
	(segment
		(start 178.299872 -356.831646)
		(end 178.619912 -356.511606)
		(width 0.13462)
		(layer "F.Cu")
		(net "P5E_PEX1_STN4_TX_C_DN<71>")
	)
	(segment
		(start 161.836862 -368.343688)
		(end 163.522914 -366.987836)
		(width 0.1651)
		(layer "In7.Cu")
		(net "P5E_PEX1_STN4_TX_C_DN<71>")
	)
	(segment
		(start 163.522914 -366.987836)
		(end 176.048924 -361.203748)
		(width 0.1651)
		(layer "In7.Cu")
		(net "P5E_PEX1_STN4_TX_C_DN<71>")
	)
	(segment
		(start 160.969452 -369.487196)
		(end 161.836862 -368.343688)
		(width 0.1651)
		(layer "In7.Cu")
		(net "P5E_PEX1_STN4_TX_C_DN<71>")
	)
	(segment
		(start 160.969452 -370.697506)
		(end 160.969452 -369.487196)
		(width 0.1651)
		(layer "In7.Cu")
		(net "P5E_PEX1_STN4_TX_C_DN<71>")
	)
	(segment
		(start 160.037272 -371.280944)
		(end 160.386014 -371.280944)
		(width 0.1651)
		(layer "In7.Cu")
		(net "P5E_PEX1_STN4_TX_C_DN<71>")
	)
	(segment
		(start 160.386014 -371.280944)
		(end 160.969452 -370.697506)
		(width 0.1651)
		(layer "In7.Cu")
		(net "P5E_PEX1_STN4_TX_C_DN<71>")
	)
	(segment
		(start 178.303682 -359.023158)
		(end 178.303682 -358.04856)
		(width 0.1651)
		(layer "In7.Cu")
		(net "P5E_PEX1_STN4_TX_C_DN<71>")
	)
	(segment
		(start 178.303682 -358.04856)
		(end 178.594512 -357.75773)
		(width 0.1651)
		(layer "In7.Cu")
		(net "P5E_PEX1_STN4_TX_C_DN<71>")
	)
	(segment
		(start 159.910018 -371.790214)
		(end 159.910018 -371.408198)
		(width 0.1651)
		(layer "In7.Cu")
		(net "P5E_PEX1_STN4_TX_C_DN<71>")
	)
	(segment
		(start 176.048924 -361.203748)
		(end 178.303682 -359.023158)
		(width 0.1651)
		(layer "In7.Cu")
		(net "P5E_PEX1_STN4_TX_C_DN<71>")
	)
	(segment
		(start 159.910018 -371.408198)
		(end 160.037272 -371.280944)
		(width 0.1651)
		(layer "In7.Cu")
		(net "P5E_PEX1_STN4_TX_C_DN<71>")
	)
	(segment
		(start 200.895712 -350.63938)
		(end 201.116692 -350.196404)
		(width 0.1651)
		(layer "In5.Cu")
		(net "P5E_PEX1_STN4_RX_DP<65>")
	)
	(segment
		(start 199.679052 -353.07778)
		(end 200.57237 -351.287334)
		(width 0.1651)
		(layer "In5.Cu")
		(net "P5E_PEX1_STN4_RX_DP<65>")
	)
	(segment
		(start 204.61859 -308.22773)
		(end 204.26807 -307.87721)
		(width 0.1651)
		(layer "In5.Cu")
		(net "P5E_PEX1_STN4_RX_DP<65>")
	)
	(segment
		(start 212.636608 -316.084458)
		(end 212.636862 -316.084458)
		(width 0.1651)
		(layer "In5.Cu")
		(net "P5E_PEX1_STN4_RX_DP<65>")
	)
	(segment
		(start 214.00262 -321.897502)
		(end 214.00262 -319.42024)
		(width 0.1651)
		(layer "In5.Cu")
		(net "P5E_PEX1_STN4_RX_DP<65>")
	)
	(segment
		(start 173.10989 -378.67209)
		(end 173.23689 -378.79909)
		(width 0.1651)
		(layer "In5.Cu")
		(net "P5E_PEX1_STN4_RX_DP<65>")
	)
	(segment
		(start 209.276696 -312.88228)
		(end 208.93532 -312.540904)
		(width 0.1651)
		(layer "In5.Cu")
		(net "P5E_PEX1_STN4_RX_DP<65>")
	)
	(segment
		(start 190.76797 -363.570266)
		(end 193.50736 -360.810556)
		(width 0.1651)
		(layer "In5.Cu")
		(net "P5E_PEX1_STN4_RX_DP<65>")
	)
	(segment
		(start 212.636862 -316.084458)
		(end 211.159344 -314.60694)
		(width 0.1651)
		(layer "In5.Cu")
		(net "P5E_PEX1_STN4_RX_DP<65>")
	)
	(segment
		(start 193.50736 -360.810556)
		(end 198.791576 -354.617274)
		(width 0.1651)
		(layer "In5.Cu")
		(net "P5E_PEX1_STN4_RX_DP<65>")
	)
	(segment
		(start 201.661014 -349.10522)
		(end 201.609706 -348.951804)
		(width 0.1651)
		(layer "In5.Cu")
		(net "P5E_PEX1_STN4_RX_DP<65>")
	)
	(segment
		(start 201.831194 -348.50832)
		(end 201.984356 -348.457012)
		(width 0.1651)
		(layer "In5.Cu")
		(net "P5E_PEX1_STN4_RX_DP<65>")
	)
	(segment
		(start 201.060812 -306.015898)
		(end 199.799448 -306.015898)
		(width 0.1651)
		(layer "In5.Cu")
		(net "P5E_PEX1_STN4_RX_DP<65>")
	)
	(segment
		(start 200.521062 -351.134172)
		(end 200.742296 -350.690688)
		(width 0.1651)
		(layer "In5.Cu")
		(net "P5E_PEX1_STN4_RX_DP<65>")
	)
	(segment
		(start 174.2694 -368.528346)
		(end 175.013874 -368.023648)
		(width 0.1651)
		(layer "In5.Cu")
		(net "P5E_PEX1_STN4_RX_DP<65>")
	)
	(segment
		(start 176.691798 -367.416334)
		(end 187.59551 -365.21136)
		(width 0.1651)
		(layer "In5.Cu")
		(net "P5E_PEX1_STN4_RX_DP<65>")
	)
	(segment
		(start 201.116692 -350.196404)
		(end 201.065384 -350.042988)
		(width 0.1651)
		(layer "In5.Cu")
		(net "P5E_PEX1_STN4_RX_DP<65>")
	)
	(segment
		(start 213.177374 -326.022208)
		(end 214.00262 -321.897502)
		(width 0.1651)
		(layer "In5.Cu")
		(net "P5E_PEX1_STN4_RX_DP<65>")
	)
	(segment
		(start 199.72528 -305.970178)
		(end 196.305424 -305.970178)
		(width 0.1143)
		(layer "In5.Cu")
		(net "P5E_PEX1_STN4_RX_DP<65>")
	)
	(segment
		(start 209.784696 -313.232292)
		(end 209.434684 -312.88228)
		(width 0.1651)
		(layer "In5.Cu")
		(net "P5E_PEX1_STN4_RX_DP<65>")
	)
	(segment
		(start 198.791576 -354.617274)
		(end 199.679052 -353.07778)
		(width 0.1651)
		(layer "In5.Cu")
		(net "P5E_PEX1_STN4_RX_DP<65>")
	)
	(segment
		(start 201.065384 -350.042988)
		(end 201.286872 -349.599504)
		(width 0.1651)
		(layer "In5.Cu")
		(net "P5E_PEX1_STN4_RX_DP<65>")
	)
	(segment
		(start 201.286872 -349.599504)
		(end 201.440034 -349.548196)
		(width 0.1651)
		(layer "In5.Cu")
		(net "P5E_PEX1_STN4_RX_DP<65>")
	)
	(segment
		(start 204.780134 -308.22773)
		(end 204.61859 -308.22773)
		(width 0.1651)
		(layer "In5.Cu")
		(net "P5E_PEX1_STN4_RX_DP<65>")
	)
	(segment
		(start 210.135216 -313.74461)
		(end 209.784696 -313.39409)
		(width 0.1651)
		(layer "In5.Cu")
		(net "P5E_PEX1_STN4_RX_DP<65>")
	)
	(segment
		(start 211.159344 -314.60694)
		(end 210.997546 -314.60694)
		(width 0.1651)
		(layer "In5.Cu")
		(net "P5E_PEX1_STN4_RX_DP<65>")
	)
	(segment
		(start 199.771 -306.015898)
		(end 199.72528 -305.970178)
		(width 0.1143)
		(layer "In5.Cu")
		(net "P5E_PEX1_STN4_RX_DP<65>")
	)
	(segment
		(start 204.26807 -307.715666)
		(end 203.63434 -307.081936)
		(width 0.1651)
		(layer "In5.Cu")
		(net "P5E_PEX1_STN4_RX_DP<65>")
	)
	(segment
		(start 209.784696 -313.39409)
		(end 209.784696 -313.232292)
		(width 0.1651)
		(layer "In5.Cu")
		(net "P5E_PEX1_STN4_RX_DP<65>")
	)
	(segment
		(start 210.647026 -314.25642)
		(end 210.647026 -314.094622)
		(width 0.1651)
		(layer "In5.Cu")
		(net "P5E_PEX1_STN4_RX_DP<65>")
	)
	(segment
		(start 173.23689 -378.79909)
		(end 173.669706 -378.79909)
		(width 0.1651)
		(layer "In5.Cu")
		(net "P5E_PEX1_STN4_RX_DP<65>")
	)
	(segment
		(start 173.669706 -378.79909)
		(end 173.887384 -378.581412)
		(width 0.1651)
		(layer "In5.Cu")
		(net "P5E_PEX1_STN4_RX_DP<65>")
	)
	(segment
		(start 201.440034 -349.548196)
		(end 201.661014 -349.10522)
		(width 0.1651)
		(layer "In5.Cu")
		(net "P5E_PEX1_STN4_RX_DP<65>")
	)
	(segment
		(start 201.609706 -348.951804)
		(end 201.831194 -348.50832)
		(width 0.1651)
		(layer "In5.Cu")
		(net "P5E_PEX1_STN4_RX_DP<65>")
	)
	(segment
		(start 200.742296 -350.690688)
		(end 200.895712 -350.63938)
		(width 0.1651)
		(layer "In5.Cu")
		(net "P5E_PEX1_STN4_RX_DP<65>")
	)
	(segment
		(start 200.57237 -351.287334)
		(end 200.521062 -351.134172)
		(width 0.1651)
		(layer "In5.Cu")
		(net "P5E_PEX1_STN4_RX_DP<65>")
	)
	(segment
		(start 196.079618 -305.514248)
		(end 195.965318 -305.399948)
		(width 0.1143)
		(layer "In5.Cu")
		(net "P5E_PEX1_STN4_RX_DP<65>")
	)
	(segment
		(start 210.647026 -314.094622)
		(end 210.297014 -313.74461)
		(width 0.1651)
		(layer "In5.Cu")
		(net "P5E_PEX1_STN4_RX_DP<65>")
	)
	(segment
		(start 204.26807 -307.87721)
		(end 204.26807 -307.715666)
		(width 0.1651)
		(layer "In5.Cu")
		(net "P5E_PEX1_STN4_RX_DP<65>")
	)
	(segment
		(start 201.984356 -348.457012)
		(end 213.177374 -326.022208)
		(width 0.1651)
		(layer "In5.Cu")
		(net "P5E_PEX1_STN4_RX_DP<65>")
	)
	(segment
		(start 208.93532 -312.540904)
		(end 208.93532 -312.382916)
		(width 0.1651)
		(layer "In5.Cu")
		(net "P5E_PEX1_STN4_RX_DP<65>")
	)
	(segment
		(start 196.305424 -305.970178)
		(end 196.079618 -305.744372)
		(width 0.1143)
		(layer "In5.Cu")
		(net "P5E_PEX1_STN4_RX_DP<65>")
	)
	(segment
		(start 195.965318 -305.399948)
		(end 195.699888 -305.399948)
		(width 0.1143)
		(layer "In5.Cu")
		(net "P5E_PEX1_STN4_RX_DP<65>")
	)
	(segment
		(start 196.079618 -305.744372)
		(end 196.079618 -305.514248)
		(width 0.1143)
		(layer "In5.Cu")
		(net "P5E_PEX1_STN4_RX_DP<65>")
	)
	(segment
		(start 214.00262 -319.42024)
		(end 212.636608 -316.084458)
		(width 0.1651)
		(layer "In5.Cu")
		(net "P5E_PEX1_STN4_RX_DP<65>")
	)
	(segment
		(start 173.887384 -369.245642)
		(end 174.2694 -368.528346)
		(width 0.1651)
		(layer "In5.Cu")
		(net "P5E_PEX1_STN4_RX_DP<65>")
	)
	(segment
		(start 187.59551 -365.21136)
		(end 190.76797 -363.570266)
		(width 0.1651)
		(layer "In5.Cu")
		(net "P5E_PEX1_STN4_RX_DP<65>")
	)
	(segment
		(start 199.799448 -306.015898)
		(end 199.771 -306.015898)
		(width 0.1143)
		(layer "In5.Cu")
		(net "P5E_PEX1_STN4_RX_DP<65>")
	)
	(segment
		(start 173.887384 -378.581412)
		(end 173.887384 -369.245642)
		(width 0.1651)
		(layer "In5.Cu")
		(net "P5E_PEX1_STN4_RX_DP<65>")
	)
	(segment
		(start 175.013874 -368.023648)
		(end 176.691798 -367.416334)
		(width 0.1651)
		(layer "In5.Cu")
		(net "P5E_PEX1_STN4_RX_DP<65>")
	)
	(segment
		(start 208.93532 -312.382916)
		(end 204.780134 -308.22773)
		(width 0.1651)
		(layer "In5.Cu")
		(net "P5E_PEX1_STN4_RX_DP<65>")
	)
	(segment
		(start 210.297014 -313.74461)
		(end 210.135216 -313.74461)
		(width 0.1651)
		(layer "In5.Cu")
		(net "P5E_PEX1_STN4_RX_DP<65>")
	)
	(segment
		(start 173.10989 -378.290074)
		(end 173.10989 -378.67209)
		(width 0.1651)
		(layer "In5.Cu")
		(net "P5E_PEX1_STN4_RX_DP<65>")
	)
	(segment
		(start 209.434684 -312.88228)
		(end 209.276696 -312.88228)
		(width 0.1651)
		(layer "In5.Cu")
		(net "P5E_PEX1_STN4_RX_DP<65>")
	)
	(segment
		(start 210.997546 -314.60694)
		(end 210.647026 -314.25642)
		(width 0.1651)
		(layer "In5.Cu")
		(net "P5E_PEX1_STN4_RX_DP<65>")
	)
	(segment
		(start 203.63434 -307.081936)
		(end 201.060812 -306.015898)
		(width 0.1651)
		(layer "In5.Cu")
		(net "P5E_PEX1_STN4_RX_DP<65>")
	)
	(segment
		(start 197.603364 -348.309184)
		(end 197.75932 -348.267274)
		(width 0.1651)
		(layer "In5.Cu")
		(net "P5E_PEX1_STN4_RX_DP<68>")
	)
	(segment
		(start 202.348084 -310.721756)
		(end 202.09891 -310.00573)
		(width 0.1651)
		(layer "In5.Cu")
		(net "P5E_PEX1_STN4_RX_DP<68>")
	)
	(segment
		(start 197.150482 -349.32366)
		(end 197.397624 -348.894654)
		(width 0.1651)
		(layer "In5.Cu")
		(net "P5E_PEX1_STN4_RX_DP<68>")
	)
	(segment
		(start 206.419958 -314.78728)
		(end 202.348084 -310.721756)
		(width 0.1651)
		(layer "In5.Cu")
		(net "P5E_PEX1_STN4_RX_DP<68>")
	)
	(segment
		(start 166.636954 -379.899164)
		(end 167.06977 -379.899164)
		(width 0.1651)
		(layer "In5.Cu")
		(net "P5E_PEX1_STN4_RX_DP<68>")
	)
	(segment
		(start 210.462622 -324.807834)
		(end 211.1375 -321.437)
		(width 0.1651)
		(layer "In5.Cu")
		(net "P5E_PEX1_STN4_RX_DP<68>")
	)
	(segment
		(start 197.979792 -308.594252)
		(end 197.979792 -308.364128)
		(width 0.1143)
		(layer "In5.Cu")
		(net "P5E_PEX1_STN4_RX_DP<68>")
	)
	(segment
		(start 198.205598 -308.820058)
		(end 197.979792 -308.594252)
		(width 0.1143)
		(layer "In5.Cu")
		(net "P5E_PEX1_STN4_RX_DP<68>")
	)
	(segment
		(start 167.287448 -379.681486)
		(end 167.287448 -369.700302)
		(width 0.1651)
		(layer "In5.Cu")
		(net "P5E_PEX1_STN4_RX_DP<68>")
	)
	(segment
		(start 197.397624 -348.894654)
		(end 197.355714 -348.738444)
		(width 0.1651)
		(layer "In5.Cu")
		(net "P5E_PEX1_STN4_RX_DP<68>")
	)
	(segment
		(start 202.09891 -310.00573)
		(end 201.429112 -309.335932)
		(width 0.1651)
		(layer "In5.Cu")
		(net "P5E_PEX1_STN4_RX_DP<68>")
	)
	(segment
		(start 207.44434 -315.469778)
		(end 206.419958 -314.78728)
		(width 0.1651)
		(layer "In5.Cu")
		(net "P5E_PEX1_STN4_RX_DP<68>")
	)
	(segment
		(start 196.746622 -349.79483)
		(end 196.994272 -349.36557)
		(width 0.1651)
		(layer "In5.Cu")
		(net "P5E_PEX1_STN4_RX_DP<68>")
	)
	(segment
		(start 196.788532 -349.95104)
		(end 196.746622 -349.79483)
		(width 0.1651)
		(layer "In5.Cu")
		(net "P5E_PEX1_STN4_RX_DP<68>")
	)
	(segment
		(start 197.355714 -348.738444)
		(end 197.603364 -348.309184)
		(width 0.1651)
		(layer "In5.Cu")
		(net "P5E_PEX1_STN4_RX_DP<68>")
	)
	(segment
		(start 166.509954 -379.772164)
		(end 166.636954 -379.899164)
		(width 0.1651)
		(layer "In5.Cu")
		(net "P5E_PEX1_STN4_RX_DP<68>")
	)
	(segment
		(start 197.75932 -348.267274)
		(end 198.103998 -347.669358)
		(width 0.1651)
		(layer "In5.Cu")
		(net "P5E_PEX1_STN4_RX_DP<68>")
	)
	(segment
		(start 207.44434 -315.470032)
		(end 207.44434 -315.469778)
		(width 0.1651)
		(layer "In5.Cu")
		(net "P5E_PEX1_STN4_RX_DP<68>")
	)
	(segment
		(start 211.1375 -319.992248)
		(end 210.365848 -318.106044)
		(width 0.1651)
		(layer "In5.Cu")
		(net "P5E_PEX1_STN4_RX_DP<68>")
	)
	(segment
		(start 196.385434 -350.42221)
		(end 196.54139 -350.380046)
		(width 0.1651)
		(layer "In5.Cu")
		(net "P5E_PEX1_STN4_RX_DP<68>")
	)
	(segment
		(start 196.179694 -351.00768)
		(end 196.137784 -350.85147)
		(width 0.1651)
		(layer "In5.Cu")
		(net "P5E_PEX1_STN4_RX_DP<68>")
	)
	(segment
		(start 193.75882 -355.20757)
		(end 196.179694 -351.00768)
		(width 0.1651)
		(layer "In5.Cu")
		(net "P5E_PEX1_STN4_RX_DP<68>")
	)
	(segment
		(start 167.820086 -368.743738)
		(end 168.318688 -368.24539)
		(width 0.1651)
		(layer "In5.Cu")
		(net "P5E_PEX1_STN4_RX_DP<68>")
	)
	(segment
		(start 198.103998 -347.669358)
		(end 205.622906 -333.760318)
		(width 0.1651)
		(layer "In5.Cu")
		(net "P5E_PEX1_STN4_RX_DP<68>")
	)
	(segment
		(start 188.747908 -361.345988)
		(end 190.742824 -359.335832)
		(width 0.1651)
		(layer "In5.Cu")
		(net "P5E_PEX1_STN4_RX_DP<68>")
	)
	(segment
		(start 206.392272 -332.096872)
		(end 206.547212 -332.050644)
		(width 0.1651)
		(layer "In5.Cu")
		(net "P5E_PEX1_STN4_RX_DP<68>")
	)
	(segment
		(start 199.67448 -308.820058)
		(end 198.205598 -308.820058)
		(width 0.1143)
		(layer "In5.Cu")
		(net "P5E_PEX1_STN4_RX_DP<68>")
	)
	(segment
		(start 199.7202 -308.865778)
		(end 199.67448 -308.820058)
		(width 0.1143)
		(layer "In5.Cu")
		(net "P5E_PEX1_STN4_RX_DP<68>")
	)
	(segment
		(start 205.96733 -333.123286)
		(end 206.202788 -332.687676)
		(width 0.1651)
		(layer "In5.Cu")
		(net "P5E_PEX1_STN4_RX_DP<68>")
	)
	(segment
		(start 167.287448 -369.700302)
		(end 167.820086 -368.743738)
		(width 0.1651)
		(layer "In5.Cu")
		(net "P5E_PEX1_STN4_RX_DP<68>")
	)
	(segment
		(start 190.742824 -359.335832)
		(end 193.75882 -355.20757)
		(width 0.1651)
		(layer "In5.Cu")
		(net "P5E_PEX1_STN4_RX_DP<68>")
	)
	(segment
		(start 186.64682 -362.453428)
		(end 188.747908 -361.345988)
		(width 0.1651)
		(layer "In5.Cu")
		(net "P5E_PEX1_STN4_RX_DP<68>")
	)
	(segment
		(start 205.812644 -333.169514)
		(end 205.96733 -333.123286)
		(width 0.1651)
		(layer "In5.Cu")
		(net "P5E_PEX1_STN4_RX_DP<68>")
	)
	(segment
		(start 173.406562 -365.381032)
		(end 175.726598 -364.661704)
		(width 0.1651)
		(layer "In5.Cu")
		(net "P5E_PEX1_STN4_RX_DP<68>")
	)
	(segment
		(start 206.202788 -332.687676)
		(end 206.15656 -332.532736)
		(width 0.1651)
		(layer "In5.Cu")
		(net "P5E_PEX1_STN4_RX_DP<68>")
	)
	(segment
		(start 206.547212 -332.050644)
		(end 210.462622 -324.807834)
		(width 0.1651)
		(layer "In5.Cu")
		(net "P5E_PEX1_STN4_RX_DP<68>")
	)
	(segment
		(start 196.54139 -350.380046)
		(end 196.788532 -349.95104)
		(width 0.1651)
		(layer "In5.Cu")
		(net "P5E_PEX1_STN4_RX_DP<68>")
	)
	(segment
		(start 171.082716 -366.36706)
		(end 173.406562 -365.381032)
		(width 0.1651)
		(layer "In5.Cu")
		(net "P5E_PEX1_STN4_RX_DP<68>")
	)
	(segment
		(start 175.726598 -364.661704)
		(end 186.64682 -362.453428)
		(width 0.1651)
		(layer "In5.Cu")
		(net "P5E_PEX1_STN4_RX_DP<68>")
	)
	(segment
		(start 208.468214 -316.152022)
		(end 207.44434 -315.470032)
		(width 0.1651)
		(layer "In5.Cu")
		(net "P5E_PEX1_STN4_RX_DP<68>")
	)
	(segment
		(start 200.29424 -308.865778)
		(end 199.748648 -308.865778)
		(width 0.1651)
		(layer "In5.Cu")
		(net "P5E_PEX1_STN4_RX_DP<68>")
	)
	(segment
		(start 197.865492 -308.249828)
		(end 197.600062 -308.249828)
		(width 0.1143)
		(layer "In5.Cu")
		(net "P5E_PEX1_STN4_RX_DP<68>")
	)
	(segment
		(start 166.509954 -379.390148)
		(end 166.509954 -379.772164)
		(width 0.1651)
		(layer "In5.Cu")
		(net "P5E_PEX1_STN4_RX_DP<68>")
	)
	(segment
		(start 205.576678 -333.605632)
		(end 205.812644 -333.169514)
		(width 0.1651)
		(layer "In5.Cu")
		(net "P5E_PEX1_STN4_RX_DP<68>")
	)
	(segment
		(start 199.748648 -308.865778)
		(end 199.7202 -308.865778)
		(width 0.1143)
		(layer "In5.Cu")
		(net "P5E_PEX1_STN4_RX_DP<68>")
	)
	(segment
		(start 167.06977 -379.899164)
		(end 167.287448 -379.681486)
		(width 0.1651)
		(layer "In5.Cu")
		(net "P5E_PEX1_STN4_RX_DP<68>")
	)
	(segment
		(start 196.994272 -349.36557)
		(end 197.150482 -349.32366)
		(width 0.1651)
		(layer "In5.Cu")
		(net "P5E_PEX1_STN4_RX_DP<68>")
	)
	(segment
		(start 168.318688 -368.24539)
		(end 171.082716 -366.36706)
		(width 0.1651)
		(layer "In5.Cu")
		(net "P5E_PEX1_STN4_RX_DP<68>")
	)
	(segment
		(start 211.1375 -321.437)
		(end 211.1375 -319.992248)
		(width 0.1651)
		(layer "In5.Cu")
		(net "P5E_PEX1_STN4_RX_DP<68>")
	)
	(segment
		(start 197.979792 -308.364128)
		(end 197.865492 -308.249828)
		(width 0.1143)
		(layer "In5.Cu")
		(net "P5E_PEX1_STN4_RX_DP<68>")
	)
	(segment
		(start 201.429112 -309.335932)
		(end 200.29424 -308.865778)
		(width 0.1651)
		(layer "In5.Cu")
		(net "P5E_PEX1_STN4_RX_DP<68>")
	)
	(segment
		(start 196.137784 -350.85147)
		(end 196.385434 -350.42221)
		(width 0.1651)
		(layer "In5.Cu")
		(net "P5E_PEX1_STN4_RX_DP<68>")
	)
	(segment
		(start 210.365848 -318.106044)
		(end 208.468214 -316.152022)
		(width 0.1651)
		(layer "In5.Cu")
		(net "P5E_PEX1_STN4_RX_DP<68>")
	)
	(segment
		(start 206.15656 -332.532736)
		(end 206.392272 -332.096872)
		(width 0.1651)
		(layer "In5.Cu")
		(net "P5E_PEX1_STN4_RX_DP<68>")
	)
	(segment
		(start 205.622906 -333.760318)
		(end 205.576678 -333.605632)
		(width 0.1651)
		(layer "In5.Cu")
		(net "P5E_PEX1_STN4_RX_DP<68>")
	)
	(segment
		(start 163.432236 -365.812832)
		(end 171.692824 -362.180632)
		(width 0.1651)
		(layer "In5.Cu")
		(net "P5E_PEX1_STN4_RX_DN<72>")
	)
	(segment
		(start 196.535548 -318.320166)
		(end 196.649848 -318.434466)
		(width 0.1143)
		(layer "In5.Cu")
		(net "P5E_PEX1_STN4_RX_DN<72>")
	)
	(segment
		(start 175.310038 -406.690068)
		(end 175.310038 -406.308052)
		(width 0.1651)
		(layer "In5.Cu")
		(net "P5E_PEX1_STN4_RX_DN<72>")
	)
	(segment
		(start 182.967122 -358.527858)
		(end 182.967122 -341.907876)
		(width 0.1651)
		(layer "In5.Cu")
		(net "P5E_PEX1_STN4_RX_DN<72>")
	)
	(segment
		(start 175.323754 -361.055412)
		(end 181.737508 -359.757472)
		(width 0.1651)
		(layer "In5.Cu")
		(net "P5E_PEX1_STN4_RX_DN<72>")
	)
	(segment
		(start 174.233332 -393.493752)
		(end 170.273472 -390.840976)
		(width 0.1651)
		(layer "In5.Cu")
		(net "P5E_PEX1_STN4_RX_DN<72>")
	)
	(segment
		(start 193.273934 -328.48042)
		(end 195.222368 -325.735696)
		(width 0.1651)
		(layer "In5.Cu")
		(net "P5E_PEX1_STN4_RX_DN<72>")
	)
	(segment
		(start 182.967122 -341.907876)
		(end 184.008776 -339.801454)
		(width 0.1651)
		(layer "In5.Cu")
		(net "P5E_PEX1_STN4_RX_DN<72>")
	)
	(segment
		(start 175.310038 -406.308052)
		(end 175.437038 -406.181052)
		(width 0.1651)
		(layer "In5.Cu")
		(net "P5E_PEX1_STN4_RX_DN<72>")
	)
	(segment
		(start 176.369472 -405.798274)
		(end 176.369472 -395.629892)
		(width 0.1651)
		(layer "In5.Cu")
		(net "P5E_PEX1_STN4_RX_DN<72>")
	)
	(segment
		(start 196.270118 -318.434466)
		(end 196.384418 -318.320166)
		(width 0.1143)
		(layer "In5.Cu")
		(net "P5E_PEX1_STN4_RX_DN<72>")
	)
	(segment
		(start 158.70428 -370.232686)
		(end 159.224472 -368.910108)
		(width 0.1651)
		(layer "In5.Cu")
		(net "P5E_PEX1_STN4_RX_DN<72>")
	)
	(segment
		(start 159.224472 -368.910108)
		(end 159.715454 -368.419126)
		(width 0.1651)
		(layer "In5.Cu")
		(net "P5E_PEX1_STN4_RX_DN<72>")
	)
	(segment
		(start 159.715454 -368.419126)
		(end 163.432236 -365.812832)
		(width 0.1651)
		(layer "In5.Cu")
		(net "P5E_PEX1_STN4_RX_DN<72>")
	)
	(segment
		(start 163.31311 -387.20014)
		(end 159.622236 -385.64947)
		(width 0.1651)
		(layer "In5.Cu")
		(net "P5E_PEX1_STN4_RX_DN<72>")
	)
	(segment
		(start 196.315838 -320.0908)
		(end 196.270118 -320.04508)
		(width 0.1143)
		(layer "In5.Cu")
		(net "P5E_PEX1_STN4_RX_DN<72>")
	)
	(segment
		(start 196.315838 -322.306696)
		(end 196.315838 -320.119248)
		(width 0.1651)
		(layer "In5.Cu")
		(net "P5E_PEX1_STN4_RX_DN<72>")
	)
	(segment
		(start 184.008776 -339.801454)
		(end 193.273934 -328.48042)
		(width 0.1651)
		(layer "In5.Cu")
		(net "P5E_PEX1_STN4_RX_DN<72>")
	)
	(segment
		(start 159.622236 -385.64947)
		(end 159.284416 -385.31165)
		(width 0.1651)
		(layer "In5.Cu")
		(net "P5E_PEX1_STN4_RX_DN<72>")
	)
	(segment
		(start 175.437038 -406.181052)
		(end 175.986694 -406.181052)
		(width 0.1651)
		(layer "In5.Cu")
		(net "P5E_PEX1_STN4_RX_DN<72>")
	)
	(segment
		(start 170.273472 -390.840976)
		(end 163.31311 -387.20014)
		(width 0.1651)
		(layer "In5.Cu")
		(net "P5E_PEX1_STN4_RX_DN<72>")
	)
	(segment
		(start 181.737508 -359.757472)
		(end 182.967122 -358.527858)
		(width 0.1651)
		(layer "In5.Cu")
		(net "P5E_PEX1_STN4_RX_DN<72>")
	)
	(segment
		(start 196.649848 -318.434466)
		(end 196.649848 -318.699896)
		(width 0.1143)
		(layer "In5.Cu")
		(net "P5E_PEX1_STN4_RX_DN<72>")
	)
	(segment
		(start 176.369472 -395.629892)
		(end 174.233332 -393.493752)
		(width 0.1651)
		(layer "In5.Cu")
		(net "P5E_PEX1_STN4_RX_DN<72>")
	)
	(segment
		(start 196.270118 -320.04508)
		(end 196.270118 -318.434466)
		(width 0.1143)
		(layer "In5.Cu")
		(net "P5E_PEX1_STN4_RX_DN<72>")
	)
	(segment
		(start 171.692824 -362.180632)
		(end 175.323754 -361.055666)
		(width 0.1651)
		(layer "In5.Cu")
		(net "P5E_PEX1_STN4_RX_DN<72>")
	)
	(segment
		(start 196.384418 -318.320166)
		(end 196.535548 -318.320166)
		(width 0.1143)
		(layer "In5.Cu")
		(net "P5E_PEX1_STN4_RX_DN<72>")
	)
	(segment
		(start 175.323754 -361.055666)
		(end 175.323754 -361.055412)
		(width 0.1651)
		(layer "In5.Cu")
		(net "P5E_PEX1_STN4_RX_DN<72>")
	)
	(segment
		(start 196.315838 -320.119248)
		(end 196.315838 -320.0908)
		(width 0.1143)
		(layer "In5.Cu")
		(net "P5E_PEX1_STN4_RX_DN<72>")
	)
	(segment
		(start 175.986694 -406.181052)
		(end 176.369472 -405.798274)
		(width 0.1651)
		(layer "In5.Cu")
		(net "P5E_PEX1_STN4_RX_DN<72>")
	)
	(segment
		(start 158.70428 -383.94259)
		(end 158.70428 -370.232686)
		(width 0.1651)
		(layer "In5.Cu")
		(net "P5E_PEX1_STN4_RX_DN<72>")
	)
	(segment
		(start 159.284416 -385.31165)
		(end 158.70428 -383.94259)
		(width 0.1651)
		(layer "In5.Cu")
		(net "P5E_PEX1_STN4_RX_DN<72>")
	)
	(segment
		(start 195.222368 -325.735696)
		(end 196.315838 -322.306696)
		(width 0.1651)
		(layer "In5.Cu")
		(net "P5E_PEX1_STN4_RX_DN<72>")
	)
	(segment
		(start 180.839872 -351.611438)
		(end 181.134512 -351.316798)
		(width 0.13462)
		(layer "F.Cu")
		(net "P5E_PEX1_STN4_TX_C_DP<70>")
	)
	(segment
		(start 181.134512 -351.316798)
		(end 181.134512 -350.685354)
		(width 0.13462)
		(layer "F.Cu")
		(net "P5E_PEX1_STN4_TX_C_DP<70>")
	)
	(segment
		(start 181.134512 -350.685354)
		(end 180.814472 -350.365314)
		(width 0.13462)
		(layer "F.Cu")
		(net "P5E_PEX1_STN4_TX_C_DP<70>")
	)
	(segment
		(start 162.109912 -371.590062)
		(end 162.109912 -371.971824)
		(width 0.1651)
		(layer "In7.Cu")
		(net "P5E_PEX1_STN4_TX_C_DP<70>")
	)
	(segment
		(start 165.41877 -366.876838)
		(end 165.868858 -366.669574)
		(width 0.1651)
		(layer "In7.Cu")
		(net "P5E_PEX1_STN4_TX_C_DP<70>")
	)
	(segment
		(start 166.50335 -366.377474)
		(end 166.953438 -366.17021)
		(width 0.1651)
		(layer "In7.Cu")
		(net "P5E_PEX1_STN4_TX_C_DP<70>")
	)
	(segment
		(start 177.414936 -361.146344)
		(end 177.415698 -361.00258)
		(width 0.1651)
		(layer "In7.Cu")
		(net "P5E_PEX1_STN4_TX_C_DP<70>")
	)
	(segment
		(start 162.469068 -372.098824)
		(end 162.887406 -371.680486)
		(width 0.1651)
		(layer "In7.Cu")
		(net "P5E_PEX1_STN4_TX_C_DP<70>")
	)
	(segment
		(start 162.109912 -371.971824)
		(end 162.236912 -372.098824)
		(width 0.1651)
		(layer "In7.Cu")
		(net "P5E_PEX1_STN4_TX_C_DP<70>")
	)
	(segment
		(start 162.887406 -369.2398)
		(end 164.400738 -367.457228)
		(width 0.1651)
		(layer "In7.Cu")
		(net "P5E_PEX1_STN4_TX_C_DP<70>")
	)
	(segment
		(start 181.130702 -352.523298)
		(end 181.130702 -351.902268)
		(width 0.1651)
		(layer "In7.Cu")
		(net "P5E_PEX1_STN4_TX_C_DP<70>")
	)
	(segment
		(start 170.207178 -364.672118)
		(end 170.342052 -364.721902)
		(width 0.1651)
		(layer "In7.Cu")
		(net "P5E_PEX1_STN4_TX_C_DP<70>")
	)
	(segment
		(start 165.368986 -367.011458)
		(end 165.368986 -367.011712)
		(width 0.1651)
		(layer "In7.Cu")
		(net "P5E_PEX1_STN4_TX_C_DP<70>")
	)
	(segment
		(start 162.236912 -372.098824)
		(end 162.469068 -372.098824)
		(width 0.1651)
		(layer "In7.Cu")
		(net "P5E_PEX1_STN4_TX_C_DP<70>")
	)
	(segment
		(start 176.81194 -361.743752)
		(end 177.414936 -361.146344)
		(width 0.1651)
		(layer "In7.Cu")
		(net "P5E_PEX1_STN4_TX_C_DP<70>")
	)
	(segment
		(start 178.759612 -359.814368)
		(end 179.576222 -359.005378)
		(width 0.1651)
		(layer "In7.Cu")
		(net "P5E_PEX1_STN4_TX_C_DP<70>")
	)
	(segment
		(start 165.868858 -366.669574)
		(end 166.003732 -366.719358)
		(width 0.1651)
		(layer "In7.Cu")
		(net "P5E_PEX1_STN4_TX_C_DP<70>")
	)
	(segment
		(start 179.576222 -354.077778)
		(end 181.130702 -352.523298)
		(width 0.1651)
		(layer "In7.Cu")
		(net "P5E_PEX1_STN4_TX_C_DP<70>")
	)
	(segment
		(start 169.75709 -364.879382)
		(end 170.207178 -364.672118)
		(width 0.1651)
		(layer "In7.Cu")
		(net "P5E_PEX1_STN4_TX_C_DP<70>")
	)
	(segment
		(start 169.257472 -365.221266)
		(end 169.707306 -365.014256)
		(width 0.1651)
		(layer "In7.Cu")
		(net "P5E_PEX1_STN4_TX_C_DP<70>")
	)
	(segment
		(start 170.342052 -364.721902)
		(end 176.81194 -361.743752)
		(width 0.1651)
		(layer "In7.Cu")
		(net "P5E_PEX1_STN4_TX_C_DP<70>")
	)
	(segment
		(start 164.400738 -367.457228)
		(end 165.368986 -367.011458)
		(width 0.1651)
		(layer "In7.Cu")
		(net "P5E_PEX1_STN4_TX_C_DP<70>")
	)
	(segment
		(start 162.887406 -371.680486)
		(end 162.887406 -369.2398)
		(width 0.1651)
		(layer "In7.Cu")
		(net "P5E_PEX1_STN4_TX_C_DP<70>")
	)
	(segment
		(start 168.67251 -365.378746)
		(end 169.122598 -365.171482)
		(width 0.1651)
		(layer "In7.Cu")
		(net "P5E_PEX1_STN4_TX_C_DP<70>")
	)
	(segment
		(start 178.263804 -360.162348)
		(end 178.616102 -359.813606)
		(width 0.1651)
		(layer "In7.Cu")
		(net "P5E_PEX1_STN4_TX_C_DP<70>")
	)
	(segment
		(start 179.576222 -359.005378)
		(end 179.576222 -354.077778)
		(width 0.1651)
		(layer "In7.Cu")
		(net "P5E_PEX1_STN4_TX_C_DP<70>")
	)
	(segment
		(start 178.616102 -359.813606)
		(end 178.759612 -359.814368)
		(width 0.1651)
		(layer "In7.Cu")
		(net "P5E_PEX1_STN4_TX_C_DP<70>")
	)
	(segment
		(start 166.453566 -366.512348)
		(end 166.50335 -366.377474)
		(width 0.1651)
		(layer "In7.Cu")
		(net "P5E_PEX1_STN4_TX_C_DP<70>")
	)
	(segment
		(start 168.172892 -365.72063)
		(end 168.622726 -365.51362)
		(width 0.1651)
		(layer "In7.Cu")
		(net "P5E_PEX1_STN4_TX_C_DP<70>")
	)
	(segment
		(start 167.58793 -365.87811)
		(end 168.038018 -365.670846)
		(width 0.1651)
		(layer "In7.Cu")
		(net "P5E_PEX1_STN4_TX_C_DP<70>")
	)
	(segment
		(start 165.368986 -367.011712)
		(end 165.41877 -366.876838)
		(width 0.1651)
		(layer "In7.Cu")
		(net "P5E_PEX1_STN4_TX_C_DP<70>")
	)
	(segment
		(start 178.263296 -360.306112)
		(end 178.263804 -360.162348)
		(width 0.1651)
		(layer "In7.Cu")
		(net "P5E_PEX1_STN4_TX_C_DP<70>")
	)
	(segment
		(start 166.003732 -366.719358)
		(end 166.453566 -366.512348)
		(width 0.1651)
		(layer "In7.Cu")
		(net "P5E_PEX1_STN4_TX_C_DP<70>")
	)
	(segment
		(start 168.038018 -365.670846)
		(end 168.172892 -365.72063)
		(width 0.1651)
		(layer "In7.Cu")
		(net "P5E_PEX1_STN4_TX_C_DP<70>")
	)
	(segment
		(start 169.707306 -365.014256)
		(end 169.75709 -364.879382)
		(width 0.1651)
		(layer "In7.Cu")
		(net "P5E_PEX1_STN4_TX_C_DP<70>")
	)
	(segment
		(start 169.122598 -365.171482)
		(end 169.257472 -365.221266)
		(width 0.1651)
		(layer "In7.Cu")
		(net "P5E_PEX1_STN4_TX_C_DP<70>")
	)
	(segment
		(start 168.622726 -365.51362)
		(end 168.67251 -365.378746)
		(width 0.1651)
		(layer "In7.Cu")
		(net "P5E_PEX1_STN4_TX_C_DP<70>")
	)
	(segment
		(start 181.130702 -351.902268)
		(end 180.839872 -351.611438)
		(width 0.1651)
		(layer "In7.Cu")
		(net "P5E_PEX1_STN4_TX_C_DP<70>")
	)
	(segment
		(start 166.953438 -366.17021)
		(end 167.088312 -366.219994)
		(width 0.1651)
		(layer "In7.Cu")
		(net "P5E_PEX1_STN4_TX_C_DP<70>")
	)
	(segment
		(start 167.088312 -366.219994)
		(end 167.538146 -366.012984)
		(width 0.1651)
		(layer "In7.Cu")
		(net "P5E_PEX1_STN4_TX_C_DP<70>")
	)
	(segment
		(start 167.538146 -366.012984)
		(end 167.58793 -365.87811)
		(width 0.1651)
		(layer "In7.Cu")
		(net "P5E_PEX1_STN4_TX_C_DP<70>")
	)
	(segment
		(start 177.767742 -360.653838)
		(end 177.911506 -360.6546)
		(width 0.1651)
		(layer "In7.Cu")
		(net "P5E_PEX1_STN4_TX_C_DP<70>")
	)
	(segment
		(start 177.415698 -361.00258)
		(end 177.767742 -360.653838)
		(width 0.1651)
		(layer "In7.Cu")
		(net "P5E_PEX1_STN4_TX_C_DP<70>")
	)
	(segment
		(start 177.911506 -360.6546)
		(end 178.263296 -360.306112)
		(width 0.1651)
		(layer "In7.Cu")
		(net "P5E_PEX1_STN4_TX_C_DP<70>")
	)
	(segment
		(start 160.89249 -391.78738)
		(end 156.875226 -389.65759)
		(width 0.1651)
		(layer "In5.Cu")
		(net "P5E_PEX1_STN4_RX_DN<77>")
	)
	(segment
		(start 165.369494 -404.6982)
		(end 165.369494 -394.923518)
		(width 0.1651)
		(layer "In5.Cu")
		(net "P5E_PEX1_STN4_RX_DN<77>")
	)
	(segment
		(start 156.875226 -389.65759)
		(end 155.211526 -387.99389)
		(width 0.1651)
		(layer "In5.Cu")
		(net "P5E_PEX1_STN4_RX_DN<77>")
	)
	(segment
		(start 165.120828 -394.550138)
		(end 160.89249 -391.78738)
		(width 0.1651)
		(layer "In5.Cu")
		(net "P5E_PEX1_STN4_RX_DN<77>")
	)
	(segment
		(start 164.986716 -405.080978)
		(end 165.369494 -404.6982)
		(width 0.1651)
		(layer "In5.Cu")
		(net "P5E_PEX1_STN4_RX_DN<77>")
	)
	(segment
		(start 164.313362 -347.692218)
		(end 164.70884 -347.29674)
		(width 0.1651)
		(layer "In5.Cu")
		(net "P5E_PEX1_STN4_RX_DN<77>")
	)
	(segment
		(start 191.785748 -316.419992)
		(end 191.900048 -316.534292)
		(width 0.1143)
		(layer "In5.Cu")
		(net "P5E_PEX1_STN4_RX_DN<77>")
	)
	(segment
		(start 164.70884 -347.29674)
		(end 166.570406 -347.29674)
		(width 0.1651)
		(layer "In5.Cu")
		(net "P5E_PEX1_STN4_RX_DN<77>")
	)
	(segment
		(start 165.369494 -394.923518)
		(end 165.120828 -394.550138)
		(width 0.1651)
		(layer "In5.Cu")
		(net "P5E_PEX1_STN4_RX_DN<77>")
	)
	(segment
		(start 164.313362 -359.090976)
		(end 164.313362 -347.692218)
		(width 0.1651)
		(layer "In5.Cu")
		(net "P5E_PEX1_STN4_RX_DN<77>")
	)
	(segment
		(start 153.8859 -368.881152)
		(end 154.537918 -366.819434)
		(width 0.1651)
		(layer "In5.Cu")
		(net "P5E_PEX1_STN4_RX_DN<77>")
	)
	(segment
		(start 191.520318 -320.04508)
		(end 191.520318 -316.534292)
		(width 0.1143)
		(layer "In5.Cu")
		(net "P5E_PEX1_STN4_RX_DN<77>")
	)
	(segment
		(start 187.762896 -327.122536)
		(end 190.917322 -323.055742)
		(width 0.1651)
		(layer "In5.Cu")
		(net "P5E_PEX1_STN4_RX_DN<77>")
	)
	(segment
		(start 191.566038 -320.0908)
		(end 191.520318 -320.04508)
		(width 0.1143)
		(layer "In5.Cu")
		(net "P5E_PEX1_STN4_RX_DN<77>")
	)
	(segment
		(start 164.039042 -359.365296)
		(end 164.313362 -359.090976)
		(width 0.1651)
		(layer "In5.Cu")
		(net "P5E_PEX1_STN4_RX_DN<77>")
	)
	(segment
		(start 180.724556 -333.339948)
		(end 187.743846 -327.141586)
		(width 0.1651)
		(layer "In5.Cu")
		(net "P5E_PEX1_STN4_RX_DN<77>")
	)
	(segment
		(start 191.566038 -321.16141)
		(end 191.566038 -320.119248)
		(width 0.1651)
		(layer "In5.Cu")
		(net "P5E_PEX1_STN4_RX_DN<77>")
	)
	(segment
		(start 191.634618 -316.419992)
		(end 191.785748 -316.419992)
		(width 0.1143)
		(layer "In5.Cu")
		(net "P5E_PEX1_STN4_RX_DN<77>")
	)
	(segment
		(start 164.31006 -405.207978)
		(end 164.43706 -405.080978)
		(width 0.1651)
		(layer "In5.Cu")
		(net "P5E_PEX1_STN4_RX_DN<77>")
	)
	(segment
		(start 191.520318 -316.534292)
		(end 191.634618 -316.419992)
		(width 0.1143)
		(layer "In5.Cu")
		(net "P5E_PEX1_STN4_RX_DN<77>")
	)
	(segment
		(start 168.487344 -340.707472)
		(end 180.724556 -333.339948)
		(width 0.1651)
		(layer "In5.Cu")
		(net "P5E_PEX1_STN4_RX_DN<77>")
	)
	(segment
		(start 191.900048 -316.534292)
		(end 191.900048 -316.799722)
		(width 0.1143)
		(layer "In5.Cu")
		(net "P5E_PEX1_STN4_RX_DN<77>")
	)
	(segment
		(start 187.743846 -327.141586)
		(end 187.762896 -327.122536)
		(width 0.1651)
		(layer "In5.Cu")
		(net "P5E_PEX1_STN4_RX_DN<77>")
	)
	(segment
		(start 167.422322 -346.444824)
		(end 167.422322 -341.907876)
		(width 0.1651)
		(layer "In5.Cu")
		(net "P5E_PEX1_STN4_RX_DN<77>")
	)
	(segment
		(start 155.211526 -387.99389)
		(end 153.8859 -384.79222)
		(width 0.1651)
		(layer "In5.Cu")
		(net "P5E_PEX1_STN4_RX_DN<77>")
	)
	(segment
		(start 166.570406 -347.29674)
		(end 167.422322 -346.444824)
		(width 0.1651)
		(layer "In5.Cu")
		(net "P5E_PEX1_STN4_RX_DN<77>")
	)
	(segment
		(start 156.680408 -364.678722)
		(end 164.039042 -359.365296)
		(width 0.1651)
		(layer "In5.Cu")
		(net "P5E_PEX1_STN4_RX_DN<77>")
	)
	(segment
		(start 190.917322 -323.055742)
		(end 191.566038 -321.16141)
		(width 0.1651)
		(layer "In5.Cu")
		(net "P5E_PEX1_STN4_RX_DN<77>")
	)
	(segment
		(start 164.43706 -405.080978)
		(end 164.986716 -405.080978)
		(width 0.1651)
		(layer "In5.Cu")
		(net "P5E_PEX1_STN4_RX_DN<77>")
	)
	(segment
		(start 154.537918 -366.819434)
		(end 156.680408 -364.678722)
		(width 0.1651)
		(layer "In5.Cu")
		(net "P5E_PEX1_STN4_RX_DN<77>")
	)
	(segment
		(start 153.8859 -384.79222)
		(end 153.8859 -368.881152)
		(width 0.1651)
		(layer "In5.Cu")
		(net "P5E_PEX1_STN4_RX_DN<77>")
	)
	(segment
		(start 164.31006 -405.589994)
		(end 164.31006 -405.207978)
		(width 0.1651)
		(layer "In5.Cu")
		(net "P5E_PEX1_STN4_RX_DN<77>")
	)
	(segment
		(start 167.422322 -341.907876)
		(end 168.487344 -340.707472)
		(width 0.1651)
		(layer "In5.Cu")
		(net "P5E_PEX1_STN4_RX_DN<77>")
	)
	(segment
		(start 191.566038 -320.119248)
		(end 191.566038 -320.0908)
		(width 0.1143)
		(layer "In5.Cu")
		(net "P5E_PEX1_STN4_RX_DN<77>")
	)
	(segment
		(start 175.190912 -350.685354)
		(end 175.510952 -350.365314)
		(width 0.13462)
		(layer "F.Cu")
		(net "P5E_PEX1_STN4_TX_C_DN<73>")
	)
	(segment
		(start 175.485552 -351.611438)
		(end 175.190912 -351.316798)
		(width 0.13462)
		(layer "F.Cu")
		(net "P5E_PEX1_STN4_TX_C_DN<73>")
	)
	(segment
		(start 175.190912 -351.316798)
		(end 175.190912 -350.685354)
		(width 0.13462)
		(layer "F.Cu")
		(net "P5E_PEX1_STN4_TX_C_DN<73>")
	)
	(segment
		(start 174.169324 -394.793216)
		(end 173.729142 -394.414756)
		(width 0.1651)
		(layer "In7.Cu")
		(net "P5E_PEX1_STN4_TX_C_DN<73>")
	)
	(segment
		(start 175.194722 -352.660458)
		(end 175.194722 -351.902268)
		(width 0.1651)
		(layer "In7.Cu")
		(net "P5E_PEX1_STN4_TX_C_DN<73>")
	)
	(segment
		(start 173.10989 -397.408146)
		(end 173.237144 -397.280892)
		(width 0.1651)
		(layer "In7.Cu")
		(net "P5E_PEX1_STN4_TX_C_DN<73>")
	)
	(segment
		(start 158.451804 -385.829556)
		(end 157.74924 -384.13436)
		(width 0.1651)
		(layer "In7.Cu")
		(net "P5E_PEX1_STN4_TX_C_DN<73>")
	)
	(segment
		(start 162.819334 -364.784894)
		(end 172.050964 -360.927904)
		(width 0.1651)
		(layer "In7.Cu")
		(net "P5E_PEX1_STN4_TX_C_DN<73>")
	)
	(segment
		(start 173.640242 -359.338626)
		(end 173.640242 -354.214938)
		(width 0.1651)
		(layer "In7.Cu")
		(net "P5E_PEX1_STN4_TX_C_DN<73>")
	)
	(segment
		(start 173.10989 -397.790162)
		(end 173.10989 -397.408146)
		(width 0.1651)
		(layer "In7.Cu")
		(net "P5E_PEX1_STN4_TX_C_DN<73>")
	)
	(segment
		(start 159.078676 -386.45719)
		(end 158.451804 -385.829556)
		(width 0.1651)
		(layer "In7.Cu")
		(net "P5E_PEX1_STN4_TX_C_DN<73>")
	)
	(segment
		(start 175.194722 -351.902268)
		(end 175.485552 -351.611438)
		(width 0.1651)
		(layer "In7.Cu")
		(net "P5E_PEX1_STN4_TX_C_DN<73>")
	)
	(segment
		(start 157.74924 -384.13436)
		(end 157.74924 -369.95735)
		(width 0.1651)
		(layer "In7.Cu")
		(net "P5E_PEX1_STN4_TX_C_DN<73>")
	)
	(segment
		(start 162.859974 -388.046214)
		(end 159.078676 -386.45719)
		(width 0.1651)
		(layer "In7.Cu")
		(net "P5E_PEX1_STN4_TX_C_DN<73>")
	)
	(segment
		(start 172.050964 -360.927904)
		(end 173.640242 -359.338626)
		(width 0.1651)
		(layer "In7.Cu")
		(net "P5E_PEX1_STN4_TX_C_DN<73>")
	)
	(segment
		(start 173.729142 -394.414756)
		(end 169.563288 -391.628884)
		(width 0.1651)
		(layer "In7.Cu")
		(net "P5E_PEX1_STN4_TX_C_DN<73>")
	)
	(segment
		(start 157.74924 -369.95735)
		(end 158.41091 -368.444018)
		(width 0.1651)
		(layer "In7.Cu")
		(net "P5E_PEX1_STN4_TX_C_DN<73>")
	)
	(segment
		(start 173.585886 -397.280892)
		(end 174.169324 -396.697454)
		(width 0.1651)
		(layer "In7.Cu")
		(net "P5E_PEX1_STN4_TX_C_DN<73>")
	)
	(segment
		(start 174.169324 -396.697454)
		(end 174.169324 -394.793216)
		(width 0.1651)
		(layer "In7.Cu")
		(net "P5E_PEX1_STN4_TX_C_DN<73>")
	)
	(segment
		(start 173.237144 -397.280892)
		(end 173.585886 -397.280892)
		(width 0.1651)
		(layer "In7.Cu")
		(net "P5E_PEX1_STN4_TX_C_DN<73>")
	)
	(segment
		(start 173.640242 -354.214938)
		(end 175.194722 -352.660458)
		(width 0.1651)
		(layer "In7.Cu")
		(net "P5E_PEX1_STN4_TX_C_DN<73>")
	)
	(segment
		(start 169.563288 -391.628884)
		(end 162.859974 -388.046214)
		(width 0.1651)
		(layer "In7.Cu")
		(net "P5E_PEX1_STN4_TX_C_DN<73>")
	)
	(segment
		(start 159.250888 -367.25225)
		(end 162.819334 -364.784894)
		(width 0.1651)
		(layer "In7.Cu")
		(net "P5E_PEX1_STN4_TX_C_DN<73>")
	)
	(segment
		(start 158.41091 -368.444018)
		(end 159.250888 -367.25225)
		(width 0.1651)
		(layer "In7.Cu")
		(net "P5E_PEX1_STN4_TX_C_DN<73>")
	)
	(segment
		(start 168.972992 -351.316798)
		(end 168.972992 -350.685354)
		(width 0.13462)
		(layer "F.Cu")
		(net "P5E_PEX1_STN4_TX_C_DN<76>")
	)
	(segment
		(start 168.972992 -350.685354)
		(end 169.293032 -350.365314)
		(width 0.13462)
		(layer "F.Cu")
		(net "P5E_PEX1_STN4_TX_C_DN<76>")
	)
	(segment
		(start 169.267632 -351.611438)
		(end 168.972992 -351.316798)
		(width 0.13462)
		(layer "F.Cu")
		(net "P5E_PEX1_STN4_TX_C_DN<76>")
	)
	(segment
		(start 154.862784 -384.654552)
		(end 154.84094 -384.602228)
		(width 0.1651)
		(layer "In7.Cu")
		(net "P5E_PEX1_STN4_TX_C_DN<76>")
	)
	(segment
		(start 154.88412 -384.706114)
		(end 154.862784 -384.654552)
		(width 0.1651)
		(layer "In7.Cu")
		(net "P5E_PEX1_STN4_TX_C_DN<76>")
	)
	(segment
		(start 161.241232 -362.337604)
		(end 166.449756 -360.16184)
		(width 0.1651)
		(layer "In7.Cu")
		(net "P5E_PEX1_STN4_TX_C_DN<76>")
	)
	(segment
		(start 167.422322 -359.189274)
		(end 167.422322 -354.235258)
		(width 0.1651)
		(layer "In7.Cu")
		(net "P5E_PEX1_STN4_TX_C_DN<76>")
	)
	(segment
		(start 166.98595 -398.380966)
		(end 167.569388 -397.797528)
		(width 0.1651)
		(layer "In7.Cu")
		(net "P5E_PEX1_STN4_TX_C_DN<76>")
	)
	(segment
		(start 154.84094 -369.126008)
		(end 155.545028 -367.434622)
		(width 0.1651)
		(layer "In7.Cu")
		(net "P5E_PEX1_STN4_TX_C_DN<76>")
	)
	(segment
		(start 157.436312 -388.86765)
		(end 156.022294 -387.453886)
		(width 0.1651)
		(layer "In7.Cu")
		(net "P5E_PEX1_STN4_TX_C_DN<76>")
	)
	(segment
		(start 166.509954 -398.890236)
		(end 166.509954 -398.50822)
		(width 0.1651)
		(layer "In7.Cu")
		(net "P5E_PEX1_STN4_TX_C_DN<76>")
	)
	(segment
		(start 155.009088 -385.007866)
		(end 154.986228 -384.952748)
		(width 0.1651)
		(layer "In7.Cu")
		(net "P5E_PEX1_STN4_TX_C_DN<76>")
	)
	(segment
		(start 166.637208 -398.380966)
		(end 166.98595 -398.380966)
		(width 0.1651)
		(layer "In7.Cu")
		(net "P5E_PEX1_STN4_TX_C_DN<76>")
	)
	(segment
		(start 154.986228 -384.952748)
		(end 154.88412 -384.706114)
		(width 0.1651)
		(layer "In7.Cu")
		(net "P5E_PEX1_STN4_TX_C_DN<76>")
	)
	(segment
		(start 156.890212 -365.39424)
		(end 161.241232 -362.337604)
		(width 0.1651)
		(layer "In7.Cu")
		(net "P5E_PEX1_STN4_TX_C_DN<76>")
	)
	(segment
		(start 167.569388 -397.797528)
		(end 167.569388 -395.269212)
		(width 0.1651)
		(layer "In7.Cu")
		(net "P5E_PEX1_STN4_TX_C_DN<76>")
	)
	(segment
		(start 167.569388 -395.269212)
		(end 165.807644 -393.507468)
		(width 0.1651)
		(layer "In7.Cu")
		(net "P5E_PEX1_STN4_TX_C_DN<76>")
	)
	(segment
		(start 156.022294 -387.453886)
		(end 155.009088 -385.007866)
		(width 0.1651)
		(layer "In7.Cu")
		(net "P5E_PEX1_STN4_TX_C_DN<76>")
	)
	(segment
		(start 166.509954 -398.50822)
		(end 166.637208 -398.380966)
		(width 0.1651)
		(layer "In7.Cu")
		(net "P5E_PEX1_STN4_TX_C_DN<76>")
	)
	(segment
		(start 166.449756 -360.16184)
		(end 167.422322 -359.189274)
		(width 0.1651)
		(layer "In7.Cu")
		(net "P5E_PEX1_STN4_TX_C_DN<76>")
	)
	(segment
		(start 167.422322 -354.235258)
		(end 168.976802 -352.680778)
		(width 0.1651)
		(layer "In7.Cu")
		(net "P5E_PEX1_STN4_TX_C_DN<76>")
	)
	(segment
		(start 168.976802 -351.902268)
		(end 169.267632 -351.611438)
		(width 0.1651)
		(layer "In7.Cu")
		(net "P5E_PEX1_STN4_TX_C_DN<76>")
	)
	(segment
		(start 165.807644 -393.507468)
		(end 164.425376 -392.583416)
		(width 0.1651)
		(layer "In7.Cu")
		(net "P5E_PEX1_STN4_TX_C_DN<76>")
	)
	(segment
		(start 154.84094 -384.602228)
		(end 154.84094 -369.126008)
		(width 0.1651)
		(layer "In7.Cu")
		(net "P5E_PEX1_STN4_TX_C_DN<76>")
	)
	(segment
		(start 168.976802 -352.680778)
		(end 168.976802 -351.902268)
		(width 0.1651)
		(layer "In7.Cu")
		(net "P5E_PEX1_STN4_TX_C_DN<76>")
	)
	(segment
		(start 164.425376 -392.583416)
		(end 157.436312 -388.86765)
		(width 0.1651)
		(layer "In7.Cu")
		(net "P5E_PEX1_STN4_TX_C_DN<76>")
	)
	(segment
		(start 155.545028 -367.434622)
		(end 156.890212 -365.39424)
		(width 0.1651)
		(layer "In7.Cu")
		(net "P5E_PEX1_STN4_TX_C_DN<76>")
	)
	(segment
		(start 171.512992 -357.75773)
		(end 171.807632 -357.46309)
		(width 0.13462)
		(layer "F.Cu")
		(net "P5E_PEX1_STN4_TX_C_DP<74>")
	)
	(segment
		(start 171.807632 -357.46309)
		(end 171.807632 -356.831646)
		(width 0.13462)
		(layer "F.Cu")
		(net "P5E_PEX1_STN4_TX_C_DP<74>")
	)
	(segment
		(start 171.807632 -356.831646)
		(end 171.487592 -356.511606)
		(width 0.13462)
		(layer "F.Cu")
		(net "P5E_PEX1_STN4_TX_C_DP<74>")
	)
	(segment
		(start 166.697152 -391.633202)
		(end 164.755322 -390.489948)
		(width 0.1651)
		(layer "In7.Cu")
		(net "P5E_PEX1_STN4_TX_C_DP<74>")
	)
	(segment
		(start 162.22218 -363.692948)
		(end 170.568874 -360.20629)
		(width 0.1651)
		(layer "In7.Cu")
		(net "P5E_PEX1_STN4_TX_C_DP<74>")
	)
	(segment
		(start 168.162478 -392.599672)
		(end 167.735504 -392.347958)
		(width 0.1651)
		(layer "In7.Cu")
		(net "P5E_PEX1_STN4_TX_C_DP<74>")
	)
	(segment
		(start 157.253178 -367.853722)
		(end 158.249874 -366.440212)
		(width 0.1651)
		(layer "In7.Cu")
		(net "P5E_PEX1_STN4_TX_C_DP<74>")
	)
	(segment
		(start 167.704008 -392.226292)
		(end 167.277288 -391.975086)
		(width 0.1651)
		(layer "In7.Cu")
		(net "P5E_PEX1_STN4_TX_C_DP<74>")
	)
	(segment
		(start 158.32836 -387.45668)
		(end 158.32836 -387.456426)
		(width 0.1651)
		(layer "In7.Cu")
		(net "P5E_PEX1_STN4_TX_C_DP<74>")
	)
	(segment
		(start 171.803822 -358.04856)
		(end 171.512992 -357.75773)
		(width 0.1651)
		(layer "In7.Cu")
		(net "P5E_PEX1_STN4_TX_C_DP<74>")
	)
	(segment
		(start 168.284144 -392.568176)
		(end 168.162478 -392.599672)
		(width 0.1651)
		(layer "In7.Cu")
		(net "P5E_PEX1_STN4_TX_C_DP<74>")
	)
	(segment
		(start 158.32836 -387.456426)
		(end 157.403038 -386.53085)
		(width 0.1651)
		(layer "In7.Cu")
		(net "P5E_PEX1_STN4_TX_C_DP<74>")
	)
	(segment
		(start 156.51226 -369.687602)
		(end 156.567632 -369.42141)
		(width 0.1651)
		(layer "In7.Cu")
		(net "P5E_PEX1_STN4_TX_C_DP<74>")
	)
	(segment
		(start 158.36392 -387.49224)
		(end 158.32836 -387.45668)
		(width 0.1651)
		(layer "In7.Cu")
		(net "P5E_PEX1_STN4_TX_C_DP<74>")
	)
	(segment
		(start 161.621724 -388.873238)
		(end 160.752028 -388.507732)
		(width 0.1651)
		(layer "In7.Cu")
		(net "P5E_PEX1_STN4_TX_C_DP<74>")
	)
	(segment
		(start 158.65729 -387.627368)
		(end 158.36392 -387.49224)
		(width 0.1651)
		(layer "In7.Cu")
		(net "P5E_PEX1_STN4_TX_C_DP<74>")
	)
	(segment
		(start 171.68749 -397.680688)
		(end 171.68749 -395.482318)
		(width 0.1651)
		(layer "In7.Cu")
		(net "P5E_PEX1_STN4_TX_C_DP<74>")
	)
	(segment
		(start 156.567632 -369.42141)
		(end 157.253178 -367.853722)
		(width 0.1651)
		(layer "In7.Cu")
		(net "P5E_PEX1_STN4_TX_C_DP<74>")
	)
	(segment
		(start 158.249874 -366.440212)
		(end 162.22218 -363.692948)
		(width 0.1651)
		(layer "In7.Cu")
		(net "P5E_PEX1_STN4_TX_C_DP<74>")
	)
	(segment
		(start 167.155622 -392.006582)
		(end 166.728648 -391.755122)
		(width 0.1651)
		(layer "In7.Cu")
		(net "P5E_PEX1_STN4_TX_C_DP<74>")
	)
	(segment
		(start 171.036996 -398.099026)
		(end 171.269152 -398.099026)
		(width 0.1651)
		(layer "In7.Cu")
		(net "P5E_PEX1_STN4_TX_C_DP<74>")
	)
	(segment
		(start 171.269152 -398.099026)
		(end 171.68749 -397.680688)
		(width 0.1651)
		(layer "In7.Cu")
		(net "P5E_PEX1_STN4_TX_C_DP<74>")
	)
	(segment
		(start 164.755322 -390.489948)
		(end 161.621724 -388.873238)
		(width 0.1651)
		(layer "In7.Cu")
		(net "P5E_PEX1_STN4_TX_C_DP<74>")
	)
	(segment
		(start 160.716214 -388.492746)
		(end 158.65729 -387.627368)
		(width 0.1651)
		(layer "In7.Cu")
		(net "P5E_PEX1_STN4_TX_C_DP<74>")
	)
	(segment
		(start 171.803822 -358.956864)
		(end 171.803822 -358.04856)
		(width 0.1651)
		(layer "In7.Cu")
		(net "P5E_PEX1_STN4_TX_C_DP<74>")
	)
	(segment
		(start 156.51226 -384.381248)
		(end 156.51226 -369.687602)
		(width 0.1651)
		(layer "In7.Cu")
		(net "P5E_PEX1_STN4_TX_C_DP<74>")
	)
	(segment
		(start 171.68749 -395.482318)
		(end 169.47388 -393.268708)
		(width 0.1651)
		(layer "In7.Cu")
		(net "P5E_PEX1_STN4_TX_C_DP<74>")
	)
	(segment
		(start 167.277288 -391.975086)
		(end 167.155622 -392.006582)
		(width 0.1651)
		(layer "In7.Cu")
		(net "P5E_PEX1_STN4_TX_C_DP<74>")
	)
	(segment
		(start 170.909996 -397.59001)
		(end 170.909996 -397.972026)
		(width 0.1651)
		(layer "In7.Cu")
		(net "P5E_PEX1_STN4_TX_C_DP<74>")
	)
	(segment
		(start 157.403038 -386.53085)
		(end 156.51226 -384.381248)
		(width 0.1651)
		(layer "In7.Cu")
		(net "P5E_PEX1_STN4_TX_C_DP<74>")
	)
	(segment
		(start 170.568874 -360.20629)
		(end 171.803822 -358.956864)
		(width 0.1651)
		(layer "In7.Cu")
		(net "P5E_PEX1_STN4_TX_C_DP<74>")
	)
	(segment
		(start 167.735504 -392.347958)
		(end 167.704008 -392.226292)
		(width 0.1651)
		(layer "In7.Cu")
		(net "P5E_PEX1_STN4_TX_C_DP<74>")
	)
	(segment
		(start 166.728648 -391.755122)
		(end 166.697152 -391.633202)
		(width 0.1651)
		(layer "In7.Cu")
		(net "P5E_PEX1_STN4_TX_C_DP<74>")
	)
	(segment
		(start 169.47388 -393.268708)
		(end 168.284144 -392.568176)
		(width 0.1651)
		(layer "In7.Cu")
		(net "P5E_PEX1_STN4_TX_C_DP<74>")
	)
	(segment
		(start 170.909996 -397.972026)
		(end 171.036996 -398.099026)
		(width 0.1651)
		(layer "In7.Cu")
		(net "P5E_PEX1_STN4_TX_C_DP<74>")
	)
	(segment
		(start 160.752028 -388.507732)
		(end 160.716214 -388.492746)
		(width 0.1651)
		(layer "In7.Cu")
		(net "P5E_PEX1_STN4_TX_C_DP<74>")
	)
	(segment
		(start 192.294002 -340.890098)
		(end 192.294002 -352.278696)
		(width 0.1651)
		(layer "In5.Cu")
		(net "P5E_PEX1_STN4_RX_DN<69>")
	)
	(segment
		(start 164.31006 -379.20803)
		(end 164.31006 -379.590046)
		(width 0.1651)
		(layer "In5.Cu")
		(net "P5E_PEX1_STN4_RX_DN<69>")
	)
	(segment
		(start 173.176184 -364.747556)
		(end 173.174914 -364.748064)
		(width 0.1651)
		(layer "In5.Cu")
		(net "P5E_PEX1_STN4_RX_DN<69>")
	)
	(segment
		(start 201.669396 -311.414922)
		(end 201.669396 -317.074042)
		(width 0.1651)
		(layer "In5.Cu")
		(net "P5E_PEX1_STN4_RX_DN<69>")
	)
	(segment
		(start 196.384418 -309.579518)
		(end 199.67448 -309.579518)
		(width 0.1143)
		(layer "In5.Cu")
		(net "P5E_PEX1_STN4_RX_DN<69>")
	)
	(segment
		(start 169.601642 -366.263936)
		(end 168.64838 -366.668304)
		(width 0.1651)
		(layer "In5.Cu")
		(net "P5E_PEX1_STN4_RX_DN<69>")
	)
	(segment
		(start 188.322204 -360.809032)
		(end 186.418474 -361.81284)
		(width 0.1651)
		(layer "In5.Cu")
		(net "P5E_PEX1_STN4_RX_DN<69>")
	)
	(segment
		(start 199.472804 -325.678038)
		(end 197.427342 -330.659486)
		(width 0.1651)
		(layer "In5.Cu")
		(net "P5E_PEX1_STN4_RX_DN<69>")
	)
	(segment
		(start 199.748648 -309.533798)
		(end 200.310242 -309.533798)
		(width 0.1651)
		(layer "In5.Cu")
		(net "P5E_PEX1_STN4_RX_DN<69>")
	)
	(segment
		(start 192.294002 -352.278696)
		(end 191.821816 -354.651818)
		(width 0.1651)
		(layer "In5.Cu")
		(net "P5E_PEX1_STN4_RX_DN<69>")
	)
	(segment
		(start 196.649848 -309.199788)
		(end 196.384418 -309.199788)
		(width 0.1143)
		(layer "In5.Cu")
		(net "P5E_PEX1_STN4_RX_DN<69>")
	)
	(segment
		(start 191.821816 -354.651818)
		(end 189.950598 -359.169462)
		(width 0.1651)
		(layer "In5.Cu")
		(net "P5E_PEX1_STN4_RX_DN<69>")
	)
	(segment
		(start 200.310242 -309.533798)
		(end 200.79081 -310.014366)
		(width 0.1651)
		(layer "In5.Cu")
		(net "P5E_PEX1_STN4_RX_DN<69>")
	)
	(segment
		(start 175.557688 -364.008924)
		(end 173.176184 -364.747556)
		(width 0.1651)
		(layer "In5.Cu")
		(net "P5E_PEX1_STN4_RX_DN<69>")
	)
	(segment
		(start 200.716388 -319.359026)
		(end 199.472804 -325.678038)
		(width 0.1651)
		(layer "In5.Cu")
		(net "P5E_PEX1_STN4_RX_DN<69>")
	)
	(segment
		(start 168.64838 -366.668304)
		(end 165.866572 -368.558572)
		(width 0.1651)
		(layer "In5.Cu")
		(net "P5E_PEX1_STN4_RX_DN<69>")
	)
	(segment
		(start 196.384418 -309.199788)
		(end 196.270118 -309.314088)
		(width 0.1143)
		(layer "In5.Cu")
		(net "P5E_PEX1_STN4_RX_DN<69>")
	)
	(segment
		(start 164.43706 -379.08103)
		(end 164.31006 -379.20803)
		(width 0.1651)
		(layer "In5.Cu")
		(net "P5E_PEX1_STN4_RX_DN<69>")
	)
	(segment
		(start 189.950598 -359.169462)
		(end 188.322204 -360.809032)
		(width 0.1651)
		(layer "In5.Cu")
		(net "P5E_PEX1_STN4_RX_DN<69>")
	)
	(segment
		(start 186.418474 -361.81284)
		(end 175.557688 -364.008924)
		(width 0.1651)
		(layer "In5.Cu")
		(net "P5E_PEX1_STN4_RX_DN<69>")
	)
	(segment
		(start 199.67448 -309.579518)
		(end 199.7202 -309.533798)
		(width 0.1143)
		(layer "In5.Cu")
		(net "P5E_PEX1_STN4_RX_DN<69>")
	)
	(segment
		(start 165.369494 -369.466114)
		(end 165.369494 -378.698252)
		(width 0.1651)
		(layer "In5.Cu")
		(net "P5E_PEX1_STN4_RX_DN<69>")
	)
	(segment
		(start 201.669396 -317.074042)
		(end 200.716388 -319.359026)
		(width 0.1651)
		(layer "In5.Cu")
		(net "P5E_PEX1_STN4_RX_DN<69>")
	)
	(segment
		(start 164.986716 -379.08103)
		(end 164.43706 -379.08103)
		(width 0.1651)
		(layer "In5.Cu")
		(net "P5E_PEX1_STN4_RX_DN<69>")
	)
	(segment
		(start 199.7202 -309.533798)
		(end 199.748648 -309.533798)
		(width 0.1143)
		(layer "In5.Cu")
		(net "P5E_PEX1_STN4_RX_DN<69>")
	)
	(segment
		(start 197.427342 -330.659486)
		(end 192.294002 -340.890098)
		(width 0.1651)
		(layer "In5.Cu")
		(net "P5E_PEX1_STN4_RX_DN<69>")
	)
	(segment
		(start 165.866572 -368.558572)
		(end 165.369494 -369.466114)
		(width 0.1651)
		(layer "In5.Cu")
		(net "P5E_PEX1_STN4_RX_DN<69>")
	)
	(segment
		(start 196.270118 -309.465218)
		(end 196.384418 -309.579518)
		(width 0.1143)
		(layer "In5.Cu")
		(net "P5E_PEX1_STN4_RX_DN<69>")
	)
	(segment
		(start 165.369494 -378.698252)
		(end 164.986716 -379.08103)
		(width 0.1651)
		(layer "In5.Cu")
		(net "P5E_PEX1_STN4_RX_DN<69>")
	)
	(segment
		(start 200.79081 -310.014366)
		(end 201.669396 -311.414922)
		(width 0.1651)
		(layer "In5.Cu")
		(net "P5E_PEX1_STN4_RX_DN<69>")
	)
	(segment
		(start 173.174914 -364.748064)
		(end 171.869608 -365.301784)
		(width 0.1651)
		(layer "In5.Cu")
		(net "P5E_PEX1_STN4_RX_DN<69>")
	)
	(segment
		(start 171.869608 -365.301784)
		(end 169.601642 -366.263936)
		(width 0.1651)
		(layer "In5.Cu")
		(net "P5E_PEX1_STN4_RX_DN<69>")
	)
	(segment
		(start 196.270118 -309.314088)
		(end 196.270118 -309.465218)
		(width 0.1143)
		(layer "In5.Cu")
		(net "P5E_PEX1_STN4_RX_DN<69>")
	)
	(segment
		(start 184.812432 -345.465146)
		(end 184.517792 -345.170506)
		(width 0.13462)
		(layer "F.Cu")
		(net "P5E_PEX1_STN4_TX_C_DN<69>")
	)
	(segment
		(start 184.517792 -344.539062)
		(end 184.837832 -344.219022)
		(width 0.13462)
		(layer "F.Cu")
		(net "P5E_PEX1_STN4_TX_C_DN<69>")
	)
	(segment
		(start 184.517792 -345.170506)
		(end 184.517792 -344.539062)
		(width 0.13462)
		(layer "F.Cu")
		(net "P5E_PEX1_STN4_TX_C_DN<69>")
	)
	(segment
		(start 179.770024 -361.362752)
		(end 182.967122 -358.72928)
		(width 0.1651)
		(layer "In7.Cu")
		(net "P5E_PEX1_STN4_TX_C_DN<69>")
	)
	(segment
		(start 165.369494 -370.697506)
		(end 165.369494 -368.618516)
		(width 0.1651)
		(layer "In7.Cu")
		(net "P5E_PEX1_STN4_TX_C_DN<69>")
	)
	(segment
		(start 182.967122 -348.063058)
		(end 184.521602 -346.508578)
		(width 0.1651)
		(layer "In7.Cu")
		(net "P5E_PEX1_STN4_TX_C_DN<69>")
	)
	(segment
		(start 164.31006 -371.790214)
		(end 164.31006 -371.408198)
		(width 0.1651)
		(layer "In7.Cu")
		(net "P5E_PEX1_STN4_TX_C_DN<69>")
	)
	(segment
		(start 165.369494 -368.618516)
		(end 165.80739 -368.171984)
		(width 0.1651)
		(layer "In7.Cu")
		(net "P5E_PEX1_STN4_TX_C_DN<69>")
	)
	(segment
		(start 184.521602 -346.508578)
		(end 184.521602 -345.755976)
		(width 0.1651)
		(layer "In7.Cu")
		(net "P5E_PEX1_STN4_TX_C_DN<69>")
	)
	(segment
		(start 164.31006 -371.408198)
		(end 164.437314 -371.280944)
		(width 0.1651)
		(layer "In7.Cu")
		(net "P5E_PEX1_STN4_TX_C_DN<69>")
	)
	(segment
		(start 164.786056 -371.280944)
		(end 165.369494 -370.697506)
		(width 0.1651)
		(layer "In7.Cu")
		(net "P5E_PEX1_STN4_TX_C_DN<69>")
	)
	(segment
		(start 177.284126 -363.088174)
		(end 179.770024 -361.362752)
		(width 0.1651)
		(layer "In7.Cu")
		(net "P5E_PEX1_STN4_TX_C_DN<69>")
	)
	(segment
		(start 165.80739 -368.171984)
		(end 171.284392 -365.65078)
		(width 0.1651)
		(layer "In7.Cu")
		(net "P5E_PEX1_STN4_TX_C_DN<69>")
	)
	(segment
		(start 171.284392 -365.65078)
		(end 177.284126 -363.088174)
		(width 0.1651)
		(layer "In7.Cu")
		(net "P5E_PEX1_STN4_TX_C_DN<69>")
	)
	(segment
		(start 164.437314 -371.280944)
		(end 164.786056 -371.280944)
		(width 0.1651)
		(layer "In7.Cu")
		(net "P5E_PEX1_STN4_TX_C_DN<69>")
	)
	(segment
		(start 184.521602 -345.755976)
		(end 184.812432 -345.465146)
		(width 0.1651)
		(layer "In7.Cu")
		(net "P5E_PEX1_STN4_TX_C_DN<69>")
	)
	(segment
		(start 182.967122 -358.72928)
		(end 182.967122 -348.063058)
		(width 0.1651)
		(layer "In7.Cu")
		(net "P5E_PEX1_STN4_TX_C_DN<69>")
	)
	(segment
		(start 187.057792 -351.611438)
		(end 187.352432 -351.316798)
		(width 0.13462)
		(layer "F.Cu")
		(net "P5E_PEX1_STN4_TX_C_DP<67>")
	)
	(segment
		(start 187.352432 -351.316798)
		(end 187.352432 -350.685354)
		(width 0.13462)
		(layer "F.Cu")
		(net "P5E_PEX1_STN4_TX_C_DP<67>")
	)
	(segment
		(start 187.352432 -350.685354)
		(end 187.032392 -350.365314)
		(width 0.13462)
		(layer "F.Cu")
		(net "P5E_PEX1_STN4_TX_C_DP<67>")
	)
	(segment
		(start 185.794142 -353.981258)
		(end 187.348622 -352.426778)
		(width 0.1651)
		(layer "In7.Cu")
		(net "P5E_PEX1_STN4_TX_C_DP<67>")
	)
	(segment
		(start 178.337718 -364.524036)
		(end 178.486562 -364.587536)
		(width 0.1651)
		(layer "In7.Cu")
		(net "P5E_PEX1_STN4_TX_C_DP<67>")
	)
	(segment
		(start 185.434732 -359.48747)
		(end 185.794142 -359.146856)
		(width 0.1651)
		(layer "In7.Cu")
		(net "P5E_PEX1_STN4_TX_C_DP<67>")
	)
	(segment
		(start 177.877978 -364.709202)
		(end 178.337718 -364.524036)
		(width 0.1651)
		(layer "In7.Cu")
		(net "P5E_PEX1_STN4_TX_C_DP<67>")
	)
	(segment
		(start 182.778654 -362.003086)
		(end 183.138318 -361.662472)
		(width 0.1651)
		(layer "In7.Cu")
		(net "P5E_PEX1_STN4_TX_C_DP<67>")
	)
	(segment
		(start 177.239676 -364.993682)
		(end 177.3555 -365.042958)
		(width 0.1651)
		(layer "In7.Cu")
		(net "P5E_PEX1_STN4_TX_C_DP<67>")
	)
	(segment
		(start 170.87977 -367.650268)
		(end 176.730406 -365.294164)
		(width 0.1651)
		(layer "In7.Cu")
		(net "P5E_PEX1_STN4_TX_C_DP<67>")
	)
	(segment
		(start 182.617618 -361.998768)
		(end 182.779162 -362.00334)
		(width 0.1651)
		(layer "In7.Cu")
		(net "P5E_PEX1_STN4_TX_C_DP<67>")
	)
	(segment
		(start 184.908952 -359.985564)
		(end 184.91327 -359.823766)
		(width 0.1651)
		(layer "In7.Cu")
		(net "P5E_PEX1_STN4_TX_C_DP<67>")
	)
	(segment
		(start 177.3555 -365.042958)
		(end 177.814732 -364.858046)
		(width 0.1651)
		(layer "In7.Cu")
		(net "P5E_PEX1_STN4_TX_C_DP<67>")
	)
	(segment
		(start 182.2577 -362.339636)
		(end 182.617618 -361.998768)
		(width 0.1651)
		(layer "In7.Cu")
		(net "P5E_PEX1_STN4_TX_C_DP<67>")
	)
	(segment
		(start 187.348622 -351.902268)
		(end 187.057792 -351.611438)
		(width 0.1651)
		(layer "In7.Cu")
		(net "P5E_PEX1_STN4_TX_C_DP<67>")
	)
	(segment
		(start 184.023762 -360.824272)
		(end 184.02808 -360.662474)
		(width 0.1651)
		(layer "In7.Cu")
		(net "P5E_PEX1_STN4_TX_C_DP<67>")
	)
	(segment
		(start 178.486562 -364.587536)
		(end 178.945794 -364.402624)
		(width 0.1651)
		(layer "In7.Cu")
		(net "P5E_PEX1_STN4_TX_C_DP<67>")
	)
	(segment
		(start 187.348622 -352.426778)
		(end 187.348622 -351.902268)
		(width 0.1651)
		(layer "In7.Cu")
		(net "P5E_PEX1_STN4_TX_C_DP<67>")
	)
	(segment
		(start 169.069258 -370.999004)
		(end 169.487596 -370.580666)
		(width 0.1651)
		(layer "In7.Cu")
		(net "P5E_PEX1_STN4_TX_C_DP<67>")
	)
	(segment
		(start 176.779936 -365.178848)
		(end 177.239676 -364.993682)
		(width 0.1651)
		(layer "In7.Cu")
		(net "P5E_PEX1_STN4_TX_C_DP<67>")
	)
	(segment
		(start 181.207918 -363.49178)
		(end 181.207918 -363.491526)
		(width 0.1651)
		(layer "In7.Cu")
		(net "P5E_PEX1_STN4_TX_C_DP<67>")
	)
	(segment
		(start 184.02808 -360.662474)
		(end 184.387998 -360.321606)
		(width 0.1651)
		(layer "In7.Cu")
		(net "P5E_PEX1_STN4_TX_C_DP<67>")
	)
	(segment
		(start 180.599842 -363.613192)
		(end 180.748686 -363.676692)
		(width 0.1651)
		(layer "In7.Cu")
		(net "P5E_PEX1_STN4_TX_C_DP<67>")
	)
	(segment
		(start 180.748686 -363.676692)
		(end 181.207918 -363.49178)
		(width 0.1651)
		(layer "In7.Cu")
		(net "P5E_PEX1_STN4_TX_C_DP<67>")
	)
	(segment
		(start 183.138572 -361.662726)
		(end 183.14289 -361.501182)
		(width 0.1651)
		(layer "In7.Cu")
		(net "P5E_PEX1_STN4_TX_C_DP<67>")
	)
	(segment
		(start 179.46878 -364.068614)
		(end 179.617624 -364.132114)
		(width 0.1651)
		(layer "In7.Cu")
		(net "P5E_PEX1_STN4_TX_C_DP<67>")
	)
	(segment
		(start 184.549542 -360.325924)
		(end 184.908698 -359.985564)
		(width 0.1651)
		(layer "In7.Cu")
		(net "P5E_PEX1_STN4_TX_C_DP<67>")
	)
	(segment
		(start 169.487596 -370.580666)
		(end 169.487596 -369.000532)
		(width 0.1651)
		(layer "In7.Cu")
		(net "P5E_PEX1_STN4_TX_C_DP<67>")
	)
	(segment
		(start 185.273188 -359.482898)
		(end 185.434732 -359.48747)
		(width 0.1651)
		(layer "In7.Cu")
		(net "P5E_PEX1_STN4_TX_C_DP<67>")
	)
	(segment
		(start 176.730406 -365.294164)
		(end 176.73066 -365.294672)
		(width 0.1651)
		(layer "In7.Cu")
		(net "P5E_PEX1_STN4_TX_C_DP<67>")
	)
	(segment
		(start 184.908698 -359.985564)
		(end 184.908952 -359.985564)
		(width 0.1651)
		(layer "In7.Cu")
		(net "P5E_PEX1_STN4_TX_C_DP<67>")
	)
	(segment
		(start 178.945794 -364.402624)
		(end 179.00904 -364.25378)
		(width 0.1651)
		(layer "In7.Cu")
		(net "P5E_PEX1_STN4_TX_C_DP<67>")
	)
	(segment
		(start 168.837102 -370.999004)
		(end 169.069258 -370.999004)
		(width 0.1651)
		(layer "In7.Cu")
		(net "P5E_PEX1_STN4_TX_C_DP<67>")
	)
	(segment
		(start 177.814732 -364.858046)
		(end 177.877978 -364.709202)
		(width 0.1651)
		(layer "In7.Cu")
		(net "P5E_PEX1_STN4_TX_C_DP<67>")
	)
	(segment
		(start 180.076856 -363.947202)
		(end 180.140102 -363.798358)
		(width 0.1651)
		(layer "In7.Cu")
		(net "P5E_PEX1_STN4_TX_C_DP<67>")
	)
	(segment
		(start 184.387998 -360.321606)
		(end 184.549542 -360.326178)
		(width 0.1651)
		(layer "In7.Cu")
		(net "P5E_PEX1_STN4_TX_C_DP<67>")
	)
	(segment
		(start 184.023254 -360.824018)
		(end 184.023762 -360.824272)
		(width 0.1651)
		(layer "In7.Cu")
		(net "P5E_PEX1_STN4_TX_C_DP<67>")
	)
	(segment
		(start 183.664352 -361.164378)
		(end 184.023254 -360.824018)
		(width 0.1651)
		(layer "In7.Cu")
		(net "P5E_PEX1_STN4_TX_C_DP<67>")
	)
	(segment
		(start 183.138318 -361.662472)
		(end 183.138572 -361.662726)
		(width 0.1651)
		(layer "In7.Cu")
		(net "P5E_PEX1_STN4_TX_C_DP<67>")
	)
	(segment
		(start 176.73066 -365.294672)
		(end 176.779936 -365.178848)
		(width 0.1651)
		(layer "In7.Cu")
		(net "P5E_PEX1_STN4_TX_C_DP<67>")
	)
	(segment
		(start 181.207918 -363.491526)
		(end 182.253382 -362.50118)
		(width 0.1651)
		(layer "In7.Cu")
		(net "P5E_PEX1_STN4_TX_C_DP<67>")
	)
	(segment
		(start 168.710102 -370.489988)
		(end 168.710102 -370.872004)
		(width 0.1651)
		(layer "In7.Cu")
		(net "P5E_PEX1_STN4_TX_C_DP<67>")
	)
	(segment
		(start 183.664352 -361.164632)
		(end 183.664352 -361.164378)
		(width 0.1651)
		(layer "In7.Cu")
		(net "P5E_PEX1_STN4_TX_C_DP<67>")
	)
	(segment
		(start 179.00904 -364.25378)
		(end 179.46878 -364.068614)
		(width 0.1651)
		(layer "In7.Cu")
		(net "P5E_PEX1_STN4_TX_C_DP<67>")
	)
	(segment
		(start 182.253382 -362.50118)
		(end 182.2577 -362.339636)
		(width 0.1651)
		(layer "In7.Cu")
		(net "P5E_PEX1_STN4_TX_C_DP<67>")
	)
	(segment
		(start 168.710102 -370.872004)
		(end 168.837102 -370.999004)
		(width 0.1651)
		(layer "In7.Cu")
		(net "P5E_PEX1_STN4_TX_C_DP<67>")
	)
	(segment
		(start 180.140102 -363.798358)
		(end 180.599842 -363.613192)
		(width 0.1651)
		(layer "In7.Cu")
		(net "P5E_PEX1_STN4_TX_C_DP<67>")
	)
	(segment
		(start 182.779162 -362.00334)
		(end 182.778654 -362.003086)
		(width 0.1651)
		(layer "In7.Cu")
		(net "P5E_PEX1_STN4_TX_C_DP<67>")
	)
	(segment
		(start 169.487596 -369.000532)
		(end 170.87977 -367.650268)
		(width 0.1651)
		(layer "In7.Cu")
		(net "P5E_PEX1_STN4_TX_C_DP<67>")
	)
	(segment
		(start 185.794142 -359.146856)
		(end 185.794142 -353.981258)
		(width 0.1651)
		(layer "In7.Cu")
		(net "P5E_PEX1_STN4_TX_C_DP<67>")
	)
	(segment
		(start 184.91327 -359.823766)
		(end 185.273188 -359.482898)
		(width 0.1651)
		(layer "In7.Cu")
		(net "P5E_PEX1_STN4_TX_C_DP<67>")
	)
	(segment
		(start 183.14289 -361.501182)
		(end 183.502808 -361.160314)
		(width 0.1651)
		(layer "In7.Cu")
		(net "P5E_PEX1_STN4_TX_C_DP<67>")
	)
	(segment
		(start 183.502808 -361.160314)
		(end 183.664352 -361.164632)
		(width 0.1651)
		(layer "In7.Cu")
		(net "P5E_PEX1_STN4_TX_C_DP<67>")
	)
	(segment
		(start 184.549542 -360.326178)
		(end 184.549542 -360.325924)
		(width 0.1651)
		(layer "In7.Cu")
		(net "P5E_PEX1_STN4_TX_C_DP<67>")
	)
	(segment
		(start 179.617624 -364.132114)
		(end 180.076856 -363.947202)
		(width 0.1651)
		(layer "In7.Cu")
		(net "P5E_PEX1_STN4_TX_C_DP<67>")
	)
	(segment
		(start 189.999874 -316.115192)
		(end 189.885574 -316.229492)
		(width 0.1143)
		(layer "In5.Cu")
		(net "P5E_PEX1_STN4_RX_DP<79>")
	)
	(segment
		(start 183.702452 -327.782428)
		(end 180.652674 -330.270104)
		(width 0.1651)
		(layer "In5.Cu")
		(net "P5E_PEX1_STN4_RX_DP<79>")
	)
	(segment
		(start 156.26969 -355.355652)
		(end 151.69388 -367.42878)
		(width 0.1651)
		(layer "In5.Cu")
		(net "P5E_PEX1_STN4_RX_DP<79>")
	)
	(segment
		(start 159.522668 -394.087604)
		(end 160.553146 -394.776198)
		(width 0.1651)
		(layer "In5.Cu")
		(net "P5E_PEX1_STN4_RX_DP<79>")
	)
	(segment
		(start 183.702706 -327.782174)
		(end 183.702706 -327.78192)
		(width 0.1651)
		(layer "In5.Cu")
		(net "P5E_PEX1_STN4_RX_DP<79>")
	)
	(segment
		(start 157.579314 -392.789156)
		(end 157.991048 -393.064238)
		(width 0.1651)
		(layer "In5.Cu")
		(net "P5E_PEX1_STN4_RX_DP<79>")
	)
	(segment
		(start 158.962852 -393.713462)
		(end 158.987236 -393.836906)
		(width 0.1651)
		(layer "In5.Cu")
		(net "P5E_PEX1_STN4_RX_DP<79>")
	)
	(segment
		(start 189.383924 -320.119248)
		(end 189.383924 -320.625216)
		(width 0.1651)
		(layer "In5.Cu")
		(net "P5E_PEX1_STN4_RX_DP<79>")
	)
	(segment
		(start 189.885574 -316.229492)
		(end 189.65545 -316.229492)
		(width 0.1143)
		(layer "In5.Cu")
		(net "P5E_PEX1_STN4_RX_DP<79>")
	)
	(segment
		(start 158.015686 -393.187428)
		(end 158.427928 -393.463018)
		(width 0.1651)
		(layer "In5.Cu")
		(net "P5E_PEX1_STN4_RX_DP<79>")
	)
	(segment
		(start 157.044136 -392.538204)
		(end 157.456378 -392.813794)
		(width 0.1651)
		(layer "In5.Cu")
		(net "P5E_PEX1_STN4_RX_DP<79>")
	)
	(segment
		(start 155.550362 -391.433304)
		(end 157.019498 -392.415014)
		(width 0.1651)
		(layer "In5.Cu")
		(net "P5E_PEX1_STN4_RX_DP<79>")
	)
	(segment
		(start 159.399478 -394.112242)
		(end 159.522668 -394.087604)
		(width 0.1651)
		(layer "In5.Cu")
		(net "P5E_PEX1_STN4_RX_DP<79>")
	)
	(segment
		(start 158.987236 -393.836906)
		(end 159.399478 -394.112242)
		(width 0.1651)
		(layer "In5.Cu")
		(net "P5E_PEX1_STN4_RX_DP<79>")
	)
	(segment
		(start 151.69388 -367.42878)
		(end 151.69388 -385.228846)
		(width 0.1651)
		(layer "In5.Cu")
		(net "P5E_PEX1_STN4_RX_DP<79>")
	)
	(segment
		(start 160.469834 -404.799038)
		(end 160.037018 -404.799038)
		(width 0.1651)
		(layer "In5.Cu")
		(net "P5E_PEX1_STN4_RX_DP<79>")
	)
	(segment
		(start 189.429644 -320.04508)
		(end 189.383924 -320.0908)
		(width 0.1143)
		(layer "In5.Cu")
		(net "P5E_PEX1_STN4_RX_DP<79>")
	)
	(segment
		(start 163.498022 -341.082122)
		(end 163.33851 -341.266526)
		(width 0.1651)
		(layer "In5.Cu")
		(net "P5E_PEX1_STN4_RX_DP<79>")
	)
	(segment
		(start 157.019498 -392.415014)
		(end 157.019752 -392.415014)
		(width 0.1651)
		(layer "In5.Cu")
		(net "P5E_PEX1_STN4_RX_DP<79>")
	)
	(segment
		(start 189.383924 -320.625216)
		(end 189.085982 -321.432682)
		(width 0.1651)
		(layer "In5.Cu")
		(net "P5E_PEX1_STN4_RX_DP<79>")
	)
	(segment
		(start 157.019752 -392.415014)
		(end 157.044136 -392.538204)
		(width 0.1651)
		(layer "In5.Cu")
		(net "P5E_PEX1_STN4_RX_DP<79>")
	)
	(segment
		(start 189.999874 -315.849762)
		(end 189.999874 -316.115192)
		(width 0.1143)
		(layer "In5.Cu")
		(net "P5E_PEX1_STN4_RX_DP<79>")
	)
	(segment
		(start 160.687512 -404.58136)
		(end 160.469834 -404.799038)
		(width 0.1651)
		(layer "In5.Cu")
		(net "P5E_PEX1_STN4_RX_DP<79>")
	)
	(segment
		(start 157.991048 -393.064238)
		(end 157.991302 -393.064238)
		(width 0.1651)
		(layer "In5.Cu")
		(net "P5E_PEX1_STN4_RX_DP<79>")
	)
	(segment
		(start 183.969406 -327.421494)
		(end 183.702706 -327.782174)
		(width 0.1651)
		(layer "In5.Cu")
		(net "P5E_PEX1_STN4_RX_DP<79>")
	)
	(segment
		(start 163.514024 -341.072724)
		(end 163.498022 -341.082122)
		(width 0.1651)
		(layer "In5.Cu")
		(net "P5E_PEX1_STN4_RX_DP<79>")
	)
	(segment
		(start 157.456378 -392.813794)
		(end 157.579314 -392.789156)
		(width 0.1651)
		(layer "In5.Cu")
		(net "P5E_PEX1_STN4_RX_DP<79>")
	)
	(segment
		(start 160.687512 -395.02715)
		(end 160.687512 -404.58136)
		(width 0.1651)
		(layer "In5.Cu")
		(net "P5E_PEX1_STN4_RX_DP<79>")
	)
	(segment
		(start 164.00018 -340.513162)
		(end 163.514024 -341.072724)
		(width 0.1651)
		(layer "In5.Cu")
		(net "P5E_PEX1_STN4_RX_DP<79>")
	)
	(segment
		(start 189.383924 -320.0908)
		(end 189.383924 -320.119248)
		(width 0.1143)
		(layer "In5.Cu")
		(net "P5E_PEX1_STN4_RX_DP<79>")
	)
	(segment
		(start 158.551118 -393.43838)
		(end 158.962852 -393.713462)
		(width 0.1651)
		(layer "In5.Cu")
		(net "P5E_PEX1_STN4_RX_DP<79>")
	)
	(segment
		(start 159.910018 -404.672038)
		(end 159.910018 -404.290022)
		(width 0.1651)
		(layer "In5.Cu")
		(net "P5E_PEX1_STN4_RX_DP<79>")
	)
	(segment
		(start 189.65545 -316.229492)
		(end 189.429644 -316.455298)
		(width 0.1143)
		(layer "In5.Cu")
		(net "P5E_PEX1_STN4_RX_DP<79>")
	)
	(segment
		(start 183.702706 -327.78192)
		(end 183.702452 -327.782428)
		(width 0.1651)
		(layer "In5.Cu")
		(net "P5E_PEX1_STN4_RX_DP<79>")
	)
	(segment
		(start 163.33851 -341.266526)
		(end 156.26969 -355.355652)
		(width 0.1651)
		(layer "In5.Cu")
		(net "P5E_PEX1_STN4_RX_DP<79>")
	)
	(segment
		(start 157.991302 -393.064238)
		(end 158.015686 -393.187428)
		(width 0.1651)
		(layer "In5.Cu")
		(net "P5E_PEX1_STN4_RX_DP<79>")
	)
	(segment
		(start 180.652674 -330.270104)
		(end 164.00018 -340.513162)
		(width 0.1651)
		(layer "In5.Cu")
		(net "P5E_PEX1_STN4_RX_DP<79>")
	)
	(segment
		(start 160.553146 -394.776198)
		(end 160.687512 -395.02715)
		(width 0.1651)
		(layer "In5.Cu")
		(net "P5E_PEX1_STN4_RX_DP<79>")
	)
	(segment
		(start 160.037018 -404.799038)
		(end 159.910018 -404.672038)
		(width 0.1651)
		(layer "In5.Cu")
		(net "P5E_PEX1_STN4_RX_DP<79>")
	)
	(segment
		(start 189.429644 -316.455298)
		(end 189.429644 -320.04508)
		(width 0.1143)
		(layer "In5.Cu")
		(net "P5E_PEX1_STN4_RX_DP<79>")
	)
	(segment
		(start 158.427928 -393.463018)
		(end 158.551118 -393.43838)
		(width 0.1651)
		(layer "In5.Cu")
		(net "P5E_PEX1_STN4_RX_DP<79>")
	)
	(segment
		(start 151.69388 -385.228846)
		(end 153.353008 -389.23595)
		(width 0.1651)
		(layer "In5.Cu")
		(net "P5E_PEX1_STN4_RX_DP<79>")
	)
	(segment
		(start 153.353008 -389.23595)
		(end 155.550362 -391.433304)
		(width 0.1651)
		(layer "In5.Cu")
		(net "P5E_PEX1_STN4_RX_DP<79>")
	)
	(segment
		(start 189.085982 -321.432682)
		(end 183.969406 -327.421494)
		(width 0.1651)
		(layer "In5.Cu")
		(net "P5E_PEX1_STN4_RX_DP<79>")
	)
	(segment
		(start 193.570352 -351.316798)
		(end 193.570352 -350.685354)
		(width 0.13462)
		(layer "F.Cu")
		(net "P5E_PEX1_STN4_TX_C_DP<65>")
	)
	(segment
		(start 193.570352 -350.685354)
		(end 193.250312 -350.365314)
		(width 0.13462)
		(layer "F.Cu")
		(net "P5E_PEX1_STN4_TX_C_DP<65>")
	)
	(segment
		(start 193.275712 -351.611438)
		(end 193.570352 -351.316798)
		(width 0.13462)
		(layer "F.Cu")
		(net "P5E_PEX1_STN4_TX_C_DP<65>")
	)
	(segment
		(start 191.850264 -357.19131)
		(end 192.040256 -356.73411)
		(width 0.1651)
		(layer "In7.Cu")
		(net "P5E_PEX1_STN4_TX_C_DP<65>")
	)
	(segment
		(start 190.485268 -358.412796)
		(end 190.835788 -358.062276)
		(width 0.1651)
		(layer "In7.Cu")
		(net "P5E_PEX1_STN4_TX_C_DP<65>")
	)
	(segment
		(start 191.985392 -356.601268)
		(end 192.175638 -356.14356)
		(width 0.1651)
		(layer "In7.Cu")
		(net "P5E_PEX1_STN4_TX_C_DP<65>")
	)
	(segment
		(start 190.135002 -358.906572)
		(end 190.485268 -358.556306)
		(width 0.1651)
		(layer "In7.Cu")
		(net "P5E_PEX1_STN4_TX_C_DP<65>")
	)
	(segment
		(start 190.835788 -358.062276)
		(end 190.979298 -358.062276)
		(width 0.1651)
		(layer "In7.Cu")
		(net "P5E_PEX1_STN4_TX_C_DP<65>")
	)
	(segment
		(start 188.141864 -360.812334)
		(end 188.645038 -360.39679)
		(width 0.1651)
		(layer "In7.Cu")
		(net "P5E_PEX1_STN4_TX_C_DP<65>")
	)
	(segment
		(start 187.20181 -361.588812)
		(end 187.583572 -361.273598)
		(width 0.1651)
		(layer "In7.Cu")
		(net "P5E_PEX1_STN4_TX_C_DP<65>")
	)
	(segment
		(start 190.979298 -358.062276)
		(end 191.850264 -357.19131)
		(width 0.1651)
		(layer "In7.Cu")
		(net "P5E_PEX1_STN4_TX_C_DP<65>")
	)
	(segment
		(start 185.718704 -362.665518)
		(end 186.100974 -362.349796)
		(width 0.1651)
		(layer "In7.Cu")
		(net "P5E_PEX1_STN4_TX_C_DP<65>")
	)
	(segment
		(start 174.255938 -368.607848)
		(end 174.769272 -368.152172)
		(width 0.1651)
		(layer "In7.Cu")
		(net "P5E_PEX1_STN4_TX_C_DP<65>")
	)
	(segment
		(start 192.175638 -356.14356)
		(end 192.30848 -356.088696)
		(width 0.1651)
		(layer "In7.Cu")
		(net "P5E_PEX1_STN4_TX_C_DP<65>")
	)
	(segment
		(start 185.16092 -363.126274)
		(end 185.321702 -363.141768)
		(width 0.1651)
		(layer "In7.Cu")
		(net "P5E_PEX1_STN4_TX_C_DP<65>")
	)
	(segment
		(start 186.100974 -362.349796)
		(end 186.261756 -362.36529)
		(width 0.1651)
		(layer "In7.Cu")
		(net "P5E_PEX1_STN4_TX_C_DP<65>")
	)
	(segment
		(start 186.643518 -362.050076)
		(end 186.658758 -361.88904)
		(width 0.1651)
		(layer "In7.Cu")
		(net "P5E_PEX1_STN4_TX_C_DP<65>")
	)
	(segment
		(start 189.640972 -359.257092)
		(end 189.991492 -358.906572)
		(width 0.1651)
		(layer "In7.Cu")
		(net "P5E_PEX1_STN4_TX_C_DP<65>")
	)
	(segment
		(start 193.566542 -351.902268)
		(end 193.275712 -351.611438)
		(width 0.1651)
		(layer "In7.Cu")
		(net "P5E_PEX1_STN4_TX_C_DP<65>")
	)
	(segment
		(start 173.887384 -370.580666)
		(end 173.887384 -369.288314)
		(width 0.1651)
		(layer "In7.Cu")
		(net "P5E_PEX1_STN4_TX_C_DP<65>")
	)
	(segment
		(start 193.566542 -353.062032)
		(end 193.566542 -351.902268)
		(width 0.1651)
		(layer "In7.Cu")
		(net "P5E_PEX1_STN4_TX_C_DP<65>")
	)
	(segment
		(start 189.991492 -358.906572)
		(end 190.135002 -358.906572)
		(width 0.1651)
		(layer "In7.Cu")
		(net "P5E_PEX1_STN4_TX_C_DP<65>")
	)
	(segment
		(start 186.658758 -361.88904)
		(end 187.041028 -361.573318)
		(width 0.1651)
		(layer "In7.Cu")
		(net "P5E_PEX1_STN4_TX_C_DP<65>")
	)
	(segment
		(start 184.77865 -363.441996)
		(end 185.16092 -363.126274)
		(width 0.1651)
		(layer "In7.Cu")
		(net "P5E_PEX1_STN4_TX_C_DP<65>")
	)
	(segment
		(start 187.583572 -361.273598)
		(end 187.598812 -361.112562)
		(width 0.1651)
		(layer "In7.Cu")
		(net "P5E_PEX1_STN4_TX_C_DP<65>")
	)
	(segment
		(start 186.261756 -362.36529)
		(end 186.643518 -362.050076)
		(width 0.1651)
		(layer "In7.Cu")
		(net "P5E_PEX1_STN4_TX_C_DP<65>")
	)
	(segment
		(start 173.10989 -370.489988)
		(end 173.10989 -370.872004)
		(width 0.1651)
		(layer "In7.Cu")
		(net "P5E_PEX1_STN4_TX_C_DP<65>")
	)
	(segment
		(start 192.040256 -356.73411)
		(end 191.985392 -356.601268)
		(width 0.1651)
		(layer "In7.Cu")
		(net "P5E_PEX1_STN4_TX_C_DP<65>")
	)
	(segment
		(start 185.703464 -362.826554)
		(end 185.718704 -362.665518)
		(width 0.1651)
		(layer "In7.Cu")
		(net "P5E_PEX1_STN4_TX_C_DP<65>")
	)
	(segment
		(start 183.396382 -364.732062)
		(end 183.823102 -364.37951)
		(width 0.1651)
		(layer "In7.Cu")
		(net "P5E_PEX1_STN4_TX_C_DP<65>")
	)
	(segment
		(start 174.769272 -368.152172)
		(end 183.396382 -364.732062)
		(width 0.1651)
		(layer "In7.Cu")
		(net "P5E_PEX1_STN4_TX_C_DP<65>")
	)
	(segment
		(start 184.381648 -363.918246)
		(end 184.76341 -363.603032)
		(width 0.1651)
		(layer "In7.Cu")
		(net "P5E_PEX1_STN4_TX_C_DP<65>")
	)
	(segment
		(start 185.321702 -363.141768)
		(end 185.703464 -362.826554)
		(width 0.1651)
		(layer "In7.Cu")
		(net "P5E_PEX1_STN4_TX_C_DP<65>")
	)
	(segment
		(start 173.469046 -370.999004)
		(end 173.887384 -370.580666)
		(width 0.1651)
		(layer "In7.Cu")
		(net "P5E_PEX1_STN4_TX_C_DP<65>")
	)
	(segment
		(start 190.485268 -358.556306)
		(end 190.485268 -358.412796)
		(width 0.1651)
		(layer "In7.Cu")
		(net "P5E_PEX1_STN4_TX_C_DP<65>")
	)
	(segment
		(start 173.10989 -370.872004)
		(end 173.23689 -370.999004)
		(width 0.1651)
		(layer "In7.Cu")
		(net "P5E_PEX1_STN4_TX_C_DP<65>")
	)
	(segment
		(start 187.041028 -361.573318)
		(end 187.20181 -361.588812)
		(width 0.1651)
		(layer "In7.Cu")
		(net "P5E_PEX1_STN4_TX_C_DP<65>")
	)
	(segment
		(start 187.981082 -360.79684)
		(end 188.141864 -360.812334)
		(width 0.1651)
		(layer "In7.Cu")
		(net "P5E_PEX1_STN4_TX_C_DP<65>")
	)
	(segment
		(start 187.598812 -361.112562)
		(end 187.981082 -360.79684)
		(width 0.1651)
		(layer "In7.Cu")
		(net "P5E_PEX1_STN4_TX_C_DP<65>")
	)
	(segment
		(start 183.823102 -364.37951)
		(end 183.838596 -364.218728)
		(width 0.1651)
		(layer "In7.Cu")
		(net "P5E_PEX1_STN4_TX_C_DP<65>")
	)
	(segment
		(start 183.838596 -364.218728)
		(end 184.220612 -363.903006)
		(width 0.1651)
		(layer "In7.Cu")
		(net "P5E_PEX1_STN4_TX_C_DP<65>")
	)
	(segment
		(start 188.645038 -360.39679)
		(end 189.640972 -359.400602)
		(width 0.1651)
		(layer "In7.Cu")
		(net "P5E_PEX1_STN4_TX_C_DP<65>")
	)
	(segment
		(start 173.23689 -370.999004)
		(end 173.469046 -370.999004)
		(width 0.1651)
		(layer "In7.Cu")
		(net "P5E_PEX1_STN4_TX_C_DP<65>")
	)
	(segment
		(start 192.30848 -356.088696)
		(end 193.566542 -353.062032)
		(width 0.1651)
		(layer "In7.Cu")
		(net "P5E_PEX1_STN4_TX_C_DP<65>")
	)
	(segment
		(start 184.76341 -363.603032)
		(end 184.77865 -363.441996)
		(width 0.1651)
		(layer "In7.Cu")
		(net "P5E_PEX1_STN4_TX_C_DP<65>")
	)
	(segment
		(start 189.640972 -359.400602)
		(end 189.640972 -359.257092)
		(width 0.1651)
		(layer "In7.Cu")
		(net "P5E_PEX1_STN4_TX_C_DP<65>")
	)
	(segment
		(start 184.220612 -363.903006)
		(end 184.381648 -363.918246)
		(width 0.1651)
		(layer "In7.Cu")
		(net "P5E_PEX1_STN4_TX_C_DP<65>")
	)
	(segment
		(start 173.887384 -369.288314)
		(end 174.255938 -368.607848)
		(width 0.1651)
		(layer "In7.Cu")
		(net "P5E_PEX1_STN4_TX_C_DP<65>")
	)
	(segment
		(start 192.735708 -318.129666)
		(end 192.850008 -318.015366)
		(width 0.1143)
		(layer "In5.Cu")
		(net "P5E_PEX1_STN4_RX_DP<76>")
	)
	(segment
		(start 192.234058 -320.119248)
		(end 192.234058 -320.0908)
		(width 0.1143)
		(layer "In5.Cu")
		(net "P5E_PEX1_STN4_RX_DP<76>")
	)
	(segment
		(start 170.01236 -346.96146)
		(end 170.249342 -346.724478)
		(width 0.1651)
		(layer "In5.Cu")
		(net "P5E_PEX1_STN4_RX_DP<76>")
	)
	(segment
		(start 167.06977 -405.899112)
		(end 167.287448 -405.681434)
		(width 0.1651)
		(layer "In5.Cu")
		(net "P5E_PEX1_STN4_RX_DP<76>")
	)
	(segment
		(start 154.559 -384.658362)
		(end 154.559 -369.213892)
		(width 0.1651)
		(layer "In5.Cu")
		(net "P5E_PEX1_STN4_RX_DP<76>")
	)
	(segment
		(start 165.627812 -393.726416)
		(end 164.28212 -392.827256)
		(width 0.1651)
		(layer "In5.Cu")
		(net "P5E_PEX1_STN4_RX_DP<76>")
	)
	(segment
		(start 161.038286 -362.363258)
		(end 165.885622 -360.231944)
		(width 0.1651)
		(layer "In5.Cu")
		(net "P5E_PEX1_STN4_RX_DP<76>")
	)
	(segment
		(start 192.279778 -318.355472)
		(end 192.505584 -318.129666)
		(width 0.1143)
		(layer "In5.Cu")
		(net "P5E_PEX1_STN4_RX_DP<76>")
	)
	(segment
		(start 164.28212 -392.827256)
		(end 157.26664 -389.096758)
		(width 0.1651)
		(layer "In5.Cu")
		(net "P5E_PEX1_STN4_RX_DP<76>")
	)
	(segment
		(start 168.092882 -346.96146)
		(end 170.01236 -346.96146)
		(width 0.1651)
		(layer "In5.Cu")
		(net "P5E_PEX1_STN4_RX_DP<76>")
	)
	(segment
		(start 170.249342 -341.80145)
		(end 170.639486 -341.357712)
		(width 0.1651)
		(layer "In5.Cu")
		(net "P5E_PEX1_STN4_RX_DP<76>")
	)
	(segment
		(start 166.636192 -394.892784)
		(end 166.294816 -394.551408)
		(width 0.1651)
		(layer "In5.Cu")
		(net "P5E_PEX1_STN4_RX_DP<76>")
	)
	(segment
		(start 166.509954 -405.772112)
		(end 166.636954 -405.899112)
		(width 0.1651)
		(layer "In5.Cu")
		(net "P5E_PEX1_STN4_RX_DP<76>")
	)
	(segment
		(start 191.50076 -323.597778)
		(end 192.23355 -321.319652)
		(width 0.1651)
		(layer "In5.Cu")
		(net "P5E_PEX1_STN4_RX_DP<76>")
	)
	(segment
		(start 192.234058 -321.318128)
		(end 192.234058 -320.119248)
		(width 0.1651)
		(layer "In5.Cu")
		(net "P5E_PEX1_STN4_RX_DP<76>")
	)
	(segment
		(start 167.140382 -347.91396)
		(end 168.092882 -346.96146)
		(width 0.1651)
		(layer "In5.Cu")
		(net "P5E_PEX1_STN4_RX_DP<76>")
	)
	(segment
		(start 157.26664 -389.096758)
		(end 155.783026 -387.613398)
		(width 0.1651)
		(layer "In5.Cu")
		(net "P5E_PEX1_STN4_RX_DP<76>")
	)
	(segment
		(start 192.505584 -318.129666)
		(end 192.735708 -318.129666)
		(width 0.1143)
		(layer "In5.Cu")
		(net "P5E_PEX1_STN4_RX_DP<76>")
	)
	(segment
		(start 170.6626 -341.3252)
		(end 176.043082 -337.742276)
		(width 0.1651)
		(layer "In5.Cu")
		(net "P5E_PEX1_STN4_RX_DP<76>")
	)
	(segment
		(start 192.234058 -320.0908)
		(end 192.279778 -320.04508)
		(width 0.1143)
		(layer "In5.Cu")
		(net "P5E_PEX1_STN4_RX_DP<76>")
	)
	(segment
		(start 155.783026 -387.613398)
		(end 154.559 -384.658362)
		(width 0.1651)
		(layer "In5.Cu")
		(net "P5E_PEX1_STN4_RX_DP<76>")
	)
	(segment
		(start 176.043082 -337.742276)
		(end 176.043336 -337.742276)
		(width 0.1651)
		(layer "In5.Cu")
		(net "P5E_PEX1_STN4_RX_DP<76>")
	)
	(segment
		(start 167.287448 -395.386052)
		(end 166.79418 -394.892784)
		(width 0.1651)
		(layer "In5.Cu")
		(net "P5E_PEX1_STN4_RX_DP<76>")
	)
	(segment
		(start 170.639486 -341.357712)
		(end 170.6626 -341.3252)
		(width 0.1651)
		(layer "In5.Cu")
		(net "P5E_PEX1_STN4_RX_DP<76>")
	)
	(segment
		(start 166.79418 -394.892784)
		(end 166.636192 -394.892784)
		(width 0.1651)
		(layer "In5.Cu")
		(net "P5E_PEX1_STN4_RX_DP<76>")
	)
	(segment
		(start 167.140382 -358.977438)
		(end 167.140382 -347.91396)
		(width 0.1651)
		(layer "In5.Cu")
		(net "P5E_PEX1_STN4_RX_DP<76>")
	)
	(segment
		(start 192.279778 -320.04508)
		(end 192.279778 -318.355472)
		(width 0.1143)
		(layer "In5.Cu")
		(net "P5E_PEX1_STN4_RX_DP<76>")
	)
	(segment
		(start 189.496446 -326.391778)
		(end 191.50076 -323.597778)
		(width 0.1651)
		(layer "In5.Cu")
		(net "P5E_PEX1_STN4_RX_DP<76>")
	)
	(segment
		(start 166.294816 -394.551408)
		(end 166.294816 -394.39342)
		(width 0.1651)
		(layer "In5.Cu")
		(net "P5E_PEX1_STN4_RX_DP<76>")
	)
	(segment
		(start 166.294816 -394.39342)
		(end 165.627812 -393.726416)
		(width 0.1651)
		(layer "In5.Cu")
		(net "P5E_PEX1_STN4_RX_DP<76>")
	)
	(segment
		(start 181.3814 -334.1878)
		(end 189.496446 -326.391778)
		(width 0.1651)
		(layer "In5.Cu")
		(net "P5E_PEX1_STN4_RX_DP<76>")
	)
	(segment
		(start 192.850008 -318.015366)
		(end 192.850008 -317.749936)
		(width 0.1143)
		(layer "In5.Cu")
		(net "P5E_PEX1_STN4_RX_DP<76>")
	)
	(segment
		(start 166.636954 -405.899112)
		(end 167.06977 -405.899112)
		(width 0.1651)
		(layer "In5.Cu")
		(net "P5E_PEX1_STN4_RX_DP<76>")
	)
	(segment
		(start 167.287448 -405.681434)
		(end 167.287448 -395.386052)
		(width 0.1651)
		(layer "In5.Cu")
		(net "P5E_PEX1_STN4_RX_DP<76>")
	)
	(segment
		(start 170.249342 -346.724478)
		(end 170.249342 -341.80145)
		(width 0.1651)
		(layer "In5.Cu")
		(net "P5E_PEX1_STN4_RX_DP<76>")
	)
	(segment
		(start 165.885622 -360.231944)
		(end 167.140382 -358.977438)
		(width 0.1651)
		(layer "In5.Cu")
		(net "P5E_PEX1_STN4_RX_DP<76>")
	)
	(segment
		(start 192.23355 -321.319652)
		(end 192.234058 -321.318128)
		(width 0.1651)
		(layer "In5.Cu")
		(net "P5E_PEX1_STN4_RX_DP<76>")
	)
	(segment
		(start 176.043336 -337.742276)
		(end 181.3814 -334.1878)
		(width 0.1651)
		(layer "In5.Cu")
		(net "P5E_PEX1_STN4_RX_DP<76>")
	)
	(segment
		(start 166.509954 -405.390096)
		(end 166.509954 -405.772112)
		(width 0.1651)
		(layer "In5.Cu")
		(net "P5E_PEX1_STN4_RX_DP<76>")
	)
	(segment
		(start 154.559 -369.213892)
		(end 155.2448 -367.064798)
		(width 0.1651)
		(layer "In5.Cu")
		(net "P5E_PEX1_STN4_RX_DP<76>")
	)
	(segment
		(start 155.2448 -367.064798)
		(end 157.11805 -365.193072)
		(width 0.1651)
		(layer "In5.Cu")
		(net "P5E_PEX1_STN4_RX_DP<76>")
	)
	(segment
		(start 157.11805 -365.193072)
		(end 161.038286 -362.363258)
		(width 0.1651)
		(layer "In5.Cu")
		(net "P5E_PEX1_STN4_RX_DP<76>")
	)
	(segment
		(start 166.158672 -357.75773)
		(end 165.864032 -357.46309)
		(width 0.13462)
		(layer "F.Cu")
		(net "P5E_PEX1_STN4_TX_C_DN<77>")
	)
	(segment
		(start 165.864032 -356.831646)
		(end 166.184072 -356.511606)
		(width 0.13462)
		(layer "F.Cu")
		(net "P5E_PEX1_STN4_TX_C_DN<77>")
	)
	(segment
		(start 165.864032 -357.46309)
		(end 165.864032 -356.831646)
		(width 0.13462)
		(layer "F.Cu")
		(net "P5E_PEX1_STN4_TX_C_DN<77>")
	)
	(segment
		(start 160.716214 -391.693908)
		(end 156.875226 -389.65759)
		(width 0.1651)
		(layer "In7.Cu")
		(net "P5E_PEX1_STN4_TX_C_DN<77>")
	)
	(segment
		(start 164.31006 -397.408146)
		(end 164.437314 -397.280892)
		(width 0.1651)
		(layer "In7.Cu")
		(net "P5E_PEX1_STN4_TX_C_DN<77>")
	)
	(segment
		(start 153.8859 -368.934746)
		(end 154.592782 -367.12779)
		(width 0.1651)
		(layer "In7.Cu")
		(net "P5E_PEX1_STN4_TX_C_DN<77>")
	)
	(segment
		(start 165.369494 -394.923264)
		(end 165.146482 -394.588492)
		(width 0.1651)
		(layer "In7.Cu")
		(net "P5E_PEX1_STN4_TX_C_DN<77>")
	)
	(segment
		(start 153.8859 -384.792474)
		(end 153.8859 -368.934746)
		(width 0.1651)
		(layer "In7.Cu")
		(net "P5E_PEX1_STN4_TX_C_DN<77>")
	)
	(segment
		(start 156.172408 -364.731046)
		(end 160.888934 -361.417616)
		(width 0.1651)
		(layer "In7.Cu")
		(net "P5E_PEX1_STN4_TX_C_DN<77>")
	)
	(segment
		(start 164.31006 -397.790162)
		(end 164.31006 -397.408146)
		(width 0.1651)
		(layer "In7.Cu")
		(net "P5E_PEX1_STN4_TX_C_DN<77>")
	)
	(segment
		(start 164.437314 -397.280892)
		(end 164.786056 -397.280892)
		(width 0.1651)
		(layer "In7.Cu")
		(net "P5E_PEX1_STN4_TX_C_DN<77>")
	)
	(segment
		(start 160.888934 -361.417616)
		(end 165.48989 -359.496868)
		(width 0.1651)
		(layer "In7.Cu")
		(net "P5E_PEX1_STN4_TX_C_DN<77>")
	)
	(segment
		(start 164.786056 -397.280892)
		(end 165.369494 -396.697454)
		(width 0.1651)
		(layer "In7.Cu")
		(net "P5E_PEX1_STN4_TX_C_DN<77>")
	)
	(segment
		(start 155.211526 -387.99389)
		(end 153.8859 -384.792474)
		(width 0.1651)
		(layer "In7.Cu")
		(net "P5E_PEX1_STN4_TX_C_DN<77>")
	)
	(segment
		(start 165.867842 -358.04856)
		(end 166.158672 -357.75773)
		(width 0.1651)
		(layer "In7.Cu")
		(net "P5E_PEX1_STN4_TX_C_DN<77>")
	)
	(segment
		(start 154.592782 -367.12779)
		(end 156.172408 -364.731046)
		(width 0.1651)
		(layer "In7.Cu")
		(net "P5E_PEX1_STN4_TX_C_DN<77>")
	)
	(segment
		(start 156.875226 -389.65759)
		(end 155.211526 -387.99389)
		(width 0.1651)
		(layer "In7.Cu")
		(net "P5E_PEX1_STN4_TX_C_DN<77>")
	)
	(segment
		(start 165.48989 -359.496868)
		(end 165.867842 -359.118916)
		(width 0.1651)
		(layer "In7.Cu")
		(net "P5E_PEX1_STN4_TX_C_DN<77>")
	)
	(segment
		(start 165.369494 -396.697454)
		(end 165.369494 -394.923264)
		(width 0.1651)
		(layer "In7.Cu")
		(net "P5E_PEX1_STN4_TX_C_DN<77>")
	)
	(segment
		(start 165.146482 -394.588492)
		(end 160.716214 -391.693908)
		(width 0.1651)
		(layer "In7.Cu")
		(net "P5E_PEX1_STN4_TX_C_DN<77>")
	)
	(segment
		(start 165.867842 -359.118916)
		(end 165.867842 -358.04856)
		(width 0.1651)
		(layer "In7.Cu")
		(net "P5E_PEX1_STN4_TX_C_DN<77>")
	)
	(segment
		(start 157.339792 -368.071146)
		(end 158.537148 -366.874552)
		(width 0.1651)
		(layer "In5.Cu")
		(net "P5E_PEX1_STN4_RX_DN<74>")
	)
	(segment
		(start 171.96943 -405.798274)
		(end 171.96943 -395.365478)
		(width 0.1651)
		(layer "In5.Cu")
		(net "P5E_PEX1_STN4_RX_DN<74>")
	)
	(segment
		(start 194.415918 -320.0908)
		(end 194.370198 -320.04508)
		(width 0.1143)
		(layer "In5.Cu")
		(net "P5E_PEX1_STN4_RX_DN<74>")
	)
	(segment
		(start 185.384694 -333.862426)
		(end 190.230506 -328.966322)
		(width 0.1651)
		(layer "In5.Cu")
		(net "P5E_PEX1_STN4_RX_DN<74>")
	)
	(segment
		(start 194.370198 -318.434466)
		(end 194.484498 -318.320166)
		(width 0.1143)
		(layer "In5.Cu")
		(net "P5E_PEX1_STN4_RX_DN<74>")
	)
	(segment
		(start 170.909996 -406.690068)
		(end 170.909996 -406.308052)
		(width 0.1651)
		(layer "In5.Cu")
		(net "P5E_PEX1_STN4_RX_DN<74>")
	)
	(segment
		(start 158.537148 -366.874552)
		(end 162.143186 -364.273592)
		(width 0.1651)
		(layer "In5.Cu")
		(net "P5E_PEX1_STN4_RX_DN<74>")
	)
	(segment
		(start 194.370198 -320.04508)
		(end 194.370198 -318.434466)
		(width 0.1143)
		(layer "In5.Cu")
		(net "P5E_PEX1_STN4_RX_DN<74>")
	)
	(segment
		(start 170.603164 -360.553508)
		(end 173.239938 -359.313734)
		(width 0.1651)
		(layer "In5.Cu")
		(net "P5E_PEX1_STN4_RX_DN<74>")
	)
	(segment
		(start 171.036996 -406.181052)
		(end 171.586652 -406.181052)
		(width 0.1651)
		(layer "In5.Cu")
		(net "P5E_PEX1_STN4_RX_DN<74>")
	)
	(segment
		(start 158.543752 -387.273292)
		(end 157.64256 -386.3721)
		(width 0.1651)
		(layer "In5.Cu")
		(net "P5E_PEX1_STN4_RX_DN<74>")
	)
	(segment
		(start 190.230506 -328.966322)
		(end 191.94145 -326.99071)
		(width 0.1651)
		(layer "In5.Cu")
		(net "P5E_PEX1_STN4_RX_DN<74>")
	)
	(segment
		(start 194.635628 -318.320166)
		(end 194.749928 -318.434466)
		(width 0.1143)
		(layer "In5.Cu")
		(net "P5E_PEX1_STN4_RX_DN<74>")
	)
	(segment
		(start 170.66895 -394.064744)
		(end 165.353746 -390.515094)
		(width 0.1651)
		(layer "In5.Cu")
		(net "P5E_PEX1_STN4_RX_DN<74>")
	)
	(segment
		(start 157.64256 -386.3721)
		(end 156.7942 -384.325622)
		(width 0.1651)
		(layer "In5.Cu")
		(net "P5E_PEX1_STN4_RX_DN<74>")
	)
	(segment
		(start 165.353746 -390.515094)
		(end 164.89172 -390.24306)
		(width 0.1651)
		(layer "In5.Cu")
		(net "P5E_PEX1_STN4_RX_DN<74>")
	)
	(segment
		(start 161.741358 -388.61746)
		(end 158.543752 -387.273292)
		(width 0.1651)
		(layer "In5.Cu")
		(net "P5E_PEX1_STN4_RX_DN<74>")
	)
	(segment
		(start 171.586652 -406.181052)
		(end 171.96943 -405.798274)
		(width 0.1651)
		(layer "In5.Cu")
		(net "P5E_PEX1_STN4_RX_DN<74>")
	)
	(segment
		(start 194.415918 -320.119248)
		(end 194.415918 -320.0908)
		(width 0.1143)
		(layer "In5.Cu")
		(net "P5E_PEX1_STN4_RX_DN<74>")
	)
	(segment
		(start 170.909996 -406.308052)
		(end 171.036996 -406.181052)
		(width 0.1651)
		(layer "In5.Cu")
		(net "P5E_PEX1_STN4_RX_DN<74>")
	)
	(segment
		(start 191.94145 -326.99071)
		(end 193.434208 -324.853808)
		(width 0.1651)
		(layer "In5.Cu")
		(net "P5E_PEX1_STN4_RX_DN<74>")
	)
	(segment
		(start 194.415918 -321.734434)
		(end 194.415918 -320.119248)
		(width 0.1651)
		(layer "In5.Cu")
		(net "P5E_PEX1_STN4_RX_DN<74>")
	)
	(segment
		(start 194.749928 -318.434466)
		(end 194.749928 -318.699896)
		(width 0.1143)
		(layer "In5.Cu")
		(net "P5E_PEX1_STN4_RX_DN<74>")
	)
	(segment
		(start 176.749202 -341.809324)
		(end 185.384694 -333.862426)
		(width 0.1651)
		(layer "In5.Cu")
		(net "P5E_PEX1_STN4_RX_DN<74>")
	)
	(segment
		(start 174.18304 -353.34194)
		(end 176.076102 -353.34194)
		(width 0.1651)
		(layer "In5.Cu")
		(net "P5E_PEX1_STN4_RX_DN<74>")
	)
	(segment
		(start 171.96943 -395.365478)
		(end 170.66895 -394.064744)
		(width 0.1651)
		(layer "In5.Cu")
		(net "P5E_PEX1_STN4_RX_DN<74>")
	)
	(segment
		(start 173.640242 -353.884738)
		(end 174.18304 -353.34194)
		(width 0.1651)
		(layer "In5.Cu")
		(net "P5E_PEX1_STN4_RX_DN<74>")
	)
	(segment
		(start 176.749202 -352.66884)
		(end 176.749202 -341.809324)
		(width 0.1651)
		(layer "In5.Cu")
		(net "P5E_PEX1_STN4_RX_DN<74>")
	)
	(segment
		(start 156.7942 -369.460018)
		(end 157.339792 -368.071146)
		(width 0.1651)
		(layer "In5.Cu")
		(net "P5E_PEX1_STN4_RX_DN<74>")
	)
	(segment
		(start 193.434208 -324.853808)
		(end 194.415918 -321.734434)
		(width 0.1651)
		(layer "In5.Cu")
		(net "P5E_PEX1_STN4_RX_DN<74>")
	)
	(segment
		(start 156.7942 -384.325622)
		(end 156.7942 -369.460018)
		(width 0.1651)
		(layer "In5.Cu")
		(net "P5E_PEX1_STN4_RX_DN<74>")
	)
	(segment
		(start 164.89172 -390.24306)
		(end 161.741358 -388.61746)
		(width 0.1651)
		(layer "In5.Cu")
		(net "P5E_PEX1_STN4_RX_DN<74>")
	)
	(segment
		(start 194.484498 -318.320166)
		(end 194.635628 -318.320166)
		(width 0.1143)
		(layer "In5.Cu")
		(net "P5E_PEX1_STN4_RX_DN<74>")
	)
	(segment
		(start 176.076102 -353.34194)
		(end 176.749202 -352.66884)
		(width 0.1651)
		(layer "In5.Cu")
		(net "P5E_PEX1_STN4_RX_DN<74>")
	)
	(segment
		(start 162.143186 -364.273592)
		(end 170.603164 -360.553508)
		(width 0.1651)
		(layer "In5.Cu")
		(net "P5E_PEX1_STN4_RX_DN<74>")
	)
	(segment
		(start 173.640242 -358.91343)
		(end 173.640242 -353.884738)
		(width 0.1651)
		(layer "In5.Cu")
		(net "P5E_PEX1_STN4_RX_DN<74>")
	)
	(segment
		(start 173.239938 -359.313734)
		(end 173.640242 -358.91343)
		(width 0.1651)
		(layer "In5.Cu")
		(net "P5E_PEX1_STN4_RX_DN<74>")
	)
	(segment
		(start 196.033898 -320.119248)
		(end 196.033898 -320.0908)
		(width 0.1143)
		(layer "In5.Cu")
		(net "P5E_PEX1_STN4_RX_DP<72>")
	)
	(segment
		(start 175.74641 -395.40561)
		(end 175.588422 -395.40561)
		(width 0.1651)
		(layer "In5.Cu")
		(net "P5E_PEX1_STN4_RX_DP<72>")
	)
	(segment
		(start 182.685182 -358.411018)
		(end 182.685182 -341.841836)
		(width 0.1651)
		(layer "In5.Cu")
		(net "P5E_PEX1_STN4_RX_DP<72>")
	)
	(segment
		(start 196.649848 -318.015366)
		(end 196.649848 -317.749936)
		(width 0.1143)
		(layer "In5.Cu")
		(net "P5E_PEX1_STN4_RX_DP<72>")
	)
	(segment
		(start 196.033898 -322.262754)
		(end 196.033898 -320.119248)
		(width 0.1651)
		(layer "In5.Cu")
		(net "P5E_PEX1_STN4_RX_DP<72>")
	)
	(segment
		(start 196.305424 -318.129666)
		(end 196.535548 -318.129666)
		(width 0.1143)
		(layer "In5.Cu")
		(net "P5E_PEX1_STN4_RX_DP<72>")
	)
	(segment
		(start 193.049652 -328.309224)
		(end 194.967098 -325.608188)
		(width 0.1651)
		(layer "In5.Cu")
		(net "P5E_PEX1_STN4_RX_DP<72>")
	)
	(segment
		(start 182.685182 -341.841836)
		(end 183.770016 -339.64753)
		(width 0.1651)
		(layer "In5.Cu")
		(net "P5E_PEX1_STN4_RX_DP<72>")
	)
	(segment
		(start 196.535548 -318.129666)
		(end 196.649848 -318.015366)
		(width 0.1143)
		(layer "In5.Cu")
		(net "P5E_PEX1_STN4_RX_DP<72>")
	)
	(segment
		(start 196.079618 -320.04508)
		(end 196.079618 -318.355472)
		(width 0.1143)
		(layer "In5.Cu")
		(net "P5E_PEX1_STN4_RX_DP<72>")
	)
	(segment
		(start 174.0535 -393.7127)
		(end 170.1292 -391.0838)
		(width 0.1651)
		(layer "In5.Cu")
		(net "P5E_PEX1_STN4_RX_DP<72>")
	)
	(segment
		(start 159.046164 -385.472178)
		(end 158.42234 -383.999994)
		(width 0.1651)
		(layer "In5.Cu")
		(net "P5E_PEX1_STN4_RX_DP<72>")
	)
	(segment
		(start 196.033898 -320.0908)
		(end 196.079618 -320.04508)
		(width 0.1143)
		(layer "In5.Cu")
		(net "P5E_PEX1_STN4_RX_DP<72>")
	)
	(segment
		(start 175.246792 -395.06398)
		(end 175.246792 -394.905992)
		(width 0.1651)
		(layer "In5.Cu")
		(net "P5E_PEX1_STN4_RX_DP<72>")
	)
	(segment
		(start 175.310038 -405.772112)
		(end 175.437038 -405.899112)
		(width 0.1651)
		(layer "In5.Cu")
		(net "P5E_PEX1_STN4_RX_DP<72>")
	)
	(segment
		(start 175.310038 -405.390096)
		(end 175.310038 -405.772112)
		(width 0.1651)
		(layer "In5.Cu")
		(net "P5E_PEX1_STN4_RX_DP<72>")
	)
	(segment
		(start 163.293044 -365.56569)
		(end 171.594018 -361.915964)
		(width 0.1651)
		(layer "In5.Cu")
		(net "P5E_PEX1_STN4_RX_DP<72>")
	)
	(segment
		(start 158.42234 -383.999994)
		(end 158.42234 -370.179092)
		(width 0.1651)
		(layer "In5.Cu")
		(net "P5E_PEX1_STN4_RX_DP<72>")
	)
	(segment
		(start 175.246792 -394.905992)
		(end 174.0535 -393.7127)
		(width 0.1651)
		(layer "In5.Cu")
		(net "P5E_PEX1_STN4_RX_DP<72>")
	)
	(segment
		(start 158.42234 -370.179092)
		(end 158.983426 -368.75212)
		(width 0.1651)
		(layer "In5.Cu")
		(net "P5E_PEX1_STN4_RX_DP<72>")
	)
	(segment
		(start 175.869854 -405.899112)
		(end 176.087532 -405.681434)
		(width 0.1651)
		(layer "In5.Cu")
		(net "P5E_PEX1_STN4_RX_DP<72>")
	)
	(segment
		(start 176.087532 -405.681434)
		(end 176.087532 -395.746732)
		(width 0.1651)
		(layer "In5.Cu")
		(net "P5E_PEX1_STN4_RX_DP<72>")
	)
	(segment
		(start 170.1292 -391.0838)
		(end 163.192968 -387.455664)
		(width 0.1651)
		(layer "In5.Cu")
		(net "P5E_PEX1_STN4_RX_DP<72>")
	)
	(segment
		(start 183.770016 -339.64753)
		(end 193.049652 -328.309224)
		(width 0.1651)
		(layer "In5.Cu")
		(net "P5E_PEX1_STN4_RX_DP<72>")
	)
	(segment
		(start 194.967098 -325.608188)
		(end 196.033898 -322.262754)
		(width 0.1651)
		(layer "In5.Cu")
		(net "P5E_PEX1_STN4_RX_DP<72>")
	)
	(segment
		(start 171.594018 -361.915964)
		(end 175.253904 -360.781854)
		(width 0.1651)
		(layer "In5.Cu")
		(net "P5E_PEX1_STN4_RX_DP<72>")
	)
	(segment
		(start 159.461962 -385.887976)
		(end 159.046164 -385.472178)
		(width 0.1651)
		(layer "In5.Cu")
		(net "P5E_PEX1_STN4_RX_DP<72>")
	)
	(segment
		(start 175.253904 -360.781854)
		(end 181.598316 -359.497884)
		(width 0.1651)
		(layer "In5.Cu")
		(net "P5E_PEX1_STN4_RX_DP<72>")
	)
	(segment
		(start 181.598316 -359.497884)
		(end 182.685182 -358.411018)
		(width 0.1651)
		(layer "In5.Cu")
		(net "P5E_PEX1_STN4_RX_DP<72>")
	)
	(segment
		(start 175.437038 -405.899112)
		(end 175.869854 -405.899112)
		(width 0.1651)
		(layer "In5.Cu")
		(net "P5E_PEX1_STN4_RX_DP<72>")
	)
	(segment
		(start 163.192968 -387.455664)
		(end 159.461962 -385.887976)
		(width 0.1651)
		(layer "In5.Cu")
		(net "P5E_PEX1_STN4_RX_DP<72>")
	)
	(segment
		(start 196.079618 -318.355472)
		(end 196.305424 -318.129666)
		(width 0.1143)
		(layer "In5.Cu")
		(net "P5E_PEX1_STN4_RX_DP<72>")
	)
	(segment
		(start 158.983426 -368.75212)
		(end 159.533336 -368.20221)
		(width 0.1651)
		(layer "In5.Cu")
		(net "P5E_PEX1_STN4_RX_DP<72>")
	)
	(segment
		(start 159.533336 -368.20221)
		(end 163.293044 -365.56569)
		(width 0.1651)
		(layer "In5.Cu")
		(net "P5E_PEX1_STN4_RX_DP<72>")
	)
	(segment
		(start 176.087532 -395.746732)
		(end 175.74641 -395.40561)
		(width 0.1651)
		(layer "In5.Cu")
		(net "P5E_PEX1_STN4_RX_DP<72>")
	)
	(segment
		(start 175.588422 -395.40561)
		(end 175.246792 -395.06398)
		(width 0.1651)
		(layer "In5.Cu")
		(net "P5E_PEX1_STN4_RX_DP<72>")
	)
	(segment
		(start 184.190386 -327.597262)
		(end 183.943752 -327.930764)
		(width 0.1651)
		(layer "In5.Cu")
		(net "P5E_PEX1_STN4_RX_DN<79>")
	)
	(segment
		(start 160.969452 -404.6982)
		(end 160.586674 -405.080978)
		(width 0.1651)
		(layer "In5.Cu")
		(net "P5E_PEX1_STN4_RX_DN<79>")
	)
	(segment
		(start 189.620144 -320.04508)
		(end 189.665864 -320.0908)
		(width 0.1143)
		(layer "In5.Cu")
		(net "P5E_PEX1_STN4_RX_DN<79>")
	)
	(segment
		(start 155.730194 -391.214356)
		(end 160.768538 -394.580872)
		(width 0.1651)
		(layer "In5.Cu")
		(net "P5E_PEX1_STN4_RX_DN<79>")
	)
	(segment
		(start 183.928004 -327.962006)
		(end 183.894984 -327.989438)
		(width 0.1651)
		(layer "In5.Cu")
		(net "P5E_PEX1_STN4_RX_DN<79>")
	)
	(segment
		(start 189.333124 -321.577462)
		(end 184.190386 -327.597262)
		(width 0.1651)
		(layer "In5.Cu")
		(net "P5E_PEX1_STN4_RX_DN<79>")
	)
	(segment
		(start 189.999874 -316.799722)
		(end 189.999874 -316.534292)
		(width 0.1143)
		(layer "In5.Cu")
		(net "P5E_PEX1_STN4_RX_DN<79>")
	)
	(segment
		(start 164.184838 -340.73084)
		(end 163.696396 -341.292688)
		(width 0.1651)
		(layer "In5.Cu")
		(net "P5E_PEX1_STN4_RX_DN<79>")
	)
	(segment
		(start 159.910018 -405.207978)
		(end 159.910018 -405.589994)
		(width 0.1651)
		(layer "In5.Cu")
		(net "P5E_PEX1_STN4_RX_DN<79>")
	)
	(segment
		(start 183.894476 -327.989946)
		(end 180.816504 -330.500736)
		(width 0.1651)
		(layer "In5.Cu")
		(net "P5E_PEX1_STN4_RX_DN<79>")
	)
	(segment
		(start 160.768538 -394.580872)
		(end 160.969452 -394.956284)
		(width 0.1651)
		(layer "In5.Cu")
		(net "P5E_PEX1_STN4_RX_DN<79>")
	)
	(segment
		(start 183.894984 -327.989438)
		(end 183.894476 -327.989946)
		(width 0.1651)
		(layer "In5.Cu")
		(net "P5E_PEX1_STN4_RX_DN<79>")
	)
	(segment
		(start 156.528262 -355.46919)
		(end 151.97582 -367.480596)
		(width 0.1651)
		(layer "In5.Cu")
		(net "P5E_PEX1_STN4_RX_DN<79>")
	)
	(segment
		(start 189.665864 -320.0908)
		(end 189.665864 -320.119248)
		(width 0.1143)
		(layer "In5.Cu")
		(net "P5E_PEX1_STN4_RX_DN<79>")
	)
	(segment
		(start 189.885574 -316.419992)
		(end 189.734444 -316.419992)
		(width 0.1143)
		(layer "In5.Cu")
		(net "P5E_PEX1_STN4_RX_DN<79>")
	)
	(segment
		(start 189.665864 -320.119248)
		(end 189.665864 -320.675762)
		(width 0.1651)
		(layer "In5.Cu")
		(net "P5E_PEX1_STN4_RX_DN<79>")
	)
	(segment
		(start 160.969452 -394.956284)
		(end 160.969452 -404.6982)
		(width 0.1651)
		(layer "In5.Cu")
		(net "P5E_PEX1_STN4_RX_DN<79>")
	)
	(segment
		(start 189.734444 -316.419992)
		(end 189.620144 -316.534292)
		(width 0.1143)
		(layer "In5.Cu")
		(net "P5E_PEX1_STN4_RX_DN<79>")
	)
	(segment
		(start 153.592022 -389.076184)
		(end 155.730194 -391.214356)
		(width 0.1651)
		(layer "In5.Cu")
		(net "P5E_PEX1_STN4_RX_DN<79>")
	)
	(segment
		(start 160.586674 -405.080978)
		(end 160.037018 -405.080978)
		(width 0.1651)
		(layer "In5.Cu")
		(net "P5E_PEX1_STN4_RX_DN<79>")
	)
	(segment
		(start 151.97582 -367.480596)
		(end 151.97582 -385.172712)
		(width 0.1651)
		(layer "In5.Cu")
		(net "P5E_PEX1_STN4_RX_DN<79>")
	)
	(segment
		(start 163.696396 -341.292688)
		(end 163.681156 -341.301832)
		(width 0.1651)
		(layer "In5.Cu")
		(net "P5E_PEX1_STN4_RX_DN<79>")
	)
	(segment
		(start 151.97582 -385.172712)
		(end 153.592022 -389.076184)
		(width 0.1651)
		(layer "In5.Cu")
		(net "P5E_PEX1_STN4_RX_DN<79>")
	)
	(segment
		(start 189.620144 -316.534292)
		(end 189.620144 -320.04508)
		(width 0.1143)
		(layer "In5.Cu")
		(net "P5E_PEX1_STN4_RX_DN<79>")
	)
	(segment
		(start 180.816504 -330.500736)
		(end 164.184838 -340.73084)
		(width 0.1651)
		(layer "In5.Cu")
		(net "P5E_PEX1_STN4_RX_DN<79>")
	)
	(segment
		(start 160.037018 -405.080978)
		(end 159.910018 -405.207978)
		(width 0.1651)
		(layer "In5.Cu")
		(net "P5E_PEX1_STN4_RX_DN<79>")
	)
	(segment
		(start 163.681156 -341.301832)
		(end 163.57473 -341.424514)
		(width 0.1651)
		(layer "In5.Cu")
		(net "P5E_PEX1_STN4_RX_DN<79>")
	)
	(segment
		(start 189.999874 -316.534292)
		(end 189.885574 -316.419992)
		(width 0.1143)
		(layer "In5.Cu")
		(net "P5E_PEX1_STN4_RX_DN<79>")
	)
	(segment
		(start 189.665864 -320.675762)
		(end 189.333124 -321.577462)
		(width 0.1651)
		(layer "In5.Cu")
		(net "P5E_PEX1_STN4_RX_DN<79>")
	)
	(segment
		(start 163.57473 -341.424514)
		(end 156.528262 -355.46919)
		(width 0.1651)
		(layer "In5.Cu")
		(net "P5E_PEX1_STN4_RX_DN<79>")
	)
	(segment
		(start 183.943752 -327.930764)
		(end 183.928004 -327.962006)
		(width 0.1651)
		(layer "In5.Cu")
		(net "P5E_PEX1_STN4_RX_DN<79>")
	)
	(segment
		(start 196.953632 -344.539062)
		(end 197.273672 -344.219022)
		(width 0.13462)
		(layer "F.Cu")
		(net "P5E_PEX1_STN4_TX_C_DN<64>")
	)
	(segment
		(start 197.248272 -345.465146)
		(end 196.953632 -345.170506)
		(width 0.13462)
		(layer "F.Cu")
		(net "P5E_PEX1_STN4_TX_C_DN<64>")
	)
	(segment
		(start 196.953632 -345.170506)
		(end 196.953632 -344.539062)
		(width 0.13462)
		(layer "F.Cu")
		(net "P5E_PEX1_STN4_TX_C_DN<64>")
	)
	(segment
		(start 175.310038 -372.890034)
		(end 175.310038 -372.508018)
		(width 0.1651)
		(layer "In7.Cu")
		(net "P5E_PEX1_STN4_TX_C_DN<64>")
	)
	(segment
		(start 177.170842 -368.540538)
		(end 184.103518 -365.78286)
		(width 0.1651)
		(layer "In7.Cu")
		(net "P5E_PEX1_STN4_TX_C_DN<64>")
	)
	(segment
		(start 187.739528 -363.382306)
		(end 192.917826 -358.203754)
		(width 0.1651)
		(layer "In7.Cu")
		(net "P5E_PEX1_STN4_TX_C_DN<64>")
	)
	(segment
		(start 175.437292 -372.380764)
		(end 175.786034 -372.380764)
		(width 0.1651)
		(layer "In7.Cu")
		(net "P5E_PEX1_STN4_TX_C_DN<64>")
	)
	(segment
		(start 196.957442 -348.467172)
		(end 196.957442 -345.755976)
		(width 0.1651)
		(layer "In7.Cu")
		(net "P5E_PEX1_STN4_TX_C_DN<64>")
	)
	(segment
		(start 176.369472 -371.797326)
		(end 176.369472 -369.341908)
		(width 0.1651)
		(layer "In7.Cu")
		(net "P5E_PEX1_STN4_TX_C_DN<64>")
	)
	(segment
		(start 192.917826 -358.203754)
		(end 196.957442 -348.467172)
		(width 0.1651)
		(layer "In7.Cu")
		(net "P5E_PEX1_STN4_TX_C_DN<64>")
	)
	(segment
		(start 196.957442 -345.755976)
		(end 197.248272 -345.465146)
		(width 0.1651)
		(layer "In7.Cu")
		(net "P5E_PEX1_STN4_TX_C_DN<64>")
	)
	(segment
		(start 175.786034 -372.380764)
		(end 176.369472 -371.797326)
		(width 0.1651)
		(layer "In7.Cu")
		(net "P5E_PEX1_STN4_TX_C_DN<64>")
	)
	(segment
		(start 175.310038 -372.508018)
		(end 175.437292 -372.380764)
		(width 0.1651)
		(layer "In7.Cu")
		(net "P5E_PEX1_STN4_TX_C_DN<64>")
	)
	(segment
		(start 184.103518 -365.78286)
		(end 187.739528 -363.382306)
		(width 0.1651)
		(layer "In7.Cu")
		(net "P5E_PEX1_STN4_TX_C_DN<64>")
	)
	(segment
		(start 176.369472 -369.341908)
		(end 177.170842 -368.540538)
		(width 0.1651)
		(layer "In7.Cu")
		(net "P5E_PEX1_STN4_TX_C_DN<64>")
	)
	(segment
		(start 196.384672 -345.465146)
		(end 196.679312 -345.170506)
		(width 0.13462)
		(layer "F.Cu")
		(net "P5E_PEX1_STN4_TX_C_DP<64>")
	)
	(segment
		(start 196.679312 -345.170506)
		(end 196.679312 -344.539062)
		(width 0.13462)
		(layer "F.Cu")
		(net "P5E_PEX1_STN4_TX_C_DP<64>")
	)
	(segment
		(start 196.679312 -344.539062)
		(end 196.359272 -344.219022)
		(width 0.13462)
		(layer "F.Cu")
		(net "P5E_PEX1_STN4_TX_C_DP<64>")
	)
	(segment
		(start 193.072258 -357.095806)
		(end 193.010282 -356.9462)
		(width 0.1651)
		(layer "In7.Cu")
		(net "P5E_PEX1_STN4_TX_C_DP<64>")
	)
	(segment
		(start 193.010282 -356.9462)
		(end 193.200274 -356.488492)
		(width 0.1651)
		(layer "In7.Cu")
		(net "P5E_PEX1_STN4_TX_C_DP<64>")
	)
	(segment
		(start 189.284864 -361.437936)
		(end 189.634876 -361.087924)
		(width 0.1651)
		(layer "In7.Cu")
		(net "P5E_PEX1_STN4_TX_C_DP<64>")
	)
	(segment
		(start 196.675502 -348.410784)
		(end 196.675502 -345.755976)
		(width 0.1651)
		(layer "In7.Cu")
		(net "P5E_PEX1_STN4_TX_C_DP<64>")
	)
	(segment
		(start 196.675502 -345.755976)
		(end 196.384672 -345.465146)
		(width 0.1651)
		(layer "In7.Cu")
		(net "P5E_PEX1_STN4_TX_C_DP<64>")
	)
	(segment
		(start 188.260736 -362.300266)
		(end 188.422534 -362.300266)
		(width 0.1651)
		(layer "In7.Cu")
		(net "P5E_PEX1_STN4_TX_C_DP<64>")
	)
	(segment
		(start 175.310038 -371.590062)
		(end 175.310038 -371.971824)
		(width 0.1651)
		(layer "In7.Cu")
		(net "P5E_PEX1_STN4_TX_C_DP<64>")
	)
	(segment
		(start 192.678812 -358.043988)
		(end 193.072258 -357.095806)
		(width 0.1651)
		(layer "In7.Cu")
		(net "P5E_PEX1_STN4_TX_C_DP<64>")
	)
	(segment
		(start 188.772546 -361.788456)
		(end 189.123066 -361.437936)
		(width 0.1651)
		(layer "In7.Cu")
		(net "P5E_PEX1_STN4_TX_C_DP<64>")
	)
	(segment
		(start 189.123066 -361.437936)
		(end 189.284864 -361.437936)
		(width 0.1651)
		(layer "In7.Cu")
		(net "P5E_PEX1_STN4_TX_C_DP<64>")
	)
	(segment
		(start 191.009524 -359.713276)
		(end 192.678812 -358.043988)
		(width 0.1651)
		(layer "In7.Cu")
		(net "P5E_PEX1_STN4_TX_C_DP<64>")
	)
	(segment
		(start 188.422534 -362.300266)
		(end 188.772546 -361.950254)
		(width 0.1651)
		(layer "In7.Cu")
		(net "P5E_PEX1_STN4_TX_C_DP<64>")
	)
	(segment
		(start 190.147194 -360.575606)
		(end 190.497206 -360.225594)
		(width 0.1651)
		(layer "In7.Cu")
		(net "P5E_PEX1_STN4_TX_C_DP<64>")
	)
	(segment
		(start 175.310038 -371.971824)
		(end 175.437038 -372.098824)
		(width 0.1651)
		(layer "In7.Cu")
		(net "P5E_PEX1_STN4_TX_C_DP<64>")
	)
	(segment
		(start 175.669194 -372.098824)
		(end 176.087532 -371.680486)
		(width 0.1651)
		(layer "In7.Cu")
		(net "P5E_PEX1_STN4_TX_C_DP<64>")
	)
	(segment
		(start 189.634876 -360.926126)
		(end 189.985396 -360.575606)
		(width 0.1651)
		(layer "In7.Cu")
		(net "P5E_PEX1_STN4_TX_C_DP<64>")
	)
	(segment
		(start 194.006978 -354.84308)
		(end 193.945256 -354.693728)
		(width 0.1651)
		(layer "In7.Cu")
		(net "P5E_PEX1_STN4_TX_C_DP<64>")
	)
	(segment
		(start 187.560204 -363.162596)
		(end 187.910216 -362.812584)
		(width 0.1651)
		(layer "In7.Cu")
		(net "P5E_PEX1_STN4_TX_C_DP<64>")
	)
	(segment
		(start 189.985396 -360.575606)
		(end 190.147194 -360.575606)
		(width 0.1651)
		(layer "In7.Cu")
		(net "P5E_PEX1_STN4_TX_C_DP<64>")
	)
	(segment
		(start 194.134994 -354.23602)
		(end 194.2846 -354.174298)
		(width 0.1651)
		(layer "In7.Cu")
		(net "P5E_PEX1_STN4_TX_C_DP<64>")
	)
	(segment
		(start 177.0126 -368.3)
		(end 183.9722 -365.5314)
		(width 0.1651)
		(layer "In7.Cu")
		(net "P5E_PEX1_STN4_TX_C_DP<64>")
	)
	(segment
		(start 193.945256 -354.693728)
		(end 194.134994 -354.23602)
		(width 0.1651)
		(layer "In7.Cu")
		(net "P5E_PEX1_STN4_TX_C_DP<64>")
	)
	(segment
		(start 190.497206 -360.063796)
		(end 190.847726 -359.713276)
		(width 0.1651)
		(layer "In7.Cu")
		(net "P5E_PEX1_STN4_TX_C_DP<64>")
	)
	(segment
		(start 194.284092 -354.174298)
		(end 196.675502 -348.410784)
		(width 0.1651)
		(layer "In7.Cu")
		(net "P5E_PEX1_STN4_TX_C_DP<64>")
	)
	(segment
		(start 193.816986 -355.30028)
		(end 194.006724 -354.84308)
		(width 0.1651)
		(layer "In7.Cu")
		(net "P5E_PEX1_STN4_TX_C_DP<64>")
	)
	(segment
		(start 189.634876 -361.087924)
		(end 189.634876 -360.926126)
		(width 0.1651)
		(layer "In7.Cu")
		(net "P5E_PEX1_STN4_TX_C_DP<64>")
	)
	(segment
		(start 190.847726 -359.713276)
		(end 191.009524 -359.713276)
		(width 0.1651)
		(layer "In7.Cu")
		(net "P5E_PEX1_STN4_TX_C_DP<64>")
	)
	(segment
		(start 193.200274 -356.488492)
		(end 193.34988 -356.42677)
		(width 0.1651)
		(layer "In7.Cu")
		(net "P5E_PEX1_STN4_TX_C_DP<64>")
	)
	(segment
		(start 194.006724 -354.84308)
		(end 194.006978 -354.84308)
		(width 0.1651)
		(layer "In7.Cu")
		(net "P5E_PEX1_STN4_TX_C_DP<64>")
	)
	(segment
		(start 193.81724 -355.300534)
		(end 193.816986 -355.30028)
		(width 0.1651)
		(layer "In7.Cu")
		(net "P5E_PEX1_STN4_TX_C_DP<64>")
	)
	(segment
		(start 190.497206 -360.225594)
		(end 190.497206 -360.063796)
		(width 0.1651)
		(layer "In7.Cu")
		(net "P5E_PEX1_STN4_TX_C_DP<64>")
	)
	(segment
		(start 176.087532 -371.680486)
		(end 176.087532 -369.225068)
		(width 0.1651)
		(layer "In7.Cu")
		(net "P5E_PEX1_STN4_TX_C_DP<64>")
	)
	(segment
		(start 187.910216 -362.812584)
		(end 187.910216 -362.650786)
		(width 0.1651)
		(layer "In7.Cu")
		(net "P5E_PEX1_STN4_TX_C_DP<64>")
	)
	(segment
		(start 187.910216 -362.650786)
		(end 188.260736 -362.300266)
		(width 0.1651)
		(layer "In7.Cu")
		(net "P5E_PEX1_STN4_TX_C_DP<64>")
	)
	(segment
		(start 175.437038 -372.098824)
		(end 175.669194 -372.098824)
		(width 0.1651)
		(layer "In7.Cu")
		(net "P5E_PEX1_STN4_TX_C_DP<64>")
	)
	(segment
		(start 193.477896 -355.819964)
		(end 193.667634 -355.362256)
		(width 0.1651)
		(layer "In7.Cu")
		(net "P5E_PEX1_STN4_TX_C_DP<64>")
	)
	(segment
		(start 193.34988 -356.42677)
		(end 193.539618 -355.969316)
		(width 0.1651)
		(layer "In7.Cu")
		(net "P5E_PEX1_STN4_TX_C_DP<64>")
	)
	(segment
		(start 176.087532 -369.225068)
		(end 177.0126 -368.3)
		(width 0.1651)
		(layer "In7.Cu")
		(net "P5E_PEX1_STN4_TX_C_DP<64>")
	)
	(segment
		(start 194.2846 -354.174298)
		(end 194.284092 -354.174298)
		(width 0.1651)
		(layer "In7.Cu")
		(net "P5E_PEX1_STN4_TX_C_DP<64>")
	)
	(segment
		(start 183.9722 -365.5314)
		(end 187.560204 -363.162596)
		(width 0.1651)
		(layer "In7.Cu")
		(net "P5E_PEX1_STN4_TX_C_DP<64>")
	)
	(segment
		(start 188.772546 -361.950254)
		(end 188.772546 -361.788456)
		(width 0.1651)
		(layer "In7.Cu")
		(net "P5E_PEX1_STN4_TX_C_DP<64>")
	)
	(segment
		(start 193.539618 -355.969316)
		(end 193.477896 -355.819964)
		(width 0.1651)
		(layer "In7.Cu")
		(net "P5E_PEX1_STN4_TX_C_DP<64>")
	)
	(segment
		(start 193.667634 -355.362256)
		(end 193.81724 -355.300534)
		(width 0.1651)
		(layer "In7.Cu")
		(net "P5E_PEX1_STN4_TX_C_DP<64>")
	)
	(segment
		(start 199.72528 -305.779678)
		(end 196.384418 -305.779678)
		(width 0.1143)
		(layer "In5.Cu")
		(net "P5E_PEX1_STN4_RX_DN<65>")
	)
	(segment
		(start 213.446614 -326.11441)
		(end 214.28456 -321.925442)
		(width 0.1651)
		(layer "In5.Cu")
		(net "P5E_PEX1_STN4_RX_DN<65>")
	)
	(segment
		(start 214.28456 -319.364614)
		(end 212.876384 -315.9252)
		(width 0.1651)
		(layer "In5.Cu")
		(net "P5E_PEX1_STN4_RX_DN<65>")
	)
	(segment
		(start 190.93688 -363.80039)
		(end 193.715132 -361.001818)
		(width 0.1651)
		(layer "In5.Cu")
		(net "P5E_PEX1_STN4_RX_DN<65>")
	)
	(segment
		(start 174.169324 -378.698252)
		(end 174.169324 -369.316254)
		(width 0.1651)
		(layer "In5.Cu")
		(net "P5E_PEX1_STN4_RX_DN<65>")
	)
	(segment
		(start 175.142906 -368.276886)
		(end 176.768252 -367.688622)
		(width 0.1651)
		(layer "In5.Cu")
		(net "P5E_PEX1_STN4_RX_DN<65>")
	)
	(segment
		(start 173.23689 -379.08103)
		(end 173.786546 -379.08103)
		(width 0.1651)
		(layer "In5.Cu")
		(net "P5E_PEX1_STN4_RX_DN<65>")
	)
	(segment
		(start 173.786546 -379.08103)
		(end 174.169324 -378.698252)
		(width 0.1651)
		(layer "In5.Cu")
		(net "P5E_PEX1_STN4_RX_DN<65>")
	)
	(segment
		(start 214.28456 -321.925442)
		(end 214.28456 -319.364614)
		(width 0.1651)
		(layer "In5.Cu")
		(net "P5E_PEX1_STN4_RX_DN<65>")
	)
	(segment
		(start 199.02297 -354.780596)
		(end 199.927718 -353.211384)
		(width 0.1651)
		(layer "In5.Cu")
		(net "P5E_PEX1_STN4_RX_DN<65>")
	)
	(segment
		(start 199.771 -305.733958)
		(end 199.72528 -305.779678)
		(width 0.1143)
		(layer "In5.Cu")
		(net "P5E_PEX1_STN4_RX_DN<65>")
	)
	(segment
		(start 174.169324 -369.316254)
		(end 174.485554 -368.722656)
		(width 0.1651)
		(layer "In5.Cu")
		(net "P5E_PEX1_STN4_RX_DN<65>")
	)
	(segment
		(start 196.384418 -305.779678)
		(end 196.270118 -305.665378)
		(width 0.1143)
		(layer "In5.Cu")
		(net "P5E_PEX1_STN4_RX_DN<65>")
	)
	(segment
		(start 176.768252 -367.688622)
		(end 187.689998 -365.480092)
		(width 0.1651)
		(layer "In5.Cu")
		(net "P5E_PEX1_STN4_RX_DN<65>")
	)
	(segment
		(start 201.116946 -305.733958)
		(end 199.799448 -305.733958)
		(width 0.1651)
		(layer "In5.Cu")
		(net "P5E_PEX1_STN4_RX_DN<65>")
	)
	(segment
		(start 196.270118 -305.514248)
		(end 196.384418 -305.399948)
		(width 0.1143)
		(layer "In5.Cu")
		(net "P5E_PEX1_STN4_RX_DN<65>")
	)
	(segment
		(start 193.715132 -361.001818)
		(end 199.02297 -354.780596)
		(width 0.1651)
		(layer "In5.Cu")
		(net "P5E_PEX1_STN4_RX_DN<65>")
	)
	(segment
		(start 199.927718 -353.211384)
		(end 213.446614 -326.11441)
		(width 0.1651)
		(layer "In5.Cu")
		(net "P5E_PEX1_STN4_RX_DN<65>")
	)
	(segment
		(start 187.689998 -365.480092)
		(end 190.93688 -363.80039)
		(width 0.1651)
		(layer "In5.Cu")
		(net "P5E_PEX1_STN4_RX_DN<65>")
	)
	(segment
		(start 173.10989 -379.20803)
		(end 173.23689 -379.08103)
		(width 0.1651)
		(layer "In5.Cu")
		(net "P5E_PEX1_STN4_RX_DN<65>")
	)
	(segment
		(start 203.794106 -306.842922)
		(end 201.116946 -305.733958)
		(width 0.1651)
		(layer "In5.Cu")
		(net "P5E_PEX1_STN4_RX_DN<65>")
	)
	(segment
		(start 196.384418 -305.399948)
		(end 196.649848 -305.399948)
		(width 0.1143)
		(layer "In5.Cu")
		(net "P5E_PEX1_STN4_RX_DN<65>")
	)
	(segment
		(start 196.270118 -305.665378)
		(end 196.270118 -305.514248)
		(width 0.1143)
		(layer "In5.Cu")
		(net "P5E_PEX1_STN4_RX_DN<65>")
	)
	(segment
		(start 199.799448 -305.733958)
		(end 199.771 -305.733958)
		(width 0.1143)
		(layer "In5.Cu")
		(net "P5E_PEX1_STN4_RX_DN<65>")
	)
	(segment
		(start 173.10989 -379.590046)
		(end 173.10989 -379.20803)
		(width 0.1651)
		(layer "In5.Cu")
		(net "P5E_PEX1_STN4_RX_DN<65>")
	)
	(segment
		(start 212.876384 -315.9252)
		(end 203.794106 -306.842922)
		(width 0.1651)
		(layer "In5.Cu")
		(net "P5E_PEX1_STN4_RX_DN<65>")
	)
	(segment
		(start 174.485554 -368.722656)
		(end 175.142906 -368.276886)
		(width 0.1651)
		(layer "In5.Cu")
		(net "P5E_PEX1_STN4_RX_DN<65>")
	)
	(segment
		(start 191.550544 -354.569522)
		(end 189.71133 -359.010204)
		(width 0.1651)
		(layer "In5.Cu")
		(net "P5E_PEX1_STN4_RX_DP<69>")
	)
	(segment
		(start 193.95059 -336.959956)
		(end 193.797174 -337.01101)
		(width 0.1651)
		(layer "In5.Cu")
		(net "P5E_PEX1_STN4_RX_DP<69>")
	)
	(segment
		(start 198.280528 -327.53808)
		(end 198.342758 -327.687432)
		(width 0.1651)
		(layer "In5.Cu")
		(net "P5E_PEX1_STN4_RX_DP<69>")
	)
	(segment
		(start 197.170294 -330.542392)
		(end 194.497198 -335.870042)
		(width 0.1651)
		(layer "In5.Cu")
		(net "P5E_PEX1_STN4_RX_DP<69>")
	)
	(segment
		(start 200.445116 -319.27673)
		(end 199.201278 -325.596504)
		(width 0.1651)
		(layer "In5.Cu")
		(net "P5E_PEX1_STN4_RX_DP<69>")
	)
	(segment
		(start 165.087554 -369.393724)
		(end 165.087554 -378.581412)
		(width 0.1651)
		(layer "In5.Cu")
		(net "P5E_PEX1_STN4_RX_DP<69>")
	)
	(segment
		(start 192.012062 -340.823296)
		(end 192.012062 -352.250756)
		(width 0.1651)
		(layer "In5.Cu")
		(net "P5E_PEX1_STN4_RX_DP<69>")
	)
	(segment
		(start 165.087554 -378.581412)
		(end 164.869876 -378.79909)
		(width 0.1651)
		(layer "In5.Cu")
		(net "P5E_PEX1_STN4_RX_DP<69>")
	)
	(segment
		(start 194.172586 -336.517488)
		(end 194.172332 -336.517488)
		(width 0.1651)
		(layer "In5.Cu")
		(net "P5E_PEX1_STN4_RX_DP<69>")
	)
	(segment
		(start 197.353936 -329.794108)
		(end 197.416166 -329.943206)
		(width 0.1651)
		(layer "In5.Cu")
		(net "P5E_PEX1_STN4_RX_DP<69>")
	)
	(segment
		(start 164.869876 -378.79909)
		(end 164.43706 -378.79909)
		(width 0.1651)
		(layer "In5.Cu")
		(net "P5E_PEX1_STN4_RX_DP<69>")
	)
	(segment
		(start 198.618094 -327.01738)
		(end 198.468488 -327.079864)
		(width 0.1651)
		(layer "In5.Cu")
		(net "P5E_PEX1_STN4_RX_DP<69>")
	)
	(segment
		(start 188.152532 -360.57967)
		(end 186.322716 -361.544362)
		(width 0.1651)
		(layer "In5.Cu")
		(net "P5E_PEX1_STN4_RX_DP<69>")
	)
	(segment
		(start 192.70345 -339.190584)
		(end 192.480946 -339.63356)
		(width 0.1651)
		(layer "In5.Cu")
		(net "P5E_PEX1_STN4_RX_DP<69>")
	)
	(segment
		(start 201.387456 -311.496202)
		(end 201.387456 -317.0174)
		(width 0.1651)
		(layer "In5.Cu")
		(net "P5E_PEX1_STN4_RX_DP<69>")
	)
	(segment
		(start 198.005446 -328.207878)
		(end 197.817232 -328.666094)
		(width 0.1651)
		(layer "In5.Cu")
		(net "P5E_PEX1_STN4_RX_DP<69>")
	)
	(segment
		(start 197.879462 -328.815446)
		(end 197.691502 -329.273408)
		(width 0.1651)
		(layer "In5.Cu")
		(net "P5E_PEX1_STN4_RX_DP<69>")
	)
	(segment
		(start 165.651942 -368.3635)
		(end 165.087554 -369.393724)
		(width 0.1651)
		(layer "In5.Cu")
		(net "P5E_PEX1_STN4_RX_DP<69>")
	)
	(segment
		(start 196.079618 -309.314088)
		(end 196.079618 -309.544212)
		(width 0.1143)
		(layer "In5.Cu")
		(net "P5E_PEX1_STN4_RX_DP<69>")
	)
	(segment
		(start 192.480946 -339.63356)
		(end 192.532 -339.786976)
		(width 0.1651)
		(layer "In5.Cu")
		(net "P5E_PEX1_STN4_RX_DP<69>")
	)
	(segment
		(start 197.691502 -329.273408)
		(end 197.54215 -329.335638)
		(width 0.1651)
		(layer "In5.Cu")
		(net "P5E_PEX1_STN4_RX_DP<69>")
	)
	(segment
		(start 193.625724 -337.607402)
		(end 193.62547 -337.607402)
		(width 0.1651)
		(layer "In5.Cu")
		(net "P5E_PEX1_STN4_RX_DP<69>")
	)
	(segment
		(start 193.250312 -338.100924)
		(end 193.028062 -338.5439)
		(width 0.1651)
		(layer "In5.Cu")
		(net "P5E_PEX1_STN4_RX_DP<69>")
	)
	(segment
		(start 200.568814 -310.19115)
		(end 201.387456 -311.496202)
		(width 0.1651)
		(layer "In5.Cu")
		(net "P5E_PEX1_STN4_RX_DP<69>")
	)
	(segment
		(start 195.699888 -309.199788)
		(end 195.965318 -309.199788)
		(width 0.1143)
		(layer "In5.Cu")
		(net "P5E_PEX1_STN4_RX_DP<69>")
	)
	(segment
		(start 194.497198 -335.870042)
		(end 194.497452 -335.870042)
		(width 0.1651)
		(layer "In5.Cu")
		(net "P5E_PEX1_STN4_RX_DP<69>")
	)
	(segment
		(start 193.950336 -336.959956)
		(end 193.95059 -336.959956)
		(width 0.1651)
		(layer "In5.Cu")
		(net "P5E_PEX1_STN4_RX_DP<69>")
	)
	(segment
		(start 197.54215 -329.335638)
		(end 197.353936 -329.794108)
		(width 0.1651)
		(layer "In5.Cu")
		(net "P5E_PEX1_STN4_RX_DP<69>")
	)
	(segment
		(start 199.748648 -309.815738)
		(end 200.193402 -309.815738)
		(width 0.1651)
		(layer "In5.Cu")
		(net "P5E_PEX1_STN4_RX_DP<69>")
	)
	(segment
		(start 198.468488 -327.079864)
		(end 198.280528 -327.53808)
		(width 0.1651)
		(layer "In5.Cu")
		(net "P5E_PEX1_STN4_RX_DP<69>")
	)
	(segment
		(start 201.387456 -317.0174)
		(end 200.445116 -319.27673)
		(width 0.1651)
		(layer "In5.Cu")
		(net "P5E_PEX1_STN4_RX_DP<69>")
	)
	(segment
		(start 195.965318 -309.199788)
		(end 196.079618 -309.314088)
		(width 0.1143)
		(layer "In5.Cu")
		(net "P5E_PEX1_STN4_RX_DP<69>")
	)
	(segment
		(start 192.532 -339.786976)
		(end 192.012062 -340.823296)
		(width 0.1651)
		(layer "In5.Cu")
		(net "P5E_PEX1_STN4_RX_DP<69>")
	)
	(segment
		(start 193.078608 -338.697316)
		(end 192.856612 -339.139784)
		(width 0.1651)
		(layer "In5.Cu")
		(net "P5E_PEX1_STN4_RX_DP<69>")
	)
	(segment
		(start 199.201278 -325.596504)
		(end 198.618094 -327.01738)
		(width 0.1651)
		(layer "In5.Cu")
		(net "P5E_PEX1_STN4_RX_DP<69>")
	)
	(segment
		(start 164.43706 -378.79909)
		(end 164.31006 -378.67209)
		(width 0.1651)
		(layer "In5.Cu")
		(net "P5E_PEX1_STN4_RX_DP<69>")
	)
	(segment
		(start 194.344036 -335.921096)
		(end 194.121786 -336.364072)
		(width 0.1651)
		(layer "In5.Cu")
		(net "P5E_PEX1_STN4_RX_DP<69>")
	)
	(segment
		(start 199.67448 -309.770018)
		(end 199.7202 -309.815738)
		(width 0.1143)
		(layer "In5.Cu")
		(net "P5E_PEX1_STN4_RX_DP<69>")
	)
	(segment
		(start 196.079618 -309.544212)
		(end 196.305424 -309.770018)
		(width 0.1143)
		(layer "In5.Cu")
		(net "P5E_PEX1_STN4_RX_DP<69>")
	)
	(segment
		(start 199.7202 -309.815738)
		(end 199.748648 -309.815738)
		(width 0.1143)
		(layer "In5.Cu")
		(net "P5E_PEX1_STN4_RX_DP<69>")
	)
	(segment
		(start 193.574924 -337.453986)
		(end 193.625724 -337.607402)
		(width 0.1651)
		(layer "In5.Cu")
		(net "P5E_PEX1_STN4_RX_DP<69>")
	)
	(segment
		(start 192.856866 -339.139784)
		(end 192.70345 -339.190584)
		(width 0.1651)
		(layer "In5.Cu")
		(net "P5E_PEX1_STN4_RX_DP<69>")
	)
	(segment
		(start 173.067472 -364.487206)
		(end 171.759372 -365.041942)
		(width 0.1651)
		(layer "In5.Cu")
		(net "P5E_PEX1_STN4_RX_DP<69>")
	)
	(segment
		(start 194.497452 -335.870042)
		(end 194.344036 -335.921096)
		(width 0.1651)
		(layer "In5.Cu")
		(net "P5E_PEX1_STN4_RX_DP<69>")
	)
	(segment
		(start 168.512744 -366.419384)
		(end 165.651942 -368.3635)
		(width 0.1651)
		(layer "In5.Cu")
		(net "P5E_PEX1_STN4_RX_DP<69>")
	)
	(segment
		(start 197.416166 -329.943206)
		(end 197.170294 -330.542392)
		(width 0.1651)
		(layer "In5.Cu")
		(net "P5E_PEX1_STN4_RX_DP<69>")
	)
	(segment
		(start 200.193402 -309.815738)
		(end 200.568814 -310.19115)
		(width 0.1651)
		(layer "In5.Cu")
		(net "P5E_PEX1_STN4_RX_DP<69>")
	)
	(segment
		(start 193.078862 -338.697316)
		(end 193.078608 -338.697316)
		(width 0.1651)
		(layer "In5.Cu")
		(net "P5E_PEX1_STN4_RX_DP<69>")
	)
	(segment
		(start 164.31006 -378.67209)
		(end 164.31006 -378.290074)
		(width 0.1651)
		(layer "In5.Cu")
		(net "P5E_PEX1_STN4_RX_DP<69>")
	)
	(segment
		(start 169.491406 -366.004094)
		(end 168.512744 -366.419384)
		(width 0.1651)
		(layer "In5.Cu")
		(net "P5E_PEX1_STN4_RX_DP<69>")
	)
	(segment
		(start 173.080934 -364.481872)
		(end 173.067472 -364.487206)
		(width 0.1651)
		(layer "In5.Cu")
		(net "P5E_PEX1_STN4_RX_DP<69>")
	)
	(segment
		(start 193.403728 -338.04987)
		(end 193.250312 -338.100924)
		(width 0.1651)
		(layer "In5.Cu")
		(net "P5E_PEX1_STN4_RX_DP<69>")
	)
	(segment
		(start 192.012062 -352.250756)
		(end 191.550544 -354.569522)
		(width 0.1651)
		(layer "In5.Cu")
		(net "P5E_PEX1_STN4_RX_DP<69>")
	)
	(segment
		(start 186.322716 -361.544362)
		(end 175.487838 -363.735366)
		(width 0.1651)
		(layer "In5.Cu")
		(net "P5E_PEX1_STN4_RX_DP<69>")
	)
	(segment
		(start 175.487838 -363.735366)
		(end 173.080934 -364.481872)
		(width 0.1651)
		(layer "In5.Cu")
		(net "P5E_PEX1_STN4_RX_DP<69>")
	)
	(segment
		(start 193.403474 -338.04987)
		(end 193.403728 -338.04987)
		(width 0.1651)
		(layer "In5.Cu")
		(net "P5E_PEX1_STN4_RX_DP<69>")
	)
	(segment
		(start 198.154798 -328.145394)
		(end 198.005446 -328.207878)
		(width 0.1651)
		(layer "In5.Cu")
		(net "P5E_PEX1_STN4_RX_DP<69>")
	)
	(segment
		(start 198.342758 -327.687432)
		(end 198.154798 -328.145394)
		(width 0.1651)
		(layer "In5.Cu")
		(net "P5E_PEX1_STN4_RX_DP<69>")
	)
	(segment
		(start 193.797174 -337.01101)
		(end 193.574924 -337.453986)
		(width 0.1651)
		(layer "In5.Cu")
		(net "P5E_PEX1_STN4_RX_DP<69>")
	)
	(segment
		(start 192.856612 -339.139784)
		(end 192.856866 -339.139784)
		(width 0.1651)
		(layer "In5.Cu")
		(net "P5E_PEX1_STN4_RX_DP<69>")
	)
	(segment
		(start 196.305424 -309.770018)
		(end 199.67448 -309.770018)
		(width 0.1143)
		(layer "In5.Cu")
		(net "P5E_PEX1_STN4_RX_DP<69>")
	)
	(segment
		(start 194.121786 -336.364072)
		(end 194.172586 -336.517488)
		(width 0.1651)
		(layer "In5.Cu")
		(net "P5E_PEX1_STN4_RX_DP<69>")
	)
	(segment
		(start 171.759372 -365.041942)
		(end 169.491406 -366.004094)
		(width 0.1651)
		(layer "In5.Cu")
		(net "P5E_PEX1_STN4_RX_DP<69>")
	)
	(segment
		(start 194.172332 -336.517488)
		(end 193.950336 -336.959956)
		(width 0.1651)
		(layer "In5.Cu")
		(net "P5E_PEX1_STN4_RX_DP<69>")
	)
	(segment
		(start 193.62547 -337.607402)
		(end 193.403474 -338.04987)
		(width 0.1651)
		(layer "In5.Cu")
		(net "P5E_PEX1_STN4_RX_DP<69>")
	)
	(segment
		(start 189.71133 -359.010204)
		(end 188.152532 -360.57967)
		(width 0.1651)
		(layer "In5.Cu")
		(net "P5E_PEX1_STN4_RX_DP<69>")
	)
	(segment
		(start 197.817232 -328.666094)
		(end 197.879462 -328.815446)
		(width 0.1651)
		(layer "In5.Cu")
		(net "P5E_PEX1_STN4_RX_DP<69>")
	)
	(segment
		(start 193.028062 -338.5439)
		(end 193.078862 -338.697316)
		(width 0.1651)
		(layer "In5.Cu")
		(net "P5E_PEX1_STN4_RX_DP<69>")
	)
	(segment
		(start 168.698672 -351.316798)
		(end 168.698672 -350.685354)
		(width 0.13462)
		(layer "F.Cu")
		(net "P5E_PEX1_STN4_TX_C_DP<76>")
	)
	(segment
		(start 168.698672 -350.685354)
		(end 168.378632 -350.365314)
		(width 0.13462)
		(layer "F.Cu")
		(net "P5E_PEX1_STN4_TX_C_DP<76>")
	)
	(segment
		(start 168.404032 -351.611438)
		(end 168.698672 -351.316798)
		(width 0.13462)
		(layer "F.Cu")
		(net "P5E_PEX1_STN4_TX_C_DP<76>")
	)
	(segment
		(start 168.694862 -351.902268)
		(end 168.404032 -351.611438)
		(width 0.1651)
		(layer "In7.Cu")
		(net "P5E_PEX1_STN4_TX_C_DP<76>")
	)
	(segment
		(start 157.26664 -389.096758)
		(end 155.783026 -387.613398)
		(width 0.1651)
		(layer "In7.Cu")
		(net "P5E_PEX1_STN4_TX_C_DP<76>")
	)
	(segment
		(start 167.140382 -359.072434)
		(end 167.140382 -354.118418)
		(width 0.1651)
		(layer "In7.Cu")
		(net "P5E_PEX1_STN4_TX_C_DP<76>")
	)
	(segment
		(start 166.509954 -397.972026)
		(end 166.636954 -398.099026)
		(width 0.1651)
		(layer "In7.Cu")
		(net "P5E_PEX1_STN4_TX_C_DP<76>")
	)
	(segment
		(start 154.60218 -384.762502)
		(end 154.559 -384.658362)
		(width 0.1651)
		(layer "In7.Cu")
		(net "P5E_PEX1_STN4_TX_C_DP<76>")
	)
	(segment
		(start 155.783026 -387.613398)
		(end 154.748484 -385.115816)
		(width 0.1651)
		(layer "In7.Cu")
		(net "P5E_PEX1_STN4_TX_C_DP<76>")
	)
	(segment
		(start 162.462972 -391.960354)
		(end 162.025584 -391.727436)
		(width 0.1651)
		(layer "In7.Cu")
		(net "P5E_PEX1_STN4_TX_C_DP<76>")
	)
	(segment
		(start 162.025584 -391.727436)
		(end 161.988754 -391.607294)
		(width 0.1651)
		(layer "In7.Cu")
		(net "P5E_PEX1_STN4_TX_C_DP<76>")
	)
	(segment
		(start 163.020502 -392.155934)
		(end 162.583368 -391.923524)
		(width 0.1651)
		(layer "In7.Cu")
		(net "P5E_PEX1_STN4_TX_C_DP<76>")
	)
	(segment
		(start 165.627812 -393.726416)
		(end 164.280342 -392.825986)
		(width 0.1651)
		(layer "In7.Cu")
		(net "P5E_PEX1_STN4_TX_C_DP<76>")
	)
	(segment
		(start 163.614862 -392.472164)
		(end 163.49472 -392.508994)
		(width 0.1651)
		(layer "In7.Cu")
		(net "P5E_PEX1_STN4_TX_C_DP<76>")
	)
	(segment
		(start 163.49472 -392.508994)
		(end 163.057078 -392.27633)
		(width 0.1651)
		(layer "In7.Cu")
		(net "P5E_PEX1_STN4_TX_C_DP<76>")
	)
	(segment
		(start 161.104326 -362.089192)
		(end 166.289736 -359.92308)
		(width 0.1651)
		(layer "In7.Cu")
		(net "P5E_PEX1_STN4_TX_C_DP<76>")
	)
	(segment
		(start 155.294838 -367.301526)
		(end 156.684218 -365.194342)
		(width 0.1651)
		(layer "In7.Cu")
		(net "P5E_PEX1_STN4_TX_C_DP<76>")
	)
	(segment
		(start 163.057078 -392.27633)
		(end 163.020502 -392.155934)
		(width 0.1651)
		(layer "In7.Cu")
		(net "P5E_PEX1_STN4_TX_C_DP<76>")
	)
	(segment
		(start 156.684218 -365.194342)
		(end 161.104326 -362.089192)
		(width 0.1651)
		(layer "In7.Cu")
		(net "P5E_PEX1_STN4_TX_C_DP<76>")
	)
	(segment
		(start 168.694862 -352.563938)
		(end 168.694862 -351.902268)
		(width 0.1651)
		(layer "In7.Cu")
		(net "P5E_PEX1_STN4_TX_C_DP<76>")
	)
	(segment
		(start 166.289736 -359.92308)
		(end 167.140382 -359.072434)
		(width 0.1651)
		(layer "In7.Cu")
		(net "P5E_PEX1_STN4_TX_C_DP<76>")
	)
	(segment
		(start 167.287448 -397.680688)
		(end 167.287448 -395.386052)
		(width 0.1651)
		(layer "In7.Cu")
		(net "P5E_PEX1_STN4_TX_C_DP<76>")
	)
	(segment
		(start 154.559 -384.658362)
		(end 154.559 -369.06962)
		(width 0.1651)
		(layer "In7.Cu")
		(net "P5E_PEX1_STN4_TX_C_DP<76>")
	)
	(segment
		(start 161.988754 -391.607294)
		(end 157.26664 -389.096758)
		(width 0.1651)
		(layer "In7.Cu")
		(net "P5E_PEX1_STN4_TX_C_DP<76>")
	)
	(segment
		(start 154.559 -369.06962)
		(end 155.294838 -367.301526)
		(width 0.1651)
		(layer "In7.Cu")
		(net "P5E_PEX1_STN4_TX_C_DP<76>")
	)
	(segment
		(start 167.140382 -354.118418)
		(end 168.694862 -352.563938)
		(width 0.1651)
		(layer "In7.Cu")
		(net "P5E_PEX1_STN4_TX_C_DP<76>")
	)
	(segment
		(start 166.636954 -398.099026)
		(end 166.86911 -398.099026)
		(width 0.1651)
		(layer "In7.Cu")
		(net "P5E_PEX1_STN4_TX_C_DP<76>")
	)
	(segment
		(start 164.280342 -392.825986)
		(end 163.614862 -392.472164)
		(width 0.1651)
		(layer "In7.Cu")
		(net "P5E_PEX1_STN4_TX_C_DP<76>")
	)
	(segment
		(start 154.748484 -385.115816)
		(end 154.60218 -384.762502)
		(width 0.1651)
		(layer "In7.Cu")
		(net "P5E_PEX1_STN4_TX_C_DP<76>")
	)
	(segment
		(start 166.86911 -398.099026)
		(end 167.287448 -397.680688)
		(width 0.1651)
		(layer "In7.Cu")
		(net "P5E_PEX1_STN4_TX_C_DP<76>")
	)
	(segment
		(start 162.583368 -391.923524)
		(end 162.462972 -391.960354)
		(width 0.1651)
		(layer "In7.Cu")
		(net "P5E_PEX1_STN4_TX_C_DP<76>")
	)
	(segment
		(start 166.509954 -397.59001)
		(end 166.509954 -397.972026)
		(width 0.1651)
		(layer "In7.Cu")
		(net "P5E_PEX1_STN4_TX_C_DP<76>")
	)
	(segment
		(start 167.287448 -395.386052)
		(end 165.627812 -393.726416)
		(width 0.1651)
		(layer "In7.Cu")
		(net "P5E_PEX1_STN4_TX_C_DP<76>")
	)
	(segment
		(start 165.589712 -356.831646)
		(end 165.269672 -356.511606)
		(width 0.13462)
		(layer "F.Cu")
		(net "P5E_PEX1_STN4_TX_C_DP<77>")
	)
	(segment
		(start 165.295072 -357.75773)
		(end 165.589712 -357.46309)
		(width 0.13462)
		(layer "F.Cu")
		(net "P5E_PEX1_STN4_TX_C_DP<77>")
	)
	(segment
		(start 165.589712 -357.46309)
		(end 165.589712 -356.831646)
		(width 0.13462)
		(layer "F.Cu")
		(net "P5E_PEX1_STN4_TX_C_DP<77>")
	)
	(segment
		(start 153.60396 -368.881406)
		(end 154.340814 -366.997234)
		(width 0.1651)
		(layer "In7.Cu")
		(net "P5E_PEX1_STN4_TX_C_DP<77>")
	)
	(segment
		(start 165.087554 -395.008608)
		(end 164.94379 -394.792962)
		(width 0.1651)
		(layer "In7.Cu")
		(net "P5E_PEX1_STN4_TX_C_DP<77>")
	)
	(segment
		(start 160.752028 -361.169204)
		(end 165.32987 -359.258108)
		(width 0.1651)
		(layer "In7.Cu")
		(net "P5E_PEX1_STN4_TX_C_DP<77>")
	)
	(segment
		(start 164.43706 -396.998952)
		(end 164.669216 -396.998952)
		(width 0.1651)
		(layer "In7.Cu")
		(net "P5E_PEX1_STN4_TX_C_DP<77>")
	)
	(segment
		(start 165.087554 -396.580614)
		(end 165.087554 -395.008608)
		(width 0.1651)
		(layer "In7.Cu")
		(net "P5E_PEX1_STN4_TX_C_DP<77>")
	)
	(segment
		(start 164.31006 -396.871952)
		(end 164.43706 -396.998952)
		(width 0.1651)
		(layer "In7.Cu")
		(net "P5E_PEX1_STN4_TX_C_DP<77>")
	)
	(segment
		(start 165.32987 -359.258108)
		(end 165.585902 -359.002076)
		(width 0.1651)
		(layer "In7.Cu")
		(net "P5E_PEX1_STN4_TX_C_DP<77>")
	)
	(segment
		(start 156.705808 -389.886952)
		(end 154.972512 -388.153656)
		(width 0.1651)
		(layer "In7.Cu")
		(net "P5E_PEX1_STN4_TX_C_DP<77>")
	)
	(segment
		(start 163.795456 -394.042646)
		(end 163.672266 -394.068554)
		(width 0.1651)
		(layer "In7.Cu")
		(net "P5E_PEX1_STN4_TX_C_DP<77>")
	)
	(segment
		(start 163.231576 -393.674092)
		(end 162.817048 -393.403328)
		(width 0.1651)
		(layer "In7.Cu")
		(net "P5E_PEX1_STN4_TX_C_DP<77>")
	)
	(segment
		(start 163.257484 -393.797282)
		(end 163.231576 -393.674092)
		(width 0.1651)
		(layer "In7.Cu")
		(net "P5E_PEX1_STN4_TX_C_DP<77>")
	)
	(segment
		(start 154.340814 -366.997234)
		(end 155.966414 -364.531148)
		(width 0.1651)
		(layer "In7.Cu")
		(net "P5E_PEX1_STN4_TX_C_DP<77>")
	)
	(segment
		(start 162.279076 -393.157964)
		(end 162.253422 -393.035028)
		(width 0.1651)
		(layer "In7.Cu")
		(net "P5E_PEX1_STN4_TX_C_DP<77>")
	)
	(segment
		(start 163.672266 -394.068554)
		(end 163.257484 -393.797282)
		(width 0.1651)
		(layer "In7.Cu")
		(net "P5E_PEX1_STN4_TX_C_DP<77>")
	)
	(segment
		(start 164.94379 -394.792962)
		(end 163.795456 -394.042646)
		(width 0.1651)
		(layer "In7.Cu")
		(net "P5E_PEX1_STN4_TX_C_DP<77>")
	)
	(segment
		(start 155.966414 -364.531148)
		(end 160.752028 -361.169204)
		(width 0.1651)
		(layer "In7.Cu")
		(net "P5E_PEX1_STN4_TX_C_DP<77>")
	)
	(segment
		(start 154.972512 -388.153656)
		(end 153.60396 -384.848608)
		(width 0.1651)
		(layer "In7.Cu")
		(net "P5E_PEX1_STN4_TX_C_DP<77>")
	)
	(segment
		(start 164.669216 -396.998952)
		(end 165.087554 -396.580614)
		(width 0.1651)
		(layer "In7.Cu")
		(net "P5E_PEX1_STN4_TX_C_DP<77>")
	)
	(segment
		(start 153.60396 -384.848608)
		(end 153.60396 -368.881406)
		(width 0.1651)
		(layer "In7.Cu")
		(net "P5E_PEX1_STN4_TX_C_DP<77>")
	)
	(segment
		(start 165.585902 -359.002076)
		(end 165.585902 -358.04856)
		(width 0.1651)
		(layer "In7.Cu")
		(net "P5E_PEX1_STN4_TX_C_DP<77>")
	)
	(segment
		(start 165.585902 -358.04856)
		(end 165.295072 -357.75773)
		(width 0.1651)
		(layer "In7.Cu")
		(net "P5E_PEX1_STN4_TX_C_DP<77>")
	)
	(segment
		(start 164.31006 -396.49019)
		(end 164.31006 -396.871952)
		(width 0.1651)
		(layer "In7.Cu")
		(net "P5E_PEX1_STN4_TX_C_DP<77>")
	)
	(segment
		(start 162.694112 -393.429236)
		(end 162.279076 -393.157964)
		(width 0.1651)
		(layer "In7.Cu")
		(net "P5E_PEX1_STN4_TX_C_DP<77>")
	)
	(segment
		(start 162.817048 -393.403328)
		(end 162.694112 -393.429236)
		(width 0.1651)
		(layer "In7.Cu")
		(net "P5E_PEX1_STN4_TX_C_DP<77>")
	)
	(segment
		(start 162.253422 -393.035028)
		(end 160.572704 -391.936986)
		(width 0.1651)
		(layer "In7.Cu")
		(net "P5E_PEX1_STN4_TX_C_DP<77>")
	)
	(segment
		(start 160.572704 -391.936986)
		(end 156.705808 -389.886952)
		(width 0.1651)
		(layer "In7.Cu")
		(net "P5E_PEX1_STN4_TX_C_DP<77>")
	)
	(segment
		(start 179.221384 -359.276396)
		(end 179.858162 -358.639618)
		(width 0.1651)
		(layer "In5.Cu")
		(net "P5E_PEX1_STN4_RX_DN<73>")
	)
	(segment
		(start 162.859974 -388.046214)
		(end 159.078422 -386.45719)
		(width 0.1651)
		(layer "In5.Cu")
		(net "P5E_PEX1_STN4_RX_DN<73>")
	)
	(segment
		(start 173.23689 -405.080978)
		(end 173.786546 -405.080978)
		(width 0.1651)
		(layer "In5.Cu")
		(net "P5E_PEX1_STN4_RX_DN<73>")
	)
	(segment
		(start 175.117252 -360.10723)
		(end 179.221384 -359.276396)
		(width 0.1651)
		(layer "In5.Cu")
		(net "P5E_PEX1_STN4_RX_DN<73>")
	)
	(segment
		(start 181.2036 -339.4456)
		(end 190.9318 -329.6158)
		(width 0.1651)
		(layer "In5.Cu")
		(net "P5E_PEX1_STN4_RX_DN<73>")
	)
	(segment
		(start 192.783206 -327.478644)
		(end 194.31762 -325.317358)
		(width 0.1651)
		(layer "In5.Cu")
		(net "P5E_PEX1_STN4_RX_DN<73>")
	)
	(segment
		(start 157.74924 -384.13436)
		(end 157.74924 -369.641374)
		(width 0.1651)
		(layer "In5.Cu")
		(net "P5E_PEX1_STN4_RX_DN<73>")
	)
	(segment
		(start 173.786546 -405.080978)
		(end 174.169324 -404.6982)
		(width 0.1651)
		(layer "In5.Cu")
		(net "P5E_PEX1_STN4_RX_DN<73>")
	)
	(segment
		(start 173.728888 -394.414756)
		(end 169.563288 -391.628884)
		(width 0.1651)
		(layer "In5.Cu")
		(net "P5E_PEX1_STN4_RX_DN<73>")
	)
	(segment
		(start 190.9318 -329.6158)
		(end 192.783206 -327.478644)
		(width 0.1651)
		(layer "In5.Cu")
		(net "P5E_PEX1_STN4_RX_DN<73>")
	)
	(segment
		(start 158.451804 -385.830064)
		(end 157.74924 -384.13436)
		(width 0.1651)
		(layer "In5.Cu")
		(net "P5E_PEX1_STN4_RX_DN<73>")
	)
	(segment
		(start 174.169324 -404.6982)
		(end 174.169324 -394.79347)
		(width 0.1651)
		(layer "In5.Cu")
		(net "P5E_PEX1_STN4_RX_DN<73>")
	)
	(segment
		(start 194.31762 -325.317358)
		(end 195.365878 -322.029836)
		(width 0.1651)
		(layer "In5.Cu")
		(net "P5E_PEX1_STN4_RX_DN<73>")
	)
	(segment
		(start 173.10989 -405.207978)
		(end 173.23689 -405.080978)
		(width 0.1651)
		(layer "In5.Cu")
		(net "P5E_PEX1_STN4_RX_DN<73>")
	)
	(segment
		(start 195.699888 -316.534292)
		(end 195.699888 -316.799722)
		(width 0.1143)
		(layer "In5.Cu")
		(net "P5E_PEX1_STN4_RX_DN<73>")
	)
	(segment
		(start 159.09417 -367.668556)
		(end 162.68573 -365.07928)
		(width 0.1651)
		(layer "In5.Cu")
		(net "P5E_PEX1_STN4_RX_DN<73>")
	)
	(segment
		(start 157.74924 -369.641374)
		(end 158.156148 -368.606832)
		(width 0.1651)
		(layer "In5.Cu")
		(net "P5E_PEX1_STN4_RX_DN<73>")
	)
	(segment
		(start 171.309284 -361.28706)
		(end 175.117252 -360.107484)
		(width 0.1651)
		(layer "In5.Cu")
		(net "P5E_PEX1_STN4_RX_DN<73>")
	)
	(segment
		(start 169.563288 -391.628884)
		(end 162.859974 -388.046214)
		(width 0.1651)
		(layer "In5.Cu")
		(net "P5E_PEX1_STN4_RX_DN<73>")
	)
	(segment
		(start 195.365878 -320.0908)
		(end 195.320158 -320.04508)
		(width 0.1143)
		(layer "In5.Cu")
		(net "P5E_PEX1_STN4_RX_DN<73>")
	)
	(segment
		(start 175.117252 -360.107484)
		(end 175.117252 -360.10723)
		(width 0.1651)
		(layer "In5.Cu")
		(net "P5E_PEX1_STN4_RX_DN<73>")
	)
	(segment
		(start 195.585588 -316.419992)
		(end 195.699888 -316.534292)
		(width 0.1143)
		(layer "In5.Cu")
		(net "P5E_PEX1_STN4_RX_DN<73>")
	)
	(segment
		(start 195.434458 -316.419992)
		(end 195.585588 -316.419992)
		(width 0.1143)
		(layer "In5.Cu")
		(net "P5E_PEX1_STN4_RX_DN<73>")
	)
	(segment
		(start 179.858162 -358.639618)
		(end 179.858162 -341.907876)
		(width 0.1651)
		(layer "In5.Cu")
		(net "P5E_PEX1_STN4_RX_DN<73>")
	)
	(segment
		(start 158.156148 -368.606832)
		(end 159.09417 -367.668556)
		(width 0.1651)
		(layer "In5.Cu")
		(net "P5E_PEX1_STN4_RX_DN<73>")
	)
	(segment
		(start 162.68573 -365.07928)
		(end 171.309284 -361.28706)
		(width 0.1651)
		(layer "In5.Cu")
		(net "P5E_PEX1_STN4_RX_DN<73>")
	)
	(segment
		(start 159.078422 -386.45719)
		(end 158.451804 -385.830064)
		(width 0.1651)
		(layer "In5.Cu")
		(net "P5E_PEX1_STN4_RX_DN<73>")
	)
	(segment
		(start 195.365878 -320.119248)
		(end 195.365878 -320.0908)
		(width 0.1143)
		(layer "In5.Cu")
		(net "P5E_PEX1_STN4_RX_DN<73>")
	)
	(segment
		(start 195.320158 -320.04508)
		(end 195.320158 -316.534292)
		(width 0.1143)
		(layer "In5.Cu")
		(net "P5E_PEX1_STN4_RX_DN<73>")
	)
	(segment
		(start 174.169324 -394.79347)
		(end 173.728888 -394.414756)
		(width 0.1651)
		(layer "In5.Cu")
		(net "P5E_PEX1_STN4_RX_DN<73>")
	)
	(segment
		(start 173.10989 -405.589994)
		(end 173.10989 -405.207978)
		(width 0.1651)
		(layer "In5.Cu")
		(net "P5E_PEX1_STN4_RX_DN<73>")
	)
	(segment
		(start 195.320158 -316.534292)
		(end 195.434458 -316.419992)
		(width 0.1143)
		(layer "In5.Cu")
		(net "P5E_PEX1_STN4_RX_DN<73>")
	)
	(segment
		(start 179.858162 -341.907876)
		(end 181.2036 -339.4456)
		(width 0.1651)
		(layer "In5.Cu")
		(net "P5E_PEX1_STN4_RX_DN<73>")
	)
	(segment
		(start 195.365878 -322.029836)
		(end 195.365878 -320.119248)
		(width 0.1651)
		(layer "In5.Cu")
		(net "P5E_PEX1_STN4_RX_DN<73>")
	)
	(segment
		(start 165.589712 -344.539062)
		(end 165.269672 -344.219022)
		(width 0.13462)
		(layer "F.Cu")
		(net "P5E_PEX1_STN4_TX_C_DP<78>")
	)
	(segment
		(start 165.589712 -345.170506)
		(end 165.589712 -344.539062)
		(width 0.13462)
		(layer "F.Cu")
		(net "P5E_PEX1_STN4_TX_C_DP<78>")
	)
	(segment
		(start 165.295072 -345.465146)
		(end 165.589712 -345.170506)
		(width 0.13462)
		(layer "F.Cu")
		(net "P5E_PEX1_STN4_TX_C_DP<78>")
	)
	(segment
		(start 155.238196 -363.874812)
		(end 153.495248 -366.536224)
		(width 0.1651)
		(layer "In7.Cu")
		(net "P5E_PEX1_STN4_TX_C_DP<78>")
	)
	(segment
		(start 162.109912 -397.972026)
		(end 162.109912 -397.59001)
		(width 0.1651)
		(layer "In7.Cu")
		(net "P5E_PEX1_STN4_TX_C_DP<78>")
	)
	(segment
		(start 155.32481 -389.98271)
		(end 155.45054 -389.98271)
		(width 0.1651)
		(layer "In7.Cu")
		(net "P5E_PEX1_STN4_TX_C_DP<78>")
	)
	(segment
		(start 164.031422 -347.981778)
		(end 164.031422 -358.621838)
		(width 0.1651)
		(layer "In7.Cu")
		(net "P5E_PEX1_STN4_TX_C_DP<78>")
	)
	(segment
		(start 165.585902 -346.427298)
		(end 164.031422 -347.981778)
		(width 0.1651)
		(layer "In7.Cu")
		(net "P5E_PEX1_STN4_TX_C_DP<78>")
	)
	(segment
		(start 162.236912 -398.099026)
		(end 162.109912 -397.972026)
		(width 0.1651)
		(layer "In7.Cu")
		(net "P5E_PEX1_STN4_TX_C_DP<78>")
	)
	(segment
		(start 152.64892 -385.038854)
		(end 154.16276 -388.69493)
		(width 0.1651)
		(layer "In7.Cu")
		(net "P5E_PEX1_STN4_TX_C_DP<78>")
	)
	(segment
		(start 161.723324 -394.404596)
		(end 162.02025 -394.701776)
		(width 0.1651)
		(layer "In7.Cu")
		(net "P5E_PEX1_STN4_TX_C_DP<78>")
	)
	(segment
		(start 154.16276 -388.69493)
		(end 154.97429 -389.50646)
		(width 0.1651)
		(layer "In7.Cu")
		(net "P5E_PEX1_STN4_TX_C_DP<78>")
	)
	(segment
		(start 156.14904 -390.68121)
		(end 161.723324 -394.404596)
		(width 0.1651)
		(layer "In7.Cu")
		(net "P5E_PEX1_STN4_TX_C_DP<78>")
	)
	(segment
		(start 162.887406 -395.569186)
		(end 162.887406 -397.680688)
		(width 0.1651)
		(layer "In7.Cu")
		(net "P5E_PEX1_STN4_TX_C_DP<78>")
	)
	(segment
		(start 162.469068 -398.099026)
		(end 162.236912 -398.099026)
		(width 0.1651)
		(layer "In7.Cu")
		(net "P5E_PEX1_STN4_TX_C_DP<78>")
	)
	(segment
		(start 162.887406 -397.680688)
		(end 162.469068 -398.099026)
		(width 0.1651)
		(layer "In7.Cu")
		(net "P5E_PEX1_STN4_TX_C_DP<78>")
	)
	(segment
		(start 160.326578 -360.300778)
		(end 155.238196 -363.874812)
		(width 0.1651)
		(layer "In7.Cu")
		(net "P5E_PEX1_STN4_TX_C_DP<78>")
	)
	(segment
		(start 165.585902 -345.755976)
		(end 165.585902 -346.427298)
		(width 0.1651)
		(layer "In7.Cu")
		(net "P5E_PEX1_STN4_TX_C_DP<78>")
	)
	(segment
		(start 162.4965 -395.178026)
		(end 162.887406 -395.569186)
		(width 0.1651)
		(layer "In7.Cu")
		(net "P5E_PEX1_STN4_TX_C_DP<78>")
	)
	(segment
		(start 163.801806 -358.851454)
		(end 160.326578 -360.300778)
		(width 0.1651)
		(layer "In7.Cu")
		(net "P5E_PEX1_STN4_TX_C_DP<78>")
	)
	(segment
		(start 164.031422 -358.621838)
		(end 163.801806 -358.851454)
		(width 0.1651)
		(layer "In7.Cu")
		(net "P5E_PEX1_STN4_TX_C_DP<78>")
	)
	(segment
		(start 152.64892 -368.701066)
		(end 152.64892 -385.038854)
		(width 0.1651)
		(layer "In7.Cu")
		(net "P5E_PEX1_STN4_TX_C_DP<78>")
	)
	(segment
		(start 162.02025 -394.701776)
		(end 162.02025 -394.827506)
		(width 0.1651)
		(layer "In7.Cu")
		(net "P5E_PEX1_STN4_TX_C_DP<78>")
	)
	(segment
		(start 165.295072 -345.465146)
		(end 165.585902 -345.755976)
		(width 0.1651)
		(layer "In7.Cu")
		(net "P5E_PEX1_STN4_TX_C_DP<78>")
	)
	(segment
		(start 162.37077 -395.178026)
		(end 162.4965 -395.178026)
		(width 0.1651)
		(layer "In7.Cu")
		(net "P5E_PEX1_STN4_TX_C_DP<78>")
	)
	(segment
		(start 154.97429 -389.50646)
		(end 154.97429 -389.63219)
		(width 0.1651)
		(layer "In7.Cu")
		(net "P5E_PEX1_STN4_TX_C_DP<78>")
	)
	(segment
		(start 162.02025 -394.827506)
		(end 162.37077 -395.178026)
		(width 0.1651)
		(layer "In7.Cu")
		(net "P5E_PEX1_STN4_TX_C_DP<78>")
	)
	(segment
		(start 155.45054 -389.98271)
		(end 156.14904 -390.68121)
		(width 0.1651)
		(layer "In7.Cu")
		(net "P5E_PEX1_STN4_TX_C_DP<78>")
	)
	(segment
		(start 153.495248 -366.536224)
		(end 152.64892 -368.701066)
		(width 0.1651)
		(layer "In7.Cu")
		(net "P5E_PEX1_STN4_TX_C_DP<78>")
	)
	(segment
		(start 154.97429 -389.63219)
		(end 155.32481 -389.98271)
		(width 0.1651)
		(layer "In7.Cu")
		(net "P5E_PEX1_STN4_TX_C_DP<78>")
	)
	(segment
		(start 171.807632 -345.170506)
		(end 171.807632 -344.539062)
		(width 0.13462)
		(layer "F.Cu")
		(net "P5E_PEX1_STN4_TX_C_DP<75>")
	)
	(segment
		(start 171.512992 -345.465146)
		(end 171.807632 -345.170506)
		(width 0.13462)
		(layer "F.Cu")
		(net "P5E_PEX1_STN4_TX_C_DP<75>")
	)
	(segment
		(start 171.807632 -344.539062)
		(end 171.487592 -344.219022)
		(width 0.13462)
		(layer "F.Cu")
		(net "P5E_PEX1_STN4_TX_C_DP<75>")
	)
	(segment
		(start 171.803822 -346.432378)
		(end 171.803822 -345.755976)
		(width 0.1651)
		(layer "In7.Cu")
		(net "P5E_PEX1_STN4_TX_C_DP<75>")
	)
	(segment
		(start 157.401514 -365.858044)
		(end 161.568384 -362.930694)
		(width 0.1651)
		(layer "In7.Cu")
		(net "P5E_PEX1_STN4_TX_C_DP<75>")
	)
	(segment
		(start 155.55722 -369.399312)
		(end 155.614116 -369.221512)
		(width 0.1651)
		(layer "In7.Cu")
		(net "P5E_PEX1_STN4_TX_C_DP<75>")
	)
	(segment
		(start 169.487596 -396.580614)
		(end 169.487596 -394.994384)
		(width 0.1651)
		(layer "In7.Cu")
		(net "P5E_PEX1_STN4_TX_C_DP<75>")
	)
	(segment
		(start 170.249342 -347.986858)
		(end 171.803822 -346.432378)
		(width 0.1651)
		(layer "In7.Cu")
		(net "P5E_PEX1_STN4_TX_C_DP<75>")
	)
	(segment
		(start 166.960804 -393.275058)
		(end 166.548562 -392.999468)
		(width 0.1651)
		(layer "In7.Cu")
		(net "P5E_PEX1_STN4_TX_C_DP<75>")
	)
	(segment
		(start 169.069258 -396.998952)
		(end 169.487596 -396.580614)
		(width 0.1651)
		(layer "In7.Cu")
		(net "P5E_PEX1_STN4_TX_C_DP<75>")
	)
	(segment
		(start 155.614116 -369.221512)
		(end 156.291788 -367.541048)
		(width 0.1651)
		(layer "In7.Cu")
		(net "P5E_PEX1_STN4_TX_C_DP<75>")
	)
	(segment
		(start 156.59354 -387.072886)
		(end 155.859988 -385.30276)
		(width 0.1651)
		(layer "In7.Cu")
		(net "P5E_PEX1_STN4_TX_C_DP<75>")
	)
	(segment
		(start 169.392346 -394.792708)
		(end 168.055798 -393.899644)
		(width 0.1651)
		(layer "In7.Cu")
		(net "P5E_PEX1_STN4_TX_C_DP<75>")
	)
	(segment
		(start 164.892228 -391.785856)
		(end 160.501584 -389.43915)
		(width 0.1651)
		(layer "In7.Cu")
		(net "P5E_PEX1_STN4_TX_C_DP<75>")
	)
	(segment
		(start 168.710102 -396.49019)
		(end 168.710102 -396.871952)
		(width 0.1651)
		(layer "In7.Cu")
		(net "P5E_PEX1_STN4_TX_C_DP<75>")
	)
	(segment
		(start 170.053 -359.0036)
		(end 170.249342 -358.807258)
		(width 0.1651)
		(layer "In7.Cu")
		(net "P5E_PEX1_STN4_TX_C_DP<75>")
	)
	(segment
		(start 166.524178 -392.876278)
		(end 164.892228 -391.785856)
		(width 0.1651)
		(layer "In7.Cu")
		(net "P5E_PEX1_STN4_TX_C_DP<75>")
	)
	(segment
		(start 168.837102 -396.998952)
		(end 169.069258 -396.998952)
		(width 0.1651)
		(layer "In7.Cu")
		(net "P5E_PEX1_STN4_TX_C_DP<75>")
	)
	(segment
		(start 167.083994 -393.25042)
		(end 166.960804 -393.275058)
		(width 0.1651)
		(layer "In7.Cu")
		(net "P5E_PEX1_STN4_TX_C_DP<75>")
	)
	(segment
		(start 167.520366 -393.648692)
		(end 167.495728 -393.525502)
		(width 0.1651)
		(layer "In7.Cu")
		(net "P5E_PEX1_STN4_TX_C_DP<75>")
	)
	(segment
		(start 167.495728 -393.525502)
		(end 167.083994 -393.25042)
		(width 0.1651)
		(layer "In7.Cu")
		(net "P5E_PEX1_STN4_TX_C_DP<75>")
	)
	(segment
		(start 156.291788 -367.541048)
		(end 157.401514 -365.858044)
		(width 0.1651)
		(layer "In7.Cu")
		(net "P5E_PEX1_STN4_TX_C_DP<75>")
	)
	(segment
		(start 166.548562 -392.999468)
		(end 166.524178 -392.876278)
		(width 0.1651)
		(layer "In7.Cu")
		(net "P5E_PEX1_STN4_TX_C_DP<75>")
	)
	(segment
		(start 160.501584 -389.43915)
		(end 157.840934 -388.32028)
		(width 0.1651)
		(layer "In7.Cu")
		(net "P5E_PEX1_STN4_TX_C_DP<75>")
	)
	(segment
		(start 155.55722 -384.571748)
		(end 155.55722 -369.399312)
		(width 0.1651)
		(layer "In7.Cu")
		(net "P5E_PEX1_STN4_TX_C_DP<75>")
	)
	(segment
		(start 170.249342 -358.807258)
		(end 170.249342 -347.986858)
		(width 0.1651)
		(layer "In7.Cu")
		(net "P5E_PEX1_STN4_TX_C_DP<75>")
	)
	(segment
		(start 169.487596 -394.994384)
		(end 169.392346 -394.792708)
		(width 0.1651)
		(layer "In7.Cu")
		(net "P5E_PEX1_STN4_TX_C_DP<75>")
	)
	(segment
		(start 171.803822 -345.755976)
		(end 171.512992 -345.465146)
		(width 0.1651)
		(layer "In7.Cu")
		(net "P5E_PEX1_STN4_TX_C_DP<75>")
	)
	(segment
		(start 168.710102 -396.871952)
		(end 168.837102 -396.998952)
		(width 0.1651)
		(layer "In7.Cu")
		(net "P5E_PEX1_STN4_TX_C_DP<75>")
	)
	(segment
		(start 168.055798 -393.899644)
		(end 167.932354 -393.924028)
		(width 0.1651)
		(layer "In7.Cu")
		(net "P5E_PEX1_STN4_TX_C_DP<75>")
	)
	(segment
		(start 167.932354 -393.924028)
		(end 167.520366 -393.648692)
		(width 0.1651)
		(layer "In7.Cu")
		(net "P5E_PEX1_STN4_TX_C_DP<75>")
	)
	(segment
		(start 161.568384 -362.930694)
		(end 168.652952 -359.97134)
		(width 0.1651)
		(layer "In7.Cu")
		(net "P5E_PEX1_STN4_TX_C_DP<75>")
	)
	(segment
		(start 168.652952 -359.97134)
		(end 170.053 -359.0036)
		(width 0.1651)
		(layer "In7.Cu")
		(net "P5E_PEX1_STN4_TX_C_DP<75>")
	)
	(segment
		(start 155.859988 -385.30276)
		(end 155.55722 -384.571748)
		(width 0.1651)
		(layer "In7.Cu")
		(net "P5E_PEX1_STN4_TX_C_DP<75>")
	)
	(segment
		(start 157.840934 -388.32028)
		(end 156.59354 -387.072886)
		(width 0.1651)
		(layer "In7.Cu")
		(net "P5E_PEX1_STN4_TX_C_DP<75>")
	)
	(segment
		(start 181.408832 -351.316798)
		(end 181.408832 -350.685354)
		(width 0.13462)
		(layer "F.Cu")
		(net "P5E_PEX1_STN4_TX_C_DN<70>")
	)
	(segment
		(start 181.703472 -351.611438)
		(end 181.408832 -351.316798)
		(width 0.13462)
		(layer "F.Cu")
		(net "P5E_PEX1_STN4_TX_C_DN<70>")
	)
	(segment
		(start 181.408832 -350.685354)
		(end 181.728872 -350.365314)
		(width 0.13462)
		(layer "F.Cu")
		(net "P5E_PEX1_STN4_TX_C_DN<70>")
	)
	(segment
		(start 181.412642 -352.640138)
		(end 181.412642 -351.902268)
		(width 0.1651)
		(layer "In7.Cu")
		(net "P5E_PEX1_STN4_TX_C_DN<70>")
	)
	(segment
		(start 176.975262 -361.97921)
		(end 179.858162 -359.12298)
		(width 0.1651)
		(layer "In7.Cu")
		(net "P5E_PEX1_STN4_TX_C_DN<70>")
	)
	(segment
		(start 162.109912 -372.508018)
		(end 162.237166 -372.380764)
		(width 0.1651)
		(layer "In7.Cu")
		(net "P5E_PEX1_STN4_TX_C_DN<70>")
	)
	(segment
		(start 163.169346 -371.797326)
		(end 163.169346 -369.343432)
		(width 0.1651)
		(layer "In7.Cu")
		(net "P5E_PEX1_STN4_TX_C_DN<70>")
	)
	(segment
		(start 179.858162 -359.12298)
		(end 179.858162 -354.194618)
		(width 0.1651)
		(layer "In7.Cu")
		(net "P5E_PEX1_STN4_TX_C_DN<70>")
	)
	(segment
		(start 179.858162 -354.194618)
		(end 181.412642 -352.640138)
		(width 0.1651)
		(layer "In7.Cu")
		(net "P5E_PEX1_STN4_TX_C_DN<70>")
	)
	(segment
		(start 162.109912 -372.890034)
		(end 162.109912 -372.508018)
		(width 0.1651)
		(layer "In7.Cu")
		(net "P5E_PEX1_STN4_TX_C_DN<70>")
	)
	(segment
		(start 164.575236 -367.687352)
		(end 176.975262 -361.97921)
		(width 0.1651)
		(layer "In7.Cu")
		(net "P5E_PEX1_STN4_TX_C_DN<70>")
	)
	(segment
		(start 163.169346 -369.343432)
		(end 164.575236 -367.687352)
		(width 0.1651)
		(layer "In7.Cu")
		(net "P5E_PEX1_STN4_TX_C_DN<70>")
	)
	(segment
		(start 162.237166 -372.380764)
		(end 162.585908 -372.380764)
		(width 0.1651)
		(layer "In7.Cu")
		(net "P5E_PEX1_STN4_TX_C_DN<70>")
	)
	(segment
		(start 181.412642 -351.902268)
		(end 181.703472 -351.611438)
		(width 0.1651)
		(layer "In7.Cu")
		(net "P5E_PEX1_STN4_TX_C_DN<70>")
	)
	(segment
		(start 162.585908 -372.380764)
		(end 163.169346 -371.797326)
		(width 0.1651)
		(layer "In7.Cu")
		(net "P5E_PEX1_STN4_TX_C_DN<70>")
	)
	(segment
		(start 212.2678 -316.963806)
		(end 212.168232 -316.77356)
		(width 0.1651)
		(layer "In5.Cu")
		(net "P5E_PEX1_STN4_RX_DN<66>")
	)
	(segment
		(start 207.74914 -313.015376)
		(end 204.261212 -309.532528)
		(width 0.1651)
		(layer "In5.Cu")
		(net "P5E_PEX1_STN4_RX_DN<66>")
	)
	(segment
		(start 172.68444 -368.588544)
		(end 173.82617 -367.729008)
		(width 0.1651)
		(layer "In5.Cu")
		(net "P5E_PEX1_STN4_RX_DN<66>")
	)
	(segment
		(start 192.490344 -360.835194)
		(end 197.288912 -355.211126)
		(width 0.1651)
		(layer "In5.Cu")
		(net "P5E_PEX1_STN4_RX_DN<66>")
	)
	(segment
		(start 198.170292 -306.464208)
		(end 198.284592 -306.349908)
		(width 0.1143)
		(layer "In5.Cu")
		(net "P5E_PEX1_STN4_RX_DN<66>")
	)
	(segment
		(start 213.32952 -319.556638)
		(end 212.2678 -316.963806)
		(width 0.1651)
		(layer "In5.Cu")
		(net "P5E_PEX1_STN4_RX_DN<66>")
	)
	(segment
		(start 213.32952 -321.82943)
		(end 213.32952 -319.556638)
		(width 0.1651)
		(layer "In5.Cu")
		(net "P5E_PEX1_STN4_RX_DN<66>")
	)
	(segment
		(start 170.909996 -380.308104)
		(end 171.036996 -380.181104)
		(width 0.1651)
		(layer "In5.Cu")
		(net "P5E_PEX1_STN4_RX_DN<66>")
	)
	(segment
		(start 200.931526 -306.696618)
		(end 199.850248 -306.696618)
		(width 0.1651)
		(layer "In5.Cu")
		(net "P5E_PEX1_STN4_RX_DN<66>")
	)
	(segment
		(start 199.77608 -306.742338)
		(end 198.298816 -306.742338)
		(width 0.1143)
		(layer "In5.Cu")
		(net "P5E_PEX1_STN4_RX_DN<66>")
	)
	(segment
		(start 202.764644 -307.455824)
		(end 200.931526 -306.696618)
		(width 0.1651)
		(layer "In5.Cu")
		(net "P5E_PEX1_STN4_RX_DN<66>")
	)
	(segment
		(start 197.288912 -355.211126)
		(end 200.195688 -350.168718)
		(width 0.1651)
		(layer "In5.Cu")
		(net "P5E_PEX1_STN4_RX_DN<66>")
	)
	(segment
		(start 212.53958 -325.778368)
		(end 213.32952 -321.82943)
		(width 0.1651)
		(layer "In5.Cu")
		(net "P5E_PEX1_STN4_RX_DN<66>")
	)
	(segment
		(start 204.261212 -309.532528)
		(end 203.949554 -308.64048)
		(width 0.1651)
		(layer "In5.Cu")
		(net "P5E_PEX1_STN4_RX_DN<66>")
	)
	(segment
		(start 198.284592 -306.349908)
		(end 198.550022 -306.349908)
		(width 0.1143)
		(layer "In5.Cu")
		(net "P5E_PEX1_STN4_RX_DN<66>")
	)
	(segment
		(start 171.036996 -380.181104)
		(end 171.586652 -380.181104)
		(width 0.1651)
		(layer "In5.Cu")
		(net "P5E_PEX1_STN4_RX_DN<66>")
	)
	(segment
		(start 198.298816 -306.742338)
		(end 198.170292 -306.613814)
		(width 0.1143)
		(layer "In5.Cu")
		(net "P5E_PEX1_STN4_RX_DN<66>")
	)
	(segment
		(start 176.456848 -366.777016)
		(end 187.370466 -364.569502)
		(width 0.1651)
		(layer "In5.Cu")
		(net "P5E_PEX1_STN4_RX_DN<66>")
	)
	(segment
		(start 198.170292 -306.613814)
		(end 198.170292 -306.464208)
		(width 0.1143)
		(layer "In5.Cu")
		(net "P5E_PEX1_STN4_RX_DN<66>")
	)
	(segment
		(start 199.8218 -306.696618)
		(end 199.77608 -306.742338)
		(width 0.1143)
		(layer "In5.Cu")
		(net "P5E_PEX1_STN4_RX_DN<66>")
	)
	(segment
		(start 171.96943 -369.574572)
		(end 172.68444 -368.588544)
		(width 0.1651)
		(layer "In5.Cu")
		(net "P5E_PEX1_STN4_RX_DN<66>")
	)
	(segment
		(start 203.949554 -308.64048)
		(end 202.764644 -307.455824)
		(width 0.1651)
		(layer "In5.Cu")
		(net "P5E_PEX1_STN4_RX_DN<66>")
	)
	(segment
		(start 171.586652 -380.181104)
		(end 171.96943 -379.798326)
		(width 0.1651)
		(layer "In5.Cu")
		(net "P5E_PEX1_STN4_RX_DN<66>")
	)
	(segment
		(start 209.780632 -314.33389)
		(end 207.74914 -313.015376)
		(width 0.1651)
		(layer "In5.Cu")
		(net "P5E_PEX1_STN4_RX_DN<66>")
	)
	(segment
		(start 171.96943 -379.798326)
		(end 171.96943 -369.574572)
		(width 0.1651)
		(layer "In5.Cu")
		(net "P5E_PEX1_STN4_RX_DN<66>")
	)
	(segment
		(start 190.27267 -363.068362)
		(end 192.490344 -360.835194)
		(width 0.1651)
		(layer "In5.Cu")
		(net "P5E_PEX1_STN4_RX_DN<66>")
	)
	(segment
		(start 187.370466 -364.569502)
		(end 190.27267 -363.068362)
		(width 0.1651)
		(layer "In5.Cu")
		(net "P5E_PEX1_STN4_RX_DN<66>")
	)
	(segment
		(start 212.168232 -316.77356)
		(end 209.780632 -314.33389)
		(width 0.1651)
		(layer "In5.Cu")
		(net "P5E_PEX1_STN4_RX_DN<66>")
	)
	(segment
		(start 170.909996 -380.69012)
		(end 170.909996 -380.308104)
		(width 0.1651)
		(layer "In5.Cu")
		(net "P5E_PEX1_STN4_RX_DN<66>")
	)
	(segment
		(start 173.82617 -367.729008)
		(end 176.456848 -366.777016)
		(width 0.1651)
		(layer "In5.Cu")
		(net "P5E_PEX1_STN4_RX_DN<66>")
	)
	(segment
		(start 200.195688 -350.168718)
		(end 212.53958 -325.778368)
		(width 0.1651)
		(layer "In5.Cu")
		(net "P5E_PEX1_STN4_RX_DN<66>")
	)
	(segment
		(start 199.850248 -306.696618)
		(end 199.8218 -306.696618)
		(width 0.1143)
		(layer "In5.Cu")
		(net "P5E_PEX1_STN4_RX_DN<66>")
	)
	(segment
		(start 199.12838 -310.529478)
		(end 199.304656 -310.705754)
		(width 0.1143)
		(layer "In5.Cu")
		(net "P5E_PEX1_STN4_RX_DN<70>")
	)
	(segment
		(start 162.236912 -380.181104)
		(end 162.109912 -380.308104)
		(width 0.1651)
		(layer "In5.Cu")
		(net "P5E_PEX1_STN4_RX_DN<70>")
	)
	(segment
		(start 167.711882 -366.032796)
		(end 163.884356 -368.678206)
		(width 0.1651)
		(layer "In5.Cu")
		(net "P5E_PEX1_STN4_RX_DN<70>")
	)
	(segment
		(start 189.185042 -358.317546)
		(end 188.834014 -358.907588)
		(width 0.1651)
		(layer "In5.Cu")
		(net "P5E_PEX1_STN4_RX_DN<70>")
	)
	(segment
		(start 188.834014 -358.907842)
		(end 188.835284 -358.913684)
		(width 0.1651)
		(layer "In5.Cu")
		(net "P5E_PEX1_STN4_RX_DN<70>")
	)
	(segment
		(start 175.419004 -363.042454)
		(end 172.580046 -363.922564)
		(width 0.1651)
		(layer "In5.Cu")
		(net "P5E_PEX1_STN4_RX_DN<70>")
	)
	(segment
		(start 199.39 -310.72582)
		(end 200.667874 -312.003694)
		(width 0.1651)
		(layer "In5.Cu")
		(net "P5E_PEX1_STN4_RX_DN<70>")
	)
	(segment
		(start 198.170292 -310.264048)
		(end 198.170292 -310.415178)
		(width 0.1143)
		(layer "In5.Cu")
		(net "P5E_PEX1_STN4_RX_DN<70>")
	)
	(segment
		(start 163.647374 -368.915442)
		(end 163.169346 -369.711224)
		(width 0.1651)
		(layer "In5.Cu")
		(net "P5E_PEX1_STN4_RX_DN<70>")
	)
	(segment
		(start 198.170292 -310.415178)
		(end 198.284592 -310.529478)
		(width 0.1143)
		(layer "In5.Cu")
		(net "P5E_PEX1_STN4_RX_DN<70>")
	)
	(segment
		(start 198.192644 -325.398892)
		(end 189.185042 -341.980266)
		(width 0.1651)
		(layer "In5.Cu")
		(net "P5E_PEX1_STN4_RX_DN<70>")
	)
	(segment
		(start 163.169346 -369.711224)
		(end 163.169346 -379.798326)
		(width 0.1651)
		(layer "In5.Cu")
		(net "P5E_PEX1_STN4_RX_DN<70>")
	)
	(segment
		(start 163.169346 -379.798326)
		(end 162.786568 -380.181104)
		(width 0.1651)
		(layer "In5.Cu")
		(net "P5E_PEX1_STN4_RX_DN<70>")
	)
	(segment
		(start 199.369934 -310.705754)
		(end 199.39 -310.72582)
		(width 0.1143)
		(layer "In5.Cu")
		(net "P5E_PEX1_STN4_RX_DN<70>")
	)
	(segment
		(start 162.109912 -380.308104)
		(end 162.109912 -380.69012)
		(width 0.1651)
		(layer "In5.Cu")
		(net "P5E_PEX1_STN4_RX_DN<70>")
	)
	(segment
		(start 198.284592 -310.529478)
		(end 199.12838 -310.529478)
		(width 0.1143)
		(layer "In5.Cu")
		(net "P5E_PEX1_STN4_RX_DN<70>")
	)
	(segment
		(start 199.304656 -310.705754)
		(end 199.369934 -310.705754)
		(width 0.1143)
		(layer "In5.Cu")
		(net "P5E_PEX1_STN4_RX_DN<70>")
	)
	(segment
		(start 188.835284 -358.913684)
		(end 187.827158 -359.928922)
		(width 0.1651)
		(layer "In5.Cu")
		(net "P5E_PEX1_STN4_RX_DN<70>")
	)
	(segment
		(start 198.550022 -310.149748)
		(end 198.284592 -310.149748)
		(width 0.1143)
		(layer "In5.Cu")
		(net "P5E_PEX1_STN4_RX_DN<70>")
	)
	(segment
		(start 200.667874 -316.993524)
		(end 199.655684 -319.630044)
		(width 0.1651)
		(layer "In5.Cu")
		(net "P5E_PEX1_STN4_RX_DN<70>")
	)
	(segment
		(start 185.967116 -360.908854)
		(end 175.419004 -363.042454)
		(width 0.1651)
		(layer "In5.Cu")
		(net "P5E_PEX1_STN4_RX_DN<70>")
	)
	(segment
		(start 187.827158 -359.928922)
		(end 185.967116 -360.908854)
		(width 0.1651)
		(layer "In5.Cu")
		(net "P5E_PEX1_STN4_RX_DN<70>")
	)
	(segment
		(start 200.667874 -312.003694)
		(end 200.667874 -316.993524)
		(width 0.1651)
		(layer "In5.Cu")
		(net "P5E_PEX1_STN4_RX_DN<70>")
	)
	(segment
		(start 162.786568 -380.181104)
		(end 162.236912 -380.181104)
		(width 0.1651)
		(layer "In5.Cu")
		(net "P5E_PEX1_STN4_RX_DN<70>")
	)
	(segment
		(start 163.884356 -368.678206)
		(end 163.647374 -368.915442)
		(width 0.1651)
		(layer "In5.Cu")
		(net "P5E_PEX1_STN4_RX_DN<70>")
	)
	(segment
		(start 188.834014 -358.907588)
		(end 188.834014 -358.907842)
		(width 0.1651)
		(layer "In5.Cu")
		(net "P5E_PEX1_STN4_RX_DN<70>")
	)
	(segment
		(start 199.655684 -319.630044)
		(end 198.192644 -325.398892)
		(width 0.1651)
		(layer "In5.Cu")
		(net "P5E_PEX1_STN4_RX_DN<70>")
	)
	(segment
		(start 198.284592 -310.149748)
		(end 198.170292 -310.264048)
		(width 0.1143)
		(layer "In5.Cu")
		(net "P5E_PEX1_STN4_RX_DN<70>")
	)
	(segment
		(start 189.185042 -341.980266)
		(end 189.185042 -358.317546)
		(width 0.1651)
		(layer "In5.Cu")
		(net "P5E_PEX1_STN4_RX_DN<70>")
	)
	(segment
		(start 172.580046 -363.922564)
		(end 167.711882 -366.032796)
		(width 0.1651)
		(layer "In5.Cu")
		(net "P5E_PEX1_STN4_RX_DN<70>")
	)
	(segment
		(start 162.755072 -350.685354)
		(end 163.075112 -350.365314)
		(width 0.13462)
		(layer "F.Cu")
		(net "P5E_PEX1_STN4_TX_C_DN<79>")
	)
	(segment
		(start 162.755072 -351.316798)
		(end 162.755072 -350.685354)
		(width 0.13462)
		(layer "F.Cu")
		(net "P5E_PEX1_STN4_TX_C_DN<79>")
	)
	(segment
		(start 163.049712 -351.611438)
		(end 162.755072 -351.316798)
		(width 0.13462)
		(layer "F.Cu")
		(net "P5E_PEX1_STN4_TX_C_DN<79>")
	)
	(segment
		(start 153.680922 -389.291068)
		(end 151.97582 -385.17576)
		(width 0.1651)
		(layer "In7.Cu")
		(net "P5E_PEX1_STN4_TX_C_DN<79>")
	)
	(segment
		(start 160.969452 -394.956284)
		(end 160.77565 -394.59408)
		(width 0.1651)
		(layer "In7.Cu")
		(net "P5E_PEX1_STN4_TX_C_DN<79>")
	)
	(segment
		(start 161.007806 -358.992678)
		(end 161.204402 -358.796082)
		(width 0.1651)
		(layer "In7.Cu")
		(net "P5E_PEX1_STN4_TX_C_DN<79>")
	)
	(segment
		(start 152.869646 -366.248188)
		(end 154.728926 -363.409738)
		(width 0.1651)
		(layer "In7.Cu")
		(net "P5E_PEX1_STN4_TX_C_DN<79>")
	)
	(segment
		(start 162.758882 -352.68916)
		(end 162.758882 -351.902268)
		(width 0.1651)
		(layer "In7.Cu")
		(net "P5E_PEX1_STN4_TX_C_DN<79>")
	)
	(segment
		(start 160.037272 -397.280892)
		(end 160.386014 -397.280892)
		(width 0.1651)
		(layer "In7.Cu")
		(net "P5E_PEX1_STN4_TX_C_DN<79>")
	)
	(segment
		(start 160.969452 -396.697454)
		(end 160.969452 -394.956284)
		(width 0.1651)
		(layer "In7.Cu")
		(net "P5E_PEX1_STN4_TX_C_DN<79>")
	)
	(segment
		(start 159.910018 -397.790162)
		(end 159.910018 -397.408146)
		(width 0.1651)
		(layer "In7.Cu")
		(net "P5E_PEX1_STN4_TX_C_DN<79>")
	)
	(segment
		(start 161.204402 -358.796082)
		(end 161.204402 -354.24364)
		(width 0.1651)
		(layer "In7.Cu")
		(net "P5E_PEX1_STN4_TX_C_DN<79>")
	)
	(segment
		(start 151.97582 -385.17576)
		(end 151.97582 -368.535712)
		(width 0.1651)
		(layer "In7.Cu")
		(net "P5E_PEX1_STN4_TX_C_DN<79>")
	)
	(segment
		(start 161.204402 -354.24364)
		(end 162.758882 -352.68916)
		(width 0.1651)
		(layer "In7.Cu")
		(net "P5E_PEX1_STN4_TX_C_DN<79>")
	)
	(segment
		(start 154.728926 -363.409738)
		(end 161.007806 -358.992678)
		(width 0.1651)
		(layer "In7.Cu")
		(net "P5E_PEX1_STN4_TX_C_DN<79>")
	)
	(segment
		(start 160.386014 -397.280892)
		(end 160.969452 -396.697454)
		(width 0.1651)
		(layer "In7.Cu")
		(net "P5E_PEX1_STN4_TX_C_DN<79>")
	)
	(segment
		(start 160.77565 -394.59408)
		(end 155.37561 -390.985756)
		(width 0.1651)
		(layer "In7.Cu")
		(net "P5E_PEX1_STN4_TX_C_DN<79>")
	)
	(segment
		(start 162.758882 -351.902268)
		(end 163.049712 -351.611438)
		(width 0.1651)
		(layer "In7.Cu")
		(net "P5E_PEX1_STN4_TX_C_DN<79>")
	)
	(segment
		(start 155.37561 -390.985756)
		(end 153.680922 -389.291068)
		(width 0.1651)
		(layer "In7.Cu")
		(net "P5E_PEX1_STN4_TX_C_DN<79>")
	)
	(segment
		(start 159.910018 -397.408146)
		(end 160.037272 -397.280892)
		(width 0.1651)
		(layer "In7.Cu")
		(net "P5E_PEX1_STN4_TX_C_DN<79>")
	)
	(segment
		(start 151.97582 -368.535712)
		(end 152.869646 -366.248188)
		(width 0.1651)
		(layer "In7.Cu")
		(net "P5E_PEX1_STN4_TX_C_DN<79>")
	)
	(segment
		(start 192.584578 -318.320166)
		(end 192.735708 -318.320166)
		(width 0.1143)
		(layer "In5.Cu")
		(net "P5E_PEX1_STN4_RX_DN<76>")
	)
	(segment
		(start 167.569388 -405.798274)
		(end 167.569388 -395.269212)
		(width 0.1651)
		(layer "In5.Cu")
		(net "P5E_PEX1_STN4_RX_DN<76>")
	)
	(segment
		(start 166.509954 -406.690068)
		(end 166.509954 -406.308052)
		(width 0.1651)
		(layer "In5.Cu")
		(net "P5E_PEX1_STN4_RX_DN<76>")
	)
	(segment
		(start 167.422322 -348.0308)
		(end 168.209722 -347.2434)
		(width 0.1651)
		(layer "In5.Cu")
		(net "P5E_PEX1_STN4_RX_DN<76>")
	)
	(segment
		(start 155.492704 -367.215928)
		(end 157.301438 -365.408464)
		(width 0.1651)
		(layer "In5.Cu")
		(net "P5E_PEX1_STN4_RX_DN<76>")
	)
	(segment
		(start 166.509954 -406.308052)
		(end 166.636954 -406.181052)
		(width 0.1651)
		(layer "In5.Cu")
		(net "P5E_PEX1_STN4_RX_DN<76>")
	)
	(segment
		(start 161.179256 -362.609638)
		(end 166.047674 -360.468926)
		(width 0.1651)
		(layer "In5.Cu")
		(net "P5E_PEX1_STN4_RX_DN<76>")
	)
	(segment
		(start 166.047674 -360.468926)
		(end 167.422322 -359.094278)
		(width 0.1651)
		(layer "In5.Cu")
		(net "P5E_PEX1_STN4_RX_DN<76>")
	)
	(segment
		(start 154.84094 -369.257834)
		(end 155.492704 -367.215928)
		(width 0.1651)
		(layer "In5.Cu")
		(net "P5E_PEX1_STN4_RX_DN<76>")
	)
	(segment
		(start 170.1292 -347.2434)
		(end 170.531282 -346.841318)
		(width 0.1651)
		(layer "In5.Cu")
		(net "P5E_PEX1_STN4_RX_DN<76>")
	)
	(segment
		(start 167.569388 -395.269212)
		(end 165.807644 -393.507468)
		(width 0.1651)
		(layer "In5.Cu")
		(net "P5E_PEX1_STN4_RX_DN<76>")
	)
	(segment
		(start 170.531282 -341.907876)
		(end 170.862498 -341.531194)
		(width 0.1651)
		(layer "In5.Cu")
		(net "P5E_PEX1_STN4_RX_DN<76>")
	)
	(segment
		(start 192.470278 -320.04508)
		(end 192.470278 -318.434466)
		(width 0.1143)
		(layer "In5.Cu")
		(net "P5E_PEX1_STN4_RX_DN<76>")
	)
	(segment
		(start 170.531282 -346.841318)
		(end 170.531282 -341.907876)
		(width 0.1651)
		(layer "In5.Cu")
		(net "P5E_PEX1_STN4_RX_DN<76>")
	)
	(segment
		(start 191.755776 -323.726302)
		(end 192.51549 -321.364102)
		(width 0.1651)
		(layer "In5.Cu")
		(net "P5E_PEX1_STN4_RX_DN<76>")
	)
	(segment
		(start 166.636954 -406.181052)
		(end 167.18661 -406.181052)
		(width 0.1651)
		(layer "In5.Cu")
		(net "P5E_PEX1_STN4_RX_DN<76>")
	)
	(segment
		(start 167.18661 -406.181052)
		(end 167.569388 -405.798274)
		(width 0.1651)
		(layer "In5.Cu")
		(net "P5E_PEX1_STN4_RX_DN<76>")
	)
	(segment
		(start 164.427154 -392.584686)
		(end 157.436312 -388.86765)
		(width 0.1651)
		(layer "In5.Cu")
		(net "P5E_PEX1_STN4_RX_DN<76>")
	)
	(segment
		(start 170.862498 -341.531194)
		(end 181.558692 -334.408526)
		(width 0.1651)
		(layer "In5.Cu")
		(net "P5E_PEX1_STN4_RX_DN<76>")
	)
	(segment
		(start 168.209722 -347.2434)
		(end 170.1292 -347.2434)
		(width 0.1651)
		(layer "In5.Cu")
		(net "P5E_PEX1_STN4_RX_DN<76>")
	)
	(segment
		(start 192.735708 -318.320166)
		(end 192.850008 -318.434466)
		(width 0.1143)
		(layer "In5.Cu")
		(net "P5E_PEX1_STN4_RX_DN<76>")
	)
	(segment
		(start 181.558692 -334.408526)
		(end 189.710568 -326.577198)
		(width 0.1651)
		(layer "In5.Cu")
		(net "P5E_PEX1_STN4_RX_DN<76>")
	)
	(segment
		(start 157.436312 -388.86765)
		(end 156.02204 -387.453632)
		(width 0.1651)
		(layer "In5.Cu")
		(net "P5E_PEX1_STN4_RX_DN<76>")
	)
	(segment
		(start 189.710568 -326.577198)
		(end 191.755776 -323.726302)
		(width 0.1651)
		(layer "In5.Cu")
		(net "P5E_PEX1_STN4_RX_DN<76>")
	)
	(segment
		(start 192.51549 -321.364102)
		(end 192.515998 -321.363594)
		(width 0.1651)
		(layer "In5.Cu")
		(net "P5E_PEX1_STN4_RX_DN<76>")
	)
	(segment
		(start 156.02204 -387.453632)
		(end 154.84094 -384.602228)
		(width 0.1651)
		(layer "In5.Cu")
		(net "P5E_PEX1_STN4_RX_DN<76>")
	)
	(segment
		(start 154.84094 -384.602228)
		(end 154.84094 -369.257834)
		(width 0.1651)
		(layer "In5.Cu")
		(net "P5E_PEX1_STN4_RX_DN<76>")
	)
	(segment
		(start 192.850008 -318.434466)
		(end 192.850008 -318.699896)
		(width 0.1143)
		(layer "In5.Cu")
		(net "P5E_PEX1_STN4_RX_DN<76>")
	)
	(segment
		(start 167.422322 -359.094278)
		(end 167.422322 -348.0308)
		(width 0.1651)
		(layer "In5.Cu")
		(net "P5E_PEX1_STN4_RX_DN<76>")
	)
	(segment
		(start 192.515998 -320.0908)
		(end 192.470278 -320.04508)
		(width 0.1143)
		(layer "In5.Cu")
		(net "P5E_PEX1_STN4_RX_DN<76>")
	)
	(segment
		(start 157.301438 -365.408464)
		(end 161.179256 -362.609638)
		(width 0.1651)
		(layer "In5.Cu")
		(net "P5E_PEX1_STN4_RX_DN<76>")
	)
	(segment
		(start 192.515998 -321.363594)
		(end 192.515998 -320.119248)
		(width 0.1651)
		(layer "In5.Cu")
		(net "P5E_PEX1_STN4_RX_DN<76>")
	)
	(segment
		(start 192.515998 -320.119248)
		(end 192.515998 -320.0908)
		(width 0.1143)
		(layer "In5.Cu")
		(net "P5E_PEX1_STN4_RX_DN<76>")
	)
	(segment
		(start 165.807644 -393.507468)
		(end 164.427154 -392.584686)
		(width 0.1651)
		(layer "In5.Cu")
		(net "P5E_PEX1_STN4_RX_DN<76>")
	)
	(segment
		(start 192.470278 -318.434466)
		(end 192.584578 -318.320166)
		(width 0.1143)
		(layer "In5.Cu")
		(net "P5E_PEX1_STN4_RX_DN<76>")
	)
	(segment
		(start 198.216012 -319.1764)
		(end 198.170292 -319.13068)
		(width 0.1143)
		(layer "In5.Cu")
		(net "P5E_PEX1_STN4_RX_DN<71>")
	)
	(segment
		(start 190.906908 -335.200752)
		(end 196.975476 -325.283576)
		(width 0.1651)
		(layer "In5.Cu")
		(net "P5E_PEX1_STN4_RX_DN<71>")
	)
	(segment
		(start 172.256704 -363.021372)
		(end 175.476916 -362.023152)
		(width 0.1651)
		(layer "In5.Cu")
		(net "P5E_PEX1_STN4_RX_DN<71>")
	)
	(segment
		(start 186.076082 -358.949498)
		(end 186.076082 -342.13292)
		(width 0.1651)
		(layer "In5.Cu")
		(net "P5E_PEX1_STN4_RX_DN<71>")
	)
	(segment
		(start 186.354212 -341.005922)
		(end 190.906908 -335.200752)
		(width 0.1651)
		(layer "In5.Cu")
		(net "P5E_PEX1_STN4_RX_DN<71>")
	)
	(segment
		(start 186.076082 -342.13292)
		(end 186.354212 -341.005922)
		(width 0.1651)
		(layer "In5.Cu")
		(net "P5E_PEX1_STN4_RX_DN<71>")
	)
	(segment
		(start 160.586674 -379.08103)
		(end 160.969452 -378.698252)
		(width 0.1651)
		(layer "In5.Cu")
		(net "P5E_PEX1_STN4_RX_DN<71>")
	)
	(segment
		(start 161.874708 -368.422428)
		(end 165.425882 -365.981742)
		(width 0.1651)
		(layer "In5.Cu")
		(net "P5E_PEX1_STN4_RX_DN<71>")
	)
	(segment
		(start 165.425882 -365.981742)
		(end 172.256704 -363.021372)
		(width 0.1651)
		(layer "In5.Cu")
		(net "P5E_PEX1_STN4_RX_DN<71>")
	)
	(segment
		(start 184.91073 -360.11485)
		(end 186.076082 -358.949498)
		(width 0.1651)
		(layer "In5.Cu")
		(net "P5E_PEX1_STN4_RX_DN<71>")
	)
	(segment
		(start 198.216012 -320.880232)
		(end 198.216012 -319.204848)
		(width 0.1651)
		(layer "In5.Cu")
		(net "P5E_PEX1_STN4_RX_DN<71>")
	)
	(segment
		(start 159.910018 -379.590046)
		(end 159.910018 -379.20803)
		(width 0.1651)
		(layer "In5.Cu")
		(net "P5E_PEX1_STN4_RX_DN<71>")
	)
	(segment
		(start 160.037018 -379.08103)
		(end 160.586674 -379.08103)
		(width 0.1651)
		(layer "In5.Cu")
		(net "P5E_PEX1_STN4_RX_DN<71>")
	)
	(segment
		(start 175.476916 -362.023152)
		(end 184.91073 -360.11485)
		(width 0.1651)
		(layer "In5.Cu")
		(net "P5E_PEX1_STN4_RX_DN<71>")
	)
	(segment
		(start 160.969452 -369.561872)
		(end 161.542222 -368.754914)
		(width 0.1651)
		(layer "In5.Cu")
		(net "P5E_PEX1_STN4_RX_DN<71>")
	)
	(segment
		(start 196.975476 -325.283576)
		(end 198.216012 -320.880232)
		(width 0.1651)
		(layer "In5.Cu")
		(net "P5E_PEX1_STN4_RX_DN<71>")
	)
	(segment
		(start 198.216012 -319.204848)
		(end 198.216012 -319.1764)
		(width 0.1143)
		(layer "In5.Cu")
		(net "P5E_PEX1_STN4_RX_DN<71>")
	)
	(segment
		(start 198.284592 -316.799722)
		(end 198.550022 -316.799722)
		(width 0.1143)
		(layer "In5.Cu")
		(net "P5E_PEX1_STN4_RX_DN<71>")
	)
	(segment
		(start 198.170292 -316.914022)
		(end 198.284592 -316.799722)
		(width 0.1143)
		(layer "In5.Cu")
		(net "P5E_PEX1_STN4_RX_DN<71>")
	)
	(segment
		(start 198.170292 -319.13068)
		(end 198.170292 -316.914022)
		(width 0.1143)
		(layer "In5.Cu")
		(net "P5E_PEX1_STN4_RX_DN<71>")
	)
	(segment
		(start 159.910018 -379.20803)
		(end 160.037018 -379.08103)
		(width 0.1651)
		(layer "In5.Cu")
		(net "P5E_PEX1_STN4_RX_DN<71>")
	)
	(segment
		(start 161.542222 -368.754914)
		(end 161.874708 -368.422428)
		(width 0.1651)
		(layer "In5.Cu")
		(net "P5E_PEX1_STN4_RX_DN<71>")
	)
	(segment
		(start 160.969452 -378.698252)
		(end 160.969452 -369.561872)
		(width 0.1651)
		(layer "In5.Cu")
		(net "P5E_PEX1_STN4_RX_DN<71>")
	)
	(segment
		(start 162.480752 -350.685354)
		(end 162.160712 -350.365314)
		(width 0.13462)
		(layer "F.Cu")
		(net "P5E_PEX1_STN4_TX_C_DP<79>")
	)
	(segment
		(start 162.480752 -351.316798)
		(end 162.480752 -350.685354)
		(width 0.13462)
		(layer "F.Cu")
		(net "P5E_PEX1_STN4_TX_C_DP<79>")
	)
	(segment
		(start 162.186112 -351.611438)
		(end 162.480752 -351.316798)
		(width 0.13462)
		(layer "F.Cu")
		(net "P5E_PEX1_STN4_TX_C_DP<79>")
	)
	(segment
		(start 152.617678 -366.11814)
		(end 154.522424 -363.210094)
		(width 0.1651)
		(layer "In7.Cu")
		(net "P5E_PEX1_STN4_TX_C_DP<79>")
	)
	(segment
		(start 160.037018 -396.998952)
		(end 160.269174 -396.998952)
		(width 0.1651)
		(layer "In7.Cu")
		(net "P5E_PEX1_STN4_TX_C_DP<79>")
	)
	(segment
		(start 155.195778 -391.204704)
		(end 153.441908 -389.450834)
		(width 0.1651)
		(layer "In7.Cu")
		(net "P5E_PEX1_STN4_TX_C_DP<79>")
	)
	(segment
		(start 160.269174 -396.998952)
		(end 160.687512 -396.580614)
		(width 0.1651)
		(layer "In7.Cu")
		(net "P5E_PEX1_STN4_TX_C_DP<79>")
	)
	(segment
		(start 159.910018 -396.871952)
		(end 160.037018 -396.998952)
		(width 0.1651)
		(layer "In7.Cu")
		(net "P5E_PEX1_STN4_TX_C_DP<79>")
	)
	(segment
		(start 162.476942 -351.902268)
		(end 162.186112 -351.611438)
		(width 0.1651)
		(layer "In7.Cu")
		(net "P5E_PEX1_STN4_TX_C_DP<79>")
	)
	(segment
		(start 160.922462 -358.679242)
		(end 160.922462 -354.1268)
		(width 0.1651)
		(layer "In7.Cu")
		(net "P5E_PEX1_STN4_TX_C_DP<79>")
	)
	(segment
		(start 159.910018 -396.49019)
		(end 159.910018 -396.871952)
		(width 0.1651)
		(layer "In7.Cu")
		(net "P5E_PEX1_STN4_TX_C_DP<79>")
	)
	(segment
		(start 151.69388 -368.482372)
		(end 152.617678 -366.11814)
		(width 0.1651)
		(layer "In7.Cu")
		(net "P5E_PEX1_STN4_TX_C_DP<79>")
	)
	(segment
		(start 157.70225 -392.986514)
		(end 157.290008 -392.710924)
		(width 0.1651)
		(layer "In7.Cu")
		(net "P5E_PEX1_STN4_TX_C_DP<79>")
	)
	(segment
		(start 157.82544 -392.961876)
		(end 157.70225 -392.986514)
		(width 0.1651)
		(layer "In7.Cu")
		(net "P5E_PEX1_STN4_TX_C_DP<79>")
	)
	(segment
		(start 151.69388 -385.231894)
		(end 151.69388 -368.482372)
		(width 0.1651)
		(layer "In7.Cu")
		(net "P5E_PEX1_STN4_TX_C_DP<79>")
	)
	(segment
		(start 157.290008 -392.710924)
		(end 157.265624 -392.587734)
		(width 0.1651)
		(layer "In7.Cu")
		(net "P5E_PEX1_STN4_TX_C_DP<79>")
	)
	(segment
		(start 160.687512 -396.580614)
		(end 160.687512 -395.02715)
		(width 0.1651)
		(layer "In7.Cu")
		(net "P5E_PEX1_STN4_TX_C_DP<79>")
	)
	(segment
		(start 156.730446 -392.33729)
		(end 156.318458 -392.0617)
		(width 0.1651)
		(layer "In7.Cu")
		(net "P5E_PEX1_STN4_TX_C_DP<79>")
	)
	(segment
		(start 160.922462 -354.1268)
		(end 162.476942 -352.57232)
		(width 0.1651)
		(layer "In7.Cu")
		(net "P5E_PEX1_STN4_TX_C_DP<79>")
	)
	(segment
		(start 162.476942 -352.57232)
		(end 162.476942 -351.902268)
		(width 0.1651)
		(layer "In7.Cu")
		(net "P5E_PEX1_STN4_TX_C_DP<79>")
	)
	(segment
		(start 160.825688 -358.776016)
		(end 160.922462 -358.679242)
		(width 0.1651)
		(layer "In7.Cu")
		(net "P5E_PEX1_STN4_TX_C_DP<79>")
	)
	(segment
		(start 160.687512 -395.02715)
		(end 160.560258 -394.789406)
		(width 0.1651)
		(layer "In7.Cu")
		(net "P5E_PEX1_STN4_TX_C_DP<79>")
	)
	(segment
		(start 157.265624 -392.587734)
		(end 156.85389 -392.312652)
		(width 0.1651)
		(layer "In7.Cu")
		(net "P5E_PEX1_STN4_TX_C_DP<79>")
	)
	(segment
		(start 154.522424 -363.210094)
		(end 160.825688 -358.776016)
		(width 0.1651)
		(layer "In7.Cu")
		(net "P5E_PEX1_STN4_TX_C_DP<79>")
	)
	(segment
		(start 156.85389 -392.312652)
		(end 156.730446 -392.33729)
		(width 0.1651)
		(layer "In7.Cu")
		(net "P5E_PEX1_STN4_TX_C_DP<79>")
	)
	(segment
		(start 156.29382 -391.93851)
		(end 155.195778 -391.204704)
		(width 0.1651)
		(layer "In7.Cu")
		(net "P5E_PEX1_STN4_TX_C_DP<79>")
	)
	(segment
		(start 160.560258 -394.789406)
		(end 157.82544 -392.961876)
		(width 0.1651)
		(layer "In7.Cu")
		(net "P5E_PEX1_STN4_TX_C_DP<79>")
	)
	(segment
		(start 153.441908 -389.450834)
		(end 151.69388 -385.231894)
		(width 0.1651)
		(layer "In7.Cu")
		(net "P5E_PEX1_STN4_TX_C_DP<79>")
	)
	(segment
		(start 156.318458 -392.0617)
		(end 156.29382 -391.93851)
		(width 0.1651)
		(layer "In7.Cu")
		(net "P5E_PEX1_STN4_TX_C_DP<79>")
	)
	(segment
		(start 190.570358 -318.434466)
		(end 190.684658 -318.320166)
		(width 0.1143)
		(layer "In5.Cu")
		(net "P5E_PEX1_STN4_RX_DN<78>")
	)
	(segment
		(start 181.647338 -331.111352)
		(end 184.550812 -328.686922)
		(width 0.1651)
		(layer "In5.Cu")
		(net "P5E_PEX1_STN4_RX_DN<78>")
	)
	(segment
		(start 157.4292 -355.822504)
		(end 164.38753 -341.95385)
		(width 0.1651)
		(layer "In5.Cu")
		(net "P5E_PEX1_STN4_RX_DN<78>")
	)
	(segment
		(start 190.616078 -320.119248)
		(end 190.616078 -320.0908)
		(width 0.1143)
		(layer "In5.Cu")
		(net "P5E_PEX1_STN4_RX_DN<78>")
	)
	(segment
		(start 190.950088 -318.434466)
		(end 190.950088 -318.699896)
		(width 0.1143)
		(layer "In5.Cu")
		(net "P5E_PEX1_STN4_RX_DN<78>")
	)
	(segment
		(start 190.616078 -320.0908)
		(end 190.570358 -320.04508)
		(width 0.1143)
		(layer "In5.Cu")
		(net "P5E_PEX1_STN4_RX_DN<78>")
	)
	(segment
		(start 184.550812 -328.686922)
		(end 185.305192 -328.020426)
		(width 0.1651)
		(layer "In5.Cu")
		(net "P5E_PEX1_STN4_RX_DN<78>")
	)
	(segment
		(start 152.93086 -384.98272)
		(end 152.93086 -367.691162)
		(width 0.1651)
		(layer "In5.Cu")
		(net "P5E_PEX1_STN4_RX_DN<78>")
	)
	(segment
		(start 190.616078 -320.993008)
		(end 190.616078 -320.119248)
		(width 0.1651)
		(layer "In5.Cu")
		(net "P5E_PEX1_STN4_RX_DN<78>")
	)
	(segment
		(start 185.305192 -328.020426)
		(end 190.022226 -322.583302)
		(width 0.1651)
		(layer "In5.Cu")
		(net "P5E_PEX1_STN4_RX_DN<78>")
	)
	(segment
		(start 190.684658 -318.320166)
		(end 190.835788 -318.320166)
		(width 0.1143)
		(layer "In5.Cu")
		(net "P5E_PEX1_STN4_RX_DN<78>")
	)
	(segment
		(start 162.109912 -406.308052)
		(end 162.236912 -406.181052)
		(width 0.1651)
		(layer "In5.Cu")
		(net "P5E_PEX1_STN4_RX_DN<78>")
	)
	(segment
		(start 161.85007 -394.132562)
		(end 156.275786 -390.409176)
		(width 0.1651)
		(layer "In5.Cu")
		(net "P5E_PEX1_STN4_RX_DN<78>")
	)
	(segment
		(start 163.169346 -395.452346)
		(end 161.85007 -394.132562)
		(width 0.1651)
		(layer "In5.Cu")
		(net "P5E_PEX1_STN4_RX_DN<78>")
	)
	(segment
		(start 190.570358 -320.04508)
		(end 190.570358 -318.434466)
		(width 0.1143)
		(layer "In5.Cu")
		(net "P5E_PEX1_STN4_RX_DN<78>")
	)
	(segment
		(start 162.109912 -406.690068)
		(end 162.109912 -406.308052)
		(width 0.1651)
		(layer "In5.Cu")
		(net "P5E_PEX1_STN4_RX_DN<78>")
	)
	(segment
		(start 190.022226 -322.583302)
		(end 190.616078 -320.993008)
		(width 0.1651)
		(layer "In5.Cu")
		(net "P5E_PEX1_STN4_RX_DN<78>")
	)
	(segment
		(start 164.809932 -341.467948)
		(end 181.647338 -331.111352)
		(width 0.1651)
		(layer "In5.Cu")
		(net "P5E_PEX1_STN4_RX_DN<78>")
	)
	(segment
		(start 162.236912 -406.181052)
		(end 162.786568 -406.181052)
		(width 0.1651)
		(layer "In5.Cu")
		(net "P5E_PEX1_STN4_RX_DN<78>")
	)
	(segment
		(start 163.169346 -405.798274)
		(end 163.169346 -395.452346)
		(width 0.1651)
		(layer "In5.Cu")
		(net "P5E_PEX1_STN4_RX_DN<78>")
	)
	(segment
		(start 154.401774 -388.535164)
		(end 152.93086 -384.98272)
		(width 0.1651)
		(layer "In5.Cu")
		(net "P5E_PEX1_STN4_RX_DN<78>")
	)
	(segment
		(start 156.275786 -390.409176)
		(end 154.401774 -388.535164)
		(width 0.1651)
		(layer "In5.Cu")
		(net "P5E_PEX1_STN4_RX_DN<78>")
	)
	(segment
		(start 164.38753 -341.95385)
		(end 164.809932 -341.467948)
		(width 0.1651)
		(layer "In5.Cu")
		(net "P5E_PEX1_STN4_RX_DN<78>")
	)
	(segment
		(start 152.93086 -367.691162)
		(end 157.4292 -355.822504)
		(width 0.1651)
		(layer "In5.Cu")
		(net "P5E_PEX1_STN4_RX_DN<78>")
	)
	(segment
		(start 190.835788 -318.320166)
		(end 190.950088 -318.434466)
		(width 0.1143)
		(layer "In5.Cu")
		(net "P5E_PEX1_STN4_RX_DN<78>")
	)
	(segment
		(start 162.786568 -406.181052)
		(end 163.169346 -405.798274)
		(width 0.1651)
		(layer "In5.Cu")
		(net "P5E_PEX1_STN4_RX_DN<78>")
	)
	(segment
		(start 187.626752 -350.685354)
		(end 187.946792 -350.365314)
		(width 0.13462)
		(layer "F.Cu")
		(net "P5E_PEX1_STN4_TX_C_DN<67>")
	)
	(segment
		(start 187.626752 -351.316798)
		(end 187.626752 -350.685354)
		(width 0.13462)
		(layer "F.Cu")
		(net "P5E_PEX1_STN4_TX_C_DN<67>")
	)
	(segment
		(start 187.921392 -351.611438)
		(end 187.626752 -351.316798)
		(width 0.13462)
		(layer "F.Cu")
		(net "P5E_PEX1_STN4_TX_C_DN<67>")
	)
	(segment
		(start 187.630562 -351.902268)
		(end 187.921392 -351.611438)
		(width 0.1651)
		(layer "In7.Cu")
		(net "P5E_PEX1_STN4_TX_C_DN<67>")
	)
	(segment
		(start 168.710102 -371.790214)
		(end 168.710102 -371.408198)
		(width 0.1651)
		(layer "In7.Cu")
		(net "P5E_PEX1_STN4_TX_C_DN<67>")
	)
	(segment
		(start 171.036488 -367.891314)
		(end 181.362858 -363.733334)
		(width 0.1651)
		(layer "In7.Cu")
		(net "P5E_PEX1_STN4_TX_C_DN<67>")
	)
	(segment
		(start 169.186098 -371.280944)
		(end 169.769536 -370.697506)
		(width 0.1651)
		(layer "In7.Cu")
		(net "P5E_PEX1_STN4_TX_C_DN<67>")
	)
	(segment
		(start 168.710102 -371.408198)
		(end 168.837356 -371.280944)
		(width 0.1651)
		(layer "In7.Cu")
		(net "P5E_PEX1_STN4_TX_C_DN<67>")
	)
	(segment
		(start 187.630562 -352.543618)
		(end 187.630562 -351.902268)
		(width 0.1651)
		(layer "In7.Cu")
		(net "P5E_PEX1_STN4_TX_C_DN<67>")
	)
	(segment
		(start 169.769536 -369.119912)
		(end 171.036488 -367.891314)
		(width 0.1651)
		(layer "In7.Cu")
		(net "P5E_PEX1_STN4_TX_C_DN<67>")
	)
	(segment
		(start 186.076082 -359.268268)
		(end 186.076082 -354.098098)
		(width 0.1651)
		(layer "In7.Cu")
		(net "P5E_PEX1_STN4_TX_C_DN<67>")
	)
	(segment
		(start 181.362858 -363.733334)
		(end 186.076082 -359.268268)
		(width 0.1651)
		(layer "In7.Cu")
		(net "P5E_PEX1_STN4_TX_C_DN<67>")
	)
	(segment
		(start 186.076082 -354.098098)
		(end 187.630562 -352.543618)
		(width 0.1651)
		(layer "In7.Cu")
		(net "P5E_PEX1_STN4_TX_C_DN<67>")
	)
	(segment
		(start 169.769536 -370.697506)
		(end 169.769536 -369.119912)
		(width 0.1651)
		(layer "In7.Cu")
		(net "P5E_PEX1_STN4_TX_C_DN<67>")
	)
	(segment
		(start 168.837356 -371.280944)
		(end 169.186098 -371.280944)
		(width 0.1651)
		(layer "In7.Cu")
		(net "P5E_PEX1_STN4_TX_C_DN<67>")
	)
	(segment
		(start 193.21145 -333.977488)
		(end 193.211196 -333.977488)
		(width 0.1651)
		(layer "In5.Cu")
		(net "P5E_PEX1_STN4_RX_DP<70>")
	)
	(segment
		(start 195.267072 -330.193904)
		(end 195.112132 -330.239624)
		(width 0.1651)
		(layer "In5.Cu")
		(net "P5E_PEX1_STN4_RX_DP<70>")
	)
	(segment
		(start 194.875404 -330.675234)
		(end 194.921124 -330.830174)
		(width 0.1651)
		(layer "In5.Cu")
		(net "P5E_PEX1_STN4_RX_DP<70>")
	)
	(segment
		(start 197.865492 -310.149748)
		(end 197.979792 -310.264048)
		(width 0.1143)
		(layer "In5.Cu")
		(net "P5E_PEX1_STN4_RX_DP<70>")
	)
	(segment
		(start 162.109912 -379.772164)
		(end 162.109912 -379.390148)
		(width 0.1651)
		(layer "In5.Cu")
		(net "P5E_PEX1_STN4_RX_DP<70>")
	)
	(segment
		(start 188.591444 -358.76357)
		(end 188.585348 -358.765094)
		(width 0.1651)
		(layer "In5.Cu")
		(net "P5E_PEX1_STN4_RX_DP<70>")
	)
	(segment
		(start 188.903102 -341.908384)
		(end 188.903102 -358.23906)
		(width 0.1651)
		(layer "In5.Cu")
		(net "P5E_PEX1_STN4_RX_DP<70>")
	)
	(segment
		(start 195.266818 -330.193904)
		(end 195.267072 -330.193904)
		(width 0.1651)
		(layer "In5.Cu")
		(net "P5E_PEX1_STN4_RX_DP<70>")
	)
	(segment
		(start 172.482002 -363.657642)
		(end 167.574214 -365.784892)
		(width 0.1651)
		(layer "In5.Cu")
		(net "P5E_PEX1_STN4_RX_DP<70>")
	)
	(segment
		(start 163.703 -368.460782)
		(end 163.423346 -368.740436)
		(width 0.1651)
		(layer "In5.Cu")
		(net "P5E_PEX1_STN4_RX_DP<70>")
	)
	(segment
		(start 187.657486 -359.69956)
		(end 185.871358 -360.640376)
		(width 0.1651)
		(layer "In5.Cu")
		(net "P5E_PEX1_STN4_RX_DP<70>")
	)
	(segment
		(start 167.574214 -365.784892)
		(end 163.703 -368.460782)
		(width 0.1651)
		(layer "In5.Cu")
		(net "P5E_PEX1_STN4_RX_DP<70>")
	)
	(segment
		(start 194.310508 -331.741526)
		(end 194.351148 -331.879194)
		(width 0.1651)
		(layer "In5.Cu")
		(net "P5E_PEX1_STN4_RX_DP<70>")
	)
	(segment
		(start 200.385934 -312.120534)
		(end 200.385934 -316.9412)
		(width 0.1651)
		(layer "In5.Cu")
		(net "P5E_PEX1_STN4_RX_DP<70>")
	)
	(segment
		(start 197.600062 -310.149748)
		(end 197.865492 -310.149748)
		(width 0.1143)
		(layer "In5.Cu")
		(net "P5E_PEX1_STN4_RX_DP<70>")
	)
	(segment
		(start 193.545206 -333.363316)
		(end 193.407538 -333.40421)
		(width 0.1651)
		(layer "In5.Cu")
		(net "P5E_PEX1_STN4_RX_DP<70>")
	)
	(segment
		(start 197.979792 -310.264048)
		(end 197.979792 -310.494172)
		(width 0.1143)
		(layer "In5.Cu")
		(net "P5E_PEX1_STN4_RX_DP<70>")
	)
	(segment
		(start 190.274194 -339.38464)
		(end 190.119 -339.43036)
		(width 0.1651)
		(layer "In5.Cu")
		(net "P5E_PEX1_STN4_RX_DP<70>")
	)
	(segment
		(start 198.205598 -310.719978)
		(end 199.049386 -310.719978)
		(width 0.1143)
		(layer "In5.Cu")
		(net "P5E_PEX1_STN4_RX_DP<70>")
	)
	(segment
		(start 197.927976 -325.29526)
		(end 195.266818 -330.193904)
		(width 0.1651)
		(layer "In5.Cu")
		(net "P5E_PEX1_STN4_RX_DP<70>")
	)
	(segment
		(start 162.669728 -379.899164)
		(end 162.236912 -379.899164)
		(width 0.1651)
		(layer "In5.Cu")
		(net "P5E_PEX1_STN4_RX_DP<70>")
	)
	(segment
		(start 194.547236 -331.305916)
		(end 194.310508 -331.741526)
		(width 0.1651)
		(layer "In5.Cu")
		(net "P5E_PEX1_STN4_RX_DP<70>")
	)
	(segment
		(start 199.386444 -319.544446)
		(end 197.927976 -325.29526)
		(width 0.1651)
		(layer "In5.Cu")
		(net "P5E_PEX1_STN4_RX_DP<70>")
	)
	(segment
		(start 193.740786 -332.790546)
		(end 193.781426 -332.928214)
		(width 0.1651)
		(layer "In5.Cu")
		(net "P5E_PEX1_STN4_RX_DP<70>")
	)
	(segment
		(start 200.385934 -316.9412)
		(end 199.386444 -319.544446)
		(width 0.1651)
		(layer "In5.Cu")
		(net "P5E_PEX1_STN4_RX_DP<70>")
	)
	(segment
		(start 194.115182 -332.314296)
		(end 193.977514 -332.354936)
		(width 0.1651)
		(layer "In5.Cu")
		(net "P5E_PEX1_STN4_RX_DP<70>")
	)
	(segment
		(start 199.19061 -310.92521)
		(end 200.385934 -312.120534)
		(width 0.1651)
		(layer "In5.Cu")
		(net "P5E_PEX1_STN4_RX_DP<70>")
	)
	(segment
		(start 194.114928 -332.314296)
		(end 194.115182 -332.314296)
		(width 0.1651)
		(layer "In5.Cu")
		(net "P5E_PEX1_STN4_RX_DP<70>")
	)
	(segment
		(start 195.112132 -330.239624)
		(end 194.875404 -330.675234)
		(width 0.1651)
		(layer "In5.Cu")
		(net "P5E_PEX1_STN4_RX_DP<70>")
	)
	(segment
		(start 189.882526 -339.86597)
		(end 189.928246 -340.02091)
		(width 0.1651)
		(layer "In5.Cu")
		(net "P5E_PEX1_STN4_RX_DP<70>")
	)
	(segment
		(start 199.170544 -310.841136)
		(end 199.170544 -310.905144)
		(width 0.1143)
		(layer "In5.Cu")
		(net "P5E_PEX1_STN4_RX_DP<70>")
	)
	(segment
		(start 193.407538 -333.40421)
		(end 193.17081 -333.839566)
		(width 0.1651)
		(layer "In5.Cu")
		(net "P5E_PEX1_STN4_RX_DP<70>")
	)
	(segment
		(start 163.423346 -368.740436)
		(end 162.887406 -369.632992)
		(width 0.1651)
		(layer "In5.Cu")
		(net "P5E_PEX1_STN4_RX_DP<70>")
	)
	(segment
		(start 194.684904 -331.265276)
		(end 194.547236 -331.305916)
		(width 0.1651)
		(layer "In5.Cu")
		(net "P5E_PEX1_STN4_RX_DP<70>")
	)
	(segment
		(start 199.049386 -310.719978)
		(end 199.170544 -310.841136)
		(width 0.1143)
		(layer "In5.Cu")
		(net "P5E_PEX1_STN4_RX_DP<70>")
	)
	(segment
		(start 193.977514 -332.354936)
		(end 193.740786 -332.790546)
		(width 0.1651)
		(layer "In5.Cu")
		(net "P5E_PEX1_STN4_RX_DP<70>")
	)
	(segment
		(start 188.585348 -358.765094)
		(end 187.657486 -359.69956)
		(width 0.1651)
		(layer "In5.Cu")
		(net "P5E_PEX1_STN4_RX_DP<70>")
	)
	(segment
		(start 194.921124 -330.830174)
		(end 194.684904 -331.265276)
		(width 0.1651)
		(layer "In5.Cu")
		(net "P5E_PEX1_STN4_RX_DP<70>")
	)
	(segment
		(start 189.928246 -340.02091)
		(end 188.903102 -341.908384)
		(width 0.1651)
		(layer "In5.Cu")
		(net "P5E_PEX1_STN4_RX_DP<70>")
	)
	(segment
		(start 194.351148 -331.879194)
		(end 194.114928 -332.314296)
		(width 0.1651)
		(layer "In5.Cu")
		(net "P5E_PEX1_STN4_RX_DP<70>")
	)
	(segment
		(start 162.887406 -369.632992)
		(end 162.887406 -379.681486)
		(width 0.1651)
		(layer "In5.Cu")
		(net "P5E_PEX1_STN4_RX_DP<70>")
	)
	(segment
		(start 162.887406 -379.681486)
		(end 162.669728 -379.899164)
		(width 0.1651)
		(layer "In5.Cu")
		(net "P5E_PEX1_STN4_RX_DP<70>")
	)
	(segment
		(start 185.871358 -360.640376)
		(end 175.349154 -362.768896)
		(width 0.1651)
		(layer "In5.Cu")
		(net "P5E_PEX1_STN4_RX_DP<70>")
	)
	(segment
		(start 199.170544 -310.905144)
		(end 199.19061 -310.92521)
		(width 0.1143)
		(layer "In5.Cu")
		(net "P5E_PEX1_STN4_RX_DP<70>")
	)
	(segment
		(start 190.119 -339.43036)
		(end 189.882526 -339.86597)
		(width 0.1651)
		(layer "In5.Cu")
		(net "P5E_PEX1_STN4_RX_DP<70>")
	)
	(segment
		(start 188.903102 -358.23906)
		(end 188.591444 -358.76357)
		(width 0.1651)
		(layer "In5.Cu")
		(net "P5E_PEX1_STN4_RX_DP<70>")
	)
	(segment
		(start 197.979792 -310.494172)
		(end 198.205598 -310.719978)
		(width 0.1143)
		(layer "In5.Cu")
		(net "P5E_PEX1_STN4_RX_DP<70>")
	)
	(segment
		(start 193.211196 -333.977488)
		(end 190.274194 -339.38464)
		(width 0.1651)
		(layer "In5.Cu")
		(net "P5E_PEX1_STN4_RX_DP<70>")
	)
	(segment
		(start 193.17081 -333.839566)
		(end 193.21145 -333.977488)
		(width 0.1651)
		(layer "In5.Cu")
		(net "P5E_PEX1_STN4_RX_DP<70>")
	)
	(segment
		(start 162.236912 -379.899164)
		(end 162.109912 -379.772164)
		(width 0.1651)
		(layer "In5.Cu")
		(net "P5E_PEX1_STN4_RX_DP<70>")
	)
	(segment
		(start 175.349154 -362.768896)
		(end 172.482002 -363.657642)
		(width 0.1651)
		(layer "In5.Cu")
		(net "P5E_PEX1_STN4_RX_DP<70>")
	)
	(segment
		(start 193.781426 -332.928214)
		(end 193.545206 -333.363316)
		(width 0.1651)
		(layer "In5.Cu")
		(net "P5E_PEX1_STN4_RX_DP<70>")
	)
	(segment
		(start 184.243472 -344.539062)
		(end 183.923432 -344.219022)
		(width 0.13462)
		(layer "F.Cu")
		(net "P5E_PEX1_STN4_TX_C_DP<69>")
	)
	(segment
		(start 184.243472 -345.170506)
		(end 184.243472 -344.539062)
		(width 0.13462)
		(layer "F.Cu")
		(net "P5E_PEX1_STN4_TX_C_DP<69>")
	)
	(segment
		(start 183.948832 -345.465146)
		(end 184.243472 -345.170506)
		(width 0.13462)
		(layer "F.Cu")
		(net "P5E_PEX1_STN4_TX_C_DP<69>")
	)
	(segment
		(start 184.239662 -345.755976)
		(end 183.948832 -345.465146)
		(width 0.1651)
		(layer "In7.Cu")
		(net "P5E_PEX1_STN4_TX_C_DP<69>")
	)
	(segment
		(start 174.41799 -364.005622)
		(end 174.903892 -363.798104)
		(width 0.1651)
		(layer "In7.Cu")
		(net "P5E_PEX1_STN4_TX_C_DP<69>")
	)
	(segment
		(start 171.170092 -365.39297)
		(end 173.822106 -364.26013)
		(width 0.1651)
		(layer "In7.Cu")
		(net "P5E_PEX1_STN4_TX_C_DP<69>")
	)
	(segment
		(start 180.572156 -360.336338)
		(end 180.587904 -360.175556)
		(width 0.1651)
		(layer "In7.Cu")
		(net "P5E_PEX1_STN4_TX_C_DP<69>")
	)
	(segment
		(start 182.570882 -356.40645)
		(end 182.570882 -355.91115)
		(width 0.1651)
		(layer "In7.Cu")
		(net "P5E_PEX1_STN4_TX_C_DP<69>")
	)
	(segment
		(start 179.59959 -361.137454)
		(end 180.572156 -360.336338)
		(width 0.1651)
		(layer "In7.Cu")
		(net "P5E_PEX1_STN4_TX_C_DP<69>")
	)
	(segment
		(start 182.570882 -355.91115)
		(end 182.685182 -355.79685)
		(width 0.1651)
		(layer "In7.Cu")
		(net "P5E_PEX1_STN4_TX_C_DP<69>")
	)
	(segment
		(start 182.072534 -359.100882)
		(end 182.685182 -358.596184)
		(width 0.1651)
		(layer "In7.Cu")
		(net "P5E_PEX1_STN4_TX_C_DP<69>")
	)
	(segment
		(start 177.146712 -362.840016)
		(end 177.596038 -362.528104)
		(width 0.1651)
		(layer "In7.Cu")
		(net "P5E_PEX1_STN4_TX_C_DP<69>")
	)
	(segment
		(start 178.626516 -361.673648)
		(end 179.033678 -361.390946)
		(width 0.1651)
		(layer "In7.Cu")
		(net "P5E_PEX1_STN4_TX_C_DP<69>")
	)
	(segment
		(start 179.033678 -361.390946)
		(end 179.192936 -361.419648)
		(width 0.1651)
		(layer "In7.Cu")
		(net "P5E_PEX1_STN4_TX_C_DP<69>")
	)
	(segment
		(start 176.025302 -363.31906)
		(end 176.0855 -363.168692)
		(width 0.1651)
		(layer "In7.Cu")
		(net "P5E_PEX1_STN4_TX_C_DP<69>")
	)
	(segment
		(start 182.685182 -358.596184)
		(end 182.685182 -356.52075)
		(width 0.1651)
		(layer "In7.Cu")
		(net "P5E_PEX1_STN4_TX_C_DP<69>")
	)
	(segment
		(start 164.43706 -370.999004)
		(end 164.669216 -370.999004)
		(width 0.1651)
		(layer "In7.Cu")
		(net "P5E_PEX1_STN4_TX_C_DP<69>")
	)
	(segment
		(start 165.087554 -370.580666)
		(end 165.087554 -368.5032)
		(width 0.1651)
		(layer "In7.Cu")
		(net "P5E_PEX1_STN4_TX_C_DP<69>")
	)
	(segment
		(start 181.51348 -359.56113)
		(end 181.528974 -359.400348)
		(width 0.1651)
		(layer "In7.Cu")
		(net "P5E_PEX1_STN4_TX_C_DP<69>")
	)
	(segment
		(start 182.685182 -347.946218)
		(end 184.239662 -346.391738)
		(width 0.1651)
		(layer "In7.Cu")
		(net "P5E_PEX1_STN4_TX_C_DP<69>")
	)
	(segment
		(start 181.528974 -359.400348)
		(end 181.911498 -359.085134)
		(width 0.1651)
		(layer "In7.Cu")
		(net "P5E_PEX1_STN4_TX_C_DP<69>")
	)
	(segment
		(start 179.192936 -361.419648)
		(end 179.59959 -361.137454)
		(width 0.1651)
		(layer "In7.Cu")
		(net "P5E_PEX1_STN4_TX_C_DP<69>")
	)
	(segment
		(start 180.587904 -360.175556)
		(end 180.970428 -359.860342)
		(width 0.1651)
		(layer "In7.Cu")
		(net "P5E_PEX1_STN4_TX_C_DP<69>")
	)
	(segment
		(start 176.0855 -363.168692)
		(end 176.54143 -362.974128)
		(width 0.1651)
		(layer "In7.Cu")
		(net "P5E_PEX1_STN4_TX_C_DP<69>")
	)
	(segment
		(start 178.031902 -362.086398)
		(end 178.19116 -362.1151)
		(width 0.1651)
		(layer "In7.Cu")
		(net "P5E_PEX1_STN4_TX_C_DP<69>")
	)
	(segment
		(start 177.596038 -362.528104)
		(end 177.62474 -362.3691)
		(width 0.1651)
		(layer "In7.Cu")
		(net "P5E_PEX1_STN4_TX_C_DP<69>")
	)
	(segment
		(start 182.685182 -355.79685)
		(end 182.685182 -347.946218)
		(width 0.1651)
		(layer "In7.Cu")
		(net "P5E_PEX1_STN4_TX_C_DP<69>")
	)
	(segment
		(start 176.69129 -363.034326)
		(end 177.146712 -362.840016)
		(width 0.1651)
		(layer "In7.Cu")
		(net "P5E_PEX1_STN4_TX_C_DP<69>")
	)
	(segment
		(start 182.685182 -356.52075)
		(end 182.570882 -356.40645)
		(width 0.1651)
		(layer "In7.Cu")
		(net "P5E_PEX1_STN4_TX_C_DP<69>")
	)
	(segment
		(start 178.19116 -362.1151)
		(end 178.597814 -361.832906)
		(width 0.1651)
		(layer "In7.Cu")
		(net "P5E_PEX1_STN4_TX_C_DP<69>")
	)
	(segment
		(start 173.822106 -364.26013)
		(end 173.862238 -364.160308)
		(width 0.1651)
		(layer "In7.Cu")
		(net "P5E_PEX1_STN4_TX_C_DP<69>")
	)
	(segment
		(start 165.087554 -368.5032)
		(end 165.64229 -367.937542)
		(width 0.1651)
		(layer "In7.Cu")
		(net "P5E_PEX1_STN4_TX_C_DP<69>")
	)
	(segment
		(start 173.862238 -364.160308)
		(end 174.317914 -363.96549)
		(width 0.1651)
		(layer "In7.Cu")
		(net "P5E_PEX1_STN4_TX_C_DP<69>")
	)
	(segment
		(start 164.31006 -370.872004)
		(end 164.43706 -370.999004)
		(width 0.1651)
		(layer "In7.Cu")
		(net "P5E_PEX1_STN4_TX_C_DP<69>")
	)
	(segment
		(start 176.54143 -362.974128)
		(end 176.69129 -363.034326)
		(width 0.1651)
		(layer "In7.Cu")
		(net "P5E_PEX1_STN4_TX_C_DP<69>")
	)
	(segment
		(start 180.970428 -359.860342)
		(end 181.13121 -359.875836)
		(width 0.1651)
		(layer "In7.Cu")
		(net "P5E_PEX1_STN4_TX_C_DP<69>")
	)
	(segment
		(start 164.669216 -370.999004)
		(end 165.087554 -370.580666)
		(width 0.1651)
		(layer "In7.Cu")
		(net "P5E_PEX1_STN4_TX_C_DP<69>")
	)
	(segment
		(start 174.317914 -363.96549)
		(end 174.41799 -364.005622)
		(width 0.1651)
		(layer "In7.Cu")
		(net "P5E_PEX1_STN4_TX_C_DP<69>")
	)
	(segment
		(start 177.62474 -362.3691)
		(end 178.031902 -362.086398)
		(width 0.1651)
		(layer "In7.Cu")
		(net "P5E_PEX1_STN4_TX_C_DP<69>")
	)
	(segment
		(start 175.42002 -363.453172)
		(end 175.56988 -363.51337)
		(width 0.1651)
		(layer "In7.Cu")
		(net "P5E_PEX1_STN4_TX_C_DP<69>")
	)
	(segment
		(start 181.911498 -359.085134)
		(end 182.072534 -359.100882)
		(width 0.1651)
		(layer "In7.Cu")
		(net "P5E_PEX1_STN4_TX_C_DP<69>")
	)
	(segment
		(start 178.597814 -361.832906)
		(end 178.626516 -361.673648)
		(width 0.1651)
		(layer "In7.Cu")
		(net "P5E_PEX1_STN4_TX_C_DP<69>")
	)
	(segment
		(start 174.96409 -363.647736)
		(end 175.42002 -363.453172)
		(width 0.1651)
		(layer "In7.Cu")
		(net "P5E_PEX1_STN4_TX_C_DP<69>")
	)
	(segment
		(start 181.13121 -359.875836)
		(end 181.51348 -359.56113)
		(width 0.1651)
		(layer "In7.Cu")
		(net "P5E_PEX1_STN4_TX_C_DP<69>")
	)
	(segment
		(start 164.31006 -370.489988)
		(end 164.31006 -370.872004)
		(width 0.1651)
		(layer "In7.Cu")
		(net "P5E_PEX1_STN4_TX_C_DP<69>")
	)
	(segment
		(start 165.64229 -367.937542)
		(end 171.170092 -365.39297)
		(width 0.1651)
		(layer "In7.Cu")
		(net "P5E_PEX1_STN4_TX_C_DP<69>")
	)
	(segment
		(start 174.903892 -363.798104)
		(end 174.96409 -363.647736)
		(width 0.1651)
		(layer "In7.Cu")
		(net "P5E_PEX1_STN4_TX_C_DP<69>")
	)
	(segment
		(start 184.239662 -346.391738)
		(end 184.239662 -345.755976)
		(width 0.1651)
		(layer "In7.Cu")
		(net "P5E_PEX1_STN4_TX_C_DP<69>")
	)
	(segment
		(start 175.56988 -363.51337)
		(end 176.025302 -363.31906)
		(width 0.1651)
		(layer "In7.Cu")
		(net "P5E_PEX1_STN4_TX_C_DP<69>")
	)
	(segment
		(start 166.158672 -345.465146)
		(end 165.864032 -345.170506)
		(width 0.13462)
		(layer "F.Cu")
		(net "P5E_PEX1_STN4_TX_C_DN<78>")
	)
	(segment
		(start 165.864032 -344.539062)
		(end 166.184072 -344.219022)
		(width 0.13462)
		(layer "F.Cu")
		(net "P5E_PEX1_STN4_TX_C_DN<78>")
	)
	(segment
		(start 165.864032 -345.170506)
		(end 165.864032 -344.539062)
		(width 0.13462)
		(layer "F.Cu")
		(net "P5E_PEX1_STN4_TX_C_DN<78>")
	)
	(segment
		(start 153.747216 -366.666272)
		(end 155.444698 -364.07471)
		(width 0.1651)
		(layer "In7.Cu")
		(net "P5E_PEX1_STN4_TX_C_DN<78>")
	)
	(segment
		(start 160.463484 -360.54919)
		(end 163.961826 -359.090214)
		(width 0.1651)
		(layer "In7.Cu")
		(net "P5E_PEX1_STN4_TX_C_DN<78>")
	)
	(segment
		(start 162.109912 -398.50822)
		(end 162.237166 -398.380966)
		(width 0.1651)
		(layer "In7.Cu")
		(net "P5E_PEX1_STN4_TX_C_DN<78>")
	)
	(segment
		(start 152.93086 -368.754406)
		(end 153.747216 -366.666272)
		(width 0.1651)
		(layer "In7.Cu")
		(net "P5E_PEX1_STN4_TX_C_DN<78>")
	)
	(segment
		(start 154.401774 -388.535164)
		(end 152.93086 -384.98272)
		(width 0.1651)
		(layer "In7.Cu")
		(net "P5E_PEX1_STN4_TX_C_DN<78>")
	)
	(segment
		(start 164.313362 -358.738678)
		(end 164.313362 -348.098618)
		(width 0.1651)
		(layer "In7.Cu")
		(net "P5E_PEX1_STN4_TX_C_DN<78>")
	)
	(segment
		(start 163.169346 -395.452346)
		(end 161.903156 -394.185648)
		(width 0.1651)
		(layer "In7.Cu")
		(net "P5E_PEX1_STN4_TX_C_DN<78>")
	)
	(segment
		(start 165.867842 -345.755976)
		(end 166.158672 -345.465146)
		(width 0.1651)
		(layer "In7.Cu")
		(net "P5E_PEX1_STN4_TX_C_DN<78>")
	)
	(segment
		(start 162.585908 -398.380966)
		(end 163.169346 -397.797528)
		(width 0.1651)
		(layer "In7.Cu")
		(net "P5E_PEX1_STN4_TX_C_DN<78>")
	)
	(segment
		(start 162.237166 -398.380966)
		(end 162.585908 -398.380966)
		(width 0.1651)
		(layer "In7.Cu")
		(net "P5E_PEX1_STN4_TX_C_DN<78>")
	)
	(segment
		(start 162.109912 -398.890236)
		(end 162.109912 -398.50822)
		(width 0.1651)
		(layer "In7.Cu")
		(net "P5E_PEX1_STN4_TX_C_DN<78>")
	)
	(segment
		(start 156.328872 -390.462262)
		(end 154.401774 -388.535164)
		(width 0.1651)
		(layer "In7.Cu")
		(net "P5E_PEX1_STN4_TX_C_DN<78>")
	)
	(segment
		(start 152.93086 -384.98272)
		(end 152.93086 -368.754406)
		(width 0.1651)
		(layer "In7.Cu")
		(net "P5E_PEX1_STN4_TX_C_DN<78>")
	)
	(segment
		(start 155.444698 -364.07471)
		(end 160.463484 -360.54919)
		(width 0.1651)
		(layer "In7.Cu")
		(net "P5E_PEX1_STN4_TX_C_DN<78>")
	)
	(segment
		(start 163.961826 -359.090214)
		(end 164.313362 -358.738678)
		(width 0.1651)
		(layer "In7.Cu")
		(net "P5E_PEX1_STN4_TX_C_DN<78>")
	)
	(segment
		(start 161.903156 -394.185648)
		(end 156.328872 -390.462262)
		(width 0.1651)
		(layer "In7.Cu")
		(net "P5E_PEX1_STN4_TX_C_DN<78>")
	)
	(segment
		(start 165.867842 -346.544138)
		(end 165.867842 -345.755976)
		(width 0.1651)
		(layer "In7.Cu")
		(net "P5E_PEX1_STN4_TX_C_DN<78>")
	)
	(segment
		(start 164.313362 -348.098618)
		(end 165.867842 -346.544138)
		(width 0.1651)
		(layer "In7.Cu")
		(net "P5E_PEX1_STN4_TX_C_DN<78>")
	)
	(segment
		(start 163.169346 -397.797528)
		(end 163.169346 -395.452346)
		(width 0.1651)
		(layer "In7.Cu")
		(net "P5E_PEX1_STN4_TX_C_DN<78>")
	)
	(segment
		(start 186.990228 -363.671612)
		(end 189.711076 -362.23702)
		(width 0.1651)
		(layer "In5.Cu")
		(net "P5E_PEX1_STN4_RX_DN<67>")
	)
	(segment
		(start 199.69988 -307.679598)
		(end 196.384418 -307.679598)
		(width 0.1143)
		(layer "In5.Cu")
		(net "P5E_PEX1_STN4_RX_DN<67>")
	)
	(segment
		(start 209.110326 -315.03874)
		(end 207.14335 -313.76112)
		(width 0.1651)
		(layer "In5.Cu")
		(net "P5E_PEX1_STN4_RX_DN<67>")
	)
	(segment
		(start 174.805594 -366.242854)
		(end 175.837088 -365.923322)
		(width 0.1651)
		(layer "In5.Cu")
		(net "P5E_PEX1_STN4_RX_DN<67>")
	)
	(segment
		(start 168.710102 -379.590046)
		(end 168.710102 -379.20803)
		(width 0.1651)
		(layer "In5.Cu")
		(net "P5E_PEX1_STN4_RX_DN<67>")
	)
	(segment
		(start 203.169774 -309.309008)
		(end 202.122024 -308.261004)
		(width 0.1651)
		(layer "In5.Cu")
		(net "P5E_PEX1_STN4_RX_DN<67>")
	)
	(segment
		(start 169.769536 -369.507008)
		(end 170.342306 -368.754914)
		(width 0.1651)
		(layer "In5.Cu")
		(net "P5E_PEX1_STN4_RX_DN<67>")
	)
	(segment
		(start 212.37448 -319.744852)
		(end 211.405216 -317.37808)
		(width 0.1651)
		(layer "In5.Cu")
		(net "P5E_PEX1_STN4_RX_DN<67>")
	)
	(segment
		(start 196.270118 -307.565298)
		(end 196.270118 -307.414168)
		(width 0.1143)
		(layer "In5.Cu")
		(net "P5E_PEX1_STN4_RX_DN<67>")
	)
	(segment
		(start 199.141334 -348.64802)
		(end 211.624926 -325.361554)
		(width 0.1651)
		(layer "In5.Cu")
		(net "P5E_PEX1_STN4_RX_DN<67>")
	)
	(segment
		(start 196.384418 -307.299868)
		(end 196.649848 -307.299868)
		(width 0.1143)
		(layer "In5.Cu")
		(net "P5E_PEX1_STN4_RX_DN<67>")
	)
	(segment
		(start 202.122024 -308.261004)
		(end 200.610978 -307.633878)
		(width 0.1651)
		(layer "In5.Cu")
		(net "P5E_PEX1_STN4_RX_DN<67>")
	)
	(segment
		(start 191.414908 -360.52125)
		(end 195.60159 -354.788978)
		(width 0.1651)
		(layer "In5.Cu")
		(net "P5E_PEX1_STN4_RX_DN<67>")
	)
	(segment
		(start 168.837102 -379.08103)
		(end 169.386758 -379.08103)
		(width 0.1651)
		(layer "In5.Cu")
		(net "P5E_PEX1_STN4_RX_DN<67>")
	)
	(segment
		(start 196.270118 -307.414168)
		(end 196.384418 -307.299868)
		(width 0.1143)
		(layer "In5.Cu")
		(net "P5E_PEX1_STN4_RX_DN<67>")
	)
	(segment
		(start 189.711076 -362.23702)
		(end 191.414908 -360.52125)
		(width 0.1651)
		(layer "In5.Cu")
		(net "P5E_PEX1_STN4_RX_DN<67>")
	)
	(segment
		(start 199.7456 -307.633878)
		(end 199.69988 -307.679598)
		(width 0.1143)
		(layer "In5.Cu")
		(net "P5E_PEX1_STN4_RX_DN<67>")
	)
	(segment
		(start 168.710102 -379.20803)
		(end 168.837102 -379.08103)
		(width 0.1651)
		(layer "In5.Cu")
		(net "P5E_PEX1_STN4_RX_DN<67>")
	)
	(segment
		(start 200.610978 -307.633878)
		(end 199.774048 -307.633878)
		(width 0.1651)
		(layer "In5.Cu")
		(net "P5E_PEX1_STN4_RX_DN<67>")
	)
	(segment
		(start 175.837088 -365.923322)
		(end 186.990228 -363.671612)
		(width 0.1651)
		(layer "In5.Cu")
		(net "P5E_PEX1_STN4_RX_DN<67>")
	)
	(segment
		(start 195.60159 -354.788978)
		(end 199.141334 -348.64802)
		(width 0.1651)
		(layer "In5.Cu")
		(net "P5E_PEX1_STN4_RX_DN<67>")
	)
	(segment
		(start 170.342306 -368.754914)
		(end 170.674792 -368.422428)
		(width 0.1651)
		(layer "In5.Cu")
		(net "P5E_PEX1_STN4_RX_DN<67>")
	)
	(segment
		(start 199.774048 -307.633878)
		(end 199.7456 -307.633878)
		(width 0.1143)
		(layer "In5.Cu")
		(net "P5E_PEX1_STN4_RX_DN<67>")
	)
	(segment
		(start 212.37448 -321.618864)
		(end 212.37448 -319.744852)
		(width 0.1651)
		(layer "In5.Cu")
		(net "P5E_PEX1_STN4_RX_DN<67>")
	)
	(segment
		(start 172.345604 -367.28654)
		(end 174.805594 -366.242854)
		(width 0.1651)
		(layer "In5.Cu")
		(net "P5E_PEX1_STN4_RX_DN<67>")
	)
	(segment
		(start 196.384418 -307.679598)
		(end 196.270118 -307.565298)
		(width 0.1143)
		(layer "In5.Cu")
		(net "P5E_PEX1_STN4_RX_DN<67>")
	)
	(segment
		(start 211.624926 -325.361554)
		(end 212.37448 -321.618864)
		(width 0.1651)
		(layer "In5.Cu")
		(net "P5E_PEX1_STN4_RX_DN<67>")
	)
	(segment
		(start 170.674792 -368.422428)
		(end 172.345604 -367.28654)
		(width 0.1651)
		(layer "In5.Cu")
		(net "P5E_PEX1_STN4_RX_DN<67>")
	)
	(segment
		(start 211.405216 -317.37808)
		(end 209.110326 -315.03874)
		(width 0.1651)
		(layer "In5.Cu")
		(net "P5E_PEX1_STN4_RX_DN<67>")
	)
	(segment
		(start 203.427838 -310.050942)
		(end 203.169774 -309.309008)
		(width 0.1651)
		(layer "In5.Cu")
		(net "P5E_PEX1_STN4_RX_DN<67>")
	)
	(segment
		(start 207.14335 -313.76112)
		(end 203.427838 -310.050942)
		(width 0.1651)
		(layer "In5.Cu")
		(net "P5E_PEX1_STN4_RX_DN<67>")
	)
	(segment
		(start 169.769536 -378.698252)
		(end 169.769536 -369.507008)
		(width 0.1651)
		(layer "In5.Cu")
		(net "P5E_PEX1_STN4_RX_DN<67>")
	)
	(segment
		(start 169.386758 -379.08103)
		(end 169.769536 -378.698252)
		(width 0.1651)
		(layer "In5.Cu")
		(net "P5E_PEX1_STN4_RX_DN<67>")
	)
	(segment
		(start 154.16276 -388.69493)
		(end 152.64892 -385.038854)
		(width 0.1651)
		(layer "In5.Cu")
		(net "P5E_PEX1_STN4_RX_DP<78>")
	)
	(segment
		(start 161.670238 -394.35151)
		(end 156.095954 -390.628124)
		(width 0.1651)
		(layer "In5.Cu")
		(net "P5E_PEX1_STN4_RX_DP<78>")
	)
	(segment
		(start 190.379858 -318.355472)
		(end 190.605664 -318.129666)
		(width 0.1143)
		(layer "In5.Cu")
		(net "P5E_PEX1_STN4_RX_DP<78>")
	)
	(segment
		(start 190.334138 -320.119248)
		(end 190.334138 -320.0908)
		(width 0.1143)
		(layer "In5.Cu")
		(net "P5E_PEX1_STN4_RX_DP<78>")
	)
	(segment
		(start 152.64892 -367.639346)
		(end 157.170628 -355.708966)
		(width 0.1651)
		(layer "In5.Cu")
		(net "P5E_PEX1_STN4_RX_DP<78>")
	)
	(segment
		(start 190.950088 -318.015366)
		(end 190.950088 -317.749936)
		(width 0.1143)
		(layer "In5.Cu")
		(net "P5E_PEX1_STN4_RX_DP<78>")
	)
	(segment
		(start 157.170628 -355.708966)
		(end 164.15131 -341.795608)
		(width 0.1651)
		(layer "In5.Cu")
		(net "P5E_PEX1_STN4_RX_DP<78>")
	)
	(segment
		(start 184.366916 -328.4728)
		(end 185.104278 -327.82129)
		(width 0.1651)
		(layer "In5.Cu")
		(net "P5E_PEX1_STN4_RX_DP<78>")
	)
	(segment
		(start 181.482238 -330.881736)
		(end 184.366916 -328.4728)
		(width 0.1651)
		(layer "In5.Cu")
		(net "P5E_PEX1_STN4_RX_DP<78>")
	)
	(segment
		(start 190.379858 -320.04508)
		(end 190.379858 -318.355472)
		(width 0.1143)
		(layer "In5.Cu")
		(net "P5E_PEX1_STN4_RX_DP<78>")
	)
	(segment
		(start 162.109912 -405.390096)
		(end 162.109912 -405.772112)
		(width 0.1651)
		(layer "In5.Cu")
		(net "P5E_PEX1_STN4_RX_DP<78>")
	)
	(segment
		(start 162.236912 -405.899112)
		(end 162.669728 -405.899112)
		(width 0.1651)
		(layer "In5.Cu")
		(net "P5E_PEX1_STN4_RX_DP<78>")
	)
	(segment
		(start 156.095954 -390.628124)
		(end 154.16276 -388.69493)
		(width 0.1651)
		(layer "In5.Cu")
		(net "P5E_PEX1_STN4_RX_DP<78>")
	)
	(segment
		(start 190.334138 -320.0908)
		(end 190.379858 -320.04508)
		(width 0.1143)
		(layer "In5.Cu")
		(net "P5E_PEX1_STN4_RX_DP<78>")
	)
	(segment
		(start 152.64892 -385.038854)
		(end 152.64892 -367.639346)
		(width 0.1651)
		(layer "In5.Cu")
		(net "P5E_PEX1_STN4_RX_DP<78>")
	)
	(segment
		(start 162.887406 -405.681434)
		(end 162.887406 -395.569186)
		(width 0.1651)
		(layer "In5.Cu")
		(net "P5E_PEX1_STN4_RX_DP<78>")
	)
	(segment
		(start 190.334138 -320.941954)
		(end 190.334138 -320.119248)
		(width 0.1651)
		(layer "In5.Cu")
		(net "P5E_PEX1_STN4_RX_DP<78>")
	)
	(segment
		(start 162.669728 -405.899112)
		(end 162.887406 -405.681434)
		(width 0.1651)
		(layer "In5.Cu")
		(net "P5E_PEX1_STN4_RX_DP<78>")
	)
	(segment
		(start 162.109912 -405.772112)
		(end 162.236912 -405.899112)
		(width 0.1651)
		(layer "In5.Cu")
		(net "P5E_PEX1_STN4_RX_DP<78>")
	)
	(segment
		(start 185.104278 -327.82129)
		(end 189.775846 -322.436998)
		(width 0.1651)
		(layer "In5.Cu")
		(net "P5E_PEX1_STN4_RX_DP<78>")
	)
	(segment
		(start 190.835788 -318.129666)
		(end 190.950088 -318.015366)
		(width 0.1143)
		(layer "In5.Cu")
		(net "P5E_PEX1_STN4_RX_DP<78>")
	)
	(segment
		(start 164.15131 -341.795608)
		(end 164.625274 -341.25027)
		(width 0.1651)
		(layer "In5.Cu")
		(net "P5E_PEX1_STN4_RX_DP<78>")
	)
	(segment
		(start 162.04692 -394.728446)
		(end 161.670238 -394.35151)
		(width 0.1651)
		(layer "In5.Cu")
		(net "P5E_PEX1_STN4_RX_DP<78>")
	)
	(segment
		(start 164.625274 -341.25027)
		(end 181.482238 -330.881736)
		(width 0.1651)
		(layer "In5.Cu")
		(net "P5E_PEX1_STN4_RX_DP<78>")
	)
	(segment
		(start 162.04692 -394.886434)
		(end 162.04692 -394.728446)
		(width 0.1651)
		(layer "In5.Cu")
		(net "P5E_PEX1_STN4_RX_DP<78>")
	)
	(segment
		(start 162.546284 -395.228064)
		(end 162.388296 -395.228064)
		(width 0.1651)
		(layer "In5.Cu")
		(net "P5E_PEX1_STN4_RX_DP<78>")
	)
	(segment
		(start 162.887406 -395.569186)
		(end 162.546284 -395.228064)
		(width 0.1651)
		(layer "In5.Cu")
		(net "P5E_PEX1_STN4_RX_DP<78>")
	)
	(segment
		(start 162.388296 -395.228064)
		(end 162.04692 -394.886434)
		(width 0.1651)
		(layer "In5.Cu")
		(net "P5E_PEX1_STN4_RX_DP<78>")
	)
	(segment
		(start 190.605664 -318.129666)
		(end 190.835788 -318.129666)
		(width 0.1143)
		(layer "In5.Cu")
		(net "P5E_PEX1_STN4_RX_DP<78>")
	)
	(segment
		(start 189.775846 -322.436998)
		(end 190.334138 -320.941954)
		(width 0.1651)
		(layer "In5.Cu")
		(net "P5E_PEX1_STN4_RX_DP<78>")
	)
	(segment
		(start 210.730846 -324.904608)
		(end 211.41944 -321.465194)
		(width 0.1651)
		(layer "In5.Cu")
		(net "P5E_PEX1_STN4_RX_DN<68>")
	)
	(segment
		(start 201.588878 -309.096918)
		(end 200.350374 -308.583838)
		(width 0.1651)
		(layer "In5.Cu")
		(net "P5E_PEX1_STN4_RX_DN<68>")
	)
	(segment
		(start 193.995548 -355.361494)
		(end 198.350378 -347.807026)
		(width 0.1651)
		(layer "In5.Cu")
		(net "P5E_PEX1_STN4_RX_DN<68>")
	)
	(segment
		(start 202.34402 -309.85206)
		(end 201.588878 -309.096918)
		(width 0.1651)
		(layer "In5.Cu")
		(net "P5E_PEX1_STN4_RX_DN<68>")
	)
	(segment
		(start 208.649824 -315.933836)
		(end 206.599536 -314.568078)
		(width 0.1651)
		(layer "In5.Cu")
		(net "P5E_PEX1_STN4_RX_DN<68>")
	)
	(segment
		(start 199.67448 -308.629558)
		(end 198.284592 -308.629558)
		(width 0.1143)
		(layer "In5.Cu")
		(net "P5E_PEX1_STN4_RX_DN<68>")
	)
	(segment
		(start 186.742578 -362.721906)
		(end 188.91758 -361.57535)
		(width 0.1651)
		(layer "In5.Cu")
		(net "P5E_PEX1_STN4_RX_DN<68>")
	)
	(segment
		(start 190.958216 -359.519474)
		(end 193.995548 -355.361494)
		(width 0.1651)
		(layer "In5.Cu")
		(net "P5E_PEX1_STN4_RX_DN<68>")
	)
	(segment
		(start 166.509954 -380.69012)
		(end 166.509954 -380.308104)
		(width 0.1651)
		(layer "In5.Cu")
		(net "P5E_PEX1_STN4_RX_DN<68>")
	)
	(segment
		(start 167.18661 -380.181104)
		(end 167.569388 -379.798326)
		(width 0.1651)
		(layer "In5.Cu")
		(net "P5E_PEX1_STN4_RX_DN<68>")
	)
	(segment
		(start 202.531472 -310.390286)
		(end 202.531218 -310.389778)
		(width 0.1651)
		(layer "In5.Cu")
		(net "P5E_PEX1_STN4_RX_DN<68>")
	)
	(segment
		(start 188.91758 -361.57535)
		(end 190.958216 -359.519474)
		(width 0.1651)
		(layer "In5.Cu")
		(net "P5E_PEX1_STN4_RX_DN<68>")
	)
	(segment
		(start 166.636954 -380.181104)
		(end 167.18661 -380.181104)
		(width 0.1651)
		(layer "In5.Cu")
		(net "P5E_PEX1_STN4_RX_DN<68>")
	)
	(segment
		(start 167.569388 -379.798326)
		(end 167.569388 -369.773708)
		(width 0.1651)
		(layer "In5.Cu")
		(net "P5E_PEX1_STN4_RX_DN<68>")
	)
	(segment
		(start 199.7202 -308.583838)
		(end 199.67448 -308.629558)
		(width 0.1143)
		(layer "In5.Cu")
		(net "P5E_PEX1_STN4_RX_DN<68>")
	)
	(segment
		(start 168.047416 -368.915442)
		(end 168.499282 -368.463576)
		(width 0.1651)
		(layer "In5.Cu")
		(net "P5E_PEX1_STN4_RX_DN<68>")
	)
	(segment
		(start 198.284592 -308.249828)
		(end 198.550022 -308.249828)
		(width 0.1143)
		(layer "In5.Cu")
		(net "P5E_PEX1_STN4_RX_DN<68>")
	)
	(segment
		(start 210.606386 -317.948564)
		(end 208.649824 -315.933836)
		(width 0.1651)
		(layer "In5.Cu")
		(net "P5E_PEX1_STN4_RX_DN<68>")
	)
	(segment
		(start 198.170292 -308.515258)
		(end 198.170292 -308.364128)
		(width 0.1143)
		(layer "In5.Cu")
		(net "P5E_PEX1_STN4_RX_DN<68>")
	)
	(segment
		(start 199.748648 -308.583838)
		(end 199.7202 -308.583838)
		(width 0.1143)
		(layer "In5.Cu")
		(net "P5E_PEX1_STN4_RX_DN<68>")
	)
	(segment
		(start 198.284592 -308.629558)
		(end 198.170292 -308.515258)
		(width 0.1143)
		(layer "In5.Cu")
		(net "P5E_PEX1_STN4_RX_DN<68>")
	)
	(segment
		(start 175.796448 -364.935262)
		(end 186.742578 -362.721906)
		(width 0.1651)
		(layer "In5.Cu")
		(net "P5E_PEX1_STN4_RX_DN<68>")
	)
	(segment
		(start 202.531218 -310.389778)
		(end 202.34402 -309.85206)
		(width 0.1651)
		(layer "In5.Cu")
		(net "P5E_PEX1_STN4_RX_DN<68>")
	)
	(segment
		(start 166.509954 -380.308104)
		(end 166.636954 -380.181104)
		(width 0.1651)
		(layer "In5.Cu")
		(net "P5E_PEX1_STN4_RX_DN<68>")
	)
	(segment
		(start 173.503336 -365.646462)
		(end 175.796448 -364.935262)
		(width 0.1651)
		(layer "In5.Cu")
		(net "P5E_PEX1_STN4_RX_DN<68>")
	)
	(segment
		(start 198.350378 -347.807026)
		(end 210.730846 -324.904608)
		(width 0.1651)
		(layer "In5.Cu")
		(net "P5E_PEX1_STN4_RX_DN<68>")
	)
	(segment
		(start 200.350374 -308.583838)
		(end 199.748648 -308.583838)
		(width 0.1651)
		(layer "In5.Cu")
		(net "P5E_PEX1_STN4_RX_DN<68>")
	)
	(segment
		(start 167.569388 -369.773708)
		(end 168.047416 -368.915442)
		(width 0.1651)
		(layer "In5.Cu")
		(net "P5E_PEX1_STN4_RX_DN<68>")
	)
	(segment
		(start 171.218352 -366.61598)
		(end 173.503336 -365.646462)
		(width 0.1651)
		(layer "In5.Cu")
		(net "P5E_PEX1_STN4_RX_DN<68>")
	)
	(segment
		(start 211.41944 -321.465194)
		(end 211.41944 -319.936622)
		(width 0.1651)
		(layer "In5.Cu")
		(net "P5E_PEX1_STN4_RX_DN<68>")
	)
	(segment
		(start 168.499282 -368.463576)
		(end 171.218352 -366.61598)
		(width 0.1651)
		(layer "In5.Cu")
		(net "P5E_PEX1_STN4_RX_DN<68>")
	)
	(segment
		(start 202.593194 -310.567832)
		(end 202.531472 -310.390286)
		(width 0.1651)
		(layer "In5.Cu")
		(net "P5E_PEX1_STN4_RX_DN<68>")
	)
	(segment
		(start 206.599536 -314.568078)
		(end 202.593194 -310.567832)
		(width 0.1651)
		(layer "In5.Cu")
		(net "P5E_PEX1_STN4_RX_DN<68>")
	)
	(segment
		(start 211.41944 -319.936622)
		(end 210.606386 -317.948564)
		(width 0.1651)
		(layer "In5.Cu")
		(net "P5E_PEX1_STN4_RX_DN<68>")
	)
	(segment
		(start 198.170292 -308.364128)
		(end 198.284592 -308.249828)
		(width 0.1143)
		(layer "In5.Cu")
		(net "P5E_PEX1_STN4_RX_DN<68>")
	)
	(segment
		(start 172.081952 -345.170506)
		(end 172.081952 -344.539062)
		(width 0.13462)
		(layer "F.Cu")
		(net "P5E_PEX1_STN4_TX_C_DN<75>")
	)
	(segment
		(start 172.376592 -345.465146)
		(end 172.081952 -345.170506)
		(width 0.13462)
		(layer "F.Cu")
		(net "P5E_PEX1_STN4_TX_C_DN<75>")
	)
	(segment
		(start 172.081952 -344.539062)
		(end 172.401992 -344.219022)
		(width 0.13462)
		(layer "F.Cu")
		(net "P5E_PEX1_STN4_TX_C_DN<75>")
	)
	(segment
		(start 165.037516 -391.54354)
		(end 160.622996 -389.184134)
		(width 0.1651)
		(layer "In7.Cu")
		(net "P5E_PEX1_STN4_TX_C_DN<75>")
	)
	(segment
		(start 161.70529 -363.179106)
		(end 168.789096 -360.22026)
		(width 0.1651)
		(layer "In7.Cu")
		(net "P5E_PEX1_STN4_TX_C_DN<75>")
	)
	(segment
		(start 168.789096 -360.22026)
		(end 170.234356 -359.221024)
		(width 0.1651)
		(layer "In7.Cu")
		(net "P5E_PEX1_STN4_TX_C_DN<75>")
	)
	(segment
		(start 170.234356 -359.221024)
		(end 170.531282 -358.924098)
		(width 0.1651)
		(layer "In7.Cu")
		(net "P5E_PEX1_STN4_TX_C_DN<75>")
	)
	(segment
		(start 155.83916 -384.515614)
		(end 155.83916 -369.443762)
		(width 0.1651)
		(layer "In7.Cu")
		(net "P5E_PEX1_STN4_TX_C_DN<75>")
	)
	(segment
		(start 158.001208 -388.081774)
		(end 156.832554 -386.91312)
		(width 0.1651)
		(layer "In7.Cu")
		(net "P5E_PEX1_STN4_TX_C_DN<75>")
	)
	(segment
		(start 168.837356 -397.280892)
		(end 169.186098 -397.280892)
		(width 0.1651)
		(layer "In7.Cu")
		(net "P5E_PEX1_STN4_TX_C_DN<75>")
	)
	(segment
		(start 156.832554 -386.91312)
		(end 156.120592 -385.19481)
		(width 0.1651)
		(layer "In7.Cu")
		(net "P5E_PEX1_STN4_TX_C_DN<75>")
	)
	(segment
		(start 172.085762 -346.549218)
		(end 172.085762 -345.755976)
		(width 0.1651)
		(layer "In7.Cu")
		(net "P5E_PEX1_STN4_TX_C_DN<75>")
	)
	(segment
		(start 172.085762 -345.755976)
		(end 172.376592 -345.465146)
		(width 0.1651)
		(layer "In7.Cu")
		(net "P5E_PEX1_STN4_TX_C_DN<75>")
	)
	(segment
		(start 160.622996 -389.184134)
		(end 158.001208 -388.081774)
		(width 0.1651)
		(layer "In7.Cu")
		(net "P5E_PEX1_STN4_TX_C_DN<75>")
	)
	(segment
		(start 168.710102 -397.408146)
		(end 168.837356 -397.280892)
		(width 0.1651)
		(layer "In7.Cu")
		(net "P5E_PEX1_STN4_TX_C_DN<75>")
	)
	(segment
		(start 157.607508 -366.057942)
		(end 161.70529 -363.179106)
		(width 0.1651)
		(layer "In7.Cu")
		(net "P5E_PEX1_STN4_TX_C_DN<75>")
	)
	(segment
		(start 168.710102 -397.790162)
		(end 168.710102 -397.408146)
		(width 0.1651)
		(layer "In7.Cu")
		(net "P5E_PEX1_STN4_TX_C_DN<75>")
	)
	(segment
		(start 155.8798 -369.31727)
		(end 156.542994 -367.672874)
		(width 0.1651)
		(layer "In7.Cu")
		(net "P5E_PEX1_STN4_TX_C_DN<75>")
	)
	(segment
		(start 169.186098 -397.280892)
		(end 169.769536 -396.697454)
		(width 0.1651)
		(layer "In7.Cu")
		(net "P5E_PEX1_STN4_TX_C_DN<75>")
	)
	(segment
		(start 156.120592 -385.19481)
		(end 155.83916 -384.515614)
		(width 0.1651)
		(layer "In7.Cu")
		(net "P5E_PEX1_STN4_TX_C_DN<75>")
	)
	(segment
		(start 170.531282 -348.103698)
		(end 172.085762 -346.549218)
		(width 0.1651)
		(layer "In7.Cu")
		(net "P5E_PEX1_STN4_TX_C_DN<75>")
	)
	(segment
		(start 169.769536 -396.697454)
		(end 169.769536 -394.931138)
		(width 0.1651)
		(layer "In7.Cu")
		(net "P5E_PEX1_STN4_TX_C_DN<75>")
	)
	(segment
		(start 169.614088 -394.6017)
		(end 165.037516 -391.54354)
		(width 0.1651)
		(layer "In7.Cu")
		(net "P5E_PEX1_STN4_TX_C_DN<75>")
	)
	(segment
		(start 169.769536 -394.931138)
		(end 169.614088 -394.6017)
		(width 0.1651)
		(layer "In7.Cu")
		(net "P5E_PEX1_STN4_TX_C_DN<75>")
	)
	(segment
		(start 170.531282 -358.924098)
		(end 170.531282 -348.103698)
		(width 0.1651)
		(layer "In7.Cu")
		(net "P5E_PEX1_STN4_TX_C_DN<75>")
	)
	(segment
		(start 155.83916 -369.443762)
		(end 155.8798 -369.31727)
		(width 0.1651)
		(layer "In7.Cu")
		(net "P5E_PEX1_STN4_TX_C_DN<75>")
	)
	(segment
		(start 156.542994 -367.672874)
		(end 157.607508 -366.057942)
		(width 0.1651)
		(layer "In7.Cu")
		(net "P5E_PEX1_STN4_TX_C_DN<75>")
	)
	(segment
		(start 200.139808 -345.94673)
		(end 200.294494 -345.899994)
		(width 0.1651)
		(layer "In5.Cu")
		(net "P5E_PEX1_STN4_RX_DP<67>")
	)
	(segment
		(start 174.708566 -365.977678)
		(end 175.767238 -365.649764)
		(width 0.1651)
		(layer "In5.Cu")
		(net "P5E_PEX1_STN4_RX_DP<67>")
	)
	(segment
		(start 201.868278 -342.722708)
		(end 202.022964 -342.675972)
		(width 0.1651)
		(layer "In5.Cu")
		(net "P5E_PEX1_STN4_RX_DP<67>")
	)
	(segment
		(start 170.494198 -368.204242)
		(end 172.209968 -367.03762)
		(width 0.1651)
		(layer "In5.Cu")
		(net "P5E_PEX1_STN4_RX_DP<67>")
	)
	(segment
		(start 211.165186 -317.536068)
		(end 208.930494 -315.25845)
		(width 0.1651)
		(layer "In5.Cu")
		(net "P5E_PEX1_STN4_RX_DP<67>")
	)
	(segment
		(start 196.025516 -353.488752)
		(end 195.983606 -353.332796)
		(width 0.1651)
		(layer "In5.Cu")
		(net "P5E_PEX1_STN4_RX_DP<67>")
	)
	(segment
		(start 195.364862 -354.635054)
		(end 196.025516 -353.488752)
		(width 0.1651)
		(layer "In5.Cu")
		(net "P5E_PEX1_STN4_RX_DP<67>")
	)
	(segment
		(start 200.870566 -344.82532)
		(end 201.1045 -344.388948)
		(width 0.1651)
		(layer "In5.Cu")
		(net "P5E_PEX1_STN4_RX_DP<67>")
	)
	(segment
		(start 196.996304 -351.804986)
		(end 197.243446 -351.37598)
		(width 0.1651)
		(layer "In5.Cu")
		(net "P5E_PEX1_STN4_RX_DP<67>")
	)
	(segment
		(start 189.541404 -362.007658)
		(end 191.19977 -360.337608)
		(width 0.1651)
		(layer "In5.Cu")
		(net "P5E_PEX1_STN4_RX_DP<67>")
	)
	(segment
		(start 196.079618 -307.414168)
		(end 195.965318 -307.299868)
		(width 0.1143)
		(layer "In5.Cu")
		(net "P5E_PEX1_STN4_RX_DP<67>")
	)
	(segment
		(start 196.634354 -352.432366)
		(end 196.592444 -352.276156)
		(width 0.1651)
		(layer "In5.Cu")
		(net "P5E_PEX1_STN4_RX_DP<67>")
	)
	(segment
		(start 197.243446 -351.37598)
		(end 197.201536 -351.21977)
		(width 0.1651)
		(layer "In5.Cu")
		(net "P5E_PEX1_STN4_RX_DP<67>")
	)
	(segment
		(start 200.481692 -345.308936)
		(end 200.71588 -344.872056)
		(width 0.1651)
		(layer "In5.Cu")
		(net "P5E_PEX1_STN4_RX_DP<67>")
	)
	(segment
		(start 199.774048 -307.915818)
		(end 199.7456 -307.915818)
		(width 0.1143)
		(layer "In5.Cu")
		(net "P5E_PEX1_STN4_RX_DP<67>")
	)
	(segment
		(start 198.894954 -348.51086)
		(end 199.952356 -346.538296)
		(width 0.1651)
		(layer "In5.Cu")
		(net "P5E_PEX1_STN4_RX_DP<67>")
	)
	(segment
		(start 197.449186 -350.79051)
		(end 197.605142 -350.7486)
		(width 0.1651)
		(layer "In5.Cu")
		(net "P5E_PEX1_STN4_RX_DP<67>")
	)
	(segment
		(start 201.63409 -343.159588)
		(end 201.868278 -342.722708)
		(width 0.1651)
		(layer "In5.Cu")
		(net "P5E_PEX1_STN4_RX_DP<67>")
	)
	(segment
		(start 199.90562 -346.38361)
		(end 200.139808 -345.94673)
		(width 0.1651)
		(layer "In5.Cu")
		(net "P5E_PEX1_STN4_RX_DP<67>")
	)
	(segment
		(start 203.182474 -310.204866)
		(end 202.924664 -309.462678)
		(width 0.1651)
		(layer "In5.Cu")
		(net "P5E_PEX1_STN4_RX_DP<67>")
	)
	(segment
		(start 200.294494 -345.899994)
		(end 200.528428 -345.463622)
		(width 0.1651)
		(layer "In5.Cu")
		(net "P5E_PEX1_STN4_RX_DP<67>")
	)
	(segment
		(start 200.71588 -344.872056)
		(end 200.870566 -344.82532)
		(width 0.1651)
		(layer "In5.Cu")
		(net "P5E_PEX1_STN4_RX_DP<67>")
	)
	(segment
		(start 196.840094 -351.846896)
		(end 196.996304 -351.804986)
		(width 0.1651)
		(layer "In5.Cu")
		(net "P5E_PEX1_STN4_RX_DP<67>")
	)
	(segment
		(start 168.837102 -378.79909)
		(end 169.269918 -378.79909)
		(width 0.1651)
		(layer "In5.Cu")
		(net "P5E_PEX1_STN4_RX_DP<67>")
	)
	(segment
		(start 201.962258 -308.500018)
		(end 200.55459 -307.915818)
		(width 0.1651)
		(layer "In5.Cu")
		(net "P5E_PEX1_STN4_RX_DP<67>")
	)
	(segment
		(start 186.89447 -363.403134)
		(end 189.541404 -362.007658)
		(width 0.1651)
		(layer "In5.Cu")
		(net "P5E_PEX1_STN4_RX_DP<67>")
	)
	(segment
		(start 197.605142 -350.7486)
		(end 197.604888 -350.7486)
		(width 0.1651)
		(layer "In5.Cu")
		(net "P5E_PEX1_STN4_RX_DP<67>")
	)
	(segment
		(start 212.09254 -321.59067)
		(end 212.09254 -319.800478)
		(width 0.1651)
		(layer "In5.Cu")
		(net "P5E_PEX1_STN4_RX_DP<67>")
	)
	(segment
		(start 202.924664 -309.462678)
		(end 201.962258 -308.500018)
		(width 0.1651)
		(layer "In5.Cu")
		(net "P5E_PEX1_STN4_RX_DP<67>")
	)
	(segment
		(start 200.55459 -307.915818)
		(end 199.774048 -307.915818)
		(width 0.1651)
		(layer "In5.Cu")
		(net "P5E_PEX1_STN4_RX_DP<67>")
	)
	(segment
		(start 205.086204 -312.105548)
		(end 205.086204 -312.105294)
		(width 0.1651)
		(layer "In5.Cu")
		(net "P5E_PEX1_STN4_RX_DP<67>")
	)
	(segment
		(start 201.1045 -344.388948)
		(end 201.057764 -344.234262)
		(width 0.1651)
		(layer "In5.Cu")
		(net "P5E_PEX1_STN4_RX_DP<67>")
	)
	(segment
		(start 175.767238 -365.649764)
		(end 186.89447 -363.403134)
		(width 0.1651)
		(layer "In5.Cu")
		(net "P5E_PEX1_STN4_RX_DP<67>")
	)
	(segment
		(start 205.086204 -312.105294)
		(end 203.182474 -310.204866)
		(width 0.1651)
		(layer "In5.Cu")
		(net "P5E_PEX1_STN4_RX_DP<67>")
	)
	(segment
		(start 199.69988 -307.870098)
		(end 196.305424 -307.870098)
		(width 0.1143)
		(layer "In5.Cu")
		(net "P5E_PEX1_STN4_RX_DP<67>")
	)
	(segment
		(start 200.528428 -345.463622)
		(end 200.481692 -345.308936)
		(width 0.1651)
		(layer "In5.Cu")
		(net "P5E_PEX1_STN4_RX_DP<67>")
	)
	(segment
		(start 201.057764 -344.234262)
		(end 201.291952 -343.797382)
		(width 0.1651)
		(layer "In5.Cu")
		(net "P5E_PEX1_STN4_RX_DP<67>")
	)
	(segment
		(start 195.965318 -307.299868)
		(end 195.699888 -307.299868)
		(width 0.1143)
		(layer "In5.Cu")
		(net "P5E_PEX1_STN4_RX_DP<67>")
	)
	(segment
		(start 202.022964 -342.675972)
		(end 211.356448 -325.265034)
		(width 0.1651)
		(layer "In5.Cu")
		(net "P5E_PEX1_STN4_RX_DP<67>")
	)
	(segment
		(start 196.231256 -352.903282)
		(end 196.387212 -352.861372)
		(width 0.1651)
		(layer "In5.Cu")
		(net "P5E_PEX1_STN4_RX_DP<67>")
	)
	(segment
		(start 201.446638 -343.750646)
		(end 201.680572 -343.31402)
		(width 0.1651)
		(layer "In5.Cu")
		(net "P5E_PEX1_STN4_RX_DP<67>")
	)
	(segment
		(start 195.983606 -353.332796)
		(end 196.231256 -352.903282)
		(width 0.1651)
		(layer "In5.Cu")
		(net "P5E_PEX1_STN4_RX_DP<67>")
	)
	(segment
		(start 199.952356 -346.538296)
		(end 199.90562 -346.38361)
		(width 0.1651)
		(layer "In5.Cu")
		(net "P5E_PEX1_STN4_RX_DP<67>")
	)
	(segment
		(start 208.930494 -315.25845)
		(end 206.965042 -313.981592)
		(width 0.1651)
		(layer "In5.Cu")
		(net "P5E_PEX1_STN4_RX_DP<67>")
	)
	(segment
		(start 201.446892 -343.750646)
		(end 201.446638 -343.750646)
		(width 0.1651)
		(layer "In5.Cu")
		(net "P5E_PEX1_STN4_RX_DP<67>")
	)
	(segment
		(start 196.387212 -352.861372)
		(end 196.634354 -352.432366)
		(width 0.1651)
		(layer "In5.Cu")
		(net "P5E_PEX1_STN4_RX_DP<67>")
	)
	(segment
		(start 197.201536 -351.21977)
		(end 197.449186 -350.79051)
		(width 0.1651)
		(layer "In5.Cu")
		(net "P5E_PEX1_STN4_RX_DP<67>")
	)
	(segment
		(start 201.680826 -343.314274)
		(end 201.63409 -343.159588)
		(width 0.1651)
		(layer "In5.Cu")
		(net "P5E_PEX1_STN4_RX_DP<67>")
	)
	(segment
		(start 206.965042 -313.981592)
		(end 205.086204 -312.105548)
		(width 0.1651)
		(layer "In5.Cu")
		(net "P5E_PEX1_STN4_RX_DP<67>")
	)
	(segment
		(start 196.305424 -307.870098)
		(end 196.079618 -307.644292)
		(width 0.1143)
		(layer "In5.Cu")
		(net "P5E_PEX1_STN4_RX_DP<67>")
	)
	(segment
		(start 169.487596 -369.411758)
		(end 170.129454 -368.568986)
		(width 0.1651)
		(layer "In5.Cu")
		(net "P5E_PEX1_STN4_RX_DP<67>")
	)
	(segment
		(start 191.19977 -360.337608)
		(end 195.364862 -354.635054)
		(width 0.1651)
		(layer "In5.Cu")
		(net "P5E_PEX1_STN4_RX_DP<67>")
	)
	(segment
		(start 201.680572 -343.31402)
		(end 201.680826 -343.314274)
		(width 0.1651)
		(layer "In5.Cu")
		(net "P5E_PEX1_STN4_RX_DP<67>")
	)
	(segment
		(start 168.710102 -378.67209)
		(end 168.837102 -378.79909)
		(width 0.1651)
		(layer "In5.Cu")
		(net "P5E_PEX1_STN4_RX_DP<67>")
	)
	(segment
		(start 169.487596 -378.581412)
		(end 169.487596 -369.411758)
		(width 0.1651)
		(layer "In5.Cu")
		(net "P5E_PEX1_STN4_RX_DP<67>")
	)
	(segment
		(start 172.209968 -367.03762)
		(end 174.708566 -365.977678)
		(width 0.1651)
		(layer "In5.Cu")
		(net "P5E_PEX1_STN4_RX_DP<67>")
	)
	(segment
		(start 168.710102 -378.290074)
		(end 168.710102 -378.67209)
		(width 0.1651)
		(layer "In5.Cu")
		(net "P5E_PEX1_STN4_RX_DP<67>")
	)
	(segment
		(start 170.129454 -368.568986)
		(end 170.494198 -368.204242)
		(width 0.1651)
		(layer "In5.Cu")
		(net "P5E_PEX1_STN4_RX_DP<67>")
	)
	(segment
		(start 196.079618 -307.644292)
		(end 196.079618 -307.414168)
		(width 0.1143)
		(layer "In5.Cu")
		(net "P5E_PEX1_STN4_RX_DP<67>")
	)
	(segment
		(start 211.356448 -325.265034)
		(end 212.09254 -321.59067)
		(width 0.1651)
		(layer "In5.Cu")
		(net "P5E_PEX1_STN4_RX_DP<67>")
	)
	(segment
		(start 196.592444 -352.276156)
		(end 196.840094 -351.846896)
		(width 0.1651)
		(layer "In5.Cu")
		(net "P5E_PEX1_STN4_RX_DP<67>")
	)
	(segment
		(start 212.09254 -319.800478)
		(end 211.165186 -317.536068)
		(width 0.1651)
		(layer "In5.Cu")
		(net "P5E_PEX1_STN4_RX_DP<67>")
	)
	(segment
		(start 199.7456 -307.915818)
		(end 199.69988 -307.870098)
		(width 0.1143)
		(layer "In5.Cu")
		(net "P5E_PEX1_STN4_RX_DP<67>")
	)
	(segment
		(start 197.604888 -350.7486)
		(end 198.894954 -348.51086)
		(width 0.1651)
		(layer "In5.Cu")
		(net "P5E_PEX1_STN4_RX_DP<67>")
	)
	(segment
		(start 201.291952 -343.797382)
		(end 201.446892 -343.750646)
		(width 0.1651)
		(layer "In5.Cu")
		(net "P5E_PEX1_STN4_RX_DP<67>")
	)
	(segment
		(start 169.269918 -378.79909)
		(end 169.487596 -378.581412)
		(width 0.1651)
		(layer "In5.Cu")
		(net "P5E_PEX1_STN4_RX_DP<67>")
	)
	(segment
		(start 174.916592 -351.316798)
		(end 174.916592 -350.685354)
		(width 0.13462)
		(layer "F.Cu")
		(net "P5E_PEX1_STN4_TX_C_DP<73>")
	)
	(segment
		(start 174.621952 -351.611438)
		(end 174.916592 -351.316798)
		(width 0.13462)
		(layer "F.Cu")
		(net "P5E_PEX1_STN4_TX_C_DP<73>")
	)
	(segment
		(start 174.916592 -350.685354)
		(end 174.596552 -350.365314)
		(width 0.13462)
		(layer "F.Cu")
		(net "P5E_PEX1_STN4_TX_C_DP<73>")
	)
	(segment
		(start 174.912782 -351.902268)
		(end 174.621952 -351.611438)
		(width 0.1651)
		(layer "In7.Cu")
		(net "P5E_PEX1_STN4_TX_C_DP<73>")
	)
	(segment
		(start 173.23689 -396.998952)
		(end 173.469046 -396.998952)
		(width 0.1651)
		(layer "In7.Cu")
		(net "P5E_PEX1_STN4_TX_C_DP<73>")
	)
	(segment
		(start 158.212536 -385.989322)
		(end 157.4673 -384.190494)
		(width 0.1651)
		(layer "In7.Cu")
		(net "P5E_PEX1_STN4_TX_C_DP<73>")
	)
	(segment
		(start 171.674028 -393.379706)
		(end 171.262548 -393.10437)
		(width 0.1651)
		(layer "In7.Cu")
		(net "P5E_PEX1_STN4_TX_C_DP<73>")
	)
	(segment
		(start 170.702732 -392.729974)
		(end 169.418 -391.870946)
		(width 0.1651)
		(layer "In7.Cu")
		(net "P5E_PEX1_STN4_TX_C_DP<73>")
	)
	(segment
		(start 158.918402 -386.695696)
		(end 158.212536 -385.989322)
		(width 0.1651)
		(layer "In7.Cu")
		(net "P5E_PEX1_STN4_TX_C_DP<73>")
	)
	(segment
		(start 173.469046 -396.998952)
		(end 173.887384 -396.580614)
		(width 0.1651)
		(layer "In7.Cu")
		(net "P5E_PEX1_STN4_TX_C_DP<73>")
	)
	(segment
		(start 173.887384 -396.580614)
		(end 173.887384 -394.922756)
		(width 0.1651)
		(layer "In7.Cu")
		(net "P5E_PEX1_STN4_TX_C_DP<73>")
	)
	(segment
		(start 172.23359 -393.754102)
		(end 172.1104 -393.77874)
		(width 0.1651)
		(layer "In7.Cu")
		(net "P5E_PEX1_STN4_TX_C_DP<73>")
	)
	(segment
		(start 173.887384 -394.922756)
		(end 173.557946 -394.6398)
		(width 0.1651)
		(layer "In7.Cu")
		(net "P5E_PEX1_STN4_TX_C_DP<73>")
	)
	(segment
		(start 171.262548 -393.10437)
		(end 171.139104 -393.129008)
		(width 0.1651)
		(layer "In7.Cu")
		(net "P5E_PEX1_STN4_TX_C_DP<73>")
	)
	(segment
		(start 171.698412 -393.50315)
		(end 171.674028 -393.379706)
		(width 0.1651)
		(layer "In7.Cu")
		(net "P5E_PEX1_STN4_TX_C_DP<73>")
	)
	(segment
		(start 171.139104 -393.129008)
		(end 170.727116 -392.853418)
		(width 0.1651)
		(layer "In7.Cu")
		(net "P5E_PEX1_STN4_TX_C_DP<73>")
	)
	(segment
		(start 173.557946 -394.6398)
		(end 172.23359 -393.754102)
		(width 0.1651)
		(layer "In7.Cu")
		(net "P5E_PEX1_STN4_TX_C_DP<73>")
	)
	(segment
		(start 159.049212 -367.048796)
		(end 162.68319 -364.535974)
		(width 0.1651)
		(layer "In7.Cu")
		(net "P5E_PEX1_STN4_TX_C_DP<73>")
	)
	(segment
		(start 171.890944 -360.689144)
		(end 173.358302 -359.221786)
		(width 0.1651)
		(layer "In7.Cu")
		(net "P5E_PEX1_STN4_TX_C_DP<73>")
	)
	(segment
		(start 157.4673 -384.190494)
		(end 157.4673 -369.898168)
		(width 0.1651)
		(layer "In7.Cu")
		(net "P5E_PEX1_STN4_TX_C_DP<73>")
	)
	(segment
		(start 170.727116 -392.853418)
		(end 170.702732 -392.729974)
		(width 0.1651)
		(layer "In7.Cu")
		(net "P5E_PEX1_STN4_TX_C_DP<73>")
	)
	(segment
		(start 173.358302 -359.221786)
		(end 173.358302 -354.098098)
		(width 0.1651)
		(layer "In7.Cu")
		(net "P5E_PEX1_STN4_TX_C_DP<73>")
	)
	(segment
		(start 174.912782 -352.543618)
		(end 174.912782 -351.902268)
		(width 0.1651)
		(layer "In7.Cu")
		(net "P5E_PEX1_STN4_TX_C_DP<73>")
	)
	(segment
		(start 158.164022 -368.304826)
		(end 159.049212 -367.048796)
		(width 0.1651)
		(layer "In7.Cu")
		(net "P5E_PEX1_STN4_TX_C_DP<73>")
	)
	(segment
		(start 173.10989 -396.49019)
		(end 173.10989 -396.871952)
		(width 0.1651)
		(layer "In7.Cu")
		(net "P5E_PEX1_STN4_TX_C_DP<73>")
	)
	(segment
		(start 157.4673 -369.898168)
		(end 158.164022 -368.304826)
		(width 0.1651)
		(layer "In7.Cu")
		(net "P5E_PEX1_STN4_TX_C_DP<73>")
	)
	(segment
		(start 162.68319 -364.535974)
		(end 171.890944 -360.689144)
		(width 0.1651)
		(layer "In7.Cu")
		(net "P5E_PEX1_STN4_TX_C_DP<73>")
	)
	(segment
		(start 173.10989 -396.871952)
		(end 173.23689 -396.998952)
		(width 0.1651)
		(layer "In7.Cu")
		(net "P5E_PEX1_STN4_TX_C_DP<73>")
	)
	(segment
		(start 172.1104 -393.77874)
		(end 171.698412 -393.50315)
		(width 0.1651)
		(layer "In7.Cu")
		(net "P5E_PEX1_STN4_TX_C_DP<73>")
	)
	(segment
		(start 169.418 -391.870946)
		(end 162.738562 -388.30123)
		(width 0.1651)
		(layer "In7.Cu")
		(net "P5E_PEX1_STN4_TX_C_DP<73>")
	)
	(segment
		(start 173.358302 -354.098098)
		(end 174.912782 -352.543618)
		(width 0.1651)
		(layer "In7.Cu")
		(net "P5E_PEX1_STN4_TX_C_DP<73>")
	)
	(segment
		(start 162.738562 -388.30123)
		(end 158.918402 -386.695696)
		(width 0.1651)
		(layer "In7.Cu")
		(net "P5E_PEX1_STN4_TX_C_DP<73>")
	)
	(segment
		(start 190.461392 -345.170506)
		(end 190.461392 -344.539062)
		(width 0.13462)
		(layer "F.Cu")
		(net "P5E_PEX1_STN4_TX_C_DP<66>")
	)
	(segment
		(start 190.461392 -344.539062)
		(end 190.141352 -344.219022)
		(width 0.13462)
		(layer "F.Cu")
		(net "P5E_PEX1_STN4_TX_C_DP<66>")
	)
	(segment
		(start 190.166752 -345.465146)
		(end 190.461392 -345.170506)
		(width 0.13462)
		(layer "F.Cu")
		(net "P5E_PEX1_STN4_TX_C_DP<66>")
	)
	(segment
		(start 184.225184 -362.400342)
		(end 184.064402 -362.38434)
		(width 0.1651)
		(layer "In7.Cu")
		(net "P5E_PEX1_STN4_TX_C_DP<66>")
	)
	(segment
		(start 185.169302 -361.62869)
		(end 185.00852 -361.612434)
		(width 0.1651)
		(layer "In7.Cu")
		(net "P5E_PEX1_STN4_TX_C_DP<66>")
	)
	(segment
		(start 185.952384 -360.840782)
		(end 185.568844 -361.154472)
		(width 0.1651)
		(layer "In7.Cu")
		(net "P5E_PEX1_STN4_TX_C_DP<66>")
	)
	(segment
		(start 171.68749 -371.680486)
		(end 171.269152 -372.098824)
		(width 0.1651)
		(layer "In7.Cu")
		(net "P5E_PEX1_STN4_TX_C_DP<66>")
	)
	(segment
		(start 172.08373 -368.767868)
		(end 171.68749 -369.4938)
		(width 0.1651)
		(layer "In7.Cu")
		(net "P5E_PEX1_STN4_TX_C_DP<66>")
	)
	(segment
		(start 186.896756 -360.068876)
		(end 186.512962 -360.382566)
		(width 0.1651)
		(layer "In7.Cu")
		(net "P5E_PEX1_STN4_TX_C_DP<66>")
	)
	(segment
		(start 187.057538 -360.084878)
		(end 186.896756 -360.068876)
		(width 0.1651)
		(layer "In7.Cu")
		(net "P5E_PEX1_STN4_TX_C_DP<66>")
	)
	(segment
		(start 188.277754 -359.08742)
		(end 187.057538 -360.084878)
		(width 0.1651)
		(layer "In7.Cu")
		(net "P5E_PEX1_STN4_TX_C_DP<66>")
	)
	(segment
		(start 184.064402 -362.38434)
		(end 183.680608 -362.69803)
		(width 0.1651)
		(layer "In7.Cu")
		(net "P5E_PEX1_STN4_TX_C_DP<66>")
	)
	(segment
		(start 190.457582 -345.755976)
		(end 190.457582 -346.295218)
		(width 0.1651)
		(layer "In7.Cu")
		(net "P5E_PEX1_STN4_TX_C_DP<66>")
	)
	(segment
		(start 186.11342 -360.856784)
		(end 185.952384 -360.840782)
		(width 0.1651)
		(layer "In7.Cu")
		(net "P5E_PEX1_STN4_TX_C_DP<66>")
	)
	(segment
		(start 182.720234 -363.630464)
		(end 182.0418 -364.1852)
		(width 0.1651)
		(layer "In7.Cu")
		(net "P5E_PEX1_STN4_TX_C_DP<66>")
	)
	(segment
		(start 188.903102 -347.849698)
		(end 188.903102 -358.462072)
		(width 0.1651)
		(layer "In7.Cu")
		(net "P5E_PEX1_STN4_TX_C_DP<66>")
	)
	(segment
		(start 185.00852 -361.612434)
		(end 184.624726 -361.926124)
		(width 0.1651)
		(layer "In7.Cu")
		(net "P5E_PEX1_STN4_TX_C_DP<66>")
	)
	(segment
		(start 184.60847 -362.086906)
		(end 184.225184 -362.400342)
		(width 0.1651)
		(layer "In7.Cu")
		(net "P5E_PEX1_STN4_TX_C_DP<66>")
	)
	(segment
		(start 183.680608 -362.69803)
		(end 183.664352 -362.858812)
		(width 0.1651)
		(layer "In7.Cu")
		(net "P5E_PEX1_STN4_TX_C_DP<66>")
	)
	(segment
		(start 171.68749 -369.4938)
		(end 171.68749 -371.680486)
		(width 0.1651)
		(layer "In7.Cu")
		(net "P5E_PEX1_STN4_TX_C_DP<66>")
	)
	(segment
		(start 190.457582 -346.295218)
		(end 188.903102 -347.849698)
		(width 0.1651)
		(layer "In7.Cu")
		(net "P5E_PEX1_STN4_TX_C_DP<66>")
	)
	(segment
		(start 183.281066 -363.172248)
		(end 183.120284 -363.155992)
		(width 0.1651)
		(layer "In7.Cu")
		(net "P5E_PEX1_STN4_TX_C_DP<66>")
	)
	(segment
		(start 184.624726 -361.926124)
		(end 184.60847 -362.086906)
		(width 0.1651)
		(layer "In7.Cu")
		(net "P5E_PEX1_STN4_TX_C_DP<66>")
	)
	(segment
		(start 170.909996 -371.971824)
		(end 170.909996 -371.590062)
		(width 0.1651)
		(layer "In7.Cu")
		(net "P5E_PEX1_STN4_TX_C_DP<66>")
	)
	(segment
		(start 190.166752 -345.465146)
		(end 190.457582 -345.755976)
		(width 0.1651)
		(layer "In7.Cu")
		(net "P5E_PEX1_STN4_TX_C_DP<66>")
	)
	(segment
		(start 173.299628 -367.713768)
		(end 172.08373 -368.767868)
		(width 0.1651)
		(layer "In7.Cu")
		(net "P5E_PEX1_STN4_TX_C_DP<66>")
	)
	(segment
		(start 182.73649 -363.469682)
		(end 182.720234 -363.630464)
		(width 0.1651)
		(layer "In7.Cu")
		(net "P5E_PEX1_STN4_TX_C_DP<66>")
	)
	(segment
		(start 171.269152 -372.098824)
		(end 171.036996 -372.098824)
		(width 0.1651)
		(layer "In7.Cu")
		(net "P5E_PEX1_STN4_TX_C_DP<66>")
	)
	(segment
		(start 186.512962 -360.382566)
		(end 186.496706 -360.543348)
		(width 0.1651)
		(layer "In7.Cu")
		(net "P5E_PEX1_STN4_TX_C_DP<66>")
	)
	(segment
		(start 188.903102 -358.462072)
		(end 188.277754 -359.08742)
		(width 0.1651)
		(layer "In7.Cu")
		(net "P5E_PEX1_STN4_TX_C_DP<66>")
	)
	(segment
		(start 185.552588 -361.315254)
		(end 185.169302 -361.62869)
		(width 0.1651)
		(layer "In7.Cu")
		(net "P5E_PEX1_STN4_TX_C_DP<66>")
	)
	(segment
		(start 185.568844 -361.154472)
		(end 185.552588 -361.315254)
		(width 0.1651)
		(layer "In7.Cu")
		(net "P5E_PEX1_STN4_TX_C_DP<66>")
	)
	(segment
		(start 186.496706 -360.543348)
		(end 186.11342 -360.856784)
		(width 0.1651)
		(layer "In7.Cu")
		(net "P5E_PEX1_STN4_TX_C_DP<66>")
	)
	(segment
		(start 171.036996 -372.098824)
		(end 170.909996 -371.971824)
		(width 0.1651)
		(layer "In7.Cu")
		(net "P5E_PEX1_STN4_TX_C_DP<66>")
	)
	(segment
		(start 183.664352 -362.858812)
		(end 183.281066 -363.172248)
		(width 0.1651)
		(layer "In7.Cu")
		(net "P5E_PEX1_STN4_TX_C_DP<66>")
	)
	(segment
		(start 182.0418 -364.1852)
		(end 173.299628 -367.713768)
		(width 0.1651)
		(layer "In7.Cu")
		(net "P5E_PEX1_STN4_TX_C_DP<66>")
	)
	(segment
		(start 183.120284 -363.155992)
		(end 182.73649 -363.469682)
		(width 0.1651)
		(layer "In7.Cu")
		(net "P5E_PEX1_STN4_TX_C_DP<66>")
	)
	(segment
		(start 172.081952 -356.831646)
		(end 172.401992 -356.511606)
		(width 0.13462)
		(layer "F.Cu")
		(net "P5E_PEX1_STN4_TX_C_DN<74>")
	)
	(segment
		(start 172.376592 -357.75773)
		(end 172.081952 -357.46309)
		(width 0.13462)
		(layer "F.Cu")
		(net "P5E_PEX1_STN4_TX_C_DN<74>")
	)
	(segment
		(start 172.081952 -357.46309)
		(end 172.081952 -356.831646)
		(width 0.13462)
		(layer "F.Cu")
		(net "P5E_PEX1_STN4_TX_C_DN<74>")
	)
	(segment
		(start 171.96943 -395.365478)
		(end 169.64787 -393.043918)
		(width 0.1651)
		(layer "In7.Cu")
		(net "P5E_PEX1_STN4_TX_C_DN<74>")
	)
	(segment
		(start 171.96943 -397.797528)
		(end 171.96943 -395.365478)
		(width 0.1651)
		(layer "In7.Cu")
		(net "P5E_PEX1_STN4_TX_C_DN<74>")
	)
	(segment
		(start 156.7942 -369.716812)
		(end 156.837888 -369.50777)
		(width 0.1651)
		(layer "In7.Cu")
		(net "P5E_PEX1_STN4_TX_C_DN<74>")
	)
	(segment
		(start 170.909996 -398.50822)
		(end 171.03725 -398.380966)
		(width 0.1651)
		(layer "In7.Cu")
		(net "P5E_PEX1_STN4_TX_C_DN<74>")
	)
	(segment
		(start 164.89172 -390.24306)
		(end 161.741358 -388.61746)
		(width 0.1651)
		(layer "In7.Cu")
		(net "P5E_PEX1_STN4_TX_C_DN<74>")
	)
	(segment
		(start 157.642052 -386.371084)
		(end 156.7942 -384.325114)
		(width 0.1651)
		(layer "In7.Cu")
		(net "P5E_PEX1_STN4_TX_C_DN<74>")
	)
	(segment
		(start 156.837888 -369.50777)
		(end 157.500066 -367.992914)
		(width 0.1651)
		(layer "In7.Cu")
		(net "P5E_PEX1_STN4_TX_C_DN<74>")
	)
	(segment
		(start 171.03725 -398.380966)
		(end 171.385992 -398.380966)
		(width 0.1651)
		(layer "In7.Cu")
		(net "P5E_PEX1_STN4_TX_C_DN<74>")
	)
	(segment
		(start 170.909996 -398.890236)
		(end 170.909996 -398.50822)
		(width 0.1651)
		(layer "In7.Cu")
		(net "P5E_PEX1_STN4_TX_C_DN<74>")
	)
	(segment
		(start 158.45155 -366.643666)
		(end 162.358324 -363.941868)
		(width 0.1651)
		(layer "In7.Cu")
		(net "P5E_PEX1_STN4_TX_C_DN<74>")
	)
	(segment
		(start 172.085762 -358.04856)
		(end 172.376592 -357.75773)
		(width 0.1651)
		(layer "In7.Cu")
		(net "P5E_PEX1_STN4_TX_C_DN<74>")
	)
	(segment
		(start 171.385992 -398.380966)
		(end 171.96943 -397.797528)
		(width 0.1651)
		(layer "In7.Cu")
		(net "P5E_PEX1_STN4_TX_C_DN<74>")
	)
	(segment
		(start 162.358324 -363.941868)
		(end 170.729656 -360.444796)
		(width 0.1651)
		(layer "In7.Cu")
		(net "P5E_PEX1_STN4_TX_C_DN<74>")
	)
	(segment
		(start 157.500066 -367.992914)
		(end 158.45155 -366.643666)
		(width 0.1651)
		(layer "In7.Cu")
		(net "P5E_PEX1_STN4_TX_C_DN<74>")
	)
	(segment
		(start 161.741358 -388.61746)
		(end 158.771082 -387.36905)
		(width 0.1651)
		(layer "In7.Cu")
		(net "P5E_PEX1_STN4_TX_C_DN<74>")
	)
	(segment
		(start 158.771082 -387.36905)
		(end 158.52775 -387.257036)
		(width 0.1651)
		(layer "In7.Cu")
		(net "P5E_PEX1_STN4_TX_C_DN<74>")
	)
	(segment
		(start 170.729656 -360.444796)
		(end 172.085762 -359.072942)
		(width 0.1651)
		(layer "In7.Cu")
		(net "P5E_PEX1_STN4_TX_C_DN<74>")
	)
	(segment
		(start 169.64787 -393.043918)
		(end 164.89172 -390.24306)
		(width 0.1651)
		(layer "In7.Cu")
		(net "P5E_PEX1_STN4_TX_C_DN<74>")
	)
	(segment
		(start 158.52775 -387.257036)
		(end 157.642052 -386.371084)
		(width 0.1651)
		(layer "In7.Cu")
		(net "P5E_PEX1_STN4_TX_C_DN<74>")
	)
	(segment
		(start 172.085762 -359.072942)
		(end 172.085762 -358.04856)
		(width 0.1651)
		(layer "In7.Cu")
		(net "P5E_PEX1_STN4_TX_C_DN<74>")
	)
	(segment
		(start 156.7942 -384.325114)
		(end 156.7942 -369.716812)
		(width 0.1651)
		(layer "In7.Cu")
		(net "P5E_PEX1_STN4_TX_C_DN<74>")
	)
	(segment
		(start 195.585588 -316.229492)
		(end 195.699888 -316.115192)
		(width 0.1143)
		(layer "In5.Cu")
		(net "P5E_PEX1_STN4_RX_DP<73>")
	)
	(segment
		(start 162.545014 -364.833154)
		(end 171.210478 -361.022392)
		(width 0.1651)
		(layer "In5.Cu")
		(net "P5E_PEX1_STN4_RX_DP<73>")
	)
	(segment
		(start 171.260516 -393.103354)
		(end 170.85945 -392.83513)
		(width 0.1651)
		(layer "In5.Cu")
		(net "P5E_PEX1_STN4_RX_DP<73>")
	)
	(segment
		(start 195.355464 -316.229492)
		(end 195.585588 -316.229492)
		(width 0.1143)
		(layer "In5.Cu")
		(net "P5E_PEX1_STN4_RX_DP<73>")
	)
	(segment
		(start 170.272202 -392.442192)
		(end 169.418 -391.870946)
		(width 0.1651)
		(layer "In5.Cu")
		(net "P5E_PEX1_STN4_RX_DP<73>")
	)
	(segment
		(start 195.083938 -320.0908)
		(end 195.129658 -320.04508)
		(width 0.1143)
		(layer "In5.Cu")
		(net "P5E_PEX1_STN4_RX_DP<73>")
	)
	(segment
		(start 195.129658 -320.04508)
		(end 195.129658 -316.455298)
		(width 0.1143)
		(layer "In5.Cu")
		(net "P5E_PEX1_STN4_RX_DP<73>")
	)
	(segment
		(start 162.738562 -388.30123)
		(end 158.918148 -386.695696)
		(width 0.1651)
		(layer "In5.Cu")
		(net "P5E_PEX1_STN4_RX_DP<73>")
	)
	(segment
		(start 179.576222 -341.83574)
		(end 180.975254 -339.27542)
		(width 0.1651)
		(layer "In5.Cu")
		(net "P5E_PEX1_STN4_RX_DP<73>")
	)
	(segment
		(start 179.576222 -358.522778)
		(end 179.576222 -341.83574)
		(width 0.1651)
		(layer "In5.Cu")
		(net "P5E_PEX1_STN4_RX_DP<73>")
	)
	(segment
		(start 170.30319 -392.597386)
		(end 170.272202 -392.442192)
		(width 0.1651)
		(layer "In5.Cu")
		(net "P5E_PEX1_STN4_RX_DP<73>")
	)
	(segment
		(start 195.083938 -320.119248)
		(end 195.083938 -320.0908)
		(width 0.1143)
		(layer "In5.Cu")
		(net "P5E_PEX1_STN4_RX_DP<73>")
	)
	(segment
		(start 171.69257 -393.526772)
		(end 171.29125 -393.258294)
		(width 0.1651)
		(layer "In5.Cu")
		(net "P5E_PEX1_STN4_RX_DP<73>")
	)
	(segment
		(start 173.10989 -404.290022)
		(end 173.10989 -404.672038)
		(width 0.1651)
		(layer "In5.Cu")
		(net "P5E_PEX1_STN4_RX_DP<73>")
	)
	(segment
		(start 170.70451 -392.865864)
		(end 170.30319 -392.597386)
		(width 0.1651)
		(layer "In5.Cu")
		(net "P5E_PEX1_STN4_RX_DP<73>")
	)
	(segment
		(start 158.918148 -386.695696)
		(end 158.21279 -385.98983)
		(width 0.1651)
		(layer "In5.Cu")
		(net "P5E_PEX1_STN4_RX_DP<73>")
	)
	(segment
		(start 195.083938 -321.985894)
		(end 195.083938 -320.119248)
		(width 0.1651)
		(layer "In5.Cu")
		(net "P5E_PEX1_STN4_RX_DP<73>")
	)
	(segment
		(start 195.699888 -316.115192)
		(end 195.699888 -315.849762)
		(width 0.1143)
		(layer "In5.Cu")
		(net "P5E_PEX1_STN4_RX_DP<73>")
	)
	(segment
		(start 172.24883 -393.764262)
		(end 171.847764 -393.496038)
		(width 0.1651)
		(layer "In5.Cu")
		(net "P5E_PEX1_STN4_RX_DP<73>")
	)
	(segment
		(start 173.23689 -404.799038)
		(end 173.669706 -404.799038)
		(width 0.1651)
		(layer "In5.Cu")
		(net "P5E_PEX1_STN4_RX_DP<73>")
	)
	(segment
		(start 158.910782 -367.453164)
		(end 162.545014 -364.833154)
		(width 0.1651)
		(layer "In5.Cu")
		(net "P5E_PEX1_STN4_RX_DP<73>")
	)
	(segment
		(start 195.129658 -316.455298)
		(end 195.355464 -316.229492)
		(width 0.1143)
		(layer "In5.Cu")
		(net "P5E_PEX1_STN4_RX_DP<73>")
	)
	(segment
		(start 175.047402 -359.833672)
		(end 179.082192 -359.016808)
		(width 0.1651)
		(layer "In5.Cu")
		(net "P5E_PEX1_STN4_RX_DP<73>")
	)
	(segment
		(start 170.85945 -392.83513)
		(end 170.70451 -392.865864)
		(width 0.1651)
		(layer "In5.Cu")
		(net "P5E_PEX1_STN4_RX_DP<73>")
	)
	(segment
		(start 171.847764 -393.496038)
		(end 171.69257 -393.526772)
		(width 0.1651)
		(layer "In5.Cu")
		(net "P5E_PEX1_STN4_RX_DP<73>")
	)
	(segment
		(start 190.72479 -329.42403)
		(end 192.560956 -327.304146)
		(width 0.1651)
		(layer "In5.Cu")
		(net "P5E_PEX1_STN4_RX_DP<73>")
	)
	(segment
		(start 194.06235 -325.18985)
		(end 195.083938 -321.985894)
		(width 0.1651)
		(layer "In5.Cu")
		(net "P5E_PEX1_STN4_RX_DP<73>")
	)
	(segment
		(start 180.975254 -339.27542)
		(end 190.72479 -329.42403)
		(width 0.1651)
		(layer "In5.Cu")
		(net "P5E_PEX1_STN4_RX_DP<73>")
	)
	(segment
		(start 179.082192 -359.016808)
		(end 179.576222 -358.522778)
		(width 0.1651)
		(layer "In5.Cu")
		(net "P5E_PEX1_STN4_RX_DP<73>")
	)
	(segment
		(start 157.4673 -369.58778)
		(end 157.915102 -368.448844)
		(width 0.1651)
		(layer "In5.Cu")
		(net "P5E_PEX1_STN4_RX_DP<73>")
	)
	(segment
		(start 173.887384 -394.92301)
		(end 173.557946 -394.6398)
		(width 0.1651)
		(layer "In5.Cu")
		(net "P5E_PEX1_STN4_RX_DP<73>")
	)
	(segment
		(start 172.836078 -394.156946)
		(end 172.706792 -394.1826)
		(width 0.1651)
		(layer "In5.Cu")
		(net "P5E_PEX1_STN4_RX_DP<73>")
	)
	(segment
		(start 173.10989 -404.672038)
		(end 173.23689 -404.799038)
		(width 0.1651)
		(layer "In5.Cu")
		(net "P5E_PEX1_STN4_RX_DP<73>")
	)
	(segment
		(start 173.887384 -404.58136)
		(end 173.887384 -394.92301)
		(width 0.1651)
		(layer "In5.Cu")
		(net "P5E_PEX1_STN4_RX_DP<73>")
	)
	(segment
		(start 169.418 -391.870946)
		(end 162.738562 -388.30123)
		(width 0.1651)
		(layer "In5.Cu")
		(net "P5E_PEX1_STN4_RX_DP<73>")
	)
	(segment
		(start 173.557946 -394.6398)
		(end 172.836078 -394.156946)
		(width 0.1651)
		(layer "In5.Cu")
		(net "P5E_PEX1_STN4_RX_DP<73>")
	)
	(segment
		(start 192.560956 -327.304146)
		(end 194.06235 -325.18985)
		(width 0.1651)
		(layer "In5.Cu")
		(net "P5E_PEX1_STN4_RX_DP<73>")
	)
	(segment
		(start 157.4673 -384.190494)
		(end 157.4673 -369.58778)
		(width 0.1651)
		(layer "In5.Cu")
		(net "P5E_PEX1_STN4_RX_DP<73>")
	)
	(segment
		(start 158.21279 -385.98983)
		(end 157.4673 -384.190494)
		(width 0.1651)
		(layer "In5.Cu")
		(net "P5E_PEX1_STN4_RX_DP<73>")
	)
	(segment
		(start 171.210478 -361.022392)
		(end 175.047402 -359.833672)
		(width 0.1651)
		(layer "In5.Cu")
		(net "P5E_PEX1_STN4_RX_DP<73>")
	)
	(segment
		(start 173.669706 -404.799038)
		(end 173.887384 -404.58136)
		(width 0.1651)
		(layer "In5.Cu")
		(net "P5E_PEX1_STN4_RX_DP<73>")
	)
	(segment
		(start 172.274484 -393.893294)
		(end 172.24883 -393.764262)
		(width 0.1651)
		(layer "In5.Cu")
		(net "P5E_PEX1_STN4_RX_DP<73>")
	)
	(segment
		(start 157.915102 -368.448844)
		(end 158.910782 -367.453164)
		(width 0.1651)
		(layer "In5.Cu")
		(net "P5E_PEX1_STN4_RX_DP<73>")
	)
	(segment
		(start 171.29125 -393.258294)
		(end 171.260516 -393.103354)
		(width 0.1651)
		(layer "In5.Cu")
		(net "P5E_PEX1_STN4_RX_DP<73>")
	)
	(segment
		(start 172.706792 -394.1826)
		(end 172.274484 -393.893294)
		(width 0.1651)
		(layer "In5.Cu")
		(net "P5E_PEX1_STN4_RX_DP<73>")
	)
	(segment
		(start 199.7202 -304.783744)
		(end 199.67448 -304.829464)
		(width 0.1143)
		(layer "In5.Cu")
		(net "P5E_PEX1_STN4_RX_DN<64>")
	)
	(segment
		(start 204.826616 -306.205636)
		(end 201.3966 -304.78476)
		(width 0.1651)
		(layer "In5.Cu")
		(net "P5E_PEX1_STN4_RX_DN<64>")
	)
	(segment
		(start 215.2396 -319.1764)
		(end 213.46668 -314.8457)
		(width 0.1651)
		(layer "In5.Cu")
		(net "P5E_PEX1_STN4_RX_DN<64>")
	)
	(segment
		(start 214.331042 -326.564498)
		(end 215.2396 -322.0212)
		(width 0.1651)
		(layer "In5.Cu")
		(net "P5E_PEX1_STN4_RX_DN<64>")
	)
	(segment
		(start 188.210698 -366.349534)
		(end 191.570102 -364.612174)
		(width 0.1651)
		(layer "In5.Cu")
		(net "P5E_PEX1_STN4_RX_DN<64>")
	)
	(segment
		(start 199.67448 -304.829464)
		(end 198.284592 -304.829464)
		(width 0.1143)
		(layer "In5.Cu")
		(net "P5E_PEX1_STN4_RX_DN<64>")
	)
	(segment
		(start 175.310038 -380.308104)
		(end 175.437038 -380.181104)
		(width 0.1651)
		(layer "In5.Cu")
		(net "P5E_PEX1_STN4_RX_DN<64>")
	)
	(segment
		(start 198.170292 -304.715164)
		(end 198.170292 -304.564034)
		(width 0.1143)
		(layer "In5.Cu")
		(net "P5E_PEX1_STN4_RX_DN<64>")
	)
	(segment
		(start 213.46668 -314.8457)
		(end 204.826616 -306.205636)
		(width 0.1651)
		(layer "In5.Cu")
		(net "P5E_PEX1_STN4_RX_DN<64>")
	)
	(segment
		(start 201.395584 -304.783744)
		(end 199.748648 -304.783744)
		(width 0.1651)
		(layer "In5.Cu")
		(net "P5E_PEX1_STN4_RX_DN<64>")
	)
	(segment
		(start 199.748648 -304.783744)
		(end 199.7202 -304.783744)
		(width 0.1143)
		(layer "In5.Cu")
		(net "P5E_PEX1_STN4_RX_DN<64>")
	)
	(segment
		(start 176.369472 -379.798326)
		(end 176.369472 -369.316508)
		(width 0.1651)
		(layer "In5.Cu")
		(net "P5E_PEX1_STN4_RX_DN<64>")
	)
	(segment
		(start 177.086514 -368.599466)
		(end 188.210698 -366.349534)
		(width 0.1651)
		(layer "In5.Cu")
		(net "P5E_PEX1_STN4_RX_DN<64>")
	)
	(segment
		(start 175.310038 -380.69012)
		(end 175.310038 -380.308104)
		(width 0.1651)
		(layer "In5.Cu")
		(net "P5E_PEX1_STN4_RX_DN<64>")
	)
	(segment
		(start 198.284592 -304.449734)
		(end 198.550022 -304.449734)
		(width 0.1143)
		(layer "In5.Cu")
		(net "P5E_PEX1_STN4_RX_DN<64>")
	)
	(segment
		(start 215.2396 -322.0212)
		(end 215.2396 -319.1764)
		(width 0.1651)
		(layer "In5.Cu")
		(net "P5E_PEX1_STN4_RX_DN<64>")
	)
	(segment
		(start 200.608692 -354.676202)
		(end 214.331042 -326.564498)
		(width 0.1651)
		(layer "In5.Cu")
		(net "P5E_PEX1_STN4_RX_DN<64>")
	)
	(segment
		(start 198.284592 -304.829464)
		(end 198.170292 -304.715164)
		(width 0.1143)
		(layer "In5.Cu")
		(net "P5E_PEX1_STN4_RX_DN<64>")
	)
	(segment
		(start 197.565772 -358.54386)
		(end 200.608692 -354.676202)
		(width 0.1651)
		(layer "In5.Cu")
		(net "P5E_PEX1_STN4_RX_DN<64>")
	)
	(segment
		(start 198.170292 -304.564034)
		(end 198.284592 -304.449734)
		(width 0.1143)
		(layer "In5.Cu")
		(net "P5E_PEX1_STN4_RX_DN<64>")
	)
	(segment
		(start 176.369472 -369.316508)
		(end 177.086514 -368.599466)
		(width 0.1651)
		(layer "In5.Cu")
		(net "P5E_PEX1_STN4_RX_DN<64>")
	)
	(segment
		(start 175.986694 -380.181104)
		(end 176.369472 -379.798326)
		(width 0.1651)
		(layer "In5.Cu")
		(net "P5E_PEX1_STN4_RX_DN<64>")
	)
	(segment
		(start 201.3966 -304.78476)
		(end 201.395584 -304.783744)
		(width 0.1651)
		(layer "In5.Cu")
		(net "P5E_PEX1_STN4_RX_DN<64>")
	)
	(segment
		(start 191.570102 -364.612174)
		(end 197.565772 -358.54386)
		(width 0.1651)
		(layer "In5.Cu")
		(net "P5E_PEX1_STN4_RX_DN<64>")
	)
	(segment
		(start 175.437038 -380.181104)
		(end 175.986694 -380.181104)
		(width 0.1651)
		(layer "In5.Cu")
		(net "P5E_PEX1_STN4_RX_DN<64>")
	)
	(segment
		(start 178.025552 -345.170506)
		(end 178.025552 -344.539062)
		(width 0.13462)
		(layer "F.Cu")
		(net "P5E_PEX1_STN4_TX_C_DP<72>")
	)
	(segment
		(start 177.730912 -345.465146)
		(end 178.025552 -345.170506)
		(width 0.13462)
		(layer "F.Cu")
		(net "P5E_PEX1_STN4_TX_C_DP<72>")
	)
	(segment
		(start 178.025552 -344.539062)
		(end 177.705512 -344.219022)
		(width 0.13462)
		(layer "F.Cu")
		(net "P5E_PEX1_STN4_TX_C_DP<72>")
	)
	(segment
		(start 174.0535 -393.7127)
		(end 173.212252 -393.149074)
		(width 0.1651)
		(layer "In7.Cu")
		(net "P5E_PEX1_STN4_TX_C_DP<72>")
	)
	(segment
		(start 159.020002 -385.410456)
		(end 158.42234 -383.999994)
		(width 0.1651)
		(layer "In7.Cu")
		(net "P5E_PEX1_STN4_TX_C_DP<72>")
	)
	(segment
		(start 176.467262 -347.941138)
		(end 178.021742 -346.386658)
		(width 0.1651)
		(layer "In7.Cu")
		(net "P5E_PEX1_STN4_TX_C_DP<72>")
	)
	(segment
		(start 158.42234 -383.999994)
		(end 158.42234 -370.200936)
		(width 0.1651)
		(layer "In7.Cu")
		(net "P5E_PEX1_STN4_TX_C_DP<72>")
	)
	(segment
		(start 175.310038 -397.59001)
		(end 175.310038 -397.972026)
		(width 0.1651)
		(layer "In7.Cu")
		(net "P5E_PEX1_STN4_TX_C_DP<72>")
	)
	(segment
		(start 176.087532 -395.746732)
		(end 174.0535 -393.7127)
		(width 0.1651)
		(layer "In7.Cu")
		(net "P5E_PEX1_STN4_TX_C_DP<72>")
	)
	(segment
		(start 178.021742 -345.755976)
		(end 177.730912 -345.465146)
		(width 0.1651)
		(layer "In7.Cu")
		(net "P5E_PEX1_STN4_TX_C_DP<72>")
	)
	(segment
		(start 175.437038 -398.099026)
		(end 175.669194 -398.099026)
		(width 0.1651)
		(layer "In7.Cu")
		(net "P5E_PEX1_STN4_TX_C_DP<72>")
	)
	(segment
		(start 172.11802 -392.522964)
		(end 171.706286 -392.24712)
		(width 0.1651)
		(layer "In7.Cu")
		(net "P5E_PEX1_STN4_TX_C_DP<72>")
	)
	(segment
		(start 172.5676 -361.442)
		(end 175.514 -359.5624)
		(width 0.1651)
		(layer "In7.Cu")
		(net "P5E_PEX1_STN4_TX_C_DP<72>")
	)
	(segment
		(start 172.65269 -392.77417)
		(end 172.24121 -392.49858)
		(width 0.1651)
		(layer "In7.Cu")
		(net "P5E_PEX1_STN4_TX_C_DP<72>")
	)
	(segment
		(start 172.677074 -392.897614)
		(end 172.65269 -392.77417)
		(width 0.1651)
		(layer "In7.Cu")
		(net "P5E_PEX1_STN4_TX_C_DP<72>")
	)
	(segment
		(start 159.522922 -385.913376)
		(end 159.020002 -385.410456)
		(width 0.1651)
		(layer "In7.Cu")
		(net "P5E_PEX1_STN4_TX_C_DP<72>")
	)
	(segment
		(start 171.706286 -392.24712)
		(end 171.681902 -392.123676)
		(width 0.1651)
		(layer "In7.Cu")
		(net "P5E_PEX1_STN4_TX_C_DP<72>")
	)
	(segment
		(start 176.087532 -397.680688)
		(end 176.087532 -395.746732)
		(width 0.1651)
		(layer "In7.Cu")
		(net "P5E_PEX1_STN4_TX_C_DP<72>")
	)
	(segment
		(start 173.088808 -393.173458)
		(end 172.677074 -392.897614)
		(width 0.1651)
		(layer "In7.Cu")
		(net "P5E_PEX1_STN4_TX_C_DP<72>")
	)
	(segment
		(start 173.212252 -393.149074)
		(end 173.088808 -393.173458)
		(width 0.1651)
		(layer "In7.Cu")
		(net "P5E_PEX1_STN4_TX_C_DP<72>")
	)
	(segment
		(start 163.1442 -365.379)
		(end 172.5676 -361.442)
		(width 0.1651)
		(layer "In7.Cu")
		(net "P5E_PEX1_STN4_TX_C_DP<72>")
	)
	(segment
		(start 170.1292 -391.0838)
		(end 163.192714 -387.455664)
		(width 0.1651)
		(layer "In7.Cu")
		(net "P5E_PEX1_STN4_TX_C_DP<72>")
	)
	(segment
		(start 172.24121 -392.49858)
		(end 172.11802 -392.522964)
		(width 0.1651)
		(layer "In7.Cu")
		(net "P5E_PEX1_STN4_TX_C_DP<72>")
	)
	(segment
		(start 159.000444 -368.77625)
		(end 159.733234 -367.73739)
		(width 0.1651)
		(layer "In7.Cu")
		(net "P5E_PEX1_STN4_TX_C_DP<72>")
	)
	(segment
		(start 175.310038 -397.972026)
		(end 175.437038 -398.099026)
		(width 0.1651)
		(layer "In7.Cu")
		(net "P5E_PEX1_STN4_TX_C_DP<72>")
	)
	(segment
		(start 159.733234 -367.73739)
		(end 163.1442 -365.379)
		(width 0.1651)
		(layer "In7.Cu")
		(net "P5E_PEX1_STN4_TX_C_DP<72>")
	)
	(segment
		(start 163.192714 -387.455664)
		(end 159.522922 -385.913376)
		(width 0.1651)
		(layer "In7.Cu")
		(net "P5E_PEX1_STN4_TX_C_DP<72>")
	)
	(segment
		(start 171.681902 -392.123676)
		(end 170.1292 -391.0838)
		(width 0.1651)
		(layer "In7.Cu")
		(net "P5E_PEX1_STN4_TX_C_DP<72>")
	)
	(segment
		(start 176.467262 -358.609138)
		(end 176.467262 -347.941138)
		(width 0.1651)
		(layer "In7.Cu")
		(net "P5E_PEX1_STN4_TX_C_DP<72>")
	)
	(segment
		(start 158.621984 -369.642136)
		(end 159.000444 -368.77625)
		(width 0.1651)
		(layer "In7.Cu")
		(net "P5E_PEX1_STN4_TX_C_DP<72>")
	)
	(segment
		(start 175.514 -359.5624)
		(end 176.467262 -358.609138)
		(width 0.1651)
		(layer "In7.Cu")
		(net "P5E_PEX1_STN4_TX_C_DP<72>")
	)
	(segment
		(start 158.42234 -370.200936)
		(end 158.621984 -369.642136)
		(width 0.1651)
		(layer "In7.Cu")
		(net "P5E_PEX1_STN4_TX_C_DP<72>")
	)
	(segment
		(start 178.021742 -346.386658)
		(end 178.021742 -345.755976)
		(width 0.1651)
		(layer "In7.Cu")
		(net "P5E_PEX1_STN4_TX_C_DP<72>")
	)
	(segment
		(start 175.669194 -398.099026)
		(end 176.087532 -397.680688)
		(width 0.1651)
		(layer "In7.Cu")
		(net "P5E_PEX1_STN4_TX_C_DP<72>")
	)
	(segment
		(start 184.243472 -357.439214)
		(end 184.243472 -356.80777)
		(width 0.13462)
		(layer "F.Cu")
		(net "P5E_PEX1_STN4_TX_C_DP<68>")
	)
	(segment
		(start 184.243472 -356.80777)
		(end 183.923432 -356.48773)
		(width 0.13462)
		(layer "F.Cu")
		(net "P5E_PEX1_STN4_TX_C_DP<68>")
	)
	(segment
		(start 183.948832 -357.733854)
		(end 184.243472 -357.439214)
		(width 0.13462)
		(layer "F.Cu")
		(net "P5E_PEX1_STN4_TX_C_DP<68>")
	)
	(segment
		(start 178.77917 -363.221016)
		(end 179.234338 -363.025944)
		(width 0.1651)
		(layer "In7.Cu")
		(net "P5E_PEX1_STN4_TX_C_DP<68>")
	)
	(segment
		(start 182.462932 -360.539538)
		(end 182.467758 -360.37774)
		(width 0.1651)
		(layer "In7.Cu")
		(net "P5E_PEX1_STN4_TX_C_DP<68>")
	)
	(segment
		(start 179.234338 -363.025944)
		(end 179.281074 -362.909358)
		(width 0.1651)
		(layer "In7.Cu")
		(net "P5E_PEX1_STN4_TX_C_DP<68>")
	)
	(segment
		(start 180.3146 -362.5596)
		(end 180.3146 -362.559346)
		(width 0.1651)
		(layer "In7.Cu")
		(net "P5E_PEX1_STN4_TX_C_DP<68>")
	)
	(segment
		(start 178.160426 -363.4867)
		(end 178.207162 -363.370114)
		(width 0.1651)
		(layer "In7.Cu")
		(net "P5E_PEX1_STN4_TX_C_DP<68>")
	)
	(segment
		(start 184.239662 -358.024684)
		(end 183.948832 -357.733854)
		(width 0.1651)
		(layer "In7.Cu")
		(net "P5E_PEX1_STN4_TX_C_DP<68>")
	)
	(segment
		(start 178.207162 -363.370114)
		(end 178.662584 -363.174534)
		(width 0.1651)
		(layer "In7.Cu")
		(net "P5E_PEX1_STN4_TX_C_DP<68>")
	)
	(segment
		(start 166.86911 -372.098824)
		(end 167.287448 -371.680486)
		(width 0.1651)
		(layer "In7.Cu")
		(net "P5E_PEX1_STN4_TX_C_DP<68>")
	)
	(segment
		(start 184.239662 -358.86898)
		(end 184.239662 -358.024684)
		(width 0.1651)
		(layer "In7.Cu")
		(net "P5E_PEX1_STN4_TX_C_DP<68>")
	)
	(segment
		(start 179.281074 -362.909358)
		(end 179.736496 -362.713778)
		(width 0.1651)
		(layer "In7.Cu")
		(net "P5E_PEX1_STN4_TX_C_DP<68>")
	)
	(segment
		(start 183.35625 -359.542588)
		(end 183.717438 -359.203244)
		(width 0.1651)
		(layer "In7.Cu")
		(net "P5E_PEX1_STN4_TX_C_DP<68>")
	)
	(segment
		(start 166.509954 -371.590062)
		(end 166.509954 -371.971824)
		(width 0.1651)
		(layer "In7.Cu")
		(net "P5E_PEX1_STN4_TX_C_DP<68>")
	)
	(segment
		(start 182.99049 -360.043222)
		(end 183.35117 -359.704132)
		(width 0.1651)
		(layer "In7.Cu")
		(net "P5E_PEX1_STN4_TX_C_DP<68>")
	)
	(segment
		(start 181.57952 -361.213146)
		(end 181.940708 -360.873802)
		(width 0.1651)
		(layer "In7.Cu")
		(net "P5E_PEX1_STN4_TX_C_DP<68>")
	)
	(segment
		(start 167.287448 -371.680486)
		(end 167.287448 -369.010946)
		(width 0.1651)
		(layer "In7.Cu")
		(net "P5E_PEX1_STN4_TX_C_DP<68>")
	)
	(segment
		(start 180.3146 -362.559346)
		(end 180.686202 -362.210096)
		(width 0.1651)
		(layer "In7.Cu")
		(net "P5E_PEX1_STN4_TX_C_DP<68>")
	)
	(segment
		(start 182.467758 -360.37774)
		(end 182.828946 -360.038396)
		(width 0.1651)
		(layer "In7.Cu")
		(net "P5E_PEX1_STN4_TX_C_DP<68>")
	)
	(segment
		(start 180.30825 -362.565188)
		(end 180.3146 -362.5596)
		(width 0.1651)
		(layer "In7.Cu")
		(net "P5E_PEX1_STN4_TX_C_DP<68>")
	)
	(segment
		(start 168.57345 -367.639854)
		(end 169.839894 -367.056924)
		(width 0.1651)
		(layer "In7.Cu")
		(net "P5E_PEX1_STN4_TX_C_DP<68>")
	)
	(segment
		(start 182.828946 -360.038396)
		(end 182.99049 -360.043222)
		(width 0.1651)
		(layer "In7.Cu")
		(net "P5E_PEX1_STN4_TX_C_DP<68>")
	)
	(segment
		(start 183.35117 -359.704132)
		(end 183.35625 -359.542588)
		(width 0.1651)
		(layer "In7.Cu")
		(net "P5E_PEX1_STN4_TX_C_DP<68>")
	)
	(segment
		(start 181.57444 -361.37469)
		(end 181.57952 -361.213146)
		(width 0.1651)
		(layer "In7.Cu")
		(net "P5E_PEX1_STN4_TX_C_DP<68>")
	)
	(segment
		(start 179.736496 -362.713778)
		(end 179.853082 -362.76026)
		(width 0.1651)
		(layer "In7.Cu")
		(net "P5E_PEX1_STN4_TX_C_DP<68>")
	)
	(segment
		(start 182.102252 -360.878628)
		(end 182.462932 -360.539538)
		(width 0.1651)
		(layer "In7.Cu")
		(net "P5E_PEX1_STN4_TX_C_DP<68>")
	)
	(segment
		(start 183.717438 -359.203244)
		(end 183.878982 -359.20807)
		(width 0.1651)
		(layer "In7.Cu")
		(net "P5E_PEX1_STN4_TX_C_DP<68>")
	)
	(segment
		(start 181.21376 -361.71378)
		(end 181.57444 -361.37469)
		(width 0.1651)
		(layer "In7.Cu")
		(net "P5E_PEX1_STN4_TX_C_DP<68>")
	)
	(segment
		(start 181.052216 -361.708954)
		(end 181.21376 -361.71378)
		(width 0.1651)
		(layer "In7.Cu")
		(net "P5E_PEX1_STN4_TX_C_DP<68>")
	)
	(segment
		(start 169.839894 -367.056924)
		(end 178.160426 -363.4867)
		(width 0.1651)
		(layer "In7.Cu")
		(net "P5E_PEX1_STN4_TX_C_DP<68>")
	)
	(segment
		(start 180.686202 -362.210096)
		(end 180.691028 -362.048552)
		(width 0.1651)
		(layer "In7.Cu")
		(net "P5E_PEX1_STN4_TX_C_DP<68>")
	)
	(segment
		(start 166.509954 -371.971824)
		(end 166.636954 -372.098824)
		(width 0.1651)
		(layer "In7.Cu")
		(net "P5E_PEX1_STN4_TX_C_DP<68>")
	)
	(segment
		(start 183.878982 -359.20807)
		(end 184.239662 -358.86898)
		(width 0.1651)
		(layer "In7.Cu")
		(net "P5E_PEX1_STN4_TX_C_DP<68>")
	)
	(segment
		(start 166.636954 -372.098824)
		(end 166.86911 -372.098824)
		(width 0.1651)
		(layer "In7.Cu")
		(net "P5E_PEX1_STN4_TX_C_DP<68>")
	)
	(segment
		(start 178.662584 -363.174534)
		(end 178.77917 -363.221016)
		(width 0.1651)
		(layer "In7.Cu")
		(net "P5E_PEX1_STN4_TX_C_DP<68>")
	)
	(segment
		(start 179.853082 -362.76026)
		(end 180.30825 -362.565188)
		(width 0.1651)
		(layer "In7.Cu")
		(net "P5E_PEX1_STN4_TX_C_DP<68>")
	)
	(segment
		(start 181.940708 -360.873802)
		(end 182.102252 -360.878628)
		(width 0.1651)
		(layer "In7.Cu")
		(net "P5E_PEX1_STN4_TX_C_DP<68>")
	)
	(segment
		(start 168.086786 -368.158522)
		(end 168.57345 -367.639854)
		(width 0.1651)
		(layer "In7.Cu")
		(net "P5E_PEX1_STN4_TX_C_DP<68>")
	)
	(segment
		(start 167.62222 -368.524028)
		(end 167.96131 -368.162586)
		(width 0.1651)
		(layer "In7.Cu")
		(net "P5E_PEX1_STN4_TX_C_DP<68>")
	)
	(segment
		(start 167.626284 -368.649758)
		(end 167.62222 -368.524028)
		(width 0.1651)
		(layer "In7.Cu")
		(net "P5E_PEX1_STN4_TX_C_DP<68>")
	)
	(segment
		(start 180.691028 -362.048552)
		(end 181.052216 -361.708954)
		(width 0.1651)
		(layer "In7.Cu")
		(net "P5E_PEX1_STN4_TX_C_DP<68>")
	)
	(segment
		(start 167.96131 -368.162586)
		(end 168.086786 -368.158522)
		(width 0.1651)
		(layer "In7.Cu")
		(net "P5E_PEX1_STN4_TX_C_DP<68>")
	)
	(segment
		(start 167.287448 -369.010946)
		(end 167.626284 -368.649758)
		(width 0.1651)
		(layer "In7.Cu")
		(net "P5E_PEX1_STN4_TX_C_DP<68>")
	)
	(segment
		(start 169.55135 -394.468604)
		(end 165.719252 -391.90803)
		(width 0.1651)
		(layer "In5.Cu")
		(net "P5E_PEX1_STN4_RX_DN<75>")
	)
	(segment
		(start 168.710102 -405.589994)
		(end 168.710102 -405.207978)
		(width 0.1651)
		(layer "In5.Cu")
		(net "P5E_PEX1_STN4_RX_DN<75>")
	)
	(segment
		(start 169.386758 -405.080978)
		(end 169.769536 -404.6982)
		(width 0.1651)
		(layer "In5.Cu")
		(net "P5E_PEX1_STN4_RX_DN<75>")
	)
	(segment
		(start 155.796488 -369.41506)
		(end 156.41066 -367.648998)
		(width 0.1651)
		(layer "In5.Cu")
		(net "P5E_PEX1_STN4_RX_DN<75>")
	)
	(segment
		(start 169.769536 -404.6982)
		(end 169.769536 -394.931138)
		(width 0.1651)
		(layer "In5.Cu")
		(net "P5E_PEX1_STN4_RX_DN<75>")
	)
	(segment
		(start 156.41066 -367.648998)
		(end 157.922468 -366.13846)
		(width 0.1651)
		(layer "In5.Cu")
		(net "P5E_PEX1_STN4_RX_DN<75>")
	)
	(segment
		(start 165.719252 -391.90803)
		(end 160.622996 -389.184134)
		(width 0.1651)
		(layer "In5.Cu")
		(net "P5E_PEX1_STN4_RX_DN<75>")
	)
	(segment
		(start 169.26179 -360.099356)
		(end 170.531282 -358.829864)
		(width 0.1651)
		(layer "In5.Cu")
		(net "P5E_PEX1_STN4_RX_DN<75>")
	)
	(segment
		(start 168.710102 -405.207978)
		(end 168.837102 -405.080978)
		(width 0.1651)
		(layer "In5.Cu")
		(net "P5E_PEX1_STN4_RX_DN<75>")
	)
	(segment
		(start 193.685668 -316.419992)
		(end 193.799968 -316.534292)
		(width 0.1143)
		(layer "In5.Cu")
		(net "P5E_PEX1_STN4_RX_DN<75>")
	)
	(segment
		(start 169.769536 -394.931138)
		(end 169.55135 -394.468604)
		(width 0.1651)
		(layer "In5.Cu")
		(net "P5E_PEX1_STN4_RX_DN<75>")
	)
	(segment
		(start 191.005968 -326.611742)
		(end 192.574164 -324.366636)
		(width 0.1651)
		(layer "In5.Cu")
		(net "P5E_PEX1_STN4_RX_DN<75>")
	)
	(segment
		(start 193.465958 -320.119248)
		(end 193.465958 -320.0908)
		(width 0.1143)
		(layer "In5.Cu")
		(net "P5E_PEX1_STN4_RX_DN<75>")
	)
	(segment
		(start 171.2722 -350.1644)
		(end 173.1518 -350.1644)
		(width 0.1651)
		(layer "In5.Cu")
		(net "P5E_PEX1_STN4_RX_DN<75>")
	)
	(segment
		(start 158.001208 -388.081774)
		(end 156.832554 -386.91312)
		(width 0.1651)
		(layer "In5.Cu")
		(net "P5E_PEX1_STN4_RX_DN<75>")
	)
	(segment
		(start 173.640242 -341.6681)
		(end 178.602894 -337.615276)
		(width 0.1651)
		(layer "In5.Cu")
		(net "P5E_PEX1_STN4_RX_DN<75>")
	)
	(segment
		(start 190.40602 -327.3044)
		(end 190.406528 -327.303892)
		(width 0.1651)
		(layer "In5.Cu")
		(net "P5E_PEX1_STN4_RX_DN<75>")
	)
	(segment
		(start 193.465958 -320.0908)
		(end 193.420238 -320.04508)
		(width 0.1143)
		(layer "In5.Cu")
		(net "P5E_PEX1_STN4_RX_DN<75>")
	)
	(segment
		(start 156.832554 -386.91312)
		(end 155.814014 -384.455162)
		(width 0.1651)
		(layer "In5.Cu")
		(net "P5E_PEX1_STN4_RX_DN<75>")
	)
	(segment
		(start 173.1518 -350.1644)
		(end 173.640242 -349.675958)
		(width 0.1651)
		(layer "In5.Cu")
		(net "P5E_PEX1_STN4_RX_DN<75>")
	)
	(segment
		(start 170.531282 -358.829864)
		(end 170.531282 -350.905318)
		(width 0.1651)
		(layer "In5.Cu")
		(net "P5E_PEX1_STN4_RX_DN<75>")
	)
	(segment
		(start 189.529212 -328.317098)
		(end 190.40602 -327.3044)
		(width 0.1651)
		(layer "In5.Cu")
		(net "P5E_PEX1_STN4_RX_DN<75>")
	)
	(segment
		(start 161.656776 -363.443774)
		(end 169.26179 -360.099356)
		(width 0.1651)
		(layer "In5.Cu")
		(net "P5E_PEX1_STN4_RX_DN<75>")
	)
	(segment
		(start 193.420238 -320.04508)
		(end 193.420238 -316.534292)
		(width 0.1143)
		(layer "In5.Cu")
		(net "P5E_PEX1_STN4_RX_DN<75>")
	)
	(segment
		(start 193.465958 -321.53225)
		(end 193.465958 -320.119248)
		(width 0.1651)
		(layer "In5.Cu")
		(net "P5E_PEX1_STN4_RX_DN<75>")
	)
	(segment
		(start 160.622996 -389.184134)
		(end 158.001208 -388.081774)
		(width 0.1651)
		(layer "In5.Cu")
		(net "P5E_PEX1_STN4_RX_DN<75>")
	)
	(segment
		(start 178.602894 -337.615276)
		(end 183.315356 -334.468724)
		(width 0.1651)
		(layer "In5.Cu")
		(net "P5E_PEX1_STN4_RX_DN<75>")
	)
	(segment
		(start 183.315356 -334.468724)
		(end 184.716674 -333.178912)
		(width 0.1651)
		(layer "In5.Cu")
		(net "P5E_PEX1_STN4_RX_DN<75>")
	)
	(segment
		(start 170.531282 -350.905318)
		(end 171.2722 -350.1644)
		(width 0.1651)
		(layer "In5.Cu")
		(net "P5E_PEX1_STN4_RX_DN<75>")
	)
	(segment
		(start 157.922468 -366.13846)
		(end 161.656776 -363.443774)
		(width 0.1651)
		(layer "In5.Cu")
		(net "P5E_PEX1_STN4_RX_DN<75>")
	)
	(segment
		(start 184.716674 -333.178912)
		(end 189.529212 -328.317098)
		(width 0.1651)
		(layer "In5.Cu")
		(net "P5E_PEX1_STN4_RX_DN<75>")
	)
	(segment
		(start 173.640242 -349.675958)
		(end 173.640242 -341.6681)
		(width 0.1651)
		(layer "In5.Cu")
		(net "P5E_PEX1_STN4_RX_DN<75>")
	)
	(segment
		(start 193.420238 -316.534292)
		(end 193.534538 -316.419992)
		(width 0.1143)
		(layer "In5.Cu")
		(net "P5E_PEX1_STN4_RX_DN<75>")
	)
	(segment
		(start 168.837102 -405.080978)
		(end 169.386758 -405.080978)
		(width 0.1651)
		(layer "In5.Cu")
		(net "P5E_PEX1_STN4_RX_DN<75>")
	)
	(segment
		(start 192.574164 -324.366636)
		(end 193.465958 -321.53225)
		(width 0.1651)
		(layer "In5.Cu")
		(net "P5E_PEX1_STN4_RX_DN<75>")
	)
	(segment
		(start 193.534538 -316.419992)
		(end 193.685668 -316.419992)
		(width 0.1143)
		(layer "In5.Cu")
		(net "P5E_PEX1_STN4_RX_DN<75>")
	)
	(segment
		(start 190.406528 -327.303892)
		(end 191.005968 -326.611742)
		(width 0.1651)
		(layer "In5.Cu")
		(net "P5E_PEX1_STN4_RX_DN<75>")
	)
	(segment
		(start 193.799968 -316.534292)
		(end 193.799968 -316.799722)
		(width 0.1143)
		(layer "In5.Cu")
		(net "P5E_PEX1_STN4_RX_DN<75>")
	)
	(segment
		(start 155.814014 -384.455162)
		(end 155.796488 -369.41506)
		(width 0.1651)
		(layer "In5.Cu")
		(net "P5E_PEX1_STN4_RX_DN<75>")
	)
	(segment
		(start 165.288722 -365.733838)
		(end 172.15866 -362.75645)
		(width 0.1651)
		(layer "In5.Cu")
		(net "P5E_PEX1_STN4_RX_DP<71>")
	)
	(segment
		(start 187.930028 -338.539328)
		(end 188.23559 -338.149692)
		(width 0.1651)
		(layer "In5.Cu")
		(net "P5E_PEX1_STN4_RX_DP<71>")
	)
	(segment
		(start 191.377316 -333.672434)
		(end 191.636142 -333.249778)
		(width 0.1651)
		(layer "In5.Cu")
		(net "P5E_PEX1_STN4_RX_DP<71>")
	)
	(segment
		(start 186.094878 -340.879684)
		(end 186.73064 -340.068662)
		(width 0.1651)
		(layer "In5.Cu")
		(net "P5E_PEX1_STN4_RX_DP<71>")
	)
	(segment
		(start 186.711336 -339.908388)
		(end 187.017152 -339.518244)
		(width 0.1651)
		(layer "In5.Cu")
		(net "P5E_PEX1_STN4_RX_DP<71>")
	)
	(segment
		(start 191.636142 -333.249778)
		(end 191.793114 -333.211932)
		(width 0.1651)
		(layer "In5.Cu")
		(net "P5E_PEX1_STN4_RX_DP<71>")
	)
	(segment
		(start 188.216032 -337.989164)
		(end 188.522102 -337.599274)
		(width 0.1651)
		(layer "In5.Cu")
		(net "P5E_PEX1_STN4_RX_DP<71>")
	)
	(segment
		(start 193.066162 -331.131672)
		(end 196.714618 -325.16953)
		(width 0.1651)
		(layer "In5.Cu")
		(net "P5E_PEX1_STN4_RX_DP<71>")
	)
	(segment
		(start 160.687512 -378.581412)
		(end 160.687512 -369.471956)
		(width 0.1651)
		(layer "In5.Cu")
		(net "P5E_PEX1_STN4_RX_DP<71>")
	)
	(segment
		(start 160.037018 -378.79909)
		(end 160.469834 -378.79909)
		(width 0.1651)
		(layer "In5.Cu")
		(net "P5E_PEX1_STN4_RX_DP<71>")
	)
	(segment
		(start 191.415162 -333.82966)
		(end 191.377316 -333.672434)
		(width 0.1651)
		(layer "In5.Cu")
		(net "P5E_PEX1_STN4_RX_DP<71>")
	)
	(segment
		(start 188.23559 -338.149692)
		(end 188.216032 -337.989164)
		(width 0.1651)
		(layer "In5.Cu")
		(net "P5E_PEX1_STN4_RX_DP<71>")
	)
	(segment
		(start 196.714618 -325.16953)
		(end 197.934072 -320.841116)
		(width 0.1651)
		(layer "In5.Cu")
		(net "P5E_PEX1_STN4_RX_DP<71>")
	)
	(segment
		(start 197.979792 -316.914022)
		(end 197.865492 -316.799722)
		(width 0.1143)
		(layer "In5.Cu")
		(net "P5E_PEX1_STN4_RX_DP<71>")
	)
	(segment
		(start 161.326068 -368.572288)
		(end 161.693606 -368.20475)
		(width 0.1651)
		(layer "In5.Cu")
		(net "P5E_PEX1_STN4_RX_DP<71>")
	)
	(segment
		(start 187.769754 -338.558886)
		(end 187.930028 -338.539328)
		(width 0.1651)
		(layer "In5.Cu")
		(net "P5E_PEX1_STN4_RX_DP<71>")
	)
	(segment
		(start 192.687956 -331.7494)
		(end 192.65011 -331.592174)
		(width 0.1651)
		(layer "In5.Cu")
		(net "P5E_PEX1_STN4_RX_DP<71>")
	)
	(segment
		(start 185.794142 -342.09863)
		(end 186.094878 -340.879684)
		(width 0.1651)
		(layer "In5.Cu")
		(net "P5E_PEX1_STN4_RX_DP<71>")
	)
	(segment
		(start 197.934072 -319.1764)
		(end 197.979792 -319.13068)
		(width 0.1143)
		(layer "In5.Cu")
		(net "P5E_PEX1_STN4_RX_DP<71>")
	)
	(segment
		(start 172.15866 -362.75645)
		(end 175.407066 -361.749594)
		(width 0.1651)
		(layer "In5.Cu")
		(net "P5E_PEX1_STN4_RX_DP<71>")
	)
	(segment
		(start 192.013586 -332.632304)
		(end 192.272412 -332.209648)
		(width 0.1651)
		(layer "In5.Cu")
		(net "P5E_PEX1_STN4_RX_DP<71>")
	)
	(segment
		(start 192.908936 -331.169518)
		(end 193.066162 -331.131672)
		(width 0.1651)
		(layer "In5.Cu")
		(net "P5E_PEX1_STN4_RX_DP<71>")
	)
	(segment
		(start 191.793114 -333.211932)
		(end 192.051432 -332.78953)
		(width 0.1651)
		(layer "In5.Cu")
		(net "P5E_PEX1_STN4_RX_DP<71>")
	)
	(segment
		(start 188.522102 -337.599274)
		(end 188.68263 -337.579716)
		(width 0.1651)
		(layer "In5.Cu")
		(net "P5E_PEX1_STN4_RX_DP<71>")
	)
	(segment
		(start 186.73064 -340.068662)
		(end 186.711336 -339.908388)
		(width 0.1651)
		(layer "In5.Cu")
		(net "P5E_PEX1_STN4_RX_DP<71>")
	)
	(segment
		(start 188.68263 -337.579716)
		(end 190.674752 -335.039462)
		(width 0.1651)
		(layer "In5.Cu")
		(net "P5E_PEX1_STN4_RX_DP<71>")
	)
	(segment
		(start 192.272412 -332.209648)
		(end 192.429638 -332.171802)
		(width 0.1651)
		(layer "In5.Cu")
		(net "P5E_PEX1_STN4_RX_DP<71>")
	)
	(segment
		(start 197.979792 -319.13068)
		(end 197.979792 -316.914022)
		(width 0.1143)
		(layer "In5.Cu")
		(net "P5E_PEX1_STN4_RX_DP<71>")
	)
	(segment
		(start 197.934072 -319.204848)
		(end 197.934072 -319.1764)
		(width 0.1143)
		(layer "In5.Cu")
		(net "P5E_PEX1_STN4_RX_DP<71>")
	)
	(segment
		(start 187.17768 -339.49894)
		(end 187.483242 -339.109304)
		(width 0.1651)
		(layer "In5.Cu")
		(net "P5E_PEX1_STN4_RX_DP<71>")
	)
	(segment
		(start 184.771538 -359.855262)
		(end 185.794142 -358.832658)
		(width 0.1651)
		(layer "In5.Cu")
		(net "P5E_PEX1_STN4_RX_DP<71>")
	)
	(segment
		(start 192.65011 -331.592174)
		(end 192.908936 -331.169518)
		(width 0.1651)
		(layer "In5.Cu")
		(net "P5E_PEX1_STN4_RX_DP<71>")
	)
	(segment
		(start 192.051432 -332.78953)
		(end 192.013586 -332.632304)
		(width 0.1651)
		(layer "In5.Cu")
		(net "P5E_PEX1_STN4_RX_DP<71>")
	)
	(segment
		(start 197.934072 -320.841116)
		(end 197.934072 -319.204848)
		(width 0.1651)
		(layer "In5.Cu")
		(net "P5E_PEX1_STN4_RX_DP<71>")
	)
	(segment
		(start 197.865492 -316.799722)
		(end 197.600062 -316.799722)
		(width 0.1143)
		(layer "In5.Cu")
		(net "P5E_PEX1_STN4_RX_DP<71>")
	)
	(segment
		(start 190.674752 -335.039462)
		(end 191.415162 -333.82966)
		(width 0.1651)
		(layer "In5.Cu")
		(net "P5E_PEX1_STN4_RX_DP<71>")
	)
	(segment
		(start 159.910018 -378.290074)
		(end 159.910018 -378.67209)
		(width 0.1651)
		(layer "In5.Cu")
		(net "P5E_PEX1_STN4_RX_DP<71>")
	)
	(segment
		(start 187.017152 -339.518244)
		(end 187.17768 -339.49894)
		(width 0.1651)
		(layer "In5.Cu")
		(net "P5E_PEX1_STN4_RX_DP<71>")
	)
	(segment
		(start 185.794142 -358.832658)
		(end 185.794142 -342.09863)
		(width 0.1651)
		(layer "In5.Cu")
		(net "P5E_PEX1_STN4_RX_DP<71>")
	)
	(segment
		(start 160.687512 -369.471956)
		(end 161.326068 -368.572288)
		(width 0.1651)
		(layer "In5.Cu")
		(net "P5E_PEX1_STN4_RX_DP<71>")
	)
	(segment
		(start 161.693606 -368.20475)
		(end 165.288722 -365.733838)
		(width 0.1651)
		(layer "In5.Cu")
		(net "P5E_PEX1_STN4_RX_DP<71>")
	)
	(segment
		(start 187.463684 -338.948776)
		(end 187.769754 -338.558886)
		(width 0.1651)
		(layer "In5.Cu")
		(net "P5E_PEX1_STN4_RX_DP<71>")
	)
	(segment
		(start 187.483242 -339.109304)
		(end 187.463684 -338.948776)
		(width 0.1651)
		(layer "In5.Cu")
		(net "P5E_PEX1_STN4_RX_DP<71>")
	)
	(segment
		(start 192.429638 -332.171802)
		(end 192.687956 -331.7494)
		(width 0.1651)
		(layer "In5.Cu")
		(net "P5E_PEX1_STN4_RX_DP<71>")
	)
	(segment
		(start 159.910018 -378.67209)
		(end 160.037018 -378.79909)
		(width 0.1651)
		(layer "In5.Cu")
		(net "P5E_PEX1_STN4_RX_DP<71>")
	)
	(segment
		(start 160.469834 -378.79909)
		(end 160.687512 -378.581412)
		(width 0.1651)
		(layer "In5.Cu")
		(net "P5E_PEX1_STN4_RX_DP<71>")
	)
	(segment
		(start 175.407066 -361.749594)
		(end 184.771538 -359.855262)
		(width 0.1651)
		(layer "In5.Cu")
		(net "P5E_PEX1_STN4_RX_DP<71>")
	)
	(segment
		(start 167.341804 -393.424664)
		(end 167.320214 -393.317222)
		(width 0.1651)
		(layer "In5.Cu")
		(net "P5E_PEX1_STN4_RX_DP<75>")
	)
	(segment
		(start 169.099738 -359.862374)
		(end 170.249342 -358.713024)
		(width 0.1651)
		(layer "In5.Cu")
		(net "P5E_PEX1_STN4_RX_DP<75>")
	)
	(segment
		(start 157.840934 -388.32028)
		(end 156.59354 -387.072886)
		(width 0.1651)
		(layer "In5.Cu")
		(net "P5E_PEX1_STN4_RX_DP<75>")
	)
	(segment
		(start 173.03496 -349.88246)
		(end 173.358302 -349.559118)
		(width 0.1651)
		(layer "In5.Cu")
		(net "P5E_PEX1_STN4_RX_DP<75>")
	)
	(segment
		(start 168.710102 -404.672038)
		(end 168.837102 -404.799038)
		(width 0.1651)
		(layer "In5.Cu")
		(net "P5E_PEX1_STN4_RX_DP<75>")
	)
	(segment
		(start 193.455544 -316.229492)
		(end 193.685668 -316.229492)
		(width 0.1143)
		(layer "In5.Cu")
		(net "P5E_PEX1_STN4_RX_DP<75>")
	)
	(segment
		(start 169.487596 -394.994384)
		(end 169.329608 -394.659612)
		(width 0.1651)
		(layer "In5.Cu")
		(net "P5E_PEX1_STN4_RX_DP<75>")
	)
	(segment
		(start 155.532074 -384.511296)
		(end 155.514294 -369.367562)
		(width 0.1651)
		(layer "In5.Cu")
		(net "P5E_PEX1_STN4_RX_DP<75>")
	)
	(segment
		(start 168.896284 -394.370052)
		(end 168.741344 -394.40104)
		(width 0.1651)
		(layer "In5.Cu")
		(net "P5E_PEX1_STN4_RX_DP<75>")
	)
	(segment
		(start 168.308782 -393.977622)
		(end 167.907716 -393.709652)
		(width 0.1651)
		(layer "In5.Cu")
		(net "P5E_PEX1_STN4_RX_DP<75>")
	)
	(segment
		(start 193.184018 -321.488816)
		(end 193.184018 -320.119248)
		(width 0.1651)
		(layer "In5.Cu")
		(net "P5E_PEX1_STN4_RX_DP<75>")
	)
	(segment
		(start 171.15536 -349.88246)
		(end 173.03496 -349.88246)
		(width 0.1651)
		(layer "In5.Cu")
		(net "P5E_PEX1_STN4_RX_DP<75>")
	)
	(segment
		(start 168.837102 -404.799038)
		(end 169.269918 -404.799038)
		(width 0.1651)
		(layer "In5.Cu")
		(net "P5E_PEX1_STN4_RX_DP<75>")
	)
	(segment
		(start 169.329608 -394.659612)
		(end 168.896284 -394.370052)
		(width 0.1651)
		(layer "In5.Cu")
		(net "P5E_PEX1_STN4_RX_DP<75>")
	)
	(segment
		(start 189.322202 -328.125328)
		(end 190.199518 -327.112122)
		(width 0.1651)
		(layer "In5.Cu")
		(net "P5E_PEX1_STN4_RX_DP<75>")
	)
	(segment
		(start 193.184018 -320.0908)
		(end 193.229738 -320.04508)
		(width 0.1143)
		(layer "In5.Cu")
		(net "P5E_PEX1_STN4_RX_DP<75>")
	)
	(segment
		(start 184.52084 -332.975966)
		(end 189.322202 -328.125328)
		(width 0.1651)
		(layer "In5.Cu")
		(net "P5E_PEX1_STN4_RX_DP<75>")
	)
	(segment
		(start 166.780464 -393.076684)
		(end 166.359332 -392.795252)
		(width 0.1651)
		(layer "In5.Cu")
		(net "P5E_PEX1_STN4_RX_DP<75>")
	)
	(segment
		(start 165.573964 -392.150346)
		(end 160.501584 -389.43915)
		(width 0.1651)
		(layer "In5.Cu")
		(net "P5E_PEX1_STN4_RX_DP<75>")
	)
	(segment
		(start 173.358302 -341.534242)
		(end 178.435 -337.3882)
		(width 0.1651)
		(layer "In5.Cu")
		(net "P5E_PEX1_STN4_RX_DP<75>")
	)
	(segment
		(start 161.515806 -363.197394)
		(end 169.099738 -359.862374)
		(width 0.1651)
		(layer "In5.Cu")
		(net "P5E_PEX1_STN4_RX_DP<75>")
	)
	(segment
		(start 170.249342 -358.713024)
		(end 170.249342 -350.788478)
		(width 0.1651)
		(layer "In5.Cu")
		(net "P5E_PEX1_STN4_RX_DP<75>")
	)
	(segment
		(start 157.73908 -365.923068)
		(end 161.491676 -363.215174)
		(width 0.1651)
		(layer "In5.Cu")
		(net "P5E_PEX1_STN4_RX_DP<75>")
	)
	(segment
		(start 167.80002 -393.730988)
		(end 167.341804 -393.424664)
		(width 0.1651)
		(layer "In5.Cu")
		(net "P5E_PEX1_STN4_RX_DP<75>")
	)
	(segment
		(start 161.491422 -363.21492)
		(end 161.515806 -363.197394)
		(width 0.1651)
		(layer "In5.Cu")
		(net "P5E_PEX1_STN4_RX_DP<75>")
	)
	(segment
		(start 193.184018 -320.119248)
		(end 193.184018 -320.0908)
		(width 0.1143)
		(layer "In5.Cu")
		(net "P5E_PEX1_STN4_RX_DP<75>")
	)
	(segment
		(start 170.249342 -350.788478)
		(end 171.15536 -349.88246)
		(width 0.1651)
		(layer "In5.Cu")
		(net "P5E_PEX1_STN4_RX_DP<75>")
	)
	(segment
		(start 190.200026 -327.111614)
		(end 190.78321 -326.43826)
		(width 0.1651)
		(layer "In5.Cu")
		(net "P5E_PEX1_STN4_RX_DP<75>")
	)
	(segment
		(start 166.331646 -392.656568)
		(end 165.573964 -392.150346)
		(width 0.1651)
		(layer "In5.Cu")
		(net "P5E_PEX1_STN4_RX_DP<75>")
	)
	(segment
		(start 168.741344 -394.40104)
		(end 168.33977 -394.132562)
		(width 0.1651)
		(layer "In5.Cu")
		(net "P5E_PEX1_STN4_RX_DP<75>")
	)
	(segment
		(start 193.799968 -316.115192)
		(end 193.799968 -315.849762)
		(width 0.1143)
		(layer "In5.Cu")
		(net "P5E_PEX1_STN4_RX_DP<75>")
	)
	(segment
		(start 160.501584 -389.43915)
		(end 157.840934 -388.32028)
		(width 0.1651)
		(layer "In5.Cu")
		(net "P5E_PEX1_STN4_RX_DP<75>")
	)
	(segment
		(start 167.907716 -393.709652)
		(end 167.80002 -393.730988)
		(width 0.1651)
		(layer "In5.Cu")
		(net "P5E_PEX1_STN4_RX_DP<75>")
	)
	(segment
		(start 166.359332 -392.795252)
		(end 166.331646 -392.656568)
		(width 0.1651)
		(layer "In5.Cu")
		(net "P5E_PEX1_STN4_RX_DP<75>")
	)
	(segment
		(start 192.318132 -324.240652)
		(end 193.184018 -321.488816)
		(width 0.1651)
		(layer "In5.Cu")
		(net "P5E_PEX1_STN4_RX_DP<75>")
	)
	(segment
		(start 156.59354 -387.072886)
		(end 155.532074 -384.511296)
		(width 0.1651)
		(layer "In5.Cu")
		(net "P5E_PEX1_STN4_RX_DP<75>")
	)
	(segment
		(start 183.14035 -334.24622)
		(end 184.52084 -332.975966)
		(width 0.1651)
		(layer "In5.Cu")
		(net "P5E_PEX1_STN4_RX_DP<75>")
	)
	(segment
		(start 156.16555 -367.495328)
		(end 157.73908 -365.923068)
		(width 0.1651)
		(layer "In5.Cu")
		(net "P5E_PEX1_STN4_RX_DP<75>")
	)
	(segment
		(start 193.685668 -316.229492)
		(end 193.799968 -316.115192)
		(width 0.1143)
		(layer "In5.Cu")
		(net "P5E_PEX1_STN4_RX_DP<75>")
	)
	(segment
		(start 161.491676 -363.215174)
		(end 161.491422 -363.21492)
		(width 0.1651)
		(layer "In5.Cu")
		(net "P5E_PEX1_STN4_RX_DP<75>")
	)
	(segment
		(start 193.229738 -316.455298)
		(end 193.455544 -316.229492)
		(width 0.1143)
		(layer "In5.Cu")
		(net "P5E_PEX1_STN4_RX_DP<75>")
	)
	(segment
		(start 190.78321 -326.43826)
		(end 192.318132 -324.240652)
		(width 0.1651)
		(layer "In5.Cu")
		(net "P5E_PEX1_STN4_RX_DP<75>")
	)
	(segment
		(start 168.33977 -394.132562)
		(end 168.308782 -393.977622)
		(width 0.1651)
		(layer "In5.Cu")
		(net "P5E_PEX1_STN4_RX_DP<75>")
	)
	(segment
		(start 178.435 -337.3882)
		(end 183.14035 -334.24622)
		(width 0.1651)
		(layer "In5.Cu")
		(net "P5E_PEX1_STN4_RX_DP<75>")
	)
	(segment
		(start 166.919148 -393.049252)
		(end 166.780464 -393.076684)
		(width 0.1651)
		(layer "In5.Cu")
		(net "P5E_PEX1_STN4_RX_DP<75>")
	)
	(segment
		(start 167.320214 -393.317222)
		(end 166.919148 -393.049252)
		(width 0.1651)
		(layer "In5.Cu")
		(net "P5E_PEX1_STN4_RX_DP<75>")
	)
	(segment
		(start 155.514294 -369.367562)
		(end 156.16555 -367.495328)
		(width 0.1651)
		(layer "In5.Cu")
		(net "P5E_PEX1_STN4_RX_DP<75>")
	)
	(segment
		(start 169.269918 -404.799038)
		(end 169.487596 -404.58136)
		(width 0.1651)
		(layer "In5.Cu")
		(net "P5E_PEX1_STN4_RX_DP<75>")
	)
	(segment
		(start 169.487596 -404.58136)
		(end 169.487596 -394.994384)
		(width 0.1651)
		(layer "In5.Cu")
		(net "P5E_PEX1_STN4_RX_DP<75>")
	)
	(segment
		(start 193.229738 -320.04508)
		(end 193.229738 -316.455298)
		(width 0.1143)
		(layer "In5.Cu")
		(net "P5E_PEX1_STN4_RX_DP<75>")
	)
	(segment
		(start 173.358302 -349.559118)
		(end 173.358302 -341.534242)
		(width 0.1651)
		(layer "In5.Cu")
		(net "P5E_PEX1_STN4_RX_DP<75>")
	)
	(segment
		(start 190.199518 -327.112122)
		(end 190.200026 -327.111614)
		(width 0.1651)
		(layer "In5.Cu")
		(net "P5E_PEX1_STN4_RX_DP<75>")
	)
	(segment
		(start 168.710102 -404.290022)
		(end 168.710102 -404.672038)
		(width 0.1651)
		(layer "In5.Cu")
		(net "P5E_PEX1_STN4_RX_DP<75>")
	)
	(segment
		(start 204.57033 -340.900258)
		(end 204.570584 -340.900512)
		(width 0.1651)
		(layer "In5.Cu")
		(net "P5E_PEX1_STN4_RX_DP<66>")
	)
	(segment
		(start 201.27214 -347.417136)
		(end 201.272394 -347.417136)
		(width 0.1651)
		(layer "In5.Cu")
		(net "P5E_PEX1_STN4_RX_DP<66>")
	)
	(segment
		(start 199.8218 -306.978558)
		(end 199.77608 -306.932838)
		(width 0.1143)
		(layer "In5.Cu")
		(net "P5E_PEX1_STN4_RX_DP<66>")
	)
	(segment
		(start 176.380394 -366.504728)
		(end 187.275978 -364.30077)
		(width 0.1651)
		(layer "In5.Cu")
		(net "P5E_PEX1_STN4_RX_DP<66>")
	)
	(segment
		(start 202.604878 -307.694838)
		(end 200.875392 -306.978558)
		(width 0.1651)
		(layer "In5.Cu")
		(net "P5E_PEX1_STN4_RX_DP<66>")
	)
	(segment
		(start 204.016102 -309.686706)
		(end 203.704444 -308.794404)
		(width 0.1651)
		(layer "In5.Cu")
		(net "P5E_PEX1_STN4_RX_DP<66>")
	)
	(segment
		(start 190.10376 -362.838238)
		(end 192.282572 -360.643932)
		(width 0.1651)
		(layer "In5.Cu")
		(net "P5E_PEX1_STN4_RX_DP<66>")
	)
	(segment
		(start 200.17105 -349.5929)
		(end 200.120758 -349.43923)
		(width 0.1651)
		(layer "In5.Cu")
		(net "P5E_PEX1_STN4_RX_DP<66>")
	)
	(segment
		(start 170.909996 -379.772164)
		(end 171.036996 -379.899164)
		(width 0.1651)
		(layer "In5.Cu")
		(net "P5E_PEX1_STN4_RX_DP<66>")
	)
	(segment
		(start 200.895204 -347.909134)
		(end 201.048874 -347.858842)
		(width 0.1651)
		(layer "In5.Cu")
		(net "P5E_PEX1_STN4_RX_DP<66>")
	)
	(segment
		(start 204.346556 -341.34171)
		(end 204.57033 -340.900258)
		(width 0.1651)
		(layer "In5.Cu")
		(net "P5E_PEX1_STN4_RX_DP<66>")
	)
	(segment
		(start 200.67143 -348.351348)
		(end 200.895204 -347.909134)
		(width 0.1651)
		(layer "In5.Cu")
		(net "P5E_PEX1_STN4_RX_DP<66>")
	)
	(segment
		(start 173.69028 -367.478056)
		(end 176.380394 -366.504728)
		(width 0.1651)
		(layer "In5.Cu")
		(net "P5E_PEX1_STN4_RX_DP<66>")
	)
	(segment
		(start 171.469812 -379.899164)
		(end 171.68749 -379.681486)
		(width 0.1651)
		(layer "In5.Cu")
		(net "P5E_PEX1_STN4_RX_DP<66>")
	)
	(segment
		(start 200.120758 -349.43923)
		(end 200.344532 -348.997016)
		(width 0.1651)
		(layer "In5.Cu")
		(net "P5E_PEX1_STN4_RX_DP<66>")
	)
	(segment
		(start 213.04758 -321.80149)
		(end 213.04758 -319.612264)
		(width 0.1651)
		(layer "In5.Cu")
		(net "P5E_PEX1_STN4_RX_DP<66>")
	)
	(segment
		(start 197.865492 -306.349908)
		(end 197.600062 -306.349908)
		(width 0.1143)
		(layer "In5.Cu")
		(net "P5E_PEX1_STN4_RX_DP<66>")
	)
	(segment
		(start 201.222102 -347.263466)
		(end 201.445876 -346.821252)
		(width 0.1651)
		(layer "In5.Cu")
		(net "P5E_PEX1_STN4_RX_DP<66>")
	)
	(segment
		(start 204.520292 -340.746842)
		(end 204.744066 -340.304628)
		(width 0.1651)
		(layer "In5.Cu")
		(net "P5E_PEX1_STN4_RX_DP<66>")
	)
	(segment
		(start 204.193394 -341.39251)
		(end 204.347064 -341.342218)
		(width 0.1651)
		(layer "In5.Cu")
		(net "P5E_PEX1_STN4_RX_DP<66>")
	)
	(segment
		(start 201.272394 -347.417136)
		(end 201.222102 -347.263466)
		(width 0.1651)
		(layer "In5.Cu")
		(net "P5E_PEX1_STN4_RX_DP<66>")
	)
	(segment
		(start 201.445876 -346.821252)
		(end 201.599546 -346.77096)
		(width 0.1651)
		(layer "In5.Cu")
		(net "P5E_PEX1_STN4_RX_DP<66>")
	)
	(segment
		(start 198.219822 -306.932838)
		(end 197.979792 -306.692808)
		(width 0.1143)
		(layer "In5.Cu")
		(net "P5E_PEX1_STN4_RX_DP<66>")
	)
	(segment
		(start 197.057518 -355.047804)
		(end 199.94753 -350.034606)
		(width 0.1651)
		(layer "In5.Cu")
		(net "P5E_PEX1_STN4_RX_DP<66>")
	)
	(segment
		(start 204.897736 -340.254336)
		(end 204.897228 -340.253828)
		(width 0.1651)
		(layer "In5.Cu")
		(net "P5E_PEX1_STN4_RX_DP<66>")
	)
	(segment
		(start 171.68749 -379.681486)
		(end 171.68749 -369.482878)
		(width 0.1651)
		(layer "In5.Cu")
		(net "P5E_PEX1_STN4_RX_DP<66>")
	)
	(segment
		(start 207.570832 -313.235848)
		(end 204.016102 -309.686706)
		(width 0.1651)
		(layer "In5.Cu")
		(net "P5E_PEX1_STN4_RX_DP<66>")
	)
	(segment
		(start 204.744066 -340.304628)
		(end 204.897736 -340.254336)
		(width 0.1651)
		(layer "In5.Cu")
		(net "P5E_PEX1_STN4_RX_DP<66>")
	)
	(segment
		(start 211.937092 -316.940946)
		(end 209.6008 -314.5536)
		(width 0.1651)
		(layer "In5.Cu")
		(net "P5E_PEX1_STN4_RX_DP<66>")
	)
	(segment
		(start 200.498202 -348.946724)
		(end 200.497948 -348.946724)
		(width 0.1651)
		(layer "In5.Cu")
		(net "P5E_PEX1_STN4_RX_DP<66>")
	)
	(segment
		(start 201.048874 -347.858842)
		(end 201.04862 -347.858842)
		(width 0.1651)
		(layer "In5.Cu")
		(net "P5E_PEX1_STN4_RX_DP<66>")
	)
	(segment
		(start 199.94753 -350.034606)
		(end 200.17105 -349.5929)
		(width 0.1651)
		(layer "In5.Cu")
		(net "P5E_PEX1_STN4_RX_DP<66>")
	)
	(segment
		(start 200.875392 -306.978558)
		(end 199.850248 -306.978558)
		(width 0.1651)
		(layer "In5.Cu")
		(net "P5E_PEX1_STN4_RX_DP<66>")
	)
	(segment
		(start 201.599292 -346.770706)
		(end 204.019658 -341.98814)
		(width 0.1651)
		(layer "In5.Cu")
		(net "P5E_PEX1_STN4_RX_DP<66>")
	)
	(segment
		(start 204.347064 -341.342218)
		(end 204.346556 -341.34171)
		(width 0.1651)
		(layer "In5.Cu")
		(net "P5E_PEX1_STN4_RX_DP<66>")
	)
	(segment
		(start 187.275978 -364.30077)
		(end 190.10376 -362.838238)
		(width 0.1651)
		(layer "In5.Cu")
		(net "P5E_PEX1_STN4_RX_DP<66>")
	)
	(segment
		(start 201.04862 -347.858842)
		(end 201.27214 -347.417136)
		(width 0.1651)
		(layer "In5.Cu")
		(net "P5E_PEX1_STN4_RX_DP<66>")
	)
	(segment
		(start 203.704444 -308.794404)
		(end 202.604878 -307.694838)
		(width 0.1651)
		(layer "In5.Cu")
		(net "P5E_PEX1_STN4_RX_DP<66>")
	)
	(segment
		(start 203.96962 -341.834724)
		(end 204.193394 -341.39251)
		(width 0.1651)
		(layer "In5.Cu")
		(net "P5E_PEX1_STN4_RX_DP<66>")
	)
	(segment
		(start 200.721468 -348.505018)
		(end 200.721722 -348.505018)
		(width 0.1651)
		(layer "In5.Cu")
		(net "P5E_PEX1_STN4_RX_DP<66>")
	)
	(segment
		(start 200.721722 -348.505018)
		(end 200.67143 -348.351348)
		(width 0.1651)
		(layer "In5.Cu")
		(net "P5E_PEX1_STN4_RX_DP<66>")
	)
	(segment
		(start 201.599546 -346.77096)
		(end 201.599292 -346.770706)
		(width 0.1651)
		(layer "In5.Cu")
		(net "P5E_PEX1_STN4_RX_DP<66>")
	)
	(segment
		(start 200.344532 -348.997016)
		(end 200.498202 -348.946724)
		(width 0.1651)
		(layer "In5.Cu")
		(net "P5E_PEX1_STN4_RX_DP<66>")
	)
	(segment
		(start 204.019912 -341.988394)
		(end 203.96962 -341.834724)
		(width 0.1651)
		(layer "In5.Cu")
		(net "P5E_PEX1_STN4_RX_DP<66>")
	)
	(segment
		(start 197.979792 -306.464208)
		(end 197.865492 -306.349908)
		(width 0.1143)
		(layer "In5.Cu")
		(net "P5E_PEX1_STN4_RX_DP<66>")
	)
	(segment
		(start 213.04758 -319.612264)
		(end 212.012022 -317.083186)
		(width 0.1651)
		(layer "In5.Cu")
		(net "P5E_PEX1_STN4_RX_DP<66>")
	)
	(segment
		(start 204.019658 -341.98814)
		(end 204.019912 -341.988394)
		(width 0.1651)
		(layer "In5.Cu")
		(net "P5E_PEX1_STN4_RX_DP<66>")
	)
	(segment
		(start 170.909996 -379.390148)
		(end 170.909996 -379.772164)
		(width 0.1651)
		(layer "In5.Cu")
		(net "P5E_PEX1_STN4_RX_DP<66>")
	)
	(segment
		(start 171.68749 -369.482878)
		(end 172.480986 -368.388646)
		(width 0.1651)
		(layer "In5.Cu")
		(net "P5E_PEX1_STN4_RX_DP<66>")
	)
	(segment
		(start 171.036996 -379.899164)
		(end 171.469812 -379.899164)
		(width 0.1651)
		(layer "In5.Cu")
		(net "P5E_PEX1_STN4_RX_DP<66>")
	)
	(segment
		(start 192.282572 -360.643932)
		(end 197.057518 -355.047804)
		(width 0.1651)
		(layer "In5.Cu")
		(net "P5E_PEX1_STN4_RX_DP<66>")
	)
	(segment
		(start 209.6008 -314.5536)
		(end 207.570832 -313.235848)
		(width 0.1651)
		(layer "In5.Cu")
		(net "P5E_PEX1_STN4_RX_DP<66>")
	)
	(segment
		(start 199.850248 -306.978558)
		(end 199.8218 -306.978558)
		(width 0.1143)
		(layer "In5.Cu")
		(net "P5E_PEX1_STN4_RX_DP<66>")
	)
	(segment
		(start 172.480986 -368.388646)
		(end 173.69028 -367.478056)
		(width 0.1651)
		(layer "In5.Cu")
		(net "P5E_PEX1_STN4_RX_DP<66>")
	)
	(segment
		(start 200.497948 -348.946724)
		(end 200.721468 -348.505018)
		(width 0.1651)
		(layer "In5.Cu")
		(net "P5E_PEX1_STN4_RX_DP<66>")
	)
	(segment
		(start 212.270594 -325.685404)
		(end 213.04758 -321.80149)
		(width 0.1651)
		(layer "In5.Cu")
		(net "P5E_PEX1_STN4_RX_DP<66>")
	)
	(segment
		(start 212.012022 -317.083186)
		(end 211.937092 -316.940946)
		(width 0.1651)
		(layer "In5.Cu")
		(net "P5E_PEX1_STN4_RX_DP<66>")
	)
	(segment
		(start 197.979792 -306.692808)
		(end 197.979792 -306.464208)
		(width 0.1143)
		(layer "In5.Cu")
		(net "P5E_PEX1_STN4_RX_DP<66>")
	)
	(segment
		(start 204.570584 -340.900512)
		(end 204.520292 -340.746842)
		(width 0.1651)
		(layer "In5.Cu")
		(net "P5E_PEX1_STN4_RX_DP<66>")
	)
	(segment
		(start 199.77608 -306.932838)
		(end 198.219822 -306.932838)
		(width 0.1143)
		(layer "In5.Cu")
		(net "P5E_PEX1_STN4_RX_DP<66>")
	)
	(segment
		(start 204.897228 -340.253828)
		(end 212.270594 -325.685404)
		(width 0.1651)
		(layer "In5.Cu")
		(net "P5E_PEX1_STN4_RX_DP<66>")
	)
	(segment
		(start 163.22675 -393.744196)
		(end 162.768026 -393.444476)
		(width 0.1651)
		(layer "In5.Cu")
		(net "P5E_PEX1_STN4_RX_DP<77>")
	)
	(segment
		(start 191.284098 -321.11442)
		(end 191.284098 -320.119248)
		(width 0.1651)
		(layer "In5.Cu")
		(net "P5E_PEX1_STN4_RX_DP<77>")
	)
	(segment
		(start 164.918136 -394.754608)
		(end 164.33165 -394.371576)
		(width 0.1651)
		(layer "In5.Cu")
		(net "P5E_PEX1_STN4_RX_DP<77>")
	)
	(segment
		(start 156.705808 -389.886952)
		(end 154.972512 -388.153656)
		(width 0.1651)
		(layer "In5.Cu")
		(net "P5E_PEX1_STN4_RX_DP<77>")
	)
	(segment
		(start 163.77285 -394.139674)
		(end 163.740338 -393.984988)
		(width 0.1651)
		(layer "In5.Cu")
		(net "P5E_PEX1_STN4_RX_DP<77>")
	)
	(segment
		(start 163.336478 -393.721082)
		(end 163.22675 -393.744196)
		(width 0.1651)
		(layer "In5.Cu")
		(net "P5E_PEX1_STN4_RX_DP<77>")
	)
	(segment
		(start 163.855654 -359.149904)
		(end 164.031422 -358.974136)
		(width 0.1651)
		(layer "In5.Cu")
		(net "P5E_PEX1_STN4_RX_DP<77>")
	)
	(segment
		(start 162.341306 -393.070842)
		(end 162.217354 -393.097004)
		(width 0.1651)
		(layer "In5.Cu")
		(net "P5E_PEX1_STN4_RX_DP<77>")
	)
	(segment
		(start 165.087554 -404.58136)
		(end 165.087554 -395.008862)
		(width 0.1651)
		(layer "In5.Cu")
		(net "P5E_PEX1_STN4_RX_DP<77>")
	)
	(segment
		(start 165.087554 -395.008862)
		(end 164.918136 -394.754608)
		(width 0.1651)
		(layer "In5.Cu")
		(net "P5E_PEX1_STN4_RX_DP<77>")
	)
	(segment
		(start 191.329818 -316.455298)
		(end 191.555624 -316.229492)
		(width 0.1143)
		(layer "In5.Cu")
		(net "P5E_PEX1_STN4_RX_DP<77>")
	)
	(segment
		(start 191.284098 -320.0908)
		(end 191.329818 -320.04508)
		(width 0.1143)
		(layer "In5.Cu")
		(net "P5E_PEX1_STN4_RX_DP<77>")
	)
	(segment
		(start 154.28976 -366.668812)
		(end 156.49702 -364.46333)
		(width 0.1651)
		(layer "In5.Cu")
		(net "P5E_PEX1_STN4_RX_DP<77>")
	)
	(segment
		(start 153.60396 -384.848354)
		(end 153.60396 -368.837464)
		(width 0.1651)
		(layer "In5.Cu")
		(net "P5E_PEX1_STN4_RX_DP<77>")
	)
	(segment
		(start 191.329818 -320.04508)
		(end 191.329818 -316.455298)
		(width 0.1143)
		(layer "In5.Cu")
		(net "P5E_PEX1_STN4_RX_DP<77>")
	)
	(segment
		(start 163.740338 -393.984988)
		(end 163.336478 -393.721082)
		(width 0.1651)
		(layer "In5.Cu")
		(net "P5E_PEX1_STN4_RX_DP<77>")
	)
	(segment
		(start 153.60396 -368.837464)
		(end 154.28976 -366.668812)
		(width 0.1651)
		(layer "In5.Cu")
		(net "P5E_PEX1_STN4_RX_DP<77>")
	)
	(segment
		(start 166.453566 -347.0148)
		(end 167.140382 -346.327984)
		(width 0.1651)
		(layer "In5.Cu")
		(net "P5E_PEX1_STN4_RX_DP<77>")
	)
	(segment
		(start 167.140382 -346.327984)
		(end 167.140382 -341.800688)
		(width 0.1651)
		(layer "In5.Cu")
		(net "P5E_PEX1_STN4_RX_DP<77>")
	)
	(segment
		(start 187.550552 -326.9361)
		(end 190.665608 -322.919852)
		(width 0.1651)
		(layer "In5.Cu")
		(net "P5E_PEX1_STN4_RX_DP<77>")
	)
	(segment
		(start 164.176964 -394.403834)
		(end 163.77285 -394.139674)
		(width 0.1651)
		(layer "In5.Cu")
		(net "P5E_PEX1_STN4_RX_DP<77>")
	)
	(segment
		(start 191.555624 -316.229492)
		(end 191.785748 -316.229492)
		(width 0.1143)
		(layer "In5.Cu")
		(net "P5E_PEX1_STN4_RX_DP<77>")
	)
	(segment
		(start 191.785748 -316.229492)
		(end 191.900048 -316.115192)
		(width 0.1143)
		(layer "In5.Cu")
		(net "P5E_PEX1_STN4_RX_DP<77>")
	)
	(segment
		(start 167.140382 -341.800688)
		(end 168.304972 -340.488016)
		(width 0.1651)
		(layer "In5.Cu")
		(net "P5E_PEX1_STN4_RX_DP<77>")
	)
	(segment
		(start 164.031422 -358.974136)
		(end 164.031422 -347.575378)
		(width 0.1651)
		(layer "In5.Cu")
		(net "P5E_PEX1_STN4_RX_DP<77>")
	)
	(segment
		(start 161.775902 -392.80846)
		(end 161.749994 -392.684508)
		(width 0.1651)
		(layer "In5.Cu")
		(net "P5E_PEX1_STN4_RX_DP<77>")
	)
	(segment
		(start 190.665608 -322.919852)
		(end 191.284098 -321.11442)
		(width 0.1651)
		(layer "In5.Cu")
		(net "P5E_PEX1_STN4_RX_DP<77>")
	)
	(segment
		(start 164.031422 -347.575378)
		(end 164.592 -347.0148)
		(width 0.1651)
		(layer "In5.Cu")
		(net "P5E_PEX1_STN4_RX_DP<77>")
	)
	(segment
		(start 162.768026 -393.444476)
		(end 162.745166 -393.334748)
		(width 0.1651)
		(layer "In5.Cu")
		(net "P5E_PEX1_STN4_RX_DP<77>")
	)
	(segment
		(start 164.869876 -404.799038)
		(end 165.087554 -404.58136)
		(width 0.1651)
		(layer "In5.Cu")
		(net "P5E_PEX1_STN4_RX_DP<77>")
	)
	(segment
		(start 164.33165 -394.371576)
		(end 164.176964 -394.403834)
		(width 0.1651)
		(layer "In5.Cu")
		(net "P5E_PEX1_STN4_RX_DP<77>")
	)
	(segment
		(start 162.217354 -393.097004)
		(end 161.775902 -392.80846)
		(width 0.1651)
		(layer "In5.Cu")
		(net "P5E_PEX1_STN4_RX_DP<77>")
	)
	(segment
		(start 162.745166 -393.334748)
		(end 162.341306 -393.070842)
		(width 0.1651)
		(layer "In5.Cu")
		(net "P5E_PEX1_STN4_RX_DP<77>")
	)
	(segment
		(start 191.900048 -316.115192)
		(end 191.900048 -315.849762)
		(width 0.1143)
		(layer "In5.Cu")
		(net "P5E_PEX1_STN4_RX_DP<77>")
	)
	(segment
		(start 164.592 -347.0148)
		(end 166.453566 -347.0148)
		(width 0.1651)
		(layer "In5.Cu")
		(net "P5E_PEX1_STN4_RX_DP<77>")
	)
	(segment
		(start 164.31006 -404.290022)
		(end 164.31006 -404.672038)
		(width 0.1651)
		(layer "In5.Cu")
		(net "P5E_PEX1_STN4_RX_DP<77>")
	)
	(segment
		(start 164.43706 -404.799038)
		(end 164.869876 -404.799038)
		(width 0.1651)
		(layer "In5.Cu")
		(net "P5E_PEX1_STN4_RX_DP<77>")
	)
	(segment
		(start 160.74898 -392.030458)
		(end 156.705808 -389.886952)
		(width 0.1651)
		(layer "In5.Cu")
		(net "P5E_PEX1_STN4_RX_DP<77>")
	)
	(segment
		(start 154.972512 -388.153656)
		(end 153.60396 -384.848354)
		(width 0.1651)
		(layer "In5.Cu")
		(net "P5E_PEX1_STN4_RX_DP<77>")
	)
	(segment
		(start 164.31006 -404.672038)
		(end 164.43706 -404.799038)
		(width 0.1651)
		(layer "In5.Cu")
		(net "P5E_PEX1_STN4_RX_DP<77>")
	)
	(segment
		(start 156.49702 -364.46333)
		(end 163.855654 -359.149904)
		(width 0.1651)
		(layer "In5.Cu")
		(net "P5E_PEX1_STN4_RX_DP<77>")
	)
	(segment
		(start 180.55717 -333.111602)
		(end 187.550552 -326.9361)
		(width 0.1651)
		(layer "In5.Cu")
		(net "P5E_PEX1_STN4_RX_DP<77>")
	)
	(segment
		(start 168.304972 -340.488016)
		(end 180.55717 -333.111602)
		(width 0.1651)
		(layer "In5.Cu")
		(net "P5E_PEX1_STN4_RX_DP<77>")
	)
	(segment
		(start 161.749994 -392.684508)
		(end 160.74898 -392.030458)
		(width 0.1651)
		(layer "In5.Cu")
		(net "P5E_PEX1_STN4_RX_DP<77>")
	)
	(segment
		(start 191.284098 -320.119248)
		(end 191.284098 -320.0908)
		(width 0.1143)
		(layer "In5.Cu")
		(net "P5E_PEX1_STN4_RX_DP<77>")
	)
	(segment
		(start 178.025552 -357.46309)
		(end 178.025552 -356.831646)
		(width 0.13462)
		(layer "F.Cu")
		(net "P5E_PEX1_STN4_TX_C_DP<71>")
	)
	(segment
		(start 178.025552 -356.831646)
		(end 177.705512 -356.511606)
		(width 0.13462)
		(layer "F.Cu")
		(net "P5E_PEX1_STN4_TX_C_DP<71>")
	)
	(segment
		(start 177.730912 -357.75773)
		(end 178.025552 -357.46309)
		(width 0.13462)
		(layer "F.Cu")
		(net "P5E_PEX1_STN4_TX_C_DP<71>")
	)
	(segment
		(start 165.689026 -365.676942)
		(end 165.239446 -365.88446)
		(width 0.1651)
		(layer "In7.Cu")
		(net "P5E_PEX1_STN4_TX_C_DP<71>")
	)
	(segment
		(start 178.021742 -358.903524)
		(end 177.203862 -359.69448)
		(width 0.1651)
		(layer "In7.Cu")
		(net "P5E_PEX1_STN4_TX_C_DP<71>")
	)
	(segment
		(start 170.074844 -363.539532)
		(end 170.025314 -363.674406)
		(width 0.1651)
		(layer "In7.Cu")
		(net "P5E_PEX1_STN4_TX_C_DP<71>")
	)
	(segment
		(start 160.037018 -370.999004)
		(end 159.910018 -370.872004)
		(width 0.1651)
		(layer "In7.Cu")
		(net "P5E_PEX1_STN4_TX_C_DP<71>")
	)
	(segment
		(start 167.272716 -364.833662)
		(end 166.822628 -365.041434)
		(width 0.1651)
		(layer "In7.Cu")
		(net "P5E_PEX1_STN4_TX_C_DP<71>")
	)
	(segment
		(start 161.633154 -368.145568)
		(end 160.687512 -369.3922)
		(width 0.1651)
		(layer "In7.Cu")
		(net "P5E_PEX1_STN4_TX_C_DP<71>")
	)
	(segment
		(start 160.687512 -369.3922)
		(end 160.687512 -370.580666)
		(width 0.1651)
		(layer "In7.Cu")
		(net "P5E_PEX1_STN4_TX_C_DP<71>")
	)
	(segment
		(start 177.730912 -357.75773)
		(end 178.021742 -358.04856)
		(width 0.1651)
		(layer "In7.Cu")
		(net "P5E_PEX1_STN4_TX_C_DP<71>")
	)
	(segment
		(start 170.524932 -363.33176)
		(end 170.074844 -363.539532)
		(width 0.1651)
		(layer "In7.Cu")
		(net "P5E_PEX1_STN4_TX_C_DP<71>")
	)
	(segment
		(start 166.188644 -365.334296)
		(end 165.738556 -365.542068)
		(width 0.1651)
		(layer "In7.Cu")
		(net "P5E_PEX1_STN4_TX_C_DP<71>")
	)
	(segment
		(start 178.021742 -358.04856)
		(end 178.021742 -358.903524)
		(width 0.1651)
		(layer "In7.Cu")
		(net "P5E_PEX1_STN4_TX_C_DP<71>")
	)
	(segment
		(start 167.9067 -364.5408)
		(end 167.85717 -364.675674)
		(width 0.1651)
		(layer "In7.Cu")
		(net "P5E_PEX1_STN4_TX_C_DP<71>")
	)
	(segment
		(start 166.822628 -365.041434)
		(end 166.773098 -365.176308)
		(width 0.1651)
		(layer "In7.Cu")
		(net "P5E_PEX1_STN4_TX_C_DP<71>")
	)
	(segment
		(start 169.575734 -363.881924)
		(end 169.44086 -363.832394)
		(width 0.1651)
		(layer "In7.Cu")
		(net "P5E_PEX1_STN4_TX_C_DP<71>")
	)
	(segment
		(start 177.060098 -359.69194)
		(end 176.703736 -360.036618)
		(width 0.1651)
		(layer "In7.Cu")
		(net "P5E_PEX1_STN4_TX_C_DP<71>")
	)
	(segment
		(start 175.887126 -360.967528)
		(end 170.659806 -363.38129)
		(width 0.1651)
		(layer "In7.Cu")
		(net "P5E_PEX1_STN4_TX_C_DP<71>")
	)
	(segment
		(start 170.025314 -363.674406)
		(end 169.575734 -363.881924)
		(width 0.1651)
		(layer "In7.Cu")
		(net "P5E_PEX1_STN4_TX_C_DP<71>")
	)
	(segment
		(start 165.104572 -365.83493)
		(end 164.654738 -366.042702)
		(width 0.1651)
		(layer "In7.Cu")
		(net "P5E_PEX1_STN4_TX_C_DP<71>")
	)
	(segment
		(start 166.773098 -365.176308)
		(end 166.323518 -365.383826)
		(width 0.1651)
		(layer "In7.Cu")
		(net "P5E_PEX1_STN4_TX_C_DP<71>")
	)
	(segment
		(start 166.323518 -365.383826)
		(end 166.188644 -365.334296)
		(width 0.1651)
		(layer "In7.Cu")
		(net "P5E_PEX1_STN4_TX_C_DP<71>")
	)
	(segment
		(start 177.203862 -359.69448)
		(end 177.060098 -359.69194)
		(width 0.1651)
		(layer "In7.Cu")
		(net "P5E_PEX1_STN4_TX_C_DP<71>")
	)
	(segment
		(start 165.738556 -365.542068)
		(end 165.689026 -365.676942)
		(width 0.1651)
		(layer "In7.Cu")
		(net "P5E_PEX1_STN4_TX_C_DP<71>")
	)
	(segment
		(start 164.654738 -366.042702)
		(end 164.604954 -366.177576)
		(width 0.1651)
		(layer "In7.Cu")
		(net "P5E_PEX1_STN4_TX_C_DP<71>")
	)
	(segment
		(start 176.703736 -360.036618)
		(end 176.70145 -360.180128)
		(width 0.1651)
		(layer "In7.Cu")
		(net "P5E_PEX1_STN4_TX_C_DP<71>")
	)
	(segment
		(start 176.70145 -360.180128)
		(end 175.887126 -360.967528)
		(width 0.1651)
		(layer "In7.Cu")
		(net "P5E_PEX1_STN4_TX_C_DP<71>")
	)
	(segment
		(start 168.491662 -364.382558)
		(end 168.356788 -364.333028)
		(width 0.1651)
		(layer "In7.Cu")
		(net "P5E_PEX1_STN4_TX_C_DP<71>")
	)
	(segment
		(start 160.269174 -370.999004)
		(end 160.037018 -370.999004)
		(width 0.1651)
		(layer "In7.Cu")
		(net "P5E_PEX1_STN4_TX_C_DP<71>")
	)
	(segment
		(start 170.659806 -363.38129)
		(end 170.524932 -363.33176)
		(width 0.1651)
		(layer "In7.Cu")
		(net "P5E_PEX1_STN4_TX_C_DP<71>")
	)
	(segment
		(start 168.990772 -364.040166)
		(end 168.941242 -364.17504)
		(width 0.1651)
		(layer "In7.Cu")
		(net "P5E_PEX1_STN4_TX_C_DP<71>")
	)
	(segment
		(start 164.604954 -366.177576)
		(end 163.373308 -366.746282)
		(width 0.1651)
		(layer "In7.Cu")
		(net "P5E_PEX1_STN4_TX_C_DP<71>")
	)
	(segment
		(start 163.373308 -366.746282)
		(end 161.633154 -368.145568)
		(width 0.1651)
		(layer "In7.Cu")
		(net "P5E_PEX1_STN4_TX_C_DP<71>")
	)
	(segment
		(start 167.85717 -364.675674)
		(end 167.40759 -364.883192)
		(width 0.1651)
		(layer "In7.Cu")
		(net "P5E_PEX1_STN4_TX_C_DP<71>")
	)
	(segment
		(start 167.40759 -364.883192)
		(end 167.272716 -364.833662)
		(width 0.1651)
		(layer "In7.Cu")
		(net "P5E_PEX1_STN4_TX_C_DP<71>")
	)
	(segment
		(start 168.941242 -364.17504)
		(end 168.491662 -364.382558)
		(width 0.1651)
		(layer "In7.Cu")
		(net "P5E_PEX1_STN4_TX_C_DP<71>")
	)
	(segment
		(start 169.44086 -363.832394)
		(end 168.990772 -364.040166)
		(width 0.1651)
		(layer "In7.Cu")
		(net "P5E_PEX1_STN4_TX_C_DP<71>")
	)
	(segment
		(start 159.910018 -370.872004)
		(end 159.910018 -370.489988)
		(width 0.1651)
		(layer "In7.Cu")
		(net "P5E_PEX1_STN4_TX_C_DP<71>")
	)
	(segment
		(start 165.239446 -365.88446)
		(end 165.104572 -365.83493)
		(width 0.1651)
		(layer "In7.Cu")
		(net "P5E_PEX1_STN4_TX_C_DP<71>")
	)
	(segment
		(start 160.687512 -370.580666)
		(end 160.269174 -370.999004)
		(width 0.1651)
		(layer "In7.Cu")
		(net "P5E_PEX1_STN4_TX_C_DP<71>")
	)
	(segment
		(start 168.356788 -364.333028)
		(end 167.9067 -364.5408)
		(width 0.1651)
		(layer "In7.Cu")
		(net "P5E_PEX1_STN4_TX_C_DP<71>")
	)
	(segment
		(start 193.178176 -324.727824)
		(end 194.133978 -321.691)
		(width 0.1651)
		(layer "In5.Cu")
		(net "P5E_PEX1_STN4_RX_DP<74>")
	)
	(segment
		(start 176.467262 -341.685372)
		(end 185.18886 -333.65948)
		(width 0.1651)
		(layer "In5.Cu")
		(net "P5E_PEX1_STN4_RX_DP<74>")
	)
	(segment
		(start 171.68749 -405.681434)
		(end 171.68749 -395.482318)
		(width 0.1651)
		(layer "In5.Cu")
		(net "P5E_PEX1_STN4_RX_DP<74>")
	)
	(segment
		(start 164.755322 -390.489948)
		(end 161.621724 -388.873238)
		(width 0.1651)
		(layer "In5.Cu")
		(net "P5E_PEX1_STN4_RX_DP<74>")
	)
	(segment
		(start 170.489118 -394.283946)
		(end 165.203886 -390.754108)
		(width 0.1651)
		(layer "In5.Cu")
		(net "P5E_PEX1_STN4_RX_DP<74>")
	)
	(segment
		(start 158.383478 -387.511798)
		(end 157.403546 -386.531866)
		(width 0.1651)
		(layer "In5.Cu")
		(net "P5E_PEX1_STN4_RX_DP<74>")
	)
	(segment
		(start 171.036996 -405.899112)
		(end 171.469812 -405.899112)
		(width 0.1651)
		(layer "In5.Cu")
		(net "P5E_PEX1_STN4_RX_DP<74>")
	)
	(segment
		(start 190.023496 -328.774552)
		(end 191.718692 -326.817228)
		(width 0.1651)
		(layer "In5.Cu")
		(net "P5E_PEX1_STN4_RX_DP<74>")
	)
	(segment
		(start 171.469812 -405.899112)
		(end 171.68749 -405.681434)
		(width 0.1651)
		(layer "In5.Cu")
		(net "P5E_PEX1_STN4_RX_DP<74>")
	)
	(segment
		(start 162.002216 -364.027212)
		(end 170.486324 -360.296714)
		(width 0.1651)
		(layer "In5.Cu")
		(net "P5E_PEX1_STN4_RX_DP<74>")
	)
	(segment
		(start 165.203886 -390.754108)
		(end 164.755322 -390.489948)
		(width 0.1651)
		(layer "In5.Cu")
		(net "P5E_PEX1_STN4_RX_DP<74>")
	)
	(segment
		(start 156.51226 -369.406424)
		(end 157.098746 -367.913158)
		(width 0.1651)
		(layer "In5.Cu")
		(net "P5E_PEX1_STN4_RX_DP<74>")
	)
	(segment
		(start 194.179698 -318.355472)
		(end 194.405504 -318.129666)
		(width 0.1143)
		(layer "In5.Cu")
		(net "P5E_PEX1_STN4_RX_DP<74>")
	)
	(segment
		(start 156.51226 -384.381756)
		(end 156.51226 -369.406424)
		(width 0.1651)
		(layer "In5.Cu")
		(net "P5E_PEX1_STN4_RX_DP<74>")
	)
	(segment
		(start 158.35376 -366.65916)
		(end 162.002216 -364.027212)
		(width 0.1651)
		(layer "In5.Cu")
		(net "P5E_PEX1_STN4_RX_DP<74>")
	)
	(segment
		(start 194.133978 -320.119248)
		(end 194.133978 -320.0908)
		(width 0.1143)
		(layer "In5.Cu")
		(net "P5E_PEX1_STN4_RX_DP<74>")
	)
	(segment
		(start 191.718692 -326.817228)
		(end 193.178176 -324.727824)
		(width 0.1651)
		(layer "In5.Cu")
		(net "P5E_PEX1_STN4_RX_DP<74>")
	)
	(segment
		(start 194.749928 -318.015366)
		(end 194.749928 -317.749936)
		(width 0.1143)
		(layer "In5.Cu")
		(net "P5E_PEX1_STN4_RX_DP<74>")
	)
	(segment
		(start 170.84675 -394.799566)
		(end 170.84675 -394.641578)
		(width 0.1651)
		(layer "In5.Cu")
		(net "P5E_PEX1_STN4_RX_DP<74>")
	)
	(segment
		(start 171.68749 -395.482318)
		(end 171.346368 -395.141196)
		(width 0.1651)
		(layer "In5.Cu")
		(net "P5E_PEX1_STN4_RX_DP<74>")
	)
	(segment
		(start 170.909996 -405.772112)
		(end 171.036996 -405.899112)
		(width 0.1651)
		(layer "In5.Cu")
		(net "P5E_PEX1_STN4_RX_DP<74>")
	)
	(segment
		(start 194.133978 -321.691)
		(end 194.133978 -320.119248)
		(width 0.1651)
		(layer "In5.Cu")
		(net "P5E_PEX1_STN4_RX_DP<74>")
	)
	(segment
		(start 194.405504 -318.129666)
		(end 194.635628 -318.129666)
		(width 0.1143)
		(layer "In5.Cu")
		(net "P5E_PEX1_STN4_RX_DP<74>")
	)
	(segment
		(start 157.098746 -367.913158)
		(end 158.35376 -366.65916)
		(width 0.1651)
		(layer "In5.Cu")
		(net "P5E_PEX1_STN4_RX_DP<74>")
	)
	(segment
		(start 171.780962 -359.687876)
		(end 171.780962 -359.68813)
		(width 0.1651)
		(layer "In5.Cu")
		(net "P5E_PEX1_STN4_RX_DP<74>")
	)
	(segment
		(start 174.0662 -353.06)
		(end 175.959262 -353.06)
		(width 0.1651)
		(layer "In5.Cu")
		(net "P5E_PEX1_STN4_RX_DP<74>")
	)
	(segment
		(start 175.959262 -353.06)
		(end 176.467262 -352.552)
		(width 0.1651)
		(layer "In5.Cu")
		(net "P5E_PEX1_STN4_RX_DP<74>")
	)
	(segment
		(start 194.179698 -320.04508)
		(end 194.179698 -318.355472)
		(width 0.1143)
		(layer "In5.Cu")
		(net "P5E_PEX1_STN4_RX_DP<74>")
	)
	(segment
		(start 170.909996 -405.390096)
		(end 170.909996 -405.772112)
		(width 0.1651)
		(layer "In5.Cu")
		(net "P5E_PEX1_STN4_RX_DP<74>")
	)
	(segment
		(start 176.467262 -352.552)
		(end 176.467262 -341.685372)
		(width 0.1651)
		(layer "In5.Cu")
		(net "P5E_PEX1_STN4_RX_DP<74>")
	)
	(segment
		(start 171.346368 -395.141196)
		(end 171.18838 -395.141196)
		(width 0.1651)
		(layer "In5.Cu")
		(net "P5E_PEX1_STN4_RX_DP<74>")
	)
	(segment
		(start 171.780962 -359.68813)
		(end 173.075346 -359.079546)
		(width 0.1651)
		(layer "In5.Cu")
		(net "P5E_PEX1_STN4_RX_DP<74>")
	)
	(segment
		(start 173.358302 -358.79659)
		(end 173.358302 -353.767898)
		(width 0.1651)
		(layer "In5.Cu")
		(net "P5E_PEX1_STN4_RX_DP<74>")
	)
	(segment
		(start 171.18838 -395.141196)
		(end 170.84675 -394.799566)
		(width 0.1651)
		(layer "In5.Cu")
		(net "P5E_PEX1_STN4_RX_DP<74>")
	)
	(segment
		(start 170.84675 -394.641578)
		(end 170.489118 -394.283946)
		(width 0.1651)
		(layer "In5.Cu")
		(net "P5E_PEX1_STN4_RX_DP<74>")
	)
	(segment
		(start 194.133978 -320.0908)
		(end 194.179698 -320.04508)
		(width 0.1143)
		(layer "In5.Cu")
		(net "P5E_PEX1_STN4_RX_DP<74>")
	)
	(segment
		(start 157.403546 -386.531866)
		(end 156.51226 -384.381756)
		(width 0.1651)
		(layer "In5.Cu")
		(net "P5E_PEX1_STN4_RX_DP<74>")
	)
	(segment
		(start 170.486324 -360.296714)
		(end 171.780962 -359.687876)
		(width 0.1651)
		(layer "In5.Cu")
		(net "P5E_PEX1_STN4_RX_DP<74>")
	)
	(segment
		(start 173.075346 -359.079546)
		(end 173.358302 -358.79659)
		(width 0.1651)
		(layer "In5.Cu")
		(net "P5E_PEX1_STN4_RX_DP<74>")
	)
	(segment
		(start 194.635628 -318.129666)
		(end 194.749928 -318.015366)
		(width 0.1143)
		(layer "In5.Cu")
		(net "P5E_PEX1_STN4_RX_DP<74>")
	)
	(segment
		(start 173.358302 -353.767898)
		(end 174.0662 -353.06)
		(width 0.1651)
		(layer "In5.Cu")
		(net "P5E_PEX1_STN4_RX_DP<74>")
	)
	(segment
		(start 185.18886 -333.65948)
		(end 190.023496 -328.774552)
		(width 0.1651)
		(layer "In5.Cu")
		(net "P5E_PEX1_STN4_RX_DP<74>")
	)
	(segment
		(start 161.621724 -388.873238)
		(end 158.383478 -387.511798)
		(width 0.1651)
		(layer "In5.Cu")
		(net "P5E_PEX1_STN4_RX_DP<74>")
	)
	(segment
		(start 178.299872 -344.539062)
		(end 178.619912 -344.219022)
		(width 0.13462)
		(layer "F.Cu")
		(net "P5E_PEX1_STN4_TX_C_DN<72>")
	)
	(segment
		(start 178.299872 -345.170506)
		(end 178.299872 -344.539062)
		(width 0.13462)
		(layer "F.Cu")
		(net "P5E_PEX1_STN4_TX_C_DN<72>")
	)
	(segment
		(start 178.594512 -345.465146)
		(end 178.299872 -345.170506)
		(width 0.13462)
		(layer "F.Cu")
		(net "P5E_PEX1_STN4_TX_C_DN<72>")
	)
	(segment
		(start 176.369472 -395.629892)
		(end 174.233332 -393.493752)
		(width 0.1651)
		(layer "In7.Cu")
		(net "P5E_PEX1_STN4_TX_C_DN<72>")
	)
	(segment
		(start 175.310038 -398.890236)
		(end 175.310038 -398.50822)
		(width 0.1651)
		(layer "In7.Cu")
		(net "P5E_PEX1_STN4_TX_C_DN<72>")
	)
	(segment
		(start 178.303682 -346.503498)
		(end 178.303682 -345.755976)
		(width 0.1651)
		(layer "In7.Cu")
		(net "P5E_PEX1_STN4_TX_C_DN<72>")
	)
	(segment
		(start 158.70428 -370.249958)
		(end 158.884366 -369.746276)
		(width 0.1651)
		(layer "In7.Cu")
		(net "P5E_PEX1_STN4_TX_C_DN<72>")
	)
	(segment
		(start 170.273472 -390.840976)
		(end 163.31311 -387.20014)
		(width 0.1651)
		(layer "In7.Cu")
		(net "P5E_PEX1_STN4_TX_C_DN<72>")
	)
	(segment
		(start 159.93491 -367.941098)
		(end 163.280344 -365.62792)
		(width 0.1651)
		(layer "In7.Cu")
		(net "P5E_PEX1_STN4_TX_C_DN<72>")
	)
	(segment
		(start 163.31311 -387.20014)
		(end 159.683196 -385.67487)
		(width 0.1651)
		(layer "In7.Cu")
		(net "P5E_PEX1_STN4_TX_C_DN<72>")
	)
	(segment
		(start 175.786034 -398.380966)
		(end 176.369472 -397.797528)
		(width 0.1651)
		(layer "In7.Cu")
		(net "P5E_PEX1_STN4_TX_C_DN<72>")
	)
	(segment
		(start 174.233332 -393.493752)
		(end 170.273472 -390.840976)
		(width 0.1651)
		(layer "In7.Cu")
		(net "P5E_PEX1_STN4_TX_C_DN<72>")
	)
	(segment
		(start 172.698918 -361.692952)
		(end 175.691546 -359.783634)
		(width 0.1651)
		(layer "In7.Cu")
		(net "P5E_PEX1_STN4_TX_C_DN<72>")
	)
	(segment
		(start 158.884366 -369.746276)
		(end 159.247332 -368.915442)
		(width 0.1651)
		(layer "In7.Cu")
		(net "P5E_PEX1_STN4_TX_C_DN<72>")
	)
	(segment
		(start 175.691546 -359.783634)
		(end 176.749202 -358.725978)
		(width 0.1651)
		(layer "In7.Cu")
		(net "P5E_PEX1_STN4_TX_C_DN<72>")
	)
	(segment
		(start 159.247332 -368.915442)
		(end 159.93491 -367.941098)
		(width 0.1651)
		(layer "In7.Cu")
		(net "P5E_PEX1_STN4_TX_C_DN<72>")
	)
	(segment
		(start 178.303682 -345.755976)
		(end 178.594512 -345.465146)
		(width 0.1651)
		(layer "In7.Cu")
		(net "P5E_PEX1_STN4_TX_C_DN<72>")
	)
	(segment
		(start 159.683196 -385.67487)
		(end 159.258254 -385.249928)
		(width 0.1651)
		(layer "In7.Cu")
		(net "P5E_PEX1_STN4_TX_C_DN<72>")
	)
	(segment
		(start 176.749202 -358.725978)
		(end 176.749202 -348.057978)
		(width 0.1651)
		(layer "In7.Cu")
		(net "P5E_PEX1_STN4_TX_C_DN<72>")
	)
	(segment
		(start 175.310038 -398.50822)
		(end 175.437292 -398.380966)
		(width 0.1651)
		(layer "In7.Cu")
		(net "P5E_PEX1_STN4_TX_C_DN<72>")
	)
	(segment
		(start 175.437292 -398.380966)
		(end 175.786034 -398.380966)
		(width 0.1651)
		(layer "In7.Cu")
		(net "P5E_PEX1_STN4_TX_C_DN<72>")
	)
	(segment
		(start 163.280344 -365.62792)
		(end 172.698918 -361.692952)
		(width 0.1651)
		(layer "In7.Cu")
		(net "P5E_PEX1_STN4_TX_C_DN<72>")
	)
	(segment
		(start 159.258254 -385.249928)
		(end 158.70428 -383.94259)
		(width 0.1651)
		(layer "In7.Cu")
		(net "P5E_PEX1_STN4_TX_C_DN<72>")
	)
	(segment
		(start 176.369472 -397.797528)
		(end 176.369472 -395.629892)
		(width 0.1651)
		(layer "In7.Cu")
		(net "P5E_PEX1_STN4_TX_C_DN<72>")
	)
	(segment
		(start 176.749202 -348.057978)
		(end 178.303682 -346.503498)
		(width 0.1651)
		(layer "In7.Cu")
		(net "P5E_PEX1_STN4_TX_C_DN<72>")
	)
	(segment
		(start 158.70428 -383.94259)
		(end 158.70428 -370.249958)
		(width 0.1651)
		(layer "In7.Cu")
		(net "P5E_PEX1_STN4_TX_C_DN<72>")
	)
	(segment
		(start 193.844672 -351.316798)
		(end 193.844672 -350.685354)
		(width 0.13462)
		(layer "F.Cu")
		(net "P5E_PEX1_STN4_TX_C_DN<65>")
	)
	(segment
		(start 194.139312 -351.611438)
		(end 193.844672 -351.316798)
		(width 0.13462)
		(layer "F.Cu")
		(net "P5E_PEX1_STN4_TX_C_DN<65>")
	)
	(segment
		(start 193.844672 -350.685354)
		(end 194.164712 -350.365314)
		(width 0.13462)
		(layer "F.Cu")
		(net "P5E_PEX1_STN4_TX_C_DN<65>")
	)
	(segment
		(start 173.10989 -371.790214)
		(end 173.10989 -371.408198)
		(width 0.1651)
		(layer "In7.Cu")
		(net "P5E_PEX1_STN4_TX_C_DN<65>")
	)
	(segment
		(start 193.848482 -353.11842)
		(end 193.848482 -351.902268)
		(width 0.1651)
		(layer "In7.Cu")
		(net "P5E_PEX1_STN4_TX_C_DN<65>")
	)
	(segment
		(start 188.83503 -360.605578)
		(end 192.089278 -357.351076)
		(width 0.1651)
		(layer "In7.Cu")
		(net "P5E_PEX1_STN4_TX_C_DN<65>")
	)
	(segment
		(start 174.919386 -368.396012)
		(end 183.54167 -364.977934)
		(width 0.1651)
		(layer "In7.Cu")
		(net "P5E_PEX1_STN4_TX_C_DN<65>")
	)
	(segment
		(start 174.480474 -368.785902)
		(end 174.919386 -368.396012)
		(width 0.1651)
		(layer "In7.Cu")
		(net "P5E_PEX1_STN4_TX_C_DN<65>")
	)
	(segment
		(start 174.169324 -369.359942)
		(end 174.480474 -368.785902)
		(width 0.1651)
		(layer "In7.Cu")
		(net "P5E_PEX1_STN4_TX_C_DN<65>")
	)
	(segment
		(start 173.585886 -371.280944)
		(end 174.169324 -370.697506)
		(width 0.1651)
		(layer "In7.Cu")
		(net "P5E_PEX1_STN4_TX_C_DN<65>")
	)
	(segment
		(start 192.089278 -357.351076)
		(end 193.848482 -353.11842)
		(width 0.1651)
		(layer "In7.Cu")
		(net "P5E_PEX1_STN4_TX_C_DN<65>")
	)
	(segment
		(start 193.848482 -351.902268)
		(end 194.139312 -351.611438)
		(width 0.1651)
		(layer "In7.Cu")
		(net "P5E_PEX1_STN4_TX_C_DN<65>")
	)
	(segment
		(start 174.169324 -370.697506)
		(end 174.169324 -369.359942)
		(width 0.1651)
		(layer "In7.Cu")
		(net "P5E_PEX1_STN4_TX_C_DN<65>")
	)
	(segment
		(start 173.237144 -371.280944)
		(end 173.585886 -371.280944)
		(width 0.1651)
		(layer "In7.Cu")
		(net "P5E_PEX1_STN4_TX_C_DN<65>")
	)
	(segment
		(start 183.54167 -364.977934)
		(end 188.83503 -360.605578)
		(width 0.1651)
		(layer "In7.Cu")
		(net "P5E_PEX1_STN4_TX_C_DN<65>")
	)
	(segment
		(start 173.10989 -371.408198)
		(end 173.237144 -371.280944)
		(width 0.1651)
		(layer "In7.Cu")
		(net "P5E_PEX1_STN4_TX_C_DN<65>")
	)
	(segment
		(start 190.735712 -345.170506)
		(end 190.735712 -344.539062)
		(width 0.13462)
		(layer "F.Cu")
		(net "P5E_PEX1_STN4_TX_C_DN<66>")
	)
	(segment
		(start 191.030352 -345.465146)
		(end 190.735712 -345.170506)
		(width 0.13462)
		(layer "F.Cu")
		(net "P5E_PEX1_STN4_TX_C_DN<66>")
	)
	(segment
		(start 190.735712 -344.539062)
		(end 191.055752 -344.219022)
		(width 0.13462)
		(layer "F.Cu")
		(net "P5E_PEX1_STN4_TX_C_DN<66>")
	)
	(segment
		(start 190.739522 -346.412058)
		(end 190.739522 -345.755976)
		(width 0.1651)
		(layer "In7.Cu")
		(net "P5E_PEX1_STN4_TX_C_DN<66>")
	)
	(segment
		(start 188.467238 -359.296716)
		(end 189.185042 -358.578912)
		(width 0.1651)
		(layer "In7.Cu")
		(net "P5E_PEX1_STN4_TX_C_DN<66>")
	)
	(segment
		(start 171.03725 -372.380764)
		(end 171.385992 -372.380764)
		(width 0.1651)
		(layer "In7.Cu")
		(net "P5E_PEX1_STN4_TX_C_DN<66>")
	)
	(segment
		(start 172.306996 -368.9477)
		(end 173.44898 -367.957862)
		(width 0.1651)
		(layer "In7.Cu")
		(net "P5E_PEX1_STN4_TX_C_DN<66>")
	)
	(segment
		(start 170.909996 -372.890034)
		(end 170.909996 -372.508018)
		(width 0.1651)
		(layer "In7.Cu")
		(net "P5E_PEX1_STN4_TX_C_DN<66>")
	)
	(segment
		(start 171.96943 -369.565936)
		(end 172.306996 -368.9477)
		(width 0.1651)
		(layer "In7.Cu")
		(net "P5E_PEX1_STN4_TX_C_DN<66>")
	)
	(segment
		(start 182.187088 -364.430818)
		(end 188.467238 -359.296716)
		(width 0.1651)
		(layer "In7.Cu")
		(net "P5E_PEX1_STN4_TX_C_DN<66>")
	)
	(segment
		(start 189.185042 -347.966538)
		(end 190.739522 -346.412058)
		(width 0.1651)
		(layer "In7.Cu")
		(net "P5E_PEX1_STN4_TX_C_DN<66>")
	)
	(segment
		(start 190.739522 -345.755976)
		(end 191.030352 -345.465146)
		(width 0.1651)
		(layer "In7.Cu")
		(net "P5E_PEX1_STN4_TX_C_DN<66>")
	)
	(segment
		(start 171.96943 -371.797326)
		(end 171.96943 -369.565936)
		(width 0.1651)
		(layer "In7.Cu")
		(net "P5E_PEX1_STN4_TX_C_DN<66>")
	)
	(segment
		(start 171.385992 -372.380764)
		(end 171.96943 -371.797326)
		(width 0.1651)
		(layer "In7.Cu")
		(net "P5E_PEX1_STN4_TX_C_DN<66>")
	)
	(segment
		(start 189.185042 -358.578912)
		(end 189.185042 -347.966538)
		(width 0.1651)
		(layer "In7.Cu")
		(net "P5E_PEX1_STN4_TX_C_DN<66>")
	)
	(segment
		(start 170.909996 -372.508018)
		(end 171.03725 -372.380764)
		(width 0.1651)
		(layer "In7.Cu")
		(net "P5E_PEX1_STN4_TX_C_DN<66>")
	)
	(segment
		(start 173.44898 -367.957862)
		(end 182.187088 -364.430818)
		(width 0.1651)
		(layer "In7.Cu")
		(net "P5E_PEX1_STN4_TX_C_DN<66>")
	)
	(segment
		(start 165.589712 -355.026722)
		(end 165.295072 -354.732082)
		(width 0.13462)
		(layer "F.Cu")
		(net "P5E_PEX1_STN4_TX_DP<77>")
	)
	(segment
		(start 165.589712 -355.658166)
		(end 165.589712 -355.026722)
		(width 0.13462)
		(layer "F.Cu")
		(net "P5E_PEX1_STN4_TX_DP<77>")
	)
	(segment
		(start 165.269672 -355.978206)
		(end 165.589712 -355.658166)
		(width 0.13462)
		(layer "F.Cu")
		(net "P5E_PEX1_STN4_TX_DP<77>")
	)
	(segment
		(start 191.329818 -319.942718)
		(end 191.329818 -311.705498)
		(width 0.1143)
		(layer "In7.Cu")
		(net "P5E_PEX1_STN4_TX_DP<77>")
	)
	(segment
		(start 191.284098 -320.016886)
		(end 191.284098 -319.988438)
		(width 0.1143)
		(layer "In7.Cu")
		(net "P5E_PEX1_STN4_TX_DP<77>")
	)
	(segment
		(start 191.900048 -311.365392)
		(end 191.900048 -311.099962)
		(width 0.1143)
		(layer "In7.Cu")
		(net "P5E_PEX1_STN4_TX_DP<77>")
	)
	(segment
		(start 167.140382 -352.119438)
		(end 167.140382 -341.247984)
		(width 0.1651)
		(layer "In7.Cu")
		(net "P5E_PEX1_STN4_TX_DP<77>")
	)
	(segment
		(start 168.189656 -340.19871)
		(end 183.298084 -330.10348)
		(width 0.1651)
		(layer "In7.Cu")
		(net "P5E_PEX1_STN4_TX_DP<77>")
	)
	(segment
		(start 165.295072 -354.732082)
		(end 165.585902 -354.441252)
		(width 0.1651)
		(layer "In7.Cu")
		(net "P5E_PEX1_STN4_TX_DP<77>")
	)
	(segment
		(start 191.284098 -319.988438)
		(end 191.329818 -319.942718)
		(width 0.1143)
		(layer "In7.Cu")
		(net "P5E_PEX1_STN4_TX_DP<77>")
	)
	(segment
		(start 165.585902 -353.673918)
		(end 167.140382 -352.119438)
		(width 0.1651)
		(layer "In7.Cu")
		(net "P5E_PEX1_STN4_TX_DP<77>")
	)
	(segment
		(start 165.585902 -354.441252)
		(end 165.585902 -353.673918)
		(width 0.1651)
		(layer "In7.Cu")
		(net "P5E_PEX1_STN4_TX_DP<77>")
	)
	(segment
		(start 191.785748 -311.479692)
		(end 191.900048 -311.365392)
		(width 0.1143)
		(layer "In7.Cu")
		(net "P5E_PEX1_STN4_TX_DP<77>")
	)
	(segment
		(start 191.329818 -311.705498)
		(end 191.555624 -311.479692)
		(width 0.1143)
		(layer "In7.Cu")
		(net "P5E_PEX1_STN4_TX_DP<77>")
	)
	(segment
		(start 191.555624 -311.479692)
		(end 191.785748 -311.479692)
		(width 0.1143)
		(layer "In7.Cu")
		(net "P5E_PEX1_STN4_TX_DP<77>")
	)
	(segment
		(start 191.284098 -320.872104)
		(end 191.284098 -320.016886)
		(width 0.1651)
		(layer "In7.Cu")
		(net "P5E_PEX1_STN4_TX_DP<77>")
	)
	(segment
		(start 167.140382 -341.247984)
		(end 168.189656 -340.19871)
		(width 0.1651)
		(layer "In7.Cu")
		(net "P5E_PEX1_STN4_TX_DP<77>")
	)
	(segment
		(start 183.298084 -330.10348)
		(end 190.40348 -322.998084)
		(width 0.1651)
		(layer "In7.Cu")
		(net "P5E_PEX1_STN4_TX_DP<77>")
	)
	(segment
		(start 190.40348 -322.998084)
		(end 191.284098 -320.872104)
		(width 0.1651)
		(layer "In7.Cu")
		(net "P5E_PEX1_STN4_TX_DP<77>")
	)
	(segment
		(start 190.735712 -343.365582)
		(end 190.735712 -342.734138)
		(width 0.13462)
		(layer "F.Cu")
		(net "P5E_PEX1_STN4_TX_DN<66>")
	)
	(segment
		(start 191.055752 -343.685622)
		(end 190.735712 -343.365582)
		(width 0.13462)
		(layer "F.Cu")
		(net "P5E_PEX1_STN4_TX_DN<66>")
	)
	(segment
		(start 190.735712 -342.734138)
		(end 191.030352 -342.439498)
		(width 0.13462)
		(layer "F.Cu")
		(net "P5E_PEX1_STN4_TX_DN<66>")
	)
	(segment
		(start 199.69988 -306.729638)
		(end 191.634618 -306.729638)
		(width 0.1143)
		(layer "In7.Cu")
		(net "P5E_PEX1_STN4_TX_DN<66>")
	)
	(segment
		(start 191.634618 -306.349908)
		(end 191.900048 -306.349908)
		(width 0.1143)
		(layer "In7.Cu")
		(net "P5E_PEX1_STN4_TX_DN<66>")
	)
	(segment
		(start 191.520318 -306.464208)
		(end 191.634618 -306.349908)
		(width 0.1143)
		(layer "In7.Cu")
		(net "P5E_PEX1_STN4_TX_DN<66>")
	)
	(segment
		(start 191.030352 -342.439498)
		(end 190.739522 -342.148668)
		(width 0.1651)
		(layer "In7.Cu")
		(net "P5E_PEX1_STN4_TX_DN<66>")
	)
	(segment
		(start 211.749386 -324.852538)
		(end 213.00948 -321.81038)
		(width 0.1651)
		(layer "In7.Cu")
		(net "P5E_PEX1_STN4_TX_DN<66>")
	)
	(segment
		(start 202.064874 -307.36413)
		(end 200.420986 -306.683918)
		(width 0.1651)
		(layer "In7.Cu")
		(net "P5E_PEX1_STN4_TX_DN<66>")
	)
	(segment
		(start 191.520318 -306.615338)
		(end 191.520318 -306.464208)
		(width 0.1143)
		(layer "In7.Cu")
		(net "P5E_PEX1_STN4_TX_DN<66>")
	)
	(segment
		(start 190.91275 -341.297768)
		(end 190.91275 -341.298022)
		(width 0.1651)
		(layer "In7.Cu")
		(net "P5E_PEX1_STN4_TX_DN<66>")
	)
	(segment
		(start 190.739522 -342.148668)
		(end 190.739522 -341.676228)
		(width 0.1651)
		(layer "In7.Cu")
		(net "P5E_PEX1_STN4_TX_DN<66>")
	)
	(segment
		(start 190.739522 -341.676228)
		(end 190.91275 -341.297768)
		(width 0.1651)
		(layer "In7.Cu")
		(net "P5E_PEX1_STN4_TX_DN<66>")
	)
	(segment
		(start 211.483956 -316.079124)
		(end 209.63763 -314.235846)
		(width 0.1651)
		(layer "In7.Cu")
		(net "P5E_PEX1_STN4_TX_DN<66>")
	)
	(segment
		(start 200.420986 -306.683918)
		(end 199.774048 -306.683918)
		(width 0.1651)
		(layer "In7.Cu")
		(net "P5E_PEX1_STN4_TX_DN<66>")
	)
	(segment
		(start 190.91275 -341.298022)
		(end 200.685908 -332.867254)
		(width 0.1651)
		(layer "In7.Cu")
		(net "P5E_PEX1_STN4_TX_DN<66>")
	)
	(segment
		(start 213.00948 -321.81038)
		(end 213.00948 -319.80759)
		(width 0.1651)
		(layer "In7.Cu")
		(net "P5E_PEX1_STN4_TX_DN<66>")
	)
	(segment
		(start 208.457292 -313.747658)
		(end 202.064874 -307.36413)
		(width 0.1651)
		(layer "In7.Cu")
		(net "P5E_PEX1_STN4_TX_DN<66>")
	)
	(segment
		(start 209.63763 -314.235846)
		(end 208.457292 -313.747658)
		(width 0.1651)
		(layer "In7.Cu")
		(net "P5E_PEX1_STN4_TX_DN<66>")
	)
	(segment
		(start 213.00948 -319.80759)
		(end 211.483956 -316.079124)
		(width 0.1651)
		(layer "In7.Cu")
		(net "P5E_PEX1_STN4_TX_DN<66>")
	)
	(segment
		(start 191.634618 -306.729638)
		(end 191.520318 -306.615338)
		(width 0.1143)
		(layer "In7.Cu")
		(net "P5E_PEX1_STN4_TX_DN<66>")
	)
	(segment
		(start 200.685908 -332.867254)
		(end 209.874866 -326.727058)
		(width 0.1651)
		(layer "In7.Cu")
		(net "P5E_PEX1_STN4_TX_DN<66>")
	)
	(segment
		(start 199.774048 -306.683918)
		(end 199.7456 -306.683918)
		(width 0.1143)
		(layer "In7.Cu")
		(net "P5E_PEX1_STN4_TX_DN<66>")
	)
	(segment
		(start 209.874866 -326.727058)
		(end 211.749386 -324.852538)
		(width 0.1651)
		(layer "In7.Cu")
		(net "P5E_PEX1_STN4_TX_DN<66>")
	)
	(segment
		(start 199.7456 -306.683918)
		(end 199.69988 -306.729638)
		(width 0.1143)
		(layer "In7.Cu")
		(net "P5E_PEX1_STN4_TX_DN<66>")
	)
	(segment
		(start 187.352432 -349.511874)
		(end 187.352432 -348.88043)
		(width 0.13462)
		(layer "F.Cu")
		(net "P5E_PEX1_STN4_TX_DP<67>")
	)
	(segment
		(start 187.352432 -348.88043)
		(end 187.057792 -348.58579)
		(width 0.13462)
		(layer "F.Cu")
		(net "P5E_PEX1_STN4_TX_DP<67>")
	)
	(segment
		(start 187.032392 -349.831914)
		(end 187.352432 -349.511874)
		(width 0.13462)
		(layer "F.Cu")
		(net "P5E_PEX1_STN4_TX_DP<67>")
	)
	(segment
		(start 199.7456 -307.915818)
		(end 199.69988 -307.870098)
		(width 0.1143)
		(layer "In7.Cu")
		(net "P5E_PEX1_STN4_TX_DP<67>")
	)
	(segment
		(start 193.229738 -307.644292)
		(end 193.229738 -307.414168)
		(width 0.1143)
		(layer "In7.Cu")
		(net "P5E_PEX1_STN4_TX_DP<67>")
	)
	(segment
		(start 208.730088 -315.552328)
		(end 208.303368 -315.375036)
		(width 0.1651)
		(layer "In7.Cu")
		(net "P5E_PEX1_STN4_TX_DP<67>")
	)
	(segment
		(start 208.303368 -315.375036)
		(end 201.403458 -308.453028)
		(width 0.1651)
		(layer "In7.Cu")
		(net "P5E_PEX1_STN4_TX_DP<67>")
	)
	(segment
		(start 193.455544 -307.870098)
		(end 193.229738 -307.644292)
		(width 0.1143)
		(layer "In7.Cu")
		(net "P5E_PEX1_STN4_TX_DP<67>")
	)
	(segment
		(start 209.49158 -325.360792)
		(end 210.683348 -324.169024)
		(width 0.1651)
		(layer "In7.Cu")
		(net "P5E_PEX1_STN4_TX_DP<67>")
	)
	(segment
		(start 187.348622 -347.593158)
		(end 188.903102 -346.038678)
		(width 0.1651)
		(layer "In7.Cu")
		(net "P5E_PEX1_STN4_TX_DP<67>")
	)
	(segment
		(start 193.229738 -307.414168)
		(end 193.115438 -307.299868)
		(width 0.1143)
		(layer "In7.Cu")
		(net "P5E_PEX1_STN4_TX_DP<67>")
	)
	(segment
		(start 199.774048 -307.915818)
		(end 199.7456 -307.915818)
		(width 0.1143)
		(layer "In7.Cu")
		(net "P5E_PEX1_STN4_TX_DP<67>")
	)
	(segment
		(start 210.683348 -324.169024)
		(end 211.60486 -321.944492)
		(width 0.1651)
		(layer "In7.Cu")
		(net "P5E_PEX1_STN4_TX_DP<67>")
	)
	(segment
		(start 189.354714 -340.565232)
		(end 200.825862 -331.15123)
		(width 0.1651)
		(layer "In7.Cu")
		(net "P5E_PEX1_STN4_TX_DP<67>")
	)
	(segment
		(start 187.348622 -348.29496)
		(end 187.348622 -347.593158)
		(width 0.1651)
		(layer "In7.Cu")
		(net "P5E_PEX1_STN4_TX_DP<67>")
	)
	(segment
		(start 211.60486 -321.944492)
		(end 211.60486 -319.64503)
		(width 0.1651)
		(layer "In7.Cu")
		(net "P5E_PEX1_STN4_TX_DP<67>")
	)
	(segment
		(start 200.825862 -331.15123)
		(end 209.49158 -325.360792)
		(width 0.1651)
		(layer "In7.Cu")
		(net "P5E_PEX1_STN4_TX_DP<67>")
	)
	(segment
		(start 187.057792 -348.58579)
		(end 187.348622 -348.29496)
		(width 0.1651)
		(layer "In7.Cu")
		(net "P5E_PEX1_STN4_TX_DP<67>")
	)
	(segment
		(start 201.403458 -308.453028)
		(end 200.10628 -307.915818)
		(width 0.1651)
		(layer "In7.Cu")
		(net "P5E_PEX1_STN4_TX_DP<67>")
	)
	(segment
		(start 210.76793 -317.596774)
		(end 208.730088 -315.552328)
		(width 0.1651)
		(layer "In7.Cu")
		(net "P5E_PEX1_STN4_TX_DP<67>")
	)
	(segment
		(start 200.10628 -307.915818)
		(end 199.774048 -307.915818)
		(width 0.1651)
		(layer "In7.Cu")
		(net "P5E_PEX1_STN4_TX_DP<67>")
	)
	(segment
		(start 211.60486 -319.64503)
		(end 210.76793 -317.596774)
		(width 0.1651)
		(layer "In7.Cu")
		(net "P5E_PEX1_STN4_TX_DP<67>")
	)
	(segment
		(start 188.903102 -341.6554)
		(end 189.354714 -340.565232)
		(width 0.1651)
		(layer "In7.Cu")
		(net "P5E_PEX1_STN4_TX_DP<67>")
	)
	(segment
		(start 199.69988 -307.870098)
		(end 193.455544 -307.870098)
		(width 0.1143)
		(layer "In7.Cu")
		(net "P5E_PEX1_STN4_TX_DP<67>")
	)
	(segment
		(start 188.903102 -346.038678)
		(end 188.903102 -341.6554)
		(width 0.1651)
		(layer "In7.Cu")
		(net "P5E_PEX1_STN4_TX_DP<67>")
	)
	(segment
		(start 193.115438 -307.299868)
		(end 192.850008 -307.299868)
		(width 0.1143)
		(layer "In7.Cu")
		(net "P5E_PEX1_STN4_TX_DP<67>")
	)
	(segment
		(start 178.619912 -355.978206)
		(end 178.299872 -355.658166)
		(width 0.13462)
		(layer "F.Cu")
		(net "P5E_PEX1_STN4_TX_DN<71>")
	)
	(segment
		(start 178.299872 -355.026722)
		(end 178.594512 -354.732082)
		(width 0.13462)
		(layer "F.Cu")
		(net "P5E_PEX1_STN4_TX_DN<71>")
	)
	(segment
		(start 178.299872 -355.658166)
		(end 178.299872 -355.026722)
		(width 0.13462)
		(layer "F.Cu")
		(net "P5E_PEX1_STN4_TX_DN<71>")
	)
	(segment
		(start 196.143372 -325.768208)
		(end 198.216012 -320.764408)
		(width 0.1651)
		(layer "In7.Cu")
		(net "P5E_PEX1_STN4_TX_DN<71>")
	)
	(segment
		(start 198.170292 -318.87668)
		(end 198.170292 -315.014102)
		(width 0.1143)
		(layer "In7.Cu")
		(net "P5E_PEX1_STN4_TX_DN<71>")
	)
	(segment
		(start 198.170292 -315.014102)
		(end 198.284592 -314.899802)
		(width 0.1143)
		(layer "In7.Cu")
		(net "P5E_PEX1_STN4_TX_DN<71>")
	)
	(segment
		(start 198.284592 -314.899802)
		(end 198.550022 -314.899802)
		(width 0.1143)
		(layer "In7.Cu")
		(net "P5E_PEX1_STN4_TX_DN<71>")
	)
	(segment
		(start 178.303682 -354.441252)
		(end 178.303682 -353.790758)
		(width 0.1651)
		(layer "In7.Cu")
		(net "P5E_PEX1_STN4_TX_DN<71>")
	)
	(segment
		(start 198.216012 -318.950848)
		(end 198.216012 -318.9224)
		(width 0.1143)
		(layer "In7.Cu")
		(net "P5E_PEX1_STN4_TX_DN<71>")
	)
	(segment
		(start 198.216012 -318.9224)
		(end 198.170292 -318.87668)
		(width 0.1143)
		(layer "In7.Cu")
		(net "P5E_PEX1_STN4_TX_DN<71>")
	)
	(segment
		(start 198.216012 -320.764408)
		(end 198.216012 -318.950848)
		(width 0.1651)
		(layer "In7.Cu")
		(net "P5E_PEX1_STN4_TX_DN<71>")
	)
	(segment
		(start 178.303682 -353.790758)
		(end 179.858162 -352.236278)
		(width 0.1651)
		(layer "In7.Cu")
		(net "P5E_PEX1_STN4_TX_DN<71>")
	)
	(segment
		(start 178.594512 -354.732082)
		(end 178.303682 -354.441252)
		(width 0.1651)
		(layer "In7.Cu")
		(net "P5E_PEX1_STN4_TX_DN<71>")
	)
	(segment
		(start 179.858162 -352.236278)
		(end 179.858162 -342.006682)
		(width 0.1651)
		(layer "In7.Cu")
		(net "P5E_PEX1_STN4_TX_DN<71>")
	)
	(segment
		(start 180.196744 -341.189056)
		(end 183.876442 -337.509358)
		(width 0.1651)
		(layer "In7.Cu")
		(net "P5E_PEX1_STN4_TX_DN<71>")
	)
	(segment
		(start 185.461148 -336.450432)
		(end 196.143372 -325.768208)
		(width 0.1651)
		(layer "In7.Cu")
		(net "P5E_PEX1_STN4_TX_DN<71>")
	)
	(segment
		(start 179.858162 -342.006682)
		(end 180.196744 -341.189056)
		(width 0.1651)
		(layer "In7.Cu")
		(net "P5E_PEX1_STN4_TX_DN<71>")
	)
	(segment
		(start 183.876442 -337.509358)
		(end 185.461148 -336.450432)
		(width 0.1651)
		(layer "In7.Cu")
		(net "P5E_PEX1_STN4_TX_DN<71>")
	)
	(segment
		(start 196.679312 -342.734138)
		(end 196.384672 -342.439498)
		(width 0.13462)
		(layer "F.Cu")
		(net "P5E_PEX1_STN4_TX_DP<64>")
	)
	(segment
		(start 196.359272 -343.685622)
		(end 196.679312 -343.365582)
		(width 0.13462)
		(layer "F.Cu")
		(net "P5E_PEX1_STN4_TX_DP<64>")
	)
	(segment
		(start 196.679312 -343.365582)
		(end 196.679312 -342.734138)
		(width 0.13462)
		(layer "F.Cu")
		(net "P5E_PEX1_STN4_TX_DP<64>")
	)
	(segment
		(start 204.435964 -306.526438)
		(end 200.909682 -305.065684)
		(width 0.1651)
		(layer "In7.Cu")
		(net "P5E_PEX1_STN4_TX_DP<64>")
	)
	(segment
		(start 200.909682 -305.065684)
		(end 199.748648 -305.065684)
		(width 0.1651)
		(layer "In7.Cu")
		(net "P5E_PEX1_STN4_TX_DP<64>")
	)
	(segment
		(start 196.675502 -341.306658)
		(end 197.940168 -338.253832)
		(width 0.1651)
		(layer "In7.Cu")
		(net "P5E_PEX1_STN4_TX_DP<64>")
	)
	(segment
		(start 214.63762 -322.136262)
		(end 214.63762 -319.471802)
		(width 0.1651)
		(layer "In7.Cu")
		(net "P5E_PEX1_STN4_TX_DP<64>")
	)
	(segment
		(start 191.329818 -304.564034)
		(end 191.215518 -304.449734)
		(width 0.1143)
		(layer "In7.Cu")
		(net "P5E_PEX1_STN4_TX_DP<64>")
	)
	(segment
		(start 213.130892 -325.773796)
		(end 214.63762 -322.136262)
		(width 0.1651)
		(layer "In7.Cu")
		(net "P5E_PEX1_STN4_TX_DP<64>")
	)
	(segment
		(start 214.63762 -319.471802)
		(end 212.733128 -314.823602)
		(width 0.1651)
		(layer "In7.Cu")
		(net "P5E_PEX1_STN4_TX_DP<64>")
	)
	(segment
		(start 191.329818 -304.794158)
		(end 191.329818 -304.564034)
		(width 0.1143)
		(layer "In7.Cu")
		(net "P5E_PEX1_STN4_TX_DP<64>")
	)
	(segment
		(start 196.675502 -342.148668)
		(end 196.675502 -341.306658)
		(width 0.1651)
		(layer "In7.Cu")
		(net "P5E_PEX1_STN4_TX_DP<64>")
	)
	(segment
		(start 199.748648 -305.065684)
		(end 199.7202 -305.065684)
		(width 0.1143)
		(layer "In7.Cu")
		(net "P5E_PEX1_STN4_TX_DP<64>")
	)
	(segment
		(start 212.733128 -314.823602)
		(end 204.435964 -306.526438)
		(width 0.1651)
		(layer "In7.Cu")
		(net "P5E_PEX1_STN4_TX_DP<64>")
	)
	(segment
		(start 202.74153 -333.45247)
		(end 210.911186 -327.993502)
		(width 0.1651)
		(layer "In7.Cu")
		(net "P5E_PEX1_STN4_TX_DP<64>")
	)
	(segment
		(start 210.911186 -327.993502)
		(end 213.130892 -325.773796)
		(width 0.1651)
		(layer "In7.Cu")
		(net "P5E_PEX1_STN4_TX_DP<64>")
	)
	(segment
		(start 199.7202 -305.065684)
		(end 199.67448 -305.019964)
		(width 0.1143)
		(layer "In7.Cu")
		(net "P5E_PEX1_STN4_TX_DP<64>")
	)
	(segment
		(start 196.384672 -342.439498)
		(end 196.675502 -342.148668)
		(width 0.1651)
		(layer "In7.Cu")
		(net "P5E_PEX1_STN4_TX_DP<64>")
	)
	(segment
		(start 191.215518 -304.449734)
		(end 190.950088 -304.449734)
		(width 0.1143)
		(layer "In7.Cu")
		(net "P5E_PEX1_STN4_TX_DP<64>")
	)
	(segment
		(start 191.555624 -305.019964)
		(end 191.329818 -304.794158)
		(width 0.1143)
		(layer "In7.Cu")
		(net "P5E_PEX1_STN4_TX_DP<64>")
	)
	(segment
		(start 197.940168 -338.253832)
		(end 202.74153 -333.45247)
		(width 0.1651)
		(layer "In7.Cu")
		(net "P5E_PEX1_STN4_TX_DP<64>")
	)
	(segment
		(start 199.67448 -305.019964)
		(end 191.555624 -305.019964)
		(width 0.1143)
		(layer "In7.Cu")
		(net "P5E_PEX1_STN4_TX_DP<64>")
	)
	(segment
		(start 168.972992 -349.511874)
		(end 168.972992 -348.88043)
		(width 0.13462)
		(layer "F.Cu")
		(net "P5E_PEX1_STN4_TX_DN<76>")
	)
	(segment
		(start 169.293032 -349.831914)
		(end 168.972992 -349.511874)
		(width 0.13462)
		(layer "F.Cu")
		(net "P5E_PEX1_STN4_TX_DN<76>")
	)
	(segment
		(start 168.972992 -348.88043)
		(end 169.267632 -348.58579)
		(width 0.13462)
		(layer "F.Cu")
		(net "P5E_PEX1_STN4_TX_DN<76>")
	)
	(segment
		(start 173.238668 -338.313014)
		(end 184.0865 -331.064616)
		(width 0.1651)
		(layer "In7.Cu")
		(net "P5E_PEX1_STN4_TX_DN<76>")
	)
	(segment
		(start 192.735708 -313.570112)
		(end 192.850008 -313.684412)
		(width 0.1143)
		(layer "In7.Cu")
		(net "P5E_PEX1_STN4_TX_DN<76>")
	)
	(segment
		(start 192.584578 -313.570112)
		(end 192.735708 -313.570112)
		(width 0.1143)
		(layer "In7.Cu")
		(net "P5E_PEX1_STN4_TX_DN<76>")
	)
	(segment
		(start 192.515998 -321.183)
		(end 192.515998 -320.002408)
		(width 0.1651)
		(layer "In7.Cu")
		(net "P5E_PEX1_STN4_TX_DN<76>")
	)
	(segment
		(start 192.850008 -313.684412)
		(end 192.850008 -313.949842)
		(width 0.1143)
		(layer "In7.Cu")
		(net "P5E_PEX1_STN4_TX_DN<76>")
	)
	(segment
		(start 168.976802 -347.709998)
		(end 170.531282 -346.155518)
		(width 0.1651)
		(layer "In7.Cu")
		(net "P5E_PEX1_STN4_TX_DN<76>")
	)
	(segment
		(start 192.470278 -319.92824)
		(end 192.470278 -313.684412)
		(width 0.1143)
		(layer "In7.Cu")
		(net "P5E_PEX1_STN4_TX_DN<76>")
	)
	(segment
		(start 192.515998 -320.002408)
		(end 192.515998 -319.97396)
		(width 0.1143)
		(layer "In7.Cu")
		(net "P5E_PEX1_STN4_TX_DN<76>")
	)
	(segment
		(start 170.531282 -346.155518)
		(end 170.531282 -341.0204)
		(width 0.1651)
		(layer "In7.Cu")
		(net "P5E_PEX1_STN4_TX_DN<76>")
	)
	(segment
		(start 192.470278 -313.684412)
		(end 192.584578 -313.570112)
		(width 0.1143)
		(layer "In7.Cu")
		(net "P5E_PEX1_STN4_TX_DN<76>")
	)
	(segment
		(start 192.515998 -319.97396)
		(end 192.470278 -319.92824)
		(width 0.1143)
		(layer "In7.Cu")
		(net "P5E_PEX1_STN4_TX_DN<76>")
	)
	(segment
		(start 191.489076 -323.66204)
		(end 192.515998 -321.183)
		(width 0.1651)
		(layer "In7.Cu")
		(net "P5E_PEX1_STN4_TX_DN<76>")
	)
	(segment
		(start 170.531282 -341.0204)
		(end 173.238668 -338.313014)
		(width 0.1651)
		(layer "In7.Cu")
		(net "P5E_PEX1_STN4_TX_DN<76>")
	)
	(segment
		(start 184.0865 -331.064616)
		(end 191.489076 -323.66204)
		(width 0.1651)
		(layer "In7.Cu")
		(net "P5E_PEX1_STN4_TX_DN<76>")
	)
	(segment
		(start 169.267632 -348.58579)
		(end 168.976802 -348.29496)
		(width 0.1651)
		(layer "In7.Cu")
		(net "P5E_PEX1_STN4_TX_DN<76>")
	)
	(segment
		(start 168.976802 -348.29496)
		(end 168.976802 -347.709998)
		(width 0.1651)
		(layer "In7.Cu")
		(net "P5E_PEX1_STN4_TX_DN<76>")
	)
	(segment
		(start 183.923432 -343.685622)
		(end 184.243472 -343.365582)
		(width 0.13462)
		(layer "F.Cu")
		(net "P5E_PEX1_STN4_TX_DP<69>")
	)
	(segment
		(start 184.243472 -342.734138)
		(end 183.948832 -342.439498)
		(width 0.13462)
		(layer "F.Cu")
		(net "P5E_PEX1_STN4_TX_DP<69>")
	)
	(segment
		(start 184.243472 -343.365582)
		(end 184.243472 -342.734138)
		(width 0.13462)
		(layer "F.Cu")
		(net "P5E_PEX1_STN4_TX_DP<69>")
	)
	(segment
		(start 184.239662 -340.13013)
		(end 198.26351 -326.106282)
		(width 0.1651)
		(layer "In7.Cu")
		(net "P5E_PEX1_STN4_TX_DP<69>")
	)
	(segment
		(start 198.263256 -326.106282)
		(end 199.410574 -323.337174)
		(width 0.1651)
		(layer "In7.Cu")
		(net "P5E_PEX1_STN4_TX_DP<69>")
	)
	(segment
		(start 201.180192 -317.450216)
		(end 201.387456 -316.411102)
		(width 0.1651)
		(layer "In7.Cu")
		(net "P5E_PEX1_STN4_TX_DP<69>")
	)
	(segment
		(start 200.00468 -309.903114)
		(end 199.917304 -309.815738)
		(width 0.1651)
		(layer "In7.Cu")
		(net "P5E_PEX1_STN4_TX_DP<69>")
	)
	(segment
		(start 199.410574 -323.337174)
		(end 199.410574 -323.337428)
		(width 0.1651)
		(layer "In7.Cu")
		(net "P5E_PEX1_STN4_TX_DP<69>")
	)
	(segment
		(start 199.917304 -309.815738)
		(end 199.774048 -309.815738)
		(width 0.1651)
		(layer "In7.Cu")
		(net "P5E_PEX1_STN4_TX_DP<69>")
	)
	(segment
		(start 193.229738 -309.544212)
		(end 193.229738 -309.314088)
		(width 0.1143)
		(layer "In7.Cu")
		(net "P5E_PEX1_STN4_TX_DP<69>")
	)
	(segment
		(start 199.774048 -309.815738)
		(end 199.7456 -309.815738)
		(width 0.1143)
		(layer "In7.Cu")
		(net "P5E_PEX1_STN4_TX_DP<69>")
	)
	(segment
		(start 200.972674 -318.489584)
		(end 200.97242 -318.489584)
		(width 0.1651)
		(layer "In7.Cu")
		(net "P5E_PEX1_STN4_TX_DP<69>")
	)
	(segment
		(start 184.239662 -342.148668)
		(end 184.239662 -340.13013)
		(width 0.1651)
		(layer "In7.Cu")
		(net "P5E_PEX1_STN4_TX_DP<69>")
	)
	(segment
		(start 199.69988 -309.770018)
		(end 193.455544 -309.770018)
		(width 0.1143)
		(layer "In7.Cu")
		(net "P5E_PEX1_STN4_TX_DP<69>")
	)
	(segment
		(start 201.179938 -317.450216)
		(end 201.180192 -317.450216)
		(width 0.1651)
		(layer "In7.Cu")
		(net "P5E_PEX1_STN4_TX_DP<69>")
	)
	(segment
		(start 201.387456 -316.411102)
		(end 201.387456 -313.241182)
		(width 0.1651)
		(layer "In7.Cu")
		(net "P5E_PEX1_STN4_TX_DP<69>")
	)
	(segment
		(start 199.410574 -323.337428)
		(end 200.557892 -320.567812)
		(width 0.1651)
		(layer "In7.Cu")
		(net "P5E_PEX1_STN4_TX_DP<69>")
	)
	(segment
		(start 193.115438 -309.199788)
		(end 192.850008 -309.199788)
		(width 0.1143)
		(layer "In7.Cu")
		(net "P5E_PEX1_STN4_TX_DP<69>")
	)
	(segment
		(start 193.229738 -309.314088)
		(end 193.115438 -309.199788)
		(width 0.1143)
		(layer "In7.Cu")
		(net "P5E_PEX1_STN4_TX_DP<69>")
	)
	(segment
		(start 200.97242 -318.489584)
		(end 201.179938 -317.450216)
		(width 0.1651)
		(layer "In7.Cu")
		(net "P5E_PEX1_STN4_TX_DP<69>")
	)
	(segment
		(start 198.26351 -326.106282)
		(end 198.263256 -326.106282)
		(width 0.1651)
		(layer "In7.Cu")
		(net "P5E_PEX1_STN4_TX_DP<69>")
	)
	(segment
		(start 201.387456 -313.241182)
		(end 200.00468 -309.903114)
		(width 0.1651)
		(layer "In7.Cu")
		(net "P5E_PEX1_STN4_TX_DP<69>")
	)
	(segment
		(start 199.7456 -309.815738)
		(end 199.69988 -309.770018)
		(width 0.1143)
		(layer "In7.Cu")
		(net "P5E_PEX1_STN4_TX_DP<69>")
	)
	(segment
		(start 200.557892 -320.567812)
		(end 200.972674 -318.489584)
		(width 0.1651)
		(layer "In7.Cu")
		(net "P5E_PEX1_STN4_TX_DP<69>")
	)
	(segment
		(start 183.948832 -342.439498)
		(end 184.239662 -342.148668)
		(width 0.1651)
		(layer "In7.Cu")
		(net "P5E_PEX1_STN4_TX_DP<69>")
	)
	(segment
		(start 193.455544 -309.770018)
		(end 193.229738 -309.544212)
		(width 0.1143)
		(layer "In7.Cu")
		(net "P5E_PEX1_STN4_TX_DP<69>")
	)
	(segment
		(start 171.807632 -342.734138)
		(end 171.512992 -342.439498)
		(width 0.13462)
		(layer "F.Cu")
		(net "P5E_PEX1_STN4_TX_DP<75>")
	)
	(segment
		(start 171.487592 -343.685622)
		(end 171.807632 -343.365582)
		(width 0.13462)
		(layer "F.Cu")
		(net "P5E_PEX1_STN4_TX_DP<75>")
	)
	(segment
		(start 171.807632 -343.365582)
		(end 171.807632 -342.734138)
		(width 0.13462)
		(layer "F.Cu")
		(net "P5E_PEX1_STN4_TX_DP<75>")
	)
	(segment
		(start 193.184018 -319.988438)
		(end 193.229738 -319.942718)
		(width 0.1143)
		(layer "In7.Cu")
		(net "P5E_PEX1_STN4_TX_DP<75>")
	)
	(segment
		(start 192.118742 -323.99097)
		(end 193.184018 -321.419474)
		(width 0.1651)
		(layer "In7.Cu")
		(net "P5E_PEX1_STN4_TX_DP<75>")
	)
	(segment
		(start 193.799968 -311.365392)
		(end 193.799968 -311.099962)
		(width 0.1143)
		(layer "In7.Cu")
		(net "P5E_PEX1_STN4_TX_DP<75>")
	)
	(segment
		(start 193.685668 -311.479692)
		(end 193.799968 -311.365392)
		(width 0.1143)
		(layer "In7.Cu")
		(net "P5E_PEX1_STN4_TX_DP<75>")
	)
	(segment
		(start 193.455544 -311.479692)
		(end 193.685668 -311.479692)
		(width 0.1143)
		(layer "In7.Cu")
		(net "P5E_PEX1_STN4_TX_DP<75>")
	)
	(segment
		(start 193.184018 -320.016886)
		(end 193.184018 -319.988438)
		(width 0.1143)
		(layer "In7.Cu")
		(net "P5E_PEX1_STN4_TX_DP<75>")
	)
	(segment
		(start 174.511208 -338.272374)
		(end 184.535318 -331.574394)
		(width 0.1651)
		(layer "In7.Cu")
		(net "P5E_PEX1_STN4_TX_DP<75>")
	)
	(segment
		(start 184.535318 -331.574394)
		(end 192.118742 -323.99097)
		(width 0.1651)
		(layer "In7.Cu")
		(net "P5E_PEX1_STN4_TX_DP<75>")
	)
	(segment
		(start 171.803822 -340.97976)
		(end 174.511208 -338.272374)
		(width 0.1651)
		(layer "In7.Cu")
		(net "P5E_PEX1_STN4_TX_DP<75>")
	)
	(segment
		(start 193.229738 -311.705498)
		(end 193.455544 -311.479692)
		(width 0.1143)
		(layer "In7.Cu")
		(net "P5E_PEX1_STN4_TX_DP<75>")
	)
	(segment
		(start 171.803822 -342.148668)
		(end 171.803822 -340.97976)
		(width 0.1651)
		(layer "In7.Cu")
		(net "P5E_PEX1_STN4_TX_DP<75>")
	)
	(segment
		(start 171.512992 -342.439498)
		(end 171.803822 -342.148668)
		(width 0.1651)
		(layer "In7.Cu")
		(net "P5E_PEX1_STN4_TX_DP<75>")
	)
	(segment
		(start 193.229738 -319.942718)
		(end 193.229738 -311.705498)
		(width 0.1143)
		(layer "In7.Cu")
		(net "P5E_PEX1_STN4_TX_DP<75>")
	)
	(segment
		(start 193.184018 -321.419474)
		(end 193.184018 -320.016886)
		(width 0.1651)
		(layer "In7.Cu")
		(net "P5E_PEX1_STN4_TX_DP<75>")
	)
	(segment
		(start 193.570352 -348.88043)
		(end 193.275712 -348.58579)
		(width 0.13462)
		(layer "F.Cu")
		(net "P5E_PEX1_STN4_TX_DP<65>")
	)
	(segment
		(start 193.570352 -349.511874)
		(end 193.570352 -348.88043)
		(width 0.13462)
		(layer "F.Cu")
		(net "P5E_PEX1_STN4_TX_DP<65>")
	)
	(segment
		(start 193.250312 -349.831914)
		(end 193.570352 -349.511874)
		(width 0.13462)
		(layer "F.Cu")
		(net "P5E_PEX1_STN4_TX_DP<65>")
	)
	(segment
		(start 210.303618 -327.250298)
		(end 212.320378 -325.233538)
		(width 0.1651)
		(layer "In7.Cu")
		(net "P5E_PEX1_STN4_TX_DP<65>")
	)
	(segment
		(start 193.229738 -305.514248)
		(end 193.115438 -305.399948)
		(width 0.1143)
		(layer "In7.Cu")
		(net "P5E_PEX1_STN4_TX_DP<65>")
	)
	(segment
		(start 213.68258 -321.945254)
		(end 213.68258 -319.675002)
		(width 0.1651)
		(layer "In7.Cu")
		(net "P5E_PEX1_STN4_TX_DP<65>")
	)
	(segment
		(start 199.799448 -306.015898)
		(end 199.771 -306.015898)
		(width 0.1143)
		(layer "In7.Cu")
		(net "P5E_PEX1_STN4_TX_DP<65>")
	)
	(segment
		(start 193.455544 -305.970178)
		(end 193.229738 -305.744372)
		(width 0.1143)
		(layer "In7.Cu")
		(net "P5E_PEX1_STN4_TX_DP<65>")
	)
	(segment
		(start 213.68258 -319.675002)
		(end 211.923122 -315.365892)
		(width 0.1651)
		(layer "In7.Cu")
		(net "P5E_PEX1_STN4_TX_DP<65>")
	)
	(segment
		(start 193.115438 -305.399948)
		(end 192.850008 -305.399948)
		(width 0.1143)
		(layer "In7.Cu")
		(net "P5E_PEX1_STN4_TX_DP<65>")
	)
	(segment
		(start 195.121022 -346.038678)
		(end 195.121022 -341.192358)
		(width 0.1651)
		(layer "In7.Cu")
		(net "P5E_PEX1_STN4_TX_DP<65>")
	)
	(segment
		(start 196.403468 -338.096352)
		(end 201.099166 -333.400654)
		(width 0.1651)
		(layer "In7.Cu")
		(net "P5E_PEX1_STN4_TX_DP<65>")
	)
	(segment
		(start 193.229738 -305.744372)
		(end 193.229738 -305.514248)
		(width 0.1143)
		(layer "In7.Cu")
		(net "P5E_PEX1_STN4_TX_DP<65>")
	)
	(segment
		(start 211.923122 -315.365892)
		(end 203.96073 -307.414168)
		(width 0.1651)
		(layer "In7.Cu")
		(net "P5E_PEX1_STN4_TX_DP<65>")
	)
	(segment
		(start 199.771 -306.015898)
		(end 199.72528 -305.970178)
		(width 0.1143)
		(layer "In7.Cu")
		(net "P5E_PEX1_STN4_TX_DP<65>")
	)
	(segment
		(start 200.581768 -306.015898)
		(end 199.799448 -306.015898)
		(width 0.1651)
		(layer "In7.Cu")
		(net "P5E_PEX1_STN4_TX_DP<65>")
	)
	(segment
		(start 193.566542 -347.593158)
		(end 195.121022 -346.038678)
		(width 0.1651)
		(layer "In7.Cu")
		(net "P5E_PEX1_STN4_TX_DP<65>")
	)
	(segment
		(start 201.099166 -333.400654)
		(end 210.303618 -327.250298)
		(width 0.1651)
		(layer "In7.Cu")
		(net "P5E_PEX1_STN4_TX_DP<65>")
	)
	(segment
		(start 199.72528 -305.970178)
		(end 193.455544 -305.970178)
		(width 0.1143)
		(layer "In7.Cu")
		(net "P5E_PEX1_STN4_TX_DP<65>")
	)
	(segment
		(start 195.121022 -341.192358)
		(end 196.403468 -338.096352)
		(width 0.1651)
		(layer "In7.Cu")
		(net "P5E_PEX1_STN4_TX_DP<65>")
	)
	(segment
		(start 193.566542 -348.29496)
		(end 193.566542 -347.593158)
		(width 0.1651)
		(layer "In7.Cu")
		(net "P5E_PEX1_STN4_TX_DP<65>")
	)
	(segment
		(start 203.96073 -307.414168)
		(end 200.581768 -306.015898)
		(width 0.1651)
		(layer "In7.Cu")
		(net "P5E_PEX1_STN4_TX_DP<65>")
	)
	(segment
		(start 193.275712 -348.58579)
		(end 193.566542 -348.29496)
		(width 0.1651)
		(layer "In7.Cu")
		(net "P5E_PEX1_STN4_TX_DP<65>")
	)
	(segment
		(start 212.320378 -325.233538)
		(end 213.68258 -321.945254)
		(width 0.1651)
		(layer "In7.Cu")
		(net "P5E_PEX1_STN4_TX_DP<65>")
	)
	(segment
		(start 163.075112 -349.831914)
		(end 162.755072 -349.511874)
		(width 0.13462)
		(layer "F.Cu")
		(net "P5E_PEX1_STN4_TX_DN<79>")
	)
	(segment
		(start 162.755072 -349.511874)
		(end 162.755072 -348.88043)
		(width 0.13462)
		(layer "F.Cu")
		(net "P5E_PEX1_STN4_TX_DN<79>")
	)
	(segment
		(start 162.755072 -348.88043)
		(end 163.049712 -348.58579)
		(width 0.13462)
		(layer "F.Cu")
		(net "P5E_PEX1_STN4_TX_DN<79>")
	)
	(segment
		(start 189.999874 -311.784492)
		(end 189.999874 -312.049922)
		(width 0.1143)
		(layer "In7.Cu")
		(net "P5E_PEX1_STN4_TX_DN<79>")
	)
	(segment
		(start 162.758882 -348.29496)
		(end 162.758882 -342.261952)
		(width 0.1651)
		(layer "In7.Cu")
		(net "P5E_PEX1_STN4_TX_DN<79>")
	)
	(segment
		(start 188.910976 -322.187824)
		(end 189.665864 -320.365628)
		(width 0.1651)
		(layer "In7.Cu")
		(net "P5E_PEX1_STN4_TX_DN<79>")
	)
	(segment
		(start 189.620144 -319.942718)
		(end 189.620144 -311.784492)
		(width 0.1143)
		(layer "In7.Cu")
		(net "P5E_PEX1_STN4_TX_DN<79>")
	)
	(segment
		(start 189.665864 -320.016886)
		(end 189.665864 -319.988438)
		(width 0.1143)
		(layer "In7.Cu")
		(net "P5E_PEX1_STN4_TX_DN<79>")
	)
	(segment
		(start 189.665864 -320.365628)
		(end 189.665864 -320.016886)
		(width 0.1651)
		(layer "In7.Cu")
		(net "P5E_PEX1_STN4_TX_DN<79>")
	)
	(segment
		(start 163.049712 -348.58579)
		(end 162.758882 -348.29496)
		(width 0.1651)
		(layer "In7.Cu")
		(net "P5E_PEX1_STN4_TX_DN<79>")
	)
	(segment
		(start 189.734444 -311.670192)
		(end 189.885574 -311.670192)
		(width 0.1143)
		(layer "In7.Cu")
		(net "P5E_PEX1_STN4_TX_DN<79>")
	)
	(segment
		(start 189.885574 -311.670192)
		(end 189.999874 -311.784492)
		(width 0.1143)
		(layer "In7.Cu")
		(net "P5E_PEX1_STN4_TX_DN<79>")
	)
	(segment
		(start 162.758882 -342.261952)
		(end 163.9443 -341.076534)
		(width 0.1651)
		(layer "In7.Cu")
		(net "P5E_PEX1_STN4_TX_DN<79>")
	)
	(segment
		(start 182.262272 -328.836528)
		(end 188.910976 -322.187824)
		(width 0.1651)
		(layer "In7.Cu")
		(net "P5E_PEX1_STN4_TX_DN<79>")
	)
	(segment
		(start 189.620144 -311.784492)
		(end 189.734444 -311.670192)
		(width 0.1143)
		(layer "In7.Cu")
		(net "P5E_PEX1_STN4_TX_DN<79>")
	)
	(segment
		(start 163.9443 -341.076534)
		(end 182.262272 -328.836528)
		(width 0.1651)
		(layer "In7.Cu")
		(net "P5E_PEX1_STN4_TX_DN<79>")
	)
	(segment
		(start 189.665864 -319.988438)
		(end 189.620144 -319.942718)
		(width 0.1143)
		(layer "In7.Cu")
		(net "P5E_PEX1_STN4_TX_DN<79>")
	)
	(segment
		(start 168.698672 -349.511874)
		(end 168.698672 -348.88043)
		(width 0.13462)
		(layer "F.Cu")
		(net "P5E_PEX1_STN4_TX_DP<76>")
	)
	(segment
		(start 168.698672 -348.88043)
		(end 168.404032 -348.58579)
		(width 0.13462)
		(layer "F.Cu")
		(net "P5E_PEX1_STN4_TX_DP<76>")
	)
	(segment
		(start 168.378632 -349.831914)
		(end 168.698672 -349.511874)
		(width 0.13462)
		(layer "F.Cu")
		(net "P5E_PEX1_STN4_TX_DP<76>")
	)
	(segment
		(start 168.694862 -347.593158)
		(end 170.249342 -346.038678)
		(width 0.1651)
		(layer "In7.Cu")
		(net "P5E_PEX1_STN4_TX_DP<76>")
	)
	(segment
		(start 192.279778 -313.605418)
		(end 192.505584 -313.379612)
		(width 0.1143)
		(layer "In7.Cu")
		(net "P5E_PEX1_STN4_TX_DP<76>")
	)
	(segment
		(start 192.735708 -313.379612)
		(end 192.850008 -313.265312)
		(width 0.1143)
		(layer "In7.Cu")
		(net "P5E_PEX1_STN4_TX_DP<76>")
	)
	(segment
		(start 192.279778 -319.92824)
		(end 192.279778 -313.605418)
		(width 0.1143)
		(layer "In7.Cu")
		(net "P5E_PEX1_STN4_TX_DP<76>")
	)
	(segment
		(start 191.250062 -323.502274)
		(end 192.234058 -321.126866)
		(width 0.1651)
		(layer "In7.Cu")
		(net "P5E_PEX1_STN4_TX_DP<76>")
	)
	(segment
		(start 192.234058 -320.002408)
		(end 192.234058 -319.97396)
		(width 0.1143)
		(layer "In7.Cu")
		(net "P5E_PEX1_STN4_TX_DP<76>")
	)
	(segment
		(start 192.234058 -321.126866)
		(end 192.234058 -320.002408)
		(width 0.1651)
		(layer "In7.Cu")
		(net "P5E_PEX1_STN4_TX_DP<76>")
	)
	(segment
		(start 168.404032 -348.58579)
		(end 168.694862 -348.29496)
		(width 0.1651)
		(layer "In7.Cu")
		(net "P5E_PEX1_STN4_TX_DP<76>")
	)
	(segment
		(start 192.234058 -319.97396)
		(end 192.279778 -319.92824)
		(width 0.1143)
		(layer "In7.Cu")
		(net "P5E_PEX1_STN4_TX_DP<76>")
	)
	(segment
		(start 183.906668 -330.845668)
		(end 191.250062 -323.502274)
		(width 0.1651)
		(layer "In7.Cu")
		(net "P5E_PEX1_STN4_TX_DP<76>")
	)
	(segment
		(start 168.694862 -348.29496)
		(end 168.694862 -347.593158)
		(width 0.1651)
		(layer "In7.Cu")
		(net "P5E_PEX1_STN4_TX_DP<76>")
	)
	(segment
		(start 173.058836 -338.094066)
		(end 183.906668 -330.845668)
		(width 0.1651)
		(layer "In7.Cu")
		(net "P5E_PEX1_STN4_TX_DP<76>")
	)
	(segment
		(start 170.249342 -346.038678)
		(end 170.249342 -340.90356)
		(width 0.1651)
		(layer "In7.Cu")
		(net "P5E_PEX1_STN4_TX_DP<76>")
	)
	(segment
		(start 192.505584 -313.379612)
		(end 192.735708 -313.379612)
		(width 0.1143)
		(layer "In7.Cu")
		(net "P5E_PEX1_STN4_TX_DP<76>")
	)
	(segment
		(start 192.850008 -313.265312)
		(end 192.850008 -312.999882)
		(width 0.1143)
		(layer "In7.Cu")
		(net "P5E_PEX1_STN4_TX_DP<76>")
	)
	(segment
		(start 170.249342 -340.90356)
		(end 173.058836 -338.094066)
		(width 0.1651)
		(layer "In7.Cu")
		(net "P5E_PEX1_STN4_TX_DP<76>")
	)
	(segment
		(start 172.081952 -355.658166)
		(end 172.081952 -355.026722)
		(width 0.13462)
		(layer "F.Cu")
		(net "P5E_PEX1_STN4_TX_DN<74>")
	)
	(segment
		(start 172.401992 -355.978206)
		(end 172.081952 -355.658166)
		(width 0.13462)
		(layer "F.Cu")
		(net "P5E_PEX1_STN4_TX_DN<74>")
	)
	(segment
		(start 172.081952 -355.026722)
		(end 172.376592 -354.732082)
		(width 0.13462)
		(layer "F.Cu")
		(net "P5E_PEX1_STN4_TX_DN<74>")
	)
	(segment
		(start 194.370198 -313.684412)
		(end 194.484498 -313.570112)
		(width 0.1143)
		(layer "In7.Cu")
		(net "P5E_PEX1_STN4_TX_DN<74>")
	)
	(segment
		(start 193.192908 -324.666356)
		(end 194.415918 -321.71386)
		(width 0.1651)
		(layer "In7.Cu")
		(net "P5E_PEX1_STN4_TX_DN<74>")
	)
	(segment
		(start 172.085762 -353.790758)
		(end 173.640242 -352.236278)
		(width 0.1651)
		(layer "In7.Cu")
		(net "P5E_PEX1_STN4_TX_DN<74>")
	)
	(segment
		(start 194.415918 -319.97396)
		(end 194.370198 -319.92824)
		(width 0.1143)
		(layer "In7.Cu")
		(net "P5E_PEX1_STN4_TX_DN<74>")
	)
	(segment
		(start 172.376592 -354.732082)
		(end 172.085762 -354.441252)
		(width 0.1651)
		(layer "In7.Cu")
		(net "P5E_PEX1_STN4_TX_DN<74>")
	)
	(segment
		(start 194.749928 -313.684412)
		(end 194.749928 -313.949842)
		(width 0.1143)
		(layer "In7.Cu")
		(net "P5E_PEX1_STN4_TX_DN<74>")
	)
	(segment
		(start 173.640242 -341.1474)
		(end 176.06645 -338.721192)
		(width 0.1651)
		(layer "In7.Cu")
		(net "P5E_PEX1_STN4_TX_DN<74>")
	)
	(segment
		(start 194.415918 -321.71386)
		(end 194.415918 -320.002408)
		(width 0.1651)
		(layer "In7.Cu")
		(net "P5E_PEX1_STN4_TX_DN<74>")
	)
	(segment
		(start 172.085762 -354.441252)
		(end 172.085762 -353.790758)
		(width 0.1651)
		(layer "In7.Cu")
		(net "P5E_PEX1_STN4_TX_DN<74>")
	)
	(segment
		(start 194.484498 -313.570112)
		(end 194.635628 -313.570112)
		(width 0.1143)
		(layer "In7.Cu")
		(net "P5E_PEX1_STN4_TX_DN<74>")
	)
	(segment
		(start 194.635628 -313.570112)
		(end 194.749928 -313.684412)
		(width 0.1143)
		(layer "In7.Cu")
		(net "P5E_PEX1_STN4_TX_DN<74>")
	)
	(segment
		(start 173.640242 -352.236278)
		(end 173.640242 -341.1474)
		(width 0.1651)
		(layer "In7.Cu")
		(net "P5E_PEX1_STN4_TX_DN<74>")
	)
	(segment
		(start 176.06645 -338.721192)
		(end 185.323988 -332.535276)
		(width 0.1651)
		(layer "In7.Cu")
		(net "P5E_PEX1_STN4_TX_DN<74>")
	)
	(segment
		(start 194.415918 -320.002408)
		(end 194.415918 -319.97396)
		(width 0.1143)
		(layer "In7.Cu")
		(net "P5E_PEX1_STN4_TX_DN<74>")
	)
	(segment
		(start 185.323988 -332.535276)
		(end 193.192908 -324.666356)
		(width 0.1651)
		(layer "In7.Cu")
		(net "P5E_PEX1_STN4_TX_DN<74>")
	)
	(segment
		(start 194.370198 -319.92824)
		(end 194.370198 -313.684412)
		(width 0.1143)
		(layer "In7.Cu")
		(net "P5E_PEX1_STN4_TX_DN<74>")
	)
	(segment
		(start 178.299872 -343.365582)
		(end 178.299872 -342.734138)
		(width 0.13462)
		(layer "F.Cu")
		(net "P5E_PEX1_STN4_TX_DN<72>")
	)
	(segment
		(start 178.299872 -342.734138)
		(end 178.594512 -342.439498)
		(width 0.13462)
		(layer "F.Cu")
		(net "P5E_PEX1_STN4_TX_DN<72>")
	)
	(segment
		(start 178.619912 -343.685622)
		(end 178.299872 -343.365582)
		(width 0.13462)
		(layer "F.Cu")
		(net "P5E_PEX1_STN4_TX_DN<72>")
	)
	(segment
		(start 196.270118 -319.92824)
		(end 196.270118 -313.684412)
		(width 0.1143)
		(layer "In7.Cu")
		(net "P5E_PEX1_STN4_TX_DN<72>")
	)
	(segment
		(start 196.535548 -313.570112)
		(end 196.649848 -313.684412)
		(width 0.1143)
		(layer "In7.Cu")
		(net "P5E_PEX1_STN4_TX_DN<72>")
	)
	(segment
		(start 182.469536 -337.105244)
		(end 185.441336 -335.119472)
		(width 0.1651)
		(layer "In7.Cu")
		(net "P5E_PEX1_STN4_TX_DN<72>")
	)
	(segment
		(start 185.441336 -335.119472)
		(end 195.047108 -325.5137)
		(width 0.1651)
		(layer "In7.Cu")
		(net "P5E_PEX1_STN4_TX_DN<72>")
	)
	(segment
		(start 178.594512 -342.439498)
		(end 178.303682 -342.148668)
		(width 0.1651)
		(layer "In7.Cu")
		(net "P5E_PEX1_STN4_TX_DN<72>")
	)
	(segment
		(start 178.303682 -342.148668)
		(end 178.303682 -341.271098)
		(width 0.1651)
		(layer "In7.Cu")
		(net "P5E_PEX1_STN4_TX_DN<72>")
	)
	(segment
		(start 196.384418 -313.570112)
		(end 196.535548 -313.570112)
		(width 0.1143)
		(layer "In7.Cu")
		(net "P5E_PEX1_STN4_TX_DN<72>")
	)
	(segment
		(start 196.315838 -319.97396)
		(end 196.270118 -319.92824)
		(width 0.1143)
		(layer "In7.Cu")
		(net "P5E_PEX1_STN4_TX_DN<72>")
	)
	(segment
		(start 195.047108 -325.5137)
		(end 196.315838 -322.450714)
		(width 0.1651)
		(layer "In7.Cu")
		(net "P5E_PEX1_STN4_TX_DN<72>")
	)
	(segment
		(start 196.649848 -313.684412)
		(end 196.649848 -313.949842)
		(width 0.1143)
		(layer "In7.Cu")
		(net "P5E_PEX1_STN4_TX_DN<72>")
	)
	(segment
		(start 196.315838 -322.450714)
		(end 196.315838 -320.002408)
		(width 0.1651)
		(layer "In7.Cu")
		(net "P5E_PEX1_STN4_TX_DN<72>")
	)
	(segment
		(start 196.315838 -320.002408)
		(end 196.315838 -319.97396)
		(width 0.1143)
		(layer "In7.Cu")
		(net "P5E_PEX1_STN4_TX_DN<72>")
	)
	(segment
		(start 178.303682 -341.271098)
		(end 182.469536 -337.105244)
		(width 0.1651)
		(layer "In7.Cu")
		(net "P5E_PEX1_STN4_TX_DN<72>")
	)
	(segment
		(start 196.270118 -313.684412)
		(end 196.384418 -313.570112)
		(width 0.1143)
		(layer "In7.Cu")
		(net "P5E_PEX1_STN4_TX_DN<72>")
	)
	(segment
		(start 190.141352 -343.685622)
		(end 190.461392 -343.365582)
		(width 0.13462)
		(layer "F.Cu")
		(net "P5E_PEX1_STN4_TX_DP<66>")
	)
	(segment
		(start 190.461392 -343.365582)
		(end 190.461392 -342.734138)
		(width 0.13462)
		(layer "F.Cu")
		(net "P5E_PEX1_STN4_TX_DP<66>")
	)
	(segment
		(start 190.461392 -342.734138)
		(end 190.166752 -342.439498)
		(width 0.13462)
		(layer "F.Cu")
		(net "P5E_PEX1_STN4_TX_DP<66>")
	)
	(segment
		(start 191.555624 -306.920138)
		(end 191.329818 -306.694332)
		(width 0.1143)
		(layer "In7.Cu")
		(net "P5E_PEX1_STN4_TX_DP<66>")
	)
	(segment
		(start 192.762886 -339.178392)
		(end 192.923922 -339.19033)
		(width 0.1651)
		(layer "In7.Cu")
		(net "P5E_PEX1_STN4_TX_DP<66>")
	)
	(segment
		(start 190.166752 -342.439498)
		(end 190.457582 -342.148668)
		(width 0.1651)
		(layer "In7.Cu")
		(net "P5E_PEX1_STN4_TX_DP<66>")
	)
	(segment
		(start 193.847212 -338.393786)
		(end 200.514712 -332.64221)
		(width 0.1651)
		(layer "In7.Cu")
		(net "P5E_PEX1_STN4_TX_DP<66>")
	)
	(segment
		(start 190.681864 -341.12454)
		(end 192.375536 -339.663532)
		(width 0.1651)
		(layer "In7.Cu")
		(net "P5E_PEX1_STN4_TX_DP<66>")
	)
	(segment
		(start 209.477864 -314.475114)
		(end 208.297526 -313.986926)
		(width 0.1651)
		(layer "In7.Cu")
		(net "P5E_PEX1_STN4_TX_DP<66>")
	)
	(segment
		(start 199.774048 -306.965858)
		(end 199.7456 -306.965858)
		(width 0.1143)
		(layer "In7.Cu")
		(net "P5E_PEX1_STN4_TX_DP<66>")
	)
	(segment
		(start 201.905108 -307.603398)
		(end 200.364852 -306.965858)
		(width 0.1651)
		(layer "In7.Cu")
		(net "P5E_PEX1_STN4_TX_DP<66>")
	)
	(segment
		(start 209.695034 -326.50811)
		(end 211.510372 -324.692772)
		(width 0.1651)
		(layer "In7.Cu")
		(net "P5E_PEX1_STN4_TX_DP<66>")
	)
	(segment
		(start 191.329818 -306.464208)
		(end 191.215518 -306.349908)
		(width 0.1143)
		(layer "In7.Cu")
		(net "P5E_PEX1_STN4_TX_DP<66>")
	)
	(segment
		(start 200.514712 -332.64221)
		(end 209.695034 -326.50811)
		(width 0.1651)
		(layer "In7.Cu")
		(net "P5E_PEX1_STN4_TX_DP<66>")
	)
	(segment
		(start 208.297526 -313.986926)
		(end 201.905108 -307.603398)
		(width 0.1651)
		(layer "In7.Cu")
		(net "P5E_PEX1_STN4_TX_DP<66>")
	)
	(segment
		(start 190.457582 -342.148668)
		(end 190.457582 -341.614252)
		(width 0.1651)
		(layer "In7.Cu")
		(net "P5E_PEX1_STN4_TX_DP<66>")
	)
	(segment
		(start 212.72754 -319.863216)
		(end 211.244434 -316.238636)
		(width 0.1651)
		(layer "In7.Cu")
		(net "P5E_PEX1_STN4_TX_DP<66>")
	)
	(segment
		(start 192.375536 -339.663532)
		(end 192.387474 -339.502242)
		(width 0.1651)
		(layer "In7.Cu")
		(net "P5E_PEX1_STN4_TX_DP<66>")
	)
	(segment
		(start 192.923922 -339.19033)
		(end 193.298826 -338.866988)
		(width 0.1651)
		(layer "In7.Cu")
		(net "P5E_PEX1_STN4_TX_DP<66>")
	)
	(segment
		(start 212.72754 -321.754246)
		(end 212.72754 -319.863216)
		(width 0.1651)
		(layer "In7.Cu")
		(net "P5E_PEX1_STN4_TX_DP<66>")
	)
	(segment
		(start 193.310764 -338.705698)
		(end 193.685922 -338.381848)
		(width 0.1651)
		(layer "In7.Cu")
		(net "P5E_PEX1_STN4_TX_DP<66>")
	)
	(segment
		(start 193.685922 -338.381848)
		(end 193.847212 -338.393786)
		(width 0.1651)
		(layer "In7.Cu")
		(net "P5E_PEX1_STN4_TX_DP<66>")
	)
	(segment
		(start 190.457582 -341.614252)
		(end 190.681864 -341.12454)
		(width 0.1651)
		(layer "In7.Cu")
		(net "P5E_PEX1_STN4_TX_DP<66>")
	)
	(segment
		(start 211.510372 -324.692772)
		(end 211.510118 -324.692772)
		(width 0.1651)
		(layer "In7.Cu")
		(net "P5E_PEX1_STN4_TX_DP<66>")
	)
	(segment
		(start 199.69988 -306.920138)
		(end 191.555624 -306.920138)
		(width 0.1143)
		(layer "In7.Cu")
		(net "P5E_PEX1_STN4_TX_DP<66>")
	)
	(segment
		(start 211.244434 -316.238636)
		(end 209.477864 -314.475114)
		(width 0.1651)
		(layer "In7.Cu")
		(net "P5E_PEX1_STN4_TX_DP<66>")
	)
	(segment
		(start 200.364852 -306.965858)
		(end 199.774048 -306.965858)
		(width 0.1651)
		(layer "In7.Cu")
		(net "P5E_PEX1_STN4_TX_DP<66>")
	)
	(segment
		(start 191.329818 -306.694332)
		(end 191.329818 -306.464208)
		(width 0.1143)
		(layer "In7.Cu")
		(net "P5E_PEX1_STN4_TX_DP<66>")
	)
	(segment
		(start 211.510118 -324.692772)
		(end 212.72754 -321.754246)
		(width 0.1651)
		(layer "In7.Cu")
		(net "P5E_PEX1_STN4_TX_DP<66>")
	)
	(segment
		(start 193.298826 -338.866988)
		(end 193.310764 -338.705698)
		(width 0.1651)
		(layer "In7.Cu")
		(net "P5E_PEX1_STN4_TX_DP<66>")
	)
	(segment
		(start 192.387474 -339.502242)
		(end 192.762886 -339.178392)
		(width 0.1651)
		(layer "In7.Cu")
		(net "P5E_PEX1_STN4_TX_DP<66>")
	)
	(segment
		(start 199.7456 -306.965858)
		(end 199.69988 -306.920138)
		(width 0.1143)
		(layer "In7.Cu")
		(net "P5E_PEX1_STN4_TX_DP<66>")
	)
	(segment
		(start 191.215518 -306.349908)
		(end 190.950088 -306.349908)
		(width 0.1143)
		(layer "In7.Cu")
		(net "P5E_PEX1_STN4_TX_DP<66>")
	)
	(segment
		(start 177.705512 -355.978206)
		(end 178.025552 -355.658166)
		(width 0.13462)
		(layer "F.Cu")
		(net "P5E_PEX1_STN4_TX_DP<71>")
	)
	(segment
		(start 178.025552 -355.658166)
		(end 178.025552 -355.026722)
		(width 0.13462)
		(layer "F.Cu")
		(net "P5E_PEX1_STN4_TX_DP<71>")
	)
	(segment
		(start 178.025552 -355.026722)
		(end 177.730912 -354.732082)
		(width 0.13462)
		(layer "F.Cu")
		(net "P5E_PEX1_STN4_TX_DP<71>")
	)
	(segment
		(start 197.934072 -318.9224)
		(end 197.979792 -318.87668)
		(width 0.1143)
		(layer "In7.Cu")
		(net "P5E_PEX1_STN4_TX_DP<71>")
	)
	(segment
		(start 179.576222 -341.950548)
		(end 179.95773 -341.02929)
		(width 0.1651)
		(layer "In7.Cu")
		(net "P5E_PEX1_STN4_TX_DP<71>")
	)
	(segment
		(start 197.979792 -315.014102)
		(end 197.865492 -314.899802)
		(width 0.1143)
		(layer "In7.Cu")
		(net "P5E_PEX1_STN4_TX_DP<71>")
	)
	(segment
		(start 197.934072 -320.708274)
		(end 197.934072 -318.950848)
		(width 0.1651)
		(layer "In7.Cu")
		(net "P5E_PEX1_STN4_TX_DP<71>")
	)
	(segment
		(start 179.95773 -341.02929)
		(end 183.69661 -337.29041)
		(width 0.1651)
		(layer "In7.Cu")
		(net "P5E_PEX1_STN4_TX_DP<71>")
	)
	(segment
		(start 197.934072 -318.950848)
		(end 197.934072 -318.9224)
		(width 0.1143)
		(layer "In7.Cu")
		(net "P5E_PEX1_STN4_TX_DP<71>")
	)
	(segment
		(start 178.021742 -353.673918)
		(end 179.576222 -352.119438)
		(width 0.1651)
		(layer "In7.Cu")
		(net "P5E_PEX1_STN4_TX_DP<71>")
	)
	(segment
		(start 185.281316 -336.231484)
		(end 195.904358 -325.608442)
		(width 0.1651)
		(layer "In7.Cu")
		(net "P5E_PEX1_STN4_TX_DP<71>")
	)
	(segment
		(start 197.979792 -318.87668)
		(end 197.979792 -315.014102)
		(width 0.1143)
		(layer "In7.Cu")
		(net "P5E_PEX1_STN4_TX_DP<71>")
	)
	(segment
		(start 195.904358 -325.608442)
		(end 197.934072 -320.708274)
		(width 0.1651)
		(layer "In7.Cu")
		(net "P5E_PEX1_STN4_TX_DP<71>")
	)
	(segment
		(start 183.69661 -337.29041)
		(end 185.281316 -336.231484)
		(width 0.1651)
		(layer "In7.Cu")
		(net "P5E_PEX1_STN4_TX_DP<71>")
	)
	(segment
		(start 179.576222 -352.119438)
		(end 179.576222 -341.950548)
		(width 0.1651)
		(layer "In7.Cu")
		(net "P5E_PEX1_STN4_TX_DP<71>")
	)
	(segment
		(start 178.021742 -354.441252)
		(end 178.021742 -353.673918)
		(width 0.1651)
		(layer "In7.Cu")
		(net "P5E_PEX1_STN4_TX_DP<71>")
	)
	(segment
		(start 177.730912 -354.732082)
		(end 178.021742 -354.441252)
		(width 0.1651)
		(layer "In7.Cu")
		(net "P5E_PEX1_STN4_TX_DP<71>")
	)
	(segment
		(start 197.865492 -314.899802)
		(end 197.600062 -314.899802)
		(width 0.1143)
		(layer "In7.Cu")
		(net "P5E_PEX1_STN4_TX_DP<71>")
	)
	(segment
		(start 171.807632 -355.026722)
		(end 171.512992 -354.732082)
		(width 0.13462)
		(layer "F.Cu")
		(net "P5E_PEX1_STN4_TX_DP<74>")
	)
	(segment
		(start 171.487592 -355.978206)
		(end 171.807632 -355.658166)
		(width 0.13462)
		(layer "F.Cu")
		(net "P5E_PEX1_STN4_TX_DP<74>")
	)
	(segment
		(start 171.807632 -355.658166)
		(end 171.807632 -355.026722)
		(width 0.13462)
		(layer "F.Cu")
		(net "P5E_PEX1_STN4_TX_DP<74>")
	)
	(segment
		(start 194.133978 -319.97396)
		(end 194.179698 -319.92824)
		(width 0.1143)
		(layer "In7.Cu")
		(net "P5E_PEX1_STN4_TX_DP<74>")
	)
	(segment
		(start 171.512992 -354.732082)
		(end 171.803822 -354.441252)
		(width 0.1651)
		(layer "In7.Cu")
		(net "P5E_PEX1_STN4_TX_DP<74>")
	)
	(segment
		(start 194.749928 -313.265312)
		(end 194.749928 -312.999882)
		(width 0.1143)
		(layer "In7.Cu")
		(net "P5E_PEX1_STN4_TX_DP<74>")
	)
	(segment
		(start 175.886618 -338.502244)
		(end 185.144156 -332.316328)
		(width 0.1651)
		(layer "In7.Cu")
		(net "P5E_PEX1_STN4_TX_DP<74>")
	)
	(segment
		(start 194.179698 -313.605418)
		(end 194.405504 -313.379612)
		(width 0.1143)
		(layer "In7.Cu")
		(net "P5E_PEX1_STN4_TX_DP<74>")
	)
	(segment
		(start 194.133978 -320.002408)
		(end 194.133978 -319.97396)
		(width 0.1143)
		(layer "In7.Cu")
		(net "P5E_PEX1_STN4_TX_DP<74>")
	)
	(segment
		(start 171.803822 -354.441252)
		(end 171.803822 -353.673918)
		(width 0.1651)
		(layer "In7.Cu")
		(net "P5E_PEX1_STN4_TX_DP<74>")
	)
	(segment
		(start 173.358302 -341.03056)
		(end 175.886618 -338.502244)
		(width 0.1651)
		(layer "In7.Cu")
		(net "P5E_PEX1_STN4_TX_DP<74>")
	)
	(segment
		(start 194.405504 -313.379612)
		(end 194.635628 -313.379612)
		(width 0.1143)
		(layer "In7.Cu")
		(net "P5E_PEX1_STN4_TX_DP<74>")
	)
	(segment
		(start 173.358302 -352.119438)
		(end 173.358302 -341.03056)
		(width 0.1651)
		(layer "In7.Cu")
		(net "P5E_PEX1_STN4_TX_DP<74>")
	)
	(segment
		(start 185.144156 -332.316328)
		(end 192.953894 -324.50659)
		(width 0.1651)
		(layer "In7.Cu")
		(net "P5E_PEX1_STN4_TX_DP<74>")
	)
	(segment
		(start 192.953894 -324.50659)
		(end 194.133978 -321.657726)
		(width 0.1651)
		(layer "In7.Cu")
		(net "P5E_PEX1_STN4_TX_DP<74>")
	)
	(segment
		(start 194.179698 -319.92824)
		(end 194.179698 -313.605418)
		(width 0.1143)
		(layer "In7.Cu")
		(net "P5E_PEX1_STN4_TX_DP<74>")
	)
	(segment
		(start 171.803822 -353.673918)
		(end 173.358302 -352.119438)
		(width 0.1651)
		(layer "In7.Cu")
		(net "P5E_PEX1_STN4_TX_DP<74>")
	)
	(segment
		(start 194.133978 -321.657726)
		(end 194.133978 -320.002408)
		(width 0.1651)
		(layer "In7.Cu")
		(net "P5E_PEX1_STN4_TX_DP<74>")
	)
	(segment
		(start 194.635628 -313.379612)
		(end 194.749928 -313.265312)
		(width 0.1143)
		(layer "In7.Cu")
		(net "P5E_PEX1_STN4_TX_DP<74>")
	)
	(segment
		(start 165.589712 -343.365582)
		(end 165.589712 -342.734138)
		(width 0.13462)
		(layer "F.Cu")
		(net "P5E_PEX1_STN4_TX_DP<78>")
	)
	(segment
		(start 165.589712 -342.734138)
		(end 165.295072 -342.439498)
		(width 0.13462)
		(layer "F.Cu")
		(net "P5E_PEX1_STN4_TX_DP<78>")
	)
	(segment
		(start 165.269672 -343.685622)
		(end 165.589712 -343.365582)
		(width 0.13462)
		(layer "F.Cu")
		(net "P5E_PEX1_STN4_TX_DP<78>")
	)
	(segment
		(start 165.585902 -342.148668)
		(end 165.585902 -340.97976)
		(width 0.1651)
		(layer "In7.Cu")
		(net "P5E_PEX1_STN4_TX_DP<78>")
	)
	(segment
		(start 165.295072 -342.439498)
		(end 165.585902 -342.148668)
		(width 0.1651)
		(layer "In7.Cu")
		(net "P5E_PEX1_STN4_TX_DP<78>")
	)
	(segment
		(start 190.334138 -320.002408)
		(end 190.334138 -319.97396)
		(width 0.1143)
		(layer "In7.Cu")
		(net "P5E_PEX1_STN4_TX_DP<78>")
	)
	(segment
		(start 190.950088 -313.265312)
		(end 190.950088 -312.999882)
		(width 0.1143)
		(layer "In7.Cu")
		(net "P5E_PEX1_STN4_TX_DP<78>")
	)
	(segment
		(start 190.605664 -313.379612)
		(end 190.835788 -313.379612)
		(width 0.1143)
		(layer "In7.Cu")
		(net "P5E_PEX1_STN4_TX_DP<78>")
	)
	(segment
		(start 165.585902 -340.97976)
		(end 166.159942 -340.40572)
		(width 0.1651)
		(layer "In7.Cu")
		(net "P5E_PEX1_STN4_TX_DP<78>")
	)
	(segment
		(start 166.159942 -340.40572)
		(end 182.690008 -329.360784)
		(width 0.1651)
		(layer "In7.Cu")
		(net "P5E_PEX1_STN4_TX_DP<78>")
	)
	(segment
		(start 190.835788 -313.379612)
		(end 190.950088 -313.265312)
		(width 0.1143)
		(layer "In7.Cu")
		(net "P5E_PEX1_STN4_TX_DP<78>")
	)
	(segment
		(start 189.570614 -322.480178)
		(end 190.334138 -320.6369)
		(width 0.1651)
		(layer "In7.Cu")
		(net "P5E_PEX1_STN4_TX_DP<78>")
	)
	(segment
		(start 190.334138 -320.6369)
		(end 190.334138 -320.002408)
		(width 0.1651)
		(layer "In7.Cu")
		(net "P5E_PEX1_STN4_TX_DP<78>")
	)
	(segment
		(start 182.690008 -329.360784)
		(end 189.570614 -322.480178)
		(width 0.1651)
		(layer "In7.Cu")
		(net "P5E_PEX1_STN4_TX_DP<78>")
	)
	(segment
		(start 190.379858 -319.92824)
		(end 190.379858 -313.605418)
		(width 0.1143)
		(layer "In7.Cu")
		(net "P5E_PEX1_STN4_TX_DP<78>")
	)
	(segment
		(start 190.334138 -319.97396)
		(end 190.379858 -319.92824)
		(width 0.1143)
		(layer "In7.Cu")
		(net "P5E_PEX1_STN4_TX_DP<78>")
	)
	(segment
		(start 190.379858 -313.605418)
		(end 190.605664 -313.379612)
		(width 0.1143)
		(layer "In7.Cu")
		(net "P5E_PEX1_STN4_TX_DP<78>")
	)
	(segment
		(start 172.081952 -343.365582)
		(end 172.081952 -342.734138)
		(width 0.13462)
		(layer "F.Cu")
		(net "P5E_PEX1_STN4_TX_DN<75>")
	)
	(segment
		(start 172.401992 -343.685622)
		(end 172.081952 -343.365582)
		(width 0.13462)
		(layer "F.Cu")
		(net "P5E_PEX1_STN4_TX_DN<75>")
	)
	(segment
		(start 172.081952 -342.734138)
		(end 172.376592 -342.439498)
		(width 0.13462)
		(layer "F.Cu")
		(net "P5E_PEX1_STN4_TX_DN<75>")
	)
	(segment
		(start 193.465958 -321.475608)
		(end 193.465958 -320.016886)
		(width 0.1651)
		(layer "In7.Cu")
		(net "P5E_PEX1_STN4_TX_DN<75>")
	)
	(segment
		(start 193.685668 -311.670192)
		(end 193.799968 -311.784492)
		(width 0.1143)
		(layer "In7.Cu")
		(net "P5E_PEX1_STN4_TX_DN<75>")
	)
	(segment
		(start 174.69104 -338.491322)
		(end 184.71515 -331.793342)
		(width 0.1651)
		(layer "In7.Cu")
		(net "P5E_PEX1_STN4_TX_DN<75>")
	)
	(segment
		(start 172.085762 -341.0966)
		(end 174.69104 -338.491322)
		(width 0.1651)
		(layer "In7.Cu")
		(net "P5E_PEX1_STN4_TX_DN<75>")
	)
	(segment
		(start 193.534538 -311.670192)
		(end 193.685668 -311.670192)
		(width 0.1143)
		(layer "In7.Cu")
		(net "P5E_PEX1_STN4_TX_DN<75>")
	)
	(segment
		(start 172.085762 -342.148668)
		(end 172.085762 -341.0966)
		(width 0.1651)
		(layer "In7.Cu")
		(net "P5E_PEX1_STN4_TX_DN<75>")
	)
	(segment
		(start 193.420238 -311.784492)
		(end 193.534538 -311.670192)
		(width 0.1143)
		(layer "In7.Cu")
		(net "P5E_PEX1_STN4_TX_DN<75>")
	)
	(segment
		(start 193.420238 -319.942718)
		(end 193.420238 -311.784492)
		(width 0.1143)
		(layer "In7.Cu")
		(net "P5E_PEX1_STN4_TX_DN<75>")
	)
	(segment
		(start 184.71515 -331.793342)
		(end 192.357756 -324.150736)
		(width 0.1651)
		(layer "In7.Cu")
		(net "P5E_PEX1_STN4_TX_DN<75>")
	)
	(segment
		(start 193.465958 -320.016886)
		(end 193.465958 -319.988438)
		(width 0.1143)
		(layer "In7.Cu")
		(net "P5E_PEX1_STN4_TX_DN<75>")
	)
	(segment
		(start 193.799968 -311.784492)
		(end 193.799968 -312.049922)
		(width 0.1143)
		(layer "In7.Cu")
		(net "P5E_PEX1_STN4_TX_DN<75>")
	)
	(segment
		(start 193.465958 -319.988438)
		(end 193.420238 -319.942718)
		(width 0.1143)
		(layer "In7.Cu")
		(net "P5E_PEX1_STN4_TX_DN<75>")
	)
	(segment
		(start 192.357756 -324.150736)
		(end 193.465958 -321.475608)
		(width 0.1651)
		(layer "In7.Cu")
		(net "P5E_PEX1_STN4_TX_DN<75>")
	)
	(segment
		(start 172.376592 -342.439498)
		(end 172.085762 -342.148668)
		(width 0.1651)
		(layer "In7.Cu")
		(net "P5E_PEX1_STN4_TX_DN<75>")
	)
	(segment
		(start 165.864032 -342.734138)
		(end 166.158672 -342.439498)
		(width 0.13462)
		(layer "F.Cu")
		(net "P5E_PEX1_STN4_TX_DN<78>")
	)
	(segment
		(start 166.184072 -343.685622)
		(end 165.864032 -343.365582)
		(width 0.13462)
		(layer "F.Cu")
		(net "P5E_PEX1_STN4_TX_DN<78>")
	)
	(segment
		(start 165.864032 -343.365582)
		(end 165.864032 -342.734138)
		(width 0.13462)
		(layer "F.Cu")
		(net "P5E_PEX1_STN4_TX_DN<78>")
	)
	(segment
		(start 190.684658 -313.570112)
		(end 190.835788 -313.570112)
		(width 0.1143)
		(layer "In7.Cu")
		(net "P5E_PEX1_STN4_TX_DN<78>")
	)
	(segment
		(start 189.809628 -322.639944)
		(end 190.616078 -320.693034)
		(width 0.1651)
		(layer "In7.Cu")
		(net "P5E_PEX1_STN4_TX_DN<78>")
	)
	(segment
		(start 190.570358 -313.684412)
		(end 190.684658 -313.570112)
		(width 0.1143)
		(layer "In7.Cu")
		(net "P5E_PEX1_STN4_TX_DN<78>")
	)
	(segment
		(start 190.616078 -319.97396)
		(end 190.570358 -319.92824)
		(width 0.1143)
		(layer "In7.Cu")
		(net "P5E_PEX1_STN4_TX_DN<78>")
	)
	(segment
		(start 190.570358 -319.92824)
		(end 190.570358 -313.684412)
		(width 0.1143)
		(layer "In7.Cu")
		(net "P5E_PEX1_STN4_TX_DN<78>")
	)
	(segment
		(start 190.616078 -320.693034)
		(end 190.616078 -320.002408)
		(width 0.1651)
		(layer "In7.Cu")
		(net "P5E_PEX1_STN4_TX_DN<78>")
	)
	(segment
		(start 166.158672 -342.439498)
		(end 165.867842 -342.148668)
		(width 0.1651)
		(layer "In7.Cu")
		(net "P5E_PEX1_STN4_TX_DN<78>")
	)
	(segment
		(start 190.950088 -313.684412)
		(end 190.950088 -313.949842)
		(width 0.1143)
		(layer "In7.Cu")
		(net "P5E_PEX1_STN4_TX_DN<78>")
	)
	(segment
		(start 165.867842 -342.148668)
		(end 165.867842 -341.0966)
		(width 0.1651)
		(layer "In7.Cu")
		(net "P5E_PEX1_STN4_TX_DN<78>")
	)
	(segment
		(start 165.867842 -341.0966)
		(end 166.339774 -340.624668)
		(width 0.1651)
		(layer "In7.Cu")
		(net "P5E_PEX1_STN4_TX_DN<78>")
	)
	(segment
		(start 190.616078 -320.002408)
		(end 190.616078 -319.97396)
		(width 0.1143)
		(layer "In7.Cu")
		(net "P5E_PEX1_STN4_TX_DN<78>")
	)
	(segment
		(start 190.835788 -313.570112)
		(end 190.950088 -313.684412)
		(width 0.1143)
		(layer "In7.Cu")
		(net "P5E_PEX1_STN4_TX_DN<78>")
	)
	(segment
		(start 166.339774 -340.624668)
		(end 182.86984 -329.579732)
		(width 0.1651)
		(layer "In7.Cu")
		(net "P5E_PEX1_STN4_TX_DN<78>")
	)
	(segment
		(start 182.86984 -329.579732)
		(end 189.809628 -322.639944)
		(width 0.1651)
		(layer "In7.Cu")
		(net "P5E_PEX1_STN4_TX_DN<78>")
	)
	(segment
		(start 177.705512 -343.685622)
		(end 178.025552 -343.365582)
		(width 0.13462)
		(layer "F.Cu")
		(net "P5E_PEX1_STN4_TX_DP<72>")
	)
	(segment
		(start 178.025552 -343.365582)
		(end 178.025552 -342.734138)
		(width 0.13462)
		(layer "F.Cu")
		(net "P5E_PEX1_STN4_TX_DP<72>")
	)
	(segment
		(start 178.025552 -342.734138)
		(end 177.730912 -342.439498)
		(width 0.13462)
		(layer "F.Cu")
		(net "P5E_PEX1_STN4_TX_DP<72>")
	)
	(segment
		(start 185.261504 -334.900524)
		(end 194.808094 -325.353934)
		(width 0.1651)
		(layer "In7.Cu")
		(net "P5E_PEX1_STN4_TX_DP<72>")
	)
	(segment
		(start 196.033898 -322.39458)
		(end 196.033898 -320.002408)
		(width 0.1651)
		(layer "In7.Cu")
		(net "P5E_PEX1_STN4_TX_DP<72>")
	)
	(segment
		(start 178.021742 -342.148668)
		(end 178.021742 -341.154258)
		(width 0.1651)
		(layer "In7.Cu")
		(net "P5E_PEX1_STN4_TX_DP<72>")
	)
	(segment
		(start 178.021742 -341.154258)
		(end 182.289704 -336.886296)
		(width 0.1651)
		(layer "In7.Cu")
		(net "P5E_PEX1_STN4_TX_DP<72>")
	)
	(segment
		(start 196.305424 -313.379612)
		(end 196.535548 -313.379612)
		(width 0.1143)
		(layer "In7.Cu")
		(net "P5E_PEX1_STN4_TX_DP<72>")
	)
	(segment
		(start 196.033898 -319.97396)
		(end 196.079618 -319.92824)
		(width 0.1143)
		(layer "In7.Cu")
		(net "P5E_PEX1_STN4_TX_DP<72>")
	)
	(segment
		(start 196.535548 -313.379612)
		(end 196.649848 -313.265312)
		(width 0.1143)
		(layer "In7.Cu")
		(net "P5E_PEX1_STN4_TX_DP<72>")
	)
	(segment
		(start 196.079618 -313.605418)
		(end 196.305424 -313.379612)
		(width 0.1143)
		(layer "In7.Cu")
		(net "P5E_PEX1_STN4_TX_DP<72>")
	)
	(segment
		(start 182.289704 -336.886296)
		(end 185.261504 -334.900524)
		(width 0.1651)
		(layer "In7.Cu")
		(net "P5E_PEX1_STN4_TX_DP<72>")
	)
	(segment
		(start 194.808094 -325.353934)
		(end 196.033898 -322.39458)
		(width 0.1651)
		(layer "In7.Cu")
		(net "P5E_PEX1_STN4_TX_DP<72>")
	)
	(segment
		(start 196.649848 -313.265312)
		(end 196.649848 -312.999882)
		(width 0.1143)
		(layer "In7.Cu")
		(net "P5E_PEX1_STN4_TX_DP<72>")
	)
	(segment
		(start 196.079618 -319.92824)
		(end 196.079618 -313.605418)
		(width 0.1143)
		(layer "In7.Cu")
		(net "P5E_PEX1_STN4_TX_DP<72>")
	)
	(segment
		(start 196.033898 -320.002408)
		(end 196.033898 -319.97396)
		(width 0.1143)
		(layer "In7.Cu")
		(net "P5E_PEX1_STN4_TX_DP<72>")
	)
	(segment
		(start 177.730912 -342.439498)
		(end 178.021742 -342.148668)
		(width 0.1651)
		(layer "In7.Cu")
		(net "P5E_PEX1_STN4_TX_DP<72>")
	)
	(segment
		(start 180.814472 -349.831914)
		(end 181.134512 -349.511874)
		(width 0.13462)
		(layer "F.Cu")
		(net "P5E_PEX1_STN4_TX_DP<70>")
	)
	(segment
		(start 181.134512 -348.88043)
		(end 180.839872 -348.58579)
		(width 0.13462)
		(layer "F.Cu")
		(net "P5E_PEX1_STN4_TX_DP<70>")
	)
	(segment
		(start 181.134512 -349.511874)
		(end 181.134512 -348.88043)
		(width 0.13462)
		(layer "F.Cu")
		(net "P5E_PEX1_STN4_TX_DP<70>")
	)
	(segment
		(start 197.979792 -312.394346)
		(end 197.979792 -312.164222)
		(width 0.1143)
		(layer "In7.Cu")
		(net "P5E_PEX1_STN4_TX_DP<70>")
	)
	(segment
		(start 198.773796 -312.620152)
		(end 198.205598 -312.620152)
		(width 0.1143)
		(layer "In7.Cu")
		(net "P5E_PEX1_STN4_TX_DP<70>")
	)
	(segment
		(start 197.34657 -325.67245)
		(end 199.661526 -320.084704)
		(width 0.1651)
		(layer "In7.Cu")
		(net "P5E_PEX1_STN4_TX_DP<70>")
	)
	(segment
		(start 198.205598 -312.620152)
		(end 197.979792 -312.394346)
		(width 0.1143)
		(layer "In7.Cu")
		(net "P5E_PEX1_STN4_TX_DP<70>")
	)
	(segment
		(start 200.0758 -314.543186)
		(end 199.682608 -313.593988)
		(width 0.1651)
		(layer "In7.Cu")
		(net "P5E_PEX1_STN4_TX_DP<70>")
	)
	(segment
		(start 182.685182 -346.038678)
		(end 182.685182 -340.333838)
		(width 0.1651)
		(layer "In7.Cu")
		(net "P5E_PEX1_STN4_TX_DP<70>")
	)
	(segment
		(start 199.064626 -312.910982)
		(end 198.773796 -312.620152)
		(width 0.1143)
		(layer "In7.Cu")
		(net "P5E_PEX1_STN4_TX_DP<70>")
	)
	(segment
		(start 199.661526 -320.084704)
		(end 200.0758 -317.84544)
		(width 0.1651)
		(layer "In7.Cu")
		(net "P5E_PEX1_STN4_TX_DP<70>")
	)
	(segment
		(start 199.084692 -312.996072)
		(end 199.064626 -312.976006)
		(width 0.1143)
		(layer "In7.Cu")
		(net "P5E_PEX1_STN4_TX_DP<70>")
	)
	(segment
		(start 181.130702 -347.593158)
		(end 182.685182 -346.038678)
		(width 0.1651)
		(layer "In7.Cu")
		(net "P5E_PEX1_STN4_TX_DP<70>")
	)
	(segment
		(start 197.865492 -312.049922)
		(end 197.600062 -312.049922)
		(width 0.1143)
		(layer "In7.Cu")
		(net "P5E_PEX1_STN4_TX_DP<70>")
	)
	(segment
		(start 199.682608 -313.593988)
		(end 199.084692 -312.996072)
		(width 0.1651)
		(layer "In7.Cu")
		(net "P5E_PEX1_STN4_TX_DP<70>")
	)
	(segment
		(start 180.839872 -348.58579)
		(end 181.130702 -348.29496)
		(width 0.1651)
		(layer "In7.Cu")
		(net "P5E_PEX1_STN4_TX_DP<70>")
	)
	(segment
		(start 181.130702 -348.29496)
		(end 181.130702 -347.593158)
		(width 0.1651)
		(layer "In7.Cu")
		(net "P5E_PEX1_STN4_TX_DP<70>")
	)
	(segment
		(start 200.0758 -317.84544)
		(end 200.0758 -314.543186)
		(width 0.1651)
		(layer "In7.Cu")
		(net "P5E_PEX1_STN4_TX_DP<70>")
	)
	(segment
		(start 182.685182 -340.333838)
		(end 197.34657 -325.67245)
		(width 0.1651)
		(layer "In7.Cu")
		(net "P5E_PEX1_STN4_TX_DP<70>")
	)
	(segment
		(start 197.979792 -312.164222)
		(end 197.865492 -312.049922)
		(width 0.1143)
		(layer "In7.Cu")
		(net "P5E_PEX1_STN4_TX_DP<70>")
	)
	(segment
		(start 199.064626 -312.976006)
		(end 199.064626 -312.910982)
		(width 0.1143)
		(layer "In7.Cu")
		(net "P5E_PEX1_STN4_TX_DP<70>")
	)
	(segment
		(start 196.953632 -343.365582)
		(end 196.953632 -342.734138)
		(width 0.13462)
		(layer "F.Cu")
		(net "P5E_PEX1_STN4_TX_DN<64>")
	)
	(segment
		(start 197.273672 -343.685622)
		(end 196.953632 -343.365582)
		(width 0.13462)
		(layer "F.Cu")
		(net "P5E_PEX1_STN4_TX_DN<64>")
	)
	(segment
		(start 196.953632 -342.734138)
		(end 197.248272 -342.439498)
		(width 0.13462)
		(layer "F.Cu")
		(net "P5E_PEX1_STN4_TX_DN<64>")
	)
	(segment
		(start 200.965816 -304.783744)
		(end 199.748648 -304.783744)
		(width 0.1651)
		(layer "In7.Cu")
		(net "P5E_PEX1_STN4_TX_DN<64>")
	)
	(segment
		(start 191.634618 -304.449734)
		(end 191.900048 -304.449734)
		(width 0.1143)
		(layer "In7.Cu")
		(net "P5E_PEX1_STN4_TX_DN<64>")
	)
	(segment
		(start 196.957442 -342.148668)
		(end 196.957442 -341.362792)
		(width 0.1651)
		(layer "In7.Cu")
		(net "P5E_PEX1_STN4_TX_DN<64>")
	)
	(segment
		(start 198.179182 -338.413598)
		(end 202.921362 -333.671418)
		(width 0.1651)
		(layer "In7.Cu")
		(net "P5E_PEX1_STN4_TX_DN<64>")
	)
	(segment
		(start 191.520318 -304.715164)
		(end 191.520318 -304.564034)
		(width 0.1143)
		(layer "In7.Cu")
		(net "P5E_PEX1_STN4_TX_DN<64>")
	)
	(segment
		(start 202.921362 -333.671418)
		(end 211.091018 -328.21245)
		(width 0.1651)
		(layer "In7.Cu")
		(net "P5E_PEX1_STN4_TX_DN<64>")
	)
	(segment
		(start 199.67448 -304.829464)
		(end 191.634618 -304.829464)
		(width 0.1143)
		(layer "In7.Cu")
		(net "P5E_PEX1_STN4_TX_DN<64>")
	)
	(segment
		(start 204.59573 -306.287424)
		(end 200.965816 -304.783744)
		(width 0.1651)
		(layer "In7.Cu")
		(net "P5E_PEX1_STN4_TX_DN<64>")
	)
	(segment
		(start 214.91956 -322.192396)
		(end 214.91956 -319.416176)
		(width 0.1651)
		(layer "In7.Cu")
		(net "P5E_PEX1_STN4_TX_DN<64>")
	)
	(segment
		(start 191.634618 -304.829464)
		(end 191.520318 -304.715164)
		(width 0.1143)
		(layer "In7.Cu")
		(net "P5E_PEX1_STN4_TX_DN<64>")
	)
	(segment
		(start 199.748648 -304.783744)
		(end 199.7202 -304.783744)
		(width 0.1143)
		(layer "In7.Cu")
		(net "P5E_PEX1_STN4_TX_DN<64>")
	)
	(segment
		(start 213.369906 -325.933562)
		(end 214.91956 -322.192396)
		(width 0.1651)
		(layer "In7.Cu")
		(net "P5E_PEX1_STN4_TX_DN<64>")
	)
	(segment
		(start 196.957442 -341.362792)
		(end 198.179182 -338.413598)
		(width 0.1651)
		(layer "In7.Cu")
		(net "P5E_PEX1_STN4_TX_DN<64>")
	)
	(segment
		(start 191.520318 -304.564034)
		(end 191.634618 -304.449734)
		(width 0.1143)
		(layer "In7.Cu")
		(net "P5E_PEX1_STN4_TX_DN<64>")
	)
	(segment
		(start 212.97265 -314.664344)
		(end 204.59573 -306.287424)
		(width 0.1651)
		(layer "In7.Cu")
		(net "P5E_PEX1_STN4_TX_DN<64>")
	)
	(segment
		(start 214.91956 -319.416176)
		(end 212.97265 -314.664344)
		(width 0.1651)
		(layer "In7.Cu")
		(net "P5E_PEX1_STN4_TX_DN<64>")
	)
	(segment
		(start 199.7202 -304.783744)
		(end 199.67448 -304.829464)
		(width 0.1143)
		(layer "In7.Cu")
		(net "P5E_PEX1_STN4_TX_DN<64>")
	)
	(segment
		(start 211.091018 -328.21245)
		(end 213.369906 -325.933562)
		(width 0.1651)
		(layer "In7.Cu")
		(net "P5E_PEX1_STN4_TX_DN<64>")
	)
	(segment
		(start 197.248272 -342.439498)
		(end 196.957442 -342.148668)
		(width 0.1651)
		(layer "In7.Cu")
		(net "P5E_PEX1_STN4_TX_DN<64>")
	)
	(segment
		(start 184.837832 -355.95433)
		(end 184.517792 -355.63429)
		(width 0.13462)
		(layer "F.Cu")
		(net "P5E_PEX1_STN4_TX_DN<68>")
	)
	(segment
		(start 184.517792 -355.63429)
		(end 184.517792 -355.002846)
		(width 0.13462)
		(layer "F.Cu")
		(net "P5E_PEX1_STN4_TX_DN<68>")
	)
	(segment
		(start 184.517792 -355.002846)
		(end 184.812432 -354.708206)
		(width 0.13462)
		(layer "F.Cu")
		(net "P5E_PEX1_STN4_TX_DN<68>")
	)
	(segment
		(start 186.076082 -352.212402)
		(end 186.076082 -342.051386)
		(width 0.1651)
		(layer "In7.Cu")
		(net "P5E_PEX1_STN4_TX_DN<68>")
	)
	(segment
		(start 210.110324 -317.909448)
		(end 208.46796 -316.260734)
		(width 0.1651)
		(layer "In7.Cu")
		(net "P5E_PEX1_STN4_TX_DN<68>")
	)
	(segment
		(start 210.9216 -319.896998)
		(end 210.110324 -317.909448)
		(width 0.1651)
		(layer "In7.Cu")
		(net "P5E_PEX1_STN4_TX_DN<68>")
	)
	(segment
		(start 210.072986 -323.827394)
		(end 210.9216 -321.77863)
		(width 0.1651)
		(layer "In7.Cu")
		(net "P5E_PEX1_STN4_TX_DN<68>")
	)
	(segment
		(start 186.478672 -341.079582)
		(end 187.400692 -340.157562)
		(width 0.1651)
		(layer "In7.Cu")
		(net "P5E_PEX1_STN4_TX_DN<68>")
	)
	(segment
		(start 200.732136 -308.734714)
		(end 200.367646 -308.583838)
		(width 0.1651)
		(layer "In7.Cu")
		(net "P5E_PEX1_STN4_TX_DN<68>")
	)
	(segment
		(start 199.774048 -308.583838)
		(end 199.7456 -308.583838)
		(width 0.1143)
		(layer "In7.Cu")
		(net "P5E_PEX1_STN4_TX_DN<68>")
	)
	(segment
		(start 198.911464 -331.620622)
		(end 209.063082 -324.837298)
		(width 0.1651)
		(layer "In7.Cu")
		(net "P5E_PEX1_STN4_TX_DN<68>")
	)
	(segment
		(start 184.521602 -353.766882)
		(end 186.076082 -352.212402)
		(width 0.1651)
		(layer "In7.Cu")
		(net "P5E_PEX1_STN4_TX_DN<68>")
	)
	(segment
		(start 184.521602 -354.417376)
		(end 184.521602 -353.766882)
		(width 0.1651)
		(layer "In7.Cu")
		(net "P5E_PEX1_STN4_TX_DN<68>")
	)
	(segment
		(start 208.46796 -316.260734)
		(end 208.071466 -316.095888)
		(width 0.1651)
		(layer "In7.Cu")
		(net "P5E_PEX1_STN4_TX_DN<68>")
	)
	(segment
		(start 199.69988 -308.629558)
		(end 191.634618 -308.629558)
		(width 0.1143)
		(layer "In7.Cu")
		(net "P5E_PEX1_STN4_TX_DN<68>")
	)
	(segment
		(start 210.9216 -321.77863)
		(end 210.9216 -319.896998)
		(width 0.1651)
		(layer "In7.Cu")
		(net "P5E_PEX1_STN4_TX_DN<68>")
	)
	(segment
		(start 186.076082 -342.051386)
		(end 186.478672 -341.079582)
		(width 0.1651)
		(layer "In7.Cu")
		(net "P5E_PEX1_STN4_TX_DN<68>")
	)
	(segment
		(start 208.071466 -316.095888)
		(end 200.732136 -308.734714)
		(width 0.1651)
		(layer "In7.Cu")
		(net "P5E_PEX1_STN4_TX_DN<68>")
	)
	(segment
		(start 209.063082 -324.837298)
		(end 210.072986 -323.827394)
		(width 0.1651)
		(layer "In7.Cu")
		(net "P5E_PEX1_STN4_TX_DN<68>")
	)
	(segment
		(start 191.520318 -308.515258)
		(end 191.520318 -308.364128)
		(width 0.1143)
		(layer "In7.Cu")
		(net "P5E_PEX1_STN4_TX_DN<68>")
	)
	(segment
		(start 199.7456 -308.583838)
		(end 199.69988 -308.629558)
		(width 0.1143)
		(layer "In7.Cu")
		(net "P5E_PEX1_STN4_TX_DN<68>")
	)
	(segment
		(start 191.634618 -308.629558)
		(end 191.520318 -308.515258)
		(width 0.1143)
		(layer "In7.Cu")
		(net "P5E_PEX1_STN4_TX_DN<68>")
	)
	(segment
		(start 184.812432 -354.708206)
		(end 184.521602 -354.417376)
		(width 0.1651)
		(layer "In7.Cu")
		(net "P5E_PEX1_STN4_TX_DN<68>")
	)
	(segment
		(start 187.400692 -340.157562)
		(end 198.911464 -331.620622)
		(width 0.1651)
		(layer "In7.Cu")
		(net "P5E_PEX1_STN4_TX_DN<68>")
	)
	(segment
		(start 191.520318 -308.364128)
		(end 191.634618 -308.249828)
		(width 0.1143)
		(layer "In7.Cu")
		(net "P5E_PEX1_STN4_TX_DN<68>")
	)
	(segment
		(start 191.634618 -308.249828)
		(end 191.900048 -308.249828)
		(width 0.1143)
		(layer "In7.Cu")
		(net "P5E_PEX1_STN4_TX_DN<68>")
	)
	(segment
		(start 200.367646 -308.583838)
		(end 199.774048 -308.583838)
		(width 0.1651)
		(layer "In7.Cu")
		(net "P5E_PEX1_STN4_TX_DN<68>")
	)
	(segment
		(start 187.626752 -349.511874)
		(end 187.626752 -348.88043)
		(width 0.13462)
		(layer "F.Cu")
		(net "P5E_PEX1_STN4_TX_DN<67>")
	)
	(segment
		(start 187.626752 -348.88043)
		(end 187.921392 -348.58579)
		(width 0.13462)
		(layer "F.Cu")
		(net "P5E_PEX1_STN4_TX_DN<67>")
	)
	(segment
		(start 187.946792 -349.831914)
		(end 187.626752 -349.511874)
		(width 0.13462)
		(layer "F.Cu")
		(net "P5E_PEX1_STN4_TX_DN<67>")
	)
	(segment
		(start 189.58814 -340.738714)
		(end 200.99401 -331.378052)
		(width 0.1651)
		(layer "In7.Cu")
		(net "P5E_PEX1_STN4_TX_DN<67>")
	)
	(segment
		(start 193.534538 -307.679598)
		(end 193.420238 -307.565298)
		(width 0.1143)
		(layer "In7.Cu")
		(net "P5E_PEX1_STN4_TX_DN<67>")
	)
	(segment
		(start 189.185042 -346.155518)
		(end 189.185042 -341.711534)
		(width 0.1651)
		(layer "In7.Cu")
		(net "P5E_PEX1_STN4_TX_DN<67>")
	)
	(segment
		(start 200.162414 -307.633878)
		(end 199.774048 -307.633878)
		(width 0.1651)
		(layer "In7.Cu")
		(net "P5E_PEX1_STN4_TX_DN<67>")
	)
	(segment
		(start 199.774048 -307.633878)
		(end 199.7456 -307.633878)
		(width 0.1143)
		(layer "In7.Cu")
		(net "P5E_PEX1_STN4_TX_DN<67>")
	)
	(segment
		(start 193.420238 -307.414168)
		(end 193.534538 -307.299868)
		(width 0.1143)
		(layer "In7.Cu")
		(net "P5E_PEX1_STN4_TX_DN<67>")
	)
	(segment
		(start 193.420238 -307.565298)
		(end 193.420238 -307.414168)
		(width 0.1143)
		(layer "In7.Cu")
		(net "P5E_PEX1_STN4_TX_DN<67>")
	)
	(segment
		(start 199.7456 -307.633878)
		(end 199.69988 -307.679598)
		(width 0.1143)
		(layer "In7.Cu")
		(net "P5E_PEX1_STN4_TX_DN<67>")
	)
	(segment
		(start 187.921392 -348.58579)
		(end 187.630562 -348.29496)
		(width 0.1651)
		(layer "In7.Cu")
		(net "P5E_PEX1_STN4_TX_DN<67>")
	)
	(segment
		(start 187.630562 -347.709998)
		(end 189.185042 -346.155518)
		(width 0.1651)
		(layer "In7.Cu")
		(net "P5E_PEX1_STN4_TX_DN<67>")
	)
	(segment
		(start 201.563478 -308.214014)
		(end 200.162414 -307.633878)
		(width 0.1651)
		(layer "In7.Cu")
		(net "P5E_PEX1_STN4_TX_DN<67>")
	)
	(segment
		(start 187.630562 -348.29496)
		(end 187.630562 -347.709998)
		(width 0.1651)
		(layer "In7.Cu")
		(net "P5E_PEX1_STN4_TX_DN<67>")
	)
	(segment
		(start 208.890362 -315.313314)
		(end 208.463642 -315.136022)
		(width 0.1651)
		(layer "In7.Cu")
		(net "P5E_PEX1_STN4_TX_DN<67>")
	)
	(segment
		(start 189.58814 -340.73846)
		(end 189.58814 -340.738714)
		(width 0.1651)
		(layer "In7.Cu")
		(net "P5E_PEX1_STN4_TX_DN<67>")
	)
	(segment
		(start 211.8868 -319.589404)
		(end 211.007706 -317.43777)
		(width 0.1651)
		(layer "In7.Cu")
		(net "P5E_PEX1_STN4_TX_DN<67>")
	)
	(segment
		(start 199.69988 -307.679598)
		(end 193.534538 -307.679598)
		(width 0.1143)
		(layer "In7.Cu")
		(net "P5E_PEX1_STN4_TX_DN<67>")
	)
	(segment
		(start 209.671412 -325.57974)
		(end 210.922362 -324.32879)
		(width 0.1651)
		(layer "In7.Cu")
		(net "P5E_PEX1_STN4_TX_DN<67>")
	)
	(segment
		(start 208.463642 -315.136022)
		(end 201.563478 -308.214014)
		(width 0.1651)
		(layer "In7.Cu")
		(net "P5E_PEX1_STN4_TX_DN<67>")
	)
	(segment
		(start 211.007706 -317.43777)
		(end 208.890362 -315.313314)
		(width 0.1651)
		(layer "In7.Cu")
		(net "P5E_PEX1_STN4_TX_DN<67>")
	)
	(segment
		(start 211.8868 -322.000626)
		(end 211.8868 -319.589404)
		(width 0.1651)
		(layer "In7.Cu")
		(net "P5E_PEX1_STN4_TX_DN<67>")
	)
	(segment
		(start 189.185042 -341.711534)
		(end 189.58814 -340.73846)
		(width 0.1651)
		(layer "In7.Cu")
		(net "P5E_PEX1_STN4_TX_DN<67>")
	)
	(segment
		(start 200.99401 -331.378052)
		(end 209.671412 -325.57974)
		(width 0.1651)
		(layer "In7.Cu")
		(net "P5E_PEX1_STN4_TX_DN<67>")
	)
	(segment
		(start 210.922362 -324.32879)
		(end 211.8868 -322.000626)
		(width 0.1651)
		(layer "In7.Cu")
		(net "P5E_PEX1_STN4_TX_DN<67>")
	)
	(segment
		(start 193.534538 -307.299868)
		(end 193.799968 -307.299868)
		(width 0.1143)
		(layer "In7.Cu")
		(net "P5E_PEX1_STN4_TX_DN<67>")
	)
	(segment
		(start 174.596552 -349.831914)
		(end 174.916592 -349.511874)
		(width 0.13462)
		(layer "F.Cu")
		(net "P5E_PEX1_STN4_TX_DP<73>")
	)
	(segment
		(start 174.916592 -348.88043)
		(end 174.621952 -348.58579)
		(width 0.13462)
		(layer "F.Cu")
		(net "P5E_PEX1_STN4_TX_DP<73>")
	)
	(segment
		(start 174.916592 -349.511874)
		(end 174.916592 -348.88043)
		(width 0.13462)
		(layer "F.Cu")
		(net "P5E_PEX1_STN4_TX_DP<73>")
	)
	(segment
		(start 195.355464 -311.479692)
		(end 195.585588 -311.479692)
		(width 0.1143)
		(layer "In7.Cu")
		(net "P5E_PEX1_STN4_TX_DP<73>")
	)
	(segment
		(start 185.609484 -333.201772)
		(end 193.89979 -324.911466)
		(width 0.1651)
		(layer "In7.Cu")
		(net "P5E_PEX1_STN4_TX_DP<73>")
	)
	(segment
		(start 174.621952 -348.58579)
		(end 174.912782 -348.29496)
		(width 0.1651)
		(layer "In7.Cu")
		(net "P5E_PEX1_STN4_TX_DP<73>")
	)
	(segment
		(start 195.129658 -319.942718)
		(end 195.129658 -311.705498)
		(width 0.1143)
		(layer "In7.Cu")
		(net "P5E_PEX1_STN4_TX_DP<73>")
	)
	(segment
		(start 195.083938 -320.016886)
		(end 195.083938 -319.988438)
		(width 0.1143)
		(layer "In7.Cu")
		(net "P5E_PEX1_STN4_TX_DP<73>")
	)
	(segment
		(start 193.89979 -324.911466)
		(end 195.083938 -322.05295)
		(width 0.1651)
		(layer "In7.Cu")
		(net "P5E_PEX1_STN4_TX_DP<73>")
	)
	(segment
		(start 195.585588 -311.479692)
		(end 195.699888 -311.365392)
		(width 0.1143)
		(layer "In7.Cu")
		(net "P5E_PEX1_STN4_TX_DP<73>")
	)
	(segment
		(start 174.912782 -348.29496)
		(end 174.912782 -347.593158)
		(width 0.1651)
		(layer "In7.Cu")
		(net "P5E_PEX1_STN4_TX_DP<73>")
	)
	(segment
		(start 181.267862 -336.10296)
		(end 185.609484 -333.201772)
		(width 0.1651)
		(layer "In7.Cu")
		(net "P5E_PEX1_STN4_TX_DP<73>")
	)
	(segment
		(start 176.467262 -346.038678)
		(end 176.467262 -340.90356)
		(width 0.1651)
		(layer "In7.Cu")
		(net "P5E_PEX1_STN4_TX_DP<73>")
	)
	(segment
		(start 195.083938 -322.05295)
		(end 195.083938 -320.016886)
		(width 0.1651)
		(layer "In7.Cu")
		(net "P5E_PEX1_STN4_TX_DP<73>")
	)
	(segment
		(start 195.699888 -311.365392)
		(end 195.699888 -311.099962)
		(width 0.1143)
		(layer "In7.Cu")
		(net "P5E_PEX1_STN4_TX_DP<73>")
	)
	(segment
		(start 195.083938 -319.988438)
		(end 195.129658 -319.942718)
		(width 0.1143)
		(layer "In7.Cu")
		(net "P5E_PEX1_STN4_TX_DP<73>")
	)
	(segment
		(start 174.912782 -347.593158)
		(end 176.467262 -346.038678)
		(width 0.1651)
		(layer "In7.Cu")
		(net "P5E_PEX1_STN4_TX_DP<73>")
	)
	(segment
		(start 176.467262 -340.90356)
		(end 181.267862 -336.10296)
		(width 0.1651)
		(layer "In7.Cu")
		(net "P5E_PEX1_STN4_TX_DP<73>")
	)
	(segment
		(start 195.129658 -311.705498)
		(end 195.355464 -311.479692)
		(width 0.1143)
		(layer "In7.Cu")
		(net "P5E_PEX1_STN4_TX_DP<73>")
	)
	(segment
		(start 165.864032 -355.658166)
		(end 165.864032 -355.026722)
		(width 0.13462)
		(layer "F.Cu")
		(net "P5E_PEX1_STN4_TX_DN<77>")
	)
	(segment
		(start 165.864032 -355.026722)
		(end 166.158672 -354.732082)
		(width 0.13462)
		(layer "F.Cu")
		(net "P5E_PEX1_STN4_TX_DN<77>")
	)
	(segment
		(start 166.184072 -355.978206)
		(end 165.864032 -355.658166)
		(width 0.13462)
		(layer "F.Cu")
		(net "P5E_PEX1_STN4_TX_DN<77>")
	)
	(segment
		(start 167.422322 -352.236278)
		(end 167.422322 -341.364824)
		(width 0.1651)
		(layer "In7.Cu")
		(net "P5E_PEX1_STN4_TX_DN<77>")
	)
	(segment
		(start 183.477916 -330.322428)
		(end 190.642494 -323.15785)
		(width 0.1651)
		(layer "In7.Cu")
		(net "P5E_PEX1_STN4_TX_DN<77>")
	)
	(segment
		(start 168.369488 -340.417658)
		(end 183.477916 -330.322428)
		(width 0.1651)
		(layer "In7.Cu")
		(net "P5E_PEX1_STN4_TX_DN<77>")
	)
	(segment
		(start 191.785748 -311.670192)
		(end 191.900048 -311.784492)
		(width 0.1143)
		(layer "In7.Cu")
		(net "P5E_PEX1_STN4_TX_DN<77>")
	)
	(segment
		(start 166.158672 -354.732082)
		(end 165.867842 -354.441252)
		(width 0.1651)
		(layer "In7.Cu")
		(net "P5E_PEX1_STN4_TX_DN<77>")
	)
	(segment
		(start 165.867842 -354.441252)
		(end 165.867842 -353.790758)
		(width 0.1651)
		(layer "In7.Cu")
		(net "P5E_PEX1_STN4_TX_DN<77>")
	)
	(segment
		(start 191.634618 -311.670192)
		(end 191.785748 -311.670192)
		(width 0.1143)
		(layer "In7.Cu")
		(net "P5E_PEX1_STN4_TX_DN<77>")
	)
	(segment
		(start 191.520318 -319.942718)
		(end 191.520318 -311.784492)
		(width 0.1143)
		(layer "In7.Cu")
		(net "P5E_PEX1_STN4_TX_DN<77>")
	)
	(segment
		(start 191.900048 -311.784492)
		(end 191.900048 -312.049922)
		(width 0.1143)
		(layer "In7.Cu")
		(net "P5E_PEX1_STN4_TX_DN<77>")
	)
	(segment
		(start 167.422322 -341.364824)
		(end 168.369488 -340.417658)
		(width 0.1651)
		(layer "In7.Cu")
		(net "P5E_PEX1_STN4_TX_DN<77>")
	)
	(segment
		(start 191.566038 -320.928238)
		(end 191.566038 -320.016886)
		(width 0.1651)
		(layer "In7.Cu")
		(net "P5E_PEX1_STN4_TX_DN<77>")
	)
	(segment
		(start 191.566038 -320.016886)
		(end 191.566038 -319.988438)
		(width 0.1143)
		(layer "In7.Cu")
		(net "P5E_PEX1_STN4_TX_DN<77>")
	)
	(segment
		(start 165.867842 -353.790758)
		(end 167.422322 -352.236278)
		(width 0.1651)
		(layer "In7.Cu")
		(net "P5E_PEX1_STN4_TX_DN<77>")
	)
	(segment
		(start 191.566038 -319.988438)
		(end 191.520318 -319.942718)
		(width 0.1143)
		(layer "In7.Cu")
		(net "P5E_PEX1_STN4_TX_DN<77>")
	)
	(segment
		(start 190.642494 -323.15785)
		(end 191.566038 -320.928238)
		(width 0.1651)
		(layer "In7.Cu")
		(net "P5E_PEX1_STN4_TX_DN<77>")
	)
	(segment
		(start 191.520318 -311.784492)
		(end 191.634618 -311.670192)
		(width 0.1143)
		(layer "In7.Cu")
		(net "P5E_PEX1_STN4_TX_DN<77>")
	)
	(segment
		(start 162.160712 -349.831914)
		(end 162.480752 -349.511874)
		(width 0.13462)
		(layer "F.Cu")
		(net "P5E_PEX1_STN4_TX_DP<79>")
	)
	(segment
		(start 162.480752 -348.88043)
		(end 162.186112 -348.58579)
		(width 0.13462)
		(layer "F.Cu")
		(net "P5E_PEX1_STN4_TX_DP<79>")
	)
	(segment
		(start 162.480752 -349.511874)
		(end 162.480752 -348.88043)
		(width 0.13462)
		(layer "F.Cu")
		(net "P5E_PEX1_STN4_TX_DP<79>")
	)
	(segment
		(start 182.08244 -328.61758)
		(end 188.671962 -322.028058)
		(width 0.1651)
		(layer "In7.Cu")
		(net "P5E_PEX1_STN4_TX_DP<79>")
	)
	(segment
		(start 189.383924 -320.309494)
		(end 189.383924 -320.016886)
		(width 0.1651)
		(layer "In7.Cu")
		(net "P5E_PEX1_STN4_TX_DP<79>")
	)
	(segment
		(start 163.764468 -340.857586)
		(end 182.08244 -328.61758)
		(width 0.1651)
		(layer "In7.Cu")
		(net "P5E_PEX1_STN4_TX_DP<79>")
	)
	(segment
		(start 162.476942 -342.145112)
		(end 163.764468 -340.857586)
		(width 0.1651)
		(layer "In7.Cu")
		(net "P5E_PEX1_STN4_TX_DP<79>")
	)
	(segment
		(start 189.429644 -311.705498)
		(end 189.65545 -311.479692)
		(width 0.1143)
		(layer "In7.Cu")
		(net "P5E_PEX1_STN4_TX_DP<79>")
	)
	(segment
		(start 162.186112 -348.58579)
		(end 162.476942 -348.29496)
		(width 0.1651)
		(layer "In7.Cu")
		(net "P5E_PEX1_STN4_TX_DP<79>")
	)
	(segment
		(start 189.429644 -319.942718)
		(end 189.429644 -311.705498)
		(width 0.1143)
		(layer "In7.Cu")
		(net "P5E_PEX1_STN4_TX_DP<79>")
	)
	(segment
		(start 189.383924 -320.016886)
		(end 189.383924 -319.988438)
		(width 0.1143)
		(layer "In7.Cu")
		(net "P5E_PEX1_STN4_TX_DP<79>")
	)
	(segment
		(start 188.671962 -322.028058)
		(end 189.383924 -320.309494)
		(width 0.1651)
		(layer "In7.Cu")
		(net "P5E_PEX1_STN4_TX_DP<79>")
	)
	(segment
		(start 162.476942 -348.29496)
		(end 162.476942 -342.145112)
		(width 0.1651)
		(layer "In7.Cu")
		(net "P5E_PEX1_STN4_TX_DP<79>")
	)
	(segment
		(start 189.65545 -311.479692)
		(end 189.885574 -311.479692)
		(width 0.1143)
		(layer "In7.Cu")
		(net "P5E_PEX1_STN4_TX_DP<79>")
	)
	(segment
		(start 189.885574 -311.479692)
		(end 189.999874 -311.365392)
		(width 0.1143)
		(layer "In7.Cu")
		(net "P5E_PEX1_STN4_TX_DP<79>")
	)
	(segment
		(start 189.999874 -311.365392)
		(end 189.999874 -311.099962)
		(width 0.1143)
		(layer "In7.Cu")
		(net "P5E_PEX1_STN4_TX_DP<79>")
	)
	(segment
		(start 189.383924 -319.988438)
		(end 189.429644 -319.942718)
		(width 0.1143)
		(layer "In7.Cu")
		(net "P5E_PEX1_STN4_TX_DP<79>")
	)
	(segment
		(start 183.923432 -355.95433)
		(end 184.243472 -355.63429)
		(width 0.13462)
		(layer "F.Cu")
		(net "P5E_PEX1_STN4_TX_DP<68>")
	)
	(segment
		(start 184.243472 -355.002846)
		(end 183.948832 -354.708206)
		(width 0.13462)
		(layer "F.Cu")
		(net "P5E_PEX1_STN4_TX_DP<68>")
	)
	(segment
		(start 184.243472 -355.63429)
		(end 184.243472 -355.002846)
		(width 0.13462)
		(layer "F.Cu")
		(net "P5E_PEX1_STN4_TX_DP<68>")
	)
	(segment
		(start 191.329818 -308.364128)
		(end 191.215518 -308.249828)
		(width 0.1143)
		(layer "In7.Cu")
		(net "P5E_PEX1_STN4_TX_DP<68>")
	)
	(segment
		(start 189.011814 -338.50072)
		(end 189.410086 -338.205572)
		(width 0.1651)
		(layer "In7.Cu")
		(net "P5E_PEX1_STN4_TX_DP<68>")
	)
	(segment
		(start 207.911192 -316.334902)
		(end 200.572116 -308.973982)
		(width 0.1651)
		(layer "In7.Cu")
		(net "P5E_PEX1_STN4_TX_DP<68>")
	)
	(segment
		(start 200.572116 -308.973982)
		(end 200.311512 -308.865778)
		(width 0.1651)
		(layer "In7.Cu")
		(net "P5E_PEX1_STN4_TX_DP<68>")
	)
	(segment
		(start 208.88325 -324.61835)
		(end 209.833972 -323.667628)
		(width 0.1651)
		(layer "In7.Cu")
		(net "P5E_PEX1_STN4_TX_DP<68>")
	)
	(segment
		(start 189.410086 -338.205572)
		(end 189.534292 -338.22386)
		(width 0.1651)
		(layer "In7.Cu")
		(net "P5E_PEX1_STN4_TX_DP<68>")
	)
	(segment
		(start 209.833972 -323.667628)
		(end 210.63966 -321.722496)
		(width 0.1651)
		(layer "In7.Cu")
		(net "P5E_PEX1_STN4_TX_DP<68>")
	)
	(segment
		(start 191.329818 -308.594252)
		(end 191.329818 -308.364128)
		(width 0.1143)
		(layer "In7.Cu")
		(net "P5E_PEX1_STN4_TX_DP<68>")
	)
	(segment
		(start 208.307686 -316.499748)
		(end 207.911192 -316.334902)
		(width 0.1651)
		(layer "In7.Cu")
		(net "P5E_PEX1_STN4_TX_DP<68>")
	)
	(segment
		(start 188.993526 -338.62518)
		(end 189.011814 -338.50072)
		(width 0.1651)
		(layer "In7.Cu")
		(net "P5E_PEX1_STN4_TX_DP<68>")
	)
	(segment
		(start 184.239662 -353.650042)
		(end 185.794142 -352.095562)
		(width 0.1651)
		(layer "In7.Cu")
		(net "P5E_PEX1_STN4_TX_DP<68>")
	)
	(segment
		(start 191.215518 -308.249828)
		(end 190.950088 -308.249828)
		(width 0.1143)
		(layer "In7.Cu")
		(net "P5E_PEX1_STN4_TX_DP<68>")
	)
	(segment
		(start 185.794142 -341.995252)
		(end 186.239658 -340.919816)
		(width 0.1651)
		(layer "In7.Cu")
		(net "P5E_PEX1_STN4_TX_DP<68>")
	)
	(segment
		(start 199.7456 -308.865778)
		(end 199.69988 -308.820058)
		(width 0.1143)
		(layer "In7.Cu")
		(net "P5E_PEX1_STN4_TX_DP<68>")
	)
	(segment
		(start 187.216034 -339.94344)
		(end 188.993526 -338.62518)
		(width 0.1651)
		(layer "In7.Cu")
		(net "P5E_PEX1_STN4_TX_DP<68>")
	)
	(segment
		(start 186.239658 -340.919816)
		(end 187.216034 -339.94344)
		(width 0.1651)
		(layer "In7.Cu")
		(net "P5E_PEX1_STN4_TX_DP<68>")
	)
	(segment
		(start 200.311512 -308.865778)
		(end 199.774048 -308.865778)
		(width 0.1651)
		(layer "In7.Cu")
		(net "P5E_PEX1_STN4_TX_DP<68>")
	)
	(segment
		(start 210.63966 -319.95237)
		(end 209.870548 -318.068452)
		(width 0.1651)
		(layer "In7.Cu")
		(net "P5E_PEX1_STN4_TX_DP<68>")
	)
	(segment
		(start 184.239662 -354.417376)
		(end 184.239662 -353.650042)
		(width 0.1651)
		(layer "In7.Cu")
		(net "P5E_PEX1_STN4_TX_DP<68>")
	)
	(segment
		(start 210.63966 -321.722496)
		(end 210.63966 -319.95237)
		(width 0.1651)
		(layer "In7.Cu")
		(net "P5E_PEX1_STN4_TX_DP<68>")
	)
	(segment
		(start 209.870548 -318.068452)
		(end 208.307686 -316.499748)
		(width 0.1651)
		(layer "In7.Cu")
		(net "P5E_PEX1_STN4_TX_DP<68>")
	)
	(segment
		(start 199.69988 -308.820058)
		(end 191.555624 -308.820058)
		(width 0.1143)
		(layer "In7.Cu")
		(net "P5E_PEX1_STN4_TX_DP<68>")
	)
	(segment
		(start 185.794142 -352.095562)
		(end 185.794142 -341.995252)
		(width 0.1651)
		(layer "In7.Cu")
		(net "P5E_PEX1_STN4_TX_DP<68>")
	)
	(segment
		(start 183.948832 -354.708206)
		(end 184.239662 -354.417376)
		(width 0.1651)
		(layer "In7.Cu")
		(net "P5E_PEX1_STN4_TX_DP<68>")
	)
	(segment
		(start 191.555624 -308.820058)
		(end 191.329818 -308.594252)
		(width 0.1143)
		(layer "In7.Cu")
		(net "P5E_PEX1_STN4_TX_DP<68>")
	)
	(segment
		(start 199.774048 -308.865778)
		(end 199.7456 -308.865778)
		(width 0.1143)
		(layer "In7.Cu")
		(net "P5E_PEX1_STN4_TX_DP<68>")
	)
	(segment
		(start 189.534292 -338.22386)
		(end 198.748904 -331.389736)
		(width 0.1651)
		(layer "In7.Cu")
		(net "P5E_PEX1_STN4_TX_DP<68>")
	)
	(segment
		(start 198.748904 -331.389736)
		(end 208.88325 -324.61835)
		(width 0.1651)
		(layer "In7.Cu")
		(net "P5E_PEX1_STN4_TX_DP<68>")
	)
	(segment
		(start 184.517792 -342.734138)
		(end 184.812432 -342.439498)
		(width 0.13462)
		(layer "F.Cu")
		(net "P5E_PEX1_STN4_TX_DN<69>")
	)
	(segment
		(start 184.837832 -343.685622)
		(end 184.517792 -343.365582)
		(width 0.13462)
		(layer "F.Cu")
		(net "P5E_PEX1_STN4_TX_DN<69>")
	)
	(segment
		(start 184.517792 -343.365582)
		(end 184.517792 -342.734138)
		(width 0.13462)
		(layer "F.Cu")
		(net "P5E_PEX1_STN4_TX_DN<69>")
	)
	(segment
		(start 198.502524 -326.266048)
		(end 200.829164 -320.650108)
		(width 0.1651)
		(layer "In7.Cu")
		(net "P5E_PEX1_STN4_TX_DN<69>")
	)
	(segment
		(start 199.69988 -309.579518)
		(end 193.534538 -309.579518)
		(width 0.1143)
		(layer "In7.Cu")
		(net "P5E_PEX1_STN4_TX_DN<69>")
	)
	(segment
		(start 193.534538 -309.199788)
		(end 193.799968 -309.199788)
		(width 0.1143)
		(layer "In7.Cu")
		(net "P5E_PEX1_STN4_TX_DN<69>")
	)
	(segment
		(start 201.669396 -316.439042)
		(end 201.669396 -313.185048)
		(width 0.1651)
		(layer "In7.Cu")
		(net "P5E_PEX1_STN4_TX_DN<69>")
	)
	(segment
		(start 184.521602 -340.24697)
		(end 198.502524 -326.266048)
		(width 0.1651)
		(layer "In7.Cu")
		(net "P5E_PEX1_STN4_TX_DN<69>")
	)
	(segment
		(start 201.669396 -313.185048)
		(end 200.243694 -309.743348)
		(width 0.1651)
		(layer "In7.Cu")
		(net "P5E_PEX1_STN4_TX_DN<69>")
	)
	(segment
		(start 193.420238 -309.465218)
		(end 193.420238 -309.314088)
		(width 0.1143)
		(layer "In7.Cu")
		(net "P5E_PEX1_STN4_TX_DN<69>")
	)
	(segment
		(start 200.034144 -309.533798)
		(end 199.774048 -309.533798)
		(width 0.1651)
		(layer "In7.Cu")
		(net "P5E_PEX1_STN4_TX_DN<69>")
	)
	(segment
		(start 200.243694 -309.743348)
		(end 200.034144 -309.533798)
		(width 0.1651)
		(layer "In7.Cu")
		(net "P5E_PEX1_STN4_TX_DN<69>")
	)
	(segment
		(start 184.812432 -342.439498)
		(end 184.521602 -342.148668)
		(width 0.1651)
		(layer "In7.Cu")
		(net "P5E_PEX1_STN4_TX_DN<69>")
	)
	(segment
		(start 193.420238 -309.314088)
		(end 193.534538 -309.199788)
		(width 0.1143)
		(layer "In7.Cu")
		(net "P5E_PEX1_STN4_TX_DN<69>")
	)
	(segment
		(start 200.829164 -320.650108)
		(end 201.669396 -316.439042)
		(width 0.1651)
		(layer "In7.Cu")
		(net "P5E_PEX1_STN4_TX_DN<69>")
	)
	(segment
		(start 184.521602 -342.148668)
		(end 184.521602 -340.24697)
		(width 0.1651)
		(layer "In7.Cu")
		(net "P5E_PEX1_STN4_TX_DN<69>")
	)
	(segment
		(start 199.774048 -309.533798)
		(end 199.7456 -309.533798)
		(width 0.1143)
		(layer "In7.Cu")
		(net "P5E_PEX1_STN4_TX_DN<69>")
	)
	(segment
		(start 193.534538 -309.579518)
		(end 193.420238 -309.465218)
		(width 0.1143)
		(layer "In7.Cu")
		(net "P5E_PEX1_STN4_TX_DN<69>")
	)
	(segment
		(start 199.7456 -309.533798)
		(end 199.69988 -309.579518)
		(width 0.1143)
		(layer "In7.Cu")
		(net "P5E_PEX1_STN4_TX_DN<69>")
	)
	(segment
		(start 181.728872 -349.831914)
		(end 181.408832 -349.511874)
		(width 0.13462)
		(layer "F.Cu")
		(net "P5E_PEX1_STN4_TX_DN<70>")
	)
	(segment
		(start 181.408832 -348.88043)
		(end 181.703472 -348.58579)
		(width 0.13462)
		(layer "F.Cu")
		(net "P5E_PEX1_STN4_TX_DN<70>")
	)
	(segment
		(start 181.408832 -349.511874)
		(end 181.408832 -348.88043)
		(width 0.13462)
		(layer "F.Cu")
		(net "P5E_PEX1_STN4_TX_DN<70>")
	)
	(segment
		(start 199.284082 -312.796682)
		(end 199.264016 -312.776616)
		(width 0.1143)
		(layer "In7.Cu")
		(net "P5E_PEX1_STN4_TX_DN<70>")
	)
	(segment
		(start 198.170292 -312.315352)
		(end 198.170292 -312.164222)
		(width 0.1143)
		(layer "In7.Cu")
		(net "P5E_PEX1_STN4_TX_DN<70>")
	)
	(segment
		(start 199.943212 -313.455812)
		(end 199.284082 -312.796682)
		(width 0.1651)
		(layer "In7.Cu")
		(net "P5E_PEX1_STN4_TX_DN<70>")
	)
	(segment
		(start 200.35774 -317.871348)
		(end 200.35774 -314.487052)
		(width 0.1651)
		(layer "In7.Cu")
		(net "P5E_PEX1_STN4_TX_DN<70>")
	)
	(segment
		(start 181.412642 -347.709998)
		(end 182.967122 -346.155518)
		(width 0.1651)
		(layer "In7.Cu")
		(net "P5E_PEX1_STN4_TX_DN<70>")
	)
	(segment
		(start 198.284592 -312.049922)
		(end 198.550022 -312.049922)
		(width 0.1143)
		(layer "In7.Cu")
		(net "P5E_PEX1_STN4_TX_DN<70>")
	)
	(segment
		(start 198.284592 -312.429652)
		(end 198.170292 -312.315352)
		(width 0.1143)
		(layer "In7.Cu")
		(net "P5E_PEX1_STN4_TX_DN<70>")
	)
	(segment
		(start 199.93356 -320.165222)
		(end 200.35774 -317.871348)
		(width 0.1651)
		(layer "In7.Cu")
		(net "P5E_PEX1_STN4_TX_DN<70>")
	)
	(segment
		(start 181.412642 -348.29496)
		(end 181.412642 -347.709998)
		(width 0.1651)
		(layer "In7.Cu")
		(net "P5E_PEX1_STN4_TX_DN<70>")
	)
	(segment
		(start 198.85279 -312.429652)
		(end 198.284592 -312.429652)
		(width 0.1143)
		(layer "In7.Cu")
		(net "P5E_PEX1_STN4_TX_DN<70>")
	)
	(segment
		(start 199.199754 -312.776616)
		(end 198.85279 -312.429652)
		(width 0.1143)
		(layer "In7.Cu")
		(net "P5E_PEX1_STN4_TX_DN<70>")
	)
	(segment
		(start 181.703472 -348.58579)
		(end 181.412642 -348.29496)
		(width 0.1651)
		(layer "In7.Cu")
		(net "P5E_PEX1_STN4_TX_DN<70>")
	)
	(segment
		(start 199.264016 -312.776616)
		(end 199.199754 -312.776616)
		(width 0.1143)
		(layer "In7.Cu")
		(net "P5E_PEX1_STN4_TX_DN<70>")
	)
	(segment
		(start 182.967122 -346.155518)
		(end 182.967122 -340.450678)
		(width 0.1651)
		(layer "In7.Cu")
		(net "P5E_PEX1_STN4_TX_DN<70>")
	)
	(segment
		(start 200.35774 -314.487052)
		(end 199.943212 -313.486292)
		(width 0.1651)
		(layer "In7.Cu")
		(net "P5E_PEX1_STN4_TX_DN<70>")
	)
	(segment
		(start 198.170292 -312.164222)
		(end 198.284592 -312.049922)
		(width 0.1143)
		(layer "In7.Cu")
		(net "P5E_PEX1_STN4_TX_DN<70>")
	)
	(segment
		(start 199.943212 -313.486292)
		(end 199.943212 -313.455812)
		(width 0.1651)
		(layer "In7.Cu")
		(net "P5E_PEX1_STN4_TX_DN<70>")
	)
	(segment
		(start 197.585584 -325.832216)
		(end 199.93356 -320.165222)
		(width 0.1651)
		(layer "In7.Cu")
		(net "P5E_PEX1_STN4_TX_DN<70>")
	)
	(segment
		(start 182.967122 -340.450678)
		(end 197.585584 -325.832216)
		(width 0.1651)
		(layer "In7.Cu")
		(net "P5E_PEX1_STN4_TX_DN<70>")
	)
	(segment
		(start 193.844672 -348.88043)
		(end 194.139312 -348.58579)
		(width 0.13462)
		(layer "F.Cu")
		(net "P5E_PEX1_STN4_TX_DN<65>")
	)
	(segment
		(start 194.164712 -349.831914)
		(end 193.844672 -349.511874)
		(width 0.13462)
		(layer "F.Cu")
		(net "P5E_PEX1_STN4_TX_DN<65>")
	)
	(segment
		(start 193.844672 -349.511874)
		(end 193.844672 -348.88043)
		(width 0.13462)
		(layer "F.Cu")
		(net "P5E_PEX1_STN4_TX_DN<65>")
	)
	(segment
		(start 212.162644 -315.206634)
		(end 204.120496 -307.1749)
		(width 0.1651)
		(layer "In7.Cu")
		(net "P5E_PEX1_STN4_TX_DN<65>")
	)
	(segment
		(start 193.420238 -305.665378)
		(end 193.420238 -305.514248)
		(width 0.1143)
		(layer "In7.Cu")
		(net "P5E_PEX1_STN4_TX_DN<65>")
	)
	(segment
		(start 204.120496 -307.1749)
		(end 200.637902 -305.733958)
		(width 0.1651)
		(layer "In7.Cu")
		(net "P5E_PEX1_STN4_TX_DN<65>")
	)
	(segment
		(start 195.402962 -346.155518)
		(end 195.402962 -341.248492)
		(width 0.1651)
		(layer "In7.Cu")
		(net "P5E_PEX1_STN4_TX_DN<65>")
	)
	(segment
		(start 212.559392 -325.393304)
		(end 213.96452 -322.001388)
		(width 0.1651)
		(layer "In7.Cu")
		(net "P5E_PEX1_STN4_TX_DN<65>")
	)
	(segment
		(start 199.799448 -305.733958)
		(end 199.771 -305.733958)
		(width 0.1143)
		(layer "In7.Cu")
		(net "P5E_PEX1_STN4_TX_DN<65>")
	)
	(segment
		(start 199.771 -305.733958)
		(end 199.72528 -305.779678)
		(width 0.1143)
		(layer "In7.Cu")
		(net "P5E_PEX1_STN4_TX_DN<65>")
	)
	(segment
		(start 193.420238 -305.514248)
		(end 193.534538 -305.399948)
		(width 0.1143)
		(layer "In7.Cu")
		(net "P5E_PEX1_STN4_TX_DN<65>")
	)
	(segment
		(start 193.848482 -348.29496)
		(end 193.848482 -347.709998)
		(width 0.1651)
		(layer "In7.Cu")
		(net "P5E_PEX1_STN4_TX_DN<65>")
	)
	(segment
		(start 199.72528 -305.779678)
		(end 193.534538 -305.779678)
		(width 0.1143)
		(layer "In7.Cu")
		(net "P5E_PEX1_STN4_TX_DN<65>")
	)
	(segment
		(start 213.96452 -319.61963)
		(end 212.162644 -315.206634)
		(width 0.1651)
		(layer "In7.Cu")
		(net "P5E_PEX1_STN4_TX_DN<65>")
	)
	(segment
		(start 195.402962 -341.248492)
		(end 196.642482 -338.256118)
		(width 0.1651)
		(layer "In7.Cu")
		(net "P5E_PEX1_STN4_TX_DN<65>")
	)
	(segment
		(start 193.848482 -347.709998)
		(end 195.402962 -346.155518)
		(width 0.1651)
		(layer "In7.Cu")
		(net "P5E_PEX1_STN4_TX_DN<65>")
	)
	(segment
		(start 196.642482 -338.256118)
		(end 201.278998 -333.619602)
		(width 0.1651)
		(layer "In7.Cu")
		(net "P5E_PEX1_STN4_TX_DN<65>")
	)
	(segment
		(start 210.48345 -327.469246)
		(end 212.559392 -325.393304)
		(width 0.1651)
		(layer "In7.Cu")
		(net "P5E_PEX1_STN4_TX_DN<65>")
	)
	(segment
		(start 193.534538 -305.779678)
		(end 193.420238 -305.665378)
		(width 0.1143)
		(layer "In7.Cu")
		(net "P5E_PEX1_STN4_TX_DN<65>")
	)
	(segment
		(start 194.139312 -348.58579)
		(end 193.848482 -348.29496)
		(width 0.1651)
		(layer "In7.Cu")
		(net "P5E_PEX1_STN4_TX_DN<65>")
	)
	(segment
		(start 201.278998 -333.619602)
		(end 210.48345 -327.469246)
		(width 0.1651)
		(layer "In7.Cu")
		(net "P5E_PEX1_STN4_TX_DN<65>")
	)
	(segment
		(start 200.637902 -305.733958)
		(end 199.799448 -305.733958)
		(width 0.1651)
		(layer "In7.Cu")
		(net "P5E_PEX1_STN4_TX_DN<65>")
	)
	(segment
		(start 213.96452 -322.001388)
		(end 213.96452 -319.61963)
		(width 0.1651)
		(layer "In7.Cu")
		(net "P5E_PEX1_STN4_TX_DN<65>")
	)
	(segment
		(start 193.534538 -305.399948)
		(end 193.799968 -305.399948)
		(width 0.1143)
		(layer "In7.Cu")
		(net "P5E_PEX1_STN4_TX_DN<65>")
	)
	(segment
		(start 175.510952 -349.831914)
		(end 175.190912 -349.511874)
		(width 0.13462)
		(layer "F.Cu")
		(net "P5E_PEX1_STN4_TX_DN<73>")
	)
	(segment
		(start 175.190912 -348.88043)
		(end 175.485552 -348.58579)
		(width 0.13462)
		(layer "F.Cu")
		(net "P5E_PEX1_STN4_TX_DN<73>")
	)
	(segment
		(start 175.190912 -349.511874)
		(end 175.190912 -348.88043)
		(width 0.13462)
		(layer "F.Cu")
		(net "P5E_PEX1_STN4_TX_DN<73>")
	)
	(segment
		(start 175.194722 -347.709998)
		(end 176.749202 -346.155518)
		(width 0.1651)
		(layer "In7.Cu")
		(net "P5E_PEX1_STN4_TX_DN<73>")
	)
	(segment
		(start 185.789316 -333.42072)
		(end 194.138804 -325.071232)
		(width 0.1651)
		(layer "In7.Cu")
		(net "P5E_PEX1_STN4_TX_DN<73>")
	)
	(segment
		(start 195.320158 -311.784492)
		(end 195.434458 -311.670192)
		(width 0.1143)
		(layer "In7.Cu")
		(net "P5E_PEX1_STN4_TX_DN<73>")
	)
	(segment
		(start 195.585588 -311.670192)
		(end 195.699888 -311.784492)
		(width 0.1143)
		(layer "In7.Cu")
		(net "P5E_PEX1_STN4_TX_DN<73>")
	)
	(segment
		(start 176.749202 -346.155518)
		(end 176.749202 -341.0204)
		(width 0.1651)
		(layer "In7.Cu")
		(net "P5E_PEX1_STN4_TX_DN<73>")
	)
	(segment
		(start 175.485552 -348.58579)
		(end 175.194722 -348.29496)
		(width 0.1651)
		(layer "In7.Cu")
		(net "P5E_PEX1_STN4_TX_DN<73>")
	)
	(segment
		(start 175.194722 -348.29496)
		(end 175.194722 -347.709998)
		(width 0.1651)
		(layer "In7.Cu")
		(net "P5E_PEX1_STN4_TX_DN<73>")
	)
	(segment
		(start 194.138804 -325.071232)
		(end 195.365878 -322.109084)
		(width 0.1651)
		(layer "In7.Cu")
		(net "P5E_PEX1_STN4_TX_DN<73>")
	)
	(segment
		(start 195.365878 -320.016886)
		(end 195.365878 -319.988438)
		(width 0.1143)
		(layer "In7.Cu")
		(net "P5E_PEX1_STN4_TX_DN<73>")
	)
	(segment
		(start 195.365878 -319.988438)
		(end 195.320158 -319.942718)
		(width 0.1143)
		(layer "In7.Cu")
		(net "P5E_PEX1_STN4_TX_DN<73>")
	)
	(segment
		(start 195.699888 -311.784492)
		(end 195.699888 -312.049922)
		(width 0.1143)
		(layer "In7.Cu")
		(net "P5E_PEX1_STN4_TX_DN<73>")
	)
	(segment
		(start 181.447694 -336.321908)
		(end 185.789316 -333.42072)
		(width 0.1651)
		(layer "In7.Cu")
		(net "P5E_PEX1_STN4_TX_DN<73>")
	)
	(segment
		(start 195.320158 -319.942718)
		(end 195.320158 -311.784492)
		(width 0.1143)
		(layer "In7.Cu")
		(net "P5E_PEX1_STN4_TX_DN<73>")
	)
	(segment
		(start 195.365878 -322.109084)
		(end 195.365878 -320.016886)
		(width 0.1651)
		(layer "In7.Cu")
		(net "P5E_PEX1_STN4_TX_DN<73>")
	)
	(segment
		(start 176.749202 -341.0204)
		(end 181.447694 -336.321908)
		(width 0.1651)
		(layer "In7.Cu")
		(net "P5E_PEX1_STN4_TX_DN<73>")
	)
	(segment
		(start 195.434458 -311.670192)
		(end 195.585588 -311.670192)
		(width 0.1143)
		(layer "In7.Cu")
		(net "P5E_PEX1_STN4_TX_DN<73>")
	)
	(via
		(at 138.92276 -221.332806)
		(size 0.508)
		(drill 0.254)
		(layers "F.Cu" "B.Cu")
		(net "SPI_PEX1_SDIO3_R")
	)
	(via
		(at 156.879036 -266.517882)
		(size 0.508)
		(drill 0.254)
		(layers "F.Cu" "B.Cu")
		(net "SPI_PEX1_SDIO3_R")
	)
	(segment
		(start 154.76855 -287.343342)
		(end 154.76855 -269.152116)
		(width 0.13208)
		(layer "B.Cu")
		(net "SPI_PEX1_SDIO3_R")
	)
	(segment
		(start 154.76855 -269.152116)
		(end 156.091382 -267.829284)
		(width 0.13208)
		(layer "B.Cu")
		(net "SPI_PEX1_SDIO3_R")
	)
	(segment
		(start 156.091382 -267.829284)
		(end 156.091382 -267.305536)
		(width 0.13208)
		(layer "B.Cu")
		(net "SPI_PEX1_SDIO3_R")
	)
	(segment
		(start 155.800044 -288.374836)
		(end 154.76855 -287.343342)
		(width 0.13208)
		(layer "B.Cu")
		(net "SPI_PEX1_SDIO3_R")
	)
	(segment
		(start 138.92276 -221.332806)
		(end 140.183108 -221.332806)
		(width 0.13208)
		(layer "B.Cu")
		(net "SPI_PEX1_SDIO3_R")
	)
	(segment
		(start 156.091382 -267.305536)
		(end 156.879036 -266.517882)
		(width 0.13208)
		(layer "B.Cu")
		(net "SPI_PEX1_SDIO3_R")
	)
	(segment
		(start 140.78966 -255.393444)
		(end 140.372338 -254.976122)
		(width 0.15494)
		(layer "In5.Cu")
		(net "SPI_PEX1_SDIO3_R")
	)
	(segment
		(start 159.016954 -268.076172)
		(end 159.016954 -269.155418)
		(width 0.15494)
		(layer "In5.Cu")
		(net "SPI_PEX1_SDIO3_R")
	)
	(segment
		(start 156.041852 -263.981692)
		(end 154.079956 -262.019796)
		(width 0.15494)
		(layer "In5.Cu")
		(net "SPI_PEX1_SDIO3_R")
	)
	(segment
		(start 159.016954 -269.155418)
		(end 158.723076 -269.449296)
		(width 0.15494)
		(layer "In5.Cu")
		(net "SPI_PEX1_SDIO3_R")
	)
	(segment
		(start 156.21889 -269.449296)
		(end 156.041852 -269.272258)
		(width 0.15494)
		(layer "In5.Cu")
		(net "SPI_PEX1_SDIO3_R")
	)
	(segment
		(start 156.041852 -269.272258)
		(end 156.041852 -268.993874)
		(width 0.15494)
		(layer "In5.Cu")
		(net "SPI_PEX1_SDIO3_R")
	)
	(segment
		(start 145.50644 -260.454648)
		(end 144.436084 -259.384292)
		(width 0.15494)
		(layer "In5.Cu")
		(net "SPI_PEX1_SDIO3_R")
	)
	(segment
		(start 156.041852 -268.993874)
		(end 155.914852 -268.866874)
		(width 0.15494)
		(layer "In5.Cu")
		(net "SPI_PEX1_SDIO3_R")
	)
	(segment
		(start 140.530326 -223.400874)
		(end 140.530326 -222.426784)
		(width 0.15494)
		(layer "In5.Cu")
		(net "SPI_PEX1_SDIO3_R")
	)
	(segment
		(start 140.61186 -241.50828)
		(end 140.61186 -232.887774)
		(width 0.15494)
		(layer "In5.Cu")
		(net "SPI_PEX1_SDIO3_R")
	)
	(segment
		(start 139.549886 -254.976122)
		(end 138.889232 -254.315468)
		(width 0.15494)
		(layer "In5.Cu")
		(net "SPI_PEX1_SDIO3_R")
	)
	(segment
		(start 144.436084 -259.384292)
		(end 143.161512 -259.384292)
		(width 0.15494)
		(layer "In5.Cu")
		(net "SPI_PEX1_SDIO3_R")
	)
	(segment
		(start 158.723076 -269.449296)
		(end 156.21889 -269.449296)
		(width 0.15494)
		(layer "In5.Cu")
		(net "SPI_PEX1_SDIO3_R")
	)
	(segment
		(start 140.61186 -232.887774)
		(end 143.330168 -230.169466)
		(width 0.15494)
		(layer "In5.Cu")
		(net "SPI_PEX1_SDIO3_R")
	)
	(segment
		(start 154.079956 -262.019796)
		(end 149.842982 -262.019796)
		(width 0.15494)
		(layer "In5.Cu")
		(net "SPI_PEX1_SDIO3_R")
	)
	(segment
		(start 140.78966 -257.01244)
		(end 140.78966 -255.393444)
		(width 0.15494)
		(layer "In5.Cu")
		(net "SPI_PEX1_SDIO3_R")
	)
	(segment
		(start 155.16733 -268.1224)
		(end 155.478988 -268.1224)
		(width 0.15494)
		(layer "In5.Cu")
		(net "SPI_PEX1_SDIO3_R")
	)
	(segment
		(start 155.478988 -268.1224)
		(end 156.041852 -267.559536)
		(width 0.15494)
		(layer "In5.Cu")
		(net "SPI_PEX1_SDIO3_R")
	)
	(segment
		(start 138.889232 -243.230908)
		(end 140.61186 -241.50828)
		(width 0.15494)
		(layer "In5.Cu")
		(net "SPI_PEX1_SDIO3_R")
	)
	(segment
		(start 156.879036 -266.517882)
		(end 156.879036 -267.412216)
		(width 0.15494)
		(layer "In5.Cu")
		(net "SPI_PEX1_SDIO3_R")
	)
	(segment
		(start 154.916124 -268.739874)
		(end 154.916124 -268.373606)
		(width 0.15494)
		(layer "In5.Cu")
		(net "SPI_PEX1_SDIO3_R")
	)
	(segment
		(start 138.889232 -254.315468)
		(end 138.889232 -243.230908)
		(width 0.15494)
		(layer "In5.Cu")
		(net "SPI_PEX1_SDIO3_R")
	)
	(segment
		(start 156.041852 -267.559536)
		(end 156.041852 -263.981692)
		(width 0.15494)
		(layer "In5.Cu")
		(net "SPI_PEX1_SDIO3_R")
	)
	(segment
		(start 144.046448 -226.916996)
		(end 140.530326 -223.400874)
		(width 0.15494)
		(layer "In5.Cu")
		(net "SPI_PEX1_SDIO3_R")
	)
	(segment
		(start 148.277834 -260.454648)
		(end 145.50644 -260.454648)
		(width 0.15494)
		(layer "In5.Cu")
		(net "SPI_PEX1_SDIO3_R")
	)
	(segment
		(start 155.914852 -268.866874)
		(end 155.043124 -268.866874)
		(width 0.15494)
		(layer "In5.Cu")
		(net "SPI_PEX1_SDIO3_R")
	)
	(segment
		(start 158.456884 -267.516102)
		(end 159.016954 -268.076172)
		(width 0.15494)
		(layer "In5.Cu")
		(net "SPI_PEX1_SDIO3_R")
	)
	(segment
		(start 140.372338 -254.976122)
		(end 139.549886 -254.976122)
		(width 0.15494)
		(layer "In5.Cu")
		(net "SPI_PEX1_SDIO3_R")
	)
	(segment
		(start 154.916124 -268.373606)
		(end 155.16733 -268.1224)
		(width 0.15494)
		(layer "In5.Cu")
		(net "SPI_PEX1_SDIO3_R")
	)
	(segment
		(start 140.530326 -222.426784)
		(end 139.436348 -221.332806)
		(width 0.15494)
		(layer "In5.Cu")
		(net "SPI_PEX1_SDIO3_R")
	)
	(segment
		(start 149.842982 -262.019796)
		(end 148.277834 -260.454648)
		(width 0.15494)
		(layer "In5.Cu")
		(net "SPI_PEX1_SDIO3_R")
	)
	(segment
		(start 139.436348 -221.332806)
		(end 138.92276 -221.332806)
		(width 0.15494)
		(layer "In5.Cu")
		(net "SPI_PEX1_SDIO3_R")
	)
	(segment
		(start 156.982922 -267.516102)
		(end 158.456884 -267.516102)
		(width 0.15494)
		(layer "In5.Cu")
		(net "SPI_PEX1_SDIO3_R")
	)
	(segment
		(start 144.046448 -227.526596)
		(end 144.046448 -226.916996)
		(width 0.15494)
		(layer "In5.Cu")
		(net "SPI_PEX1_SDIO3_R")
	)
	(segment
		(start 143.161512 -259.384292)
		(end 140.78966 -257.01244)
		(width 0.15494)
		(layer "In5.Cu")
		(net "SPI_PEX1_SDIO3_R")
	)
	(segment
		(start 156.879036 -267.412216)
		(end 156.982922 -267.516102)
		(width 0.15494)
		(layer "In5.Cu")
		(net "SPI_PEX1_SDIO3_R")
	)
	(segment
		(start 155.043124 -268.866874)
		(end 154.916124 -268.739874)
		(width 0.15494)
		(layer "In5.Cu")
		(net "SPI_PEX1_SDIO3_R")
	)
	(segment
		(start 143.330168 -230.169466)
		(end 143.330168 -228.242876)
		(width 0.15494)
		(layer "In5.Cu")
		(net "SPI_PEX1_SDIO3_R")
	)
	(segment
		(start 143.330168 -228.242876)
		(end 144.046448 -227.526596)
		(width 0.15494)
		(layer "In5.Cu")
		(net "SPI_PEX1_SDIO3_R")
	)
	(via
		(at 137.922254 -222.214186)
		(size 0.6604)
		(drill 0.3302)
		(layers "F.Cu" "B.Cu")
		(net "SPI_PEX1_SDIO0_MUX")
	)
	(segment
		(start 136.13892 -222.214186)
		(end 137.922254 -222.214186)
		(width 0.13208)
		(layer "B.Cu")
		(net "SPI_PEX1_SDIO0_MUX")
	)
	(segment
		(start 138.040872 -223.692212)
		(end 138.040872 -224.341182)
		(width 0.13208)
		(layer "B.Cu")
		(net "SPI_PEX1_SDIO0_MUX")
	)
	(segment
		(start 138.266932 -222.558864)
		(end 138.266932 -223.466152)
		(width 0.13208)
		(layer "B.Cu")
		(net "SPI_PEX1_SDIO0_MUX")
	)
	(segment
		(start 137.922254 -222.214186)
		(end 138.266932 -222.558864)
		(width 0.13208)
		(layer "B.Cu")
		(net "SPI_PEX1_SDIO0_MUX")
	)
	(segment
		(start 138.266932 -223.466152)
		(end 138.040872 -223.692212)
		(width 0.13208)
		(layer "B.Cu")
		(net "SPI_PEX1_SDIO0_MUX")
	)
	(via
		(at 131.075176 -223.561148)
		(size 0.6604)
		(drill 0.3302)
		(layers "F.Cu" "B.Cu")
		(net "SPI_PEX1_CLK_MUX")
	)
	(segment
		(start 131.075176 -223.561148)
		(end 131.075176 -225.360484)
		(width 0.13208)
		(layer "B.Cu")
		(net "SPI_PEX1_CLK_MUX")
	)
	(segment
		(start 134.019036 -227.211382)
		(end 136.863328 -227.211382)
		(width 0.13208)
		(layer "B.Cu")
		(net "SPI_PEX1_CLK_MUX")
	)
	(segment
		(start 137.405872 -227.753926)
		(end 137.405872 -229.827582)
		(width 0.13208)
		(layer "B.Cu")
		(net "SPI_PEX1_CLK_MUX")
	)
	(segment
		(start 131.075176 -225.360484)
		(end 131.658614 -226.233736)
		(width 0.13208)
		(layer "B.Cu")
		(net "SPI_PEX1_CLK_MUX")
	)
	(segment
		(start 131.075176 -222.040958)
		(end 131.075176 -223.561148)
		(width 0.13208)
		(layer "B.Cu")
		(net "SPI_PEX1_CLK_MUX")
	)
	(segment
		(start 136.863328 -227.211382)
		(end 137.405872 -227.753926)
		(width 0.13208)
		(layer "B.Cu")
		(net "SPI_PEX1_CLK_MUX")
	)
	(segment
		(start 131.658614 -226.233736)
		(end 134.019036 -227.211382)
		(width 0.13208)
		(layer "B.Cu")
		(net "SPI_PEX1_CLK_MUX")
	)
	(via
		(at 140.54709 -229.97287)
		(size 0.6604)
		(drill 0.3302)
		(layers "F.Cu" "B.Cu")
		(net "SPI_PEX1_CS_MUX_N")
	)
	(segment
		(start 136.28497 -231.606598)
		(end 139.681458 -231.606598)
		(width 0.13208)
		(layer "B.Cu")
		(net "SPI_PEX1_CS_MUX_N")
	)
	(segment
		(start 135.500872 -229.827582)
		(end 135.500872 -230.8225)
		(width 0.13208)
		(layer "B.Cu")
		(net "SPI_PEX1_CS_MUX_N")
	)
	(segment
		(start 140.54709 -229.97287)
		(end 140.282168 -229.707948)
		(width 0.13208)
		(layer "B.Cu")
		(net "SPI_PEX1_CS_MUX_N")
	)
	(segment
		(start 139.681458 -231.606598)
		(end 140.54709 -230.740966)
		(width 0.13208)
		(layer "B.Cu")
		(net "SPI_PEX1_CS_MUX_N")
	)
	(segment
		(start 135.500872 -230.8225)
		(end 136.28497 -231.606598)
		(width 0.13208)
		(layer "B.Cu")
		(net "SPI_PEX1_CS_MUX_N")
	)
	(segment
		(start 140.282168 -229.707948)
		(end 140.282168 -228.74605)
		(width 0.13208)
		(layer "B.Cu")
		(net "SPI_PEX1_CS_MUX_N")
	)
	(segment
		(start 140.54709 -230.740966)
		(end 140.54709 -229.97287)
		(width 0.13208)
		(layer "B.Cu")
		(net "SPI_PEX1_CS_MUX_N")
	)
	(via
		(at 134.893304 -231.95026)
		(size 0.508)
		(drill 0.254)
		(layers "F.Cu" "B.Cu")
		(net "SPI_PEX1_CS_R_N")
	)
	(via
		(at 155.69057 -269.987014)
		(size 0.508)
		(drill 0.254)
		(layers "F.Cu" "B.Cu")
		(net "SPI_PEX1_CS_R_N")
	)
	(segment
		(start 134.230872 -229.827582)
		(end 134.230872 -230.4669)
		(width 0.13208)
		(layer "B.Cu")
		(net "SPI_PEX1_CS_R_N")
	)
	(segment
		(start 156.750004 -285.637986)
		(end 156.750004 -288.374836)
		(width 0.13208)
		(layer "B.Cu")
		(net "SPI_PEX1_CS_R_N")
	)
	(segment
		(start 134.230872 -230.4669)
		(end 134.893304 -231.129332)
		(width 0.13208)
		(layer "B.Cu")
		(net "SPI_PEX1_CS_R_N")
	)
	(segment
		(start 134.893304 -231.129332)
		(end 134.893304 -231.95026)
		(width 0.13208)
		(layer "B.Cu")
		(net "SPI_PEX1_CS_R_N")
	)
	(segment
		(start 155.77058 -271.71396)
		(end 155.77058 -285.056326)
		(width 0.13208)
		(layer "B.Cu")
		(net "SPI_PEX1_CS_R_N")
	)
	(segment
		(start 156.492448 -285.38043)
		(end 156.750004 -285.637986)
		(width 0.13208)
		(layer "B.Cu")
		(net "SPI_PEX1_CS_R_N")
	)
	(segment
		(start 155.69057 -269.987014)
		(end 155.69057 -271.63395)
		(width 0.13208)
		(layer "B.Cu")
		(net "SPI_PEX1_CS_R_N")
	)
	(segment
		(start 155.69057 -271.63395)
		(end 155.77058 -271.71396)
		(width 0.13208)
		(layer "B.Cu")
		(net "SPI_PEX1_CS_R_N")
	)
	(segment
		(start 156.094684 -285.38043)
		(end 156.492448 -285.38043)
		(width 0.13208)
		(layer "B.Cu")
		(net "SPI_PEX1_CS_R_N")
	)
	(segment
		(start 155.77058 -285.056326)
		(end 156.094684 -285.38043)
		(width 0.13208)
		(layer "B.Cu")
		(net "SPI_PEX1_CS_R_N")
	)
	(segment
		(start 139.349734 -265.53668)
		(end 134.80034 -260.987286)
		(width 0.15494)
		(layer "In5.Cu")
		(net "SPI_PEX1_CS_R_N")
	)
	(segment
		(start 160.569402 -270.17345)
		(end 160.569402 -270.893286)
		(width 0.15494)
		(layer "In5.Cu")
		(net "SPI_PEX1_CS_R_N")
	)
	(segment
		(start 134.80034 -260.987286)
		(end 134.80034 -246.930418)
		(width 0.15494)
		(layer "In5.Cu")
		(net "SPI_PEX1_CS_R_N")
	)
	(segment
		(start 160.382966 -269.987014)
		(end 160.569402 -270.17345)
		(width 0.15494)
		(layer "In5.Cu")
		(net "SPI_PEX1_CS_R_N")
	)
	(segment
		(start 133.472682 -244.533674)
		(end 134.893304 -243.113052)
		(width 0.15494)
		(layer "In5.Cu")
		(net "SPI_PEX1_CS_R_N")
	)
	(segment
		(start 160.569402 -270.893286)
		(end 160.325054 -271.137634)
		(width 0.15494)
		(layer "In5.Cu")
		(net "SPI_PEX1_CS_R_N")
	)
	(segment
		(start 134.80034 -246.930418)
		(end 133.472682 -245.60276)
		(width 0.15494)
		(layer "In5.Cu")
		(net "SPI_PEX1_CS_R_N")
	)
	(segment
		(start 134.893304 -243.113052)
		(end 134.893304 -231.95026)
		(width 0.15494)
		(layer "In5.Cu")
		(net "SPI_PEX1_CS_R_N")
	)
	(segment
		(start 133.472682 -245.60276)
		(end 133.472682 -244.533674)
		(width 0.15494)
		(layer "In5.Cu")
		(net "SPI_PEX1_CS_R_N")
	)
	(segment
		(start 154.581606 -271.137634)
		(end 154.143964 -270.699992)
		(width 0.15494)
		(layer "In5.Cu")
		(net "SPI_PEX1_CS_R_N")
	)
	(segment
		(start 154.143964 -270.699992)
		(end 154.143964 -267.164312)
		(width 0.15494)
		(layer "In5.Cu")
		(net "SPI_PEX1_CS_R_N")
	)
	(segment
		(start 152.516332 -265.53668)
		(end 139.349734 -265.53668)
		(width 0.15494)
		(layer "In5.Cu")
		(net "SPI_PEX1_CS_R_N")
	)
	(segment
		(start 155.69057 -269.987014)
		(end 160.382966 -269.987014)
		(width 0.15494)
		(layer "In5.Cu")
		(net "SPI_PEX1_CS_R_N")
	)
	(segment
		(start 154.143964 -267.164312)
		(end 152.516332 -265.53668)
		(width 0.15494)
		(layer "In5.Cu")
		(net "SPI_PEX1_CS_R_N")
	)
	(segment
		(start 160.325054 -271.137634)
		(end 154.581606 -271.137634)
		(width 0.15494)
		(layer "In5.Cu")
		(net "SPI_PEX1_CS_R_N")
	)
	(via
		(at 134.865872 -225.623882)
		(size 0.508)
		(drill 0.254)
		(layers "F.Cu" "B.Cu")
		(net "SPI_PEX1_SDIO1_R")
	)
	(via
		(at 154.034236 -264.643616)
		(size 0.508)
		(drill 0.254)
		(layers "F.Cu" "B.Cu")
		(net "SPI_PEX1_SDIO1_R")
	)
	(segment
		(start 152.80894 -293.824152)
		(end 152.105614 -293.824152)
		(width 0.13208)
		(layer "B.Cu")
		(net "SPI_PEX1_SDIO1_R")
	)
	(segment
		(start 154.868118 -296.475658)
		(end 154.868118 -296.168064)
		(width 0.13208)
		(layer "B.Cu")
		(net "SPI_PEX1_SDIO1_R")
	)
	(segment
		(start 155.772104 -296.8498)
		(end 155.24226 -296.8498)
		(width 0.13208)
		(layer "B.Cu")
		(net "SPI_PEX1_SDIO1_R")
	)
	(segment
		(start 155.24226 -296.8498)
		(end 154.868118 -296.475658)
		(width 0.13208)
		(layer "B.Cu")
		(net "SPI_PEX1_SDIO1_R")
	)
	(segment
		(start 154.868118 -296.168064)
		(end 153.737818 -295.037764)
		(width 0.13208)
		(layer "B.Cu")
		(net "SPI_PEX1_SDIO1_R")
	)
	(segment
		(start 150.83028 -292.548818)
		(end 150.83028 -274.183348)
		(width 0.13208)
		(layer "B.Cu")
		(net "SPI_PEX1_SDIO1_R")
	)
	(segment
		(start 151.406352 -273.607276)
		(end 151.406352 -267.2715)
		(width 0.13208)
		(layer "B.Cu")
		(net "SPI_PEX1_SDIO1_R")
	)
	(segment
		(start 152.105614 -293.824152)
		(end 150.83028 -292.548818)
		(width 0.13208)
		(layer "B.Cu")
		(net "SPI_PEX1_SDIO1_R")
	)
	(segment
		(start 155.873704 -296.9514)
		(end 155.772104 -296.8498)
		(width 0.13208)
		(layer "B.Cu")
		(net "SPI_PEX1_SDIO1_R")
	)
	(segment
		(start 153.005536 -294.020748)
		(end 152.80894 -293.824152)
		(width 0.13208)
		(layer "B.Cu")
		(net "SPI_PEX1_SDIO1_R")
	)
	(segment
		(start 153.354532 -295.037764)
		(end 153.005536 -294.688768)
		(width 0.13208)
		(layer "B.Cu")
		(net "SPI_PEX1_SDIO1_R")
	)
	(segment
		(start 151.406352 -267.2715)
		(end 154.034236 -264.643616)
		(width 0.13208)
		(layer "B.Cu")
		(net "SPI_PEX1_SDIO1_R")
	)
	(segment
		(start 153.737818 -295.037764)
		(end 153.354532 -295.037764)
		(width 0.13208)
		(layer "B.Cu")
		(net "SPI_PEX1_SDIO1_R")
	)
	(segment
		(start 150.83028 -274.183348)
		(end 151.406352 -273.607276)
		(width 0.13208)
		(layer "B.Cu")
		(net "SPI_PEX1_SDIO1_R")
	)
	(segment
		(start 153.005536 -294.688768)
		(end 153.005536 -294.020748)
		(width 0.13208)
		(layer "B.Cu")
		(net "SPI_PEX1_SDIO1_R")
	)
	(segment
		(start 134.865872 -224.341182)
		(end 134.865872 -225.623882)
		(width 0.13208)
		(layer "B.Cu")
		(net "SPI_PEX1_SDIO1_R")
	)
	(segment
		(start 136.651492 -230.377746)
		(end 137.3124 -229.716838)
		(width 0.15494)
		(layer "In5.Cu")
		(net "SPI_PEX1_SDIO1_R")
	)
	(segment
		(start 136.8298 -227.1268)
		(end 136.36879 -227.1268)
		(width 0.15494)
		(layer "In5.Cu")
		(net "SPI_PEX1_SDIO1_R")
	)
	(segment
		(start 137.3124 -229.716838)
		(end 137.3124 -227.6094)
		(width 0.15494)
		(layer "In5.Cu")
		(net "SPI_PEX1_SDIO1_R")
	)
	(segment
		(start 140.004292 -264.2108)
		(end 136.2456 -260.452108)
		(width 0.15494)
		(layer "In5.Cu")
		(net "SPI_PEX1_SDIO1_R")
	)
	(segment
		(start 136.36879 -227.1268)
		(end 134.865872 -225.623882)
		(width 0.15494)
		(layer "In5.Cu")
		(net "SPI_PEX1_SDIO1_R")
	)
	(segment
		(start 153.60142 -264.2108)
		(end 140.004292 -264.2108)
		(width 0.15494)
		(layer "In5.Cu")
		(net "SPI_PEX1_SDIO1_R")
	)
	(segment
		(start 137.3124 -227.6094)
		(end 136.8298 -227.1268)
		(width 0.15494)
		(layer "In5.Cu")
		(net "SPI_PEX1_SDIO1_R")
	)
	(segment
		(start 136.2456 -251.027692)
		(end 136.651492 -250.6218)
		(width 0.15494)
		(layer "In5.Cu")
		(net "SPI_PEX1_SDIO1_R")
	)
	(segment
		(start 136.651492 -250.6218)
		(end 136.651492 -230.377746)
		(width 0.15494)
		(layer "In5.Cu")
		(net "SPI_PEX1_SDIO1_R")
	)
	(segment
		(start 136.2456 -260.452108)
		(end 136.2456 -251.027692)
		(width 0.15494)
		(layer "In5.Cu")
		(net "SPI_PEX1_SDIO1_R")
	)
	(segment
		(start 154.034236 -264.643616)
		(end 153.60142 -264.2108)
		(width 0.15494)
		(layer "In5.Cu")
		(net "SPI_PEX1_SDIO1_R")
	)
	(via
		(at 136.770872 -225.560382)
		(size 0.508)
		(drill 0.254)
		(layers "F.Cu" "B.Cu")
		(net "SPI_PEX1_SDIO0_R")
	)
	(via
		(at 154.430222 -263.37768)
		(size 0.508)
		(drill 0.254)
		(layers "F.Cu" "B.Cu")
		(net "SPI_PEX1_SDIO0_R")
	)
	(segment
		(start 155.873704 -295.79824)
		(end 154.981148 -294.905684)
		(width 0.13208)
		(layer "B.Cu")
		(net "SPI_PEX1_SDIO0_R")
	)
	(segment
		(start 154.482292 -294.004492)
		(end 154.249374 -294.004492)
		(width 0.13208)
		(layer "B.Cu")
		(net "SPI_PEX1_SDIO0_R")
	)
	(segment
		(start 151.33066 -292.341554)
		(end 151.33066 -274.553172)
		(width 0.13208)
		(layer "B.Cu")
		(net "SPI_PEX1_SDIO0_R")
	)
	(segment
		(start 153.395172 -293.15029)
		(end 152.139396 -293.15029)
		(width 0.13208)
		(layer "B.Cu")
		(net "SPI_PEX1_SDIO0_R")
	)
	(segment
		(start 151.33066 -274.553172)
		(end 151.922734 -273.961098)
		(width 0.13208)
		(layer "B.Cu")
		(net "SPI_PEX1_SDIO0_R")
	)
	(segment
		(start 152.139396 -293.15029)
		(end 151.33066 -292.341554)
		(width 0.13208)
		(layer "B.Cu")
		(net "SPI_PEX1_SDIO0_R")
	)
	(segment
		(start 151.922734 -267.943838)
		(end 155.083256 -264.783316)
		(width 0.13208)
		(layer "B.Cu")
		(net "SPI_PEX1_SDIO0_R")
	)
	(segment
		(start 155.083256 -264.030714)
		(end 154.430222 -263.37768)
		(width 0.13208)
		(layer "B.Cu")
		(net "SPI_PEX1_SDIO0_R")
	)
	(segment
		(start 151.922734 -273.961098)
		(end 151.922734 -267.943838)
		(width 0.13208)
		(layer "B.Cu")
		(net "SPI_PEX1_SDIO0_R")
	)
	(segment
		(start 154.249374 -294.004492)
		(end 153.395172 -293.15029)
		(width 0.13208)
		(layer "B.Cu")
		(net "SPI_PEX1_SDIO0_R")
	)
	(segment
		(start 154.981148 -294.905684)
		(end 154.981148 -294.503348)
		(width 0.13208)
		(layer "B.Cu")
		(net "SPI_PEX1_SDIO0_R")
	)
	(segment
		(start 154.981148 -294.503348)
		(end 154.482292 -294.004492)
		(width 0.13208)
		(layer "B.Cu")
		(net "SPI_PEX1_SDIO0_R")
	)
	(segment
		(start 155.083256 -264.783316)
		(end 155.083256 -264.030714)
		(width 0.13208)
		(layer "B.Cu")
		(net "SPI_PEX1_SDIO0_R")
	)
	(segment
		(start 136.770872 -224.341182)
		(end 136.770872 -225.560382)
		(width 0.13208)
		(layer "B.Cu")
		(net "SPI_PEX1_SDIO0_R")
	)
	(segment
		(start 136.9822 -251.332746)
		(end 136.9822 -260.197346)
		(width 0.15494)
		(layer "In5.Cu")
		(net "SPI_PEX1_SDIO0_R")
	)
	(segment
		(start 139.079732 -229.07879)
		(end 137.2616 -230.896922)
		(width 0.15494)
		(layer "In5.Cu")
		(net "SPI_PEX1_SDIO0_R")
	)
	(segment
		(start 137.2616 -230.896922)
		(end 137.2616 -251.053346)
		(width 0.15494)
		(layer "In5.Cu")
		(net "SPI_PEX1_SDIO0_R")
	)
	(segment
		(start 137.354056 -225.560382)
		(end 139.079732 -227.286058)
		(width 0.15494)
		(layer "In5.Cu")
		(net "SPI_PEX1_SDIO0_R")
	)
	(segment
		(start 154.133042 -263.67486)
		(end 154.430222 -263.37768)
		(width 0.15494)
		(layer "In5.Cu")
		(net "SPI_PEX1_SDIO0_R")
	)
	(segment
		(start 139.079732 -227.286058)
		(end 139.079732 -229.07879)
		(width 0.15494)
		(layer "In5.Cu")
		(net "SPI_PEX1_SDIO0_R")
	)
	(segment
		(start 137.2616 -251.053346)
		(end 136.9822 -251.332746)
		(width 0.15494)
		(layer "In5.Cu")
		(net "SPI_PEX1_SDIO0_R")
	)
	(segment
		(start 136.770872 -225.560382)
		(end 137.354056 -225.560382)
		(width 0.15494)
		(layer "In5.Cu")
		(net "SPI_PEX1_SDIO0_R")
	)
	(segment
		(start 140.459714 -263.67486)
		(end 154.133042 -263.67486)
		(width 0.15494)
		(layer "In5.Cu")
		(net "SPI_PEX1_SDIO0_R")
	)
	(segment
		(start 136.9822 -260.197346)
		(end 140.459714 -263.67486)
		(width 0.15494)
		(layer "In5.Cu")
		(net "SPI_PEX1_SDIO0_R")
	)
	(via
		(at 139.152122 -226.814126)
		(size 0.6604)
		(drill 0.3302)
		(layers "F.Cu" "B.Cu")
		(net "SPI_PEX1_SDIO1_MUX")
	)
	(segment
		(start 136.05002 -226.042474)
		(end 136.374124 -226.366578)
		(width 0.13208)
		(layer "B.Cu")
		(net "SPI_PEX1_SDIO1_MUX")
	)
	(segment
		(start 139.152122 -227.313236)
		(end 139.275058 -227.436172)
		(width 0.13208)
		(layer "B.Cu")
		(net "SPI_PEX1_SDIO1_MUX")
	)
	(segment
		(start 136.135872 -225.242882)
		(end 136.05002 -225.328734)
		(width 0.13208)
		(layer "B.Cu")
		(net "SPI_PEX1_SDIO1_MUX")
	)
	(segment
		(start 138.06932 -226.366578)
		(end 138.516868 -226.814126)
		(width 0.13208)
		(layer "B.Cu")
		(net "SPI_PEX1_SDIO1_MUX")
	)
	(segment
		(start 136.135872 -224.341182)
		(end 136.135872 -225.242882)
		(width 0.13208)
		(layer "B.Cu")
		(net "SPI_PEX1_SDIO1_MUX")
	)
	(segment
		(start 138.516868 -226.814126)
		(end 139.152122 -226.814126)
		(width 0.13208)
		(layer "B.Cu")
		(net "SPI_PEX1_SDIO1_MUX")
	)
	(segment
		(start 136.05002 -225.328734)
		(end 136.05002 -226.042474)
		(width 0.13208)
		(layer "B.Cu")
		(net "SPI_PEX1_SDIO1_MUX")
	)
	(segment
		(start 136.374124 -226.366578)
		(end 138.06932 -226.366578)
		(width 0.13208)
		(layer "B.Cu")
		(net "SPI_PEX1_SDIO1_MUX")
	)
	(segment
		(start 139.275058 -227.436172)
		(end 139.275058 -227.94595)
		(width 0.13208)
		(layer "B.Cu")
		(net "SPI_PEX1_SDIO1_MUX")
	)
	(segment
		(start 139.152122 -226.814126)
		(end 139.152122 -227.313236)
		(width 0.13208)
		(layer "B.Cu")
		(net "SPI_PEX1_SDIO1_MUX")
	)
	(via
		(at 155.13812 -266.963398)
		(size 0.508)
		(drill 0.254)
		(layers "F.Cu" "B.Cu")
		(net "SPI_PEX1_CLK_R")
	)
	(via
		(at 135.418322 -228.06914)
		(size 0.508)
		(drill 0.254)
		(layers "F.Cu" "B.Cu")
		(net "SPI_PEX1_CLK_R")
	)
	(segment
		(start 136.135872 -229.209346)
		(end 136.135872 -229.827582)
		(width 0.13208)
		(layer "B.Cu")
		(net "SPI_PEX1_CLK_R")
	)
	(segment
		(start 135.418322 -228.06914)
		(end 135.418322 -228.491796)
		(width 0.13208)
		(layer "B.Cu")
		(net "SPI_PEX1_CLK_R")
	)
	(segment
		(start 155.757118 -291.72662)
		(end 155.353512 -291.323014)
		(width 0.13208)
		(layer "B.Cu")
		(net "SPI_PEX1_CLK_R")
	)
	(segment
		(start 153.88209 -289.88258)
		(end 153.88209 -269.118842)
		(width 0.13208)
		(layer "B.Cu")
		(net "SPI_PEX1_CLK_R")
	)
	(segment
		(start 153.88209 -269.118842)
		(end 155.13812 -267.862812)
		(width 0.13208)
		(layer "B.Cu")
		(net "SPI_PEX1_CLK_R")
	)
	(segment
		(start 135.418322 -228.491796)
		(end 136.135872 -229.209346)
		(width 0.13208)
		(layer "B.Cu")
		(net "SPI_PEX1_CLK_R")
	)
	(segment
		(start 154.746452 -290.1696)
		(end 154.16911 -290.1696)
		(width 0.13208)
		(layer "B.Cu")
		(net "SPI_PEX1_CLK_R")
	)
	(segment
		(start 155.353512 -291.323014)
		(end 155.353512 -290.77666)
		(width 0.13208)
		(layer "B.Cu")
		(net "SPI_PEX1_CLK_R")
	)
	(segment
		(start 155.353512 -290.77666)
		(end 154.746452 -290.1696)
		(width 0.13208)
		(layer "B.Cu")
		(net "SPI_PEX1_CLK_R")
	)
	(segment
		(start 154.16911 -290.1696)
		(end 153.88209 -289.88258)
		(width 0.13208)
		(layer "B.Cu")
		(net "SPI_PEX1_CLK_R")
	)
	(segment
		(start 155.13812 -267.862812)
		(end 155.13812 -266.963398)
		(width 0.13208)
		(layer "B.Cu")
		(net "SPI_PEX1_CLK_R")
	)
	(segment
		(start 134.218426 -230.598726)
		(end 134.218426 -230.345234)
		(width 0.15494)
		(layer "In5.Cu")
		(net "SPI_PEX1_CLK_R")
	)
	(segment
		(start 135.678926 -230.853234)
		(end 134.472934 -230.853234)
		(width 0.15494)
		(layer "In5.Cu")
		(net "SPI_PEX1_CLK_R")
	)
	(segment
		(start 155.13812 -266.963398)
		(end 153.048462 -264.87374)
		(width 0.15494)
		(layer "In5.Cu")
		(net "SPI_PEX1_CLK_R")
	)
	(segment
		(start 135.46328 -244.981984)
		(end 135.886444 -244.55882)
		(width 0.15494)
		(layer "In5.Cu")
		(net "SPI_PEX1_CLK_R")
	)
	(segment
		(start 153.048462 -264.87374)
		(end 139.712446 -264.87374)
		(width 0.15494)
		(layer "In5.Cu")
		(net "SPI_PEX1_CLK_R")
	)
	(segment
		(start 136.044432 -230.075994)
		(end 136.044432 -229.209092)
		(width 0.15494)
		(layer "In5.Cu")
		(net "SPI_PEX1_CLK_R")
	)
	(segment
		(start 135.418322 -228.582982)
		(end 135.418322 -228.06914)
		(width 0.15494)
		(layer "In5.Cu")
		(net "SPI_PEX1_CLK_R")
	)
	(segment
		(start 135.886444 -231.060752)
		(end 135.678926 -230.853234)
		(width 0.15494)
		(layer "In5.Cu")
		(net "SPI_PEX1_CLK_R")
	)
	(segment
		(start 135.886444 -244.55882)
		(end 135.886444 -231.060752)
		(width 0.15494)
		(layer "In5.Cu")
		(net "SPI_PEX1_CLK_R")
	)
	(segment
		(start 136.044432 -229.209092)
		(end 135.418322 -228.582982)
		(width 0.15494)
		(layer "In5.Cu")
		(net "SPI_PEX1_CLK_R")
	)
	(segment
		(start 134.472934 -230.853234)
		(end 134.218426 -230.598726)
		(width 0.15494)
		(layer "In5.Cu")
		(net "SPI_PEX1_CLK_R")
	)
	(segment
		(start 135.909812 -230.210614)
		(end 136.044432 -230.075994)
		(width 0.15494)
		(layer "In5.Cu")
		(net "SPI_PEX1_CLK_R")
	)
	(segment
		(start 139.712446 -264.87374)
		(end 135.46328 -260.624574)
		(width 0.15494)
		(layer "In5.Cu")
		(net "SPI_PEX1_CLK_R")
	)
	(segment
		(start 135.46328 -260.624574)
		(end 135.46328 -244.981984)
		(width 0.15494)
		(layer "In5.Cu")
		(net "SPI_PEX1_CLK_R")
	)
	(segment
		(start 134.353046 -230.210614)
		(end 135.909812 -230.210614)
		(width 0.15494)
		(layer "In5.Cu")
		(net "SPI_PEX1_CLK_R")
	)
	(segment
		(start 134.218426 -230.345234)
		(end 134.353046 -230.210614)
		(width 0.15494)
		(layer "In5.Cu")
		(net "SPI_PEX1_CLK_R")
	)
	(via
		(at 131.293108 -231.203754)
		(size 0.508)
		(drill 0.254)
		(layers "F.Cu" "B.Cu")
		(net "SPI_PEX1_SDIO2_R")
	)
	(via
		(at 153.335228 -267.578078)
		(size 0.508)
		(drill 0.254)
		(layers "F.Cu" "B.Cu")
		(net "SPI_PEX1_SDIO2_R")
	)
	(segment
		(start 155.229814 -293.04996)
		(end 154.822144 -292.64229)
		(width 0.13208)
		(layer "B.Cu")
		(net "SPI_PEX1_SDIO2_R")
	)
	(segment
		(start 155.819094 -294.8051)
		(end 155.819094 -293.41064)
		(width 0.13208)
		(layer "B.Cu")
		(net "SPI_PEX1_SDIO2_R")
	)
	(segment
		(start 152.4508 -268.462506)
		(end 153.335228 -267.578078)
		(width 0.13208)
		(layer "B.Cu")
		(net "SPI_PEX1_SDIO2_R")
	)
	(segment
		(start 151.83104 -291.651944)
		(end 151.83104 -275.135086)
		(width 0.13208)
		(layer "B.Cu")
		(net "SPI_PEX1_SDIO2_R")
	)
	(segment
		(start 151.83104 -275.135086)
		(end 152.4508 -274.515326)
		(width 0.13208)
		(layer "B.Cu")
		(net "SPI_PEX1_SDIO2_R")
	)
	(segment
		(start 154.499564 -292.065964)
		(end 152.24506 -292.065964)
		(width 0.13208)
		(layer "B.Cu")
		(net "SPI_PEX1_SDIO2_R")
	)
	(segment
		(start 152.4508 -274.515326)
		(end 152.4508 -268.462506)
		(width 0.13208)
		(layer "B.Cu")
		(net "SPI_PEX1_SDIO2_R")
	)
	(segment
		(start 154.822144 -292.64229)
		(end 154.822144 -292.388544)
		(width 0.13208)
		(layer "B.Cu")
		(net "SPI_PEX1_SDIO2_R")
	)
	(segment
		(start 155.458414 -293.04996)
		(end 155.229814 -293.04996)
		(width 0.13208)
		(layer "B.Cu")
		(net "SPI_PEX1_SDIO2_R")
	)
	(segment
		(start 152.24506 -292.065964)
		(end 151.83104 -291.651944)
		(width 0.13208)
		(layer "B.Cu")
		(net "SPI_PEX1_SDIO2_R")
	)
	(segment
		(start 154.822144 -292.388544)
		(end 154.499564 -292.065964)
		(width 0.13208)
		(layer "B.Cu")
		(net "SPI_PEX1_SDIO2_R")
	)
	(segment
		(start 131.293108 -229.997)
		(end 131.293108 -231.203754)
		(width 0.13208)
		(layer "B.Cu")
		(net "SPI_PEX1_SDIO2_R")
	)
	(segment
		(start 155.819094 -293.41064)
		(end 155.458414 -293.04996)
		(width 0.13208)
		(layer "B.Cu")
		(net "SPI_PEX1_SDIO2_R")
	)
	(segment
		(start 151.105616 -269.370048)
		(end 150.970996 -269.504668)
		(width 0.15494)
		(layer "In5.Cu")
		(net "SPI_PEX1_SDIO2_R")
	)
	(segment
		(start 150.667974 -267.571728)
		(end 150.497286 -267.742416)
		(width 0.15494)
		(layer "In5.Cu")
		(net "SPI_PEX1_SDIO2_R")
	)
	(segment
		(start 129.33807 -239.402112)
		(end 129.20345 -239.536732)
		(width 0.15494)
		(layer "In5.Cu")
		(net "SPI_PEX1_SDIO2_R")
	)
	(segment
		(start 152.216104 -269.370048)
		(end 151.105616 -269.370048)
		(width 0.15494)
		(layer "In5.Cu")
		(net "SPI_PEX1_SDIO2_R")
	)
	(segment
		(start 131.293108 -231.203754)
		(end 131.293108 -232.818178)
		(width 0.15494)
		(layer "In5.Cu")
		(net "SPI_PEX1_SDIO2_R")
	)
	(segment
		(start 129.972054 -240.179352)
		(end 129.972054 -242.040664)
		(width 0.15494)
		(layer "In5.Cu")
		(net "SPI_PEX1_SDIO2_R")
	)
	(segment
		(start 129.972054 -239.267492)
		(end 129.837434 -239.402112)
		(width 0.15494)
		(layer "In5.Cu")
		(net "SPI_PEX1_SDIO2_R")
	)
	(segment
		(start 153.335228 -270.738092)
		(end 153.335228 -267.578078)
		(width 0.15494)
		(layer "In5.Cu")
		(net "SPI_PEX1_SDIO2_R")
	)
	(segment
		(start 131.293108 -232.818178)
		(end 129.972054 -234.139232)
		(width 0.15494)
		(layer "In5.Cu")
		(net "SPI_PEX1_SDIO2_R")
	)
	(segment
		(start 152.485344 -270.872712)
		(end 153.200608 -270.872712)
		(width 0.15494)
		(layer "In5.Cu")
		(net "SPI_PEX1_SDIO2_R")
	)
	(segment
		(start 129.33807 -240.044732)
		(end 129.837434 -240.044732)
		(width 0.15494)
		(layer "In5.Cu")
		(net "SPI_PEX1_SDIO2_R")
	)
	(segment
		(start 153.200608 -270.872712)
		(end 153.335228 -270.738092)
		(width 0.15494)
		(layer "In5.Cu")
		(net "SPI_PEX1_SDIO2_R")
	)
	(segment
		(start 129.972054 -242.040664)
		(end 132.536184 -244.604794)
		(width 0.15494)
		(layer "In5.Cu")
		(net "SPI_PEX1_SDIO2_R")
	)
	(segment
		(start 134.2644 -261.5438)
		(end 138.79322 -266.07262)
		(width 0.15494)
		(layer "In5.Cu")
		(net "SPI_PEX1_SDIO2_R")
	)
	(segment
		(start 152.005538 -266.07262)
		(end 152.350724 -266.417806)
		(width 0.15494)
		(layer "In5.Cu")
		(net "SPI_PEX1_SDIO2_R")
	)
	(segment
		(start 152.350724 -269.235428)
		(end 152.216104 -269.370048)
		(width 0.15494)
		(layer "In5.Cu")
		(net "SPI_PEX1_SDIO2_R")
	)
	(segment
		(start 152.350724 -266.417806)
		(end 152.350724 -267.437108)
		(width 0.15494)
		(layer "In5.Cu")
		(net "SPI_PEX1_SDIO2_R")
	)
	(segment
		(start 151.105616 -270.269208)
		(end 152.216104 -270.269208)
		(width 0.15494)
		(layer "In5.Cu")
		(net "SPI_PEX1_SDIO2_R")
	)
	(segment
		(start 132.536184 -244.604794)
		(end 132.536184 -245.559834)
		(width 0.15494)
		(layer "In5.Cu")
		(net "SPI_PEX1_SDIO2_R")
	)
	(segment
		(start 152.216104 -270.269208)
		(end 152.350724 -270.403828)
		(width 0.15494)
		(layer "In5.Cu")
		(net "SPI_PEX1_SDIO2_R")
	)
	(segment
		(start 152.350724 -267.437108)
		(end 152.216104 -267.571728)
		(width 0.15494)
		(layer "In5.Cu")
		(net "SPI_PEX1_SDIO2_R")
	)
	(segment
		(start 129.972054 -234.139232)
		(end 129.972054 -239.267492)
		(width 0.15494)
		(layer "In5.Cu")
		(net "SPI_PEX1_SDIO2_R")
	)
	(segment
		(start 150.497286 -268.343888)
		(end 150.624286 -268.470888)
		(width 0.15494)
		(layer "In5.Cu")
		(net "SPI_PEX1_SDIO2_R")
	)
	(segment
		(start 150.497286 -267.742416)
		(end 150.497286 -268.343888)
		(width 0.15494)
		(layer "In5.Cu")
		(net "SPI_PEX1_SDIO2_R")
	)
	(segment
		(start 152.350724 -270.403828)
		(end 152.350724 -270.738092)
		(width 0.15494)
		(layer "In5.Cu")
		(net "SPI_PEX1_SDIO2_R")
	)
	(segment
		(start 150.624286 -268.470888)
		(end 152.216104 -268.470888)
		(width 0.15494)
		(layer "In5.Cu")
		(net "SPI_PEX1_SDIO2_R")
	)
	(segment
		(start 150.970996 -270.134588)
		(end 151.105616 -270.269208)
		(width 0.15494)
		(layer "In5.Cu")
		(net "SPI_PEX1_SDIO2_R")
	)
	(segment
		(start 134.2644 -247.28805)
		(end 134.2644 -261.5438)
		(width 0.15494)
		(layer "In5.Cu")
		(net "SPI_PEX1_SDIO2_R")
	)
	(segment
		(start 129.20345 -239.536732)
		(end 129.20345 -239.910112)
		(width 0.15494)
		(layer "In5.Cu")
		(net "SPI_PEX1_SDIO2_R")
	)
	(segment
		(start 152.216104 -268.470888)
		(end 152.350724 -268.605508)
		(width 0.15494)
		(layer "In5.Cu")
		(net "SPI_PEX1_SDIO2_R")
	)
	(segment
		(start 129.20345 -239.910112)
		(end 129.33807 -240.044732)
		(width 0.15494)
		(layer "In5.Cu")
		(net "SPI_PEX1_SDIO2_R")
	)
	(segment
		(start 152.216104 -267.571728)
		(end 150.667974 -267.571728)
		(width 0.15494)
		(layer "In5.Cu")
		(net "SPI_PEX1_SDIO2_R")
	)
	(segment
		(start 138.79322 -266.07262)
		(end 152.005538 -266.07262)
		(width 0.15494)
		(layer "In5.Cu")
		(net "SPI_PEX1_SDIO2_R")
	)
	(segment
		(start 132.536184 -245.559834)
		(end 134.2644 -247.28805)
		(width 0.15494)
		(layer "In5.Cu")
		(net "SPI_PEX1_SDIO2_R")
	)
	(segment
		(start 129.837434 -240.044732)
		(end 129.972054 -240.179352)
		(width 0.15494)
		(layer "In5.Cu")
		(net "SPI_PEX1_SDIO2_R")
	)
	(segment
		(start 152.350724 -268.605508)
		(end 152.350724 -269.235428)
		(width 0.15494)
		(layer "In5.Cu")
		(net "SPI_PEX1_SDIO2_R")
	)
	(segment
		(start 152.350724 -270.738092)
		(end 152.485344 -270.872712)
		(width 0.15494)
		(layer "In5.Cu")
		(net "SPI_PEX1_SDIO2_R")
	)
	(segment
		(start 150.970996 -269.504668)
		(end 150.970996 -270.134588)
		(width 0.15494)
		(layer "In5.Cu")
		(net "SPI_PEX1_SDIO2_R")
	)
	(segment
		(start 129.837434 -239.402112)
		(end 129.33807 -239.402112)
		(width 0.15494)
		(layer "In5.Cu")
		(net "SPI_PEX1_SDIO2_R")
	)
	(via
		(at 361.923838 -237.941358)
		(size 0.508)
		(drill 0.254)
		(layers "F.Cu" "B.Cu")
		(net "SPI_PEX3_SDIO2_R")
	)
	(via
		(at 385.53517 -267.578078)
		(size 0.508)
		(drill 0.254)
		(layers "F.Cu" "B.Cu")
		(net "SPI_PEX3_SDIO2_R")
	)
	(segment
		(start 363.73054 -232.134664)
		(end 361.923838 -233.941366)
		(width 0.13208)
		(layer "B.Cu")
		(net "SPI_PEX3_SDIO2_R")
	)
	(segment
		(start 388.019036 -294.8051)
		(end 388.019036 -293.312088)
		(width 0.13208)
		(layer "B.Cu")
		(net "SPI_PEX3_SDIO2_R")
	)
	(segment
		(start 387.35254 -293.04996)
		(end 387.022086 -292.719506)
		(width 0.13208)
		(layer "B.Cu")
		(net "SPI_PEX3_SDIO2_R")
	)
	(segment
		(start 388.019036 -293.312088)
		(end 387.756908 -293.04996)
		(width 0.13208)
		(layer "B.Cu")
		(net "SPI_PEX3_SDIO2_R")
	)
	(segment
		(start 363.73054 -230.23449)
		(end 363.73054 -232.134664)
		(width 0.13208)
		(layer "B.Cu")
		(net "SPI_PEX3_SDIO2_R")
	)
	(segment
		(start 386.720334 -292.065964)
		(end 384.445002 -292.065964)
		(width 0.13208)
		(layer "B.Cu")
		(net "SPI_PEX3_SDIO2_R")
	)
	(segment
		(start 387.756908 -293.04996)
		(end 387.35254 -293.04996)
		(width 0.13208)
		(layer "B.Cu")
		(net "SPI_PEX3_SDIO2_R")
	)
	(segment
		(start 384.030982 -291.651944)
		(end 384.030982 -275.135086)
		(width 0.13208)
		(layer "B.Cu")
		(net "SPI_PEX3_SDIO2_R")
	)
	(segment
		(start 387.022086 -292.367716)
		(end 386.720334 -292.065964)
		(width 0.13208)
		(layer "B.Cu")
		(net "SPI_PEX3_SDIO2_R")
	)
	(segment
		(start 361.923838 -233.941366)
		(end 361.923838 -237.941358)
		(width 0.13208)
		(layer "B.Cu")
		(net "SPI_PEX3_SDIO2_R")
	)
	(segment
		(start 363.49305 -229.997)
		(end 363.73054 -230.23449)
		(width 0.13208)
		(layer "B.Cu")
		(net "SPI_PEX3_SDIO2_R")
	)
	(segment
		(start 384.445002 -292.065964)
		(end 384.030982 -291.651944)
		(width 0.13208)
		(layer "B.Cu")
		(net "SPI_PEX3_SDIO2_R")
	)
	(segment
		(start 387.022086 -292.719506)
		(end 387.022086 -292.367716)
		(width 0.13208)
		(layer "B.Cu")
		(net "SPI_PEX3_SDIO2_R")
	)
	(segment
		(start 384.030982 -275.135086)
		(end 384.871214 -274.294854)
		(width 0.13208)
		(layer "B.Cu")
		(net "SPI_PEX3_SDIO2_R")
	)
	(segment
		(start 384.871214 -268.242034)
		(end 385.53517 -267.578078)
		(width 0.13208)
		(layer "B.Cu")
		(net "SPI_PEX3_SDIO2_R")
	)
	(segment
		(start 384.871214 -274.294854)
		(end 384.871214 -268.242034)
		(width 0.13208)
		(layer "B.Cu")
		(net "SPI_PEX3_SDIO2_R")
	)
	(segment
		(start 384.840226 -270.14932)
		(end 384.705606 -270.0147)
		(width 0.15494)
		(layer "In5.Cu")
		(net "SPI_PEX3_SDIO2_R")
	)
	(segment
		(start 384.840226 -266.417806)
		(end 384.494024 -266.071604)
		(width 0.15494)
		(layer "In5.Cu")
		(net "SPI_PEX3_SDIO2_R")
	)
	(segment
		(start 380.547118 -266.071604)
		(end 371.108224 -266.071604)
		(width 0.15494)
		(layer "In5.Cu")
		(net "SPI_PEX3_SDIO2_R")
	)
	(segment
		(start 384.840226 -270.548354)
		(end 384.840226 -270.14932)
		(width 0.15494)
		(layer "In5.Cu")
		(net "SPI_PEX3_SDIO2_R")
	)
	(segment
		(start 381.446278 -266.876276)
		(end 380.816358 -266.876276)
		(width 0.15494)
		(layer "In5.Cu")
		(net "SPI_PEX3_SDIO2_R")
	)
	(segment
		(start 384.705606 -268.21638)
		(end 382.678432 -268.21638)
		(width 0.15494)
		(layer "In5.Cu")
		(net "SPI_PEX3_SDIO2_R")
	)
	(segment
		(start 384.705606 -269.11554)
		(end 384.840226 -268.98092)
		(width 0.15494)
		(layer "In5.Cu")
		(net "SPI_PEX3_SDIO2_R")
	)
	(segment
		(start 382.710944 -267.31722)
		(end 384.705606 -267.31722)
		(width 0.15494)
		(layer "In5.Cu")
		(net "SPI_PEX3_SDIO2_R")
	)
	(segment
		(start 383.233676 -269.25016)
		(end 383.368296 -269.11554)
		(width 0.15494)
		(layer "In5.Cu")
		(net "SPI_PEX3_SDIO2_R")
	)
	(segment
		(start 366.749076 -247.612916)
		(end 366.24895 -247.11279)
		(width 0.15494)
		(layer "In5.Cu")
		(net "SPI_PEX3_SDIO2_R")
	)
	(segment
		(start 384.705606 -267.31722)
		(end 384.840226 -267.1826)
		(width 0.15494)
		(layer "In5.Cu")
		(net "SPI_PEX3_SDIO2_R")
	)
	(segment
		(start 380.681738 -266.206224)
		(end 380.547118 -266.071604)
		(width 0.15494)
		(layer "In5.Cu")
		(net "SPI_PEX3_SDIO2_R")
	)
	(segment
		(start 371.108224 -266.071604)
		(end 366.749076 -261.712456)
		(width 0.15494)
		(layer "In5.Cu")
		(net "SPI_PEX3_SDIO2_R")
	)
	(segment
		(start 381.715518 -266.071604)
		(end 381.580898 -266.206224)
		(width 0.15494)
		(layer "In5.Cu")
		(net "SPI_PEX3_SDIO2_R")
	)
	(segment
		(start 381.580898 -266.206224)
		(end 381.580898 -266.741656)
		(width 0.15494)
		(layer "In5.Cu")
		(net "SPI_PEX3_SDIO2_R")
	)
	(segment
		(start 382.678432 -268.21638)
		(end 382.551432 -268.08938)
		(width 0.15494)
		(layer "In5.Cu")
		(net "SPI_PEX3_SDIO2_R")
	)
	(segment
		(start 380.816358 -266.876276)
		(end 380.681738 -266.741656)
		(width 0.15494)
		(layer "In5.Cu")
		(net "SPI_PEX3_SDIO2_R")
	)
	(segment
		(start 383.368296 -270.0147)
		(end 383.233676 -269.88008)
		(width 0.15494)
		(layer "In5.Cu")
		(net "SPI_PEX3_SDIO2_R")
	)
	(segment
		(start 381.580898 -266.741656)
		(end 381.446278 -266.876276)
		(width 0.15494)
		(layer "In5.Cu")
		(net "SPI_PEX3_SDIO2_R")
	)
	(segment
		(start 362.379768 -239.510824)
		(end 362.37926 -239.510824)
		(width 0.15494)
		(layer "In5.Cu")
		(net "SPI_PEX3_SDIO2_R")
	)
	(segment
		(start 361.968034 -239.09909)
		(end 361.923838 -239.054894)
		(width 0.15494)
		(layer "In5.Cu")
		(net "SPI_PEX3_SDIO2_R")
	)
	(segment
		(start 380.681738 -266.741656)
		(end 380.681738 -266.206224)
		(width 0.15494)
		(layer "In5.Cu")
		(net "SPI_PEX3_SDIO2_R")
	)
	(segment
		(start 365.369094 -242.50015)
		(end 362.379768 -239.510824)
		(width 0.15494)
		(layer "In5.Cu")
		(net "SPI_PEX3_SDIO2_R")
	)
	(segment
		(start 385.43738 -270.675354)
		(end 384.967226 -270.675354)
		(width 0.15494)
		(layer "In5.Cu")
		(net "SPI_PEX3_SDIO2_R")
	)
	(segment
		(start 385.73202 -267.774928)
		(end 385.73202 -270.380714)
		(width 0.15494)
		(layer "In5.Cu")
		(net "SPI_PEX3_SDIO2_R")
	)
	(segment
		(start 384.967226 -270.675354)
		(end 384.840226 -270.548354)
		(width 0.15494)
		(layer "In5.Cu")
		(net "SPI_PEX3_SDIO2_R")
	)
	(segment
		(start 366.749076 -261.712456)
		(end 366.749076 -247.612916)
		(width 0.15494)
		(layer "In5.Cu")
		(net "SPI_PEX3_SDIO2_R")
	)
	(segment
		(start 362.37926 -239.510824)
		(end 361.968034 -239.099598)
		(width 0.15494)
		(layer "In5.Cu")
		(net "SPI_PEX3_SDIO2_R")
	)
	(segment
		(start 384.840226 -268.351)
		(end 384.705606 -268.21638)
		(width 0.15494)
		(layer "In5.Cu")
		(net "SPI_PEX3_SDIO2_R")
	)
	(segment
		(start 365.85144 -242.50015)
		(end 365.369094 -242.50015)
		(width 0.15494)
		(layer "In5.Cu")
		(net "SPI_PEX3_SDIO2_R")
	)
	(segment
		(start 382.551432 -268.08938)
		(end 382.551432 -267.476732)
		(width 0.15494)
		(layer "In5.Cu")
		(net "SPI_PEX3_SDIO2_R")
	)
	(segment
		(start 384.705606 -270.0147)
		(end 383.368296 -270.0147)
		(width 0.15494)
		(layer "In5.Cu")
		(net "SPI_PEX3_SDIO2_R")
	)
	(segment
		(start 361.968034 -239.099598)
		(end 361.968034 -239.09909)
		(width 0.15494)
		(layer "In5.Cu")
		(net "SPI_PEX3_SDIO2_R")
	)
	(segment
		(start 383.368296 -269.11554)
		(end 384.705606 -269.11554)
		(width 0.15494)
		(layer "In5.Cu")
		(net "SPI_PEX3_SDIO2_R")
	)
	(segment
		(start 383.233676 -269.88008)
		(end 383.233676 -269.25016)
		(width 0.15494)
		(layer "In5.Cu")
		(net "SPI_PEX3_SDIO2_R")
	)
	(segment
		(start 385.73202 -270.380714)
		(end 385.43738 -270.675354)
		(width 0.15494)
		(layer "In5.Cu")
		(net "SPI_PEX3_SDIO2_R")
	)
	(segment
		(start 366.24895 -242.89766)
		(end 365.85144 -242.50015)
		(width 0.15494)
		(layer "In5.Cu")
		(net "SPI_PEX3_SDIO2_R")
	)
	(segment
		(start 361.923838 -239.054894)
		(end 361.923838 -237.941358)
		(width 0.15494)
		(layer "In5.Cu")
		(net "SPI_PEX3_SDIO2_R")
	)
	(segment
		(start 382.551432 -267.476732)
		(end 382.710944 -267.31722)
		(width 0.15494)
		(layer "In5.Cu")
		(net "SPI_PEX3_SDIO2_R")
	)
	(segment
		(start 366.24895 -247.11279)
		(end 366.24895 -242.89766)
		(width 0.15494)
		(layer "In5.Cu")
		(net "SPI_PEX3_SDIO2_R")
	)
	(segment
		(start 384.494024 -266.071604)
		(end 381.715518 -266.071604)
		(width 0.15494)
		(layer "In5.Cu")
		(net "SPI_PEX3_SDIO2_R")
	)
	(segment
		(start 384.840226 -268.98092)
		(end 384.840226 -268.351)
		(width 0.15494)
		(layer "In5.Cu")
		(net "SPI_PEX3_SDIO2_R")
	)
	(segment
		(start 384.840226 -267.1826)
		(end 384.840226 -266.417806)
		(width 0.15494)
		(layer "In5.Cu")
		(net "SPI_PEX3_SDIO2_R")
	)
	(segment
		(start 385.53517 -267.578078)
		(end 385.73202 -267.774928)
		(width 0.15494)
		(layer "In5.Cu")
		(net "SPI_PEX3_SDIO2_R")
	)
	(via
		(at 363.196378 -237.997492)
		(size 0.508)
		(drill 0.254)
		(layers "F.Cu" "B.Cu")
		(net "SPI_PEX3_CS_R_N")
	)
	(via
		(at 389.012684 -269.943326)
		(size 0.508)
		(drill 0.254)
		(layers "F.Cu" "B.Cu")
		(net "SPI_PEX3_CS_R_N")
	)
	(segment
		(start 388.751572 -281.671776)
		(end 388.350506 -281.671776)
		(width 0.13208)
		(layer "B.Cu")
		(net "SPI_PEX3_CS_R_N")
	)
	(segment
		(start 389.032242 -281.391106)
		(end 388.751572 -281.671776)
		(width 0.13208)
		(layer "B.Cu")
		(net "SPI_PEX3_CS_R_N")
	)
	(segment
		(start 387.978396 -282.043886)
		(end 387.978396 -287.403286)
		(width 0.13208)
		(layer "B.Cu")
		(net "SPI_PEX3_CS_R_N")
	)
	(segment
		(start 366.430814 -233.135932)
		(end 366.430814 -229.827582)
		(width 0.13208)
		(layer "B.Cu")
		(net "SPI_PEX3_CS_R_N")
	)
	(segment
		(start 364.89005 -236.30382)
		(end 364.89005 -234.676696)
		(width 0.13208)
		(layer "B.Cu")
		(net "SPI_PEX3_CS_R_N")
	)
	(segment
		(start 363.196378 -237.997492)
		(end 364.89005 -236.30382)
		(width 0.13208)
		(layer "B.Cu")
		(net "SPI_PEX3_CS_R_N")
	)
	(segment
		(start 388.350506 -281.671776)
		(end 387.978396 -282.043886)
		(width 0.13208)
		(layer "B.Cu")
		(net "SPI_PEX3_CS_R_N")
	)
	(segment
		(start 389.032242 -269.962884)
		(end 389.032242 -281.391106)
		(width 0.13208)
		(layer "B.Cu")
		(net "SPI_PEX3_CS_R_N")
	)
	(segment
		(start 387.978396 -287.403286)
		(end 388.949946 -288.374836)
		(width 0.13208)
		(layer "B.Cu")
		(net "SPI_PEX3_CS_R_N")
	)
	(segment
		(start 389.012684 -269.943326)
		(end 389.032242 -269.962884)
		(width 0.13208)
		(layer "B.Cu")
		(net "SPI_PEX3_CS_R_N")
	)
	(segment
		(start 364.89005 -234.676696)
		(end 366.430814 -233.135932)
		(width 0.13208)
		(layer "B.Cu")
		(net "SPI_PEX3_CS_R_N")
	)
	(segment
		(start 389.012684 -269.943326)
		(end 393.466066 -269.943326)
		(width 0.15494)
		(layer "In5.Cu")
		(net "SPI_PEX3_CS_R_N")
	)
	(segment
		(start 366.78489 -246.890794)
		(end 366.78489 -241.58575)
		(width 0.15494)
		(layer "In5.Cu")
		(net "SPI_PEX3_CS_R_N")
	)
	(segment
		(start 393.623038 -270.100298)
		(end 393.623038 -270.88338)
		(width 0.15494)
		(layer "In5.Cu")
		(net "SPI_PEX3_CS_R_N")
	)
	(segment
		(start 367.285016 -261.49046)
		(end 367.285016 -247.39092)
		(width 0.15494)
		(layer "In5.Cu")
		(net "SPI_PEX3_CS_R_N")
	)
	(segment
		(start 386.26796 -270.66748)
		(end 386.26796 -267.066268)
		(width 0.15494)
		(layer "In5.Cu")
		(net "SPI_PEX3_CS_R_N")
	)
	(segment
		(start 367.285016 -247.39092)
		(end 366.78489 -246.890794)
		(width 0.15494)
		(layer "In5.Cu")
		(net "SPI_PEX3_CS_R_N")
	)
	(segment
		(start 386.659882 -271.059402)
		(end 386.26796 -270.66748)
		(width 0.15494)
		(layer "In5.Cu")
		(net "SPI_PEX3_CS_R_N")
	)
	(segment
		(start 384.737356 -265.535664)
		(end 371.33022 -265.535664)
		(width 0.15494)
		(layer "In5.Cu")
		(net "SPI_PEX3_CS_R_N")
	)
	(segment
		(start 366.78489 -241.58575)
		(end 363.196378 -237.997492)
		(width 0.15494)
		(layer "In5.Cu")
		(net "SPI_PEX3_CS_R_N")
	)
	(segment
		(start 393.447016 -271.059402)
		(end 386.659882 -271.059402)
		(width 0.15494)
		(layer "In5.Cu")
		(net "SPI_PEX3_CS_R_N")
	)
	(segment
		(start 371.33022 -265.535664)
		(end 367.285016 -261.49046)
		(width 0.15494)
		(layer "In5.Cu")
		(net "SPI_PEX3_CS_R_N")
	)
	(segment
		(start 386.26796 -267.066268)
		(end 384.737356 -265.535664)
		(width 0.15494)
		(layer "In5.Cu")
		(net "SPI_PEX3_CS_R_N")
	)
	(segment
		(start 393.623038 -270.88338)
		(end 393.447016 -271.059402)
		(width 0.15494)
		(layer "In5.Cu")
		(net "SPI_PEX3_CS_R_N")
	)
	(segment
		(start 393.466066 -269.943326)
		(end 393.623038 -270.100298)
		(width 0.15494)
		(layer "In5.Cu")
		(net "SPI_PEX3_CS_R_N")
	)
	(via
		(at 368.970814 -225.560382)
		(size 0.508)
		(drill 0.254)
		(layers "F.Cu" "B.Cu")
		(net "SPI_PEX3_SDIO0_R")
	)
	(via
		(at 386.613146 -263.022334)
		(size 0.508)
		(drill 0.254)
		(layers "F.Cu" "B.Cu")
		(net "SPI_PEX3_SDIO0_R")
	)
	(segment
		(start 384.317748 -293.1287)
		(end 385.872482 -293.1287)
		(width 0.13208)
		(layer "B.Cu")
		(net "SPI_PEX3_SDIO0_R")
	)
	(segment
		(start 384.350006 -267.716508)
		(end 384.350006 -273.733768)
		(width 0.13208)
		(layer "B.Cu")
		(net "SPI_PEX3_SDIO0_R")
	)
	(segment
		(start 386.11556 -293.371778)
		(end 386.11556 -293.670736)
		(width 0.13208)
		(layer "B.Cu")
		(net "SPI_PEX3_SDIO0_R")
	)
	(segment
		(start 385.872482 -293.1287)
		(end 386.11556 -293.371778)
		(width 0.13208)
		(layer "B.Cu")
		(net "SPI_PEX3_SDIO0_R")
	)
	(segment
		(start 387.18109 -294.321484)
		(end 387.18109 -294.905684)
		(width 0.13208)
		(layer "B.Cu")
		(net "SPI_PEX3_SDIO0_R")
	)
	(segment
		(start 386.449316 -294.004492)
		(end 386.864098 -294.004492)
		(width 0.13208)
		(layer "B.Cu")
		(net "SPI_PEX3_SDIO0_R")
	)
	(segment
		(start 386.864098 -294.004492)
		(end 387.18109 -294.321484)
		(width 0.13208)
		(layer "B.Cu")
		(net "SPI_PEX3_SDIO0_R")
	)
	(segment
		(start 387.18109 -294.905684)
		(end 388.073646 -295.79824)
		(width 0.13208)
		(layer "B.Cu")
		(net "SPI_PEX3_SDIO0_R")
	)
	(segment
		(start 383.530602 -292.341554)
		(end 384.317748 -293.1287)
		(width 0.13208)
		(layer "B.Cu")
		(net "SPI_PEX3_SDIO0_R")
	)
	(segment
		(start 387.364732 -264.701782)
		(end 384.350006 -267.716508)
		(width 0.13208)
		(layer "B.Cu")
		(net "SPI_PEX3_SDIO0_R")
	)
	(segment
		(start 383.530602 -274.553172)
		(end 383.530602 -292.341554)
		(width 0.13208)
		(layer "B.Cu")
		(net "SPI_PEX3_SDIO0_R")
	)
	(segment
		(start 368.970814 -225.560382)
		(end 368.970814 -224.341182)
		(width 0.13208)
		(layer "B.Cu")
		(net "SPI_PEX3_SDIO0_R")
	)
	(segment
		(start 386.613146 -263.022334)
		(end 387.240018 -263.022334)
		(width 0.13208)
		(layer "B.Cu")
		(net "SPI_PEX3_SDIO0_R")
	)
	(segment
		(start 384.350006 -273.733768)
		(end 383.530602 -274.553172)
		(width 0.13208)
		(layer "B.Cu")
		(net "SPI_PEX3_SDIO0_R")
	)
	(segment
		(start 387.240018 -263.022334)
		(end 387.364732 -263.147048)
		(width 0.13208)
		(layer "B.Cu")
		(net "SPI_PEX3_SDIO0_R")
	)
	(segment
		(start 386.11556 -293.670736)
		(end 386.449316 -294.004492)
		(width 0.13208)
		(layer "B.Cu")
		(net "SPI_PEX3_SDIO0_R")
	)
	(segment
		(start 387.364732 -263.147048)
		(end 387.364732 -264.701782)
		(width 0.13208)
		(layer "B.Cu")
		(net "SPI_PEX3_SDIO0_R")
	)
	(segment
		(start 370.586762 -229.527608)
		(end 371.462046 -228.652324)
		(width 0.15494)
		(layer "In5.Cu")
		(net "SPI_PEX3_SDIO0_R")
	)
	(segment
		(start 383.350516 -262.405368)
		(end 383.215896 -262.539988)
		(width 0.15494)
		(layer "In5.Cu")
		(net "SPI_PEX3_SDIO0_R")
	)
	(segment
		(start 370.463572 -226.795076)
		(end 369.923568 -226.795076)
		(width 0.15494)
		(layer "In5.Cu")
		(net "SPI_PEX3_SDIO0_R")
	)
	(segment
		(start 376.248676 -263.485122)
		(end 376.11558 -263.618218)
		(width 0.15494)
		(layer "In5.Cu")
		(net "SPI_PEX3_SDIO0_R")
	)
	(segment
		(start 369.923568 -226.795076)
		(end 368.970814 -225.842322)
		(width 0.15494)
		(layer "In5.Cu")
		(net "SPI_PEX3_SDIO0_R")
	)
	(segment
		(start 370.586762 -241.682778)
		(end 370.586762 -229.527608)
		(width 0.15494)
		(layer "In5.Cu")
		(net "SPI_PEX3_SDIO0_R")
	)
	(segment
		(start 386.2578 -263.37768)
		(end 384.242056 -263.37768)
		(width 0.15494)
		(layer "In5.Cu")
		(net "SPI_PEX3_SDIO0_R")
	)
	(segment
		(start 372.046246 -263.618218)
		(end 369.146836 -260.718808)
		(width 0.15494)
		(layer "In5.Cu")
		(net "SPI_PEX3_SDIO0_R")
	)
	(segment
		(start 368.970814 -225.842322)
		(end 368.970814 -225.560382)
		(width 0.15494)
		(layer "In5.Cu")
		(net "SPI_PEX3_SDIO0_R")
	)
	(segment
		(start 383.071116 -263.485122)
		(end 376.248676 -263.485122)
		(width 0.15494)
		(layer "In5.Cu")
		(net "SPI_PEX3_SDIO0_R")
	)
	(segment
		(start 371.462046 -228.652324)
		(end 371.462046 -227.79355)
		(width 0.15494)
		(layer "In5.Cu")
		(net "SPI_PEX3_SDIO0_R")
	)
	(segment
		(start 376.11558 -263.618218)
		(end 372.046246 -263.618218)
		(width 0.15494)
		(layer "In5.Cu")
		(net "SPI_PEX3_SDIO0_R")
	)
	(segment
		(start 383.980436 -262.405368)
		(end 383.350516 -262.405368)
		(width 0.15494)
		(layer "In5.Cu")
		(net "SPI_PEX3_SDIO0_R")
	)
	(segment
		(start 384.115056 -262.539988)
		(end 383.980436 -262.405368)
		(width 0.15494)
		(layer "In5.Cu")
		(net "SPI_PEX3_SDIO0_R")
	)
	(segment
		(start 384.115056 -263.25068)
		(end 384.115056 -262.539988)
		(width 0.15494)
		(layer "In5.Cu")
		(net "SPI_PEX3_SDIO0_R")
	)
	(segment
		(start 383.215896 -262.539988)
		(end 383.215896 -263.340342)
		(width 0.15494)
		(layer "In5.Cu")
		(net "SPI_PEX3_SDIO0_R")
	)
	(segment
		(start 369.146836 -260.718808)
		(end 369.146836 -243.122704)
		(width 0.15494)
		(layer "In5.Cu")
		(net "SPI_PEX3_SDIO0_R")
	)
	(segment
		(start 383.215896 -263.340342)
		(end 383.071116 -263.485122)
		(width 0.15494)
		(layer "In5.Cu")
		(net "SPI_PEX3_SDIO0_R")
	)
	(segment
		(start 371.462046 -227.79355)
		(end 370.463572 -226.795076)
		(width 0.15494)
		(layer "In5.Cu")
		(net "SPI_PEX3_SDIO0_R")
	)
	(segment
		(start 386.613146 -263.022334)
		(end 386.2578 -263.37768)
		(width 0.15494)
		(layer "In5.Cu")
		(net "SPI_PEX3_SDIO0_R")
	)
	(segment
		(start 384.242056 -263.37768)
		(end 384.115056 -263.25068)
		(width 0.15494)
		(layer "In5.Cu")
		(net "SPI_PEX3_SDIO0_R")
	)
	(segment
		(start 369.146836 -243.122704)
		(end 370.586762 -241.682778)
		(width 0.15494)
		(layer "In5.Cu")
		(net "SPI_PEX3_SDIO0_R")
	)
	(via
		(at 371.447314 -226.776788)
		(size 0.6604)
		(drill 0.3302)
		(layers "F.Cu" "B.Cu")
		(net "SPI_PEX3_SDIO1_MUX")
	)
	(segment
		(start 368.335814 -224.341182)
		(end 368.335814 -225.242882)
		(width 0.13208)
		(layer "B.Cu")
		(net "SPI_PEX3_SDIO1_MUX")
	)
	(segment
		(start 370.011198 -226.776788)
		(end 371.447314 -226.776788)
		(width 0.13208)
		(layer "B.Cu")
		(net "SPI_PEX3_SDIO1_MUX")
	)
	(segment
		(start 369.794282 -226.559872)
		(end 370.011198 -226.776788)
		(width 0.13208)
		(layer "B.Cu")
		(net "SPI_PEX3_SDIO1_MUX")
	)
	(segment
		(start 368.76736 -226.559872)
		(end 369.794282 -226.559872)
		(width 0.13208)
		(layer "B.Cu")
		(net "SPI_PEX3_SDIO1_MUX")
	)
	(segment
		(start 368.249962 -225.328734)
		(end 368.249962 -226.042474)
		(width 0.13208)
		(layer "B.Cu")
		(net "SPI_PEX3_SDIO1_MUX")
	)
	(segment
		(start 371.475 -226.804474)
		(end 371.475 -227.94595)
		(width 0.13208)
		(layer "B.Cu")
		(net "SPI_PEX3_SDIO1_MUX")
	)
	(segment
		(start 371.447314 -226.776788)
		(end 371.475 -226.804474)
		(width 0.13208)
		(layer "B.Cu")
		(net "SPI_PEX3_SDIO1_MUX")
	)
	(segment
		(start 368.335814 -225.242882)
		(end 368.249962 -225.328734)
		(width 0.13208)
		(layer "B.Cu")
		(net "SPI_PEX3_SDIO1_MUX")
	)
	(segment
		(start 368.249962 -226.042474)
		(end 368.76736 -226.559872)
		(width 0.13208)
		(layer "B.Cu")
		(net "SPI_PEX3_SDIO1_MUX")
	)
	(via
		(at 363.275118 -223.561148)
		(size 0.6604)
		(drill 0.3302)
		(layers "F.Cu" "B.Cu")
		(net "SPI_PEX3_CLK_MUX")
	)
	(segment
		(start 369.156488 -227.39604)
		(end 369.605814 -227.845366)
		(width 0.13208)
		(layer "B.Cu")
		(net "SPI_PEX3_CLK_MUX")
	)
	(segment
		(start 363.275118 -225.630232)
		(end 364.193582 -226.548696)
		(width 0.13208)
		(layer "B.Cu")
		(net "SPI_PEX3_CLK_MUX")
	)
	(segment
		(start 363.275118 -222.040958)
		(end 363.275118 -223.561148)
		(width 0.13208)
		(layer "B.Cu")
		(net "SPI_PEX3_CLK_MUX")
	)
	(segment
		(start 369.605814 -227.845366)
		(end 369.605814 -229.827582)
		(width 0.13208)
		(layer "B.Cu")
		(net "SPI_PEX3_CLK_MUX")
	)
	(segment
		(start 364.193582 -226.548696)
		(end 364.787688 -226.548696)
		(width 0.13208)
		(layer "B.Cu")
		(net "SPI_PEX3_CLK_MUX")
	)
	(segment
		(start 364.787688 -226.548696)
		(end 365.635032 -227.39604)
		(width 0.13208)
		(layer "B.Cu")
		(net "SPI_PEX3_CLK_MUX")
	)
	(segment
		(start 363.275118 -223.561148)
		(end 363.275118 -225.630232)
		(width 0.13208)
		(layer "B.Cu")
		(net "SPI_PEX3_CLK_MUX")
	)
	(segment
		(start 365.635032 -227.39604)
		(end 369.156488 -227.39604)
		(width 0.13208)
		(layer "B.Cu")
		(net "SPI_PEX3_CLK_MUX")
	)
	(via
		(at 372.747032 -229.97287)
		(size 0.6604)
		(drill 0.3302)
		(layers "F.Cu" "B.Cu")
		(net "SPI_PEX3_CS_MUX_N")
	)
	(segment
		(start 367.952782 -231.074468)
		(end 371.645434 -231.074468)
		(width 0.13208)
		(layer "B.Cu")
		(net "SPI_PEX3_CS_MUX_N")
	)
	(segment
		(start 372.48211 -229.707948)
		(end 372.48211 -228.74605)
		(width 0.13208)
		(layer "B.Cu")
		(net "SPI_PEX3_CS_MUX_N")
	)
	(segment
		(start 372.747032 -229.97287)
		(end 372.48211 -229.707948)
		(width 0.13208)
		(layer "B.Cu")
		(net "SPI_PEX3_CS_MUX_N")
	)
	(segment
		(start 367.700814 -230.8225)
		(end 367.952782 -231.074468)
		(width 0.13208)
		(layer "B.Cu")
		(net "SPI_PEX3_CS_MUX_N")
	)
	(segment
		(start 367.700814 -229.827582)
		(end 367.700814 -230.8225)
		(width 0.13208)
		(layer "B.Cu")
		(net "SPI_PEX3_CS_MUX_N")
	)
	(segment
		(start 371.645434 -231.074468)
		(end 372.747032 -229.97287)
		(width 0.13208)
		(layer "B.Cu")
		(net "SPI_PEX3_CS_MUX_N")
	)
	(via
		(at 371.122702 -221.332806)
		(size 0.508)
		(drill 0.254)
		(layers "F.Cu" "B.Cu")
		(net "SPI_PEX3_SDIO3_R")
	)
	(via
		(at 389.114538 -265.737848)
		(size 0.508)
		(drill 0.254)
		(layers "F.Cu" "B.Cu")
		(net "SPI_PEX3_SDIO3_R")
	)
	(segment
		(start 387.06298 -287.43783)
		(end 387.999986 -288.374836)
		(width 0.13208)
		(layer "B.Cu")
		(net "SPI_PEX3_SDIO3_R")
	)
	(segment
		(start 388.291324 -266.561062)
		(end 388.291324 -268.415516)
		(width 0.13208)
		(layer "B.Cu")
		(net "SPI_PEX3_SDIO3_R")
	)
	(segment
		(start 388.009384 -280.458672)
		(end 387.808724 -280.659332)
		(width 0.13208)
		(layer "B.Cu")
		(net "SPI_PEX3_SDIO3_R")
	)
	(segment
		(start 371.122702 -221.332806)
		(end 372.38305 -221.332806)
		(width 0.13208)
		(layer "B.Cu")
		(net "SPI_PEX3_SDIO3_R")
	)
	(segment
		(start 388.009384 -268.697456)
		(end 388.009384 -280.458672)
		(width 0.13208)
		(layer "B.Cu")
		(net "SPI_PEX3_SDIO3_R")
	)
	(segment
		(start 387.437884 -280.659332)
		(end 387.06298 -281.034236)
		(width 0.13208)
		(layer "B.Cu")
		(net "SPI_PEX3_SDIO3_R")
	)
	(segment
		(start 387.06298 -281.034236)
		(end 387.06298 -287.43783)
		(width 0.13208)
		(layer "B.Cu")
		(net "SPI_PEX3_SDIO3_R")
	)
	(segment
		(start 388.291324 -268.415516)
		(end 388.009384 -268.697456)
		(width 0.13208)
		(layer "B.Cu")
		(net "SPI_PEX3_SDIO3_R")
	)
	(segment
		(start 387.808724 -280.659332)
		(end 387.437884 -280.659332)
		(width 0.13208)
		(layer "B.Cu")
		(net "SPI_PEX3_SDIO3_R")
	)
	(segment
		(start 389.114538 -265.737848)
		(end 388.291324 -266.561062)
		(width 0.13208)
		(layer "B.Cu")
		(net "SPI_PEX3_SDIO3_R")
	)
	(segment
		(start 372.55577 -239.044988)
		(end 372.55577 -239.674908)
		(width 0.15494)
		(layer "In5.Cu")
		(net "SPI_PEX3_SDIO3_R")
	)
	(segment
		(start 372.69039 -242.507008)
		(end 372.55577 -242.641628)
		(width 0.15494)
		(layer "In5.Cu")
		(net "SPI_PEX3_SDIO3_R")
	)
	(segment
		(start 374.127268 -240.574068)
		(end 373.992648 -240.708688)
		(width 0.15494)
		(layer "In5.Cu")
		(net "SPI_PEX3_SDIO3_R")
	)
	(segment
		(start 373.992648 -238.910368)
		(end 372.69039 -238.910368)
		(width 0.15494)
		(layer "In5.Cu")
		(net "SPI_PEX3_SDIO3_R")
	)
	(segment
		(start 380.629414 -260.606286)
		(end 381.119126 -261.095998)
		(width 0.15494)
		(layer "In5.Cu")
		(net "SPI_PEX3_SDIO3_R")
	)
	(segment
		(start 372.55577 -243.271548)
		(end 372.69039 -243.406168)
		(width 0.15494)
		(layer "In5.Cu")
		(net "SPI_PEX3_SDIO3_R")
	)
	(segment
		(start 372.55577 -242.641628)
		(end 372.55577 -243.271548)
		(width 0.15494)
		(layer "In5.Cu")
		(net "SPI_PEX3_SDIO3_R")
	)
	(segment
		(start 372.16715 -235.969302)
		(end 372.410736 -236.212888)
		(width 0.15494)
		(layer "In5.Cu")
		(net "SPI_PEX3_SDIO3_R")
	)
	(segment
		(start 373.992648 -236.212888)
		(end 374.127268 -236.347508)
		(width 0.15494)
		(layer "In5.Cu")
		(net "SPI_PEX3_SDIO3_R")
	)
	(segment
		(start 371.520466 -250.813062)
		(end 371.520466 -253.62281)
		(width 0.15494)
		(layer "In5.Cu")
		(net "SPI_PEX3_SDIO3_R")
	)
	(segment
		(start 385.925314 -261.095998)
		(end 388.387336 -263.55802)
		(width 0.15494)
		(layer "In5.Cu")
		(net "SPI_PEX3_SDIO3_R")
	)
	(segment
		(start 374.127268 -243.540788)
		(end 374.127268 -244.170708)
		(width 0.15494)
		(layer "In5.Cu")
		(net "SPI_PEX3_SDIO3_R")
	)
	(segment
		(start 372.55577 -241.473228)
		(end 372.69039 -241.607848)
		(width 0.15494)
		(layer "In5.Cu")
		(net "SPI_PEX3_SDIO3_R")
	)
	(segment
		(start 374.127268 -242.372388)
		(end 373.992648 -242.507008)
		(width 0.15494)
		(layer "In5.Cu")
		(net "SPI_PEX3_SDIO3_R")
	)
	(segment
		(start 373.992648 -237.112048)
		(end 372.69039 -237.112048)
		(width 0.15494)
		(layer "In5.Cu")
		(net "SPI_PEX3_SDIO3_R")
	)
	(segment
		(start 372.16715 -233.265218)
		(end 372.16715 -235.969302)
		(width 0.15494)
		(layer "In5.Cu")
		(net "SPI_PEX3_SDIO3_R")
	)
	(segment
		(start 373.992648 -240.708688)
		(end 372.69039 -240.708688)
		(width 0.15494)
		(layer "In5.Cu")
		(net "SPI_PEX3_SDIO3_R")
	)
	(segment
		(start 373.992648 -241.607848)
		(end 374.127268 -241.742468)
		(width 0.15494)
		(layer "In5.Cu")
		(net "SPI_PEX3_SDIO3_R")
	)
	(segment
		(start 376.217434 -260.874002)
		(end 376.884946 -260.874002)
		(width 0.15494)
		(layer "In5.Cu")
		(net "SPI_PEX3_SDIO3_R")
	)
	(segment
		(start 372.69039 -240.708688)
		(end 372.55577 -240.843308)
		(width 0.15494)
		(layer "In5.Cu")
		(net "SPI_PEX3_SDIO3_R")
	)
	(segment
		(start 371.520466 -253.62281)
		(end 373.17172 -255.274064)
		(width 0.15494)
		(layer "In5.Cu")
		(net "SPI_PEX3_SDIO3_R")
	)
	(segment
		(start 372.69039 -244.305328)
		(end 371.315488 -245.68023)
		(width 0.15494)
		(layer "In5.Cu")
		(net "SPI_PEX3_SDIO3_R")
	)
	(segment
		(start 374.127268 -238.775748)
		(end 373.992648 -238.910368)
		(width 0.15494)
		(layer "In5.Cu")
		(net "SPI_PEX3_SDIO3_R")
	)
	(segment
		(start 372.69039 -243.406168)
		(end 373.992648 -243.406168)
		(width 0.15494)
		(layer "In5.Cu")
		(net "SPI_PEX3_SDIO3_R")
	)
	(segment
		(start 372.55577 -237.246668)
		(end 372.55577 -237.876588)
		(width 0.15494)
		(layer "In5.Cu")
		(net "SPI_PEX3_SDIO3_R")
	)
	(segment
		(start 370.867686 -248.521728)
		(end 370.867686 -250.160282)
		(width 0.15494)
		(layer "In5.Cu")
		(net "SPI_PEX3_SDIO3_R")
	)
	(segment
		(start 388.387336 -265.010646)
		(end 389.114538 -265.737848)
		(width 0.15494)
		(layer "In5.Cu")
		(net "SPI_PEX3_SDIO3_R")
	)
	(segment
		(start 373.992648 -243.406168)
		(end 374.127268 -243.540788)
		(width 0.15494)
		(layer "In5.Cu")
		(net "SPI_PEX3_SDIO3_R")
	)
	(segment
		(start 371.837712 -221.332806)
		(end 372.377462 -221.872556)
		(width 0.15494)
		(layer "In5.Cu")
		(net "SPI_PEX3_SDIO3_R")
	)
	(segment
		(start 375.554748 -260.211316)
		(end 376.217434 -260.874002)
		(width 0.15494)
		(layer "In5.Cu")
		(net "SPI_PEX3_SDIO3_R")
	)
	(segment
		(start 374.127268 -236.977428)
		(end 373.992648 -237.112048)
		(width 0.15494)
		(layer "In5.Cu")
		(net "SPI_PEX3_SDIO3_R")
	)
	(segment
		(start 376.884946 -260.874002)
		(end 377.152662 -260.606286)
		(width 0.15494)
		(layer "In5.Cu")
		(net "SPI_PEX3_SDIO3_R")
	)
	(segment
		(start 371.315488 -248.073926)
		(end 370.867686 -248.521728)
		(width 0.15494)
		(layer "In5.Cu")
		(net "SPI_PEX3_SDIO3_R")
	)
	(segment
		(start 373.992648 -239.809528)
		(end 374.127268 -239.944148)
		(width 0.15494)
		(layer "In5.Cu")
		(net "SPI_PEX3_SDIO3_R")
	)
	(segment
		(start 375.554748 -260.112256)
		(end 375.554748 -260.211316)
		(width 0.15494)
		(layer "In5.Cu")
		(net "SPI_PEX3_SDIO3_R")
	)
	(segment
		(start 372.55577 -239.674908)
		(end 372.69039 -239.809528)
		(width 0.15494)
		(layer "In5.Cu")
		(net "SPI_PEX3_SDIO3_R")
	)
	(segment
		(start 372.69039 -239.809528)
		(end 373.992648 -239.809528)
		(width 0.15494)
		(layer "In5.Cu")
		(net "SPI_PEX3_SDIO3_R")
	)
	(segment
		(start 377.152662 -260.606286)
		(end 380.629414 -260.606286)
		(width 0.15494)
		(layer "In5.Cu")
		(net "SPI_PEX3_SDIO3_R")
	)
	(segment
		(start 372.410736 -236.212888)
		(end 373.992648 -236.212888)
		(width 0.15494)
		(layer "In5.Cu")
		(net "SPI_PEX3_SDIO3_R")
	)
	(segment
		(start 371.122702 -221.332806)
		(end 371.837712 -221.332806)
		(width 0.15494)
		(layer "In5.Cu")
		(net "SPI_PEX3_SDIO3_R")
	)
	(segment
		(start 373.992648 -244.305328)
		(end 372.69039 -244.305328)
		(width 0.15494)
		(layer "In5.Cu")
		(net "SPI_PEX3_SDIO3_R")
	)
	(segment
		(start 370.867686 -250.160282)
		(end 371.520466 -250.813062)
		(width 0.15494)
		(layer "In5.Cu")
		(net "SPI_PEX3_SDIO3_R")
	)
	(segment
		(start 372.69039 -237.112048)
		(end 372.55577 -237.246668)
		(width 0.15494)
		(layer "In5.Cu")
		(net "SPI_PEX3_SDIO3_R")
	)
	(segment
		(start 372.55577 -237.876588)
		(end 372.69039 -238.011208)
		(width 0.15494)
		(layer "In5.Cu")
		(net "SPI_PEX3_SDIO3_R")
	)
	(segment
		(start 372.69039 -238.011208)
		(end 373.992648 -238.011208)
		(width 0.15494)
		(layer "In5.Cu")
		(net "SPI_PEX3_SDIO3_R")
	)
	(segment
		(start 381.119126 -261.095998)
		(end 385.925314 -261.095998)
		(width 0.15494)
		(layer "In5.Cu")
		(net "SPI_PEX3_SDIO3_R")
	)
	(segment
		(start 374.127268 -239.944148)
		(end 374.127268 -240.574068)
		(width 0.15494)
		(layer "In5.Cu")
		(net "SPI_PEX3_SDIO3_R")
	)
	(segment
		(start 374.127268 -244.170708)
		(end 373.992648 -244.305328)
		(width 0.15494)
		(layer "In5.Cu")
		(net "SPI_PEX3_SDIO3_R")
	)
	(segment
		(start 373.992648 -238.011208)
		(end 374.127268 -238.145828)
		(width 0.15494)
		(layer "In5.Cu")
		(net "SPI_PEX3_SDIO3_R")
	)
	(segment
		(start 372.377462 -221.872556)
		(end 372.377462 -233.054906)
		(width 0.15494)
		(layer "In5.Cu")
		(net "SPI_PEX3_SDIO3_R")
	)
	(segment
		(start 374.127268 -236.347508)
		(end 374.127268 -236.977428)
		(width 0.15494)
		(layer "In5.Cu")
		(net "SPI_PEX3_SDIO3_R")
	)
	(segment
		(start 372.55577 -240.843308)
		(end 372.55577 -241.473228)
		(width 0.15494)
		(layer "In5.Cu")
		(net "SPI_PEX3_SDIO3_R")
	)
	(segment
		(start 373.17172 -257.729228)
		(end 375.554748 -260.112256)
		(width 0.15494)
		(layer "In5.Cu")
		(net "SPI_PEX3_SDIO3_R")
	)
	(segment
		(start 374.127268 -238.145828)
		(end 374.127268 -238.775748)
		(width 0.15494)
		(layer "In5.Cu")
		(net "SPI_PEX3_SDIO3_R")
	)
	(segment
		(start 388.387336 -263.55802)
		(end 388.387336 -265.010646)
		(width 0.15494)
		(layer "In5.Cu")
		(net "SPI_PEX3_SDIO3_R")
	)
	(segment
		(start 374.127268 -241.742468)
		(end 374.127268 -242.372388)
		(width 0.15494)
		(layer "In5.Cu")
		(net "SPI_PEX3_SDIO3_R")
	)
	(segment
		(start 373.992648 -242.507008)
		(end 372.69039 -242.507008)
		(width 0.15494)
		(layer "In5.Cu")
		(net "SPI_PEX3_SDIO3_R")
	)
	(segment
		(start 372.69039 -238.910368)
		(end 372.55577 -239.044988)
		(width 0.15494)
		(layer "In5.Cu")
		(net "SPI_PEX3_SDIO3_R")
	)
	(segment
		(start 371.315488 -245.68023)
		(end 371.315488 -248.073926)
		(width 0.15494)
		(layer "In5.Cu")
		(net "SPI_PEX3_SDIO3_R")
	)
	(segment
		(start 372.69039 -241.607848)
		(end 373.992648 -241.607848)
		(width 0.15494)
		(layer "In5.Cu")
		(net "SPI_PEX3_SDIO3_R")
	)
	(segment
		(start 372.377462 -233.054906)
		(end 372.16715 -233.265218)
		(width 0.15494)
		(layer "In5.Cu")
		(net "SPI_PEX3_SDIO3_R")
	)
	(segment
		(start 373.17172 -255.274064)
		(end 373.17172 -257.729228)
		(width 0.15494)
		(layer "In5.Cu")
		(net "SPI_PEX3_SDIO3_R")
	)
	(via
		(at 370.122196 -222.214186)
		(size 0.6604)
		(drill 0.3302)
		(layers "F.Cu" "B.Cu")
		(net "SPI_PEX3_SDIO0_MUX")
	)
	(segment
		(start 370.466874 -222.558864)
		(end 370.122196 -222.214186)
		(width 0.13208)
		(layer "B.Cu")
		(net "SPI_PEX3_SDIO0_MUX")
	)
	(segment
		(start 370.240814 -223.692212)
		(end 370.466874 -223.466152)
		(width 0.13208)
		(layer "B.Cu")
		(net "SPI_PEX3_SDIO0_MUX")
	)
	(segment
		(start 370.240814 -224.341182)
		(end 370.240814 -223.692212)
		(width 0.13208)
		(layer "B.Cu")
		(net "SPI_PEX3_SDIO0_MUX")
	)
	(segment
		(start 370.466874 -223.466152)
		(end 370.466874 -222.558864)
		(width 0.13208)
		(layer "B.Cu")
		(net "SPI_PEX3_SDIO0_MUX")
	)
	(segment
		(start 370.122196 -222.214186)
		(end 368.338862 -222.214186)
		(width 0.13208)
		(layer "B.Cu")
		(net "SPI_PEX3_SDIO0_MUX")
	)
	(via
		(at 366.070642 -226.557078)
		(size 0.508)
		(drill 0.254)
		(layers "F.Cu" "B.Cu")
		(net "SPI_PEX3_SDIO1_R")
	)
	(via
		(at 386.572506 -264.367772)
		(size 0.508)
		(drill 0.254)
		(layers "F.Cu" "B.Cu")
		(net "SPI_PEX3_SDIO1_R")
	)
	(segment
		(start 385.205478 -294.688768)
		(end 385.205478 -294.264588)
		(width 0.13208)
		(layer "B.Cu")
		(net "SPI_PEX3_SDIO1_R")
	)
	(segment
		(start 384.905504 -293.964614)
		(end 384.446018 -293.964614)
		(width 0.13208)
		(layer "B.Cu")
		(net "SPI_PEX3_SDIO1_R")
	)
	(segment
		(start 387.291072 -296.863262)
		(end 387.06806 -296.64025)
		(width 0.13208)
		(layer "B.Cu")
		(net "SPI_PEX3_SDIO1_R")
	)
	(segment
		(start 383.030222 -274.183348)
		(end 383.828544 -273.385026)
		(width 0.13208)
		(layer "B.Cu")
		(net "SPI_PEX3_SDIO1_R")
	)
	(segment
		(start 385.205478 -294.264588)
		(end 384.905504 -293.964614)
		(width 0.13208)
		(layer "B.Cu")
		(net "SPI_PEX3_SDIO1_R")
	)
	(segment
		(start 384.446018 -293.964614)
		(end 383.030222 -292.548818)
		(width 0.13208)
		(layer "B.Cu")
		(net "SPI_PEX3_SDIO1_R")
	)
	(segment
		(start 367.065814 -224.341182)
		(end 367.065814 -225.561906)
		(width 0.13208)
		(layer "B.Cu")
		(net "SPI_PEX3_SDIO1_R")
	)
	(segment
		(start 388.073646 -296.9514)
		(end 387.985508 -296.863262)
		(width 0.13208)
		(layer "B.Cu")
		(net "SPI_PEX3_SDIO1_R")
	)
	(segment
		(start 367.065814 -225.561906)
		(end 366.070642 -226.557078)
		(width 0.13208)
		(layer "B.Cu")
		(net "SPI_PEX3_SDIO1_R")
	)
	(segment
		(start 385.554474 -295.037764)
		(end 385.205478 -294.688768)
		(width 0.13208)
		(layer "B.Cu")
		(net "SPI_PEX3_SDIO1_R")
	)
	(segment
		(start 385.93776 -295.037764)
		(end 385.554474 -295.037764)
		(width 0.13208)
		(layer "B.Cu")
		(net "SPI_PEX3_SDIO1_R")
	)
	(segment
		(start 387.06806 -296.64025)
		(end 387.06806 -296.168064)
		(width 0.13208)
		(layer "B.Cu")
		(net "SPI_PEX3_SDIO1_R")
	)
	(segment
		(start 387.06806 -296.168064)
		(end 385.93776 -295.037764)
		(width 0.13208)
		(layer "B.Cu")
		(net "SPI_PEX3_SDIO1_R")
	)
	(segment
		(start 387.985508 -296.863262)
		(end 387.291072 -296.863262)
		(width 0.13208)
		(layer "B.Cu")
		(net "SPI_PEX3_SDIO1_R")
	)
	(segment
		(start 383.828544 -273.385026)
		(end 383.828544 -267.111734)
		(width 0.13208)
		(layer "B.Cu")
		(net "SPI_PEX3_SDIO1_R")
	)
	(segment
		(start 383.030222 -292.548818)
		(end 383.030222 -274.183348)
		(width 0.13208)
		(layer "B.Cu")
		(net "SPI_PEX3_SDIO1_R")
	)
	(segment
		(start 383.828544 -267.111734)
		(end 386.572506 -264.367772)
		(width 0.13208)
		(layer "B.Cu")
		(net "SPI_PEX3_SDIO1_R")
	)
	(segment
		(start 369.476274 -228.157786)
		(end 369.476274 -227.712016)
		(width 0.15494)
		(layer "In5.Cu")
		(net "SPI_PEX3_SDIO1_R")
	)
	(segment
		(start 370.050822 -241.460782)
		(end 370.050822 -228.732334)
		(width 0.15494)
		(layer "In5.Cu")
		(net "SPI_PEX3_SDIO1_R")
	)
	(segment
		(start 366.454944 -227.38207)
		(end 366.070642 -226.997768)
		(width 0.15494)
		(layer "In5.Cu")
		(net "SPI_PEX3_SDIO1_R")
	)
	(segment
		(start 369.476274 -227.712016)
		(end 369.146328 -227.38207)
		(width 0.15494)
		(layer "In5.Cu")
		(net "SPI_PEX3_SDIO1_R")
	)
	(segment
		(start 386.572506 -264.367772)
		(end 386.414518 -264.209784)
		(width 0.15494)
		(layer "In5.Cu")
		(net "SPI_PEX3_SDIO1_R")
	)
	(segment
		(start 366.070642 -226.997768)
		(end 366.070642 -226.557078)
		(width 0.15494)
		(layer "In5.Cu")
		(net "SPI_PEX3_SDIO1_R")
	)
	(segment
		(start 368.610896 -260.940804)
		(end 368.610896 -242.900708)
		(width 0.15494)
		(layer "In5.Cu")
		(net "SPI_PEX3_SDIO1_R")
	)
	(segment
		(start 368.610896 -242.900708)
		(end 370.050822 -241.460782)
		(width 0.15494)
		(layer "In5.Cu")
		(net "SPI_PEX3_SDIO1_R")
	)
	(segment
		(start 369.146328 -227.38207)
		(end 366.454944 -227.38207)
		(width 0.15494)
		(layer "In5.Cu")
		(net "SPI_PEX3_SDIO1_R")
	)
	(segment
		(start 371.879876 -264.209784)
		(end 368.610896 -260.940804)
		(width 0.15494)
		(layer "In5.Cu")
		(net "SPI_PEX3_SDIO1_R")
	)
	(segment
		(start 386.414518 -264.209784)
		(end 371.879876 -264.209784)
		(width 0.15494)
		(layer "In5.Cu")
		(net "SPI_PEX3_SDIO1_R")
	)
	(segment
		(start 370.050822 -228.732334)
		(end 369.476274 -228.157786)
		(width 0.15494)
		(layer "In5.Cu")
		(net "SPI_PEX3_SDIO1_R")
	)
	(via
		(at 387.338062 -266.963398)
		(size 0.508)
		(drill 0.254)
		(layers "F.Cu" "B.Cu")
		(net "SPI_PEX3_CLK_R")
	)
	(via
		(at 367.604294 -228.237034)
		(size 0.508)
		(drill 0.254)
		(layers "F.Cu" "B.Cu")
		(net "SPI_PEX3_CLK_R")
	)
	(segment
		(start 387.07695 -279.636728)
		(end 386.88645 -279.827228)
		(width 0.13208)
		(layer "B.Cu")
		(net "SPI_PEX3_CLK_R")
	)
	(segment
		(start 367.828068 -228.460808)
		(end 367.828068 -228.7016)
		(width 0.13208)
		(layer "B.Cu")
		(net "SPI_PEX3_CLK_R")
	)
	(segment
		(start 387.338062 -267.862812)
		(end 387.07695 -268.123924)
		(width 0.13208)
		(layer "B.Cu")
		(net "SPI_PEX3_CLK_R")
	)
	(segment
		(start 387.553454 -291.323014)
		(end 387.95706 -291.72662)
		(width 0.13208)
		(layer "B.Cu")
		(net "SPI_PEX3_CLK_R")
	)
	(segment
		(start 368.335814 -229.209346)
		(end 368.335814 -229.827582)
		(width 0.13208)
		(layer "B.Cu")
		(net "SPI_PEX3_CLK_R")
	)
	(segment
		(start 387.553454 -290.77666)
		(end 387.553454 -291.323014)
		(width 0.13208)
		(layer "B.Cu")
		(net "SPI_PEX3_CLK_R")
	)
	(segment
		(start 386.88645 -279.827228)
		(end 386.365242 -279.827228)
		(width 0.13208)
		(layer "B.Cu")
		(net "SPI_PEX3_CLK_R")
	)
	(segment
		(start 386.081016 -289.881564)
		(end 386.369052 -290.1696)
		(width 0.13208)
		(layer "B.Cu")
		(net "SPI_PEX3_CLK_R")
	)
	(segment
		(start 387.07695 -268.123924)
		(end 387.07695 -279.636728)
		(width 0.13208)
		(layer "B.Cu")
		(net "SPI_PEX3_CLK_R")
	)
	(segment
		(start 387.338062 -266.963398)
		(end 387.338062 -267.862812)
		(width 0.13208)
		(layer "B.Cu")
		(net "SPI_PEX3_CLK_R")
	)
	(segment
		(start 386.081016 -280.111454)
		(end 386.081016 -289.881564)
		(width 0.13208)
		(layer "B.Cu")
		(net "SPI_PEX3_CLK_R")
	)
	(segment
		(start 386.365242 -279.827228)
		(end 386.081016 -280.111454)
		(width 0.13208)
		(layer "B.Cu")
		(net "SPI_PEX3_CLK_R")
	)
	(segment
		(start 367.604294 -228.237034)
		(end 367.828068 -228.460808)
		(width 0.13208)
		(layer "B.Cu")
		(net "SPI_PEX3_CLK_R")
	)
	(segment
		(start 367.828068 -228.7016)
		(end 368.335814 -229.209346)
		(width 0.13208)
		(layer "B.Cu")
		(net "SPI_PEX3_CLK_R")
	)
	(segment
		(start 386.369052 -290.1696)
		(end 386.946394 -290.1696)
		(width 0.13208)
		(layer "B.Cu")
		(net "SPI_PEX3_CLK_R")
	)
	(segment
		(start 386.946394 -290.1696)
		(end 387.553454 -290.77666)
		(width 0.13208)
		(layer "B.Cu")
		(net "SPI_PEX3_CLK_R")
	)
	(segment
		(start 388.122668 -268.334998)
		(end 388.122668 -266.470384)
		(width 0.15494)
		(layer "In5.Cu")
		(net "SPI_PEX3_CLK_R")
	)
	(segment
		(start 385.577842 -265.203178)
		(end 385.247388 -264.872724)
		(width 0.15494)
		(layer "In5.Cu")
		(net "SPI_PEX3_CLK_R")
	)
	(segment
		(start 367.947956 -243.538248)
		(end 367.947956 -242.62588)
		(width 0.15494)
		(layer "In5.Cu")
		(net "SPI_PEX3_CLK_R")
	)
	(segment
		(start 367.613692 -244.572028)
		(end 367.479072 -244.437408)
		(width 0.15494)
		(layer "In5.Cu")
		(net "SPI_PEX3_CLK_R")
	)
	(segment
		(start 371.605048 -264.872724)
		(end 367.947956 -261.215632)
		(width 0.15494)
		(layer "In5.Cu")
		(net "SPI_PEX3_CLK_R")
	)
	(segment
		(start 386.940044 -268.27861)
		(end 387.130544 -268.46911)
		(width 0.15494)
		(layer "In5.Cu")
		(net "SPI_PEX3_CLK_R")
	)
	(segment
		(start 386.58165 -265.820398)
		(end 386.58165 -265.330178)
		(width 0.15494)
		(layer "In5.Cu")
		(net "SPI_PEX3_CLK_R")
	)
	(segment
		(start 367.479072 -243.807488)
		(end 367.613692 -243.672868)
		(width 0.15494)
		(layer "In5.Cu")
		(net "SPI_PEX3_CLK_R")
	)
	(segment
		(start 387.338062 -266.963398)
		(end 387.067044 -266.963398)
		(width 0.15494)
		(layer "In5.Cu")
		(net "SPI_PEX3_CLK_R")
	)
	(segment
		(start 367.613692 -243.672868)
		(end 367.813336 -243.672868)
		(width 0.15494)
		(layer "In5.Cu")
		(net "SPI_PEX3_CLK_R")
	)
	(segment
		(start 367.613692 -246.370348)
		(end 367.479072 -246.235728)
		(width 0.15494)
		(layer "In5.Cu")
		(net "SPI_PEX3_CLK_R")
	)
	(segment
		(start 387.130544 -268.46911)
		(end 387.988556 -268.46911)
		(width 0.15494)
		(layer "In5.Cu")
		(net "SPI_PEX3_CLK_R")
	)
	(segment
		(start 367.947956 -242.62588)
		(end 369.38458 -241.189256)
		(width 0.15494)
		(layer "In5.Cu")
		(net "SPI_PEX3_CLK_R")
	)
	(segment
		(start 385.247388 -264.872724)
		(end 371.605048 -264.872724)
		(width 0.15494)
		(layer "In5.Cu")
		(net "SPI_PEX3_CLK_R")
	)
	(segment
		(start 367.813336 -243.672868)
		(end 367.947956 -243.538248)
		(width 0.15494)
		(layer "In5.Cu")
		(net "SPI_PEX3_CLK_R")
	)
	(segment
		(start 367.604294 -228.697536)
		(end 367.604294 -228.237034)
		(width 0.15494)
		(layer "In5.Cu")
		(net "SPI_PEX3_CLK_R")
	)
	(segment
		(start 367.947956 -244.706648)
		(end 367.813336 -244.572028)
		(width 0.15494)
		(layer "In5.Cu")
		(net "SPI_PEX3_CLK_R")
	)
	(segment
		(start 367.813336 -244.572028)
		(end 367.613692 -244.572028)
		(width 0.15494)
		(layer "In5.Cu")
		(net "SPI_PEX3_CLK_R")
	)
	(segment
		(start 367.479072 -246.235728)
		(end 367.479072 -245.605808)
		(width 0.15494)
		(layer "In5.Cu")
		(net "SPI_PEX3_CLK_R")
	)
	(segment
		(start 386.58165 -265.330178)
		(end 386.45465 -265.203178)
		(width 0.15494)
		(layer "In5.Cu")
		(net "SPI_PEX3_CLK_R")
	)
	(segment
		(start 387.627622 -265.975338)
		(end 386.73659 -265.975338)
		(width 0.15494)
		(layer "In5.Cu")
		(net "SPI_PEX3_CLK_R")
	)
	(segment
		(start 367.947956 -261.215632)
		(end 367.947956 -246.504968)
		(width 0.15494)
		(layer "In5.Cu")
		(net "SPI_PEX3_CLK_R")
	)
	(segment
		(start 386.73659 -265.975338)
		(end 386.58165 -265.820398)
		(width 0.15494)
		(layer "In5.Cu")
		(net "SPI_PEX3_CLK_R")
	)
	(segment
		(start 367.813336 -245.471188)
		(end 367.947956 -245.336568)
		(width 0.15494)
		(layer "In5.Cu")
		(net "SPI_PEX3_CLK_R")
	)
	(segment
		(start 367.947956 -245.336568)
		(end 367.947956 -244.706648)
		(width 0.15494)
		(layer "In5.Cu")
		(net "SPI_PEX3_CLK_R")
	)
	(segment
		(start 367.947956 -246.504968)
		(end 367.813336 -246.370348)
		(width 0.15494)
		(layer "In5.Cu")
		(net "SPI_PEX3_CLK_R")
	)
	(segment
		(start 367.613692 -245.471188)
		(end 367.813336 -245.471188)
		(width 0.15494)
		(layer "In5.Cu")
		(net "SPI_PEX3_CLK_R")
	)
	(segment
		(start 387.067044 -266.963398)
		(end 386.940044 -267.090398)
		(width 0.15494)
		(layer "In5.Cu")
		(net "SPI_PEX3_CLK_R")
	)
	(segment
		(start 386.45465 -265.203178)
		(end 385.577842 -265.203178)
		(width 0.15494)
		(layer "In5.Cu")
		(net "SPI_PEX3_CLK_R")
	)
	(segment
		(start 386.940044 -267.090398)
		(end 386.940044 -268.27861)
		(width 0.15494)
		(layer "In5.Cu")
		(net "SPI_PEX3_CLK_R")
	)
	(segment
		(start 387.988556 -268.46911)
		(end 388.122668 -268.334998)
		(width 0.15494)
		(layer "In5.Cu")
		(net "SPI_PEX3_CLK_R")
	)
	(segment
		(start 367.813336 -246.370348)
		(end 367.613692 -246.370348)
		(width 0.15494)
		(layer "In5.Cu")
		(net "SPI_PEX3_CLK_R")
	)
	(segment
		(start 369.38458 -241.189256)
		(end 369.38458 -230.477822)
		(width 0.15494)
		(layer "In5.Cu")
		(net "SPI_PEX3_CLK_R")
	)
	(segment
		(start 388.122668 -266.470384)
		(end 387.627622 -265.975338)
		(width 0.15494)
		(layer "In5.Cu")
		(net "SPI_PEX3_CLK_R")
	)
	(segment
		(start 367.479072 -244.437408)
		(end 367.479072 -243.807488)
		(width 0.15494)
		(layer "In5.Cu")
		(net "SPI_PEX3_CLK_R")
	)
	(segment
		(start 369.38458 -230.477822)
		(end 367.604294 -228.697536)
		(width 0.15494)
		(layer "In5.Cu")
		(net "SPI_PEX3_CLK_R")
	)
	(segment
		(start 367.479072 -245.605808)
		(end 367.613692 -245.471188)
		(width 0.15494)
		(layer "In5.Cu")
		(net "SPI_PEX3_CLK_R")
	)
	(segment
		(start 50.716688 -357.46309)
		(end 50.716688 -356.831646)
		(width 0.13462)
		(layer "F.Cu")
		(net "P5E_PEX0_STN4_TX_C_DP<64>")
	)
	(segment
		(start 50.716688 -356.831646)
		(end 50.396648 -356.511606)
		(width 0.13462)
		(layer "F.Cu")
		(net "P5E_PEX0_STN4_TX_C_DP<64>")
	)
	(segment
		(start 50.422048 -357.75773)
		(end 50.716688 -357.46309)
		(width 0.13462)
		(layer "F.Cu")
		(net "P5E_PEX0_STN4_TX_C_DP<64>")
	)
	(segment
		(start 44.996862 -367.396014)
		(end 45.272452 -366.984026)
		(width 0.1651)
		(layer "In11.Cu")
		(net "P5E_PEX0_STN4_TX_C_DP<64>")
	)
	(segment
		(start 49.082706 -361.486958)
		(end 49.357788 -361.075224)
		(width 0.1651)
		(layer "In11.Cu")
		(net "P5E_PEX0_STN4_TX_C_DP<64>")
	)
	(segment
		(start 47.463202 -363.910626)
		(end 48.68037 -362.089192)
		(width 0.1651)
		(layer "In11.Cu")
		(net "P5E_PEX0_STN4_TX_C_DP<64>")
	)
	(segment
		(start 46.785784 -364.924594)
		(end 47.060866 -364.51286)
		(width 0.1651)
		(layer "In11.Cu")
		(net "P5E_PEX0_STN4_TX_C_DP<64>")
	)
	(segment
		(start 48.648874 -361.930442)
		(end 48.92421 -361.518454)
		(width 0.1651)
		(layer "In11.Cu")
		(net "P5E_PEX0_STN4_TX_C_DP<64>")
	)
	(segment
		(start 45.674534 -366.3823)
		(end 45.94987 -365.970312)
		(width 0.1651)
		(layer "In11.Cu")
		(net "P5E_PEX0_STN4_TX_C_DP<64>")
	)
	(segment
		(start 43.860466 -372.099078)
		(end 44.20235 -371.757194)
		(width 0.1651)
		(layer "In11.Cu")
		(net "P5E_PEX0_STN4_TX_C_DP<64>")
	)
	(segment
		(start 49.601628 -360.504486)
		(end 49.760124 -360.47299)
		(width 0.1651)
		(layer "In11.Cu")
		(net "P5E_PEX0_STN4_TX_C_DP<64>")
	)
	(segment
		(start 49.326292 -360.916474)
		(end 49.601628 -360.504486)
		(width 0.1651)
		(layer "In11.Cu")
		(net "P5E_PEX0_STN4_TX_C_DP<64>")
	)
	(segment
		(start 45.430948 -366.95253)
		(end 45.70603 -366.540796)
		(width 0.1651)
		(layer "In11.Cu")
		(net "P5E_PEX0_STN4_TX_C_DP<64>")
	)
	(segment
		(start 46.627288 -364.956344)
		(end 46.785784 -364.924594)
		(width 0.1651)
		(layer "In11.Cu")
		(net "P5E_PEX0_STN4_TX_C_DP<64>")
	)
	(segment
		(start 50.712878 -359.047288)
		(end 50.712878 -358.04856)
		(width 0.1651)
		(layer "In11.Cu")
		(net "P5E_PEX0_STN4_TX_C_DP<64>")
	)
	(segment
		(start 45.94987 -365.970312)
		(end 46.108366 -365.938562)
		(width 0.1651)
		(layer "In11.Cu")
		(net "P5E_PEX0_STN4_TX_C_DP<64>")
	)
	(segment
		(start 46.351952 -365.368332)
		(end 46.627288 -364.956344)
		(width 0.1651)
		(layer "In11.Cu")
		(net "P5E_PEX0_STN4_TX_C_DP<64>")
	)
	(segment
		(start 50.03546 -360.061256)
		(end 50.003964 -359.902506)
		(width 0.1651)
		(layer "In11.Cu")
		(net "P5E_PEX0_STN4_TX_C_DP<64>")
	)
	(segment
		(start 44.61891 -368.167666)
		(end 45.028358 -367.554764)
		(width 0.1651)
		(layer "In11.Cu")
		(net "P5E_PEX0_STN4_TX_C_DP<64>")
	)
	(segment
		(start 47.02937 -364.354364)
		(end 47.304706 -363.942376)
		(width 0.1651)
		(layer "In11.Cu")
		(net "P5E_PEX0_STN4_TX_C_DP<64>")
	)
	(segment
		(start 45.272452 -366.984026)
		(end 45.430948 -366.95253)
		(width 0.1651)
		(layer "In11.Cu")
		(net "P5E_PEX0_STN4_TX_C_DP<64>")
	)
	(segment
		(start 45.70603 -366.540796)
		(end 45.674534 -366.3823)
		(width 0.1651)
		(layer "In11.Cu")
		(net "P5E_PEX0_STN4_TX_C_DP<64>")
	)
	(segment
		(start 50.003964 -359.902506)
		(end 50.2793 -359.490518)
		(width 0.1651)
		(layer "In11.Cu")
		(net "P5E_PEX0_STN4_TX_C_DP<64>")
	)
	(segment
		(start 46.108366 -365.938562)
		(end 46.383448 -365.526828)
		(width 0.1651)
		(layer "In11.Cu")
		(net "P5E_PEX0_STN4_TX_C_DP<64>")
	)
	(segment
		(start 43.310048 -371.590062)
		(end 43.310048 -371.972078)
		(width 0.1651)
		(layer "In11.Cu")
		(net "P5E_PEX0_STN4_TX_C_DP<64>")
	)
	(segment
		(start 44.20235 -371.757194)
		(end 44.20235 -369.540536)
		(width 0.1651)
		(layer "In11.Cu")
		(net "P5E_PEX0_STN4_TX_C_DP<64>")
	)
	(segment
		(start 49.357788 -361.075224)
		(end 49.326292 -360.916474)
		(width 0.1651)
		(layer "In11.Cu")
		(net "P5E_PEX0_STN4_TX_C_DP<64>")
	)
	(segment
		(start 44.20235 -369.540536)
		(end 44.61891 -368.167666)
		(width 0.1651)
		(layer "In11.Cu")
		(net "P5E_PEX0_STN4_TX_C_DP<64>")
	)
	(segment
		(start 49.760124 -360.47299)
		(end 50.035206 -360.061256)
		(width 0.1651)
		(layer "In11.Cu")
		(net "P5E_PEX0_STN4_TX_C_DP<64>")
	)
	(segment
		(start 45.028358 -367.554764)
		(end 44.996862 -367.396014)
		(width 0.1651)
		(layer "In11.Cu")
		(net "P5E_PEX0_STN4_TX_C_DP<64>")
	)
	(segment
		(start 48.92421 -361.518454)
		(end 49.082706 -361.486958)
		(width 0.1651)
		(layer "In11.Cu")
		(net "P5E_PEX0_STN4_TX_C_DP<64>")
	)
	(segment
		(start 50.2793 -359.490518)
		(end 50.437796 -359.459022)
		(width 0.1651)
		(layer "In11.Cu")
		(net "P5E_PEX0_STN4_TX_C_DP<64>")
	)
	(segment
		(start 47.304706 -363.942376)
		(end 47.463202 -363.910626)
		(width 0.1651)
		(layer "In11.Cu")
		(net "P5E_PEX0_STN4_TX_C_DP<64>")
	)
	(segment
		(start 43.437048 -372.099078)
		(end 43.860466 -372.099078)
		(width 0.1651)
		(layer "In11.Cu")
		(net "P5E_PEX0_STN4_TX_C_DP<64>")
	)
	(segment
		(start 50.712878 -358.04856)
		(end 50.422048 -357.75773)
		(width 0.1651)
		(layer "In11.Cu")
		(net "P5E_PEX0_STN4_TX_C_DP<64>")
	)
	(segment
		(start 47.060866 -364.51286)
		(end 47.02937 -364.354364)
		(width 0.1651)
		(layer "In11.Cu")
		(net "P5E_PEX0_STN4_TX_C_DP<64>")
	)
	(segment
		(start 50.437796 -359.459022)
		(end 50.712878 -359.047288)
		(width 0.1651)
		(layer "In11.Cu")
		(net "P5E_PEX0_STN4_TX_C_DP<64>")
	)
	(segment
		(start 48.68037 -362.089192)
		(end 48.648874 -361.930442)
		(width 0.1651)
		(layer "In11.Cu")
		(net "P5E_PEX0_STN4_TX_C_DP<64>")
	)
	(segment
		(start 50.035206 -360.061256)
		(end 50.03546 -360.061256)
		(width 0.1651)
		(layer "In11.Cu")
		(net "P5E_PEX0_STN4_TX_C_DP<64>")
	)
	(segment
		(start 43.310048 -371.972078)
		(end 43.437048 -372.099078)
		(width 0.1651)
		(layer "In11.Cu")
		(net "P5E_PEX0_STN4_TX_C_DP<64>")
	)
	(segment
		(start 46.383448 -365.526828)
		(end 46.351952 -365.368332)
		(width 0.1651)
		(layer "In11.Cu")
		(net "P5E_PEX0_STN4_TX_C_DP<64>")
	)
	(segment
		(start 291.889942 -378.67209)
		(end 292.016942 -378.79909)
		(width 0.1651)
		(layer "In15.Cu")
		(net "P5E_PEX2_STN4_RX_DP<69>")
	)
	(segment
		(start 305.48453 -351.010982)
		(end 305.615086 -350.950276)
		(width 0.1651)
		(layer "In15.Cu")
		(net "P5E_PEX2_STN4_RX_DP<69>")
	)
	(segment
		(start 292.733984 -369.880642)
		(end 293.113714 -368.714528)
		(width 0.1651)
		(layer "In15.Cu")
		(net "P5E_PEX2_STN4_RX_DP<69>")
	)
	(segment
		(start 305.614832 -350.950276)
		(end 305.784758 -350.484948)
		(width 0.1651)
		(layer "In15.Cu")
		(net "P5E_PEX2_STN4_RX_DP<69>")
	)
	(segment
		(start 314.16879 -327.533762)
		(end 315.887354 -322.829682)
		(width 0.1651)
		(layer "In15.Cu")
		(net "P5E_PEX2_STN4_RX_DP<69>")
	)
	(segment
		(start 296.794428 -365.134144)
		(end 296.79646 -364.99038)
		(width 0.1651)
		(layer "In15.Cu")
		(net "P5E_PEX2_STN4_RX_DP<69>")
	)
	(segment
		(start 313.868562 -328.059796)
		(end 314.038488 -327.594214)
		(width 0.1651)
		(layer "In15.Cu")
		(net "P5E_PEX2_STN4_RX_DP<69>")
	)
	(segment
		(start 292.447218 -378.79909)
		(end 292.733984 -378.512324)
		(width 0.1651)
		(layer "In15.Cu")
		(net "P5E_PEX2_STN4_RX_DP<69>")
	)
	(segment
		(start 306.024788 -349.828866)
		(end 306.024534 -349.828866)
		(width 0.1651)
		(layer "In15.Cu")
		(net "P5E_PEX2_STN4_RX_DP<69>")
	)
	(segment
		(start 312.3946 -309.770018)
		(end 312.179462 -309.55488)
		(width 0.1143)
		(layer "In15.Cu")
		(net "P5E_PEX2_STN4_RX_DP<69>")
	)
	(segment
		(start 295.94048 -365.822992)
		(end 296.295826 -365.477552)
		(width 0.1651)
		(layer "In15.Cu")
		(net "P5E_PEX2_STN4_RX_DP<69>")
	)
	(segment
		(start 313.929268 -328.190098)
		(end 313.868562 -328.059796)
		(width 0.1651)
		(layer "In15.Cu")
		(net "P5E_PEX2_STN4_RX_DP<69>")
	)
	(segment
		(start 314.169044 -327.533762)
		(end 314.16879 -327.533762)
		(width 0.1651)
		(layer "In15.Cu")
		(net "P5E_PEX2_STN4_RX_DP<69>")
	)
	(segment
		(start 313.759342 -328.655172)
		(end 313.929268 -328.190098)
		(width 0.1651)
		(layer "In15.Cu")
		(net "P5E_PEX2_STN4_RX_DP<69>")
	)
	(segment
		(start 292.016942 -378.79909)
		(end 292.447218 -378.79909)
		(width 0.1651)
		(layer "In15.Cu")
		(net "P5E_PEX2_STN4_RX_DP<69>")
	)
	(segment
		(start 314.038488 -327.594214)
		(end 314.169044 -327.533762)
		(width 0.1651)
		(layer "In15.Cu")
		(net "P5E_PEX2_STN4_RX_DP<69>")
	)
	(segment
		(start 312.179462 -309.55488)
		(end 312.179462 -309.314088)
		(width 0.1143)
		(layer "In15.Cu")
		(net "P5E_PEX2_STN4_RX_DP<69>")
	)
	(segment
		(start 305.724306 -350.3549)
		(end 305.894232 -349.889318)
		(width 0.1651)
		(layer "In15.Cu")
		(net "P5E_PEX2_STN4_RX_DP<69>")
	)
	(segment
		(start 292.733984 -378.512324)
		(end 292.733984 -369.880642)
		(width 0.1651)
		(layer "In15.Cu")
		(net "P5E_PEX2_STN4_RX_DP<69>")
	)
	(segment
		(start 316.528958 -309.815738)
		(end 315.852048 -309.815738)
		(width 0.1651)
		(layer "In15.Cu")
		(net "P5E_PEX2_STN4_RX_DP<69>")
	)
	(segment
		(start 296.79646 -364.99038)
		(end 297.151806 -364.64494)
		(width 0.1651)
		(layer "In15.Cu")
		(net "P5E_PEX2_STN4_RX_DP<69>")
	)
	(segment
		(start 296.295826 -365.477552)
		(end 296.43959 -365.47933)
		(width 0.1651)
		(layer "In15.Cu")
		(net "P5E_PEX2_STN4_RX_DP<69>")
	)
	(segment
		(start 297.29557 -364.646718)
		(end 302.439324 -359.643426)
		(width 0.1651)
		(layer "In15.Cu")
		(net "P5E_PEX2_STN4_RX_DP<69>")
	)
	(segment
		(start 306.194206 -349.363792)
		(end 306.194714 -349.363792)
		(width 0.1651)
		(layer "In15.Cu")
		(net "P5E_PEX2_STN4_RX_DP<69>")
	)
	(segment
		(start 315.77788 -309.770018)
		(end 312.3946 -309.770018)
		(width 0.1143)
		(layer "In15.Cu")
		(net "P5E_PEX2_STN4_RX_DP<69>")
	)
	(segment
		(start 315.852048 -309.815738)
		(end 315.8236 -309.815738)
		(width 0.1143)
		(layer "In15.Cu")
		(net "P5E_PEX2_STN4_RX_DP<69>")
	)
	(segment
		(start 291.889942 -378.290074)
		(end 291.889942 -378.67209)
		(width 0.1651)
		(layer "In15.Cu")
		(net "P5E_PEX2_STN4_RX_DP<69>")
	)
	(segment
		(start 312.065162 -309.199788)
		(end 311.799732 -309.199788)
		(width 0.1143)
		(layer "In15.Cu")
		(net "P5E_PEX2_STN4_RX_DP<69>")
	)
	(segment
		(start 313.628786 -328.715624)
		(end 313.759342 -328.655172)
		(width 0.1651)
		(layer "In15.Cu")
		(net "P5E_PEX2_STN4_RX_DP<69>")
	)
	(segment
		(start 306.434236 -348.707202)
		(end 313.519312 -329.311508)
		(width 0.1651)
		(layer "In15.Cu")
		(net "P5E_PEX2_STN4_RX_DP<69>")
	)
	(segment
		(start 313.519312 -329.311508)
		(end 313.519566 -329.311508)
		(width 0.1651)
		(layer "In15.Cu")
		(net "P5E_PEX2_STN4_RX_DP<69>")
	)
	(segment
		(start 295.938448 -365.966756)
		(end 295.94048 -365.822992)
		(width 0.1651)
		(layer "In15.Cu")
		(net "P5E_PEX2_STN4_RX_DP<69>")
	)
	(segment
		(start 305.314604 -351.47631)
		(end 305.48453 -351.010982)
		(width 0.1651)
		(layer "In15.Cu")
		(net "P5E_PEX2_STN4_RX_DP<69>")
	)
	(segment
		(start 305.615086 -350.950276)
		(end 305.614832 -350.950276)
		(width 0.1651)
		(layer "In15.Cu")
		(net "P5E_PEX2_STN4_RX_DP<69>")
	)
	(segment
		(start 295.084754 -366.655604)
		(end 295.439846 -366.310164)
		(width 0.1651)
		(layer "In15.Cu")
		(net "P5E_PEX2_STN4_RX_DP<69>")
	)
	(segment
		(start 296.43959 -365.47933)
		(end 296.794428 -365.134144)
		(width 0.1651)
		(layer "In15.Cu")
		(net "P5E_PEX2_STN4_RX_DP<69>")
	)
	(segment
		(start 315.8236 -309.815738)
		(end 315.77788 -309.770018)
		(width 0.1143)
		(layer "In15.Cu")
		(net "P5E_PEX2_STN4_RX_DP<69>")
	)
	(segment
		(start 317.4238 -317.072772)
		(end 317.4238 -311.139586)
		(width 0.1651)
		(layer "In15.Cu")
		(net "P5E_PEX2_STN4_RX_DP<69>")
	)
	(segment
		(start 313.45886 -329.181206)
		(end 313.628786 -328.715624)
		(width 0.1651)
		(layer "In15.Cu")
		(net "P5E_PEX2_STN4_RX_DP<69>")
	)
	(segment
		(start 305.894232 -349.889318)
		(end 306.024788 -349.828866)
		(width 0.1651)
		(layer "In15.Cu")
		(net "P5E_PEX2_STN4_RX_DP<69>")
	)
	(segment
		(start 317.4238 -311.139586)
		(end 317.120524 -310.407304)
		(width 0.1651)
		(layer "In15.Cu")
		(net "P5E_PEX2_STN4_RX_DP<69>")
	)
	(segment
		(start 297.151806 -364.64494)
		(end 297.29557 -364.646718)
		(width 0.1651)
		(layer "In15.Cu")
		(net "P5E_PEX2_STN4_RX_DP<69>")
	)
	(segment
		(start 313.519566 -329.311508)
		(end 313.45886 -329.181206)
		(width 0.1651)
		(layer "In15.Cu")
		(net "P5E_PEX2_STN4_RX_DP<69>")
	)
	(segment
		(start 302.439324 -359.643426)
		(end 305.375056 -351.606612)
		(width 0.1651)
		(layer "In15.Cu")
		(net "P5E_PEX2_STN4_RX_DP<69>")
	)
	(segment
		(start 306.134008 -349.23349)
		(end 306.303934 -348.767908)
		(width 0.1651)
		(layer "In15.Cu")
		(net "P5E_PEX2_STN4_RX_DP<69>")
	)
	(segment
		(start 293.113714 -368.714528)
		(end 295.082722 -366.799368)
		(width 0.1651)
		(layer "In15.Cu")
		(net "P5E_PEX2_STN4_RX_DP<69>")
	)
	(segment
		(start 295.439846 -366.310164)
		(end 295.58361 -366.311942)
		(width 0.1651)
		(layer "In15.Cu")
		(net "P5E_PEX2_STN4_RX_DP<69>")
	)
	(segment
		(start 306.194714 -349.363792)
		(end 306.134008 -349.23349)
		(width 0.1651)
		(layer "In15.Cu")
		(net "P5E_PEX2_STN4_RX_DP<69>")
	)
	(segment
		(start 295.58361 -366.311942)
		(end 295.938448 -365.966756)
		(width 0.1651)
		(layer "In15.Cu")
		(net "P5E_PEX2_STN4_RX_DP<69>")
	)
	(segment
		(start 295.082722 -366.799368)
		(end 295.084754 -366.655604)
		(width 0.1651)
		(layer "In15.Cu")
		(net "P5E_PEX2_STN4_RX_DP<69>")
	)
	(segment
		(start 317.120524 -310.407304)
		(end 316.528958 -309.815738)
		(width 0.1651)
		(layer "In15.Cu")
		(net "P5E_PEX2_STN4_RX_DP<69>")
	)
	(segment
		(start 306.43449 -348.707456)
		(end 306.434236 -348.707202)
		(width 0.1651)
		(layer "In15.Cu")
		(net "P5E_PEX2_STN4_RX_DP<69>")
	)
	(segment
		(start 315.887354 -322.829682)
		(end 317.4238 -317.072772)
		(width 0.1651)
		(layer "In15.Cu")
		(net "P5E_PEX2_STN4_RX_DP<69>")
	)
	(segment
		(start 306.303934 -348.767908)
		(end 306.43449 -348.707456)
		(width 0.1651)
		(layer "In15.Cu")
		(net "P5E_PEX2_STN4_RX_DP<69>")
	)
	(segment
		(start 312.179462 -309.314088)
		(end 312.065162 -309.199788)
		(width 0.1143)
		(layer "In15.Cu")
		(net "P5E_PEX2_STN4_RX_DP<69>")
	)
	(segment
		(start 305.785012 -350.485202)
		(end 305.724306 -350.3549)
		(width 0.1651)
		(layer "In15.Cu")
		(net "P5E_PEX2_STN4_RX_DP<69>")
	)
	(segment
		(start 305.375056 -351.606612)
		(end 305.314604 -351.47631)
		(width 0.1651)
		(layer "In15.Cu")
		(net "P5E_PEX2_STN4_RX_DP<69>")
	)
	(segment
		(start 305.784758 -350.484948)
		(end 305.785012 -350.485202)
		(width 0.1651)
		(layer "In15.Cu")
		(net "P5E_PEX2_STN4_RX_DP<69>")
	)
	(segment
		(start 306.024534 -349.828866)
		(end 306.194206 -349.363792)
		(width 0.1651)
		(layer "In15.Cu")
		(net "P5E_PEX2_STN4_RX_DP<69>")
	)
	(segment
		(start 44.773088 -344.539062)
		(end 45.093128 -344.219022)
		(width 0.13462)
		(layer "F.Cu")
		(net "P5E_PEX0_STN4_TX_C_DN<68>")
	)
	(segment
		(start 45.067728 -345.465146)
		(end 44.773088 -345.170506)
		(width 0.13462)
		(layer "F.Cu")
		(net "P5E_PEX0_STN4_TX_C_DN<68>")
	)
	(segment
		(start 44.773088 -345.170506)
		(end 44.773088 -344.539062)
		(width 0.13462)
		(layer "F.Cu")
		(net "P5E_PEX0_STN4_TX_C_DN<68>")
	)
	(segment
		(start 44.776898 -345.755976)
		(end 45.067728 -345.465146)
		(width 0.1651)
		(layer "In11.Cu")
		(net "P5E_PEX0_STN4_TX_C_DN<68>")
	)
	(segment
		(start 36.765738 -366.43183)
		(end 43.222418 -358.564434)
		(width 0.1651)
		(layer "In11.Cu")
		(net "P5E_PEX0_STN4_TX_C_DN<68>")
	)
	(segment
		(start 44.776898 -346.438982)
		(end 44.776898 -345.755976)
		(width 0.1651)
		(layer "In11.Cu")
		(net "P5E_PEX0_STN4_TX_C_DN<68>")
	)
	(segment
		(start 43.222418 -347.993462)
		(end 44.776898 -346.438982)
		(width 0.1651)
		(layer "In11.Cu")
		(net "P5E_PEX0_STN4_TX_C_DN<68>")
	)
	(segment
		(start 35.177222 -372.381018)
		(end 35.68446 -371.87378)
		(width 0.1651)
		(layer "In11.Cu")
		(net "P5E_PEX0_STN4_TX_C_DN<68>")
	)
	(segment
		(start 35.68446 -371.87378)
		(end 35.68446 -369.45316)
		(width 0.1651)
		(layer "In11.Cu")
		(net "P5E_PEX0_STN4_TX_C_DN<68>")
	)
	(segment
		(start 34.636964 -372.381018)
		(end 35.177222 -372.381018)
		(width 0.1651)
		(layer "In11.Cu")
		(net "P5E_PEX0_STN4_TX_C_DN<68>")
	)
	(segment
		(start 35.68446 -369.45316)
		(end 36.765738 -366.43183)
		(width 0.1651)
		(layer "In11.Cu")
		(net "P5E_PEX0_STN4_TX_C_DN<68>")
	)
	(segment
		(start 34.509964 -372.890034)
		(end 34.509964 -372.508018)
		(width 0.1651)
		(layer "In11.Cu")
		(net "P5E_PEX0_STN4_TX_C_DN<68>")
	)
	(segment
		(start 43.222418 -358.564434)
		(end 43.222418 -347.993462)
		(width 0.1651)
		(layer "In11.Cu")
		(net "P5E_PEX0_STN4_TX_C_DN<68>")
	)
	(segment
		(start 34.509964 -372.508018)
		(end 34.636964 -372.381018)
		(width 0.1651)
		(layer "In11.Cu")
		(net "P5E_PEX0_STN4_TX_C_DN<68>")
	)
	(segment
		(start 283.736542 -350.685354)
		(end 283.736542 -351.316798)
		(width 0.13462)
		(layer "F.Cu")
		(net "P5E_PEX2_STN4_TX_C_DP<72>")
	)
	(segment
		(start 283.416502 -350.365314)
		(end 283.736542 -350.685354)
		(width 0.13462)
		(layer "F.Cu")
		(net "P5E_PEX2_STN4_TX_C_DP<72>")
	)
	(segment
		(start 283.736542 -351.316798)
		(end 283.441902 -351.611438)
		(width 0.13462)
		(layer "F.Cu")
		(net "P5E_PEX2_STN4_TX_C_DP<72>")
	)
	(segment
		(start 282.178252 -358.836976)
		(end 285.6865 -379.44679)
		(width 0.1651)
		(layer "In11.Cu")
		(net "P5E_PEX2_STN4_TX_C_DP<72>")
	)
	(segment
		(start 303.046638 -394.161264)
		(end 303.255172 -394.650468)
		(width 0.1651)
		(layer "In11.Cu")
		(net "P5E_PEX2_STN4_TX_C_DP<72>")
	)
	(segment
		(start 302.48733 -393.798044)
		(end 303.046638 -394.161264)
		(width 0.1651)
		(layer "In11.Cu")
		(net "P5E_PEX2_STN4_TX_C_DP<72>")
	)
	(segment
		(start 283.732732 -352.356166)
		(end 282.178252 -353.910646)
		(width 0.1651)
		(layer "In11.Cu")
		(net "P5E_PEX2_STN4_TX_C_DP<72>")
	)
	(segment
		(start 301.384462 -393.187428)
		(end 301.507398 -393.161266)
		(width 0.1651)
		(layer "In11.Cu")
		(net "P5E_PEX2_STN4_TX_C_DP<72>")
	)
	(segment
		(start 286.16148 -384.613912)
		(end 286.62249 -385.565904)
		(width 0.1651)
		(layer "In11.Cu")
		(net "P5E_PEX2_STN4_TX_C_DP<72>")
	)
	(segment
		(start 300.968918 -392.917172)
		(end 301.384462 -393.187428)
		(width 0.1651)
		(layer "In11.Cu")
		(net "P5E_PEX2_STN4_TX_C_DP<72>")
	)
	(segment
		(start 301.507398 -393.161266)
		(end 301.922688 -393.431014)
		(width 0.1651)
		(layer "In11.Cu")
		(net "P5E_PEX2_STN4_TX_C_DP<72>")
	)
	(segment
		(start 303.539652 -395.316456)
		(end 303.733962 -395.771878)
		(width 0.1651)
		(layer "In11.Cu")
		(net "P5E_PEX2_STN4_TX_C_DP<72>")
	)
	(segment
		(start 283.441902 -351.611438)
		(end 283.732732 -351.902268)
		(width 0.1651)
		(layer "In11.Cu")
		(net "P5E_PEX2_STN4_TX_C_DP<72>")
	)
	(segment
		(start 303.733962 -395.771878)
		(end 303.733962 -397.812514)
		(width 0.1651)
		(layer "In11.Cu")
		(net "P5E_PEX2_STN4_TX_C_DP<72>")
	)
	(segment
		(start 303.733962 -397.812514)
		(end 303.447196 -398.09928)
		(width 0.1651)
		(layer "In11.Cu")
		(net "P5E_PEX2_STN4_TX_C_DP<72>")
	)
	(segment
		(start 286.62249 -385.565904)
		(end 287.45434 -386.357622)
		(width 0.1651)
		(layer "In11.Cu")
		(net "P5E_PEX2_STN4_TX_C_DP<72>")
	)
	(segment
		(start 301.94885 -393.55395)
		(end 302.364394 -393.823952)
		(width 0.1651)
		(layer "In11.Cu")
		(net "P5E_PEX2_STN4_TX_C_DP<72>")
	)
	(segment
		(start 282.178252 -353.910646)
		(end 282.178252 -358.836976)
		(width 0.1651)
		(layer "In11.Cu")
		(net "P5E_PEX2_STN4_TX_C_DP<72>")
	)
	(segment
		(start 285.6865 -379.44679)
		(end 286.16148 -384.613912)
		(width 0.1651)
		(layer "In11.Cu")
		(net "P5E_PEX2_STN4_TX_C_DP<72>")
	)
	(segment
		(start 299.988986 -392.280394)
		(end 300.40453 -392.55065)
		(width 0.1651)
		(layer "In11.Cu")
		(net "P5E_PEX2_STN4_TX_C_DP<72>")
	)
	(segment
		(start 300.942756 -392.794236)
		(end 300.968918 -392.917172)
		(width 0.1651)
		(layer "In11.Cu")
		(net "P5E_PEX2_STN4_TX_C_DP<72>")
	)
	(segment
		(start 303.194974 -394.800328)
		(end 303.389538 -395.256258)
		(width 0.1651)
		(layer "In11.Cu")
		(net "P5E_PEX2_STN4_TX_C_DP<72>")
	)
	(segment
		(start 303.255172 -394.650468)
		(end 303.194974 -394.800328)
		(width 0.1651)
		(layer "In11.Cu")
		(net "P5E_PEX2_STN4_TX_C_DP<72>")
	)
	(segment
		(start 301.922688 -393.431014)
		(end 301.94885 -393.55395)
		(width 0.1651)
		(layer "In11.Cu")
		(net "P5E_PEX2_STN4_TX_C_DP<72>")
	)
	(segment
		(start 296.653458 -390.007348)
		(end 299.962824 -392.157458)
		(width 0.1651)
		(layer "In11.Cu")
		(net "P5E_PEX2_STN4_TX_C_DP<72>")
	)
	(segment
		(start 300.527466 -392.524488)
		(end 300.942756 -392.794236)
		(width 0.1651)
		(layer "In11.Cu")
		(net "P5E_PEX2_STN4_TX_C_DP<72>")
	)
	(segment
		(start 303.01692 -398.09928)
		(end 302.88992 -397.97228)
		(width 0.1651)
		(layer "In11.Cu")
		(net "P5E_PEX2_STN4_TX_C_DP<72>")
	)
	(segment
		(start 303.389538 -395.256258)
		(end 303.539652 -395.316456)
		(width 0.1651)
		(layer "In11.Cu")
		(net "P5E_PEX2_STN4_TX_C_DP<72>")
	)
	(segment
		(start 283.732732 -351.902268)
		(end 283.732732 -352.356166)
		(width 0.1651)
		(layer "In11.Cu")
		(net "P5E_PEX2_STN4_TX_C_DP<72>")
	)
	(segment
		(start 302.88992 -397.97228)
		(end 302.88992 -397.59001)
		(width 0.1651)
		(layer "In11.Cu")
		(net "P5E_PEX2_STN4_TX_C_DP<72>")
	)
	(segment
		(start 299.962824 -392.157458)
		(end 299.988986 -392.280394)
		(width 0.1651)
		(layer "In11.Cu")
		(net "P5E_PEX2_STN4_TX_C_DP<72>")
	)
	(segment
		(start 302.364394 -393.823952)
		(end 302.48733 -393.798044)
		(width 0.1651)
		(layer "In11.Cu")
		(net "P5E_PEX2_STN4_TX_C_DP<72>")
	)
	(segment
		(start 303.447196 -398.09928)
		(end 303.01692 -398.09928)
		(width 0.1651)
		(layer "In11.Cu")
		(net "P5E_PEX2_STN4_TX_C_DP<72>")
	)
	(segment
		(start 287.45434 -386.357622)
		(end 296.653458 -390.007348)
		(width 0.1651)
		(layer "In11.Cu")
		(net "P5E_PEX2_STN4_TX_C_DP<72>")
	)
	(segment
		(start 300.40453 -392.55065)
		(end 300.527466 -392.524488)
		(width 0.1651)
		(layer "In11.Cu")
		(net "P5E_PEX2_STN4_TX_C_DP<72>")
	)
	(segment
		(start 38.555168 -356.831646)
		(end 38.875208 -356.511606)
		(width 0.13462)
		(layer "F.Cu")
		(net "P5E_PEX0_STN4_TX_C_DN<70>")
	)
	(segment
		(start 38.849808 -357.75773)
		(end 38.555168 -357.46309)
		(width 0.13462)
		(layer "F.Cu")
		(net "P5E_PEX0_STN4_TX_C_DN<70>")
	)
	(segment
		(start 38.555168 -357.46309)
		(end 38.555168 -356.831646)
		(width 0.13462)
		(layer "F.Cu")
		(net "P5E_PEX0_STN4_TX_C_DN<70>")
	)
	(segment
		(start 31.284418 -371.87378)
		(end 31.284418 -369.322858)
		(width 0.1651)
		(layer "In11.Cu")
		(net "P5E_PEX0_STN4_TX_C_DN<70>")
	)
	(segment
		(start 31.284418 -369.322858)
		(end 31.787592 -367.79962)
		(width 0.1651)
		(layer "In11.Cu")
		(net "P5E_PEX0_STN4_TX_C_DN<70>")
	)
	(segment
		(start 38.558978 -358.04856)
		(end 38.849808 -357.75773)
		(width 0.1651)
		(layer "In11.Cu")
		(net "P5E_PEX0_STN4_TX_C_DN<70>")
	)
	(segment
		(start 30.236922 -372.381018)
		(end 30.77718 -372.381018)
		(width 0.1651)
		(layer "In11.Cu")
		(net "P5E_PEX0_STN4_TX_C_DN<70>")
	)
	(segment
		(start 30.77718 -372.381018)
		(end 31.284418 -371.87378)
		(width 0.1651)
		(layer "In11.Cu")
		(net "P5E_PEX0_STN4_TX_C_DN<70>")
	)
	(segment
		(start 30.109922 -372.508018)
		(end 30.236922 -372.381018)
		(width 0.1651)
		(layer "In11.Cu")
		(net "P5E_PEX0_STN4_TX_C_DN<70>")
	)
	(segment
		(start 38.503352 -358.744266)
		(end 38.558978 -358.68864)
		(width 0.1651)
		(layer "In11.Cu")
		(net "P5E_PEX0_STN4_TX_C_DN<70>")
	)
	(segment
		(start 30.109922 -372.890034)
		(end 30.109922 -372.508018)
		(width 0.1651)
		(layer "In11.Cu")
		(net "P5E_PEX0_STN4_TX_C_DN<70>")
	)
	(segment
		(start 31.787592 -367.79962)
		(end 38.503352 -358.744266)
		(width 0.1651)
		(layer "In11.Cu")
		(net "P5E_PEX0_STN4_TX_C_DN<70>")
	)
	(segment
		(start 38.558978 -358.68864)
		(end 38.558978 -358.04856)
		(width 0.1651)
		(layer "In11.Cu")
		(net "P5E_PEX0_STN4_TX_C_DN<70>")
	)
	(segment
		(start 26.439368 -355.978206)
		(end 26.119328 -355.658166)
		(width 0.13462)
		(layer "F.Cu")
		(net "P5E_PEX0_STN4_TX_DN<76>")
	)
	(segment
		(start 26.119328 -355.026722)
		(end 26.413968 -354.732082)
		(width 0.13462)
		(layer "F.Cu")
		(net "P5E_PEX0_STN4_TX_DN<76>")
	)
	(segment
		(start 26.119328 -355.658166)
		(end 26.119328 -355.026722)
		(width 0.13462)
		(layer "F.Cu")
		(net "P5E_PEX0_STN4_TX_DN<76>")
	)
	(segment
		(start 76.37018 -313.735212)
		(end 76.53528 -313.570112)
		(width 0.1143)
		(layer "In11.Cu")
		(net "P5E_PEX0_STN4_TX_DN<76>")
	)
	(segment
		(start 26.413968 -354.732082)
		(end 26.123138 -354.441252)
		(width 0.1651)
		(layer "In11.Cu")
		(net "P5E_PEX0_STN4_TX_DN<76>")
	)
	(segment
		(start 27.677618 -352.220022)
		(end 27.677618 -340.716362)
		(width 0.1651)
		(layer "In11.Cu")
		(net "P5E_PEX0_STN4_TX_DN<76>")
	)
	(segment
		(start 76.4159 -321.356482)
		(end 76.4159 -320.294)
		(width 0.1651)
		(layer "In11.Cu")
		(net "P5E_PEX0_STN4_TX_DN<76>")
	)
	(segment
		(start 27.677618 -340.716362)
		(end 29.200348 -339.193632)
		(width 0.1651)
		(layer "In11.Cu")
		(net "P5E_PEX0_STN4_TX_DN<76>")
	)
	(segment
		(start 26.123138 -354.441252)
		(end 26.123138 -353.774502)
		(width 0.1651)
		(layer "In11.Cu")
		(net "P5E_PEX0_STN4_TX_DN<76>")
	)
	(segment
		(start 29.200348 -339.193632)
		(end 41.392094 -332.677008)
		(width 0.1651)
		(layer "In11.Cu")
		(net "P5E_PEX0_STN4_TX_DN<76>")
	)
	(segment
		(start 76.74991 -313.659012)
		(end 76.74991 -313.949842)
		(width 0.1143)
		(layer "In11.Cu")
		(net "P5E_PEX0_STN4_TX_DN<76>")
	)
	(segment
		(start 76.4159 -320.265552)
		(end 76.37018 -320.219832)
		(width 0.1143)
		(layer "In11.Cu")
		(net "P5E_PEX0_STN4_TX_DN<76>")
	)
	(segment
		(start 75.620626 -323.276976)
		(end 76.4159 -321.356482)
		(width 0.1651)
		(layer "In11.Cu")
		(net "P5E_PEX0_STN4_TX_DN<76>")
	)
	(segment
		(start 76.37018 -320.219832)
		(end 76.37018 -313.735212)
		(width 0.1143)
		(layer "In11.Cu")
		(net "P5E_PEX0_STN4_TX_DN<76>")
	)
	(segment
		(start 41.392094 -332.677008)
		(end 53.371496 -328.390504)
		(width 0.1651)
		(layer "In11.Cu")
		(net "P5E_PEX0_STN4_TX_DN<76>")
	)
	(segment
		(start 76.4159 -320.294)
		(end 76.4159 -320.265552)
		(width 0.1143)
		(layer "In11.Cu")
		(net "P5E_PEX0_STN4_TX_DN<76>")
	)
	(segment
		(start 73.570338 -324.372986)
		(end 75.620626 -323.276976)
		(width 0.1651)
		(layer "In11.Cu")
		(net "P5E_PEX0_STN4_TX_DN<76>")
	)
	(segment
		(start 26.123138 -353.774502)
		(end 27.677618 -352.220022)
		(width 0.1651)
		(layer "In11.Cu")
		(net "P5E_PEX0_STN4_TX_DN<76>")
	)
	(segment
		(start 53.371496 -328.390504)
		(end 73.570338 -324.372986)
		(width 0.1651)
		(layer "In11.Cu")
		(net "P5E_PEX0_STN4_TX_DN<76>")
	)
	(segment
		(start 76.66101 -313.570112)
		(end 76.74991 -313.659012)
		(width 0.1143)
		(layer "In11.Cu")
		(net "P5E_PEX0_STN4_TX_DN<76>")
	)
	(segment
		(start 76.53528 -313.570112)
		(end 76.66101 -313.570112)
		(width 0.1143)
		(layer "In11.Cu")
		(net "P5E_PEX0_STN4_TX_DN<76>")
	)
	(segment
		(start 274.409662 -357.46309)
		(end 274.115022 -357.75773)
		(width 0.13462)
		(layer "F.Cu")
		(net "P5E_PEX2_STN4_TX_C_DP<76>")
	)
	(segment
		(start 274.409662 -356.831646)
		(end 274.409662 -357.46309)
		(width 0.13462)
		(layer "F.Cu")
		(net "P5E_PEX2_STN4_TX_C_DP<76>")
	)
	(segment
		(start 274.089622 -356.511606)
		(end 274.409662 -356.831646)
		(width 0.13462)
		(layer "F.Cu")
		(net "P5E_PEX2_STN4_TX_C_DP<76>")
	)
	(segment
		(start 294.647112 -398.09928)
		(end 294.216836 -398.09928)
		(width 0.1651)
		(layer "In11.Cu")
		(net "P5E_PEX2_STN4_TX_C_DP<76>")
	)
	(segment
		(start 290.589716 -391.930128)
		(end 291.132006 -392.143488)
		(width 0.1651)
		(layer "In11.Cu")
		(net "P5E_PEX2_STN4_TX_C_DP<76>")
	)
	(segment
		(start 274.405852 -358.04856)
		(end 274.405852 -358.802686)
		(width 0.1651)
		(layer "In11.Cu")
		(net "P5E_PEX2_STN4_TX_C_DP<76>")
	)
	(segment
		(start 289.963352 -391.683494)
		(end 290.01339 -391.79881)
		(width 0.1651)
		(layer "In11.Cu")
		(net "P5E_PEX2_STN4_TX_C_DP<76>")
	)
	(segment
		(start 291.132006 -392.143488)
		(end 291.979096 -392.693906)
		(width 0.1651)
		(layer "In11.Cu")
		(net "P5E_PEX2_STN4_TX_C_DP<76>")
	)
	(segment
		(start 288.875978 -391.255504)
		(end 288.92627 -391.37082)
		(width 0.1651)
		(layer "In11.Cu")
		(net "P5E_PEX2_STN4_TX_C_DP<76>")
	)
	(segment
		(start 292.58641 -393.088622)
		(end 293.027608 -393.375388)
		(width 0.1651)
		(layer "In11.Cu")
		(net "P5E_PEX2_STN4_TX_C_DP<76>")
	)
	(segment
		(start 281.37358 -378.761752)
		(end 282.256992 -385.929378)
		(width 0.1651)
		(layer "In11.Cu")
		(net "P5E_PEX2_STN4_TX_C_DP<76>")
	)
	(segment
		(start 294.109394 -394.74775)
		(end 294.441118 -395.11605)
		(width 0.1651)
		(layer "In11.Cu")
		(net "P5E_PEX2_STN4_TX_C_DP<76>")
	)
	(segment
		(start 289.38728 -391.55243)
		(end 289.502596 -391.502138)
		(width 0.1651)
		(layer "In11.Cu")
		(net "P5E_PEX2_STN4_TX_C_DP<76>")
	)
	(segment
		(start 294.089836 -397.97228)
		(end 294.089836 -397.59001)
		(width 0.1651)
		(layer "In11.Cu")
		(net "P5E_PEX2_STN4_TX_C_DP<76>")
	)
	(segment
		(start 292.012624 -392.852148)
		(end 292.428168 -393.12215)
		(width 0.1651)
		(layer "In11.Cu")
		(net "P5E_PEX2_STN4_TX_C_DP<76>")
	)
	(segment
		(start 282.256992 -385.929378)
		(end 283.205682 -387.816852)
		(width 0.1651)
		(layer "In11.Cu")
		(net "P5E_PEX2_STN4_TX_C_DP<76>")
	)
	(segment
		(start 292.428168 -393.12215)
		(end 292.58641 -393.088622)
		(width 0.1651)
		(layer "In11.Cu")
		(net "P5E_PEX2_STN4_TX_C_DP<76>")
	)
	(segment
		(start 288.299906 -391.12444)
		(end 288.415222 -391.074148)
		(width 0.1651)
		(layer "In11.Cu")
		(net "P5E_PEX2_STN4_TX_C_DP<76>")
	)
	(segment
		(start 294.441118 -395.11605)
		(end 294.602662 -395.124432)
		(width 0.1651)
		(layer "In11.Cu")
		(net "P5E_PEX2_STN4_TX_C_DP<76>")
	)
	(segment
		(start 291.979096 -392.693906)
		(end 292.012624 -392.852148)
		(width 0.1651)
		(layer "In11.Cu")
		(net "P5E_PEX2_STN4_TX_C_DP<76>")
	)
	(segment
		(start 274.405852 -358.802686)
		(end 281.37358 -378.761752)
		(width 0.1651)
		(layer "In11.Cu")
		(net "P5E_PEX2_STN4_TX_C_DP<76>")
	)
	(segment
		(start 289.502596 -391.502138)
		(end 289.963352 -391.683494)
		(width 0.1651)
		(layer "In11.Cu")
		(net "P5E_PEX2_STN4_TX_C_DP<76>")
	)
	(segment
		(start 287.838642 -390.94283)
		(end 288.299906 -391.12444)
		(width 0.1651)
		(layer "In11.Cu")
		(net "P5E_PEX2_STN4_TX_C_DP<76>")
	)
	(segment
		(start 285.327598 -389.859266)
		(end 287.788604 -390.827514)
		(width 0.1651)
		(layer "In11.Cu")
		(net "P5E_PEX2_STN4_TX_C_DP<76>")
	)
	(segment
		(start 290.01339 -391.79881)
		(end 290.474654 -391.98042)
		(width 0.1651)
		(layer "In11.Cu")
		(net "P5E_PEX2_STN4_TX_C_DP<76>")
	)
	(segment
		(start 288.415222 -391.074148)
		(end 288.875978 -391.255504)
		(width 0.1651)
		(layer "In11.Cu")
		(net "P5E_PEX2_STN4_TX_C_DP<76>")
	)
	(segment
		(start 288.92627 -391.37082)
		(end 289.38728 -391.55243)
		(width 0.1651)
		(layer "In11.Cu")
		(net "P5E_PEX2_STN4_TX_C_DP<76>")
	)
	(segment
		(start 290.474654 -391.98042)
		(end 290.589716 -391.930128)
		(width 0.1651)
		(layer "In11.Cu")
		(net "P5E_PEX2_STN4_TX_C_DP<76>")
	)
	(segment
		(start 293.027608 -393.375388)
		(end 294.11803 -394.586206)
		(width 0.1651)
		(layer "In11.Cu")
		(net "P5E_PEX2_STN4_TX_C_DP<76>")
	)
	(segment
		(start 274.115022 -357.75773)
		(end 274.405852 -358.04856)
		(width 0.1651)
		(layer "In11.Cu")
		(net "P5E_PEX2_STN4_TX_C_DP<76>")
	)
	(segment
		(start 287.788604 -390.827514)
		(end 287.838642 -390.94283)
		(width 0.1651)
		(layer "In11.Cu")
		(net "P5E_PEX2_STN4_TX_C_DP<76>")
	)
	(segment
		(start 294.216836 -398.09928)
		(end 294.089836 -397.97228)
		(width 0.1651)
		(layer "In11.Cu")
		(net "P5E_PEX2_STN4_TX_C_DP<76>")
	)
	(segment
		(start 283.205682 -387.816852)
		(end 285.327598 -389.859266)
		(width 0.1651)
		(layer "In11.Cu")
		(net "P5E_PEX2_STN4_TX_C_DP<76>")
	)
	(segment
		(start 294.11803 -394.586206)
		(end 294.109394 -394.74775)
		(width 0.1651)
		(layer "In11.Cu")
		(net "P5E_PEX2_STN4_TX_C_DP<76>")
	)
	(segment
		(start 294.933878 -397.812514)
		(end 294.647112 -398.09928)
		(width 0.1651)
		(layer "In11.Cu")
		(net "P5E_PEX2_STN4_TX_C_DP<76>")
	)
	(segment
		(start 294.602662 -395.124432)
		(end 294.933878 -395.492478)
		(width 0.1651)
		(layer "In11.Cu")
		(net "P5E_PEX2_STN4_TX_C_DP<76>")
	)
	(segment
		(start 294.933878 -395.492478)
		(end 294.933878 -397.812514)
		(width 0.1651)
		(layer "In11.Cu")
		(net "P5E_PEX2_STN4_TX_C_DP<76>")
	)
	(segment
		(start 12.231116 -125.894846)
		(end 11.5824 -125.894846)
		(width 0.13208)
		(layer "F.Cu")
		(net "PWRGD_P3V3_NIC0")
	)
	(segment
		(start 10.51052 -124.963428)
		(end 10.51052 -125.979428)
		(width 0.13208)
		(layer "F.Cu")
		(net "PWRGD_P3V3_NIC0")
	)
	(segment
		(start 11.5824 -125.894846)
		(end 11.495024 -125.982222)
		(width 0.13208)
		(layer "F.Cu")
		(net "PWRGD_P3V3_NIC0")
	)
	(segment
		(start 11.49223 -125.979428)
		(end 10.51052 -125.979428)
		(width 0.13208)
		(layer "F.Cu")
		(net "PWRGD_P3V3_NIC0")
	)
	(segment
		(start 11.495024 -125.982222)
		(end 11.49223 -125.979428)
		(width 0.13208)
		(layer "F.Cu")
		(net "PWRGD_P3V3_NIC0")
	)
	(via
		(at 11.495024 -125.982222)
		(size 0.508)
		(drill 0.254)
		(layers "F.Cu" "B.Cu")
		(net "PWRGD_P3V3_NIC0")
	)
	(segment
		(start 32.658558 -378.79909)
		(end 33.185862 -378.271786)
		(width 0.1651)
		(layer "In15.Cu")
		(net "P5E_PEX0_STN4_RX_DP<69>")
	)
	(segment
		(start 35.199066 -365.566198)
		(end 35.467036 -365.165132)
		(width 0.1651)
		(layer "In15.Cu")
		(net "P5E_PEX0_STN4_RX_DP<69>")
	)
	(segment
		(start 33.185862 -368.5794)
		(end 33.519364 -368.080036)
		(width 0.1651)
		(layer "In15.Cu")
		(net "P5E_PEX0_STN4_RX_DP<69>")
	)
	(segment
		(start 33.759648 -367.537492)
		(end 33.900618 -367.509552)
		(width 0.1651)
		(layer "In15.Cu")
		(net "P5E_PEX0_STN4_RX_DP<69>")
	)
	(segment
		(start 34.168588 -367.108486)
		(end 34.140648 -366.967516)
		(width 0.1651)
		(layer "In15.Cu")
		(net "P5E_PEX0_STN4_RX_DP<69>")
	)
	(segment
		(start 36.47821 -363.651292)
		(end 36.988242 -362.800646)
		(width 0.1651)
		(layer "In15.Cu")
		(net "P5E_PEX0_STN4_RX_DP<69>")
	)
	(segment
		(start 38.542722 -360.207306)
		(end 38.79088 -359.79354)
		(width 0.1651)
		(layer "In15.Cu")
		(net "P5E_PEX0_STN4_RX_DP<69>")
	)
	(segment
		(start 33.900618 -367.509552)
		(end 34.168588 -367.108486)
		(width 0.1651)
		(layer "In15.Cu")
		(net "P5E_PEX0_STN4_RX_DP<69>")
	)
	(segment
		(start 39.831518 -357.880158)
		(end 39.831518 -342.09228)
		(width 0.1651)
		(layer "In15.Cu")
		(net "P5E_PEX0_STN4_RX_DP<69>")
	)
	(segment
		(start 32.31007 -378.290074)
		(end 32.31007 -378.67209)
		(width 0.1651)
		(layer "In15.Cu")
		(net "P5E_PEX0_STN4_RX_DP<69>")
	)
	(segment
		(start 34.789618 -365.995966)
		(end 35.058096 -365.594392)
		(width 0.1651)
		(layer "In15.Cu")
		(net "P5E_PEX0_STN4_RX_DP<69>")
	)
	(segment
		(start 82.105246 -325.74484)
		(end 84.651342 -319.597532)
		(width 0.1651)
		(layer "In15.Cu")
		(net "P5E_PEX0_STN4_RX_DP<69>")
	)
	(segment
		(start 39.00424 -359.240074)
		(end 39.143686 -359.205022)
		(width 0.1651)
		(layer "In15.Cu")
		(net "P5E_PEX0_STN4_RX_DP<69>")
	)
	(segment
		(start 33.519364 -368.080036)
		(end 33.491424 -367.939066)
		(width 0.1651)
		(layer "In15.Cu")
		(net "P5E_PEX0_STN4_RX_DP<69>")
	)
	(segment
		(start 79.97952 -309.49392)
		(end 79.97952 -309.288688)
		(width 0.1143)
		(layer "In15.Cu")
		(net "P5E_PEX0_STN4_RX_DP<69>")
	)
	(segment
		(start 36.988242 -362.800646)
		(end 36.95319 -362.6612)
		(width 0.1651)
		(layer "In15.Cu")
		(net "P5E_PEX0_STN4_RX_DP<69>")
	)
	(segment
		(start 38.40353 -360.242358)
		(end 38.542976 -360.20756)
		(width 0.1651)
		(layer "In15.Cu")
		(net "P5E_PEX0_STN4_RX_DP<69>")
	)
	(segment
		(start 38.542976 -360.20756)
		(end 38.542722 -360.207306)
		(width 0.1651)
		(layer "In15.Cu")
		(net "P5E_PEX0_STN4_RX_DP<69>")
	)
	(segment
		(start 33.185862 -378.271786)
		(end 33.185862 -368.5794)
		(width 0.1651)
		(layer "In15.Cu")
		(net "P5E_PEX0_STN4_RX_DP<69>")
	)
	(segment
		(start 34.140648 -366.967516)
		(end 34.408872 -366.565942)
		(width 0.1651)
		(layer "In15.Cu")
		(net "P5E_PEX0_STN4_RX_DP<69>")
	)
	(segment
		(start 36.95319 -362.6612)
		(end 37.201602 -362.246926)
		(width 0.1651)
		(layer "In15.Cu")
		(net "P5E_PEX0_STN4_RX_DP<69>")
	)
	(segment
		(start 37.588952 -361.798362)
		(end 37.554154 -361.658916)
		(width 0.1651)
		(layer "In15.Cu")
		(net "P5E_PEX0_STN4_RX_DP<69>")
	)
	(segment
		(start 83.645248 -309.815738)
		(end 83.6168 -309.815738)
		(width 0.1143)
		(layer "In15.Cu")
		(net "P5E_PEX0_STN4_RX_DP<69>")
	)
	(segment
		(start 79.021686 -328.8284)
		(end 82.105246 -325.74484)
		(width 0.1651)
		(layer "In15.Cu")
		(net "P5E_PEX0_STN4_RX_DP<69>")
	)
	(segment
		(start 79.89062 -309.199788)
		(end 79.59979 -309.199788)
		(width 0.1143)
		(layer "In15.Cu")
		(net "P5E_PEX0_STN4_RX_DP<69>")
	)
	(segment
		(start 39.740332 -358.20985)
		(end 39.831518 -357.880158)
		(width 0.1651)
		(layer "In15.Cu")
		(net "P5E_PEX0_STN4_RX_DP<69>")
	)
	(segment
		(start 80.255618 -309.770018)
		(end 79.97952 -309.49392)
		(width 0.1143)
		(layer "In15.Cu")
		(net "P5E_PEX0_STN4_RX_DP<69>")
	)
	(segment
		(start 34.408872 -366.565942)
		(end 34.549842 -366.538002)
		(width 0.1651)
		(layer "In15.Cu")
		(net "P5E_PEX0_STN4_RX_DP<69>")
	)
	(segment
		(start 35.467036 -365.165132)
		(end 35.438842 -365.024162)
		(width 0.1651)
		(layer "In15.Cu")
		(net "P5E_PEX0_STN4_RX_DP<69>")
	)
	(segment
		(start 40.967406 -340.59876)
		(end 44.571158 -339.106002)
		(width 0.1651)
		(layer "In15.Cu")
		(net "P5E_PEX0_STN4_RX_DP<69>")
	)
	(segment
		(start 44.571158 -339.106002)
		(end 47.166022 -338.318856)
		(width 0.1651)
		(layer "In15.Cu")
		(net "P5E_PEX0_STN4_RX_DP<69>")
	)
	(segment
		(start 84.651342 -319.597532)
		(end 85.09 -317.393066)
		(width 0.1651)
		(layer "In15.Cu")
		(net "P5E_PEX0_STN4_RX_DP<69>")
	)
	(segment
		(start 35.058096 -365.594392)
		(end 35.199066 -365.566198)
		(width 0.1651)
		(layer "In15.Cu")
		(net "P5E_PEX0_STN4_RX_DP<69>")
	)
	(segment
		(start 85.09 -317.393066)
		(end 85.09 -310.685434)
		(width 0.1651)
		(layer "In15.Cu")
		(net "P5E_PEX0_STN4_RX_DP<69>")
	)
	(segment
		(start 40.084502 -341.481664)
		(end 40.967406 -340.59876)
		(width 0.1651)
		(layer "In15.Cu")
		(net "P5E_PEX0_STN4_RX_DP<69>")
	)
	(segment
		(start 34.549842 -366.538002)
		(end 34.817812 -366.136936)
		(width 0.1651)
		(layer "In15.Cu")
		(net "P5E_PEX0_STN4_RX_DP<69>")
	)
	(segment
		(start 37.201602 -362.246926)
		(end 37.341048 -362.212128)
		(width 0.1651)
		(layer "In15.Cu")
		(net "P5E_PEX0_STN4_RX_DP<69>")
	)
	(segment
		(start 34.817812 -366.136936)
		(end 34.789618 -365.995966)
		(width 0.1651)
		(layer "In15.Cu")
		(net "P5E_PEX0_STN4_RX_DP<69>")
	)
	(segment
		(start 32.31007 -378.67209)
		(end 32.43707 -378.79909)
		(width 0.1651)
		(layer "In15.Cu")
		(net "P5E_PEX0_STN4_RX_DP<69>")
	)
	(segment
		(start 37.802566 -361.244896)
		(end 37.942012 -361.209844)
		(width 0.1651)
		(layer "In15.Cu")
		(net "P5E_PEX0_STN4_RX_DP<69>")
	)
	(segment
		(start 38.79088 -359.79354)
		(end 38.755828 -359.654094)
		(width 0.1651)
		(layer "In15.Cu")
		(net "P5E_PEX0_STN4_RX_DP<69>")
	)
	(segment
		(start 32.43707 -378.79909)
		(end 32.658558 -378.79909)
		(width 0.1651)
		(layer "In15.Cu")
		(net "P5E_PEX0_STN4_RX_DP<69>")
	)
	(segment
		(start 83.57108 -309.770018)
		(end 80.255618 -309.770018)
		(width 0.1143)
		(layer "In15.Cu")
		(net "P5E_PEX0_STN4_RX_DP<69>")
	)
	(segment
		(start 35.70732 -364.622588)
		(end 35.84829 -364.594394)
		(width 0.1651)
		(layer "In15.Cu")
		(net "P5E_PEX0_STN4_RX_DP<69>")
	)
	(segment
		(start 33.491424 -367.939066)
		(end 33.759648 -367.537492)
		(width 0.1651)
		(layer "In15.Cu")
		(net "P5E_PEX0_STN4_RX_DP<69>")
	)
	(segment
		(start 38.755828 -359.654094)
		(end 39.00424 -359.240074)
		(width 0.1651)
		(layer "In15.Cu")
		(net "P5E_PEX0_STN4_RX_DP<69>")
	)
	(segment
		(start 85.09 -310.685434)
		(end 84.220304 -309.815738)
		(width 0.1651)
		(layer "In15.Cu")
		(net "P5E_PEX0_STN4_RX_DP<69>")
	)
	(segment
		(start 39.831518 -342.09228)
		(end 40.084502 -341.481664)
		(width 0.1651)
		(layer "In15.Cu")
		(net "P5E_PEX0_STN4_RX_DP<69>")
	)
	(segment
		(start 39.143686 -359.205022)
		(end 39.740332 -358.20985)
		(width 0.1651)
		(layer "In15.Cu")
		(net "P5E_PEX0_STN4_RX_DP<69>")
	)
	(segment
		(start 69.792596 -332.650592)
		(end 79.021686 -328.8284)
		(width 0.1651)
		(layer "In15.Cu")
		(net "P5E_PEX0_STN4_RX_DP<69>")
	)
	(segment
		(start 84.220304 -309.815738)
		(end 83.645248 -309.815738)
		(width 0.1651)
		(layer "In15.Cu")
		(net "P5E_PEX0_STN4_RX_DP<69>")
	)
	(segment
		(start 79.97952 -309.288688)
		(end 79.89062 -309.199788)
		(width 0.1143)
		(layer "In15.Cu")
		(net "P5E_PEX0_STN4_RX_DP<69>")
	)
	(segment
		(start 37.942012 -361.209844)
		(end 38.189916 -360.796078)
		(width 0.1651)
		(layer "In15.Cu")
		(net "P5E_PEX0_STN4_RX_DP<69>")
	)
	(segment
		(start 35.84829 -364.594394)
		(end 36.47821 -363.651292)
		(width 0.1651)
		(layer "In15.Cu")
		(net "P5E_PEX0_STN4_RX_DP<69>")
	)
	(segment
		(start 83.6168 -309.815738)
		(end 83.57108 -309.770018)
		(width 0.1143)
		(layer "In15.Cu")
		(net "P5E_PEX0_STN4_RX_DP<69>")
	)
	(segment
		(start 37.341048 -362.212128)
		(end 37.588952 -361.798362)
		(width 0.1651)
		(layer "In15.Cu")
		(net "P5E_PEX0_STN4_RX_DP<69>")
	)
	(segment
		(start 38.155118 -360.656632)
		(end 38.40353 -360.242358)
		(width 0.1651)
		(layer "In15.Cu")
		(net "P5E_PEX0_STN4_RX_DP<69>")
	)
	(segment
		(start 35.438842 -365.024162)
		(end 35.70732 -364.622588)
		(width 0.1651)
		(layer "In15.Cu")
		(net "P5E_PEX0_STN4_RX_DP<69>")
	)
	(segment
		(start 47.166022 -338.318856)
		(end 69.792596 -332.650592)
		(width 0.1651)
		(layer "In15.Cu")
		(net "P5E_PEX0_STN4_RX_DP<69>")
	)
	(segment
		(start 38.189916 -360.796078)
		(end 38.155118 -360.656632)
		(width 0.1651)
		(layer "In15.Cu")
		(net "P5E_PEX0_STN4_RX_DP<69>")
	)
	(segment
		(start 37.554154 -361.658916)
		(end 37.802566 -361.244896)
		(width 0.1651)
		(layer "In15.Cu")
		(net "P5E_PEX0_STN4_RX_DP<69>")
	)
	(segment
		(start 47.607728 -348.88043)
		(end 47.313088 -348.58579)
		(width 0.13462)
		(layer "F.Cu")
		(net "P5E_PEX0_STN4_TX_DP<66>")
	)
	(segment
		(start 47.607728 -349.511874)
		(end 47.607728 -348.88043)
		(width 0.13462)
		(layer "F.Cu")
		(net "P5E_PEX0_STN4_TX_DP<66>")
	)
	(segment
		(start 47.287688 -349.831914)
		(end 47.607728 -349.511874)
		(width 0.13462)
		(layer "F.Cu")
		(net "P5E_PEX0_STN4_TX_DP<66>")
	)
	(segment
		(start 79.21752 -332.809596)
		(end 94.06763 -327.495916)
		(width 0.1651)
		(layer "In11.Cu")
		(net "P5E_PEX0_STN4_TX_DP<66>")
	)
	(segment
		(start 97.347278 -322.433188)
		(end 97.347278 -319.3669)
		(width 0.1651)
		(layer "In11.Cu")
		(net "P5E_PEX0_STN4_TX_DP<66>")
	)
	(segment
		(start 96.176846 -316.540642)
		(end 94.009464 -314.37326)
		(width 0.1651)
		(layer "In11.Cu")
		(net "P5E_PEX0_STN4_TX_DP<66>")
	)
	(segment
		(start 47.313088 -348.58579)
		(end 47.603918 -348.29496)
		(width 0.1651)
		(layer "In11.Cu")
		(net "P5E_PEX0_STN4_TX_DP<66>")
	)
	(segment
		(start 75.22972 -306.438808)
		(end 75.14082 -306.349908)
		(width 0.1143)
		(layer "In11.Cu")
		(net "P5E_PEX0_STN4_TX_DP<66>")
	)
	(segment
		(start 83.57108 -306.91328)
		(end 75.499468 -306.91328)
		(width 0.1143)
		(layer "In11.Cu")
		(net "P5E_PEX0_STN4_TX_DP<66>")
	)
	(segment
		(start 94.00921 -314.37326)
		(end 91.526614 -313.344814)
		(width 0.1651)
		(layer "In11.Cu")
		(net "P5E_PEX0_STN4_TX_DP<66>")
	)
	(segment
		(start 83.899248 -306.959)
		(end 83.645248 -306.959)
		(width 0.1651)
		(layer "In11.Cu")
		(net "P5E_PEX0_STN4_TX_DP<66>")
	)
	(segment
		(start 47.603918 -348.29496)
		(end 47.603918 -347.620082)
		(width 0.1651)
		(layer "In11.Cu")
		(net "P5E_PEX0_STN4_TX_DP<66>")
	)
	(segment
		(start 91.526614 -313.344814)
		(end 85.765894 -307.584094)
		(width 0.1651)
		(layer "In11.Cu")
		(net "P5E_PEX0_STN4_TX_DP<66>")
	)
	(segment
		(start 83.6168 -306.959)
		(end 83.57108 -306.91328)
		(width 0.1143)
		(layer "In11.Cu")
		(net "P5E_PEX0_STN4_TX_DP<66>")
	)
	(segment
		(start 49.547526 -340.629494)
		(end 50.436272 -339.740494)
		(width 0.1651)
		(layer "In11.Cu")
		(net "P5E_PEX0_STN4_TX_DP<66>")
	)
	(segment
		(start 94.06763 -327.495916)
		(end 96.086676 -325.47687)
		(width 0.1651)
		(layer "In11.Cu")
		(net "P5E_PEX0_STN4_TX_DP<66>")
	)
	(segment
		(start 94.009464 -314.37326)
		(end 94.00921 -314.37326)
		(width 0.1651)
		(layer "In11.Cu")
		(net "P5E_PEX0_STN4_TX_DP<66>")
	)
	(segment
		(start 97.347278 -319.3669)
		(end 96.176846 -316.540642)
		(width 0.1651)
		(layer "In11.Cu")
		(net "P5E_PEX0_STN4_TX_DP<66>")
	)
	(segment
		(start 49.158398 -346.065602)
		(end 49.158398 -341.568786)
		(width 0.1651)
		(layer "In11.Cu")
		(net "P5E_PEX0_STN4_TX_DP<66>")
	)
	(segment
		(start 96.086676 -325.47687)
		(end 97.347278 -322.433188)
		(width 0.1651)
		(layer "In11.Cu")
		(net "P5E_PEX0_STN4_TX_DP<66>")
	)
	(segment
		(start 75.14082 -306.349908)
		(end 74.84999 -306.349908)
		(width 0.1143)
		(layer "In11.Cu")
		(net "P5E_PEX0_STN4_TX_DP<66>")
	)
	(segment
		(start 50.436272 -339.740494)
		(end 58.027062 -337.024472)
		(width 0.1651)
		(layer "In11.Cu")
		(net "P5E_PEX0_STN4_TX_DP<66>")
	)
	(segment
		(start 75.499468 -306.91328)
		(end 75.22972 -306.643532)
		(width 0.1143)
		(layer "In11.Cu")
		(net "P5E_PEX0_STN4_TX_DP<66>")
	)
	(segment
		(start 47.603918 -347.620082)
		(end 49.158398 -346.065602)
		(width 0.1651)
		(layer "In11.Cu")
		(net "P5E_PEX0_STN4_TX_DP<66>")
	)
	(segment
		(start 49.158398 -341.568786)
		(end 49.547526 -340.629494)
		(width 0.1651)
		(layer "In11.Cu")
		(net "P5E_PEX0_STN4_TX_DP<66>")
	)
	(segment
		(start 84.368132 -307.005228)
		(end 83.899248 -306.959)
		(width 0.1651)
		(layer "In11.Cu")
		(net "P5E_PEX0_STN4_TX_DP<66>")
	)
	(segment
		(start 83.645248 -306.959)
		(end 83.6168 -306.959)
		(width 0.1143)
		(layer "In11.Cu")
		(net "P5E_PEX0_STN4_TX_DP<66>")
	)
	(segment
		(start 85.765894 -307.584094)
		(end 84.368132 -307.005228)
		(width 0.1651)
		(layer "In11.Cu")
		(net "P5E_PEX0_STN4_TX_DP<66>")
	)
	(segment
		(start 58.027062 -337.024472)
		(end 79.21752 -332.809596)
		(width 0.1651)
		(layer "In11.Cu")
		(net "P5E_PEX0_STN4_TX_DP<66>")
	)
	(segment
		(start 75.22972 -306.643532)
		(end 75.22972 -306.438808)
		(width 0.1143)
		(layer "In11.Cu")
		(net "P5E_PEX0_STN4_TX_DP<66>")
	)
	(segment
		(start 286.845502 -345.170506)
		(end 286.550862 -345.465146)
		(width 0.13462)
		(layer "F.Cu")
		(net "P5E_PEX2_STN4_TX_C_DP<71>")
	)
	(segment
		(start 286.525462 -344.219022)
		(end 286.845502 -344.539062)
		(width 0.13462)
		(layer "F.Cu")
		(net "P5E_PEX2_STN4_TX_C_DP<71>")
	)
	(segment
		(start 286.845502 -344.539062)
		(end 286.845502 -345.170506)
		(width 0.13462)
		(layer "F.Cu")
		(net "P5E_PEX2_STN4_TX_C_DP<71>")
	)
	(segment
		(start 286.940498 -364.723172)
		(end 286.794956 -364.249462)
		(width 0.1651)
		(layer "In11.Cu")
		(net "P5E_PEX2_STN4_TX_C_DP<71>")
	)
	(segment
		(start 287.4899 -370.872258)
		(end 287.6169 -370.999258)
		(width 0.1651)
		(layer "In11.Cu")
		(net "P5E_PEX2_STN4_TX_C_DP<71>")
	)
	(segment
		(start 287.228788 -365.27232)
		(end 287.0835 -364.798864)
		(width 0.1651)
		(layer "In11.Cu")
		(net "P5E_PEX2_STN4_TX_C_DP<71>")
	)
	(segment
		(start 288.333942 -370.712492)
		(end 288.333942 -368.870738)
		(width 0.1651)
		(layer "In11.Cu")
		(net "P5E_PEX2_STN4_TX_C_DP<71>")
	)
	(segment
		(start 287.298384 -365.888778)
		(end 287.152842 -365.415068)
		(width 0.1651)
		(layer "In11.Cu")
		(net "P5E_PEX2_STN4_TX_C_DP<71>")
	)
	(segment
		(start 287.0835 -364.798864)
		(end 286.940498 -364.723172)
		(width 0.1651)
		(layer "In11.Cu")
		(net "P5E_PEX2_STN4_TX_C_DP<71>")
	)
	(segment
		(start 286.154876 -361.775502)
		(end 285.287212 -358.949498)
		(width 0.1651)
		(layer "In11.Cu")
		(net "P5E_PEX2_STN4_TX_C_DP<71>")
	)
	(segment
		(start 286.582358 -363.557566)
		(end 286.43707 -363.083856)
		(width 0.1651)
		(layer "In11.Cu")
		(net "P5E_PEX2_STN4_TX_C_DP<71>")
	)
	(segment
		(start 286.224472 -362.39196)
		(end 286.079184 -361.91825)
		(width 0.1651)
		(layer "In11.Cu")
		(net "P5E_PEX2_STN4_TX_C_DP<71>")
	)
	(segment
		(start 287.799272 -367.130076)
		(end 287.65627 -367.054384)
		(width 0.1651)
		(layer "In11.Cu")
		(net "P5E_PEX2_STN4_TX_C_DP<71>")
	)
	(segment
		(start 286.43707 -363.083856)
		(end 286.512762 -362.941108)
		(width 0.1651)
		(layer "In11.Cu")
		(net "P5E_PEX2_STN4_TX_C_DP<71>")
	)
	(segment
		(start 288.333942 -368.870738)
		(end 288.157412 -368.295682)
		(width 0.1651)
		(layer "In11.Cu")
		(net "P5E_PEX2_STN4_TX_C_DP<71>")
	)
	(segment
		(start 288.047176 -370.999258)
		(end 288.333942 -370.712492)
		(width 0.1651)
		(layer "In11.Cu")
		(net "P5E_PEX2_STN4_TX_C_DP<71>")
	)
	(segment
		(start 286.079184 -361.91825)
		(end 286.154876 -361.775502)
		(width 0.1651)
		(layer "In11.Cu")
		(net "P5E_PEX2_STN4_TX_C_DP<71>")
	)
	(segment
		(start 287.441386 -365.96447)
		(end 287.298384 -365.888778)
		(width 0.1651)
		(layer "In11.Cu")
		(net "P5E_PEX2_STN4_TX_C_DP<71>")
	)
	(segment
		(start 286.367474 -362.467652)
		(end 286.224472 -362.39196)
		(width 0.1651)
		(layer "In11.Cu")
		(net "P5E_PEX2_STN4_TX_C_DP<71>")
	)
	(segment
		(start 288.157412 -368.295682)
		(end 288.01441 -368.21999)
		(width 0.1651)
		(layer "In11.Cu")
		(net "P5E_PEX2_STN4_TX_C_DP<71>")
	)
	(segment
		(start 287.510728 -366.580674)
		(end 287.586674 -366.437926)
		(width 0.1651)
		(layer "In11.Cu")
		(net "P5E_PEX2_STN4_TX_C_DP<71>")
	)
	(segment
		(start 287.152842 -365.415068)
		(end 287.228788 -365.27232)
		(width 0.1651)
		(layer "In11.Cu")
		(net "P5E_PEX2_STN4_TX_C_DP<71>")
	)
	(segment
		(start 286.841692 -345.755976)
		(end 286.550862 -345.465146)
		(width 0.1651)
		(layer "In11.Cu")
		(net "P5E_PEX2_STN4_TX_C_DP<71>")
	)
	(segment
		(start 287.65627 -367.054384)
		(end 287.510728 -366.580674)
		(width 0.1651)
		(layer "In11.Cu")
		(net "P5E_PEX2_STN4_TX_C_DP<71>")
	)
	(segment
		(start 286.794956 -364.249462)
		(end 286.870648 -364.106714)
		(width 0.1651)
		(layer "In11.Cu")
		(net "P5E_PEX2_STN4_TX_C_DP<71>")
	)
	(segment
		(start 287.94456 -367.603532)
		(end 287.799272 -367.130076)
		(width 0.1651)
		(layer "In11.Cu")
		(net "P5E_PEX2_STN4_TX_C_DP<71>")
	)
	(segment
		(start 286.512762 -362.941108)
		(end 286.367474 -362.467652)
		(width 0.1651)
		(layer "In11.Cu")
		(net "P5E_PEX2_STN4_TX_C_DP<71>")
	)
	(segment
		(start 285.287212 -347.764354)
		(end 286.841692 -346.209874)
		(width 0.1651)
		(layer "In11.Cu")
		(net "P5E_PEX2_STN4_TX_C_DP<71>")
	)
	(segment
		(start 287.4899 -370.489988)
		(end 287.4899 -370.872258)
		(width 0.1651)
		(layer "In11.Cu")
		(net "P5E_PEX2_STN4_TX_C_DP<71>")
	)
	(segment
		(start 287.868868 -367.74628)
		(end 287.94456 -367.603532)
		(width 0.1651)
		(layer "In11.Cu")
		(net "P5E_PEX2_STN4_TX_C_DP<71>")
	)
	(segment
		(start 285.287212 -358.949498)
		(end 285.287212 -347.764354)
		(width 0.1651)
		(layer "In11.Cu")
		(net "P5E_PEX2_STN4_TX_C_DP<71>")
	)
	(segment
		(start 286.870648 -364.106714)
		(end 286.72536 -363.633258)
		(width 0.1651)
		(layer "In11.Cu")
		(net "P5E_PEX2_STN4_TX_C_DP<71>")
	)
	(segment
		(start 286.841692 -346.209874)
		(end 286.841692 -345.755976)
		(width 0.1651)
		(layer "In11.Cu")
		(net "P5E_PEX2_STN4_TX_C_DP<71>")
	)
	(segment
		(start 288.01441 -368.21999)
		(end 287.868868 -367.74628)
		(width 0.1651)
		(layer "In11.Cu")
		(net "P5E_PEX2_STN4_TX_C_DP<71>")
	)
	(segment
		(start 287.6169 -370.999258)
		(end 288.047176 -370.999258)
		(width 0.1651)
		(layer "In11.Cu")
		(net "P5E_PEX2_STN4_TX_C_DP<71>")
	)
	(segment
		(start 287.586674 -366.437926)
		(end 287.441386 -365.96447)
		(width 0.1651)
		(layer "In11.Cu")
		(net "P5E_PEX2_STN4_TX_C_DP<71>")
	)
	(segment
		(start 286.72536 -363.633258)
		(end 286.582358 -363.557566)
		(width 0.1651)
		(layer "In11.Cu")
		(net "P5E_PEX2_STN4_TX_C_DP<71>")
	)
	(segment
		(start 57.18556 -141.6558)
		(end 56.90616 -141.9352)
		(width 0.4572)
		(layer "F.Cu")
		(net "P3V3_NIC0")
	)
	(segment
		(start 62.23 -171.661328)
		(end 62.23 -172.329348)
		(width 0.4572)
		(layer "F.Cu")
		(net "P3V3_NIC0")
	)
	(segment
		(start 38.20795 -158.3944)
		(end 37.57295 -158.3944)
		(width 0.4064)
		(layer "F.Cu")
		(net "P3V3_NIC0")
	)
	(segment
		(start 63.16726 -171.675806)
		(end 63.16726 -172.343826)
		(width 0.4572)
		(layer "F.Cu")
		(net "P3V3_NIC0")
	)
	(segment
		(start 62.23 -170.77182)
		(end 62.23 -171.661328)
		(width 0.4572)
		(layer "F.Cu")
		(net "P3V3_NIC0")
	)
	(segment
		(start 9.71042 -125.979428)
		(end 9.0551 -125.979428)
		(width 0.4064)
		(layer "F.Cu")
		(net "P3V3_NIC0")
	)
	(segment
		(start 38.20795 -153.3144)
		(end 37.57295 -153.3144)
		(width 0.4064)
		(layer "F.Cu")
		(net "P3V3_NIC0")
	)
	(segment
		(start 38.20795 -157.3784)
		(end 37.57295 -157.3784)
		(width 0.4064)
		(layer "F.Cu")
		(net "P3V3_NIC0")
	)
	(segment
		(start 56.28005 -142.9512)
		(end 56.922416 -142.9512)
		(width 0.4064)
		(layer "F.Cu")
		(net "P3V3_NIC0")
	)
	(segment
		(start 61.493908 -166.070534)
		(end 61.493908 -166.705534)
		(width 0.4064)
		(layer "F.Cu")
		(net "P3V3_NIC0")
	)
	(segment
		(start 61.616082 -170.157902)
		(end 62.23 -170.77182)
		(width 0.4572)
		(layer "F.Cu")
		(net "P3V3_NIC0")
	)
	(segment
		(start 56.90616 -141.9352)
		(end 56.28005 -141.9352)
		(width 0.4064)
		(layer "F.Cu")
		(net "P3V3_NIC0")
	)
	(segment
		(start 12.609322 -119.505476)
		(end 12.609322 -120.11787)
		(width 0.4572)
		(layer "F.Cu")
		(net "P3V3_NIC0")
	)
	(segment
		(start 57.66435 -141.6558)
		(end 57.18556 -141.6558)
		(width 0.4572)
		(layer "F.Cu")
		(net "P3V3_NIC0")
	)
	(via
		(at 44.60621 -140.565378)
		(size 0.508)
		(drill 0.254)
		(layers "F.Cu" "B.Cu")
		(net "P3V3_NIC0")
	)
	(via
		(at 43.97121 -140.565378)
		(size 0.508)
		(drill 0.254)
		(layers "F.Cu" "B.Cu")
		(net "P3V3_NIC0")
	)
	(via
		(at 44.60621 -139.930378)
		(size 0.508)
		(drill 0.254)
		(layers "F.Cu" "B.Cu")
		(net "P3V3_NIC0")
	)
	(via
		(at 18.70202 -116.751608)
		(size 0.508)
		(drill 0.254)
		(layers "F.Cu" "B.Cu")
		(net "P3V3_NIC0")
	)
	(via
		(at 19.820382 -125.382782)
		(size 0.508)
		(drill 0.254)
		(layers "F.Cu" "B.Cu")
		(net "P3V3_NIC0")
	)
	(via
		(at 35.669474 -138.88847)
		(size 0.6604)
		(drill 0.3302)
		(layers "F.Cu" "B.Cu")
		(net "P3V3_NIC0")
	)
	(via
		(at 12.609322 -120.11787)
		(size 0.508)
		(drill 0.254)
		(layers "F.Cu" "B.Cu")
		(net "P3V3_NIC0")
	)
	(via
		(at 63.16726 -172.343826)
		(size 0.508)
		(drill 0.254)
		(layers "F.Cu" "B.Cu")
		(net "P3V3_NIC0")
	)
	(via
		(at 19.820382 -126.652782)
		(size 0.508)
		(drill 0.254)
		(layers "F.Cu" "B.Cu")
		(net "P3V3_NIC0")
	)
	(via
		(at 18.70202 -117.386608)
		(size 0.508)
		(drill 0.254)
		(layers "F.Cu" "B.Cu")
		(net "P3V3_NIC0")
	)
	(via
		(at 37.57295 -157.3784)
		(size 0.508)
		(drill 0.254)
		(layers "F.Cu" "B.Cu")
		(net "P3V3_NIC0")
	)
	(via
		(at 41.07561 -138.699748)
		(size 0.6604)
		(drill 0.3302)
		(layers "F.Cu" "B.Cu")
		(net "P3V3_NIC0")
	)
	(via
		(at 18.70202 -118.021608)
		(size 0.508)
		(drill 0.254)
		(layers "F.Cu" "B.Cu")
		(net "P3V3_NIC0")
	)
	(via
		(at 16.866362 -125.218698)
		(size 0.508)
		(drill 0.254)
		(layers "F.Cu" "B.Cu")
		(net "P3V3_NIC0")
	)
	(via
		(at 16.866362 -125.853698)
		(size 0.508)
		(drill 0.254)
		(layers "F.Cu" "B.Cu")
		(net "P3V3_NIC0")
	)
	(via
		(at 18.151094 -126.530354)
		(size 0.508)
		(drill 0.254)
		(layers "F.Cu" "B.Cu")
		(net "P3V3_NIC0")
	)
	(via
		(at 29.854906 -139.171172)
		(size 0.6604)
		(drill 0.3302)
		(layers "F.Cu" "B.Cu")
		(net "P3V3_NIC0")
	)
	(via
		(at 15.9258 -124.768356)
		(size 0.508)
		(drill 0.254)
		(layers "F.Cu" "B.Cu")
		(net "P3V3_NIC0")
	)
	(via
		(at 48.54575 -155.0416)
		(size 0.508)
		(drill 0.254)
		(layers "F.Cu" "B.Cu")
		(net "P3V3_NIC0")
	)
	(via
		(at 56.922416 -142.9512)
		(size 0.508)
		(drill 0.254)
		(layers "F.Cu" "B.Cu")
		(net "P3V3_NIC0")
	)
	(via
		(at 61.493908 -166.705534)
		(size 0.508)
		(drill 0.254)
		(layers "F.Cu" "B.Cu")
		(net "P3V3_NIC0")
	)
	(via
		(at 18.06702 -116.751608)
		(size 0.508)
		(drill 0.254)
		(layers "F.Cu" "B.Cu")
		(net "P3V3_NIC0")
	)
	(via
		(at 9.0551 -125.979428)
		(size 0.508)
		(drill 0.254)
		(layers "F.Cu" "B.Cu")
		(net "P3V3_NIC0")
	)
	(via
		(at 18.06702 -118.021608)
		(size 0.508)
		(drill 0.254)
		(layers "F.Cu" "B.Cu")
		(net "P3V3_NIC0")
	)
	(via
		(at 37.57295 -158.3944)
		(size 0.508)
		(drill 0.254)
		(layers "F.Cu" "B.Cu")
		(net "P3V3_NIC0")
	)
	(via
		(at 19.820382 -126.017782)
		(size 0.508)
		(drill 0.254)
		(layers "F.Cu" "B.Cu")
		(net "P3V3_NIC0")
	)
	(via
		(at 15.9258 -125.403356)
		(size 0.508)
		(drill 0.254)
		(layers "F.Cu" "B.Cu")
		(net "P3V3_NIC0")
	)
	(via
		(at 56.90616 -141.9352)
		(size 0.508)
		(drill 0.254)
		(layers "F.Cu" "B.Cu")
		(net "P3V3_NIC0")
	)
	(via
		(at 37.57295 -153.3144)
		(size 0.508)
		(drill 0.254)
		(layers "F.Cu" "B.Cu")
		(net "P3V3_NIC0")
	)
	(via
		(at 18.786094 -125.768354)
		(size 0.508)
		(drill 0.254)
		(layers "F.Cu" "B.Cu")
		(net "P3V3_NIC0")
	)
	(via
		(at 62.23 -172.329348)
		(size 0.508)
		(drill 0.254)
		(layers "F.Cu" "B.Cu")
		(net "P3V3_NIC0")
	)
	(via
		(at 18.151094 -125.768354)
		(size 0.508)
		(drill 0.254)
		(layers "F.Cu" "B.Cu")
		(net "P3V3_NIC0")
	)
	(via
		(at 18.06702 -117.386608)
		(size 0.508)
		(drill 0.254)
		(layers "F.Cu" "B.Cu")
		(net "P3V3_NIC0")
	)
	(via
		(at 19.820382 -124.747782)
		(size 0.508)
		(drill 0.254)
		(layers "F.Cu" "B.Cu")
		(net "P3V3_NIC0")
	)
	(via
		(at 18.786094 -126.530354)
		(size 0.508)
		(drill 0.254)
		(layers "F.Cu" "B.Cu")
		(net "P3V3_NIC0")
	)
	(via
		(at 43.97121 -139.930378)
		(size 0.508)
		(drill 0.254)
		(layers "F.Cu" "B.Cu")
		(net "P3V3_NIC0")
	)
	(segment
		(start 49.15535 -155.0416)
		(end 48.54575 -155.0416)
		(width 0.4572)
		(layer "B.Cu")
		(net "P3V3_NIC0")
	)
	(segment
		(start 25.550368 -345.465146)
		(end 25.845008 -345.170506)
		(width 0.13462)
		(layer "F.Cu")
		(net "P5E_PEX0_STN4_TX_C_DP<77>")
	)
	(segment
		(start 25.845008 -345.170506)
		(end 25.845008 -344.539062)
		(width 0.13462)
		(layer "F.Cu")
		(net "P5E_PEX0_STN4_TX_C_DP<77>")
	)
	(segment
		(start 25.845008 -344.539062)
		(end 25.524968 -344.219022)
		(width 0.13462)
		(layer "F.Cu")
		(net "P5E_PEX0_STN4_TX_C_DP<77>")
	)
	(segment
		(start 22.996652 -387.966966)
		(end 21.543264 -384.45821)
		(width 0.1651)
		(layer "In11.Cu")
		(net "P5E_PEX0_STN4_TX_C_DP<77>")
	)
	(segment
		(start 25.841198 -346.322142)
		(end 25.841198 -345.755976)
		(width 0.1651)
		(layer "In11.Cu")
		(net "P5E_PEX0_STN4_TX_C_DP<77>")
	)
	(segment
		(start 32.290512 -394.237972)
		(end 31.87827 -393.962382)
		(width 0.1651)
		(layer "In11.Cu")
		(net "P5E_PEX0_STN4_TX_C_DP<77>")
	)
	(segment
		(start 32.31007 -396.872206)
		(end 32.43707 -396.999206)
		(width 0.1651)
		(layer "In11.Cu")
		(net "P5E_PEX0_STN4_TX_C_DP<77>")
	)
	(segment
		(start 32.825436 -394.488416)
		(end 32.413702 -394.213334)
		(width 0.1651)
		(layer "In11.Cu")
		(net "P5E_PEX0_STN4_TX_C_DP<77>")
	)
	(segment
		(start 33.202372 -396.630144)
		(end 33.202372 -394.865352)
		(width 0.1651)
		(layer "In11.Cu")
		(net "P5E_PEX0_STN4_TX_C_DP<77>")
	)
	(segment
		(start 30.90672 -393.313158)
		(end 30.882336 -393.189968)
		(width 0.1651)
		(layer "In11.Cu")
		(net "P5E_PEX0_STN4_TX_C_DP<77>")
	)
	(segment
		(start 30.882336 -393.189968)
		(end 27.780234 -391.117328)
		(width 0.1651)
		(layer "In11.Cu")
		(net "P5E_PEX0_STN4_TX_C_DP<77>")
	)
	(segment
		(start 32.43707 -396.999206)
		(end 32.83331 -396.999206)
		(width 0.1651)
		(layer "In11.Cu")
		(net "P5E_PEX0_STN4_TX_C_DP<77>")
	)
	(segment
		(start 31.87827 -393.962382)
		(end 31.853886 -393.839192)
		(width 0.1651)
		(layer "In11.Cu")
		(net "P5E_PEX0_STN4_TX_C_DP<77>")
	)
	(segment
		(start 25.841198 -345.755976)
		(end 25.550368 -345.465146)
		(width 0.1651)
		(layer "In11.Cu")
		(net "P5E_PEX0_STN4_TX_C_DP<77>")
	)
	(segment
		(start 23.219664 -360.378248)
		(end 24.286718 -358.381808)
		(width 0.1651)
		(layer "In11.Cu")
		(net "P5E_PEX0_STN4_TX_C_DP<77>")
	)
	(segment
		(start 31.853886 -393.839192)
		(end 31.442152 -393.56411)
		(width 0.1651)
		(layer "In11.Cu")
		(net "P5E_PEX0_STN4_TX_C_DP<77>")
	)
	(segment
		(start 24.286718 -347.876622)
		(end 25.841198 -346.322142)
		(width 0.1651)
		(layer "In11.Cu")
		(net "P5E_PEX0_STN4_TX_C_DP<77>")
	)
	(segment
		(start 21.760688 -367.713514)
		(end 23.219664 -360.378248)
		(width 0.1651)
		(layer "In11.Cu")
		(net "P5E_PEX0_STN4_TX_C_DP<77>")
	)
	(segment
		(start 24.991822 -389.962136)
		(end 22.996652 -387.966966)
		(width 0.1651)
		(layer "In11.Cu")
		(net "P5E_PEX0_STN4_TX_C_DP<77>")
	)
	(segment
		(start 24.286718 -358.381808)
		(end 24.286718 -347.876622)
		(width 0.1651)
		(layer "In11.Cu")
		(net "P5E_PEX0_STN4_TX_C_DP<77>")
	)
	(segment
		(start 21.760688 -368.119914)
		(end 21.760688 -367.713514)
		(width 0.1651)
		(layer "In11.Cu")
		(net "P5E_PEX0_STN4_TX_C_DP<77>")
	)
	(segment
		(start 32.31007 -396.49019)
		(end 32.31007 -396.872206)
		(width 0.1651)
		(layer "In11.Cu")
		(net "P5E_PEX0_STN4_TX_C_DP<77>")
	)
	(segment
		(start 21.543264 -384.45821)
		(end 21.543264 -381.615442)
		(width 0.1651)
		(layer "In11.Cu")
		(net "P5E_PEX0_STN4_TX_C_DP<77>")
	)
	(segment
		(start 31.318962 -393.588748)
		(end 30.90672 -393.313158)
		(width 0.1651)
		(layer "In11.Cu")
		(net "P5E_PEX0_STN4_TX_C_DP<77>")
	)
	(segment
		(start 32.83331 -396.999206)
		(end 33.202372 -396.630144)
		(width 0.1651)
		(layer "In11.Cu")
		(net "P5E_PEX0_STN4_TX_C_DP<77>")
	)
	(segment
		(start 31.442152 -393.56411)
		(end 31.318962 -393.588748)
		(width 0.1651)
		(layer "In11.Cu")
		(net "P5E_PEX0_STN4_TX_C_DP<77>")
	)
	(segment
		(start 32.413702 -394.213334)
		(end 32.290512 -394.237972)
		(width 0.1651)
		(layer "In11.Cu")
		(net "P5E_PEX0_STN4_TX_C_DP<77>")
	)
	(segment
		(start 27.780234 -391.117328)
		(end 24.991822 -389.962136)
		(width 0.1651)
		(layer "In11.Cu")
		(net "P5E_PEX0_STN4_TX_C_DP<77>")
	)
	(segment
		(start 21.543264 -381.615442)
		(end 21.760688 -368.119914)
		(width 0.1651)
		(layer "In11.Cu")
		(net "P5E_PEX0_STN4_TX_C_DP<77>")
	)
	(segment
		(start 33.202372 -394.865352)
		(end 32.825436 -394.488416)
		(width 0.1651)
		(layer "In11.Cu")
		(net "P5E_PEX0_STN4_TX_C_DP<77>")
	)
	(segment
		(start 303.68621 -363.899196)
		(end 303.829466 -363.891068)
		(width 0.1651)
		(layer "In15.Cu")
		(net "P5E_PEX2_STN4_RX_DP<66>")
	)
	(segment
		(start 314.734956 -340.957916)
		(end 317.1698 -337.927188)
		(width 0.1651)
		(layer "In15.Cu")
		(net "P5E_PEX2_STN4_RX_DP<66>")
	)
	(segment
		(start 302.23841 -365.671608)
		(end 302.568356 -365.302546)
		(width 0.1651)
		(layer "In15.Cu")
		(net "P5E_PEX2_STN4_RX_DP<66>")
	)
	(segment
		(start 303.033938 -364.781338)
		(end 303.363884 -364.412276)
		(width 0.1651)
		(layer "In15.Cu")
		(net "P5E_PEX2_STN4_RX_DP<66>")
	)
	(segment
		(start 328.7014 -318.713612)
		(end 327.981564 -316.975998)
		(width 0.1651)
		(layer "In15.Cu")
		(net "P5E_PEX2_STN4_RX_DP<66>")
	)
	(segment
		(start 317.91783 -336.996278)
		(end 317.902336 -336.85353)
		(width 0.1651)
		(layer "In15.Cu")
		(net "P5E_PEX2_STN4_RX_DP<66>")
	)
	(segment
		(start 317.464694 -337.398106)
		(end 317.607696 -337.382358)
		(width 0.1651)
		(layer "In15.Cu")
		(net "P5E_PEX2_STN4_RX_DP<66>")
	)
	(segment
		(start 318.212724 -336.467196)
		(end 318.355472 -336.451702)
		(width 0.1651)
		(layer "In15.Cu")
		(net "P5E_PEX2_STN4_RX_DP<66>")
	)
	(segment
		(start 324.672452 -312.023252)
		(end 321.22364 -308.574694)
		(width 0.1651)
		(layer "In15.Cu")
		(net "P5E_PEX2_STN4_RX_DP<66>")
	)
	(segment
		(start 318.213994 -306.965858)
		(end 315.852048 -306.965858)
		(width 0.1651)
		(layer "In15.Cu")
		(net "P5E_PEX2_STN4_RX_DP<66>")
	)
	(segment
		(start 303.363884 -364.412276)
		(end 303.355756 -364.268766)
		(width 0.1651)
		(layer "In15.Cu")
		(net "P5E_PEX2_STN4_RX_DP<66>")
	)
	(segment
		(start 318.665606 -336.065622)
		(end 318.650112 -335.922874)
		(width 0.1651)
		(layer "In15.Cu")
		(net "P5E_PEX2_STN4_RX_DP<66>")
	)
	(segment
		(start 298.616878 -379.899164)
		(end 299.047154 -379.899164)
		(width 0.1651)
		(layer "In15.Cu")
		(net "P5E_PEX2_STN4_RX_DP<66>")
	)
	(segment
		(start 318.650112 -335.922874)
		(end 318.9605 -335.53654)
		(width 0.1651)
		(layer "In15.Cu")
		(net "P5E_PEX2_STN4_RX_DP<66>")
	)
	(segment
		(start 299.33392 -369.479068)
		(end 299.94098 -368.242342)
		(width 0.1651)
		(layer "In15.Cu")
		(net "P5E_PEX2_STN4_RX_DP<66>")
	)
	(segment
		(start 327.84669 -324.638416)
		(end 328.7014 -322.575174)
		(width 0.1651)
		(layer "In15.Cu")
		(net "P5E_PEX2_STN4_RX_DP<66>")
	)
	(segment
		(start 314.294774 -306.920138)
		(end 314.079636 -306.705)
		(width 0.1143)
		(layer "In15.Cu")
		(net "P5E_PEX2_STN4_RX_DP<66>")
	)
	(segment
		(start 314.348114 -342.071198)
		(end 314.734956 -340.957916)
		(width 0.1651)
		(layer "In15.Cu")
		(net "P5E_PEX2_STN4_RX_DP<66>")
	)
	(segment
		(start 302.568356 -365.302546)
		(end 302.560228 -365.159036)
		(width 0.1651)
		(layer "In15.Cu")
		(net "P5E_PEX2_STN4_RX_DP<66>")
	)
	(segment
		(start 298.489878 -379.390148)
		(end 298.489878 -379.772164)
		(width 0.1651)
		(layer "In15.Cu")
		(net "P5E_PEX2_STN4_RX_DP<66>")
	)
	(segment
		(start 319.103248 -335.521046)
		(end 327.84669 -324.638416)
		(width 0.1651)
		(layer "In15.Cu")
		(net "P5E_PEX2_STN4_RX_DP<66>")
	)
	(segment
		(start 321.22364 -308.574694)
		(end 318.213994 -306.965858)
		(width 0.1651)
		(layer "In15.Cu")
		(net "P5E_PEX2_STN4_RX_DP<66>")
	)
	(segment
		(start 313.965336 -306.349908)
		(end 313.699906 -306.349908)
		(width 0.1143)
		(layer "In15.Cu")
		(net "P5E_PEX2_STN4_RX_DP<66>")
	)
	(segment
		(start 301.772828 -366.192562)
		(end 301.7647 -366.049306)
		(width 0.1651)
		(layer "In15.Cu")
		(net "P5E_PEX2_STN4_RX_DP<66>")
	)
	(segment
		(start 302.560228 -365.159036)
		(end 302.890682 -364.789466)
		(width 0.1651)
		(layer "In15.Cu")
		(net "P5E_PEX2_STN4_RX_DP<66>")
	)
	(segment
		(start 318.355472 -336.451702)
		(end 318.665606 -336.065622)
		(width 0.1651)
		(layer "In15.Cu")
		(net "P5E_PEX2_STN4_RX_DP<66>")
	)
	(segment
		(start 314.079636 -306.464208)
		(end 313.965336 -306.349908)
		(width 0.1143)
		(layer "In15.Cu")
		(net "P5E_PEX2_STN4_RX_DP<66>")
	)
	(segment
		(start 318.9605 -335.53654)
		(end 319.103248 -335.521046)
		(width 0.1651)
		(layer "In15.Cu")
		(net "P5E_PEX2_STN4_RX_DP<66>")
	)
	(segment
		(start 303.829466 -363.891068)
		(end 314.062364 -352.44151)
		(width 0.1651)
		(layer "In15.Cu")
		(net "P5E_PEX2_STN4_RX_DP<66>")
	)
	(segment
		(start 314.079636 -306.705)
		(end 314.079636 -306.464208)
		(width 0.1143)
		(layer "In15.Cu")
		(net "P5E_PEX2_STN4_RX_DP<66>")
	)
	(segment
		(start 317.902336 -336.85353)
		(end 318.212724 -336.467196)
		(width 0.1651)
		(layer "In15.Cu")
		(net "P5E_PEX2_STN4_RX_DP<66>")
	)
	(segment
		(start 299.047154 -379.899164)
		(end 299.33392 -379.612398)
		(width 0.1651)
		(layer "In15.Cu")
		(net "P5E_PEX2_STN4_RX_DP<66>")
	)
	(segment
		(start 301.7647 -366.049306)
		(end 302.095154 -365.679736)
		(width 0.1651)
		(layer "In15.Cu")
		(net "P5E_PEX2_STN4_RX_DP<66>")
	)
	(segment
		(start 317.154306 -337.78444)
		(end 317.464694 -337.398106)
		(width 0.1651)
		(layer "In15.Cu")
		(net "P5E_PEX2_STN4_RX_DP<66>")
	)
	(segment
		(start 315.8236 -306.965858)
		(end 315.77788 -306.920138)
		(width 0.1143)
		(layer "In15.Cu")
		(net "P5E_PEX2_STN4_RX_DP<66>")
	)
	(segment
		(start 315.852048 -306.965858)
		(end 315.8236 -306.965858)
		(width 0.1143)
		(layer "In15.Cu")
		(net "P5E_PEX2_STN4_RX_DP<66>")
	)
	(segment
		(start 327.981564 -316.975998)
		(end 324.672452 -312.023252)
		(width 0.1651)
		(layer "In15.Cu")
		(net "P5E_PEX2_STN4_RX_DP<66>")
	)
	(segment
		(start 314.348114 -351.693734)
		(end 314.348114 -342.071198)
		(width 0.1651)
		(layer "In15.Cu")
		(net "P5E_PEX2_STN4_RX_DP<66>")
	)
	(segment
		(start 299.94098 -368.242342)
		(end 301.772828 -366.192562)
		(width 0.1651)
		(layer "In15.Cu")
		(net "P5E_PEX2_STN4_RX_DP<66>")
	)
	(segment
		(start 315.77788 -306.920138)
		(end 314.294774 -306.920138)
		(width 0.1143)
		(layer "In15.Cu")
		(net "P5E_PEX2_STN4_RX_DP<66>")
	)
	(segment
		(start 328.7014 -322.575174)
		(end 328.7014 -318.713612)
		(width 0.1651)
		(layer "In15.Cu")
		(net "P5E_PEX2_STN4_RX_DP<66>")
	)
	(segment
		(start 314.062364 -352.44151)
		(end 314.348114 -351.693734)
		(width 0.1651)
		(layer "In15.Cu")
		(net "P5E_PEX2_STN4_RX_DP<66>")
	)
	(segment
		(start 299.33392 -379.612398)
		(end 299.33392 -369.479068)
		(width 0.1651)
		(layer "In15.Cu")
		(net "P5E_PEX2_STN4_RX_DP<66>")
	)
	(segment
		(start 317.1698 -337.927188)
		(end 317.154306 -337.78444)
		(width 0.1651)
		(layer "In15.Cu")
		(net "P5E_PEX2_STN4_RX_DP<66>")
	)
	(segment
		(start 303.355756 -364.268766)
		(end 303.68621 -363.899196)
		(width 0.1651)
		(layer "In15.Cu")
		(net "P5E_PEX2_STN4_RX_DP<66>")
	)
	(segment
		(start 298.489878 -379.772164)
		(end 298.616878 -379.899164)
		(width 0.1651)
		(layer "In15.Cu")
		(net "P5E_PEX2_STN4_RX_DP<66>")
	)
	(segment
		(start 302.095154 -365.679736)
		(end 302.23841 -365.671608)
		(width 0.1651)
		(layer "In15.Cu")
		(net "P5E_PEX2_STN4_RX_DP<66>")
	)
	(segment
		(start 302.890682 -364.789466)
		(end 303.033938 -364.781338)
		(width 0.1651)
		(layer "In15.Cu")
		(net "P5E_PEX2_STN4_RX_DP<66>")
	)
	(segment
		(start 317.607696 -337.382358)
		(end 317.91783 -336.996278)
		(width 0.1651)
		(layer "In15.Cu")
		(net "P5E_PEX2_STN4_RX_DP<66>")
	)
	(segment
		(start 299.875702 -356.511606)
		(end 299.555662 -356.831646)
		(width 0.13462)
		(layer "F.Cu")
		(net "P5E_PEX2_STN4_TX_C_DN<64>")
	)
	(segment
		(start 299.555662 -357.46309)
		(end 299.850302 -357.75773)
		(width 0.13462)
		(layer "F.Cu")
		(net "P5E_PEX2_STN4_TX_C_DN<64>")
	)
	(segment
		(start 299.555662 -356.831646)
		(end 299.555662 -357.46309)
		(width 0.13462)
		(layer "F.Cu")
		(net "P5E_PEX2_STN4_TX_C_DN<64>")
	)
	(segment
		(start 302.88992 -372.508018)
		(end 302.88992 -372.890034)
		(width 0.1651)
		(layer "In11.Cu")
		(net "P5E_PEX2_STN4_TX_C_DN<64>")
	)
	(segment
		(start 303.01692 -372.381018)
		(end 302.88992 -372.508018)
		(width 0.1651)
		(layer "In11.Cu")
		(net "P5E_PEX2_STN4_TX_C_DN<64>")
	)
	(segment
		(start 299.559472 -358.04856)
		(end 299.559472 -358.90708)
		(width 0.1651)
		(layer "In11.Cu")
		(net "P5E_PEX2_STN4_TX_C_DN<64>")
	)
	(segment
		(start 304.015902 -368.7826)
		(end 304.015902 -371.929152)
		(width 0.1651)
		(layer "In11.Cu")
		(net "P5E_PEX2_STN4_TX_C_DN<64>")
	)
	(segment
		(start 299.850302 -357.75773)
		(end 299.559472 -358.04856)
		(width 0.1651)
		(layer "In11.Cu")
		(net "P5E_PEX2_STN4_TX_C_DN<64>")
	)
	(segment
		(start 304.015902 -371.929152)
		(end 303.564036 -372.381018)
		(width 0.1651)
		(layer "In11.Cu")
		(net "P5E_PEX2_STN4_TX_C_DN<64>")
	)
	(segment
		(start 303.564036 -372.381018)
		(end 303.01692 -372.381018)
		(width 0.1651)
		(layer "In11.Cu")
		(net "P5E_PEX2_STN4_TX_C_DN<64>")
	)
	(segment
		(start 299.559472 -358.90708)
		(end 304.015902 -368.7826)
		(width 0.1651)
		(layer "In11.Cu")
		(net "P5E_PEX2_STN4_TX_C_DN<64>")
	)
	(segment
		(start 9.71042 -124.963428)
		(end 9.0551 -124.963428)
		(width 0.13208)
		(layer "F.Cu")
		(net "PWRGD_P3V3_NIC0_R")
	)
	(segment
		(start 10.577322 -119.505476)
		(end 10.577322 -120.248426)
		(width 0.13208)
		(layer "F.Cu")
		(net "PWRGD_P3V3_NIC0_R")
	)
	(segment
		(start 346.893896 -223.987106)
		(end 347.293692 -224.386902)
		(width 0.13208)
		(layer "F.Cu")
		(net "PWRGD_P3V3_NIC0_R")
	)
	(via
		(at 9.0551 -124.963428)
		(size 0.508)
		(drill 0.254)
		(layers "F.Cu" "B.Cu")
		(net "PWRGD_P3V3_NIC0_R")
	)
	(via
		(at 347.293692 -224.386902)
		(size 0.4572)
		(drill 0.254)
		(layers "F.Cu" "B.Cu")
		(net "PWRGD_P3V3_NIC0_R")
	)
	(via
		(at 10.577322 -120.248426)
		(size 0.508)
		(drill 0.254)
		(layers "F.Cu" "B.Cu")
		(net "PWRGD_P3V3_NIC0_R")
	)
	(via
		(at 31.098998 -218.63685)
		(size 0.508)
		(drill 0.254)
		(layers "F.Cu" "B.Cu")
		(net "PWRGD_P3V3_NIC0_R")
	)
	(segment
		(start 9.565386 -121.260362)
		(end 10.577322 -120.248426)
		(width 0.15494)
		(layer "In5.Cu")
		(net "PWRGD_P3V3_NIC0_R")
	)
	(segment
		(start 9.0551 -124.963428)
		(end 6.778244 -124.963428)
		(width 0.15494)
		(layer "In5.Cu")
		(net "PWRGD_P3V3_NIC0_R")
	)
	(segment
		(start 9.565386 -124.453142)
		(end 9.565386 -121.260362)
		(width 0.15494)
		(layer "In5.Cu")
		(net "PWRGD_P3V3_NIC0_R")
	)
	(segment
		(start 9.853422 -216.941908)
		(end 29.404056 -216.941908)
		(width 0.15494)
		(layer "In5.Cu")
		(net "PWRGD_P3V3_NIC0_R")
	)
	(segment
		(start 29.404056 -216.941908)
		(end 31.098998 -218.63685)
		(width 0.15494)
		(layer "In5.Cu")
		(net "PWRGD_P3V3_NIC0_R")
	)
	(segment
		(start 9.0551 -124.963428)
		(end 9.565386 -124.453142)
		(width 0.15494)
		(layer "In5.Cu")
		(net "PWRGD_P3V3_NIC0_R")
	)
	(segment
		(start 5.885688 -125.855984)
		(end 5.885688 -212.974174)
		(width 0.15494)
		(layer "In5.Cu")
		(net "PWRGD_P3V3_NIC0_R")
	)
	(segment
		(start 6.778244 -124.963428)
		(end 5.885688 -125.855984)
		(width 0.15494)
		(layer "In5.Cu")
		(net "PWRGD_P3V3_NIC0_R")
	)
	(segment
		(start 5.885688 -212.974174)
		(end 9.853422 -216.941908)
		(width 0.15494)
		(layer "In5.Cu")
		(net "PWRGD_P3V3_NIC0_R")
	)
	(segment
		(start 341.9856 -238.5568)
		(end 343.078054 -238.5568)
		(width 0.15494)
		(layer "In13.Cu")
		(net "PWRGD_P3V3_NIC0_R")
	)
	(segment
		(start 129.960624 -224.788476)
		(end 140.025374 -234.853226)
		(width 0.15494)
		(layer "In13.Cu")
		(net "PWRGD_P3V3_NIC0_R")
	)
	(segment
		(start 214.967058 -239.20323)
		(end 221.47657 -239.20323)
		(width 0.15494)
		(layer "In13.Cu")
		(net "PWRGD_P3V3_NIC0_R")
	)
	(segment
		(start 346.583 -235.3564)
		(end 346.583 -234.696)
		(width 0.15494)
		(layer "In13.Cu")
		(net "PWRGD_P3V3_NIC0_R")
	)
	(segment
		(start 345.841574 -235.742226)
		(end 346.197174 -235.742226)
		(width 0.15494)
		(layer "In13.Cu")
		(net "PWRGD_P3V3_NIC0_R")
	)
	(segment
		(start 207.749648 -239.6998)
		(end 214.470488 -239.6998)
		(width 0.15494)
		(layer "In13.Cu")
		(net "PWRGD_P3V3_NIC0_R")
	)
	(segment
		(start 344.9066 -237.363)
		(end 345.5797 -236.6899)
		(width 0.15494)
		(layer "In13.Cu")
		(net "PWRGD_P3V3_NIC0_R")
	)
	(segment
		(start 329.38593 -241.6302)
		(end 338.9122 -241.6302)
		(width 0.15494)
		(layer "In13.Cu")
		(net "PWRGD_P3V3_NIC0_R")
	)
	(segment
		(start 100.226114 -211.55406)
		(end 100.939854 -212.2678)
		(width 0.15494)
		(layer "In13.Cu")
		(net "PWRGD_P3V3_NIC0_R")
	)
	(segment
		(start 306.749704 -242.13058)
		(end 328.88555 -242.13058)
		(width 0.15494)
		(layer "In13.Cu")
		(net "PWRGD_P3V3_NIC0_R")
	)
	(segment
		(start 31.098998 -218.63685)
		(end 34.038794 -218.63685)
		(width 0.15494)
		(layer "In13.Cu")
		(net "PWRGD_P3V3_NIC0_R")
	)
	(segment
		(start 221.47657 -239.20323)
		(end 222.17634 -238.50346)
		(width 0.15494)
		(layer "In13.Cu")
		(net "PWRGD_P3V3_NIC0_R")
	)
	(segment
		(start 343.078054 -238.5568)
		(end 344.271854 -237.363)
		(width 0.15494)
		(layer "In13.Cu")
		(net "PWRGD_P3V3_NIC0_R")
	)
	(segment
		(start 348.491048 -225.021902)
		(end 348.258384 -224.789238)
		(width 0.0889)
		(layer "In13.Cu")
		(net "PWRGD_P3V3_NIC0_R")
	)
	(segment
		(start 70.965822 -211.55406)
		(end 100.226114 -211.55406)
		(width 0.15494)
		(layer "In13.Cu")
		(net "PWRGD_P3V3_NIC0_R")
	)
	(segment
		(start 106.8832 -211.5312)
		(end 108.3056 -211.5312)
		(width 0.15494)
		(layer "In13.Cu")
		(net "PWRGD_P3V3_NIC0_R")
	)
	(segment
		(start 129.960624 -224.221548)
		(end 129.960624 -224.788476)
		(width 0.15494)
		(layer "In13.Cu")
		(net "PWRGD_P3V3_NIC0_R")
	)
	(segment
		(start 338.9122 -241.6302)
		(end 341.9856 -238.5568)
		(width 0.15494)
		(layer "In13.Cu")
		(net "PWRGD_P3V3_NIC0_R")
	)
	(segment
		(start 129.970784 -224.211388)
		(end 129.960624 -224.221548)
		(width 0.15494)
		(layer "In13.Cu")
		(net "PWRGD_P3V3_NIC0_R")
	)
	(segment
		(start 140.025374 -234.853226)
		(end 172.368972 -234.853226)
		(width 0.15494)
		(layer "In13.Cu")
		(net "PWRGD_P3V3_NIC0_R")
	)
	(segment
		(start 347.696028 -224.789238)
		(end 347.293692 -224.386902)
		(width 0.0889)
		(layer "In13.Cu")
		(net "PWRGD_P3V3_NIC0_R")
	)
	(segment
		(start 34.038794 -218.63685)
		(end 52.576222 -210.95843)
		(width 0.15494)
		(layer "In13.Cu")
		(net "PWRGD_P3V3_NIC0_R")
	)
	(segment
		(start 129.687574 -223.526858)
		(end 129.970784 -223.810068)
		(width 0.15494)
		(layer "In13.Cu")
		(net "PWRGD_P3V3_NIC0_R")
	)
	(segment
		(start 129.276094 -223.537018)
		(end 129.286254 -223.526858)
		(width 0.15494)
		(layer "In13.Cu")
		(net "PWRGD_P3V3_NIC0_R")
	)
	(segment
		(start 52.576222 -210.95843)
		(end 62.989714 -210.95843)
		(width 0.15494)
		(layer "In13.Cu")
		(net "PWRGD_P3V3_NIC0_R")
	)
	(segment
		(start 348.491048 -227.3554)
		(end 348.491048 -225.021902)
		(width 0.0889)
		(layer "In13.Cu")
		(net "PWRGD_P3V3_NIC0_R")
	)
	(segment
		(start 346.583 -234.696)
		(end 348.491048 -232.787952)
		(width 0.15494)
		(layer "In13.Cu")
		(net "PWRGD_P3V3_NIC0_R")
	)
	(segment
		(start 108.3056 -211.5312)
		(end 109.0422 -212.2678)
		(width 0.15494)
		(layer "In13.Cu")
		(net "PWRGD_P3V3_NIC0_R")
	)
	(segment
		(start 129.970784 -223.810068)
		(end 129.970784 -224.211388)
		(width 0.15494)
		(layer "In13.Cu")
		(net "PWRGD_P3V3_NIC0_R")
	)
	(segment
		(start 345.5797 -236.0041)
		(end 345.841574 -235.742226)
		(width 0.15494)
		(layer "In13.Cu")
		(net "PWRGD_P3V3_NIC0_R")
	)
	(segment
		(start 100.939854 -212.2678)
		(end 106.1466 -212.2678)
		(width 0.15494)
		(layer "In13.Cu")
		(net "PWRGD_P3V3_NIC0_R")
	)
	(segment
		(start 124.781818 -223.537018)
		(end 129.276094 -223.537018)
		(width 0.15494)
		(layer "In13.Cu")
		(net "PWRGD_P3V3_NIC0_R")
	)
	(segment
		(start 240.180114 -238.50346)
		(end 241.477292 -239.800638)
		(width 0.15494)
		(layer "In13.Cu")
		(net "PWRGD_P3V3_NIC0_R")
	)
	(segment
		(start 62.989714 -210.95843)
		(end 63.613284 -211.582)
		(width 0.15494)
		(layer "In13.Cu")
		(net "PWRGD_P3V3_NIC0_R")
	)
	(segment
		(start 129.286254 -223.526858)
		(end 129.687574 -223.526858)
		(width 0.15494)
		(layer "In13.Cu")
		(net "PWRGD_P3V3_NIC0_R")
	)
	(segment
		(start 63.613284 -211.582)
		(end 70.937882 -211.582)
		(width 0.15494)
		(layer "In13.Cu")
		(net "PWRGD_P3V3_NIC0_R")
	)
	(segment
		(start 70.937882 -211.582)
		(end 70.965822 -211.55406)
		(width 0.15494)
		(layer "In13.Cu")
		(net "PWRGD_P3V3_NIC0_R")
	)
	(segment
		(start 328.88555 -242.13058)
		(end 329.38593 -241.6302)
		(width 0.15494)
		(layer "In13.Cu")
		(net "PWRGD_P3V3_NIC0_R")
	)
	(segment
		(start 275.819616 -240.8936)
		(end 305.512724 -240.8936)
		(width 0.15494)
		(layer "In13.Cu")
		(net "PWRGD_P3V3_NIC0_R")
	)
	(segment
		(start 172.368972 -234.853226)
		(end 179.476146 -241.9604)
		(width 0.15494)
		(layer "In13.Cu")
		(net "PWRGD_P3V3_NIC0_R")
	)
	(segment
		(start 274.726654 -239.800638)
		(end 275.819616 -240.8936)
		(width 0.15494)
		(layer "In13.Cu")
		(net "PWRGD_P3V3_NIC0_R")
	)
	(segment
		(start 109.0422 -212.2678)
		(end 113.5126 -212.2678)
		(width 0.15494)
		(layer "In13.Cu")
		(net "PWRGD_P3V3_NIC0_R")
	)
	(segment
		(start 106.1466 -212.2678)
		(end 106.8832 -211.5312)
		(width 0.15494)
		(layer "In13.Cu")
		(net "PWRGD_P3V3_NIC0_R")
	)
	(segment
		(start 305.512724 -240.8936)
		(end 306.749704 -242.13058)
		(width 0.15494)
		(layer "In13.Cu")
		(net "PWRGD_P3V3_NIC0_R")
	)
	(segment
		(start 348.258384 -224.789238)
		(end 347.696028 -224.789238)
		(width 0.0889)
		(layer "In13.Cu")
		(net "PWRGD_P3V3_NIC0_R")
	)
	(segment
		(start 348.491048 -232.787952)
		(end 348.491048 -227.3554)
		(width 0.15494)
		(layer "In13.Cu")
		(net "PWRGD_P3V3_NIC0_R")
	)
	(segment
		(start 214.470488 -239.6998)
		(end 214.967058 -239.20323)
		(width 0.15494)
		(layer "In13.Cu")
		(net "PWRGD_P3V3_NIC0_R")
	)
	(segment
		(start 222.17634 -238.50346)
		(end 240.180114 -238.50346)
		(width 0.15494)
		(layer "In13.Cu")
		(net "PWRGD_P3V3_NIC0_R")
	)
	(segment
		(start 346.197174 -235.742226)
		(end 346.583 -235.3564)
		(width 0.15494)
		(layer "In13.Cu")
		(net "PWRGD_P3V3_NIC0_R")
	)
	(segment
		(start 113.5126 -212.2678)
		(end 124.781818 -223.537018)
		(width 0.15494)
		(layer "In13.Cu")
		(net "PWRGD_P3V3_NIC0_R")
	)
	(segment
		(start 241.477292 -239.800638)
		(end 274.726654 -239.800638)
		(width 0.15494)
		(layer "In13.Cu")
		(net "PWRGD_P3V3_NIC0_R")
	)
	(segment
		(start 344.271854 -237.363)
		(end 344.9066 -237.363)
		(width 0.15494)
		(layer "In13.Cu")
		(net "PWRGD_P3V3_NIC0_R")
	)
	(segment
		(start 205.489048 -241.9604)
		(end 207.749648 -239.6998)
		(width 0.15494)
		(layer "In13.Cu")
		(net "PWRGD_P3V3_NIC0_R")
	)
	(segment
		(start 345.5797 -236.6899)
		(end 345.5797 -236.0041)
		(width 0.15494)
		(layer "In13.Cu")
		(net "PWRGD_P3V3_NIC0_R")
	)
	(segment
		(start 179.476146 -241.9604)
		(end 205.489048 -241.9604)
		(width 0.15494)
		(layer "In13.Cu")
		(net "PWRGD_P3V3_NIC0_R")
	)
	(segment
		(start 38.280848 -355.658166)
		(end 38.280848 -355.026722)
		(width 0.13462)
		(layer "F.Cu")
		(net "P5E_PEX0_STN4_TX_DP<70>")
	)
	(segment
		(start 37.960808 -355.978206)
		(end 38.280848 -355.658166)
		(width 0.13462)
		(layer "F.Cu")
		(net "P5E_PEX0_STN4_TX_DP<70>")
	)
	(segment
		(start 38.280848 -355.026722)
		(end 37.986208 -354.732082)
		(width 0.13462)
		(layer "F.Cu")
		(net "P5E_PEX0_STN4_TX_DP<70>")
	)
	(segment
		(start 82.633058 -312.620152)
		(end 82.967068 -312.954162)
		(width 0.1143)
		(layer "In11.Cu")
		(net "P5E_PEX0_STN4_TX_DP<70>")
	)
	(segment
		(start 39.831518 -352.103182)
		(end 38.277038 -353.657662)
		(width 0.1651)
		(layer "In11.Cu")
		(net "P5E_PEX0_STN4_TX_DP<70>")
	)
	(segment
		(start 39.831518 -342.048846)
		(end 39.831518 -352.103182)
		(width 0.1651)
		(layer "In11.Cu")
		(net "P5E_PEX0_STN4_TX_DP<70>")
	)
	(segment
		(start 56.03113 -333.524606)
		(end 46.60392 -336.898234)
		(width 0.1651)
		(layer "In11.Cu")
		(net "P5E_PEX0_STN4_TX_DP<70>")
	)
	(segment
		(start 41.900094 -339.412326)
		(end 40.272462 -341.040212)
		(width 0.1651)
		(layer "In11.Cu")
		(net "P5E_PEX0_STN4_TX_DP<70>")
	)
	(segment
		(start 84.025994 -314.418218)
		(end 84.025994 -320.791586)
		(width 0.1651)
		(layer "In11.Cu")
		(net "P5E_PEX0_STN4_TX_DP<70>")
	)
	(segment
		(start 78.51267 -328.405236)
		(end 78.512162 -328.40549)
		(width 0.1651)
		(layer "In11.Cu")
		(net "P5E_PEX0_STN4_TX_DP<70>")
	)
	(segment
		(start 76.582016 -329.436984)
		(end 56.03113 -333.524606)
		(width 0.1651)
		(layer "In11.Cu")
		(net "P5E_PEX0_STN4_TX_DP<70>")
	)
	(segment
		(start 84.025994 -320.791586)
		(end 83.479894 -322.1101)
		(width 0.1651)
		(layer "In11.Cu")
		(net "P5E_PEX0_STN4_TX_DP<70>")
	)
	(segment
		(start 83.492086 -313.88431)
		(end 83.512152 -313.904376)
		(width 0.1143)
		(layer "In11.Cu")
		(net "P5E_PEX0_STN4_TX_DP<70>")
	)
	(segment
		(start 46.60392 -336.898234)
		(end 41.900094 -339.412326)
		(width 0.1651)
		(layer "In11.Cu")
		(net "P5E_PEX0_STN4_TX_DP<70>")
	)
	(segment
		(start 40.232838 -341.079836)
		(end 39.831518 -342.048846)
		(width 0.1651)
		(layer "In11.Cu")
		(net "P5E_PEX0_STN4_TX_DP<70>")
	)
	(segment
		(start 81.499964 -312.049922)
		(end 81.790794 -312.049922)
		(width 0.1143)
		(layer "In11.Cu")
		(net "P5E_PEX0_STN4_TX_DP<70>")
	)
	(segment
		(start 40.272462 -341.040212)
		(end 40.272208 -341.040212)
		(width 0.1651)
		(layer "In11.Cu")
		(net "P5E_PEX0_STN4_TX_DP<70>")
	)
	(segment
		(start 82.967068 -313.294268)
		(end 83.492086 -313.819286)
		(width 0.1143)
		(layer "In11.Cu")
		(net "P5E_PEX0_STN4_TX_DP<70>")
	)
	(segment
		(start 81.879694 -312.138822)
		(end 81.879694 -312.343546)
		(width 0.1143)
		(layer "In11.Cu")
		(net "P5E_PEX0_STN4_TX_DP<70>")
	)
	(segment
		(start 40.272208 -341.040212)
		(end 40.232838 -341.079836)
		(width 0.1651)
		(layer "In11.Cu")
		(net "P5E_PEX0_STN4_TX_DP<70>")
	)
	(segment
		(start 83.492086 -313.819286)
		(end 83.492086 -313.88431)
		(width 0.1143)
		(layer "In11.Cu")
		(net "P5E_PEX0_STN4_TX_DP<70>")
	)
	(segment
		(start 81.879694 -312.343546)
		(end 82.1563 -312.620152)
		(width 0.1143)
		(layer "In11.Cu")
		(net "P5E_PEX0_STN4_TX_DP<70>")
	)
	(segment
		(start 82.1563 -312.620152)
		(end 82.633058 -312.620152)
		(width 0.1143)
		(layer "In11.Cu")
		(net "P5E_PEX0_STN4_TX_DP<70>")
	)
	(segment
		(start 83.479894 -322.1101)
		(end 80.80629 -326.111362)
		(width 0.1651)
		(layer "In11.Cu")
		(net "P5E_PEX0_STN4_TX_DP<70>")
	)
	(segment
		(start 80.80629 -326.111362)
		(end 78.51267 -328.405236)
		(width 0.1651)
		(layer "In11.Cu")
		(net "P5E_PEX0_STN4_TX_DP<70>")
	)
	(segment
		(start 81.790794 -312.049922)
		(end 81.879694 -312.138822)
		(width 0.1143)
		(layer "In11.Cu")
		(net "P5E_PEX0_STN4_TX_DP<70>")
	)
	(segment
		(start 38.277038 -354.441252)
		(end 37.986208 -354.732082)
		(width 0.1651)
		(layer "In11.Cu")
		(net "P5E_PEX0_STN4_TX_DP<70>")
	)
	(segment
		(start 83.512152 -313.904376)
		(end 84.025994 -314.418218)
		(width 0.1651)
		(layer "In11.Cu")
		(net "P5E_PEX0_STN4_TX_DP<70>")
	)
	(segment
		(start 82.967068 -312.954162)
		(end 82.967068 -313.294268)
		(width 0.1143)
		(layer "In11.Cu")
		(net "P5E_PEX0_STN4_TX_DP<70>")
	)
	(segment
		(start 78.512162 -328.40549)
		(end 76.582016 -329.436984)
		(width 0.1651)
		(layer "In11.Cu")
		(net "P5E_PEX0_STN4_TX_DP<70>")
	)
	(segment
		(start 38.277038 -353.657662)
		(end 38.277038 -354.441252)
		(width 0.1651)
		(layer "In11.Cu")
		(net "P5E_PEX0_STN4_TX_DP<70>")
	)
	(segment
		(start 293.657782 -344.219022)
		(end 293.337742 -344.539062)
		(width 0.13462)
		(layer "F.Cu")
		(net "P5E_PEX2_STN4_TX_C_DN<68>")
	)
	(segment
		(start 293.337742 -344.539062)
		(end 293.337742 -345.170506)
		(width 0.13462)
		(layer "F.Cu")
		(net "P5E_PEX2_STN4_TX_C_DN<68>")
	)
	(segment
		(start 293.337742 -345.170506)
		(end 293.632382 -345.465146)
		(width 0.13462)
		(layer "F.Cu")
		(net "P5E_PEX2_STN4_TX_C_DN<68>")
	)
	(segment
		(start 295.215818 -368.7699)
		(end 295.215818 -371.929152)
		(width 0.1651)
		(layer "In11.Cu")
		(net "P5E_PEX2_STN4_TX_C_DN<68>")
	)
	(segment
		(start 291.787072 -358.85882)
		(end 295.215818 -368.7699)
		(width 0.1651)
		(layer "In11.Cu")
		(net "P5E_PEX2_STN4_TX_C_DN<68>")
	)
	(segment
		(start 293.341552 -345.755976)
		(end 293.341552 -346.326714)
		(width 0.1651)
		(layer "In11.Cu")
		(net "P5E_PEX2_STN4_TX_C_DN<68>")
	)
	(segment
		(start 291.787072 -347.881194)
		(end 291.787072 -358.85882)
		(width 0.1651)
		(layer "In11.Cu")
		(net "P5E_PEX2_STN4_TX_C_DN<68>")
	)
	(segment
		(start 294.216836 -372.381018)
		(end 294.089836 -372.508018)
		(width 0.1651)
		(layer "In11.Cu")
		(net "P5E_PEX2_STN4_TX_C_DN<68>")
	)
	(segment
		(start 293.341552 -346.326714)
		(end 291.787072 -347.881194)
		(width 0.1651)
		(layer "In11.Cu")
		(net "P5E_PEX2_STN4_TX_C_DN<68>")
	)
	(segment
		(start 293.632382 -345.465146)
		(end 293.341552 -345.755976)
		(width 0.1651)
		(layer "In11.Cu")
		(net "P5E_PEX2_STN4_TX_C_DN<68>")
	)
	(segment
		(start 294.763952 -372.381018)
		(end 294.216836 -372.381018)
		(width 0.1651)
		(layer "In11.Cu")
		(net "P5E_PEX2_STN4_TX_C_DN<68>")
	)
	(segment
		(start 295.215818 -371.929152)
		(end 294.763952 -372.381018)
		(width 0.1651)
		(layer "In11.Cu")
		(net "P5E_PEX2_STN4_TX_C_DN<68>")
	)
	(segment
		(start 294.089836 -372.508018)
		(end 294.089836 -372.890034)
		(width 0.1651)
		(layer "In11.Cu")
		(net "P5E_PEX2_STN4_TX_C_DN<68>")
	)
	(segment
		(start 12.231116 -126.394718)
		(end 12.179554 -126.394718)
		(width 0.13208)
		(layer "F.Cu")
		(net "P3V3_NIC0_SS")
	)
	(segment
		(start 12.179554 -126.394718)
		(end 11.522964 -127.051308)
		(width 0.13208)
		(layer "F.Cu")
		(net "P3V3_NIC0_SS")
	)
	(segment
		(start 11.126216 -127.051308)
		(end 10.5664 -127.051308)
		(width 0.13208)
		(layer "F.Cu")
		(net "P3V3_NIC0_SS")
	)
	(segment
		(start 10.5664 -127.051308)
		(end 10.51052 -126.995428)
		(width 0.13208)
		(layer "F.Cu")
		(net "P3V3_NIC0_SS")
	)
	(segment
		(start 11.522964 -127.051308)
		(end 11.126216 -127.051308)
		(width 0.13208)
		(layer "F.Cu")
		(net "P3V3_NIC0_SS")
	)
	(via
		(at 11.126216 -127.051308)
		(size 0.508)
		(drill 0.254)
		(layers "F.Cu" "B.Cu")
		(net "P3V3_NIC0_SS")
	)
	(segment
		(start 32.657288 -355.978206)
		(end 32.337248 -355.658166)
		(width 0.13462)
		(layer "F.Cu")
		(net "P5E_PEX0_STN4_TX_DN<73>")
	)
	(segment
		(start 32.337248 -355.658166)
		(end 32.337248 -355.026722)
		(width 0.13462)
		(layer "F.Cu")
		(net "P5E_PEX0_STN4_TX_DN<73>")
	)
	(segment
		(start 32.337248 -355.026722)
		(end 32.631888 -354.732082)
		(width 0.13462)
		(layer "F.Cu")
		(net "P5E_PEX0_STN4_TX_DN<73>")
	)
	(segment
		(start 32.631888 -354.732082)
		(end 32.341058 -354.441252)
		(width 0.1651)
		(layer "In11.Cu")
		(net "P5E_PEX0_STN4_TX_DN<73>")
	)
	(segment
		(start 54.83606 -331.077316)
		(end 75.389232 -326.989186)
		(width 0.1651)
		(layer "In11.Cu")
		(net "P5E_PEX0_STN4_TX_DN<73>")
	)
	(segment
		(start 79.22006 -320.219832)
		(end 79.22006 -311.835292)
		(width 0.1143)
		(layer "In11.Cu")
		(net "P5E_PEX0_STN4_TX_DN<73>")
	)
	(segment
		(start 76.88072 -326.19188)
		(end 78.162404 -324.909942)
		(width 0.1651)
		(layer "In11.Cu")
		(net "P5E_PEX0_STN4_TX_DN<73>")
	)
	(segment
		(start 79.26578 -322.246244)
		(end 79.26578 -320.294)
		(width 0.1651)
		(layer "In11.Cu")
		(net "P5E_PEX0_STN4_TX_DN<73>")
	)
	(segment
		(start 33.895538 -341.288116)
		(end 36.381436 -338.802218)
		(width 0.1651)
		(layer "In11.Cu")
		(net "P5E_PEX0_STN4_TX_DN<73>")
	)
	(segment
		(start 42.728642 -335.40954)
		(end 54.83606 -331.077316)
		(width 0.1651)
		(layer "In11.Cu")
		(net "P5E_PEX0_STN4_TX_DN<73>")
	)
	(segment
		(start 33.895538 -352.220022)
		(end 33.895538 -341.288116)
		(width 0.1651)
		(layer "In11.Cu")
		(net "P5E_PEX0_STN4_TX_DN<73>")
	)
	(segment
		(start 79.51089 -311.670192)
		(end 79.59979 -311.759092)
		(width 0.1143)
		(layer "In11.Cu")
		(net "P5E_PEX0_STN4_TX_DN<73>")
	)
	(segment
		(start 79.26578 -320.265552)
		(end 79.22006 -320.219832)
		(width 0.1143)
		(layer "In11.Cu")
		(net "P5E_PEX0_STN4_TX_DN<73>")
	)
	(segment
		(start 79.38516 -311.670192)
		(end 79.51089 -311.670192)
		(width 0.1143)
		(layer "In11.Cu")
		(net "P5E_PEX0_STN4_TX_DN<73>")
	)
	(segment
		(start 78.162404 -324.909942)
		(end 79.26578 -322.246244)
		(width 0.1651)
		(layer "In11.Cu")
		(net "P5E_PEX0_STN4_TX_DN<73>")
	)
	(segment
		(start 32.341058 -354.441252)
		(end 32.341058 -353.774502)
		(width 0.1651)
		(layer "In11.Cu")
		(net "P5E_PEX0_STN4_TX_DN<73>")
	)
	(segment
		(start 79.59979 -311.759092)
		(end 79.59979 -312.049922)
		(width 0.1143)
		(layer "In11.Cu")
		(net "P5E_PEX0_STN4_TX_DN<73>")
	)
	(segment
		(start 32.341058 -353.774502)
		(end 33.895538 -352.220022)
		(width 0.1651)
		(layer "In11.Cu")
		(net "P5E_PEX0_STN4_TX_DN<73>")
	)
	(segment
		(start 79.26578 -320.294)
		(end 79.26578 -320.265552)
		(width 0.1143)
		(layer "In11.Cu")
		(net "P5E_PEX0_STN4_TX_DN<73>")
	)
	(segment
		(start 75.389232 -326.989186)
		(end 76.88072 -326.19188)
		(width 0.1651)
		(layer "In11.Cu")
		(net "P5E_PEX0_STN4_TX_DN<73>")
	)
	(segment
		(start 79.22006 -311.835292)
		(end 79.38516 -311.670192)
		(width 0.1143)
		(layer "In11.Cu")
		(net "P5E_PEX0_STN4_TX_DN<73>")
	)
	(segment
		(start 36.381436 -338.802218)
		(end 42.728642 -335.40954)
		(width 0.1651)
		(layer "In11.Cu")
		(net "P5E_PEX0_STN4_TX_DN<73>")
	)
	(segment
		(start 282.400248 -368.113056)
		(end 285.287212 -357.867966)
		(width 0.1651)
		(layer "In15.Cu")
		(net "P5E_PEX2_STN4_RX_DP<76>")
	)
	(segment
		(start 294.933878 -405.612346)
		(end 294.933878 -396.29461)
		(width 0.1651)
		(layer "In15.Cu")
		(net "P5E_PEX2_STN4_RX_DP<76>")
	)
	(segment
		(start 308.333902 -322.381118)
		(end 308.333902 -319.941448)
		(width 0.1651)
		(layer "In15.Cu")
		(net "P5E_PEX2_STN4_RX_DP<76>")
	)
	(segment
		(start 282.268168 -385.531868)
		(end 281.733498 -372.469918)
		(width 0.1651)
		(layer "In15.Cu")
		(net "P5E_PEX2_STN4_RX_DP<76>")
	)
	(segment
		(start 308.333902 -319.913)
		(end 308.379622 -319.86728)
		(width 0.1143)
		(layer "In15.Cu")
		(net "P5E_PEX2_STN4_RX_DP<76>")
	)
	(segment
		(start 290.882832 -392.546586)
		(end 290.76142 -392.579352)
		(width 0.1651)
		(layer "In15.Cu")
		(net "P5E_PEX2_STN4_RX_DP<76>")
	)
	(segment
		(start 294.371776 -394.893546)
		(end 293.722044 -394.17879)
		(width 0.1651)
		(layer "In15.Cu")
		(net "P5E_PEX2_STN4_RX_DP<76>")
	)
	(segment
		(start 308.379622 -318.344804)
		(end 308.59476 -318.129666)
		(width 0.1143)
		(layer "In15.Cu")
		(net "P5E_PEX2_STN4_RX_DP<76>")
	)
	(segment
		(start 285.996634 -340.47176)
		(end 306.583334 -324.131686)
		(width 0.1651)
		(layer "In15.Cu")
		(net "P5E_PEX2_STN4_RX_DP<76>")
	)
	(segment
		(start 294.216836 -405.899112)
		(end 294.647112 -405.899112)
		(width 0.1651)
		(layer "In15.Cu")
		(net "P5E_PEX2_STN4_RX_DP<76>")
	)
	(segment
		(start 290.298886 -392.210798)
		(end 288.4678 -391.158222)
		(width 0.1651)
		(layer "In15.Cu")
		(net "P5E_PEX2_STN4_RX_DP<76>")
	)
	(segment
		(start 308.949852 -318.015366)
		(end 308.949852 -317.749936)
		(width 0.1143)
		(layer "In15.Cu")
		(net "P5E_PEX2_STN4_RX_DP<76>")
	)
	(segment
		(start 281.733498 -372.469918)
		(end 282.400248 -368.113056)
		(width 0.1651)
		(layer "In15.Cu")
		(net "P5E_PEX2_STN4_RX_DP<76>")
	)
	(segment
		(start 306.583334 -324.131686)
		(end 308.333902 -322.381118)
		(width 0.1651)
		(layer "In15.Cu")
		(net "P5E_PEX2_STN4_RX_DP<76>")
	)
	(segment
		(start 286.0675 -390.10971)
		(end 283.233114 -388.03326)
		(width 0.1651)
		(layer "In15.Cu")
		(net "P5E_PEX2_STN4_RX_DP<76>")
	)
	(segment
		(start 308.835552 -318.129666)
		(end 308.949852 -318.015366)
		(width 0.1143)
		(layer "In15.Cu")
		(net "P5E_PEX2_STN4_RX_DP<76>")
	)
	(segment
		(start 294.933878 -396.29461)
		(end 294.371776 -394.893546)
		(width 0.1651)
		(layer "In15.Cu")
		(net "P5E_PEX2_STN4_RX_DP<76>")
	)
	(segment
		(start 285.287212 -341.545164)
		(end 285.996634 -340.47176)
		(width 0.1651)
		(layer "In15.Cu")
		(net "P5E_PEX2_STN4_RX_DP<76>")
	)
	(segment
		(start 290.331652 -392.33221)
		(end 290.298886 -392.210798)
		(width 0.1651)
		(layer "In15.Cu")
		(net "P5E_PEX2_STN4_RX_DP<76>")
	)
	(segment
		(start 308.379622 -319.86728)
		(end 308.379622 -318.344804)
		(width 0.1143)
		(layer "In15.Cu")
		(net "P5E_PEX2_STN4_RX_DP<76>")
	)
	(segment
		(start 308.59476 -318.129666)
		(end 308.835552 -318.129666)
		(width 0.1143)
		(layer "In15.Cu")
		(net "P5E_PEX2_STN4_RX_DP<76>")
	)
	(segment
		(start 293.722044 -394.17879)
		(end 290.882832 -392.546586)
		(width 0.1651)
		(layer "In15.Cu")
		(net "P5E_PEX2_STN4_RX_DP<76>")
	)
	(segment
		(start 290.76142 -392.579352)
		(end 290.331652 -392.33221)
		(width 0.1651)
		(layer "In15.Cu")
		(net "P5E_PEX2_STN4_RX_DP<76>")
	)
	(segment
		(start 294.089836 -405.772112)
		(end 294.216836 -405.899112)
		(width 0.1651)
		(layer "In15.Cu")
		(net "P5E_PEX2_STN4_RX_DP<76>")
	)
	(segment
		(start 308.333902 -319.941448)
		(end 308.333902 -319.913)
		(width 0.1143)
		(layer "In15.Cu")
		(net "P5E_PEX2_STN4_RX_DP<76>")
	)
	(segment
		(start 283.233114 -388.03326)
		(end 282.268168 -385.531868)
		(width 0.1651)
		(layer "In15.Cu")
		(net "P5E_PEX2_STN4_RX_DP<76>")
	)
	(segment
		(start 285.287212 -357.867966)
		(end 285.287212 -341.545164)
		(width 0.1651)
		(layer "In15.Cu")
		(net "P5E_PEX2_STN4_RX_DP<76>")
	)
	(segment
		(start 294.647112 -405.899112)
		(end 294.933878 -405.612346)
		(width 0.1651)
		(layer "In15.Cu")
		(net "P5E_PEX2_STN4_RX_DP<76>")
	)
	(segment
		(start 294.089836 -405.390096)
		(end 294.089836 -405.772112)
		(width 0.1651)
		(layer "In15.Cu")
		(net "P5E_PEX2_STN4_RX_DP<76>")
	)
	(segment
		(start 288.4678 -391.158222)
		(end 286.0675 -390.10971)
		(width 0.1651)
		(layer "In15.Cu")
		(net "P5E_PEX2_STN4_RX_DP<76>")
	)
	(segment
		(start 11.406632 -124.995432)
		(end 11.80592 -125.39472)
		(width 0.13208)
		(layer "F.Cu")
		(net "P3V3_NIC0_OCP")
	)
	(segment
		(start 10.51052 -124.09932)
		(end 10.51052 -123.947428)
		(width 0.13208)
		(layer "F.Cu")
		(net "P3V3_NIC0_OCP")
	)
	(segment
		(start 11.162792 -124.995432)
		(end 11.162792 -124.751592)
		(width 0.13208)
		(layer "F.Cu")
		(net "P3V3_NIC0_OCP")
	)
	(segment
		(start 11.162792 -124.995432)
		(end 11.406632 -124.995432)
		(width 0.13208)
		(layer "F.Cu")
		(net "P3V3_NIC0_OCP")
	)
	(segment
		(start 11.80592 -125.39472)
		(end 12.231116 -125.39472)
		(width 0.13208)
		(layer "F.Cu")
		(net "P3V3_NIC0_OCP")
	)
	(segment
		(start 11.162792 -124.751592)
		(end 10.51052 -124.09932)
		(width 0.13208)
		(layer "F.Cu")
		(net "P3V3_NIC0_OCP")
	)
	(via
		(at 11.162792 -124.995432)
		(size 0.508)
		(drill 0.254)
		(layers "F.Cu" "B.Cu")
		(net "P3V3_NIC0_OCP")
	)
	(segment
		(start 287.119822 -356.831646)
		(end 287.119822 -357.46309)
		(width 0.13462)
		(layer "F.Cu")
		(net "P5E_PEX2_STN4_TX_C_DN<70>")
	)
	(segment
		(start 287.439862 -356.511606)
		(end 287.119822 -356.831646)
		(width 0.13462)
		(layer "F.Cu")
		(net "P5E_PEX2_STN4_TX_C_DN<70>")
	)
	(segment
		(start 287.119822 -357.46309)
		(end 287.414462 -357.75773)
		(width 0.13462)
		(layer "F.Cu")
		(net "P5E_PEX2_STN4_TX_C_DN<70>")
	)
	(segment
		(start 287.414462 -357.75773)
		(end 287.123632 -358.04856)
		(width 0.1651)
		(layer "In11.Cu")
		(net "P5E_PEX2_STN4_TX_C_DN<70>")
	)
	(segment
		(start 290.815776 -368.82832)
		(end 290.815776 -371.929152)
		(width 0.1651)
		(layer "In11.Cu")
		(net "P5E_PEX2_STN4_TX_C_DN<70>")
	)
	(segment
		(start 289.816794 -372.381018)
		(end 289.689794 -372.508018)
		(width 0.1651)
		(layer "In11.Cu")
		(net "P5E_PEX2_STN4_TX_C_DN<70>")
	)
	(segment
		(start 289.689794 -372.508018)
		(end 289.689794 -372.890034)
		(width 0.1651)
		(layer "In11.Cu")
		(net "P5E_PEX2_STN4_TX_C_DN<70>")
	)
	(segment
		(start 290.815776 -371.929152)
		(end 290.36391 -372.381018)
		(width 0.1651)
		(layer "In11.Cu")
		(net "P5E_PEX2_STN4_TX_C_DN<70>")
	)
	(segment
		(start 287.123632 -358.88422)
		(end 290.815776 -368.82832)
		(width 0.1651)
		(layer "In11.Cu")
		(net "P5E_PEX2_STN4_TX_C_DN<70>")
	)
	(segment
		(start 290.36391 -372.381018)
		(end 289.816794 -372.381018)
		(width 0.1651)
		(layer "In11.Cu")
		(net "P5E_PEX2_STN4_TX_C_DN<70>")
	)
	(segment
		(start 287.123632 -358.04856)
		(end 287.123632 -358.88422)
		(width 0.1651)
		(layer "In11.Cu")
		(net "P5E_PEX2_STN4_TX_C_DN<70>")
	)
	(segment
		(start 431.351944 -342.73363)
		(end 431.057812 -342.439498)
		(width 0.13462)
		(layer "F.Cu")
		(net "P5E_PEX3_STN4_TX_DP<69>")
	)
	(segment
		(start 431.032412 -343.685622)
		(end 431.351944 -343.36609)
		(width 0.13462)
		(layer "F.Cu")
		(net "P5E_PEX3_STN4_TX_DP<69>")
	)
	(segment
		(start 431.351944 -343.36609)
		(end 431.351944 -342.73363)
		(width 0.13462)
		(layer "F.Cu")
		(net "P5E_PEX3_STN4_TX_DP<69>")
	)
	(segment
		(start 433.34686 -312.370978)
		(end 432.422554 -310.139588)
		(width 0.1651)
		(layer "In7.Cu")
		(net "P5E_PEX3_STN4_TX_DP<69>")
	)
	(segment
		(start 431.348642 -341.54491)
		(end 432.652932 -320.854324)
		(width 0.1651)
		(layer "In7.Cu")
		(net "P5E_PEX3_STN4_TX_DP<69>")
	)
	(segment
		(start 433.34686 -316.687708)
		(end 433.34686 -312.370978)
		(width 0.1651)
		(layer "In7.Cu")
		(net "P5E_PEX3_STN4_TX_DP<69>")
	)
	(segment
		(start 432.656996 -320.83121)
		(end 432.65725 -320.830702)
		(width 0.1651)
		(layer "In7.Cu")
		(net "P5E_PEX3_STN4_TX_DP<69>")
	)
	(segment
		(start 425.31538 -309.199788)
		(end 425.04995 -309.199788)
		(width 0.1143)
		(layer "In7.Cu")
		(net "P5E_PEX3_STN4_TX_DP<69>")
	)
	(segment
		(start 431.057812 -342.439498)
		(end 431.348642 -342.148668)
		(width 0.1651)
		(layer "In7.Cu")
		(net "P5E_PEX3_STN4_TX_DP<69>")
	)
	(segment
		(start 432.65725 -320.830702)
		(end 433.2351 -317.72606)
		(width 0.1651)
		(layer "In7.Cu")
		(net "P5E_PEX3_STN4_TX_DP<69>")
	)
	(segment
		(start 432.656742 -320.833496)
		(end 432.656996 -320.831972)
		(width 0.1651)
		(layer "In7.Cu")
		(net "P5E_PEX3_STN4_TX_DP<69>")
	)
	(segment
		(start 425.655486 -309.770018)
		(end 425.42968 -309.544212)
		(width 0.1143)
		(layer "In7.Cu")
		(net "P5E_PEX3_STN4_TX_DP<69>")
	)
	(segment
		(start 425.42968 -309.314088)
		(end 425.31538 -309.199788)
		(width 0.1143)
		(layer "In7.Cu")
		(net "P5E_PEX3_STN4_TX_DP<69>")
	)
	(segment
		(start 432.652932 -320.854324)
		(end 432.65598 -320.83756)
		(width 0.1651)
		(layer "In7.Cu")
		(net "P5E_PEX3_STN4_TX_DP<69>")
	)
	(segment
		(start 432.656488 -320.834766)
		(end 432.656742 -320.833496)
		(width 0.1651)
		(layer "In7.Cu")
		(net "P5E_PEX3_STN4_TX_DP<69>")
	)
	(segment
		(start 432.422554 -310.139588)
		(end 432.098704 -309.815738)
		(width 0.1651)
		(layer "In7.Cu")
		(net "P5E_PEX3_STN4_TX_DP<69>")
	)
	(segment
		(start 432.656996 -320.831972)
		(end 432.656996 -320.83121)
		(width 0.1651)
		(layer "In7.Cu")
		(net "P5E_PEX3_STN4_TX_DP<69>")
	)
	(segment
		(start 432.656234 -320.83629)
		(end 432.656488 -320.834766)
		(width 0.1651)
		(layer "In7.Cu")
		(net "P5E_PEX3_STN4_TX_DP<69>")
	)
	(segment
		(start 425.42968 -309.544212)
		(end 425.42968 -309.314088)
		(width 0.1143)
		(layer "In7.Cu")
		(net "P5E_PEX3_STN4_TX_DP<69>")
	)
	(segment
		(start 433.2351 -317.72606)
		(end 433.34686 -316.687708)
		(width 0.1651)
		(layer "In7.Cu")
		(net "P5E_PEX3_STN4_TX_DP<69>")
	)
	(segment
		(start 431.955448 -309.815738)
		(end 431.927 -309.815738)
		(width 0.1143)
		(layer "In7.Cu")
		(net "P5E_PEX3_STN4_TX_DP<69>")
	)
	(segment
		(start 432.65598 -320.83756)
		(end 432.656234 -320.83629)
		(width 0.1651)
		(layer "In7.Cu")
		(net "P5E_PEX3_STN4_TX_DP<69>")
	)
	(segment
		(start 431.348642 -342.148668)
		(end 431.348642 -341.54491)
		(width 0.1651)
		(layer "In7.Cu")
		(net "P5E_PEX3_STN4_TX_DP<69>")
	)
	(segment
		(start 431.88128 -309.770018)
		(end 425.655486 -309.770018)
		(width 0.1143)
		(layer "In7.Cu")
		(net "P5E_PEX3_STN4_TX_DP<69>")
	)
	(segment
		(start 431.927 -309.815738)
		(end 431.88128 -309.770018)
		(width 0.1143)
		(layer "In7.Cu")
		(net "P5E_PEX3_STN4_TX_DP<69>")
	)
	(segment
		(start 432.098704 -309.815738)
		(end 431.955448 -309.815738)
		(width 0.1651)
		(layer "In7.Cu")
		(net "P5E_PEX3_STN4_TX_DP<69>")
	)
	(segment
		(start 35.171888 -349.511874)
		(end 35.171888 -348.88043)
		(width 0.13462)
		(layer "F.Cu")
		(net "P5E_PEX0_STN4_TX_DP<72>")
	)
	(segment
		(start 35.171888 -348.88043)
		(end 34.877248 -348.58579)
		(width 0.13462)
		(layer "F.Cu")
		(net "P5E_PEX0_STN4_TX_DP<72>")
	)
	(segment
		(start 34.851848 -349.831914)
		(end 35.171888 -349.511874)
		(width 0.13462)
		(layer "F.Cu")
		(net "P5E_PEX0_STN4_TX_DP<72>")
	)
	(segment
		(start 35.168078 -347.620082)
		(end 36.722558 -346.065602)
		(width 0.1651)
		(layer "In11.Cu")
		(net "P5E_PEX0_STN4_TX_DP<72>")
	)
	(segment
		(start 36.762436 -340.956138)
		(end 36.76269 -340.956138)
		(width 0.1651)
		(layer "In11.Cu")
		(net "P5E_PEX0_STN4_TX_DP<72>")
	)
	(segment
		(start 36.722558 -346.065602)
		(end 36.722558 -341.02294)
		(width 0.1651)
		(layer "In11.Cu")
		(net "P5E_PEX0_STN4_TX_DP<72>")
	)
	(segment
		(start 36.76269 -340.956138)
		(end 38.095428 -338.732368)
		(width 0.1651)
		(layer "In11.Cu")
		(net "P5E_PEX0_STN4_TX_DP<72>")
	)
	(segment
		(start 79.9338 -322.589652)
		(end 79.9338 -320.294)
		(width 0.1651)
		(layer "In11.Cu")
		(net "P5E_PEX0_STN4_TX_DP<72>")
	)
	(segment
		(start 77.282802 -326.805798)
		(end 78.827122 -325.261478)
		(width 0.1651)
		(layer "In11.Cu")
		(net "P5E_PEX0_STN4_TX_DP<72>")
	)
	(segment
		(start 35.168078 -348.29496)
		(end 35.168078 -347.620082)
		(width 0.1651)
		(layer "In11.Cu")
		(net "P5E_PEX0_STN4_TX_DP<72>")
	)
	(segment
		(start 38.095428 -338.732368)
		(end 43.178222 -336.015838)
		(width 0.1651)
		(layer "In11.Cu")
		(net "P5E_PEX0_STN4_TX_DP<72>")
	)
	(segment
		(start 79.97952 -320.219832)
		(end 79.97952 -313.656218)
		(width 0.1143)
		(layer "In11.Cu")
		(net "P5E_PEX0_STN4_TX_DP<72>")
	)
	(segment
		(start 80.256126 -313.379612)
		(end 80.46085 -313.379612)
		(width 0.1143)
		(layer "In11.Cu")
		(net "P5E_PEX0_STN4_TX_DP<72>")
	)
	(segment
		(start 55.34406 -331.662786)
		(end 75.81265 -327.591674)
		(width 0.1651)
		(layer "In11.Cu")
		(net "P5E_PEX0_STN4_TX_DP<72>")
	)
	(segment
		(start 79.97952 -313.656218)
		(end 80.256126 -313.379612)
		(width 0.1143)
		(layer "In11.Cu")
		(net "P5E_PEX0_STN4_TX_DP<72>")
	)
	(segment
		(start 80.54975 -313.290712)
		(end 80.54975 -312.999882)
		(width 0.1143)
		(layer "In11.Cu")
		(net "P5E_PEX0_STN4_TX_DP<72>")
	)
	(segment
		(start 34.877248 -348.58579)
		(end 35.168078 -348.29496)
		(width 0.1651)
		(layer "In11.Cu")
		(net "P5E_PEX0_STN4_TX_DP<72>")
	)
	(segment
		(start 43.178222 -336.015838)
		(end 55.34406 -331.662786)
		(width 0.1651)
		(layer "In11.Cu")
		(net "P5E_PEX0_STN4_TX_DP<72>")
	)
	(segment
		(start 79.9338 -320.265552)
		(end 79.97952 -320.219832)
		(width 0.1143)
		(layer "In11.Cu")
		(net "P5E_PEX0_STN4_TX_DP<72>")
	)
	(segment
		(start 79.9338 -320.294)
		(end 79.9338 -320.265552)
		(width 0.1143)
		(layer "In11.Cu")
		(net "P5E_PEX0_STN4_TX_DP<72>")
	)
	(segment
		(start 36.722558 -341.02294)
		(end 36.762436 -340.956138)
		(width 0.1651)
		(layer "In11.Cu")
		(net "P5E_PEX0_STN4_TX_DP<72>")
	)
	(segment
		(start 75.81265 -327.591674)
		(end 77.282802 -326.805798)
		(width 0.1651)
		(layer "In11.Cu")
		(net "P5E_PEX0_STN4_TX_DP<72>")
	)
	(segment
		(start 80.46085 -313.379612)
		(end 80.54975 -313.290712)
		(width 0.1143)
		(layer "In11.Cu")
		(net "P5E_PEX0_STN4_TX_DP<72>")
	)
	(segment
		(start 78.827122 -325.261478)
		(end 79.9338 -322.589652)
		(width 0.1651)
		(layer "In11.Cu")
		(net "P5E_PEX0_STN4_TX_DP<72>")
	)
	(segment
		(start 280.901902 -345.170506)
		(end 281.196542 -345.465146)
		(width 0.13462)
		(layer "F.Cu")
		(net "P5E_PEX2_STN4_TX_C_DN<74>")
	)
	(segment
		(start 280.901902 -344.539062)
		(end 280.901902 -345.170506)
		(width 0.13462)
		(layer "F.Cu")
		(net "P5E_PEX2_STN4_TX_C_DN<74>")
	)
	(segment
		(start 281.221942 -344.219022)
		(end 280.901902 -344.539062)
		(width 0.13462)
		(layer "F.Cu")
		(net "P5E_PEX2_STN4_TX_C_DN<74>")
	)
	(segment
		(start 284.435296 -385.166362)
		(end 283.69006 -378.847604)
		(width 0.1651)
		(layer "In11.Cu")
		(net "P5E_PEX2_STN4_TX_C_DN<74>")
	)
	(segment
		(start 279.351232 -358.83596)
		(end 279.351232 -347.881194)
		(width 0.1651)
		(layer "In11.Cu")
		(net "P5E_PEX2_STN4_TX_C_DN<74>")
	)
	(segment
		(start 285.01213 -386.36829)
		(end 284.435296 -385.166362)
		(width 0.1651)
		(layer "In11.Cu")
		(net "P5E_PEX2_STN4_TX_C_DN<74>")
	)
	(segment
		(start 299.61586 -395.693392)
		(end 298.56557 -393.922758)
		(width 0.1651)
		(layer "In11.Cu")
		(net "P5E_PEX2_STN4_TX_C_DN<74>")
	)
	(segment
		(start 279.351232 -347.881194)
		(end 280.905712 -346.326714)
		(width 0.1651)
		(layer "In11.Cu")
		(net "P5E_PEX2_STN4_TX_C_DN<74>")
	)
	(segment
		(start 280.905712 -346.326714)
		(end 280.905712 -345.755976)
		(width 0.1651)
		(layer "In11.Cu")
		(net "P5E_PEX2_STN4_TX_C_DN<74>")
	)
	(segment
		(start 298.56557 -393.922758)
		(end 294.200326 -390.920986)
		(width 0.1651)
		(layer "In11.Cu")
		(net "P5E_PEX2_STN4_TX_C_DN<74>")
	)
	(segment
		(start 299.163994 -398.38122)
		(end 299.61586 -397.929354)
		(width 0.1651)
		(layer "In11.Cu")
		(net "P5E_PEX2_STN4_TX_C_DN<74>")
	)
	(segment
		(start 283.69006 -378.847604)
		(end 279.351232 -358.83596)
		(width 0.1651)
		(layer "In11.Cu")
		(net "P5E_PEX2_STN4_TX_C_DN<74>")
	)
	(segment
		(start 294.200326 -390.920986)
		(end 286.424878 -387.751574)
		(width 0.1651)
		(layer "In11.Cu")
		(net "P5E_PEX2_STN4_TX_C_DN<74>")
	)
	(segment
		(start 298.489878 -398.890236)
		(end 298.489878 -398.50822)
		(width 0.1651)
		(layer "In11.Cu")
		(net "P5E_PEX2_STN4_TX_C_DN<74>")
	)
	(segment
		(start 299.61586 -397.929354)
		(end 299.61586 -395.693392)
		(width 0.1651)
		(layer "In11.Cu")
		(net "P5E_PEX2_STN4_TX_C_DN<74>")
	)
	(segment
		(start 298.616878 -398.38122)
		(end 299.163994 -398.38122)
		(width 0.1651)
		(layer "In11.Cu")
		(net "P5E_PEX2_STN4_TX_C_DN<74>")
	)
	(segment
		(start 286.424878 -387.751574)
		(end 285.01213 -386.36829)
		(width 0.1651)
		(layer "In11.Cu")
		(net "P5E_PEX2_STN4_TX_C_DN<74>")
	)
	(segment
		(start 280.905712 -345.755976)
		(end 281.196542 -345.465146)
		(width 0.1651)
		(layer "In11.Cu")
		(net "P5E_PEX2_STN4_TX_C_DN<74>")
	)
	(segment
		(start 298.489878 -398.50822)
		(end 298.616878 -398.38122)
		(width 0.1651)
		(layer "In11.Cu")
		(net "P5E_PEX2_STN4_TX_C_DN<74>")
	)
	(segment
		(start 425.728892 -343.685622)
		(end 425.408344 -343.365074)
		(width 0.13462)
		(layer "F.Cu")
		(net "P5E_PEX3_STN4_TX_DN<72>")
	)
	(segment
		(start 425.408344 -342.734646)
		(end 425.703492 -342.439498)
		(width 0.13462)
		(layer "F.Cu")
		(net "P5E_PEX3_STN4_TX_DN<72>")
	)
	(segment
		(start 425.408344 -343.365074)
		(end 425.408344 -342.734646)
		(width 0.13462)
		(layer "F.Cu")
		(net "P5E_PEX3_STN4_TX_DN<72>")
	)
	(segment
		(start 428.51578 -319.9384)
		(end 428.51578 -319.909952)
		(width 0.1143)
		(layer "In7.Cu")
		(net "P5E_PEX3_STN4_TX_DN<72>")
	)
	(segment
		(start 425.412662 -341.633556)
		(end 428.51578 -323.363844)
		(width 0.1651)
		(layer "In7.Cu")
		(net "P5E_PEX3_STN4_TX_DN<72>")
	)
	(segment
		(start 428.51578 -323.363844)
		(end 428.51578 -319.9384)
		(width 0.1651)
		(layer "In7.Cu")
		(net "P5E_PEX3_STN4_TX_DN<72>")
	)
	(segment
		(start 428.47006 -313.684412)
		(end 428.58436 -313.570112)
		(width 0.1143)
		(layer "In7.Cu")
		(net "P5E_PEX3_STN4_TX_DN<72>")
	)
	(segment
		(start 428.84979 -313.684412)
		(end 428.84979 -313.949842)
		(width 0.1143)
		(layer "In7.Cu")
		(net "P5E_PEX3_STN4_TX_DN<72>")
	)
	(segment
		(start 425.703492 -342.439498)
		(end 425.412662 -342.148668)
		(width 0.1651)
		(layer "In7.Cu")
		(net "P5E_PEX3_STN4_TX_DN<72>")
	)
	(segment
		(start 428.51578 -319.909952)
		(end 428.47006 -319.864232)
		(width 0.1143)
		(layer "In7.Cu")
		(net "P5E_PEX3_STN4_TX_DN<72>")
	)
	(segment
		(start 428.47006 -319.864232)
		(end 428.47006 -313.684412)
		(width 0.1143)
		(layer "In7.Cu")
		(net "P5E_PEX3_STN4_TX_DN<72>")
	)
	(segment
		(start 428.58436 -313.570112)
		(end 428.73549 -313.570112)
		(width 0.1143)
		(layer "In7.Cu")
		(net "P5E_PEX3_STN4_TX_DN<72>")
	)
	(segment
		(start 425.412662 -342.148668)
		(end 425.412662 -341.633556)
		(width 0.1651)
		(layer "In7.Cu")
		(net "P5E_PEX3_STN4_TX_DN<72>")
	)
	(segment
		(start 428.73549 -313.570112)
		(end 428.84979 -313.684412)
		(width 0.1143)
		(layer "In7.Cu")
		(net "P5E_PEX3_STN4_TX_DN<72>")
	)
	(segment
		(start 28.633928 -349.831914)
		(end 28.953968 -349.511874)
		(width 0.13462)
		(layer "F.Cu")
		(net "P5E_PEX0_STN4_TX_DP<75>")
	)
	(segment
		(start 28.953968 -349.511874)
		(end 28.953968 -348.88043)
		(width 0.13462)
		(layer "F.Cu")
		(net "P5E_PEX0_STN4_TX_DP<75>")
	)
	(segment
		(start 28.953968 -348.88043)
		(end 28.659328 -348.58579)
		(width 0.13462)
		(layer "F.Cu")
		(net "P5E_PEX0_STN4_TX_DP<75>")
	)
	(segment
		(start 77.69987 -311.390792)
		(end 77.69987 -311.099962)
		(width 0.1143)
		(layer "In11.Cu")
		(net "P5E_PEX0_STN4_TX_DP<75>")
	)
	(segment
		(start 74.272648 -324.975728)
		(end 74.272394 -324.975728)
		(width 0.1651)
		(layer "In11.Cu")
		(net "P5E_PEX0_STN4_TX_DP<75>")
	)
	(segment
		(start 77.08392 -320.265552)
		(end 77.12964 -320.219832)
		(width 0.1143)
		(layer "In11.Cu")
		(net "P5E_PEX0_STN4_TX_DP<75>")
	)
	(segment
		(start 77.08392 -321.545458)
		(end 77.08392 -320.294)
		(width 0.1651)
		(layer "In11.Cu")
		(net "P5E_PEX0_STN4_TX_DP<75>")
	)
	(segment
		(start 47.580804 -331.20076)
		(end 53.346858 -329.137772)
		(width 0.1651)
		(layer "In11.Cu")
		(net "P5E_PEX0_STN4_TX_DP<75>")
	)
	(segment
		(start 30.504638 -346.065602)
		(end 30.504638 -339.987382)
		(width 0.1651)
		(layer "In11.Cu")
		(net "P5E_PEX0_STN4_TX_DP<75>")
	)
	(segment
		(start 28.950158 -348.29496)
		(end 28.950158 -347.620082)
		(width 0.1651)
		(layer "In11.Cu")
		(net "P5E_PEX0_STN4_TX_DP<75>")
	)
	(segment
		(start 75.62977 -324.250304)
		(end 76.2 -323.680328)
		(width 0.1651)
		(layer "In11.Cu")
		(net "P5E_PEX0_STN4_TX_DP<75>")
	)
	(segment
		(start 30.504638 -339.987382)
		(end 31.960566 -338.5312)
		(width 0.1651)
		(layer "In11.Cu")
		(net "P5E_PEX0_STN4_TX_DP<75>")
	)
	(segment
		(start 41.814496 -333.264256)
		(end 47.581058 -331.20076)
		(width 0.1651)
		(layer "In11.Cu")
		(net "P5E_PEX0_STN4_TX_DP<75>")
	)
	(segment
		(start 74.272394 -324.975728)
		(end 75.62977 -324.250304)
		(width 0.1651)
		(layer "In11.Cu")
		(net "P5E_PEX0_STN4_TX_DP<75>")
	)
	(segment
		(start 77.12964 -320.219832)
		(end 77.12964 -311.756298)
		(width 0.1143)
		(layer "In11.Cu")
		(net "P5E_PEX0_STN4_TX_DP<75>")
	)
	(segment
		(start 28.950158 -347.620082)
		(end 30.504638 -346.065602)
		(width 0.1651)
		(layer "In11.Cu")
		(net "P5E_PEX0_STN4_TX_DP<75>")
	)
	(segment
		(start 47.581058 -331.20076)
		(end 47.580804 -331.20076)
		(width 0.1651)
		(layer "In11.Cu")
		(net "P5E_PEX0_STN4_TX_DP<75>")
	)
	(segment
		(start 28.659328 -348.58579)
		(end 28.950158 -348.29496)
		(width 0.1651)
		(layer "In11.Cu")
		(net "P5E_PEX0_STN4_TX_DP<75>")
	)
	(segment
		(start 77.61097 -311.479692)
		(end 77.69987 -311.390792)
		(width 0.1143)
		(layer "In11.Cu")
		(net "P5E_PEX0_STN4_TX_DP<75>")
	)
	(segment
		(start 77.406246 -311.479692)
		(end 77.61097 -311.479692)
		(width 0.1143)
		(layer "In11.Cu")
		(net "P5E_PEX0_STN4_TX_DP<75>")
	)
	(segment
		(start 77.08392 -320.294)
		(end 77.08392 -320.265552)
		(width 0.1143)
		(layer "In11.Cu")
		(net "P5E_PEX0_STN4_TX_DP<75>")
	)
	(segment
		(start 77.12964 -311.756298)
		(end 77.406246 -311.479692)
		(width 0.1143)
		(layer "In11.Cu")
		(net "P5E_PEX0_STN4_TX_DP<75>")
	)
	(segment
		(start 76.2 -323.680328)
		(end 77.08392 -321.545458)
		(width 0.1651)
		(layer "In11.Cu")
		(net "P5E_PEX0_STN4_TX_DP<75>")
	)
	(segment
		(start 31.960566 -338.5312)
		(end 41.814496 -333.264256)
		(width 0.1651)
		(layer "In11.Cu")
		(net "P5E_PEX0_STN4_TX_DP<75>")
	)
	(segment
		(start 53.346858 -329.137772)
		(end 74.272648 -324.975728)
		(width 0.1651)
		(layer "In11.Cu")
		(net "P5E_PEX0_STN4_TX_DP<75>")
	)
	(segment
		(start 299.281342 -357.46309)
		(end 298.986702 -357.75773)
		(width 0.13462)
		(layer "F.Cu")
		(net "P5E_PEX2_STN4_TX_C_DP<64>")
	)
	(segment
		(start 298.961302 -356.511606)
		(end 299.281342 -356.831646)
		(width 0.13462)
		(layer "F.Cu")
		(net "P5E_PEX2_STN4_TX_C_DP<64>")
	)
	(segment
		(start 299.281342 -356.831646)
		(end 299.281342 -357.46309)
		(width 0.13462)
		(layer "F.Cu")
		(net "P5E_PEX2_STN4_TX_C_DP<64>")
	)
	(segment
		(start 302.440848 -365.978186)
		(end 302.644556 -366.429544)
		(width 0.1651)
		(layer "In11.Cu")
		(net "P5E_PEX2_STN4_TX_C_DP<64>")
	)
	(segment
		(start 301.286164 -363.698028)
		(end 301.437802 -363.755178)
		(width 0.1651)
		(layer "In11.Cu")
		(net "P5E_PEX2_STN4_TX_C_DP<64>")
	)
	(segment
		(start 301.939198 -364.866682)
		(end 302.142906 -365.31804)
		(width 0.1651)
		(layer "In11.Cu")
		(net "P5E_PEX2_STN4_TX_C_DP<64>")
	)
	(segment
		(start 302.289464 -365.921036)
		(end 302.440848 -365.978186)
		(width 0.1651)
		(layer "In11.Cu")
		(net "P5E_PEX2_STN4_TX_C_DP<64>")
	)
	(segment
		(start 303.089056 -367.692178)
		(end 303.292764 -368.14379)
		(width 0.1651)
		(layer "In11.Cu")
		(net "P5E_PEX2_STN4_TX_C_DP<64>")
	)
	(segment
		(start 300.63821 -361.983528)
		(end 300.580806 -362.134658)
		(width 0.1651)
		(layer "In11.Cu")
		(net "P5E_PEX2_STN4_TX_C_DP<64>")
	)
	(segment
		(start 301.437802 -363.755178)
		(end 301.641256 -364.206536)
		(width 0.1651)
		(layer "In11.Cu")
		(net "P5E_PEX2_STN4_TX_C_DP<64>")
	)
	(segment
		(start 301.584106 -364.35792)
		(end 301.787814 -364.809532)
		(width 0.1651)
		(layer "In11.Cu")
		(net "P5E_PEX2_STN4_TX_C_DP<64>")
	)
	(segment
		(start 302.587406 -366.580928)
		(end 302.791114 -367.03254)
		(width 0.1651)
		(layer "In11.Cu")
		(net "P5E_PEX2_STN4_TX_C_DP<64>")
	)
	(segment
		(start 303.733962 -371.812312)
		(end 303.447196 -372.099078)
		(width 0.1651)
		(layer "In11.Cu")
		(net "P5E_PEX2_STN4_TX_C_DP<64>")
	)
	(segment
		(start 300.580806 -362.134658)
		(end 300.784514 -362.586524)
		(width 0.1651)
		(layer "In11.Cu")
		(net "P5E_PEX2_STN4_TX_C_DP<64>")
	)
	(segment
		(start 302.88992 -371.972078)
		(end 302.88992 -371.590062)
		(width 0.1651)
		(layer "In11.Cu")
		(net "P5E_PEX2_STN4_TX_C_DP<64>")
	)
	(segment
		(start 300.07941 -361.023154)
		(end 300.283118 -361.47502)
		(width 0.1651)
		(layer "In11.Cu")
		(net "P5E_PEX2_STN4_TX_C_DP<64>")
	)
	(segment
		(start 300.283118 -361.47502)
		(end 300.434756 -361.53217)
		(width 0.1651)
		(layer "In11.Cu")
		(net "P5E_PEX2_STN4_TX_C_DP<64>")
	)
	(segment
		(start 302.142906 -365.31804)
		(end 302.085756 -365.469424)
		(width 0.1651)
		(layer "In11.Cu")
		(net "P5E_PEX2_STN4_TX_C_DP<64>")
	)
	(segment
		(start 300.434756 -361.53217)
		(end 300.63821 -361.983528)
		(width 0.1651)
		(layer "In11.Cu")
		(net "P5E_PEX2_STN4_TX_C_DP<64>")
	)
	(segment
		(start 303.444148 -368.20094)
		(end 303.733962 -368.843306)
		(width 0.1651)
		(layer "In11.Cu")
		(net "P5E_PEX2_STN4_TX_C_DP<64>")
	)
	(segment
		(start 300.784514 -362.586524)
		(end 300.936152 -362.643674)
		(width 0.1651)
		(layer "In11.Cu")
		(net "P5E_PEX2_STN4_TX_C_DP<64>")
	)
	(segment
		(start 299.277532 -358.967786)
		(end 300.13656 -360.872024)
		(width 0.1651)
		(layer "In11.Cu")
		(net "P5E_PEX2_STN4_TX_C_DP<64>")
	)
	(segment
		(start 302.791114 -367.03254)
		(end 302.942498 -367.08969)
		(width 0.1651)
		(layer "In11.Cu")
		(net "P5E_PEX2_STN4_TX_C_DP<64>")
	)
	(segment
		(start 298.986702 -357.75773)
		(end 299.277532 -358.04856)
		(width 0.1651)
		(layer "In11.Cu")
		(net "P5E_PEX2_STN4_TX_C_DP<64>")
	)
	(segment
		(start 303.01692 -372.099078)
		(end 302.88992 -371.972078)
		(width 0.1651)
		(layer "In11.Cu")
		(net "P5E_PEX2_STN4_TX_C_DP<64>")
	)
	(segment
		(start 301.787814 -364.809532)
		(end 301.939198 -364.866682)
		(width 0.1651)
		(layer "In11.Cu")
		(net "P5E_PEX2_STN4_TX_C_DP<64>")
	)
	(segment
		(start 301.082456 -363.246162)
		(end 301.286164 -363.698028)
		(width 0.1651)
		(layer "In11.Cu")
		(net "P5E_PEX2_STN4_TX_C_DP<64>")
	)
	(segment
		(start 300.13656 -360.872024)
		(end 300.07941 -361.023154)
		(width 0.1651)
		(layer "In11.Cu")
		(net "P5E_PEX2_STN4_TX_C_DP<64>")
	)
	(segment
		(start 300.936152 -362.643674)
		(end 301.139606 -363.095032)
		(width 0.1651)
		(layer "In11.Cu")
		(net "P5E_PEX2_STN4_TX_C_DP<64>")
	)
	(segment
		(start 302.644556 -366.429544)
		(end 302.587406 -366.580928)
		(width 0.1651)
		(layer "In11.Cu")
		(net "P5E_PEX2_STN4_TX_C_DP<64>")
	)
	(segment
		(start 302.942498 -367.08969)
		(end 303.146206 -367.541048)
		(width 0.1651)
		(layer "In11.Cu")
		(net "P5E_PEX2_STN4_TX_C_DP<64>")
	)
	(segment
		(start 303.733962 -368.843306)
		(end 303.733962 -371.812312)
		(width 0.1651)
		(layer "In11.Cu")
		(net "P5E_PEX2_STN4_TX_C_DP<64>")
	)
	(segment
		(start 299.277532 -358.04856)
		(end 299.277532 -358.967786)
		(width 0.1651)
		(layer "In11.Cu")
		(net "P5E_PEX2_STN4_TX_C_DP<64>")
	)
	(segment
		(start 303.447196 -372.099078)
		(end 303.01692 -372.099078)
		(width 0.1651)
		(layer "In11.Cu")
		(net "P5E_PEX2_STN4_TX_C_DP<64>")
	)
	(segment
		(start 303.292764 -368.14379)
		(end 303.444148 -368.20094)
		(width 0.1651)
		(layer "In11.Cu")
		(net "P5E_PEX2_STN4_TX_C_DP<64>")
	)
	(segment
		(start 302.085756 -365.469424)
		(end 302.289464 -365.921036)
		(width 0.1651)
		(layer "In11.Cu")
		(net "P5E_PEX2_STN4_TX_C_DP<64>")
	)
	(segment
		(start 303.146206 -367.541048)
		(end 303.089056 -367.692178)
		(width 0.1651)
		(layer "In11.Cu")
		(net "P5E_PEX2_STN4_TX_C_DP<64>")
	)
	(segment
		(start 301.641256 -364.206536)
		(end 301.584106 -364.35792)
		(width 0.1651)
		(layer "In11.Cu")
		(net "P5E_PEX2_STN4_TX_C_DP<64>")
	)
	(segment
		(start 301.139606 -363.095032)
		(end 301.082456 -363.246162)
		(width 0.1651)
		(layer "In11.Cu")
		(net "P5E_PEX2_STN4_TX_C_DP<64>")
	)
	(segment
		(start 412.698184 -355.658674)
		(end 412.698184 -355.026214)
		(width 0.13462)
		(layer "F.Cu")
		(net "P5E_PEX3_STN4_TX_DP<77>")
	)
	(segment
		(start 412.378652 -355.978206)
		(end 412.698184 -355.658674)
		(width 0.13462)
		(layer "F.Cu")
		(net "P5E_PEX3_STN4_TX_DP<77>")
	)
	(segment
		(start 412.698184 -355.026214)
		(end 412.404052 -354.732082)
		(width 0.13462)
		(layer "F.Cu")
		(net "P5E_PEX3_STN4_TX_DP<77>")
	)
	(segment
		(start 423.48404 -319.909952)
		(end 423.52976 -319.864232)
		(width 0.1143)
		(layer "In7.Cu")
		(net "P5E_PEX3_STN4_TX_DP<77>")
	)
	(segment
		(start 423.755566 -311.479692)
		(end 423.98569 -311.479692)
		(width 0.1143)
		(layer "In7.Cu")
		(net "P5E_PEX3_STN4_TX_DP<77>")
	)
	(segment
		(start 424.09999 -311.365392)
		(end 424.09999 -311.099962)
		(width 0.1143)
		(layer "In7.Cu")
		(net "P5E_PEX3_STN4_TX_DP<77>")
	)
	(segment
		(start 414.249362 -341.667338)
		(end 423.178224 -322.303394)
		(width 0.1651)
		(layer "In7.Cu")
		(net "P5E_PEX3_STN4_TX_DP<77>")
	)
	(segment
		(start 412.694882 -353.814126)
		(end 414.249362 -352.259646)
		(width 0.1651)
		(layer "In7.Cu")
		(net "P5E_PEX3_STN4_TX_DP<77>")
	)
	(segment
		(start 423.48404 -320.91122)
		(end 423.48404 -319.9384)
		(width 0.1651)
		(layer "In7.Cu")
		(net "P5E_PEX3_STN4_TX_DP<77>")
	)
	(segment
		(start 414.249362 -352.259646)
		(end 414.249362 -341.667338)
		(width 0.1651)
		(layer "In7.Cu")
		(net "P5E_PEX3_STN4_TX_DP<77>")
	)
	(segment
		(start 412.694882 -354.441252)
		(end 412.694882 -353.814126)
		(width 0.1651)
		(layer "In7.Cu")
		(net "P5E_PEX3_STN4_TX_DP<77>")
	)
	(segment
		(start 423.48404 -319.9384)
		(end 423.48404 -319.909952)
		(width 0.1143)
		(layer "In7.Cu")
		(net "P5E_PEX3_STN4_TX_DP<77>")
	)
	(segment
		(start 423.98569 -311.479692)
		(end 424.09999 -311.365392)
		(width 0.1143)
		(layer "In7.Cu")
		(net "P5E_PEX3_STN4_TX_DP<77>")
	)
	(segment
		(start 412.404052 -354.732082)
		(end 412.694882 -354.441252)
		(width 0.1651)
		(layer "In7.Cu")
		(net "P5E_PEX3_STN4_TX_DP<77>")
	)
	(segment
		(start 423.52976 -319.864232)
		(end 423.52976 -311.705498)
		(width 0.1143)
		(layer "In7.Cu")
		(net "P5E_PEX3_STN4_TX_DP<77>")
	)
	(segment
		(start 423.52976 -311.705498)
		(end 423.755566 -311.479692)
		(width 0.1143)
		(layer "In7.Cu")
		(net "P5E_PEX3_STN4_TX_DP<77>")
	)
	(segment
		(start 423.178224 -322.303394)
		(end 423.48404 -320.91122)
		(width 0.1651)
		(layer "In7.Cu")
		(net "P5E_PEX3_STN4_TX_DP<77>")
	)
	(segment
		(start 38.875208 -355.978206)
		(end 38.555168 -355.658166)
		(width 0.13462)
		(layer "F.Cu")
		(net "P5E_PEX0_STN4_TX_DN<70>")
	)
	(segment
		(start 38.555168 -355.658166)
		(end 38.555168 -355.026722)
		(width 0.13462)
		(layer "F.Cu")
		(net "P5E_PEX0_STN4_TX_DN<70>")
	)
	(segment
		(start 38.555168 -355.026722)
		(end 38.849808 -354.732082)
		(width 0.13462)
		(layer "F.Cu")
		(net "P5E_PEX0_STN4_TX_DN<70>")
	)
	(segment
		(start 83.711542 -313.704986)
		(end 84.307934 -314.301378)
		(width 0.1651)
		(layer "In11.Cu")
		(net "P5E_PEX0_STN4_TX_DN<70>")
	)
	(segment
		(start 42.07002 -339.641434)
		(end 40.471852 -341.239602)
		(width 0.1651)
		(layer "In11.Cu")
		(net "P5E_PEX0_STN4_TX_DN<70>")
	)
	(segment
		(start 56.106568 -333.797148)
		(end 46.718474 -337.156806)
		(width 0.1651)
		(layer "In11.Cu")
		(net "P5E_PEX0_STN4_TX_DN<70>")
	)
	(segment
		(start 84.307934 -314.301378)
		(end 84.307934 -320.84772)
		(width 0.1651)
		(layer "In11.Cu")
		(net "P5E_PEX0_STN4_TX_DN<70>")
	)
	(segment
		(start 83.627214 -313.68492)
		(end 83.691476 -313.68492)
		(width 0.1143)
		(layer "In11.Cu")
		(net "P5E_PEX0_STN4_TX_DN<70>")
	)
	(segment
		(start 82.070194 -312.264552)
		(end 82.235294 -312.429652)
		(width 0.1143)
		(layer "In11.Cu")
		(net "P5E_PEX0_STN4_TX_DN<70>")
	)
	(segment
		(start 78.682088 -328.634598)
		(end 76.678028 -329.705462)
		(width 0.1651)
		(layer "In11.Cu")
		(net "P5E_PEX0_STN4_TX_DN<70>")
	)
	(segment
		(start 83.157568 -312.875168)
		(end 83.157568 -313.215274)
		(width 0.1143)
		(layer "In11.Cu")
		(net "P5E_PEX0_STN4_TX_DN<70>")
	)
	(segment
		(start 81.025238 -326.291194)
		(end 78.682088 -328.634598)
		(width 0.1651)
		(layer "In11.Cu")
		(net "P5E_PEX0_STN4_TX_DN<70>")
	)
	(segment
		(start 76.678028 -329.705462)
		(end 56.106568 -333.797148)
		(width 0.1651)
		(layer "In11.Cu")
		(net "P5E_PEX0_STN4_TX_DN<70>")
	)
	(segment
		(start 82.159094 -312.049922)
		(end 82.070194 -312.138822)
		(width 0.1143)
		(layer "In11.Cu")
		(net "P5E_PEX0_STN4_TX_DN<70>")
	)
	(segment
		(start 38.558978 -353.774502)
		(end 38.558978 -354.441252)
		(width 0.1651)
		(layer "In11.Cu")
		(net "P5E_PEX0_STN4_TX_DN<70>")
	)
	(segment
		(start 40.113458 -352.220022)
		(end 38.558978 -353.774502)
		(width 0.1651)
		(layer "In11.Cu")
		(net "P5E_PEX0_STN4_TX_DN<70>")
	)
	(segment
		(start 82.070194 -312.138822)
		(end 82.070194 -312.264552)
		(width 0.1143)
		(layer "In11.Cu")
		(net "P5E_PEX0_STN4_TX_DN<70>")
	)
	(segment
		(start 83.72983 -322.243704)
		(end 81.025238 -326.291194)
		(width 0.1651)
		(layer "In11.Cu")
		(net "P5E_PEX0_STN4_TX_DN<70>")
	)
	(segment
		(start 83.157568 -313.215274)
		(end 83.627214 -313.68492)
		(width 0.1143)
		(layer "In11.Cu")
		(net "P5E_PEX0_STN4_TX_DN<70>")
	)
	(segment
		(start 82.235294 -312.429652)
		(end 82.712052 -312.429652)
		(width 0.1143)
		(layer "In11.Cu")
		(net "P5E_PEX0_STN4_TX_DN<70>")
	)
	(segment
		(start 83.691476 -313.68492)
		(end 83.711542 -313.704986)
		(width 0.1143)
		(layer "In11.Cu")
		(net "P5E_PEX0_STN4_TX_DN<70>")
	)
	(segment
		(start 82.712052 -312.429652)
		(end 83.157568 -312.875168)
		(width 0.1143)
		(layer "In11.Cu")
		(net "P5E_PEX0_STN4_TX_DN<70>")
	)
	(segment
		(start 40.471852 -341.239602)
		(end 40.113458 -342.10498)
		(width 0.1651)
		(layer "In11.Cu")
		(net "P5E_PEX0_STN4_TX_DN<70>")
	)
	(segment
		(start 46.718474 -337.156806)
		(end 42.07002 -339.641434)
		(width 0.1651)
		(layer "In11.Cu")
		(net "P5E_PEX0_STN4_TX_DN<70>")
	)
	(segment
		(start 38.558978 -354.441252)
		(end 38.849808 -354.732082)
		(width 0.1651)
		(layer "In11.Cu")
		(net "P5E_PEX0_STN4_TX_DN<70>")
	)
	(segment
		(start 40.113458 -342.10498)
		(end 40.113458 -352.220022)
		(width 0.1651)
		(layer "In11.Cu")
		(net "P5E_PEX0_STN4_TX_DN<70>")
	)
	(segment
		(start 82.449924 -312.049922)
		(end 82.159094 -312.049922)
		(width 0.1143)
		(layer "In11.Cu")
		(net "P5E_PEX0_STN4_TX_DN<70>")
	)
	(segment
		(start 84.307934 -320.84772)
		(end 83.72983 -322.243704)
		(width 0.1651)
		(layer "In11.Cu")
		(net "P5E_PEX0_STN4_TX_DN<70>")
	)
	(segment
		(start 274.409662 -345.170506)
		(end 274.115022 -345.465146)
		(width 0.13462)
		(layer "F.Cu")
		(net "P5E_PEX2_STN4_TX_C_DP<77>")
	)
	(segment
		(start 274.409662 -344.539062)
		(end 274.409662 -345.170506)
		(width 0.13462)
		(layer "F.Cu")
		(net "P5E_PEX2_STN4_TX_C_DP<77>")
	)
	(segment
		(start 274.089622 -344.219022)
		(end 274.409662 -344.539062)
		(width 0.13462)
		(layer "F.Cu")
		(net "P5E_PEX2_STN4_TX_C_DP<77>")
	)
	(segment
		(start 287.137348 -391.835386)
		(end 287.252918 -391.785602)
		(width 0.1651)
		(layer "In11.Cu")
		(net "P5E_PEX2_STN4_TX_C_DP<77>")
	)
	(segment
		(start 289.307524 -392.70305)
		(end 289.423094 -392.65352)
		(width 0.1651)
		(layer "In11.Cu")
		(net "P5E_PEX2_STN4_TX_C_DP<77>")
	)
	(segment
		(start 286.6771 -391.651236)
		(end 287.137348 -391.835386)
		(width 0.1651)
		(layer "In11.Cu")
		(net "P5E_PEX2_STN4_TX_C_DP<77>")
	)
	(segment
		(start 288.338006 -392.219688)
		(end 288.797746 -392.40333)
		(width 0.1651)
		(layer "In11.Cu")
		(net "P5E_PEX2_STN4_TX_C_DP<77>")
	)
	(segment
		(start 291.889942 -396.872206)
		(end 291.889942 -396.49019)
		(width 0.1651)
		(layer "In11.Cu")
		(net "P5E_PEX2_STN4_TX_C_DP<77>")
	)
	(segment
		(start 289.423094 -392.65352)
		(end 289.882834 -392.837416)
		(width 0.1651)
		(layer "In11.Cu")
		(net "P5E_PEX2_STN4_TX_C_DP<77>")
	)
	(segment
		(start 280.299668 -378.888244)
		(end 281.269948 -386.222494)
		(width 0.1651)
		(layer "In11.Cu")
		(net "P5E_PEX2_STN4_TX_C_DP<77>")
	)
	(segment
		(start 288.222436 -392.269218)
		(end 288.338006 -392.219688)
		(width 0.1651)
		(layer "In11.Cu")
		(net "P5E_PEX2_STN4_TX_C_DP<77>")
	)
	(segment
		(start 287.712658 -391.969498)
		(end 287.762188 -392.085068)
		(width 0.1651)
		(layer "In11.Cu")
		(net "P5E_PEX2_STN4_TX_C_DP<77>")
	)
	(segment
		(start 274.405852 -345.755976)
		(end 274.405852 -346.209874)
		(width 0.1651)
		(layer "In11.Cu")
		(net "P5E_PEX2_STN4_TX_C_DP<77>")
	)
	(segment
		(start 286.05226 -391.4013)
		(end 286.16783 -391.35177)
		(width 0.1651)
		(layer "In11.Cu")
		(net "P5E_PEX2_STN4_TX_C_DP<77>")
	)
	(segment
		(start 288.797746 -392.40333)
		(end 288.847276 -392.5189)
		(width 0.1651)
		(layer "In11.Cu")
		(net "P5E_PEX2_STN4_TX_C_DP<77>")
	)
	(segment
		(start 285.592012 -391.21715)
		(end 286.05226 -391.4013)
		(width 0.1651)
		(layer "In11.Cu")
		(net "P5E_PEX2_STN4_TX_C_DP<77>")
	)
	(segment
		(start 272.851372 -347.764354)
		(end 272.851372 -358.774746)
		(width 0.1651)
		(layer "In11.Cu")
		(net "P5E_PEX2_STN4_TX_C_DP<77>")
	)
	(segment
		(start 292.016942 -396.999206)
		(end 291.889942 -396.872206)
		(width 0.1651)
		(layer "In11.Cu")
		(net "P5E_PEX2_STN4_TX_C_DP<77>")
	)
	(segment
		(start 274.115022 -345.465146)
		(end 274.405852 -345.755976)
		(width 0.1651)
		(layer "In11.Cu")
		(net "P5E_PEX2_STN4_TX_C_DP<77>")
	)
	(segment
		(start 292.733984 -396.71244)
		(end 292.447218 -396.999206)
		(width 0.1651)
		(layer "In11.Cu")
		(net "P5E_PEX2_STN4_TX_C_DP<77>")
	)
	(segment
		(start 285.542482 -391.10158)
		(end 285.592012 -391.21715)
		(width 0.1651)
		(layer "In11.Cu")
		(net "P5E_PEX2_STN4_TX_C_DP<77>")
	)
	(segment
		(start 289.932364 -392.952986)
		(end 290.392358 -393.137136)
		(width 0.1651)
		(layer "In11.Cu")
		(net "P5E_PEX2_STN4_TX_C_DP<77>")
	)
	(segment
		(start 291.622226 -393.84351)
		(end 291.620956 -394.005054)
		(width 0.1651)
		(layer "In11.Cu")
		(net "P5E_PEX2_STN4_TX_C_DP<77>")
	)
	(segment
		(start 291.968936 -394.358114)
		(end 292.130734 -394.359384)
		(width 0.1651)
		(layer "In11.Cu")
		(net "P5E_PEX2_STN4_TX_C_DP<77>")
	)
	(segment
		(start 284.938724 -390.86028)
		(end 285.542482 -391.10158)
		(width 0.1651)
		(layer "In11.Cu")
		(net "P5E_PEX2_STN4_TX_C_DP<77>")
	)
	(segment
		(start 291.620956 -394.005054)
		(end 291.968936 -394.358114)
		(width 0.1651)
		(layer "In11.Cu")
		(net "P5E_PEX2_STN4_TX_C_DP<77>")
	)
	(segment
		(start 287.252918 -391.785602)
		(end 287.712658 -391.969498)
		(width 0.1651)
		(layer "In11.Cu")
		(net "P5E_PEX2_STN4_TX_C_DP<77>")
	)
	(segment
		(start 281.269948 -386.222494)
		(end 282.323794 -388.347458)
		(width 0.1651)
		(layer "In11.Cu")
		(net "P5E_PEX2_STN4_TX_C_DP<77>")
	)
	(segment
		(start 289.882834 -392.837416)
		(end 289.932364 -392.952986)
		(width 0.1651)
		(layer "In11.Cu")
		(net "P5E_PEX2_STN4_TX_C_DP<77>")
	)
	(segment
		(start 290.392358 -393.137136)
		(end 290.507928 -393.087606)
		(width 0.1651)
		(layer "In11.Cu")
		(net "P5E_PEX2_STN4_TX_C_DP<77>")
	)
	(segment
		(start 274.405852 -346.209874)
		(end 272.851372 -347.764354)
		(width 0.1651)
		(layer "In11.Cu")
		(net "P5E_PEX2_STN4_TX_C_DP<77>")
	)
	(segment
		(start 272.851372 -358.774746)
		(end 280.299668 -378.888244)
		(width 0.1651)
		(layer "In11.Cu")
		(net "P5E_PEX2_STN4_TX_C_DP<77>")
	)
	(segment
		(start 286.16783 -391.35177)
		(end 286.62757 -391.535666)
		(width 0.1651)
		(layer "In11.Cu")
		(net "P5E_PEX2_STN4_TX_C_DP<77>")
	)
	(segment
		(start 292.130734 -394.359384)
		(end 292.733984 -394.971524)
		(width 0.1651)
		(layer "In11.Cu")
		(net "P5E_PEX2_STN4_TX_C_DP<77>")
	)
	(segment
		(start 291.117274 -393.331192)
		(end 291.622226 -393.84351)
		(width 0.1651)
		(layer "In11.Cu")
		(net "P5E_PEX2_STN4_TX_C_DP<77>")
	)
	(segment
		(start 290.507928 -393.087606)
		(end 291.117274 -393.331192)
		(width 0.1651)
		(layer "In11.Cu")
		(net "P5E_PEX2_STN4_TX_C_DP<77>")
	)
	(segment
		(start 292.733984 -394.971524)
		(end 292.733984 -396.71244)
		(width 0.1651)
		(layer "In11.Cu")
		(net "P5E_PEX2_STN4_TX_C_DP<77>")
	)
	(segment
		(start 286.62757 -391.535666)
		(end 286.6771 -391.651236)
		(width 0.1651)
		(layer "In11.Cu")
		(net "P5E_PEX2_STN4_TX_C_DP<77>")
	)
	(segment
		(start 288.847276 -392.5189)
		(end 289.307524 -392.70305)
		(width 0.1651)
		(layer "In11.Cu")
		(net "P5E_PEX2_STN4_TX_C_DP<77>")
	)
	(segment
		(start 282.323794 -388.347458)
		(end 284.938724 -390.86028)
		(width 0.1651)
		(layer "In11.Cu")
		(net "P5E_PEX2_STN4_TX_C_DP<77>")
	)
	(segment
		(start 292.447218 -396.999206)
		(end 292.016942 -396.999206)
		(width 0.1651)
		(layer "In11.Cu")
		(net "P5E_PEX2_STN4_TX_C_DP<77>")
	)
	(segment
		(start 287.762188 -392.085068)
		(end 288.222436 -392.269218)
		(width 0.1651)
		(layer "In11.Cu")
		(net "P5E_PEX2_STN4_TX_C_DP<77>")
	)
	(segment
		(start 314.033916 -321.355974)
		(end 314.033916 -319.001648)
		(width 0.1651)
		(layer "In15.Cu")
		(net "P5E_PEX2_STN4_RX_DP<71>")
	)
	(segment
		(start 291.719762 -365.924592)
		(end 291.863018 -365.93653)
		(width 0.1651)
		(layer "In15.Cu")
		(net "P5E_PEX2_STN4_RX_DP<71>")
	)
	(segment
		(start 313.952382 -316.799722)
		(end 313.699906 -316.799722)
		(width 0.1143)
		(layer "In15.Cu")
		(net "P5E_PEX2_STN4_RX_DP<71>")
	)
	(segment
		(start 288.333942 -378.512324)
		(end 288.333942 -369.22964)
		(width 0.1651)
		(layer "In15.Cu")
		(net "P5E_PEX2_STN4_RX_DP<71>")
	)
	(segment
		(start 314.033916 -319.001648)
		(end 314.033916 -318.9732)
		(width 0.1143)
		(layer "In15.Cu")
		(net "P5E_PEX2_STN4_RX_DP<71>")
	)
	(segment
		(start 287.4899 -378.67209)
		(end 287.6169 -378.79909)
		(width 0.1651)
		(layer "In15.Cu")
		(net "P5E_PEX2_STN4_RX_DP<71>")
	)
	(segment
		(start 304.998882 -346.338906)
		(end 304.999136 -346.338144)
		(width 0.1651)
		(layer "In15.Cu")
		(net "P5E_PEX2_STN4_RX_DP<71>")
	)
	(segment
		(start 291.863018 -365.93653)
		(end 292.24097 -365.616744)
		(width 0.1651)
		(layer "In15.Cu")
		(net "P5E_PEX2_STN4_RX_DP<71>")
	)
	(segment
		(start 314.079636 -318.92748)
		(end 314.079636 -316.926976)
		(width 0.1143)
		(layer "In15.Cu")
		(net "P5E_PEX2_STN4_RX_DP<71>")
	)
	(segment
		(start 288.047176 -378.79909)
		(end 288.333942 -378.512324)
		(width 0.1651)
		(layer "In15.Cu")
		(net "P5E_PEX2_STN4_RX_DP<71>")
	)
	(segment
		(start 304.700178 -346.865956)
		(end 304.86858 -346.40012)
		(width 0.1651)
		(layer "In15.Cu")
		(net "P5E_PEX2_STN4_RX_DP<71>")
	)
	(segment
		(start 305.274726 -345.277186)
		(end 305.405028 -345.216226)
		(width 0.1651)
		(layer "In15.Cu")
		(net "P5E_PEX2_STN4_RX_DP<71>")
	)
	(segment
		(start 292.252908 -365.473488)
		(end 292.631114 -365.153194)
		(width 0.1651)
		(layer "In15.Cu")
		(net "P5E_PEX2_STN4_RX_DP<71>")
	)
	(segment
		(start 293.542466 -364.381796)
		(end 293.685722 -364.393734)
		(width 0.1651)
		(layer "In15.Cu")
		(net "P5E_PEX2_STN4_RX_DP<71>")
	)
	(segment
		(start 314.033916 -318.9732)
		(end 314.079636 -318.92748)
		(width 0.1143)
		(layer "In15.Cu")
		(net "P5E_PEX2_STN4_RX_DP<71>")
	)
	(segment
		(start 293.16426 -364.70209)
		(end 293.542466 -364.381796)
		(width 0.1651)
		(layer "In15.Cu")
		(net "P5E_PEX2_STN4_RX_DP<71>")
	)
	(segment
		(start 305.167284 -345.873324)
		(end 305.106324 -345.743276)
		(width 0.1651)
		(layer "In15.Cu")
		(net "P5E_PEX2_STN4_RX_DP<71>")
	)
	(segment
		(start 300.579028 -358.559862)
		(end 304.761138 -346.996258)
		(width 0.1651)
		(layer "In15.Cu")
		(net "P5E_PEX2_STN4_RX_DP<71>")
	)
	(segment
		(start 305.106324 -345.743276)
		(end 305.274726 -345.277186)
		(width 0.1651)
		(layer "In15.Cu")
		(net "P5E_PEX2_STN4_RX_DP<71>")
	)
	(segment
		(start 304.86858 -346.40012)
		(end 304.998882 -346.338906)
		(width 0.1651)
		(layer "In15.Cu")
		(net "P5E_PEX2_STN4_RX_DP<71>")
	)
	(segment
		(start 304.761138 -346.996258)
		(end 304.700178 -346.865956)
		(width 0.1651)
		(layer "In15.Cu")
		(net "P5E_PEX2_STN4_RX_DP<71>")
	)
	(segment
		(start 305.405028 -345.216226)
		(end 305.57343 -344.750644)
		(width 0.1651)
		(layer "In15.Cu")
		(net "P5E_PEX2_STN4_RX_DP<71>")
	)
	(segment
		(start 287.4899 -378.290074)
		(end 287.4899 -378.67209)
		(width 0.1651)
		(layer "In15.Cu")
		(net "P5E_PEX2_STN4_RX_DP<71>")
	)
	(segment
		(start 292.631114 -365.153194)
		(end 292.77437 -365.165132)
		(width 0.1651)
		(layer "In15.Cu")
		(net "P5E_PEX2_STN4_RX_DP<71>")
	)
	(segment
		(start 291.329618 -366.387888)
		(end 291.341556 -366.244632)
		(width 0.1651)
		(layer "In15.Cu")
		(net "P5E_PEX2_STN4_RX_DP<71>")
	)
	(segment
		(start 288.333942 -369.22964)
		(end 288.81451 -368.516408)
		(width 0.1651)
		(layer "In15.Cu")
		(net "P5E_PEX2_STN4_RX_DP<71>")
	)
	(segment
		(start 305.673252 -344.13825)
		(end 305.81981 -344.06967)
		(width 0.1651)
		(layer "In15.Cu")
		(net "P5E_PEX2_STN4_RX_DP<71>")
	)
	(segment
		(start 287.6169 -378.79909)
		(end 288.047176 -378.79909)
		(width 0.1651)
		(layer "In15.Cu")
		(net "P5E_PEX2_STN4_RX_DP<71>")
	)
	(segment
		(start 288.81451 -368.516408)
		(end 291.329618 -366.387888)
		(width 0.1651)
		(layer "In15.Cu")
		(net "P5E_PEX2_STN4_RX_DP<71>")
	)
	(segment
		(start 314.079636 -316.926976)
		(end 313.952382 -316.799722)
		(width 0.1143)
		(layer "In15.Cu")
		(net "P5E_PEX2_STN4_RX_DP<71>")
	)
	(segment
		(start 291.341556 -366.244632)
		(end 291.719762 -365.924592)
		(width 0.1651)
		(layer "In15.Cu")
		(net "P5E_PEX2_STN4_RX_DP<71>")
	)
	(segment
		(start 293.152322 -364.845346)
		(end 293.16426 -364.70209)
		(width 0.1651)
		(layer "In15.Cu")
		(net "P5E_PEX2_STN4_RX_DP<71>")
	)
	(segment
		(start 293.685722 -364.393734)
		(end 300.579028 -358.559862)
		(width 0.1651)
		(layer "In15.Cu")
		(net "P5E_PEX2_STN4_RX_DP<71>")
	)
	(segment
		(start 292.24097 -365.616744)
		(end 292.252908 -365.473488)
		(width 0.1651)
		(layer "In15.Cu")
		(net "P5E_PEX2_STN4_RX_DP<71>")
	)
	(segment
		(start 305.57343 -344.750644)
		(end 305.50485 -344.60434)
		(width 0.1651)
		(layer "In15.Cu")
		(net "P5E_PEX2_STN4_RX_DP<71>")
	)
	(segment
		(start 305.81981 -344.06967)
		(end 305.819302 -344.06967)
		(width 0.1651)
		(layer "In15.Cu")
		(net "P5E_PEX2_STN4_RX_DP<71>")
	)
	(segment
		(start 292.77437 -365.165132)
		(end 293.152322 -364.845346)
		(width 0.1651)
		(layer "In15.Cu")
		(net "P5E_PEX2_STN4_RX_DP<71>")
	)
	(segment
		(start 304.999136 -346.338144)
		(end 305.167284 -345.873324)
		(width 0.1651)
		(layer "In15.Cu")
		(net "P5E_PEX2_STN4_RX_DP<71>")
	)
	(segment
		(start 305.50485 -344.60434)
		(end 305.673252 -344.13825)
		(width 0.1651)
		(layer "In15.Cu")
		(net "P5E_PEX2_STN4_RX_DP<71>")
	)
	(segment
		(start 305.819302 -344.06967)
		(end 314.033916 -321.355974)
		(width 0.1651)
		(layer "In15.Cu")
		(net "P5E_PEX2_STN4_RX_DP<71>")
	)
	(segment
		(start 425.134024 -343.36609)
		(end 425.134024 -342.73363)
		(width 0.13462)
		(layer "F.Cu")
		(net "P5E_PEX3_STN4_TX_DP<72>")
	)
	(segment
		(start 425.134024 -342.73363)
		(end 424.839892 -342.439498)
		(width 0.13462)
		(layer "F.Cu")
		(net "P5E_PEX3_STN4_TX_DP<72>")
	)
	(segment
		(start 424.814492 -343.685622)
		(end 425.134024 -343.36609)
		(width 0.13462)
		(layer "F.Cu")
		(net "P5E_PEX3_STN4_TX_DP<72>")
	)
	(segment
		(start 428.23384 -323.339968)
		(end 428.23384 -319.9384)
		(width 0.1651)
		(layer "In7.Cu")
		(net "P5E_PEX3_STN4_TX_DP<72>")
	)
	(segment
		(start 428.27956 -313.605418)
		(end 428.505366 -313.379612)
		(width 0.1143)
		(layer "In7.Cu")
		(net "P5E_PEX3_STN4_TX_DP<72>")
	)
	(segment
		(start 428.505366 -313.379612)
		(end 428.73549 -313.379612)
		(width 0.1143)
		(layer "In7.Cu")
		(net "P5E_PEX3_STN4_TX_DP<72>")
	)
	(segment
		(start 428.23384 -319.909952)
		(end 428.27956 -319.864232)
		(width 0.1143)
		(layer "In7.Cu")
		(net "P5E_PEX3_STN4_TX_DP<72>")
	)
	(segment
		(start 424.839892 -342.439498)
		(end 425.130722 -342.148668)
		(width 0.1651)
		(layer "In7.Cu")
		(net "P5E_PEX3_STN4_TX_DP<72>")
	)
	(segment
		(start 428.23384 -319.9384)
		(end 428.23384 -319.909952)
		(width 0.1143)
		(layer "In7.Cu")
		(net "P5E_PEX3_STN4_TX_DP<72>")
	)
	(segment
		(start 428.27956 -319.864232)
		(end 428.27956 -313.605418)
		(width 0.1143)
		(layer "In7.Cu")
		(net "P5E_PEX3_STN4_TX_DP<72>")
	)
	(segment
		(start 428.84979 -313.265312)
		(end 428.84979 -312.999882)
		(width 0.1143)
		(layer "In7.Cu")
		(net "P5E_PEX3_STN4_TX_DP<72>")
	)
	(segment
		(start 428.73549 -313.379612)
		(end 428.84979 -313.265312)
		(width 0.1143)
		(layer "In7.Cu")
		(net "P5E_PEX3_STN4_TX_DP<72>")
	)
	(segment
		(start 425.130722 -341.60968)
		(end 428.23384 -323.339968)
		(width 0.1651)
		(layer "In7.Cu")
		(net "P5E_PEX3_STN4_TX_DP<72>")
	)
	(segment
		(start 425.130722 -342.148668)
		(end 425.130722 -341.60968)
		(width 0.1651)
		(layer "In7.Cu")
		(net "P5E_PEX3_STN4_TX_DP<72>")
	)
	(segment
		(start 298.128944 -340.977728)
		(end 298.643802 -340.068662)
		(width 0.1651)
		(layer "In15.Cu")
		(net "P5E_PEX2_STN4_RX_DP<72>")
	)
	(segment
		(start 302.053498 -393.633452)
		(end 301.218854 -392.778742)
		(width 0.1651)
		(layer "In15.Cu")
		(net "P5E_PEX2_STN4_RX_DP<72>")
	)
	(segment
		(start 286.156908 -384.597148)
		(end 285.693358 -372.495572)
		(width 0.1651)
		(layer "In15.Cu")
		(net "P5E_PEX2_STN4_RX_DP<72>")
	)
	(segment
		(start 298.127674 -340.97976)
		(end 298.128944 -340.977728)
		(width 0.1651)
		(layer "In15.Cu")
		(net "P5E_PEX2_STN4_RX_DP<72>")
	)
	(segment
		(start 285.693358 -372.495572)
		(end 286.11322 -369.37188)
		(width 0.1651)
		(layer "In15.Cu")
		(net "P5E_PEX2_STN4_RX_DP<72>")
	)
	(segment
		(start 312.133742 -323.708522)
		(end 312.133742 -319.941448)
		(width 0.1651)
		(layer "In15.Cu")
		(net "P5E_PEX2_STN4_RX_DP<72>")
	)
	(segment
		(start 303.286668 -394.896086)
		(end 302.52416 -394.11529)
		(width 0.1651)
		(layer "In15.Cu")
		(net "P5E_PEX2_STN4_RX_DP<72>")
	)
	(segment
		(start 303.447196 -405.899112)
		(end 303.733962 -405.612346)
		(width 0.1651)
		(layer "In15.Cu")
		(net "P5E_PEX2_STN4_RX_DP<72>")
	)
	(segment
		(start 299.004736 -391.410444)
		(end 288.200846 -386.707634)
		(width 0.1651)
		(layer "In15.Cu")
		(net "P5E_PEX2_STN4_RX_DP<72>")
	)
	(segment
		(start 298.125642 -340.978744)
		(end 298.127674 -340.97976)
		(width 0.1651)
		(layer "In15.Cu")
		(net "P5E_PEX2_STN4_RX_DP<72>")
	)
	(segment
		(start 302.39843 -394.113766)
		(end 302.052228 -393.759182)
		(width 0.1651)
		(layer "In15.Cu")
		(net "P5E_PEX2_STN4_RX_DP<72>")
	)
	(segment
		(start 298.643802 -340.068662)
		(end 311.71261 -324.725792)
		(width 0.1651)
		(layer "In15.Cu")
		(net "P5E_PEX2_STN4_RX_DP<72>")
	)
	(segment
		(start 297.723052 -342.114886)
		(end 298.124372 -340.980776)
		(width 0.1651)
		(layer "In15.Cu")
		(net "P5E_PEX2_STN4_RX_DP<72>")
	)
	(segment
		(start 312.179462 -319.86728)
		(end 312.179462 -318.344804)
		(width 0.1143)
		(layer "In15.Cu")
		(net "P5E_PEX2_STN4_RX_DP<72>")
	)
	(segment
		(start 312.179462 -318.344804)
		(end 312.3946 -318.129666)
		(width 0.1143)
		(layer "In15.Cu")
		(net "P5E_PEX2_STN4_RX_DP<72>")
	)
	(segment
		(start 297.723052 -357.843328)
		(end 297.723052 -342.114886)
		(width 0.1651)
		(layer "In15.Cu")
		(net "P5E_PEX2_STN4_RX_DP<72>")
	)
	(segment
		(start 303.733962 -396.088108)
		(end 303.286668 -394.896086)
		(width 0.1651)
		(layer "In15.Cu")
		(net "P5E_PEX2_STN4_RX_DP<72>")
	)
	(segment
		(start 297.163998 -359.052622)
		(end 297.263312 -358.953308)
		(width 0.1651)
		(layer "In15.Cu")
		(net "P5E_PEX2_STN4_RX_DP<72>")
	)
	(segment
		(start 303.733962 -405.612346)
		(end 303.733962 -396.088108)
		(width 0.1651)
		(layer "In15.Cu")
		(net "P5E_PEX2_STN4_RX_DP<72>")
	)
	(segment
		(start 302.88992 -405.772112)
		(end 303.01692 -405.899112)
		(width 0.1651)
		(layer "In15.Cu")
		(net "P5E_PEX2_STN4_RX_DP<72>")
	)
	(segment
		(start 312.3946 -318.129666)
		(end 312.635392 -318.129666)
		(width 0.1143)
		(layer "In15.Cu")
		(net "P5E_PEX2_STN4_RX_DP<72>")
	)
	(segment
		(start 301.218854 -392.778742)
		(end 299.004736 -391.410444)
		(width 0.1651)
		(layer "In15.Cu")
		(net "P5E_PEX2_STN4_RX_DP<72>")
	)
	(segment
		(start 312.133742 -319.913)
		(end 312.179462 -319.86728)
		(width 0.1143)
		(layer "In15.Cu")
		(net "P5E_PEX2_STN4_RX_DP<72>")
	)
	(segment
		(start 311.71261 -324.725792)
		(end 312.133742 -323.708522)
		(width 0.1651)
		(layer "In15.Cu")
		(net "P5E_PEX2_STN4_RX_DP<72>")
	)
	(segment
		(start 286.634936 -385.58597)
		(end 286.156908 -384.597148)
		(width 0.1651)
		(layer "In15.Cu")
		(net "P5E_PEX2_STN4_RX_DP<72>")
	)
	(segment
		(start 302.052228 -393.759182)
		(end 302.053498 -393.633452)
		(width 0.1651)
		(layer "In15.Cu")
		(net "P5E_PEX2_STN4_RX_DP<72>")
	)
	(segment
		(start 312.133742 -319.941448)
		(end 312.133742 -319.913)
		(width 0.1143)
		(layer "In15.Cu")
		(net "P5E_PEX2_STN4_RX_DP<72>")
	)
	(segment
		(start 288.200846 -386.707634)
		(end 286.634936 -385.58597)
		(width 0.1651)
		(layer "In15.Cu")
		(net "P5E_PEX2_STN4_RX_DP<72>")
	)
	(segment
		(start 302.52416 -394.11529)
		(end 302.39843 -394.113766)
		(width 0.1651)
		(layer "In15.Cu")
		(net "P5E_PEX2_STN4_RX_DP<72>")
	)
	(segment
		(start 298.124372 -340.980776)
		(end 298.125642 -340.978744)
		(width 0.1651)
		(layer "In15.Cu")
		(net "P5E_PEX2_STN4_RX_DP<72>")
	)
	(segment
		(start 302.88992 -405.390096)
		(end 302.88992 -405.772112)
		(width 0.1651)
		(layer "In15.Cu")
		(net "P5E_PEX2_STN4_RX_DP<72>")
	)
	(segment
		(start 297.263312 -358.953308)
		(end 297.723052 -357.843328)
		(width 0.1651)
		(layer "In15.Cu")
		(net "P5E_PEX2_STN4_RX_DP<72>")
	)
	(segment
		(start 286.11322 -369.37188)
		(end 286.724852 -368.371374)
		(width 0.1651)
		(layer "In15.Cu")
		(net "P5E_PEX2_STN4_RX_DP<72>")
	)
	(segment
		(start 303.01692 -405.899112)
		(end 303.447196 -405.899112)
		(width 0.1651)
		(layer "In15.Cu")
		(net "P5E_PEX2_STN4_RX_DP<72>")
	)
	(segment
		(start 312.635392 -318.129666)
		(end 312.749692 -318.015366)
		(width 0.1143)
		(layer "In15.Cu")
		(net "P5E_PEX2_STN4_RX_DP<72>")
	)
	(segment
		(start 312.749692 -318.015366)
		(end 312.749692 -317.749936)
		(width 0.1143)
		(layer "In15.Cu")
		(net "P5E_PEX2_STN4_RX_DP<72>")
	)
	(segment
		(start 286.724852 -368.371374)
		(end 297.163998 -359.052622)
		(width 0.1651)
		(layer "In15.Cu")
		(net "P5E_PEX2_STN4_RX_DP<72>")
	)
	(segment
		(start 293.337742 -356.831646)
		(end 293.337742 -357.46309)
		(width 0.13462)
		(layer "F.Cu")
		(net "P5E_PEX2_STN4_TX_C_DN<67>")
	)
	(segment
		(start 293.657782 -356.511606)
		(end 293.337742 -356.831646)
		(width 0.13462)
		(layer "F.Cu")
		(net "P5E_PEX2_STN4_TX_C_DN<67>")
	)
	(segment
		(start 293.337742 -357.46309)
		(end 293.632382 -357.75773)
		(width 0.13462)
		(layer "F.Cu")
		(net "P5E_PEX2_STN4_TX_C_DN<67>")
	)
	(segment
		(start 296.416984 -371.281198)
		(end 296.289984 -371.408198)
		(width 0.1651)
		(layer "In11.Cu")
		(net "P5E_PEX2_STN4_TX_C_DN<67>")
	)
	(segment
		(start 293.632382 -357.75773)
		(end 293.341552 -358.04856)
		(width 0.1651)
		(layer "In11.Cu")
		(net "P5E_PEX2_STN4_TX_C_DN<67>")
	)
	(segment
		(start 297.415966 -370.829332)
		(end 296.9641 -371.281198)
		(width 0.1651)
		(layer "In11.Cu")
		(net "P5E_PEX2_STN4_TX_C_DN<67>")
	)
	(segment
		(start 296.289984 -371.408198)
		(end 296.289984 -371.790214)
		(width 0.1651)
		(layer "In11.Cu")
		(net "P5E_PEX2_STN4_TX_C_DN<67>")
	)
	(segment
		(start 296.9641 -371.281198)
		(end 296.416984 -371.281198)
		(width 0.1651)
		(layer "In11.Cu")
		(net "P5E_PEX2_STN4_TX_C_DN<67>")
	)
	(segment
		(start 293.341552 -358.04856)
		(end 293.341552 -358.81564)
		(width 0.1651)
		(layer "In11.Cu")
		(net "P5E_PEX2_STN4_TX_C_DN<67>")
	)
	(segment
		(start 293.341552 -358.81564)
		(end 297.415966 -368.74704)
		(width 0.1651)
		(layer "In11.Cu")
		(net "P5E_PEX2_STN4_TX_C_DN<67>")
	)
	(segment
		(start 297.415966 -368.74704)
		(end 297.415966 -370.829332)
		(width 0.1651)
		(layer "In11.Cu")
		(net "P5E_PEX2_STN4_TX_C_DN<67>")
	)
	(segment
		(start 290.548822 -350.365314)
		(end 290.228782 -350.685354)
		(width 0.13462)
		(layer "F.Cu")
		(net "P5E_PEX2_STN4_TX_C_DN<69>")
	)
	(segment
		(start 290.228782 -351.316798)
		(end 290.523422 -351.611438)
		(width 0.13462)
		(layer "F.Cu")
		(net "P5E_PEX2_STN4_TX_C_DN<69>")
	)
	(segment
		(start 290.228782 -350.685354)
		(end 290.228782 -351.316798)
		(width 0.13462)
		(layer "F.Cu")
		(net "P5E_PEX2_STN4_TX_C_DN<69>")
	)
	(segment
		(start 292.016942 -371.281198)
		(end 291.889942 -371.408198)
		(width 0.1651)
		(layer "In11.Cu")
		(net "P5E_PEX2_STN4_TX_C_DN<69>")
	)
	(segment
		(start 293.015924 -370.829332)
		(end 292.564058 -371.281198)
		(width 0.1651)
		(layer "In11.Cu")
		(net "P5E_PEX2_STN4_TX_C_DN<69>")
	)
	(segment
		(start 288.678112 -358.902)
		(end 293.015924 -368.73434)
		(width 0.1651)
		(layer "In11.Cu")
		(net "P5E_PEX2_STN4_TX_C_DN<69>")
	)
	(segment
		(start 290.523422 -351.611438)
		(end 290.232592 -351.902268)
		(width 0.1651)
		(layer "In11.Cu")
		(net "P5E_PEX2_STN4_TX_C_DN<69>")
	)
	(segment
		(start 288.678112 -354.027486)
		(end 288.678112 -358.902)
		(width 0.1651)
		(layer "In11.Cu")
		(net "P5E_PEX2_STN4_TX_C_DN<69>")
	)
	(segment
		(start 291.889942 -371.408198)
		(end 291.889942 -371.790214)
		(width 0.1651)
		(layer "In11.Cu")
		(net "P5E_PEX2_STN4_TX_C_DN<69>")
	)
	(segment
		(start 293.015924 -368.73434)
		(end 293.015924 -370.829332)
		(width 0.1651)
		(layer "In11.Cu")
		(net "P5E_PEX2_STN4_TX_C_DN<69>")
	)
	(segment
		(start 292.564058 -371.281198)
		(end 292.016942 -371.281198)
		(width 0.1651)
		(layer "In11.Cu")
		(net "P5E_PEX2_STN4_TX_C_DN<69>")
	)
	(segment
		(start 290.232592 -352.473006)
		(end 288.678112 -354.027486)
		(width 0.1651)
		(layer "In11.Cu")
		(net "P5E_PEX2_STN4_TX_C_DN<69>")
	)
	(segment
		(start 290.232592 -351.902268)
		(end 290.232592 -352.473006)
		(width 0.1651)
		(layer "In11.Cu")
		(net "P5E_PEX2_STN4_TX_C_DN<69>")
	)
	(segment
		(start 418.916104 -343.36609)
		(end 418.916104 -342.73363)
		(width 0.13462)
		(layer "F.Cu")
		(net "P5E_PEX3_STN4_TX_DP<75>")
	)
	(segment
		(start 418.916104 -342.73363)
		(end 418.621972 -342.439498)
		(width 0.13462)
		(layer "F.Cu")
		(net "P5E_PEX3_STN4_TX_DP<75>")
	)
	(segment
		(start 418.596572 -343.685622)
		(end 418.916104 -343.36609)
		(width 0.13462)
		(layer "F.Cu")
		(net "P5E_PEX3_STN4_TX_DP<75>")
	)
	(segment
		(start 425.655486 -311.479692)
		(end 425.88561 -311.479692)
		(width 0.1143)
		(layer "In7.Cu")
		(net "P5E_PEX3_STN4_TX_DP<75>")
	)
	(segment
		(start 418.912802 -342.148668)
		(end 418.912802 -341.633048)
		(width 0.1651)
		(layer "In7.Cu")
		(net "P5E_PEX3_STN4_TX_DP<75>")
	)
	(segment
		(start 425.42968 -311.705498)
		(end 425.655486 -311.479692)
		(width 0.1143)
		(layer "In7.Cu")
		(net "P5E_PEX3_STN4_TX_DP<75>")
	)
	(segment
		(start 425.42968 -319.864232)
		(end 425.42968 -311.705498)
		(width 0.1143)
		(layer "In7.Cu")
		(net "P5E_PEX3_STN4_TX_DP<75>")
	)
	(segment
		(start 425.38396 -319.9384)
		(end 425.38396 -319.909952)
		(width 0.1143)
		(layer "In7.Cu")
		(net "P5E_PEX3_STN4_TX_DP<75>")
	)
	(segment
		(start 425.38396 -319.909952)
		(end 425.42968 -319.864232)
		(width 0.1143)
		(layer "In7.Cu")
		(net "P5E_PEX3_STN4_TX_DP<75>")
	)
	(segment
		(start 425.99991 -311.365392)
		(end 425.99991 -311.099962)
		(width 0.1143)
		(layer "In7.Cu")
		(net "P5E_PEX3_STN4_TX_DP<75>")
	)
	(segment
		(start 418.621972 -342.439498)
		(end 418.912802 -342.148668)
		(width 0.1651)
		(layer "In7.Cu")
		(net "P5E_PEX3_STN4_TX_DP<75>")
	)
	(segment
		(start 425.127674 -322.810124)
		(end 425.38396 -321.217798)
		(width 0.1651)
		(layer "In7.Cu")
		(net "P5E_PEX3_STN4_TX_DP<75>")
	)
	(segment
		(start 418.912802 -341.633048)
		(end 425.127674 -322.810124)
		(width 0.1651)
		(layer "In7.Cu")
		(net "P5E_PEX3_STN4_TX_DP<75>")
	)
	(segment
		(start 425.88561 -311.479692)
		(end 425.99991 -311.365392)
		(width 0.1143)
		(layer "In7.Cu")
		(net "P5E_PEX3_STN4_TX_DP<75>")
	)
	(segment
		(start 425.38396 -321.217798)
		(end 425.38396 -319.9384)
		(width 0.1651)
		(layer "In7.Cu")
		(net "P5E_PEX3_STN4_TX_DP<75>")
	)
	(segment
		(start 292.743382 -344.219022)
		(end 293.063422 -344.539062)
		(width 0.13462)
		(layer "F.Cu")
		(net "P5E_PEX2_STN4_TX_C_DP<68>")
	)
	(segment
		(start 293.063422 -344.539062)
		(end 293.063422 -345.170506)
		(width 0.13462)
		(layer "F.Cu")
		(net "P5E_PEX2_STN4_TX_C_DP<68>")
	)
	(segment
		(start 293.063422 -345.170506)
		(end 292.768782 -345.465146)
		(width 0.13462)
		(layer "F.Cu")
		(net "P5E_PEX2_STN4_TX_C_DP<68>")
	)
	(segment
		(start 293.604188 -365.324136)
		(end 293.76624 -365.792258)
		(width 0.1651)
		(layer "In11.Cu")
		(net "P5E_PEX2_STN4_TX_C_DP<68>")
	)
	(segment
		(start 293.059612 -346.209874)
		(end 291.505132 -347.764354)
		(width 0.1651)
		(layer "In11.Cu")
		(net "P5E_PEX2_STN4_TX_C_DP<68>")
	)
	(segment
		(start 293.513002 -364.710726)
		(end 293.6748 -365.178594)
		(width 0.1651)
		(layer "In11.Cu")
		(net "P5E_PEX2_STN4_TX_C_DP<68>")
	)
	(segment
		(start 293.911782 -365.863124)
		(end 294.07358 -366.330992)
		(width 0.1651)
		(layer "In11.Cu")
		(net "P5E_PEX2_STN4_TX_C_DP<68>")
	)
	(segment
		(start 293.76624 -365.792258)
		(end 293.911782 -365.863124)
		(width 0.1651)
		(layer "In11.Cu")
		(net "P5E_PEX2_STN4_TX_C_DP<68>")
	)
	(segment
		(start 294.310562 -367.015522)
		(end 294.47236 -367.48339)
		(width 0.1651)
		(layer "In11.Cu")
		(net "P5E_PEX2_STN4_TX_C_DP<68>")
	)
	(segment
		(start 293.205408 -364.171738)
		(end 293.36746 -364.63986)
		(width 0.1651)
		(layer "In11.Cu")
		(net "P5E_PEX2_STN4_TX_C_DP<68>")
	)
	(segment
		(start 292.768782 -345.465146)
		(end 293.059612 -345.755976)
		(width 0.1651)
		(layer "In11.Cu")
		(net "P5E_PEX2_STN4_TX_C_DP<68>")
	)
	(segment
		(start 292.478714 -361.7214)
		(end 292.407848 -361.866688)
		(width 0.1651)
		(layer "In11.Cu")
		(net "P5E_PEX2_STN4_TX_C_DP<68>")
	)
	(segment
		(start 294.933878 -368.817398)
		(end 294.933878 -371.812312)
		(width 0.1651)
		(layer "In11.Cu")
		(net "P5E_PEX2_STN4_TX_C_DP<68>")
	)
	(segment
		(start 294.563546 -368.097054)
		(end 294.709342 -368.16792)
		(width 0.1651)
		(layer "In11.Cu")
		(net "P5E_PEX2_STN4_TX_C_DP<68>")
	)
	(segment
		(start 294.933878 -371.812312)
		(end 294.647112 -372.099078)
		(width 0.1651)
		(layer "In11.Cu")
		(net "P5E_PEX2_STN4_TX_C_DP<68>")
	)
	(segment
		(start 292.87724 -362.873798)
		(end 292.806628 -363.01934)
		(width 0.1651)
		(layer "In11.Cu")
		(net "P5E_PEX2_STN4_TX_C_DP<68>")
	)
	(segment
		(start 293.059612 -345.755976)
		(end 293.059612 -346.209874)
		(width 0.1651)
		(layer "In11.Cu")
		(net "P5E_PEX2_STN4_TX_C_DP<68>")
	)
	(segment
		(start 293.114222 -363.558328)
		(end 293.27602 -364.026196)
		(width 0.1651)
		(layer "In11.Cu")
		(net "P5E_PEX2_STN4_TX_C_DP<68>")
	)
	(segment
		(start 293.27602 -364.026196)
		(end 293.205408 -364.171738)
		(width 0.1651)
		(layer "In11.Cu")
		(net "P5E_PEX2_STN4_TX_C_DP<68>")
	)
	(segment
		(start 294.47236 -367.48339)
		(end 294.401748 -367.628932)
		(width 0.1651)
		(layer "In11.Cu")
		(net "P5E_PEX2_STN4_TX_C_DP<68>")
	)
	(segment
		(start 294.401748 -367.628932)
		(end 294.563546 -368.097054)
		(width 0.1651)
		(layer "In11.Cu")
		(net "P5E_PEX2_STN4_TX_C_DP<68>")
	)
	(segment
		(start 294.002968 -366.476534)
		(end 294.16502 -366.94491)
		(width 0.1651)
		(layer "In11.Cu")
		(net "P5E_PEX2_STN4_TX_C_DP<68>")
	)
	(segment
		(start 294.07358 -366.330992)
		(end 294.002968 -366.476534)
		(width 0.1651)
		(layer "In11.Cu")
		(net "P5E_PEX2_STN4_TX_C_DP<68>")
	)
	(segment
		(start 291.505132 -347.764354)
		(end 291.505132 -358.906318)
		(width 0.1651)
		(layer "In11.Cu")
		(net "P5E_PEX2_STN4_TX_C_DP<68>")
	)
	(segment
		(start 292.407848 -361.866688)
		(end 292.5699 -362.335064)
		(width 0.1651)
		(layer "In11.Cu")
		(net "P5E_PEX2_STN4_TX_C_DP<68>")
	)
	(segment
		(start 291.505132 -358.906318)
		(end 292.478714 -361.7214)
		(width 0.1651)
		(layer "In11.Cu")
		(net "P5E_PEX2_STN4_TX_C_DP<68>")
	)
	(segment
		(start 294.16502 -366.94491)
		(end 294.310562 -367.015522)
		(width 0.1651)
		(layer "In11.Cu")
		(net "P5E_PEX2_STN4_TX_C_DP<68>")
	)
	(segment
		(start 294.216836 -372.099078)
		(end 294.089836 -371.972078)
		(width 0.1651)
		(layer "In11.Cu")
		(net "P5E_PEX2_STN4_TX_C_DP<68>")
	)
	(segment
		(start 294.647112 -372.099078)
		(end 294.216836 -372.099078)
		(width 0.1651)
		(layer "In11.Cu")
		(net "P5E_PEX2_STN4_TX_C_DP<68>")
	)
	(segment
		(start 292.806628 -363.01934)
		(end 292.96868 -363.487462)
		(width 0.1651)
		(layer "In11.Cu")
		(net "P5E_PEX2_STN4_TX_C_DP<68>")
	)
	(segment
		(start 294.709342 -368.16792)
		(end 294.933878 -368.817398)
		(width 0.1651)
		(layer "In11.Cu")
		(net "P5E_PEX2_STN4_TX_C_DP<68>")
	)
	(segment
		(start 293.36746 -364.63986)
		(end 293.513002 -364.710726)
		(width 0.1651)
		(layer "In11.Cu")
		(net "P5E_PEX2_STN4_TX_C_DP<68>")
	)
	(segment
		(start 292.715442 -362.40593)
		(end 292.87724 -362.873798)
		(width 0.1651)
		(layer "In11.Cu")
		(net "P5E_PEX2_STN4_TX_C_DP<68>")
	)
	(segment
		(start 292.96868 -363.487462)
		(end 293.114222 -363.558328)
		(width 0.1651)
		(layer "In11.Cu")
		(net "P5E_PEX2_STN4_TX_C_DP<68>")
	)
	(segment
		(start 293.6748 -365.178594)
		(end 293.604188 -365.324136)
		(width 0.1651)
		(layer "In11.Cu")
		(net "P5E_PEX2_STN4_TX_C_DP<68>")
	)
	(segment
		(start 294.089836 -371.972078)
		(end 294.089836 -371.590062)
		(width 0.1651)
		(layer "In11.Cu")
		(net "P5E_PEX2_STN4_TX_C_DP<68>")
	)
	(segment
		(start 292.5699 -362.335064)
		(end 292.715442 -362.40593)
		(width 0.1651)
		(layer "In11.Cu")
		(net "P5E_PEX2_STN4_TX_C_DP<68>")
	)
	(segment
		(start 317.457074 -351.920556)
		(end 317.457074 -342.081866)
		(width 0.1651)
		(layer "In15.Cu")
		(net "P5E_PEX2_STN4_RX_DP<65>")
	)
	(segment
		(start 319.689988 -338.285328)
		(end 319.660778 -338.126578)
		(width 0.1651)
		(layer "In15.Cu")
		(net "P5E_PEX2_STN4_RX_DP<65>")
	)
	(segment
		(start 318.969136 -339.130894)
		(end 319.250314 -338.722462)
		(width 0.1651)
		(layer "In15.Cu")
		(net "P5E_PEX2_STN4_RX_DP<65>")
	)
	(segment
		(start 304.795428 -364.814104)
		(end 305.12512 -364.444788)
		(width 0.1651)
		(layer "In15.Cu")
		(net "P5E_PEX2_STN4_RX_DP<65>")
	)
	(segment
		(start 319.250314 -338.722462)
		(end 319.409318 -338.693252)
		(width 0.1651)
		(layer "In15.Cu")
		(net "P5E_PEX2_STN4_RX_DP<65>")
	)
	(segment
		(start 320.38163 -337.281012)
		(end 320.35242 -337.122262)
		(width 0.1651)
		(layer "In15.Cu")
		(net "P5E_PEX2_STN4_RX_DP<65>")
	)
	(segment
		(start 303.501044 -366.263936)
		(end 303.4919 -366.102646)
		(width 0.1651)
		(layer "In15.Cu")
		(net "P5E_PEX2_STN4_RX_DP<65>")
	)
	(segment
		(start 300.689772 -378.67209)
		(end 300.816772 -378.79909)
		(width 0.1651)
		(layer "In15.Cu")
		(net "P5E_PEX2_STN4_RX_DP<65>")
	)
	(segment
		(start 317.697104 -341.179912)
		(end 318.9986 -339.289644)
		(width 0.1651)
		(layer "In15.Cu")
		(net "P5E_PEX2_STN4_RX_DP<65>")
	)
	(segment
		(start 329.692 -322.862448)
		(end 329.692 -318.573404)
		(width 0.1651)
		(layer "In15.Cu")
		(net "P5E_PEX2_STN4_RX_DP<65>")
	)
	(segment
		(start 320.10096 -337.688936)
		(end 320.38163 -337.281012)
		(width 0.1651)
		(layer "In15.Cu")
		(net "P5E_PEX2_STN4_RX_DP<65>")
	)
	(segment
		(start 319.660778 -338.126578)
		(end 319.941956 -337.718146)
		(width 0.1651)
		(layer "In15.Cu")
		(net "P5E_PEX2_STN4_RX_DP<65>")
	)
	(segment
		(start 325.55942 -311.53862)
		(end 321.83578 -307.815234)
		(width 0.1651)
		(layer "In15.Cu")
		(net "P5E_PEX2_STN4_RX_DP<65>")
	)
	(segment
		(start 328.760328 -325.111618)
		(end 329.692 -322.862448)
		(width 0.1651)
		(layer "In15.Cu")
		(net "P5E_PEX2_STN4_RX_DP<65>")
	)
	(segment
		(start 319.409318 -338.693252)
		(end 319.689988 -338.285328)
		(width 0.1651)
		(layer "In15.Cu")
		(net "P5E_PEX2_STN4_RX_DP<65>")
	)
	(segment
		(start 325.256144 -330.20127)
		(end 325.22668 -330.042266)
		(width 0.1651)
		(layer "In15.Cu")
		(net "P5E_PEX2_STN4_RX_DP<65>")
	)
	(segment
		(start 319.941956 -337.718146)
		(end 320.10096 -337.688936)
		(width 0.1651)
		(layer "In15.Cu")
		(net "P5E_PEX2_STN4_RX_DP<65>")
	)
	(segment
		(start 312.3946 -305.970178)
		(end 312.179462 -305.75504)
		(width 0.1143)
		(layer "In15.Cu")
		(net "P5E_PEX2_STN4_RX_DP<65>")
	)
	(segment
		(start 329.692 -318.573404)
		(end 328.765662 -316.337442)
		(width 0.1651)
		(layer "In15.Cu")
		(net "P5E_PEX2_STN4_RX_DP<65>")
	)
	(segment
		(start 304.313082 -365.354362)
		(end 304.303938 -365.193072)
		(width 0.1651)
		(layer "In15.Cu")
		(net "P5E_PEX2_STN4_RX_DP<65>")
	)
	(segment
		(start 320.792348 -336.68462)
		(end 325.256144 -330.20127)
		(width 0.1651)
		(layer "In15.Cu")
		(net "P5E_PEX2_STN4_RX_DP<65>")
	)
	(segment
		(start 305.12512 -364.444788)
		(end 305.115976 -364.283498)
		(width 0.1651)
		(layer "In15.Cu")
		(net "P5E_PEX2_STN4_RX_DP<65>")
	)
	(segment
		(start 318.9986 -339.289644)
		(end 318.969136 -339.130894)
		(width 0.1651)
		(layer "In15.Cu")
		(net "P5E_PEX2_STN4_RX_DP<65>")
	)
	(segment
		(start 303.821846 -365.732822)
		(end 303.98339 -365.723678)
		(width 0.1651)
		(layer "In15.Cu")
		(net "P5E_PEX2_STN4_RX_DP<65>")
	)
	(segment
		(start 312.179462 -305.514248)
		(end 312.065162 -305.399948)
		(width 0.1143)
		(layer "In15.Cu")
		(net "P5E_PEX2_STN4_RX_DP<65>")
	)
	(segment
		(start 317.298324 -352.304096)
		(end 317.457074 -351.920556)
		(width 0.1651)
		(layer "In15.Cu")
		(net "P5E_PEX2_STN4_RX_DP<65>")
	)
	(segment
		(start 325.22668 -330.042266)
		(end 325.507858 -329.634088)
		(width 0.1651)
		(layer "In15.Cu")
		(net "P5E_PEX2_STN4_RX_DP<65>")
	)
	(segment
		(start 301.533814 -369.290092)
		(end 302.065182 -367.87201)
		(width 0.1651)
		(layer "In15.Cu")
		(net "P5E_PEX2_STN4_RX_DP<65>")
	)
	(segment
		(start 305.115976 -364.283498)
		(end 305.446176 -363.913674)
		(width 0.1651)
		(layer "In15.Cu")
		(net "P5E_PEX2_STN4_RX_DP<65>")
	)
	(segment
		(start 305.607466 -363.90453)
		(end 314.82284 -353.583748)
		(width 0.1651)
		(layer "In15.Cu")
		(net "P5E_PEX2_STN4_RX_DP<65>")
	)
	(segment
		(start 320.35242 -337.122262)
		(end 320.633598 -336.71383)
		(width 0.1651)
		(layer "In15.Cu")
		(net "P5E_PEX2_STN4_RX_DP<65>")
	)
	(segment
		(start 300.689772 -378.290074)
		(end 300.689772 -378.67209)
		(width 0.1651)
		(layer "In15.Cu")
		(net "P5E_PEX2_STN4_RX_DP<65>")
	)
	(segment
		(start 317.457074 -342.081866)
		(end 317.697104 -341.179912)
		(width 0.1651)
		(layer "In15.Cu")
		(net "P5E_PEX2_STN4_RX_DP<65>")
	)
	(segment
		(start 315.852048 -306.015898)
		(end 315.8236 -306.015898)
		(width 0.1143)
		(layer "In15.Cu")
		(net "P5E_PEX2_STN4_RX_DP<65>")
	)
	(segment
		(start 303.4919 -366.102646)
		(end 303.821846 -365.732822)
		(width 0.1651)
		(layer "In15.Cu")
		(net "P5E_PEX2_STN4_RX_DP<65>")
	)
	(segment
		(start 325.507858 -329.634088)
		(end 325.666862 -329.604624)
		(width 0.1651)
		(layer "In15.Cu")
		(net "P5E_PEX2_STN4_RX_DP<65>")
	)
	(segment
		(start 305.446176 -363.913674)
		(end 305.607466 -363.90453)
		(width 0.1651)
		(layer "In15.Cu")
		(net "P5E_PEX2_STN4_RX_DP<65>")
	)
	(segment
		(start 318.469518 -306.015898)
		(end 315.852048 -306.015898)
		(width 0.1651)
		(layer "In15.Cu")
		(net "P5E_PEX2_STN4_RX_DP<65>")
	)
	(segment
		(start 317.043054 -352.559112)
		(end 317.298324 -352.304096)
		(width 0.1651)
		(layer "In15.Cu")
		(net "P5E_PEX2_STN4_RX_DP<65>")
	)
	(segment
		(start 304.634138 -364.823248)
		(end 304.795428 -364.814104)
		(width 0.1651)
		(layer "In15.Cu")
		(net "P5E_PEX2_STN4_RX_DP<65>")
	)
	(segment
		(start 315.8236 -306.015898)
		(end 315.77788 -305.970178)
		(width 0.1143)
		(layer "In15.Cu")
		(net "P5E_PEX2_STN4_RX_DP<65>")
	)
	(segment
		(start 301.247048 -378.79909)
		(end 301.533814 -378.512324)
		(width 0.1651)
		(layer "In15.Cu")
		(net "P5E_PEX2_STN4_RX_DP<65>")
	)
	(segment
		(start 328.765662 -316.337442)
		(end 325.55942 -311.53862)
		(width 0.1651)
		(layer "In15.Cu")
		(net "P5E_PEX2_STN4_RX_DP<65>")
	)
	(segment
		(start 301.533814 -378.512324)
		(end 301.533814 -369.290092)
		(width 0.1651)
		(layer "In15.Cu")
		(net "P5E_PEX2_STN4_RX_DP<65>")
	)
	(segment
		(start 312.179462 -305.75504)
		(end 312.179462 -305.514248)
		(width 0.1143)
		(layer "In15.Cu")
		(net "P5E_PEX2_STN4_RX_DP<65>")
	)
	(segment
		(start 304.303938 -365.193072)
		(end 304.634138 -364.823248)
		(width 0.1651)
		(layer "In15.Cu")
		(net "P5E_PEX2_STN4_RX_DP<65>")
	)
	(segment
		(start 314.82284 -353.583748)
		(end 315.205364 -353.318826)
		(width 0.1651)
		(layer "In15.Cu")
		(net "P5E_PEX2_STN4_RX_DP<65>")
	)
	(segment
		(start 325.666862 -329.604624)
		(end 328.760328 -325.111618)
		(width 0.1651)
		(layer "In15.Cu")
		(net "P5E_PEX2_STN4_RX_DP<65>")
	)
	(segment
		(start 315.205364 -353.318826)
		(end 317.043054 -352.559112)
		(width 0.1651)
		(layer "In15.Cu")
		(net "P5E_PEX2_STN4_RX_DP<65>")
	)
	(segment
		(start 303.98339 -365.723678)
		(end 304.313082 -365.354362)
		(width 0.1651)
		(layer "In15.Cu")
		(net "P5E_PEX2_STN4_RX_DP<65>")
	)
	(segment
		(start 321.83578 -307.815234)
		(end 318.469518 -306.015898)
		(width 0.1651)
		(layer "In15.Cu")
		(net "P5E_PEX2_STN4_RX_DP<65>")
	)
	(segment
		(start 312.065162 -305.399948)
		(end 311.799732 -305.399948)
		(width 0.1143)
		(layer "In15.Cu")
		(net "P5E_PEX2_STN4_RX_DP<65>")
	)
	(segment
		(start 300.816772 -378.79909)
		(end 301.247048 -378.79909)
		(width 0.1651)
		(layer "In15.Cu")
		(net "P5E_PEX2_STN4_RX_DP<65>")
	)
	(segment
		(start 315.77788 -305.970178)
		(end 312.3946 -305.970178)
		(width 0.1143)
		(layer "In15.Cu")
		(net "P5E_PEX2_STN4_RX_DP<65>")
	)
	(segment
		(start 320.633598 -336.71383)
		(end 320.792348 -336.68462)
		(width 0.1651)
		(layer "In15.Cu")
		(net "P5E_PEX2_STN4_RX_DP<65>")
	)
	(segment
		(start 302.065182 -367.87201)
		(end 303.501044 -366.263936)
		(width 0.1651)
		(layer "In15.Cu")
		(net "P5E_PEX2_STN4_RX_DP<65>")
	)
	(segment
		(start 440.953144 -349.511366)
		(end 440.953144 -348.880938)
		(width 0.13462)
		(layer "F.Cu")
		(net "P5E_PEX3_STN4_TX_DN<64>")
	)
	(segment
		(start 441.273692 -349.831914)
		(end 440.953144 -349.511366)
		(width 0.13462)
		(layer "F.Cu")
		(net "P5E_PEX3_STN4_TX_DN<64>")
	)
	(segment
		(start 440.953144 -348.880938)
		(end 441.248292 -348.58579)
		(width 0.13462)
		(layer "F.Cu")
		(net "P5E_PEX3_STN4_TX_DN<64>")
	)
	(segment
		(start 441.248292 -348.58579)
		(end 440.957462 -348.29496)
		(width 0.1651)
		(layer "In7.Cu")
		(net "P5E_PEX3_STN4_TX_DN<64>")
	)
	(segment
		(start 440.957462 -348.29496)
		(end 440.957462 -347.784674)
		(width 0.1651)
		(layer "In7.Cu")
		(net "P5E_PEX3_STN4_TX_DN<64>")
	)
	(segment
		(start 447.414396 -321.292474)
		(end 446.853056 -317.338964)
		(width 0.1651)
		(layer "In7.Cu")
		(net "P5E_PEX3_STN4_TX_DN<64>")
	)
	(segment
		(start 442.490098 -346.252292)
		(end 447.421254 -321.339972)
		(width 0.1651)
		(layer "In7.Cu")
		(net "P5E_PEX3_STN4_TX_DN<64>")
	)
	(segment
		(start 423.72026 -304.564034)
		(end 423.83456 -304.449734)
		(width 0.1143)
		(layer "In7.Cu")
		(net "P5E_PEX3_STN4_TX_DN<64>")
	)
	(segment
		(start 431.9778 -304.783744)
		(end 431.93208 -304.829464)
		(width 0.1143)
		(layer "In7.Cu")
		(net "P5E_PEX3_STN4_TX_DN<64>")
	)
	(segment
		(start 433.225194 -304.783744)
		(end 432.006248 -304.783744)
		(width 0.1651)
		(layer "In7.Cu")
		(net "P5E_PEX3_STN4_TX_DN<64>")
	)
	(segment
		(start 423.72026 -304.715164)
		(end 423.72026 -304.564034)
		(width 0.1143)
		(layer "In7.Cu")
		(net "P5E_PEX3_STN4_TX_DN<64>")
	)
	(segment
		(start 423.83456 -304.829464)
		(end 423.72026 -304.715164)
		(width 0.1143)
		(layer "In7.Cu")
		(net "P5E_PEX3_STN4_TX_DN<64>")
	)
	(segment
		(start 445.46139 -315.253116)
		(end 442.212984 -311.641744)
		(width 0.1651)
		(layer "In7.Cu")
		(net "P5E_PEX3_STN4_TX_DN<64>")
	)
	(segment
		(start 423.83456 -304.449734)
		(end 424.09999 -304.449734)
		(width 0.1143)
		(layer "In7.Cu")
		(net "P5E_PEX3_STN4_TX_DN<64>")
	)
	(segment
		(start 440.957462 -347.784674)
		(end 442.490098 -346.252292)
		(width 0.1651)
		(layer "In7.Cu")
		(net "P5E_PEX3_STN4_TX_DN<64>")
	)
	(segment
		(start 432.006248 -304.783744)
		(end 431.9778 -304.783744)
		(width 0.1143)
		(layer "In7.Cu")
		(net "P5E_PEX3_STN4_TX_DN<64>")
	)
	(segment
		(start 431.93208 -304.829464)
		(end 423.83456 -304.829464)
		(width 0.1143)
		(layer "In7.Cu")
		(net "P5E_PEX3_STN4_TX_DN<64>")
	)
	(segment
		(start 446.853056 -317.338964)
		(end 445.46139 -315.253116)
		(width 0.1651)
		(layer "In7.Cu")
		(net "P5E_PEX3_STN4_TX_DN<64>")
	)
	(segment
		(start 447.421254 -321.339972)
		(end 447.414396 -321.292474)
		(width 0.1651)
		(layer "In7.Cu")
		(net "P5E_PEX3_STN4_TX_DN<64>")
	)
	(segment
		(start 442.212984 -311.641744)
		(end 436.861204 -306.289964)
		(width 0.1651)
		(layer "In7.Cu")
		(net "P5E_PEX3_STN4_TX_DN<64>")
	)
	(segment
		(start 436.861204 -306.289964)
		(end 433.225194 -304.783744)
		(width 0.1651)
		(layer "In7.Cu")
		(net "P5E_PEX3_STN4_TX_DN<64>")
	)
	(segment
		(start 293.015924 -378.629164)
		(end 293.015924 -369.9256)
		(width 0.1651)
		(layer "In15.Cu")
		(net "P5E_PEX2_STN4_RX_DN<69>")
	)
	(segment
		(start 312.369962 -309.314088)
		(end 312.484262 -309.199788)
		(width 0.1143)
		(layer "In15.Cu")
		(net "P5E_PEX2_STN4_RX_DN<69>")
	)
	(segment
		(start 317.359538 -310.247538)
		(end 316.645798 -309.533798)
		(width 0.1651)
		(layer "In15.Cu")
		(net "P5E_PEX2_STN4_RX_DN<69>")
	)
	(segment
		(start 302.682148 -359.800652)
		(end 316.156594 -322.914518)
		(width 0.1651)
		(layer "In15.Cu")
		(net "P5E_PEX2_STN4_RX_DN<69>")
	)
	(segment
		(start 293.360348 -368.868198)
		(end 297.49242 -364.848902)
		(width 0.1651)
		(layer "In15.Cu")
		(net "P5E_PEX2_STN4_RX_DN<69>")
	)
	(segment
		(start 292.564058 -379.08103)
		(end 293.015924 -378.629164)
		(width 0.1651)
		(layer "In15.Cu")
		(net "P5E_PEX2_STN4_RX_DN<69>")
	)
	(segment
		(start 317.70574 -311.083452)
		(end 317.359538 -310.247538)
		(width 0.1651)
		(layer "In15.Cu")
		(net "P5E_PEX2_STN4_RX_DN<69>")
	)
	(segment
		(start 293.015924 -369.9256)
		(end 293.360348 -368.868198)
		(width 0.1651)
		(layer "In15.Cu")
		(net "P5E_PEX2_STN4_RX_DN<69>")
	)
	(segment
		(start 312.369962 -309.475886)
		(end 312.369962 -309.314088)
		(width 0.1143)
		(layer "In15.Cu")
		(net "P5E_PEX2_STN4_RX_DN<69>")
	)
	(segment
		(start 291.889942 -379.590046)
		(end 291.889942 -379.20803)
		(width 0.1651)
		(layer "In15.Cu")
		(net "P5E_PEX2_STN4_RX_DN<69>")
	)
	(segment
		(start 315.8236 -309.533798)
		(end 315.77788 -309.579518)
		(width 0.1143)
		(layer "In15.Cu")
		(net "P5E_PEX2_STN4_RX_DN<69>")
	)
	(segment
		(start 312.484262 -309.199788)
		(end 312.749692 -309.199788)
		(width 0.1143)
		(layer "In15.Cu")
		(net "P5E_PEX2_STN4_RX_DN<69>")
	)
	(segment
		(start 312.473594 -309.579518)
		(end 312.369962 -309.475886)
		(width 0.1143)
		(layer "In15.Cu")
		(net "P5E_PEX2_STN4_RX_DN<69>")
	)
	(segment
		(start 316.156594 -322.914518)
		(end 317.70574 -317.109856)
		(width 0.1651)
		(layer "In15.Cu")
		(net "P5E_PEX2_STN4_RX_DN<69>")
	)
	(segment
		(start 315.852048 -309.533798)
		(end 315.8236 -309.533798)
		(width 0.1143)
		(layer "In15.Cu")
		(net "P5E_PEX2_STN4_RX_DN<69>")
	)
	(segment
		(start 316.645798 -309.533798)
		(end 315.852048 -309.533798)
		(width 0.1651)
		(layer "In15.Cu")
		(net "P5E_PEX2_STN4_RX_DN<69>")
	)
	(segment
		(start 315.77788 -309.579518)
		(end 312.473594 -309.579518)
		(width 0.1143)
		(layer "In15.Cu")
		(net "P5E_PEX2_STN4_RX_DN<69>")
	)
	(segment
		(start 297.492166 -364.848902)
		(end 302.682148 -359.800652)
		(width 0.1651)
		(layer "In15.Cu")
		(net "P5E_PEX2_STN4_RX_DN<69>")
	)
	(segment
		(start 297.49242 -364.848902)
		(end 297.492166 -364.848902)
		(width 0.1651)
		(layer "In15.Cu")
		(net "P5E_PEX2_STN4_RX_DN<69>")
	)
	(segment
		(start 317.70574 -317.109856)
		(end 317.70574 -311.083452)
		(width 0.1651)
		(layer "In15.Cu")
		(net "P5E_PEX2_STN4_RX_DN<69>")
	)
	(segment
		(start 291.889942 -379.20803)
		(end 292.016942 -379.08103)
		(width 0.1651)
		(layer "In15.Cu")
		(net "P5E_PEX2_STN4_RX_DN<69>")
	)
	(segment
		(start 292.016942 -379.08103)
		(end 292.564058 -379.08103)
		(width 0.1651)
		(layer "In15.Cu")
		(net "P5E_PEX2_STN4_RX_DN<69>")
	)
	(segment
		(start 422.299384 -349.511366)
		(end 422.299384 -348.880938)
		(width 0.13462)
		(layer "F.Cu")
		(net "P5E_PEX3_STN4_TX_DN<73>")
	)
	(segment
		(start 422.619932 -349.831914)
		(end 422.299384 -349.511366)
		(width 0.13462)
		(layer "F.Cu")
		(net "P5E_PEX3_STN4_TX_DN<73>")
	)
	(segment
		(start 422.299384 -348.880938)
		(end 422.594532 -348.58579)
		(width 0.13462)
		(layer "F.Cu")
		(net "P5E_PEX3_STN4_TX_DN<73>")
	)
	(segment
		(start 427.78553 -311.670192)
		(end 427.89983 -311.784492)
		(width 0.1143)
		(layer "In7.Cu")
		(net "P5E_PEX3_STN4_TX_DN<73>")
	)
	(segment
		(start 422.303702 -348.29496)
		(end 422.303702 -347.784674)
		(width 0.1651)
		(layer "In7.Cu")
		(net "P5E_PEX3_STN4_TX_DN<73>")
	)
	(segment
		(start 427.5201 -311.784492)
		(end 427.6344 -311.670192)
		(width 0.1143)
		(layer "In7.Cu")
		(net "P5E_PEX3_STN4_TX_DN<73>")
	)
	(segment
		(start 427.56582 -319.909952)
		(end 427.5201 -319.864232)
		(width 0.1143)
		(layer "In7.Cu")
		(net "P5E_PEX3_STN4_TX_DN<73>")
	)
	(segment
		(start 427.56582 -322.985384)
		(end 427.56582 -319.9384)
		(width 0.1651)
		(layer "In7.Cu")
		(net "P5E_PEX3_STN4_TX_DN<73>")
	)
	(segment
		(start 422.594532 -348.58579)
		(end 422.303702 -348.29496)
		(width 0.1651)
		(layer "In7.Cu")
		(net "P5E_PEX3_STN4_TX_DN<73>")
	)
	(segment
		(start 422.303702 -347.784674)
		(end 423.858182 -346.230194)
		(width 0.1651)
		(layer "In7.Cu")
		(net "P5E_PEX3_STN4_TX_DN<73>")
	)
	(segment
		(start 427.89983 -311.784492)
		(end 427.89983 -312.049922)
		(width 0.1143)
		(layer "In7.Cu")
		(net "P5E_PEX3_STN4_TX_DN<73>")
	)
	(segment
		(start 423.858182 -341.728806)
		(end 427.56582 -322.985384)
		(width 0.1651)
		(layer "In7.Cu")
		(net "P5E_PEX3_STN4_TX_DN<73>")
	)
	(segment
		(start 427.6344 -311.670192)
		(end 427.78553 -311.670192)
		(width 0.1143)
		(layer "In7.Cu")
		(net "P5E_PEX3_STN4_TX_DN<73>")
	)
	(segment
		(start 427.56582 -319.9384)
		(end 427.56582 -319.909952)
		(width 0.1143)
		(layer "In7.Cu")
		(net "P5E_PEX3_STN4_TX_DN<73>")
	)
	(segment
		(start 423.858182 -346.230194)
		(end 423.858182 -341.728806)
		(width 0.1651)
		(layer "In7.Cu")
		(net "P5E_PEX3_STN4_TX_DN<73>")
	)
	(segment
		(start 427.5201 -319.864232)
		(end 427.5201 -311.784492)
		(width 0.1143)
		(layer "In7.Cu")
		(net "P5E_PEX3_STN4_TX_DN<73>")
	)
	(segment
		(start 321.917822 -338.913724)
		(end 322.16217 -338.482432)
		(width 0.1651)
		(layer "In15.Cu")
		(net "P5E_PEX2_STN4_RX_DP<64>")
	)
	(segment
		(start 322.317872 -338.439252)
		(end 329.8317 -325.16445)
		(width 0.1651)
		(layer "In15.Cu")
		(net "P5E_PEX2_STN4_RX_DP<64>")
	)
	(segment
		(start 322.16217 -338.482432)
		(end 322.317872 -338.439252)
		(width 0.1651)
		(layer "In15.Cu")
		(net "P5E_PEX2_STN4_RX_DP<64>")
	)
	(segment
		(start 320.566034 -354.882704)
		(end 320.566034 -342.192356)
		(width 0.1651)
		(layer "In15.Cu")
		(net "P5E_PEX2_STN4_RX_DP<64>")
	)
	(segment
		(start 320.709036 -341.281512)
		(end 321.360292 -340.130892)
		(width 0.1651)
		(layer "In15.Cu")
		(net "P5E_PEX2_STN4_RX_DP<64>")
	)
	(segment
		(start 306.617624 -365.168434)
		(end 306.7431 -365.165386)
		(width 0.1651)
		(layer "In15.Cu")
		(net "P5E_PEX2_STN4_RX_DP<64>")
	)
	(segment
		(start 307.081174 -364.681008)
		(end 307.422804 -364.321852)
		(width 0.1651)
		(layer "In15.Cu")
		(net "P5E_PEX2_STN4_RX_DP<64>")
	)
	(segment
		(start 303.01692 -379.899164)
		(end 303.447196 -379.899164)
		(width 0.1651)
		(layer "In15.Cu")
		(net "P5E_PEX2_STN4_RX_DP<64>")
	)
	(segment
		(start 330.6572 -323.171566)
		(end 330.6572 -318.374522)
		(width 0.1651)
		(layer "In15.Cu")
		(net "P5E_PEX2_STN4_RX_DP<64>")
	)
	(segment
		(start 315.772292 -356.15626)
		(end 319.094866 -356.15626)
		(width 0.1651)
		(layer "In15.Cu")
		(net "P5E_PEX2_STN4_RX_DP<64>")
	)
	(segment
		(start 321.56146 -339.543644)
		(end 321.717162 -339.500464)
		(width 0.1651)
		(layer "In15.Cu")
		(net "P5E_PEX2_STN4_RX_DP<64>")
	)
	(segment
		(start 302.88992 -379.772164)
		(end 303.01692 -379.899164)
		(width 0.1651)
		(layer "In15.Cu")
		(net "P5E_PEX2_STN4_RX_DP<64>")
	)
	(segment
		(start 302.88992 -379.390148)
		(end 302.88992 -379.772164)
		(width 0.1651)
		(layer "In15.Cu")
		(net "P5E_PEX2_STN4_RX_DP<64>")
	)
	(segment
		(start 319.094866 -356.15626)
		(end 320.032634 -355.767386)
		(width 0.1651)
		(layer "In15.Cu")
		(net "P5E_PEX2_STN4_RX_DP<64>")
	)
	(segment
		(start 314.294774 -305.019964)
		(end 314.079636 -304.804826)
		(width 0.1143)
		(layer "In15.Cu")
		(net "P5E_PEX2_STN4_RX_DP<64>")
	)
	(segment
		(start 314.079636 -304.564034)
		(end 313.965336 -304.449734)
		(width 0.1143)
		(layer "In15.Cu")
		(net "P5E_PEX2_STN4_RX_DP<64>")
	)
	(segment
		(start 308.227476 -363.456982)
		(end 308.370986 -363.453426)
		(width 0.1651)
		(layer "In15.Cu")
		(net "P5E_PEX2_STN4_RX_DP<64>")
	)
	(segment
		(start 320.566034 -342.192356)
		(end 320.709036 -341.281512)
		(width 0.1651)
		(layer "In15.Cu")
		(net "P5E_PEX2_STN4_RX_DP<64>")
	)
	(segment
		(start 320.032634 -355.767386)
		(end 320.317622 -355.482398)
		(width 0.1651)
		(layer "In15.Cu")
		(net "P5E_PEX2_STN4_RX_DP<64>")
	)
	(segment
		(start 303.733962 -379.612398)
		(end 303.733962 -368.877342)
		(width 0.1651)
		(layer "In15.Cu")
		(net "P5E_PEX2_STN4_RX_DP<64>")
	)
	(segment
		(start 321.717162 -339.500464)
		(end 321.961002 -339.069426)
		(width 0.1651)
		(layer "In15.Cu")
		(net "P5E_PEX2_STN4_RX_DP<64>")
	)
	(segment
		(start 315.8236 -305.065684)
		(end 315.77788 -305.019964)
		(width 0.1143)
		(layer "In15.Cu")
		(net "P5E_PEX2_STN4_RX_DP<64>")
	)
	(segment
		(start 305.470814 -366.37468)
		(end 305.812444 -366.015524)
		(width 0.1651)
		(layer "In15.Cu")
		(net "P5E_PEX2_STN4_RX_DP<64>")
	)
	(segment
		(start 307.422804 -364.321852)
		(end 307.54828 -364.31855)
		(width 0.1651)
		(layer "In15.Cu")
		(net "P5E_PEX2_STN4_RX_DP<64>")
	)
	(segment
		(start 321.317112 -339.974936)
		(end 321.56146 -339.543644)
		(width 0.1651)
		(layer "In15.Cu")
		(net "P5E_PEX2_STN4_RX_DP<64>")
	)
	(segment
		(start 315.054234 -356.4255)
		(end 315.772292 -356.15626)
		(width 0.1651)
		(layer "In15.Cu")
		(net "P5E_PEX2_STN4_RX_DP<64>")
	)
	(segment
		(start 330.6572 -318.374522)
		(end 329.642724 -315.925962)
		(width 0.1651)
		(layer "In15.Cu")
		(net "P5E_PEX2_STN4_RX_DP<64>")
	)
	(segment
		(start 318.857122 -305.065684)
		(end 315.852048 -305.065684)
		(width 0.1651)
		(layer "In15.Cu")
		(net "P5E_PEX2_STN4_RX_DP<64>")
	)
	(segment
		(start 308.370986 -363.453426)
		(end 315.054234 -356.4255)
		(width 0.1651)
		(layer "In15.Cu")
		(net "P5E_PEX2_STN4_RX_DP<64>")
	)
	(segment
		(start 313.965336 -304.449734)
		(end 313.699906 -304.449734)
		(width 0.1143)
		(layer "In15.Cu")
		(net "P5E_PEX2_STN4_RX_DP<64>")
	)
	(segment
		(start 307.885846 -363.816138)
		(end 308.227476 -363.456982)
		(width 0.1651)
		(layer "In15.Cu")
		(net "P5E_PEX2_STN4_RX_DP<64>")
	)
	(segment
		(start 306.275994 -365.527844)
		(end 306.617624 -365.168434)
		(width 0.1651)
		(layer "In15.Cu")
		(net "P5E_PEX2_STN4_RX_DP<64>")
	)
	(segment
		(start 322.296536 -306.90439)
		(end 318.857122 -305.065684)
		(width 0.1651)
		(layer "In15.Cu")
		(net "P5E_PEX2_STN4_RX_DP<64>")
	)
	(segment
		(start 303.733962 -368.877342)
		(end 304.153824 -367.88852)
		(width 0.1651)
		(layer "In15.Cu")
		(net "P5E_PEX2_STN4_RX_DP<64>")
	)
	(segment
		(start 305.473862 -366.500156)
		(end 305.470814 -366.37468)
		(width 0.1651)
		(layer "In15.Cu")
		(net "P5E_PEX2_STN4_RX_DP<64>")
	)
	(segment
		(start 306.279042 -365.65332)
		(end 306.275994 -365.527844)
		(width 0.1651)
		(layer "In15.Cu")
		(net "P5E_PEX2_STN4_RX_DP<64>")
	)
	(segment
		(start 305.812444 -366.015524)
		(end 305.93792 -366.012222)
		(width 0.1651)
		(layer "In15.Cu")
		(net "P5E_PEX2_STN4_RX_DP<64>")
	)
	(segment
		(start 307.54828 -364.31855)
		(end 307.889402 -363.959648)
		(width 0.1651)
		(layer "In15.Cu")
		(net "P5E_PEX2_STN4_RX_DP<64>")
	)
	(segment
		(start 329.8317 -325.16445)
		(end 330.6572 -323.171566)
		(width 0.1651)
		(layer "In15.Cu")
		(net "P5E_PEX2_STN4_RX_DP<64>")
	)
	(segment
		(start 307.889402 -363.959648)
		(end 307.885846 -363.816138)
		(width 0.1651)
		(layer "In15.Cu")
		(net "P5E_PEX2_STN4_RX_DP<64>")
	)
	(segment
		(start 321.360292 -340.130892)
		(end 321.317112 -339.974936)
		(width 0.1651)
		(layer "In15.Cu")
		(net "P5E_PEX2_STN4_RX_DP<64>")
	)
	(segment
		(start 303.447196 -379.899164)
		(end 303.733962 -379.612398)
		(width 0.1651)
		(layer "In15.Cu")
		(net "P5E_PEX2_STN4_RX_DP<64>")
	)
	(segment
		(start 321.961002 -339.069426)
		(end 321.917822 -338.913724)
		(width 0.1651)
		(layer "In15.Cu")
		(net "P5E_PEX2_STN4_RX_DP<64>")
	)
	(segment
		(start 315.77788 -305.019964)
		(end 314.294774 -305.019964)
		(width 0.1143)
		(layer "In15.Cu")
		(net "P5E_PEX2_STN4_RX_DP<64>")
	)
	(segment
		(start 305.93792 -366.012222)
		(end 306.279042 -365.65332)
		(width 0.1651)
		(layer "In15.Cu")
		(net "P5E_PEX2_STN4_RX_DP<64>")
	)
	(segment
		(start 314.079636 -304.804826)
		(end 314.079636 -304.564034)
		(width 0.1143)
		(layer "In15.Cu")
		(net "P5E_PEX2_STN4_RX_DP<64>")
	)
	(segment
		(start 307.084222 -364.806484)
		(end 307.081174 -364.681008)
		(width 0.1651)
		(layer "In15.Cu")
		(net "P5E_PEX2_STN4_RX_DP<64>")
	)
	(segment
		(start 329.642724 -315.925962)
		(end 326.269096 -310.876696)
		(width 0.1651)
		(layer "In15.Cu")
		(net "P5E_PEX2_STN4_RX_DP<64>")
	)
	(segment
		(start 320.317622 -355.482398)
		(end 320.566034 -354.882704)
		(width 0.1651)
		(layer "In15.Cu")
		(net "P5E_PEX2_STN4_RX_DP<64>")
	)
	(segment
		(start 315.852048 -305.065684)
		(end 315.8236 -305.065684)
		(width 0.1143)
		(layer "In15.Cu")
		(net "P5E_PEX2_STN4_RX_DP<64>")
	)
	(segment
		(start 326.269096 -310.876696)
		(end 322.296536 -306.90439)
		(width 0.1651)
		(layer "In15.Cu")
		(net "P5E_PEX2_STN4_RX_DP<64>")
	)
	(segment
		(start 304.153824 -367.88852)
		(end 305.473862 -366.500156)
		(width 0.1651)
		(layer "In15.Cu")
		(net "P5E_PEX2_STN4_RX_DP<64>")
	)
	(segment
		(start 306.7431 -365.165386)
		(end 307.084222 -364.806484)
		(width 0.1651)
		(layer "In15.Cu")
		(net "P5E_PEX2_STN4_RX_DP<64>")
	)
	(segment
		(start 282.548076 -385.473702)
		(end 282.016454 -372.485666)
		(width 0.1651)
		(layer "In15.Cu")
		(net "P5E_PEX2_STN4_RX_DN<76>")
	)
	(segment
		(start 282.016454 -372.485666)
		(end 282.6766 -368.173)
		(width 0.1651)
		(layer "In15.Cu")
		(net "P5E_PEX2_STN4_RX_DN<76>")
	)
	(segment
		(start 293.901114 -393.956286)
		(end 288.5948 -390.906)
		(width 0.1651)
		(layer "In15.Cu")
		(net "P5E_PEX2_STN4_RX_DN<76>")
	)
	(segment
		(start 282.6766 -368.173)
		(end 285.569152 -357.907082)
		(width 0.1651)
		(layer "In15.Cu")
		(net "P5E_PEX2_STN4_RX_DN<76>")
	)
	(segment
		(start 308.615842 -322.497958)
		(end 308.615842 -319.941448)
		(width 0.1651)
		(layer "In15.Cu")
		(net "P5E_PEX2_STN4_RX_DN<76>")
	)
	(segment
		(start 308.949852 -318.434466)
		(end 308.949852 -318.699896)
		(width 0.1143)
		(layer "In15.Cu")
		(net "P5E_PEX2_STN4_RX_DN<76>")
	)
	(segment
		(start 308.570122 -319.86728)
		(end 308.570122 -318.423798)
		(width 0.1143)
		(layer "In15.Cu")
		(net "P5E_PEX2_STN4_RX_DN<76>")
	)
	(segment
		(start 295.215818 -396.24)
		(end 294.6146 -394.7414)
		(width 0.1651)
		(layer "In15.Cu")
		(net "P5E_PEX2_STN4_RX_DN<76>")
	)
	(segment
		(start 308.570122 -318.423798)
		(end 308.673754 -318.320166)
		(width 0.1143)
		(layer "In15.Cu")
		(net "P5E_PEX2_STN4_RX_DN<76>")
	)
	(segment
		(start 285.569152 -341.63)
		(end 286.2072 -340.6648)
		(width 0.1651)
		(layer "In15.Cu")
		(net "P5E_PEX2_STN4_RX_DN<76>")
	)
	(segment
		(start 286.208978 -389.863838)
		(end 283.46654 -387.854444)
		(width 0.1651)
		(layer "In15.Cu")
		(net "P5E_PEX2_STN4_RX_DN<76>")
	)
	(segment
		(start 308.615842 -319.913)
		(end 308.570122 -319.86728)
		(width 0.1143)
		(layer "In15.Cu")
		(net "P5E_PEX2_STN4_RX_DN<76>")
	)
	(segment
		(start 294.763952 -406.181052)
		(end 295.215818 -405.729186)
		(width 0.1651)
		(layer "In15.Cu")
		(net "P5E_PEX2_STN4_RX_DN<76>")
	)
	(segment
		(start 286.2072 -340.6648)
		(end 306.771294 -324.342506)
		(width 0.1651)
		(layer "In15.Cu")
		(net "P5E_PEX2_STN4_RX_DN<76>")
	)
	(segment
		(start 285.569152 -357.907082)
		(end 285.569152 -341.63)
		(width 0.1651)
		(layer "In15.Cu")
		(net "P5E_PEX2_STN4_RX_DN<76>")
	)
	(segment
		(start 308.615842 -319.941448)
		(end 308.615842 -319.913)
		(width 0.1143)
		(layer "In15.Cu")
		(net "P5E_PEX2_STN4_RX_DN<76>")
	)
	(segment
		(start 294.089836 -406.308052)
		(end 294.216836 -406.181052)
		(width 0.1651)
		(layer "In15.Cu")
		(net "P5E_PEX2_STN4_RX_DN<76>")
	)
	(segment
		(start 308.673754 -318.320166)
		(end 308.835552 -318.320166)
		(width 0.1143)
		(layer "In15.Cu")
		(net "P5E_PEX2_STN4_RX_DN<76>")
	)
	(segment
		(start 306.771294 -324.342506)
		(end 308.615842 -322.497958)
		(width 0.1651)
		(layer "In15.Cu")
		(net "P5E_PEX2_STN4_RX_DN<76>")
	)
	(segment
		(start 283.46654 -387.854444)
		(end 282.548076 -385.473702)
		(width 0.1651)
		(layer "In15.Cu")
		(net "P5E_PEX2_STN4_RX_DN<76>")
	)
	(segment
		(start 288.5948 -390.906)
		(end 286.208978 -389.863838)
		(width 0.1651)
		(layer "In15.Cu")
		(net "P5E_PEX2_STN4_RX_DN<76>")
	)
	(segment
		(start 294.216836 -406.181052)
		(end 294.763952 -406.181052)
		(width 0.1651)
		(layer "In15.Cu")
		(net "P5E_PEX2_STN4_RX_DN<76>")
	)
	(segment
		(start 294.089836 -406.690068)
		(end 294.089836 -406.308052)
		(width 0.1651)
		(layer "In15.Cu")
		(net "P5E_PEX2_STN4_RX_DN<76>")
	)
	(segment
		(start 294.6146 -394.7414)
		(end 293.901114 -393.956286)
		(width 0.1651)
		(layer "In15.Cu")
		(net "P5E_PEX2_STN4_RX_DN<76>")
	)
	(segment
		(start 295.215818 -405.729186)
		(end 295.215818 -396.24)
		(width 0.1651)
		(layer "In15.Cu")
		(net "P5E_PEX2_STN4_RX_DN<76>")
	)
	(segment
		(start 308.835552 -318.320166)
		(end 308.949852 -318.434466)
		(width 0.1143)
		(layer "In15.Cu")
		(net "P5E_PEX2_STN4_RX_DN<76>")
	)
	(segment
		(start 422.025064 -349.512382)
		(end 422.025064 -348.879922)
		(width 0.13462)
		(layer "F.Cu")
		(net "P5E_PEX3_STN4_TX_DP<73>")
	)
	(segment
		(start 422.025064 -348.879922)
		(end 421.730932 -348.58579)
		(width 0.13462)
		(layer "F.Cu")
		(net "P5E_PEX3_STN4_TX_DP<73>")
	)
	(segment
		(start 421.705532 -349.831914)
		(end 422.025064 -349.512382)
		(width 0.13462)
		(layer "F.Cu")
		(net "P5E_PEX3_STN4_TX_DP<73>")
	)
	(segment
		(start 427.28388 -322.957698)
		(end 427.28388 -319.9384)
		(width 0.1651)
		(layer "In7.Cu")
		(net "P5E_PEX3_STN4_TX_DP<73>")
	)
	(segment
		(start 427.3296 -319.864232)
		(end 427.3296 -311.705498)
		(width 0.1143)
		(layer "In7.Cu")
		(net "P5E_PEX3_STN4_TX_DP<73>")
	)
	(segment
		(start 427.78553 -311.479692)
		(end 427.89983 -311.365392)
		(width 0.1143)
		(layer "In7.Cu")
		(net "P5E_PEX3_STN4_TX_DP<73>")
	)
	(segment
		(start 427.28388 -319.909952)
		(end 427.3296 -319.864232)
		(width 0.1143)
		(layer "In7.Cu")
		(net "P5E_PEX3_STN4_TX_DP<73>")
	)
	(segment
		(start 422.021762 -347.667834)
		(end 423.576242 -346.113354)
		(width 0.1651)
		(layer "In7.Cu")
		(net "P5E_PEX3_STN4_TX_DP<73>")
	)
	(segment
		(start 421.730932 -348.58579)
		(end 422.021762 -348.29496)
		(width 0.1651)
		(layer "In7.Cu")
		(net "P5E_PEX3_STN4_TX_DP<73>")
	)
	(segment
		(start 427.89983 -311.365392)
		(end 427.89983 -311.099962)
		(width 0.1143)
		(layer "In7.Cu")
		(net "P5E_PEX3_STN4_TX_DP<73>")
	)
	(segment
		(start 427.3296 -311.705498)
		(end 427.555406 -311.479692)
		(width 0.1143)
		(layer "In7.Cu")
		(net "P5E_PEX3_STN4_TX_DP<73>")
	)
	(segment
		(start 427.555406 -311.479692)
		(end 427.78553 -311.479692)
		(width 0.1143)
		(layer "In7.Cu")
		(net "P5E_PEX3_STN4_TX_DP<73>")
	)
	(segment
		(start 423.576242 -346.113354)
		(end 423.576242 -341.70112)
		(width 0.1651)
		(layer "In7.Cu")
		(net "P5E_PEX3_STN4_TX_DP<73>")
	)
	(segment
		(start 427.28388 -319.9384)
		(end 427.28388 -319.909952)
		(width 0.1143)
		(layer "In7.Cu")
		(net "P5E_PEX3_STN4_TX_DP<73>")
	)
	(segment
		(start 423.576242 -341.70112)
		(end 427.28388 -322.957698)
		(width 0.1651)
		(layer "In7.Cu")
		(net "P5E_PEX3_STN4_TX_DP<73>")
	)
	(segment
		(start 422.021762 -348.29496)
		(end 422.021762 -347.667834)
		(width 0.1651)
		(layer "In7.Cu")
		(net "P5E_PEX3_STN4_TX_DP<73>")
	)
	(segment
		(start 311.183782 -319.913)
		(end 311.229502 -319.86728)
		(width 0.1143)
		(layer "In15.Cu")
		(net "P5E_PEX2_STN4_RX_DP<73>")
	)
	(segment
		(start 298.091606 -392.07186)
		(end 297.63593 -391.878058)
		(width 0.1651)
		(layer "In15.Cu")
		(net "P5E_PEX2_STN4_RX_DP<73>")
	)
	(segment
		(start 295.061386 -340.865714)
		(end 295.06291 -340.863174)
		(width 0.1651)
		(layer "In15.Cu")
		(net "P5E_PEX2_STN4_RX_DP<73>")
	)
	(segment
		(start 294.214042 -358.888538)
		(end 294.614092 -357.92283)
		(width 0.1651)
		(layer "In15.Cu")
		(net "P5E_PEX2_STN4_RX_DP<73>")
	)
	(segment
		(start 300.544992 -394.038074)
		(end 300.197266 -393.685014)
		(width 0.1651)
		(layer "In15.Cu")
		(net "P5E_PEX2_STN4_RX_DP<73>")
	)
	(segment
		(start 301.247048 -404.799038)
		(end 301.533814 -404.512272)
		(width 0.1651)
		(layer "In15.Cu")
		(net "P5E_PEX2_STN4_RX_DP<73>")
	)
	(segment
		(start 300.689772 -404.672038)
		(end 300.816772 -404.799038)
		(width 0.1651)
		(layer "In15.Cu")
		(net "P5E_PEX2_STN4_RX_DP<73>")
	)
	(segment
		(start 295.057322 -340.86673)
		(end 295.061386 -340.865714)
		(width 0.1651)
		(layer "In15.Cu")
		(net "P5E_PEX2_STN4_RX_DP<73>")
	)
	(segment
		(start 301.533814 -395.523466)
		(end 301.250604 -394.663676)
		(width 0.1651)
		(layer "In15.Cu")
		(net "P5E_PEX2_STN4_RX_DP<73>")
	)
	(segment
		(start 297.48607 -391.938256)
		(end 297.03014 -391.7442)
		(width 0.1651)
		(layer "In15.Cu")
		(net "P5E_PEX2_STN4_RX_DP<73>")
	)
	(segment
		(start 294.614092 -357.92283)
		(end 294.614092 -342.008968)
		(width 0.1651)
		(layer "In15.Cu")
		(net "P5E_PEX2_STN4_RX_DP<73>")
	)
	(segment
		(start 287.821624 -387.69925)
		(end 285.691326 -386.192776)
		(width 0.1651)
		(layer "In15.Cu")
		(net "P5E_PEX2_STN4_RX_DP<73>")
	)
	(segment
		(start 310.851804 -324.257416)
		(end 311.183782 -323.455792)
		(width 0.1651)
		(layer "In15.Cu")
		(net "P5E_PEX2_STN4_RX_DP<73>")
	)
	(segment
		(start 300.197774 -393.595098)
		(end 299.619416 -393.008104)
		(width 0.1651)
		(layer "In15.Cu")
		(net "P5E_PEX2_STN4_RX_DP<73>")
	)
	(segment
		(start 297.03014 -391.7442)
		(end 296.969688 -391.594086)
		(width 0.1651)
		(layer "In15.Cu")
		(net "P5E_PEX2_STN4_RX_DP<73>")
	)
	(segment
		(start 295.06291 -340.863174)
		(end 295.338754 -340.42731)
		(width 0.1651)
		(layer "In15.Cu")
		(net "P5E_PEX2_STN4_RX_DP<73>")
	)
	(segment
		(start 297.63593 -391.878058)
		(end 297.48607 -391.938256)
		(width 0.1651)
		(layer "In15.Cu")
		(net "P5E_PEX2_STN4_RX_DP<73>")
	)
	(segment
		(start 300.689772 -404.290022)
		(end 300.689772 -404.672038)
		(width 0.1651)
		(layer "In15.Cu")
		(net "P5E_PEX2_STN4_RX_DP<73>")
	)
	(segment
		(start 299.619416 -393.008104)
		(end 298.091606 -392.07186)
		(width 0.1651)
		(layer "In15.Cu")
		(net "P5E_PEX2_STN4_RX_DP<73>")
	)
	(segment
		(start 285.190692 -384.77571)
		(end 284.722824 -372.347744)
		(width 0.1651)
		(layer "In15.Cu")
		(net "P5E_PEX2_STN4_RX_DP<73>")
	)
	(segment
		(start 295.338754 -340.42731)
		(end 310.851804 -324.257416)
		(width 0.1651)
		(layer "In15.Cu")
		(net "P5E_PEX2_STN4_RX_DP<73>")
	)
	(segment
		(start 311.44464 -316.229492)
		(end 311.685432 -316.229492)
		(width 0.1143)
		(layer "In15.Cu")
		(net "P5E_PEX2_STN4_RX_DP<73>")
	)
	(segment
		(start 311.229502 -316.44463)
		(end 311.44464 -316.229492)
		(width 0.1143)
		(layer "In15.Cu")
		(net "P5E_PEX2_STN4_RX_DP<73>")
	)
	(segment
		(start 311.183782 -319.941448)
		(end 311.183782 -319.913)
		(width 0.1143)
		(layer "In15.Cu")
		(net "P5E_PEX2_STN4_RX_DP<73>")
	)
	(segment
		(start 311.685432 -316.229492)
		(end 311.799732 -316.115192)
		(width 0.1143)
		(layer "In15.Cu")
		(net "P5E_PEX2_STN4_RX_DP<73>")
	)
	(segment
		(start 295.84777 -391.116312)
		(end 287.821624 -387.69925)
		(width 0.1651)
		(layer "In15.Cu")
		(net "P5E_PEX2_STN4_RX_DP<73>")
	)
	(segment
		(start 301.250604 -394.663676)
		(end 300.634908 -394.038836)
		(width 0.1651)
		(layer "In15.Cu")
		(net "P5E_PEX2_STN4_RX_DP<73>")
	)
	(segment
		(start 296.364152 -391.460482)
		(end 295.908222 -391.26668)
		(width 0.1651)
		(layer "In15.Cu")
		(net "P5E_PEX2_STN4_RX_DP<73>")
	)
	(segment
		(start 311.229502 -319.86728)
		(end 311.229502 -316.44463)
		(width 0.1143)
		(layer "In15.Cu")
		(net "P5E_PEX2_STN4_RX_DP<73>")
	)
	(segment
		(start 285.691326 -386.192776)
		(end 285.190692 -384.77571)
		(width 0.1651)
		(layer "In15.Cu")
		(net "P5E_PEX2_STN4_RX_DP<73>")
	)
	(segment
		(start 285.211774 -368.902742)
		(end 285.957518 -367.720626)
		(width 0.1651)
		(layer "In15.Cu")
		(net "P5E_PEX2_STN4_RX_DP<73>")
	)
	(segment
		(start 300.197266 -393.685014)
		(end 300.197774 -393.595098)
		(width 0.1651)
		(layer "In15.Cu")
		(net "P5E_PEX2_STN4_RX_DP<73>")
	)
	(segment
		(start 284.722824 -372.347744)
		(end 285.211774 -368.902742)
		(width 0.1651)
		(layer "In15.Cu")
		(net "P5E_PEX2_STN4_RX_DP<73>")
	)
	(segment
		(start 296.969688 -391.594086)
		(end 296.514012 -391.400284)
		(width 0.1651)
		(layer "In15.Cu")
		(net "P5E_PEX2_STN4_RX_DP<73>")
	)
	(segment
		(start 285.957518 -367.720626)
		(end 294.214042 -358.888538)
		(width 0.1651)
		(layer "In15.Cu")
		(net "P5E_PEX2_STN4_RX_DP<73>")
	)
	(segment
		(start 295.908222 -391.26668)
		(end 295.84777 -391.116312)
		(width 0.1651)
		(layer "In15.Cu")
		(net "P5E_PEX2_STN4_RX_DP<73>")
	)
	(segment
		(start 294.614092 -342.008968)
		(end 295.057322 -340.86673)
		(width 0.1651)
		(layer "In15.Cu")
		(net "P5E_PEX2_STN4_RX_DP<73>")
	)
	(segment
		(start 311.183782 -323.455792)
		(end 311.183782 -319.941448)
		(width 0.1651)
		(layer "In15.Cu")
		(net "P5E_PEX2_STN4_RX_DP<73>")
	)
	(segment
		(start 300.634908 -394.038836)
		(end 300.544992 -394.038074)
		(width 0.1651)
		(layer "In15.Cu")
		(net "P5E_PEX2_STN4_RX_DP<73>")
	)
	(segment
		(start 311.799732 -316.115192)
		(end 311.799732 -315.849762)
		(width 0.1143)
		(layer "In15.Cu")
		(net "P5E_PEX2_STN4_RX_DP<73>")
	)
	(segment
		(start 300.816772 -404.799038)
		(end 301.247048 -404.799038)
		(width 0.1651)
		(layer "In15.Cu")
		(net "P5E_PEX2_STN4_RX_DP<73>")
	)
	(segment
		(start 301.533814 -404.512272)
		(end 301.533814 -395.523466)
		(width 0.1651)
		(layer "In15.Cu")
		(net "P5E_PEX2_STN4_RX_DP<73>")
	)
	(segment
		(start 296.514012 -391.400284)
		(end 296.364152 -391.460482)
		(width 0.1651)
		(layer "In15.Cu")
		(net "P5E_PEX2_STN4_RX_DP<73>")
	)
	(segment
		(start 271.575022 -351.316798)
		(end 271.869662 -351.611438)
		(width 0.13462)
		(layer "F.Cu")
		(net "P5E_PEX2_STN4_TX_C_DN<78>")
	)
	(segment
		(start 271.575022 -350.685354)
		(end 271.575022 -351.316798)
		(width 0.13462)
		(layer "F.Cu")
		(net "P5E_PEX2_STN4_TX_C_DN<78>")
	)
	(segment
		(start 271.895062 -350.365314)
		(end 271.575022 -350.685354)
		(width 0.13462)
		(layer "F.Cu")
		(net "P5E_PEX2_STN4_TX_C_DN<78>")
	)
	(segment
		(start 289.237674 -393.479782)
		(end 284.66542 -391.583164)
		(width 0.1651)
		(layer "In11.Cu")
		(net "P5E_PEX2_STN4_TX_C_DN<78>")
	)
	(segment
		(start 289.689794 -398.890236)
		(end 289.689794 -398.50822)
		(width 0.1651)
		(layer "In11.Cu")
		(net "P5E_PEX2_STN4_TX_C_DN<78>")
	)
	(segment
		(start 271.578832 -352.473006)
		(end 271.578832 -351.902268)
		(width 0.1651)
		(layer "In11.Cu")
		(net "P5E_PEX2_STN4_TX_C_DN<78>")
	)
	(segment
		(start 270.024352 -354.027486)
		(end 271.578832 -352.473006)
		(width 0.1651)
		(layer "In11.Cu")
		(net "P5E_PEX2_STN4_TX_C_DN<78>")
	)
	(segment
		(start 290.815776 -395.7955)
		(end 289.237674 -393.479782)
		(width 0.1651)
		(layer "In11.Cu")
		(net "P5E_PEX2_STN4_TX_C_DN<78>")
	)
	(segment
		(start 281.840178 -388.90448)
		(end 280.582624 -386.42671)
		(width 0.1651)
		(layer "In11.Cu")
		(net "P5E_PEX2_STN4_TX_C_DN<78>")
	)
	(segment
		(start 289.689794 -398.50822)
		(end 289.816794 -398.38122)
		(width 0.1651)
		(layer "In11.Cu")
		(net "P5E_PEX2_STN4_TX_C_DN<78>")
	)
	(segment
		(start 271.578832 -351.902268)
		(end 271.869662 -351.611438)
		(width 0.1651)
		(layer "In11.Cu")
		(net "P5E_PEX2_STN4_TX_C_DN<78>")
	)
	(segment
		(start 270.024352 -358.448356)
		(end 270.024352 -354.027486)
		(width 0.1651)
		(layer "In11.Cu")
		(net "P5E_PEX2_STN4_TX_C_DN<78>")
	)
	(segment
		(start 279.625552 -379.105922)
		(end 270.024352 -358.448356)
		(width 0.1651)
		(layer "In11.Cu")
		(net "P5E_PEX2_STN4_TX_C_DN<78>")
	)
	(segment
		(start 289.816794 -398.38122)
		(end 290.36391 -398.38122)
		(width 0.1651)
		(layer "In11.Cu")
		(net "P5E_PEX2_STN4_TX_C_DN<78>")
	)
	(segment
		(start 284.66542 -391.583164)
		(end 281.840178 -388.90448)
		(width 0.1651)
		(layer "In11.Cu")
		(net "P5E_PEX2_STN4_TX_C_DN<78>")
	)
	(segment
		(start 290.36391 -398.38122)
		(end 290.815776 -397.929354)
		(width 0.1651)
		(layer "In11.Cu")
		(net "P5E_PEX2_STN4_TX_C_DN<78>")
	)
	(segment
		(start 290.815776 -397.929354)
		(end 290.815776 -395.7955)
		(width 0.1651)
		(layer "In11.Cu")
		(net "P5E_PEX2_STN4_TX_C_DN<78>")
	)
	(segment
		(start 280.582624 -386.42671)
		(end 279.625552 -379.105922)
		(width 0.1651)
		(layer "In11.Cu")
		(net "P5E_PEX2_STN4_TX_C_DN<78>")
	)
	(segment
		(start 274.683982 -357.46309)
		(end 274.978622 -357.75773)
		(width 0.13462)
		(layer "F.Cu")
		(net "P5E_PEX2_STN4_TX_C_DN<76>")
	)
	(segment
		(start 275.004022 -356.511606)
		(end 274.683982 -356.831646)
		(width 0.13462)
		(layer "F.Cu")
		(net "P5E_PEX2_STN4_TX_C_DN<76>")
	)
	(segment
		(start 274.683982 -356.831646)
		(end 274.683982 -357.46309)
		(width 0.13462)
		(layer "F.Cu")
		(net "P5E_PEX2_STN4_TX_C_DN<76>")
	)
	(segment
		(start 291.262816 -391.891774)
		(end 285.483046 -389.617204)
		(width 0.1651)
		(layer "In11.Cu")
		(net "P5E_PEX2_STN4_TX_C_DN<76>")
	)
	(segment
		(start 282.531058 -385.84632)
		(end 281.649932 -378.697236)
		(width 0.1651)
		(layer "In11.Cu")
		(net "P5E_PEX2_STN4_TX_C_DN<76>")
	)
	(segment
		(start 293.21252 -393.15898)
		(end 291.262816 -391.891774)
		(width 0.1651)
		(layer "In11.Cu")
		(net "P5E_PEX2_STN4_TX_C_DN<76>")
	)
	(segment
		(start 294.763952 -398.38122)
		(end 295.215818 -397.929354)
		(width 0.1651)
		(layer "In11.Cu")
		(net "P5E_PEX2_STN4_TX_C_DN<76>")
	)
	(segment
		(start 285.483046 -389.617204)
		(end 283.43606 -387.64718)
		(width 0.1651)
		(layer "In11.Cu")
		(net "P5E_PEX2_STN4_TX_C_DN<76>")
	)
	(segment
		(start 295.215818 -395.38402)
		(end 293.21252 -393.15898)
		(width 0.1651)
		(layer "In11.Cu")
		(net "P5E_PEX2_STN4_TX_C_DN<76>")
	)
	(segment
		(start 283.43606 -387.64718)
		(end 282.531058 -385.84632)
		(width 0.1651)
		(layer "In11.Cu")
		(net "P5E_PEX2_STN4_TX_C_DN<76>")
	)
	(segment
		(start 294.089836 -398.50822)
		(end 294.216836 -398.38122)
		(width 0.1651)
		(layer "In11.Cu")
		(net "P5E_PEX2_STN4_TX_C_DN<76>")
	)
	(segment
		(start 294.216836 -398.38122)
		(end 294.763952 -398.38122)
		(width 0.1651)
		(layer "In11.Cu")
		(net "P5E_PEX2_STN4_TX_C_DN<76>")
	)
	(segment
		(start 294.089836 -398.890236)
		(end 294.089836 -398.50822)
		(width 0.1651)
		(layer "In11.Cu")
		(net "P5E_PEX2_STN4_TX_C_DN<76>")
	)
	(segment
		(start 274.687792 -358.75468)
		(end 274.687792 -358.04856)
		(width 0.1651)
		(layer "In11.Cu")
		(net "P5E_PEX2_STN4_TX_C_DN<76>")
	)
	(segment
		(start 274.687792 -358.04856)
		(end 274.978622 -357.75773)
		(width 0.1651)
		(layer "In11.Cu")
		(net "P5E_PEX2_STN4_TX_C_DN<76>")
	)
	(segment
		(start 295.215818 -397.929354)
		(end 295.215818 -395.38402)
		(width 0.1651)
		(layer "In11.Cu")
		(net "P5E_PEX2_STN4_TX_C_DN<76>")
	)
	(segment
		(start 281.649932 -378.697236)
		(end 274.687792 -358.75468)
		(width 0.1651)
		(layer "In11.Cu")
		(net "P5E_PEX2_STN4_TX_C_DN<76>")
	)
	(segment
		(start 289.780726 -395.151864)
		(end 289.475926 -394.760958)
		(width 0.1651)
		(layer "In15.Cu")
		(net "P5E_PEX2_STN4_RX_DP<78>")
	)
	(segment
		(start 290.533836 -396.53464)
		(end 290.269676 -395.634464)
		(width 0.1651)
		(layer "In15.Cu")
		(net "P5E_PEX2_STN4_RX_DP<78>")
	)
	(segment
		(start 289.49142 -394.636244)
		(end 289.155378 -394.205206)
		(width 0.1651)
		(layer "In15.Cu")
		(net "P5E_PEX2_STN4_RX_DP<78>")
	)
	(segment
		(start 306.433982 -321.512438)
		(end 306.433982 -319.941448)
		(width 0.1651)
		(layer "In15.Cu")
		(net "P5E_PEX2_STN4_RX_DP<78>")
	)
	(segment
		(start 279.069292 -359.400602)
		(end 279.069292 -341.581232)
		(width 0.1651)
		(layer "In15.Cu")
		(net "P5E_PEX2_STN4_RX_DP<78>")
	)
	(segment
		(start 285.024068 -391.800334)
		(end 281.625294 -389.243824)
		(width 0.1651)
		(layer "In15.Cu")
		(net "P5E_PEX2_STN4_RX_DP<78>")
	)
	(segment
		(start 306.69484 -318.129666)
		(end 306.935632 -318.129666)
		(width 0.1143)
		(layer "In15.Cu")
		(net "P5E_PEX2_STN4_RX_DP<78>")
	)
	(segment
		(start 289.90544 -395.167358)
		(end 289.780726 -395.151864)
		(width 0.1651)
		(layer "In15.Cu")
		(net "P5E_PEX2_STN4_RX_DP<78>")
	)
	(segment
		(start 306.433982 -319.913)
		(end 306.479702 -319.86728)
		(width 0.1143)
		(layer "In15.Cu")
		(net "P5E_PEX2_STN4_RX_DP<78>")
	)
	(segment
		(start 290.24707 -405.899112)
		(end 290.533836 -405.612346)
		(width 0.1651)
		(layer "In15.Cu")
		(net "P5E_PEX2_STN4_RX_DP<78>")
	)
	(segment
		(start 289.475926 -394.760958)
		(end 289.49142 -394.636244)
		(width 0.1651)
		(layer "In15.Cu")
		(net "P5E_PEX2_STN4_RX_DP<78>")
	)
	(segment
		(start 280.23185 -385.875276)
		(end 279.069292 -359.400602)
		(width 0.1651)
		(layer "In15.Cu")
		(net "P5E_PEX2_STN4_RX_DP<78>")
	)
	(segment
		(start 289.689794 -405.390096)
		(end 289.689794 -405.772112)
		(width 0.1651)
		(layer "In15.Cu")
		(net "P5E_PEX2_STN4_RX_DP<78>")
	)
	(segment
		(start 290.533836 -405.612346)
		(end 290.533836 -396.53464)
		(width 0.1651)
		(layer "In15.Cu")
		(net "P5E_PEX2_STN4_RX_DP<78>")
	)
	(segment
		(start 289.816794 -405.899112)
		(end 290.24707 -405.899112)
		(width 0.1651)
		(layer "In15.Cu")
		(net "P5E_PEX2_STN4_RX_DP<78>")
	)
	(segment
		(start 287.533334 -392.927078)
		(end 285.024068 -391.800334)
		(width 0.1651)
		(layer "In15.Cu")
		(net "P5E_PEX2_STN4_RX_DP<78>")
	)
	(segment
		(start 306.935632 -318.129666)
		(end 307.049932 -318.015366)
		(width 0.1143)
		(layer "In15.Cu")
		(net "P5E_PEX2_STN4_RX_DP<78>")
	)
	(segment
		(start 279.069292 -341.581232)
		(end 279.68702 -340.813136)
		(width 0.1651)
		(layer "In15.Cu")
		(net "P5E_PEX2_STN4_RX_DP<78>")
	)
	(segment
		(start 305.59756 -322.34886)
		(end 306.433982 -321.512438)
		(width 0.1651)
		(layer "In15.Cu")
		(net "P5E_PEX2_STN4_RX_DP<78>")
	)
	(segment
		(start 281.625294 -389.243824)
		(end 280.23185 -385.875276)
		(width 0.1651)
		(layer "In15.Cu")
		(net "P5E_PEX2_STN4_RX_DP<78>")
	)
	(segment
		(start 306.479702 -319.86728)
		(end 306.479702 -318.344804)
		(width 0.1143)
		(layer "In15.Cu")
		(net "P5E_PEX2_STN4_RX_DP<78>")
	)
	(segment
		(start 290.269676 -395.634464)
		(end 289.90544 -395.167358)
		(width 0.1651)
		(layer "In15.Cu")
		(net "P5E_PEX2_STN4_RX_DP<78>")
	)
	(segment
		(start 307.049932 -318.015366)
		(end 307.049932 -317.749936)
		(width 0.1143)
		(layer "In15.Cu")
		(net "P5E_PEX2_STN4_RX_DP<78>")
	)
	(segment
		(start 306.479702 -318.344804)
		(end 306.69484 -318.129666)
		(width 0.1143)
		(layer "In15.Cu")
		(net "P5E_PEX2_STN4_RX_DP<78>")
	)
	(segment
		(start 289.155378 -394.205206)
		(end 287.533334 -392.927078)
		(width 0.1651)
		(layer "In15.Cu")
		(net "P5E_PEX2_STN4_RX_DP<78>")
	)
	(segment
		(start 306.433982 -319.941448)
		(end 306.433982 -319.913)
		(width 0.1143)
		(layer "In15.Cu")
		(net "P5E_PEX2_STN4_RX_DP<78>")
	)
	(segment
		(start 289.689794 -405.772112)
		(end 289.816794 -405.899112)
		(width 0.1651)
		(layer "In15.Cu")
		(net "P5E_PEX2_STN4_RX_DP<78>")
	)
	(segment
		(start 279.68702 -340.813136)
		(end 305.59756 -322.34886)
		(width 0.1651)
		(layer "In15.Cu")
		(net "P5E_PEX2_STN4_RX_DP<78>")
	)
	(segment
		(start 428.837852 -349.831914)
		(end 428.517304 -349.511366)
		(width 0.13462)
		(layer "F.Cu")
		(net "P5E_PEX3_STN4_TX_DN<70>")
	)
	(segment
		(start 428.517304 -348.880938)
		(end 428.812452 -348.58579)
		(width 0.13462)
		(layer "F.Cu")
		(net "P5E_PEX3_STN4_TX_DN<70>")
	)
	(segment
		(start 428.517304 -349.511366)
		(end 428.517304 -348.880938)
		(width 0.13462)
		(layer "F.Cu")
		(net "P5E_PEX3_STN4_TX_DN<70>")
	)
	(segment
		(start 430.076356 -341.70874)
		(end 431.975768 -320.779648)
		(width 0.1651)
		(layer "In7.Cu")
		(net "P5E_PEX3_STN4_TX_DN<70>")
	)
	(segment
		(start 431.440336 -312.626756)
		(end 431.42027 -312.60669)
		(width 0.1143)
		(layer "In7.Cu")
		(net "P5E_PEX3_STN4_TX_DN<70>")
	)
	(segment
		(start 430.076102 -341.708994)
		(end 430.076356 -341.70874)
		(width 0.1651)
		(layer "In7.Cu")
		(net "P5E_PEX3_STN4_TX_DN<70>")
	)
	(segment
		(start 430.076102 -346.230194)
		(end 430.076102 -341.708994)
		(width 0.1651)
		(layer "In7.Cu")
		(net "P5E_PEX3_STN4_TX_DN<70>")
	)
	(segment
		(start 430.370234 -312.164222)
		(end 430.484534 -312.049922)
		(width 0.1143)
		(layer "In7.Cu")
		(net "P5E_PEX3_STN4_TX_DN<70>")
	)
	(segment
		(start 431.975768 -320.779648)
		(end 432.43754 -318.290956)
		(width 0.1651)
		(layer "In7.Cu")
		(net "P5E_PEX3_STN4_TX_DN<70>")
	)
	(segment
		(start 431.42027 -312.60669)
		(end 431.349912 -312.60669)
		(width 0.1143)
		(layer "In7.Cu")
		(net "P5E_PEX3_STN4_TX_DN<70>")
	)
	(segment
		(start 428.521622 -348.29496)
		(end 428.521622 -347.784674)
		(width 0.1651)
		(layer "In7.Cu")
		(net "P5E_PEX3_STN4_TX_DN<70>")
	)
	(segment
		(start 431.172874 -312.429652)
		(end 430.458118 -312.429652)
		(width 0.1143)
		(layer "In7.Cu")
		(net "P5E_PEX3_STN4_TX_DN<70>")
	)
	(segment
		(start 431.865532 -313.051952)
		(end 431.440336 -312.626756)
		(width 0.1651)
		(layer "In7.Cu")
		(net "P5E_PEX3_STN4_TX_DN<70>")
	)
	(segment
		(start 431.865532 -313.082432)
		(end 431.865532 -313.051952)
		(width 0.1651)
		(layer "In7.Cu")
		(net "P5E_PEX3_STN4_TX_DN<70>")
	)
	(segment
		(start 431.349912 -312.60669)
		(end 431.172874 -312.429652)
		(width 0.1143)
		(layer "In7.Cu")
		(net "P5E_PEX3_STN4_TX_DN<70>")
	)
	(segment
		(start 428.521622 -347.784674)
		(end 430.076102 -346.230194)
		(width 0.1651)
		(layer "In7.Cu")
		(net "P5E_PEX3_STN4_TX_DN<70>")
	)
	(segment
		(start 430.484534 -312.049922)
		(end 430.749964 -312.049922)
		(width 0.1143)
		(layer "In7.Cu")
		(net "P5E_PEX3_STN4_TX_DN<70>")
	)
	(segment
		(start 428.812452 -348.58579)
		(end 428.521622 -348.29496)
		(width 0.1651)
		(layer "In7.Cu")
		(net "P5E_PEX3_STN4_TX_DN<70>")
	)
	(segment
		(start 432.43754 -318.290956)
		(end 432.43754 -314.46343)
		(width 0.1651)
		(layer "In7.Cu")
		(net "P5E_PEX3_STN4_TX_DN<70>")
	)
	(segment
		(start 432.43754 -314.46343)
		(end 431.865532 -313.082432)
		(width 0.1651)
		(layer "In7.Cu")
		(net "P5E_PEX3_STN4_TX_DN<70>")
	)
	(segment
		(start 430.370234 -312.341768)
		(end 430.370234 -312.164222)
		(width 0.1143)
		(layer "In7.Cu")
		(net "P5E_PEX3_STN4_TX_DN<70>")
	)
	(segment
		(start 430.458118 -312.429652)
		(end 430.370234 -312.341768)
		(width 0.1143)
		(layer "In7.Cu")
		(net "P5E_PEX3_STN4_TX_DN<70>")
	)
	(segment
		(start 440.678824 -348.879922)
		(end 440.384692 -348.58579)
		(width 0.13462)
		(layer "F.Cu")
		(net "P5E_PEX3_STN4_TX_DP<64>")
	)
	(segment
		(start 440.359292 -349.831914)
		(end 440.678824 -349.512382)
		(width 0.13462)
		(layer "F.Cu")
		(net "P5E_PEX3_STN4_TX_DP<64>")
	)
	(segment
		(start 440.678824 -349.512382)
		(end 440.678824 -348.879922)
		(width 0.13462)
		(layer "F.Cu")
		(net "P5E_PEX3_STN4_TX_DP<64>")
	)
	(segment
		(start 442.00826 -311.8358)
		(end 436.701438 -306.528978)
		(width 0.1651)
		(layer "In7.Cu")
		(net "P5E_PEX3_STN4_TX_DP<64>")
	)
	(segment
		(start 447.13525 -321.332098)
		(end 446.5828 -317.442342)
		(width 0.1651)
		(layer "In7.Cu")
		(net "P5E_PEX3_STN4_TX_DP<64>")
	)
	(segment
		(start 445.238124 -315.426598)
		(end 442.00826 -311.8358)
		(width 0.1651)
		(layer "In7.Cu")
		(net "P5E_PEX3_STN4_TX_DP<64>")
	)
	(segment
		(start 431.93208 -305.019964)
		(end 423.755566 -305.019964)
		(width 0.1143)
		(layer "In7.Cu")
		(net "P5E_PEX3_STN4_TX_DP<64>")
	)
	(segment
		(start 440.675522 -348.29496)
		(end 440.675522 -347.667834)
		(width 0.1651)
		(layer "In7.Cu")
		(net "P5E_PEX3_STN4_TX_DP<64>")
	)
	(segment
		(start 431.9778 -305.065684)
		(end 431.93208 -305.019964)
		(width 0.1143)
		(layer "In7.Cu")
		(net "P5E_PEX3_STN4_TX_DP<64>")
	)
	(segment
		(start 423.52976 -304.564034)
		(end 423.41546 -304.449734)
		(width 0.1143)
		(layer "In7.Cu")
		(net "P5E_PEX3_STN4_TX_DP<64>")
	)
	(segment
		(start 446.5828 -317.442342)
		(end 445.238124 -315.426598)
		(width 0.1651)
		(layer "In7.Cu")
		(net "P5E_PEX3_STN4_TX_DP<64>")
	)
	(segment
		(start 440.384692 -348.58579)
		(end 440.675522 -348.29496)
		(width 0.1651)
		(layer "In7.Cu")
		(net "P5E_PEX3_STN4_TX_DP<64>")
	)
	(segment
		(start 436.701438 -306.528978)
		(end 433.16906 -305.065684)
		(width 0.1651)
		(layer "In7.Cu")
		(net "P5E_PEX3_STN4_TX_DP<64>")
	)
	(segment
		(start 423.41546 -304.449734)
		(end 423.15003 -304.449734)
		(width 0.1143)
		(layer "In7.Cu")
		(net "P5E_PEX3_STN4_TX_DP<64>")
	)
	(segment
		(start 433.16906 -305.065684)
		(end 432.006248 -305.065684)
		(width 0.1651)
		(layer "In7.Cu")
		(net "P5E_PEX3_STN4_TX_DP<64>")
	)
	(segment
		(start 423.755566 -305.019964)
		(end 423.52976 -304.794158)
		(width 0.1143)
		(layer "In7.Cu")
		(net "P5E_PEX3_STN4_TX_DP<64>")
	)
	(segment
		(start 442.230002 -346.113354)
		(end 447.13525 -321.332098)
		(width 0.1651)
		(layer "In7.Cu")
		(net "P5E_PEX3_STN4_TX_DP<64>")
	)
	(segment
		(start 440.675522 -347.667834)
		(end 442.230002 -346.113354)
		(width 0.1651)
		(layer "In7.Cu")
		(net "P5E_PEX3_STN4_TX_DP<64>")
	)
	(segment
		(start 423.52976 -304.794158)
		(end 423.52976 -304.564034)
		(width 0.1143)
		(layer "In7.Cu")
		(net "P5E_PEX3_STN4_TX_DP<64>")
	)
	(segment
		(start 432.006248 -305.065684)
		(end 431.9778 -305.065684)
		(width 0.1143)
		(layer "In7.Cu")
		(net "P5E_PEX3_STN4_TX_DP<64>")
	)
	(segment
		(start 409.589224 -348.879922)
		(end 409.295092 -348.58579)
		(width 0.13462)
		(layer "F.Cu")
		(net "P5E_PEX3_STN4_TX_DP<79>")
	)
	(segment
		(start 409.269692 -349.831914)
		(end 409.589224 -349.512382)
		(width 0.13462)
		(layer "F.Cu")
		(net "P5E_PEX3_STN4_TX_DP<79>")
	)
	(segment
		(start 409.589224 -349.512382)
		(end 409.589224 -348.879922)
		(width 0.13462)
		(layer "F.Cu")
		(net "P5E_PEX3_STN4_TX_DP<79>")
	)
	(segment
		(start 421.583866 -319.966848)
		(end 421.629586 -319.921128)
		(width 0.1143)
		(layer "In7.Cu")
		(net "P5E_PEX3_STN4_TX_DP<79>")
	)
	(segment
		(start 422.199816 -311.365392)
		(end 422.199816 -311.099962)
		(width 0.1143)
		(layer "In7.Cu")
		(net "P5E_PEX3_STN4_TX_DP<79>")
	)
	(segment
		(start 421.855392 -311.479692)
		(end 422.085516 -311.479692)
		(width 0.1143)
		(layer "In7.Cu")
		(net "P5E_PEX3_STN4_TX_DP<79>")
	)
	(segment
		(start 421.335962 -321.651376)
		(end 421.583866 -320.640456)
		(width 0.1651)
		(layer "In7.Cu")
		(net "P5E_PEX3_STN4_TX_DP<79>")
	)
	(segment
		(start 421.583866 -319.995296)
		(end 421.583866 -319.966848)
		(width 0.1143)
		(layer "In7.Cu")
		(net "P5E_PEX3_STN4_TX_DP<79>")
	)
	(segment
		(start 411.140402 -341.20201)
		(end 421.335962 -321.651376)
		(width 0.1651)
		(layer "In7.Cu")
		(net "P5E_PEX3_STN4_TX_DP<79>")
	)
	(segment
		(start 409.585922 -348.29496)
		(end 409.585922 -347.667834)
		(width 0.1651)
		(layer "In7.Cu")
		(net "P5E_PEX3_STN4_TX_DP<79>")
	)
	(segment
		(start 421.629586 -311.705498)
		(end 421.855392 -311.479692)
		(width 0.1143)
		(layer "In7.Cu")
		(net "P5E_PEX3_STN4_TX_DP<79>")
	)
	(segment
		(start 421.583866 -320.640456)
		(end 421.583866 -319.995296)
		(width 0.1651)
		(layer "In7.Cu")
		(net "P5E_PEX3_STN4_TX_DP<79>")
	)
	(segment
		(start 421.629586 -319.921128)
		(end 421.629586 -311.705498)
		(width 0.1143)
		(layer "In7.Cu")
		(net "P5E_PEX3_STN4_TX_DP<79>")
	)
	(segment
		(start 411.140402 -346.113354)
		(end 411.140402 -341.20201)
		(width 0.1651)
		(layer "In7.Cu")
		(net "P5E_PEX3_STN4_TX_DP<79>")
	)
	(segment
		(start 409.295092 -348.58579)
		(end 409.585922 -348.29496)
		(width 0.1651)
		(layer "In7.Cu")
		(net "P5E_PEX3_STN4_TX_DP<79>")
	)
	(segment
		(start 422.085516 -311.479692)
		(end 422.199816 -311.365392)
		(width 0.1143)
		(layer "In7.Cu")
		(net "P5E_PEX3_STN4_TX_DP<79>")
	)
	(segment
		(start 409.585922 -347.667834)
		(end 411.140402 -346.113354)
		(width 0.1651)
		(layer "In7.Cu")
		(net "P5E_PEX3_STN4_TX_DP<79>")
	)
	(segment
		(start 428.242984 -349.512382)
		(end 428.242984 -348.879922)
		(width 0.13462)
		(layer "F.Cu")
		(net "P5E_PEX3_STN4_TX_DP<70>")
	)
	(segment
		(start 427.923452 -349.831914)
		(end 428.242984 -349.512382)
		(width 0.13462)
		(layer "F.Cu")
		(net "P5E_PEX3_STN4_TX_DP<70>")
	)
	(segment
		(start 428.242984 -348.879922)
		(end 427.948852 -348.58579)
		(width 0.13462)
		(layer "F.Cu")
		(net "P5E_PEX3_STN4_TX_DP<70>")
	)
	(segment
		(start 427.948852 -348.58579)
		(end 428.239682 -348.29496)
		(width 0.1651)
		(layer "In7.Cu")
		(net "P5E_PEX3_STN4_TX_DP<70>")
	)
	(segment
		(start 431.604928 -313.190128)
		(end 431.240946 -312.826146)
		(width 0.1651)
		(layer "In7.Cu")
		(net "P5E_PEX3_STN4_TX_DP<70>")
	)
	(segment
		(start 430.179734 -312.420762)
		(end 430.179734 -312.164222)
		(width 0.1143)
		(layer "In7.Cu")
		(net "P5E_PEX3_STN4_TX_DP<70>")
	)
	(segment
		(start 431.696114 -320.74104)
		(end 432.1556 -318.264794)
		(width 0.1651)
		(layer "In7.Cu")
		(net "P5E_PEX3_STN4_TX_DP<70>")
	)
	(segment
		(start 431.22088 -312.80608)
		(end 431.22088 -312.747152)
		(width 0.1143)
		(layer "In7.Cu")
		(net "P5E_PEX3_STN4_TX_DP<70>")
	)
	(segment
		(start 429.794162 -341.695786)
		(end 431.696114 -320.74104)
		(width 0.1651)
		(layer "In7.Cu")
		(net "P5E_PEX3_STN4_TX_DP<70>")
	)
	(segment
		(start 428.239682 -347.667834)
		(end 429.794162 -346.113354)
		(width 0.1651)
		(layer "In7.Cu")
		(net "P5E_PEX3_STN4_TX_DP<70>")
	)
	(segment
		(start 431.22088 -312.747152)
		(end 431.09388 -312.620152)
		(width 0.1143)
		(layer "In7.Cu")
		(net "P5E_PEX3_STN4_TX_DP<70>")
	)
	(segment
		(start 431.09388 -312.620152)
		(end 430.379124 -312.620152)
		(width 0.1143)
		(layer "In7.Cu")
		(net "P5E_PEX3_STN4_TX_DP<70>")
	)
	(segment
		(start 428.239682 -348.29496)
		(end 428.239682 -347.667834)
		(width 0.1651)
		(layer "In7.Cu")
		(net "P5E_PEX3_STN4_TX_DP<70>")
	)
	(segment
		(start 430.065434 -312.049922)
		(end 429.800004 -312.049922)
		(width 0.1143)
		(layer "In7.Cu")
		(net "P5E_PEX3_STN4_TX_DP<70>")
	)
	(segment
		(start 430.179734 -312.164222)
		(end 430.065434 -312.049922)
		(width 0.1143)
		(layer "In7.Cu")
		(net "P5E_PEX3_STN4_TX_DP<70>")
	)
	(segment
		(start 430.379124 -312.620152)
		(end 430.179734 -312.420762)
		(width 0.1143)
		(layer "In7.Cu")
		(net "P5E_PEX3_STN4_TX_DP<70>")
	)
	(segment
		(start 431.240946 -312.826146)
		(end 431.22088 -312.80608)
		(width 0.1143)
		(layer "In7.Cu")
		(net "P5E_PEX3_STN4_TX_DP<70>")
	)
	(segment
		(start 429.794162 -346.113354)
		(end 429.794162 -341.695786)
		(width 0.1651)
		(layer "In7.Cu")
		(net "P5E_PEX3_STN4_TX_DP<70>")
	)
	(segment
		(start 432.1556 -318.264794)
		(end 432.1556 -314.519564)
		(width 0.1651)
		(layer "In7.Cu")
		(net "P5E_PEX3_STN4_TX_DP<70>")
	)
	(segment
		(start 432.1556 -314.519564)
		(end 431.604928 -313.190128)
		(width 0.1651)
		(layer "In7.Cu")
		(net "P5E_PEX3_STN4_TX_DP<70>")
	)
	(segment
		(start 418.916104 -355.658674)
		(end 418.916104 -355.026214)
		(width 0.13462)
		(layer "F.Cu")
		(net "P5E_PEX3_STN4_TX_DP<74>")
	)
	(segment
		(start 418.916104 -355.026214)
		(end 418.621972 -354.732082)
		(width 0.13462)
		(layer "F.Cu")
		(net "P5E_PEX3_STN4_TX_DP<74>")
	)
	(segment
		(start 418.596572 -355.978206)
		(end 418.916104 -355.658674)
		(width 0.13462)
		(layer "F.Cu")
		(net "P5E_PEX3_STN4_TX_DP<74>")
	)
	(segment
		(start 418.912802 -353.814126)
		(end 420.467282 -352.259646)
		(width 0.1651)
		(layer "In7.Cu")
		(net "P5E_PEX3_STN4_TX_DP<74>")
	)
	(segment
		(start 426.83557 -313.379612)
		(end 426.94987 -313.265312)
		(width 0.1143)
		(layer "In7.Cu")
		(net "P5E_PEX3_STN4_TX_DP<74>")
	)
	(segment
		(start 426.140118 -322.81495)
		(end 426.33392 -321.49923)
		(width 0.1651)
		(layer "In7.Cu")
		(net "P5E_PEX3_STN4_TX_DP<74>")
	)
	(segment
		(start 426.94987 -313.265312)
		(end 426.94987 -312.999882)
		(width 0.1143)
		(layer "In7.Cu")
		(net "P5E_PEX3_STN4_TX_DP<74>")
	)
	(segment
		(start 426.33392 -319.909952)
		(end 426.37964 -319.864232)
		(width 0.1143)
		(layer "In7.Cu")
		(net "P5E_PEX3_STN4_TX_DP<74>")
	)
	(segment
		(start 418.912802 -354.441252)
		(end 418.912802 -353.814126)
		(width 0.1651)
		(layer "In7.Cu")
		(net "P5E_PEX3_STN4_TX_DP<74>")
	)
	(segment
		(start 426.33392 -319.9384)
		(end 426.33392 -319.909952)
		(width 0.1143)
		(layer "In7.Cu")
		(net "P5E_PEX3_STN4_TX_DP<74>")
	)
	(segment
		(start 420.467282 -341.68334)
		(end 426.140118 -322.81495)
		(width 0.1651)
		(layer "In7.Cu")
		(net "P5E_PEX3_STN4_TX_DP<74>")
	)
	(segment
		(start 426.33392 -321.49923)
		(end 426.33392 -319.9384)
		(width 0.1651)
		(layer "In7.Cu")
		(net "P5E_PEX3_STN4_TX_DP<74>")
	)
	(segment
		(start 426.37964 -313.605418)
		(end 426.605446 -313.379612)
		(width 0.1143)
		(layer "In7.Cu")
		(net "P5E_PEX3_STN4_TX_DP<74>")
	)
	(segment
		(start 426.37964 -319.864232)
		(end 426.37964 -313.605418)
		(width 0.1143)
		(layer "In7.Cu")
		(net "P5E_PEX3_STN4_TX_DP<74>")
	)
	(segment
		(start 420.467282 -352.259646)
		(end 420.467282 -341.68334)
		(width 0.1651)
		(layer "In7.Cu")
		(net "P5E_PEX3_STN4_TX_DP<74>")
	)
	(segment
		(start 418.621972 -354.732082)
		(end 418.912802 -354.441252)
		(width 0.1651)
		(layer "In7.Cu")
		(net "P5E_PEX3_STN4_TX_DP<74>")
	)
	(segment
		(start 426.605446 -313.379612)
		(end 426.83557 -313.379612)
		(width 0.1143)
		(layer "In7.Cu")
		(net "P5E_PEX3_STN4_TX_DP<74>")
	)
	(segment
		(start 431.351944 -355.658674)
		(end 431.351944 -355.026214)
		(width 0.13462)
		(layer "F.Cu")
		(net "P5E_PEX3_STN4_TX_DP<68>")
	)
	(segment
		(start 431.351944 -355.026214)
		(end 431.057812 -354.732082)
		(width 0.13462)
		(layer "F.Cu")
		(net "P5E_PEX3_STN4_TX_DP<68>")
	)
	(segment
		(start 431.032412 -355.978206)
		(end 431.351944 -355.658674)
		(width 0.13462)
		(layer "F.Cu")
		(net "P5E_PEX3_STN4_TX_DP<68>")
	)
	(segment
		(start 432.71186 -309.06974)
		(end 432.219354 -308.865778)
		(width 0.1651)
		(layer "In7.Cu")
		(net "P5E_PEX3_STN4_TX_DP<68>")
	)
	(segment
		(start 431.980848 -308.865778)
		(end 431.9524 -308.865778)
		(width 0.1143)
		(layer "In7.Cu")
		(net "P5E_PEX3_STN4_TX_DP<68>")
	)
	(segment
		(start 431.9524 -308.865778)
		(end 431.90668 -308.820058)
		(width 0.1143)
		(layer "In7.Cu")
		(net "P5E_PEX3_STN4_TX_DP<68>")
	)
	(segment
		(start 431.348642 -354.441252)
		(end 431.348642 -353.814126)
		(width 0.1651)
		(layer "In7.Cu")
		(net "P5E_PEX3_STN4_TX_DP<68>")
	)
	(segment
		(start 423.41546 -308.249828)
		(end 423.15003 -308.249828)
		(width 0.1143)
		(layer "In7.Cu")
		(net "P5E_PEX3_STN4_TX_DP<68>")
	)
	(segment
		(start 423.52976 -308.364128)
		(end 423.41546 -308.249828)
		(width 0.1143)
		(layer "In7.Cu")
		(net "P5E_PEX3_STN4_TX_DP<68>")
	)
	(segment
		(start 442.67374 -322.99148)
		(end 443.05982 -321.12458)
		(width 0.1651)
		(layer "In7.Cu")
		(net "P5E_PEX3_STN4_TX_DP<68>")
	)
	(segment
		(start 438.62244 -314.98032)
		(end 432.71186 -309.06974)
		(width 0.1651)
		(layer "In7.Cu")
		(net "P5E_PEX3_STN4_TX_DP<68>")
	)
	(segment
		(start 432.903122 -341.672926)
		(end 442.67374 -322.99148)
		(width 0.1651)
		(layer "In7.Cu")
		(net "P5E_PEX3_STN4_TX_DP<68>")
	)
	(segment
		(start 431.348642 -353.814126)
		(end 432.903122 -352.259646)
		(width 0.1651)
		(layer "In7.Cu")
		(net "P5E_PEX3_STN4_TX_DP<68>")
	)
	(segment
		(start 431.90668 -308.820058)
		(end 423.755566 -308.820058)
		(width 0.1143)
		(layer "In7.Cu")
		(net "P5E_PEX3_STN4_TX_DP<68>")
	)
	(segment
		(start 443.05982 -321.12458)
		(end 442.76518 -318.8589)
		(width 0.1651)
		(layer "In7.Cu")
		(net "P5E_PEX3_STN4_TX_DP<68>")
	)
	(segment
		(start 432.219354 -308.865778)
		(end 431.980848 -308.865778)
		(width 0.1651)
		(layer "In7.Cu")
		(net "P5E_PEX3_STN4_TX_DP<68>")
	)
	(segment
		(start 423.52976 -308.594252)
		(end 423.52976 -308.364128)
		(width 0.1143)
		(layer "In7.Cu")
		(net "P5E_PEX3_STN4_TX_DP<68>")
	)
	(segment
		(start 432.903122 -352.259646)
		(end 432.903122 -341.672926)
		(width 0.1651)
		(layer "In7.Cu")
		(net "P5E_PEX3_STN4_TX_DP<68>")
	)
	(segment
		(start 441.82792 -317.5381)
		(end 438.62244 -314.98032)
		(width 0.1651)
		(layer "In7.Cu")
		(net "P5E_PEX3_STN4_TX_DP<68>")
	)
	(segment
		(start 442.76518 -318.8589)
		(end 441.82792 -317.5381)
		(width 0.1651)
		(layer "In7.Cu")
		(net "P5E_PEX3_STN4_TX_DP<68>")
	)
	(segment
		(start 423.755566 -308.820058)
		(end 423.52976 -308.594252)
		(width 0.1143)
		(layer "In7.Cu")
		(net "P5E_PEX3_STN4_TX_DP<68>")
	)
	(segment
		(start 431.057812 -354.732082)
		(end 431.348642 -354.441252)
		(width 0.1651)
		(layer "In7.Cu")
		(net "P5E_PEX3_STN4_TX_DP<68>")
	)
	(segment
		(start 438.164732 -355.978206)
		(end 437.844184 -355.657658)
		(width 0.13462)
		(layer "F.Cu")
		(net "P5E_PEX3_STN4_TX_DN<65>")
	)
	(segment
		(start 437.844184 -355.02723)
		(end 438.139332 -354.732082)
		(width 0.13462)
		(layer "F.Cu")
		(net "P5E_PEX3_STN4_TX_DN<65>")
	)
	(segment
		(start 437.844184 -355.657658)
		(end 437.844184 -355.02723)
		(width 0.13462)
		(layer "F.Cu")
		(net "P5E_PEX3_STN4_TX_DN<65>")
	)
	(segment
		(start 432.970432 -305.733958)
		(end 431.958496 -305.733958)
		(width 0.1651)
		(layer "In7.Cu")
		(net "P5E_PEX3_STN4_TX_DN<65>")
	)
	(segment
		(start 437.848502 -354.441252)
		(end 437.848502 -353.930966)
		(width 0.1651)
		(layer "In7.Cu")
		(net "P5E_PEX3_STN4_TX_DN<65>")
	)
	(segment
		(start 439.402982 -352.376486)
		(end 439.402982 -341.712296)
		(width 0.1651)
		(layer "In7.Cu")
		(net "P5E_PEX3_STN4_TX_DN<65>")
	)
	(segment
		(start 431.930048 -305.733958)
		(end 431.884328 -305.779678)
		(width 0.1143)
		(layer "In7.Cu")
		(net "P5E_PEX3_STN4_TX_DN<65>")
	)
	(segment
		(start 445.900556 -317.680848)
		(end 444.335408 -315.445648)
		(width 0.1651)
		(layer "In7.Cu")
		(net "P5E_PEX3_STN4_TX_DN<65>")
	)
	(segment
		(start 425.73448 -305.779678)
		(end 425.62018 -305.665378)
		(width 0.1143)
		(layer "In7.Cu")
		(net "P5E_PEX3_STN4_TX_DN<65>")
	)
	(segment
		(start 438.139332 -354.732082)
		(end 437.848502 -354.441252)
		(width 0.1651)
		(layer "In7.Cu")
		(net "P5E_PEX3_STN4_TX_DN<65>")
	)
	(segment
		(start 444.335408 -315.445648)
		(end 441.563252 -312.371232)
		(width 0.1651)
		(layer "In7.Cu")
		(net "P5E_PEX3_STN4_TX_DN<65>")
	)
	(segment
		(start 436.308754 -307.116734)
		(end 432.970432 -305.733958)
		(width 0.1651)
		(layer "In7.Cu")
		(net "P5E_PEX3_STN4_TX_DN<65>")
	)
	(segment
		(start 431.958496 -305.733958)
		(end 431.930048 -305.733958)
		(width 0.1143)
		(layer "In7.Cu")
		(net "P5E_PEX3_STN4_TX_DN<65>")
	)
	(segment
		(start 439.402982 -341.712296)
		(end 445.806322 -323.883782)
		(width 0.1651)
		(layer "In7.Cu")
		(net "P5E_PEX3_STN4_TX_DN<65>")
	)
	(segment
		(start 431.884328 -305.779678)
		(end 425.73448 -305.779678)
		(width 0.1143)
		(layer "In7.Cu")
		(net "P5E_PEX3_STN4_TX_DN<65>")
	)
	(segment
		(start 445.81318 -323.864478)
		(end 445.81699 -323.846444)
		(width 0.1651)
		(layer "In7.Cu")
		(net "P5E_PEX3_STN4_TX_DN<65>")
	)
	(segment
		(start 445.806322 -323.883782)
		(end 445.807084 -323.881496)
		(width 0.1651)
		(layer "In7.Cu")
		(net "P5E_PEX3_STN4_TX_DN<65>")
	)
	(segment
		(start 437.848502 -353.930966)
		(end 439.402982 -352.376486)
		(width 0.1651)
		(layer "In7.Cu")
		(net "P5E_PEX3_STN4_TX_DN<65>")
	)
	(segment
		(start 445.81699 -323.846444)
		(end 446.368424 -321.314826)
		(width 0.1651)
		(layer "In7.Cu")
		(net "P5E_PEX3_STN4_TX_DN<65>")
	)
	(segment
		(start 425.62018 -305.514248)
		(end 425.73448 -305.399948)
		(width 0.1143)
		(layer "In7.Cu")
		(net "P5E_PEX3_STN4_TX_DN<65>")
	)
	(segment
		(start 441.563252 -312.371232)
		(end 436.308754 -307.116734)
		(width 0.1651)
		(layer "In7.Cu")
		(net "P5E_PEX3_STN4_TX_DN<65>")
	)
	(segment
		(start 425.73448 -305.399948)
		(end 425.99991 -305.399948)
		(width 0.1143)
		(layer "In7.Cu")
		(net "P5E_PEX3_STN4_TX_DN<65>")
	)
	(segment
		(start 446.368424 -321.314826)
		(end 445.900556 -317.680848)
		(width 0.1651)
		(layer "In7.Cu")
		(net "P5E_PEX3_STN4_TX_DN<65>")
	)
	(segment
		(start 425.62018 -305.665378)
		(end 425.62018 -305.514248)
		(width 0.1143)
		(layer "In7.Cu")
		(net "P5E_PEX3_STN4_TX_DN<65>")
	)
	(segment
		(start 445.807084 -323.881496)
		(end 445.81318 -323.864478)
		(width 0.1651)
		(layer "In7.Cu")
		(net "P5E_PEX3_STN4_TX_DN<65>")
	)
	(segment
		(start 437.844184 -343.365074)
		(end 437.844184 -342.734646)
		(width 0.13462)
		(layer "F.Cu")
		(net "P5E_PEX3_STN4_TX_DN<66>")
	)
	(segment
		(start 438.164732 -343.685622)
		(end 437.844184 -343.365074)
		(width 0.13462)
		(layer "F.Cu")
		(net "P5E_PEX3_STN4_TX_DN<66>")
	)
	(segment
		(start 437.844184 -342.734646)
		(end 438.139332 -342.439498)
		(width 0.13462)
		(layer "F.Cu")
		(net "P5E_PEX3_STN4_TX_DN<66>")
	)
	(segment
		(start 434.120544 -307.260244)
		(end 432.729386 -306.683918)
		(width 0.1651)
		(layer "In7.Cu")
		(net "P5E_PEX3_STN4_TX_DN<66>")
	)
	(segment
		(start 439.957464 -313.097164)
		(end 434.120544 -307.260244)
		(width 0.1651)
		(layer "In7.Cu")
		(net "P5E_PEX3_STN4_TX_DN<66>")
	)
	(segment
		(start 443.501272 -315.99759)
		(end 439.957464 -313.097164)
		(width 0.1651)
		(layer "In7.Cu")
		(net "P5E_PEX3_STN4_TX_DN<66>")
	)
	(segment
		(start 444.892684 -323.57822)
		(end 445.382904 -321.257676)
		(width 0.1651)
		(layer "In7.Cu")
		(net "P5E_PEX3_STN4_TX_DN<66>")
	)
	(segment
		(start 423.83456 -306.349908)
		(end 424.09999 -306.349908)
		(width 0.1143)
		(layer "In7.Cu")
		(net "P5E_PEX3_STN4_TX_DN<66>")
	)
	(segment
		(start 444.96101 -318.046354)
		(end 443.501272 -315.99759)
		(width 0.1651)
		(layer "In7.Cu")
		(net "P5E_PEX3_STN4_TX_DN<66>")
	)
	(segment
		(start 431.833528 -306.729638)
		(end 423.83456 -306.729638)
		(width 0.1143)
		(layer "In7.Cu")
		(net "P5E_PEX3_STN4_TX_DN<66>")
	)
	(segment
		(start 423.72026 -306.464208)
		(end 423.83456 -306.349908)
		(width 0.1143)
		(layer "In7.Cu")
		(net "P5E_PEX3_STN4_TX_DN<66>")
	)
	(segment
		(start 431.907696 -306.683918)
		(end 431.879248 -306.683918)
		(width 0.1143)
		(layer "In7.Cu")
		(net "P5E_PEX3_STN4_TX_DN<66>")
	)
	(segment
		(start 444.888112 -323.600826)
		(end 444.892684 -323.57822)
		(width 0.1651)
		(layer "In7.Cu")
		(net "P5E_PEX3_STN4_TX_DN<66>")
	)
	(segment
		(start 432.729386 -306.683918)
		(end 431.907696 -306.683918)
		(width 0.1651)
		(layer "In7.Cu")
		(net "P5E_PEX3_STN4_TX_DN<66>")
	)
	(segment
		(start 438.139332 -342.439498)
		(end 437.848502 -342.148668)
		(width 0.1651)
		(layer "In7.Cu")
		(net "P5E_PEX3_STN4_TX_DN<66>")
	)
	(segment
		(start 437.848502 -342.148668)
		(end 437.848502 -341.671148)
		(width 0.1651)
		(layer "In7.Cu")
		(net "P5E_PEX3_STN4_TX_DN<66>")
	)
	(segment
		(start 437.848502 -341.671148)
		(end 444.888112 -323.600826)
		(width 0.1651)
		(layer "In7.Cu")
		(net "P5E_PEX3_STN4_TX_DN<66>")
	)
	(segment
		(start 431.879248 -306.683918)
		(end 431.833528 -306.729638)
		(width 0.1143)
		(layer "In7.Cu")
		(net "P5E_PEX3_STN4_TX_DN<66>")
	)
	(segment
		(start 445.382904 -321.257676)
		(end 444.96101 -318.046354)
		(width 0.1651)
		(layer "In7.Cu")
		(net "P5E_PEX3_STN4_TX_DN<66>")
	)
	(segment
		(start 423.72026 -306.615338)
		(end 423.72026 -306.464208)
		(width 0.1143)
		(layer "In7.Cu")
		(net "P5E_PEX3_STN4_TX_DN<66>")
	)
	(segment
		(start 423.83456 -306.729638)
		(end 423.72026 -306.615338)
		(width 0.1143)
		(layer "In7.Cu")
		(net "P5E_PEX3_STN4_TX_DN<66>")
	)
	(segment
		(start 419.510972 -355.978206)
		(end 419.190424 -355.657658)
		(width 0.13462)
		(layer "F.Cu")
		(net "P5E_PEX3_STN4_TX_DN<74>")
	)
	(segment
		(start 419.190424 -355.657658)
		(end 419.190424 -355.02723)
		(width 0.13462)
		(layer "F.Cu")
		(net "P5E_PEX3_STN4_TX_DN<74>")
	)
	(segment
		(start 419.190424 -355.02723)
		(end 419.485572 -354.732082)
		(width 0.13462)
		(layer "F.Cu")
		(net "P5E_PEX3_STN4_TX_DN<74>")
	)
	(segment
		(start 426.61586 -319.9384)
		(end 426.61586 -319.909952)
		(width 0.1143)
		(layer "In7.Cu")
		(net "P5E_PEX3_STN4_TX_DN<74>")
	)
	(segment
		(start 426.57014 -313.684412)
		(end 426.68444 -313.570112)
		(width 0.1143)
		(layer "In7.Cu")
		(net "P5E_PEX3_STN4_TX_DN<74>")
	)
	(segment
		(start 426.94987 -313.684412)
		(end 426.94987 -313.949842)
		(width 0.1143)
		(layer "In7.Cu")
		(net "P5E_PEX3_STN4_TX_DN<74>")
	)
	(segment
		(start 426.416216 -322.876418)
		(end 426.61586 -321.520058)
		(width 0.1651)
		(layer "In7.Cu")
		(net "P5E_PEX3_STN4_TX_DN<74>")
	)
	(segment
		(start 426.83557 -313.570112)
		(end 426.94987 -313.684412)
		(width 0.1143)
		(layer "In7.Cu")
		(net "P5E_PEX3_STN4_TX_DN<74>")
	)
	(segment
		(start 426.61586 -319.909952)
		(end 426.57014 -319.864232)
		(width 0.1143)
		(layer "In7.Cu")
		(net "P5E_PEX3_STN4_TX_DN<74>")
	)
	(segment
		(start 426.61586 -321.520058)
		(end 426.61586 -319.9384)
		(width 0.1651)
		(layer "In7.Cu")
		(net "P5E_PEX3_STN4_TX_DN<74>")
	)
	(segment
		(start 419.485572 -354.732082)
		(end 419.194742 -354.441252)
		(width 0.1651)
		(layer "In7.Cu")
		(net "P5E_PEX3_STN4_TX_DN<74>")
	)
	(segment
		(start 426.57014 -319.864232)
		(end 426.57014 -313.684412)
		(width 0.1143)
		(layer "In7.Cu")
		(net "P5E_PEX3_STN4_TX_DN<74>")
	)
	(segment
		(start 420.749222 -352.376486)
		(end 420.749222 -341.724996)
		(width 0.1651)
		(layer "In7.Cu")
		(net "P5E_PEX3_STN4_TX_DN<74>")
	)
	(segment
		(start 420.749222 -341.724996)
		(end 426.416216 -322.876418)
		(width 0.1651)
		(layer "In7.Cu")
		(net "P5E_PEX3_STN4_TX_DN<74>")
	)
	(segment
		(start 419.194742 -354.441252)
		(end 419.194742 -353.930966)
		(width 0.1651)
		(layer "In7.Cu")
		(net "P5E_PEX3_STN4_TX_DN<74>")
	)
	(segment
		(start 426.68444 -313.570112)
		(end 426.83557 -313.570112)
		(width 0.1143)
		(layer "In7.Cu")
		(net "P5E_PEX3_STN4_TX_DN<74>")
	)
	(segment
		(start 419.194742 -353.930966)
		(end 420.749222 -352.376486)
		(width 0.1651)
		(layer "In7.Cu")
		(net "P5E_PEX3_STN4_TX_DN<74>")
	)
	(segment
		(start 421.705532 -350.365314)
		(end 422.02608 -350.685862)
		(width 0.13462)
		(layer "F.Cu")
		(net "P5E_PEX3_STN4_TX_C_DP<73>")
	)
	(segment
		(start 422.02608 -351.31629)
		(end 421.730932 -351.611438)
		(width 0.13462)
		(layer "F.Cu")
		(net "P5E_PEX3_STN4_TX_C_DP<73>")
	)
	(segment
		(start 422.02608 -350.685862)
		(end 422.02608 -351.31629)
		(width 0.13462)
		(layer "F.Cu")
		(net "P5E_PEX3_STN4_TX_C_DP<73>")
	)
	(segment
		(start 422.021762 -351.902268)
		(end 421.730932 -351.611438)
		(width 0.1651)
		(layer "In7.Cu")
		(net "P5E_PEX3_STN4_TX_C_DP<73>")
	)
	(segment
		(start 432.55311 -394.043662)
		(end 432.415442 -394.084556)
		(width 0.1651)
		(layer "In7.Cu")
		(net "P5E_PEX3_STN4_TX_C_DP<73>")
	)
	(segment
		(start 433.247038 -396.999206)
		(end 433.533804 -396.71244)
		(width 0.1651)
		(layer "In7.Cu")
		(net "P5E_PEX3_STN4_TX_C_DP<73>")
	)
	(segment
		(start 432.689762 -396.49019)
		(end 432.689762 -396.872206)
		(width 0.1651)
		(layer "In7.Cu")
		(net "P5E_PEX3_STN4_TX_C_DP<73>")
	)
	(segment
		(start 431.979578 -393.84859)
		(end 431.938684 -393.710668)
		(width 0.1651)
		(layer "In7.Cu")
		(net "P5E_PEX3_STN4_TX_C_DP<73>")
	)
	(segment
		(start 433.533804 -394.732764)
		(end 433.189126 -394.388086)
		(width 0.1651)
		(layer "In7.Cu")
		(net "P5E_PEX3_STN4_TX_C_DP<73>")
	)
	(segment
		(start 432.816762 -396.999206)
		(end 433.247038 -396.999206)
		(width 0.1651)
		(layer "In7.Cu")
		(net "P5E_PEX3_STN4_TX_C_DP<73>")
	)
	(segment
		(start 417.277042 -385.027678)
		(end 416.826954 -383.496566)
		(width 0.1651)
		(layer "In7.Cu")
		(net "P5E_PEX3_STN4_TX_C_DP<73>")
	)
	(segment
		(start 433.189126 -394.388086)
		(end 432.55311 -394.043662)
		(width 0.1651)
		(layer "In7.Cu")
		(net "P5E_PEX3_STN4_TX_C_DP<73>")
	)
	(segment
		(start 431.938684 -393.710668)
		(end 431.938684 -393.710922)
		(width 0.1651)
		(layer "In7.Cu")
		(net "P5E_PEX3_STN4_TX_C_DP<73>")
	)
	(segment
		(start 431.938684 -393.710922)
		(end 431.503328 -393.47521)
		(width 0.1651)
		(layer "In7.Cu")
		(net "P5E_PEX3_STN4_TX_C_DP<73>")
	)
	(segment
		(start 417.115244 -369.392962)
		(end 420.467282 -358.777032)
		(width 0.1651)
		(layer "In7.Cu")
		(net "P5E_PEX3_STN4_TX_C_DP<73>")
	)
	(segment
		(start 416.826954 -383.496566)
		(end 417.115244 -369.392962)
		(width 0.1651)
		(layer "In7.Cu")
		(net "P5E_PEX3_STN4_TX_C_DP<73>")
	)
	(segment
		(start 433.533804 -396.71244)
		(end 433.533804 -394.732764)
		(width 0.1651)
		(layer "In7.Cu")
		(net "P5E_PEX3_STN4_TX_C_DP<73>")
	)
	(segment
		(start 431.503328 -393.47521)
		(end 431.503328 -393.474956)
		(width 0.1651)
		(layer "In7.Cu")
		(net "P5E_PEX3_STN4_TX_C_DP<73>")
	)
	(segment
		(start 432.689762 -396.872206)
		(end 432.816762 -396.999206)
		(width 0.1651)
		(layer "In7.Cu")
		(net "P5E_PEX3_STN4_TX_C_DP<73>")
	)
	(segment
		(start 422.021762 -352.356166)
		(end 422.021762 -351.902268)
		(width 0.1651)
		(layer "In7.Cu")
		(net "P5E_PEX3_STN4_TX_C_DP<73>")
	)
	(segment
		(start 430.888902 -393.141962)
		(end 430.888648 -393.142216)
		(width 0.1651)
		(layer "In7.Cu")
		(net "P5E_PEX3_STN4_TX_C_DP<73>")
	)
	(segment
		(start 430.929796 -393.27963)
		(end 430.888902 -393.141962)
		(width 0.1651)
		(layer "In7.Cu")
		(net "P5E_PEX3_STN4_TX_C_DP<73>")
	)
	(segment
		(start 420.467282 -358.777032)
		(end 420.467282 -353.910646)
		(width 0.1651)
		(layer "In7.Cu")
		(net "P5E_PEX3_STN4_TX_C_DP<73>")
	)
	(segment
		(start 431.503328 -393.474956)
		(end 431.36566 -393.51585)
		(width 0.1651)
		(layer "In7.Cu")
		(net "P5E_PEX3_STN4_TX_C_DP<73>")
	)
	(segment
		(start 431.36566 -393.51585)
		(end 430.929796 -393.27963)
		(width 0.1651)
		(layer "In7.Cu")
		(net "P5E_PEX3_STN4_TX_C_DP<73>")
	)
	(segment
		(start 420.467282 -353.910646)
		(end 422.021762 -352.356166)
		(width 0.1651)
		(layer "In7.Cu")
		(net "P5E_PEX3_STN4_TX_C_DP<73>")
	)
	(segment
		(start 432.415442 -394.084556)
		(end 431.979578 -393.84859)
		(width 0.1651)
		(layer "In7.Cu")
		(net "P5E_PEX3_STN4_TX_C_DP<73>")
	)
	(segment
		(start 418.109908 -386.22097)
		(end 417.277042 -385.027678)
		(width 0.1651)
		(layer "In7.Cu")
		(net "P5E_PEX3_STN4_TX_C_DP<73>")
	)
	(segment
		(start 430.888648 -393.142216)
		(end 418.109908 -386.22097)
		(width 0.1651)
		(layer "In7.Cu")
		(net "P5E_PEX3_STN4_TX_C_DP<73>")
	)
	(segment
		(start 434.460904 -349.512382)
		(end 434.460904 -348.879922)
		(width 0.13462)
		(layer "F.Cu")
		(net "P5E_PEX3_STN4_TX_DP<67>")
	)
	(segment
		(start 434.141372 -349.831914)
		(end 434.460904 -349.512382)
		(width 0.13462)
		(layer "F.Cu")
		(net "P5E_PEX3_STN4_TX_DP<67>")
	)
	(segment
		(start 434.460904 -348.879922)
		(end 434.166772 -348.58579)
		(width 0.13462)
		(layer "F.Cu")
		(net "P5E_PEX3_STN4_TX_DP<67>")
	)
	(segment
		(start 443.65926 -323.29628)
		(end 444.10122 -321.19824)
		(width 0.1651)
		(layer "In7.Cu")
		(net "P5E_PEX3_STN4_TX_DP<67>")
	)
	(segment
		(start 444.10122 -321.19824)
		(end 443.748668 -318.527684)
		(width 0.1651)
		(layer "In7.Cu")
		(net "P5E_PEX3_STN4_TX_DP<67>")
	)
	(segment
		(start 425.42968 -307.644292)
		(end 425.42968 -307.414168)
		(width 0.1143)
		(layer "In7.Cu")
		(net "P5E_PEX3_STN4_TX_DP<67>")
	)
	(segment
		(start 433.338224 -308.288944)
		(end 432.43754 -307.915818)
		(width 0.1651)
		(layer "In7.Cu")
		(net "P5E_PEX3_STN4_TX_DP<67>")
	)
	(segment
		(start 431.980848 -307.915818)
		(end 431.9524 -307.915818)
		(width 0.1143)
		(layer "In7.Cu")
		(net "P5E_PEX3_STN4_TX_DP<67>")
	)
	(segment
		(start 431.9524 -307.915818)
		(end 431.90668 -307.870098)
		(width 0.1143)
		(layer "In7.Cu")
		(net "P5E_PEX3_STN4_TX_DP<67>")
	)
	(segment
		(start 432.43754 -307.915818)
		(end 431.980848 -307.915818)
		(width 0.1651)
		(layer "In7.Cu")
		(net "P5E_PEX3_STN4_TX_DP<67>")
	)
	(segment
		(start 431.90668 -307.870098)
		(end 425.655486 -307.870098)
		(width 0.1143)
		(layer "In7.Cu")
		(net "P5E_PEX3_STN4_TX_DP<67>")
	)
	(segment
		(start 425.42968 -307.414168)
		(end 425.31538 -307.299868)
		(width 0.1143)
		(layer "In7.Cu")
		(net "P5E_PEX3_STN4_TX_DP<67>")
	)
	(segment
		(start 425.31538 -307.299868)
		(end 425.04995 -307.299868)
		(width 0.1143)
		(layer "In7.Cu")
		(net "P5E_PEX3_STN4_TX_DP<67>")
	)
	(segment
		(start 439.12282 -314.07354)
		(end 433.338224 -308.288944)
		(width 0.1651)
		(layer "In7.Cu")
		(net "P5E_PEX3_STN4_TX_DP<67>")
	)
	(segment
		(start 425.655486 -307.870098)
		(end 425.42968 -307.644292)
		(width 0.1143)
		(layer "In7.Cu")
		(net "P5E_PEX3_STN4_TX_DP<67>")
	)
	(segment
		(start 434.457602 -348.29496)
		(end 434.457602 -347.667834)
		(width 0.1651)
		(layer "In7.Cu")
		(net "P5E_PEX3_STN4_TX_DP<67>")
	)
	(segment
		(start 443.748668 -318.527684)
		(end 442.63564 -316.945264)
		(width 0.1651)
		(layer "In7.Cu")
		(net "P5E_PEX3_STN4_TX_DP<67>")
	)
	(segment
		(start 442.63564 -316.945264)
		(end 439.12282 -314.07354)
		(width 0.1651)
		(layer "In7.Cu")
		(net "P5E_PEX3_STN4_TX_DP<67>")
	)
	(segment
		(start 436.012082 -346.113354)
		(end 436.012082 -341.75446)
		(width 0.1651)
		(layer "In7.Cu")
		(net "P5E_PEX3_STN4_TX_DP<67>")
	)
	(segment
		(start 434.457602 -347.667834)
		(end 436.012082 -346.113354)
		(width 0.1651)
		(layer "In7.Cu")
		(net "P5E_PEX3_STN4_TX_DP<67>")
	)
	(segment
		(start 436.012082 -341.75446)
		(end 443.65926 -323.29628)
		(width 0.1651)
		(layer "In7.Cu")
		(net "P5E_PEX3_STN4_TX_DP<67>")
	)
	(segment
		(start 434.166772 -348.58579)
		(end 434.457602 -348.29496)
		(width 0.1651)
		(layer "In7.Cu")
		(net "P5E_PEX3_STN4_TX_DP<67>")
	)
	(segment
		(start 425.13504 -345.169998)
		(end 424.839892 -345.465146)
		(width 0.13462)
		(layer "F.Cu")
		(net "P5E_PEX3_STN4_TX_C_DP<72>")
	)
	(segment
		(start 424.814492 -344.219022)
		(end 425.13504 -344.53957)
		(width 0.13462)
		(layer "F.Cu")
		(net "P5E_PEX3_STN4_TX_C_DP<72>")
	)
	(segment
		(start 425.13504 -344.53957)
		(end 425.13504 -345.169998)
		(width 0.13462)
		(layer "F.Cu")
		(net "P5E_PEX3_STN4_TX_C_DP<72>")
	)
	(segment
		(start 417.885118 -383.44983)
		(end 418.15258 -369.374166)
		(width 0.1651)
		(layer "In7.Cu")
		(net "P5E_PEX3_STN4_TX_C_DP<72>")
	)
	(segment
		(start 434.88991 -397.59001)
		(end 434.88991 -397.97228)
		(width 0.1651)
		(layer "In7.Cu")
		(net "P5E_PEX3_STN4_TX_C_DP<72>")
	)
	(segment
		(start 433.906422 -393.569698)
		(end 433.769008 -393.611354)
		(width 0.1651)
		(layer "In7.Cu")
		(net "P5E_PEX3_STN4_TX_C_DP<72>")
	)
	(segment
		(start 435.240176 -394.83792)
		(end 434.889656 -394.4874)
		(width 0.1651)
		(layer "In7.Cu")
		(net "P5E_PEX3_STN4_TX_C_DP<72>")
	)
	(segment
		(start 425.130722 -346.209874)
		(end 425.130722 -345.755976)
		(width 0.1651)
		(layer "In7.Cu")
		(net "P5E_PEX3_STN4_TX_C_DP<72>")
	)
	(segment
		(start 434.889656 -394.343636)
		(end 434.35524 -393.80922)
		(width 0.1651)
		(layer "In7.Cu")
		(net "P5E_PEX3_STN4_TX_C_DP<72>")
	)
	(segment
		(start 418.15258 -369.374166)
		(end 423.576242 -358.702102)
		(width 0.1651)
		(layer "In7.Cu")
		(net "P5E_PEX3_STN4_TX_C_DP<72>")
	)
	(segment
		(start 433.289964 -393.24026)
		(end 418.77361 -385.488434)
		(width 0.1651)
		(layer "In7.Cu")
		(net "P5E_PEX3_STN4_TX_C_DP<72>")
	)
	(segment
		(start 423.576242 -358.702102)
		(end 423.576242 -347.764354)
		(width 0.1651)
		(layer "In7.Cu")
		(net "P5E_PEX3_STN4_TX_C_DP<72>")
	)
	(segment
		(start 418.77361 -385.488434)
		(end 418.212524 -384.676142)
		(width 0.1651)
		(layer "In7.Cu")
		(net "P5E_PEX3_STN4_TX_C_DP<72>")
	)
	(segment
		(start 434.88991 -397.97228)
		(end 435.01691 -398.09928)
		(width 0.1651)
		(layer "In7.Cu")
		(net "P5E_PEX3_STN4_TX_C_DP<72>")
	)
	(segment
		(start 435.733952 -397.812514)
		(end 435.733952 -395.187932)
		(width 0.1651)
		(layer "In7.Cu")
		(net "P5E_PEX3_STN4_TX_C_DP<72>")
	)
	(segment
		(start 423.576242 -347.764354)
		(end 425.130722 -346.209874)
		(width 0.1651)
		(layer "In7.Cu")
		(net "P5E_PEX3_STN4_TX_C_DP<72>")
	)
	(segment
		(start 418.212524 -384.676142)
		(end 417.885118 -383.44983)
		(width 0.1651)
		(layer "In7.Cu")
		(net "P5E_PEX3_STN4_TX_C_DP<72>")
	)
	(segment
		(start 434.35524 -393.80922)
		(end 433.906422 -393.569698)
		(width 0.1651)
		(layer "In7.Cu")
		(net "P5E_PEX3_STN4_TX_C_DP<72>")
	)
	(segment
		(start 435.01691 -398.09928)
		(end 435.447186 -398.09928)
		(width 0.1651)
		(layer "In7.Cu")
		(net "P5E_PEX3_STN4_TX_C_DP<72>")
	)
	(segment
		(start 433.331874 -393.377674)
		(end 433.289964 -393.24026)
		(width 0.1651)
		(layer "In7.Cu")
		(net "P5E_PEX3_STN4_TX_C_DP<72>")
	)
	(segment
		(start 435.447186 -398.09928)
		(end 435.733952 -397.812514)
		(width 0.1651)
		(layer "In7.Cu")
		(net "P5E_PEX3_STN4_TX_C_DP<72>")
	)
	(segment
		(start 435.733952 -395.187932)
		(end 435.38394 -394.83792)
		(width 0.1651)
		(layer "In7.Cu")
		(net "P5E_PEX3_STN4_TX_C_DP<72>")
	)
	(segment
		(start 433.769008 -393.611354)
		(end 433.331874 -393.377674)
		(width 0.1651)
		(layer "In7.Cu")
		(net "P5E_PEX3_STN4_TX_C_DP<72>")
	)
	(segment
		(start 425.130722 -345.755976)
		(end 424.839892 -345.465146)
		(width 0.1651)
		(layer "In7.Cu")
		(net "P5E_PEX3_STN4_TX_C_DP<72>")
	)
	(segment
		(start 435.38394 -394.83792)
		(end 435.240176 -394.83792)
		(width 0.1651)
		(layer "In7.Cu")
		(net "P5E_PEX3_STN4_TX_C_DP<72>")
	)
	(segment
		(start 434.889656 -394.4874)
		(end 434.889656 -394.343636)
		(width 0.1651)
		(layer "In7.Cu")
		(net "P5E_PEX3_STN4_TX_C_DP<72>")
	)
	(segment
		(start 412.972504 -343.365074)
		(end 412.972504 -342.734646)
		(width 0.13462)
		(layer "F.Cu")
		(net "P5E_PEX3_STN4_TX_DN<78>")
	)
	(segment
		(start 413.293052 -343.685622)
		(end 412.972504 -343.365074)
		(width 0.13462)
		(layer "F.Cu")
		(net "P5E_PEX3_STN4_TX_DN<78>")
	)
	(segment
		(start 412.972504 -342.734646)
		(end 413.267652 -342.439498)
		(width 0.13462)
		(layer "F.Cu")
		(net "P5E_PEX3_STN4_TX_DN<78>")
	)
	(segment
		(start 423.03573 -313.570112)
		(end 423.15003 -313.684412)
		(width 0.1143)
		(layer "In7.Cu")
		(net "P5E_PEX3_STN4_TX_DN<78>")
	)
	(segment
		(start 412.976822 -341.519256)
		(end 422.52646 -322.10248)
		(width 0.1651)
		(layer "In7.Cu")
		(net "P5E_PEX3_STN4_TX_DN<78>")
	)
	(segment
		(start 422.52646 -322.10248)
		(end 422.81602 -320.857372)
		(width 0.1651)
		(layer "In7.Cu")
		(net "P5E_PEX3_STN4_TX_DN<78>")
	)
	(segment
		(start 422.7703 -319.864232)
		(end 422.7703 -313.684412)
		(width 0.1143)
		(layer "In7.Cu")
		(net "P5E_PEX3_STN4_TX_DN<78>")
	)
	(segment
		(start 413.267652 -342.439498)
		(end 412.976822 -342.148668)
		(width 0.1651)
		(layer "In7.Cu")
		(net "P5E_PEX3_STN4_TX_DN<78>")
	)
	(segment
		(start 423.15003 -313.684412)
		(end 423.15003 -313.949842)
		(width 0.1143)
		(layer "In7.Cu")
		(net "P5E_PEX3_STN4_TX_DN<78>")
	)
	(segment
		(start 422.8846 -313.570112)
		(end 423.03573 -313.570112)
		(width 0.1143)
		(layer "In7.Cu")
		(net "P5E_PEX3_STN4_TX_DN<78>")
	)
	(segment
		(start 422.81602 -320.857372)
		(end 422.81602 -319.9384)
		(width 0.1651)
		(layer "In7.Cu")
		(net "P5E_PEX3_STN4_TX_DN<78>")
	)
	(segment
		(start 422.7703 -313.684412)
		(end 422.8846 -313.570112)
		(width 0.1143)
		(layer "In7.Cu")
		(net "P5E_PEX3_STN4_TX_DN<78>")
	)
	(segment
		(start 422.81602 -319.9384)
		(end 422.81602 -319.909952)
		(width 0.1143)
		(layer "In7.Cu")
		(net "P5E_PEX3_STN4_TX_DN<78>")
	)
	(segment
		(start 412.976822 -342.148668)
		(end 412.976822 -341.519256)
		(width 0.1651)
		(layer "In7.Cu")
		(net "P5E_PEX3_STN4_TX_DN<78>")
	)
	(segment
		(start 422.81602 -319.909952)
		(end 422.7703 -319.864232)
		(width 0.1143)
		(layer "In7.Cu")
		(net "P5E_PEX3_STN4_TX_DN<78>")
	)
	(segment
		(start 410.184092 -350.365314)
		(end 409.86456 -350.684846)
		(width 0.13462)
		(layer "F.Cu")
		(net "P5E_PEX3_STN4_TX_C_DN<79>")
	)
	(segment
		(start 409.86456 -351.317306)
		(end 410.158692 -351.611438)
		(width 0.13462)
		(layer "F.Cu")
		(net "P5E_PEX3_STN4_TX_C_DN<79>")
	)
	(segment
		(start 409.86456 -350.684846)
		(end 409.86456 -351.317306)
		(width 0.13462)
		(layer "F.Cu")
		(net "P5E_PEX3_STN4_TX_C_DN<79>")
	)
	(segment
		(start 420.168578 -394.418058)
		(end 414.465516 -390.623044)
		(width 0.1651)
		(layer "In7.Cu")
		(net "P5E_PEX3_STN4_TX_C_DN<79>")
	)
	(segment
		(start 420.615872 -396.82928)
		(end 420.615872 -394.865352)
		(width 0.1651)
		(layer "In7.Cu")
		(net "P5E_PEX3_STN4_TX_C_DN<79>")
	)
	(segment
		(start 414.465516 -390.623044)
		(end 412.17088 -387.97738)
		(width 0.1651)
		(layer "In7.Cu")
		(net "P5E_PEX3_STN4_TX_C_DN<79>")
	)
	(segment
		(start 410.95422 -383.81686)
		(end 409.867862 -352.83648)
		(width 0.1651)
		(layer "In7.Cu")
		(net "P5E_PEX3_STN4_TX_C_DN<79>")
	)
	(segment
		(start 420.164006 -397.281146)
		(end 420.615872 -396.82928)
		(width 0.1651)
		(layer "In7.Cu")
		(net "P5E_PEX3_STN4_TX_C_DN<79>")
	)
	(segment
		(start 409.867862 -352.83648)
		(end 409.867862 -351.902268)
		(width 0.1651)
		(layer "In7.Cu")
		(net "P5E_PEX3_STN4_TX_C_DN<79>")
	)
	(segment
		(start 420.615872 -394.865352)
		(end 420.168578 -394.418058)
		(width 0.1651)
		(layer "In7.Cu")
		(net "P5E_PEX3_STN4_TX_C_DN<79>")
	)
	(segment
		(start 419.48989 -397.790162)
		(end 419.48989 -397.408146)
		(width 0.1651)
		(layer "In7.Cu")
		(net "P5E_PEX3_STN4_TX_C_DN<79>")
	)
	(segment
		(start 409.867862 -351.902268)
		(end 410.158692 -351.611438)
		(width 0.1651)
		(layer "In7.Cu")
		(net "P5E_PEX3_STN4_TX_C_DN<79>")
	)
	(segment
		(start 412.17088 -387.97738)
		(end 410.95422 -383.81686)
		(width 0.1651)
		(layer "In7.Cu")
		(net "P5E_PEX3_STN4_TX_C_DN<79>")
	)
	(segment
		(start 419.48989 -397.408146)
		(end 419.61689 -397.281146)
		(width 0.1651)
		(layer "In7.Cu")
		(net "P5E_PEX3_STN4_TX_C_DN<79>")
	)
	(segment
		(start 419.61689 -397.281146)
		(end 420.164006 -397.281146)
		(width 0.1651)
		(layer "In7.Cu")
		(net "P5E_PEX3_STN4_TX_C_DN<79>")
	)
	(segment
		(start 419.19144 -356.831138)
		(end 419.19144 -357.463598)
		(width 0.13462)
		(layer "F.Cu")
		(net "P5E_PEX3_STN4_TX_C_DN<74>")
	)
	(segment
		(start 419.510972 -356.511606)
		(end 419.19144 -356.831138)
		(width 0.13462)
		(layer "F.Cu")
		(net "P5E_PEX3_STN4_TX_C_DN<74>")
	)
	(segment
		(start 419.19144 -357.463598)
		(end 419.485572 -357.75773)
		(width 0.13462)
		(layer "F.Cu")
		(net "P5E_PEX3_STN4_TX_C_DN<74>")
	)
	(segment
		(start 419.194742 -358.04856)
		(end 419.485572 -357.75773)
		(width 0.1651)
		(layer "In7.Cu")
		(net "P5E_PEX3_STN4_TX_C_DN<74>")
	)
	(segment
		(start 430.489868 -398.50822)
		(end 430.616868 -398.38122)
		(width 0.1651)
		(layer "In7.Cu")
		(net "P5E_PEX3_STN4_TX_C_DN<74>")
	)
	(segment
		(start 429.56353 -393.32535)
		(end 417.709096 -386.8166)
		(width 0.1651)
		(layer "In7.Cu")
		(net "P5E_PEX3_STN4_TX_C_DN<74>")
	)
	(segment
		(start 416.043618 -383.561082)
		(end 416.378898 -369.369848)
		(width 0.1651)
		(layer "In7.Cu")
		(net "P5E_PEX3_STN4_TX_C_DN<74>")
	)
	(segment
		(start 431.61585 -397.929354)
		(end 431.61585 -395.37767)
		(width 0.1651)
		(layer "In7.Cu")
		(net "P5E_PEX3_STN4_TX_C_DN<74>")
	)
	(segment
		(start 430.489868 -398.890236)
		(end 430.489868 -398.50822)
		(width 0.1651)
		(layer "In7.Cu")
		(net "P5E_PEX3_STN4_TX_C_DN<74>")
	)
	(segment
		(start 419.194742 -358.796844)
		(end 419.194742 -358.04856)
		(width 0.1651)
		(layer "In7.Cu")
		(net "P5E_PEX3_STN4_TX_C_DN<74>")
	)
	(segment
		(start 431.61585 -395.37767)
		(end 429.56353 -393.32535)
		(width 0.1651)
		(layer "In7.Cu")
		(net "P5E_PEX3_STN4_TX_C_DN<74>")
	)
	(segment
		(start 416.563302 -385.292092)
		(end 416.043618 -383.561082)
		(width 0.1651)
		(layer "In7.Cu")
		(net "P5E_PEX3_STN4_TX_C_DN<74>")
	)
	(segment
		(start 431.163984 -398.38122)
		(end 431.61585 -397.929354)
		(width 0.1651)
		(layer "In7.Cu")
		(net "P5E_PEX3_STN4_TX_C_DN<74>")
	)
	(segment
		(start 430.616868 -398.38122)
		(end 431.163984 -398.38122)
		(width 0.1651)
		(layer "In7.Cu")
		(net "P5E_PEX3_STN4_TX_C_DN<74>")
	)
	(segment
		(start 417.709096 -386.8166)
		(end 416.563302 -385.292092)
		(width 0.1651)
		(layer "In7.Cu")
		(net "P5E_PEX3_STN4_TX_C_DN<74>")
	)
	(segment
		(start 416.378898 -369.369848)
		(end 419.194742 -358.796844)
		(width 0.1651)
		(layer "In7.Cu")
		(net "P5E_PEX3_STN4_TX_C_DN<74>")
	)
	(segment
		(start 431.62728 -357.463598)
		(end 431.921412 -357.75773)
		(width 0.13462)
		(layer "F.Cu")
		(net "P5E_PEX3_STN4_TX_C_DN<68>")
	)
	(segment
		(start 431.946812 -356.511606)
		(end 431.62728 -356.831138)
		(width 0.13462)
		(layer "F.Cu")
		(net "P5E_PEX3_STN4_TX_C_DN<68>")
	)
	(segment
		(start 431.62728 -356.831138)
		(end 431.62728 -357.463598)
		(width 0.13462)
		(layer "F.Cu")
		(net "P5E_PEX3_STN4_TX_C_DN<68>")
	)
	(segment
		(start 427.215808 -371.929152)
		(end 427.215808 -368.74704)
		(width 0.1651)
		(layer "In7.Cu")
		(net "P5E_PEX3_STN4_TX_C_DN<68>")
	)
	(segment
		(start 427.215808 -368.74704)
		(end 431.630582 -358.849676)
		(width 0.1651)
		(layer "In7.Cu")
		(net "P5E_PEX3_STN4_TX_C_DN<68>")
	)
	(segment
		(start 426.763942 -372.381018)
		(end 427.215808 -371.929152)
		(width 0.1651)
		(layer "In7.Cu")
		(net "P5E_PEX3_STN4_TX_C_DN<68>")
	)
	(segment
		(start 426.089826 -372.508018)
		(end 426.216826 -372.381018)
		(width 0.1651)
		(layer "In7.Cu")
		(net "P5E_PEX3_STN4_TX_C_DN<68>")
	)
	(segment
		(start 426.216826 -372.381018)
		(end 426.763942 -372.381018)
		(width 0.1651)
		(layer "In7.Cu")
		(net "P5E_PEX3_STN4_TX_C_DN<68>")
	)
	(segment
		(start 426.089826 -372.890034)
		(end 426.089826 -372.508018)
		(width 0.1651)
		(layer "In7.Cu")
		(net "P5E_PEX3_STN4_TX_C_DN<68>")
	)
	(segment
		(start 431.630582 -358.849676)
		(end 431.630582 -358.04856)
		(width 0.1651)
		(layer "In7.Cu")
		(net "P5E_PEX3_STN4_TX_C_DN<68>")
	)
	(segment
		(start 431.630582 -358.04856)
		(end 431.921412 -357.75773)
		(width 0.1651)
		(layer "In7.Cu")
		(net "P5E_PEX3_STN4_TX_C_DN<68>")
	)
	(segment
		(start 418.537136 -365.030004)
		(end 418.661342 -365.0107)
		(width 0.1651)
		(layer "In5.Cu")
		(net "P5E_PEX3_STN4_RX_DP<74>")
	)
	(segment
		(start 418.661342 -365.0107)
		(end 423.576242 -358.28224)
		(width 0.1651)
		(layer "In5.Cu")
		(net "P5E_PEX3_STN4_RX_DP<74>")
	)
	(segment
		(start 426.33392 -319.909952)
		(end 426.37964 -319.864232)
		(width 0.1143)
		(layer "In5.Cu")
		(net "P5E_PEX3_STN4_RX_DP<74>")
	)
	(segment
		(start 418.264086 -365.554514)
		(end 418.244782 -365.430308)
		(width 0.1651)
		(layer "In5.Cu")
		(net "P5E_PEX3_STN4_RX_DP<74>")
	)
	(segment
		(start 426.37964 -318.355472)
		(end 426.605446 -318.129666)
		(width 0.1143)
		(layer "In5.Cu")
		(net "P5E_PEX3_STN4_RX_DP<74>")
	)
	(segment
		(start 426.94987 -318.015366)
		(end 426.94987 -317.749936)
		(width 0.1143)
		(layer "In5.Cu")
		(net "P5E_PEX3_STN4_RX_DP<74>")
	)
	(segment
		(start 426.605446 -318.129666)
		(end 426.83557 -318.129666)
		(width 0.1143)
		(layer "In5.Cu")
		(net "P5E_PEX3_STN4_RX_DP<74>")
	)
	(segment
		(start 431.060606 -395.39799)
		(end 429.25238 -393.662662)
		(width 0.1651)
		(layer "In5.Cu")
		(net "P5E_PEX3_STN4_RX_DP<74>")
	)
	(segment
		(start 431.365914 -405.570436)
		(end 431.365914 -396.224506)
		(width 0.1651)
		(layer "In5.Cu")
		(net "P5E_PEX3_STN4_RX_DP<74>")
	)
	(segment
		(start 418.244782 -365.430308)
		(end 418.537136 -365.030004)
		(width 0.1651)
		(layer "In5.Cu")
		(net "P5E_PEX3_STN4_RX_DP<74>")
	)
	(segment
		(start 429.25238 -393.662662)
		(end 418.007292 -387.63702)
		(width 0.1651)
		(layer "In5.Cu")
		(net "P5E_PEX3_STN4_RX_DP<74>")
	)
	(segment
		(start 418.007292 -387.63702)
		(end 416.798506 -386.41528)
		(width 0.1651)
		(layer "In5.Cu")
		(net "P5E_PEX3_STN4_RX_DP<74>")
	)
	(segment
		(start 416.547808 -367.904268)
		(end 418.264086 -365.554514)
		(width 0.1651)
		(layer "In5.Cu")
		(net "P5E_PEX3_STN4_RX_DP<74>")
	)
	(segment
		(start 426.83557 -318.129666)
		(end 426.94987 -318.015366)
		(width 0.1143)
		(layer "In5.Cu")
		(net "P5E_PEX3_STN4_RX_DP<74>")
	)
	(segment
		(start 430.663096 -405.902922)
		(end 431.033428 -405.902922)
		(width 0.1651)
		(layer "In5.Cu")
		(net "P5E_PEX3_STN4_RX_DP<74>")
	)
	(segment
		(start 416.28187 -368.510058)
		(end 416.547808 -367.904268)
		(width 0.1651)
		(layer "In5.Cu")
		(net "P5E_PEX3_STN4_RX_DP<74>")
	)
	(segment
		(start 430.489868 -405.390096)
		(end 430.489868 -405.729694)
		(width 0.1651)
		(layer "In5.Cu")
		(net "P5E_PEX3_STN4_RX_DP<74>")
	)
	(segment
		(start 423.576242 -358.28224)
		(end 423.576242 -341.912448)
		(width 0.1651)
		(layer "In5.Cu")
		(net "P5E_PEX3_STN4_RX_DP<74>")
	)
	(segment
		(start 423.576242 -341.912448)
		(end 426.33392 -324.784212)
		(width 0.1651)
		(layer "In5.Cu")
		(net "P5E_PEX3_STN4_RX_DP<74>")
	)
	(segment
		(start 431.033428 -405.902922)
		(end 431.365914 -405.570436)
		(width 0.1651)
		(layer "In5.Cu")
		(net "P5E_PEX3_STN4_RX_DP<74>")
	)
	(segment
		(start 415.95548 -384.319272)
		(end 415.99485 -369.955572)
		(width 0.1651)
		(layer "In5.Cu")
		(net "P5E_PEX3_STN4_RX_DP<74>")
	)
	(segment
		(start 426.33392 -324.784212)
		(end 426.33392 -319.9384)
		(width 0.1651)
		(layer "In5.Cu")
		(net "P5E_PEX3_STN4_RX_DP<74>")
	)
	(segment
		(start 431.365914 -396.224506)
		(end 431.060606 -395.39799)
		(width 0.1651)
		(layer "In5.Cu")
		(net "P5E_PEX3_STN4_RX_DP<74>")
	)
	(segment
		(start 426.37964 -319.864232)
		(end 426.37964 -318.355472)
		(width 0.1143)
		(layer "In5.Cu")
		(net "P5E_PEX3_STN4_RX_DP<74>")
	)
	(segment
		(start 430.489868 -405.729694)
		(end 430.663096 -405.902922)
		(width 0.1651)
		(layer "In5.Cu")
		(net "P5E_PEX3_STN4_RX_DP<74>")
	)
	(segment
		(start 426.33392 -319.9384)
		(end 426.33392 -319.909952)
		(width 0.1143)
		(layer "In5.Cu")
		(net "P5E_PEX3_STN4_RX_DP<74>")
	)
	(segment
		(start 415.99485 -369.955572)
		(end 416.28187 -368.510058)
		(width 0.1651)
		(layer "In5.Cu")
		(net "P5E_PEX3_STN4_RX_DP<74>")
	)
	(segment
		(start 416.798506 -386.41528)
		(end 415.95548 -384.319272)
		(width 0.1651)
		(layer "In5.Cu")
		(net "P5E_PEX3_STN4_RX_DP<74>")
	)
	(segment
		(start 434.88991 -380.69012)
		(end 434.88991 -380.358142)
		(width 0.1651)
		(layer "In5.Cu")
		(net "P5E_PEX3_STN4_RX_DN<64>")
	)
	(segment
		(start 445.044322 -362.237528)
		(end 446.41008 -358.940354)
		(width 0.1651)
		(layer "In5.Cu")
		(net "P5E_PEX3_STN4_RX_DN<64>")
	)
	(segment
		(start 447.40703 -322.4276)
		(end 447.40703 -316.86627)
		(width 0.1651)
		(layer "In5.Cu")
		(net "P5E_PEX3_STN4_RX_DN<64>")
	)
	(segment
		(start 431.988468 -304.783744)
		(end 431.942748 -304.829464)
		(width 0.1143)
		(layer "In5.Cu")
		(net "P5E_PEX3_STN4_RX_DN<64>")
	)
	(segment
		(start 435.063138 -380.184914)
		(end 435.55031 -380.184914)
		(width 0.1651)
		(layer "In5.Cu")
		(net "P5E_PEX3_STN4_RX_DN<64>")
	)
	(segment
		(start 446.41008 -358.732074)
		(end 447.40703 -322.4276)
		(width 0.1651)
		(layer "In5.Cu")
		(net "P5E_PEX3_STN4_RX_DN<64>")
	)
	(segment
		(start 430.370234 -304.564034)
		(end 430.484534 -304.449734)
		(width 0.1143)
		(layer "In5.Cu")
		(net "P5E_PEX3_STN4_RX_DN<64>")
	)
	(segment
		(start 435.55031 -380.184914)
		(end 436.047896 -379.687328)
		(width 0.1651)
		(layer "In5.Cu")
		(net "P5E_PEX3_STN4_RX_DN<64>")
	)
	(segment
		(start 434.062124 -304.783744)
		(end 432.016916 -304.783744)
		(width 0.1651)
		(layer "In5.Cu")
		(net "P5E_PEX3_STN4_RX_DN<64>")
	)
	(segment
		(start 447.40703 -316.86627)
		(end 436.217314 -305.676554)
		(width 0.1651)
		(layer "In5.Cu")
		(net "P5E_PEX3_STN4_RX_DN<64>")
	)
	(segment
		(start 436.047896 -379.687328)
		(end 436.047896 -369.040664)
		(width 0.1651)
		(layer "In5.Cu")
		(net "P5E_PEX3_STN4_RX_DN<64>")
	)
	(segment
		(start 431.942748 -304.829464)
		(end 430.484534 -304.829464)
		(width 0.1143)
		(layer "In5.Cu")
		(net "P5E_PEX3_STN4_RX_DN<64>")
	)
	(segment
		(start 440.625992 -365.735362)
		(end 445.044322 -362.237528)
		(width 0.1651)
		(layer "In5.Cu")
		(net "P5E_PEX3_STN4_RX_DN<64>")
	)
	(segment
		(start 446.41008 -358.940354)
		(end 446.41008 -358.732074)
		(width 0.1651)
		(layer "In5.Cu")
		(net "P5E_PEX3_STN4_RX_DN<64>")
	)
	(segment
		(start 436.047896 -369.040664)
		(end 436.735728 -368.261646)
		(width 0.1651)
		(layer "In5.Cu")
		(net "P5E_PEX3_STN4_RX_DN<64>")
	)
	(segment
		(start 430.370234 -304.715164)
		(end 430.370234 -304.564034)
		(width 0.1143)
		(layer "In5.Cu")
		(net "P5E_PEX3_STN4_RX_DN<64>")
	)
	(segment
		(start 434.88991 -380.358142)
		(end 435.063138 -380.184914)
		(width 0.1651)
		(layer "In5.Cu")
		(net "P5E_PEX3_STN4_RX_DN<64>")
	)
	(segment
		(start 436.217314 -305.676554)
		(end 434.062124 -304.783744)
		(width 0.1651)
		(layer "In5.Cu")
		(net "P5E_PEX3_STN4_RX_DN<64>")
	)
	(segment
		(start 436.735728 -368.261646)
		(end 440.625992 -365.735362)
		(width 0.1651)
		(layer "In5.Cu")
		(net "P5E_PEX3_STN4_RX_DN<64>")
	)
	(segment
		(start 430.484534 -304.829464)
		(end 430.370234 -304.715164)
		(width 0.1143)
		(layer "In5.Cu")
		(net "P5E_PEX3_STN4_RX_DN<64>")
	)
	(segment
		(start 430.484534 -304.449734)
		(end 430.749964 -304.449734)
		(width 0.1143)
		(layer "In5.Cu")
		(net "P5E_PEX3_STN4_RX_DN<64>")
	)
	(segment
		(start 432.016916 -304.783744)
		(end 431.988468 -304.783744)
		(width 0.1143)
		(layer "In5.Cu")
		(net "P5E_PEX3_STN4_RX_DN<64>")
	)
	(segment
		(start 412.378652 -343.685622)
		(end 412.698184 -343.36609)
		(width 0.13462)
		(layer "F.Cu")
		(net "P5E_PEX3_STN4_TX_DP<78>")
	)
	(segment
		(start 412.698184 -343.36609)
		(end 412.698184 -342.73363)
		(width 0.13462)
		(layer "F.Cu")
		(net "P5E_PEX3_STN4_TX_DP<78>")
	)
	(segment
		(start 412.698184 -342.73363)
		(end 412.404052 -342.439498)
		(width 0.13462)
		(layer "F.Cu")
		(net "P5E_PEX3_STN4_TX_DP<78>")
	)
	(segment
		(start 412.404052 -342.439498)
		(end 412.694882 -342.148668)
		(width 0.1651)
		(layer "In7.Cu")
		(net "P5E_PEX3_STN4_TX_DP<78>")
	)
	(segment
		(start 423.15003 -313.265312)
		(end 423.15003 -312.999882)
		(width 0.1143)
		(layer "In7.Cu")
		(net "P5E_PEX3_STN4_TX_DP<78>")
	)
	(segment
		(start 412.694882 -342.148668)
		(end 412.694882 -341.45347)
		(width 0.1651)
		(layer "In7.Cu")
		(net "P5E_PEX3_STN4_TX_DP<78>")
	)
	(segment
		(start 422.5798 -313.605418)
		(end 422.805606 -313.379612)
		(width 0.1143)
		(layer "In7.Cu")
		(net "P5E_PEX3_STN4_TX_DP<78>")
	)
	(segment
		(start 422.805606 -313.379612)
		(end 423.03573 -313.379612)
		(width 0.1143)
		(layer "In7.Cu")
		(net "P5E_PEX3_STN4_TX_DP<78>")
	)
	(segment
		(start 422.53408 -319.9384)
		(end 422.53408 -319.909952)
		(width 0.1143)
		(layer "In7.Cu")
		(net "P5E_PEX3_STN4_TX_DP<78>")
	)
	(segment
		(start 422.5798 -319.864232)
		(end 422.5798 -313.605418)
		(width 0.1143)
		(layer "In7.Cu")
		(net "P5E_PEX3_STN4_TX_DP<78>")
	)
	(segment
		(start 422.53408 -320.82486)
		(end 422.53408 -319.9384)
		(width 0.1651)
		(layer "In7.Cu")
		(net "P5E_PEX3_STN4_TX_DP<78>")
	)
	(segment
		(start 423.03573 -313.379612)
		(end 423.15003 -313.265312)
		(width 0.1143)
		(layer "In7.Cu")
		(net "P5E_PEX3_STN4_TX_DP<78>")
	)
	(segment
		(start 422.258998 -322.006976)
		(end 422.53408 -320.82486)
		(width 0.1651)
		(layer "In7.Cu")
		(net "P5E_PEX3_STN4_TX_DP<78>")
	)
	(segment
		(start 412.694882 -341.45347)
		(end 422.258998 -322.006976)
		(width 0.1651)
		(layer "In7.Cu")
		(net "P5E_PEX3_STN4_TX_DP<78>")
	)
	(segment
		(start 422.53408 -319.909952)
		(end 422.5798 -319.864232)
		(width 0.1143)
		(layer "In7.Cu")
		(net "P5E_PEX3_STN4_TX_DP<78>")
	)
	(segment
		(start 430.484534 -316.799722)
		(end 430.749964 -316.799722)
		(width 0.1143)
		(layer "In5.Cu")
		(net "P5E_PEX3_STN4_RX_DN<71>")
	)
	(segment
		(start 433.185062 -358.82834)
		(end 433.185062 -342.086438)
		(width 0.1651)
		(layer "In5.Cu")
		(net "P5E_PEX3_STN4_RX_DN<71>")
	)
	(segment
		(start 430.370234 -316.914022)
		(end 430.484534 -316.799722)
		(width 0.1143)
		(layer "In5.Cu")
		(net "P5E_PEX3_STN4_RX_DN<71>")
	)
	(segment
		(start 419.48989 -379.590046)
		(end 419.48989 -379.258068)
		(width 0.1651)
		(layer "In5.Cu")
		(net "P5E_PEX3_STN4_RX_DN<71>")
	)
	(segment
		(start 420.647876 -369.47221)
		(end 421.042084 -368.647218)
		(width 0.1651)
		(layer "In5.Cu")
		(net "P5E_PEX3_STN4_RX_DN<71>")
	)
	(segment
		(start 430.415954 -319.027048)
		(end 430.415954 -318.9986)
		(width 0.1143)
		(layer "In5.Cu")
		(net "P5E_PEX3_STN4_RX_DN<71>")
	)
	(segment
		(start 430.415954 -323.743828)
		(end 430.415954 -319.027048)
		(width 0.1651)
		(layer "In5.Cu")
		(net "P5E_PEX3_STN4_RX_DN<71>")
	)
	(segment
		(start 421.042084 -368.647218)
		(end 433.185062 -358.82834)
		(width 0.1651)
		(layer "In5.Cu")
		(net "P5E_PEX3_STN4_RX_DN<71>")
	)
	(segment
		(start 419.48989 -379.258068)
		(end 419.663118 -379.08484)
		(width 0.1651)
		(layer "In5.Cu")
		(net "P5E_PEX3_STN4_RX_DN<71>")
	)
	(segment
		(start 420.15029 -379.08484)
		(end 420.647876 -378.587254)
		(width 0.1651)
		(layer "In5.Cu")
		(net "P5E_PEX3_STN4_RX_DN<71>")
	)
	(segment
		(start 433.185062 -342.086438)
		(end 430.415954 -323.743828)
		(width 0.1651)
		(layer "In5.Cu")
		(net "P5E_PEX3_STN4_RX_DN<71>")
	)
	(segment
		(start 420.647876 -378.587254)
		(end 420.647876 -369.47221)
		(width 0.1651)
		(layer "In5.Cu")
		(net "P5E_PEX3_STN4_RX_DN<71>")
	)
	(segment
		(start 419.663118 -379.08484)
		(end 420.15029 -379.08484)
		(width 0.1651)
		(layer "In5.Cu")
		(net "P5E_PEX3_STN4_RX_DN<71>")
	)
	(segment
		(start 430.370234 -318.95288)
		(end 430.370234 -316.914022)
		(width 0.1143)
		(layer "In5.Cu")
		(net "P5E_PEX3_STN4_RX_DN<71>")
	)
	(segment
		(start 430.415954 -318.9986)
		(end 430.370234 -318.95288)
		(width 0.1143)
		(layer "In5.Cu")
		(net "P5E_PEX3_STN4_RX_DN<71>")
	)
	(segment
		(start 431.626264 -355.657658)
		(end 431.626264 -355.02723)
		(width 0.13462)
		(layer "F.Cu")
		(net "P5E_PEX3_STN4_TX_DN<68>")
	)
	(segment
		(start 431.946812 -355.978206)
		(end 431.626264 -355.657658)
		(width 0.13462)
		(layer "F.Cu")
		(net "P5E_PEX3_STN4_TX_DN<68>")
	)
	(segment
		(start 431.626264 -355.02723)
		(end 431.921412 -354.732082)
		(width 0.13462)
		(layer "F.Cu")
		(net "P5E_PEX3_STN4_TX_DN<68>")
	)
	(segment
		(start 443.035944 -318.752982)
		(end 442.03493 -317.34252)
		(width 0.1651)
		(layer "In7.Cu")
		(net "P5E_PEX3_STN4_TX_DN<68>")
	)
	(segment
		(start 432.275488 -308.583838)
		(end 431.980848 -308.583838)
		(width 0.1651)
		(layer "In7.Cu")
		(net "P5E_PEX3_STN4_TX_DN<68>")
	)
	(segment
		(start 423.72026 -308.515258)
		(end 423.72026 -308.364128)
		(width 0.1143)
		(layer "In7.Cu")
		(net "P5E_PEX3_STN4_TX_DN<68>")
	)
	(segment
		(start 431.980848 -308.583838)
		(end 431.9524 -308.583838)
		(width 0.1143)
		(layer "In7.Cu")
		(net "P5E_PEX3_STN4_TX_DN<68>")
	)
	(segment
		(start 431.630582 -354.441252)
		(end 431.630582 -353.930966)
		(width 0.1651)
		(layer "In7.Cu")
		(net "P5E_PEX3_STN4_TX_DN<68>")
	)
	(segment
		(start 433.185062 -341.742268)
		(end 442.941964 -323.087238)
		(width 0.1651)
		(layer "In7.Cu")
		(net "P5E_PEX3_STN4_TX_DN<68>")
	)
	(segment
		(start 433.185062 -352.376486)
		(end 433.185062 -341.742268)
		(width 0.1651)
		(layer "In7.Cu")
		(net "P5E_PEX3_STN4_TX_DN<68>")
	)
	(segment
		(start 438.810654 -314.769754)
		(end 432.871626 -308.830726)
		(width 0.1651)
		(layer "In7.Cu")
		(net "P5E_PEX3_STN4_TX_DN<68>")
	)
	(segment
		(start 443.34557 -321.135248)
		(end 443.035944 -318.752982)
		(width 0.1651)
		(layer "In7.Cu")
		(net "P5E_PEX3_STN4_TX_DN<68>")
	)
	(segment
		(start 442.03493 -317.34252)
		(end 438.810654 -314.769754)
		(width 0.1651)
		(layer "In7.Cu")
		(net "P5E_PEX3_STN4_TX_DN<68>")
	)
	(segment
		(start 423.83456 -308.249828)
		(end 424.09999 -308.249828)
		(width 0.1143)
		(layer "In7.Cu")
		(net "P5E_PEX3_STN4_TX_DN<68>")
	)
	(segment
		(start 431.9524 -308.583838)
		(end 431.90668 -308.629558)
		(width 0.1143)
		(layer "In7.Cu")
		(net "P5E_PEX3_STN4_TX_DN<68>")
	)
	(segment
		(start 432.871626 -308.830726)
		(end 432.275488 -308.583838)
		(width 0.1651)
		(layer "In7.Cu")
		(net "P5E_PEX3_STN4_TX_DN<68>")
	)
	(segment
		(start 431.90668 -308.629558)
		(end 423.83456 -308.629558)
		(width 0.1143)
		(layer "In7.Cu")
		(net "P5E_PEX3_STN4_TX_DN<68>")
	)
	(segment
		(start 442.941964 -323.087238)
		(end 442.949838 -323.04863)
		(width 0.1651)
		(layer "In7.Cu")
		(net "P5E_PEX3_STN4_TX_DN<68>")
	)
	(segment
		(start 442.949838 -323.04863)
		(end 443.34557 -321.135248)
		(width 0.1651)
		(layer "In7.Cu")
		(net "P5E_PEX3_STN4_TX_DN<68>")
	)
	(segment
		(start 423.83456 -308.629558)
		(end 423.72026 -308.515258)
		(width 0.1143)
		(layer "In7.Cu")
		(net "P5E_PEX3_STN4_TX_DN<68>")
	)
	(segment
		(start 431.630582 -353.930966)
		(end 433.185062 -352.376486)
		(width 0.1651)
		(layer "In7.Cu")
		(net "P5E_PEX3_STN4_TX_DN<68>")
	)
	(segment
		(start 431.921412 -354.732082)
		(end 431.630582 -354.441252)
		(width 0.1651)
		(layer "In7.Cu")
		(net "P5E_PEX3_STN4_TX_DN<68>")
	)
	(segment
		(start 423.72026 -308.364128)
		(end 423.83456 -308.249828)
		(width 0.1143)
		(layer "In7.Cu")
		(net "P5E_PEX3_STN4_TX_DN<68>")
	)
	(segment
		(start 423.889932 -404.290022)
		(end 423.889932 -404.62962)
		(width 0.1651)
		(layer "In5.Cu")
		(net "P5E_PEX3_STN4_RX_DP<77>")
	)
	(segment
		(start 423.48404 -319.909952)
		(end 423.52976 -319.864232)
		(width 0.1143)
		(layer "In5.Cu")
		(net "P5E_PEX3_STN4_RX_DP<77>")
	)
	(segment
		(start 423.52976 -316.455298)
		(end 423.755566 -316.229492)
		(width 0.1143)
		(layer "In5.Cu")
		(net "P5E_PEX3_STN4_RX_DP<77>")
	)
	(segment
		(start 416.290506 -390.036812)
		(end 414.393634 -388.250684)
		(width 0.1651)
		(layer "In5.Cu")
		(net "P5E_PEX3_STN4_RX_DP<77>")
	)
	(segment
		(start 413.576008 -363.84357)
		(end 414.249362 -358.82834)
		(width 0.1651)
		(layer "In5.Cu")
		(net "P5E_PEX3_STN4_RX_DP<77>")
	)
	(segment
		(start 424.06316 -404.802848)
		(end 424.433492 -404.802848)
		(width 0.1651)
		(layer "In5.Cu")
		(net "P5E_PEX3_STN4_RX_DP<77>")
	)
	(segment
		(start 414.393634 -388.250684)
		(end 413.006286 -384.79984)
		(width 0.1651)
		(layer "In5.Cu")
		(net "P5E_PEX3_STN4_RX_DP<77>")
	)
	(segment
		(start 424.433492 -404.802848)
		(end 424.765978 -404.470362)
		(width 0.1651)
		(layer "In5.Cu")
		(net "P5E_PEX3_STN4_RX_DP<77>")
	)
	(segment
		(start 424.765978 -404.470362)
		(end 424.765978 -395.22781)
		(width 0.1651)
		(layer "In5.Cu")
		(net "P5E_PEX3_STN4_RX_DP<77>")
	)
	(segment
		(start 419.78707 -392.014964)
		(end 419.631114 -392.058144)
		(width 0.1651)
		(layer "In5.Cu")
		(net "P5E_PEX3_STN4_RX_DP<77>")
	)
	(segment
		(start 423.48404 -322.251324)
		(end 423.48404 -319.9384)
		(width 0.1651)
		(layer "In5.Cu")
		(net "P5E_PEX3_STN4_RX_DP<77>")
	)
	(segment
		(start 413.006286 -384.79984)
		(end 413.053022 -367.739168)
		(width 0.1651)
		(layer "In5.Cu")
		(net "P5E_PEX3_STN4_RX_DP<77>")
	)
	(segment
		(start 423.52976 -319.864232)
		(end 423.52976 -316.455298)
		(width 0.1143)
		(layer "In5.Cu")
		(net "P5E_PEX3_STN4_RX_DP<77>")
	)
	(segment
		(start 423.98569 -316.229492)
		(end 424.09999 -316.115192)
		(width 0.1143)
		(layer "In5.Cu")
		(net "P5E_PEX3_STN4_RX_DP<77>")
	)
	(segment
		(start 414.249362 -341.980774)
		(end 423.48404 -322.251324)
		(width 0.1651)
		(layer "In5.Cu")
		(net "P5E_PEX3_STN4_RX_DP<77>")
	)
	(segment
		(start 413.479488 -364.561374)
		(end 413.381444 -364.43285)
		(width 0.1651)
		(layer "In5.Cu")
		(net "P5E_PEX3_STN4_RX_DP<77>")
	)
	(segment
		(start 423.755566 -316.229492)
		(end 423.98569 -316.229492)
		(width 0.1143)
		(layer "In5.Cu")
		(net "P5E_PEX3_STN4_RX_DP<77>")
	)
	(segment
		(start 424.09999 -316.115192)
		(end 424.09999 -315.849762)
		(width 0.1143)
		(layer "In5.Cu")
		(net "P5E_PEX3_STN4_RX_DP<77>")
	)
	(segment
		(start 414.249362 -358.82834)
		(end 414.249362 -341.980774)
		(width 0.1651)
		(layer "In5.Cu")
		(net "P5E_PEX3_STN4_RX_DP<77>")
	)
	(segment
		(start 413.447484 -363.941614)
		(end 413.576008 -363.84357)
		(width 0.1651)
		(layer "In5.Cu")
		(net "P5E_PEX3_STN4_RX_DP<77>")
	)
	(segment
		(start 413.053022 -367.739168)
		(end 413.479488 -364.561374)
		(width 0.1651)
		(layer "In5.Cu")
		(net "P5E_PEX3_STN4_RX_DP<77>")
	)
	(segment
		(start 423.889932 -404.62962)
		(end 424.06316 -404.802848)
		(width 0.1651)
		(layer "In5.Cu")
		(net "P5E_PEX3_STN4_RX_DP<77>")
	)
	(segment
		(start 419.199822 -391.81405)
		(end 419.156642 -391.658348)
		(width 0.1651)
		(layer "In5.Cu")
		(net "P5E_PEX3_STN4_RX_DP<77>")
	)
	(segment
		(start 424.765978 -395.22781)
		(end 424.546268 -394.753338)
		(width 0.1651)
		(layer "In5.Cu")
		(net "P5E_PEX3_STN4_RX_DP<77>")
	)
	(segment
		(start 424.128184 -394.47089)
		(end 419.78707 -392.014964)
		(width 0.1651)
		(layer "In5.Cu")
		(net "P5E_PEX3_STN4_RX_DP<77>")
	)
	(segment
		(start 424.546268 -394.753338)
		(end 424.128184 -394.47089)
		(width 0.1651)
		(layer "In5.Cu")
		(net "P5E_PEX3_STN4_RX_DP<77>")
	)
	(segment
		(start 419.631114 -392.058144)
		(end 419.199822 -391.81405)
		(width 0.1651)
		(layer "In5.Cu")
		(net "P5E_PEX3_STN4_RX_DP<77>")
	)
	(segment
		(start 419.156642 -391.658348)
		(end 416.290506 -390.036812)
		(width 0.1651)
		(layer "In5.Cu")
		(net "P5E_PEX3_STN4_RX_DP<77>")
	)
	(segment
		(start 413.381444 -364.43285)
		(end 413.447484 -363.941614)
		(width 0.1651)
		(layer "In5.Cu")
		(net "P5E_PEX3_STN4_RX_DP<77>")
	)
	(segment
		(start 423.48404 -319.9384)
		(end 423.48404 -319.909952)
		(width 0.1143)
		(layer "In5.Cu")
		(net "P5E_PEX3_STN4_RX_DP<77>")
	)
	(segment
		(start 432.95316 -319.153794)
		(end 433.73294 -317.271146)
		(width 0.1651)
		(layer "In5.Cu")
		(net "P5E_PEX3_STN4_RX_DN<69>")
	)
	(segment
		(start 439.402982 -341.935054)
		(end 432.95316 -322.561966)
		(width 0.1651)
		(layer "In5.Cu")
		(net "P5E_PEX3_STN4_RX_DN<69>")
	)
	(segment
		(start 433.73294 -317.271146)
		(end 433.73294 -310.80964)
		(width 0.1651)
		(layer "In5.Cu")
		(net "P5E_PEX3_STN4_RX_DN<69>")
	)
	(segment
		(start 428.47006 -309.314088)
		(end 428.58436 -309.199788)
		(width 0.1143)
		(layer "In5.Cu")
		(net "P5E_PEX3_STN4_RX_DN<69>")
	)
	(segment
		(start 432.95316 -322.561966)
		(end 432.95316 -319.153794)
		(width 0.1651)
		(layer "In5.Cu")
		(net "P5E_PEX3_STN4_RX_DN<69>")
	)
	(segment
		(start 428.58436 -309.199788)
		(end 428.84979 -309.199788)
		(width 0.1143)
		(layer "In5.Cu")
		(net "P5E_PEX3_STN4_RX_DN<69>")
	)
	(segment
		(start 433.020216 -309.73014)
		(end 432.546252 -309.533798)
		(width 0.1651)
		(layer "In5.Cu")
		(net "P5E_PEX3_STN4_RX_DN<69>")
	)
	(segment
		(start 423.889932 -379.258068)
		(end 424.06316 -379.08484)
		(width 0.1651)
		(layer "In5.Cu")
		(net "P5E_PEX3_STN4_RX_DN<69>")
	)
	(segment
		(start 425.047918 -369.682776)
		(end 425.42587 -368.770408)
		(width 0.1651)
		(layer "In5.Cu")
		(net "P5E_PEX3_STN4_RX_DN<69>")
	)
	(segment
		(start 433.473352 -310.183276)
		(end 433.020216 -309.73014)
		(width 0.1651)
		(layer "In5.Cu")
		(net "P5E_PEX3_STN4_RX_DN<69>")
	)
	(segment
		(start 432.546252 -309.533798)
		(end 431.955448 -309.533798)
		(width 0.1651)
		(layer "In5.Cu")
		(net "P5E_PEX3_STN4_RX_DN<69>")
	)
	(segment
		(start 423.889932 -379.590046)
		(end 423.889932 -379.258068)
		(width 0.1651)
		(layer "In5.Cu")
		(net "P5E_PEX3_STN4_RX_DN<69>")
	)
	(segment
		(start 424.06316 -379.08484)
		(end 424.550332 -379.08484)
		(width 0.1651)
		(layer "In5.Cu")
		(net "P5E_PEX3_STN4_RX_DN<69>")
	)
	(segment
		(start 428.47006 -309.465218)
		(end 428.47006 -309.314088)
		(width 0.1143)
		(layer "In5.Cu")
		(net "P5E_PEX3_STN4_RX_DN<69>")
	)
	(segment
		(start 431.955448 -309.533798)
		(end 431.927 -309.533798)
		(width 0.1143)
		(layer "In5.Cu")
		(net "P5E_PEX3_STN4_RX_DN<69>")
	)
	(segment
		(start 431.88128 -309.579518)
		(end 428.58436 -309.579518)
		(width 0.1143)
		(layer "In5.Cu")
		(net "P5E_PEX3_STN4_RX_DN<69>")
	)
	(segment
		(start 433.73294 -310.80964)
		(end 433.473352 -310.183276)
		(width 0.1651)
		(layer "In5.Cu")
		(net "P5E_PEX3_STN4_RX_DN<69>")
	)
	(segment
		(start 431.927 -309.533798)
		(end 431.88128 -309.579518)
		(width 0.1143)
		(layer "In5.Cu")
		(net "P5E_PEX3_STN4_RX_DN<69>")
	)
	(segment
		(start 424.550332 -379.08484)
		(end 425.047918 -378.587254)
		(width 0.1651)
		(layer "In5.Cu")
		(net "P5E_PEX3_STN4_RX_DN<69>")
	)
	(segment
		(start 425.047918 -378.587254)
		(end 425.047918 -369.682776)
		(width 0.1651)
		(layer "In5.Cu")
		(net "P5E_PEX3_STN4_RX_DN<69>")
	)
	(segment
		(start 439.003694 -359.00106)
		(end 439.402982 -358.233472)
		(width 0.1651)
		(layer "In5.Cu")
		(net "P5E_PEX3_STN4_RX_DN<69>")
	)
	(segment
		(start 426.262292 -367.933986)
		(end 439.003694 -359.00106)
		(width 0.1651)
		(layer "In5.Cu")
		(net "P5E_PEX3_STN4_RX_DN<69>")
	)
	(segment
		(start 439.402982 -358.233472)
		(end 439.402982 -341.935054)
		(width 0.1651)
		(layer "In5.Cu")
		(net "P5E_PEX3_STN4_RX_DN<69>")
	)
	(segment
		(start 425.42587 -368.770408)
		(end 426.262292 -367.933986)
		(width 0.1651)
		(layer "In5.Cu")
		(net "P5E_PEX3_STN4_RX_DN<69>")
	)
	(segment
		(start 428.58436 -309.579518)
		(end 428.47006 -309.465218)
		(width 0.1143)
		(layer "In5.Cu")
		(net "P5E_PEX3_STN4_RX_DN<69>")
	)
	(segment
		(start 437.250332 -355.978206)
		(end 437.569864 -355.658674)
		(width 0.13462)
		(layer "F.Cu")
		(net "P5E_PEX3_STN4_TX_DP<65>")
	)
	(segment
		(start 437.569864 -355.658674)
		(end 437.569864 -355.026214)
		(width 0.13462)
		(layer "F.Cu")
		(net "P5E_PEX3_STN4_TX_DP<65>")
	)
	(segment
		(start 437.569864 -355.026214)
		(end 437.275732 -354.732082)
		(width 0.13462)
		(layer "F.Cu")
		(net "P5E_PEX3_STN4_TX_DP<65>")
	)
	(segment
		(start 445.540892 -323.788024)
		(end 445.5414 -323.7865)
		(width 0.1651)
		(layer "In7.Cu")
		(net "P5E_PEX3_STN4_TX_DP<65>")
	)
	(segment
		(start 441.358782 -312.565542)
		(end 436.148988 -307.355748)
		(width 0.1651)
		(layer "In7.Cu")
		(net "P5E_PEX3_STN4_TX_DP<65>")
	)
	(segment
		(start 445.629792 -317.78575)
		(end 444.114428 -315.62167)
		(width 0.1651)
		(layer "In7.Cu")
		(net "P5E_PEX3_STN4_TX_DP<65>")
	)
	(segment
		(start 431.930048 -306.015898)
		(end 431.884328 -305.970178)
		(width 0.1143)
		(layer "In7.Cu")
		(net "P5E_PEX3_STN4_TX_DP<65>")
	)
	(segment
		(start 432.914298 -306.015898)
		(end 431.958496 -306.015898)
		(width 0.1651)
		(layer "In7.Cu")
		(net "P5E_PEX3_STN4_TX_DP<65>")
	)
	(segment
		(start 437.275732 -354.732082)
		(end 437.566562 -354.441252)
		(width 0.1651)
		(layer "In7.Cu")
		(net "P5E_PEX3_STN4_TX_DP<65>")
	)
	(segment
		(start 445.5414 -323.7865)
		(end 446.08242 -321.30238)
		(width 0.1651)
		(layer "In7.Cu")
		(net "P5E_PEX3_STN4_TX_DP<65>")
	)
	(segment
		(start 431.884328 -305.970178)
		(end 425.655486 -305.970178)
		(width 0.1143)
		(layer "In7.Cu")
		(net "P5E_PEX3_STN4_TX_DP<65>")
	)
	(segment
		(start 425.31538 -305.399948)
		(end 425.04995 -305.399948)
		(width 0.1143)
		(layer "In7.Cu")
		(net "P5E_PEX3_STN4_TX_DP<65>")
	)
	(segment
		(start 437.566562 -354.441252)
		(end 437.566562 -353.814126)
		(width 0.1651)
		(layer "In7.Cu")
		(net "P5E_PEX3_STN4_TX_DP<65>")
	)
	(segment
		(start 436.148988 -307.355748)
		(end 432.914298 -306.015898)
		(width 0.1651)
		(layer "In7.Cu")
		(net "P5E_PEX3_STN4_TX_DP<65>")
	)
	(segment
		(start 444.114428 -315.62167)
		(end 441.358782 -312.565542)
		(width 0.1651)
		(layer "In7.Cu")
		(net "P5E_PEX3_STN4_TX_DP<65>")
	)
	(segment
		(start 439.121042 -341.66302)
		(end 445.540892 -323.788024)
		(width 0.1651)
		(layer "In7.Cu")
		(net "P5E_PEX3_STN4_TX_DP<65>")
	)
	(segment
		(start 446.08242 -321.30238)
		(end 445.629792 -317.78575)
		(width 0.1651)
		(layer "In7.Cu")
		(net "P5E_PEX3_STN4_TX_DP<65>")
	)
	(segment
		(start 439.121042 -352.259646)
		(end 439.121042 -341.66302)
		(width 0.1651)
		(layer "In7.Cu")
		(net "P5E_PEX3_STN4_TX_DP<65>")
	)
	(segment
		(start 425.655486 -305.970178)
		(end 425.42968 -305.744372)
		(width 0.1143)
		(layer "In7.Cu")
		(net "P5E_PEX3_STN4_TX_DP<65>")
	)
	(segment
		(start 425.42968 -305.744372)
		(end 425.42968 -305.514248)
		(width 0.1143)
		(layer "In7.Cu")
		(net "P5E_PEX3_STN4_TX_DP<65>")
	)
	(segment
		(start 425.42968 -305.514248)
		(end 425.31538 -305.399948)
		(width 0.1143)
		(layer "In7.Cu")
		(net "P5E_PEX3_STN4_TX_DP<65>")
	)
	(segment
		(start 437.566562 -353.814126)
		(end 439.121042 -352.259646)
		(width 0.1651)
		(layer "In7.Cu")
		(net "P5E_PEX3_STN4_TX_DP<65>")
	)
	(segment
		(start 431.958496 -306.015898)
		(end 431.930048 -306.015898)
		(width 0.1143)
		(layer "In7.Cu")
		(net "P5E_PEX3_STN4_TX_DP<65>")
	)
	(segment
		(start 437.8452 -356.831138)
		(end 437.8452 -357.463598)
		(width 0.13462)
		(layer "F.Cu")
		(net "P5E_PEX3_STN4_TX_C_DN<65>")
	)
	(segment
		(start 438.164732 -356.511606)
		(end 437.8452 -356.831138)
		(width 0.13462)
		(layer "F.Cu")
		(net "P5E_PEX3_STN4_TX_C_DN<65>")
	)
	(segment
		(start 437.8452 -357.463598)
		(end 438.139332 -357.75773)
		(width 0.13462)
		(layer "F.Cu")
		(net "P5E_PEX3_STN4_TX_C_DN<65>")
	)
	(segment
		(start 432.689762 -371.790214)
		(end 432.689762 -371.408198)
		(width 0.1651)
		(layer "In7.Cu")
		(net "P5E_PEX3_STN4_TX_C_DN<65>")
	)
	(segment
		(start 433.815744 -368.80038)
		(end 437.828182 -358.8385)
		(width 0.1651)
		(layer "In7.Cu")
		(net "P5E_PEX3_STN4_TX_C_DN<65>")
	)
	(segment
		(start 437.848502 -358.04856)
		(end 438.139332 -357.75773)
		(width 0.1651)
		(layer "In7.Cu")
		(net "P5E_PEX3_STN4_TX_C_DN<65>")
	)
	(segment
		(start 433.815744 -370.829332)
		(end 433.815744 -368.80038)
		(width 0.1651)
		(layer "In7.Cu")
		(net "P5E_PEX3_STN4_TX_C_DN<65>")
	)
	(segment
		(start 432.689762 -371.408198)
		(end 432.816762 -371.281198)
		(width 0.1651)
		(layer "In7.Cu")
		(net "P5E_PEX3_STN4_TX_C_DN<65>")
	)
	(segment
		(start 437.838342 -358.785922)
		(end 437.846724 -358.785922)
		(width 0.1651)
		(layer "In7.Cu")
		(net "P5E_PEX3_STN4_TX_C_DN<65>")
	)
	(segment
		(start 437.828182 -358.8385)
		(end 437.838342 -358.785922)
		(width 0.1651)
		(layer "In7.Cu")
		(net "P5E_PEX3_STN4_TX_C_DN<65>")
	)
	(segment
		(start 437.848502 -358.7877)
		(end 437.848502 -358.04856)
		(width 0.1651)
		(layer "In7.Cu")
		(net "P5E_PEX3_STN4_TX_C_DN<65>")
	)
	(segment
		(start 433.363878 -371.281198)
		(end 433.815744 -370.829332)
		(width 0.1651)
		(layer "In7.Cu")
		(net "P5E_PEX3_STN4_TX_C_DN<65>")
	)
	(segment
		(start 437.846724 -358.785922)
		(end 437.848502 -358.7877)
		(width 0.1651)
		(layer "In7.Cu")
		(net "P5E_PEX3_STN4_TX_C_DN<65>")
	)
	(segment
		(start 432.816762 -371.281198)
		(end 433.363878 -371.281198)
		(width 0.1651)
		(layer "In7.Cu")
		(net "P5E_PEX3_STN4_TX_C_DN<65>")
	)
	(segment
		(start 415.807144 -349.512382)
		(end 415.807144 -348.879922)
		(width 0.13462)
		(layer "F.Cu")
		(net "P5E_PEX3_STN4_TX_DP<76>")
	)
	(segment
		(start 415.807144 -348.879922)
		(end 415.513012 -348.58579)
		(width 0.13462)
		(layer "F.Cu")
		(net "P5E_PEX3_STN4_TX_DP<76>")
	)
	(segment
		(start 415.487612 -349.831914)
		(end 415.807144 -349.512382)
		(width 0.13462)
		(layer "F.Cu")
		(net "P5E_PEX3_STN4_TX_DP<76>")
	)
	(segment
		(start 417.358322 -341.66302)
		(end 424.163236 -322.61302)
		(width 0.1651)
		(layer "In7.Cu")
		(net "P5E_PEX3_STN4_TX_DP<76>")
	)
	(segment
		(start 424.434 -319.909952)
		(end 424.47972 -319.864232)
		(width 0.1143)
		(layer "In7.Cu")
		(net "P5E_PEX3_STN4_TX_DP<76>")
	)
	(segment
		(start 415.513012 -348.58579)
		(end 415.803842 -348.29496)
		(width 0.1651)
		(layer "In7.Cu")
		(net "P5E_PEX3_STN4_TX_DP<76>")
	)
	(segment
		(start 425.04995 -313.265312)
		(end 425.04995 -312.999882)
		(width 0.1143)
		(layer "In7.Cu")
		(net "P5E_PEX3_STN4_TX_DP<76>")
	)
	(segment
		(start 424.163236 -322.61302)
		(end 424.434 -321.05092)
		(width 0.1651)
		(layer "In7.Cu")
		(net "P5E_PEX3_STN4_TX_DP<76>")
	)
	(segment
		(start 417.358322 -346.113354)
		(end 417.358322 -341.66302)
		(width 0.1651)
		(layer "In7.Cu")
		(net "P5E_PEX3_STN4_TX_DP<76>")
	)
	(segment
		(start 424.434 -321.05092)
		(end 424.434 -319.9384)
		(width 0.1651)
		(layer "In7.Cu")
		(net "P5E_PEX3_STN4_TX_DP<76>")
	)
	(segment
		(start 424.93565 -313.379612)
		(end 425.04995 -313.265312)
		(width 0.1143)
		(layer "In7.Cu")
		(net "P5E_PEX3_STN4_TX_DP<76>")
	)
	(segment
		(start 424.434 -319.9384)
		(end 424.434 -319.909952)
		(width 0.1143)
		(layer "In7.Cu")
		(net "P5E_PEX3_STN4_TX_DP<76>")
	)
	(segment
		(start 415.803842 -347.667834)
		(end 417.358322 -346.113354)
		(width 0.1651)
		(layer "In7.Cu")
		(net "P5E_PEX3_STN4_TX_DP<76>")
	)
	(segment
		(start 415.803842 -348.29496)
		(end 415.803842 -347.667834)
		(width 0.1651)
		(layer "In7.Cu")
		(net "P5E_PEX3_STN4_TX_DP<76>")
	)
	(segment
		(start 424.47972 -319.864232)
		(end 424.47972 -313.605418)
		(width 0.1143)
		(layer "In7.Cu")
		(net "P5E_PEX3_STN4_TX_DP<76>")
	)
	(segment
		(start 424.705526 -313.379612)
		(end 424.93565 -313.379612)
		(width 0.1143)
		(layer "In7.Cu")
		(net "P5E_PEX3_STN4_TX_DP<76>")
	)
	(segment
		(start 424.47972 -313.605418)
		(end 424.705526 -313.379612)
		(width 0.1143)
		(layer "In7.Cu")
		(net "P5E_PEX3_STN4_TX_DP<76>")
	)
	(segment
		(start 437.250332 -344.219022)
		(end 437.57088 -344.53957)
		(width 0.13462)
		(layer "F.Cu")
		(net "P5E_PEX3_STN4_TX_C_DP<66>")
	)
	(segment
		(start 437.57088 -345.169998)
		(end 437.275732 -345.465146)
		(width 0.13462)
		(layer "F.Cu")
		(net "P5E_PEX3_STN4_TX_C_DP<66>")
	)
	(segment
		(start 437.57088 -344.53957)
		(end 437.57088 -345.169998)
		(width 0.13462)
		(layer "F.Cu")
		(net "P5E_PEX3_STN4_TX_C_DP<66>")
	)
	(segment
		(start 435.649624 -359.3084)
		(end 435.801516 -359.253536)
		(width 0.1651)
		(layer "In7.Cu")
		(net "P5E_PEX3_STN4_TX_C_DP<66>")
	)
	(segment
		(start 433.938426 -363.22)
		(end 433.883562 -363.067854)
		(width 0.1651)
		(layer "In7.Cu")
		(net "P5E_PEX3_STN4_TX_C_DP<66>")
	)
	(segment
		(start 432.06289 -367.213134)
		(end 432.008026 -367.060988)
		(width 0.1651)
		(layer "In7.Cu")
		(net "P5E_PEX3_STN4_TX_C_DP<66>")
	)
	(segment
		(start 434.246274 -362.564426)
		(end 434.45684 -362.11637)
		(width 0.1651)
		(layer "In7.Cu")
		(net "P5E_PEX3_STN4_TX_C_DP<66>")
	)
	(segment
		(start 431.047144 -372.099078)
		(end 431.33391 -371.812312)
		(width 0.1651)
		(layer "In7.Cu")
		(net "P5E_PEX3_STN4_TX_C_DP<66>")
	)
	(segment
		(start 432.370738 -366.55756)
		(end 432.581304 -366.109504)
		(width 0.1651)
		(layer "In7.Cu")
		(net "P5E_PEX3_STN4_TX_C_DP<66>")
	)
	(segment
		(start 434.764688 -361.460796)
		(end 434.975254 -361.01274)
		(width 0.1651)
		(layer "In7.Cu")
		(net "P5E_PEX3_STN4_TX_C_DP<66>")
	)
	(segment
		(start 430.489868 -371.972078)
		(end 430.616868 -372.099078)
		(width 0.1651)
		(layer "In7.Cu")
		(net "P5E_PEX3_STN4_TX_C_DP<66>")
	)
	(segment
		(start 431.852324 -367.66119)
		(end 432.06289 -367.213134)
		(width 0.1651)
		(layer "In7.Cu")
		(net "P5E_PEX3_STN4_TX_C_DP<66>")
	)
	(segment
		(start 434.612796 -361.51566)
		(end 434.764688 -361.460796)
		(width 0.1651)
		(layer "In7.Cu")
		(net "P5E_PEX3_STN4_TX_C_DP<66>")
	)
	(segment
		(start 431.700432 -367.716054)
		(end 431.852324 -367.66119)
		(width 0.1651)
		(layer "In7.Cu")
		(net "P5E_PEX3_STN4_TX_C_DP<66>")
	)
	(segment
		(start 432.73726 -365.508794)
		(end 432.889152 -365.45393)
		(width 0.1651)
		(layer "In7.Cu")
		(net "P5E_PEX3_STN4_TX_C_DP<66>")
	)
	(segment
		(start 436.012082 -358.80548)
		(end 436.012082 -347.764354)
		(width 0.1651)
		(layer "In7.Cu")
		(net "P5E_PEX3_STN4_TX_C_DP<66>")
	)
	(segment
		(start 431.544476 -368.316764)
		(end 431.489612 -368.164618)
		(width 0.1651)
		(layer "In7.Cu")
		(net "P5E_PEX3_STN4_TX_C_DP<66>")
	)
	(segment
		(start 432.52644 -365.957358)
		(end 432.73726 -365.508794)
		(width 0.1651)
		(layer "In7.Cu")
		(net "P5E_PEX3_STN4_TX_C_DP<66>")
	)
	(segment
		(start 437.566562 -346.209874)
		(end 437.566562 -345.755976)
		(width 0.1651)
		(layer "In7.Cu")
		(net "P5E_PEX3_STN4_TX_C_DP<66>")
	)
	(segment
		(start 431.33391 -371.812312)
		(end 431.33391 -368.76482)
		(width 0.1651)
		(layer "In7.Cu")
		(net "P5E_PEX3_STN4_TX_C_DP<66>")
	)
	(segment
		(start 432.889152 -365.45393)
		(end 433.938426 -363.22)
		(width 0.1651)
		(layer "In7.Cu")
		(net "P5E_PEX3_STN4_TX_C_DP<66>")
	)
	(segment
		(start 434.975254 -361.01274)
		(end 434.92039 -360.860594)
		(width 0.1651)
		(layer "In7.Cu")
		(net "P5E_PEX3_STN4_TX_C_DP<66>")
	)
	(segment
		(start 435.438804 -359.756964)
		(end 435.649624 -359.3084)
		(width 0.1651)
		(layer "In7.Cu")
		(net "P5E_PEX3_STN4_TX_C_DP<66>")
	)
	(segment
		(start 435.283102 -360.357166)
		(end 435.493668 -359.90911)
		(width 0.1651)
		(layer "In7.Cu")
		(net "P5E_PEX3_STN4_TX_C_DP<66>")
	)
	(segment
		(start 434.45684 -362.11637)
		(end 434.401976 -361.964224)
		(width 0.1651)
		(layer "In7.Cu")
		(net "P5E_PEX3_STN4_TX_C_DP<66>")
	)
	(segment
		(start 432.581304 -366.109504)
		(end 432.52644 -365.957358)
		(width 0.1651)
		(layer "In7.Cu")
		(net "P5E_PEX3_STN4_TX_C_DP<66>")
	)
	(segment
		(start 435.13121 -360.41203)
		(end 435.283102 -360.357166)
		(width 0.1651)
		(layer "In7.Cu")
		(net "P5E_PEX3_STN4_TX_C_DP<66>")
	)
	(segment
		(start 434.094382 -362.61929)
		(end 434.246274 -362.564426)
		(width 0.1651)
		(layer "In7.Cu")
		(net "P5E_PEX3_STN4_TX_C_DP<66>")
	)
	(segment
		(start 430.489868 -371.590062)
		(end 430.489868 -371.972078)
		(width 0.1651)
		(layer "In7.Cu")
		(net "P5E_PEX3_STN4_TX_C_DP<66>")
	)
	(segment
		(start 435.493668 -359.90911)
		(end 435.438804 -359.756964)
		(width 0.1651)
		(layer "In7.Cu")
		(net "P5E_PEX3_STN4_TX_C_DP<66>")
	)
	(segment
		(start 431.489612 -368.164618)
		(end 431.700432 -367.716054)
		(width 0.1651)
		(layer "In7.Cu")
		(net "P5E_PEX3_STN4_TX_C_DP<66>")
	)
	(segment
		(start 435.801516 -359.253536)
		(end 436.012082 -358.80548)
		(width 0.1651)
		(layer "In7.Cu")
		(net "P5E_PEX3_STN4_TX_C_DP<66>")
	)
	(segment
		(start 430.616868 -372.099078)
		(end 431.047144 -372.099078)
		(width 0.1651)
		(layer "In7.Cu")
		(net "P5E_PEX3_STN4_TX_C_DP<66>")
	)
	(segment
		(start 434.401976 -361.964224)
		(end 434.612796 -361.51566)
		(width 0.1651)
		(layer "In7.Cu")
		(net "P5E_PEX3_STN4_TX_C_DP<66>")
	)
	(segment
		(start 432.218846 -366.612424)
		(end 432.370738 -366.55756)
		(width 0.1651)
		(layer "In7.Cu")
		(net "P5E_PEX3_STN4_TX_C_DP<66>")
	)
	(segment
		(start 436.012082 -347.764354)
		(end 437.566562 -346.209874)
		(width 0.1651)
		(layer "In7.Cu")
		(net "P5E_PEX3_STN4_TX_C_DP<66>")
	)
	(segment
		(start 437.566562 -345.755976)
		(end 437.275732 -345.465146)
		(width 0.1651)
		(layer "In7.Cu")
		(net "P5E_PEX3_STN4_TX_C_DP<66>")
	)
	(segment
		(start 434.92039 -360.860594)
		(end 435.13121 -360.41203)
		(width 0.1651)
		(layer "In7.Cu")
		(net "P5E_PEX3_STN4_TX_C_DP<66>")
	)
	(segment
		(start 433.883562 -363.067854)
		(end 434.094382 -362.61929)
		(width 0.1651)
		(layer "In7.Cu")
		(net "P5E_PEX3_STN4_TX_C_DP<66>")
	)
	(segment
		(start 432.008026 -367.060988)
		(end 432.218846 -366.612424)
		(width 0.1651)
		(layer "In7.Cu")
		(net "P5E_PEX3_STN4_TX_C_DP<66>")
	)
	(segment
		(start 431.33391 -368.76482)
		(end 431.544476 -368.316764)
		(width 0.1651)
		(layer "In7.Cu")
		(net "P5E_PEX3_STN4_TX_C_DP<66>")
	)
	(segment
		(start 431.626264 -343.365074)
		(end 431.626264 -342.734646)
		(width 0.13462)
		(layer "F.Cu")
		(net "P5E_PEX3_STN4_TX_DN<69>")
	)
	(segment
		(start 431.626264 -342.734646)
		(end 431.921412 -342.439498)
		(width 0.13462)
		(layer "F.Cu")
		(net "P5E_PEX3_STN4_TX_DN<69>")
	)
	(segment
		(start 431.946812 -343.685622)
		(end 431.626264 -343.365074)
		(width 0.13462)
		(layer "F.Cu")
		(net "P5E_PEX3_STN4_TX_DN<69>")
	)
	(segment
		(start 432.933856 -320.886328)
		(end 432.934364 -320.883788)
		(width 0.1651)
		(layer "In7.Cu")
		(net "P5E_PEX3_STN4_TX_DN<69>")
	)
	(segment
		(start 433.6288 -316.702948)
		(end 433.6288 -312.314844)
		(width 0.1651)
		(layer "In7.Cu")
		(net "P5E_PEX3_STN4_TX_DN<69>")
	)
	(segment
		(start 431.927 -309.533798)
		(end 431.88128 -309.579518)
		(width 0.1143)
		(layer "In7.Cu")
		(net "P5E_PEX3_STN4_TX_DN<69>")
	)
	(segment
		(start 433.5145 -317.766954)
		(end 433.6288 -316.702948)
		(width 0.1651)
		(layer "In7.Cu")
		(net "P5E_PEX3_STN4_TX_DN<69>")
	)
	(segment
		(start 432.934364 -320.883788)
		(end 432.934618 -320.882264)
		(width 0.1651)
		(layer "In7.Cu")
		(net "P5E_PEX3_STN4_TX_DN<69>")
	)
	(segment
		(start 432.933348 -320.889122)
		(end 432.933602 -320.887852)
		(width 0.1651)
		(layer "In7.Cu")
		(net "P5E_PEX3_STN4_TX_DN<69>")
	)
	(segment
		(start 431.630582 -341.5538)
		(end 432.933348 -320.889122)
		(width 0.1651)
		(layer "In7.Cu")
		(net "P5E_PEX3_STN4_TX_DN<69>")
	)
	(segment
		(start 431.955448 -309.533798)
		(end 431.927 -309.533798)
		(width 0.1143)
		(layer "In7.Cu")
		(net "P5E_PEX3_STN4_TX_DN<69>")
	)
	(segment
		(start 432.933602 -320.887852)
		(end 432.933856 -320.886328)
		(width 0.1651)
		(layer "In7.Cu")
		(net "P5E_PEX3_STN4_TX_DN<69>")
	)
	(segment
		(start 425.62018 -309.314088)
		(end 425.73448 -309.199788)
		(width 0.1143)
		(layer "In7.Cu")
		(net "P5E_PEX3_STN4_TX_DN<69>")
	)
	(segment
		(start 432.934618 -320.882264)
		(end 433.5145 -317.766954)
		(width 0.1651)
		(layer "In7.Cu")
		(net "P5E_PEX3_STN4_TX_DN<69>")
	)
	(segment
		(start 425.62018 -309.465218)
		(end 425.62018 -309.314088)
		(width 0.1143)
		(layer "In7.Cu")
		(net "P5E_PEX3_STN4_TX_DN<69>")
	)
	(segment
		(start 432.215544 -309.533798)
		(end 431.955448 -309.533798)
		(width 0.1651)
		(layer "In7.Cu")
		(net "P5E_PEX3_STN4_TX_DN<69>")
	)
	(segment
		(start 425.73448 -309.579518)
		(end 425.62018 -309.465218)
		(width 0.1143)
		(layer "In7.Cu")
		(net "P5E_PEX3_STN4_TX_DN<69>")
	)
	(segment
		(start 431.630582 -342.148668)
		(end 431.630582 -341.5538)
		(width 0.1651)
		(layer "In7.Cu")
		(net "P5E_PEX3_STN4_TX_DN<69>")
	)
	(segment
		(start 425.73448 -309.199788)
		(end 425.99991 -309.199788)
		(width 0.1143)
		(layer "In7.Cu")
		(net "P5E_PEX3_STN4_TX_DN<69>")
	)
	(segment
		(start 433.6288 -312.314844)
		(end 432.661568 -309.979822)
		(width 0.1651)
		(layer "In7.Cu")
		(net "P5E_PEX3_STN4_TX_DN<69>")
	)
	(segment
		(start 431.88128 -309.579518)
		(end 425.73448 -309.579518)
		(width 0.1143)
		(layer "In7.Cu")
		(net "P5E_PEX3_STN4_TX_DN<69>")
	)
	(segment
		(start 431.921412 -342.439498)
		(end 431.630582 -342.148668)
		(width 0.1651)
		(layer "In7.Cu")
		(net "P5E_PEX3_STN4_TX_DN<69>")
	)
	(segment
		(start 432.661568 -309.979822)
		(end 432.215544 -309.533798)
		(width 0.1651)
		(layer "In7.Cu")
		(net "P5E_PEX3_STN4_TX_DN<69>")
	)
	(segment
		(start 423.76598 -319.909952)
		(end 423.72026 -319.864232)
		(width 0.1143)
		(layer "In5.Cu")
		(net "P5E_PEX3_STN4_RX_DN<77>")
	)
	(segment
		(start 414.63214 -388.08787)
		(end 413.28848 -384.745738)
		(width 0.1651)
		(layer "In5.Cu")
		(net "P5E_PEX3_STN4_RX_DN<77>")
	)
	(segment
		(start 416.459162 -389.807958)
		(end 414.63214 -388.08787)
		(width 0.1651)
		(layer "In5.Cu")
		(net "P5E_PEX3_STN4_RX_DN<77>")
	)
	(segment
		(start 425.047918 -395.16558)
		(end 424.76928 -394.5636)
		(width 0.1651)
		(layer "In5.Cu")
		(net "P5E_PEX3_STN4_RX_DN<77>")
	)
	(segment
		(start 423.83456 -316.419992)
		(end 423.98569 -316.419992)
		(width 0.1143)
		(layer "In5.Cu")
		(net "P5E_PEX3_STN4_RX_DN<77>")
	)
	(segment
		(start 423.72026 -319.864232)
		(end 423.72026 -316.534292)
		(width 0.1143)
		(layer "In5.Cu")
		(net "P5E_PEX3_STN4_RX_DN<77>")
	)
	(segment
		(start 423.76598 -322.314062)
		(end 423.76598 -319.9384)
		(width 0.1651)
		(layer "In5.Cu")
		(net "P5E_PEX3_STN4_RX_DN<77>")
	)
	(segment
		(start 413.334962 -367.758472)
		(end 414.531302 -358.84739)
		(width 0.1651)
		(layer "In5.Cu")
		(net "P5E_PEX3_STN4_RX_DN<77>")
	)
	(segment
		(start 424.76928 -394.5636)
		(end 424.276774 -394.23086)
		(width 0.1651)
		(layer "In5.Cu")
		(net "P5E_PEX3_STN4_RX_DN<77>")
	)
	(segment
		(start 423.889932 -405.258016)
		(end 424.06316 -405.084788)
		(width 0.1651)
		(layer "In5.Cu")
		(net "P5E_PEX3_STN4_RX_DN<77>")
	)
	(segment
		(start 423.76598 -319.9384)
		(end 423.76598 -319.909952)
		(width 0.1143)
		(layer "In5.Cu")
		(net "P5E_PEX3_STN4_RX_DN<77>")
	)
	(segment
		(start 424.550332 -405.084788)
		(end 425.047918 -404.587202)
		(width 0.1651)
		(layer "In5.Cu")
		(net "P5E_PEX3_STN4_RX_DN<77>")
	)
	(segment
		(start 414.531302 -358.84739)
		(end 414.531302 -342.043512)
		(width 0.1651)
		(layer "In5.Cu")
		(net "P5E_PEX3_STN4_RX_DN<77>")
	)
	(segment
		(start 423.72026 -316.534292)
		(end 423.83456 -316.419992)
		(width 0.1143)
		(layer "In5.Cu")
		(net "P5E_PEX3_STN4_RX_DN<77>")
	)
	(segment
		(start 425.047918 -404.587202)
		(end 425.047918 -395.16558)
		(width 0.1651)
		(layer "In5.Cu")
		(net "P5E_PEX3_STN4_RX_DN<77>")
	)
	(segment
		(start 424.09999 -316.534292)
		(end 424.09999 -316.799722)
		(width 0.1143)
		(layer "In5.Cu")
		(net "P5E_PEX3_STN4_RX_DN<77>")
	)
	(segment
		(start 423.889932 -405.589994)
		(end 423.889932 -405.258016)
		(width 0.1651)
		(layer "In5.Cu")
		(net "P5E_PEX3_STN4_RX_DN<77>")
	)
	(segment
		(start 423.98569 -316.419992)
		(end 424.09999 -316.534292)
		(width 0.1143)
		(layer "In5.Cu")
		(net "P5E_PEX3_STN4_RX_DN<77>")
	)
	(segment
		(start 414.531302 -342.043512)
		(end 423.76598 -322.314062)
		(width 0.1651)
		(layer "In5.Cu")
		(net "P5E_PEX3_STN4_RX_DN<77>")
	)
	(segment
		(start 413.28848 -384.745738)
		(end 413.334962 -367.758472)
		(width 0.1651)
		(layer "In5.Cu")
		(net "P5E_PEX3_STN4_RX_DN<77>")
	)
	(segment
		(start 424.276774 -394.23086)
		(end 416.459162 -389.807958)
		(width 0.1651)
		(layer "In5.Cu")
		(net "P5E_PEX3_STN4_RX_DN<77>")
	)
	(segment
		(start 424.06316 -405.084788)
		(end 424.550332 -405.084788)
		(width 0.1651)
		(layer "In5.Cu")
		(net "P5E_PEX3_STN4_RX_DN<77>")
	)
	(segment
		(start 413.293052 -355.978206)
		(end 412.972504 -355.657658)
		(width 0.13462)
		(layer "F.Cu")
		(net "P5E_PEX3_STN4_TX_DN<77>")
	)
	(segment
		(start 412.972504 -355.02723)
		(end 413.267652 -354.732082)
		(width 0.13462)
		(layer "F.Cu")
		(net "P5E_PEX3_STN4_TX_DN<77>")
	)
	(segment
		(start 412.972504 -355.657658)
		(end 412.972504 -355.02723)
		(width 0.13462)
		(layer "F.Cu")
		(net "P5E_PEX3_STN4_TX_DN<77>")
	)
	(segment
		(start 423.72026 -319.864232)
		(end 423.72026 -311.784492)
		(width 0.1143)
		(layer "In7.Cu")
		(net "P5E_PEX3_STN4_TX_DN<77>")
	)
	(segment
		(start 423.76598 -319.9384)
		(end 423.76598 -319.909952)
		(width 0.1143)
		(layer "In7.Cu")
		(net "P5E_PEX3_STN4_TX_DN<77>")
	)
	(segment
		(start 423.98569 -311.670192)
		(end 424.09999 -311.784492)
		(width 0.1143)
		(layer "In7.Cu")
		(net "P5E_PEX3_STN4_TX_DN<77>")
	)
	(segment
		(start 423.76598 -319.909952)
		(end 423.72026 -319.864232)
		(width 0.1143)
		(layer "In7.Cu")
		(net "P5E_PEX3_STN4_TX_DN<77>")
	)
	(segment
		(start 423.83456 -311.670192)
		(end 423.98569 -311.670192)
		(width 0.1143)
		(layer "In7.Cu")
		(net "P5E_PEX3_STN4_TX_DN<77>")
	)
	(segment
		(start 412.976822 -354.441252)
		(end 412.976822 -353.930966)
		(width 0.1651)
		(layer "In7.Cu")
		(net "P5E_PEX3_STN4_TX_DN<77>")
	)
	(segment
		(start 423.72026 -311.784492)
		(end 423.83456 -311.670192)
		(width 0.1143)
		(layer "In7.Cu")
		(net "P5E_PEX3_STN4_TX_DN<77>")
	)
	(segment
		(start 414.531302 -352.376486)
		(end 414.531302 -341.729314)
		(width 0.1651)
		(layer "In7.Cu")
		(net "P5E_PEX3_STN4_TX_DN<77>")
	)
	(segment
		(start 413.267652 -354.732082)
		(end 412.976822 -354.441252)
		(width 0.1651)
		(layer "In7.Cu")
		(net "P5E_PEX3_STN4_TX_DN<77>")
	)
	(segment
		(start 412.976822 -353.930966)
		(end 414.531302 -352.376486)
		(width 0.1651)
		(layer "In7.Cu")
		(net "P5E_PEX3_STN4_TX_DN<77>")
	)
	(segment
		(start 424.09999 -311.784492)
		(end 424.09999 -312.049922)
		(width 0.1143)
		(layer "In7.Cu")
		(net "P5E_PEX3_STN4_TX_DN<77>")
	)
	(segment
		(start 414.531302 -341.729314)
		(end 423.44721 -322.393818)
		(width 0.1651)
		(layer "In7.Cu")
		(net "P5E_PEX3_STN4_TX_DN<77>")
	)
	(segment
		(start 423.76598 -320.941954)
		(end 423.76598 -319.9384)
		(width 0.1651)
		(layer "In7.Cu")
		(net "P5E_PEX3_STN4_TX_DN<77>")
	)
	(segment
		(start 423.44721 -322.393818)
		(end 423.76598 -320.941954)
		(width 0.1651)
		(layer "In7.Cu")
		(net "P5E_PEX3_STN4_TX_DN<77>")
	)
	(segment
		(start 432.26228 -368.508534)
		(end 432.025552 -368.745262)
		(width 0.1651)
		(layer "In5.Cu")
		(net "P5E_PEX3_STN4_RX_DN<66>")
	)
	(segment
		(start 431.933096 -306.683918)
		(end 433.436776 -306.683918)
		(width 0.1651)
		(layer "In5.Cu")
		(net "P5E_PEX3_STN4_RX_DN<66>")
	)
	(segment
		(start 430.484534 -306.729638)
		(end 431.858928 -306.729638)
		(width 0.1143)
		(layer "In5.Cu")
		(net "P5E_PEX3_STN4_RX_DN<66>")
	)
	(segment
		(start 431.858928 -306.729638)
		(end 431.904648 -306.683918)
		(width 0.1143)
		(layer "In5.Cu")
		(net "P5E_PEX3_STN4_RX_DN<66>")
	)
	(segment
		(start 436.435246 -309.544466)
		(end 439.84037 -312.94959)
		(width 0.1651)
		(layer "In5.Cu")
		(net "P5E_PEX3_STN4_RX_DN<66>")
	)
	(segment
		(start 439.84037 -312.94959)
		(end 440.941968 -313.406028)
		(width 0.1651)
		(layer "In5.Cu")
		(net "P5E_PEX3_STN4_RX_DN<66>")
	)
	(segment
		(start 437.961786 -364.666784)
		(end 432.26228 -368.508534)
		(width 0.1651)
		(layer "In5.Cu")
		(net "P5E_PEX3_STN4_RX_DN<66>")
	)
	(segment
		(start 432.025552 -368.745262)
		(end 431.647854 -369.657122)
		(width 0.1651)
		(layer "In5.Cu")
		(net "P5E_PEX3_STN4_RX_DN<66>")
	)
	(segment
		(start 430.484534 -306.349908)
		(end 430.370234 -306.464208)
		(width 0.1143)
		(layer "In5.Cu")
		(net "P5E_PEX3_STN4_RX_DN<66>")
	)
	(segment
		(start 445.48298 -317.94704)
		(end 445.48298 -322.04787)
		(width 0.1651)
		(layer "In5.Cu")
		(net "P5E_PEX3_STN4_RX_DN<66>")
	)
	(segment
		(start 431.647854 -369.657122)
		(end 431.647854 -379.687328)
		(width 0.1651)
		(layer "In5.Cu")
		(net "P5E_PEX3_STN4_RX_DN<66>")
	)
	(segment
		(start 433.436776 -306.683918)
		(end 434.634894 -307.180234)
		(width 0.1651)
		(layer "In5.Cu")
		(net "P5E_PEX3_STN4_RX_DN<66>")
	)
	(segment
		(start 431.150268 -380.184914)
		(end 430.663096 -380.184914)
		(width 0.1651)
		(layer "In5.Cu")
		(net "P5E_PEX3_STN4_RX_DN<66>")
	)
	(segment
		(start 430.370234 -306.464208)
		(end 430.370234 -306.615338)
		(width 0.1143)
		(layer "In5.Cu")
		(net "P5E_PEX3_STN4_RX_DN<66>")
	)
	(segment
		(start 430.663096 -380.184914)
		(end 430.489868 -380.358142)
		(width 0.1651)
		(layer "In5.Cu")
		(net "P5E_PEX3_STN4_RX_DN<66>")
	)
	(segment
		(start 440.941968 -313.406028)
		(end 445.48298 -317.94704)
		(width 0.1651)
		(layer "In5.Cu")
		(net "P5E_PEX3_STN4_RX_DN<66>")
	)
	(segment
		(start 443.637162 -360.124502)
		(end 437.961786 -364.666784)
		(width 0.1651)
		(layer "In5.Cu")
		(net "P5E_PEX3_STN4_RX_DN<66>")
	)
	(segment
		(start 431.647854 -379.687328)
		(end 431.150268 -380.184914)
		(width 0.1651)
		(layer "In5.Cu")
		(net "P5E_PEX3_STN4_RX_DN<66>")
	)
	(segment
		(start 430.749964 -306.349908)
		(end 430.484534 -306.349908)
		(width 0.1143)
		(layer "In5.Cu")
		(net "P5E_PEX3_STN4_RX_DN<66>")
	)
	(segment
		(start 444.484252 -358.42194)
		(end 443.637162 -360.124502)
		(width 0.1651)
		(layer "In5.Cu")
		(net "P5E_PEX3_STN4_RX_DN<66>")
	)
	(segment
		(start 436.036466 -308.581806)
		(end 436.435246 -309.544466)
		(width 0.1651)
		(layer "In5.Cu")
		(net "P5E_PEX3_STN4_RX_DN<66>")
	)
	(segment
		(start 434.634894 -307.180234)
		(end 436.036466 -308.581806)
		(width 0.1651)
		(layer "In5.Cu")
		(net "P5E_PEX3_STN4_RX_DN<66>")
	)
	(segment
		(start 431.904648 -306.683918)
		(end 431.933096 -306.683918)
		(width 0.1143)
		(layer "In5.Cu")
		(net "P5E_PEX3_STN4_RX_DN<66>")
	)
	(segment
		(start 445.48298 -322.04787)
		(end 444.484252 -358.42194)
		(width 0.1651)
		(layer "In5.Cu")
		(net "P5E_PEX3_STN4_RX_DN<66>")
	)
	(segment
		(start 430.370234 -306.615338)
		(end 430.484534 -306.729638)
		(width 0.1143)
		(layer "In5.Cu")
		(net "P5E_PEX3_STN4_RX_DN<66>")
	)
	(segment
		(start 430.489868 -380.358142)
		(end 430.489868 -380.69012)
		(width 0.1651)
		(layer "In5.Cu")
		(net "P5E_PEX3_STN4_RX_DN<66>")
	)
	(segment
		(start 259.437632 -227.332032)
		(end 259.393182 -227.332032)
		(width 0.13208)
		(layer "F.Cu")
		(net "SPI_PEX2_CS_MUX_R_N")
	)
	(segment
		(start 259.393182 -227.332032)
		(end 258.050284 -228.67493)
		(width 0.13208)
		(layer "F.Cu")
		(net "SPI_PEX2_CS_MUX_R_N")
	)
	(segment
		(start 256.699766 -228.67493)
		(end 256.859786 -228.67493)
		(width 0.13208)
		(layer "F.Cu")
		(net "SPI_PEX2_CS_MUX_R_N")
	)
	(segment
		(start 258.050284 -228.67493)
		(end 256.859786 -228.67493)
		(width 0.13208)
		(layer "F.Cu")
		(net "SPI_PEX2_CS_MUX_R_N")
	)
	(via
		(at 259.437632 -227.332032)
		(size 0.508)
		(drill 0.254)
		(layers "F.Cu" "B.Cu")
		(net "SPI_PEX2_CS_MUX_R_N")
	)
	(segment
		(start 257.531108 -227.867464)
		(end 257.531108 -226.92487)
		(width 0.13208)
		(layer "B.Cu")
		(net "SPI_PEX2_CS_MUX_R_N")
	)
	(segment
		(start 257.529838 -227.868734)
		(end 257.531108 -227.867464)
		(width 0.13208)
		(layer "B.Cu")
		(net "SPI_PEX2_CS_MUX_R_N")
	)
	(segment
		(start 259.393182 -227.332032)
		(end 259.437632 -227.332032)
		(width 0.13208)
		(layer "B.Cu")
		(net "SPI_PEX2_CS_MUX_R_N")
	)
	(segment
		(start 257.531108 -227.867464)
		(end 257.609594 -227.94595)
		(width 0.13208)
		(layer "B.Cu")
		(net "SPI_PEX2_CS_MUX_R_N")
	)
	(segment
		(start 258.779264 -227.94595)
		(end 259.393182 -227.332032)
		(width 0.13208)
		(layer "B.Cu")
		(net "SPI_PEX2_CS_MUX_R_N")
	)
	(segment
		(start 257.609594 -227.94595)
		(end 258.779264 -227.94595)
		(width 0.13208)
		(layer "B.Cu")
		(net "SPI_PEX2_CS_MUX_R_N")
	)
	(segment
		(start 426.57014 -319.864232)
		(end 426.57014 -318.434466)
		(width 0.1143)
		(layer "In5.Cu")
		(net "P5E_PEX3_STN4_RX_DN<74>")
	)
	(segment
		(start 416.552634 -368.595148)
		(end 416.79368 -368.045746)
		(width 0.1651)
		(layer "In5.Cu")
		(net "P5E_PEX3_STN4_RX_DN<74>")
	)
	(segment
		(start 426.61586 -324.806818)
		(end 426.61586 -319.9384)
		(width 0.1651)
		(layer "In5.Cu")
		(net "P5E_PEX3_STN4_RX_DN<74>")
	)
	(segment
		(start 416.237674 -384.264916)
		(end 416.27679 -369.983766)
		(width 0.1651)
		(layer "In5.Cu")
		(net "P5E_PEX3_STN4_RX_DN<74>")
	)
	(segment
		(start 431.302668 -395.239494)
		(end 429.419766 -393.432284)
		(width 0.1651)
		(layer "In5.Cu")
		(net "P5E_PEX3_STN4_RX_DN<74>")
	)
	(segment
		(start 431.150268 -406.184862)
		(end 431.647854 -405.687276)
		(width 0.1651)
		(layer "In5.Cu")
		(net "P5E_PEX3_STN4_RX_DN<74>")
	)
	(segment
		(start 416.27679 -369.983766)
		(end 416.552634 -368.595148)
		(width 0.1651)
		(layer "In5.Cu")
		(net "P5E_PEX3_STN4_RX_DN<74>")
	)
	(segment
		(start 429.419766 -393.432284)
		(end 418.17798 -387.40842)
		(width 0.1651)
		(layer "In5.Cu")
		(net "P5E_PEX3_STN4_RX_DN<74>")
	)
	(segment
		(start 426.68444 -318.320166)
		(end 426.83557 -318.320166)
		(width 0.1143)
		(layer "In5.Cu")
		(net "P5E_PEX3_STN4_RX_DN<74>")
	)
	(segment
		(start 426.61586 -319.909952)
		(end 426.57014 -319.864232)
		(width 0.1143)
		(layer "In5.Cu")
		(net "P5E_PEX3_STN4_RX_DN<74>")
	)
	(segment
		(start 430.489868 -406.35809)
		(end 430.663096 -406.184862)
		(width 0.1651)
		(layer "In5.Cu")
		(net "P5E_PEX3_STN4_RX_DN<74>")
	)
	(segment
		(start 431.647854 -396.17396)
		(end 431.302668 -395.239494)
		(width 0.1651)
		(layer "In5.Cu")
		(net "P5E_PEX3_STN4_RX_DN<74>")
	)
	(segment
		(start 423.858182 -341.935054)
		(end 426.61586 -324.806818)
		(width 0.1651)
		(layer "In5.Cu")
		(net "P5E_PEX3_STN4_RX_DN<74>")
	)
	(segment
		(start 423.858182 -358.374442)
		(end 423.858182 -341.935054)
		(width 0.1651)
		(layer "In5.Cu")
		(net "P5E_PEX3_STN4_RX_DN<74>")
	)
	(segment
		(start 426.61586 -319.9384)
		(end 426.61586 -319.909952)
		(width 0.1143)
		(layer "In5.Cu")
		(net "P5E_PEX3_STN4_RX_DN<74>")
	)
	(segment
		(start 426.57014 -318.434466)
		(end 426.68444 -318.320166)
		(width 0.1143)
		(layer "In5.Cu")
		(net "P5E_PEX3_STN4_RX_DN<74>")
	)
	(segment
		(start 417.039044 -386.257292)
		(end 416.237674 -384.264916)
		(width 0.1651)
		(layer "In5.Cu")
		(net "P5E_PEX3_STN4_RX_DN<74>")
	)
	(segment
		(start 418.17798 -387.40842)
		(end 417.039044 -386.257292)
		(width 0.1651)
		(layer "In5.Cu")
		(net "P5E_PEX3_STN4_RX_DN<74>")
	)
	(segment
		(start 430.489868 -406.690068)
		(end 430.489868 -406.35809)
		(width 0.1651)
		(layer "In5.Cu")
		(net "P5E_PEX3_STN4_RX_DN<74>")
	)
	(segment
		(start 416.79368 -368.045746)
		(end 423.858182 -358.374442)
		(width 0.1651)
		(layer "In5.Cu")
		(net "P5E_PEX3_STN4_RX_DN<74>")
	)
	(segment
		(start 430.663096 -406.184862)
		(end 431.150268 -406.184862)
		(width 0.1651)
		(layer "In5.Cu")
		(net "P5E_PEX3_STN4_RX_DN<74>")
	)
	(segment
		(start 431.647854 -405.687276)
		(end 431.647854 -396.17396)
		(width 0.1651)
		(layer "In5.Cu")
		(net "P5E_PEX3_STN4_RX_DN<74>")
	)
	(segment
		(start 426.83557 -318.320166)
		(end 426.94987 -318.434466)
		(width 0.1143)
		(layer "In5.Cu")
		(net "P5E_PEX3_STN4_RX_DN<74>")
	)
	(segment
		(start 426.94987 -318.434466)
		(end 426.94987 -318.699896)
		(width 0.1143)
		(layer "In5.Cu")
		(net "P5E_PEX3_STN4_RX_DN<74>")
	)
	(segment
		(start 425.134024 -355.658674)
		(end 425.134024 -355.026214)
		(width 0.13462)
		(layer "F.Cu")
		(net "P5E_PEX3_STN4_TX_DP<71>")
	)
	(segment
		(start 424.814492 -355.978206)
		(end 425.134024 -355.658674)
		(width 0.13462)
		(layer "F.Cu")
		(net "P5E_PEX3_STN4_TX_DP<71>")
	)
	(segment
		(start 425.134024 -355.026214)
		(end 424.839892 -354.732082)
		(width 0.13462)
		(layer "F.Cu")
		(net "P5E_PEX3_STN4_TX_DP<71>")
	)
	(segment
		(start 430.134014 -321.113658)
		(end 430.134014 -319.027048)
		(width 0.1651)
		(layer "In7.Cu")
		(net "P5E_PEX3_STN4_TX_DP<71>")
	)
	(segment
		(start 430.134014 -318.9986)
		(end 430.179734 -318.95288)
		(width 0.1143)
		(layer "In7.Cu")
		(net "P5E_PEX3_STN4_TX_DP<71>")
	)
	(segment
		(start 430.065434 -314.899802)
		(end 429.800004 -314.899802)
		(width 0.1143)
		(layer "In7.Cu")
		(net "P5E_PEX3_STN4_TX_DP<71>")
	)
	(segment
		(start 426.685202 -341.406988)
		(end 430.134014 -321.113658)
		(width 0.1651)
		(layer "In7.Cu")
		(net "P5E_PEX3_STN4_TX_DP<71>")
	)
	(segment
		(start 430.134014 -319.027048)
		(end 430.134014 -318.9986)
		(width 0.1143)
		(layer "In7.Cu")
		(net "P5E_PEX3_STN4_TX_DP<71>")
	)
	(segment
		(start 426.685202 -352.259646)
		(end 426.685202 -341.406988)
		(width 0.1651)
		(layer "In7.Cu")
		(net "P5E_PEX3_STN4_TX_DP<71>")
	)
	(segment
		(start 425.130722 -353.814126)
		(end 426.685202 -352.259646)
		(width 0.1651)
		(layer "In7.Cu")
		(net "P5E_PEX3_STN4_TX_DP<71>")
	)
	(segment
		(start 425.130722 -354.441252)
		(end 425.130722 -353.814126)
		(width 0.1651)
		(layer "In7.Cu")
		(net "P5E_PEX3_STN4_TX_DP<71>")
	)
	(segment
		(start 430.179734 -318.95288)
		(end 430.179734 -315.014102)
		(width 0.1143)
		(layer "In7.Cu")
		(net "P5E_PEX3_STN4_TX_DP<71>")
	)
	(segment
		(start 424.839892 -354.732082)
		(end 425.130722 -354.441252)
		(width 0.1651)
		(layer "In7.Cu")
		(net "P5E_PEX3_STN4_TX_DP<71>")
	)
	(segment
		(start 430.179734 -315.014102)
		(end 430.065434 -314.899802)
		(width 0.1143)
		(layer "In7.Cu")
		(net "P5E_PEX3_STN4_TX_DP<71>")
	)
	(segment
		(start 250.694444 -221.949518)
		(end 248.561098 -221.949518)
		(width 0.13208)
		(layer "F.Cu")
		(net "SPI_PEX2_SDIO0_MUX_R")
	)
	(segment
		(start 248.185686 -222.32493)
		(end 247.099582 -222.32493)
		(width 0.13208)
		(layer "F.Cu")
		(net "SPI_PEX2_SDIO0_MUX_R")
	)
	(segment
		(start 252.080014 -221.081092)
		(end 251.577094 -221.584012)
		(width 0.13208)
		(layer "F.Cu")
		(net "SPI_PEX2_SDIO0_MUX_R")
	)
	(segment
		(start 251.577094 -221.584012)
		(end 250.694444 -221.949518)
		(width 0.13208)
		(layer "F.Cu")
		(net "SPI_PEX2_SDIO0_MUX_R")
	)
	(segment
		(start 248.561098 -221.949518)
		(end 248.185686 -222.32493)
		(width 0.13208)
		(layer "F.Cu")
		(net "SPI_PEX2_SDIO0_MUX_R")
	)
	(via
		(at 252.080014 -221.081092)
		(size 0.508)
		(drill 0.254)
		(layers "F.Cu" "B.Cu")
		(net "SPI_PEX2_SDIO0_MUX_R")
	)
	(segment
		(start 253.398528 -221.081092)
		(end 252.080014 -221.081092)
		(width 0.13208)
		(layer "B.Cu")
		(net "SPI_PEX2_SDIO0_MUX_R")
	)
	(segment
		(start 428.950374 -379.08484)
		(end 428.463202 -379.08484)
		(width 0.1651)
		(layer "In5.Cu")
		(net "P5E_PEX3_STN4_RX_DN<67>")
	)
	(segment
		(start 428.289974 -379.258068)
		(end 428.289974 -379.590046)
		(width 0.1651)
		(layer "In5.Cu")
		(net "P5E_PEX3_STN4_RX_DN<67>")
	)
	(segment
		(start 442.838078 -359.517442)
		(end 436.990998 -363.90834)
		(width 0.1651)
		(layer "In5.Cu")
		(net "P5E_PEX3_STN4_RX_DN<67>")
	)
	(segment
		(start 439.166 -313.73572)
		(end 440.384438 -314.240418)
		(width 0.1651)
		(layer "In5.Cu")
		(net "P5E_PEX3_STN4_RX_DN<67>")
	)
	(segment
		(start 444.519558 -318.375538)
		(end 444.519558 -321.896232)
		(width 0.1651)
		(layer "In5.Cu")
		(net "P5E_PEX3_STN4_RX_DN<67>")
	)
	(segment
		(start 432.050952 -307.633878)
		(end 433.153566 -307.633878)
		(width 0.1651)
		(layer "In5.Cu")
		(net "P5E_PEX3_STN4_RX_DN<67>")
	)
	(segment
		(start 433.153566 -307.633878)
		(end 434.067712 -308.012592)
		(width 0.1651)
		(layer "In5.Cu")
		(net "P5E_PEX3_STN4_RX_DN<67>")
	)
	(segment
		(start 434.067712 -308.012592)
		(end 435.186074 -309.130954)
		(width 0.1651)
		(layer "In5.Cu")
		(net "P5E_PEX3_STN4_RX_DN<67>")
	)
	(segment
		(start 429.44796 -378.587254)
		(end 428.950374 -379.08484)
		(width 0.1651)
		(layer "In5.Cu")
		(net "P5E_PEX3_STN4_RX_DN<67>")
	)
	(segment
		(start 428.84979 -307.299868)
		(end 428.58436 -307.299868)
		(width 0.1143)
		(layer "In5.Cu")
		(net "P5E_PEX3_STN4_RX_DN<67>")
	)
	(segment
		(start 429.44796 -369.657376)
		(end 429.44796 -378.587254)
		(width 0.1651)
		(layer "In5.Cu")
		(net "P5E_PEX3_STN4_RX_DN<67>")
	)
	(segment
		(start 440.384438 -314.240418)
		(end 444.519558 -318.375538)
		(width 0.1651)
		(layer "In5.Cu")
		(net "P5E_PEX3_STN4_RX_DN<67>")
	)
	(segment
		(start 429.8696 -368.639344)
		(end 429.44796 -369.657376)
		(width 0.1651)
		(layer "In5.Cu")
		(net "P5E_PEX3_STN4_RX_DN<67>")
	)
	(segment
		(start 428.47006 -307.414168)
		(end 428.47006 -307.565298)
		(width 0.1143)
		(layer "In5.Cu")
		(net "P5E_PEX3_STN4_RX_DN<67>")
	)
	(segment
		(start 428.58436 -307.299868)
		(end 428.47006 -307.414168)
		(width 0.1143)
		(layer "In5.Cu")
		(net "P5E_PEX3_STN4_RX_DN<67>")
	)
	(segment
		(start 428.58436 -307.679598)
		(end 431.976784 -307.679598)
		(width 0.1143)
		(layer "In5.Cu")
		(net "P5E_PEX3_STN4_RX_DN<67>")
	)
	(segment
		(start 436.990998 -363.90834)
		(end 430.150524 -368.35842)
		(width 0.1651)
		(layer "In5.Cu")
		(net "P5E_PEX3_STN4_RX_DN<67>")
	)
	(segment
		(start 432.022504 -307.633878)
		(end 432.050952 -307.633878)
		(width 0.1143)
		(layer "In5.Cu")
		(net "P5E_PEX3_STN4_RX_DN<67>")
	)
	(segment
		(start 431.976784 -307.679598)
		(end 432.022504 -307.633878)
		(width 0.1143)
		(layer "In5.Cu")
		(net "P5E_PEX3_STN4_RX_DN<67>")
	)
	(segment
		(start 428.463202 -379.08484)
		(end 428.289974 -379.258068)
		(width 0.1651)
		(layer "In5.Cu")
		(net "P5E_PEX3_STN4_RX_DN<67>")
	)
	(segment
		(start 435.186074 -309.130954)
		(end 435.628034 -310.197754)
		(width 0.1651)
		(layer "In5.Cu")
		(net "P5E_PEX3_STN4_RX_DN<67>")
	)
	(segment
		(start 430.150524 -368.35842)
		(end 429.8696 -368.639344)
		(width 0.1651)
		(layer "In5.Cu")
		(net "P5E_PEX3_STN4_RX_DN<67>")
	)
	(segment
		(start 443.522608 -358.192832)
		(end 442.838078 -359.517442)
		(width 0.1651)
		(layer "In5.Cu")
		(net "P5E_PEX3_STN4_RX_DN<67>")
	)
	(segment
		(start 444.519558 -321.896232)
		(end 443.522608 -358.192832)
		(width 0.1651)
		(layer "In5.Cu")
		(net "P5E_PEX3_STN4_RX_DN<67>")
	)
	(segment
		(start 435.628034 -310.197754)
		(end 439.166 -313.73572)
		(width 0.1651)
		(layer "In5.Cu")
		(net "P5E_PEX3_STN4_RX_DN<67>")
	)
	(segment
		(start 428.47006 -307.565298)
		(end 428.58436 -307.679598)
		(width 0.1143)
		(layer "In5.Cu")
		(net "P5E_PEX3_STN4_RX_DN<67>")
	)
	(segment
		(start 25.763982 -53.96357)
		(end 25.867868 -54.067456)
		(width 0.13208)
		(layer "F.Cu")
		(net "P12V_SSD0_OCP")
	)
	(segment
		(start 24.147272 -54.144164)
		(end 24.575516 -54.144164)
		(width 0.13208)
		(layer "F.Cu")
		(net "P12V_SSD0_OCP")
	)
	(segment
		(start 24.575516 -54.144164)
		(end 24.75611 -53.96357)
		(width 0.13208)
		(layer "F.Cu")
		(net "P12V_SSD0_OCP")
	)
	(segment
		(start 25.154128 -53.96357)
		(end 25.763982 -53.96357)
		(width 0.13208)
		(layer "F.Cu")
		(net "P12V_SSD0_OCP")
	)
	(segment
		(start 24.75611 -53.96357)
		(end 25.154128 -53.96357)
		(width 0.13208)
		(layer "F.Cu")
		(net "P12V_SSD0_OCP")
	)
	(via
		(at 25.154128 -53.96357)
		(size 0.508)
		(drill 0.254)
		(layers "F.Cu" "B.Cu")
		(net "P12V_SSD0_OCP")
	)
	(segment
		(start 275.699728 -294.94988)
		(end 275.224748 -294.4749)
		(width 0.13208)
		(layer "F.Cu")
		(net "SPI_PEX2_SDIO1")
	)
	(via
		(at 275.224748 -294.4749)
		(size 0.4064)
		(drill 0.2032)
		(layers "F.Cu" "B.Cu")
		(net "SPI_PEX2_SDIO1")
	)
	(via
		(at 274.749768 -295.89984)
		(size 0.6604)
		(drill 0.3302)
		(layers "F.Cu" "B.Cu")
		(net "SPI_PEX2_SDIO1")
	)
	(segment
		(start 274.749768 -295.89984)
		(end 275.224748 -295.42486)
		(width 0.13208)
		(layer "B.Cu")
		(net "SPI_PEX2_SDIO1")
	)
	(segment
		(start 274.082764 -295.89984)
		(end 273.031204 -296.9514)
		(width 0.13208)
		(layer "B.Cu")
		(net "SPI_PEX2_SDIO1")
	)
	(segment
		(start 273.031204 -296.9514)
		(end 272.773648 -296.9514)
		(width 0.13208)
		(layer "B.Cu")
		(net "SPI_PEX2_SDIO1")
	)
	(segment
		(start 275.224748 -295.42486)
		(end 275.224748 -294.4749)
		(width 0.13208)
		(layer "B.Cu")
		(net "SPI_PEX2_SDIO1")
	)
	(segment
		(start 274.749768 -295.89984)
		(end 274.082764 -295.89984)
		(width 0.13208)
		(layer "B.Cu")
		(net "SPI_PEX2_SDIO1")
	)
	(segment
		(start 431.980848 -310.765698)
		(end 432.214528 -310.765698)
		(width 0.1651)
		(layer "In5.Cu")
		(net "P5E_PEX3_STN4_RX_DP<70>")
	)
	(segment
		(start 426.013118 -365.962438)
		(end 425.613068 -366.254284)
		(width 0.1651)
		(layer "In5.Cu")
		(net "P5E_PEX3_STN4_RX_DP<70>")
	)
	(segment
		(start 430.976278 -362.20146)
		(end 430.951386 -362.361226)
		(width 0.1651)
		(layer "In5.Cu")
		(net "P5E_PEX3_STN4_RX_DP<70>")
	)
	(segment
		(start 425.613068 -366.254284)
		(end 425.453302 -366.229392)
		(width 0.1651)
		(layer "In5.Cu")
		(net "P5E_PEX3_STN4_RX_DP<70>")
	)
	(segment
		(start 426.494448 -365.519462)
		(end 426.029374 -365.858806)
		(width 0.1651)
		(layer "In5.Cu")
		(net "P5E_PEX3_STN4_RX_DP<70>")
	)
	(segment
		(start 432.214528 -310.765698)
		(end 432.347624 -310.898794)
		(width 0.1651)
		(layer "In5.Cu")
		(net "P5E_PEX3_STN4_RX_DP<70>")
	)
	(segment
		(start 429.991266 -362.920026)
		(end 429.966374 -363.079538)
		(width 0.1651)
		(layer "In5.Cu")
		(net "P5E_PEX3_STN4_RX_DP<70>")
	)
	(segment
		(start 425.052998 -366.521492)
		(end 425.027852 -366.681258)
		(width 0.1651)
		(layer "In5.Cu")
		(net "P5E_PEX3_STN4_RX_DP<70>")
	)
	(segment
		(start 430.179734 -310.264048)
		(end 430.179734 -310.494172)
		(width 0.1143)
		(layer "In5.Cu")
		(net "P5E_PEX3_STN4_RX_DP<70>")
	)
	(segment
		(start 431.68189 -322.802504)
		(end 436.012082 -342.464136)
		(width 0.1651)
		(layer "In5.Cu")
		(net "P5E_PEX3_STN4_RX_DP<70>")
	)
	(segment
		(start 430.39157 -362.627926)
		(end 429.991266 -362.920026)
		(width 0.1651)
		(layer "In5.Cu")
		(net "P5E_PEX3_STN4_RX_DP<70>")
	)
	(segment
		(start 431.936652 -361.64266)
		(end 431.536602 -361.934252)
		(width 0.1651)
		(layer "In5.Cu")
		(net "P5E_PEX3_STN4_RX_DP<70>")
	)
	(segment
		(start 426.998384 -365.244126)
		(end 426.598334 -365.535718)
		(width 0.1651)
		(layer "In5.Cu")
		(net "P5E_PEX3_STN4_RX_DP<70>")
	)
	(segment
		(start 431.961798 -361.482894)
		(end 431.936652 -361.64266)
		(width 0.1651)
		(layer "In5.Cu")
		(net "P5E_PEX3_STN4_RX_DP<70>")
	)
	(segment
		(start 430.179734 -310.494172)
		(end 430.40554 -310.719978)
		(width 0.1143)
		(layer "In5.Cu")
		(net "P5E_PEX3_STN4_RX_DP<70>")
	)
	(segment
		(start 432.46167 -316.943994)
		(end 431.68189 -318.826896)
		(width 0.1651)
		(layer "In5.Cu")
		(net "P5E_PEX3_STN4_RX_DP<70>")
	)
	(segment
		(start 427.47946 -364.800896)
		(end 427.01464 -365.139986)
		(width 0.1651)
		(layer "In5.Cu")
		(net "P5E_PEX3_STN4_RX_DP<70>")
	)
	(segment
		(start 432.347624 -310.898794)
		(end 432.46167 -311.17413)
		(width 0.1651)
		(layer "In5.Cu")
		(net "P5E_PEX3_STN4_RX_DP<70>")
	)
	(segment
		(start 430.40554 -310.719978)
		(end 431.90668 -310.719978)
		(width 0.1143)
		(layer "In5.Cu")
		(net "P5E_PEX3_STN4_RX_DP<70>")
	)
	(segment
		(start 436.012082 -358.400858)
		(end 435.793642 -358.829864)
		(width 0.1651)
		(layer "In5.Cu")
		(net "P5E_PEX3_STN4_RX_DP<70>")
	)
	(segment
		(start 431.9524 -310.765698)
		(end 431.980848 -310.765698)
		(width 0.1143)
		(layer "In5.Cu")
		(net "P5E_PEX3_STN4_RX_DP<70>")
	)
	(segment
		(start 429.966374 -363.079538)
		(end 427.5836 -364.817152)
		(width 0.1651)
		(layer "In5.Cu")
		(net "P5E_PEX3_STN4_RX_DP<70>")
	)
	(segment
		(start 432.521868 -361.215686)
		(end 432.362102 -361.190794)
		(width 0.1651)
		(layer "In5.Cu")
		(net "P5E_PEX3_STN4_RX_DP<70>")
	)
	(segment
		(start 430.951386 -362.361226)
		(end 430.551336 -362.652818)
		(width 0.1651)
		(layer "In5.Cu")
		(net "P5E_PEX3_STN4_RX_DP<70>")
	)
	(segment
		(start 436.012082 -342.464136)
		(end 436.012082 -358.400858)
		(width 0.1651)
		(layer "In5.Cu")
		(net "P5E_PEX3_STN4_RX_DP<70>")
	)
	(segment
		(start 431.90668 -310.719978)
		(end 431.9524 -310.765698)
		(width 0.1143)
		(layer "In5.Cu")
		(net "P5E_PEX3_STN4_RX_DP<70>")
	)
	(segment
		(start 431.376836 -361.90936)
		(end 430.976278 -362.20146)
		(width 0.1651)
		(layer "In5.Cu")
		(net "P5E_PEX3_STN4_RX_DP<70>")
	)
	(segment
		(start 435.793642 -358.829864)
		(end 432.521868 -361.215686)
		(width 0.1651)
		(layer "In5.Cu")
		(net "P5E_PEX3_STN4_RX_DP<70>")
	)
	(segment
		(start 431.68189 -318.826896)
		(end 431.68189 -322.802504)
		(width 0.1651)
		(layer "In5.Cu")
		(net "P5E_PEX3_STN4_RX_DP<70>")
	)
	(segment
		(start 430.065434 -310.149748)
		(end 430.179734 -310.264048)
		(width 0.1143)
		(layer "In5.Cu")
		(net "P5E_PEX3_STN4_RX_DP<70>")
	)
	(segment
		(start 432.362102 -361.190794)
		(end 431.961798 -361.482894)
		(width 0.1651)
		(layer "In5.Cu")
		(net "P5E_PEX3_STN4_RX_DP<70>")
	)
	(segment
		(start 429.800004 -310.149748)
		(end 430.065434 -310.149748)
		(width 0.1143)
		(layer "In5.Cu")
		(net "P5E_PEX3_STN4_RX_DP<70>")
	)
	(segment
		(start 427.01464 -365.139986)
		(end 426.998384 -365.244126)
		(width 0.1651)
		(layer "In5.Cu")
		(net "P5E_PEX3_STN4_RX_DP<70>")
	)
	(segment
		(start 427.5836 -364.817152)
		(end 427.47946 -364.800896)
		(width 0.1651)
		(layer "In5.Cu")
		(net "P5E_PEX3_STN4_RX_DP<70>")
	)
	(segment
		(start 421.863012 -379.902974)
		(end 421.689784 -379.729746)
		(width 0.1651)
		(layer "In5.Cu")
		(net "P5E_PEX3_STN4_RX_DP<70>")
	)
	(segment
		(start 422.56583 -369.313206)
		(end 422.56583 -379.570488)
		(width 0.1651)
		(layer "In5.Cu")
		(net "P5E_PEX3_STN4_RX_DP<70>")
	)
	(segment
		(start 432.46167 -311.17413)
		(end 432.46167 -316.943994)
		(width 0.1651)
		(layer "In5.Cu")
		(net "P5E_PEX3_STN4_RX_DP<70>")
	)
	(segment
		(start 426.598334 -365.535718)
		(end 426.494448 -365.519462)
		(width 0.1651)
		(layer "In5.Cu")
		(net "P5E_PEX3_STN4_RX_DP<70>")
	)
	(segment
		(start 430.551336 -362.652818)
		(end 430.39157 -362.627926)
		(width 0.1651)
		(layer "In5.Cu")
		(net "P5E_PEX3_STN4_RX_DP<70>")
	)
	(segment
		(start 422.233344 -379.902974)
		(end 421.863012 -379.902974)
		(width 0.1651)
		(layer "In5.Cu")
		(net "P5E_PEX3_STN4_RX_DP<70>")
	)
	(segment
		(start 425.453302 -366.229392)
		(end 425.052998 -366.521492)
		(width 0.1651)
		(layer "In5.Cu")
		(net "P5E_PEX3_STN4_RX_DP<70>")
	)
	(segment
		(start 426.029374 -365.858806)
		(end 426.013118 -365.962438)
		(width 0.1651)
		(layer "In5.Cu")
		(net "P5E_PEX3_STN4_RX_DP<70>")
	)
	(segment
		(start 422.56583 -379.570488)
		(end 422.233344 -379.902974)
		(width 0.1651)
		(layer "In5.Cu")
		(net "P5E_PEX3_STN4_RX_DP<70>")
	)
	(segment
		(start 431.536602 -361.934252)
		(end 431.376836 -361.90936)
		(width 0.1651)
		(layer "In5.Cu")
		(net "P5E_PEX3_STN4_RX_DP<70>")
	)
	(segment
		(start 423.258234 -367.971832)
		(end 422.56583 -369.313206)
		(width 0.1651)
		(layer "In5.Cu")
		(net "P5E_PEX3_STN4_RX_DP<70>")
	)
	(segment
		(start 421.689784 -379.729746)
		(end 421.689784 -379.390148)
		(width 0.1651)
		(layer "In5.Cu")
		(net "P5E_PEX3_STN4_RX_DP<70>")
	)
	(segment
		(start 425.027852 -366.681258)
		(end 423.258234 -367.971832)
		(width 0.1651)
		(layer "In5.Cu")
		(net "P5E_PEX3_STN4_RX_DP<70>")
	)
	(segment
		(start 24.475948 -51.67503)
		(end 24.475948 -52.933092)
		(width 0.13208)
		(layer "F.Cu")
		(net "P12V_SSD0_SS")
	)
	(segment
		(start 24.475948 -52.933092)
		(end 24.264874 -53.144166)
		(width 0.13208)
		(layer "F.Cu")
		(net "P12V_SSD0_SS")
	)
	(segment
		(start 24.264874 -53.144166)
		(end 24.147272 -53.144166)
		(width 0.13208)
		(layer "F.Cu")
		(net "P12V_SSD0_SS")
	)
	(segment
		(start 25.867868 -51.019456)
		(end 25.131522 -51.019456)
		(width 0.13208)
		(layer "F.Cu")
		(net "P12V_SSD0_SS")
	)
	(segment
		(start 25.131522 -51.019456)
		(end 24.475948 -51.67503)
		(width 0.13208)
		(layer "F.Cu")
		(net "P12V_SSD0_SS")
	)
	(via
		(at 25.131522 -51.019456)
		(size 0.508)
		(drill 0.254)
		(layers "F.Cu" "B.Cu")
		(net "P12V_SSD0_SS")
	)
	(segment
		(start 274.749768 -294.94988)
		(end 274.274788 -294.4749)
		(width 0.13208)
		(layer "F.Cu")
		(net "SPI_PEX2_SDIO0")
	)
	(via
		(at 274.274788 -294.4749)
		(size 0.508)
		(drill 0.254)
		(layers "F.Cu" "B.Cu")
		(net "SPI_PEX2_SDIO0")
	)
	(segment
		(start 273.5834 -295.79824)
		(end 272.773648 -295.79824)
		(width 0.13208)
		(layer "B.Cu")
		(net "SPI_PEX2_SDIO0")
	)
	(segment
		(start 274.274788 -294.4749)
		(end 274.274788 -295.106852)
		(width 0.13208)
		(layer "B.Cu")
		(net "SPI_PEX2_SDIO0")
	)
	(segment
		(start 274.274788 -295.106852)
		(end 273.5834 -295.79824)
		(width 0.13208)
		(layer "B.Cu")
		(net "SPI_PEX2_SDIO0")
	)
	(segment
		(start 411.222952 -364.334044)
		(end 411.314646 -364.42015)
		(width 0.1651)
		(layer "In5.Cu")
		(net "P5E_PEX3_STN4_RX_DP<78>")
	)
	(segment
		(start 422.56583 -405.570436)
		(end 422.233344 -405.902922)
		(width 0.1651)
		(layer "In5.Cu")
		(net "P5E_PEX3_STN4_RX_DP<78>")
	)
	(segment
		(start 411.140402 -358.832912)
		(end 411.293564 -363.74705)
		(width 0.1651)
		(layer "In5.Cu")
		(net "P5E_PEX3_STN4_RX_DP<78>")
	)
	(segment
		(start 423.03573 -318.129666)
		(end 422.805606 -318.129666)
		(width 0.1143)
		(layer "In5.Cu")
		(net "P5E_PEX3_STN4_RX_DP<78>")
	)
	(segment
		(start 415.66211 -390.779)
		(end 421.175942 -394.315442)
		(width 0.1651)
		(layer "In5.Cu")
		(net "P5E_PEX3_STN4_RX_DP<78>")
	)
	(segment
		(start 422.805606 -318.129666)
		(end 422.5798 -318.355472)
		(width 0.1143)
		(layer "In5.Cu")
		(net "P5E_PEX3_STN4_RX_DP<78>")
	)
	(segment
		(start 421.175942 -394.315442)
		(end 422.331896 -395.454632)
		(width 0.1651)
		(layer "In5.Cu")
		(net "P5E_PEX3_STN4_RX_DP<78>")
	)
	(segment
		(start 423.15003 -317.749936)
		(end 423.15003 -318.015366)
		(width 0.1143)
		(layer "In5.Cu")
		(net "P5E_PEX3_STN4_RX_DP<78>")
	)
	(segment
		(start 411.293564 -363.74705)
		(end 411.207458 -363.838744)
		(width 0.1651)
		(layer "In5.Cu")
		(net "P5E_PEX3_STN4_RX_DP<78>")
	)
	(segment
		(start 421.863012 -405.902922)
		(end 421.689784 -405.729694)
		(width 0.1651)
		(layer "In5.Cu")
		(net "P5E_PEX3_STN4_RX_DP<78>")
	)
	(segment
		(start 411.949646 -384.770884)
		(end 413.575246 -388.814056)
		(width 0.1651)
		(layer "In5.Cu")
		(net "P5E_PEX3_STN4_RX_DP<78>")
	)
	(segment
		(start 422.56583 -395.869668)
		(end 422.56583 -405.570436)
		(width 0.1651)
		(layer "In5.Cu")
		(net "P5E_PEX3_STN4_RX_DP<78>")
	)
	(segment
		(start 422.53408 -319.909952)
		(end 422.53408 -319.9384)
		(width 0.1143)
		(layer "In5.Cu")
		(net "P5E_PEX3_STN4_RX_DP<78>")
	)
	(segment
		(start 411.207458 -363.838744)
		(end 411.222952 -364.334044)
		(width 0.1651)
		(layer "In5.Cu")
		(net "P5E_PEX3_STN4_RX_DP<78>")
	)
	(segment
		(start 423.15003 -318.015366)
		(end 423.03573 -318.129666)
		(width 0.1143)
		(layer "In5.Cu")
		(net "P5E_PEX3_STN4_RX_DP<78>")
	)
	(segment
		(start 422.53408 -321.84848)
		(end 411.140402 -341.860378)
		(width 0.1651)
		(layer "In5.Cu")
		(net "P5E_PEX3_STN4_RX_DP<78>")
	)
	(segment
		(start 422.233344 -405.902922)
		(end 421.863012 -405.902922)
		(width 0.1651)
		(layer "In5.Cu")
		(net "P5E_PEX3_STN4_RX_DP<78>")
	)
	(segment
		(start 422.5798 -319.864232)
		(end 422.53408 -319.909952)
		(width 0.1143)
		(layer "In5.Cu")
		(net "P5E_PEX3_STN4_RX_DP<78>")
	)
	(segment
		(start 411.140402 -341.860378)
		(end 411.140402 -358.832912)
		(width 0.1651)
		(layer "In5.Cu")
		(net "P5E_PEX3_STN4_RX_DP<78>")
	)
	(segment
		(start 411.314646 -364.42015)
		(end 411.949646 -384.770884)
		(width 0.1651)
		(layer "In5.Cu")
		(net "P5E_PEX3_STN4_RX_DP<78>")
	)
	(segment
		(start 422.5798 -318.355472)
		(end 422.5798 -319.864232)
		(width 0.1143)
		(layer "In5.Cu")
		(net "P5E_PEX3_STN4_RX_DP<78>")
	)
	(segment
		(start 421.689784 -405.729694)
		(end 421.689784 -405.390096)
		(width 0.1651)
		(layer "In5.Cu")
		(net "P5E_PEX3_STN4_RX_DP<78>")
	)
	(segment
		(start 422.331896 -395.454632)
		(end 422.56583 -395.869668)
		(width 0.1651)
		(layer "In5.Cu")
		(net "P5E_PEX3_STN4_RX_DP<78>")
	)
	(segment
		(start 413.575246 -388.814056)
		(end 415.66211 -390.779)
		(width 0.1651)
		(layer "In5.Cu")
		(net "P5E_PEX3_STN4_RX_DP<78>")
	)
	(segment
		(start 422.53408 -319.9384)
		(end 422.53408 -321.84848)
		(width 0.1651)
		(layer "In5.Cu")
		(net "P5E_PEX3_STN4_RX_DP<78>")
	)
	(segment
		(start 409.863544 -348.880938)
		(end 410.158692 -348.58579)
		(width 0.13462)
		(layer "F.Cu")
		(net "P5E_PEX3_STN4_TX_DN<79>")
	)
	(segment
		(start 410.184092 -349.831914)
		(end 409.863544 -349.511366)
		(width 0.13462)
		(layer "F.Cu")
		(net "P5E_PEX3_STN4_TX_DN<79>")
	)
	(segment
		(start 409.863544 -349.511366)
		(end 409.863544 -348.880938)
		(width 0.13462)
		(layer "F.Cu")
		(net "P5E_PEX3_STN4_TX_DN<79>")
	)
	(segment
		(start 421.820086 -311.784492)
		(end 421.934386 -311.670192)
		(width 0.1143)
		(layer "In7.Cu")
		(net "P5E_PEX3_STN4_TX_DN<79>")
	)
	(segment
		(start 421.6019 -321.751706)
		(end 421.865806 -320.674746)
		(width 0.1651)
		(layer "In7.Cu")
		(net "P5E_PEX3_STN4_TX_DN<79>")
	)
	(segment
		(start 422.199816 -311.784492)
		(end 422.199816 -312.049922)
		(width 0.1143)
		(layer "In7.Cu")
		(net "P5E_PEX3_STN4_TX_DN<79>")
	)
	(segment
		(start 422.085516 -311.670192)
		(end 422.199816 -311.784492)
		(width 0.1143)
		(layer "In7.Cu")
		(net "P5E_PEX3_STN4_TX_DN<79>")
	)
	(segment
		(start 411.422342 -346.230194)
		(end 411.422342 -341.271352)
		(width 0.1651)
		(layer "In7.Cu")
		(net "P5E_PEX3_STN4_TX_DN<79>")
	)
	(segment
		(start 409.867862 -348.29496)
		(end 409.867862 -347.784674)
		(width 0.1651)
		(layer "In7.Cu")
		(net "P5E_PEX3_STN4_TX_DN<79>")
	)
	(segment
		(start 421.934386 -311.670192)
		(end 422.085516 -311.670192)
		(width 0.1143)
		(layer "In7.Cu")
		(net "P5E_PEX3_STN4_TX_DN<79>")
	)
	(segment
		(start 421.865806 -320.674746)
		(end 421.865806 -319.995296)
		(width 0.1651)
		(layer "In7.Cu")
		(net "P5E_PEX3_STN4_TX_DN<79>")
	)
	(segment
		(start 410.158692 -348.58579)
		(end 409.867862 -348.29496)
		(width 0.1651)
		(layer "In7.Cu")
		(net "P5E_PEX3_STN4_TX_DN<79>")
	)
	(segment
		(start 409.867862 -347.784674)
		(end 411.422342 -346.230194)
		(width 0.1651)
		(layer "In7.Cu")
		(net "P5E_PEX3_STN4_TX_DN<79>")
	)
	(segment
		(start 421.820086 -319.921128)
		(end 421.820086 -311.784492)
		(width 0.1143)
		(layer "In7.Cu")
		(net "P5E_PEX3_STN4_TX_DN<79>")
	)
	(segment
		(start 421.865806 -319.966848)
		(end 421.820086 -319.921128)
		(width 0.1143)
		(layer "In7.Cu")
		(net "P5E_PEX3_STN4_TX_DN<79>")
	)
	(segment
		(start 421.865806 -319.995296)
		(end 421.865806 -319.966848)
		(width 0.1143)
		(layer "In7.Cu")
		(net "P5E_PEX3_STN4_TX_DN<79>")
	)
	(segment
		(start 411.422342 -341.271352)
		(end 421.6019 -321.751706)
		(width 0.1651)
		(layer "In7.Cu")
		(net "P5E_PEX3_STN4_TX_DN<79>")
	)
	(segment
		(start 256.699766 -229.94493)
		(end 256.859786 -229.94493)
		(width 0.13208)
		(layer "F.Cu")
		(net "SPI_PEX2_SDIO1_MUX_R")
	)
	(segment
		(start 255.374902 -229.94493)
		(end 256.699766 -229.94493)
		(width 0.13208)
		(layer "F.Cu")
		(net "SPI_PEX2_SDIO1_MUX_R")
	)
	(via
		(at 255.374902 -229.94493)
		(size 0.508)
		(drill 0.254)
		(layers "F.Cu" "B.Cu")
		(net "SPI_PEX2_SDIO1_MUX_R")
	)
	(segment
		(start 255.374902 -228.74605)
		(end 255.374902 -229.94493)
		(width 0.13208)
		(layer "B.Cu")
		(net "SPI_PEX2_SDIO1_MUX_R")
	)
	(segment
		(start 431.946812 -344.219022)
		(end 431.62728 -344.538554)
		(width 0.13462)
		(layer "F.Cu")
		(net "P5E_PEX3_STN4_TX_C_DN<69>")
	)
	(segment
		(start 431.62728 -344.538554)
		(end 431.62728 -345.171014)
		(width 0.13462)
		(layer "F.Cu")
		(net "P5E_PEX3_STN4_TX_C_DN<69>")
	)
	(segment
		(start 431.62728 -345.171014)
		(end 431.921412 -345.465146)
		(width 0.13462)
		(layer "F.Cu")
		(net "P5E_PEX3_STN4_TX_C_DN<69>")
	)
	(segment
		(start 424.564048 -371.281198)
		(end 424.016932 -371.281198)
		(width 0.1651)
		(layer "In7.Cu")
		(net "P5E_PEX3_STN4_TX_C_DN<69>")
	)
	(segment
		(start 423.889932 -371.408198)
		(end 423.889932 -371.790214)
		(width 0.1651)
		(layer "In7.Cu")
		(net "P5E_PEX3_STN4_TX_C_DN<69>")
	)
	(segment
		(start 430.076102 -358.87279)
		(end 425.015914 -368.86769)
		(width 0.1651)
		(layer "In7.Cu")
		(net "P5E_PEX3_STN4_TX_C_DN<69>")
	)
	(segment
		(start 431.630582 -346.326714)
		(end 430.076102 -347.881194)
		(width 0.1651)
		(layer "In7.Cu")
		(net "P5E_PEX3_STN4_TX_C_DN<69>")
	)
	(segment
		(start 425.015914 -370.829332)
		(end 424.564048 -371.281198)
		(width 0.1651)
		(layer "In7.Cu")
		(net "P5E_PEX3_STN4_TX_C_DN<69>")
	)
	(segment
		(start 424.016932 -371.281198)
		(end 423.889932 -371.408198)
		(width 0.1651)
		(layer "In7.Cu")
		(net "P5E_PEX3_STN4_TX_C_DN<69>")
	)
	(segment
		(start 431.921412 -345.465146)
		(end 431.630582 -345.755976)
		(width 0.1651)
		(layer "In7.Cu")
		(net "P5E_PEX3_STN4_TX_C_DN<69>")
	)
	(segment
		(start 430.076102 -347.881194)
		(end 430.076102 -358.87279)
		(width 0.1651)
		(layer "In7.Cu")
		(net "P5E_PEX3_STN4_TX_C_DN<69>")
	)
	(segment
		(start 425.015914 -368.86769)
		(end 425.015914 -370.829332)
		(width 0.1651)
		(layer "In7.Cu")
		(net "P5E_PEX3_STN4_TX_C_DN<69>")
	)
	(segment
		(start 431.630582 -345.755976)
		(end 431.630582 -346.326714)
		(width 0.1651)
		(layer "In7.Cu")
		(net "P5E_PEX3_STN4_TX_C_DN<69>")
	)
	(segment
		(start 275.699728 -293.99992)
		(end 275.224748 -293.52494)
		(width 0.13208)
		(layer "F.Cu")
		(net "SPI_PEX2_SDIO2")
	)
	(via
		(at 275.224748 -293.52494)
		(size 0.508)
		(drill 0.254)
		(layers "F.Cu" "B.Cu")
		(net "SPI_PEX2_SDIO2")
	)
	(segment
		(start 274.786852 -293.962836)
		(end 273.082766 -293.962836)
		(width 0.13208)
		(layer "B.Cu")
		(net "SPI_PEX2_SDIO2")
	)
	(segment
		(start 273.082766 -293.962836)
		(end 272.719038 -294.326564)
		(width 0.13208)
		(layer "B.Cu")
		(net "SPI_PEX2_SDIO2")
	)
	(segment
		(start 272.719038 -294.326564)
		(end 272.719038 -294.8051)
		(width 0.13208)
		(layer "B.Cu")
		(net "SPI_PEX2_SDIO2")
	)
	(segment
		(start 275.224748 -293.52494)
		(end 274.786852 -293.962836)
		(width 0.13208)
		(layer "B.Cu")
		(net "SPI_PEX2_SDIO2")
	)
	(segment
		(start 418.596572 -356.511606)
		(end 418.91712 -356.832154)
		(width 0.13462)
		(layer "F.Cu")
		(net "P5E_PEX3_STN4_TX_C_DP<74>")
	)
	(segment
		(start 418.91712 -356.832154)
		(end 418.91712 -357.462582)
		(width 0.13462)
		(layer "F.Cu")
		(net "P5E_PEX3_STN4_TX_C_DP<74>")
	)
	(segment
		(start 418.91712 -357.462582)
		(end 418.621972 -357.75773)
		(width 0.13462)
		(layer "F.Cu")
		(net "P5E_PEX3_STN4_TX_C_DP<74>")
	)
	(segment
		(start 417.51885 -363.59846)
		(end 417.646358 -363.11967)
		(width 0.1651)
		(layer "In7.Cu")
		(net "P5E_PEX3_STN4_TX_C_DP<74>")
	)
	(segment
		(start 431.33391 -397.812514)
		(end 431.33391 -395.49451)
		(width 0.1651)
		(layer "In7.Cu")
		(net "P5E_PEX3_STN4_TX_C_DP<74>")
	)
	(segment
		(start 416.09772 -369.329716)
		(end 417.590986 -363.722666)
		(width 0.1651)
		(layer "In7.Cu")
		(net "P5E_PEX3_STN4_TX_C_DP<74>")
	)
	(segment
		(start 418.912802 -358.75976)
		(end 418.912802 -358.04856)
		(width 0.1651)
		(layer "In7.Cu")
		(net "P5E_PEX3_STN4_TX_C_DP<74>")
	)
	(segment
		(start 417.646358 -363.11967)
		(end 417.770818 -363.047534)
		(width 0.1651)
		(layer "In7.Cu")
		(net "P5E_PEX3_STN4_TX_C_DP<74>")
	)
	(segment
		(start 417.770818 -363.047534)
		(end 418.912802 -358.75976)
		(width 0.1651)
		(layer "In7.Cu")
		(net "P5E_PEX3_STN4_TX_C_DP<74>")
	)
	(segment
		(start 430.577498 -394.738098)
		(end 430.451768 -394.738098)
		(width 0.1651)
		(layer "In7.Cu")
		(net "P5E_PEX3_STN4_TX_C_DP<74>")
	)
	(segment
		(start 431.33391 -395.49451)
		(end 430.577498 -394.738098)
		(width 0.1651)
		(layer "In7.Cu")
		(net "P5E_PEX3_STN4_TX_C_DP<74>")
	)
	(segment
		(start 430.451768 -394.738098)
		(end 430.101502 -394.387832)
		(width 0.1651)
		(layer "In7.Cu")
		(net "P5E_PEX3_STN4_TX_C_DP<74>")
	)
	(segment
		(start 431.047144 -398.09928)
		(end 431.33391 -397.812514)
		(width 0.1651)
		(layer "In7.Cu")
		(net "P5E_PEX3_STN4_TX_C_DP<74>")
	)
	(segment
		(start 417.52012 -387.034532)
		(end 416.307524 -385.421378)
		(width 0.1651)
		(layer "In7.Cu")
		(net "P5E_PEX3_STN4_TX_C_DP<74>")
	)
	(segment
		(start 430.616868 -398.09928)
		(end 431.047144 -398.09928)
		(width 0.1651)
		(layer "In7.Cu")
		(net "P5E_PEX3_STN4_TX_C_DP<74>")
	)
	(segment
		(start 430.489868 -397.59001)
		(end 430.489868 -397.97228)
		(width 0.1651)
		(layer "In7.Cu")
		(net "P5E_PEX3_STN4_TX_C_DP<74>")
	)
	(segment
		(start 418.912802 -358.04856)
		(end 418.621972 -357.75773)
		(width 0.1651)
		(layer "In7.Cu")
		(net "P5E_PEX3_STN4_TX_C_DP<74>")
	)
	(segment
		(start 430.101502 -394.262102)
		(end 429.392588 -393.553188)
		(width 0.1651)
		(layer "In7.Cu")
		(net "P5E_PEX3_STN4_TX_C_DP<74>")
	)
	(segment
		(start 415.760662 -383.599182)
		(end 416.09772 -369.329716)
		(width 0.1651)
		(layer "In7.Cu")
		(net "P5E_PEX3_STN4_TX_C_DP<74>")
	)
	(segment
		(start 429.392588 -393.553188)
		(end 417.52012 -387.034532)
		(width 0.1651)
		(layer "In7.Cu")
		(net "P5E_PEX3_STN4_TX_C_DP<74>")
	)
	(segment
		(start 430.101502 -394.387832)
		(end 430.101502 -394.262102)
		(width 0.1651)
		(layer "In7.Cu")
		(net "P5E_PEX3_STN4_TX_C_DP<74>")
	)
	(segment
		(start 416.307524 -385.421378)
		(end 415.760662 -383.599182)
		(width 0.1651)
		(layer "In7.Cu")
		(net "P5E_PEX3_STN4_TX_C_DP<74>")
	)
	(segment
		(start 430.489868 -397.97228)
		(end 430.616868 -398.09928)
		(width 0.1651)
		(layer "In7.Cu")
		(net "P5E_PEX3_STN4_TX_C_DP<74>")
	)
	(segment
		(start 417.590986 -363.722666)
		(end 417.51885 -363.59846)
		(width 0.1651)
		(layer "In7.Cu")
		(net "P5E_PEX3_STN4_TX_C_DP<74>")
	)
	(segment
		(start 24.516334 -53.644038)
		(end 25.137364 -53.023008)
		(width 0.13208)
		(layer "F.Cu")
		(net "PWRGD_P12V_SSD0")
	)
	(segment
		(start 25.867868 -52.035456)
		(end 25.867868 -53.051456)
		(width 0.13208)
		(layer "F.Cu")
		(net "PWRGD_P12V_SSD0")
	)
	(segment
		(start 24.147272 -53.644038)
		(end 24.516334 -53.644038)
		(width 0.13208)
		(layer "F.Cu")
		(net "PWRGD_P12V_SSD0")
	)
	(segment
		(start 25.601422 -53.051456)
		(end 25.867868 -53.051456)
		(width 0.13208)
		(layer "F.Cu")
		(net "PWRGD_P12V_SSD0")
	)
	(segment
		(start 25.137364 -53.023008)
		(end 25.137364 -52.587398)
		(width 0.13208)
		(layer "F.Cu")
		(net "PWRGD_P12V_SSD0")
	)
	(segment
		(start 25.137364 -52.587398)
		(end 25.601422 -53.051456)
		(width 0.13208)
		(layer "F.Cu")
		(net "PWRGD_P12V_SSD0")
	)
	(via
		(at 25.137364 -52.587398)
		(size 0.508)
		(drill 0.254)
		(layers "F.Cu" "B.Cu")
		(net "PWRGD_P12V_SSD0")
	)
	(segment
		(start 258.5212 -220.23451)
		(end 257.935476 -220.820234)
		(width 0.13208)
		(layer "F.Cu")
		(net "SPI_PEX2_SDIO3_R1")
	)
	(segment
		(start 257.935476 -220.820234)
		(end 257.369056 -221.05493)
		(width 0.13208)
		(layer "F.Cu")
		(net "SPI_PEX2_SDIO3_R1")
	)
	(segment
		(start 257.369056 -221.05493)
		(end 256.859786 -221.05493)
		(width 0.13208)
		(layer "F.Cu")
		(net "SPI_PEX2_SDIO3_R1")
	)
	(via
		(at 258.5212 -220.23451)
		(size 0.508)
		(drill 0.254)
		(layers "F.Cu" "B.Cu")
		(net "SPI_PEX2_SDIO3_R1")
	)
	(segment
		(start 258.197604 -220.524324)
		(end 258.5212 -220.200728)
		(width 0.13208)
		(layer "B.Cu")
		(net "SPI_PEX2_SDIO3_R1")
	)
	(segment
		(start 257.322574 -220.524324)
		(end 257.314192 -220.532706)
		(width 0.13208)
		(layer "B.Cu")
		(net "SPI_PEX2_SDIO3_R1")
	)
	(segment
		(start 257.322574 -220.524324)
		(end 258.197604 -220.524324)
		(width 0.13208)
		(layer "B.Cu")
		(net "SPI_PEX2_SDIO3_R1")
	)
	(segment
		(start 257.314192 -220.532706)
		(end 256.282952 -220.532706)
		(width 0.13208)
		(layer "B.Cu")
		(net "SPI_PEX2_SDIO3_R1")
	)
	(segment
		(start 258.5212 -220.200728)
		(end 258.5212 -220.23451)
		(width 0.13208)
		(layer "B.Cu")
		(net "SPI_PEX2_SDIO3_R1")
	)
	(segment
		(start 428.23384 -319.913)
		(end 428.23384 -319.941448)
		(width 0.1143)
		(layer "In5.Cu")
		(net "P5E_PEX3_STN4_RX_DP<72>")
	)
	(segment
		(start 428.23384 -320.260472)
		(end 429.794162 -342.322658)
		(width 0.1651)
		(layer "In5.Cu")
		(net "P5E_PEX3_STN4_RX_DP<72>")
	)
	(segment
		(start 428.84979 -318.015366)
		(end 428.73549 -318.129666)
		(width 0.1143)
		(layer "In5.Cu")
		(net "P5E_PEX3_STN4_RX_DP<72>")
	)
	(segment
		(start 428.84979 -317.749936)
		(end 428.84979 -318.015366)
		(width 0.1143)
		(layer "In5.Cu")
		(net "P5E_PEX3_STN4_RX_DP<72>")
	)
	(segment
		(start 425.981876 -389.466328)
		(end 426.018452 -389.586724)
		(width 0.1651)
		(layer "In5.Cu")
		(net "P5E_PEX3_STN4_RX_DP<72>")
	)
	(segment
		(start 417.920678 -370.217954)
		(end 417.88334 -383.794)
		(width 0.1651)
		(layer "In5.Cu")
		(net "P5E_PEX3_STN4_RX_DP<72>")
	)
	(segment
		(start 417.88334 -383.794)
		(end 418.539422 -385.422902)
		(width 0.1651)
		(layer "In5.Cu")
		(net "P5E_PEX3_STN4_RX_DP<72>")
	)
	(segment
		(start 428.505366 -318.129666)
		(end 428.27956 -318.355472)
		(width 0.1143)
		(layer "In5.Cu")
		(net "P5E_PEX3_STN4_RX_DP<72>")
	)
	(segment
		(start 428.73549 -318.129666)
		(end 428.505366 -318.129666)
		(width 0.1143)
		(layer "In5.Cu")
		(net "P5E_PEX3_STN4_RX_DP<72>")
	)
	(segment
		(start 434.88991 -405.729694)
		(end 434.88991 -405.390096)
		(width 0.1651)
		(layer "In5.Cu")
		(net "P5E_PEX3_STN4_RX_DP<72>")
	)
	(segment
		(start 418.35832 -368.789458)
		(end 418.124132 -369.193318)
		(width 0.1651)
		(layer "In5.Cu")
		(net "P5E_PEX3_STN4_RX_DP<72>")
	)
	(segment
		(start 435.063138 -405.902922)
		(end 434.88991 -405.729694)
		(width 0.1651)
		(layer "In5.Cu")
		(net "P5E_PEX3_STN4_RX_DP<72>")
	)
	(segment
		(start 418.124132 -369.193318)
		(end 417.920678 -370.217954)
		(width 0.1651)
		(layer "In5.Cu")
		(net "P5E_PEX3_STN4_RX_DP<72>")
	)
	(segment
		(start 426.456094 -389.819642)
		(end 426.576236 -389.782812)
		(width 0.1651)
		(layer "In5.Cu")
		(net "P5E_PEX3_STN4_RX_DP<72>")
	)
	(segment
		(start 425.981876 -389.466582)
		(end 425.981876 -389.466328)
		(width 0.1651)
		(layer "In5.Cu")
		(net "P5E_PEX3_STN4_RX_DP<72>")
	)
	(segment
		(start 428.27956 -319.86728)
		(end 428.23384 -319.913)
		(width 0.1143)
		(layer "In5.Cu")
		(net "P5E_PEX3_STN4_RX_DP<72>")
	)
	(segment
		(start 426.576236 -389.782812)
		(end 434.111908 -393.792964)
		(width 0.1651)
		(layer "In5.Cu")
		(net "P5E_PEX3_STN4_RX_DP<72>")
	)
	(segment
		(start 435.43347 -405.902922)
		(end 435.063138 -405.902922)
		(width 0.1651)
		(layer "In5.Cu")
		(net "P5E_PEX3_STN4_RX_DP<72>")
	)
	(segment
		(start 428.27956 -318.355472)
		(end 428.27956 -319.86728)
		(width 0.1143)
		(layer "In5.Cu")
		(net "P5E_PEX3_STN4_RX_DP<72>")
	)
	(segment
		(start 428.23384 -319.941448)
		(end 428.23384 -320.260472)
		(width 0.1651)
		(layer "In5.Cu")
		(net "P5E_PEX3_STN4_RX_DP<72>")
	)
	(segment
		(start 434.111908 -393.792964)
		(end 435.765956 -395.92504)
		(width 0.1651)
		(layer "In5.Cu")
		(net "P5E_PEX3_STN4_RX_DP<72>")
	)
	(segment
		(start 418.746178 -385.615942)
		(end 425.981876 -389.466582)
		(width 0.1651)
		(layer "In5.Cu")
		(net "P5E_PEX3_STN4_RX_DP<72>")
	)
	(segment
		(start 429.794162 -358.82834)
		(end 418.35832 -368.789458)
		(width 0.1651)
		(layer "In5.Cu")
		(net "P5E_PEX3_STN4_RX_DP<72>")
	)
	(segment
		(start 426.018452 -389.586724)
		(end 426.456094 -389.819642)
		(width 0.1651)
		(layer "In5.Cu")
		(net "P5E_PEX3_STN4_RX_DP<72>")
	)
	(segment
		(start 435.765956 -395.92504)
		(end 435.765956 -405.570436)
		(width 0.1651)
		(layer "In5.Cu")
		(net "P5E_PEX3_STN4_RX_DP<72>")
	)
	(segment
		(start 418.539422 -385.422902)
		(end 418.746178 -385.615942)
		(width 0.1651)
		(layer "In5.Cu")
		(net "P5E_PEX3_STN4_RX_DP<72>")
	)
	(segment
		(start 429.794162 -342.322658)
		(end 429.794162 -358.82834)
		(width 0.1651)
		(layer "In5.Cu")
		(net "P5E_PEX3_STN4_RX_DP<72>")
	)
	(segment
		(start 435.765956 -405.570436)
		(end 435.43347 -405.902922)
		(width 0.1651)
		(layer "In5.Cu")
		(net "P5E_PEX3_STN4_RX_DP<72>")
	)
	(segment
		(start 437.250332 -343.685622)
		(end 437.569864 -343.36609)
		(width 0.13462)
		(layer "F.Cu")
		(net "P5E_PEX3_STN4_TX_DP<66>")
	)
	(segment
		(start 437.569864 -342.73363)
		(end 437.275732 -342.439498)
		(width 0.13462)
		(layer "F.Cu")
		(net "P5E_PEX3_STN4_TX_DP<66>")
	)
	(segment
		(start 437.569864 -343.36609)
		(end 437.569864 -342.73363)
		(width 0.13462)
		(layer "F.Cu")
		(net "P5E_PEX3_STN4_TX_DP<66>")
	)
	(segment
		(start 423.41546 -306.349908)
		(end 423.15003 -306.349908)
		(width 0.1143)
		(layer "In7.Cu")
		(net "P5E_PEX3_STN4_TX_DP<66>")
	)
	(segment
		(start 439.76798 -313.30646)
		(end 433.960778 -307.499258)
		(width 0.1651)
		(layer "In7.Cu")
		(net "P5E_PEX3_STN4_TX_DP<66>")
	)
	(segment
		(start 431.833528 -306.920138)
		(end 423.755566 -306.920138)
		(width 0.1143)
		(layer "In7.Cu")
		(net "P5E_PEX3_STN4_TX_DP<66>")
	)
	(segment
		(start 444.6905 -318.15278)
		(end 443.2935 -316.1919)
		(width 0.1651)
		(layer "In7.Cu")
		(net "P5E_PEX3_STN4_TX_DP<66>")
	)
	(segment
		(start 423.755566 -306.920138)
		(end 423.52976 -306.694332)
		(width 0.1143)
		(layer "In7.Cu")
		(net "P5E_PEX3_STN4_TX_DP<66>")
	)
	(segment
		(start 444.61684 -323.5198)
		(end 445.0969 -321.2465)
		(width 0.1651)
		(layer "In7.Cu")
		(net "P5E_PEX3_STN4_TX_DP<66>")
	)
	(segment
		(start 432.673252 -306.965858)
		(end 431.907696 -306.965858)
		(width 0.1651)
		(layer "In7.Cu")
		(net "P5E_PEX3_STN4_TX_DP<66>")
	)
	(segment
		(start 431.879248 -306.965858)
		(end 431.833528 -306.920138)
		(width 0.1143)
		(layer "In7.Cu")
		(net "P5E_PEX3_STN4_TX_DP<66>")
	)
	(segment
		(start 423.52976 -306.464208)
		(end 423.41546 -306.349908)
		(width 0.1143)
		(layer "In7.Cu")
		(net "P5E_PEX3_STN4_TX_DP<66>")
	)
	(segment
		(start 431.907696 -306.965858)
		(end 431.879248 -306.965858)
		(width 0.1143)
		(layer "In7.Cu")
		(net "P5E_PEX3_STN4_TX_DP<66>")
	)
	(segment
		(start 443.2935 -316.1919)
		(end 439.76798 -313.30646)
		(width 0.1651)
		(layer "In7.Cu")
		(net "P5E_PEX3_STN4_TX_DP<66>")
	)
	(segment
		(start 433.960778 -307.499258)
		(end 432.673252 -306.965858)
		(width 0.1651)
		(layer "In7.Cu")
		(net "P5E_PEX3_STN4_TX_DP<66>")
	)
	(segment
		(start 437.566562 -342.148668)
		(end 437.566562 -341.618062)
		(width 0.1651)
		(layer "In7.Cu")
		(net "P5E_PEX3_STN4_TX_DP<66>")
	)
	(segment
		(start 437.275732 -342.439498)
		(end 437.566562 -342.148668)
		(width 0.1651)
		(layer "In7.Cu")
		(net "P5E_PEX3_STN4_TX_DP<66>")
	)
	(segment
		(start 445.0969 -321.2465)
		(end 444.6905 -318.15278)
		(width 0.1651)
		(layer "In7.Cu")
		(net "P5E_PEX3_STN4_TX_DP<66>")
	)
	(segment
		(start 437.566562 -341.618062)
		(end 444.61684 -323.5198)
		(width 0.1651)
		(layer "In7.Cu")
		(net "P5E_PEX3_STN4_TX_DP<66>")
	)
	(segment
		(start 423.52976 -306.694332)
		(end 423.52976 -306.464208)
		(width 0.1143)
		(layer "In7.Cu")
		(net "P5E_PEX3_STN4_TX_DP<66>")
	)
	(segment
		(start 5.644134 -65.21196)
		(end 6.187694 -65.75552)
		(width 0.13208)
		(layer "F.Cu")
		(net "PWRGD_P12V_SSD0_R")
	)
	(segment
		(start 3.48361 -61.487812)
		(end 2.422398 -61.487812)
		(width 0.13208)
		(layer "F.Cu")
		(net "PWRGD_P12V_SSD0_R")
	)
	(segment
		(start 340.36 -228.31044)
		(end 340.493858 -227.987098)
		(width 0.13208)
		(layer "F.Cu")
		(net "PWRGD_P12V_SSD0_R")
	)
	(segment
		(start 26.667968 -53.051456)
		(end 27.323288 -53.051456)
		(width 0.13208)
		(layer "F.Cu")
		(net "PWRGD_P12V_SSD0_R")
	)
	(segment
		(start 1.778 -64.948054)
		(end 2.041906 -65.21196)
		(width 0.13208)
		(layer "F.Cu")
		(net "PWRGD_P12V_SSD0_R")
	)
	(segment
		(start 6.187694 -65.75552)
		(end 14.728698 -65.75552)
		(width 0.13208)
		(layer "F.Cu")
		(net "PWRGD_P12V_SSD0_R")
	)
	(segment
		(start 340.36 -228.6)
		(end 340.36 -228.31044)
		(width 0.13208)
		(layer "F.Cu")
		(net "PWRGD_P12V_SSD0_R")
	)
	(segment
		(start 1.778 -62.13221)
		(end 1.778 -64.948054)
		(width 0.13208)
		(layer "F.Cu")
		(net "PWRGD_P12V_SSD0_R")
	)
	(segment
		(start 2.422398 -61.487812)
		(end 1.778 -62.13221)
		(width 0.13208)
		(layer "F.Cu")
		(net "PWRGD_P12V_SSD0_R")
	)
	(segment
		(start 2.041906 -65.21196)
		(end 5.644134 -65.21196)
		(width 0.13208)
		(layer "F.Cu")
		(net "PWRGD_P12V_SSD0_R")
	)
	(via
		(at 27.323288 -53.051456)
		(size 0.508)
		(drill 0.254)
		(layers "F.Cu" "B.Cu")
		(net "PWRGD_P12V_SSD0_R")
	)
	(via
		(at 340.36 -228.6)
		(size 0.508)
		(drill 0.254)
		(layers "F.Cu" "B.Cu")
		(net "PWRGD_P12V_SSD0_R")
	)
	(via
		(at 30.090618 -202.38339)
		(size 0.508)
		(drill 0.254)
		(layers "F.Cu" "B.Cu")
		(net "PWRGD_P12V_SSD0_R")
	)
	(via
		(at 14.728698 -65.75552)
		(size 0.508)
		(drill 0.254)
		(layers "F.Cu" "B.Cu")
		(net "PWRGD_P12V_SSD0_R")
	)
	(segment
		(start 28.31084 -97.34169)
		(end 25.405588 -100.246942)
		(width 0.15494)
		(layer "In5.Cu")
		(net "PWRGD_P12V_SSD0_R")
	)
	(segment
		(start 25.777952 -192.828164)
		(end 30.090618 -197.14083)
		(width 0.15494)
		(layer "In5.Cu")
		(net "PWRGD_P12V_SSD0_R")
	)
	(segment
		(start 26.94305 -66.235072)
		(end 28.31084 -67.602862)
		(width 0.15494)
		(layer "In5.Cu")
		(net "PWRGD_P12V_SSD0_R")
	)
	(segment
		(start 19.43481 -64.53886)
		(end 25.015952 -64.53886)
		(width 0.15494)
		(layer "In5.Cu")
		(net "PWRGD_P12V_SSD0_R")
	)
	(segment
		(start 25.777952 -166.78148)
		(end 25.777952 -192.828164)
		(width 0.15494)
		(layer "In5.Cu")
		(net "PWRGD_P12V_SSD0_R")
	)
	(segment
		(start 25.405588 -165.88232)
		(end 25.777952 -166.78148)
		(width 0.15494)
		(layer "In5.Cu")
		(net "PWRGD_P12V_SSD0_R")
	)
	(segment
		(start 27.485086 -55.72633)
		(end 26.96591 -55.72633)
		(width 0.15494)
		(layer "In5.Cu")
		(net "PWRGD_P12V_SSD0_R")
	)
	(segment
		(start 26.806906 -55.885334)
		(end 26.806906 -57.090818)
		(width 0.15494)
		(layer "In5.Cu")
		(net "PWRGD_P12V_SSD0_R")
	)
	(segment
		(start 27.97556 -53.703728)
		(end 27.97556 -55.235856)
		(width 0.15494)
		(layer "In5.Cu")
		(net "PWRGD_P12V_SSD0_R")
	)
	(segment
		(start 27.323288 -53.051456)
		(end 27.97556 -53.703728)
		(width 0.15494)
		(layer "In5.Cu")
		(net "PWRGD_P12V_SSD0_R")
	)
	(segment
		(start 25.405588 -100.246942)
		(end 25.405588 -165.88232)
		(width 0.15494)
		(layer "In5.Cu")
		(net "PWRGD_P12V_SSD0_R")
	)
	(segment
		(start 25.261316 -64.293496)
		(end 25.261316 -55.113428)
		(width 0.15494)
		(layer "In5.Cu")
		(net "PWRGD_P12V_SSD0_R")
	)
	(segment
		(start 26.96591 -55.72633)
		(end 26.806906 -55.885334)
		(width 0.15494)
		(layer "In5.Cu")
		(net "PWRGD_P12V_SSD0_R")
	)
	(segment
		(start 27.97556 -55.235856)
		(end 27.485086 -55.72633)
		(width 0.15494)
		(layer "In5.Cu")
		(net "PWRGD_P12V_SSD0_R")
	)
	(segment
		(start 25.015952 -64.53886)
		(end 25.261316 -64.293496)
		(width 0.15494)
		(layer "In5.Cu")
		(net "PWRGD_P12V_SSD0_R")
	)
	(segment
		(start 18.21815 -65.75552)
		(end 19.43481 -64.53886)
		(width 0.15494)
		(layer "In5.Cu")
		(net "PWRGD_P12V_SSD0_R")
	)
	(segment
		(start 28.31084 -67.602862)
		(end 28.31084 -97.34169)
		(width 0.15494)
		(layer "In5.Cu")
		(net "PWRGD_P12V_SSD0_R")
	)
	(segment
		(start 30.090618 -197.14083)
		(end 30.090618 -202.38339)
		(width 0.15494)
		(layer "In5.Cu")
		(net "PWRGD_P12V_SSD0_R")
	)
	(segment
		(start 14.728698 -65.75552)
		(end 18.21815 -65.75552)
		(width 0.15494)
		(layer "In5.Cu")
		(net "PWRGD_P12V_SSD0_R")
	)
	(segment
		(start 25.261316 -55.113428)
		(end 27.323288 -53.051456)
		(width 0.15494)
		(layer "In5.Cu")
		(net "PWRGD_P12V_SSD0_R")
	)
	(segment
		(start 26.806906 -57.090818)
		(end 26.94305 -57.226962)
		(width 0.15494)
		(layer "In5.Cu")
		(net "PWRGD_P12V_SSD0_R")
	)
	(segment
		(start 26.94305 -57.226962)
		(end 26.94305 -66.235072)
		(width 0.15494)
		(layer "In5.Cu")
		(net "PWRGD_P12V_SSD0_R")
	)
	(segment
		(start 340.296246 -230.872284)
		(end 340.84387 -230.32466)
		(width 0.15494)
		(layer "In15.Cu")
		(net "PWRGD_P12V_SSD0_R")
	)
	(segment
		(start 145.21053 -221.266258)
		(end 156.193998 -221.266258)
		(width 0.15494)
		(layer "In15.Cu")
		(net "PWRGD_P12V_SSD0_R")
	)
	(segment
		(start 324.568566 -233.270806)
		(end 325.584312 -232.25506)
		(width 0.15494)
		(layer "In15.Cu")
		(net "PWRGD_P12V_SSD0_R")
	)
	(segment
		(start 259.324602 -224.724214)
		(end 260.392418 -225.79203)
		(width 0.15494)
		(layer "In15.Cu")
		(net "PWRGD_P12V_SSD0_R")
	)
	(segment
		(start 290.9316 -232.3592)
		(end 291.9476 -231.3432)
		(width 0.15494)
		(layer "In15.Cu")
		(net "PWRGD_P12V_SSD0_R")
	)
	(segment
		(start 291.9476 -231.3432)
		(end 320.426334 -231.3432)
		(width 0.15494)
		(layer "In15.Cu")
		(net "PWRGD_P12V_SSD0_R")
	)
	(segment
		(start 327.04659 -231.29494)
		(end 329.936348 -231.29494)
		(width 0.15494)
		(layer "In15.Cu")
		(net "PWRGD_P12V_SSD0_R")
	)
	(segment
		(start 117.658642 -211.078318)
		(end 117.658642 -213.558882)
		(width 0.15494)
		(layer "In15.Cu")
		(net "PWRGD_P12V_SSD0_R")
	)
	(segment
		(start 325.584312 -232.25506)
		(end 326.08647 -232.25506)
		(width 0.15494)
		(layer "In15.Cu")
		(net "PWRGD_P12V_SSD0_R")
	)
	(segment
		(start 189.41161 -227.65766)
		(end 192.910968 -231.157018)
		(width 0.15494)
		(layer "In15.Cu")
		(net "PWRGD_P12V_SSD0_R")
	)
	(segment
		(start 265.48715 -226.5172)
		(end 271.32915 -232.3592)
		(width 0.15494)
		(layer "In15.Cu")
		(net "PWRGD_P12V_SSD0_R")
	)
	(segment
		(start 137.3632 -224.131632)
		(end 137.407904 -224.176336)
		(width 0.15494)
		(layer "In15.Cu")
		(net "PWRGD_P12V_SSD0_R")
	)
	(segment
		(start 208.872582 -230.15956)
		(end 213.87816 -230.15956)
		(width 0.15494)
		(layer "In15.Cu")
		(net "PWRGD_P12V_SSD0_R")
	)
	(segment
		(start 246.377968 -225.33356)
		(end 249.92076 -225.33356)
		(width 0.15494)
		(layer "In15.Cu")
		(net "PWRGD_P12V_SSD0_R")
	)
	(segment
		(start 321.744086 -232.660952)
		(end 323.557392 -232.660952)
		(width 0.15494)
		(layer "In15.Cu")
		(net "PWRGD_P12V_SSD0_R")
	)
	(segment
		(start 320.426334 -231.3432)
		(end 321.744086 -232.660952)
		(width 0.15494)
		(layer "In15.Cu")
		(net "PWRGD_P12V_SSD0_R")
	)
	(segment
		(start 156.193998 -221.266258)
		(end 162.5854 -227.65766)
		(width 0.15494)
		(layer "In15.Cu")
		(net "PWRGD_P12V_SSD0_R")
	)
	(segment
		(start 162.5854 -227.65766)
		(end 189.41161 -227.65766)
		(width 0.15494)
		(layer "In15.Cu")
		(net "PWRGD_P12V_SSD0_R")
	)
	(segment
		(start 141.110208 -224.17151)
		(end 142.305278 -224.17151)
		(width 0.15494)
		(layer "In15.Cu")
		(net "PWRGD_P12V_SSD0_R")
	)
	(segment
		(start 102.447852 -204.70114)
		(end 111.281464 -204.70114)
		(width 0.15494)
		(layer "In15.Cu")
		(net "PWRGD_P12V_SSD0_R")
	)
	(segment
		(start 31.0642 -202.38339)
		(end 31.22041 -202.5396)
		(width 0.15494)
		(layer "In15.Cu")
		(net "PWRGD_P12V_SSD0_R")
	)
	(segment
		(start 249.92076 -225.33356)
		(end 250.530106 -224.724214)
		(width 0.15494)
		(layer "In15.Cu")
		(net "PWRGD_P12V_SSD0_R")
	)
	(segment
		(start 262.142732 -226.5172)
		(end 265.48715 -226.5172)
		(width 0.15494)
		(layer "In15.Cu")
		(net "PWRGD_P12V_SSD0_R")
	)
	(segment
		(start 213.87816 -230.15956)
		(end 214.48649 -230.76789)
		(width 0.15494)
		(layer "In15.Cu")
		(net "PWRGD_P12V_SSD0_R")
	)
	(segment
		(start 250.530106 -224.724214)
		(end 259.324602 -224.724214)
		(width 0.15494)
		(layer "In15.Cu")
		(net "PWRGD_P12V_SSD0_R")
	)
	(segment
		(start 324.167246 -233.270806)
		(end 324.568566 -233.270806)
		(width 0.15494)
		(layer "In15.Cu")
		(net "PWRGD_P12V_SSD0_R")
	)
	(segment
		(start 214.48649 -230.76789)
		(end 241.949478 -230.76789)
		(width 0.15494)
		(layer "In15.Cu")
		(net "PWRGD_P12V_SSD0_R")
	)
	(segment
		(start 142.305278 -224.17151)
		(end 145.21053 -221.266258)
		(width 0.15494)
		(layer "In15.Cu")
		(net "PWRGD_P12V_SSD0_R")
	)
	(segment
		(start 241.949478 -230.76789)
		(end 243.053108 -229.66426)
		(width 0.15494)
		(layer "In15.Cu")
		(net "PWRGD_P12V_SSD0_R")
	)
	(segment
		(start 111.281464 -204.70114)
		(end 117.658642 -211.078318)
		(width 0.15494)
		(layer "In15.Cu")
		(net "PWRGD_P12V_SSD0_R")
	)
	(segment
		(start 128.594358 -224.494598)
		(end 130.716274 -224.494598)
		(width 0.15494)
		(layer "In15.Cu")
		(net "PWRGD_P12V_SSD0_R")
	)
	(segment
		(start 30.090618 -202.38339)
		(end 31.0642 -202.38339)
		(width 0.15494)
		(layer "In15.Cu")
		(net "PWRGD_P12V_SSD0_R")
	)
	(segment
		(start 117.658642 -213.558882)
		(end 128.594358 -224.494598)
		(width 0.15494)
		(layer "In15.Cu")
		(net "PWRGD_P12V_SSD0_R")
	)
	(segment
		(start 243.053108 -229.66426)
		(end 243.053108 -228.65842)
		(width 0.15494)
		(layer "In15.Cu")
		(net "PWRGD_P12V_SSD0_R")
	)
	(segment
		(start 130.716274 -224.494598)
		(end 131.07924 -224.131632)
		(width 0.15494)
		(layer "In15.Cu")
		(net "PWRGD_P12V_SSD0_R")
	)
	(segment
		(start 31.22041 -202.5396)
		(end 97.227898 -202.5396)
		(width 0.15494)
		(layer "In15.Cu")
		(net "PWRGD_P12V_SSD0_R")
	)
	(segment
		(start 141.105382 -224.176336)
		(end 141.110208 -224.17151)
		(width 0.15494)
		(layer "In15.Cu")
		(net "PWRGD_P12V_SSD0_R")
	)
	(segment
		(start 131.07924 -224.131632)
		(end 137.3632 -224.131632)
		(width 0.15494)
		(layer "In15.Cu")
		(net "PWRGD_P12V_SSD0_R")
	)
	(segment
		(start 271.32915 -232.3592)
		(end 290.9316 -232.3592)
		(width 0.15494)
		(layer "In15.Cu")
		(net "PWRGD_P12V_SSD0_R")
	)
	(segment
		(start 243.053108 -228.65842)
		(end 246.377968 -225.33356)
		(width 0.15494)
		(layer "In15.Cu")
		(net "PWRGD_P12V_SSD0_R")
	)
	(segment
		(start 323.557392 -232.660952)
		(end 324.167246 -233.270806)
		(width 0.15494)
		(layer "In15.Cu")
		(net "PWRGD_P12V_SSD0_R")
	)
	(segment
		(start 260.392418 -225.79203)
		(end 262.142732 -226.5172)
		(width 0.15494)
		(layer "In15.Cu")
		(net "PWRGD_P12V_SSD0_R")
	)
	(segment
		(start 137.407904 -224.176336)
		(end 141.105382 -224.176336)
		(width 0.15494)
		(layer "In15.Cu")
		(net "PWRGD_P12V_SSD0_R")
	)
	(segment
		(start 340.84387 -229.08387)
		(end 340.36 -228.6)
		(width 0.15494)
		(layer "In15.Cu")
		(net "PWRGD_P12V_SSD0_R")
	)
	(segment
		(start 326.08647 -232.25506)
		(end 327.04659 -231.29494)
		(width 0.15494)
		(layer "In15.Cu")
		(net "PWRGD_P12V_SSD0_R")
	)
	(segment
		(start 330.359004 -230.872284)
		(end 340.296246 -230.872284)
		(width 0.15494)
		(layer "In15.Cu")
		(net "PWRGD_P12V_SSD0_R")
	)
	(segment
		(start 192.910968 -231.157018)
		(end 207.875124 -231.157018)
		(width 0.15494)
		(layer "In15.Cu")
		(net "PWRGD_P12V_SSD0_R")
	)
	(segment
		(start 97.227898 -202.5396)
		(end 102.447852 -204.70114)
		(width 0.15494)
		(layer "In15.Cu")
		(net "PWRGD_P12V_SSD0_R")
	)
	(segment
		(start 207.875124 -231.157018)
		(end 208.872582 -230.15956)
		(width 0.15494)
		(layer "In15.Cu")
		(net "PWRGD_P12V_SSD0_R")
	)
	(segment
		(start 340.84387 -230.32466)
		(end 340.84387 -229.08387)
		(width 0.15494)
		(layer "In15.Cu")
		(net "PWRGD_P12V_SSD0_R")
	)
	(segment
		(start 329.936348 -231.29494)
		(end 330.359004 -230.872284)
		(width 0.15494)
		(layer "In15.Cu")
		(net "PWRGD_P12V_SSD0_R")
	)
	(segment
		(start 247.099582 -229.94493)
		(end 245.758208 -229.94493)
		(width 0.13208)
		(layer "F.Cu")
		(net "SPI_PEX2_SDIO2_R1")
	)
	(segment
		(start 245.758208 -229.94493)
		(end 245.570502 -229.757224)
		(width 0.13208)
		(layer "F.Cu")
		(net "SPI_PEX2_SDIO2_R1")
	)
	(via
		(at 245.570502 -229.757224)
		(size 0.508)
		(drill 0.254)
		(layers "F.Cu" "B.Cu")
		(net "SPI_PEX2_SDIO2_R1")
	)
	(segment
		(start 246.699532 -227.965)
		(end 246.699532 -228.981)
		(width 0.13208)
		(layer "B.Cu")
		(net "SPI_PEX2_SDIO2_R1")
	)
	(segment
		(start 245.937278 -230.124)
		(end 246.572532 -230.124)
		(width 0.13208)
		(layer "B.Cu")
		(net "SPI_PEX2_SDIO2_R1")
	)
	(segment
		(start 246.699532 -228.981)
		(end 246.699532 -229.997)
		(width 0.13208)
		(layer "B.Cu")
		(net "SPI_PEX2_SDIO2_R1")
	)
	(segment
		(start 245.570502 -229.757224)
		(end 245.937278 -230.124)
		(width 0.13208)
		(layer "B.Cu")
		(net "SPI_PEX2_SDIO2_R1")
	)
	(segment
		(start 246.572532 -230.124)
		(end 246.699532 -229.997)
		(width 0.13208)
		(layer "B.Cu")
		(net "SPI_PEX2_SDIO2_R1")
	)
	(segment
		(start 437.57088 -357.462582)
		(end 437.275732 -357.75773)
		(width 0.13462)
		(layer "F.Cu")
		(net "P5E_PEX3_STN4_TX_C_DP<65>")
	)
	(segment
		(start 437.250332 -356.511606)
		(end 437.57088 -356.832154)
		(width 0.13462)
		(layer "F.Cu")
		(net "P5E_PEX3_STN4_TX_C_DP<65>")
	)
	(segment
		(start 437.57088 -356.832154)
		(end 437.57088 -357.462582)
		(width 0.13462)
		(layer "F.Cu")
		(net "P5E_PEX3_STN4_TX_C_DP<65>")
	)
	(segment
		(start 432.689762 -370.489988)
		(end 432.689762 -370.872258)
		(width 0.1651)
		(layer "In7.Cu")
		(net "P5E_PEX3_STN4_TX_C_DP<65>")
	)
	(segment
		(start 436.574184 -360.891328)
		(end 436.723028 -360.828082)
		(width 0.1651)
		(layer "In7.Cu")
		(net "P5E_PEX3_STN4_TX_C_DP<65>")
	)
	(segment
		(start 435.356 -364.221014)
		(end 435.540912 -363.762036)
		(width 0.1651)
		(layer "In7.Cu")
		(net "P5E_PEX3_STN4_TX_C_DP<65>")
	)
	(segment
		(start 433.989226 -367.614454)
		(end 434.174138 -367.155222)
		(width 0.1651)
		(layer "In7.Cu")
		(net "P5E_PEX3_STN4_TX_C_DP<65>")
	)
	(segment
		(start 435.022498 -364.744254)
		(end 435.20741 -364.284514)
		(width 0.1651)
		(layer "In7.Cu")
		(net "P5E_PEX3_STN4_TX_C_DP<65>")
	)
	(segment
		(start 434.630068 -366.02416)
		(end 434.566822 -365.875316)
		(width 0.1651)
		(layer "In7.Cu")
		(net "P5E_PEX3_STN4_TX_C_DP<65>")
	)
	(segment
		(start 435.997096 -362.630974)
		(end 435.933596 -362.48213)
		(width 0.1651)
		(layer "In7.Cu")
		(net "P5E_PEX3_STN4_TX_C_DP<65>")
	)
	(segment
		(start 436.722774 -360.828082)
		(end 436.907686 -360.36885)
		(width 0.1651)
		(layer "In7.Cu")
		(net "P5E_PEX3_STN4_TX_C_DP<65>")
	)
	(segment
		(start 435.663086 -363.153452)
		(end 435.812184 -363.090206)
		(width 0.1651)
		(layer "In7.Cu")
		(net "P5E_PEX3_STN4_TX_C_DP<65>")
	)
	(segment
		(start 434.296058 -366.546638)
		(end 434.445156 -366.483392)
		(width 0.1651)
		(layer "In7.Cu")
		(net "P5E_PEX3_STN4_TX_C_DP<65>")
	)
	(segment
		(start 436.907686 -360.36885)
		(end 436.90794 -360.36885)
		(width 0.1651)
		(layer "In7.Cu")
		(net "P5E_PEX3_STN4_TX_C_DP<65>")
	)
	(segment
		(start 437.149748 -359.767632)
		(end 437.566562 -358.733344)
		(width 0.1651)
		(layer "In7.Cu")
		(net "P5E_PEX3_STN4_TX_C_DP<65>")
	)
	(segment
		(start 436.389018 -361.351068)
		(end 436.574184 -360.891328)
		(width 0.1651)
		(layer "In7.Cu")
		(net "P5E_PEX3_STN4_TX_C_DP<65>")
	)
	(segment
		(start 435.540912 -363.762036)
		(end 435.54142 -363.762036)
		(width 0.1651)
		(layer "In7.Cu")
		(net "P5E_PEX3_STN4_TX_C_DP<65>")
	)
	(segment
		(start 435.933596 -362.48213)
		(end 436.118762 -362.02239)
		(width 0.1651)
		(layer "In7.Cu")
		(net "P5E_PEX3_STN4_TX_C_DP<65>")
	)
	(segment
		(start 436.723028 -360.828082)
		(end 436.722774 -360.828082)
		(width 0.1651)
		(layer "In7.Cu")
		(net "P5E_PEX3_STN4_TX_C_DP<65>")
	)
	(segment
		(start 434.445156 -366.483392)
		(end 434.444902 -366.483392)
		(width 0.1651)
		(layer "In7.Cu")
		(net "P5E_PEX3_STN4_TX_C_DP<65>")
	)
	(segment
		(start 435.356508 -364.221268)
		(end 435.356 -364.221014)
		(width 0.1651)
		(layer "In7.Cu")
		(net "P5E_PEX3_STN4_TX_C_DP<65>")
	)
	(segment
		(start 434.174138 -367.155222)
		(end 434.174392 -367.155222)
		(width 0.1651)
		(layer "In7.Cu")
		(net "P5E_PEX3_STN4_TX_C_DP<65>")
	)
	(segment
		(start 433.718716 -368.286284)
		(end 433.65547 -368.13744)
		(width 0.1651)
		(layer "In7.Cu")
		(net "P5E_PEX3_STN4_TX_C_DP<65>")
	)
	(segment
		(start 434.629814 -366.02416)
		(end 434.630068 -366.02416)
		(width 0.1651)
		(layer "In7.Cu")
		(net "P5E_PEX3_STN4_TX_C_DP<65>")
	)
	(segment
		(start 432.816762 -370.999258)
		(end 433.247038 -370.999258)
		(width 0.1651)
		(layer "In7.Cu")
		(net "P5E_PEX3_STN4_TX_C_DP<65>")
	)
	(segment
		(start 436.865776 -360.269536)
		(end 437.050942 -359.809796)
		(width 0.1651)
		(layer "In7.Cu")
		(net "P5E_PEX3_STN4_TX_C_DP<65>")
	)
	(segment
		(start 436.267606 -361.959144)
		(end 436.267098 -361.959144)
		(width 0.1651)
		(layer "In7.Cu")
		(net "P5E_PEX3_STN4_TX_C_DP<65>")
	)
	(segment
		(start 433.533804 -368.745516)
		(end 433.718716 -368.286284)
		(width 0.1651)
		(layer "In7.Cu")
		(net "P5E_PEX3_STN4_TX_C_DP<65>")
	)
	(segment
		(start 437.150002 -359.767632)
		(end 437.149748 -359.767632)
		(width 0.1651)
		(layer "In7.Cu")
		(net "P5E_PEX3_STN4_TX_C_DP<65>")
	)
	(segment
		(start 433.533804 -370.712492)
		(end 433.533804 -368.745516)
		(width 0.1651)
		(layer "In7.Cu")
		(net "P5E_PEX3_STN4_TX_C_DP<65>")
	)
	(segment
		(start 435.20741 -364.284514)
		(end 435.356508 -364.221268)
		(width 0.1651)
		(layer "In7.Cu")
		(net "P5E_PEX3_STN4_TX_C_DP<65>")
	)
	(segment
		(start 435.811676 -363.089444)
		(end 435.996588 -362.63072)
		(width 0.1651)
		(layer "In7.Cu")
		(net "P5E_PEX3_STN4_TX_C_DP<65>")
	)
	(segment
		(start 435.085236 -364.892844)
		(end 435.085744 -364.893098)
		(width 0.1651)
		(layer "In7.Cu")
		(net "P5E_PEX3_STN4_TX_C_DP<65>")
	)
	(segment
		(start 435.085744 -364.893098)
		(end 435.022498 -364.744254)
		(width 0.1651)
		(layer "In7.Cu")
		(net "P5E_PEX3_STN4_TX_C_DP<65>")
	)
	(segment
		(start 434.174392 -367.155222)
		(end 434.111146 -367.006378)
		(width 0.1651)
		(layer "In7.Cu")
		(net "P5E_PEX3_STN4_TX_C_DP<65>")
	)
	(segment
		(start 434.751734 -365.415576)
		(end 434.900832 -365.35233)
		(width 0.1651)
		(layer "In7.Cu")
		(net "P5E_PEX3_STN4_TX_C_DP<65>")
	)
	(segment
		(start 433.98948 -367.614454)
		(end 433.989226 -367.614454)
		(width 0.1651)
		(layer "In7.Cu")
		(net "P5E_PEX3_STN4_TX_C_DP<65>")
	)
	(segment
		(start 435.478174 -363.613192)
		(end 435.663086 -363.153452)
		(width 0.1651)
		(layer "In7.Cu")
		(net "P5E_PEX3_STN4_TX_C_DP<65>")
	)
	(segment
		(start 437.566562 -358.733344)
		(end 437.566562 -358.04856)
		(width 0.1651)
		(layer "In7.Cu")
		(net "P5E_PEX3_STN4_TX_C_DP<65>")
	)
	(segment
		(start 436.267098 -361.959144)
		(end 436.45201 -361.499658)
		(width 0.1651)
		(layer "In7.Cu")
		(net "P5E_PEX3_STN4_TX_C_DP<65>")
	)
	(segment
		(start 433.65547 -368.13744)
		(end 433.840382 -367.6777)
		(width 0.1651)
		(layer "In7.Cu")
		(net "P5E_PEX3_STN4_TX_C_DP<65>")
	)
	(segment
		(start 434.111146 -367.006378)
		(end 434.296058 -366.546638)
		(width 0.1651)
		(layer "In7.Cu")
		(net "P5E_PEX3_STN4_TX_C_DP<65>")
	)
	(segment
		(start 435.812184 -363.090206)
		(end 435.811676 -363.089444)
		(width 0.1651)
		(layer "In7.Cu")
		(net "P5E_PEX3_STN4_TX_C_DP<65>")
	)
	(segment
		(start 434.566822 -365.875316)
		(end 434.751734 -365.415576)
		(width 0.1651)
		(layer "In7.Cu")
		(net "P5E_PEX3_STN4_TX_C_DP<65>")
	)
	(segment
		(start 436.118762 -362.02239)
		(end 436.267606 -361.959144)
		(width 0.1651)
		(layer "In7.Cu")
		(net "P5E_PEX3_STN4_TX_C_DP<65>")
	)
	(segment
		(start 436.90794 -360.36885)
		(end 436.865776 -360.269536)
		(width 0.1651)
		(layer "In7.Cu")
		(net "P5E_PEX3_STN4_TX_C_DP<65>")
	)
	(segment
		(start 436.45201 -361.499658)
		(end 436.452518 -361.499912)
		(width 0.1651)
		(layer "In7.Cu")
		(net "P5E_PEX3_STN4_TX_C_DP<65>")
	)
	(segment
		(start 436.452518 -361.499912)
		(end 436.389018 -361.351068)
		(width 0.1651)
		(layer "In7.Cu")
		(net "P5E_PEX3_STN4_TX_C_DP<65>")
	)
	(segment
		(start 437.050942 -359.809796)
		(end 437.150002 -359.767632)
		(width 0.1651)
		(layer "In7.Cu")
		(net "P5E_PEX3_STN4_TX_C_DP<65>")
	)
	(segment
		(start 435.54142 -363.762036)
		(end 435.478174 -363.613192)
		(width 0.1651)
		(layer "In7.Cu")
		(net "P5E_PEX3_STN4_TX_C_DP<65>")
	)
	(segment
		(start 433.840382 -367.6777)
		(end 433.98948 -367.614454)
		(width 0.1651)
		(layer "In7.Cu")
		(net "P5E_PEX3_STN4_TX_C_DP<65>")
	)
	(segment
		(start 437.566562 -358.04856)
		(end 437.275732 -357.75773)
		(width 0.1651)
		(layer "In7.Cu")
		(net "P5E_PEX3_STN4_TX_C_DP<65>")
	)
	(segment
		(start 435.996588 -362.63072)
		(end 435.997096 -362.630974)
		(width 0.1651)
		(layer "In7.Cu")
		(net "P5E_PEX3_STN4_TX_C_DP<65>")
	)
	(segment
		(start 434.900832 -365.35233)
		(end 434.900324 -365.35233)
		(width 0.1651)
		(layer "In7.Cu")
		(net "P5E_PEX3_STN4_TX_C_DP<65>")
	)
	(segment
		(start 434.444902 -366.483392)
		(end 434.629814 -366.02416)
		(width 0.1651)
		(layer "In7.Cu")
		(net "P5E_PEX3_STN4_TX_C_DP<65>")
	)
	(segment
		(start 434.900324 -365.35233)
		(end 435.085236 -364.892844)
		(width 0.1651)
		(layer "In7.Cu")
		(net "P5E_PEX3_STN4_TX_C_DP<65>")
	)
	(segment
		(start 432.689762 -370.872258)
		(end 432.816762 -370.999258)
		(width 0.1651)
		(layer "In7.Cu")
		(net "P5E_PEX3_STN4_TX_C_DP<65>")
	)
	(segment
		(start 433.247038 -370.999258)
		(end 433.533804 -370.712492)
		(width 0.1651)
		(layer "In7.Cu")
		(net "P5E_PEX3_STN4_TX_C_DP<65>")
	)
	(segment
		(start 248.63552 -220.866208)
		(end 248.299732 -220.866208)
		(width 0.13208)
		(layer "F.Cu")
		(net "SPI_PEX2_CLK_MUX_R")
	)
	(segment
		(start 248.11101 -221.05493)
		(end 247.099582 -221.05493)
		(width 0.13208)
		(layer "F.Cu")
		(net "SPI_PEX2_CLK_MUX_R")
	)
	(segment
		(start 248.299732 -220.866208)
		(end 248.11101 -221.05493)
		(width 0.13208)
		(layer "F.Cu")
		(net "SPI_PEX2_CLK_MUX_R")
	)
	(via
		(at 248.63552 -220.866208)
		(size 0.508)
		(drill 0.254)
		(layers "F.Cu" "B.Cu")
		(net "SPI_PEX2_CLK_MUX_R")
	)
	(segment
		(start 247.757696 -221.240858)
		(end 247.17502 -221.240858)
		(width 0.13208)
		(layer "B.Cu")
		(net "SPI_PEX2_CLK_MUX_R")
	)
	(segment
		(start 248.132346 -220.866208)
		(end 247.757696 -221.240858)
		(width 0.13208)
		(layer "B.Cu")
		(net "SPI_PEX2_CLK_MUX_R")
	)
	(segment
		(start 248.63552 -220.866208)
		(end 248.132346 -220.866208)
		(width 0.13208)
		(layer "B.Cu")
		(net "SPI_PEX2_CLK_MUX_R")
	)
	(segment
		(start 424.814492 -356.511606)
		(end 425.13504 -356.832154)
		(width 0.13462)
		(layer "F.Cu")
		(net "P5E_PEX3_STN4_TX_C_DP<71>")
	)
	(segment
		(start 425.13504 -356.832154)
		(end 425.13504 -357.462582)
		(width 0.13462)
		(layer "F.Cu")
		(net "P5E_PEX3_STN4_TX_C_DP<71>")
	)
	(segment
		(start 425.13504 -357.462582)
		(end 424.839892 -357.75773)
		(width 0.13462)
		(layer "F.Cu")
		(net "P5E_PEX3_STN4_TX_C_DP<71>")
	)
	(segment
		(start 423.86123 -361.196128)
		(end 423.996866 -361.149392)
		(width 0.1651)
		(layer "In7.Cu")
		(net "P5E_PEX3_STN4_TX_C_DP<71>")
	)
	(segment
		(start 422.643808 -363.923834)
		(end 422.597072 -363.787944)
		(width 0.1651)
		(layer "In7.Cu")
		(net "P5E_PEX3_STN4_TX_C_DP<71>")
	)
	(segment
		(start 420.333932 -370.712492)
		(end 420.333932 -368.661442)
		(width 0.1651)
		(layer "In7.Cu")
		(net "P5E_PEX3_STN4_TX_C_DP<71>")
	)
	(segment
		(start 420.721536 -367.635028)
		(end 420.857172 -367.588292)
		(width 0.1651)
		(layer "In7.Cu")
		(net "P5E_PEX3_STN4_TX_C_DP<71>")
	)
	(segment
		(start 423.167302 -362.850684)
		(end 423.120566 -362.714794)
		(width 0.1651)
		(layer "In7.Cu")
		(net "P5E_PEX3_STN4_TX_C_DP<71>")
	)
	(segment
		(start 423.996612 -361.149392)
		(end 425.130722 -358.824022)
		(width 0.1651)
		(layer "In7.Cu")
		(net "P5E_PEX3_STN4_TX_C_DP<71>")
	)
	(segment
		(start 423.643806 -361.641644)
		(end 423.86123 -361.196128)
		(width 0.1651)
		(layer "In7.Cu")
		(net "P5E_PEX3_STN4_TX_C_DP<71>")
	)
	(segment
		(start 423.690542 -361.777534)
		(end 423.643806 -361.641644)
		(width 0.1651)
		(layer "In7.Cu")
		(net "P5E_PEX3_STN4_TX_C_DP<71>")
	)
	(segment
		(start 421.074088 -367.143284)
		(end 421.027352 -367.007394)
		(width 0.1651)
		(layer "In7.Cu")
		(net "P5E_PEX3_STN4_TX_C_DP<71>")
	)
	(segment
		(start 420.857172 -367.588292)
		(end 421.074088 -367.143284)
		(width 0.1651)
		(layer "In7.Cu")
		(net "P5E_PEX3_STN4_TX_C_DP<71>")
	)
	(segment
		(start 421.550592 -365.934244)
		(end 421.768016 -365.488728)
		(width 0.1651)
		(layer "In7.Cu")
		(net "P5E_PEX3_STN4_TX_C_DP<71>")
	)
	(segment
		(start 421.027352 -367.007394)
		(end 421.244776 -366.561878)
		(width 0.1651)
		(layer "In7.Cu")
		(net "P5E_PEX3_STN4_TX_C_DP<71>")
	)
	(segment
		(start 422.073832 -364.861094)
		(end 422.291256 -364.415578)
		(width 0.1651)
		(layer "In7.Cu")
		(net "P5E_PEX3_STN4_TX_C_DP<71>")
	)
	(segment
		(start 425.130722 -358.04856)
		(end 424.839892 -357.75773)
		(width 0.1651)
		(layer "In7.Cu")
		(net "P5E_PEX3_STN4_TX_C_DP<71>")
	)
	(segment
		(start 419.48989 -370.872258)
		(end 419.61689 -370.999258)
		(width 0.1651)
		(layer "In7.Cu")
		(net "P5E_PEX3_STN4_TX_C_DP<71>")
	)
	(segment
		(start 420.550848 -368.216434)
		(end 420.504112 -368.080544)
		(width 0.1651)
		(layer "In7.Cu")
		(net "P5E_PEX3_STN4_TX_C_DP<71>")
	)
	(segment
		(start 419.48989 -370.489988)
		(end 419.48989 -370.872258)
		(width 0.1651)
		(layer "In7.Cu")
		(net "P5E_PEX3_STN4_TX_C_DP<71>")
	)
	(segment
		(start 422.950386 -363.295692)
		(end 422.950132 -363.295438)
		(width 0.1651)
		(layer "In7.Cu")
		(net "P5E_PEX3_STN4_TX_C_DP<71>")
	)
	(segment
		(start 425.130722 -358.824022)
		(end 425.130722 -358.04856)
		(width 0.1651)
		(layer "In7.Cu")
		(net "P5E_PEX3_STN4_TX_C_DP<71>")
	)
	(segment
		(start 422.120568 -364.996984)
		(end 422.073832 -364.861094)
		(width 0.1651)
		(layer "In7.Cu")
		(net "P5E_PEX3_STN4_TX_C_DP<71>")
	)
	(segment
		(start 422.597072 -363.787944)
		(end 422.814496 -363.342428)
		(width 0.1651)
		(layer "In7.Cu")
		(net "P5E_PEX3_STN4_TX_C_DP<71>")
	)
	(segment
		(start 419.61689 -370.999258)
		(end 420.047166 -370.999258)
		(width 0.1651)
		(layer "In7.Cu")
		(net "P5E_PEX3_STN4_TX_C_DP<71>")
	)
	(segment
		(start 423.120566 -362.714794)
		(end 423.33799 -362.269278)
		(width 0.1651)
		(layer "In7.Cu")
		(net "P5E_PEX3_STN4_TX_C_DP<71>")
	)
	(segment
		(start 420.333932 -368.661442)
		(end 420.550848 -368.216434)
		(width 0.1651)
		(layer "In7.Cu")
		(net "P5E_PEX3_STN4_TX_C_DP<71>")
	)
	(segment
		(start 422.814496 -363.342428)
		(end 422.950386 -363.295692)
		(width 0.1651)
		(layer "In7.Cu")
		(net "P5E_PEX3_STN4_TX_C_DP<71>")
	)
	(segment
		(start 423.996866 -361.149392)
		(end 423.996612 -361.149392)
		(width 0.1651)
		(layer "In7.Cu")
		(net "P5E_PEX3_STN4_TX_C_DP<71>")
	)
	(segment
		(start 422.291256 -364.415578)
		(end 422.426892 -364.368842)
		(width 0.1651)
		(layer "In7.Cu")
		(net "P5E_PEX3_STN4_TX_C_DP<71>")
	)
	(segment
		(start 422.950132 -363.295438)
		(end 423.167048 -362.850684)
		(width 0.1651)
		(layer "In7.Cu")
		(net "P5E_PEX3_STN4_TX_C_DP<71>")
	)
	(segment
		(start 421.380412 -366.515142)
		(end 421.597328 -366.070134)
		(width 0.1651)
		(layer "In7.Cu")
		(net "P5E_PEX3_STN4_TX_C_DP<71>")
	)
	(segment
		(start 421.768016 -365.488728)
		(end 421.903652 -365.441992)
		(width 0.1651)
		(layer "In7.Cu")
		(net "P5E_PEX3_STN4_TX_C_DP<71>")
	)
	(segment
		(start 421.903652 -365.441992)
		(end 422.120568 -364.996984)
		(width 0.1651)
		(layer "In7.Cu")
		(net "P5E_PEX3_STN4_TX_C_DP<71>")
	)
	(segment
		(start 421.244776 -366.561878)
		(end 421.380412 -366.515142)
		(width 0.1651)
		(layer "In7.Cu")
		(net "P5E_PEX3_STN4_TX_C_DP<71>")
	)
	(segment
		(start 422.426892 -364.368842)
		(end 422.643808 -363.923834)
		(width 0.1651)
		(layer "In7.Cu")
		(net "P5E_PEX3_STN4_TX_C_DP<71>")
	)
	(segment
		(start 423.167048 -362.850684)
		(end 423.167302 -362.850684)
		(width 0.1651)
		(layer "In7.Cu")
		(net "P5E_PEX3_STN4_TX_C_DP<71>")
	)
	(segment
		(start 421.597328 -366.070134)
		(end 421.550592 -365.934244)
		(width 0.1651)
		(layer "In7.Cu")
		(net "P5E_PEX3_STN4_TX_C_DP<71>")
	)
	(segment
		(start 423.473626 -362.222542)
		(end 423.690542 -361.777534)
		(width 0.1651)
		(layer "In7.Cu")
		(net "P5E_PEX3_STN4_TX_C_DP<71>")
	)
	(segment
		(start 420.504112 -368.080544)
		(end 420.721536 -367.635028)
		(width 0.1651)
		(layer "In7.Cu")
		(net "P5E_PEX3_STN4_TX_C_DP<71>")
	)
	(segment
		(start 420.047166 -370.999258)
		(end 420.333932 -370.712492)
		(width 0.1651)
		(layer "In7.Cu")
		(net "P5E_PEX3_STN4_TX_C_DP<71>")
	)
	(segment
		(start 423.33799 -362.269278)
		(end 423.473626 -362.222542)
		(width 0.1651)
		(layer "In7.Cu")
		(net "P5E_PEX3_STN4_TX_C_DP<71>")
	)
	(segment
		(start 419.190424 -343.365074)
		(end 419.190424 -342.734646)
		(width 0.13462)
		(layer "F.Cu")
		(net "P5E_PEX3_STN4_TX_DN<75>")
	)
	(segment
		(start 419.190424 -342.734646)
		(end 419.485572 -342.439498)
		(width 0.13462)
		(layer "F.Cu")
		(net "P5E_PEX3_STN4_TX_DN<75>")
	)
	(segment
		(start 419.510972 -343.685622)
		(end 419.190424 -343.365074)
		(width 0.13462)
		(layer "F.Cu")
		(net "P5E_PEX3_STN4_TX_DN<75>")
	)
	(segment
		(start 425.6659 -319.9384)
		(end 425.6659 -319.909952)
		(width 0.1143)
		(layer "In7.Cu")
		(net "P5E_PEX3_STN4_TX_DN<75>")
	)
	(segment
		(start 425.402502 -322.87718)
		(end 425.6659 -321.240404)
		(width 0.1651)
		(layer "In7.Cu")
		(net "P5E_PEX3_STN4_TX_DN<75>")
	)
	(segment
		(start 419.485572 -342.439498)
		(end 419.194742 -342.148668)
		(width 0.1651)
		(layer "In7.Cu")
		(net "P5E_PEX3_STN4_TX_DN<75>")
	)
	(segment
		(start 425.73448 -311.670192)
		(end 425.88561 -311.670192)
		(width 0.1143)
		(layer "In7.Cu")
		(net "P5E_PEX3_STN4_TX_DN<75>")
	)
	(segment
		(start 425.6659 -321.240404)
		(end 425.6659 -319.9384)
		(width 0.1651)
		(layer "In7.Cu")
		(net "P5E_PEX3_STN4_TX_DN<75>")
	)
	(segment
		(start 419.194742 -342.148668)
		(end 419.194742 -341.678514)
		(width 0.1651)
		(layer "In7.Cu")
		(net "P5E_PEX3_STN4_TX_DN<75>")
	)
	(segment
		(start 425.99991 -311.784492)
		(end 425.99991 -312.049922)
		(width 0.1143)
		(layer "In7.Cu")
		(net "P5E_PEX3_STN4_TX_DN<75>")
	)
	(segment
		(start 425.62018 -311.784492)
		(end 425.73448 -311.670192)
		(width 0.1143)
		(layer "In7.Cu")
		(net "P5E_PEX3_STN4_TX_DN<75>")
	)
	(segment
		(start 419.194742 -341.678514)
		(end 425.402502 -322.87718)
		(width 0.1651)
		(layer "In7.Cu")
		(net "P5E_PEX3_STN4_TX_DN<75>")
	)
	(segment
		(start 425.62018 -319.864232)
		(end 425.62018 -311.784492)
		(width 0.1143)
		(layer "In7.Cu")
		(net "P5E_PEX3_STN4_TX_DN<75>")
	)
	(segment
		(start 425.88561 -311.670192)
		(end 425.99991 -311.784492)
		(width 0.1143)
		(layer "In7.Cu")
		(net "P5E_PEX3_STN4_TX_DN<75>")
	)
	(segment
		(start 425.6659 -319.909952)
		(end 425.62018 -319.864232)
		(width 0.1143)
		(layer "In7.Cu")
		(net "P5E_PEX3_STN4_TX_DN<75>")
	)
	(via
		(at 248.353834 -225.471736)
		(size 0.6604)
		(drill 0.3302)
		(layers "F.Cu" "B.Cu")
		(net "SPI_MUX_PEX2_EN_N")
	)
	(segment
		(start 248.353834 -225.471736)
		(end 250.105672 -225.471736)
		(width 0.13208)
		(layer "B.Cu")
		(net "SPI_MUX_PEX2_EN_N")
	)
	(segment
		(start 250.105672 -225.471736)
		(end 250.330716 -225.246692)
		(width 0.13208)
		(layer "B.Cu")
		(net "SPI_MUX_PEX2_EN_N")
	)
	(segment
		(start 250.330716 -225.246692)
		(end 250.330716 -224.341182)
		(width 0.13208)
		(layer "B.Cu")
		(net "SPI_MUX_PEX2_EN_N")
	)
	(segment
		(start 248.353834 -224.337118)
		(end 248.353834 -225.471736)
		(width 0.13208)
		(layer "B.Cu")
		(net "SPI_MUX_PEX2_EN_N")
	)
	(segment
		(start 434.73624 -350.684846)
		(end 434.73624 -351.317306)
		(width 0.13462)
		(layer "F.Cu")
		(net "P5E_PEX3_STN4_TX_C_DN<67>")
	)
	(segment
		(start 435.055772 -350.365314)
		(end 434.73624 -350.684846)
		(width 0.13462)
		(layer "F.Cu")
		(net "P5E_PEX3_STN4_TX_C_DN<67>")
	)
	(segment
		(start 434.73624 -351.317306)
		(end 435.030372 -351.611438)
		(width 0.13462)
		(layer "F.Cu")
		(net "P5E_PEX3_STN4_TX_C_DN<67>")
	)
	(segment
		(start 428.96409 -371.281198)
		(end 429.415956 -370.829332)
		(width 0.1651)
		(layer "In7.Cu")
		(net "P5E_PEX3_STN4_TX_C_DN<67>")
	)
	(segment
		(start 429.99787 -367.315242)
		(end 430.250854 -366.63757)
		(width 0.1651)
		(layer "In7.Cu")
		(net "P5E_PEX3_STN4_TX_C_DN<67>")
	)
	(segment
		(start 429.415956 -370.829332)
		(end 429.415956 -368.87404)
		(width 0.1651)
		(layer "In7.Cu")
		(net "P5E_PEX3_STN4_TX_C_DN<67>")
	)
	(segment
		(start 429.997616 -367.316004)
		(end 429.99787 -367.315242)
		(width 0.1651)
		(layer "In7.Cu")
		(net "P5E_PEX3_STN4_TX_C_DN<67>")
	)
	(segment
		(start 430.251108 -366.636808)
		(end 433.185062 -358.777032)
		(width 0.1651)
		(layer "In7.Cu")
		(net "P5E_PEX3_STN4_TX_C_DN<67>")
	)
	(segment
		(start 430.250854 -366.63757)
		(end 430.251108 -366.636808)
		(width 0.1651)
		(layer "In7.Cu")
		(net "P5E_PEX3_STN4_TX_C_DN<67>")
	)
	(segment
		(start 428.289974 -371.408198)
		(end 428.416974 -371.281198)
		(width 0.1651)
		(layer "In7.Cu")
		(net "P5E_PEX3_STN4_TX_C_DN<67>")
	)
	(segment
		(start 428.416974 -371.281198)
		(end 428.96409 -371.281198)
		(width 0.1651)
		(layer "In7.Cu")
		(net "P5E_PEX3_STN4_TX_C_DN<67>")
	)
	(segment
		(start 433.185062 -354.027486)
		(end 434.739542 -352.473006)
		(width 0.1651)
		(layer "In7.Cu")
		(net "P5E_PEX3_STN4_TX_C_DN<67>")
	)
	(segment
		(start 433.185062 -358.777032)
		(end 433.185062 -354.027486)
		(width 0.1651)
		(layer "In7.Cu")
		(net "P5E_PEX3_STN4_TX_C_DN<67>")
	)
	(segment
		(start 429.415956 -368.87404)
		(end 429.997616 -367.316004)
		(width 0.1651)
		(layer "In7.Cu")
		(net "P5E_PEX3_STN4_TX_C_DN<67>")
	)
	(segment
		(start 428.289974 -371.790214)
		(end 428.289974 -371.408198)
		(width 0.1651)
		(layer "In7.Cu")
		(net "P5E_PEX3_STN4_TX_C_DN<67>")
	)
	(segment
		(start 434.739542 -351.902268)
		(end 435.030372 -351.611438)
		(width 0.1651)
		(layer "In7.Cu")
		(net "P5E_PEX3_STN4_TX_C_DN<67>")
	)
	(segment
		(start 434.739542 -352.473006)
		(end 434.739542 -351.902268)
		(width 0.1651)
		(layer "In7.Cu")
		(net "P5E_PEX3_STN4_TX_C_DN<67>")
	)
	(segment
		(start 435.055772 -349.831914)
		(end 434.735224 -349.511366)
		(width 0.13462)
		(layer "F.Cu")
		(net "P5E_PEX3_STN4_TX_DN<67>")
	)
	(segment
		(start 434.735224 -349.511366)
		(end 434.735224 -348.880938)
		(width 0.13462)
		(layer "F.Cu")
		(net "P5E_PEX3_STN4_TX_DN<67>")
	)
	(segment
		(start 434.735224 -348.880938)
		(end 435.030372 -348.58579)
		(width 0.13462)
		(layer "F.Cu")
		(net "P5E_PEX3_STN4_TX_DN<67>")
	)
	(segment
		(start 439.312304 -313.864244)
		(end 433.49799 -308.04993)
		(width 0.1651)
		(layer "In7.Cu")
		(net "P5E_PEX3_STN4_TX_DN<67>")
	)
	(segment
		(start 425.73448 -307.299868)
		(end 425.99991 -307.299868)
		(width 0.1143)
		(layer "In7.Cu")
		(net "P5E_PEX3_STN4_TX_DN<67>")
	)
	(segment
		(start 431.90668 -307.679598)
		(end 425.73448 -307.679598)
		(width 0.1143)
		(layer "In7.Cu")
		(net "P5E_PEX3_STN4_TX_DN<67>")
	)
	(segment
		(start 433.49799 -308.04993)
		(end 432.493674 -307.633878)
		(width 0.1651)
		(layer "In7.Cu")
		(net "P5E_PEX3_STN4_TX_DN<67>")
	)
	(segment
		(start 434.739542 -347.784674)
		(end 436.294022 -346.230194)
		(width 0.1651)
		(layer "In7.Cu")
		(net "P5E_PEX3_STN4_TX_DN<67>")
	)
	(segment
		(start 443.935358 -323.354192)
		(end 444.387224 -321.209162)
		(width 0.1651)
		(layer "In7.Cu")
		(net "P5E_PEX3_STN4_TX_DN<67>")
	)
	(segment
		(start 436.294022 -346.230194)
		(end 436.294022 -341.810594)
		(width 0.1651)
		(layer "In7.Cu")
		(net "P5E_PEX3_STN4_TX_DN<67>")
	)
	(segment
		(start 431.9524 -307.633878)
		(end 431.90668 -307.679598)
		(width 0.1143)
		(layer "In7.Cu")
		(net "P5E_PEX3_STN4_TX_DN<67>")
	)
	(segment
		(start 434.739542 -348.29496)
		(end 434.739542 -347.784674)
		(width 0.1651)
		(layer "In7.Cu")
		(net "P5E_PEX3_STN4_TX_DN<67>")
	)
	(segment
		(start 442.844174 -316.751208)
		(end 439.312304 -313.864244)
		(width 0.1651)
		(layer "In7.Cu")
		(net "P5E_PEX3_STN4_TX_DN<67>")
	)
	(segment
		(start 425.62018 -307.414168)
		(end 425.73448 -307.299868)
		(width 0.1143)
		(layer "In7.Cu")
		(net "P5E_PEX3_STN4_TX_DN<67>")
	)
	(segment
		(start 443.92977 -323.3801)
		(end 443.935358 -323.354192)
		(width 0.1651)
		(layer "In7.Cu")
		(net "P5E_PEX3_STN4_TX_DN<67>")
	)
	(segment
		(start 431.980848 -307.633878)
		(end 431.9524 -307.633878)
		(width 0.1143)
		(layer "In7.Cu")
		(net "P5E_PEX3_STN4_TX_DN<67>")
	)
	(segment
		(start 425.62018 -307.565298)
		(end 425.62018 -307.414168)
		(width 0.1143)
		(layer "In7.Cu")
		(net "P5E_PEX3_STN4_TX_DN<67>")
	)
	(segment
		(start 436.294022 -341.810594)
		(end 443.92977 -323.3801)
		(width 0.1651)
		(layer "In7.Cu")
		(net "P5E_PEX3_STN4_TX_DN<67>")
	)
	(segment
		(start 444.019178 -318.42202)
		(end 442.844174 -316.751208)
		(width 0.1651)
		(layer "In7.Cu")
		(net "P5E_PEX3_STN4_TX_DN<67>")
	)
	(segment
		(start 444.387224 -321.209162)
		(end 444.019178 -318.42202)
		(width 0.1651)
		(layer "In7.Cu")
		(net "P5E_PEX3_STN4_TX_DN<67>")
	)
	(segment
		(start 432.493674 -307.633878)
		(end 431.980848 -307.633878)
		(width 0.1651)
		(layer "In7.Cu")
		(net "P5E_PEX3_STN4_TX_DN<67>")
	)
	(segment
		(start 425.73448 -307.679598)
		(end 425.62018 -307.565298)
		(width 0.1143)
		(layer "In7.Cu")
		(net "P5E_PEX3_STN4_TX_DN<67>")
	)
	(segment
		(start 435.030372 -348.58579)
		(end 434.739542 -348.29496)
		(width 0.1651)
		(layer "In7.Cu")
		(net "P5E_PEX3_STN4_TX_DN<67>")
	)
	(segment
		(start 274.749768 -293.04996)
		(end 274.274788 -292.57498)
		(width 0.13208)
		(layer "F.Cu")
		(net "SPI_PEX2_CLK")
	)
	(via
		(at 274.274788 -292.57498)
		(size 0.508)
		(drill 0.254)
		(layers "F.Cu" "B.Cu")
		(net "SPI_PEX2_CLK")
	)
	(segment
		(start 273.030442 -292.1)
		(end 273.661632 -292.1)
		(width 0.13208)
		(layer "B.Cu")
		(net "SPI_PEX2_CLK")
	)
	(segment
		(start 273.661632 -292.1)
		(end 274.136612 -292.57498)
		(width 0.13208)
		(layer "B.Cu")
		(net "SPI_PEX2_CLK")
	)
	(segment
		(start 274.136612 -292.57498)
		(end 274.274788 -292.57498)
		(width 0.13208)
		(layer "B.Cu")
		(net "SPI_PEX2_CLK")
	)
	(segment
		(start 272.657062 -291.72662)
		(end 273.030442 -292.1)
		(width 0.13208)
		(layer "B.Cu")
		(net "SPI_PEX2_CLK")
	)
	(segment
		(start 428.51578 -319.941448)
		(end 428.51578 -320.250312)
		(width 0.1651)
		(layer "In5.Cu")
		(net "P5E_PEX3_STN4_RX_DN<72>")
	)
	(segment
		(start 428.84979 -318.699896)
		(end 428.84979 -318.434466)
		(width 0.1143)
		(layer "In5.Cu")
		(net "P5E_PEX3_STN4_RX_DN<72>")
	)
	(segment
		(start 418.202618 -370.246148)
		(end 418.165534 -383.739644)
		(width 0.1651)
		(layer "In5.Cu")
		(net "P5E_PEX3_STN4_RX_DN<72>")
	)
	(segment
		(start 435.55031 -406.184862)
		(end 435.063138 -406.184862)
		(width 0.1651)
		(layer "In5.Cu")
		(net "P5E_PEX3_STN4_RX_DN<72>")
	)
	(segment
		(start 436.047896 -405.687276)
		(end 435.55031 -406.184862)
		(width 0.1651)
		(layer "In5.Cu")
		(net "P5E_PEX3_STN4_RX_DN<72>")
	)
	(segment
		(start 418.391594 -369.294156)
		(end 418.202618 -370.246148)
		(width 0.1651)
		(layer "In5.Cu")
		(net "P5E_PEX3_STN4_RX_DN<72>")
	)
	(segment
		(start 435.063138 -406.184862)
		(end 434.88991 -406.35809)
		(width 0.1651)
		(layer "In5.Cu")
		(net "P5E_PEX3_STN4_RX_DN<72>")
	)
	(segment
		(start 430.076102 -358.956864)
		(end 418.578792 -368.971576)
		(width 0.1651)
		(layer "In5.Cu")
		(net "P5E_PEX3_STN4_RX_DN<72>")
	)
	(segment
		(start 430.076102 -342.312498)
		(end 430.076102 -358.956864)
		(width 0.1651)
		(layer "In5.Cu")
		(net "P5E_PEX3_STN4_RX_DN<72>")
	)
	(segment
		(start 428.84979 -318.434466)
		(end 428.73549 -318.320166)
		(width 0.1143)
		(layer "In5.Cu")
		(net "P5E_PEX3_STN4_RX_DN<72>")
	)
	(segment
		(start 418.578792 -368.971576)
		(end 418.391594 -369.294156)
		(width 0.1651)
		(layer "In5.Cu")
		(net "P5E_PEX3_STN4_RX_DN<72>")
	)
	(segment
		(start 434.297836 -393.572238)
		(end 436.047896 -395.828266)
		(width 0.1651)
		(layer "In5.Cu")
		(net "P5E_PEX3_STN4_RX_DN<72>")
	)
	(segment
		(start 428.73549 -318.320166)
		(end 428.58436 -318.320166)
		(width 0.1143)
		(layer "In5.Cu")
		(net "P5E_PEX3_STN4_RX_DN<72>")
	)
	(segment
		(start 418.911532 -385.384548)
		(end 434.297836 -393.572238)
		(width 0.1651)
		(layer "In5.Cu")
		(net "P5E_PEX3_STN4_RX_DN<72>")
	)
	(segment
		(start 428.51578 -319.913)
		(end 428.51578 -319.941448)
		(width 0.1143)
		(layer "In5.Cu")
		(net "P5E_PEX3_STN4_RX_DN<72>")
	)
	(segment
		(start 436.047896 -395.828266)
		(end 436.047896 -405.687276)
		(width 0.1651)
		(layer "In5.Cu")
		(net "P5E_PEX3_STN4_RX_DN<72>")
	)
	(segment
		(start 434.88991 -406.35809)
		(end 434.88991 -406.690068)
		(width 0.1651)
		(layer "In5.Cu")
		(net "P5E_PEX3_STN4_RX_DN<72>")
	)
	(segment
		(start 428.58436 -318.320166)
		(end 428.47006 -318.434466)
		(width 0.1143)
		(layer "In5.Cu")
		(net "P5E_PEX3_STN4_RX_DN<72>")
	)
	(segment
		(start 428.51578 -320.250312)
		(end 430.076102 -342.312498)
		(width 0.1651)
		(layer "In5.Cu")
		(net "P5E_PEX3_STN4_RX_DN<72>")
	)
	(segment
		(start 428.47006 -319.86728)
		(end 428.51578 -319.913)
		(width 0.1143)
		(layer "In5.Cu")
		(net "P5E_PEX3_STN4_RX_DN<72>")
	)
	(segment
		(start 428.47006 -318.434466)
		(end 428.47006 -319.86728)
		(width 0.1143)
		(layer "In5.Cu")
		(net "P5E_PEX3_STN4_RX_DN<72>")
	)
	(segment
		(start 418.165534 -383.739644)
		(end 418.777674 -385.25958)
		(width 0.1651)
		(layer "In5.Cu")
		(net "P5E_PEX3_STN4_RX_DN<72>")
	)
	(segment
		(start 418.777674 -385.25958)
		(end 418.911532 -385.384548)
		(width 0.1651)
		(layer "In5.Cu")
		(net "P5E_PEX3_STN4_RX_DN<72>")
	)
	(segment
		(start 275.699728 -293.04996)
		(end 275.224748 -292.57498)
		(width 0.13208)
		(layer "F.Cu")
		(net "SPI_PEX2_SDIO3")
	)
	(via
		(at 271.899888 -290.42106)
		(size 0.6604)
		(drill 0.3302)
		(layers "F.Cu" "B.Cu")
		(net "SPI_PEX2_SDIO3")
	)
	(via
		(at 275.224748 -292.57498)
		(size 0.4064)
		(drill 0.2032)
		(layers "F.Cu" "B.Cu")
		(net "SPI_PEX2_SDIO3")
	)
	(segment
		(start 271.899888 -290.42106)
		(end 272.666714 -291.187886)
		(width 0.13208)
		(layer "B.Cu")
		(net "SPI_PEX2_SDIO3")
	)
	(segment
		(start 271.899888 -289.174936)
		(end 271.899888 -290.42106)
		(width 0.13208)
		(layer "B.Cu")
		(net "SPI_PEX2_SDIO3")
	)
	(segment
		(start 273.814794 -291.378132)
		(end 273.814794 -291.79393)
		(width 0.13208)
		(layer "B.Cu")
		(net "SPI_PEX2_SDIO3")
	)
	(segment
		(start 273.624548 -291.187886)
		(end 273.814794 -291.378132)
		(width 0.13208)
		(layer "B.Cu")
		(net "SPI_PEX2_SDIO3")
	)
	(segment
		(start 274.694396 -292.044628)
		(end 275.224748 -292.57498)
		(width 0.13208)
		(layer "B.Cu")
		(net "SPI_PEX2_SDIO3")
	)
	(segment
		(start 274.065492 -292.044628)
		(end 274.694396 -292.044628)
		(width 0.13208)
		(layer "B.Cu")
		(net "SPI_PEX2_SDIO3")
	)
	(segment
		(start 273.814794 -291.79393)
		(end 274.065492 -292.044628)
		(width 0.13208)
		(layer "B.Cu")
		(net "SPI_PEX2_SDIO3")
	)
	(segment
		(start 272.666714 -291.187886)
		(end 273.624548 -291.187886)
		(width 0.13208)
		(layer "B.Cu")
		(net "SPI_PEX2_SDIO3")
	)
	(segment
		(start 425.728892 -344.219022)
		(end 425.40936 -344.538554)
		(width 0.13462)
		(layer "F.Cu")
		(net "P5E_PEX3_STN4_TX_C_DN<72>")
	)
	(segment
		(start 425.40936 -345.171014)
		(end 425.703492 -345.465146)
		(width 0.13462)
		(layer "F.Cu")
		(net "P5E_PEX3_STN4_TX_C_DN<72>")
	)
	(segment
		(start 425.40936 -344.538554)
		(end 425.40936 -345.171014)
		(width 0.13462)
		(layer "F.Cu")
		(net "P5E_PEX3_STN4_TX_C_DN<72>")
	)
	(segment
		(start 436.015892 -395.071092)
		(end 436.015892 -397.929354)
		(width 0.1651)
		(layer "In7.Cu")
		(net "P5E_PEX3_STN4_TX_C_DN<72>")
	)
	(segment
		(start 423.858182 -347.881194)
		(end 423.858182 -358.769666)
		(width 0.1651)
		(layer "In7.Cu")
		(net "P5E_PEX3_STN4_TX_C_DN<72>")
	)
	(segment
		(start 418.966904 -385.271772)
		(end 434.525166 -393.580112)
		(width 0.1651)
		(layer "In7.Cu")
		(net "P5E_PEX3_STN4_TX_C_DN<72>")
	)
	(segment
		(start 418.43325 -369.44427)
		(end 418.16782 -383.41554)
		(width 0.1651)
		(layer "In7.Cu")
		(net "P5E_PEX3_STN4_TX_C_DN<72>")
	)
	(segment
		(start 423.858182 -358.769666)
		(end 418.43325 -369.44427)
		(width 0.1651)
		(layer "In7.Cu")
		(net "P5E_PEX3_STN4_TX_C_DN<72>")
	)
	(segment
		(start 434.525166 -393.580112)
		(end 436.015892 -395.071092)
		(width 0.1651)
		(layer "In7.Cu")
		(net "P5E_PEX3_STN4_TX_C_DN<72>")
	)
	(segment
		(start 425.703492 -345.465146)
		(end 425.412662 -345.755976)
		(width 0.1651)
		(layer "In7.Cu")
		(net "P5E_PEX3_STN4_TX_C_DN<72>")
	)
	(segment
		(start 418.16782 -383.41554)
		(end 418.47262 -384.556)
		(width 0.1651)
		(layer "In7.Cu")
		(net "P5E_PEX3_STN4_TX_C_DN<72>")
	)
	(segment
		(start 434.88991 -398.50822)
		(end 434.88991 -398.890236)
		(width 0.1651)
		(layer "In7.Cu")
		(net "P5E_PEX3_STN4_TX_C_DN<72>")
	)
	(segment
		(start 418.47262 -384.556)
		(end 418.966904 -385.271772)
		(width 0.1651)
		(layer "In7.Cu")
		(net "P5E_PEX3_STN4_TX_C_DN<72>")
	)
	(segment
		(start 425.412662 -345.755976)
		(end 425.412662 -346.326714)
		(width 0.1651)
		(layer "In7.Cu")
		(net "P5E_PEX3_STN4_TX_C_DN<72>")
	)
	(segment
		(start 436.015892 -397.929354)
		(end 435.564026 -398.38122)
		(width 0.1651)
		(layer "In7.Cu")
		(net "P5E_PEX3_STN4_TX_C_DN<72>")
	)
	(segment
		(start 425.412662 -346.326714)
		(end 423.858182 -347.881194)
		(width 0.1651)
		(layer "In7.Cu")
		(net "P5E_PEX3_STN4_TX_C_DN<72>")
	)
	(segment
		(start 435.01691 -398.38122)
		(end 434.88991 -398.50822)
		(width 0.1651)
		(layer "In7.Cu")
		(net "P5E_PEX3_STN4_TX_C_DN<72>")
	)
	(segment
		(start 435.564026 -398.38122)
		(end 435.01691 -398.38122)
		(width 0.1651)
		(layer "In7.Cu")
		(net "P5E_PEX3_STN4_TX_C_DN<72>")
	)
	(segment
		(start 425.408344 -355.02723)
		(end 425.703492 -354.732082)
		(width 0.13462)
		(layer "F.Cu")
		(net "P5E_PEX3_STN4_TX_DN<71>")
	)
	(segment
		(start 425.728892 -355.978206)
		(end 425.408344 -355.657658)
		(width 0.13462)
		(layer "F.Cu")
		(net "P5E_PEX3_STN4_TX_DN<71>")
	)
	(segment
		(start 425.408344 -355.657658)
		(end 425.408344 -355.02723)
		(width 0.13462)
		(layer "F.Cu")
		(net "P5E_PEX3_STN4_TX_DN<71>")
	)
	(segment
		(start 426.967142 -352.376486)
		(end 426.967142 -341.430864)
		(width 0.1651)
		(layer "In7.Cu")
		(net "P5E_PEX3_STN4_TX_DN<71>")
	)
	(segment
		(start 425.412662 -354.441252)
		(end 425.412662 -353.930966)
		(width 0.1651)
		(layer "In7.Cu")
		(net "P5E_PEX3_STN4_TX_DN<71>")
	)
	(segment
		(start 425.703492 -354.732082)
		(end 425.412662 -354.441252)
		(width 0.1651)
		(layer "In7.Cu")
		(net "P5E_PEX3_STN4_TX_DN<71>")
	)
	(segment
		(start 430.415954 -321.137534)
		(end 430.415954 -319.027048)
		(width 0.1651)
		(layer "In7.Cu")
		(net "P5E_PEX3_STN4_TX_DN<71>")
	)
	(segment
		(start 430.370234 -318.95288)
		(end 430.370234 -315.014102)
		(width 0.1143)
		(layer "In7.Cu")
		(net "P5E_PEX3_STN4_TX_DN<71>")
	)
	(segment
		(start 425.412662 -353.930966)
		(end 426.967142 -352.376486)
		(width 0.1651)
		(layer "In7.Cu")
		(net "P5E_PEX3_STN4_TX_DN<71>")
	)
	(segment
		(start 430.415954 -318.9986)
		(end 430.370234 -318.95288)
		(width 0.1143)
		(layer "In7.Cu")
		(net "P5E_PEX3_STN4_TX_DN<71>")
	)
	(segment
		(start 430.484534 -314.899802)
		(end 430.749964 -314.899802)
		(width 0.1143)
		(layer "In7.Cu")
		(net "P5E_PEX3_STN4_TX_DN<71>")
	)
	(segment
		(start 430.370234 -315.014102)
		(end 430.484534 -314.899802)
		(width 0.1143)
		(layer "In7.Cu")
		(net "P5E_PEX3_STN4_TX_DN<71>")
	)
	(segment
		(start 426.967142 -341.430864)
		(end 430.415954 -321.137534)
		(width 0.1651)
		(layer "In7.Cu")
		(net "P5E_PEX3_STN4_TX_DN<71>")
	)
	(segment
		(start 430.415954 -319.027048)
		(end 430.415954 -318.9986)
		(width 0.1143)
		(layer "In7.Cu")
		(net "P5E_PEX3_STN4_TX_DN<71>")
	)
	(segment
		(start 274.749768 -292.099746)
		(end 274.274788 -291.624766)
		(width 0.13208)
		(layer "F.Cu")
		(net "SPI_PEX2_CS_N")
	)
	(via
		(at 274.274788 -291.624766)
		(size 0.4064)
		(drill 0.2032)
		(layers "F.Cu" "B.Cu")
		(net "SPI_PEX2_CS_N")
	)
	(via
		(at 274.74672 -291.152834)
		(size 0.6604)
		(drill 0.3302)
		(layers "F.Cu" "B.Cu")
		(net "SPI_PEX2_CS_N")
	)
	(segment
		(start 273.799808 -289.174936)
		(end 272.849848 -289.174936)
		(width 0.13208)
		(layer "B.Cu")
		(net "SPI_PEX2_CS_N")
	)
	(segment
		(start 274.74672 -289.50285)
		(end 274.418806 -289.174936)
		(width 0.13208)
		(layer "B.Cu")
		(net "SPI_PEX2_CS_N")
	)
	(segment
		(start 274.274788 -291.624766)
		(end 274.74672 -291.152834)
		(width 0.13208)
		(layer "B.Cu")
		(net "SPI_PEX2_CS_N")
	)
	(segment
		(start 274.418806 -289.174936)
		(end 273.799808 -289.174936)
		(width 0.13208)
		(layer "B.Cu")
		(net "SPI_PEX2_CS_N")
	)
	(segment
		(start 274.74672 -291.152834)
		(end 274.74672 -289.50285)
		(width 0.13208)
		(layer "B.Cu")
		(net "SPI_PEX2_CS_N")
	)
	(segment
		(start 418.596572 -344.219022)
		(end 418.91712 -344.53957)
		(width 0.13462)
		(layer "F.Cu")
		(net "P5E_PEX3_STN4_TX_C_DP<75>")
	)
	(segment
		(start 418.91712 -345.169998)
		(end 418.621972 -345.465146)
		(width 0.13462)
		(layer "F.Cu")
		(net "P5E_PEX3_STN4_TX_C_DP<75>")
	)
	(segment
		(start 418.91712 -344.53957)
		(end 418.91712 -345.169998)
		(width 0.13462)
		(layer "F.Cu")
		(net "P5E_PEX3_STN4_TX_C_DP<75>")
	)
	(segment
		(start 428.289974 -396.49019)
		(end 428.289974 -396.872206)
		(width 0.1651)
		(layer "In7.Cu")
		(net "P5E_PEX3_STN4_TX_C_DP<75>")
	)
	(segment
		(start 428.03064 -393.955016)
		(end 427.909736 -393.989814)
		(width 0.1651)
		(layer "In7.Cu")
		(net "P5E_PEX3_STN4_TX_C_DP<75>")
	)
	(segment
		(start 426.886878 -393.424664)
		(end 426.453046 -393.184888)
		(width 0.1651)
		(layer "In7.Cu")
		(net "P5E_PEX3_STN4_TX_C_DP<75>")
	)
	(segment
		(start 418.912802 -345.755976)
		(end 418.621972 -345.465146)
		(width 0.1651)
		(layer "In7.Cu")
		(net "P5E_PEX3_STN4_TX_C_DP<75>")
	)
	(segment
		(start 417.358322 -358.722676)
		(end 417.358322 -347.764354)
		(width 0.1651)
		(layer "In7.Cu")
		(net "P5E_PEX3_STN4_TX_C_DP<75>")
	)
	(segment
		(start 426.453046 -393.184888)
		(end 426.418248 -393.063984)
		(width 0.1651)
		(layer "In7.Cu")
		(net "P5E_PEX3_STN4_TX_C_DP<75>")
	)
	(segment
		(start 429.134016 -394.864336)
		(end 428.463964 -394.194284)
		(width 0.1651)
		(layer "In7.Cu")
		(net "P5E_PEX3_STN4_TX_C_DP<75>")
	)
	(segment
		(start 414.73501 -383.573782)
		(end 415.11474 -369.237514)
		(width 0.1651)
		(layer "In7.Cu")
		(net "P5E_PEX3_STN4_TX_C_DP<75>")
	)
	(segment
		(start 427.475904 -393.750038)
		(end 427.441106 -393.629134)
		(width 0.1651)
		(layer "In7.Cu")
		(net "P5E_PEX3_STN4_TX_C_DP<75>")
	)
	(segment
		(start 417.358322 -347.764354)
		(end 418.912802 -346.209874)
		(width 0.1651)
		(layer "In7.Cu")
		(net "P5E_PEX3_STN4_TX_C_DP<75>")
	)
	(segment
		(start 428.416974 -396.999206)
		(end 428.84725 -396.999206)
		(width 0.1651)
		(layer "In7.Cu")
		(net "P5E_PEX3_STN4_TX_C_DP<75>")
	)
	(segment
		(start 415.11474 -369.237514)
		(end 415.115502 -369.211352)
		(width 0.1651)
		(layer "In7.Cu")
		(net "P5E_PEX3_STN4_TX_C_DP<75>")
	)
	(segment
		(start 427.441106 -393.629134)
		(end 427.007782 -393.389866)
		(width 0.1651)
		(layer "In7.Cu")
		(net "P5E_PEX3_STN4_TX_C_DP<75>")
	)
	(segment
		(start 428.289974 -396.872206)
		(end 428.416974 -396.999206)
		(width 0.1651)
		(layer "In7.Cu")
		(net "P5E_PEX3_STN4_TX_C_DP<75>")
	)
	(segment
		(start 415.397188 -385.866894)
		(end 414.73501 -383.573782)
		(width 0.1651)
		(layer "In7.Cu")
		(net "P5E_PEX3_STN4_TX_C_DP<75>")
	)
	(segment
		(start 427.007782 -393.389866)
		(end 426.886878 -393.424664)
		(width 0.1651)
		(layer "In7.Cu")
		(net "P5E_PEX3_STN4_TX_C_DP<75>")
	)
	(segment
		(start 418.912802 -346.209874)
		(end 418.912802 -345.755976)
		(width 0.1651)
		(layer "In7.Cu")
		(net "P5E_PEX3_STN4_TX_C_DP<75>")
	)
	(segment
		(start 426.418248 -393.063984)
		(end 416.890962 -387.801104)
		(width 0.1651)
		(layer "In7.Cu")
		(net "P5E_PEX3_STN4_TX_C_DP<75>")
	)
	(segment
		(start 428.84725 -396.999206)
		(end 429.134016 -396.71244)
		(width 0.1651)
		(layer "In7.Cu")
		(net "P5E_PEX3_STN4_TX_C_DP<75>")
	)
	(segment
		(start 427.909736 -393.989814)
		(end 427.475904 -393.750038)
		(width 0.1651)
		(layer "In7.Cu")
		(net "P5E_PEX3_STN4_TX_C_DP<75>")
	)
	(segment
		(start 415.115502 -369.211352)
		(end 417.358322 -358.722676)
		(width 0.1651)
		(layer "In7.Cu")
		(net "P5E_PEX3_STN4_TX_C_DP<75>")
	)
	(segment
		(start 416.890962 -387.801104)
		(end 415.397188 -385.866894)
		(width 0.1651)
		(layer "In7.Cu")
		(net "P5E_PEX3_STN4_TX_C_DP<75>")
	)
	(segment
		(start 428.463964 -394.194284)
		(end 428.03064 -393.955016)
		(width 0.1651)
		(layer "In7.Cu")
		(net "P5E_PEX3_STN4_TX_C_DP<75>")
	)
	(segment
		(start 429.134016 -396.71244)
		(end 429.134016 -394.864336)
		(width 0.1651)
		(layer "In7.Cu")
		(net "P5E_PEX3_STN4_TX_C_DP<75>")
	)
	(segment
		(start 416.081464 -349.511366)
		(end 416.081464 -348.880938)
		(width 0.13462)
		(layer "F.Cu")
		(net "P5E_PEX3_STN4_TX_DN<76>")
	)
	(segment
		(start 416.081464 -348.880938)
		(end 416.376612 -348.58579)
		(width 0.13462)
		(layer "F.Cu")
		(net "P5E_PEX3_STN4_TX_DN<76>")
	)
	(segment
		(start 416.402012 -349.831914)
		(end 416.081464 -349.511366)
		(width 0.13462)
		(layer "F.Cu")
		(net "P5E_PEX3_STN4_TX_DN<76>")
	)
	(segment
		(start 416.376612 -348.58579)
		(end 416.085782 -348.29496)
		(width 0.1651)
		(layer "In7.Cu")
		(net "P5E_PEX3_STN4_TX_DN<76>")
	)
	(segment
		(start 424.71594 -321.075304)
		(end 424.71594 -319.9384)
		(width 0.1651)
		(layer "In7.Cu")
		(net "P5E_PEX3_STN4_TX_DN<76>")
	)
	(segment
		(start 424.437048 -322.685156)
		(end 424.71594 -321.075304)
		(width 0.1651)
		(layer "In7.Cu")
		(net "P5E_PEX3_STN4_TX_DN<76>")
	)
	(segment
		(start 424.71594 -319.9384)
		(end 424.71594 -319.909952)
		(width 0.1143)
		(layer "In7.Cu")
		(net "P5E_PEX3_STN4_TX_DN<76>")
	)
	(segment
		(start 424.78452 -313.570112)
		(end 424.93565 -313.570112)
		(width 0.1143)
		(layer "In7.Cu")
		(net "P5E_PEX3_STN4_TX_DN<76>")
	)
	(segment
		(start 416.085782 -348.29496)
		(end 416.085782 -347.784674)
		(width 0.1651)
		(layer "In7.Cu")
		(net "P5E_PEX3_STN4_TX_DN<76>")
	)
	(segment
		(start 425.04995 -313.684412)
		(end 425.04995 -313.949842)
		(width 0.1143)
		(layer "In7.Cu")
		(net "P5E_PEX3_STN4_TX_DN<76>")
	)
	(segment
		(start 417.640262 -346.230194)
		(end 417.640262 -341.712042)
		(width 0.1651)
		(layer "In7.Cu")
		(net "P5E_PEX3_STN4_TX_DN<76>")
	)
	(segment
		(start 424.71594 -319.909952)
		(end 424.67022 -319.864232)
		(width 0.1143)
		(layer "In7.Cu")
		(net "P5E_PEX3_STN4_TX_DN<76>")
	)
	(segment
		(start 424.67022 -313.684412)
		(end 424.78452 -313.570112)
		(width 0.1143)
		(layer "In7.Cu")
		(net "P5E_PEX3_STN4_TX_DN<76>")
	)
	(segment
		(start 417.640262 -341.712042)
		(end 424.437048 -322.685156)
		(width 0.1651)
		(layer "In7.Cu")
		(net "P5E_PEX3_STN4_TX_DN<76>")
	)
	(segment
		(start 424.67022 -319.864232)
		(end 424.67022 -313.684412)
		(width 0.1143)
		(layer "In7.Cu")
		(net "P5E_PEX3_STN4_TX_DN<76>")
	)
	(segment
		(start 416.085782 -347.784674)
		(end 417.640262 -346.230194)
		(width 0.1651)
		(layer "In7.Cu")
		(net "P5E_PEX3_STN4_TX_DN<76>")
	)
	(segment
		(start 424.93565 -313.570112)
		(end 425.04995 -313.684412)
		(width 0.1143)
		(layer "In7.Cu")
		(net "P5E_PEX3_STN4_TX_DN<76>")
	)
	(segment
		(start 435.701186 -365.85017)
		(end 435.542436 -365.819436)
		(width 0.1651)
		(layer "In5.Cu")
		(net "P5E_PEX3_STN4_RX_DP<66>")
	)
	(segment
		(start 434.475128 -307.419248)
		(end 435.797452 -308.741572)
		(width 0.1651)
		(layer "In5.Cu")
		(net "P5E_PEX3_STN4_RX_DP<66>")
	)
	(segment
		(start 444.20409 -358.35209)
		(end 443.412372 -359.943146)
		(width 0.1651)
		(layer "In5.Cu")
		(net "P5E_PEX3_STN4_RX_DP<66>")
	)
	(segment
		(start 431.786538 -368.585496)
		(end 431.365914 -369.600988)
		(width 0.1651)
		(layer "In5.Cu")
		(net "P5E_PEX3_STN4_RX_DP<66>")
	)
	(segment
		(start 445.20104 -318.06388)
		(end 445.20104 -322.043806)
		(width 0.1651)
		(layer "In5.Cu")
		(net "P5E_PEX3_STN4_RX_DP<66>")
	)
	(segment
		(start 439.179208 -363.330998)
		(end 438.79262 -363.64037)
		(width 0.1651)
		(layer "In5.Cu")
		(net "P5E_PEX3_STN4_RX_DP<66>")
	)
	(segment
		(start 434.690012 -366.531906)
		(end 434.531262 -366.500918)
		(width 0.1651)
		(layer "In5.Cu")
		(net "P5E_PEX3_STN4_RX_DP<66>")
	)
	(segment
		(start 431.904648 -306.965858)
		(end 431.933096 -306.965858)
		(width 0.1143)
		(layer "In5.Cu")
		(net "P5E_PEX3_STN4_RX_DP<66>")
	)
	(segment
		(start 440.083702 -362.509562)
		(end 440.071764 -362.61675)
		(width 0.1651)
		(layer "In5.Cu")
		(net "P5E_PEX3_STN4_RX_DP<66>")
	)
	(segment
		(start 440.782202 -313.645042)
		(end 445.20104 -318.06388)
		(width 0.1651)
		(layer "In5.Cu")
		(net "P5E_PEX3_STN4_RX_DP<66>")
	)
	(segment
		(start 440.577732 -362.211874)
		(end 440.470544 -362.199936)
		(width 0.1651)
		(layer "In5.Cu")
		(net "P5E_PEX3_STN4_RX_DP<66>")
	)
	(segment
		(start 440.470544 -362.199936)
		(end 440.083702 -362.509562)
		(width 0.1651)
		(layer "In5.Cu")
		(net "P5E_PEX3_STN4_RX_DP<66>")
	)
	(segment
		(start 433.10937 -367.459768)
		(end 433.078382 -367.618264)
		(width 0.1651)
		(layer "In5.Cu")
		(net "P5E_PEX3_STN4_RX_DP<66>")
	)
	(segment
		(start 436.196232 -309.704232)
		(end 439.680604 -313.188604)
		(width 0.1651)
		(layer "In5.Cu")
		(net "P5E_PEX3_STN4_RX_DP<66>")
	)
	(segment
		(start 439.191146 -363.22381)
		(end 439.179208 -363.330998)
		(width 0.1651)
		(layer "In5.Cu")
		(net "P5E_PEX3_STN4_RX_DP<66>")
	)
	(segment
		(start 435.100476 -366.2553)
		(end 434.690012 -366.531906)
		(width 0.1651)
		(layer "In5.Cu")
		(net "P5E_PEX3_STN4_RX_DP<66>")
	)
	(segment
		(start 439.685176 -362.926122)
		(end 439.577988 -362.914184)
		(width 0.1651)
		(layer "In5.Cu")
		(net "P5E_PEX3_STN4_RX_DP<66>")
	)
	(segment
		(start 430.065434 -306.349908)
		(end 430.179734 -306.464208)
		(width 0.1143)
		(layer "In5.Cu")
		(net "P5E_PEX3_STN4_RX_DP<66>")
	)
	(segment
		(start 431.365914 -369.600988)
		(end 431.365914 -379.570488)
		(width 0.1651)
		(layer "In5.Cu")
		(net "P5E_PEX3_STN4_RX_DP<66>")
	)
	(segment
		(start 431.858928 -306.920138)
		(end 431.904648 -306.965858)
		(width 0.1143)
		(layer "In5.Cu")
		(net "P5E_PEX3_STN4_RX_DP<66>")
	)
	(segment
		(start 433.078382 -367.618264)
		(end 432.082194 -368.28984)
		(width 0.1651)
		(layer "In5.Cu")
		(net "P5E_PEX3_STN4_RX_DP<66>")
	)
	(segment
		(start 439.577988 -362.914184)
		(end 439.191146 -363.22381)
		(width 0.1651)
		(layer "In5.Cu")
		(net "P5E_PEX3_STN4_RX_DP<66>")
	)
	(segment
		(start 432.082194 -368.28984)
		(end 431.786538 -368.585496)
		(width 0.1651)
		(layer "In5.Cu")
		(net "P5E_PEX3_STN4_RX_DP<66>")
	)
	(segment
		(start 430.40554 -306.920138)
		(end 431.858928 -306.920138)
		(width 0.1143)
		(layer "In5.Cu")
		(net "P5E_PEX3_STN4_RX_DP<66>")
	)
	(segment
		(start 435.542436 -365.819436)
		(end 435.131464 -366.09655)
		(width 0.1651)
		(layer "In5.Cu")
		(net "P5E_PEX3_STN4_RX_DP<66>")
	)
	(segment
		(start 433.380642 -306.965858)
		(end 434.475128 -307.419248)
		(width 0.1651)
		(layer "In5.Cu")
		(net "P5E_PEX3_STN4_RX_DP<66>")
	)
	(segment
		(start 435.131464 -366.09655)
		(end 435.100476 -366.2553)
		(width 0.1651)
		(layer "In5.Cu")
		(net "P5E_PEX3_STN4_RX_DP<66>")
	)
	(segment
		(start 430.179734 -306.694332)
		(end 430.40554 -306.920138)
		(width 0.1143)
		(layer "In5.Cu")
		(net "P5E_PEX3_STN4_RX_DP<66>")
	)
	(segment
		(start 434.089302 -366.936782)
		(end 433.678838 -367.213388)
		(width 0.1651)
		(layer "In5.Cu")
		(net "P5E_PEX3_STN4_RX_DP<66>")
	)
	(segment
		(start 431.365914 -379.570488)
		(end 431.033428 -379.902974)
		(width 0.1651)
		(layer "In5.Cu")
		(net "P5E_PEX3_STN4_RX_DP<66>")
	)
	(segment
		(start 440.071764 -362.61675)
		(end 439.685176 -362.926122)
		(width 0.1651)
		(layer "In5.Cu")
		(net "P5E_PEX3_STN4_RX_DP<66>")
	)
	(segment
		(start 434.12029 -366.778032)
		(end 434.089302 -366.936782)
		(width 0.1651)
		(layer "In5.Cu")
		(net "P5E_PEX3_STN4_RX_DP<66>")
	)
	(segment
		(start 438.631838 -363.62259)
		(end 438.244996 -363.932216)
		(width 0.1651)
		(layer "In5.Cu")
		(net "P5E_PEX3_STN4_RX_DP<66>")
	)
	(segment
		(start 438.227216 -364.092998)
		(end 437.7944 -364.4392)
		(width 0.1651)
		(layer "In5.Cu")
		(net "P5E_PEX3_STN4_RX_DP<66>")
	)
	(segment
		(start 430.179734 -306.464208)
		(end 430.179734 -306.694332)
		(width 0.1143)
		(layer "In5.Cu")
		(net "P5E_PEX3_STN4_RX_DP<66>")
	)
	(segment
		(start 445.20104 -322.043806)
		(end 444.20409 -358.35209)
		(width 0.1651)
		(layer "In5.Cu")
		(net "P5E_PEX3_STN4_RX_DP<66>")
	)
	(segment
		(start 438.244996 -363.932216)
		(end 438.227216 -364.092998)
		(width 0.1651)
		(layer "In5.Cu")
		(net "P5E_PEX3_STN4_RX_DP<66>")
	)
	(segment
		(start 431.033428 -379.902974)
		(end 430.663096 -379.902974)
		(width 0.1651)
		(layer "In5.Cu")
		(net "P5E_PEX3_STN4_RX_DP<66>")
	)
	(segment
		(start 430.663096 -379.902974)
		(end 430.489868 -379.729746)
		(width 0.1651)
		(layer "In5.Cu")
		(net "P5E_PEX3_STN4_RX_DP<66>")
	)
	(segment
		(start 439.680604 -313.188604)
		(end 440.782202 -313.645042)
		(width 0.1651)
		(layer "In5.Cu")
		(net "P5E_PEX3_STN4_RX_DP<66>")
	)
	(segment
		(start 434.531262 -366.500918)
		(end 434.12029 -366.778032)
		(width 0.1651)
		(layer "In5.Cu")
		(net "P5E_PEX3_STN4_RX_DP<66>")
	)
	(segment
		(start 443.412372 -359.943146)
		(end 440.577732 -362.211874)
		(width 0.1651)
		(layer "In5.Cu")
		(net "P5E_PEX3_STN4_RX_DP<66>")
	)
	(segment
		(start 433.520342 -367.182654)
		(end 433.10937 -367.459768)
		(width 0.1651)
		(layer "In5.Cu")
		(net "P5E_PEX3_STN4_RX_DP<66>")
	)
	(segment
		(start 429.800004 -306.349908)
		(end 430.065434 -306.349908)
		(width 0.1143)
		(layer "In5.Cu")
		(net "P5E_PEX3_STN4_RX_DP<66>")
	)
	(segment
		(start 433.678838 -367.213388)
		(end 433.520342 -367.182654)
		(width 0.1651)
		(layer "In5.Cu")
		(net "P5E_PEX3_STN4_RX_DP<66>")
	)
	(segment
		(start 438.79262 -363.64037)
		(end 438.631838 -363.62259)
		(width 0.1651)
		(layer "In5.Cu")
		(net "P5E_PEX3_STN4_RX_DP<66>")
	)
	(segment
		(start 431.933096 -306.965858)
		(end 433.380642 -306.965858)
		(width 0.1651)
		(layer "In5.Cu")
		(net "P5E_PEX3_STN4_RX_DP<66>")
	)
	(segment
		(start 437.7944 -364.4392)
		(end 435.701186 -365.85017)
		(width 0.1651)
		(layer "In5.Cu")
		(net "P5E_PEX3_STN4_RX_DP<66>")
	)
	(segment
		(start 430.489868 -379.729746)
		(end 430.489868 -379.390148)
		(width 0.1651)
		(layer "In5.Cu")
		(net "P5E_PEX3_STN4_RX_DP<66>")
	)
	(segment
		(start 435.797452 -308.741572)
		(end 436.196232 -309.704232)
		(width 0.1651)
		(layer "In5.Cu")
		(net "P5E_PEX3_STN4_RX_DP<66>")
	)
	(segment
		(start 416.08248 -351.317306)
		(end 416.376612 -351.611438)
		(width 0.13462)
		(layer "F.Cu")
		(net "P5E_PEX3_STN4_TX_C_DN<76>")
	)
	(segment
		(start 416.08248 -350.684846)
		(end 416.08248 -351.317306)
		(width 0.13462)
		(layer "F.Cu")
		(net "P5E_PEX3_STN4_TX_C_DN<76>")
	)
	(segment
		(start 416.402012 -350.365314)
		(end 416.08248 -350.684846)
		(width 0.13462)
		(layer "F.Cu")
		(net "P5E_PEX3_STN4_TX_C_DN<76>")
	)
	(segment
		(start 426.089826 -398.890236)
		(end 426.089826 -398.50822)
		(width 0.1651)
		(layer "In7.Cu")
		(net "P5E_PEX3_STN4_TX_C_DN<76>")
	)
	(segment
		(start 414.031176 -383.714244)
		(end 414.030922 -383.713482)
		(width 0.1651)
		(layer "In7.Cu")
		(net "P5E_PEX3_STN4_TX_C_DN<76>")
	)
	(segment
		(start 414.030922 -383.713482)
		(end 414.031176 -383.713482)
		(width 0.1651)
		(layer "In7.Cu")
		(net "P5E_PEX3_STN4_TX_C_DN<76>")
	)
	(segment
		(start 416.085782 -352.473006)
		(end 416.085782 -351.902268)
		(width 0.1651)
		(layer "In7.Cu")
		(net "P5E_PEX3_STN4_TX_C_DN<76>")
	)
	(segment
		(start 414.814004 -386.287264)
		(end 414.031176 -383.714244)
		(width 0.1651)
		(layer "In7.Cu")
		(net "P5E_PEX3_STN4_TX_C_DN<76>")
	)
	(segment
		(start 426.763942 -398.38122)
		(end 427.215808 -397.929354)
		(width 0.1651)
		(layer "In7.Cu")
		(net "P5E_PEX3_STN4_TX_C_DN<76>")
	)
	(segment
		(start 414.031176 -383.713482)
		(end 414.030922 -383.713228)
		(width 0.1651)
		(layer "In7.Cu")
		(net "P5E_PEX3_STN4_TX_C_DN<76>")
	)
	(segment
		(start 414.531302 -354.027486)
		(end 416.085782 -352.473006)
		(width 0.1651)
		(layer "In7.Cu")
		(net "P5E_PEX3_STN4_TX_C_DN<76>")
	)
	(segment
		(start 427.215808 -397.929354)
		(end 427.215808 -395.133068)
		(width 0.1651)
		(layer "In7.Cu")
		(net "P5E_PEX3_STN4_TX_C_DN<76>")
	)
	(segment
		(start 427.215808 -395.133068)
		(end 425.29633 -393.21359)
		(width 0.1651)
		(layer "In7.Cu")
		(net "P5E_PEX3_STN4_TX_C_DN<76>")
	)
	(segment
		(start 416.085782 -351.902268)
		(end 416.376612 -351.611438)
		(width 0.1651)
		(layer "In7.Cu")
		(net "P5E_PEX3_STN4_TX_C_DN<76>")
	)
	(segment
		(start 414.030922 -383.713228)
		(end 414.531302 -358.47274)
		(width 0.1651)
		(layer "In7.Cu")
		(net "P5E_PEX3_STN4_TX_C_DN<76>")
	)
	(segment
		(start 426.216826 -398.38122)
		(end 426.763942 -398.38122)
		(width 0.1651)
		(layer "In7.Cu")
		(net "P5E_PEX3_STN4_TX_C_DN<76>")
	)
	(segment
		(start 425.29633 -393.21359)
		(end 416.409632 -388.304278)
		(width 0.1651)
		(layer "In7.Cu")
		(net "P5E_PEX3_STN4_TX_C_DN<76>")
	)
	(segment
		(start 416.409632 -388.304278)
		(end 414.814004 -386.287264)
		(width 0.1651)
		(layer "In7.Cu")
		(net "P5E_PEX3_STN4_TX_C_DN<76>")
	)
	(segment
		(start 414.531302 -358.47274)
		(end 414.531302 -354.027486)
		(width 0.1651)
		(layer "In7.Cu")
		(net "P5E_PEX3_STN4_TX_C_DN<76>")
	)
	(segment
		(start 426.089826 -398.50822)
		(end 426.216826 -398.38122)
		(width 0.1651)
		(layer "In7.Cu")
		(net "P5E_PEX3_STN4_TX_C_DN<76>")
	)
	(segment
		(start 425.62018 -316.534292)
		(end 425.73448 -316.419992)
		(width 0.1143)
		(layer "In5.Cu")
		(net "P5E_PEX3_STN4_RX_DN<75>")
	)
	(segment
		(start 429.44796 -395.50086)
		(end 429.274986 -394.727176)
		(width 0.1651)
		(layer "In5.Cu")
		(net "P5E_PEX3_STN4_RX_DN<75>")
	)
	(segment
		(start 420.749222 -358.901492)
		(end 420.749222 -341.901018)
		(width 0.1651)
		(layer "In5.Cu")
		(net "P5E_PEX3_STN4_RX_DN<75>")
	)
	(segment
		(start 425.663106 -323.289676)
		(end 425.6659 -323.286882)
		(width 0.1651)
		(layer "In5.Cu")
		(net "P5E_PEX3_STN4_RX_DN<75>")
	)
	(segment
		(start 425.62018 -319.864232)
		(end 425.62018 -316.534292)
		(width 0.1143)
		(layer "In5.Cu")
		(net "P5E_PEX3_STN4_RX_DN<75>")
	)
	(segment
		(start 425.73448 -316.419992)
		(end 425.88561 -316.419992)
		(width 0.1143)
		(layer "In5.Cu")
		(net "P5E_PEX3_STN4_RX_DN<75>")
	)
	(segment
		(start 429.44796 -404.587202)
		(end 429.44796 -395.50086)
		(width 0.1651)
		(layer "In5.Cu")
		(net "P5E_PEX3_STN4_RX_DN<75>")
	)
	(segment
		(start 417.64966 -388.242556)
		(end 416.250882 -386.863082)
		(width 0.1651)
		(layer "In5.Cu")
		(net "P5E_PEX3_STN4_RX_DN<75>")
	)
	(segment
		(start 415.495994 -368.368072)
		(end 420.749222 -358.901492)
		(width 0.1651)
		(layer "In5.Cu")
		(net "P5E_PEX3_STN4_RX_DN<75>")
	)
	(segment
		(start 425.6659 -323.286882)
		(end 425.6659 -319.9384)
		(width 0.1651)
		(layer "In5.Cu")
		(net "P5E_PEX3_STN4_RX_DN<75>")
	)
	(segment
		(start 428.484284 -394.027406)
		(end 417.64966 -388.242556)
		(width 0.1651)
		(layer "In5.Cu")
		(net "P5E_PEX3_STN4_RX_DN<75>")
	)
	(segment
		(start 428.289974 -405.258016)
		(end 428.463202 -405.084788)
		(width 0.1651)
		(layer "In5.Cu")
		(net "P5E_PEX3_STN4_RX_DN<75>")
	)
	(segment
		(start 428.463202 -405.084788)
		(end 428.950374 -405.084788)
		(width 0.1651)
		(layer "In5.Cu")
		(net "P5E_PEX3_STN4_RX_DN<75>")
	)
	(segment
		(start 425.6659 -319.9384)
		(end 425.6659 -319.909952)
		(width 0.1143)
		(layer "In5.Cu")
		(net "P5E_PEX3_STN4_RX_DN<75>")
	)
	(segment
		(start 428.289974 -405.589994)
		(end 428.289974 -405.258016)
		(width 0.1651)
		(layer "In5.Cu")
		(net "P5E_PEX3_STN4_RX_DN<75>")
	)
	(segment
		(start 415.268918 -384.42519)
		(end 415.310574 -369.302538)
		(width 0.1651)
		(layer "In5.Cu")
		(net "P5E_PEX3_STN4_RX_DN<75>")
	)
	(segment
		(start 428.950374 -405.084788)
		(end 429.44796 -404.587202)
		(width 0.1651)
		(layer "In5.Cu")
		(net "P5E_PEX3_STN4_RX_DN<75>")
	)
	(segment
		(start 425.99991 -316.534292)
		(end 425.99991 -316.799722)
		(width 0.1143)
		(layer "In5.Cu")
		(net "P5E_PEX3_STN4_RX_DN<75>")
	)
	(segment
		(start 429.274986 -394.727176)
		(end 428.484284 -394.027406)
		(width 0.1651)
		(layer "In5.Cu")
		(net "P5E_PEX3_STN4_RX_DN<75>")
	)
	(segment
		(start 425.6659 -319.909952)
		(end 425.62018 -319.864232)
		(width 0.1143)
		(layer "In5.Cu")
		(net "P5E_PEX3_STN4_RX_DN<75>")
	)
	(segment
		(start 415.310574 -369.302538)
		(end 415.495994 -368.368072)
		(width 0.1651)
		(layer "In5.Cu")
		(net "P5E_PEX3_STN4_RX_DN<75>")
	)
	(segment
		(start 420.749222 -341.901018)
		(end 425.663106 -323.289676)
		(width 0.1651)
		(layer "In5.Cu")
		(net "P5E_PEX3_STN4_RX_DN<75>")
	)
	(segment
		(start 425.88561 -316.419992)
		(end 425.99991 -316.534292)
		(width 0.1143)
		(layer "In5.Cu")
		(net "P5E_PEX3_STN4_RX_DN<75>")
	)
	(segment
		(start 416.250882 -386.863082)
		(end 415.268918 -384.42519)
		(width 0.1651)
		(layer "In5.Cu")
		(net "P5E_PEX3_STN4_RX_DN<75>")
	)
	(segment
		(start 14.860016 -229.94493)
		(end 15.020036 -229.94493)
		(width 0.13208)
		(layer "F.Cu")
		(net "SPI_PEX0_SDIO2_R1")
	)
	(segment
		(start 13.227558 -229.94493)
		(end 14.860016 -229.94493)
		(width 0.13208)
		(layer "F.Cu")
		(net "SPI_PEX0_SDIO2_R1")
	)
	(via
		(at 13.227558 -229.94493)
		(size 0.508)
		(drill 0.254)
		(layers "F.Cu" "B.Cu")
		(net "SPI_PEX0_SDIO2_R1")
	)
	(segment
		(start 14.430248 -227.965)
		(end 14.430248 -228.981)
		(width 0.13208)
		(layer "B.Cu")
		(net "SPI_PEX0_SDIO2_R1")
	)
	(segment
		(start 14.430248 -229.997)
		(end 14.378178 -229.94493)
		(width 0.13208)
		(layer "B.Cu")
		(net "SPI_PEX0_SDIO2_R1")
	)
	(segment
		(start 14.378178 -229.94493)
		(end 13.227558 -229.94493)
		(width 0.13208)
		(layer "B.Cu")
		(net "SPI_PEX0_SDIO2_R1")
	)
	(segment
		(start 14.430248 -228.981)
		(end 14.430248 -229.997)
		(width 0.13208)
		(layer "B.Cu")
		(net "SPI_PEX0_SDIO2_R1")
	)
	(segment
		(start 413.293052 -344.219022)
		(end 412.97352 -344.538554)
		(width 0.13462)
		(layer "F.Cu")
		(net "P5E_PEX3_STN4_TX_C_DN<78>")
	)
	(segment
		(start 412.97352 -345.171014)
		(end 413.267652 -345.465146)
		(width 0.13462)
		(layer "F.Cu")
		(net "P5E_PEX3_STN4_TX_C_DN<78>")
	)
	(segment
		(start 412.97352 -344.538554)
		(end 412.97352 -345.171014)
		(width 0.13462)
		(layer "F.Cu")
		(net "P5E_PEX3_STN4_TX_C_DN<78>")
	)
	(segment
		(start 415.139378 -389.87476)
		(end 413.03448 -387.32206)
		(width 0.1651)
		(layer "In7.Cu")
		(net "P5E_PEX3_STN4_TX_C_DN<78>")
	)
	(segment
		(start 412.976822 -345.755976)
		(end 413.267652 -345.465146)
		(width 0.1651)
		(layer "In7.Cu")
		(net "P5E_PEX3_STN4_TX_C_DN<78>")
	)
	(segment
		(start 412.976822 -346.326714)
		(end 412.976822 -345.755976)
		(width 0.1651)
		(layer "In7.Cu")
		(net "P5E_PEX3_STN4_TX_C_DN<78>")
	)
	(segment
		(start 422.815766 -395.465046)
		(end 421.366696 -394.015976)
		(width 0.1651)
		(layer "In7.Cu")
		(net "P5E_PEX3_STN4_TX_C_DN<78>")
	)
	(segment
		(start 411.422342 -358.413558)
		(end 411.422342 -347.881194)
		(width 0.1651)
		(layer "In7.Cu")
		(net "P5E_PEX3_STN4_TX_C_DN<78>")
	)
	(segment
		(start 422.815766 -397.929354)
		(end 422.815766 -395.465046)
		(width 0.1651)
		(layer "In7.Cu")
		(net "P5E_PEX3_STN4_TX_C_DN<78>")
	)
	(segment
		(start 421.689784 -398.890236)
		(end 421.689784 -398.50822)
		(width 0.1651)
		(layer "In7.Cu")
		(net "P5E_PEX3_STN4_TX_C_DN<78>")
	)
	(segment
		(start 413.03448 -387.32206)
		(end 411.96514 -383.8067)
		(width 0.1651)
		(layer "In7.Cu")
		(net "P5E_PEX3_STN4_TX_C_DN<78>")
	)
	(segment
		(start 411.96514 -383.8067)
		(end 411.422342 -358.413558)
		(width 0.1651)
		(layer "In7.Cu")
		(net "P5E_PEX3_STN4_TX_C_DN<78>")
	)
	(segment
		(start 422.3639 -398.38122)
		(end 422.815766 -397.929354)
		(width 0.1651)
		(layer "In7.Cu")
		(net "P5E_PEX3_STN4_TX_C_DN<78>")
	)
	(segment
		(start 411.422342 -347.881194)
		(end 412.976822 -346.326714)
		(width 0.1651)
		(layer "In7.Cu")
		(net "P5E_PEX3_STN4_TX_C_DN<78>")
	)
	(segment
		(start 421.816784 -398.38122)
		(end 422.3639 -398.38122)
		(width 0.1651)
		(layer "In7.Cu")
		(net "P5E_PEX3_STN4_TX_C_DN<78>")
	)
	(segment
		(start 421.689784 -398.50822)
		(end 421.816784 -398.38122)
		(width 0.1651)
		(layer "In7.Cu")
		(net "P5E_PEX3_STN4_TX_C_DN<78>")
	)
	(segment
		(start 421.366696 -394.015976)
		(end 415.139378 -389.87476)
		(width 0.1651)
		(layer "In7.Cu")
		(net "P5E_PEX3_STN4_TX_C_DN<78>")
	)
	(segment
		(start 43.499786 -293.04996)
		(end 43.024806 -292.57498)
		(width 0.13208)
		(layer "F.Cu")
		(net "SPI_PEX0_SDIO3")
	)
	(via
		(at 39.699946 -290.42106)
		(size 0.6604)
		(drill 0.3302)
		(layers "F.Cu" "B.Cu")
		(net "SPI_PEX0_SDIO3")
	)
	(via
		(at 43.024806 -292.57498)
		(size 0.4064)
		(drill 0.2032)
		(layers "F.Cu" "B.Cu")
		(net "SPI_PEX0_SDIO3")
	)
	(segment
		(start 41.614852 -291.378132)
		(end 41.424606 -291.187886)
		(width 0.13208)
		(layer "B.Cu")
		(net "SPI_PEX0_SDIO3")
	)
	(segment
		(start 43.024806 -292.57498)
		(end 42.494454 -292.044628)
		(width 0.13208)
		(layer "B.Cu")
		(net "SPI_PEX0_SDIO3")
	)
	(segment
		(start 42.494454 -292.044628)
		(end 41.86555 -292.044628)
		(width 0.13208)
		(layer "B.Cu")
		(net "SPI_PEX0_SDIO3")
	)
	(segment
		(start 41.614852 -291.79393)
		(end 41.614852 -291.378132)
		(width 0.13208)
		(layer "B.Cu")
		(net "SPI_PEX0_SDIO3")
	)
	(segment
		(start 41.424606 -291.187886)
		(end 40.466772 -291.187886)
		(width 0.13208)
		(layer "B.Cu")
		(net "SPI_PEX0_SDIO3")
	)
	(segment
		(start 40.466772 -291.187886)
		(end 39.699946 -290.42106)
		(width 0.13208)
		(layer "B.Cu")
		(net "SPI_PEX0_SDIO3")
	)
	(segment
		(start 41.86555 -292.044628)
		(end 41.614852 -291.79393)
		(width 0.13208)
		(layer "B.Cu")
		(net "SPI_PEX0_SDIO3")
	)
	(segment
		(start 39.699946 -290.42106)
		(end 39.699946 -289.174936)
		(width 0.13208)
		(layer "B.Cu")
		(net "SPI_PEX0_SDIO3")
	)
	(segment
		(start 408.71902 -364.342934)
		(end 408.786838 -364.259114)
		(width 0.1651)
		(layer "In5.Cu")
		(net "P5E_PEX3_STN4_RX_DP<79>")
	)
	(segment
		(start 408.77109 -364.835694)
		(end 408.71902 -364.342934)
		(width 0.1651)
		(layer "In5.Cu")
		(net "P5E_PEX3_STN4_RX_DP<79>")
	)
	(segment
		(start 421.629586 -316.455298)
		(end 421.855392 -316.229492)
		(width 0.1143)
		(layer "In5.Cu")
		(net "P5E_PEX3_STN4_RX_DP<79>")
	)
	(segment
		(start 420.302182 -395.007592)
		(end 419.890956 -394.626846)
		(width 0.1651)
		(layer "In5.Cu")
		(net "P5E_PEX3_STN4_RX_DP<79>")
	)
	(segment
		(start 408.650948 -363.69879)
		(end 408.599132 -363.20603)
		(width 0.1651)
		(layer "In5.Cu")
		(net "P5E_PEX3_STN4_RX_DP<79>")
	)
	(segment
		(start 420.365936 -395.572742)
		(end 420.302182 -395.007592)
		(width 0.1651)
		(layer "In5.Cu")
		(net "P5E_PEX3_STN4_RX_DP<79>")
	)
	(segment
		(start 408.735022 -363.766608)
		(end 408.650948 -363.69879)
		(width 0.1651)
		(layer "In5.Cu")
		(net "P5E_PEX3_STN4_RX_DP<79>")
	)
	(segment
		(start 421.583866 -321.287902)
		(end 421.583866 -319.9384)
		(width 0.1651)
		(layer "In5.Cu")
		(net "P5E_PEX3_STN4_RX_DP<79>")
	)
	(segment
		(start 411.013656 -385.373626)
		(end 408.977592 -366.065562)
		(width 0.1651)
		(layer "In5.Cu")
		(net "P5E_PEX3_STN4_RX_DP<79>")
	)
	(segment
		(start 419.890956 -394.626846)
		(end 414.945322 -391.557256)
		(width 0.1651)
		(layer "In5.Cu")
		(net "P5E_PEX3_STN4_RX_DP<79>")
	)
	(segment
		(start 408.599132 -363.20603)
		(end 408.66695 -363.12221)
		(width 0.1651)
		(layer "In5.Cu")
		(net "P5E_PEX3_STN4_RX_DP<79>")
	)
	(segment
		(start 419.48989 -404.290022)
		(end 419.48989 -404.62962)
		(width 0.1651)
		(layer "In5.Cu")
		(net "P5E_PEX3_STN4_RX_DP<79>")
	)
	(segment
		(start 408.879548 -365.986568)
		(end 408.827732 -365.493808)
		(width 0.1651)
		(layer "In5.Cu")
		(net "P5E_PEX3_STN4_RX_DP<79>")
	)
	(segment
		(start 422.199816 -316.115192)
		(end 422.199816 -315.849762)
		(width 0.1143)
		(layer "In5.Cu")
		(net "P5E_PEX3_STN4_RX_DP<79>")
	)
	(segment
		(start 408.85491 -364.903512)
		(end 408.77109 -364.835694)
		(width 0.1651)
		(layer "In5.Cu")
		(net "P5E_PEX3_STN4_RX_DP<79>")
	)
	(segment
		(start 408.827732 -365.493808)
		(end 408.906726 -365.396018)
		(width 0.1651)
		(layer "In5.Cu")
		(net "P5E_PEX3_STN4_RX_DP<79>")
	)
	(segment
		(start 421.583866 -319.9384)
		(end 421.583866 -319.909952)
		(width 0.1143)
		(layer "In5.Cu")
		(net "P5E_PEX3_STN4_RX_DP<79>")
	)
	(segment
		(start 408.203654 -358.727248)
		(end 407.821892 -343.686384)
		(width 0.1651)
		(layer "In5.Cu")
		(net "P5E_PEX3_STN4_RX_DP<79>")
	)
	(segment
		(start 419.663118 -404.802848)
		(end 420.03345 -404.802848)
		(width 0.1651)
		(layer "In5.Cu")
		(net "P5E_PEX3_STN4_RX_DP<79>")
	)
	(segment
		(start 422.085516 -316.229492)
		(end 422.199816 -316.115192)
		(width 0.1143)
		(layer "In5.Cu")
		(net "P5E_PEX3_STN4_RX_DP<79>")
	)
	(segment
		(start 407.821892 -343.686384)
		(end 408.0637 -341.722964)
		(width 0.1651)
		(layer "In5.Cu")
		(net "P5E_PEX3_STN4_RX_DP<79>")
	)
	(segment
		(start 420.03345 -404.802848)
		(end 420.365936 -404.470362)
		(width 0.1651)
		(layer "In5.Cu")
		(net "P5E_PEX3_STN4_RX_DP<79>")
	)
	(segment
		(start 408.786838 -364.259114)
		(end 408.735022 -363.766608)
		(width 0.1651)
		(layer "In5.Cu")
		(net "P5E_PEX3_STN4_RX_DP<79>")
	)
	(segment
		(start 419.48989 -404.62962)
		(end 419.663118 -404.802848)
		(width 0.1651)
		(layer "In5.Cu")
		(net "P5E_PEX3_STN4_RX_DP<79>")
	)
	(segment
		(start 421.629586 -319.864232)
		(end 421.629586 -316.455298)
		(width 0.1143)
		(layer "In5.Cu")
		(net "P5E_PEX3_STN4_RX_DP<79>")
	)
	(segment
		(start 408.66695 -363.12221)
		(end 408.20467 -358.738424)
		(width 0.1651)
		(layer "In5.Cu")
		(net "P5E_PEX3_STN4_RX_DP<79>")
	)
	(segment
		(start 421.583866 -319.909952)
		(end 421.629586 -319.864232)
		(width 0.1143)
		(layer "In5.Cu")
		(net "P5E_PEX3_STN4_RX_DP<79>")
	)
	(segment
		(start 408.0637 -341.722964)
		(end 421.583866 -321.287902)
		(width 0.1651)
		(layer "In5.Cu")
		(net "P5E_PEX3_STN4_RX_DP<79>")
	)
	(segment
		(start 421.855392 -316.229492)
		(end 422.085516 -316.229492)
		(width 0.1143)
		(layer "In5.Cu")
		(net "P5E_PEX3_STN4_RX_DP<79>")
	)
	(segment
		(start 420.365936 -404.470362)
		(end 420.365936 -395.572742)
		(width 0.1651)
		(layer "In5.Cu")
		(net "P5E_PEX3_STN4_RX_DP<79>")
	)
	(segment
		(start 408.977592 -366.065562)
		(end 408.879548 -365.986568)
		(width 0.1651)
		(layer "In5.Cu")
		(net "P5E_PEX3_STN4_RX_DP<79>")
	)
	(segment
		(start 408.906726 -365.396018)
		(end 408.85491 -364.903512)
		(width 0.1651)
		(layer "In5.Cu")
		(net "P5E_PEX3_STN4_RX_DP<79>")
	)
	(segment
		(start 412.769304 -389.358124)
		(end 411.013656 -385.373626)
		(width 0.1651)
		(layer "In5.Cu")
		(net "P5E_PEX3_STN4_RX_DP<79>")
	)
	(segment
		(start 408.20467 -358.738424)
		(end 408.203654 -358.727248)
		(width 0.1651)
		(layer "In5.Cu")
		(net "P5E_PEX3_STN4_RX_DP<79>")
	)
	(segment
		(start 414.945322 -391.557256)
		(end 412.769304 -389.358124)
		(width 0.1651)
		(layer "In5.Cu")
		(net "P5E_PEX3_STN4_RX_DP<79>")
	)
	(segment
		(start 42.549826 -292.099746)
		(end 42.074846 -291.624766)
		(width 0.13208)
		(layer "F.Cu")
		(net "SPI_PEX0_CS_N")
	)
	(via
		(at 42.546778 -291.152834)
		(size 0.6604)
		(drill 0.3302)
		(layers "F.Cu" "B.Cu")
		(net "SPI_PEX0_CS_N")
	)
	(via
		(at 42.074846 -291.624766)
		(size 0.4064)
		(drill 0.2032)
		(layers "F.Cu" "B.Cu")
		(net "SPI_PEX0_CS_N")
	)
	(segment
		(start 40.649906 -289.174936)
		(end 41.538906 -289.174936)
		(width 0.13208)
		(layer "B.Cu")
		(net "SPI_PEX0_CS_N")
	)
	(segment
		(start 41.538906 -289.174936)
		(end 42.207688 -289.174936)
		(width 0.13208)
		(layer "B.Cu")
		(net "SPI_PEX0_CS_N")
	)
	(segment
		(start 42.546778 -291.152834)
		(end 42.074846 -291.624766)
		(width 0.13208)
		(layer "B.Cu")
		(net "SPI_PEX0_CS_N")
	)
	(segment
		(start 42.546778 -289.514026)
		(end 42.546778 -291.152834)
		(width 0.13208)
		(layer "B.Cu")
		(net "SPI_PEX0_CS_N")
	)
	(segment
		(start 42.207688 -289.174936)
		(end 42.546778 -289.514026)
		(width 0.13208)
		(layer "B.Cu")
		(net "SPI_PEX0_CS_N")
	)
	(segment
		(start 412.6992 -356.832154)
		(end 412.6992 -357.462582)
		(width 0.13462)
		(layer "F.Cu")
		(net "P5E_PEX3_STN4_TX_C_DP<77>")
	)
	(segment
		(start 412.6992 -357.462582)
		(end 412.404052 -357.75773)
		(width 0.13462)
		(layer "F.Cu")
		(net "P5E_PEX3_STN4_TX_C_DP<77>")
	)
	(segment
		(start 412.378652 -356.511606)
		(end 412.6992 -356.832154)
		(width 0.13462)
		(layer "F.Cu")
		(net "P5E_PEX3_STN4_TX_C_DP<77>")
	)
	(segment
		(start 422.464738 -393.274804)
		(end 422.430448 -393.1539)
		(width 0.1651)
		(layer "In7.Cu")
		(net "P5E_PEX3_STN4_TX_C_DP<77>")
	)
	(segment
		(start 413.62122 -386.8801)
		(end 412.694882 -383.71272)
		(width 0.1651)
		(layer "In7.Cu")
		(net "P5E_PEX3_STN4_TX_C_DP<77>")
	)
	(segment
		(start 424.447208 -396.999206)
		(end 424.733974 -396.71244)
		(width 0.1651)
		(layer "In7.Cu")
		(net "P5E_PEX3_STN4_TX_C_DP<77>")
	)
	(segment
		(start 415.579052 -389.333994)
		(end 413.62122 -386.8801)
		(width 0.1651)
		(layer "In7.Cu")
		(net "P5E_PEX3_STN4_TX_C_DP<77>")
	)
	(segment
		(start 424.733974 -396.71244)
		(end 424.733974 -395.000734)
		(width 0.1651)
		(layer "In7.Cu")
		(net "P5E_PEX3_STN4_TX_C_DP<77>")
	)
	(segment
		(start 421.409876 -392.584686)
		(end 415.579052 -389.333994)
		(width 0.1651)
		(layer "In7.Cu")
		(net "P5E_PEX3_STN4_TX_C_DP<77>")
	)
	(segment
		(start 412.694882 -358.04856)
		(end 412.404052 -357.75773)
		(width 0.1651)
		(layer "In7.Cu")
		(net "P5E_PEX3_STN4_TX_C_DP<77>")
	)
	(segment
		(start 423.889932 -396.872206)
		(end 424.016932 -396.999206)
		(width 0.1651)
		(layer "In7.Cu")
		(net "P5E_PEX3_STN4_TX_C_DP<77>")
	)
	(segment
		(start 422.897808 -393.516104)
		(end 422.464738 -393.274804)
		(width 0.1651)
		(layer "In7.Cu")
		(net "P5E_PEX3_STN4_TX_C_DP<77>")
	)
	(segment
		(start 422.430448 -393.1539)
		(end 421.997886 -392.912854)
		(width 0.1651)
		(layer "In7.Cu")
		(net "P5E_PEX3_STN4_TX_C_DP<77>")
	)
	(segment
		(start 421.876982 -392.947144)
		(end 421.444166 -392.705844)
		(width 0.1651)
		(layer "In7.Cu")
		(net "P5E_PEX3_STN4_TX_C_DP<77>")
	)
	(segment
		(start 423.46245 -393.72921)
		(end 423.018712 -393.481814)
		(width 0.1651)
		(layer "In7.Cu")
		(net "P5E_PEX3_STN4_TX_C_DP<77>")
	)
	(segment
		(start 424.733974 -395.000734)
		(end 423.46245 -393.72921)
		(width 0.1651)
		(layer "In7.Cu")
		(net "P5E_PEX3_STN4_TX_C_DP<77>")
	)
	(segment
		(start 424.016932 -396.999206)
		(end 424.447208 -396.999206)
		(width 0.1651)
		(layer "In7.Cu")
		(net "P5E_PEX3_STN4_TX_C_DP<77>")
	)
	(segment
		(start 412.694882 -383.71272)
		(end 412.694882 -358.04856)
		(width 0.1651)
		(layer "In7.Cu")
		(net "P5E_PEX3_STN4_TX_C_DP<77>")
	)
	(segment
		(start 423.889932 -396.49019)
		(end 423.889932 -396.872206)
		(width 0.1651)
		(layer "In7.Cu")
		(net "P5E_PEX3_STN4_TX_C_DP<77>")
	)
	(segment
		(start 421.997886 -392.912854)
		(end 421.876982 -392.947144)
		(width 0.1651)
		(layer "In7.Cu")
		(net "P5E_PEX3_STN4_TX_C_DP<77>")
	)
	(segment
		(start 423.018712 -393.481814)
		(end 422.897808 -393.516104)
		(width 0.1651)
		(layer "In7.Cu")
		(net "P5E_PEX3_STN4_TX_C_DP<77>")
	)
	(segment
		(start 421.444166 -392.705844)
		(end 421.409876 -392.584686)
		(width 0.1651)
		(layer "In7.Cu")
		(net "P5E_PEX3_STN4_TX_C_DP<77>")
	)
	(segment
		(start 43.499786 -293.99992)
		(end 43.024806 -293.52494)
		(width 0.13208)
		(layer "F.Cu")
		(net "SPI_PEX0_SDIO2")
	)
	(via
		(at 43.024806 -293.52494)
		(size 0.508)
		(drill 0.254)
		(layers "F.Cu" "B.Cu")
		(net "SPI_PEX0_SDIO2")
	)
	(segment
		(start 40.905176 -293.940484)
		(end 40.519096 -294.326564)
		(width 0.13208)
		(layer "B.Cu")
		(net "SPI_PEX0_SDIO2")
	)
	(segment
		(start 43.024806 -293.52494)
		(end 42.609262 -293.940484)
		(width 0.13208)
		(layer "B.Cu")
		(net "SPI_PEX0_SDIO2")
	)
	(segment
		(start 40.519096 -294.326564)
		(end 40.519096 -294.8051)
		(width 0.13208)
		(layer "B.Cu")
		(net "SPI_PEX0_SDIO2")
	)
	(segment
		(start 42.609262 -293.940484)
		(end 40.905176 -293.940484)
		(width 0.13208)
		(layer "B.Cu")
		(net "SPI_PEX0_SDIO2")
	)
	(segment
		(start 427.505876 -368.758724)
		(end 427.247812 -369.381786)
		(width 0.1651)
		(layer "In5.Cu")
		(net "P5E_PEX3_STN4_RX_DN<68>")
	)
	(segment
		(start 430.484534 -308.629558)
		(end 431.914808 -308.629558)
		(width 0.1143)
		(layer "In5.Cu")
		(net "P5E_PEX3_STN4_RX_DN<68>")
	)
	(segment
		(start 430.370234 -308.515258)
		(end 430.484534 -308.629558)
		(width 0.1143)
		(layer "In5.Cu")
		(net "P5E_PEX3_STN4_RX_DN<68>")
	)
	(segment
		(start 426.750226 -380.184914)
		(end 426.263054 -380.184914)
		(width 0.1651)
		(layer "In5.Cu")
		(net "P5E_PEX3_STN4_RX_DN<68>")
	)
	(segment
		(start 430.370234 -308.364128)
		(end 430.370234 -308.515258)
		(width 0.1143)
		(layer "In5.Cu")
		(net "P5E_PEX3_STN4_RX_DN<68>")
	)
	(segment
		(start 430.484534 -308.249828)
		(end 430.370234 -308.364128)
		(width 0.1143)
		(layer "In5.Cu")
		(net "P5E_PEX3_STN4_RX_DN<68>")
	)
	(segment
		(start 439.72607 -315.16447)
		(end 443.5602 -318.9986)
		(width 0.1651)
		(layer "In5.Cu")
		(net "P5E_PEX3_STN4_RX_DN<68>")
	)
	(segment
		(start 427.247812 -379.687328)
		(end 426.750226 -380.184914)
		(width 0.1651)
		(layer "In5.Cu")
		(net "P5E_PEX3_STN4_RX_DN<68>")
	)
	(segment
		(start 426.089826 -380.358142)
		(end 426.089826 -380.69012)
		(width 0.1651)
		(layer "In5.Cu")
		(net "P5E_PEX3_STN4_RX_DN<68>")
	)
	(segment
		(start 442.172598 -358.70261)
		(end 441.954412 -358.924606)
		(width 0.1651)
		(layer "In5.Cu")
		(net "P5E_PEX3_STN4_RX_DN<68>")
	)
	(segment
		(start 428.075852 -368.188748)
		(end 427.505876 -368.758724)
		(width 0.1651)
		(layer "In5.Cu")
		(net "P5E_PEX3_STN4_RX_DN<68>")
	)
	(segment
		(start 443.5602 -321.719956)
		(end 442.570108 -357.768398)
		(width 0.1651)
		(layer "In5.Cu")
		(net "P5E_PEX3_STN4_RX_DN<68>")
	)
	(segment
		(start 431.960528 -308.583838)
		(end 431.988976 -308.583838)
		(width 0.1143)
		(layer "In5.Cu")
		(net "P5E_PEX3_STN4_RX_DN<68>")
	)
	(segment
		(start 443.5602 -318.9986)
		(end 443.5602 -321.719956)
		(width 0.1651)
		(layer "In5.Cu")
		(net "P5E_PEX3_STN4_RX_DN<68>")
	)
	(segment
		(start 442.570108 -357.768398)
		(end 442.172598 -358.70261)
		(width 0.1651)
		(layer "In5.Cu")
		(net "P5E_PEX3_STN4_RX_DN<68>")
	)
	(segment
		(start 434.7083 -310.63692)
		(end 438.88914 -314.81776)
		(width 0.1651)
		(layer "In5.Cu")
		(net "P5E_PEX3_STN4_RX_DN<68>")
	)
	(segment
		(start 438.88914 -314.81776)
		(end 439.72607 -315.16447)
		(width 0.1651)
		(layer "In5.Cu")
		(net "P5E_PEX3_STN4_RX_DN<68>")
	)
	(segment
		(start 441.29325 -359.332276)
		(end 428.075852 -368.188748)
		(width 0.1651)
		(layer "In5.Cu")
		(net "P5E_PEX3_STN4_RX_DN<68>")
	)
	(segment
		(start 434.280564 -309.60441)
		(end 434.7083 -310.63692)
		(width 0.1651)
		(layer "In5.Cu")
		(net "P5E_PEX3_STN4_RX_DN<68>")
	)
	(segment
		(start 441.954412 -358.924606)
		(end 441.29325 -359.332276)
		(width 0.1651)
		(layer "In5.Cu")
		(net "P5E_PEX3_STN4_RX_DN<68>")
	)
	(segment
		(start 431.988976 -308.583838)
		(end 433.259992 -308.583838)
		(width 0.1651)
		(layer "In5.Cu")
		(net "P5E_PEX3_STN4_RX_DN<68>")
	)
	(segment
		(start 427.247812 -369.381786)
		(end 427.247812 -379.687328)
		(width 0.1651)
		(layer "In5.Cu")
		(net "P5E_PEX3_STN4_RX_DN<68>")
	)
	(segment
		(start 426.263054 -380.184914)
		(end 426.089826 -380.358142)
		(width 0.1651)
		(layer "In5.Cu")
		(net "P5E_PEX3_STN4_RX_DN<68>")
	)
	(segment
		(start 430.749964 -308.249828)
		(end 430.484534 -308.249828)
		(width 0.1143)
		(layer "In5.Cu")
		(net "P5E_PEX3_STN4_RX_DN<68>")
	)
	(segment
		(start 431.914808 -308.629558)
		(end 431.960528 -308.583838)
		(width 0.1143)
		(layer "In5.Cu")
		(net "P5E_PEX3_STN4_RX_DN<68>")
	)
	(segment
		(start 433.259992 -308.583838)
		(end 434.280564 -309.60441)
		(width 0.1651)
		(layer "In5.Cu")
		(net "P5E_PEX3_STN4_RX_DN<68>")
	)
	(via
		(at 16.19123 -225.491802)
		(size 0.6604)
		(drill 0.3302)
		(layers "F.Cu" "B.Cu")
		(net "SPI_MUX_PEX0_EN_N")
	)
	(segment
		(start 18.168112 -225.25609)
		(end 17.9324 -225.491802)
		(width 0.13208)
		(layer "B.Cu")
		(net "SPI_MUX_PEX0_EN_N")
	)
	(segment
		(start 17.9324 -225.491802)
		(end 16.19123 -225.491802)
		(width 0.13208)
		(layer "B.Cu")
		(net "SPI_MUX_PEX0_EN_N")
	)
	(segment
		(start 18.168112 -224.341182)
		(end 18.168112 -225.25609)
		(width 0.13208)
		(layer "B.Cu")
		(net "SPI_MUX_PEX0_EN_N")
	)
	(segment
		(start 16.19123 -225.491802)
		(end 16.19123 -224.337118)
		(width 0.13208)
		(layer "B.Cu")
		(net "SPI_MUX_PEX0_EN_N")
	)
	(segment
		(start 438.779412 -362.212636)
		(end 438.619392 -362.19003)
		(width 0.1651)
		(layer "In5.Cu")
		(net "P5E_PEX3_STN4_RX_DP<67>")
	)
	(segment
		(start 439.754518 -361.480354)
		(end 439.594498 -361.457748)
		(width 0.1651)
		(layer "In5.Cu")
		(net "P5E_PEX3_STN4_RX_DP<67>")
	)
	(segment
		(start 433.143152 -366.075214)
		(end 433.142898 -366.075214)
		(width 0.1651)
		(layer "In5.Cu")
		(net "P5E_PEX3_STN4_RX_DP<67>")
	)
	(segment
		(start 432.569874 -366.311688)
		(end 432.154584 -366.582198)
		(width 0.1651)
		(layer "In5.Cu")
		(net "P5E_PEX3_STN4_RX_DP<67>")
	)
	(segment
		(start 443.242446 -358.120696)
		(end 442.617098 -359.330752)
		(width 0.1651)
		(layer "In5.Cu")
		(net "P5E_PEX3_STN4_RX_DP<67>")
	)
	(segment
		(start 436.8292 -363.6772)
		(end 433.750212 -365.680244)
		(width 0.1651)
		(layer "In5.Cu")
		(net "P5E_PEX3_STN4_RX_DP<67>")
	)
	(segment
		(start 431.705766 -367.010188)
		(end 431.547778 -366.97666)
		(width 0.1651)
		(layer "In5.Cu")
		(net "P5E_PEX3_STN4_RX_DP<67>")
	)
	(segment
		(start 439.175144 -361.915456)
		(end 438.779412 -362.212636)
		(width 0.1651)
		(layer "In5.Cu")
		(net "P5E_PEX3_STN4_RX_DP<67>")
	)
	(segment
		(start 437.247792 -363.219746)
		(end 437.225186 -363.38002)
		(width 0.1651)
		(layer "In5.Cu")
		(net "P5E_PEX3_STN4_RX_DP<67>")
	)
	(segment
		(start 442.664088 -316.918848)
		(end 442.664088 -317.080392)
		(width 0.1651)
		(layer "In5.Cu")
		(net "P5E_PEX3_STN4_RX_DP<67>")
	)
	(segment
		(start 437.225186 -363.38002)
		(end 437.224932 -363.38002)
		(width 0.1651)
		(layer "In5.Cu")
		(net "P5E_PEX3_STN4_RX_DP<67>")
	)
	(segment
		(start 433.17668 -365.917226)
		(end 433.143152 -366.075214)
		(width 0.1651)
		(layer "In5.Cu")
		(net "P5E_PEX3_STN4_RX_DP<67>")
	)
	(segment
		(start 433.59197 -365.646716)
		(end 433.17668 -365.917226)
		(width 0.1651)
		(layer "In5.Cu")
		(net "P5E_PEX3_STN4_RX_DP<67>")
	)
	(segment
		(start 428.833534 -378.8029)
		(end 428.463202 -378.8029)
		(width 0.1651)
		(layer "In5.Cu")
		(net "P5E_PEX3_STN4_RX_DP<67>")
	)
	(segment
		(start 437.644286 -362.922312)
		(end 437.247792 -363.219746)
		(width 0.1651)
		(layer "In5.Cu")
		(net "P5E_PEX3_STN4_RX_DP<67>")
	)
	(segment
		(start 439.006234 -313.974734)
		(end 440.224672 -314.479432)
		(width 0.1651)
		(layer "In5.Cu")
		(net "P5E_PEX3_STN4_RX_DP<67>")
	)
	(segment
		(start 437.224932 -363.38002)
		(end 436.8292 -363.6772)
		(width 0.1651)
		(layer "In5.Cu")
		(net "P5E_PEX3_STN4_RX_DP<67>")
	)
	(segment
		(start 439.198004 -361.755436)
		(end 439.175398 -361.915456)
		(width 0.1651)
		(layer "In5.Cu")
		(net "P5E_PEX3_STN4_RX_DP<67>")
	)
	(segment
		(start 432.022504 -307.915818)
		(end 432.050952 -307.915818)
		(width 0.1143)
		(layer "In5.Cu")
		(net "P5E_PEX3_STN4_RX_DP<67>")
	)
	(segment
		(start 429.971962 -368.138202)
		(end 429.630586 -368.479578)
		(width 0.1651)
		(layer "In5.Cu")
		(net "P5E_PEX3_STN4_RX_DP<67>")
	)
	(segment
		(start 442.664088 -317.080392)
		(end 443.014608 -317.430912)
		(width 0.1651)
		(layer "In5.Cu")
		(net "P5E_PEX3_STN4_RX_DP<67>")
	)
	(segment
		(start 432.121056 -366.740186)
		(end 432.120802 -366.740186)
		(width 0.1651)
		(layer "In5.Cu")
		(net "P5E_PEX3_STN4_RX_DP<67>")
	)
	(segment
		(start 440.224672 -314.479432)
		(end 442.664088 -316.918848)
		(width 0.1651)
		(layer "In5.Cu")
		(net "P5E_PEX3_STN4_RX_DP<67>")
	)
	(segment
		(start 431.132234 -367.246916)
		(end 431.09896 -367.405158)
		(width 0.1651)
		(layer "In5.Cu")
		(net "P5E_PEX3_STN4_RX_DP<67>")
	)
	(segment
		(start 433.097432 -307.915818)
		(end 433.907946 -308.251606)
		(width 0.1651)
		(layer "In5.Cu")
		(net "P5E_PEX3_STN4_RX_DP<67>")
	)
	(segment
		(start 433.907946 -308.251606)
		(end 434.94706 -309.29072)
		(width 0.1651)
		(layer "In5.Cu")
		(net "P5E_PEX3_STN4_RX_DP<67>")
	)
	(segment
		(start 431.098706 -367.405158)
		(end 429.971962 -368.138202)
		(width 0.1651)
		(layer "In5.Cu")
		(net "P5E_PEX3_STN4_RX_DP<67>")
	)
	(segment
		(start 432.154584 -366.582198)
		(end 432.121056 -366.740186)
		(width 0.1651)
		(layer "In5.Cu")
		(net "P5E_PEX3_STN4_RX_DP<67>")
	)
	(segment
		(start 428.16526 -307.299868)
		(end 428.27956 -307.414168)
		(width 0.1143)
		(layer "In5.Cu")
		(net "P5E_PEX3_STN4_RX_DP<67>")
	)
	(segment
		(start 443.176152 -317.430912)
		(end 444.237618 -318.492378)
		(width 0.1651)
		(layer "In5.Cu")
		(net "P5E_PEX3_STN4_RX_DP<67>")
	)
	(segment
		(start 428.27956 -307.414168)
		(end 428.27956 -307.644292)
		(width 0.1143)
		(layer "In5.Cu")
		(net "P5E_PEX3_STN4_RX_DP<67>")
	)
	(segment
		(start 431.547778 -366.97666)
		(end 431.132234 -367.246916)
		(width 0.1651)
		(layer "In5.Cu")
		(net "P5E_PEX3_STN4_RX_DP<67>")
	)
	(segment
		(start 432.050952 -307.915818)
		(end 433.097432 -307.915818)
		(width 0.1651)
		(layer "In5.Cu")
		(net "P5E_PEX3_STN4_RX_DP<67>")
	)
	(segment
		(start 429.16602 -369.601242)
		(end 429.16602 -378.470414)
		(width 0.1651)
		(layer "In5.Cu")
		(net "P5E_PEX3_STN4_RX_DP<67>")
	)
	(segment
		(start 443.014608 -317.430912)
		(end 443.176152 -317.430912)
		(width 0.1651)
		(layer "In5.Cu")
		(net "P5E_PEX3_STN4_RX_DP<67>")
	)
	(segment
		(start 428.505366 -307.870098)
		(end 431.976784 -307.870098)
		(width 0.1143)
		(layer "In5.Cu")
		(net "P5E_PEX3_STN4_RX_DP<67>")
	)
	(segment
		(start 437.804306 -362.944918)
		(end 437.644286 -362.922312)
		(width 0.1651)
		(layer "In5.Cu")
		(net "P5E_PEX3_STN4_RX_DP<67>")
	)
	(segment
		(start 431.976784 -307.870098)
		(end 432.022504 -307.915818)
		(width 0.1143)
		(layer "In5.Cu")
		(net "P5E_PEX3_STN4_RX_DP<67>")
	)
	(segment
		(start 438.200292 -362.647738)
		(end 438.200038 -362.647738)
		(width 0.1651)
		(layer "In5.Cu")
		(net "P5E_PEX3_STN4_RX_DP<67>")
	)
	(segment
		(start 428.463202 -378.8029)
		(end 428.289974 -378.629672)
		(width 0.1651)
		(layer "In5.Cu")
		(net "P5E_PEX3_STN4_RX_DP<67>")
	)
	(segment
		(start 434.94706 -309.29072)
		(end 435.38902 -310.35752)
		(width 0.1651)
		(layer "In5.Cu")
		(net "P5E_PEX3_STN4_RX_DP<67>")
	)
	(segment
		(start 427.89983 -307.299868)
		(end 428.16526 -307.299868)
		(width 0.1143)
		(layer "In5.Cu")
		(net "P5E_PEX3_STN4_RX_DP<67>")
	)
	(segment
		(start 444.237618 -318.492378)
		(end 444.237618 -321.892168)
		(width 0.1651)
		(layer "In5.Cu")
		(net "P5E_PEX3_STN4_RX_DP<67>")
	)
	(segment
		(start 444.237618 -321.892168)
		(end 443.242446 -358.120696)
		(width 0.1651)
		(layer "In5.Cu")
		(net "P5E_PEX3_STN4_RX_DP<67>")
	)
	(segment
		(start 432.120802 -366.740186)
		(end 431.705766 -367.010188)
		(width 0.1651)
		(layer "In5.Cu")
		(net "P5E_PEX3_STN4_RX_DP<67>")
	)
	(segment
		(start 431.09896 -367.405158)
		(end 431.098706 -367.405158)
		(width 0.1651)
		(layer "In5.Cu")
		(net "P5E_PEX3_STN4_RX_DP<67>")
	)
	(segment
		(start 439.594498 -361.457748)
		(end 439.198004 -361.755436)
		(width 0.1651)
		(layer "In5.Cu")
		(net "P5E_PEX3_STN4_RX_DP<67>")
	)
	(segment
		(start 438.222898 -362.487464)
		(end 438.200292 -362.647738)
		(width 0.1651)
		(layer "In5.Cu")
		(net "P5E_PEX3_STN4_RX_DP<67>")
	)
	(segment
		(start 435.38902 -310.35752)
		(end 439.006234 -313.974734)
		(width 0.1651)
		(layer "In5.Cu")
		(net "P5E_PEX3_STN4_RX_DP<67>")
	)
	(segment
		(start 428.27956 -307.644292)
		(end 428.505366 -307.870098)
		(width 0.1143)
		(layer "In5.Cu")
		(net "P5E_PEX3_STN4_RX_DP<67>")
	)
	(segment
		(start 429.16602 -378.470414)
		(end 428.833534 -378.8029)
		(width 0.1651)
		(layer "In5.Cu")
		(net "P5E_PEX3_STN4_RX_DP<67>")
	)
	(segment
		(start 429.630586 -368.479578)
		(end 429.16602 -369.601242)
		(width 0.1651)
		(layer "In5.Cu")
		(net "P5E_PEX3_STN4_RX_DP<67>")
	)
	(segment
		(start 433.750212 -365.680244)
		(end 433.59197 -365.646716)
		(width 0.1651)
		(layer "In5.Cu")
		(net "P5E_PEX3_STN4_RX_DP<67>")
	)
	(segment
		(start 438.619392 -362.19003)
		(end 438.222898 -362.487464)
		(width 0.1651)
		(layer "In5.Cu")
		(net "P5E_PEX3_STN4_RX_DP<67>")
	)
	(segment
		(start 438.200038 -362.647738)
		(end 437.804306 -362.944918)
		(width 0.1651)
		(layer "In5.Cu")
		(net "P5E_PEX3_STN4_RX_DP<67>")
	)
	(segment
		(start 439.175398 -361.915456)
		(end 439.175144 -361.915456)
		(width 0.1651)
		(layer "In5.Cu")
		(net "P5E_PEX3_STN4_RX_DP<67>")
	)
	(segment
		(start 428.289974 -378.629672)
		(end 428.289974 -378.290074)
		(width 0.1651)
		(layer "In5.Cu")
		(net "P5E_PEX3_STN4_RX_DP<67>")
	)
	(segment
		(start 442.617098 -359.330752)
		(end 439.754518 -361.480354)
		(width 0.1651)
		(layer "In5.Cu")
		(net "P5E_PEX3_STN4_RX_DP<67>")
	)
	(segment
		(start 433.142898 -366.075214)
		(end 432.727862 -366.345216)
		(width 0.1651)
		(layer "In5.Cu")
		(net "P5E_PEX3_STN4_RX_DP<67>")
	)
	(segment
		(start 432.727862 -366.345216)
		(end 432.569874 -366.311688)
		(width 0.1651)
		(layer "In5.Cu")
		(net "P5E_PEX3_STN4_RX_DP<67>")
	)
	(segment
		(start 24.62022 -229.94493)
		(end 23.212298 -229.94493)
		(width 0.13208)
		(layer "F.Cu")
		(net "SPI_PEX0_SDIO1_MUX_R")
	)
	(via
		(at 23.212298 -229.94493)
		(size 0.508)
		(drill 0.254)
		(layers "F.Cu" "B.Cu")
		(net "SPI_PEX0_SDIO1_MUX_R")
	)
	(segment
		(start 23.212298 -228.74605)
		(end 23.212298 -229.94493)
		(width 0.13208)
		(layer "B.Cu")
		(net "SPI_PEX0_SDIO1_MUX_R")
	)
	(segment
		(start 434.141372 -350.365314)
		(end 434.46192 -350.685862)
		(width 0.13462)
		(layer "F.Cu")
		(net "P5E_PEX3_STN4_TX_C_DP<67>")
	)
	(segment
		(start 434.46192 -350.685862)
		(end 434.46192 -351.31629)
		(width 0.13462)
		(layer "F.Cu")
		(net "P5E_PEX3_STN4_TX_C_DP<67>")
	)
	(segment
		(start 434.46192 -351.31629)
		(end 434.166772 -351.611438)
		(width 0.13462)
		(layer "F.Cu")
		(net "P5E_PEX3_STN4_TX_C_DP<67>")
	)
	(segment
		(start 429.560482 -367.680748)
		(end 429.560228 -367.680748)
		(width 0.1651)
		(layer "In7.Cu")
		(net "P5E_PEX3_STN4_TX_C_DP<67>")
	)
	(segment
		(start 432.730148 -359.189782)
		(end 432.903122 -358.725978)
		(width 0.1651)
		(layer "In7.Cu")
		(net "P5E_PEX3_STN4_TX_C_DP<67>")
	)
	(segment
		(start 431.155348 -363.116876)
		(end 431.328576 -362.652564)
		(width 0.1651)
		(layer "In7.Cu")
		(net "P5E_PEX3_STN4_TX_C_DP<67>")
	)
	(segment
		(start 430.092866 -365.92764)
		(end 430.266094 -365.463328)
		(width 0.1651)
		(layer "In7.Cu")
		(net "P5E_PEX3_STN4_TX_C_DP<67>")
	)
	(segment
		(start 431.45964 -362.592874)
		(end 431.632614 -362.12907)
		(width 0.1651)
		(layer "In7.Cu")
		(net "P5E_PEX3_STN4_TX_C_DP<67>")
	)
	(segment
		(start 432.156362 -360.39933)
		(end 432.303682 -360.33202)
		(width 0.1651)
		(layer "In7.Cu")
		(net "P5E_PEX3_STN4_TX_C_DP<67>")
	)
	(segment
		(start 429.733456 -367.216944)
		(end 429.6664 -367.069878)
		(width 0.1651)
		(layer "In7.Cu")
		(net "P5E_PEX3_STN4_TX_C_DP<67>")
	)
	(segment
		(start 431.042064 -363.71149)
		(end 431.215038 -363.247686)
		(width 0.1651)
		(layer "In7.Cu")
		(net "P5E_PEX3_STN4_TX_C_DP<67>")
	)
	(segment
		(start 431.877216 -361.474258)
		(end 432.05019 -361.010454)
		(width 0.1651)
		(layer "In7.Cu")
		(net "P5E_PEX3_STN4_TX_C_DP<67>")
	)
	(segment
		(start 429.839628 -366.605566)
		(end 429.986948 -366.53851)
		(width 0.1651)
		(layer "In7.Cu")
		(net "P5E_PEX3_STN4_TX_C_DP<67>")
	)
	(segment
		(start 430.412906 -365.396272)
		(end 430.797462 -364.366302)
		(width 0.1651)
		(layer "In7.Cu")
		(net "P5E_PEX3_STN4_TX_C_DP<67>")
	)
	(segment
		(start 429.134016 -368.822986)
		(end 429.30699 -368.359182)
		(width 0.1651)
		(layer "In7.Cu")
		(net "P5E_PEX3_STN4_TX_C_DP<67>")
	)
	(segment
		(start 431.983134 -360.863642)
		(end 432.156362 -360.39933)
		(width 0.1651)
		(layer "In7.Cu")
		(net "P5E_PEX3_STN4_TX_C_DP<67>")
	)
	(segment
		(start 428.289974 -370.489988)
		(end 428.289974 -370.872258)
		(width 0.1651)
		(layer "In7.Cu")
		(net "P5E_PEX3_STN4_TX_C_DP<67>")
	)
	(segment
		(start 429.560228 -367.680748)
		(end 429.733202 -367.217706)
		(width 0.1651)
		(layer "In7.Cu")
		(net "P5E_PEX3_STN4_TX_C_DP<67>")
	)
	(segment
		(start 431.632614 -362.12907)
		(end 431.572924 -361.99826)
		(width 0.1651)
		(layer "In7.Cu")
		(net "P5E_PEX3_STN4_TX_C_DP<67>")
	)
	(segment
		(start 430.797462 -364.366302)
		(end 430.797716 -364.366302)
		(width 0.1651)
		(layer "In7.Cu")
		(net "P5E_PEX3_STN4_TX_C_DP<67>")
	)
	(segment
		(start 430.159922 -366.074706)
		(end 430.092866 -365.92764)
		(width 0.1651)
		(layer "In7.Cu")
		(net "P5E_PEX3_STN4_TX_C_DP<67>")
	)
	(segment
		(start 431.746152 -361.533948)
		(end 431.877216 -361.474258)
		(width 0.1651)
		(layer "In7.Cu")
		(net "P5E_PEX3_STN4_TX_C_DP<67>")
	)
	(segment
		(start 430.159668 -366.074706)
		(end 430.159922 -366.074706)
		(width 0.1651)
		(layer "In7.Cu")
		(net "P5E_PEX3_STN4_TX_C_DP<67>")
	)
	(segment
		(start 429.30699 -368.359182)
		(end 429.239934 -368.212116)
		(width 0.1651)
		(layer "In7.Cu")
		(net "P5E_PEX3_STN4_TX_C_DP<67>")
	)
	(segment
		(start 429.413162 -367.747804)
		(end 429.560482 -367.680748)
		(width 0.1651)
		(layer "In7.Cu")
		(net "P5E_PEX3_STN4_TX_C_DP<67>")
	)
	(segment
		(start 428.289974 -370.872258)
		(end 428.416974 -370.999258)
		(width 0.1651)
		(layer "In7.Cu")
		(net "P5E_PEX3_STN4_TX_C_DP<67>")
	)
	(segment
		(start 434.457602 -352.356166)
		(end 434.457602 -351.902268)
		(width 0.1651)
		(layer "In7.Cu")
		(net "P5E_PEX3_STN4_TX_C_DP<67>")
	)
	(segment
		(start 430.797716 -364.366302)
		(end 430.738026 -364.235492)
		(width 0.1651)
		(layer "In7.Cu")
		(net "P5E_PEX3_STN4_TX_C_DP<67>")
	)
	(segment
		(start 429.986694 -366.53851)
		(end 430.159668 -366.074706)
		(width 0.1651)
		(layer "In7.Cu")
		(net "P5E_PEX3_STN4_TX_C_DP<67>")
	)
	(segment
		(start 430.413414 -365.396272)
		(end 430.412906 -365.396272)
		(width 0.1651)
		(layer "In7.Cu")
		(net "P5E_PEX3_STN4_TX_C_DP<67>")
	)
	(segment
		(start 431.328576 -362.652564)
		(end 431.45964 -362.592874)
		(width 0.1651)
		(layer "In7.Cu")
		(net "P5E_PEX3_STN4_TX_C_DP<67>")
	)
	(segment
		(start 432.903122 -353.910646)
		(end 434.457602 -352.356166)
		(width 0.1651)
		(layer "In7.Cu")
		(net "P5E_PEX3_STN4_TX_C_DP<67>")
	)
	(segment
		(start 432.476656 -359.868216)
		(end 432.4096 -359.721404)
		(width 0.1651)
		(layer "In7.Cu")
		(net "P5E_PEX3_STN4_TX_C_DP<67>")
	)
	(segment
		(start 430.266094 -365.463328)
		(end 430.413414 -365.396272)
		(width 0.1651)
		(layer "In7.Cu")
		(net "P5E_PEX3_STN4_TX_C_DP<67>")
	)
	(segment
		(start 434.457602 -351.902268)
		(end 434.166772 -351.611438)
		(width 0.1651)
		(layer "In7.Cu")
		(net "P5E_PEX3_STN4_TX_C_DP<67>")
	)
	(segment
		(start 429.239934 -368.212116)
		(end 429.413162 -367.747804)
		(width 0.1651)
		(layer "In7.Cu")
		(net "P5E_PEX3_STN4_TX_C_DP<67>")
	)
	(segment
		(start 430.911 -363.77118)
		(end 431.042064 -363.71149)
		(width 0.1651)
		(layer "In7.Cu")
		(net "P5E_PEX3_STN4_TX_C_DP<67>")
	)
	(segment
		(start 432.582828 -359.257092)
		(end 432.730148 -359.189782)
		(width 0.1651)
		(layer "In7.Cu")
		(net "P5E_PEX3_STN4_TX_C_DP<67>")
	)
	(segment
		(start 429.6664 -367.069878)
		(end 429.839628 -366.605566)
		(width 0.1651)
		(layer "In7.Cu")
		(net "P5E_PEX3_STN4_TX_C_DP<67>")
	)
	(segment
		(start 431.215038 -363.247686)
		(end 431.155348 -363.116876)
		(width 0.1651)
		(layer "In7.Cu")
		(net "P5E_PEX3_STN4_TX_C_DP<67>")
	)
	(segment
		(start 432.903122 -358.725978)
		(end 432.903122 -353.910646)
		(width 0.1651)
		(layer "In7.Cu")
		(net "P5E_PEX3_STN4_TX_C_DP<67>")
	)
	(segment
		(start 428.84725 -370.999258)
		(end 429.134016 -370.712492)
		(width 0.1651)
		(layer "In7.Cu")
		(net "P5E_PEX3_STN4_TX_C_DP<67>")
	)
	(segment
		(start 432.4096 -359.721404)
		(end 432.582828 -359.257092)
		(width 0.1651)
		(layer "In7.Cu")
		(net "P5E_PEX3_STN4_TX_C_DP<67>")
	)
	(segment
		(start 429.134016 -370.712492)
		(end 429.134016 -368.822986)
		(width 0.1651)
		(layer "In7.Cu")
		(net "P5E_PEX3_STN4_TX_C_DP<67>")
	)
	(segment
		(start 432.303682 -360.33202)
		(end 432.476656 -359.868216)
		(width 0.1651)
		(layer "In7.Cu")
		(net "P5E_PEX3_STN4_TX_C_DP<67>")
	)
	(segment
		(start 432.05019 -361.010454)
		(end 431.983134 -360.863642)
		(width 0.1651)
		(layer "In7.Cu")
		(net "P5E_PEX3_STN4_TX_C_DP<67>")
	)
	(segment
		(start 430.738026 -364.235492)
		(end 430.911 -363.77118)
		(width 0.1651)
		(layer "In7.Cu")
		(net "P5E_PEX3_STN4_TX_C_DP<67>")
	)
	(segment
		(start 428.416974 -370.999258)
		(end 428.84725 -370.999258)
		(width 0.1651)
		(layer "In7.Cu")
		(net "P5E_PEX3_STN4_TX_C_DP<67>")
	)
	(segment
		(start 429.733202 -367.217706)
		(end 429.733456 -367.216944)
		(width 0.1651)
		(layer "In7.Cu")
		(net "P5E_PEX3_STN4_TX_C_DP<67>")
	)
	(segment
		(start 429.986948 -366.53851)
		(end 429.986694 -366.53851)
		(width 0.1651)
		(layer "In7.Cu")
		(net "P5E_PEX3_STN4_TX_C_DP<67>")
	)
	(segment
		(start 431.572924 -361.99826)
		(end 431.746152 -361.533948)
		(width 0.1651)
		(layer "In7.Cu")
		(net "P5E_PEX3_STN4_TX_C_DP<67>")
	)
	(segment
		(start 15.869666 -222.32493)
		(end 15.020036 -222.32493)
		(width 0.13208)
		(layer "F.Cu")
		(net "SPI_PEX0_SDIO0_MUX_R")
	)
	(segment
		(start 16.23822 -222.172276)
		(end 15.869666 -222.32493)
		(width 0.13208)
		(layer "F.Cu")
		(net "SPI_PEX0_SDIO0_MUX_R")
	)
	(via
		(at 16.23822 -222.172276)
		(size 0.508)
		(drill 0.254)
		(layers "F.Cu" "B.Cu")
		(net "SPI_PEX0_SDIO0_MUX_R")
	)
	(segment
		(start 19.27606 -221.92361)
		(end 18.532348 -221.179898)
		(width 0.13208)
		(layer "B.Cu")
		(net "SPI_PEX0_SDIO0_MUX_R")
	)
	(segment
		(start 19.27606 -222.214186)
		(end 19.27606 -221.92361)
		(width 0.13208)
		(layer "B.Cu")
		(net "SPI_PEX0_SDIO0_MUX_R")
	)
	(segment
		(start 17.230598 -221.179898)
		(end 16.23822 -222.172276)
		(width 0.13208)
		(layer "B.Cu")
		(net "SPI_PEX0_SDIO0_MUX_R")
	)
	(segment
		(start 18.532348 -221.179898)
		(end 17.230598 -221.179898)
		(width 0.13208)
		(layer "B.Cu")
		(net "SPI_PEX0_SDIO0_MUX_R")
	)
	(segment
		(start 421.689784 -380.358142)
		(end 421.689784 -380.69012)
		(width 0.1651)
		(layer "In5.Cu")
		(net "P5E_PEX3_STN4_RX_DN<70>")
	)
	(segment
		(start 430.370234 -310.415178)
		(end 430.484534 -310.529478)
		(width 0.1143)
		(layer "In5.Cu")
		(net "P5E_PEX3_STN4_RX_DN<70>")
	)
	(segment
		(start 432.586638 -310.739028)
		(end 432.74361 -311.117996)
		(width 0.1651)
		(layer "In5.Cu")
		(net "P5E_PEX3_STN4_RX_DN<70>")
	)
	(segment
		(start 431.980848 -310.483758)
		(end 432.331368 -310.483758)
		(width 0.1651)
		(layer "In5.Cu")
		(net "P5E_PEX3_STN4_RX_DN<70>")
	)
	(segment
		(start 436.294022 -342.433402)
		(end 436.294022 -358.468422)
		(width 0.1651)
		(layer "In5.Cu")
		(net "P5E_PEX3_STN4_RX_DN<70>")
	)
	(segment
		(start 430.484534 -310.529478)
		(end 431.90668 -310.529478)
		(width 0.1143)
		(layer "In5.Cu")
		(net "P5E_PEX3_STN4_RX_DN<70>")
	)
	(segment
		(start 432.74361 -311.117996)
		(end 432.74361 -317.000128)
		(width 0.1651)
		(layer "In5.Cu")
		(net "P5E_PEX3_STN4_RX_DN<70>")
	)
	(segment
		(start 422.350184 -380.184914)
		(end 421.863012 -380.184914)
		(width 0.1651)
		(layer "In5.Cu")
		(net "P5E_PEX3_STN4_RX_DN<70>")
	)
	(segment
		(start 422.84777 -369.381786)
		(end 422.84777 -379.687328)
		(width 0.1651)
		(layer "In5.Cu")
		(net "P5E_PEX3_STN4_RX_DN<70>")
	)
	(segment
		(start 431.96383 -322.77177)
		(end 436.294022 -342.433402)
		(width 0.1651)
		(layer "In5.Cu")
		(net "P5E_PEX3_STN4_RX_DN<70>")
	)
	(segment
		(start 432.74361 -317.000128)
		(end 431.96383 -318.88303)
		(width 0.1651)
		(layer "In5.Cu")
		(net "P5E_PEX3_STN4_RX_DN<70>")
	)
	(segment
		(start 430.370234 -310.264048)
		(end 430.370234 -310.415178)
		(width 0.1143)
		(layer "In5.Cu")
		(net "P5E_PEX3_STN4_RX_DN<70>")
	)
	(segment
		(start 422.84777 -379.687328)
		(end 422.350184 -380.184914)
		(width 0.1651)
		(layer "In5.Cu")
		(net "P5E_PEX3_STN4_RX_DN<70>")
	)
	(segment
		(start 432.331368 -310.483758)
		(end 432.586638 -310.739028)
		(width 0.1651)
		(layer "In5.Cu")
		(net "P5E_PEX3_STN4_RX_DN<70>")
	)
	(segment
		(start 431.90668 -310.529478)
		(end 431.9524 -310.483758)
		(width 0.1143)
		(layer "In5.Cu")
		(net "P5E_PEX3_STN4_RX_DN<70>")
	)
	(segment
		(start 430.484534 -310.149748)
		(end 430.370234 -310.264048)
		(width 0.1143)
		(layer "In5.Cu")
		(net "P5E_PEX3_STN4_RX_DN<70>")
	)
	(segment
		(start 431.96383 -318.88303)
		(end 431.96383 -322.77177)
		(width 0.1651)
		(layer "In5.Cu")
		(net "P5E_PEX3_STN4_RX_DN<70>")
	)
	(segment
		(start 431.9524 -310.483758)
		(end 431.980848 -310.483758)
		(width 0.1143)
		(layer "In5.Cu")
		(net "P5E_PEX3_STN4_RX_DN<70>")
	)
	(segment
		(start 430.749964 -310.149748)
		(end 430.484534 -310.149748)
		(width 0.1143)
		(layer "In5.Cu")
		(net "P5E_PEX3_STN4_RX_DN<70>")
	)
	(segment
		(start 423.478452 -368.160554)
		(end 422.84777 -369.381786)
		(width 0.1651)
		(layer "In5.Cu")
		(net "P5E_PEX3_STN4_RX_DN<70>")
	)
	(segment
		(start 436.294022 -358.468422)
		(end 436.014622 -359.018078)
		(width 0.1651)
		(layer "In5.Cu")
		(net "P5E_PEX3_STN4_RX_DN<70>")
	)
	(segment
		(start 421.863012 -380.184914)
		(end 421.689784 -380.358142)
		(width 0.1651)
		(layer "In5.Cu")
		(net "P5E_PEX3_STN4_RX_DN<70>")
	)
	(segment
		(start 436.014622 -359.018078)
		(end 423.478452 -368.160554)
		(width 0.1651)
		(layer "In5.Cu")
		(net "P5E_PEX3_STN4_RX_DN<70>")
	)
	(segment
		(start 26.35758 -220.524324)
		(end 25.826974 -221.05493)
		(width 0.13208)
		(layer "F.Cu")
		(net "SPI_PEX0_SDIO3_R1")
	)
	(segment
		(start 25.826974 -221.05493)
		(end 24.62022 -221.05493)
		(width 0.13208)
		(layer "F.Cu")
		(net "SPI_PEX0_SDIO3_R1")
	)
	(via
		(at 26.35758 -220.524324)
		(size 0.508)
		(drill 0.254)
		(layers "F.Cu" "B.Cu")
		(net "SPI_PEX0_SDIO3_R1")
	)
	(segment
		(start 24.120348 -220.532706)
		(end 25.151588 -220.532706)
		(width 0.13208)
		(layer "B.Cu")
		(net "SPI_PEX0_SDIO3_R1")
	)
	(segment
		(start 25.151588 -220.532706)
		(end 25.15997 -220.524324)
		(width 0.13208)
		(layer "B.Cu")
		(net "SPI_PEX0_SDIO3_R1")
	)
	(segment
		(start 25.15997 -220.524324)
		(end 26.35758 -220.524324)
		(width 0.13208)
		(layer "B.Cu")
		(net "SPI_PEX0_SDIO3_R1")
	)
	(segment
		(start 427.053502 -395.284452)
		(end 425.911772 -394.036804)
		(width 0.1651)
		(layer "In5.Cu")
		(net "P5E_PEX3_STN4_RX_DN<76>")
	)
	(segment
		(start 417.640262 -341.935054)
		(end 424.71594 -322.571872)
		(width 0.1651)
		(layer "In5.Cu")
		(net "P5E_PEX3_STN4_RX_DN<76>")
	)
	(segment
		(start 424.93565 -318.320166)
		(end 425.04995 -318.434466)
		(width 0.1143)
		(layer "In5.Cu")
		(net "P5E_PEX3_STN4_RX_DN<76>")
	)
	(segment
		(start 427.247812 -405.687276)
		(end 427.247812 -396.03934)
		(width 0.1651)
		(layer "In5.Cu")
		(net "P5E_PEX3_STN4_RX_DN<76>")
	)
	(segment
		(start 425.04995 -318.434466)
		(end 425.04995 -318.699896)
		(width 0.1143)
		(layer "In5.Cu")
		(net "P5E_PEX3_STN4_RX_DN<76>")
	)
	(segment
		(start 426.263054 -406.184862)
		(end 426.750226 -406.184862)
		(width 0.1651)
		(layer "In5.Cu")
		(net "P5E_PEX3_STN4_RX_DN<76>")
	)
	(segment
		(start 427.247812 -396.03934)
		(end 427.053502 -395.284452)
		(width 0.1651)
		(layer "In5.Cu")
		(net "P5E_PEX3_STN4_RX_DN<76>")
	)
	(segment
		(start 425.911772 -394.036804)
		(end 417.100258 -389.068818)
		(width 0.1651)
		(layer "In5.Cu")
		(net "P5E_PEX3_STN4_RX_DN<76>")
	)
	(segment
		(start 424.71594 -319.909952)
		(end 424.67022 -319.864232)
		(width 0.1143)
		(layer "In5.Cu")
		(net "P5E_PEX3_STN4_RX_DN<76>")
	)
	(segment
		(start 415.440368 -387.499098)
		(end 414.279588 -384.612134)
		(width 0.1651)
		(layer "In5.Cu")
		(net "P5E_PEX3_STN4_RX_DN<76>")
	)
	(segment
		(start 426.089826 -406.690068)
		(end 426.089826 -406.35809)
		(width 0.1651)
		(layer "In5.Cu")
		(net "P5E_PEX3_STN4_RX_DN<76>")
	)
	(segment
		(start 426.750226 -406.184862)
		(end 427.247812 -405.687276)
		(width 0.1651)
		(layer "In5.Cu")
		(net "P5E_PEX3_STN4_RX_DN<76>")
	)
	(segment
		(start 417.640262 -358.874314)
		(end 417.640262 -341.935054)
		(width 0.1651)
		(layer "In5.Cu")
		(net "P5E_PEX3_STN4_RX_DN<76>")
	)
	(segment
		(start 424.67022 -318.434466)
		(end 424.78452 -318.320166)
		(width 0.1143)
		(layer "In5.Cu")
		(net "P5E_PEX3_STN4_RX_DN<76>")
	)
	(segment
		(start 414.279588 -384.612134)
		(end 414.322768 -368.81181)
		(width 0.1651)
		(layer "In5.Cu")
		(net "P5E_PEX3_STN4_RX_DN<76>")
	)
	(segment
		(start 424.78452 -318.320166)
		(end 424.93565 -318.320166)
		(width 0.1143)
		(layer "In5.Cu")
		(net "P5E_PEX3_STN4_RX_DN<76>")
	)
	(segment
		(start 424.67022 -319.864232)
		(end 424.67022 -318.434466)
		(width 0.1143)
		(layer "In5.Cu")
		(net "P5E_PEX3_STN4_RX_DN<76>")
	)
	(segment
		(start 414.322768 -368.81181)
		(end 417.640262 -358.874314)
		(width 0.1651)
		(layer "In5.Cu")
		(net "P5E_PEX3_STN4_RX_DN<76>")
	)
	(segment
		(start 424.71594 -319.9384)
		(end 424.71594 -319.909952)
		(width 0.1143)
		(layer "In5.Cu")
		(net "P5E_PEX3_STN4_RX_DN<76>")
	)
	(segment
		(start 424.71594 -322.571872)
		(end 424.71594 -319.9384)
		(width 0.1651)
		(layer "In5.Cu")
		(net "P5E_PEX3_STN4_RX_DN<76>")
	)
	(segment
		(start 426.089826 -406.35809)
		(end 426.263054 -406.184862)
		(width 0.1651)
		(layer "In5.Cu")
		(net "P5E_PEX3_STN4_RX_DN<76>")
	)
	(segment
		(start 417.100258 -389.068818)
		(end 415.440368 -387.499098)
		(width 0.1651)
		(layer "In5.Cu")
		(net "P5E_PEX3_STN4_RX_DN<76>")
	)
	(segment
		(start 42.549826 -293.04996)
		(end 42.074846 -292.57498)
		(width 0.13208)
		(layer "F.Cu")
		(net "SPI_PEX0_CLK")
	)
	(via
		(at 42.074846 -292.57498)
		(size 0.508)
		(drill 0.254)
		(layers "F.Cu" "B.Cu")
		(net "SPI_PEX0_CLK")
	)
	(segment
		(start 41.244266 -292.1)
		(end 40.8305 -292.1)
		(width 0.13208)
		(layer "B.Cu")
		(net "SPI_PEX0_CLK")
	)
	(segment
		(start 40.8305 -292.1)
		(end 40.45712 -291.72662)
		(width 0.13208)
		(layer "B.Cu")
		(net "SPI_PEX0_CLK")
	)
	(segment
		(start 41.719246 -292.57498)
		(end 41.244266 -292.1)
		(width 0.13208)
		(layer "B.Cu")
		(net "SPI_PEX0_CLK")
	)
	(segment
		(start 42.074846 -292.57498)
		(end 41.719246 -292.57498)
		(width 0.13208)
		(layer "B.Cu")
		(net "SPI_PEX0_CLK")
	)
	(segment
		(start 427.5201 -316.534292)
		(end 427.6344 -316.419992)
		(width 0.1143)
		(layer "In5.Cu")
		(net "P5E_PEX3_STN4_RX_DN<73>")
	)
	(segment
		(start 427.5201 -319.864232)
		(end 427.5201 -316.534292)
		(width 0.1143)
		(layer "In5.Cu")
		(net "P5E_PEX3_STN4_RX_DN<73>")
	)
	(segment
		(start 417.237926 -370.18087)
		(end 417.479988 -368.960146)
		(width 0.1651)
		(layer "In5.Cu")
		(net "P5E_PEX3_STN4_RX_DN<73>")
	)
	(segment
		(start 427.78553 -316.419992)
		(end 427.89983 -316.534292)
		(width 0.1143)
		(layer "In5.Cu")
		(net "P5E_PEX3_STN4_RX_DN<73>")
	)
	(segment
		(start 433.350162 -405.084788)
		(end 433.847748 -404.587202)
		(width 0.1651)
		(layer "In5.Cu")
		(net "P5E_PEX3_STN4_RX_DN<73>")
	)
	(segment
		(start 427.56582 -331.690726)
		(end 427.56582 -319.9384)
		(width 0.1651)
		(layer "In5.Cu")
		(net "P5E_PEX3_STN4_RX_DN<73>")
	)
	(segment
		(start 427.89983 -316.534292)
		(end 427.89983 -316.799722)
		(width 0.1143)
		(layer "In5.Cu")
		(net "P5E_PEX3_STN4_RX_DN<73>")
	)
	(segment
		(start 433.173886 -394.230606)
		(end 418.6555 -386.495036)
		(width 0.1651)
		(layer "In5.Cu")
		(net "P5E_PEX3_STN4_RX_DN<73>")
	)
	(segment
		(start 433.847748 -404.587202)
		(end 433.847748 -395.21892)
		(width 0.1651)
		(layer "In5.Cu")
		(net "P5E_PEX3_STN4_RX_DN<73>")
	)
	(segment
		(start 433.847748 -395.21892)
		(end 433.60594 -394.61948)
		(width 0.1651)
		(layer "In5.Cu")
		(net "P5E_PEX3_STN4_RX_DN<73>")
	)
	(segment
		(start 427.6344 -316.419992)
		(end 427.78553 -316.419992)
		(width 0.1143)
		(layer "In5.Cu")
		(net "P5E_PEX3_STN4_RX_DN<73>")
	)
	(segment
		(start 432.689762 -405.258016)
		(end 432.86299 -405.084788)
		(width 0.1651)
		(layer "In5.Cu")
		(net "P5E_PEX3_STN4_RX_DN<73>")
	)
	(segment
		(start 427.56582 -319.909952)
		(end 427.5201 -319.864232)
		(width 0.1143)
		(layer "In5.Cu")
		(net "P5E_PEX3_STN4_RX_DN<73>")
	)
	(segment
		(start 427.56582 -319.9384)
		(end 427.56582 -319.909952)
		(width 0.1143)
		(layer "In5.Cu")
		(net "P5E_PEX3_STN4_RX_DN<73>")
	)
	(segment
		(start 426.967142 -342.217502)
		(end 427.56582 -331.690726)
		(width 0.1651)
		(layer "In5.Cu")
		(net "P5E_PEX3_STN4_RX_DN<73>")
	)
	(segment
		(start 426.967142 -358.515158)
		(end 426.967142 -342.217502)
		(width 0.1651)
		(layer "In5.Cu")
		(net "P5E_PEX3_STN4_RX_DN<73>")
	)
	(segment
		(start 432.86299 -405.084788)
		(end 433.350162 -405.084788)
		(width 0.1651)
		(layer "In5.Cu")
		(net "P5E_PEX3_STN4_RX_DN<73>")
	)
	(segment
		(start 417.20008 -384.042412)
		(end 417.237926 -370.18087)
		(width 0.1651)
		(layer "In5.Cu")
		(net "P5E_PEX3_STN4_RX_DN<73>")
	)
	(segment
		(start 417.920424 -385.774438)
		(end 417.20008 -384.042412)
		(width 0.1651)
		(layer "In5.Cu")
		(net "P5E_PEX3_STN4_RX_DN<73>")
	)
	(segment
		(start 432.689762 -405.589994)
		(end 432.689762 -405.258016)
		(width 0.1651)
		(layer "In5.Cu")
		(net "P5E_PEX3_STN4_RX_DN<73>")
	)
	(segment
		(start 433.60594 -394.61948)
		(end 433.173886 -394.230606)
		(width 0.1651)
		(layer "In5.Cu")
		(net "P5E_PEX3_STN4_RX_DN<73>")
	)
	(segment
		(start 417.754816 -368.422682)
		(end 426.967142 -358.515158)
		(width 0.1651)
		(layer "In5.Cu")
		(net "P5E_PEX3_STN4_RX_DN<73>")
	)
	(segment
		(start 418.6555 -386.495036)
		(end 417.920424 -385.774438)
		(width 0.1651)
		(layer "In5.Cu")
		(net "P5E_PEX3_STN4_RX_DN<73>")
	)
	(segment
		(start 417.479988 -368.960146)
		(end 417.754816 -368.422682)
		(width 0.1651)
		(layer "In5.Cu")
		(net "P5E_PEX3_STN4_RX_DN<73>")
	)
	(segment
		(start 42.549826 -294.94988)
		(end 42.074846 -294.4749)
		(width 0.13208)
		(layer "F.Cu")
		(net "SPI_PEX0_SDIO0")
	)
	(via
		(at 42.074846 -294.4749)
		(size 0.508)
		(drill 0.254)
		(layers "F.Cu" "B.Cu")
		(net "SPI_PEX0_SDIO0")
	)
	(segment
		(start 42.074846 -294.4749)
		(end 42.074846 -295.106852)
		(width 0.13208)
		(layer "B.Cu")
		(net "SPI_PEX0_SDIO0")
	)
	(segment
		(start 42.074846 -295.106852)
		(end 41.383458 -295.79824)
		(width 0.13208)
		(layer "B.Cu")
		(net "SPI_PEX0_SDIO0")
	)
	(segment
		(start 41.383458 -295.79824)
		(end 40.573706 -295.79824)
		(width 0.13208)
		(layer "B.Cu")
		(net "SPI_PEX0_SDIO0")
	)
	(segment
		(start 440.67984 -350.685862)
		(end 440.67984 -351.31629)
		(width 0.13462)
		(layer "F.Cu")
		(net "P5E_PEX3_STN4_TX_C_DP<64>")
	)
	(segment
		(start 440.67984 -351.31629)
		(end 440.384692 -351.611438)
		(width 0.13462)
		(layer "F.Cu")
		(net "P5E_PEX3_STN4_TX_C_DP<64>")
	)
	(segment
		(start 440.359292 -350.365314)
		(end 440.67984 -350.685862)
		(width 0.13462)
		(layer "F.Cu")
		(net "P5E_PEX3_STN4_TX_C_DP<64>")
	)
	(segment
		(start 436.902098 -365.389922)
		(end 436.757064 -365.461804)
		(width 0.1651)
		(layer "In7.Cu")
		(net "P5E_PEX3_STN4_TX_C_DP<64>")
	)
	(segment
		(start 437.901588 -362.42371)
		(end 437.7436 -362.892848)
		(width 0.1651)
		(layer "In7.Cu")
		(net "P5E_PEX3_STN4_TX_C_DP<64>")
	)
	(segment
		(start 438.680352 -360.112818)
		(end 438.522364 -360.581956)
		(width 0.1651)
		(layer "In7.Cu")
		(net "P5E_PEX3_STN4_TX_C_DP<64>")
	)
	(segment
		(start 435.89194 -368.387122)
		(end 435.733952 -368.85626)
		(width 0.1651)
		(layer "In7.Cu")
		(net "P5E_PEX3_STN4_TX_C_DP<64>")
	)
	(segment
		(start 438.219088 -361.123484)
		(end 438.29097 -361.268264)
		(width 0.1651)
		(layer "In7.Cu")
		(net "P5E_PEX3_STN4_TX_C_DP<64>")
	)
	(segment
		(start 436.123334 -367.700814)
		(end 435.9783 -367.772696)
		(width 0.1651)
		(layer "In7.Cu")
		(net "P5E_PEX3_STN4_TX_C_DP<64>")
	)
	(segment
		(start 436.598822 -365.931196)
		(end 436.670704 -366.07623)
		(width 0.1651)
		(layer "In7.Cu")
		(net "P5E_PEX3_STN4_TX_C_DP<64>")
	)
	(segment
		(start 437.987948 -361.809284)
		(end 437.829706 -362.27893)
		(width 0.1651)
		(layer "In7.Cu")
		(net "P5E_PEX3_STN4_TX_C_DP<64>")
	)
	(segment
		(start 438.766712 -359.498392)
		(end 438.60847 -359.968038)
		(width 0.1651)
		(layer "In7.Cu")
		(net "P5E_PEX3_STN4_TX_C_DP<64>")
	)
	(segment
		(start 437.512206 -363.579156)
		(end 436.902098 -365.389922)
		(width 0.1651)
		(layer "In7.Cu")
		(net "P5E_PEX3_STN4_TX_C_DP<64>")
	)
	(segment
		(start 438.522364 -360.581956)
		(end 438.37733 -360.653838)
		(width 0.1651)
		(layer "In7.Cu")
		(net "P5E_PEX3_STN4_TX_C_DP<64>")
	)
	(segment
		(start 437.7436 -362.892848)
		(end 437.598566 -362.96473)
		(width 0.1651)
		(layer "In7.Cu")
		(net "P5E_PEX3_STN4_TX_C_DP<64>")
	)
	(segment
		(start 436.367682 -366.61725)
		(end 436.209694 -367.086642)
		(width 0.1651)
		(layer "In7.Cu")
		(net "P5E_PEX3_STN4_TX_C_DP<64>")
	)
	(segment
		(start 436.757064 -365.461804)
		(end 436.598822 -365.931196)
		(width 0.1651)
		(layer "In7.Cu")
		(net "P5E_PEX3_STN4_TX_C_DP<64>")
	)
	(segment
		(start 439.121042 -358.80548)
		(end 438.911746 -359.42651)
		(width 0.1651)
		(layer "In7.Cu")
		(net "P5E_PEX3_STN4_TX_C_DP<64>")
	)
	(segment
		(start 435.9783 -367.772696)
		(end 435.820312 -368.242088)
		(width 0.1651)
		(layer "In7.Cu")
		(net "P5E_PEX3_STN4_TX_C_DP<64>")
	)
	(segment
		(start 435.733952 -371.812312)
		(end 435.447186 -372.099078)
		(width 0.1651)
		(layer "In7.Cu")
		(net "P5E_PEX3_STN4_TX_C_DP<64>")
	)
	(segment
		(start 435.820312 -368.242088)
		(end 435.89194 -368.387122)
		(width 0.1651)
		(layer "In7.Cu")
		(net "P5E_PEX3_STN4_TX_C_DP<64>")
	)
	(segment
		(start 439.121042 -353.910646)
		(end 439.121042 -358.80548)
		(width 0.1651)
		(layer "In7.Cu")
		(net "P5E_PEX3_STN4_TX_C_DP<64>")
	)
	(segment
		(start 437.598566 -362.96473)
		(end 437.440324 -363.434376)
		(width 0.1651)
		(layer "In7.Cu")
		(net "P5E_PEX3_STN4_TX_C_DP<64>")
	)
	(segment
		(start 440.675522 -352.356166)
		(end 439.121042 -353.910646)
		(width 0.1651)
		(layer "In7.Cu")
		(net "P5E_PEX3_STN4_TX_C_DP<64>")
	)
	(segment
		(start 435.733952 -368.85626)
		(end 435.733952 -371.812312)
		(width 0.1651)
		(layer "In7.Cu")
		(net "P5E_PEX3_STN4_TX_C_DP<64>")
	)
	(segment
		(start 436.512716 -366.545368)
		(end 436.367682 -366.61725)
		(width 0.1651)
		(layer "In7.Cu")
		(net "P5E_PEX3_STN4_TX_C_DP<64>")
	)
	(segment
		(start 436.209694 -367.086642)
		(end 436.281322 -367.231676)
		(width 0.1651)
		(layer "In7.Cu")
		(net "P5E_PEX3_STN4_TX_C_DP<64>")
	)
	(segment
		(start 438.132982 -361.737402)
		(end 437.987948 -361.809284)
		(width 0.1651)
		(layer "In7.Cu")
		(net "P5E_PEX3_STN4_TX_C_DP<64>")
	)
	(segment
		(start 436.281322 -367.231676)
		(end 436.123334 -367.700814)
		(width 0.1651)
		(layer "In7.Cu")
		(net "P5E_PEX3_STN4_TX_C_DP<64>")
	)
	(segment
		(start 438.29097 -361.268264)
		(end 438.132982 -361.737402)
		(width 0.1651)
		(layer "In7.Cu")
		(net "P5E_PEX3_STN4_TX_C_DP<64>")
	)
	(segment
		(start 438.911746 -359.42651)
		(end 438.766712 -359.498392)
		(width 0.1651)
		(layer "In7.Cu")
		(net "P5E_PEX3_STN4_TX_C_DP<64>")
	)
	(segment
		(start 434.88991 -371.972078)
		(end 434.88991 -371.590062)
		(width 0.1651)
		(layer "In7.Cu")
		(net "P5E_PEX3_STN4_TX_C_DP<64>")
	)
	(segment
		(start 435.447186 -372.099078)
		(end 435.01691 -372.099078)
		(width 0.1651)
		(layer "In7.Cu")
		(net "P5E_PEX3_STN4_TX_C_DP<64>")
	)
	(segment
		(start 435.01691 -372.099078)
		(end 434.88991 -371.972078)
		(width 0.1651)
		(layer "In7.Cu")
		(net "P5E_PEX3_STN4_TX_C_DP<64>")
	)
	(segment
		(start 437.829706 -362.27893)
		(end 437.901588 -362.42371)
		(width 0.1651)
		(layer "In7.Cu")
		(net "P5E_PEX3_STN4_TX_C_DP<64>")
	)
	(segment
		(start 438.60847 -359.968038)
		(end 438.680352 -360.112818)
		(width 0.1651)
		(layer "In7.Cu")
		(net "P5E_PEX3_STN4_TX_C_DP<64>")
	)
	(segment
		(start 437.440324 -363.434376)
		(end 437.512206 -363.579156)
		(width 0.1651)
		(layer "In7.Cu")
		(net "P5E_PEX3_STN4_TX_C_DP<64>")
	)
	(segment
		(start 440.384692 -351.611438)
		(end 440.675522 -351.902268)
		(width 0.1651)
		(layer "In7.Cu")
		(net "P5E_PEX3_STN4_TX_C_DP<64>")
	)
	(segment
		(start 436.670704 -366.07623)
		(end 436.512716 -366.545368)
		(width 0.1651)
		(layer "In7.Cu")
		(net "P5E_PEX3_STN4_TX_C_DP<64>")
	)
	(segment
		(start 438.37733 -360.653838)
		(end 438.219088 -361.123484)
		(width 0.1651)
		(layer "In7.Cu")
		(net "P5E_PEX3_STN4_TX_C_DP<64>")
	)
	(segment
		(start 440.675522 -351.902268)
		(end 440.675522 -352.356166)
		(width 0.1651)
		(layer "In7.Cu")
		(net "P5E_PEX3_STN4_TX_C_DP<64>")
	)
	(segment
		(start 16.248126 -220.84665)
		(end 16.039846 -221.05493)
		(width 0.13208)
		(layer "F.Cu")
		(net "SPI_PEX0_CLK_MUX_R")
	)
	(segment
		(start 16.039846 -221.05493)
		(end 15.020036 -221.05493)
		(width 0.13208)
		(layer "F.Cu")
		(net "SPI_PEX0_CLK_MUX_R")
	)
	(via
		(at 16.248126 -220.84665)
		(size 0.508)
		(drill 0.254)
		(layers "F.Cu" "B.Cu")
		(net "SPI_PEX0_CLK_MUX_R")
	)
	(segment
		(start 15.853918 -221.240858)
		(end 16.248126 -220.84665)
		(width 0.13208)
		(layer "B.Cu")
		(net "SPI_PEX0_CLK_MUX_R")
	)
	(segment
		(start 15.012416 -221.240858)
		(end 15.853918 -221.240858)
		(width 0.13208)
		(layer "B.Cu")
		(net "SPI_PEX0_CLK_MUX_R")
	)
	(segment
		(start 431.35296 -356.832154)
		(end 431.35296 -357.462582)
		(width 0.13462)
		(layer "F.Cu")
		(net "P5E_PEX3_STN4_TX_C_DP<68>")
	)
	(segment
		(start 431.032412 -356.511606)
		(end 431.35296 -356.832154)
		(width 0.13462)
		(layer "F.Cu")
		(net "P5E_PEX3_STN4_TX_C_DP<68>")
	)
	(segment
		(start 431.35296 -357.462582)
		(end 431.057812 -357.75773)
		(width 0.13462)
		(layer "F.Cu")
		(net "P5E_PEX3_STN4_TX_C_DP<68>")
	)
	(segment
		(start 426.089826 -371.972078)
		(end 426.216826 -372.099078)
		(width 0.1651)
		(layer "In7.Cu")
		(net "P5E_PEX3_STN4_TX_C_DP<68>")
	)
	(segment
		(start 428.272956 -365.403892)
		(end 428.42434 -365.346234)
		(width 0.1651)
		(layer "In7.Cu")
		(net "P5E_PEX3_STN4_TX_C_DP<68>")
	)
	(segment
		(start 428.128938 -366.007396)
		(end 428.129192 -366.00765)
		(width 0.1651)
		(layer "In7.Cu")
		(net "P5E_PEX3_STN4_TX_C_DP<68>")
	)
	(segment
		(start 426.647102 -372.099078)
		(end 426.933868 -371.812312)
		(width 0.1651)
		(layer "In7.Cu")
		(net "P5E_PEX3_STN4_TX_C_DP<68>")
	)
	(segment
		(start 431.348642 -358.04856)
		(end 431.057812 -357.75773)
		(width 0.1651)
		(layer "In7.Cu")
		(net "P5E_PEX3_STN4_TX_C_DP<68>")
	)
	(segment
		(start 427.776386 -366.517428)
		(end 427.927516 -366.45977)
		(width 0.1651)
		(layer "In7.Cu")
		(net "P5E_PEX3_STN4_TX_C_DP<68>")
	)
	(segment
		(start 430.851818 -359.903014)
		(end 430.79416 -359.752138)
		(width 0.1651)
		(layer "In7.Cu")
		(net "P5E_PEX3_STN4_TX_C_DP<68>")
	)
	(segment
		(start 428.129192 -366.00765)
		(end 428.07128 -365.85652)
		(width 0.1651)
		(layer "In7.Cu")
		(net "P5E_PEX3_STN4_TX_C_DP<68>")
	)
	(segment
		(start 429.858424 -362.130086)
		(end 429.858678 -362.130086)
		(width 0.1651)
		(layer "In7.Cu")
		(net "P5E_PEX3_STN4_TX_C_DP<68>")
	)
	(segment
		(start 430.002442 -361.526582)
		(end 430.153572 -361.46867)
		(width 0.1651)
		(layer "In7.Cu")
		(net "P5E_PEX3_STN4_TX_C_DP<68>")
	)
	(segment
		(start 430.995836 -359.29951)
		(end 431.146966 -359.241598)
		(width 0.1651)
		(layer "In7.Cu")
		(net "P5E_PEX3_STN4_TX_C_DP<68>")
	)
	(segment
		(start 430.354994 -361.01655)
		(end 430.355248 -361.01655)
		(width 0.1651)
		(layer "In7.Cu")
		(net "P5E_PEX3_STN4_TX_C_DP<68>")
	)
	(segment
		(start 426.216826 -372.099078)
		(end 426.647102 -372.099078)
		(width 0.1651)
		(layer "In7.Cu")
		(net "P5E_PEX3_STN4_TX_C_DP<68>")
	)
	(segment
		(start 430.297336 -360.865674)
		(end 430.499012 -360.413046)
		(width 0.1651)
		(layer "In7.Cu")
		(net "P5E_PEX3_STN4_TX_C_DP<68>")
	)
	(segment
		(start 429.858678 -362.130086)
		(end 429.800766 -361.97921)
		(width 0.1651)
		(layer "In7.Cu")
		(net "P5E_PEX3_STN4_TX_C_DP<68>")
	)
	(segment
		(start 428.42434 -365.346234)
		(end 428.423832 -365.345726)
		(width 0.1651)
		(layer "In7.Cu")
		(net "P5E_PEX3_STN4_TX_C_DP<68>")
	)
	(segment
		(start 427.927516 -366.45977)
		(end 427.927262 -366.459516)
		(width 0.1651)
		(layer "In7.Cu")
		(net "P5E_PEX3_STN4_TX_C_DP<68>")
	)
	(segment
		(start 428.920656 -364.23219)
		(end 429.858424 -362.130086)
		(width 0.1651)
		(layer "In7.Cu")
		(net "P5E_PEX3_STN4_TX_C_DP<68>")
	)
	(segment
		(start 429.800766 -361.97921)
		(end 430.002442 -361.526582)
		(width 0.1651)
		(layer "In7.Cu")
		(net "P5E_PEX3_STN4_TX_C_DP<68>")
	)
	(segment
		(start 428.568104 -364.742984)
		(end 428.76978 -364.290356)
		(width 0.1651)
		(layer "In7.Cu")
		(net "P5E_PEX3_STN4_TX_C_DP<68>")
	)
	(segment
		(start 428.625508 -364.894114)
		(end 428.626016 -364.894114)
		(width 0.1651)
		(layer "In7.Cu")
		(net "P5E_PEX3_STN4_TX_C_DP<68>")
	)
	(segment
		(start 428.626016 -364.894114)
		(end 428.568104 -364.742984)
		(width 0.1651)
		(layer "In7.Cu")
		(net "P5E_PEX3_STN4_TX_C_DP<68>")
	)
	(segment
		(start 427.430692 -367.573306)
		(end 427.430438 -367.573306)
		(width 0.1651)
		(layer "In7.Cu")
		(net "P5E_PEX3_STN4_TX_C_DP<68>")
	)
	(segment
		(start 428.921164 -364.232698)
		(end 428.920656 -364.23219)
		(width 0.1651)
		(layer "In7.Cu")
		(net "P5E_PEX3_STN4_TX_C_DP<68>")
	)
	(segment
		(start 426.933868 -368.686842)
		(end 427.135544 -368.234722)
		(width 0.1651)
		(layer "In7.Cu")
		(net "P5E_PEX3_STN4_TX_C_DP<68>")
	)
	(segment
		(start 430.79416 -359.752138)
		(end 430.995836 -359.29951)
		(width 0.1651)
		(layer "In7.Cu")
		(net "P5E_PEX3_STN4_TX_C_DP<68>")
	)
	(segment
		(start 427.135544 -368.234722)
		(end 427.077632 -368.083592)
		(width 0.1651)
		(layer "In7.Cu")
		(net "P5E_PEX3_STN4_TX_C_DP<68>")
	)
	(segment
		(start 427.574456 -366.970056)
		(end 427.776386 -366.517428)
		(width 0.1651)
		(layer "In7.Cu")
		(net "P5E_PEX3_STN4_TX_C_DP<68>")
	)
	(segment
		(start 427.927262 -366.459516)
		(end 428.128938 -366.007396)
		(width 0.1651)
		(layer "In7.Cu")
		(net "P5E_PEX3_STN4_TX_C_DP<68>")
	)
	(segment
		(start 430.153572 -361.46867)
		(end 430.153318 -361.46867)
		(width 0.1651)
		(layer "In7.Cu")
		(net "P5E_PEX3_STN4_TX_C_DP<68>")
	)
	(segment
		(start 427.632368 -367.121186)
		(end 427.574456 -366.970056)
		(width 0.1651)
		(layer "In7.Cu")
		(net "P5E_PEX3_STN4_TX_C_DP<68>")
	)
	(segment
		(start 427.430438 -367.573306)
		(end 427.632114 -367.121186)
		(width 0.1651)
		(layer "In7.Cu")
		(net "P5E_PEX3_STN4_TX_C_DP<68>")
	)
	(segment
		(start 428.07128 -365.85652)
		(end 428.272956 -365.403892)
		(width 0.1651)
		(layer "In7.Cu")
		(net "P5E_PEX3_STN4_TX_C_DP<68>")
	)
	(segment
		(start 427.279562 -367.630964)
		(end 427.430692 -367.573306)
		(width 0.1651)
		(layer "In7.Cu")
		(net "P5E_PEX3_STN4_TX_C_DP<68>")
	)
	(segment
		(start 428.423832 -365.345726)
		(end 428.625508 -364.894114)
		(width 0.1651)
		(layer "In7.Cu")
		(net "P5E_PEX3_STN4_TX_C_DP<68>")
	)
	(segment
		(start 428.76978 -364.290356)
		(end 428.921164 -364.232698)
		(width 0.1651)
		(layer "In7.Cu")
		(net "P5E_PEX3_STN4_TX_C_DP<68>")
	)
	(segment
		(start 427.077632 -368.083592)
		(end 427.279562 -367.630964)
		(width 0.1651)
		(layer "In7.Cu")
		(net "P5E_PEX3_STN4_TX_C_DP<68>")
	)
	(segment
		(start 431.146966 -359.241598)
		(end 431.348642 -358.789478)
		(width 0.1651)
		(layer "In7.Cu")
		(net "P5E_PEX3_STN4_TX_C_DP<68>")
	)
	(segment
		(start 426.933868 -371.812312)
		(end 426.933868 -368.686842)
		(width 0.1651)
		(layer "In7.Cu")
		(net "P5E_PEX3_STN4_TX_C_DP<68>")
	)
	(segment
		(start 431.348642 -358.789478)
		(end 431.348642 -358.04856)
		(width 0.1651)
		(layer "In7.Cu")
		(net "P5E_PEX3_STN4_TX_C_DP<68>")
	)
	(segment
		(start 430.153318 -361.46867)
		(end 430.354994 -361.01655)
		(width 0.1651)
		(layer "In7.Cu")
		(net "P5E_PEX3_STN4_TX_C_DP<68>")
	)
	(segment
		(start 426.089826 -371.590062)
		(end 426.089826 -371.972078)
		(width 0.1651)
		(layer "In7.Cu")
		(net "P5E_PEX3_STN4_TX_C_DP<68>")
	)
	(segment
		(start 430.650142 -360.355134)
		(end 430.851818 -359.903014)
		(width 0.1651)
		(layer "In7.Cu")
		(net "P5E_PEX3_STN4_TX_C_DP<68>")
	)
	(segment
		(start 427.632114 -367.121186)
		(end 427.632368 -367.121186)
		(width 0.1651)
		(layer "In7.Cu")
		(net "P5E_PEX3_STN4_TX_C_DP<68>")
	)
	(segment
		(start 430.499012 -360.413046)
		(end 430.650142 -360.355134)
		(width 0.1651)
		(layer "In7.Cu")
		(net "P5E_PEX3_STN4_TX_C_DP<68>")
	)
	(segment
		(start 430.355248 -361.01655)
		(end 430.297336 -360.865674)
		(width 0.1651)
		(layer "In7.Cu")
		(net "P5E_PEX3_STN4_TX_C_DP<68>")
	)
	(segment
		(start 43.499786 -294.94988)
		(end 43.024806 -294.4749)
		(width 0.13208)
		(layer "F.Cu")
		(net "SPI_PEX0_SDIO1")
	)
	(via
		(at 43.024806 -294.4749)
		(size 0.4064)
		(drill 0.2032)
		(layers "F.Cu" "B.Cu")
		(net "SPI_PEX0_SDIO1")
	)
	(via
		(at 42.549826 -295.89984)
		(size 0.6604)
		(drill 0.3302)
		(layers "F.Cu" "B.Cu")
		(net "SPI_PEX0_SDIO1")
	)
	(segment
		(start 41.882822 -295.89984)
		(end 42.549826 -295.89984)
		(width 0.13208)
		(layer "B.Cu")
		(net "SPI_PEX0_SDIO1")
	)
	(segment
		(start 40.573706 -296.9514)
		(end 40.831262 -296.9514)
		(width 0.13208)
		(layer "B.Cu")
		(net "SPI_PEX0_SDIO1")
	)
	(segment
		(start 40.831262 -296.9514)
		(end 41.882822 -295.89984)
		(width 0.13208)
		(layer "B.Cu")
		(net "SPI_PEX0_SDIO1")
	)
	(segment
		(start 42.549826 -295.89984)
		(end 43.024806 -295.42486)
		(width 0.13208)
		(layer "B.Cu")
		(net "SPI_PEX0_SDIO1")
	)
	(segment
		(start 43.024806 -295.42486)
		(end 43.024806 -294.4749)
		(width 0.13208)
		(layer "B.Cu")
		(net "SPI_PEX0_SDIO1")
	)
	(segment
		(start 415.487612 -350.365314)
		(end 415.80816 -350.685862)
		(width 0.13462)
		(layer "F.Cu")
		(net "P5E_PEX3_STN4_TX_C_DP<76>")
	)
	(segment
		(start 415.80816 -351.31629)
		(end 415.513012 -351.611438)
		(width 0.13462)
		(layer "F.Cu")
		(net "P5E_PEX3_STN4_TX_C_DP<76>")
	)
	(segment
		(start 415.80816 -350.685862)
		(end 415.80816 -351.31629)
		(width 0.13462)
		(layer "F.Cu")
		(net "P5E_PEX3_STN4_TX_C_DP<76>")
	)
	(segment
		(start 425.125134 -393.441174)
		(end 424.603672 -393.153138)
		(width 0.1651)
		(layer "In7.Cu")
		(net "P5E_PEX3_STN4_TX_C_DP<76>")
	)
	(segment
		(start 426.089826 -397.59001)
		(end 426.089826 -397.97228)
		(width 0.1651)
		(layer "In7.Cu")
		(net "P5E_PEX3_STN4_TX_C_DP<76>")
	)
	(segment
		(start 424.603672 -393.153138)
		(end 424.482768 -393.187936)
		(width 0.1651)
		(layer "In7.Cu")
		(net "P5E_PEX3_STN4_TX_C_DP<76>")
	)
	(segment
		(start 424.048936 -392.94816)
		(end 424.014138 -392.827256)
		(width 0.1651)
		(layer "In7.Cu")
		(net "P5E_PEX3_STN4_TX_C_DP<76>")
	)
	(segment
		(start 414.55975 -386.42036)
		(end 413.761174 -383.796032)
		(width 0.1651)
		(layer "In7.Cu")
		(net "P5E_PEX3_STN4_TX_C_DP<76>")
	)
	(segment
		(start 426.404278 -394.720318)
		(end 426.278548 -394.720318)
		(width 0.1651)
		(layer "In7.Cu")
		(net "P5E_PEX3_STN4_TX_C_DP<76>")
	)
	(segment
		(start 424.482768 -393.187936)
		(end 424.048936 -392.94816)
		(width 0.1651)
		(layer "In7.Cu")
		(net "P5E_PEX3_STN4_TX_C_DP<76>")
	)
	(segment
		(start 414.249362 -358.469692)
		(end 414.249362 -353.910646)
		(width 0.1651)
		(layer "In7.Cu")
		(net "P5E_PEX3_STN4_TX_C_DP<76>")
	)
	(segment
		(start 415.803842 -352.356166)
		(end 415.803842 -351.902268)
		(width 0.1651)
		(layer "In7.Cu")
		(net "P5E_PEX3_STN4_TX_C_DP<76>")
	)
	(segment
		(start 425.928282 -394.244322)
		(end 425.125134 -393.441174)
		(width 0.1651)
		(layer "In7.Cu")
		(net "P5E_PEX3_STN4_TX_C_DP<76>")
	)
	(segment
		(start 414.249362 -353.910646)
		(end 415.803842 -352.356166)
		(width 0.1651)
		(layer "In7.Cu")
		(net "P5E_PEX3_STN4_TX_C_DP<76>")
	)
	(segment
		(start 413.761174 -383.796032)
		(end 413.76092 -383.79527)
		(width 0.1651)
		(layer "In7.Cu")
		(net "P5E_PEX3_STN4_TX_C_DP<76>")
	)
	(segment
		(start 416.223704 -388.523734)
		(end 414.55975 -386.42036)
		(width 0.1651)
		(layer "In7.Cu")
		(net "P5E_PEX3_STN4_TX_C_DP<76>")
	)
	(segment
		(start 415.803842 -351.902268)
		(end 415.513012 -351.611438)
		(width 0.1651)
		(layer "In7.Cu")
		(net "P5E_PEX3_STN4_TX_C_DP<76>")
	)
	(segment
		(start 425.928282 -394.370052)
		(end 425.928282 -394.244322)
		(width 0.1651)
		(layer "In7.Cu")
		(net "P5E_PEX3_STN4_TX_C_DP<76>")
	)
	(segment
		(start 426.089826 -397.97228)
		(end 426.216826 -398.09928)
		(width 0.1651)
		(layer "In7.Cu")
		(net "P5E_PEX3_STN4_TX_C_DP<76>")
	)
	(segment
		(start 426.933868 -395.249908)
		(end 426.404278 -394.720318)
		(width 0.1651)
		(layer "In7.Cu")
		(net "P5E_PEX3_STN4_TX_C_DP<76>")
	)
	(segment
		(start 426.933868 -397.812514)
		(end 426.933868 -395.249908)
		(width 0.1651)
		(layer "In7.Cu")
		(net "P5E_PEX3_STN4_TX_C_DP<76>")
	)
	(segment
		(start 426.647102 -398.09928)
		(end 426.933868 -397.812514)
		(width 0.1651)
		(layer "In7.Cu")
		(net "P5E_PEX3_STN4_TX_C_DP<76>")
	)
	(segment
		(start 426.216826 -398.09928)
		(end 426.647102 -398.09928)
		(width 0.1651)
		(layer "In7.Cu")
		(net "P5E_PEX3_STN4_TX_C_DP<76>")
	)
	(segment
		(start 413.76092 -383.79527)
		(end 413.747966 -383.752598)
		(width 0.1651)
		(layer "In7.Cu")
		(net "P5E_PEX3_STN4_TX_C_DP<76>")
	)
	(segment
		(start 426.278548 -394.720318)
		(end 425.928282 -394.370052)
		(width 0.1651)
		(layer "In7.Cu")
		(net "P5E_PEX3_STN4_TX_C_DP<76>")
	)
	(segment
		(start 424.014138 -392.827256)
		(end 416.223704 -388.523734)
		(width 0.1651)
		(layer "In7.Cu")
		(net "P5E_PEX3_STN4_TX_C_DP<76>")
	)
	(segment
		(start 413.747966 -383.752598)
		(end 414.249362 -358.469692)
		(width 0.1651)
		(layer "In7.Cu")
		(net "P5E_PEX3_STN4_TX_C_DP<76>")
	)
	(segment
		(start 26.337768 -228.67493)
		(end 24.62022 -228.67493)
		(width 0.13208)
		(layer "F.Cu")
		(net "SPI_PEX0_CS_MUX_R_N")
	)
	(via
		(at 26.337768 -228.67493)
		(size 0.508)
		(drill 0.254)
		(layers "F.Cu" "B.Cu")
		(net "SPI_PEX0_CS_MUX_R_N")
	)
	(segment
		(start 24.219408 -227.588826)
		(end 24.219408 -227.94595)
		(width 0.13208)
		(layer "B.Cu")
		(net "SPI_PEX0_CS_MUX_R_N")
	)
	(segment
		(start 24.496522 -226.936046)
		(end 24.496522 -227.311712)
		(width 0.13208)
		(layer "B.Cu")
		(net "SPI_PEX0_CS_MUX_R_N")
	)
	(segment
		(start 24.219408 -227.94595)
		(end 25.608788 -227.94595)
		(width 0.13208)
		(layer "B.Cu")
		(net "SPI_PEX0_CS_MUX_R_N")
	)
	(segment
		(start 25.608788 -227.94595)
		(end 26.337768 -228.67493)
		(width 0.13208)
		(layer "B.Cu")
		(net "SPI_PEX0_CS_MUX_R_N")
	)
	(segment
		(start 24.496522 -227.311712)
		(end 24.219408 -227.588826)
		(width 0.13208)
		(layer "B.Cu")
		(net "SPI_PEX0_CS_MUX_R_N")
	)
	(segment
		(start 441.273692 -350.365314)
		(end 440.95416 -350.684846)
		(width 0.13462)
		(layer "F.Cu")
		(net "P5E_PEX3_STN4_TX_C_DN<64>")
	)
	(segment
		(start 440.95416 -351.317306)
		(end 441.248292 -351.611438)
		(width 0.13462)
		(layer "F.Cu")
		(net "P5E_PEX3_STN4_TX_C_DN<64>")
	)
	(segment
		(start 440.95416 -350.684846)
		(end 440.95416 -351.317306)
		(width 0.13462)
		(layer "F.Cu")
		(net "P5E_PEX3_STN4_TX_C_DN<64>")
	)
	(segment
		(start 439.402982 -354.027486)
		(end 439.402982 -358.851962)
		(width 0.1651)
		(layer "In7.Cu")
		(net "P5E_PEX3_STN4_TX_C_DN<64>")
	)
	(segment
		(start 435.564026 -372.381018)
		(end 435.01691 -372.381018)
		(width 0.1651)
		(layer "In7.Cu")
		(net "P5E_PEX3_STN4_TX_C_DN<64>")
	)
	(segment
		(start 441.248292 -351.611438)
		(end 440.957462 -351.902268)
		(width 0.1651)
		(layer "In7.Cu")
		(net "P5E_PEX3_STN4_TX_C_DN<64>")
	)
	(segment
		(start 434.88991 -372.508018)
		(end 434.88991 -372.890034)
		(width 0.1651)
		(layer "In7.Cu")
		(net "P5E_PEX3_STN4_TX_C_DN<64>")
	)
	(segment
		(start 440.957462 -352.473006)
		(end 439.402982 -354.027486)
		(width 0.1651)
		(layer "In7.Cu")
		(net "P5E_PEX3_STN4_TX_C_DN<64>")
	)
	(segment
		(start 435.01691 -372.381018)
		(end 434.88991 -372.508018)
		(width 0.1651)
		(layer "In7.Cu")
		(net "P5E_PEX3_STN4_TX_C_DN<64>")
	)
	(segment
		(start 436.015892 -371.929152)
		(end 435.564026 -372.381018)
		(width 0.1651)
		(layer "In7.Cu")
		(net "P5E_PEX3_STN4_TX_C_DN<64>")
	)
	(segment
		(start 436.015892 -368.902742)
		(end 436.015892 -371.929152)
		(width 0.1651)
		(layer "In7.Cu")
		(net "P5E_PEX3_STN4_TX_C_DN<64>")
	)
	(segment
		(start 440.957462 -351.902268)
		(end 440.957462 -352.473006)
		(width 0.1651)
		(layer "In7.Cu")
		(net "P5E_PEX3_STN4_TX_C_DN<64>")
	)
	(segment
		(start 439.402982 -358.851962)
		(end 436.015892 -368.902742)
		(width 0.1651)
		(layer "In7.Cu")
		(net "P5E_PEX3_STN4_TX_C_DN<64>")
	)
	(segment
		(start 435.780434 -360.91622)
		(end 436.185818 -360.631994)
		(width 0.1651)
		(layer "In5.Cu")
		(net "P5E_PEX3_STN4_RX_DP<69>")
	)
	(segment
		(start 433.451 -317.215012)
		(end 433.451 -310.865774)
		(width 0.1651)
		(layer "In5.Cu")
		(net "P5E_PEX3_STN4_RX_DP<69>")
	)
	(segment
		(start 428.16526 -309.199788)
		(end 427.89983 -309.199788)
		(width 0.1143)
		(layer "In5.Cu")
		(net "P5E_PEX3_STN4_RX_DP<69>")
	)
	(segment
		(start 424.765978 -369.626642)
		(end 425.186856 -368.610642)
		(width 0.1651)
		(layer "In5.Cu")
		(net "P5E_PEX3_STN4_RX_DP<69>")
	)
	(segment
		(start 435.215284 -361.17276)
		(end 435.621176 -360.88828)
		(width 0.1651)
		(layer "In5.Cu")
		(net "P5E_PEX3_STN4_RX_DP<69>")
	)
	(segment
		(start 423.889932 -378.290074)
		(end 423.889932 -378.629672)
		(width 0.1651)
		(layer "In5.Cu")
		(net "P5E_PEX3_STN4_RX_DP<69>")
	)
	(segment
		(start 429.551592 -365.283242)
		(end 433.19065 -362.732066)
		(width 0.1651)
		(layer "In5.Cu")
		(net "P5E_PEX3_STN4_RX_DP<69>")
	)
	(segment
		(start 434.78196 -361.616244)
		(end 435.187344 -361.332018)
		(width 0.1651)
		(layer "In5.Cu")
		(net "P5E_PEX3_STN4_RX_DP<69>")
	)
	(segment
		(start 425.186856 -368.610642)
		(end 426.080174 -367.71707)
		(width 0.1651)
		(layer "In5.Cu")
		(net "P5E_PEX3_STN4_RX_DP<69>")
	)
	(segment
		(start 424.06316 -378.8029)
		(end 424.433492 -378.8029)
		(width 0.1651)
		(layer "In5.Cu")
		(net "P5E_PEX3_STN4_RX_DP<69>")
	)
	(segment
		(start 434.622702 -361.588304)
		(end 434.78196 -361.616244)
		(width 0.1651)
		(layer "In5.Cu")
		(net "P5E_PEX3_STN4_RX_DP<69>")
	)
	(segment
		(start 428.986442 -365.539782)
		(end 429.392334 -365.255302)
		(width 0.1651)
		(layer "In5.Cu")
		(net "P5E_PEX3_STN4_RX_DP<69>")
	)
	(segment
		(start 429.392334 -365.255302)
		(end 429.551592 -365.283242)
		(width 0.1651)
		(layer "In5.Cu")
		(net "P5E_PEX3_STN4_RX_DP<69>")
	)
	(segment
		(start 427.554644 -366.68329)
		(end 427.960028 -366.399064)
		(width 0.1651)
		(layer "In5.Cu")
		(net "P5E_PEX3_STN4_RX_DP<69>")
	)
	(segment
		(start 434.21681 -361.872784)
		(end 434.622702 -361.588304)
		(width 0.1651)
		(layer "In5.Cu")
		(net "P5E_PEX3_STN4_RX_DP<69>")
	)
	(segment
		(start 427.395386 -366.65535)
		(end 427.554644 -366.68329)
		(width 0.1651)
		(layer "In5.Cu")
		(net "P5E_PEX3_STN4_RX_DP<69>")
	)
	(segment
		(start 426.989494 -366.940084)
		(end 427.395386 -366.65535)
		(width 0.1651)
		(layer "In5.Cu")
		(net "P5E_PEX3_STN4_RX_DP<69>")
	)
	(segment
		(start 433.783486 -362.316268)
		(end 434.18887 -362.032042)
		(width 0.1651)
		(layer "In5.Cu")
		(net "P5E_PEX3_STN4_RX_DP<69>")
	)
	(segment
		(start 428.505366 -309.770018)
		(end 428.27956 -309.544212)
		(width 0.1143)
		(layer "In5.Cu")
		(net "P5E_PEX3_STN4_RX_DP<69>")
	)
	(segment
		(start 436.213758 -360.472736)
		(end 436.61965 -360.188256)
		(width 0.1651)
		(layer "In5.Cu")
		(net "P5E_PEX3_STN4_RX_DP<69>")
	)
	(segment
		(start 426.080174 -367.71707)
		(end 426.961554 -367.099088)
		(width 0.1651)
		(layer "In5.Cu")
		(net "P5E_PEX3_STN4_RX_DP<69>")
	)
	(segment
		(start 438.785254 -358.809544)
		(end 439.121042 -358.164384)
		(width 0.1651)
		(layer "In5.Cu")
		(net "P5E_PEX3_STN4_RX_DP<69>")
	)
	(segment
		(start 428.39386 -365.955326)
		(end 428.553118 -365.983266)
		(width 0.1651)
		(layer "In5.Cu")
		(net "P5E_PEX3_STN4_RX_DP<69>")
	)
	(segment
		(start 433.21859 -362.572808)
		(end 433.624482 -362.288074)
		(width 0.1651)
		(layer "In5.Cu")
		(net "P5E_PEX3_STN4_RX_DP<69>")
	)
	(segment
		(start 432.86045 -309.969154)
		(end 432.490118 -309.815738)
		(width 0.1651)
		(layer "In5.Cu")
		(net "P5E_PEX3_STN4_RX_DP<69>")
	)
	(segment
		(start 427.960028 -366.399064)
		(end 427.987968 -366.239806)
		(width 0.1651)
		(layer "In5.Cu")
		(net "P5E_PEX3_STN4_RX_DP<69>")
	)
	(segment
		(start 436.61965 -360.188256)
		(end 436.778908 -360.216196)
		(width 0.1651)
		(layer "In5.Cu")
		(net "P5E_PEX3_STN4_RX_DP<69>")
	)
	(segment
		(start 428.27956 -309.314088)
		(end 428.16526 -309.199788)
		(width 0.1143)
		(layer "In5.Cu")
		(net "P5E_PEX3_STN4_RX_DP<69>")
	)
	(segment
		(start 426.961554 -367.099088)
		(end 426.989494 -366.940084)
		(width 0.1651)
		(layer "In5.Cu")
		(net "P5E_PEX3_STN4_RX_DP<69>")
	)
	(segment
		(start 424.765978 -378.470414)
		(end 424.765978 -369.626642)
		(width 0.1651)
		(layer "In5.Cu")
		(net "P5E_PEX3_STN4_RX_DP<69>")
	)
	(segment
		(start 433.451 -310.865774)
		(end 433.234338 -310.343042)
		(width 0.1651)
		(layer "In5.Cu")
		(net "P5E_PEX3_STN4_RX_DP<69>")
	)
	(segment
		(start 432.67122 -319.09766)
		(end 433.451 -317.215012)
		(width 0.1651)
		(layer "In5.Cu")
		(net "P5E_PEX3_STN4_RX_DP<69>")
	)
	(segment
		(start 432.490118 -309.815738)
		(end 431.955448 -309.815738)
		(width 0.1651)
		(layer "In5.Cu")
		(net "P5E_PEX3_STN4_RX_DP<69>")
	)
	(segment
		(start 433.624482 -362.288074)
		(end 433.783486 -362.316268)
		(width 0.1651)
		(layer "In5.Cu")
		(net "P5E_PEX3_STN4_RX_DP<69>")
	)
	(segment
		(start 428.553118 -365.983266)
		(end 428.958502 -365.69904)
		(width 0.1651)
		(layer "In5.Cu")
		(net "P5E_PEX3_STN4_RX_DP<69>")
	)
	(segment
		(start 431.955448 -309.815738)
		(end 431.927 -309.815738)
		(width 0.1143)
		(layer "In5.Cu")
		(net "P5E_PEX3_STN4_RX_DP<69>")
	)
	(segment
		(start 433.19065 -362.732066)
		(end 433.21859 -362.572808)
		(width 0.1651)
		(layer "In5.Cu")
		(net "P5E_PEX3_STN4_RX_DP<69>")
	)
	(segment
		(start 427.987968 -366.239806)
		(end 428.39386 -365.955326)
		(width 0.1651)
		(layer "In5.Cu")
		(net "P5E_PEX3_STN4_RX_DP<69>")
	)
	(segment
		(start 428.958502 -365.69904)
		(end 428.986442 -365.539782)
		(width 0.1651)
		(layer "In5.Cu")
		(net "P5E_PEX3_STN4_RX_DP<69>")
	)
	(segment
		(start 431.927 -309.815738)
		(end 431.88128 -309.770018)
		(width 0.1143)
		(layer "In5.Cu")
		(net "P5E_PEX3_STN4_RX_DP<69>")
	)
	(segment
		(start 436.185818 -360.631994)
		(end 436.213758 -360.472736)
		(width 0.1651)
		(layer "In5.Cu")
		(net "P5E_PEX3_STN4_RX_DP<69>")
	)
	(segment
		(start 434.18887 -362.032042)
		(end 434.21681 -361.872784)
		(width 0.1651)
		(layer "In5.Cu")
		(net "P5E_PEX3_STN4_RX_DP<69>")
	)
	(segment
		(start 424.433492 -378.8029)
		(end 424.765978 -378.470414)
		(width 0.1651)
		(layer "In5.Cu")
		(net "P5E_PEX3_STN4_RX_DP<69>")
	)
	(segment
		(start 432.67122 -322.607686)
		(end 432.67122 -319.09766)
		(width 0.1651)
		(layer "In5.Cu")
		(net "P5E_PEX3_STN4_RX_DP<69>")
	)
	(segment
		(start 431.88128 -309.770018)
		(end 428.505366 -309.770018)
		(width 0.1143)
		(layer "In5.Cu")
		(net "P5E_PEX3_STN4_RX_DP<69>")
	)
	(segment
		(start 433.234338 -310.343042)
		(end 432.86045 -309.969154)
		(width 0.1651)
		(layer "In5.Cu")
		(net "P5E_PEX3_STN4_RX_DP<69>")
	)
	(segment
		(start 423.889932 -378.629672)
		(end 424.06316 -378.8029)
		(width 0.1651)
		(layer "In5.Cu")
		(net "P5E_PEX3_STN4_RX_DP<69>")
	)
	(segment
		(start 439.121042 -358.164384)
		(end 439.121042 -341.980774)
		(width 0.1651)
		(layer "In5.Cu")
		(net "P5E_PEX3_STN4_RX_DP<69>")
	)
	(segment
		(start 439.121042 -341.980774)
		(end 432.67122 -322.607686)
		(width 0.1651)
		(layer "In5.Cu")
		(net "P5E_PEX3_STN4_RX_DP<69>")
	)
	(segment
		(start 428.27956 -309.544212)
		(end 428.27956 -309.314088)
		(width 0.1143)
		(layer "In5.Cu")
		(net "P5E_PEX3_STN4_RX_DP<69>")
	)
	(segment
		(start 435.621176 -360.88828)
		(end 435.780434 -360.91622)
		(width 0.1651)
		(layer "In5.Cu")
		(net "P5E_PEX3_STN4_RX_DP<69>")
	)
	(segment
		(start 435.187344 -361.332018)
		(end 435.215284 -361.17276)
		(width 0.1651)
		(layer "In5.Cu")
		(net "P5E_PEX3_STN4_RX_DP<69>")
	)
	(segment
		(start 436.778908 -360.216196)
		(end 438.785254 -358.809544)
		(width 0.1651)
		(layer "In5.Cu")
		(net "P5E_PEX3_STN4_RX_DP<69>")
	)
	(segment
		(start 419.663118 -378.8029)
		(end 420.03345 -378.8029)
		(width 0.1651)
		(layer "In5.Cu")
		(net "P5E_PEX3_STN4_RX_DP<71>")
	)
	(segment
		(start 428.198534 -362.366814)
		(end 428.584106 -362.055156)
		(width 0.1651)
		(layer "In5.Cu")
		(net "P5E_PEX3_STN4_RX_DP<71>")
	)
	(segment
		(start 423.73169 -365.962438)
		(end 423.892472 -365.979456)
		(width 0.1651)
		(layer "In5.Cu")
		(net "P5E_PEX3_STN4_RX_DP<71>")
	)
	(segment
		(start 429.111918 -361.758992)
		(end 429.126904 -361.61599)
		(width 0.1651)
		(layer "In5.Cu")
		(net "P5E_PEX3_STN4_RX_DP<71>")
	)
	(segment
		(start 429.126904 -361.61599)
		(end 429.512476 -361.304332)
		(width 0.1651)
		(layer "In5.Cu")
		(net "P5E_PEX3_STN4_RX_DP<71>")
	)
	(segment
		(start 422.94429 -366.746282)
		(end 423.329354 -366.434878)
		(width 0.1651)
		(layer "In5.Cu")
		(net "P5E_PEX3_STN4_RX_DP<71>")
	)
	(segment
		(start 420.815008 -368.467894)
		(end 422.380918 -367.201704)
		(width 0.1651)
		(layer "In5.Cu")
		(net "P5E_PEX3_STN4_RX_DP<71>")
	)
	(segment
		(start 429.512476 -361.304332)
		(end 429.655224 -361.319572)
		(width 0.1651)
		(layer "In5.Cu")
		(net "P5E_PEX3_STN4_RX_DP<71>")
	)
	(segment
		(start 420.365936 -369.408202)
		(end 420.815008 -368.467894)
		(width 0.1651)
		(layer "In5.Cu")
		(net "P5E_PEX3_STN4_RX_DP<71>")
	)
	(segment
		(start 423.892472 -365.979456)
		(end 424.277536 -365.668052)
		(width 0.1651)
		(layer "In5.Cu")
		(net "P5E_PEX3_STN4_RX_DP<71>")
	)
	(segment
		(start 430.065434 -316.799722)
		(end 429.800004 -316.799722)
		(width 0.1143)
		(layer "In5.Cu")
		(net "P5E_PEX3_STN4_RX_DP<71>")
	)
	(segment
		(start 432.903122 -342.107774)
		(end 430.134014 -323.765164)
		(width 0.1651)
		(layer "In5.Cu")
		(net "P5E_PEX3_STN4_RX_DP<71>")
	)
	(segment
		(start 419.48989 -378.290074)
		(end 419.48989 -378.629672)
		(width 0.1651)
		(layer "In5.Cu")
		(net "P5E_PEX3_STN4_RX_DP<71>")
	)
	(segment
		(start 427.798484 -362.820966)
		(end 428.183548 -362.509562)
		(width 0.1651)
		(layer "In5.Cu")
		(net "P5E_PEX3_STN4_RX_DP<71>")
	)
	(segment
		(start 422.397936 -367.040922)
		(end 422.783508 -366.729264)
		(width 0.1651)
		(layer "In5.Cu")
		(net "P5E_PEX3_STN4_RX_DP<71>")
	)
	(segment
		(start 424.277536 -365.668052)
		(end 424.294554 -365.507524)
		(width 0.1651)
		(layer "In5.Cu")
		(net "P5E_PEX3_STN4_RX_DP<71>")
	)
	(segment
		(start 424.8404 -365.212884)
		(end 427.255178 -363.260386)
		(width 0.1651)
		(layer "In5.Cu")
		(net "P5E_PEX3_STN4_RX_DP<71>")
	)
	(segment
		(start 422.783508 -366.729264)
		(end 422.94429 -366.746282)
		(width 0.1651)
		(layer "In5.Cu")
		(net "P5E_PEX3_STN4_RX_DP<71>")
	)
	(segment
		(start 420.03345 -378.8029)
		(end 420.365936 -378.470414)
		(width 0.1651)
		(layer "In5.Cu")
		(net "P5E_PEX3_STN4_RX_DP<71>")
	)
	(segment
		(start 428.726854 -362.070142)
		(end 429.111918 -361.758992)
		(width 0.1651)
		(layer "In5.Cu")
		(net "P5E_PEX3_STN4_RX_DP<71>")
	)
	(segment
		(start 429.655224 -361.319572)
		(end 432.903122 -358.69372)
		(width 0.1651)
		(layer "In5.Cu")
		(net "P5E_PEX3_STN4_RX_DP<71>")
	)
	(segment
		(start 427.255178 -363.260386)
		(end 427.270164 -363.117638)
		(width 0.1651)
		(layer "In5.Cu")
		(net "P5E_PEX3_STN4_RX_DP<71>")
	)
	(segment
		(start 428.183548 -362.509562)
		(end 428.198534 -362.366814)
		(width 0.1651)
		(layer "In5.Cu")
		(net "P5E_PEX3_STN4_RX_DP<71>")
	)
	(segment
		(start 427.655736 -362.80598)
		(end 427.798484 -362.820966)
		(width 0.1651)
		(layer "In5.Cu")
		(net "P5E_PEX3_STN4_RX_DP<71>")
	)
	(segment
		(start 420.365936 -378.470414)
		(end 420.365936 -369.408202)
		(width 0.1651)
		(layer "In5.Cu")
		(net "P5E_PEX3_STN4_RX_DP<71>")
	)
	(segment
		(start 430.134014 -318.9986)
		(end 430.179734 -318.95288)
		(width 0.1143)
		(layer "In5.Cu")
		(net "P5E_PEX3_STN4_RX_DP<71>")
	)
	(segment
		(start 430.134014 -323.765164)
		(end 430.134014 -319.027048)
		(width 0.1651)
		(layer "In5.Cu")
		(net "P5E_PEX3_STN4_RX_DP<71>")
	)
	(segment
		(start 430.179734 -318.95288)
		(end 430.179734 -316.914022)
		(width 0.1143)
		(layer "In5.Cu")
		(net "P5E_PEX3_STN4_RX_DP<71>")
	)
	(segment
		(start 430.134014 -319.027048)
		(end 430.134014 -318.9986)
		(width 0.1143)
		(layer "In5.Cu")
		(net "P5E_PEX3_STN4_RX_DP<71>")
	)
	(segment
		(start 419.48989 -378.629672)
		(end 419.663118 -378.8029)
		(width 0.1651)
		(layer "In5.Cu")
		(net "P5E_PEX3_STN4_RX_DP<71>")
	)
	(segment
		(start 430.179734 -316.914022)
		(end 430.065434 -316.799722)
		(width 0.1143)
		(layer "In5.Cu")
		(net "P5E_PEX3_STN4_RX_DP<71>")
	)
	(segment
		(start 423.346372 -366.27435)
		(end 423.73169 -365.962438)
		(width 0.1651)
		(layer "In5.Cu")
		(net "P5E_PEX3_STN4_RX_DP<71>")
	)
	(segment
		(start 432.903122 -358.69372)
		(end 432.903122 -342.107774)
		(width 0.1651)
		(layer "In5.Cu")
		(net "P5E_PEX3_STN4_RX_DP<71>")
	)
	(segment
		(start 423.329354 -366.434878)
		(end 423.346372 -366.27435)
		(width 0.1651)
		(layer "In5.Cu")
		(net "P5E_PEX3_STN4_RX_DP<71>")
	)
	(segment
		(start 427.270164 -363.117638)
		(end 427.655736 -362.80598)
		(width 0.1651)
		(layer "In5.Cu")
		(net "P5E_PEX3_STN4_RX_DP<71>")
	)
	(segment
		(start 428.584106 -362.055156)
		(end 428.726854 -362.070142)
		(width 0.1651)
		(layer "In5.Cu")
		(net "P5E_PEX3_STN4_RX_DP<71>")
	)
	(segment
		(start 424.679872 -365.195866)
		(end 424.8404 -365.212884)
		(width 0.1651)
		(layer "In5.Cu")
		(net "P5E_PEX3_STN4_RX_DP<71>")
	)
	(segment
		(start 422.380918 -367.201704)
		(end 422.397936 -367.040922)
		(width 0.1651)
		(layer "In5.Cu")
		(net "P5E_PEX3_STN4_RX_DP<71>")
	)
	(segment
		(start 424.294554 -365.507524)
		(end 424.679872 -365.195866)
		(width 0.1651)
		(layer "In5.Cu")
		(net "P5E_PEX3_STN4_RX_DP<71>")
	)
	(segment
		(start 425.381166 -323.252846)
		(end 425.38142 -323.25183)
		(width 0.1651)
		(layer "In5.Cu")
		(net "P5E_PEX3_STN4_RX_DP<75>")
	)
	(segment
		(start 423.365676 -391.71499)
		(end 422.928288 -391.481564)
		(width 0.1651)
		(layer "In5.Cu")
		(net "P5E_PEX3_STN4_RX_DP<75>")
	)
	(segment
		(start 425.38142 -323.25183)
		(end 425.38396 -323.242432)
		(width 0.1651)
		(layer "In5.Cu")
		(net "P5E_PEX3_STN4_RX_DP<75>")
	)
	(segment
		(start 420.467282 -358.82834)
		(end 420.467282 -341.864188)
		(width 0.1651)
		(layer "In5.Cu")
		(net "P5E_PEX3_STN4_RX_DP<75>")
	)
	(segment
		(start 429.16602 -395.532102)
		(end 429.019716 -394.877798)
		(width 0.1651)
		(layer "In5.Cu")
		(net "P5E_PEX3_STN4_RX_DP<75>")
	)
	(segment
		(start 425.42714 -392.815826)
		(end 424.990006 -392.582146)
		(width 0.1651)
		(layer "In5.Cu")
		(net "P5E_PEX3_STN4_RX_DP<75>")
	)
	(segment
		(start 423.485818 -391.678414)
		(end 423.365676 -391.71499)
		(width 0.1651)
		(layer "In5.Cu")
		(net "P5E_PEX3_STN4_RX_DP<75>")
	)
	(segment
		(start 428.322232 -394.260578)
		(end 425.547282 -392.77925)
		(width 0.1651)
		(layer "In5.Cu")
		(net "P5E_PEX3_STN4_RX_DP<75>")
	)
	(segment
		(start 428.833534 -404.802848)
		(end 429.16602 -404.470362)
		(width 0.1651)
		(layer "In5.Cu")
		(net "P5E_PEX3_STN4_RX_DP<75>")
	)
	(segment
		(start 422.928288 -391.481564)
		(end 422.891966 -391.361168)
		(width 0.1651)
		(layer "In5.Cu")
		(net "P5E_PEX3_STN4_RX_DP<75>")
	)
	(segment
		(start 429.16602 -404.470362)
		(end 429.16602 -395.532102)
		(width 0.1651)
		(layer "In5.Cu")
		(net "P5E_PEX3_STN4_RX_DP<75>")
	)
	(segment
		(start 425.547282 -392.77925)
		(end 425.42714 -392.815826)
		(width 0.1651)
		(layer "In5.Cu")
		(net "P5E_PEX3_STN4_RX_DP<75>")
	)
	(segment
		(start 416.011106 -387.022848)
		(end 415.007298 -384.5306)
		(width 0.1651)
		(layer "In5.Cu")
		(net "P5E_PEX3_STN4_RX_DP<75>")
	)
	(segment
		(start 428.289974 -404.62962)
		(end 428.463202 -404.802848)
		(width 0.1651)
		(layer "In5.Cu")
		(net "P5E_PEX3_STN4_RX_DP<75>")
	)
	(segment
		(start 425.42968 -316.455298)
		(end 425.655486 -316.229492)
		(width 0.1143)
		(layer "In5.Cu")
		(net "P5E_PEX3_STN4_RX_DP<75>")
	)
	(segment
		(start 428.289974 -404.290022)
		(end 428.289974 -404.62962)
		(width 0.1651)
		(layer "In5.Cu")
		(net "P5E_PEX3_STN4_RX_DP<75>")
	)
	(segment
		(start 422.891966 -391.361168)
		(end 417.48075 -388.472172)
		(width 0.1651)
		(layer "In5.Cu")
		(net "P5E_PEX3_STN4_RX_DP<75>")
	)
	(segment
		(start 425.655486 -316.229492)
		(end 425.88561 -316.229492)
		(width 0.1143)
		(layer "In5.Cu")
		(net "P5E_PEX3_STN4_RX_DP<75>")
	)
	(segment
		(start 423.922698 -391.911586)
		(end 423.485818 -391.678414)
		(width 0.1651)
		(layer "In5.Cu")
		(net "P5E_PEX3_STN4_RX_DP<75>")
	)
	(segment
		(start 415.007298 -384.5306)
		(end 415.007044 -384.5306)
		(width 0.1651)
		(layer "In5.Cu")
		(net "P5E_PEX3_STN4_RX_DP<75>")
	)
	(segment
		(start 420.467282 -341.864188)
		(end 425.381166 -323.252846)
		(width 0.1651)
		(layer "In5.Cu")
		(net "P5E_PEX3_STN4_RX_DP<75>")
	)
	(segment
		(start 425.38396 -319.9384)
		(end 425.38396 -319.909952)
		(width 0.1143)
		(layer "In5.Cu")
		(net "P5E_PEX3_STN4_RX_DP<75>")
	)
	(segment
		(start 424.990006 -392.582146)
		(end 424.95343 -392.462004)
		(width 0.1651)
		(layer "In5.Cu")
		(net "P5E_PEX3_STN4_RX_DP<75>")
	)
	(segment
		(start 425.99991 -316.115192)
		(end 425.99991 -315.849762)
		(width 0.1143)
		(layer "In5.Cu")
		(net "P5E_PEX3_STN4_RX_DP<75>")
	)
	(segment
		(start 415.228024 -368.269774)
		(end 420.467282 -358.82834)
		(width 0.1651)
		(layer "In5.Cu")
		(net "P5E_PEX3_STN4_RX_DP<75>")
	)
	(segment
		(start 423.959274 -392.031728)
		(end 423.922698 -391.911586)
		(width 0.1651)
		(layer "In5.Cu")
		(net "P5E_PEX3_STN4_RX_DP<75>")
	)
	(segment
		(start 428.463202 -404.802848)
		(end 428.833534 -404.802848)
		(width 0.1651)
		(layer "In5.Cu")
		(net "P5E_PEX3_STN4_RX_DP<75>")
	)
	(segment
		(start 424.51655 -392.228832)
		(end 424.396408 -392.265408)
		(width 0.1651)
		(layer "In5.Cu")
		(net "P5E_PEX3_STN4_RX_DP<75>")
	)
	(segment
		(start 424.396408 -392.265408)
		(end 423.959274 -392.031728)
		(width 0.1651)
		(layer "In5.Cu")
		(net "P5E_PEX3_STN4_RX_DP<75>")
	)
	(segment
		(start 417.48075 -388.472172)
		(end 416.011106 -387.022848)
		(width 0.1651)
		(layer "In5.Cu")
		(net "P5E_PEX3_STN4_RX_DP<75>")
	)
	(segment
		(start 425.42968 -319.864232)
		(end 425.42968 -316.455298)
		(width 0.1143)
		(layer "In5.Cu")
		(net "P5E_PEX3_STN4_RX_DP<75>")
	)
	(segment
		(start 415.007044 -384.5306)
		(end 414.986724 -384.479546)
		(width 0.1651)
		(layer "In5.Cu")
		(net "P5E_PEX3_STN4_RX_DP<75>")
	)
	(segment
		(start 425.38396 -319.909952)
		(end 425.42968 -319.864232)
		(width 0.1143)
		(layer "In5.Cu")
		(net "P5E_PEX3_STN4_RX_DP<75>")
	)
	(segment
		(start 425.88561 -316.229492)
		(end 425.99991 -316.115192)
		(width 0.1143)
		(layer "In5.Cu")
		(net "P5E_PEX3_STN4_RX_DP<75>")
	)
	(segment
		(start 429.019716 -394.877798)
		(end 428.322232 -394.260578)
		(width 0.1651)
		(layer "In5.Cu")
		(net "P5E_PEX3_STN4_RX_DP<75>")
	)
	(segment
		(start 414.986724 -384.479546)
		(end 415.028634 -369.274344)
		(width 0.1651)
		(layer "In5.Cu")
		(net "P5E_PEX3_STN4_RX_DP<75>")
	)
	(segment
		(start 425.38396 -323.242432)
		(end 425.38396 -319.9384)
		(width 0.1651)
		(layer "In5.Cu")
		(net "P5E_PEX3_STN4_RX_DP<75>")
	)
	(segment
		(start 415.028634 -369.274344)
		(end 415.228024 -368.269774)
		(width 0.1651)
		(layer "In5.Cu")
		(net "P5E_PEX3_STN4_RX_DP<75>")
	)
	(segment
		(start 424.95343 -392.462004)
		(end 424.51655 -392.228832)
		(width 0.1651)
		(layer "In5.Cu")
		(net "P5E_PEX3_STN4_RX_DP<75>")
	)
	(segment
		(start 159.599884 -293.04996)
		(end 159.124904 -292.57498)
		(width 0.13208)
		(layer "F.Cu")
		(net "SPI_PEX1_SDIO3")
	)
	(via
		(at 159.124904 -292.57498)
		(size 0.4064)
		(drill 0.2032)
		(layers "F.Cu" "B.Cu")
		(net "SPI_PEX1_SDIO3")
	)
	(via
		(at 155.800044 -290.42106)
		(size 0.6604)
		(drill 0.3302)
		(layers "F.Cu" "B.Cu")
		(net "SPI_PEX1_SDIO3")
	)
	(segment
		(start 156.56687 -291.187886)
		(end 155.800044 -290.42106)
		(width 0.13208)
		(layer "B.Cu")
		(net "SPI_PEX1_SDIO3")
	)
	(segment
		(start 158.594552 -292.044628)
		(end 158.008828 -292.044628)
		(width 0.13208)
		(layer "B.Cu")
		(net "SPI_PEX1_SDIO3")
	)
	(segment
		(start 157.71495 -291.75075)
		(end 157.71495 -291.378132)
		(width 0.13208)
		(layer "B.Cu")
		(net "SPI_PEX1_SDIO3")
	)
	(segment
		(start 157.524704 -291.187886)
		(end 156.56687 -291.187886)
		(width 0.13208)
		(layer "B.Cu")
		(net "SPI_PEX1_SDIO3")
	)
	(segment
		(start 159.124904 -292.57498)
		(end 158.594552 -292.044628)
		(width 0.13208)
		(layer "B.Cu")
		(net "SPI_PEX1_SDIO3")
	)
	(segment
		(start 158.008828 -292.044628)
		(end 157.71495 -291.75075)
		(width 0.13208)
		(layer "B.Cu")
		(net "SPI_PEX1_SDIO3")
	)
	(segment
		(start 157.71495 -291.378132)
		(end 157.524704 -291.187886)
		(width 0.13208)
		(layer "B.Cu")
		(net "SPI_PEX1_SDIO3")
	)
	(segment
		(start 155.800044 -290.42106)
		(end 155.800044 -289.174936)
		(width 0.13208)
		(layer "B.Cu")
		(net "SPI_PEX1_SDIO3")
	)
	(segment
		(start 419.19144 -344.538554)
		(end 419.19144 -345.171014)
		(width 0.13462)
		(layer "F.Cu")
		(net "P5E_PEX3_STN4_TX_C_DN<75>")
	)
	(segment
		(start 419.19144 -345.171014)
		(end 419.485572 -345.465146)
		(width 0.13462)
		(layer "F.Cu")
		(net "P5E_PEX3_STN4_TX_C_DN<75>")
	)
	(segment
		(start 419.510972 -344.219022)
		(end 419.19144 -344.538554)
		(width 0.13462)
		(layer "F.Cu")
		(net "P5E_PEX3_STN4_TX_C_DN<75>")
	)
	(segment
		(start 428.96409 -397.281146)
		(end 429.415956 -396.82928)
		(width 0.1651)
		(layer "In7.Cu")
		(net "P5E_PEX3_STN4_TX_C_DN<75>")
	)
	(segment
		(start 417.640262 -358.752648)
		(end 417.640262 -347.881194)
		(width 0.1651)
		(layer "In7.Cu")
		(net "P5E_PEX3_STN4_TX_C_DN<75>")
	)
	(segment
		(start 417.640262 -347.881194)
		(end 419.194742 -346.326714)
		(width 0.1651)
		(layer "In7.Cu")
		(net "P5E_PEX3_STN4_TX_C_DN<75>")
	)
	(segment
		(start 419.194742 -346.326714)
		(end 419.194742 -345.755976)
		(width 0.1651)
		(layer "In7.Cu")
		(net "P5E_PEX3_STN4_TX_C_DN<75>")
	)
	(segment
		(start 417.078668 -387.58241)
		(end 415.65322 -385.7371)
		(width 0.1651)
		(layer "In7.Cu")
		(net "P5E_PEX3_STN4_TX_C_DN<75>")
	)
	(segment
		(start 428.416974 -397.281146)
		(end 428.96409 -397.281146)
		(width 0.1651)
		(layer "In7.Cu")
		(net "P5E_PEX3_STN4_TX_C_DN<75>")
	)
	(segment
		(start 415.39668 -369.24488)
		(end 417.640262 -358.752648)
		(width 0.1651)
		(layer "In7.Cu")
		(net "P5E_PEX3_STN4_TX_C_DN<75>")
	)
	(segment
		(start 428.63516 -393.9667)
		(end 417.078668 -387.58241)
		(width 0.1651)
		(layer "In7.Cu")
		(net "P5E_PEX3_STN4_TX_C_DN<75>")
	)
	(segment
		(start 429.415956 -396.82928)
		(end 429.415956 -394.747496)
		(width 0.1651)
		(layer "In7.Cu")
		(net "P5E_PEX3_STN4_TX_C_DN<75>")
	)
	(segment
		(start 419.194742 -345.755976)
		(end 419.485572 -345.465146)
		(width 0.1651)
		(layer "In7.Cu")
		(net "P5E_PEX3_STN4_TX_C_DN<75>")
	)
	(segment
		(start 415.65322 -385.7371)
		(end 415.01822 -383.53746)
		(width 0.1651)
		(layer "In7.Cu")
		(net "P5E_PEX3_STN4_TX_C_DN<75>")
	)
	(segment
		(start 428.289974 -397.408146)
		(end 428.416974 -397.281146)
		(width 0.1651)
		(layer "In7.Cu")
		(net "P5E_PEX3_STN4_TX_C_DN<75>")
	)
	(segment
		(start 428.289974 -397.790162)
		(end 428.289974 -397.408146)
		(width 0.1651)
		(layer "In7.Cu")
		(net "P5E_PEX3_STN4_TX_C_DN<75>")
	)
	(segment
		(start 415.01822 -383.53746)
		(end 415.39668 -369.24488)
		(width 0.1651)
		(layer "In7.Cu")
		(net "P5E_PEX3_STN4_TX_C_DN<75>")
	)
	(segment
		(start 429.415956 -394.747496)
		(end 428.63516 -393.9667)
		(width 0.1651)
		(layer "In7.Cu")
		(net "P5E_PEX3_STN4_TX_C_DN<75>")
	)
	(segment
		(start 158.649924 -294.94988)
		(end 158.174944 -294.4749)
		(width 0.13208)
		(layer "F.Cu")
		(net "SPI_PEX1_SDIO0")
	)
	(via
		(at 158.174944 -294.4749)
		(size 0.508)
		(drill 0.254)
		(layers "F.Cu" "B.Cu")
		(net "SPI_PEX1_SDIO0")
	)
	(segment
		(start 157.483556 -295.79824)
		(end 156.673804 -295.79824)
		(width 0.13208)
		(layer "B.Cu")
		(net "SPI_PEX1_SDIO0")
	)
	(segment
		(start 158.174944 -294.4749)
		(end 158.174944 -295.106852)
		(width 0.13208)
		(layer "B.Cu")
		(net "SPI_PEX1_SDIO0")
	)
	(segment
		(start 158.174944 -295.106852)
		(end 157.483556 -295.79824)
		(width 0.13208)
		(layer "B.Cu")
		(net "SPI_PEX1_SDIO0")
	)
	(segment
		(start 446.451482 -317.279782)
		(end 446.451482 -322.22567)
		(width 0.1651)
		(layer "In5.Cu")
		(net "P5E_PEX3_STN4_RX_DN<65>")
	)
	(segment
		(start 433.787042 -305.733958)
		(end 435.696868 -306.525168)
		(width 0.1651)
		(layer "In5.Cu")
		(net "P5E_PEX3_STN4_RX_DN<65>")
	)
	(segment
		(start 434.332888 -368.571526)
		(end 433.847748 -369.742974)
		(width 0.1651)
		(layer "In5.Cu")
		(net "P5E_PEX3_STN4_RX_DN<65>")
	)
	(segment
		(start 445.449706 -358.710484)
		(end 444.022734 -361.51312)
		(width 0.1651)
		(layer "In5.Cu")
		(net "P5E_PEX3_STN4_RX_DN<65>")
	)
	(segment
		(start 432.009296 -305.733958)
		(end 433.787042 -305.733958)
		(width 0.1651)
		(layer "In5.Cu")
		(net "P5E_PEX3_STN4_RX_DN<65>")
	)
	(segment
		(start 431.935128 -305.779678)
		(end 431.980848 -305.733958)
		(width 0.1143)
		(layer "In5.Cu")
		(net "P5E_PEX3_STN4_RX_DN<65>")
	)
	(segment
		(start 428.58436 -305.399948)
		(end 428.47006 -305.514248)
		(width 0.1143)
		(layer "In5.Cu")
		(net "P5E_PEX3_STN4_RX_DN<65>")
	)
	(segment
		(start 432.689762 -379.258068)
		(end 432.689762 -379.590046)
		(width 0.1651)
		(layer "In5.Cu")
		(net "P5E_PEX3_STN4_RX_DN<65>")
	)
	(segment
		(start 439.779664 -364.781338)
		(end 434.70068 -368.203734)
		(width 0.1651)
		(layer "In5.Cu")
		(net "P5E_PEX3_STN4_RX_DN<65>")
	)
	(segment
		(start 428.47006 -305.514248)
		(end 428.47006 -305.665378)
		(width 0.1143)
		(layer "In5.Cu")
		(net "P5E_PEX3_STN4_RX_DN<65>")
	)
	(segment
		(start 428.47006 -305.665378)
		(end 428.58436 -305.779678)
		(width 0.1143)
		(layer "In5.Cu")
		(net "P5E_PEX3_STN4_RX_DN<65>")
	)
	(segment
		(start 432.86299 -379.08484)
		(end 432.689762 -379.258068)
		(width 0.1651)
		(layer "In5.Cu")
		(net "P5E_PEX3_STN4_RX_DN<65>")
	)
	(segment
		(start 434.70068 -368.203734)
		(end 434.332888 -368.571526)
		(width 0.1651)
		(layer "In5.Cu")
		(net "P5E_PEX3_STN4_RX_DN<65>")
	)
	(segment
		(start 433.847748 -378.587254)
		(end 433.350162 -379.08484)
		(width 0.1651)
		(layer "In5.Cu")
		(net "P5E_PEX3_STN4_RX_DN<65>")
	)
	(segment
		(start 431.980848 -305.733958)
		(end 432.009296 -305.733958)
		(width 0.1143)
		(layer "In5.Cu")
		(net "P5E_PEX3_STN4_RX_DN<65>")
	)
	(segment
		(start 433.350162 -379.08484)
		(end 432.86299 -379.08484)
		(width 0.1651)
		(layer "In5.Cu")
		(net "P5E_PEX3_STN4_RX_DN<65>")
	)
	(segment
		(start 428.84979 -305.399948)
		(end 428.58436 -305.399948)
		(width 0.1143)
		(layer "In5.Cu")
		(net "P5E_PEX3_STN4_RX_DN<65>")
	)
	(segment
		(start 435.696868 -306.525168)
		(end 446.451482 -317.279782)
		(width 0.1651)
		(layer "In5.Cu")
		(net "P5E_PEX3_STN4_RX_DN<65>")
	)
	(segment
		(start 446.451482 -322.22567)
		(end 445.449706 -358.710484)
		(width 0.1651)
		(layer "In5.Cu")
		(net "P5E_PEX3_STN4_RX_DN<65>")
	)
	(segment
		(start 444.022734 -361.51312)
		(end 439.779664 -364.781338)
		(width 0.1651)
		(layer "In5.Cu")
		(net "P5E_PEX3_STN4_RX_DN<65>")
	)
	(segment
		(start 428.58436 -305.779678)
		(end 431.935128 -305.779678)
		(width 0.1143)
		(layer "In5.Cu")
		(net "P5E_PEX3_STN4_RX_DN<65>")
	)
	(segment
		(start 433.847748 -369.742974)
		(end 433.847748 -378.587254)
		(width 0.1651)
		(layer "In5.Cu")
		(net "P5E_PEX3_STN4_RX_DN<65>")
	)
	(segment
		(start 159.599884 -293.99992)
		(end 159.124904 -293.52494)
		(width 0.13208)
		(layer "F.Cu")
		(net "SPI_PEX1_SDIO2")
	)
	(via
		(at 159.124904 -293.52494)
		(size 0.508)
		(drill 0.254)
		(layers "F.Cu" "B.Cu")
		(net "SPI_PEX1_SDIO2")
	)
	(segment
		(start 159.124904 -293.52494)
		(end 158.695644 -293.9542)
		(width 0.13208)
		(layer "B.Cu")
		(net "SPI_PEX1_SDIO2")
	)
	(segment
		(start 156.991558 -293.9542)
		(end 156.619194 -294.326564)
		(width 0.13208)
		(layer "B.Cu")
		(net "SPI_PEX1_SDIO2")
	)
	(segment
		(start 158.695644 -293.9542)
		(end 156.991558 -293.9542)
		(width 0.13208)
		(layer "B.Cu")
		(net "SPI_PEX1_SDIO2")
	)
	(segment
		(start 156.619194 -294.326564)
		(end 156.619194 -294.8051)
		(width 0.13208)
		(layer "B.Cu")
		(net "SPI_PEX1_SDIO2")
	)
	(segment
		(start 423.03573 -318.320166)
		(end 423.15003 -318.434466)
		(width 0.1143)
		(layer "In5.Cu")
		(net "P5E_PEX3_STN4_RX_DN<78>")
	)
	(segment
		(start 412.230062 -384.711956)
		(end 411.422342 -358.82834)
		(width 0.1651)
		(layer "In5.Cu")
		(net "P5E_PEX3_STN4_RX_DN<78>")
	)
	(segment
		(start 422.7703 -319.864232)
		(end 422.7703 -318.434466)
		(width 0.1143)
		(layer "In5.Cu")
		(net "P5E_PEX3_STN4_RX_DN<78>")
	)
	(segment
		(start 422.8846 -318.320166)
		(end 423.03573 -318.320166)
		(width 0.1143)
		(layer "In5.Cu")
		(net "P5E_PEX3_STN4_RX_DN<78>")
	)
	(segment
		(start 411.422342 -341.935054)
		(end 422.816274 -321.922902)
		(width 0.1651)
		(layer "In5.Cu")
		(net "P5E_PEX3_STN4_RX_DN<78>")
	)
	(segment
		(start 421.689784 -406.35809)
		(end 421.863012 -406.184862)
		(width 0.1651)
		(layer "In5.Cu")
		(net "P5E_PEX3_STN4_RX_DN<78>")
	)
	(segment
		(start 422.816274 -321.922902)
		(end 422.81602 -321.922648)
		(width 0.1651)
		(layer "In5.Cu")
		(net "P5E_PEX3_STN4_RX_DN<78>")
	)
	(segment
		(start 421.689784 -406.690068)
		(end 421.689784 -406.35809)
		(width 0.1651)
		(layer "In5.Cu")
		(net "P5E_PEX3_STN4_RX_DN<78>")
	)
	(segment
		(start 421.863012 -406.184862)
		(end 422.350184 -406.184862)
		(width 0.1651)
		(layer "In5.Cu")
		(net "P5E_PEX3_STN4_RX_DN<78>")
	)
	(segment
		(start 415.836354 -390.555734)
		(end 413.813752 -388.651242)
		(width 0.1651)
		(layer "In5.Cu")
		(net "P5E_PEX3_STN4_RX_DN<78>")
	)
	(segment
		(start 413.813752 -388.651242)
		(end 412.230062 -384.711956)
		(width 0.1651)
		(layer "In5.Cu")
		(net "P5E_PEX3_STN4_RX_DN<78>")
	)
	(segment
		(start 422.350184 -406.184862)
		(end 422.84777 -405.687276)
		(width 0.1651)
		(layer "In5.Cu")
		(net "P5E_PEX3_STN4_RX_DN<78>")
	)
	(segment
		(start 423.15003 -318.434466)
		(end 423.15003 -318.699896)
		(width 0.1143)
		(layer "In5.Cu")
		(net "P5E_PEX3_STN4_RX_DN<78>")
	)
	(segment
		(start 422.81602 -319.9384)
		(end 422.81602 -319.909952)
		(width 0.1143)
		(layer "In5.Cu")
		(net "P5E_PEX3_STN4_RX_DN<78>")
	)
	(segment
		(start 411.422342 -358.82834)
		(end 411.422342 -341.935054)
		(width 0.1651)
		(layer "In5.Cu")
		(net "P5E_PEX3_STN4_RX_DN<78>")
	)
	(segment
		(start 422.81602 -321.922648)
		(end 422.81602 -319.9384)
		(width 0.1651)
		(layer "In5.Cu")
		(net "P5E_PEX3_STN4_RX_DN<78>")
	)
	(segment
		(start 422.55821 -395.281404)
		(end 421.35298 -394.093954)
		(width 0.1651)
		(layer "In5.Cu")
		(net "P5E_PEX3_STN4_RX_DN<78>")
	)
	(segment
		(start 422.81602 -319.909952)
		(end 422.7703 -319.864232)
		(width 0.1143)
		(layer "In5.Cu")
		(net "P5E_PEX3_STN4_RX_DN<78>")
	)
	(segment
		(start 422.7703 -318.434466)
		(end 422.8846 -318.320166)
		(width 0.1143)
		(layer "In5.Cu")
		(net "P5E_PEX3_STN4_RX_DN<78>")
	)
	(segment
		(start 421.35298 -394.093954)
		(end 415.836354 -390.555734)
		(width 0.1651)
		(layer "In5.Cu")
		(net "P5E_PEX3_STN4_RX_DN<78>")
	)
	(segment
		(start 422.84777 -395.7955)
		(end 422.55821 -395.281404)
		(width 0.1651)
		(layer "In5.Cu")
		(net "P5E_PEX3_STN4_RX_DN<78>")
	)
	(segment
		(start 422.84777 -405.687276)
		(end 422.84777 -395.7955)
		(width 0.1651)
		(layer "In5.Cu")
		(net "P5E_PEX3_STN4_RX_DN<78>")
	)
	(segment
		(start 129.094992 -221.221554)
		(end 129.094992 -221.823026)
		(width 0.13208)
		(layer "F.Cu")
		(net "SPI_PEX1_CLK_MUX_R")
	)
	(segment
		(start 130.922776 -221.05493)
		(end 129.261616 -221.05493)
		(width 0.13208)
		(layer "F.Cu")
		(net "SPI_PEX1_CLK_MUX_R")
	)
	(segment
		(start 129.261616 -221.05493)
		(end 129.094992 -221.221554)
		(width 0.13208)
		(layer "F.Cu")
		(net "SPI_PEX1_CLK_MUX_R")
	)
	(via
		(at 129.094992 -221.823026)
		(size 0.508)
		(drill 0.254)
		(layers "F.Cu" "B.Cu")
		(net "SPI_PEX1_CLK_MUX_R")
	)
	(segment
		(start 129.67716 -221.240858)
		(end 129.094992 -221.823026)
		(width 0.13208)
		(layer "B.Cu")
		(net "SPI_PEX1_CLK_MUX_R")
	)
	(segment
		(start 131.075176 -221.240858)
		(end 129.67716 -221.240858)
		(width 0.13208)
		(layer "B.Cu")
		(net "SPI_PEX1_CLK_MUX_R")
	)
	(segment
		(start 447.12509 -316.98311)
		(end 436.057548 -305.915568)
		(width 0.1651)
		(layer "In5.Cu")
		(net "P5E_PEX3_STN4_RX_DP<64>")
	)
	(segment
		(start 441.915804 -364.354618)
		(end 441.9346 -364.193836)
		(width 0.1651)
		(layer "In5.Cu")
		(net "P5E_PEX3_STN4_RX_DP<64>")
	)
	(segment
		(start 442.890402 -363.43717)
		(end 443.279022 -363.129322)
		(width 0.1651)
		(layer "In5.Cu")
		(net "P5E_PEX3_STN4_RX_DP<64>")
	)
	(segment
		(start 442.871606 -363.597698)
		(end 442.890402 -363.43717)
		(width 0.1651)
		(layer "In5.Cu")
		(net "P5E_PEX3_STN4_RX_DP<64>")
	)
	(segment
		(start 437.987694 -367.112296)
		(end 438.021222 -366.954054)
		(width 0.1651)
		(layer "In5.Cu")
		(net "P5E_PEX3_STN4_RX_DP<64>")
	)
	(segment
		(start 443.279022 -363.129322)
		(end 443.43955 -363.148118)
		(width 0.1651)
		(layer "In5.Cu")
		(net "P5E_PEX3_STN4_RX_DP<64>")
	)
	(segment
		(start 446.12814 -358.88422)
		(end 446.12814 -358.72801)
		(width 0.1651)
		(layer "In5.Cu")
		(net "P5E_PEX3_STN4_RX_DP<64>")
	)
	(segment
		(start 435.765956 -368.933984)
		(end 436.5498 -368.046)
		(width 0.1651)
		(layer "In5.Cu")
		(net "P5E_PEX3_STN4_RX_DP<64>")
	)
	(segment
		(start 430.179734 -304.794158)
		(end 430.179734 -304.564034)
		(width 0.1143)
		(layer "In5.Cu")
		(net "P5E_PEX3_STN4_RX_DP<64>")
	)
	(segment
		(start 439.459624 -366.020096)
		(end 439.617612 -366.053878)
		(width 0.1651)
		(layer "In5.Cu")
		(net "P5E_PEX3_STN4_RX_DP<64>")
	)
	(segment
		(start 430.065434 -304.449734)
		(end 429.800004 -304.449734)
		(width 0.1143)
		(layer "In5.Cu")
		(net "P5E_PEX3_STN4_RX_DP<64>")
	)
	(segment
		(start 431.942748 -305.019964)
		(end 430.40554 -305.019964)
		(width 0.1143)
		(layer "In5.Cu")
		(net "P5E_PEX3_STN4_RX_DP<64>")
	)
	(segment
		(start 430.40554 -305.019964)
		(end 430.179734 -304.794158)
		(width 0.1143)
		(layer "In5.Cu")
		(net "P5E_PEX3_STN4_RX_DP<64>")
	)
	(segment
		(start 441.9346 -364.193836)
		(end 442.322966 -363.886242)
		(width 0.1651)
		(layer "In5.Cu")
		(net "P5E_PEX3_STN4_RX_DP<64>")
	)
	(segment
		(start 447.12509 -322.423536)
		(end 447.12509 -316.98311)
		(width 0.1651)
		(layer "In5.Cu")
		(net "P5E_PEX3_STN4_RX_DP<64>")
	)
	(segment
		(start 435.765956 -379.570488)
		(end 435.765956 -368.933984)
		(width 0.1651)
		(layer "In5.Cu")
		(net "P5E_PEX3_STN4_RX_DP<64>")
	)
	(segment
		(start 436.057548 -305.915568)
		(end 434.00599 -305.065684)
		(width 0.1651)
		(layer "In5.Cu")
		(net "P5E_PEX3_STN4_RX_DP<64>")
	)
	(segment
		(start 439.043826 -366.290098)
		(end 439.459624 -366.020096)
		(width 0.1651)
		(layer "In5.Cu")
		(net "P5E_PEX3_STN4_RX_DP<64>")
	)
	(segment
		(start 437.572404 -367.38179)
		(end 437.987694 -367.112296)
		(width 0.1651)
		(layer "In5.Cu")
		(net "P5E_PEX3_STN4_RX_DP<64>")
	)
	(segment
		(start 438.595008 -366.717834)
		(end 439.010298 -366.44834)
		(width 0.1651)
		(layer "In5.Cu")
		(net "P5E_PEX3_STN4_RX_DP<64>")
	)
	(segment
		(start 446.12814 -358.72801)
		(end 447.12509 -322.423536)
		(width 0.1651)
		(layer "In5.Cu")
		(net "P5E_PEX3_STN4_RX_DP<64>")
	)
	(segment
		(start 442.483494 -363.905038)
		(end 442.871606 -363.597698)
		(width 0.1651)
		(layer "In5.Cu")
		(net "P5E_PEX3_STN4_RX_DP<64>")
	)
	(segment
		(start 438.021222 -366.954054)
		(end 438.43702 -366.684052)
		(width 0.1651)
		(layer "In5.Cu")
		(net "P5E_PEX3_STN4_RX_DP<64>")
	)
	(segment
		(start 435.43347 -379.902974)
		(end 435.765956 -379.570488)
		(width 0.1651)
		(layer "In5.Cu")
		(net "P5E_PEX3_STN4_RX_DP<64>")
	)
	(segment
		(start 440.4614 -365.506)
		(end 441.915804 -364.354618)
		(width 0.1651)
		(layer "In5.Cu")
		(net "P5E_PEX3_STN4_RX_DP<64>")
	)
	(segment
		(start 435.063138 -379.902974)
		(end 435.43347 -379.902974)
		(width 0.1651)
		(layer "In5.Cu")
		(net "P5E_PEX3_STN4_RX_DP<64>")
	)
	(segment
		(start 437.414416 -367.348262)
		(end 437.572404 -367.38179)
		(width 0.1651)
		(layer "In5.Cu")
		(net "P5E_PEX3_STN4_RX_DP<64>")
	)
	(segment
		(start 439.617612 -366.053878)
		(end 440.4614 -365.506)
		(width 0.1651)
		(layer "In5.Cu")
		(net "P5E_PEX3_STN4_RX_DP<64>")
	)
	(segment
		(start 430.179734 -304.564034)
		(end 430.065434 -304.449734)
		(width 0.1143)
		(layer "In5.Cu")
		(net "P5E_PEX3_STN4_RX_DP<64>")
	)
	(segment
		(start 434.00599 -305.065684)
		(end 432.016916 -305.065684)
		(width 0.1651)
		(layer "In5.Cu")
		(net "P5E_PEX3_STN4_RX_DP<64>")
	)
	(segment
		(start 444.811658 -362.06176)
		(end 446.12814 -358.88422)
		(width 0.1651)
		(layer "In5.Cu")
		(net "P5E_PEX3_STN4_RX_DP<64>")
	)
	(segment
		(start 431.988468 -305.065684)
		(end 431.942748 -305.019964)
		(width 0.1143)
		(layer "In5.Cu")
		(net "P5E_PEX3_STN4_RX_DP<64>")
	)
	(segment
		(start 436.998618 -367.618264)
		(end 437.414416 -367.348262)
		(width 0.1651)
		(layer "In5.Cu")
		(net "P5E_PEX3_STN4_RX_DP<64>")
	)
	(segment
		(start 442.322966 -363.886242)
		(end 442.483494 -363.905038)
		(width 0.1651)
		(layer "In5.Cu")
		(net "P5E_PEX3_STN4_RX_DP<64>")
	)
	(segment
		(start 443.43955 -363.148118)
		(end 444.811658 -362.06176)
		(width 0.1651)
		(layer "In5.Cu")
		(net "P5E_PEX3_STN4_RX_DP<64>")
	)
	(segment
		(start 434.88991 -379.729746)
		(end 435.063138 -379.902974)
		(width 0.1651)
		(layer "In5.Cu")
		(net "P5E_PEX3_STN4_RX_DP<64>")
	)
	(segment
		(start 439.010298 -366.44834)
		(end 439.043826 -366.290098)
		(width 0.1651)
		(layer "In5.Cu")
		(net "P5E_PEX3_STN4_RX_DP<64>")
	)
	(segment
		(start 436.5498 -368.046)
		(end 436.96509 -367.776506)
		(width 0.1651)
		(layer "In5.Cu")
		(net "P5E_PEX3_STN4_RX_DP<64>")
	)
	(segment
		(start 438.43702 -366.684052)
		(end 438.595008 -366.717834)
		(width 0.1651)
		(layer "In5.Cu")
		(net "P5E_PEX3_STN4_RX_DP<64>")
	)
	(segment
		(start 436.96509 -367.776506)
		(end 436.998618 -367.618264)
		(width 0.1651)
		(layer "In5.Cu")
		(net "P5E_PEX3_STN4_RX_DP<64>")
	)
	(segment
		(start 434.88991 -379.390148)
		(end 434.88991 -379.729746)
		(width 0.1651)
		(layer "In5.Cu")
		(net "P5E_PEX3_STN4_RX_DP<64>")
	)
	(segment
		(start 432.016916 -305.065684)
		(end 431.988468 -305.065684)
		(width 0.1143)
		(layer "In5.Cu")
		(net "P5E_PEX3_STN4_RX_DP<64>")
	)
	(segment
		(start 159.599884 -294.94988)
		(end 159.124904 -294.4749)
		(width 0.13208)
		(layer "F.Cu")
		(net "SPI_PEX1_SDIO1")
	)
	(via
		(at 159.124904 -294.4749)
		(size 0.4064)
		(drill 0.2032)
		(layers "F.Cu" "B.Cu")
		(net "SPI_PEX1_SDIO1")
	)
	(via
		(at 158.649924 -295.89984)
		(size 0.6604)
		(drill 0.3302)
		(layers "F.Cu" "B.Cu")
		(net "SPI_PEX1_SDIO1")
	)
	(segment
		(start 157.98292 -295.89984)
		(end 156.93136 -296.9514)
		(width 0.13208)
		(layer "B.Cu")
		(net "SPI_PEX1_SDIO1")
	)
	(segment
		(start 159.124904 -295.42486)
		(end 159.124904 -294.4749)
		(width 0.13208)
		(layer "B.Cu")
		(net "SPI_PEX1_SDIO1")
	)
	(segment
		(start 158.649924 -295.89984)
		(end 157.98292 -295.89984)
		(width 0.13208)
		(layer "B.Cu")
		(net "SPI_PEX1_SDIO1")
	)
	(segment
		(start 158.649924 -295.89984)
		(end 159.124904 -295.42486)
		(width 0.13208)
		(layer "B.Cu")
		(net "SPI_PEX1_SDIO1")
	)
	(segment
		(start 156.93136 -296.9514)
		(end 156.673804 -296.9514)
		(width 0.13208)
		(layer "B.Cu")
		(net "SPI_PEX1_SDIO1")
	)
	(segment
		(start 429.800004 -308.249828)
		(end 430.065434 -308.249828)
		(width 0.1143)
		(layer "In5.Cu")
		(net "P5E_PEX3_STN4_RX_DP<68>")
	)
	(segment
		(start 442.111384 -358.125522)
		(end 441.933838 -358.542844)
		(width 0.1651)
		(layer "In5.Cu")
		(net "P5E_PEX3_STN4_RX_DP<68>")
	)
	(segment
		(start 437.865012 -361.152186)
		(end 437.453278 -361.42803)
		(width 0.1651)
		(layer "In5.Cu")
		(net "P5E_PEX3_STN4_RX_DP<68>")
	)
	(segment
		(start 431.988976 -308.865778)
		(end 433.143152 -308.865778)
		(width 0.1651)
		(layer "In5.Cu")
		(net "P5E_PEX3_STN4_RX_DP<68>")
	)
	(segment
		(start 431.960528 -308.865778)
		(end 431.988976 -308.865778)
		(width 0.1143)
		(layer "In5.Cu")
		(net "P5E_PEX3_STN4_RX_DP<68>")
	)
	(segment
		(start 432.335686 -364.857284)
		(end 431.923952 -365.133382)
		(width 0.1651)
		(layer "In5.Cu")
		(net "P5E_PEX3_STN4_RX_DP<68>")
	)
	(segment
		(start 431.914808 -308.820058)
		(end 431.960528 -308.865778)
		(width 0.1143)
		(layer "In5.Cu")
		(net "P5E_PEX3_STN4_RX_DP<68>")
	)
	(segment
		(start 432.923696 -364.520734)
		(end 432.905408 -364.612936)
		(width 0.1651)
		(layer "In5.Cu")
		(net "P5E_PEX3_STN4_RX_DP<68>")
	)
	(segment
		(start 443.27826 -321.715892)
		(end 442.289692 -357.707184)
		(width 0.1651)
		(layer "In5.Cu")
		(net "P5E_PEX3_STN4_RX_DP<68>")
	)
	(segment
		(start 441.77712 -358.702356)
		(end 441.140596 -359.094786)
		(width 0.1651)
		(layer "In5.Cu")
		(net "P5E_PEX3_STN4_RX_DP<68>")
	)
	(segment
		(start 433.143152 -308.865778)
		(end 434.04155 -309.764176)
		(width 0.1651)
		(layer "In5.Cu")
		(net "P5E_PEX3_STN4_RX_DP<68>")
	)
	(segment
		(start 438.46623 -360.749342)
		(end 438.434734 -360.907838)
		(width 0.1651)
		(layer "In5.Cu")
		(net "P5E_PEX3_STN4_RX_DP<68>")
	)
	(segment
		(start 430.468278 -366.246156)
		(end 430.309528 -366.214914)
		(width 0.1651)
		(layer "In5.Cu")
		(net "P5E_PEX3_STN4_RX_DP<68>")
	)
	(segment
		(start 437.421782 -361.586526)
		(end 433.507134 -364.209584)
		(width 0.1651)
		(layer "In5.Cu")
		(net "P5E_PEX3_STN4_RX_DP<68>")
	)
	(segment
		(start 438.877964 -360.473244)
		(end 438.46623 -360.749342)
		(width 0.1651)
		(layer "In5.Cu")
		(net "P5E_PEX3_STN4_RX_DP<68>")
	)
	(segment
		(start 438.434734 -360.907838)
		(end 438.023508 -361.183428)
		(width 0.1651)
		(layer "In5.Cu")
		(net "P5E_PEX3_STN4_RX_DP<68>")
	)
	(segment
		(start 438.729374 -315.056774)
		(end 439.566304 -315.403484)
		(width 0.1651)
		(layer "In5.Cu")
		(net "P5E_PEX3_STN4_RX_DP<68>")
	)
	(segment
		(start 433.414932 -364.191296)
		(end 432.923696 -364.520734)
		(width 0.1651)
		(layer "In5.Cu")
		(net "P5E_PEX3_STN4_RX_DP<68>")
	)
	(segment
		(start 430.065434 -308.249828)
		(end 430.179734 -308.364128)
		(width 0.1143)
		(layer "In5.Cu")
		(net "P5E_PEX3_STN4_RX_DP<68>")
	)
	(segment
		(start 433.507134 -364.209584)
		(end 433.414932 -364.191296)
		(width 0.1651)
		(layer "In5.Cu")
		(net "P5E_PEX3_STN4_RX_DP<68>")
	)
	(segment
		(start 437.453278 -361.42803)
		(end 437.421782 -361.586526)
		(width 0.1651)
		(layer "In5.Cu")
		(net "P5E_PEX3_STN4_RX_DP<68>")
	)
	(segment
		(start 441.140596 -359.094786)
		(end 439.03646 -360.50474)
		(width 0.1651)
		(layer "In5.Cu")
		(net "P5E_PEX3_STN4_RX_DP<68>")
	)
	(segment
		(start 432.494182 -364.888526)
		(end 432.335686 -364.857284)
		(width 0.1651)
		(layer "In5.Cu")
		(net "P5E_PEX3_STN4_RX_DP<68>")
	)
	(segment
		(start 427.89602 -367.9698)
		(end 427.266862 -368.598958)
		(width 0.1651)
		(layer "In5.Cu")
		(net "P5E_PEX3_STN4_RX_DP<68>")
	)
	(segment
		(start 426.633386 -379.902974)
		(end 426.263054 -379.902974)
		(width 0.1651)
		(layer "In5.Cu")
		(net "P5E_PEX3_STN4_RX_DP<68>")
	)
	(segment
		(start 426.965872 -369.325652)
		(end 426.965872 -379.570488)
		(width 0.1651)
		(layer "In5.Cu")
		(net "P5E_PEX3_STN4_RX_DP<68>")
	)
	(segment
		(start 430.40554 -308.820058)
		(end 431.914808 -308.820058)
		(width 0.1143)
		(layer "In5.Cu")
		(net "P5E_PEX3_STN4_RX_DP<68>")
	)
	(segment
		(start 427.266862 -368.598958)
		(end 426.965872 -369.325652)
		(width 0.1651)
		(layer "In5.Cu")
		(net "P5E_PEX3_STN4_RX_DP<68>")
	)
	(segment
		(start 426.089826 -379.729746)
		(end 426.089826 -379.390148)
		(width 0.1651)
		(layer "In5.Cu")
		(net "P5E_PEX3_STN4_RX_DP<68>")
	)
	(segment
		(start 429.866552 -366.649508)
		(end 427.89602 -367.9698)
		(width 0.1651)
		(layer "In5.Cu")
		(net "P5E_PEX3_STN4_RX_DP<68>")
	)
	(segment
		(start 438.023508 -361.183428)
		(end 437.865012 -361.152186)
		(width 0.1651)
		(layer "In5.Cu")
		(net "P5E_PEX3_STN4_RX_DP<68>")
	)
	(segment
		(start 430.879504 -365.970566)
		(end 430.468278 -366.246156)
		(width 0.1651)
		(layer "In5.Cu")
		(net "P5E_PEX3_STN4_RX_DP<68>")
	)
	(segment
		(start 430.911 -365.81207)
		(end 430.879504 -365.970566)
		(width 0.1651)
		(layer "In5.Cu")
		(net "P5E_PEX3_STN4_RX_DP<68>")
	)
	(segment
		(start 439.566304 -315.403484)
		(end 443.27826 -319.11544)
		(width 0.1651)
		(layer "In5.Cu")
		(net "P5E_PEX3_STN4_RX_DP<68>")
	)
	(segment
		(start 441.933838 -358.542844)
		(end 441.77712 -358.702356)
		(width 0.1651)
		(layer "In5.Cu")
		(net "P5E_PEX3_STN4_RX_DP<68>")
	)
	(segment
		(start 439.03646 -360.50474)
		(end 438.877964 -360.473244)
		(width 0.1651)
		(layer "In5.Cu")
		(net "P5E_PEX3_STN4_RX_DP<68>")
	)
	(segment
		(start 443.27826 -319.11544)
		(end 443.27826 -321.715892)
		(width 0.1651)
		(layer "In5.Cu")
		(net "P5E_PEX3_STN4_RX_DP<68>")
	)
	(segment
		(start 430.179734 -308.594252)
		(end 430.40554 -308.820058)
		(width 0.1143)
		(layer "In5.Cu")
		(net "P5E_PEX3_STN4_RX_DP<68>")
	)
	(segment
		(start 442.111638 -358.125522)
		(end 442.111384 -358.125522)
		(width 0.1651)
		(layer "In5.Cu")
		(net "P5E_PEX3_STN4_RX_DP<68>")
	)
	(segment
		(start 430.179734 -308.364128)
		(end 430.179734 -308.594252)
		(width 0.1143)
		(layer "In5.Cu")
		(net "P5E_PEX3_STN4_RX_DP<68>")
	)
	(segment
		(start 431.892456 -365.291878)
		(end 431.48123 -365.567468)
		(width 0.1651)
		(layer "In5.Cu")
		(net "P5E_PEX3_STN4_RX_DP<68>")
	)
	(segment
		(start 431.923952 -365.133382)
		(end 431.892456 -365.291878)
		(width 0.1651)
		(layer "In5.Cu")
		(net "P5E_PEX3_STN4_RX_DP<68>")
	)
	(segment
		(start 434.469286 -310.796686)
		(end 438.729374 -315.056774)
		(width 0.1651)
		(layer "In5.Cu")
		(net "P5E_PEX3_STN4_RX_DP<68>")
	)
	(segment
		(start 430.309528 -366.214914)
		(end 429.897794 -366.490758)
		(width 0.1651)
		(layer "In5.Cu")
		(net "P5E_PEX3_STN4_RX_DP<68>")
	)
	(segment
		(start 426.263054 -379.902974)
		(end 426.089826 -379.729746)
		(width 0.1651)
		(layer "In5.Cu")
		(net "P5E_PEX3_STN4_RX_DP<68>")
	)
	(segment
		(start 431.48123 -365.567468)
		(end 431.322734 -365.535972)
		(width 0.1651)
		(layer "In5.Cu")
		(net "P5E_PEX3_STN4_RX_DP<68>")
	)
	(segment
		(start 431.322734 -365.535972)
		(end 430.911 -365.81207)
		(width 0.1651)
		(layer "In5.Cu")
		(net "P5E_PEX3_STN4_RX_DP<68>")
	)
	(segment
		(start 426.965872 -379.570488)
		(end 426.633386 -379.902974)
		(width 0.1651)
		(layer "In5.Cu")
		(net "P5E_PEX3_STN4_RX_DP<68>")
	)
	(segment
		(start 434.04155 -309.764176)
		(end 434.469286 -310.796686)
		(width 0.1651)
		(layer "In5.Cu")
		(net "P5E_PEX3_STN4_RX_DP<68>")
	)
	(segment
		(start 429.897794 -366.490758)
		(end 429.866552 -366.649508)
		(width 0.1651)
		(layer "In5.Cu")
		(net "P5E_PEX3_STN4_RX_DP<68>")
	)
	(segment
		(start 442.289692 -357.707184)
		(end 442.111638 -358.125522)
		(width 0.1651)
		(layer "In5.Cu")
		(net "P5E_PEX3_STN4_RX_DP<68>")
	)
	(segment
		(start 432.905408 -364.612936)
		(end 432.494182 -364.888526)
		(width 0.1651)
		(layer "In5.Cu")
		(net "P5E_PEX3_STN4_RX_DP<68>")
	)
	(segment
		(start 208.173828 -190.427356)
		(end 205.9559 -190.427356)
		(width 0.13208)
		(layer "F.Cu")
		(net "SEL_FLASH_PEX3_BUF_R")
	)
	(segment
		(start 209.026252 -181.877208)
		(end 209.466434 -181.877208)
		(width 0.13208)
		(layer "F.Cu")
		(net "SEL_FLASH_PEX3_BUF_R")
	)
	(segment
		(start 209.466434 -181.877208)
		(end 210.130136 -181.213506)
		(width 0.13208)
		(layer "F.Cu")
		(net "SEL_FLASH_PEX3_BUF_R")
	)
	(segment
		(start 205.9559 -190.427356)
		(end 205.791816 -190.263272)
		(width 0.13208)
		(layer "F.Cu")
		(net "SEL_FLASH_PEX3_BUF_R")
	)
	(segment
		(start 208.826354 -191.079882)
		(end 208.173828 -190.427356)
		(width 0.13208)
		(layer "F.Cu")
		(net "SEL_FLASH_PEX3_BUF_R")
	)
	(segment
		(start 210.130136 -180.248306)
		(end 210.130136 -181.213506)
		(width 0.13208)
		(layer "F.Cu")
		(net "SEL_FLASH_PEX3_BUF_R")
	)
	(segment
		(start 205.791816 -185.111644)
		(end 209.026252 -181.877208)
		(width 0.13208)
		(layer "F.Cu")
		(net "SEL_FLASH_PEX3_BUF_R")
	)
	(segment
		(start 205.791816 -190.263272)
		(end 205.791816 -185.111644)
		(width 0.13208)
		(layer "F.Cu")
		(net "SEL_FLASH_PEX3_BUF_R")
	)
	(via
		(at 365.532162 -228.235256)
		(size 0.508)
		(drill 0.254)
		(layers "F.Cu" "B.Cu")
		(net "SEL_FLASH_PEX3_BUF_R")
	)
	(via
		(at 208.826354 -191.079882)
		(size 0.508)
		(drill 0.254)
		(layers "F.Cu" "B.Cu")
		(net "SEL_FLASH_PEX3_BUF_R")
	)
	(via
		(at 291.456872 -194.587622)
		(size 0.508)
		(drill 0.254)
		(layers "F.Cu" "B.Cu")
		(net "SEL_FLASH_PEX3_BUF_R")
	)
	(segment
		(start 291.911532 -195.042282)
		(end 293.435532 -195.042282)
		(width 0.13208)
		(layer "B.Cu")
		(net "SEL_FLASH_PEX3_BUF_R")
	)
	(segment
		(start 291.456872 -194.587622)
		(end 291.911532 -195.042282)
		(width 0.13208)
		(layer "B.Cu")
		(net "SEL_FLASH_PEX3_BUF_R")
	)
	(segment
		(start 365.795814 -229.827582)
		(end 365.795814 -228.498908)
		(width 0.13208)
		(layer "B.Cu")
		(net "SEL_FLASH_PEX3_BUF_R")
	)
	(segment
		(start 365.795814 -228.498908)
		(end 365.532162 -228.235256)
		(width 0.13208)
		(layer "B.Cu")
		(net "SEL_FLASH_PEX3_BUF_R")
	)
	(segment
		(start 293.921942 -195.528692)
		(end 293.921942 -196.149722)
		(width 0.13208)
		(layer "B.Cu")
		(net "SEL_FLASH_PEX3_BUF_R")
	)
	(segment
		(start 293.435532 -195.042282)
		(end 293.921942 -195.528692)
		(width 0.13208)
		(layer "B.Cu")
		(net "SEL_FLASH_PEX3_BUF_R")
	)
	(segment
		(start 352.788474 -201.50455)
		(end 353.716844 -202.43292)
		(width 0.15494)
		(layer "In13.Cu")
		(net "SEL_FLASH_PEX3_BUF_R")
	)
	(segment
		(start 367.332006 -221.279466)
		(end 367.332006 -223.999552)
		(width 0.15494)
		(layer "In13.Cu")
		(net "SEL_FLASH_PEX3_BUF_R")
	)
	(segment
		(start 371.026944 -207.065626)
		(end 371.026944 -217.584528)
		(width 0.15494)
		(layer "In13.Cu")
		(net "SEL_FLASH_PEX3_BUF_R")
	)
	(segment
		(start 353.716844 -202.43292)
		(end 353.716844 -204.467206)
		(width 0.15494)
		(layer "In13.Cu")
		(net "SEL_FLASH_PEX3_BUF_R")
	)
	(segment
		(start 315.458856 -196.688964)
		(end 319.431162 -200.66127)
		(width 0.15494)
		(layer "In13.Cu")
		(net "SEL_FLASH_PEX3_BUF_R")
	)
	(segment
		(start 293.558214 -196.688964)
		(end 315.458856 -196.688964)
		(width 0.15494)
		(layer "In13.Cu")
		(net "SEL_FLASH_PEX3_BUF_R")
	)
	(segment
		(start 353.716844 -204.467206)
		(end 353.942396 -204.692758)
		(width 0.15494)
		(layer "In13.Cu")
		(net "SEL_FLASH_PEX3_BUF_R")
	)
	(segment
		(start 353.942396 -204.692758)
		(end 368.654076 -204.692758)
		(width 0.15494)
		(layer "In13.Cu")
		(net "SEL_FLASH_PEX3_BUF_R")
	)
	(segment
		(start 336.048096 -201.50455)
		(end 352.788474 -201.50455)
		(width 0.15494)
		(layer "In13.Cu")
		(net "SEL_FLASH_PEX3_BUF_R")
	)
	(segment
		(start 319.431162 -200.66127)
		(end 335.204816 -200.66127)
		(width 0.15494)
		(layer "In13.Cu")
		(net "SEL_FLASH_PEX3_BUF_R")
	)
	(segment
		(start 367.332006 -223.999552)
		(end 365.256572 -226.074986)
		(width 0.15494)
		(layer "In13.Cu")
		(net "SEL_FLASH_PEX3_BUF_R")
	)
	(segment
		(start 291.456872 -194.587622)
		(end 293.558214 -196.688964)
		(width 0.15494)
		(layer "In13.Cu")
		(net "SEL_FLASH_PEX3_BUF_R")
	)
	(segment
		(start 365.256572 -227.959666)
		(end 365.532162 -228.235256)
		(width 0.15494)
		(layer "In13.Cu")
		(net "SEL_FLASH_PEX3_BUF_R")
	)
	(segment
		(start 368.654076 -204.692758)
		(end 371.026944 -207.065626)
		(width 0.15494)
		(layer "In13.Cu")
		(net "SEL_FLASH_PEX3_BUF_R")
	)
	(segment
		(start 335.204816 -200.66127)
		(end 336.048096 -201.50455)
		(width 0.15494)
		(layer "In13.Cu")
		(net "SEL_FLASH_PEX3_BUF_R")
	)
	(segment
		(start 365.256572 -226.074986)
		(end 365.256572 -227.959666)
		(width 0.15494)
		(layer "In13.Cu")
		(net "SEL_FLASH_PEX3_BUF_R")
	)
	(segment
		(start 371.026944 -217.584528)
		(end 367.332006 -221.279466)
		(width 0.15494)
		(layer "In13.Cu")
		(net "SEL_FLASH_PEX3_BUF_R")
	)
	(segment
		(start 251.979684 -192.958212)
		(end 255.441704 -189.496192)
		(width 0.15494)
		(layer "In15.Cu")
		(net "SEL_FLASH_PEX3_BUF_R")
	)
	(segment
		(start 208.826354 -190.18631)
		(end 210.4263 -188.586364)
		(width 0.15494)
		(layer "In15.Cu")
		(net "SEL_FLASH_PEX3_BUF_R")
	)
	(segment
		(start 241.191034 -192.958212)
		(end 251.979684 -192.958212)
		(width 0.15494)
		(layer "In15.Cu")
		(net "SEL_FLASH_PEX3_BUF_R")
	)
	(segment
		(start 271.954244 -189.496192)
		(end 277.045674 -194.587622)
		(width 0.15494)
		(layer "In15.Cu")
		(net "SEL_FLASH_PEX3_BUF_R")
	)
	(segment
		(start 277.045674 -194.587622)
		(end 291.456872 -194.587622)
		(width 0.15494)
		(layer "In15.Cu")
		(net "SEL_FLASH_PEX3_BUF_R")
	)
	(segment
		(start 255.441704 -189.496192)
		(end 271.954244 -189.496192)
		(width 0.15494)
		(layer "In15.Cu")
		(net "SEL_FLASH_PEX3_BUF_R")
	)
	(segment
		(start 235.935266 -187.702444)
		(end 241.191034 -192.958212)
		(width 0.15494)
		(layer "In15.Cu")
		(net "SEL_FLASH_PEX3_BUF_R")
	)
	(segment
		(start 221.637098 -187.702444)
		(end 235.935266 -187.702444)
		(width 0.15494)
		(layer "In15.Cu")
		(net "SEL_FLASH_PEX3_BUF_R")
	)
	(segment
		(start 208.826354 -191.079882)
		(end 208.826354 -190.18631)
		(width 0.15494)
		(layer "In15.Cu")
		(net "SEL_FLASH_PEX3_BUF_R")
	)
	(segment
		(start 220.753178 -188.586364)
		(end 221.637098 -187.702444)
		(width 0.15494)
		(layer "In15.Cu")
		(net "SEL_FLASH_PEX3_BUF_R")
	)
	(segment
		(start 210.4263 -188.586364)
		(end 220.753178 -188.586364)
		(width 0.15494)
		(layer "In15.Cu")
		(net "SEL_FLASH_PEX3_BUF_R")
	)
	(segment
		(start 142.040356 -228.13899)
		(end 141.504416 -228.67493)
		(width 0.13208)
		(layer "F.Cu")
		(net "SPI_PEX1_CS_MUX_R_N")
	)
	(segment
		(start 142.040356 -227.94595)
		(end 142.040356 -228.13899)
		(width 0.13208)
		(layer "F.Cu")
		(net "SPI_PEX1_CS_MUX_R_N")
	)
	(segment
		(start 141.504416 -228.67493)
		(end 140.68298 -228.67493)
		(width 0.13208)
		(layer "F.Cu")
		(net "SPI_PEX1_CS_MUX_R_N")
	)
	(via
		(at 142.040356 -227.94595)
		(size 0.508)
		(drill 0.254)
		(layers "F.Cu" "B.Cu")
		(net "SPI_PEX1_CS_MUX_R_N")
	)
	(segment
		(start 142.040356 -227.94595)
		(end 140.282168 -227.94595)
		(width 0.13208)
		(layer "B.Cu")
		(net "SPI_PEX1_CS_MUX_R_N")
	)
	(segment
		(start 140.282168 -227.21316)
		(end 140.559282 -226.936046)
		(width 0.13208)
		(layer "B.Cu")
		(net "SPI_PEX1_CS_MUX_R_N")
	)
	(segment
		(start 140.282168 -227.94595)
		(end 140.282168 -227.21316)
		(width 0.13208)
		(layer "B.Cu")
		(net "SPI_PEX1_CS_MUX_R_N")
	)
	(segment
		(start 422.619932 -350.365314)
		(end 422.3004 -350.684846)
		(width 0.13462)
		(layer "F.Cu")
		(net "P5E_PEX3_STN4_TX_C_DN<73>")
	)
	(segment
		(start 422.3004 -351.317306)
		(end 422.594532 -351.611438)
		(width 0.13462)
		(layer "F.Cu")
		(net "P5E_PEX3_STN4_TX_C_DN<73>")
	)
	(segment
		(start 422.3004 -350.684846)
		(end 422.3004 -351.317306)
		(width 0.13462)
		(layer "F.Cu")
		(net "P5E_PEX3_STN4_TX_C_DN<73>")
	)
	(segment
		(start 422.303702 -351.902268)
		(end 422.303702 -352.473006)
		(width 0.1651)
		(layer "In7.Cu")
		(net "P5E_PEX3_STN4_TX_C_DN<73>")
	)
	(segment
		(start 433.35956 -394.15974)
		(end 433.815744 -394.615924)
		(width 0.1651)
		(layer "In7.Cu")
		(net "P5E_PEX3_STN4_TX_C_DN<73>")
	)
	(segment
		(start 422.594532 -351.611438)
		(end 422.303702 -351.902268)
		(width 0.1651)
		(layer "In7.Cu")
		(net "P5E_PEX3_STN4_TX_C_DN<73>")
	)
	(segment
		(start 422.303702 -352.473006)
		(end 420.749222 -354.027486)
		(width 0.1651)
		(layer "In7.Cu")
		(net "P5E_PEX3_STN4_TX_C_DN<73>")
	)
	(segment
		(start 433.363878 -397.281146)
		(end 432.816762 -397.281146)
		(width 0.1651)
		(layer "In7.Cu")
		(net "P5E_PEX3_STN4_TX_C_DN<73>")
	)
	(segment
		(start 417.10991 -383.45872)
		(end 417.534598 -384.90398)
		(width 0.1651)
		(layer "In7.Cu")
		(net "P5E_PEX3_STN4_TX_C_DN<73>")
	)
	(segment
		(start 433.815744 -396.82928)
		(end 433.363878 -397.281146)
		(width 0.1651)
		(layer "In7.Cu")
		(net "P5E_PEX3_STN4_TX_C_DN<73>")
	)
	(segment
		(start 433.815744 -394.615924)
		(end 433.815744 -396.82928)
		(width 0.1651)
		(layer "In7.Cu")
		(net "P5E_PEX3_STN4_TX_C_DN<73>")
	)
	(segment
		(start 432.816762 -397.281146)
		(end 432.689762 -397.408146)
		(width 0.1651)
		(layer "In7.Cu")
		(net "P5E_PEX3_STN4_TX_C_DN<73>")
	)
	(segment
		(start 432.689762 -397.408146)
		(end 432.689762 -397.790162)
		(width 0.1651)
		(layer "In7.Cu")
		(net "P5E_PEX3_STN4_TX_C_DN<73>")
	)
	(segment
		(start 420.749222 -354.027486)
		(end 420.749222 -358.82072)
		(width 0.1651)
		(layer "In7.Cu")
		(net "P5E_PEX3_STN4_TX_C_DN<73>")
	)
	(segment
		(start 420.749222 -358.82072)
		(end 417.396422 -369.43919)
		(width 0.1651)
		(layer "In7.Cu")
		(net "P5E_PEX3_STN4_TX_C_DN<73>")
	)
	(segment
		(start 417.534598 -384.90398)
		(end 418.302948 -386.004816)
		(width 0.1651)
		(layer "In7.Cu")
		(net "P5E_PEX3_STN4_TX_C_DN<73>")
	)
	(segment
		(start 418.302948 -386.004816)
		(end 433.35956 -394.15974)
		(width 0.1651)
		(layer "In7.Cu")
		(net "P5E_PEX3_STN4_TX_C_DN<73>")
	)
	(segment
		(start 417.396422 -369.43919)
		(end 417.10991 -383.45872)
		(width 0.1651)
		(layer "In7.Cu")
		(net "P5E_PEX3_STN4_TX_C_DN<73>")
	)
	(segment
		(start 141.889734 -221.05493)
		(end 140.68298 -221.05493)
		(width 0.13208)
		(layer "F.Cu")
		(net "SPI_PEX1_SDIO3_R1")
	)
	(segment
		(start 142.14475 -220.799914)
		(end 141.889734 -221.05493)
		(width 0.13208)
		(layer "F.Cu")
		(net "SPI_PEX1_SDIO3_R1")
	)
	(segment
		(start 142.528036 -220.799914)
		(end 142.14475 -220.799914)
		(width 0.13208)
		(layer "F.Cu")
		(net "SPI_PEX1_SDIO3_R1")
	)
	(via
		(at 142.528036 -220.799914)
		(size 0.508)
		(drill 0.254)
		(layers "F.Cu" "B.Cu")
		(net "SPI_PEX1_SDIO3_R1")
	)
	(segment
		(start 142.252446 -220.524324)
		(end 142.528036 -220.799914)
		(width 0.13208)
		(layer "B.Cu")
		(net "SPI_PEX1_SDIO3_R1")
	)
	(segment
		(start 140.183108 -220.532706)
		(end 141.214348 -220.532706)
		(width 0.13208)
		(layer "B.Cu")
		(net "SPI_PEX1_SDIO3_R1")
	)
	(segment
		(start 141.22273 -220.524324)
		(end 142.252446 -220.524324)
		(width 0.13208)
		(layer "B.Cu")
		(net "SPI_PEX1_SDIO3_R1")
	)
	(segment
		(start 141.214348 -220.532706)
		(end 141.22273 -220.524324)
		(width 0.13208)
		(layer "B.Cu")
		(net "SPI_PEX1_SDIO3_R1")
	)
	(segment
		(start 432.689762 -378.629672)
		(end 432.689762 -378.290074)
		(width 0.1651)
		(layer "In5.Cu")
		(net "P5E_PEX3_STN4_RX_DP<65>")
	)
	(segment
		(start 436.285894 -366.795304)
		(end 436.127398 -366.76457)
		(width 0.1651)
		(layer "In5.Cu")
		(net "P5E_PEX3_STN4_RX_DP<65>")
	)
	(segment
		(start 440.793124 -363.500416)
		(end 440.772296 -363.66069)
		(width 0.1651)
		(layer "In5.Cu")
		(net "P5E_PEX3_STN4_RX_DP<65>")
	)
	(segment
		(start 437.70804 -365.837216)
		(end 437.297322 -366.113822)
		(width 0.1651)
		(layer "In5.Cu")
		(net "P5E_PEX3_STN4_RX_DP<65>")
	)
	(segment
		(start 441.738258 -362.916724)
		(end 441.346082 -363.21873)
		(width 0.1651)
		(layer "In5.Cu")
		(net "P5E_PEX3_STN4_RX_DP<65>")
	)
	(segment
		(start 435.685438 -367.20018)
		(end 434.520594 -367.98504)
		(width 0.1651)
		(layer "In5.Cu")
		(net "P5E_PEX3_STN4_RX_DP<65>")
	)
	(segment
		(start 445.007492 -316.234572)
		(end 446.169542 -317.396622)
		(width 0.1651)
		(layer "In5.Cu")
		(net "P5E_PEX3_STN4_RX_DP<65>")
	)
	(segment
		(start 443.278006 -361.730798)
		(end 443.117732 -361.70997)
		(width 0.1651)
		(layer "In5.Cu")
		(net "P5E_PEX3_STN4_RX_DP<65>")
	)
	(segment
		(start 436.696612 -366.518698)
		(end 436.285894 -366.795304)
		(width 0.1651)
		(layer "In5.Cu")
		(net "P5E_PEX3_STN4_RX_DP<65>")
	)
	(segment
		(start 437.738774 -365.678466)
		(end 437.70804 -365.837216)
		(width 0.1651)
		(layer "In5.Cu")
		(net "P5E_PEX3_STN4_RX_DP<65>")
	)
	(segment
		(start 438.149746 -365.401352)
		(end 437.738774 -365.678466)
		(width 0.1651)
		(layer "In5.Cu")
		(net "P5E_PEX3_STN4_RX_DP<65>")
	)
	(segment
		(start 437.138572 -366.082834)
		(end 436.7276 -366.359948)
		(width 0.1651)
		(layer "In5.Cu")
		(net "P5E_PEX3_STN4_RX_DP<65>")
	)
	(segment
		(start 442.312044 -362.474764)
		(end 442.151516 -362.453936)
		(width 0.1651)
		(layer "In5.Cu")
		(net "P5E_PEX3_STN4_RX_DP<65>")
	)
	(segment
		(start 435.716426 -367.04143)
		(end 435.685438 -367.20018)
		(width 0.1651)
		(layer "In5.Cu")
		(net "P5E_PEX3_STN4_RX_DP<65>")
	)
	(segment
		(start 442.70422 -362.172758)
		(end 442.312044 -362.474764)
		(width 0.1651)
		(layer "In5.Cu")
		(net "P5E_PEX3_STN4_RX_DP<65>")
	)
	(segment
		(start 446.169542 -317.396622)
		(end 446.169542 -322.221606)
		(width 0.1651)
		(layer "In5.Cu")
		(net "P5E_PEX3_STN4_RX_DP<65>")
	)
	(segment
		(start 427.89983 -305.399948)
		(end 428.16526 -305.399948)
		(width 0.1143)
		(layer "In5.Cu")
		(net "P5E_PEX3_STN4_RX_DP<65>")
	)
	(segment
		(start 433.565808 -369.68684)
		(end 433.565808 -378.470414)
		(width 0.1651)
		(layer "In5.Cu")
		(net "P5E_PEX3_STN4_RX_DP<65>")
	)
	(segment
		(start 441.346082 -363.21873)
		(end 441.185554 -363.197902)
		(width 0.1651)
		(layer "In5.Cu")
		(net "P5E_PEX3_STN4_RX_DP<65>")
	)
	(segment
		(start 444.845948 -316.234572)
		(end 445.007492 -316.234572)
		(width 0.1651)
		(layer "In5.Cu")
		(net "P5E_PEX3_STN4_RX_DP<65>")
	)
	(segment
		(start 439.614564 -364.55223)
		(end 438.308496 -365.43234)
		(width 0.1651)
		(layer "In5.Cu")
		(net "P5E_PEX3_STN4_RX_DP<65>")
	)
	(segment
		(start 428.27956 -305.744372)
		(end 428.505366 -305.970178)
		(width 0.1143)
		(layer "In5.Cu")
		(net "P5E_PEX3_STN4_RX_DP<65>")
	)
	(segment
		(start 434.093874 -368.41176)
		(end 433.565808 -369.68684)
		(width 0.1651)
		(layer "In5.Cu")
		(net "P5E_PEX3_STN4_RX_DP<65>")
	)
	(segment
		(start 443.117732 -361.70997)
		(end 442.725048 -362.012484)
		(width 0.1651)
		(layer "In5.Cu")
		(net "P5E_PEX3_STN4_RX_DP<65>")
	)
	(segment
		(start 432.86299 -378.8029)
		(end 432.689762 -378.629672)
		(width 0.1651)
		(layer "In5.Cu")
		(net "P5E_PEX3_STN4_RX_DP<65>")
	)
	(segment
		(start 440.772296 -363.66069)
		(end 439.614564 -364.55223)
		(width 0.1651)
		(layer "In5.Cu")
		(net "P5E_PEX3_STN4_RX_DP<65>")
	)
	(segment
		(start 436.7276 -366.359948)
		(end 436.696612 -366.518698)
		(width 0.1651)
		(layer "In5.Cu")
		(net "P5E_PEX3_STN4_RX_DP<65>")
	)
	(segment
		(start 444.495428 -315.884052)
		(end 444.845948 -316.234572)
		(width 0.1651)
		(layer "In5.Cu")
		(net "P5E_PEX3_STN4_RX_DP<65>")
	)
	(segment
		(start 437.297322 -366.113822)
		(end 437.138572 -366.082834)
		(width 0.1651)
		(layer "In5.Cu")
		(net "P5E_PEX3_STN4_RX_DP<65>")
	)
	(segment
		(start 445.169544 -358.63911)
		(end 443.80023 -361.328462)
		(width 0.1651)
		(layer "In5.Cu")
		(net "P5E_PEX3_STN4_RX_DP<65>")
	)
	(segment
		(start 428.505366 -305.970178)
		(end 431.935128 -305.970178)
		(width 0.1143)
		(layer "In5.Cu")
		(net "P5E_PEX3_STN4_RX_DP<65>")
	)
	(segment
		(start 441.759086 -362.75645)
		(end 441.738258 -362.916724)
		(width 0.1651)
		(layer "In5.Cu")
		(net "P5E_PEX3_STN4_RX_DP<65>")
	)
	(segment
		(start 443.80023 -361.328462)
		(end 443.278006 -361.730798)
		(width 0.1651)
		(layer "In5.Cu")
		(net "P5E_PEX3_STN4_RX_DP<65>")
	)
	(segment
		(start 432.009296 -306.015898)
		(end 433.730908 -306.015898)
		(width 0.1651)
		(layer "In5.Cu")
		(net "P5E_PEX3_STN4_RX_DP<65>")
	)
	(segment
		(start 436.127398 -366.76457)
		(end 435.716426 -367.04143)
		(width 0.1651)
		(layer "In5.Cu")
		(net "P5E_PEX3_STN4_RX_DP<65>")
	)
	(segment
		(start 433.233322 -378.8029)
		(end 432.86299 -378.8029)
		(width 0.1651)
		(layer "In5.Cu")
		(net "P5E_PEX3_STN4_RX_DP<65>")
	)
	(segment
		(start 441.185554 -363.197902)
		(end 440.793124 -363.500416)
		(width 0.1651)
		(layer "In5.Cu")
		(net "P5E_PEX3_STN4_RX_DP<65>")
	)
	(segment
		(start 435.537102 -306.764182)
		(end 444.495428 -315.722508)
		(width 0.1651)
		(layer "In5.Cu")
		(net "P5E_PEX3_STN4_RX_DP<65>")
	)
	(segment
		(start 442.725048 -362.012484)
		(end 442.70422 -362.172758)
		(width 0.1651)
		(layer "In5.Cu")
		(net "P5E_PEX3_STN4_RX_DP<65>")
	)
	(segment
		(start 434.520594 -367.98504)
		(end 434.093874 -368.41176)
		(width 0.1651)
		(layer "In5.Cu")
		(net "P5E_PEX3_STN4_RX_DP<65>")
	)
	(segment
		(start 433.730908 -306.015898)
		(end 435.537102 -306.764182)
		(width 0.1651)
		(layer "In5.Cu")
		(net "P5E_PEX3_STN4_RX_DP<65>")
	)
	(segment
		(start 433.565808 -378.470414)
		(end 433.233322 -378.8029)
		(width 0.1651)
		(layer "In5.Cu")
		(net "P5E_PEX3_STN4_RX_DP<65>")
	)
	(segment
		(start 431.980848 -306.015898)
		(end 432.009296 -306.015898)
		(width 0.1143)
		(layer "In5.Cu")
		(net "P5E_PEX3_STN4_RX_DP<65>")
	)
	(segment
		(start 438.308496 -365.43234)
		(end 438.149746 -365.401352)
		(width 0.1651)
		(layer "In5.Cu")
		(net "P5E_PEX3_STN4_RX_DP<65>")
	)
	(segment
		(start 428.16526 -305.399948)
		(end 428.27956 -305.514248)
		(width 0.1143)
		(layer "In5.Cu")
		(net "P5E_PEX3_STN4_RX_DP<65>")
	)
	(segment
		(start 431.935128 -305.970178)
		(end 431.980848 -306.015898)
		(width 0.1143)
		(layer "In5.Cu")
		(net "P5E_PEX3_STN4_RX_DP<65>")
	)
	(segment
		(start 442.151516 -362.453936)
		(end 441.759086 -362.75645)
		(width 0.1651)
		(layer "In5.Cu")
		(net "P5E_PEX3_STN4_RX_DP<65>")
	)
	(segment
		(start 444.495428 -315.722508)
		(end 444.495428 -315.884052)
		(width 0.1651)
		(layer "In5.Cu")
		(net "P5E_PEX3_STN4_RX_DP<65>")
	)
	(segment
		(start 428.27956 -305.514248)
		(end 428.27956 -305.744372)
		(width 0.1143)
		(layer "In5.Cu")
		(net "P5E_PEX3_STN4_RX_DP<65>")
	)
	(segment
		(start 446.169542 -322.221606)
		(end 445.169544 -358.63911)
		(width 0.1651)
		(layer "In5.Cu")
		(net "P5E_PEX3_STN4_RX_DP<65>")
	)
	(via
		(at 132.25399 -225.491802)
		(size 0.6604)
		(drill 0.3302)
		(layers "F.Cu" "B.Cu")
		(net "SPI_MUX_PEX1_EN_N")
	)
	(segment
		(start 132.25399 -224.337118)
		(end 132.25399 -225.491802)
		(width 0.13208)
		(layer "B.Cu")
		(net "SPI_MUX_PEX1_EN_N")
	)
	(segment
		(start 134.034784 -225.491802)
		(end 134.230872 -225.295714)
		(width 0.13208)
		(layer "B.Cu")
		(net "SPI_MUX_PEX1_EN_N")
	)
	(segment
		(start 134.230872 -225.295714)
		(end 134.230872 -224.341182)
		(width 0.13208)
		(layer "B.Cu")
		(net "SPI_MUX_PEX1_EN_N")
	)
	(segment
		(start 132.25399 -225.491802)
		(end 134.034784 -225.491802)
		(width 0.13208)
		(layer "B.Cu")
		(net "SPI_MUX_PEX1_EN_N")
	)
	(segment
		(start 428.51832 -350.684846)
		(end 428.51832 -351.317306)
		(width 0.13462)
		(layer "F.Cu")
		(net "P5E_PEX3_STN4_TX_C_DN<70>")
	)
	(segment
		(start 428.837852 -350.365314)
		(end 428.51832 -350.684846)
		(width 0.13462)
		(layer "F.Cu")
		(net "P5E_PEX3_STN4_TX_C_DN<70>")
	)
	(segment
		(start 428.51832 -351.317306)
		(end 428.812452 -351.611438)
		(width 0.13462)
		(layer "F.Cu")
		(net "P5E_PEX3_STN4_TX_C_DN<70>")
	)
	(segment
		(start 428.521622 -352.473006)
		(end 426.967142 -354.027486)
		(width 0.1651)
		(layer "In7.Cu")
		(net "P5E_PEX3_STN4_TX_C_DN<70>")
	)
	(segment
		(start 428.812452 -351.611438)
		(end 428.521622 -351.902268)
		(width 0.1651)
		(layer "In7.Cu")
		(net "P5E_PEX3_STN4_TX_C_DN<70>")
	)
	(segment
		(start 422.815766 -371.929152)
		(end 422.3639 -372.381018)
		(width 0.1651)
		(layer "In7.Cu")
		(net "P5E_PEX3_STN4_TX_C_DN<70>")
	)
	(segment
		(start 428.521622 -351.902268)
		(end 428.521622 -352.473006)
		(width 0.1651)
		(layer "In7.Cu")
		(net "P5E_PEX3_STN4_TX_C_DN<70>")
	)
	(segment
		(start 422.815766 -368.838988)
		(end 422.815766 -371.929152)
		(width 0.1651)
		(layer "In7.Cu")
		(net "P5E_PEX3_STN4_TX_C_DN<70>")
	)
	(segment
		(start 426.967142 -354.027486)
		(end 426.967142 -358.83342)
		(width 0.1651)
		(layer "In7.Cu")
		(net "P5E_PEX3_STN4_TX_C_DN<70>")
	)
	(segment
		(start 426.967142 -358.83342)
		(end 422.815766 -368.838988)
		(width 0.1651)
		(layer "In7.Cu")
		(net "P5E_PEX3_STN4_TX_C_DN<70>")
	)
	(segment
		(start 421.816784 -372.381018)
		(end 421.689784 -372.508018)
		(width 0.1651)
		(layer "In7.Cu")
		(net "P5E_PEX3_STN4_TX_C_DN<70>")
	)
	(segment
		(start 422.3639 -372.381018)
		(end 421.816784 -372.381018)
		(width 0.1651)
		(layer "In7.Cu")
		(net "P5E_PEX3_STN4_TX_C_DN<70>")
	)
	(segment
		(start 421.689784 -372.508018)
		(end 421.689784 -372.890034)
		(width 0.1651)
		(layer "In7.Cu")
		(net "P5E_PEX3_STN4_TX_C_DN<70>")
	)
	(segment
		(start 130.922776 -229.94493)
		(end 129.290318 -229.94493)
		(width 0.13208)
		(layer "F.Cu")
		(net "SPI_PEX1_SDIO2_R1")
	)
	(via
		(at 129.290318 -229.94493)
		(size 0.508)
		(drill 0.254)
		(layers "F.Cu" "B.Cu")
		(net "SPI_PEX1_SDIO2_R1")
	)
	(segment
		(start 130.493008 -229.997)
		(end 130.440938 -229.94493)
		(width 0.13208)
		(layer "B.Cu")
		(net "SPI_PEX1_SDIO2_R1")
	)
	(segment
		(start 130.493008 -228.981)
		(end 130.493008 -229.997)
		(width 0.13208)
		(layer "B.Cu")
		(net "SPI_PEX1_SDIO2_R1")
	)
	(segment
		(start 130.493008 -227.965)
		(end 130.493008 -228.981)
		(width 0.13208)
		(layer "B.Cu")
		(net "SPI_PEX1_SDIO2_R1")
	)
	(segment
		(start 130.440938 -229.94493)
		(end 129.290318 -229.94493)
		(width 0.13208)
		(layer "B.Cu")
		(net "SPI_PEX1_SDIO2_R1")
	)
	(segment
		(start 412.378652 -344.219022)
		(end 412.6992 -344.53957)
		(width 0.13462)
		(layer "F.Cu")
		(net "P5E_PEX3_STN4_TX_C_DP<78>")
	)
	(segment
		(start 412.6992 -344.53957)
		(end 412.6992 -345.169998)
		(width 0.13462)
		(layer "F.Cu")
		(net "P5E_PEX3_STN4_TX_C_DP<78>")
	)
	(segment
		(start 412.6992 -345.169998)
		(end 412.404052 -345.465146)
		(width 0.13462)
		(layer "F.Cu")
		(net "P5E_PEX3_STN4_TX_C_DP<78>")
	)
	(segment
		(start 411.281372 -365.003334)
		(end 411.190186 -364.916466)
		(width 0.1651)
		(layer "In7.Cu")
		(net "P5E_PEX3_STN4_TX_C_DP<78>")
	)
	(segment
		(start 422.533826 -397.812514)
		(end 422.533826 -395.581886)
		(width 0.1651)
		(layer "In7.Cu")
		(net "P5E_PEX3_STN4_TX_C_DP<78>")
	)
	(segment
		(start 421.695372 -394.743432)
		(end 421.187118 -394.235178)
		(width 0.1651)
		(layer "In7.Cu")
		(net "P5E_PEX3_STN4_TX_C_DP<78>")
	)
	(segment
		(start 411.683962 -383.851658)
		(end 411.281118 -365.003334)
		(width 0.1651)
		(layer "In7.Cu")
		(net "P5E_PEX3_STN4_TX_C_DP<78>")
	)
	(segment
		(start 412.694882 -345.755976)
		(end 412.404052 -345.465146)
		(width 0.1651)
		(layer "In7.Cu")
		(net "P5E_PEX3_STN4_TX_C_DP<78>")
	)
	(segment
		(start 412.780988 -387.458204)
		(end 411.683962 -383.851658)
		(width 0.1651)
		(layer "In7.Cu")
		(net "P5E_PEX3_STN4_TX_C_DP<78>")
	)
	(segment
		(start 421.187118 -394.235178)
		(end 414.94837 -390.086342)
		(width 0.1651)
		(layer "In7.Cu")
		(net "P5E_PEX3_STN4_TX_C_DP<78>")
	)
	(segment
		(start 421.816784 -398.09928)
		(end 422.24706 -398.09928)
		(width 0.1651)
		(layer "In7.Cu")
		(net "P5E_PEX3_STN4_TX_C_DP<78>")
	)
	(segment
		(start 422.045638 -395.219428)
		(end 421.695372 -394.869162)
		(width 0.1651)
		(layer "In7.Cu")
		(net "P5E_PEX3_STN4_TX_C_DP<78>")
	)
	(segment
		(start 411.190186 -364.916466)
		(end 411.179772 -364.420912)
		(width 0.1651)
		(layer "In7.Cu")
		(net "P5E_PEX3_STN4_TX_C_DP<78>")
	)
	(segment
		(start 422.24706 -398.09928)
		(end 422.533826 -397.812514)
		(width 0.1651)
		(layer "In7.Cu")
		(net "P5E_PEX3_STN4_TX_C_DP<78>")
	)
	(segment
		(start 422.171368 -395.219428)
		(end 422.045638 -395.219428)
		(width 0.1651)
		(layer "In7.Cu")
		(net "P5E_PEX3_STN4_TX_C_DP<78>")
	)
	(segment
		(start 421.689784 -397.97228)
		(end 421.816784 -398.09928)
		(width 0.1651)
		(layer "In7.Cu")
		(net "P5E_PEX3_STN4_TX_C_DP<78>")
	)
	(segment
		(start 411.26664 -364.330234)
		(end 411.140402 -358.416606)
		(width 0.1651)
		(layer "In7.Cu")
		(net "P5E_PEX3_STN4_TX_C_DP<78>")
	)
	(segment
		(start 421.695372 -394.869162)
		(end 421.695372 -394.743432)
		(width 0.1651)
		(layer "In7.Cu")
		(net "P5E_PEX3_STN4_TX_C_DP<78>")
	)
	(segment
		(start 411.140402 -358.416606)
		(end 411.140402 -347.764354)
		(width 0.1651)
		(layer "In7.Cu")
		(net "P5E_PEX3_STN4_TX_C_DP<78>")
	)
	(segment
		(start 411.281118 -365.003334)
		(end 411.281372 -365.003334)
		(width 0.1651)
		(layer "In7.Cu")
		(net "P5E_PEX3_STN4_TX_C_DP<78>")
	)
	(segment
		(start 412.694882 -346.209874)
		(end 412.694882 -345.755976)
		(width 0.1651)
		(layer "In7.Cu")
		(net "P5E_PEX3_STN4_TX_C_DP<78>")
	)
	(segment
		(start 414.94837 -390.086342)
		(end 412.780988 -387.458204)
		(width 0.1651)
		(layer "In7.Cu")
		(net "P5E_PEX3_STN4_TX_C_DP<78>")
	)
	(segment
		(start 411.179772 -364.420912)
		(end 411.26664 -364.330234)
		(width 0.1651)
		(layer "In7.Cu")
		(net "P5E_PEX3_STN4_TX_C_DP<78>")
	)
	(segment
		(start 411.140402 -347.764354)
		(end 412.694882 -346.209874)
		(width 0.1651)
		(layer "In7.Cu")
		(net "P5E_PEX3_STN4_TX_C_DP<78>")
	)
	(segment
		(start 422.533826 -395.581886)
		(end 422.171368 -395.219428)
		(width 0.1651)
		(layer "In7.Cu")
		(net "P5E_PEX3_STN4_TX_C_DP<78>")
	)
	(segment
		(start 421.689784 -397.59001)
		(end 421.689784 -397.97228)
		(width 0.1651)
		(layer "In7.Cu")
		(net "P5E_PEX3_STN4_TX_C_DP<78>")
	)
	(segment
		(start 158.649924 -293.04996)
		(end 158.174944 -292.57498)
		(width 0.13208)
		(layer "F.Cu")
		(net "SPI_PEX1_CLK")
	)
	(via
		(at 158.174944 -292.57498)
		(size 0.508)
		(drill 0.254)
		(layers "F.Cu" "B.Cu")
		(net "SPI_PEX1_CLK")
	)
	(segment
		(start 157.623764 -292.0238)
		(end 156.854398 -292.0238)
		(width 0.13208)
		(layer "B.Cu")
		(net "SPI_PEX1_CLK")
	)
	(segment
		(start 158.174944 -292.57498)
		(end 157.623764 -292.0238)
		(width 0.13208)
		(layer "B.Cu")
		(net "SPI_PEX1_CLK")
	)
	(segment
		(start 156.854398 -292.0238)
		(end 156.557218 -291.72662)
		(width 0.13208)
		(layer "B.Cu")
		(net "SPI_PEX1_CLK")
	)
	(segment
		(start 432.689762 -404.62962)
		(end 432.86299 -404.802848)
		(width 0.1651)
		(layer "In5.Cu")
		(net "P5E_PEX3_STN4_RX_DP<73>")
	)
	(segment
		(start 427.505622 -391.530332)
		(end 427.38548 -391.566908)
		(width 0.1651)
		(layer "In5.Cu")
		(net "P5E_PEX3_STN4_RX_DP<73>")
	)
	(segment
		(start 427.3296 -316.455298)
		(end 427.555406 -316.229492)
		(width 0.1143)
		(layer "In5.Cu")
		(net "P5E_PEX3_STN4_RX_DP<73>")
	)
	(segment
		(start 426.685202 -358.40416)
		(end 426.685202 -342.209374)
		(width 0.1651)
		(layer "In5.Cu")
		(net "P5E_PEX3_STN4_RX_DP<73>")
	)
	(segment
		(start 433.010818 -394.46327)
		(end 427.505622 -391.530332)
		(width 0.1651)
		(layer "In5.Cu")
		(net "P5E_PEX3_STN4_RX_DP<73>")
	)
	(segment
		(start 427.3296 -319.864232)
		(end 427.3296 -316.455298)
		(width 0.1143)
		(layer "In5.Cu")
		(net "P5E_PEX3_STN4_RX_DP<73>")
	)
	(segment
		(start 426.911262 -391.21334)
		(end 426.474382 -390.980676)
		(width 0.1651)
		(layer "In5.Cu")
		(net "P5E_PEX3_STN4_RX_DP<73>")
	)
	(segment
		(start 427.28388 -331.682598)
		(end 427.28388 -319.9384)
		(width 0.1651)
		(layer "In5.Cu")
		(net "P5E_PEX3_STN4_RX_DP<73>")
	)
	(segment
		(start 426.35424 -391.017506)
		(end 425.916852 -390.784334)
		(width 0.1651)
		(layer "In5.Cu")
		(net "P5E_PEX3_STN4_RX_DP<73>")
	)
	(segment
		(start 416.917886 -384.098292)
		(end 416.955986 -370.15293)
		(width 0.1651)
		(layer "In5.Cu")
		(net "P5E_PEX3_STN4_RX_DP<73>")
	)
	(segment
		(start 433.565808 -395.273784)
		(end 433.368704 -394.785596)
		(width 0.1651)
		(layer "In5.Cu")
		(net "P5E_PEX3_STN4_RX_DP<73>")
	)
	(segment
		(start 417.521644 -368.25936)
		(end 426.685202 -358.40416)
		(width 0.1651)
		(layer "In5.Cu")
		(net "P5E_PEX3_STN4_RX_DP<73>")
	)
	(segment
		(start 425.880022 -390.663938)
		(end 425.443142 -390.431274)
		(width 0.1651)
		(layer "In5.Cu")
		(net "P5E_PEX3_STN4_RX_DP<73>")
	)
	(segment
		(start 426.474382 -390.980676)
		(end 426.35424 -391.017506)
		(width 0.1651)
		(layer "In5.Cu")
		(net "P5E_PEX3_STN4_RX_DP<73>")
	)
	(segment
		(start 427.89983 -316.115192)
		(end 427.89983 -315.849762)
		(width 0.1143)
		(layer "In5.Cu")
		(net "P5E_PEX3_STN4_RX_DP<73>")
	)
	(segment
		(start 427.28388 -319.909952)
		(end 427.3296 -319.864232)
		(width 0.1143)
		(layer "In5.Cu")
		(net "P5E_PEX3_STN4_RX_DP<73>")
	)
	(segment
		(start 426.948092 -391.333736)
		(end 426.911262 -391.21334)
		(width 0.1651)
		(layer "In5.Cu")
		(net "P5E_PEX3_STN4_RX_DP<73>")
	)
	(segment
		(start 417.211002 -368.866674)
		(end 417.521644 -368.25936)
		(width 0.1651)
		(layer "In5.Cu")
		(net "P5E_PEX3_STN4_RX_DP<73>")
	)
	(segment
		(start 425.443142 -390.431274)
		(end 425.322746 -390.46785)
		(width 0.1651)
		(layer "In5.Cu")
		(net "P5E_PEX3_STN4_RX_DP<73>")
	)
	(segment
		(start 425.916852 -390.784334)
		(end 425.880022 -390.663938)
		(width 0.1651)
		(layer "In5.Cu")
		(net "P5E_PEX3_STN4_RX_DP<73>")
	)
	(segment
		(start 433.565808 -404.470362)
		(end 433.565808 -395.273784)
		(width 0.1651)
		(layer "In5.Cu")
		(net "P5E_PEX3_STN4_RX_DP<73>")
	)
	(segment
		(start 418.486844 -386.724906)
		(end 417.681918 -385.935728)
		(width 0.1651)
		(layer "In5.Cu")
		(net "P5E_PEX3_STN4_RX_DP<73>")
	)
	(segment
		(start 427.28388 -319.9384)
		(end 427.28388 -319.909952)
		(width 0.1143)
		(layer "In5.Cu")
		(net "P5E_PEX3_STN4_RX_DP<73>")
	)
	(segment
		(start 425.322746 -390.46785)
		(end 424.885358 -390.234678)
		(width 0.1651)
		(layer "In5.Cu")
		(net "P5E_PEX3_STN4_RX_DP<73>")
	)
	(segment
		(start 433.368704 -394.785596)
		(end 433.010818 -394.46327)
		(width 0.1651)
		(layer "In5.Cu")
		(net "P5E_PEX3_STN4_RX_DP<73>")
	)
	(segment
		(start 433.233322 -404.802848)
		(end 433.565808 -404.470362)
		(width 0.1651)
		(layer "In5.Cu")
		(net "P5E_PEX3_STN4_RX_DP<73>")
	)
	(segment
		(start 417.681918 -385.935728)
		(end 416.917886 -384.098292)
		(width 0.1651)
		(layer "In5.Cu")
		(net "P5E_PEX3_STN4_RX_DP<73>")
	)
	(segment
		(start 427.78553 -316.229492)
		(end 427.89983 -316.115192)
		(width 0.1143)
		(layer "In5.Cu")
		(net "P5E_PEX3_STN4_RX_DP<73>")
	)
	(segment
		(start 424.885358 -390.234678)
		(end 424.848782 -390.114536)
		(width 0.1651)
		(layer "In5.Cu")
		(net "P5E_PEX3_STN4_RX_DP<73>")
	)
	(segment
		(start 426.685202 -342.209374)
		(end 427.28388 -331.682598)
		(width 0.1651)
		(layer "In5.Cu")
		(net "P5E_PEX3_STN4_RX_DP<73>")
	)
	(segment
		(start 424.848782 -390.114536)
		(end 418.486844 -386.724906)
		(width 0.1651)
		(layer "In5.Cu")
		(net "P5E_PEX3_STN4_RX_DP<73>")
	)
	(segment
		(start 416.955986 -370.15293)
		(end 417.211002 -368.866674)
		(width 0.1651)
		(layer "In5.Cu")
		(net "P5E_PEX3_STN4_RX_DP<73>")
	)
	(segment
		(start 427.555406 -316.229492)
		(end 427.78553 -316.229492)
		(width 0.1143)
		(layer "In5.Cu")
		(net "P5E_PEX3_STN4_RX_DP<73>")
	)
	(segment
		(start 427.38548 -391.566908)
		(end 426.948092 -391.333736)
		(width 0.1651)
		(layer "In5.Cu")
		(net "P5E_PEX3_STN4_RX_DP<73>")
	)
	(segment
		(start 432.86299 -404.802848)
		(end 433.233322 -404.802848)
		(width 0.1651)
		(layer "In5.Cu")
		(net "P5E_PEX3_STN4_RX_DP<73>")
	)
	(segment
		(start 432.689762 -404.290022)
		(end 432.689762 -404.62962)
		(width 0.1651)
		(layer "In5.Cu")
		(net "P5E_PEX3_STN4_RX_DP<73>")
	)
	(segment
		(start 131.082796 -222.32493)
		(end 131.932426 -222.32493)
		(width 0.13208)
		(layer "F.Cu")
		(net "SPI_PEX1_SDIO0_MUX_R")
	)
	(segment
		(start 131.932426 -222.32493)
		(end 132.30098 -222.172276)
		(width 0.13208)
		(layer "F.Cu")
		(net "SPI_PEX1_SDIO0_MUX_R")
	)
	(via
		(at 132.30098 -222.172276)
		(size 0.508)
		(drill 0.254)
		(layers "F.Cu" "B.Cu")
		(net "SPI_PEX1_SDIO0_MUX_R")
	)
	(segment
		(start 135.33882 -222.214186)
		(end 135.33882 -221.92361)
		(width 0.13208)
		(layer "B.Cu")
		(net "SPI_PEX1_SDIO0_MUX_R")
	)
	(segment
		(start 134.26821 -220.853)
		(end 133.620256 -220.853)
		(width 0.13208)
		(layer "B.Cu")
		(net "SPI_PEX1_SDIO0_MUX_R")
	)
	(segment
		(start 133.620256 -220.853)
		(end 132.30098 -222.172276)
		(width 0.13208)
		(layer "B.Cu")
		(net "SPI_PEX1_SDIO0_MUX_R")
	)
	(segment
		(start 135.33882 -221.92361)
		(end 134.26821 -220.853)
		(width 0.13208)
		(layer "B.Cu")
		(net "SPI_PEX1_SDIO0_MUX_R")
	)
	(segment
		(start 428.244 -351.31629)
		(end 427.948852 -351.611438)
		(width 0.13462)
		(layer "F.Cu")
		(net "P5E_PEX3_STN4_TX_C_DP<70>")
	)
	(segment
		(start 427.923452 -350.365314)
		(end 428.244 -350.685862)
		(width 0.13462)
		(layer "F.Cu")
		(net "P5E_PEX3_STN4_TX_C_DP<70>")
	)
	(segment
		(start 428.244 -350.685862)
		(end 428.244 -351.31629)
		(width 0.13462)
		(layer "F.Cu")
		(net "P5E_PEX3_STN4_TX_C_DP<70>")
	)
	(segment
		(start 428.239682 -352.356166)
		(end 428.239682 -351.902268)
		(width 0.1651)
		(layer "In7.Cu")
		(net "P5E_PEX3_STN4_TX_C_DP<70>")
	)
	(segment
		(start 425.039028 -362.744258)
		(end 425.039282 -362.744258)
		(width 0.1651)
		(layer "In7.Cu")
		(net "P5E_PEX3_STN4_TX_C_DP<70>")
	)
	(segment
		(start 422.696132 -368.12601)
		(end 422.886378 -367.668048)
		(width 0.1651)
		(layer "In7.Cu")
		(net "P5E_PEX3_STN4_TX_C_DP<70>")
	)
	(segment
		(start 425.49699 -361.64139)
		(end 425.441872 -361.508802)
		(width 0.1651)
		(layer "In7.Cu")
		(net "P5E_PEX3_STN4_TX_C_DP<70>")
	)
	(segment
		(start 424.391582 -364.30458)
		(end 424.58132 -363.847126)
		(width 0.1651)
		(layer "In7.Cu")
		(net "P5E_PEX3_STN4_TX_C_DP<70>")
	)
	(segment
		(start 423.934128 -365.407448)
		(end 424.123866 -364.949994)
		(width 0.1651)
		(layer "In7.Cu")
		(net "P5E_PEX3_STN4_TX_C_DP<70>")
	)
	(segment
		(start 423.666412 -366.052862)
		(end 423.611548 -365.920274)
		(width 0.1651)
		(layer "In7.Cu")
		(net "P5E_PEX3_STN4_TX_C_DP<70>")
	)
	(segment
		(start 425.17441 -362.153708)
		(end 425.307252 -362.098844)
		(width 0.1651)
		(layer "In7.Cu")
		(net "P5E_PEX3_STN4_TX_C_DP<70>")
	)
	(segment
		(start 421.816784 -372.099078)
		(end 422.24706 -372.099078)
		(width 0.1651)
		(layer "In7.Cu")
		(net "P5E_PEX3_STN4_TX_C_DP<70>")
	)
	(segment
		(start 424.259248 -364.359444)
		(end 424.39209 -364.30458)
		(width 0.1651)
		(layer "In7.Cu")
		(net "P5E_PEX3_STN4_TX_C_DP<70>")
	)
	(segment
		(start 422.533826 -371.812312)
		(end 422.533826 -368.7826)
		(width 0.1651)
		(layer "In7.Cu")
		(net "P5E_PEX3_STN4_TX_C_DP<70>")
	)
	(segment
		(start 424.581828 -363.847126)
		(end 424.526964 -363.714538)
		(width 0.1651)
		(layer "In7.Cu")
		(net "P5E_PEX3_STN4_TX_C_DP<70>")
	)
	(segment
		(start 423.15384 -367.023142)
		(end 423.343832 -366.565434)
		(width 0.1651)
		(layer "In7.Cu")
		(net "P5E_PEX3_STN4_TX_C_DP<70>")
	)
	(segment
		(start 422.533826 -368.7826)
		(end 422.75125 -368.258598)
		(width 0.1651)
		(layer "In7.Cu")
		(net "P5E_PEX3_STN4_TX_C_DP<70>")
	)
	(segment
		(start 426.685202 -358.777032)
		(end 426.685202 -353.910646)
		(width 0.1651)
		(layer "In7.Cu")
		(net "P5E_PEX3_STN4_TX_C_DP<70>")
	)
	(segment
		(start 425.039282 -362.744258)
		(end 424.984418 -362.61167)
		(width 0.1651)
		(layer "In7.Cu")
		(net "P5E_PEX3_STN4_TX_C_DP<70>")
	)
	(segment
		(start 424.12412 -364.949994)
		(end 424.069256 -364.817406)
		(width 0.1651)
		(layer "In7.Cu")
		(net "P5E_PEX3_STN4_TX_C_DP<70>")
	)
	(segment
		(start 426.685202 -353.910646)
		(end 428.239682 -352.356166)
		(width 0.1651)
		(layer "In7.Cu")
		(net "P5E_PEX3_STN4_TX_C_DP<70>")
	)
	(segment
		(start 423.80154 -365.462312)
		(end 423.934382 -365.407448)
		(width 0.1651)
		(layer "In7.Cu")
		(net "P5E_PEX3_STN4_TX_C_DP<70>")
	)
	(segment
		(start 421.689784 -371.972078)
		(end 421.816784 -372.099078)
		(width 0.1651)
		(layer "In7.Cu")
		(net "P5E_PEX3_STN4_TX_C_DP<70>")
	)
	(segment
		(start 425.306744 -362.098844)
		(end 425.496736 -361.64139)
		(width 0.1651)
		(layer "In7.Cu")
		(net "P5E_PEX3_STN4_TX_C_DP<70>")
	)
	(segment
		(start 425.764706 -360.995976)
		(end 425.764452 -360.995976)
		(width 0.1651)
		(layer "In7.Cu")
		(net "P5E_PEX3_STN4_TX_C_DP<70>")
	)
	(segment
		(start 423.934382 -365.407448)
		(end 423.934128 -365.407448)
		(width 0.1651)
		(layer "In7.Cu")
		(net "P5E_PEX3_STN4_TX_C_DP<70>")
	)
	(segment
		(start 422.24706 -372.099078)
		(end 422.533826 -371.812312)
		(width 0.1651)
		(layer "In7.Cu")
		(net "P5E_PEX3_STN4_TX_C_DP<70>")
	)
	(segment
		(start 424.849544 -363.201712)
		(end 424.849036 -363.201712)
		(width 0.1651)
		(layer "In7.Cu")
		(net "P5E_PEX3_STN4_TX_C_DP<70>")
	)
	(segment
		(start 424.58132 -363.847126)
		(end 424.581828 -363.847126)
		(width 0.1651)
		(layer "In7.Cu")
		(net "P5E_PEX3_STN4_TX_C_DP<70>")
	)
	(segment
		(start 423.343832 -366.565434)
		(end 423.476674 -366.510316)
		(width 0.1651)
		(layer "In7.Cu")
		(net "P5E_PEX3_STN4_TX_C_DP<70>")
	)
	(segment
		(start 423.476674 -366.510316)
		(end 423.666412 -366.052862)
		(width 0.1651)
		(layer "In7.Cu")
		(net "P5E_PEX3_STN4_TX_C_DP<70>")
	)
	(segment
		(start 423.208704 -367.15573)
		(end 423.15384 -367.023142)
		(width 0.1651)
		(layer "In7.Cu")
		(net "P5E_PEX3_STN4_TX_C_DP<70>")
	)
	(segment
		(start 424.069256 -364.817406)
		(end 424.259248 -364.359444)
		(width 0.1651)
		(layer "In7.Cu")
		(net "P5E_PEX3_STN4_TX_C_DP<70>")
	)
	(segment
		(start 425.496736 -361.64139)
		(end 425.49699 -361.64139)
		(width 0.1651)
		(layer "In7.Cu")
		(net "P5E_PEX3_STN4_TX_C_DP<70>")
	)
	(segment
		(start 425.764452 -360.995976)
		(end 426.685202 -358.777032)
		(width 0.1651)
		(layer "In7.Cu")
		(net "P5E_PEX3_STN4_TX_C_DP<70>")
	)
	(segment
		(start 422.886378 -367.668048)
		(end 423.018966 -367.613184)
		(width 0.1651)
		(layer "In7.Cu")
		(net "P5E_PEX3_STN4_TX_C_DP<70>")
	)
	(segment
		(start 421.689784 -371.590062)
		(end 421.689784 -371.972078)
		(width 0.1651)
		(layer "In7.Cu")
		(net "P5E_PEX3_STN4_TX_C_DP<70>")
	)
	(segment
		(start 425.441872 -361.508802)
		(end 425.632118 -361.05084)
		(width 0.1651)
		(layer "In7.Cu")
		(net "P5E_PEX3_STN4_TX_C_DP<70>")
	)
	(segment
		(start 428.239682 -351.902268)
		(end 427.948852 -351.611438)
		(width 0.1651)
		(layer "In7.Cu")
		(net "P5E_PEX3_STN4_TX_C_DP<70>")
	)
	(segment
		(start 424.984418 -362.61167)
		(end 425.17441 -362.153708)
		(width 0.1651)
		(layer "In7.Cu")
		(net "P5E_PEX3_STN4_TX_C_DP<70>")
	)
	(segment
		(start 425.307252 -362.098844)
		(end 425.306744 -362.098844)
		(width 0.1651)
		(layer "In7.Cu")
		(net "P5E_PEX3_STN4_TX_C_DP<70>")
	)
	(segment
		(start 424.39209 -364.30458)
		(end 424.391582 -364.30458)
		(width 0.1651)
		(layer "In7.Cu")
		(net "P5E_PEX3_STN4_TX_C_DP<70>")
	)
	(segment
		(start 424.716956 -363.256576)
		(end 424.849544 -363.201712)
		(width 0.1651)
		(layer "In7.Cu")
		(net "P5E_PEX3_STN4_TX_C_DP<70>")
	)
	(segment
		(start 425.632118 -361.05084)
		(end 425.764706 -360.995976)
		(width 0.1651)
		(layer "In7.Cu")
		(net "P5E_PEX3_STN4_TX_C_DP<70>")
	)
	(segment
		(start 423.018966 -367.613184)
		(end 423.208704 -367.15573)
		(width 0.1651)
		(layer "In7.Cu")
		(net "P5E_PEX3_STN4_TX_C_DP<70>")
	)
	(segment
		(start 423.611548 -365.920274)
		(end 423.80154 -365.462312)
		(width 0.1651)
		(layer "In7.Cu")
		(net "P5E_PEX3_STN4_TX_C_DP<70>")
	)
	(segment
		(start 424.526964 -363.714538)
		(end 424.716956 -363.256576)
		(width 0.1651)
		(layer "In7.Cu")
		(net "P5E_PEX3_STN4_TX_C_DP<70>")
	)
	(segment
		(start 424.123866 -364.949994)
		(end 424.12412 -364.949994)
		(width 0.1651)
		(layer "In7.Cu")
		(net "P5E_PEX3_STN4_TX_C_DP<70>")
	)
	(segment
		(start 424.849036 -363.201712)
		(end 425.039028 -362.744258)
		(width 0.1651)
		(layer "In7.Cu")
		(net "P5E_PEX3_STN4_TX_C_DP<70>")
	)
	(segment
		(start 422.75125 -368.258598)
		(end 422.696132 -368.12601)
		(width 0.1651)
		(layer "In7.Cu")
		(net "P5E_PEX3_STN4_TX_C_DP<70>")
	)
	(segment
		(start 139.275058 -229.94493)
		(end 140.68298 -229.94493)
		(width 0.13208)
		(layer "F.Cu")
		(net "SPI_PEX1_SDIO1_MUX_R")
	)
	(via
		(at 139.275058 -229.94493)
		(size 0.508)
		(drill 0.254)
		(layers "F.Cu" "B.Cu")
		(net "SPI_PEX1_SDIO1_MUX_R")
	)
	(segment
		(start 139.275058 -228.74605)
		(end 139.275058 -229.94493)
		(width 0.13208)
		(layer "B.Cu")
		(net "SPI_PEX1_SDIO1_MUX_R")
	)
	(segment
		(start 431.35296 -344.53957)
		(end 431.35296 -345.169998)
		(width 0.13462)
		(layer "F.Cu")
		(net "P5E_PEX3_STN4_TX_C_DP<69>")
	)
	(segment
		(start 431.35296 -345.169998)
		(end 431.057812 -345.465146)
		(width 0.13462)
		(layer "F.Cu")
		(net "P5E_PEX3_STN4_TX_C_DP<69>")
	)
	(segment
		(start 431.032412 -344.219022)
		(end 431.35296 -344.53957)
		(width 0.13462)
		(layer "F.Cu")
		(net "P5E_PEX3_STN4_TX_C_DP<69>")
	)
	(segment
		(start 428.436024 -361.235498)
		(end 428.58944 -361.185206)
		(width 0.1651)
		(layer "In7.Cu")
		(net "P5E_PEX3_STN4_TX_C_DP<69>")
	)
	(segment
		(start 425.2849 -367.712498)
		(end 425.284646 -367.712498)
		(width 0.1651)
		(layer "In7.Cu")
		(net "P5E_PEX3_STN4_TX_C_DP<69>")
	)
	(segment
		(start 425.682156 -366.674908)
		(end 425.835826 -366.624616)
		(width 0.1651)
		(layer "In7.Cu")
		(net "P5E_PEX3_STN4_TX_C_DP<69>")
	)
	(segment
		(start 426.559726 -364.941358)
		(end 426.783754 -364.499144)
		(width 0.1651)
		(layer "In7.Cu")
		(net "P5E_PEX3_STN4_TX_C_DP<69>")
	)
	(segment
		(start 424.733974 -368.80038)
		(end 424.957494 -368.358674)
		(width 0.1651)
		(layer "In7.Cu")
		(net "P5E_PEX3_STN4_TX_C_DP<69>")
	)
	(segment
		(start 428.038514 -362.273088)
		(end 428.262034 -361.831382)
		(width 0.1651)
		(layer "In7.Cu")
		(net "P5E_PEX3_STN4_TX_C_DP<69>")
	)
	(segment
		(start 426.783754 -364.499144)
		(end 426.93717 -364.448852)
		(width 0.1651)
		(layer "In7.Cu")
		(net "P5E_PEX3_STN4_TX_C_DP<69>")
	)
	(segment
		(start 428.770542 -360.614468)
		(end 429.01108 -360.139488)
		(width 0.1651)
		(layer "In7.Cu")
		(net "P5E_PEX3_STN4_TX_C_DP<69>")
	)
	(segment
		(start 425.13123 -367.76279)
		(end 425.2849 -367.712498)
		(width 0.1651)
		(layer "In7.Cu")
		(net "P5E_PEX3_STN4_TX_C_DP<69>")
	)
	(segment
		(start 431.348642 -345.755976)
		(end 431.057812 -345.465146)
		(width 0.1651)
		(layer "In7.Cu")
		(net "P5E_PEX3_STN4_TX_C_DP<69>")
	)
	(segment
		(start 427.711362 -362.91901)
		(end 427.711616 -362.919264)
		(width 0.1651)
		(layer "In7.Cu")
		(net "P5E_PEX3_STN4_TX_C_DP<69>")
	)
	(segment
		(start 423.889932 -370.489988)
		(end 423.889932 -370.872258)
		(width 0.1651)
		(layer "In7.Cu")
		(net "P5E_PEX3_STN4_TX_C_DP<69>")
	)
	(segment
		(start 427.711616 -362.919264)
		(end 427.661324 -362.765594)
		(width 0.1651)
		(layer "In7.Cu")
		(net "P5E_PEX3_STN4_TX_C_DP<69>")
	)
	(segment
		(start 428.58944 -361.185206)
		(end 428.812706 -360.7435)
		(width 0.1651)
		(layer "In7.Cu")
		(net "P5E_PEX3_STN4_TX_C_DP<69>")
	)
	(segment
		(start 427.487842 -363.360716)
		(end 427.711362 -362.91901)
		(width 0.1651)
		(layer "In7.Cu")
		(net "P5E_PEX3_STN4_TX_C_DP<69>")
	)
	(segment
		(start 426.936916 -364.448598)
		(end 427.160436 -364.007146)
		(width 0.1651)
		(layer "In7.Cu")
		(net "P5E_PEX3_STN4_TX_C_DP<69>")
	)
	(segment
		(start 425.508166 -367.270792)
		(end 425.50842 -367.270792)
		(width 0.1651)
		(layer "In7.Cu")
		(net "P5E_PEX3_STN4_TX_C_DP<69>")
	)
	(segment
		(start 427.488096 -363.36097)
		(end 427.487842 -363.360716)
		(width 0.1651)
		(layer "In7.Cu")
		(net "P5E_PEX3_STN4_TX_C_DP<69>")
	)
	(segment
		(start 427.110398 -363.853476)
		(end 427.334426 -363.411262)
		(width 0.1651)
		(layer "In7.Cu")
		(net "P5E_PEX3_STN4_TX_C_DP<69>")
	)
	(segment
		(start 426.059092 -366.18291)
		(end 426.059346 -366.18291)
		(width 0.1651)
		(layer "In7.Cu")
		(net "P5E_PEX3_STN4_TX_C_DP<69>")
	)
	(segment
		(start 425.458128 -367.117122)
		(end 425.682156 -366.674908)
		(width 0.1651)
		(layer "In7.Cu")
		(net "P5E_PEX3_STN4_TX_C_DP<69>")
	)
	(segment
		(start 427.885352 -362.32338)
		(end 428.038768 -362.273088)
		(width 0.1651)
		(layer "In7.Cu")
		(net "P5E_PEX3_STN4_TX_C_DP<69>")
	)
	(segment
		(start 426.009054 -366.02924)
		(end 426.233082 -365.587026)
		(width 0.1651)
		(layer "In7.Cu")
		(net "P5E_PEX3_STN4_TX_C_DP<69>")
	)
	(segment
		(start 428.812706 -360.7435)
		(end 428.770542 -360.614468)
		(width 0.1651)
		(layer "In7.Cu")
		(net "P5E_PEX3_STN4_TX_C_DP<69>")
	)
	(segment
		(start 427.16069 -364.007146)
		(end 427.110398 -363.853476)
		(width 0.1651)
		(layer "In7.Cu")
		(net "P5E_PEX3_STN4_TX_C_DP<69>")
	)
	(segment
		(start 426.610018 -365.095028)
		(end 426.559726 -364.941358)
		(width 0.1651)
		(layer "In7.Cu")
		(net "P5E_PEX3_STN4_TX_C_DP<69>")
	)
	(segment
		(start 425.835572 -366.624362)
		(end 426.059092 -366.18291)
		(width 0.1651)
		(layer "In7.Cu")
		(net "P5E_PEX3_STN4_TX_C_DP<69>")
	)
	(segment
		(start 425.835826 -366.624616)
		(end 425.835572 -366.624362)
		(width 0.1651)
		(layer "In7.Cu")
		(net "P5E_PEX3_STN4_TX_C_DP<69>")
	)
	(segment
		(start 427.334426 -363.411262)
		(end 427.488096 -363.36097)
		(width 0.1651)
		(layer "In7.Cu")
		(net "P5E_PEX3_STN4_TX_C_DP<69>")
	)
	(segment
		(start 429.140112 -360.097324)
		(end 429.794162 -358.80548)
		(width 0.1651)
		(layer "In7.Cu")
		(net "P5E_PEX3_STN4_TX_C_DP<69>")
	)
	(segment
		(start 424.733974 -370.712492)
		(end 424.733974 -368.80038)
		(width 0.1651)
		(layer "In7.Cu")
		(net "P5E_PEX3_STN4_TX_C_DP<69>")
	)
	(segment
		(start 425.284646 -367.712498)
		(end 425.508166 -367.270792)
		(width 0.1651)
		(layer "In7.Cu")
		(net "P5E_PEX3_STN4_TX_C_DP<69>")
	)
	(segment
		(start 425.50842 -367.270792)
		(end 425.458128 -367.117122)
		(width 0.1651)
		(layer "In7.Cu")
		(net "P5E_PEX3_STN4_TX_C_DP<69>")
	)
	(segment
		(start 429.794162 -358.80548)
		(end 429.794162 -347.764354)
		(width 0.1651)
		(layer "In7.Cu")
		(net "P5E_PEX3_STN4_TX_C_DP<69>")
	)
	(segment
		(start 431.348642 -346.209874)
		(end 431.348642 -345.755976)
		(width 0.1651)
		(layer "In7.Cu")
		(net "P5E_PEX3_STN4_TX_C_DP<69>")
	)
	(segment
		(start 424.957494 -368.358674)
		(end 424.907202 -368.205004)
		(width 0.1651)
		(layer "In7.Cu")
		(net "P5E_PEX3_STN4_TX_C_DP<69>")
	)
	(segment
		(start 429.794162 -347.764354)
		(end 431.348642 -346.209874)
		(width 0.1651)
		(layer "In7.Cu")
		(net "P5E_PEX3_STN4_TX_C_DP<69>")
	)
	(segment
		(start 429.01108 -360.139488)
		(end 429.140112 -360.097324)
		(width 0.1651)
		(layer "In7.Cu")
		(net "P5E_PEX3_STN4_TX_C_DP<69>")
	)
	(segment
		(start 427.160436 -364.007146)
		(end 427.16069 -364.007146)
		(width 0.1651)
		(layer "In7.Cu")
		(net "P5E_PEX3_STN4_TX_C_DP<69>")
	)
	(segment
		(start 428.262034 -361.831382)
		(end 428.262288 -361.831382)
		(width 0.1651)
		(layer "In7.Cu")
		(net "P5E_PEX3_STN4_TX_C_DP<69>")
	)
	(segment
		(start 428.211996 -361.677712)
		(end 428.436024 -361.235498)
		(width 0.1651)
		(layer "In7.Cu")
		(net "P5E_PEX3_STN4_TX_C_DP<69>")
	)
	(segment
		(start 424.016932 -370.999258)
		(end 424.447208 -370.999258)
		(width 0.1651)
		(layer "In7.Cu")
		(net "P5E_PEX3_STN4_TX_C_DP<69>")
	)
	(segment
		(start 424.447208 -370.999258)
		(end 424.733974 -370.712492)
		(width 0.1651)
		(layer "In7.Cu")
		(net "P5E_PEX3_STN4_TX_C_DP<69>")
	)
	(segment
		(start 426.93717 -364.448852)
		(end 426.936916 -364.448598)
		(width 0.1651)
		(layer "In7.Cu")
		(net "P5E_PEX3_STN4_TX_C_DP<69>")
	)
	(segment
		(start 428.038768 -362.273088)
		(end 428.038514 -362.273088)
		(width 0.1651)
		(layer "In7.Cu")
		(net "P5E_PEX3_STN4_TX_C_DP<69>")
	)
	(segment
		(start 427.661324 -362.765594)
		(end 427.885352 -362.32338)
		(width 0.1651)
		(layer "In7.Cu")
		(net "P5E_PEX3_STN4_TX_C_DP<69>")
	)
	(segment
		(start 426.059346 -366.18291)
		(end 426.009054 -366.02924)
		(width 0.1651)
		(layer "In7.Cu")
		(net "P5E_PEX3_STN4_TX_C_DP<69>")
	)
	(segment
		(start 426.233082 -365.587026)
		(end 426.386498 -365.536734)
		(width 0.1651)
		(layer "In7.Cu")
		(net "P5E_PEX3_STN4_TX_C_DP<69>")
	)
	(segment
		(start 428.262288 -361.831382)
		(end 428.211996 -361.677712)
		(width 0.1651)
		(layer "In7.Cu")
		(net "P5E_PEX3_STN4_TX_C_DP<69>")
	)
	(segment
		(start 426.386244 -365.53648)
		(end 426.609764 -365.095028)
		(width 0.1651)
		(layer "In7.Cu")
		(net "P5E_PEX3_STN4_TX_C_DP<69>")
	)
	(segment
		(start 426.609764 -365.095028)
		(end 426.610018 -365.095028)
		(width 0.1651)
		(layer "In7.Cu")
		(net "P5E_PEX3_STN4_TX_C_DP<69>")
	)
	(segment
		(start 424.907202 -368.205004)
		(end 425.13123 -367.76279)
		(width 0.1651)
		(layer "In7.Cu")
		(net "P5E_PEX3_STN4_TX_C_DP<69>")
	)
	(segment
		(start 426.386498 -365.536734)
		(end 426.386244 -365.53648)
		(width 0.1651)
		(layer "In7.Cu")
		(net "P5E_PEX3_STN4_TX_C_DP<69>")
	)
	(segment
		(start 423.889932 -370.872258)
		(end 424.016932 -370.999258)
		(width 0.1651)
		(layer "In7.Cu")
		(net "P5E_PEX3_STN4_TX_C_DP<69>")
	)
	(segment
		(start 158.649924 -292.099746)
		(end 158.174944 -291.624766)
		(width 0.13208)
		(layer "F.Cu")
		(net "SPI_PEX1_CS_N")
	)
	(via
		(at 158.174944 -291.624766)
		(size 0.4064)
		(drill 0.2032)
		(layers "F.Cu" "B.Cu")
		(net "SPI_PEX1_CS_N")
	)
	(via
		(at 158.646876 -291.152834)
		(size 0.6604)
		(drill 0.3302)
		(layers "F.Cu" "B.Cu")
		(net "SPI_PEX1_CS_N")
	)
	(segment
		(start 158.646876 -291.152834)
		(end 158.174944 -291.624766)
		(width 0.13208)
		(layer "B.Cu")
		(net "SPI_PEX1_CS_N")
	)
	(segment
		(start 158.646876 -289.514026)
		(end 158.646876 -291.152834)
		(width 0.13208)
		(layer "B.Cu")
		(net "SPI_PEX1_CS_N")
	)
	(segment
		(start 157.699964 -289.174936)
		(end 156.750004 -289.174936)
		(width 0.13208)
		(layer "B.Cu")
		(net "SPI_PEX1_CS_N")
	)
	(segment
		(start 158.307786 -289.174936)
		(end 158.646876 -289.514026)
		(width 0.13208)
		(layer "B.Cu")
		(net "SPI_PEX1_CS_N")
	)
	(segment
		(start 157.699964 -289.174936)
		(end 158.307786 -289.174936)
		(width 0.13208)
		(layer "B.Cu")
		(net "SPI_PEX1_CS_N")
	)
	(segment
		(start 422.085516 -316.419992)
		(end 422.199816 -316.534292)
		(width 0.1143)
		(layer "In5.Cu")
		(net "P5E_PEX3_STN4_RX_DN<79>")
	)
	(segment
		(start 422.199816 -316.534292)
		(end 422.199816 -316.799722)
		(width 0.1143)
		(layer "In5.Cu")
		(net "P5E_PEX3_STN4_RX_DN<79>")
	)
	(segment
		(start 411.2895 -385.30022)
		(end 408.485594 -358.70896)
		(width 0.1651)
		(layer "In5.Cu")
		(net "P5E_PEX3_STN4_RX_DN<79>")
	)
	(segment
		(start 421.865806 -319.909952)
		(end 421.820086 -319.864232)
		(width 0.1143)
		(layer "In5.Cu")
		(net "P5E_PEX3_STN4_RX_DN<79>")
	)
	(segment
		(start 408.48534 -358.70896)
		(end 408.10434 -343.7001)
		(width 0.1651)
		(layer "In5.Cu")
		(net "P5E_PEX3_STN4_RX_DN<79>")
	)
	(segment
		(start 420.647876 -404.587202)
		(end 420.647876 -395.55674)
		(width 0.1651)
		(layer "In5.Cu")
		(net "P5E_PEX3_STN4_RX_DN<79>")
	)
	(segment
		(start 413.00654 -389.19658)
		(end 411.2895 -385.30022)
		(width 0.1651)
		(layer "In5.Cu")
		(net "P5E_PEX3_STN4_RX_DN<79>")
	)
	(segment
		(start 420.15029 -405.084788)
		(end 420.647876 -404.587202)
		(width 0.1651)
		(layer "In5.Cu")
		(net "P5E_PEX3_STN4_RX_DN<79>")
	)
	(segment
		(start 420.647876 -395.55674)
		(end 420.570914 -394.871702)
		(width 0.1651)
		(layer "In5.Cu")
		(net "P5E_PEX3_STN4_RX_DN<79>")
	)
	(segment
		(start 408.33548 -341.823294)
		(end 421.865806 -321.372738)
		(width 0.1651)
		(layer "In5.Cu")
		(net "P5E_PEX3_STN4_RX_DN<79>")
	)
	(segment
		(start 421.865806 -321.372738)
		(end 421.865806 -319.9384)
		(width 0.1651)
		(layer "In5.Cu")
		(net "P5E_PEX3_STN4_RX_DN<79>")
	)
	(segment
		(start 421.865806 -319.9384)
		(end 421.865806 -319.909952)
		(width 0.1143)
		(layer "In5.Cu")
		(net "P5E_PEX3_STN4_RX_DN<79>")
	)
	(segment
		(start 408.10434 -343.7001)
		(end 408.33548 -341.823294)
		(width 0.1651)
		(layer "In5.Cu")
		(net "P5E_PEX3_STN4_RX_DN<79>")
	)
	(segment
		(start 421.934386 -316.419992)
		(end 422.085516 -316.419992)
		(width 0.1143)
		(layer "In5.Cu")
		(net "P5E_PEX3_STN4_RX_DN<79>")
	)
	(segment
		(start 421.820086 -316.534292)
		(end 421.934386 -316.419992)
		(width 0.1143)
		(layer "In5.Cu")
		(net "P5E_PEX3_STN4_RX_DN<79>")
	)
	(segment
		(start 408.485594 -358.70896)
		(end 408.48534 -358.70896)
		(width 0.1651)
		(layer "In5.Cu")
		(net "P5E_PEX3_STN4_RX_DN<79>")
	)
	(segment
		(start 420.570914 -394.871702)
		(end 420.06266 -394.401548)
		(width 0.1651)
		(layer "In5.Cu")
		(net "P5E_PEX3_STN4_RX_DN<79>")
	)
	(segment
		(start 419.48989 -405.258016)
		(end 419.663118 -405.084788)
		(width 0.1651)
		(layer "In5.Cu")
		(net "P5E_PEX3_STN4_RX_DN<79>")
	)
	(segment
		(start 421.820086 -319.864232)
		(end 421.820086 -316.534292)
		(width 0.1143)
		(layer "In5.Cu")
		(net "P5E_PEX3_STN4_RX_DN<79>")
	)
	(segment
		(start 415.12236 -391.33526)
		(end 413.00654 -389.19658)
		(width 0.1651)
		(layer "In5.Cu")
		(net "P5E_PEX3_STN4_RX_DN<79>")
	)
	(segment
		(start 420.06266 -394.401548)
		(end 415.12236 -391.33526)
		(width 0.1651)
		(layer "In5.Cu")
		(net "P5E_PEX3_STN4_RX_DN<79>")
	)
	(segment
		(start 419.663118 -405.084788)
		(end 420.15029 -405.084788)
		(width 0.1651)
		(layer "In5.Cu")
		(net "P5E_PEX3_STN4_RX_DN<79>")
	)
	(segment
		(start 419.48989 -405.589994)
		(end 419.48989 -405.258016)
		(width 0.1651)
		(layer "In5.Cu")
		(net "P5E_PEX3_STN4_RX_DN<79>")
	)
	(segment
		(start 437.8452 -344.538554)
		(end 437.8452 -345.171014)
		(width 0.13462)
		(layer "F.Cu")
		(net "P5E_PEX3_STN4_TX_C_DN<66>")
	)
	(segment
		(start 437.8452 -345.171014)
		(end 438.139332 -345.465146)
		(width 0.13462)
		(layer "F.Cu")
		(net "P5E_PEX3_STN4_TX_C_DN<66>")
	)
	(segment
		(start 438.164732 -344.219022)
		(end 437.8452 -344.538554)
		(width 0.13462)
		(layer "F.Cu")
		(net "P5E_PEX3_STN4_TX_C_DN<66>")
	)
	(segment
		(start 431.61585 -368.827812)
		(end 431.61585 -371.929152)
		(width 0.1651)
		(layer "In7.Cu")
		(net "P5E_PEX3_STN4_TX_C_DN<66>")
	)
	(segment
		(start 437.848502 -345.755976)
		(end 437.848502 -346.326714)
		(width 0.1651)
		(layer "In7.Cu")
		(net "P5E_PEX3_STN4_TX_C_DN<66>")
	)
	(segment
		(start 437.848502 -346.326714)
		(end 436.294022 -347.881194)
		(width 0.1651)
		(layer "In7.Cu")
		(net "P5E_PEX3_STN4_TX_C_DN<66>")
	)
	(segment
		(start 436.294022 -358.868472)
		(end 431.61585 -368.827812)
		(width 0.1651)
		(layer "In7.Cu")
		(net "P5E_PEX3_STN4_TX_C_DN<66>")
	)
	(segment
		(start 431.61585 -371.929152)
		(end 431.163984 -372.381018)
		(width 0.1651)
		(layer "In7.Cu")
		(net "P5E_PEX3_STN4_TX_C_DN<66>")
	)
	(segment
		(start 430.489868 -372.508018)
		(end 430.489868 -372.890034)
		(width 0.1651)
		(layer "In7.Cu")
		(net "P5E_PEX3_STN4_TX_C_DN<66>")
	)
	(segment
		(start 431.163984 -372.381018)
		(end 430.616868 -372.381018)
		(width 0.1651)
		(layer "In7.Cu")
		(net "P5E_PEX3_STN4_TX_C_DN<66>")
	)
	(segment
		(start 436.294022 -347.881194)
		(end 436.294022 -358.868472)
		(width 0.1651)
		(layer "In7.Cu")
		(net "P5E_PEX3_STN4_TX_C_DN<66>")
	)
	(segment
		(start 430.616868 -372.381018)
		(end 430.489868 -372.508018)
		(width 0.1651)
		(layer "In7.Cu")
		(net "P5E_PEX3_STN4_TX_C_DN<66>")
	)
	(segment
		(start 438.139332 -345.465146)
		(end 437.848502 -345.755976)
		(width 0.1651)
		(layer "In7.Cu")
		(net "P5E_PEX3_STN4_TX_C_DN<66>")
	)
	(segment
		(start 412.97352 -356.831138)
		(end 412.97352 -357.463598)
		(width 0.13462)
		(layer "F.Cu")
		(net "P5E_PEX3_STN4_TX_C_DN<77>")
	)
	(segment
		(start 412.97352 -357.463598)
		(end 413.267652 -357.75773)
		(width 0.13462)
		(layer "F.Cu")
		(net "P5E_PEX3_STN4_TX_C_DN<77>")
	)
	(segment
		(start 413.293052 -356.511606)
		(end 412.97352 -356.831138)
		(width 0.13462)
		(layer "F.Cu")
		(net "P5E_PEX3_STN4_TX_C_DN<77>")
	)
	(segment
		(start 423.889932 -397.790162)
		(end 423.889932 -397.408146)
		(width 0.1651)
		(layer "In7.Cu")
		(net "P5E_PEX3_STN4_TX_C_DN<77>")
	)
	(segment
		(start 415.76498 -389.114538)
		(end 413.87649 -386.747512)
		(width 0.1651)
		(layer "In7.Cu")
		(net "P5E_PEX3_STN4_TX_C_DN<77>")
	)
	(segment
		(start 423.889932 -397.408146)
		(end 424.016932 -397.281146)
		(width 0.1651)
		(layer "In7.Cu")
		(net "P5E_PEX3_STN4_TX_C_DN<77>")
	)
	(segment
		(start 423.6339 -393.50188)
		(end 415.76498 -389.114538)
		(width 0.1651)
		(layer "In7.Cu")
		(net "P5E_PEX3_STN4_TX_C_DN<77>")
	)
	(segment
		(start 424.016932 -397.281146)
		(end 424.564048 -397.281146)
		(width 0.1651)
		(layer "In7.Cu")
		(net "P5E_PEX3_STN4_TX_C_DN<77>")
	)
	(segment
		(start 413.87649 -386.747512)
		(end 412.976822 -383.672334)
		(width 0.1651)
		(layer "In7.Cu")
		(net "P5E_PEX3_STN4_TX_C_DN<77>")
	)
	(segment
		(start 412.976822 -358.04856)
		(end 413.267652 -357.75773)
		(width 0.1651)
		(layer "In7.Cu")
		(net "P5E_PEX3_STN4_TX_C_DN<77>")
	)
	(segment
		(start 412.976822 -383.672334)
		(end 412.976822 -358.04856)
		(width 0.1651)
		(layer "In7.Cu")
		(net "P5E_PEX3_STN4_TX_C_DN<77>")
	)
	(segment
		(start 424.564048 -397.281146)
		(end 425.015914 -396.82928)
		(width 0.1651)
		(layer "In7.Cu")
		(net "P5E_PEX3_STN4_TX_C_DN<77>")
	)
	(segment
		(start 425.015914 -396.82928)
		(end 425.015914 -394.883894)
		(width 0.1651)
		(layer "In7.Cu")
		(net "P5E_PEX3_STN4_TX_C_DN<77>")
	)
	(segment
		(start 425.015914 -394.883894)
		(end 423.6339 -393.50188)
		(width 0.1651)
		(layer "In7.Cu")
		(net "P5E_PEX3_STN4_TX_C_DN<77>")
	)
	(segment
		(start 424.93565 -318.129666)
		(end 424.705526 -318.129666)
		(width 0.1143)
		(layer "In5.Cu")
		(net "P5E_PEX3_STN4_RX_DP<76>")
	)
	(segment
		(start 415.23666 -364.90275)
		(end 415.292794 -365.015272)
		(width 0.1651)
		(layer "In5.Cu")
		(net "P5E_PEX3_STN4_RX_DP<76>")
	)
	(segment
		(start 424.434 -322.521834)
		(end 417.358322 -341.885016)
		(width 0.1651)
		(layer "In5.Cu")
		(net "P5E_PEX3_STN4_RX_DP<76>")
	)
	(segment
		(start 424.705526 -318.129666)
		(end 424.47972 -318.355472)
		(width 0.1143)
		(layer "In5.Cu")
		(net "P5E_PEX3_STN4_RX_DP<76>")
	)
	(segment
		(start 424.47972 -319.864232)
		(end 424.434 -319.909952)
		(width 0.1143)
		(layer "In5.Cu")
		(net "P5E_PEX3_STN4_RX_DP<76>")
	)
	(segment
		(start 424.47972 -318.355472)
		(end 424.47972 -319.864232)
		(width 0.1143)
		(layer "In5.Cu")
		(net "P5E_PEX3_STN4_RX_DP<76>")
	)
	(segment
		(start 414.040574 -368.811048)
		(end 414.040828 -368.811048)
		(width 0.1651)
		(layer "In5.Cu")
		(net "P5E_PEX3_STN4_RX_DP<76>")
	)
	(segment
		(start 426.797978 -395.422882)
		(end 426.965872 -396.075154)
		(width 0.1651)
		(layer "In5.Cu")
		(net "P5E_PEX3_STN4_RX_DP<76>")
	)
	(segment
		(start 424.434 -319.9384)
		(end 424.434 -322.521834)
		(width 0.1651)
		(layer "In5.Cu")
		(net "P5E_PEX3_STN4_RX_DP<76>")
	)
	(segment
		(start 417.358322 -358.82834)
		(end 415.506154 -364.376462)
		(width 0.1651)
		(layer "In5.Cu")
		(net "P5E_PEX3_STN4_RX_DP<76>")
	)
	(segment
		(start 415.393378 -364.432596)
		(end 415.23666 -364.90275)
		(width 0.1651)
		(layer "In5.Cu")
		(net "P5E_PEX3_STN4_RX_DP<76>")
	)
	(segment
		(start 417.358322 -341.885016)
		(end 417.358322 -358.82834)
		(width 0.1651)
		(layer "In5.Cu")
		(net "P5E_PEX3_STN4_RX_DP<76>")
	)
	(segment
		(start 414.040828 -368.811048)
		(end 413.997394 -384.666236)
		(width 0.1651)
		(layer "In5.Cu")
		(net "P5E_PEX3_STN4_RX_DP<76>")
	)
	(segment
		(start 426.263054 -405.902922)
		(end 426.089826 -405.729694)
		(width 0.1651)
		(layer "In5.Cu")
		(net "P5E_PEX3_STN4_RX_DP<76>")
	)
	(segment
		(start 426.965872 -405.570436)
		(end 426.633386 -405.902922)
		(width 0.1651)
		(layer "In5.Cu")
		(net "P5E_PEX3_STN4_RX_DP<76>")
	)
	(segment
		(start 414.040828 -368.765582)
		(end 414.040574 -368.811048)
		(width 0.1651)
		(layer "In5.Cu")
		(net "P5E_PEX3_STN4_RX_DP<76>")
	)
	(segment
		(start 425.733972 -394.260578)
		(end 426.797978 -395.422882)
		(width 0.1651)
		(layer "In5.Cu")
		(net "P5E_PEX3_STN4_RX_DP<76>")
	)
	(segment
		(start 425.04995 -318.015366)
		(end 424.93565 -318.129666)
		(width 0.1143)
		(layer "In5.Cu")
		(net "P5E_PEX3_STN4_RX_DP<76>")
	)
	(segment
		(start 415.292794 -365.015272)
		(end 414.040828 -368.765582)
		(width 0.1651)
		(layer "In5.Cu")
		(net "P5E_PEX3_STN4_RX_DP<76>")
	)
	(segment
		(start 415.201608 -387.661658)
		(end 416.931602 -389.297418)
		(width 0.1651)
		(layer "In5.Cu")
		(net "P5E_PEX3_STN4_RX_DP<76>")
	)
	(segment
		(start 426.633386 -405.902922)
		(end 426.263054 -405.902922)
		(width 0.1651)
		(layer "In5.Cu")
		(net "P5E_PEX3_STN4_RX_DP<76>")
	)
	(segment
		(start 425.04995 -317.749936)
		(end 425.04995 -318.015366)
		(width 0.1143)
		(layer "In5.Cu")
		(net "P5E_PEX3_STN4_RX_DP<76>")
	)
	(segment
		(start 416.931602 -389.297418)
		(end 425.733972 -394.260578)
		(width 0.1651)
		(layer "In5.Cu")
		(net "P5E_PEX3_STN4_RX_DP<76>")
	)
	(segment
		(start 426.089826 -405.729694)
		(end 426.089826 -405.390096)
		(width 0.1651)
		(layer "In5.Cu")
		(net "P5E_PEX3_STN4_RX_DP<76>")
	)
	(segment
		(start 426.965872 -396.075154)
		(end 426.965872 -405.570436)
		(width 0.1651)
		(layer "In5.Cu")
		(net "P5E_PEX3_STN4_RX_DP<76>")
	)
	(segment
		(start 413.997394 -384.666236)
		(end 415.201608 -387.661658)
		(width 0.1651)
		(layer "In5.Cu")
		(net "P5E_PEX3_STN4_RX_DP<76>")
	)
	(segment
		(start 415.506154 -364.376462)
		(end 415.393378 -364.432596)
		(width 0.1651)
		(layer "In5.Cu")
		(net "P5E_PEX3_STN4_RX_DP<76>")
	)
	(segment
		(start 424.434 -319.909952)
		(end 424.434 -319.9384)
		(width 0.1143)
		(layer "In5.Cu")
		(net "P5E_PEX3_STN4_RX_DP<76>")
	)
	(segment
		(start 409.59024 -351.31629)
		(end 409.295092 -351.611438)
		(width 0.13462)
		(layer "F.Cu")
		(net "P5E_PEX3_STN4_TX_C_DP<79>")
	)
	(segment
		(start 409.59024 -350.685862)
		(end 409.59024 -351.31629)
		(width 0.13462)
		(layer "F.Cu")
		(net "P5E_PEX3_STN4_TX_C_DP<79>")
	)
	(segment
		(start 409.269692 -350.365314)
		(end 409.59024 -350.685862)
		(width 0.13462)
		(layer "F.Cu")
		(net "P5E_PEX3_STN4_TX_C_DP<79>")
	)
	(segment
		(start 420.333932 -394.982192)
		(end 419.989 -394.63726)
		(width 0.1651)
		(layer "In7.Cu")
		(net "P5E_PEX3_STN4_TX_C_DP<79>")
	)
	(segment
		(start 411.917388 -388.11581)
		(end 410.67355 -383.862072)
		(width 0.1651)
		(layer "In7.Cu")
		(net "P5E_PEX3_STN4_TX_C_DP<79>")
	)
	(segment
		(start 419.989 -394.63726)
		(end 418.921438 -393.927076)
		(width 0.1651)
		(layer "In7.Cu")
		(net "P5E_PEX3_STN4_TX_C_DP<79>")
	)
	(segment
		(start 409.585922 -351.902268)
		(end 409.295092 -351.611438)
		(width 0.1651)
		(layer "In7.Cu")
		(net "P5E_PEX3_STN4_TX_C_DP<79>")
	)
	(segment
		(start 414.277556 -390.836658)
		(end 411.917388 -388.11581)
		(width 0.1651)
		(layer "In7.Cu")
		(net "P5E_PEX3_STN4_TX_C_DP<79>")
	)
	(segment
		(start 419.48989 -396.872206)
		(end 419.61689 -396.999206)
		(width 0.1651)
		(layer "In7.Cu")
		(net "P5E_PEX3_STN4_TX_C_DP<79>")
	)
	(segment
		(start 419.61689 -396.999206)
		(end 420.047166 -396.999206)
		(width 0.1651)
		(layer "In7.Cu")
		(net "P5E_PEX3_STN4_TX_C_DP<79>")
	)
	(segment
		(start 417.38804 -392.906504)
		(end 414.277556 -390.836658)
		(width 0.1651)
		(layer "In7.Cu")
		(net "P5E_PEX3_STN4_TX_C_DP<79>")
	)
	(segment
		(start 417.825428 -393.304522)
		(end 417.412678 -393.029694)
		(width 0.1651)
		(layer "In7.Cu")
		(net "P5E_PEX3_STN4_TX_C_DP<79>")
	)
	(segment
		(start 417.948618 -393.27963)
		(end 417.825428 -393.304522)
		(width 0.1651)
		(layer "In7.Cu")
		(net "P5E_PEX3_STN4_TX_C_DP<79>")
	)
	(segment
		(start 419.48989 -396.49019)
		(end 419.48989 -396.872206)
		(width 0.1651)
		(layer "In7.Cu")
		(net "P5E_PEX3_STN4_TX_C_DP<79>")
	)
	(segment
		(start 418.921438 -393.927076)
		(end 418.798248 -393.951714)
		(width 0.1651)
		(layer "In7.Cu")
		(net "P5E_PEX3_STN4_TX_C_DP<79>")
	)
	(segment
		(start 420.047166 -396.999206)
		(end 420.333932 -396.71244)
		(width 0.1651)
		(layer "In7.Cu")
		(net "P5E_PEX3_STN4_TX_C_DP<79>")
	)
	(segment
		(start 418.36086 -393.55395)
		(end 417.948618 -393.27963)
		(width 0.1651)
		(layer "In7.Cu")
		(net "P5E_PEX3_STN4_TX_C_DP<79>")
	)
	(segment
		(start 409.585922 -352.84156)
		(end 409.585922 -351.902268)
		(width 0.1651)
		(layer "In7.Cu")
		(net "P5E_PEX3_STN4_TX_C_DP<79>")
	)
	(segment
		(start 418.798248 -393.951714)
		(end 418.385752 -393.67714)
		(width 0.1651)
		(layer "In7.Cu")
		(net "P5E_PEX3_STN4_TX_C_DP<79>")
	)
	(segment
		(start 418.385752 -393.67714)
		(end 418.36086 -393.55395)
		(width 0.1651)
		(layer "In7.Cu")
		(net "P5E_PEX3_STN4_TX_C_DP<79>")
	)
	(segment
		(start 417.412678 -393.029694)
		(end 417.38804 -392.906504)
		(width 0.1651)
		(layer "In7.Cu")
		(net "P5E_PEX3_STN4_TX_C_DP<79>")
	)
	(segment
		(start 410.67355 -383.862072)
		(end 409.585922 -352.84156)
		(width 0.1651)
		(layer "In7.Cu")
		(net "P5E_PEX3_STN4_TX_C_DP<79>")
	)
	(segment
		(start 420.333932 -396.71244)
		(end 420.333932 -394.982192)
		(width 0.1651)
		(layer "In7.Cu")
		(net "P5E_PEX3_STN4_TX_C_DP<79>")
	)
	(segment
		(start 425.40936 -357.463598)
		(end 425.703492 -357.75773)
		(width 0.13462)
		(layer "F.Cu")
		(net "P5E_PEX3_STN4_TX_C_DN<71>")
	)
	(segment
		(start 425.40936 -356.831138)
		(end 425.40936 -357.463598)
		(width 0.13462)
		(layer "F.Cu")
		(net "P5E_PEX3_STN4_TX_C_DN<71>")
	)
	(segment
		(start 425.728892 -356.511606)
		(end 425.40936 -356.831138)
		(width 0.13462)
		(layer "F.Cu")
		(net "P5E_PEX3_STN4_TX_C_DN<71>")
	)
	(segment
		(start 420.615872 -370.829332)
		(end 420.615872 -368.72672)
		(width 0.1651)
		(layer "In7.Cu")
		(net "P5E_PEX3_STN4_TX_C_DN<71>")
	)
	(segment
		(start 419.48989 -371.790214)
		(end 419.48989 -371.408198)
		(width 0.1651)
		(layer "In7.Cu")
		(net "P5E_PEX3_STN4_TX_C_DN<71>")
	)
	(segment
		(start 420.164006 -371.281198)
		(end 420.615872 -370.829332)
		(width 0.1651)
		(layer "In7.Cu")
		(net "P5E_PEX3_STN4_TX_C_DN<71>")
	)
	(segment
		(start 419.61689 -371.281198)
		(end 420.164006 -371.281198)
		(width 0.1651)
		(layer "In7.Cu")
		(net "P5E_PEX3_STN4_TX_C_DN<71>")
	)
	(segment
		(start 420.615872 -368.72672)
		(end 425.412662 -358.8893)
		(width 0.1651)
		(layer "In7.Cu")
		(net "P5E_PEX3_STN4_TX_C_DN<71>")
	)
	(segment
		(start 425.412662 -358.8893)
		(end 425.412662 -358.04856)
		(width 0.1651)
		(layer "In7.Cu")
		(net "P5E_PEX3_STN4_TX_C_DN<71>")
	)
	(segment
		(start 419.48989 -371.408198)
		(end 419.61689 -371.281198)
		(width 0.1651)
		(layer "In7.Cu")
		(net "P5E_PEX3_STN4_TX_C_DN<71>")
	)
	(segment
		(start 425.412662 -358.04856)
		(end 425.703492 -357.75773)
		(width 0.1651)
		(layer "In7.Cu")
		(net "P5E_PEX3_STN4_TX_C_DN<71>")
	)
	(segment
		(start 8.821928 -135.866886)
		(end 8.013446 -135.058404)
		(width 0.13208)
		(layer "F.Cu")
		(net "P12V_NIC0_EN_R")
	)
	(segment
		(start 8.013446 -134.042404)
		(end 8.013446 -135.058404)
		(width 0.13208)
		(layer "F.Cu")
		(net "P12V_NIC0_EN_R")
	)
	(segment
		(start 9.22274 -136.267698)
		(end 8.821928 -135.866886)
		(width 0.13208)
		(layer "F.Cu")
		(net "P12V_NIC0_EN_R")
	)
	(segment
		(start 9.734042 -136.267698)
		(end 9.22274 -136.267698)
		(width 0.13208)
		(layer "F.Cu")
		(net "P12V_NIC0_EN_R")
	)
	(via
		(at 8.821928 -135.866886)
		(size 0.508)
		(drill 0.254)
		(layers "F.Cu" "B.Cu")
		(net "P12V_NIC0_EN_R")
	)
	(segment
		(start 7.213346 -138.360404)
		(end 6.558026 -138.360404)
		(width 0.13208)
		(layer "F.Cu")
		(net "PWRGD_P12V_NIC0_R")
	)
	(segment
		(start 7.649718 -158.828994)
		(end 7.032244 -158.828994)
		(width 0.13208)
		(layer "F.Cu")
		(net "PWRGD_P12V_NIC0_R")
	)
	(segment
		(start 350.893888 -226.387152)
		(end 351.293684 -226.786948)
		(width 0.13208)
		(layer "F.Cu")
		(net "PWRGD_P12V_NIC0_R")
	)
	(via
		(at 61.009276 -163.350702)
		(size 0.508)
		(drill 0.254)
		(layers "F.Cu" "B.Cu")
		(net "PWRGD_P12V_NIC0_R")
	)
	(via
		(at 351.293684 -226.786948)
		(size 0.4572)
		(drill 0.254)
		(layers "F.Cu" "B.Cu")
		(net "PWRGD_P12V_NIC0_R")
	)
	(via
		(at 6.558026 -138.360404)
		(size 0.508)
		(drill 0.254)
		(layers "F.Cu" "B.Cu")
		(net "PWRGD_P12V_NIC0_R")
	)
	(via
		(at 63.01486 -175.542956)
		(size 0.508)
		(drill 0.254)
		(layers "F.Cu" "B.Cu")
		(net "PWRGD_P12V_NIC0_R")
	)
	(via
		(at 7.032244 -158.828994)
		(size 0.508)
		(drill 0.254)
		(layers "F.Cu" "B.Cu")
		(net "PWRGD_P12V_NIC0_R")
	)
	(segment
		(start 60.295536 -163.350702)
		(end 59.960256 -163.015422)
		(width 0.13208)
		(layer "B.Cu")
		(net "PWRGD_P12V_NIC0_R")
	)
	(segment
		(start 60.084716 -161.463736)
		(end 60.511436 -161.463736)
		(width 0.13208)
		(layer "B.Cu")
		(net "PWRGD_P12V_NIC0_R")
	)
	(segment
		(start 59.960256 -161.588196)
		(end 60.084716 -161.463736)
		(width 0.13208)
		(layer "B.Cu")
		(net "PWRGD_P12V_NIC0_R")
	)
	(segment
		(start 61.009276 -163.350702)
		(end 60.295536 -163.350702)
		(width 0.13208)
		(layer "B.Cu")
		(net "PWRGD_P12V_NIC0_R")
	)
	(segment
		(start 59.960256 -163.015422)
		(end 59.960256 -161.588196)
		(width 0.13208)
		(layer "B.Cu")
		(net "PWRGD_P12V_NIC0_R")
	)
	(segment
		(start 60.94603 -163.413948)
		(end 61.009276 -163.350702)
		(width 0.15494)
		(layer "In5.Cu")
		(net "PWRGD_P12V_NIC0_R")
	)
	(segment
		(start 63.01486 -175.542956)
		(end 60.94603 -173.474126)
		(width 0.15494)
		(layer "In5.Cu")
		(net "PWRGD_P12V_NIC0_R")
	)
	(segment
		(start 60.94603 -173.474126)
		(end 60.94603 -163.413948)
		(width 0.15494)
		(layer "In5.Cu")
		(net "PWRGD_P12V_NIC0_R")
	)
	(segment
		(start 5.697728 -157.494478)
		(end 7.032244 -158.828994)
		(width 0.15494)
		(layer "In7.Cu")
		(net "PWRGD_P12V_NIC0_R")
	)
	(segment
		(start 5.697728 -139.241276)
		(end 5.697728 -157.494478)
		(width 0.15494)
		(layer "In7.Cu")
		(net "PWRGD_P12V_NIC0_R")
	)
	(segment
		(start 6.558026 -138.380978)
		(end 5.697728 -139.241276)
		(width 0.15494)
		(layer "In7.Cu")
		(net "PWRGD_P12V_NIC0_R")
	)
	(segment
		(start 6.558026 -138.360404)
		(end 6.558026 -138.380978)
		(width 0.15494)
		(layer "In7.Cu")
		(net "PWRGD_P12V_NIC0_R")
	)
	(segment
		(start 355.449378 -174.25543)
		(end 357.214678 -172.49013)
		(width 0.15494)
		(layer "In15.Cu")
		(net "PWRGD_P12V_NIC0_R")
	)
	(segment
		(start 112.23879 -187.53328)
		(end 113.13287 -186.6392)
		(width 0.15494)
		(layer "In15.Cu")
		(net "PWRGD_P12V_NIC0_R")
	)
	(segment
		(start 106.16057 -187.53328)
		(end 112.23879 -187.53328)
		(width 0.15494)
		(layer "In15.Cu")
		(net "PWRGD_P12V_NIC0_R")
	)
	(segment
		(start 352.218498 -227.711762)
		(end 351.293684 -226.786948)
		(width 0.15494)
		(layer "In15.Cu")
		(net "PWRGD_P12V_NIC0_R")
	)
	(segment
		(start 340.99754 -169.56913)
		(end 341.67572 -170.24731)
		(width 0.15494)
		(layer "In15.Cu")
		(net "PWRGD_P12V_NIC0_R")
	)
	(segment
		(start 28.386024 -188.232288)
		(end 6.398768 -188.232288)
		(width 0.15494)
		(layer "In15.Cu")
		(net "PWRGD_P12V_NIC0_R")
	)
	(segment
		(start 369.128294 -233.299254)
		(end 358.33558 -233.299254)
		(width 0.15494)
		(layer "In15.Cu")
		(net "PWRGD_P12V_NIC0_R")
	)
	(segment
		(start 343.553542 -170.24731)
		(end 347.561662 -174.25543)
		(width 0.15494)
		(layer "In15.Cu")
		(net "PWRGD_P12V_NIC0_R")
	)
	(segment
		(start 237.077504 -173.16069)
		(end 237.360714 -173.4439)
		(width 0.15494)
		(layer "In15.Cu")
		(net "PWRGD_P12V_NIC0_R")
	)
	(segment
		(start 102.152196 -185.872882)
		(end 106.16057 -187.53328)
		(width 0.15494)
		(layer "In15.Cu")
		(net "PWRGD_P12V_NIC0_R")
	)
	(segment
		(start 357.214678 -172.49013)
		(end 362.15066 -172.49013)
		(width 0.15494)
		(layer "In15.Cu")
		(net "PWRGD_P12V_NIC0_R")
	)
	(segment
		(start 5.980176 -158.828994)
		(end 7.032244 -158.828994)
		(width 0.15494)
		(layer "In15.Cu")
		(net "PWRGD_P12V_NIC0_R")
	)
	(segment
		(start 235.565442 -171.31792)
		(end 237.077504 -172.829982)
		(width 0.15494)
		(layer "In15.Cu")
		(net "PWRGD_P12V_NIC0_R")
	)
	(segment
		(start 215.79586 -171.31792)
		(end 235.565442 -171.31792)
		(width 0.15494)
		(layer "In15.Cu")
		(net "PWRGD_P12V_NIC0_R")
	)
	(segment
		(start 141.465046 -187.01639)
		(end 165.983412 -187.01639)
		(width 0.15494)
		(layer "In15.Cu")
		(net "PWRGD_P12V_NIC0_R")
	)
	(segment
		(start 139.051284 -189.430152)
		(end 141.465046 -187.01639)
		(width 0.15494)
		(layer "In15.Cu")
		(net "PWRGD_P12V_NIC0_R")
	)
	(segment
		(start 5.283454 -159.525716)
		(end 5.980176 -158.828994)
		(width 0.15494)
		(layer "In15.Cu")
		(net "PWRGD_P12V_NIC0_R")
	)
	(segment
		(start 286.79648 -170.15587)
		(end 334.2386 -170.15587)
		(width 0.15494)
		(layer "In15.Cu")
		(net "PWRGD_P12V_NIC0_R")
	)
	(segment
		(start 358.33558 -233.299254)
		(end 357.0097 -231.973374)
		(width 0.15494)
		(layer "In15.Cu")
		(net "PWRGD_P12V_NIC0_R")
	)
	(segment
		(start 63.01486 -175.542956)
		(end 91.82227 -175.542956)
		(width 0.15494)
		(layer "In15.Cu")
		(net "PWRGD_P12V_NIC0_R")
	)
	(segment
		(start 370.239544 -183.133492)
		(end 372.724426 -185.618374)
		(width 0.15494)
		(layer "In15.Cu")
		(net "PWRGD_P12V_NIC0_R")
	)
	(segment
		(start 353.895152 -228.635052)
		(end 352.971862 -227.711762)
		(width 0.15494)
		(layer "In15.Cu")
		(net "PWRGD_P12V_NIC0_R")
	)
	(segment
		(start 124.935996 -186.6392)
		(end 127.726948 -189.430152)
		(width 0.15494)
		(layer "In15.Cu")
		(net "PWRGD_P12V_NIC0_R")
	)
	(segment
		(start 341.67572 -170.24731)
		(end 343.553542 -170.24731)
		(width 0.15494)
		(layer "In15.Cu")
		(net "PWRGD_P12V_NIC0_R")
	)
	(segment
		(start 370.239544 -180.579014)
		(end 370.239544 -183.133492)
		(width 0.15494)
		(layer "In15.Cu")
		(net "PWRGD_P12V_NIC0_R")
	)
	(segment
		(start 91.82227 -175.542956)
		(end 102.152196 -185.872882)
		(width 0.15494)
		(layer "In15.Cu")
		(net "PWRGD_P12V_NIC0_R")
	)
	(segment
		(start 334.2386 -170.15587)
		(end 334.82534 -169.56913)
		(width 0.15494)
		(layer "In15.Cu")
		(net "PWRGD_P12V_NIC0_R")
	)
	(segment
		(start 334.82534 -169.56913)
		(end 340.99754 -169.56913)
		(width 0.15494)
		(layer "In15.Cu")
		(net "PWRGD_P12V_NIC0_R")
	)
	(segment
		(start 372.724426 -185.618374)
		(end 372.724426 -229.703122)
		(width 0.15494)
		(layer "In15.Cu")
		(net "PWRGD_P12V_NIC0_R")
	)
	(segment
		(start 180.74005 -174.602394)
		(end 181.89194 -173.450504)
		(width 0.15494)
		(layer "In15.Cu")
		(net "PWRGD_P12V_NIC0_R")
	)
	(segment
		(start 257.630676 -171.323)
		(end 285.62808 -171.323)
		(width 0.15494)
		(layer "In15.Cu")
		(net "PWRGD_P12V_NIC0_R")
	)
	(segment
		(start 347.561662 -174.25543)
		(end 355.449378 -174.25543)
		(width 0.15494)
		(layer "In15.Cu")
		(net "PWRGD_P12V_NIC0_R")
	)
	(segment
		(start 179.864258 -174.965106)
		(end 180.74005 -174.602394)
		(width 0.15494)
		(layer "In15.Cu")
		(net "PWRGD_P12V_NIC0_R")
	)
	(segment
		(start 181.89194 -173.450504)
		(end 213.663276 -173.450504)
		(width 0.15494)
		(layer "In15.Cu")
		(net "PWRGD_P12V_NIC0_R")
	)
	(segment
		(start 353.895152 -229.156514)
		(end 353.895152 -228.635052)
		(width 0.15494)
		(layer "In15.Cu")
		(net "PWRGD_P12V_NIC0_R")
	)
	(segment
		(start 372.724426 -229.703122)
		(end 369.128294 -233.299254)
		(width 0.15494)
		(layer "In15.Cu")
		(net "PWRGD_P12V_NIC0_R")
	)
	(segment
		(start 237.360714 -173.4439)
		(end 255.509776 -173.4439)
		(width 0.15494)
		(layer "In15.Cu")
		(net "PWRGD_P12V_NIC0_R")
	)
	(segment
		(start 165.983412 -187.01639)
		(end 178.034696 -174.965106)
		(width 0.15494)
		(layer "In15.Cu")
		(net "PWRGD_P12V_NIC0_R")
	)
	(segment
		(start 113.13287 -186.6392)
		(end 124.935996 -186.6392)
		(width 0.15494)
		(layer "In15.Cu")
		(net "PWRGD_P12V_NIC0_R")
	)
	(segment
		(start 6.398768 -188.232288)
		(end 5.283454 -187.116974)
		(width 0.15494)
		(layer "In15.Cu")
		(net "PWRGD_P12V_NIC0_R")
	)
	(segment
		(start 285.62808 -171.323)
		(end 286.79648 -170.15587)
		(width 0.15494)
		(layer "In15.Cu")
		(net "PWRGD_P12V_NIC0_R")
	)
	(segment
		(start 255.509776 -173.4439)
		(end 257.630676 -171.323)
		(width 0.15494)
		(layer "In15.Cu")
		(net "PWRGD_P12V_NIC0_R")
	)
	(segment
		(start 352.971862 -227.711762)
		(end 352.218498 -227.711762)
		(width 0.15494)
		(layer "In15.Cu")
		(net "PWRGD_P12V_NIC0_R")
	)
	(segment
		(start 357.0097 -231.973374)
		(end 356.712012 -231.973374)
		(width 0.15494)
		(layer "In15.Cu")
		(net "PWRGD_P12V_NIC0_R")
	)
	(segment
		(start 237.077504 -172.829982)
		(end 237.077504 -173.16069)
		(width 0.15494)
		(layer "In15.Cu")
		(net "PWRGD_P12V_NIC0_R")
	)
	(segment
		(start 356.712012 -231.973374)
		(end 353.895152 -229.156514)
		(width 0.15494)
		(layer "In15.Cu")
		(net "PWRGD_P12V_NIC0_R")
	)
	(segment
		(start 63.01486 -175.542956)
		(end 41.075356 -175.542956)
		(width 0.15494)
		(layer "In15.Cu")
		(net "PWRGD_P12V_NIC0_R")
	)
	(segment
		(start 5.283454 -187.116974)
		(end 5.283454 -159.525716)
		(width 0.15494)
		(layer "In15.Cu")
		(net "PWRGD_P12V_NIC0_R")
	)
	(segment
		(start 127.726948 -189.430152)
		(end 139.051284 -189.430152)
		(width 0.15494)
		(layer "In15.Cu")
		(net "PWRGD_P12V_NIC0_R")
	)
	(segment
		(start 178.034696 -174.965106)
		(end 179.864258 -174.965106)
		(width 0.15494)
		(layer "In15.Cu")
		(net "PWRGD_P12V_NIC0_R")
	)
	(segment
		(start 41.075356 -175.542956)
		(end 28.386024 -188.232288)
		(width 0.15494)
		(layer "In15.Cu")
		(net "PWRGD_P12V_NIC0_R")
	)
	(segment
		(start 213.663276 -173.450504)
		(end 215.79586 -171.31792)
		(width 0.15494)
		(layer "In15.Cu")
		(net "PWRGD_P12V_NIC0_R")
	)
	(segment
		(start 362.15066 -172.49013)
		(end 370.239544 -180.579014)
		(width 0.15494)
		(layer "In15.Cu")
		(net "PWRGD_P12V_NIC0_R")
	)
	(segment
		(start 9.254998 -137.267696)
		(end 9.074404 -137.44829)
		(width 0.13208)
		(layer "F.Cu")
		(net "P12V_NIC0_OCP")
	)
	(segment
		(start 9.734042 -137.267696)
		(end 9.254998 -137.267696)
		(width 0.13208)
		(layer "F.Cu")
		(net "P12V_NIC0_OCP")
	)
	(segment
		(start 8.117332 -137.44829)
		(end 8.013446 -137.344404)
		(width 0.13208)
		(layer "F.Cu")
		(net "P12V_NIC0_OCP")
	)
	(segment
		(start 8.727186 -137.44829)
		(end 8.117332 -137.44829)
		(width 0.13208)
		(layer "F.Cu")
		(net "P12V_NIC0_OCP")
	)
	(segment
		(start 9.074404 -137.44829)
		(end 8.727186 -137.44829)
		(width 0.13208)
		(layer "F.Cu")
		(net "P12V_NIC0_OCP")
	)
	(via
		(at 8.727186 -137.44829)
		(size 0.508)
		(drill 0.254)
		(layers "F.Cu" "B.Cu")
		(net "P12V_NIC0_OCP")
	)
	(via
		(at 43.520106 -145.30578)
		(size 0.508)
		(drill 0.254)
		(layers "F.Cu" "B.Cu")
		(net "P12V_NIC0")
	)
	(via
		(at 22.159722 -143.482568)
		(size 0.6604)
		(drill 0.3302)
		(layers "F.Cu" "B.Cu")
		(net "P12V_NIC0")
	)
	(via
		(at 19.845782 -141.858238)
		(size 0.508)
		(drill 0.254)
		(layers "F.Cu" "B.Cu")
		(net "P12V_NIC0")
	)
	(via
		(at 19.845782 -141.197838)
		(size 0.508)
		(drill 0.254)
		(layers "F.Cu" "B.Cu")
		(net "P12V_NIC0")
	)
	(via
		(at 19.845782 -142.518638)
		(size 0.508)
		(drill 0.254)
		(layers "F.Cu" "B.Cu")
		(net "P12V_NIC0")
	)
	(via
		(at 43.862244 -144.761712)
		(size 0.508)
		(drill 0.254)
		(layers "F.Cu" "B.Cu")
		(net "P12V_NIC0")
	)
	(via
		(at 45.05579 -143.999966)
		(size 0.508)
		(drill 0.254)
		(layers "F.Cu" "B.Cu")
		(net "P12V_NIC0")
	)
	(via
		(at 21.796248 -141.772894)
		(size 0.6604)
		(drill 0.3302)
		(layers "F.Cu" "B.Cu")
		(net "P12V_NIC0")
	)
	(via
		(at 19.845782 -143.179038)
		(size 0.508)
		(drill 0.254)
		(layers "F.Cu" "B.Cu")
		(net "P12V_NIC0")
	)
	(via
		(at 44.983146 -144.634204)
		(size 0.508)
		(drill 0.254)
		(layers "F.Cu" "B.Cu")
		(net "P12V_NIC0")
	)
	(via
		(at 44.393104 -144.39265)
		(size 0.508)
		(drill 0.254)
		(layers "F.Cu" "B.Cu")
		(net "P12V_NIC0")
	)
	(via
		(at 44.458382 -145.024348)
		(size 0.508)
		(drill 0.254)
		(layers "F.Cu" "B.Cu")
		(net "P12V_NIC0")
	)
	(via
		(at 19.845782 -140.537438)
		(size 0.508)
		(drill 0.254)
		(layers "F.Cu" "B.Cu")
		(net "P12V_NIC0")
	)
	(via
		(at 19.845782 -143.915638)
		(size 0.508)
		(drill 0.254)
		(layers "F.Cu" "B.Cu")
		(net "P12V_NIC0")
	)
	(segment
		(start 8.013446 -140.392404)
		(end 8.749792 -140.392404)
		(width 0.13208)
		(layer "F.Cu")
		(net "P12V_NIC0_SS")
	)
	(segment
		(start 9.734042 -138.267694)
		(end 9.550654 -138.267694)
		(width 0.13208)
		(layer "F.Cu")
		(net "P12V_NIC0_SS")
	)
	(segment
		(start 9.401302 -138.417046)
		(end 9.401302 -139.740894)
		(width 0.13208)
		(layer "F.Cu")
		(net "P12V_NIC0_SS")
	)
	(segment
		(start 9.401302 -139.740894)
		(end 8.749792 -140.392404)
		(width 0.13208)
		(layer "F.Cu")
		(net "P12V_NIC0_SS")
	)
	(segment
		(start 9.550654 -138.267694)
		(end 9.401302 -138.417046)
		(width 0.13208)
		(layer "F.Cu")
		(net "P12V_NIC0_SS")
	)
	(via
		(at 8.749792 -140.392404)
		(size 0.508)
		(drill 0.254)
		(layers "F.Cu" "B.Cu")
		(net "P12V_NIC0_SS")
	)
	(segment
		(start 8.61695 -139.376404)
		(end 8.013446 -139.376404)
		(width 0.13208)
		(layer "F.Cu")
		(net "PWRGD_P12V_NIC0")
	)
	(segment
		(start 9.36498 -137.767822)
		(end 8.74395 -138.388852)
		(width 0.13208)
		(layer "F.Cu")
		(net "PWRGD_P12V_NIC0")
	)
	(segment
		(start 8.74395 -138.388852)
		(end 8.74395 -138.824462)
		(width 0.13208)
		(layer "F.Cu")
		(net "PWRGD_P12V_NIC0")
	)
	(segment
		(start 9.734042 -137.767822)
		(end 9.36498 -137.767822)
		(width 0.13208)
		(layer "F.Cu")
		(net "PWRGD_P12V_NIC0")
	)
	(segment
		(start 8.74395 -138.824462)
		(end 8.74395 -139.249404)
		(width 0.13208)
		(layer "F.Cu")
		(net "PWRGD_P12V_NIC0")
	)
	(segment
		(start 8.013446 -138.360404)
		(end 8.013446 -139.376404)
		(width 0.13208)
		(layer "F.Cu")
		(net "PWRGD_P12V_NIC0")
	)
	(segment
		(start 8.74395 -139.249404)
		(end 8.61695 -139.376404)
		(width 0.13208)
		(layer "F.Cu")
		(net "PWRGD_P12V_NIC0")
	)
	(via
		(at 8.74395 -138.824462)
		(size 0.508)
		(drill 0.254)
		(layers "F.Cu" "B.Cu")
		(net "PWRGD_P12V_NIC0")
	)
	(segment
		(start 364.510828 -220.84665)
		(end 364.302548 -221.05493)
		(width 0.13208)
		(layer "F.Cu")
		(net "SPI_PEX3_CLK_MUX_R")
	)
	(segment
		(start 364.302548 -221.05493)
		(end 363.282738 -221.05493)
		(width 0.13208)
		(layer "F.Cu")
		(net "SPI_PEX3_CLK_MUX_R")
	)
	(via
		(at 364.510828 -220.84665)
		(size 0.508)
		(drill 0.254)
		(layers "F.Cu" "B.Cu")
		(net "SPI_PEX3_CLK_MUX_R")
	)
	(segment
		(start 363.275118 -221.240858)
		(end 364.11662 -221.240858)
		(width 0.13208)
		(layer "B.Cu")
		(net "SPI_PEX3_CLK_MUX_R")
	)
	(segment
		(start 364.11662 -221.240858)
		(end 364.510828 -220.84665)
		(width 0.13208)
		(layer "B.Cu")
		(net "SPI_PEX3_CLK_MUX_R")
	)
	(segment
		(start 372.882922 -229.94493)
		(end 371.475 -229.94493)
		(width 0.13208)
		(layer "F.Cu")
		(net "SPI_PEX3_SDIO1_MUX_R")
	)
	(via
		(at 371.475 -229.94493)
		(size 0.508)
		(drill 0.254)
		(layers "F.Cu" "B.Cu")
		(net "SPI_PEX3_SDIO1_MUX_R")
	)
	(segment
		(start 371.475 -228.74605)
		(end 371.475 -229.94493)
		(width 0.13208)
		(layer "B.Cu")
		(net "SPI_PEX3_SDIO1_MUX_R")
	)
	(segment
		(start 374.620282 -220.524324)
		(end 374.089676 -221.05493)
		(width 0.13208)
		(layer "F.Cu")
		(net "SPI_PEX3_SDIO3_R1")
	)
	(segment
		(start 374.089676 -221.05493)
		(end 372.882922 -221.05493)
		(width 0.13208)
		(layer "F.Cu")
		(net "SPI_PEX3_SDIO3_R1")
	)
	(via
		(at 374.620282 -220.524324)
		(size 0.508)
		(drill 0.254)
		(layers "F.Cu" "B.Cu")
		(net "SPI_PEX3_SDIO3_R1")
	)
	(segment
		(start 373.422672 -220.524324)
		(end 374.620282 -220.524324)
		(width 0.13208)
		(layer "B.Cu")
		(net "SPI_PEX3_SDIO3_R1")
	)
	(segment
		(start 372.38305 -220.532706)
		(end 373.41429 -220.532706)
		(width 0.13208)
		(layer "B.Cu")
		(net "SPI_PEX3_SDIO3_R1")
	)
	(segment
		(start 373.41429 -220.532706)
		(end 373.422672 -220.524324)
		(width 0.13208)
		(layer "B.Cu")
		(net "SPI_PEX3_SDIO3_R1")
	)
	(segment
		(start 361.49026 -229.94493)
		(end 363.122718 -229.94493)
		(width 0.13208)
		(layer "F.Cu")
		(net "SPI_PEX3_SDIO2_R1")
	)
	(via
		(at 361.49026 -229.94493)
		(size 0.508)
		(drill 0.254)
		(layers "F.Cu" "B.Cu")
		(net "SPI_PEX3_SDIO2_R1")
	)
	(segment
		(start 362.69295 -227.965)
		(end 362.69295 -228.981)
		(width 0.13208)
		(layer "B.Cu")
		(net "SPI_PEX3_SDIO2_R1")
	)
	(segment
		(start 362.69295 -229.997)
		(end 362.64088 -229.94493)
		(width 0.13208)
		(layer "B.Cu")
		(net "SPI_PEX3_SDIO2_R1")
	)
	(segment
		(start 362.69295 -228.981)
		(end 362.69295 -229.997)
		(width 0.13208)
		(layer "B.Cu")
		(net "SPI_PEX3_SDIO2_R1")
	)
	(segment
		(start 362.64088 -229.94493)
		(end 361.49026 -229.94493)
		(width 0.13208)
		(layer "B.Cu")
		(net "SPI_PEX3_SDIO2_R1")
	)
	(segment
		(start 373.511318 -228.67493)
		(end 372.882922 -228.67493)
		(width 0.13208)
		(layer "F.Cu")
		(net "SPI_PEX3_CS_MUX_R_N")
	)
	(segment
		(start 374.240298 -227.94595)
		(end 373.511318 -228.67493)
		(width 0.13208)
		(layer "F.Cu")
		(net "SPI_PEX3_CS_MUX_R_N")
	)
	(via
		(at 374.240298 -227.94595)
		(size 0.508)
		(drill 0.254)
		(layers "F.Cu" "B.Cu")
		(net "SPI_PEX3_CS_MUX_R_N")
	)
	(segment
		(start 372.759224 -227.32746)
		(end 372.759224 -226.936046)
		(width 0.13208)
		(layer "B.Cu")
		(net "SPI_PEX3_CS_MUX_R_N")
	)
	(segment
		(start 372.48211 -227.604574)
		(end 372.759224 -227.32746)
		(width 0.13208)
		(layer "B.Cu")
		(net "SPI_PEX3_CS_MUX_R_N")
	)
	(segment
		(start 372.48211 -227.94595)
		(end 372.48211 -227.604574)
		(width 0.13208)
		(layer "B.Cu")
		(net "SPI_PEX3_CS_MUX_R_N")
	)
	(segment
		(start 374.240298 -227.94595)
		(end 372.48211 -227.94595)
		(width 0.13208)
		(layer "B.Cu")
		(net "SPI_PEX3_CS_MUX_R_N")
	)
	(segment
		(start 271.895062 -349.831914)
		(end 271.575022 -349.511874)
		(width 0.13462)
		(layer "F.Cu")
		(net "P5E_PEX2_STN4_TX_DN<78>")
	)
	(segment
		(start 271.575022 -349.511874)
		(end 271.575022 -348.88043)
		(width 0.13462)
		(layer "F.Cu")
		(net "P5E_PEX2_STN4_TX_DN<78>")
	)
	(segment
		(start 271.575022 -348.88043)
		(end 271.869662 -348.58579)
		(width 0.13462)
		(layer "F.Cu")
		(net "P5E_PEX2_STN4_TX_DN<78>")
	)
	(segment
		(start 275.321014 -338.784438)
		(end 274.885658 -339.021674)
		(width 0.1651)
		(layer "In11.Cu")
		(net "P5E_PEX2_STN4_TX_DN<78>")
	)
	(segment
		(start 273.225006 -339.795866)
		(end 273.179286 -339.950806)
		(width 0.1651)
		(layer "In11.Cu")
		(net "P5E_PEX2_STN4_TX_DN<78>")
	)
	(segment
		(start 273.179286 -339.950806)
		(end 272.74393 -340.188042)
		(width 0.1651)
		(layer "In11.Cu")
		(net "P5E_PEX2_STN4_TX_DN<78>")
	)
	(segment
		(start 274.29587 -339.212682)
		(end 274.25015 -339.367622)
		(width 0.1651)
		(layer "In11.Cu")
		(net "P5E_PEX2_STN4_TX_DN<78>")
	)
	(segment
		(start 272.154142 -340.37905)
		(end 272.154142 -340.378796)
		(width 0.1651)
		(layer "In11.Cu")
		(net "P5E_PEX2_STN4_TX_DN<78>")
	)
	(segment
		(start 306.715922 -320.051938)
		(end 306.715922 -320.074036)
		(width 0.1143)
		(layer "In11.Cu")
		(net "P5E_PEX2_STN4_TX_DN<78>")
	)
	(segment
		(start 306.715922 -320.074036)
		(end 306.715922 -321.179698)
		(width 0.1651)
		(layer "In11.Cu")
		(net "P5E_PEX2_STN4_TX_DN<78>")
	)
	(segment
		(start 306.670202 -313.673744)
		(end 306.670202 -320.006218)
		(width 0.1143)
		(layer "In11.Cu")
		(net "P5E_PEX2_STN4_TX_DN<78>")
	)
	(segment
		(start 306.773834 -313.570112)
		(end 306.670202 -313.673744)
		(width 0.1143)
		(layer "In11.Cu")
		(net "P5E_PEX2_STN4_TX_DN<78>")
	)
	(segment
		(start 271.518126 -340.725252)
		(end 270.666718 -341.188802)
		(width 0.1651)
		(layer "In11.Cu")
		(net "P5E_PEX2_STN4_TX_DN<78>")
	)
	(segment
		(start 274.730718 -338.975954)
		(end 274.29587 -339.212682)
		(width 0.1651)
		(layer "In11.Cu")
		(net "P5E_PEX2_STN4_TX_DN<78>")
	)
	(segment
		(start 271.67332 -340.770972)
		(end 271.518126 -340.725252)
		(width 0.1651)
		(layer "In11.Cu")
		(net "P5E_PEX2_STN4_TX_DN<78>")
	)
	(segment
		(start 305.884072 -322.011548)
		(end 275.366734 -338.629498)
		(width 0.1651)
		(layer "In11.Cu")
		(net "P5E_PEX2_STN4_TX_DN<78>")
	)
	(segment
		(start 306.670202 -320.006218)
		(end 306.715922 -320.051938)
		(width 0.1143)
		(layer "In11.Cu")
		(net "P5E_PEX2_STN4_TX_DN<78>")
	)
	(segment
		(start 274.885658 -339.021674)
		(end 274.730718 -338.975954)
		(width 0.1651)
		(layer "In11.Cu")
		(net "P5E_PEX2_STN4_TX_DN<78>")
	)
	(segment
		(start 273.659854 -339.559138)
		(end 273.225006 -339.795866)
		(width 0.1651)
		(layer "In11.Cu")
		(net "P5E_PEX2_STN4_TX_DN<78>")
	)
	(segment
		(start 272.154142 -340.378796)
		(end 272.108422 -340.533736)
		(width 0.1651)
		(layer "In11.Cu")
		(net "P5E_PEX2_STN4_TX_DN<78>")
	)
	(segment
		(start 307.049932 -313.684412)
		(end 306.935632 -313.570112)
		(width 0.1143)
		(layer "In11.Cu")
		(net "P5E_PEX2_STN4_TX_DN<78>")
	)
	(segment
		(start 306.715922 -321.179698)
		(end 305.884072 -322.011548)
		(width 0.1651)
		(layer "In11.Cu")
		(net "P5E_PEX2_STN4_TX_DN<78>")
	)
	(segment
		(start 274.25015 -339.367622)
		(end 273.814794 -339.604858)
		(width 0.1651)
		(layer "In11.Cu")
		(net "P5E_PEX2_STN4_TX_DN<78>")
	)
	(segment
		(start 272.58899 -340.142322)
		(end 272.154142 -340.37905)
		(width 0.1651)
		(layer "In11.Cu")
		(net "P5E_PEX2_STN4_TX_DN<78>")
	)
	(segment
		(start 306.935632 -313.570112)
		(end 306.773834 -313.570112)
		(width 0.1143)
		(layer "In11.Cu")
		(net "P5E_PEX2_STN4_TX_DN<78>")
	)
	(segment
		(start 270.666718 -341.188802)
		(end 270.024352 -341.831168)
		(width 0.1651)
		(layer "In11.Cu")
		(net "P5E_PEX2_STN4_TX_DN<78>")
	)
	(segment
		(start 307.049932 -313.949842)
		(end 307.049932 -313.684412)
		(width 0.1143)
		(layer "In11.Cu")
		(net "P5E_PEX2_STN4_TX_DN<78>")
	)
	(segment
		(start 275.366734 -338.629498)
		(end 275.321014 -338.784438)
		(width 0.1651)
		(layer "In11.Cu")
		(net "P5E_PEX2_STN4_TX_DN<78>")
	)
	(segment
		(start 271.578832 -347.667834)
		(end 271.578832 -348.29496)
		(width 0.1651)
		(layer "In11.Cu")
		(net "P5E_PEX2_STN4_TX_DN<78>")
	)
	(segment
		(start 273.814794 -339.604858)
		(end 273.659854 -339.559138)
		(width 0.1651)
		(layer "In11.Cu")
		(net "P5E_PEX2_STN4_TX_DN<78>")
	)
	(segment
		(start 270.024352 -346.113354)
		(end 271.578832 -347.667834)
		(width 0.1651)
		(layer "In11.Cu")
		(net "P5E_PEX2_STN4_TX_DN<78>")
	)
	(segment
		(start 272.74393 -340.188042)
		(end 272.58899 -340.142322)
		(width 0.1651)
		(layer "In11.Cu")
		(net "P5E_PEX2_STN4_TX_DN<78>")
	)
	(segment
		(start 272.108422 -340.533736)
		(end 271.67332 -340.770972)
		(width 0.1651)
		(layer "In11.Cu")
		(net "P5E_PEX2_STN4_TX_DN<78>")
	)
	(segment
		(start 271.578832 -348.29496)
		(end 271.869662 -348.58579)
		(width 0.1651)
		(layer "In11.Cu")
		(net "P5E_PEX2_STN4_TX_DN<78>")
	)
	(segment
		(start 270.024352 -341.831168)
		(end 270.024352 -346.113354)
		(width 0.1651)
		(layer "In11.Cu")
		(net "P5E_PEX2_STN4_TX_DN<78>")
	)
	(segment
		(start 292.743382 -355.978206)
		(end 293.063422 -355.658166)
		(width 0.13462)
		(layer "F.Cu")
		(net "P5E_PEX2_STN4_TX_DP<67>")
	)
	(segment
		(start 293.063422 -355.658166)
		(end 293.063422 -355.026722)
		(width 0.13462)
		(layer "F.Cu")
		(net "P5E_PEX2_STN4_TX_DP<67>")
	)
	(segment
		(start 293.063422 -355.026722)
		(end 292.768782 -354.732082)
		(width 0.13462)
		(layer "F.Cu")
		(net "P5E_PEX2_STN4_TX_DP<67>")
	)
	(segment
		(start 295.28008 -341.05977)
		(end 295.280334 -341.05977)
		(width 0.1651)
		(layer "In11.Cu")
		(net "P5E_PEX2_STN4_TX_DP<67>")
	)
	(segment
		(start 322.72986 -313.78144)
		(end 317.051436 -308.103016)
		(width 0.1651)
		(layer "In11.Cu")
		(net "P5E_PEX2_STN4_TX_DP<67>")
	)
	(segment
		(start 309.34025 -307.644292)
		(end 309.34025 -307.424836)
		(width 0.1143)
		(layer "In11.Cu")
		(net "P5E_PEX2_STN4_TX_DP<67>")
	)
	(segment
		(start 309.566056 -307.870098)
		(end 309.34025 -307.644292)
		(width 0.1143)
		(layer "In11.Cu")
		(net "P5E_PEX2_STN4_TX_DP<67>")
	)
	(segment
		(start 309.215282 -307.299868)
		(end 308.949852 -307.299868)
		(width 0.1143)
		(layer "In11.Cu")
		(net "P5E_PEX2_STN4_TX_DP<67>")
	)
	(segment
		(start 327.3171 -325.689722)
		(end 328.97572 -322.424806)
		(width 0.1651)
		(layer "In11.Cu")
		(net "P5E_PEX2_STN4_TX_DP<67>")
	)
	(segment
		(start 295.719246 -340.621112)
		(end 295.877996 -340.651084)
		(width 0.1651)
		(layer "In11.Cu")
		(net "P5E_PEX2_STN4_TX_DP<67>")
	)
	(segment
		(start 294.614092 -352.259646)
		(end 294.614092 -341.843614)
		(width 0.1651)
		(layer "In11.Cu")
		(net "P5E_PEX2_STN4_TX_DP<67>")
	)
	(segment
		(start 293.059612 -354.441252)
		(end 293.059612 -353.814126)
		(width 0.1651)
		(layer "In11.Cu")
		(net "P5E_PEX2_STN4_TX_DP<67>")
	)
	(segment
		(start 315.8744 -307.915818)
		(end 315.82868 -307.870098)
		(width 0.1143)
		(layer "In11.Cu")
		(net "P5E_PEX2_STN4_TX_DP<67>")
	)
	(segment
		(start 317.051436 -308.103016)
		(end 316.11062 -307.915818)
		(width 0.1651)
		(layer "In11.Cu")
		(net "P5E_PEX2_STN4_TX_DP<67>")
	)
	(segment
		(start 309.34025 -307.424836)
		(end 309.215282 -307.299868)
		(width 0.1143)
		(layer "In11.Cu")
		(net "P5E_PEX2_STN4_TX_DP<67>")
	)
	(segment
		(start 292.768782 -354.732082)
		(end 293.059612 -354.441252)
		(width 0.1651)
		(layer "In11.Cu")
		(net "P5E_PEX2_STN4_TX_DP<67>")
	)
	(segment
		(start 295.877996 -340.651084)
		(end 296.380662 -340.307422)
		(width 0.1651)
		(layer "In11.Cu")
		(net "P5E_PEX2_STN4_TX_DP<67>")
	)
	(segment
		(start 293.059612 -353.814126)
		(end 294.614092 -352.259646)
		(width 0.1651)
		(layer "In11.Cu")
		(net "P5E_PEX2_STN4_TX_DP<67>")
	)
	(segment
		(start 315.902848 -307.915818)
		(end 315.8744 -307.915818)
		(width 0.1143)
		(layer "In11.Cu")
		(net "P5E_PEX2_STN4_TX_DP<67>")
	)
	(segment
		(start 316.11062 -307.915818)
		(end 315.902848 -307.915818)
		(width 0.1651)
		(layer "In11.Cu")
		(net "P5E_PEX2_STN4_TX_DP<67>")
	)
	(segment
		(start 328.97572 -319.696846)
		(end 328.975466 -319.696592)
		(width 0.1651)
		(layer "In11.Cu")
		(net "P5E_PEX2_STN4_TX_DP<67>")
	)
	(segment
		(start 294.614092 -341.843614)
		(end 294.88511 -341.329772)
		(width 0.1651)
		(layer "In11.Cu")
		(net "P5E_PEX2_STN4_TX_DP<67>")
	)
	(segment
		(start 328.97572 -322.424806)
		(end 328.97572 -319.696846)
		(width 0.1651)
		(layer "In11.Cu")
		(net "P5E_PEX2_STN4_TX_DP<67>")
	)
	(segment
		(start 294.88511 -341.329772)
		(end 295.28008 -341.05977)
		(width 0.1651)
		(layer "In11.Cu")
		(net "P5E_PEX2_STN4_TX_DP<67>")
	)
	(segment
		(start 328.975466 -319.696592)
		(end 327.918064 -317.143384)
		(width 0.1651)
		(layer "In11.Cu")
		(net "P5E_PEX2_STN4_TX_DP<67>")
	)
	(segment
		(start 325.578216 -327.493122)
		(end 327.3171 -325.689722)
		(width 0.1651)
		(layer "In11.Cu")
		(net "P5E_PEX2_STN4_TX_DP<67>")
	)
	(segment
		(start 315.82868 -307.870098)
		(end 309.566056 -307.870098)
		(width 0.1143)
		(layer "In11.Cu")
		(net "P5E_PEX2_STN4_TX_DP<67>")
	)
	(segment
		(start 295.310052 -340.90102)
		(end 295.719246 -340.621112)
		(width 0.1651)
		(layer "In11.Cu")
		(net "P5E_PEX2_STN4_TX_DP<67>")
	)
	(segment
		(start 325.847456 -315.072776)
		(end 322.72986 -313.78144)
		(width 0.1651)
		(layer "In11.Cu")
		(net "P5E_PEX2_STN4_TX_DP<67>")
	)
	(segment
		(start 295.280334 -341.05977)
		(end 295.310052 -340.90102)
		(width 0.1651)
		(layer "In11.Cu")
		(net "P5E_PEX2_STN4_TX_DP<67>")
	)
	(segment
		(start 296.380662 -340.307422)
		(end 325.578216 -327.493122)
		(width 0.1651)
		(layer "In11.Cu")
		(net "P5E_PEX2_STN4_TX_DP<67>")
	)
	(segment
		(start 327.918064 -317.143384)
		(end 325.847456 -315.072776)
		(width 0.1651)
		(layer "In11.Cu")
		(net "P5E_PEX2_STN4_TX_DP<67>")
	)
	(segment
		(start 293.063422 -342.734138)
		(end 292.768782 -342.439498)
		(width 0.13462)
		(layer "F.Cu")
		(net "P5E_PEX2_STN4_TX_DP<68>")
	)
	(segment
		(start 293.063422 -343.365582)
		(end 293.063422 -342.734138)
		(width 0.13462)
		(layer "F.Cu")
		(net "P5E_PEX2_STN4_TX_DP<68>")
	)
	(segment
		(start 292.743382 -343.685622)
		(end 293.063422 -343.365582)
		(width 0.13462)
		(layer "F.Cu")
		(net "P5E_PEX2_STN4_TX_DP<68>")
	)
	(segment
		(start 327.9775 -319.954148)
		(end 326.996552 -317.585852)
		(width 0.1651)
		(layer "In11.Cu")
		(net "P5E_PEX2_STN4_TX_DP<68>")
	)
	(segment
		(start 293.848028 -340.583266)
		(end 294.256968 -340.303612)
		(width 0.1651)
		(layer "In11.Cu")
		(net "P5E_PEX2_STN4_TX_DP<68>")
	)
	(segment
		(start 325.179182 -326.527922)
		(end 326.48398 -325.1708)
		(width 0.1651)
		(layer "In11.Cu")
		(net "P5E_PEX2_STN4_TX_DP<68>")
	)
	(segment
		(start 326.483726 -325.1708)
		(end 327.9775 -322.20916)
		(width 0.1651)
		(layer "In11.Cu")
		(net "P5E_PEX2_STN4_TX_DP<68>")
	)
	(segment
		(start 315.82868 -308.820058)
		(end 307.666136 -308.820058)
		(width 0.1143)
		(layer "In11.Cu")
		(net "P5E_PEX2_STN4_TX_DP<68>")
	)
	(segment
		(start 307.44033 -308.594252)
		(end 307.44033 -308.374796)
		(width 0.1143)
		(layer "In11.Cu")
		(net "P5E_PEX2_STN4_TX_DP<68>")
	)
	(segment
		(start 294.256968 -340.303612)
		(end 294.415972 -340.33333)
		(width 0.1651)
		(layer "In11.Cu")
		(net "P5E_PEX2_STN4_TX_DP<68>")
	)
	(segment
		(start 316.094872 -308.865778)
		(end 315.902848 -308.865778)
		(width 0.1651)
		(layer "In11.Cu")
		(net "P5E_PEX2_STN4_TX_DP<68>")
	)
	(segment
		(start 307.315362 -308.249828)
		(end 307.049932 -308.249828)
		(width 0.1143)
		(layer "In11.Cu")
		(net "P5E_PEX2_STN4_TX_DP<68>")
	)
	(segment
		(start 292.768782 -342.439498)
		(end 293.059612 -342.148668)
		(width 0.1651)
		(layer "In11.Cu")
		(net "P5E_PEX2_STN4_TX_DP<68>")
	)
	(segment
		(start 315.8744 -308.865778)
		(end 315.82868 -308.820058)
		(width 0.1143)
		(layer "In11.Cu")
		(net "P5E_PEX2_STN4_TX_DP<68>")
	)
	(segment
		(start 325.302118 -315.891418)
		(end 322.201794 -314.607194)
		(width 0.1651)
		(layer "In11.Cu")
		(net "P5E_PEX2_STN4_TX_DP<68>")
	)
	(segment
		(start 315.902848 -308.865778)
		(end 315.8744 -308.865778)
		(width 0.1143)
		(layer "In11.Cu")
		(net "P5E_PEX2_STN4_TX_DP<68>")
	)
	(segment
		(start 293.059612 -341.371428)
		(end 293.40937 -341.02167)
		(width 0.1651)
		(layer "In11.Cu")
		(net "P5E_PEX2_STN4_TX_DP<68>")
	)
	(segment
		(start 326.48398 -325.1708)
		(end 326.483726 -325.1708)
		(width 0.1651)
		(layer "In11.Cu")
		(net "P5E_PEX2_STN4_TX_DP<68>")
	)
	(segment
		(start 293.40937 -341.02167)
		(end 293.818056 -340.74227)
		(width 0.1651)
		(layer "In11.Cu")
		(net "P5E_PEX2_STN4_TX_DP<68>")
	)
	(segment
		(start 327.9775 -322.20916)
		(end 327.9775 -319.954148)
		(width 0.1651)
		(layer "In11.Cu")
		(net "P5E_PEX2_STN4_TX_DP<68>")
	)
	(segment
		(start 307.44033 -308.374796)
		(end 307.315362 -308.249828)
		(width 0.1143)
		(layer "In11.Cu")
		(net "P5E_PEX2_STN4_TX_DP<68>")
	)
	(segment
		(start 307.666136 -308.820058)
		(end 307.44033 -308.594252)
		(width 0.1143)
		(layer "In11.Cu")
		(net "P5E_PEX2_STN4_TX_DP<68>")
	)
	(segment
		(start 316.71895 -309.12435)
		(end 316.094872 -308.865778)
		(width 0.1651)
		(layer "In11.Cu")
		(net "P5E_PEX2_STN4_TX_DP<68>")
	)
	(segment
		(start 295.581578 -339.536278)
		(end 325.179182 -326.527922)
		(width 0.1651)
		(layer "In11.Cu")
		(net "P5E_PEX2_STN4_TX_DP<68>")
	)
	(segment
		(start 322.201794 -314.607194)
		(end 316.71895 -309.12435)
		(width 0.1651)
		(layer "In11.Cu")
		(net "P5E_PEX2_STN4_TX_DP<68>")
	)
	(segment
		(start 293.818056 -340.74227)
		(end 293.848028 -340.583266)
		(width 0.1651)
		(layer "In11.Cu")
		(net "P5E_PEX2_STN4_TX_DP<68>")
	)
	(segment
		(start 293.059612 -342.148668)
		(end 293.059612 -341.371428)
		(width 0.1651)
		(layer "In11.Cu")
		(net "P5E_PEX2_STN4_TX_DP<68>")
	)
	(segment
		(start 326.996552 -317.585852)
		(end 325.302118 -315.891418)
		(width 0.1651)
		(layer "In11.Cu")
		(net "P5E_PEX2_STN4_TX_DP<68>")
	)
	(segment
		(start 294.415972 -340.33333)
		(end 295.581578 -339.536278)
		(width 0.1651)
		(layer "In11.Cu")
		(net "P5E_PEX2_STN4_TX_DP<68>")
	)
	(segment
		(start 296.172382 -348.88043)
		(end 295.877742 -348.58579)
		(width 0.13462)
		(layer "F.Cu")
		(net "P5E_PEX2_STN4_TX_DP<66>")
	)
	(segment
		(start 295.852342 -349.831914)
		(end 296.172382 -349.511874)
		(width 0.13462)
		(layer "F.Cu")
		(net "P5E_PEX2_STN4_TX_DP<66>")
	)
	(segment
		(start 296.172382 -349.511874)
		(end 296.172382 -348.88043)
		(width 0.13462)
		(layer "F.Cu")
		(net "P5E_PEX2_STN4_TX_DP<66>")
	)
	(segment
		(start 323.274436 -312.954416)
		(end 317.52159 -307.20157)
		(width 0.1651)
		(layer "In11.Cu")
		(net "P5E_PEX2_STN4_TX_DP<66>")
	)
	(segment
		(start 307.666136 -306.920138)
		(end 307.44033 -306.694332)
		(width 0.1143)
		(layer "In11.Cu")
		(net "P5E_PEX2_STN4_TX_DP<66>")
	)
	(segment
		(start 307.44033 -306.474876)
		(end 307.315362 -306.349908)
		(width 0.1143)
		(layer "In11.Cu")
		(net "P5E_PEX2_STN4_TX_DP<66>")
	)
	(segment
		(start 328.1553 -326.1995)
		(end 329.94092 -322.648834)
		(width 0.1651)
		(layer "In11.Cu")
		(net "P5E_PEX2_STN4_TX_DP<66>")
	)
	(segment
		(start 298.208446 -341.006176)
		(end 298.558966 -340.655656)
		(width 0.1651)
		(layer "In11.Cu")
		(net "P5E_PEX2_STN4_TX_DP<66>")
	)
	(segment
		(start 296.168572 -347.667834)
		(end 297.723052 -346.113354)
		(width 0.1651)
		(layer "In11.Cu")
		(net "P5E_PEX2_STN4_TX_DP<66>")
	)
	(segment
		(start 315.902848 -306.965858)
		(end 315.8744 -306.965858)
		(width 0.1143)
		(layer "In11.Cu")
		(net "P5E_PEX2_STN4_TX_DP<66>")
	)
	(segment
		(start 316.154562 -306.965858)
		(end 315.902848 -306.965858)
		(width 0.1651)
		(layer "In11.Cu")
		(net "P5E_PEX2_STN4_TX_DP<66>")
	)
	(segment
		(start 295.877742 -348.58579)
		(end 296.168572 -348.29496)
		(width 0.1651)
		(layer "In11.Cu")
		(net "P5E_PEX2_STN4_TX_DP<66>")
	)
	(segment
		(start 299.27931 -340.096856)
		(end 326.061832 -328.41184)
		(width 0.1651)
		(layer "In11.Cu")
		(net "P5E_PEX2_STN4_TX_DP<66>")
	)
	(segment
		(start 298.72051 -340.655656)
		(end 299.27931 -340.096856)
		(width 0.1651)
		(layer "In11.Cu")
		(net "P5E_PEX2_STN4_TX_DP<66>")
	)
	(segment
		(start 326.39635 -314.24753)
		(end 326.396096 -314.24753)
		(width 0.1651)
		(layer "In11.Cu")
		(net "P5E_PEX2_STN4_TX_DP<66>")
	)
	(segment
		(start 329.94092 -322.648834)
		(end 329.94092 -319.422272)
		(width 0.1651)
		(layer "In11.Cu")
		(net "P5E_PEX2_STN4_TX_DP<66>")
	)
	(segment
		(start 307.44033 -306.694332)
		(end 307.44033 -306.474876)
		(width 0.1143)
		(layer "In11.Cu")
		(net "P5E_PEX2_STN4_TX_DP<66>")
	)
	(segment
		(start 307.315362 -306.349908)
		(end 307.049932 -306.349908)
		(width 0.1143)
		(layer "In11.Cu")
		(net "P5E_PEX2_STN4_TX_DP<66>")
	)
	(segment
		(start 315.82868 -306.920138)
		(end 307.666136 -306.920138)
		(width 0.1143)
		(layer "In11.Cu")
		(net "P5E_PEX2_STN4_TX_DP<66>")
	)
	(segment
		(start 298.558966 -340.655656)
		(end 298.72051 -340.655656)
		(width 0.1651)
		(layer "In11.Cu")
		(net "P5E_PEX2_STN4_TX_DP<66>")
	)
	(segment
		(start 298.208446 -341.167974)
		(end 298.208446 -341.006176)
		(width 0.1651)
		(layer "In11.Cu")
		(net "P5E_PEX2_STN4_TX_DP<66>")
	)
	(segment
		(start 316.51575 -307.001672)
		(end 316.154562 -306.965858)
		(width 0.1651)
		(layer "In11.Cu")
		(net "P5E_PEX2_STN4_TX_DP<66>")
	)
	(segment
		(start 329.94092 -319.422272)
		(end 328.788268 -316.639448)
		(width 0.1651)
		(layer "In11.Cu")
		(net "P5E_PEX2_STN4_TX_DP<66>")
	)
	(segment
		(start 328.788268 -316.639448)
		(end 326.39635 -314.24753)
		(width 0.1651)
		(layer "In11.Cu")
		(net "P5E_PEX2_STN4_TX_DP<66>")
	)
	(segment
		(start 297.858434 -341.517986)
		(end 298.208446 -341.167974)
		(width 0.1651)
		(layer "In11.Cu")
		(net "P5E_PEX2_STN4_TX_DP<66>")
	)
	(segment
		(start 297.723052 -341.844884)
		(end 297.858434 -341.517986)
		(width 0.1651)
		(layer "In11.Cu")
		(net "P5E_PEX2_STN4_TX_DP<66>")
	)
	(segment
		(start 315.8744 -306.965858)
		(end 315.82868 -306.920138)
		(width 0.1143)
		(layer "In11.Cu")
		(net "P5E_PEX2_STN4_TX_DP<66>")
	)
	(segment
		(start 296.168572 -348.29496)
		(end 296.168572 -347.667834)
		(width 0.1651)
		(layer "In11.Cu")
		(net "P5E_PEX2_STN4_TX_DP<66>")
	)
	(segment
		(start 297.723052 -346.113354)
		(end 297.723052 -341.844884)
		(width 0.1651)
		(layer "In11.Cu")
		(net "P5E_PEX2_STN4_TX_DP<66>")
	)
	(segment
		(start 317.52159 -307.20157)
		(end 316.51575 -307.001672)
		(width 0.1651)
		(layer "In11.Cu")
		(net "P5E_PEX2_STN4_TX_DP<66>")
	)
	(segment
		(start 326.061832 -328.41184)
		(end 328.1553 -326.1995)
		(width 0.1651)
		(layer "In11.Cu")
		(net "P5E_PEX2_STN4_TX_DP<66>")
	)
	(segment
		(start 326.396096 -314.24753)
		(end 323.274436 -312.954416)
		(width 0.1651)
		(layer "In11.Cu")
		(net "P5E_PEX2_STN4_TX_DP<66>")
	)
	(segment
		(start 298.57319 -213.923118)
		(end 300.82236 -216.172288)
		(width 0.13208)
		(layer "F.Cu")
		(net "SPI_BIC1_CLK_LS23_R2")
	)
	(via
		(at 300.82236 -216.172288)
		(size 0.508)
		(drill 0.254)
		(layers "F.Cu" "B.Cu")
		(net "SPI_BIC1_CLK_LS23_R2")
	)
	(via
		(at 368.626644 -228.231446)
		(size 0.508)
		(drill 0.254)
		(layers "F.Cu" "B.Cu")
		(net "SPI_BIC1_CLK_LS23_R2")
	)
	(segment
		(start 368.626644 -228.231446)
		(end 368.626644 -228.548438)
		(width 0.13208)
		(layer "B.Cu")
		(net "SPI_BIC1_CLK_LS23_R2")
	)
	(segment
		(start 368.970814 -228.892608)
		(end 368.970814 -229.827582)
		(width 0.13208)
		(layer "B.Cu")
		(net "SPI_BIC1_CLK_LS23_R2")
	)
	(segment
		(start 368.626644 -228.548438)
		(end 368.970814 -228.892608)
		(width 0.13208)
		(layer "B.Cu")
		(net "SPI_BIC1_CLK_LS23_R2")
	)
	(segment
		(start 327.932034 -234.65028)
		(end 327.797414 -234.7849)
		(width 0.15494)
		(layer "In11.Cu")
		(net "SPI_BIC1_CLK_LS23_R2")
	)
	(segment
		(start 328.440034 -233.86415)
		(end 328.066654 -233.86415)
		(width 0.15494)
		(layer "In11.Cu")
		(net "SPI_BIC1_CLK_LS23_R2")
	)
	(segment
		(start 327.797414 -234.7849)
		(end 327.482962 -234.7849)
		(width 0.15494)
		(layer "In11.Cu")
		(net "SPI_BIC1_CLK_LS23_R2")
	)
	(segment
		(start 321.935602 -228.621844)
		(end 315.241432 -221.927674)
		(width 0.15494)
		(layer "In11.Cu")
		(net "SPI_BIC1_CLK_LS23_R2")
	)
	(segment
		(start 331.922374 -233.86415)
		(end 331.787754 -233.99877)
		(width 0.15494)
		(layer "In11.Cu")
		(net "SPI_BIC1_CLK_LS23_R2")
	)
	(segment
		(start 331.145134 -234.65028)
		(end 331.145134 -233.99877)
		(width 0.15494)
		(layer "In11.Cu")
		(net "SPI_BIC1_CLK_LS23_R2")
	)
	(segment
		(start 352.299778 -234.82427)
		(end 351.69348 -234.217972)
		(width 0.15494)
		(layer "In11.Cu")
		(net "SPI_BIC1_CLK_LS23_R2")
	)
	(segment
		(start 331.653134 -234.7849)
		(end 331.279754 -234.7849)
		(width 0.15494)
		(layer "In11.Cu")
		(net "SPI_BIC1_CLK_LS23_R2")
	)
	(segment
		(start 358.76865 -234.25785)
		(end 355.211888 -234.25785)
		(width 0.15494)
		(layer "In11.Cu")
		(net "SPI_BIC1_CLK_LS23_R2")
	)
	(segment
		(start 329.725274 -233.86415)
		(end 329.351894 -233.86415)
		(width 0.15494)
		(layer "In11.Cu")
		(net "SPI_BIC1_CLK_LS23_R2")
	)
	(segment
		(start 324.555612 -231.85755)
		(end 323.487034 -229.27818)
		(width 0.15494)
		(layer "In11.Cu")
		(net "SPI_BIC1_CLK_LS23_R2")
	)
	(segment
		(start 323.46392 -229.255066)
		(end 321.935602 -228.621844)
		(width 0.15494)
		(layer "In11.Cu")
		(net "SPI_BIC1_CLK_LS23_R2")
	)
	(segment
		(start 331.145134 -233.99877)
		(end 331.010514 -233.86415)
		(width 0.15494)
		(layer "In11.Cu")
		(net "SPI_BIC1_CLK_LS23_R2")
	)
	(segment
		(start 332.295754 -233.86415)
		(end 331.922374 -233.86415)
		(width 0.15494)
		(layer "In11.Cu")
		(net "SPI_BIC1_CLK_LS23_R2")
	)
	(segment
		(start 330.637134 -233.86415)
		(end 330.502514 -233.99877)
		(width 0.15494)
		(layer "In11.Cu")
		(net "SPI_BIC1_CLK_LS23_R2")
	)
	(segment
		(start 329.859894 -233.99877)
		(end 329.725274 -233.86415)
		(width 0.15494)
		(layer "In11.Cu")
		(net "SPI_BIC1_CLK_LS23_R2")
	)
	(segment
		(start 330.502514 -234.65028)
		(end 330.367894 -234.7849)
		(width 0.15494)
		(layer "In11.Cu")
		(net "SPI_BIC1_CLK_LS23_R2")
	)
	(segment
		(start 333.39405 -234.217972)
		(end 332.827122 -234.7849)
		(width 0.15494)
		(layer "In11.Cu")
		(net "SPI_BIC1_CLK_LS23_R2")
	)
	(segment
		(start 332.430374 -234.65028)
		(end 332.430374 -233.99877)
		(width 0.15494)
		(layer "In11.Cu")
		(net "SPI_BIC1_CLK_LS23_R2")
	)
	(segment
		(start 330.367894 -234.7849)
		(end 329.994514 -234.7849)
		(width 0.15494)
		(layer "In11.Cu")
		(net "SPI_BIC1_CLK_LS23_R2")
	)
	(segment
		(start 330.502514 -233.99877)
		(end 330.502514 -234.65028)
		(width 0.15494)
		(layer "In11.Cu")
		(net "SPI_BIC1_CLK_LS23_R2")
	)
	(segment
		(start 329.994514 -234.7849)
		(end 329.859894 -234.65028)
		(width 0.15494)
		(layer "In11.Cu")
		(net "SPI_BIC1_CLK_LS23_R2")
	)
	(segment
		(start 331.010514 -233.86415)
		(end 330.637134 -233.86415)
		(width 0.15494)
		(layer "In11.Cu")
		(net "SPI_BIC1_CLK_LS23_R2")
	)
	(segment
		(start 301.135034 -216.484962)
		(end 300.82236 -216.172288)
		(width 0.15494)
		(layer "In11.Cu")
		(net "SPI_BIC1_CLK_LS23_R2")
	)
	(segment
		(start 332.827122 -234.7849)
		(end 332.564994 -234.7849)
		(width 0.15494)
		(layer "In11.Cu")
		(net "SPI_BIC1_CLK_LS23_R2")
	)
	(segment
		(start 301.710598 -216.484962)
		(end 301.135034 -216.484962)
		(width 0.15494)
		(layer "In11.Cu")
		(net "SPI_BIC1_CLK_LS23_R2")
	)
	(segment
		(start 329.351894 -233.86415)
		(end 329.217274 -233.99877)
		(width 0.15494)
		(layer "In11.Cu")
		(net "SPI_BIC1_CLK_LS23_R2")
	)
	(segment
		(start 327.482962 -234.7849)
		(end 324.555612 -231.85755)
		(width 0.15494)
		(layer "In11.Cu")
		(net "SPI_BIC1_CLK_LS23_R2")
	)
	(segment
		(start 354.645468 -234.82427)
		(end 352.299778 -234.82427)
		(width 0.15494)
		(layer "In11.Cu")
		(net "SPI_BIC1_CLK_LS23_R2")
	)
	(segment
		(start 368.626644 -228.231446)
		(end 368.626644 -228.623368)
		(width 0.15494)
		(layer "In11.Cu")
		(net "SPI_BIC1_CLK_LS23_R2")
	)
	(segment
		(start 355.211888 -234.25785)
		(end 354.645468 -234.82427)
		(width 0.15494)
		(layer "In11.Cu")
		(net "SPI_BIC1_CLK_LS23_R2")
	)
	(segment
		(start 332.564994 -234.7849)
		(end 332.430374 -234.65028)
		(width 0.15494)
		(layer "In11.Cu")
		(net "SPI_BIC1_CLK_LS23_R2")
	)
	(segment
		(start 301.973996 -216.74836)
		(end 301.710598 -216.484962)
		(width 0.15494)
		(layer "In11.Cu")
		(net "SPI_BIC1_CLK_LS23_R2")
	)
	(segment
		(start 329.082654 -234.7849)
		(end 328.709274 -234.7849)
		(width 0.15494)
		(layer "In11.Cu")
		(net "SPI_BIC1_CLK_LS23_R2")
	)
	(segment
		(start 329.217274 -234.65028)
		(end 329.082654 -234.7849)
		(width 0.15494)
		(layer "In11.Cu")
		(net "SPI_BIC1_CLK_LS23_R2")
	)
	(segment
		(start 328.066654 -233.86415)
		(end 327.932034 -233.99877)
		(width 0.15494)
		(layer "In11.Cu")
		(net "SPI_BIC1_CLK_LS23_R2")
	)
	(segment
		(start 331.279754 -234.7849)
		(end 331.145134 -234.65028)
		(width 0.15494)
		(layer "In11.Cu")
		(net "SPI_BIC1_CLK_LS23_R2")
	)
	(segment
		(start 332.430374 -233.99877)
		(end 332.295754 -233.86415)
		(width 0.15494)
		(layer "In11.Cu")
		(net "SPI_BIC1_CLK_LS23_R2")
	)
	(segment
		(start 323.487034 -229.27818)
		(end 323.46392 -229.255066)
		(width 0.15494)
		(layer "In11.Cu")
		(net "SPI_BIC1_CLK_LS23_R2")
	)
	(segment
		(start 331.787754 -233.99877)
		(end 331.787754 -234.65028)
		(width 0.15494)
		(layer "In11.Cu")
		(net "SPI_BIC1_CLK_LS23_R2")
	)
	(segment
		(start 351.69348 -234.217972)
		(end 333.39405 -234.217972)
		(width 0.15494)
		(layer "In11.Cu")
		(net "SPI_BIC1_CLK_LS23_R2")
	)
	(segment
		(start 365.978948 -231.271064)
		(end 358.76865 -234.25785)
		(width 0.15494)
		(layer "In11.Cu")
		(net "SPI_BIC1_CLK_LS23_R2")
	)
	(segment
		(start 368.626644 -228.623368)
		(end 365.978948 -231.271064)
		(width 0.15494)
		(layer "In11.Cu")
		(net "SPI_BIC1_CLK_LS23_R2")
	)
	(segment
		(start 315.241432 -221.927674)
		(end 302.73752 -216.74836)
		(width 0.15494)
		(layer "In11.Cu")
		(net "SPI_BIC1_CLK_LS23_R2")
	)
	(segment
		(start 327.932034 -233.99877)
		(end 327.932034 -234.65028)
		(width 0.15494)
		(layer "In11.Cu")
		(net "SPI_BIC1_CLK_LS23_R2")
	)
	(segment
		(start 331.787754 -234.65028)
		(end 331.653134 -234.7849)
		(width 0.15494)
		(layer "In11.Cu")
		(net "SPI_BIC1_CLK_LS23_R2")
	)
	(segment
		(start 302.73752 -216.74836)
		(end 301.973996 -216.74836)
		(width 0.15494)
		(layer "In11.Cu")
		(net "SPI_BIC1_CLK_LS23_R2")
	)
	(segment
		(start 328.574654 -234.65028)
		(end 328.574654 -233.99877)
		(width 0.15494)
		(layer "In11.Cu")
		(net "SPI_BIC1_CLK_LS23_R2")
	)
	(segment
		(start 329.859894 -234.65028)
		(end 329.859894 -233.99877)
		(width 0.15494)
		(layer "In11.Cu")
		(net "SPI_BIC1_CLK_LS23_R2")
	)
	(segment
		(start 328.709274 -234.7849)
		(end 328.574654 -234.65028)
		(width 0.15494)
		(layer "In11.Cu")
		(net "SPI_BIC1_CLK_LS23_R2")
	)
	(segment
		(start 329.217274 -233.99877)
		(end 329.217274 -234.65028)
		(width 0.15494)
		(layer "In11.Cu")
		(net "SPI_BIC1_CLK_LS23_R2")
	)
	(segment
		(start 328.574654 -233.99877)
		(end 328.440034 -233.86415)
		(width 0.15494)
		(layer "In11.Cu")
		(net "SPI_BIC1_CLK_LS23_R2")
	)
	(segment
		(start 286.525462 -343.685622)
		(end 286.845502 -343.365582)
		(width 0.13462)
		(layer "F.Cu")
		(net "P5E_PEX2_STN4_TX_DP<71>")
	)
	(segment
		(start 286.845502 -342.734138)
		(end 286.550862 -342.439498)
		(width 0.13462)
		(layer "F.Cu")
		(net "P5E_PEX2_STN4_TX_DP<71>")
	)
	(segment
		(start 286.845502 -343.365582)
		(end 286.845502 -342.734138)
		(width 0.13462)
		(layer "F.Cu")
		(net "P5E_PEX2_STN4_TX_DP<71>")
	)
	(segment
		(start 286.841692 -341.503508)
		(end 287.838896 -340.506304)
		(width 0.1651)
		(layer "In11.Cu")
		(net "P5E_PEX2_STN4_TX_DP<71>")
	)
	(segment
		(start 308.932072 -328.183748)
		(end 312.580782 -324.534784)
		(width 0.1651)
		(layer "In11.Cu")
		(net "P5E_PEX2_STN4_TX_DP<71>")
	)
	(segment
		(start 287.838896 -340.506304)
		(end 308.932072 -328.183748)
		(width 0.1651)
		(layer "In11.Cu")
		(net "P5E_PEX2_STN4_TX_DP<71>")
	)
	(segment
		(start 314.033916 -319.052448)
		(end 314.033916 -319.024)
		(width 0.1143)
		(layer "In11.Cu")
		(net "P5E_PEX2_STN4_TX_DP<71>")
	)
	(segment
		(start 286.841692 -342.148668)
		(end 286.841692 -341.503508)
		(width 0.1651)
		(layer "In11.Cu")
		(net "P5E_PEX2_STN4_TX_DP<71>")
	)
	(segment
		(start 314.033916 -319.024)
		(end 314.079636 -318.97828)
		(width 0.1143)
		(layer "In11.Cu")
		(net "P5E_PEX2_STN4_TX_DP<71>")
	)
	(segment
		(start 313.965336 -314.899802)
		(end 313.699906 -314.899802)
		(width 0.1143)
		(layer "In11.Cu")
		(net "P5E_PEX2_STN4_TX_DP<71>")
	)
	(segment
		(start 314.079636 -318.97828)
		(end 314.079636 -315.014102)
		(width 0.1143)
		(layer "In11.Cu")
		(net "P5E_PEX2_STN4_TX_DP<71>")
	)
	(segment
		(start 312.580782 -324.534784)
		(end 314.033916 -321.816476)
		(width 0.1651)
		(layer "In11.Cu")
		(net "P5E_PEX2_STN4_TX_DP<71>")
	)
	(segment
		(start 314.033916 -321.816476)
		(end 314.033916 -319.052448)
		(width 0.1651)
		(layer "In11.Cu")
		(net "P5E_PEX2_STN4_TX_DP<71>")
	)
	(segment
		(start 314.079636 -315.014102)
		(end 313.965336 -314.899802)
		(width 0.1143)
		(layer "In11.Cu")
		(net "P5E_PEX2_STN4_TX_DP<71>")
	)
	(segment
		(start 286.550862 -342.439498)
		(end 286.841692 -342.148668)
		(width 0.1651)
		(layer "In11.Cu")
		(net "P5E_PEX2_STN4_TX_DP<71>")
	)
	(segment
		(start 302.505872 -215.570562)
		(end 302.141636 -215.206326)
		(width 0.13208)
		(layer "F.Cu")
		(net "SPI_BIC1_CS0_LS23_R2_N")
	)
	(segment
		(start 300.872398 -215.206326)
		(end 299.58919 -213.923118)
		(width 0.13208)
		(layer "F.Cu")
		(net "SPI_BIC1_CS0_LS23_R2_N")
	)
	(segment
		(start 302.141636 -215.206326)
		(end 300.872398 -215.206326)
		(width 0.13208)
		(layer "F.Cu")
		(net "SPI_BIC1_CS0_LS23_R2_N")
	)
	(via
		(at 302.505872 -215.570562)
		(size 0.508)
		(drill 0.254)
		(layers "F.Cu" "B.Cu")
		(net "SPI_BIC1_CS0_LS23_R2_N")
	)
	(via
		(at 366.580674 -228.347524)
		(size 0.508)
		(drill 0.254)
		(layers "F.Cu" "B.Cu")
		(net "SPI_BIC1_CS0_LS23_R2_N")
	)
	(segment
		(start 366.580674 -228.72573)
		(end 367.065814 -229.21087)
		(width 0.13208)
		(layer "B.Cu")
		(net "SPI_BIC1_CS0_LS23_R2_N")
	)
	(segment
		(start 366.580674 -228.347524)
		(end 366.580674 -228.72573)
		(width 0.13208)
		(layer "B.Cu")
		(net "SPI_BIC1_CS0_LS23_R2_N")
	)
	(segment
		(start 367.065814 -229.21087)
		(end 367.065814 -229.827582)
		(width 0.13208)
		(layer "B.Cu")
		(net "SPI_BIC1_CS0_LS23_R2_N")
	)
	(segment
		(start 318.705992 -220.27642)
		(end 318.171068 -220.81109)
		(width 0.15494)
		(layer "In11.Cu")
		(net "SPI_BIC1_CS0_LS23_R2_N")
	)
	(segment
		(start 318.895984 -220.27642)
		(end 318.705992 -220.27642)
		(width 0.15494)
		(layer "In11.Cu")
		(net "SPI_BIC1_CS0_LS23_R2_N")
	)
	(segment
		(start 354.999798 -233.588306)
		(end 354.574856 -233.163364)
		(width 0.15494)
		(layer "In11.Cu")
		(net "SPI_BIC1_CS0_LS23_R2_N")
	)
	(segment
		(start 319.160398 -220.540834)
		(end 318.895984 -220.27642)
		(width 0.15494)
		(layer "In11.Cu")
		(net "SPI_BIC1_CS0_LS23_R2_N")
	)
	(segment
		(start 317.342774 -218.913202)
		(end 317.342774 -218.72321)
		(width 0.15494)
		(layer "In11.Cu")
		(net "SPI_BIC1_CS0_LS23_R2_N")
	)
	(segment
		(start 325.690738 -227.110798)
		(end 324.310248 -227.110798)
		(width 0.15494)
		(layer "In11.Cu")
		(net "SPI_BIC1_CS0_LS23_R2_N")
	)
	(segment
		(start 320.06921 -221.449646)
		(end 319.804796 -221.185232)
		(width 0.15494)
		(layer "In11.Cu")
		(net "SPI_BIC1_CS0_LS23_R2_N")
	)
	(segment
		(start 317.262256 -219.902278)
		(end 317.072264 -219.902278)
		(width 0.15494)
		(layer "In11.Cu")
		(net "SPI_BIC1_CS0_LS23_R2_N")
	)
	(segment
		(start 317.716662 -220.356684)
		(end 318.251586 -219.822014)
		(width 0.15494)
		(layer "In11.Cu")
		(net "SPI_BIC1_CS0_LS23_R2_N")
	)
	(segment
		(start 317.07836 -218.458796)
		(end 316.888368 -218.458796)
		(width 0.15494)
		(layer "In11.Cu")
		(net "SPI_BIC1_CS0_LS23_R2_N")
	)
	(segment
		(start 324.310248 -227.110798)
		(end 321.361562 -224.162112)
		(width 0.15494)
		(layer "In11.Cu")
		(net "SPI_BIC1_CS0_LS23_R2_N")
	)
	(segment
		(start 319.534286 -222.174308)
		(end 320.06921 -221.639638)
		(width 0.15494)
		(layer "In11.Cu")
		(net "SPI_BIC1_CS0_LS23_R2_N")
	)
	(segment
		(start 318.625474 -221.265496)
		(end 319.160398 -220.730826)
		(width 0.15494)
		(layer "In11.Cu")
		(net "SPI_BIC1_CS0_LS23_R2_N")
	)
	(segment
		(start 319.614804 -221.185232)
		(end 319.07988 -221.719902)
		(width 0.15494)
		(layer "In11.Cu")
		(net "SPI_BIC1_CS0_LS23_R2_N")
	)
	(segment
		(start 317.716662 -220.546676)
		(end 317.716662 -220.356684)
		(width 0.15494)
		(layer "In11.Cu")
		(net "SPI_BIC1_CS0_LS23_R2_N")
	)
	(segment
		(start 318.251586 -219.822014)
		(end 318.251586 -219.632022)
		(width 0.15494)
		(layer "In11.Cu")
		(net "SPI_BIC1_CS0_LS23_R2_N")
	)
	(segment
		(start 334.700372 -233.50982)
		(end 333.386176 -232.195624)
		(width 0.15494)
		(layer "In11.Cu")
		(net "SPI_BIC1_CS0_LS23_R2_N")
	)
	(segment
		(start 313.275472 -220.335856)
		(end 303.025556 -216.090246)
		(width 0.15494)
		(layer "In11.Cu")
		(net "SPI_BIC1_CS0_LS23_R2_N")
	)
	(segment
		(start 320.443098 -223.08312)
		(end 320.978022 -222.54845)
		(width 0.15494)
		(layer "In11.Cu")
		(net "SPI_BIC1_CS0_LS23_R2_N")
	)
	(segment
		(start 352.402394 -233.163364)
		(end 352.055938 -233.50982)
		(width 0.15494)
		(layer "In11.Cu")
		(net "SPI_BIC1_CS0_LS23_R2_N")
	)
	(segment
		(start 318.889888 -221.719902)
		(end 318.625474 -221.455488)
		(width 0.15494)
		(layer "In11.Cu")
		(net "SPI_BIC1_CS0_LS23_R2_N")
	)
	(segment
		(start 316.888368 -218.458796)
		(end 315.010292 -220.335856)
		(width 0.15494)
		(layer "In11.Cu")
		(net "SPI_BIC1_CS0_LS23_R2_N")
	)
	(segment
		(start 315.010292 -220.335856)
		(end 313.275472 -220.335856)
		(width 0.15494)
		(layer "In11.Cu")
		(net "SPI_BIC1_CS0_LS23_R2_N")
	)
	(segment
		(start 318.625474 -221.455488)
		(end 318.625474 -221.265496)
		(width 0.15494)
		(layer "In11.Cu")
		(net "SPI_BIC1_CS0_LS23_R2_N")
	)
	(segment
		(start 317.981076 -220.81109)
		(end 317.716662 -220.546676)
		(width 0.15494)
		(layer "In11.Cu")
		(net "SPI_BIC1_CS0_LS23_R2_N")
	)
	(segment
		(start 319.7987 -222.628714)
		(end 319.534286 -222.3643)
		(width 0.15494)
		(layer "In11.Cu")
		(net "SPI_BIC1_CS0_LS23_R2_N")
	)
	(segment
		(start 319.07988 -221.719902)
		(end 318.889888 -221.719902)
		(width 0.15494)
		(layer "In11.Cu")
		(net "SPI_BIC1_CS0_LS23_R2_N")
	)
	(segment
		(start 317.79718 -219.367608)
		(end 317.262256 -219.902278)
		(width 0.15494)
		(layer "In11.Cu")
		(net "SPI_BIC1_CS0_LS23_R2_N")
	)
	(segment
		(start 316.80785 -219.637864)
		(end 316.80785 -219.447872)
		(width 0.15494)
		(layer "In11.Cu")
		(net "SPI_BIC1_CS0_LS23_R2_N")
	)
	(segment
		(start 320.523616 -222.094044)
		(end 319.988692 -222.628714)
		(width 0.15494)
		(layer "In11.Cu")
		(net "SPI_BIC1_CS0_LS23_R2_N")
	)
	(segment
		(start 333.386176 -232.195624)
		(end 329.059794 -232.195624)
		(width 0.15494)
		(layer "In11.Cu")
		(net "SPI_BIC1_CS0_LS23_R2_N")
	)
	(segment
		(start 320.443098 -223.273112)
		(end 320.443098 -223.08312)
		(width 0.15494)
		(layer "In11.Cu")
		(net "SPI_BIC1_CS0_LS23_R2_N")
	)
	(segment
		(start 317.342774 -218.72321)
		(end 317.07836 -218.458796)
		(width 0.15494)
		(layer "In11.Cu")
		(net "SPI_BIC1_CS0_LS23_R2_N")
	)
	(segment
		(start 320.713608 -222.094044)
		(end 320.523616 -222.094044)
		(width 0.15494)
		(layer "In11.Cu")
		(net "SPI_BIC1_CS0_LS23_R2_N")
	)
	(segment
		(start 354.574856 -233.163364)
		(end 352.402394 -233.163364)
		(width 0.15494)
		(layer "In11.Cu")
		(net "SPI_BIC1_CS0_LS23_R2_N")
	)
	(segment
		(start 321.886834 -223.457262)
		(end 321.886834 -223.26727)
		(width 0.15494)
		(layer "In11.Cu")
		(net "SPI_BIC1_CS0_LS23_R2_N")
	)
	(segment
		(start 319.160398 -220.730826)
		(end 319.160398 -220.540834)
		(width 0.15494)
		(layer "In11.Cu")
		(net "SPI_BIC1_CS0_LS23_R2_N")
	)
	(segment
		(start 319.534286 -222.3643)
		(end 319.534286 -222.174308)
		(width 0.15494)
		(layer "In11.Cu")
		(net "SPI_BIC1_CS0_LS23_R2_N")
	)
	(segment
		(start 321.886834 -223.26727)
		(end 321.62242 -223.002856)
		(width 0.15494)
		(layer "In11.Cu")
		(net "SPI_BIC1_CS0_LS23_R2_N")
	)
	(segment
		(start 363.2835 -231.644698)
		(end 358.591358 -233.588306)
		(width 0.15494)
		(layer "In11.Cu")
		(net "SPI_BIC1_CS0_LS23_R2_N")
	)
	(segment
		(start 320.897504 -223.537526)
		(end 320.707512 -223.537526)
		(width 0.15494)
		(layer "In11.Cu")
		(net "SPI_BIC1_CS0_LS23_R2_N")
	)
	(segment
		(start 321.361562 -224.162112)
		(end 321.361562 -223.98228)
		(width 0.15494)
		(layer "In11.Cu")
		(net "SPI_BIC1_CS0_LS23_R2_N")
	)
	(segment
		(start 352.055938 -233.50982)
		(end 334.700372 -233.50982)
		(width 0.15494)
		(layer "In11.Cu")
		(net "SPI_BIC1_CS0_LS23_R2_N")
	)
	(segment
		(start 316.80785 -219.447872)
		(end 317.342774 -218.913202)
		(width 0.15494)
		(layer "In11.Cu")
		(net "SPI_BIC1_CS0_LS23_R2_N")
	)
	(segment
		(start 317.987172 -219.367608)
		(end 317.79718 -219.367608)
		(width 0.15494)
		(layer "In11.Cu")
		(net "SPI_BIC1_CS0_LS23_R2_N")
	)
	(segment
		(start 318.171068 -220.81109)
		(end 317.981076 -220.81109)
		(width 0.15494)
		(layer "In11.Cu")
		(net "SPI_BIC1_CS0_LS23_R2_N")
	)
	(segment
		(start 320.707512 -223.537526)
		(end 320.443098 -223.273112)
		(width 0.15494)
		(layer "In11.Cu")
		(net "SPI_BIC1_CS0_LS23_R2_N")
	)
	(segment
		(start 320.978022 -222.358458)
		(end 320.713608 -222.094044)
		(width 0.15494)
		(layer "In11.Cu")
		(net "SPI_BIC1_CS0_LS23_R2_N")
	)
	(segment
		(start 320.06921 -221.639638)
		(end 320.06921 -221.449646)
		(width 0.15494)
		(layer "In11.Cu")
		(net "SPI_BIC1_CS0_LS23_R2_N")
	)
	(segment
		(start 366.580674 -228.347524)
		(end 363.2835 -231.644698)
		(width 0.15494)
		(layer "In11.Cu")
		(net "SPI_BIC1_CS0_LS23_R2_N")
	)
	(segment
		(start 318.251586 -219.632022)
		(end 317.987172 -219.367608)
		(width 0.15494)
		(layer "In11.Cu")
		(net "SPI_BIC1_CS0_LS23_R2_N")
	)
	(segment
		(start 321.361562 -223.98228)
		(end 321.886834 -223.457262)
		(width 0.15494)
		(layer "In11.Cu")
		(net "SPI_BIC1_CS0_LS23_R2_N")
	)
	(segment
		(start 321.62242 -223.002856)
		(end 321.432428 -223.002856)
		(width 0.15494)
		(layer "In11.Cu")
		(net "SPI_BIC1_CS0_LS23_R2_N")
	)
	(segment
		(start 329.059794 -232.195624)
		(end 326.415908 -229.551738)
		(width 0.15494)
		(layer "In11.Cu")
		(net "SPI_BIC1_CS0_LS23_R2_N")
	)
	(segment
		(start 319.988692 -222.628714)
		(end 319.7987 -222.628714)
		(width 0.15494)
		(layer "In11.Cu")
		(net "SPI_BIC1_CS0_LS23_R2_N")
	)
	(segment
		(start 303.025556 -216.090246)
		(end 302.505872 -215.570562)
		(width 0.15494)
		(layer "In11.Cu")
		(net "SPI_BIC1_CS0_LS23_R2_N")
	)
	(segment
		(start 326.415908 -227.835968)
		(end 325.690738 -227.110798)
		(width 0.15494)
		(layer "In11.Cu")
		(net "SPI_BIC1_CS0_LS23_R2_N")
	)
	(segment
		(start 320.978022 -222.54845)
		(end 320.978022 -222.358458)
		(width 0.15494)
		(layer "In11.Cu")
		(net "SPI_BIC1_CS0_LS23_R2_N")
	)
	(segment
		(start 321.432428 -223.002856)
		(end 320.897504 -223.537526)
		(width 0.15494)
		(layer "In11.Cu")
		(net "SPI_BIC1_CS0_LS23_R2_N")
	)
	(segment
		(start 358.591358 -233.588306)
		(end 354.999798 -233.588306)
		(width 0.15494)
		(layer "In11.Cu")
		(net "SPI_BIC1_CS0_LS23_R2_N")
	)
	(segment
		(start 326.415908 -229.551738)
		(end 326.415908 -227.835968)
		(width 0.15494)
		(layer "In11.Cu")
		(net "SPI_BIC1_CS0_LS23_R2_N")
	)
	(segment
		(start 317.072264 -219.902278)
		(end 316.80785 -219.637864)
		(width 0.15494)
		(layer "In11.Cu")
		(net "SPI_BIC1_CS0_LS23_R2_N")
	)
	(segment
		(start 319.804796 -221.185232)
		(end 319.614804 -221.185232)
		(width 0.15494)
		(layer "In11.Cu")
		(net "SPI_BIC1_CS0_LS23_R2_N")
	)
	(segment
		(start 293.657782 -343.685622)
		(end 293.337742 -343.365582)
		(width 0.13462)
		(layer "F.Cu")
		(net "P5E_PEX2_STN4_TX_DN<68>")
	)
	(segment
		(start 293.337742 -343.365582)
		(end 293.337742 -342.734138)
		(width 0.13462)
		(layer "F.Cu")
		(net "P5E_PEX2_STN4_TX_DN<68>")
	)
	(segment
		(start 293.337742 -342.734138)
		(end 293.632382 -342.439498)
		(width 0.13462)
		(layer "F.Cu")
		(net "P5E_PEX2_STN4_TX_DN<68>")
	)
	(segment
		(start 293.632382 -342.439498)
		(end 293.341552 -342.148668)
		(width 0.1651)
		(layer "In11.Cu")
		(net "P5E_PEX2_STN4_TX_DN<68>")
	)
	(segment
		(start 326.716644 -325.335646)
		(end 328.25944 -322.27647)
		(width 0.1651)
		(layer "In11.Cu")
		(net "P5E_PEX2_STN4_TX_DN<68>")
	)
	(segment
		(start 293.341552 -341.488268)
		(end 293.590218 -341.239602)
		(width 0.1651)
		(layer "In11.Cu")
		(net "P5E_PEX2_STN4_TX_DN<68>")
	)
	(segment
		(start 307.74513 -308.629558)
		(end 307.63083 -308.515258)
		(width 0.1143)
		(layer "In11.Cu")
		(net "P5E_PEX2_STN4_TX_DN<68>")
	)
	(segment
		(start 316.878716 -308.885336)
		(end 316.151006 -308.583838)
		(width 0.1651)
		(layer "In11.Cu")
		(net "P5E_PEX2_STN4_TX_DN<68>")
	)
	(segment
		(start 327.235566 -317.426086)
		(end 325.461884 -315.652404)
		(width 0.1651)
		(layer "In11.Cu")
		(net "P5E_PEX2_STN4_TX_DN<68>")
	)
	(segment
		(start 328.25944 -319.898014)
		(end 327.235566 -317.426086)
		(width 0.1651)
		(layer "In11.Cu")
		(net "P5E_PEX2_STN4_TX_DN<68>")
	)
	(segment
		(start 325.344028 -326.763634)
		(end 326.716644 -325.335646)
		(width 0.1651)
		(layer "In11.Cu")
		(net "P5E_PEX2_STN4_TX_DN<68>")
	)
	(segment
		(start 307.63083 -308.35346)
		(end 307.734462 -308.249828)
		(width 0.1143)
		(layer "In11.Cu")
		(net "P5E_PEX2_STN4_TX_DN<68>")
	)
	(segment
		(start 293.590218 -341.239602)
		(end 295.718992 -339.783928)
		(width 0.1651)
		(layer "In11.Cu")
		(net "P5E_PEX2_STN4_TX_DN<68>")
	)
	(segment
		(start 293.341552 -342.148668)
		(end 293.341552 -341.488268)
		(width 0.1651)
		(layer "In11.Cu")
		(net "P5E_PEX2_STN4_TX_DN<68>")
	)
	(segment
		(start 295.718992 -339.783928)
		(end 325.344028 -326.763634)
		(width 0.1651)
		(layer "In11.Cu")
		(net "P5E_PEX2_STN4_TX_DN<68>")
	)
	(segment
		(start 315.82868 -308.629558)
		(end 307.74513 -308.629558)
		(width 0.1143)
		(layer "In11.Cu")
		(net "P5E_PEX2_STN4_TX_DN<68>")
	)
	(segment
		(start 315.902848 -308.583838)
		(end 315.8744 -308.583838)
		(width 0.1143)
		(layer "In11.Cu")
		(net "P5E_PEX2_STN4_TX_DN<68>")
	)
	(segment
		(start 316.151006 -308.583838)
		(end 315.902848 -308.583838)
		(width 0.1651)
		(layer "In11.Cu")
		(net "P5E_PEX2_STN4_TX_DN<68>")
	)
	(segment
		(start 307.734462 -308.249828)
		(end 307.999892 -308.249828)
		(width 0.1143)
		(layer "In11.Cu")
		(net "P5E_PEX2_STN4_TX_DN<68>")
	)
	(segment
		(start 322.36156 -314.36818)
		(end 316.878716 -308.885336)
		(width 0.1651)
		(layer "In11.Cu")
		(net "P5E_PEX2_STN4_TX_DN<68>")
	)
	(segment
		(start 328.25944 -322.27647)
		(end 328.25944 -319.898014)
		(width 0.1651)
		(layer "In11.Cu")
		(net "P5E_PEX2_STN4_TX_DN<68>")
	)
	(segment
		(start 307.63083 -308.515258)
		(end 307.63083 -308.35346)
		(width 0.1143)
		(layer "In11.Cu")
		(net "P5E_PEX2_STN4_TX_DN<68>")
	)
	(segment
		(start 315.8744 -308.583838)
		(end 315.82868 -308.629558)
		(width 0.1143)
		(layer "In11.Cu")
		(net "P5E_PEX2_STN4_TX_DN<68>")
	)
	(segment
		(start 325.461884 -315.652404)
		(end 322.36156 -314.36818)
		(width 0.1651)
		(layer "In11.Cu")
		(net "P5E_PEX2_STN4_TX_DN<68>")
	)
	(segment
		(start 302.314102 -217.631264)
		(end 300.768004 -218.271598)
		(width 0.13208)
		(layer "F.Cu")
		(net "SPI_BIC1_MISO_LS23_R2")
	)
	(segment
		(start 296.46245 -218.271598)
		(end 294.62222 -217.509344)
		(width 0.13208)
		(layer "F.Cu")
		(net "SPI_BIC1_MISO_LS23_R2")
	)
	(segment
		(start 294.073834 -214.358474)
		(end 294.50919 -213.923118)
		(width 0.13208)
		(layer "F.Cu")
		(net "SPI_BIC1_MISO_LS23_R2")
	)
	(segment
		(start 294.073834 -216.960958)
		(end 294.073834 -214.358474)
		(width 0.13208)
		(layer "F.Cu")
		(net "SPI_BIC1_MISO_LS23_R2")
	)
	(segment
		(start 300.768004 -218.271598)
		(end 296.46245 -218.271598)
		(width 0.13208)
		(layer "F.Cu")
		(net "SPI_BIC1_MISO_LS23_R2")
	)
	(segment
		(start 294.62222 -217.509344)
		(end 294.073834 -216.960958)
		(width 0.13208)
		(layer "F.Cu")
		(net "SPI_BIC1_MISO_LS23_R2")
	)
	(via
		(at 302.314102 -217.631264)
		(size 0.508)
		(drill 0.254)
		(layers "F.Cu" "B.Cu")
		(net "SPI_BIC1_MISO_LS23_R2")
	)
	(via
		(at 367.123218 -226.539552)
		(size 0.508)
		(drill 0.254)
		(layers "F.Cu" "B.Cu")
		(net "SPI_BIC1_MISO_LS23_R2")
	)
	(segment
		(start 367.700814 -224.341182)
		(end 367.700814 -225.961956)
		(width 0.13208)
		(layer "B.Cu")
		(net "SPI_BIC1_MISO_LS23_R2")
	)
	(segment
		(start 367.700814 -225.961956)
		(end 367.123218 -226.539552)
		(width 0.13208)
		(layer "B.Cu")
		(net "SPI_BIC1_MISO_LS23_R2")
	)
	(segment
		(start 334.204564 -237.028228)
		(end 335.322164 -238.145828)
		(width 0.15494)
		(layer "In11.Cu")
		(net "SPI_BIC1_MISO_LS23_R2")
	)
	(segment
		(start 367.953798 -227.370132)
		(end 367.123218 -226.539552)
		(width 0.15494)
		(layer "In11.Cu")
		(net "SPI_BIC1_MISO_LS23_R2")
	)
	(segment
		(start 312.730388 -221.945962)
		(end 322.081652 -231.297226)
		(width 0.15494)
		(layer "In11.Cu")
		(net "SPI_BIC1_MISO_LS23_R2")
	)
	(segment
		(start 342.532208 -237.122462)
		(end 353.634802 -237.122462)
		(width 0.15494)
		(layer "In11.Cu")
		(net "SPI_BIC1_MISO_LS23_R2")
	)
	(segment
		(start 322.081652 -231.297226)
		(end 322.081652 -236.106208)
		(width 0.15494)
		(layer "In11.Cu")
		(net "SPI_BIC1_MISO_LS23_R2")
	)
	(segment
		(start 353.634802 -237.122462)
		(end 366.366298 -231.84866)
		(width 0.15494)
		(layer "In11.Cu")
		(net "SPI_BIC1_MISO_LS23_R2")
	)
	(segment
		(start 369.484148 -227.71989)
		(end 369.13439 -227.370132)
		(width 0.15494)
		(layer "In11.Cu")
		(net "SPI_BIC1_MISO_LS23_R2")
	)
	(segment
		(start 369.13439 -227.370132)
		(end 367.953798 -227.370132)
		(width 0.15494)
		(layer "In11.Cu")
		(net "SPI_BIC1_MISO_LS23_R2")
	)
	(segment
		(start 335.322164 -238.145828)
		(end 341.508842 -238.145828)
		(width 0.15494)
		(layer "In11.Cu")
		(net "SPI_BIC1_MISO_LS23_R2")
	)
	(segment
		(start 369.484148 -228.73081)
		(end 369.484148 -227.71989)
		(width 0.15494)
		(layer "In11.Cu")
		(net "SPI_BIC1_MISO_LS23_R2")
	)
	(segment
		(start 323.003672 -237.028228)
		(end 334.204564 -237.028228)
		(width 0.15494)
		(layer "In11.Cu")
		(net "SPI_BIC1_MISO_LS23_R2")
	)
	(segment
		(start 341.508842 -238.145828)
		(end 342.532208 -237.122462)
		(width 0.15494)
		(layer "In11.Cu")
		(net "SPI_BIC1_MISO_LS23_R2")
	)
	(segment
		(start 366.366298 -231.84866)
		(end 369.484148 -228.73081)
		(width 0.15494)
		(layer "In11.Cu")
		(net "SPI_BIC1_MISO_LS23_R2")
	)
	(segment
		(start 302.314102 -217.631264)
		(end 312.730388 -221.945962)
		(width 0.15494)
		(layer "In11.Cu")
		(net "SPI_BIC1_MISO_LS23_R2")
	)
	(segment
		(start 322.081652 -236.106208)
		(end 323.003672 -237.028228)
		(width 0.15494)
		(layer "In11.Cu")
		(net "SPI_BIC1_MISO_LS23_R2")
	)
	(segment
		(start 294.721026 -215.743282)
		(end 296.54119 -213.923118)
		(width 0.13208)
		(layer "F.Cu")
		(net "SPI_BIC1_MOSI_LS23_R2")
	)
	(segment
		(start 296.4307 -217.564462)
		(end 295.113964 -217.019124)
		(width 0.13208)
		(layer "F.Cu")
		(net "SPI_BIC1_MOSI_LS23_R2")
	)
	(segment
		(start 295.113964 -217.019124)
		(end 294.721026 -216.626186)
		(width 0.13208)
		(layer "F.Cu")
		(net "SPI_BIC1_MOSI_LS23_R2")
	)
	(segment
		(start 294.721026 -216.626186)
		(end 294.721026 -215.743282)
		(width 0.13208)
		(layer "F.Cu")
		(net "SPI_BIC1_MOSI_LS23_R2")
	)
	(segment
		(start 300.485048 -217.564462)
		(end 296.4307 -217.564462)
		(width 0.13208)
		(layer "F.Cu")
		(net "SPI_BIC1_MOSI_LS23_R2")
	)
	(via
		(at 370.133372 -225.746056)
		(size 0.508)
		(drill 0.254)
		(layers "F.Cu" "B.Cu")
		(net "SPI_BIC1_MOSI_LS23_R2")
	)
	(via
		(at 300.485048 -217.564462)
		(size 0.508)
		(drill 0.254)
		(layers "F.Cu" "B.Cu")
		(net "SPI_BIC1_MOSI_LS23_R2")
	)
	(segment
		(start 369.605814 -224.341182)
		(end 369.605814 -225.218498)
		(width 0.13208)
		(layer "B.Cu")
		(net "SPI_BIC1_MOSI_LS23_R2")
	)
	(segment
		(start 369.605814 -225.218498)
		(end 370.133372 -225.746056)
		(width 0.13208)
		(layer "B.Cu")
		(net "SPI_BIC1_MOSI_LS23_R2")
	)
	(segment
		(start 338.920074 -240.377472)
		(end 339.788754 -240.377472)
		(width 0.15494)
		(layer "In11.Cu")
		(net "SPI_BIC1_MOSI_LS23_R2")
	)
	(segment
		(start 341.5538 -240.420398)
		(end 348.456758 -240.420398)
		(width 0.15494)
		(layer "In11.Cu")
		(net "SPI_BIC1_MOSI_LS23_R2")
	)
	(segment
		(start 310.15305 -223.63938)
		(end 316.60338 -230.088948)
		(width 0.15494)
		(layer "In11.Cu")
		(net "SPI_BIC1_MOSI_LS23_R2")
	)
	(segment
		(start 316.60338 -230.088948)
		(end 317.62954 -232.56621)
		(width 0.15494)
		(layer "In11.Cu")
		(net "SPI_BIC1_MOSI_LS23_R2")
	)
	(segment
		(start 348.456758 -240.420398)
		(end 353.006914 -237.98784)
		(width 0.15494)
		(layer "In11.Cu")
		(net "SPI_BIC1_MOSI_LS23_R2")
	)
	(segment
		(start 370.079016 -229.004114)
		(end 370.079016 -226.69246)
		(width 0.15494)
		(layer "In11.Cu")
		(net "SPI_BIC1_MOSI_LS23_R2")
	)
	(segment
		(start 370.079016 -226.69246)
		(end 370.133372 -226.638104)
		(width 0.15494)
		(layer "In11.Cu")
		(net "SPI_BIC1_MOSI_LS23_R2")
	)
	(segment
		(start 317.62954 -232.56621)
		(end 324.681596 -239.618266)
		(width 0.15494)
		(layer "In11.Cu")
		(net "SPI_BIC1_MOSI_LS23_R2")
	)
	(segment
		(start 370.133372 -226.638104)
		(end 370.133372 -225.746056)
		(width 0.15494)
		(layer "In11.Cu")
		(net "SPI_BIC1_MOSI_LS23_R2")
	)
	(segment
		(start 330.892404 -240.853468)
		(end 338.444078 -240.853468)
		(width 0.15494)
		(layer "In11.Cu")
		(net "SPI_BIC1_MOSI_LS23_R2")
	)
	(segment
		(start 366.814354 -232.268776)
		(end 370.079016 -229.004114)
		(width 0.15494)
		(layer "In11.Cu")
		(net "SPI_BIC1_MOSI_LS23_R2")
	)
	(segment
		(start 353.006914 -237.98784)
		(end 366.814354 -232.268776)
		(width 0.15494)
		(layer "In11.Cu")
		(net "SPI_BIC1_MOSI_LS23_R2")
	)
	(segment
		(start 341.059262 -239.92586)
		(end 341.5538 -240.420398)
		(width 0.15494)
		(layer "In11.Cu")
		(net "SPI_BIC1_MOSI_LS23_R2")
	)
	(segment
		(start 340.240366 -239.92586)
		(end 341.059262 -239.92586)
		(width 0.15494)
		(layer "In11.Cu")
		(net "SPI_BIC1_MOSI_LS23_R2")
	)
	(segment
		(start 324.681596 -239.618266)
		(end 330.892404 -240.853468)
		(width 0.15494)
		(layer "In11.Cu")
		(net "SPI_BIC1_MOSI_LS23_R2")
	)
	(segment
		(start 300.485048 -217.564462)
		(end 301.751746 -218.604084)
		(width 0.15494)
		(layer "In11.Cu")
		(net "SPI_BIC1_MOSI_LS23_R2")
	)
	(segment
		(start 301.751746 -218.604084)
		(end 310.15305 -223.63938)
		(width 0.15494)
		(layer "In11.Cu")
		(net "SPI_BIC1_MOSI_LS23_R2")
	)
	(segment
		(start 339.788754 -240.377472)
		(end 340.240366 -239.92586)
		(width 0.15494)
		(layer "In11.Cu")
		(net "SPI_BIC1_MOSI_LS23_R2")
	)
	(segment
		(start 338.444078 -240.853468)
		(end 338.920074 -240.377472)
		(width 0.15494)
		(layer "In11.Cu")
		(net "SPI_BIC1_MOSI_LS23_R2")
	)
	(segment
		(start 277.792942 -348.88043)
		(end 278.087582 -348.58579)
		(width 0.13462)
		(layer "F.Cu")
		(net "P5E_PEX2_STN4_TX_DN<75>")
	)
	(segment
		(start 278.112982 -349.831914)
		(end 277.792942 -349.511874)
		(width 0.13462)
		(layer "F.Cu")
		(net "P5E_PEX2_STN4_TX_DN<75>")
	)
	(segment
		(start 277.792942 -349.511874)
		(end 277.792942 -348.88043)
		(width 0.13462)
		(layer "F.Cu")
		(net "P5E_PEX2_STN4_TX_DN<75>")
	)
	(segment
		(start 307.370734 -324.604126)
		(end 309.494428 -322.480432)
		(width 0.1651)
		(layer "In11.Cu")
		(net "P5E_PEX2_STN4_TX_DN<75>")
	)
	(segment
		(start 280.97988 -339.6742)
		(end 281.71775 -339.253068)
		(width 0.1651)
		(layer "In11.Cu")
		(net "P5E_PEX2_STN4_TX_DN<75>")
	)
	(segment
		(start 282.932632 -338.690966)
		(end 283.362908 -338.445094)
		(width 0.1651)
		(layer "In11.Cu")
		(net "P5E_PEX2_STN4_TX_DN<75>")
	)
	(segment
		(start 309.785512 -311.670192)
		(end 309.899812 -311.784492)
		(width 0.1143)
		(layer "In11.Cu")
		(net "P5E_PEX2_STN4_TX_DN<75>")
	)
	(segment
		(start 279.351232 -341.302848)
		(end 280.97988 -339.6742)
		(width 0.1651)
		(layer "In11.Cu")
		(net "P5E_PEX2_STN4_TX_DN<75>")
	)
	(segment
		(start 277.796752 -348.29496)
		(end 277.796752 -347.784674)
		(width 0.1651)
		(layer "In11.Cu")
		(net "P5E_PEX2_STN4_TX_DN<75>")
	)
	(segment
		(start 309.623714 -311.670192)
		(end 309.785512 -311.670192)
		(width 0.1143)
		(layer "In11.Cu")
		(net "P5E_PEX2_STN4_TX_DN<75>")
	)
	(segment
		(start 309.565802 -320.001138)
		(end 309.520082 -319.955418)
		(width 0.1143)
		(layer "In11.Cu")
		(net "P5E_PEX2_STN4_TX_DN<75>")
	)
	(segment
		(start 309.520082 -311.773824)
		(end 309.623714 -311.670192)
		(width 0.1143)
		(layer "In11.Cu")
		(net "P5E_PEX2_STN4_TX_DN<75>")
	)
	(segment
		(start 283.835602 -338.043774)
		(end 283.991558 -338.086192)
		(width 0.1651)
		(layer "In11.Cu")
		(net "P5E_PEX2_STN4_TX_DN<75>")
	)
	(segment
		(start 281.71775 -339.253068)
		(end 281.873706 -339.295486)
		(width 0.1651)
		(layer "In11.Cu")
		(net "P5E_PEX2_STN4_TX_DN<75>")
	)
	(segment
		(start 279.351232 -346.230194)
		(end 279.351232 -341.302848)
		(width 0.1651)
		(layer "In11.Cu")
		(net "P5E_PEX2_STN4_TX_DN<75>")
	)
	(segment
		(start 309.494428 -322.480432)
		(end 309.565802 -322.30822)
		(width 0.1651)
		(layer "In11.Cu")
		(net "P5E_PEX2_STN4_TX_DN<75>")
	)
	(segment
		(start 282.346654 -338.893912)
		(end 282.776676 -338.648548)
		(width 0.1651)
		(layer "In11.Cu")
		(net "P5E_PEX2_STN4_TX_DN<75>")
	)
	(segment
		(start 309.565802 -320.023236)
		(end 309.565802 -320.001138)
		(width 0.1143)
		(layer "In11.Cu")
		(net "P5E_PEX2_STN4_TX_DN<75>")
	)
	(segment
		(start 309.565802 -322.30822)
		(end 309.565802 -320.023236)
		(width 0.1651)
		(layer "In11.Cu")
		(net "P5E_PEX2_STN4_TX_DN<75>")
	)
	(segment
		(start 283.991558 -338.086192)
		(end 284.421834 -337.84032)
		(width 0.1651)
		(layer "In11.Cu")
		(net "P5E_PEX2_STN4_TX_DN<75>")
	)
	(segment
		(start 309.899812 -311.784492)
		(end 309.899812 -312.049922)
		(width 0.1143)
		(layer "In11.Cu")
		(net "P5E_PEX2_STN4_TX_DN<75>")
	)
	(segment
		(start 282.776676 -338.648548)
		(end 282.932632 -338.690966)
		(width 0.1651)
		(layer "In11.Cu")
		(net "P5E_PEX2_STN4_TX_DN<75>")
	)
	(segment
		(start 278.087582 -348.58579)
		(end 277.796752 -348.29496)
		(width 0.1651)
		(layer "In11.Cu")
		(net "P5E_PEX2_STN4_TX_DN<75>")
	)
	(segment
		(start 277.796752 -347.784674)
		(end 279.351232 -346.230194)
		(width 0.1651)
		(layer "In11.Cu")
		(net "P5E_PEX2_STN4_TX_DN<75>")
	)
	(segment
		(start 283.362908 -338.445094)
		(end 283.40558 -338.289138)
		(width 0.1651)
		(layer "In11.Cu")
		(net "P5E_PEX2_STN4_TX_DN<75>")
	)
	(segment
		(start 282.346654 -338.893658)
		(end 282.346654 -338.893912)
		(width 0.1651)
		(layer "In11.Cu")
		(net "P5E_PEX2_STN4_TX_DN<75>")
	)
	(segment
		(start 282.303982 -339.049614)
		(end 282.346654 -338.893658)
		(width 0.1651)
		(layer "In11.Cu")
		(net "P5E_PEX2_STN4_TX_DN<75>")
	)
	(segment
		(start 283.40558 -338.289138)
		(end 283.835602 -338.043774)
		(width 0.1651)
		(layer "In11.Cu")
		(net "P5E_PEX2_STN4_TX_DN<75>")
	)
	(segment
		(start 284.421834 -337.84032)
		(end 284.464506 -337.684364)
		(width 0.1651)
		(layer "In11.Cu")
		(net "P5E_PEX2_STN4_TX_DN<75>")
	)
	(segment
		(start 309.520082 -319.955418)
		(end 309.520082 -311.773824)
		(width 0.1143)
		(layer "In11.Cu")
		(net "P5E_PEX2_STN4_TX_DN<75>")
	)
	(segment
		(start 284.464506 -337.684364)
		(end 307.370734 -324.604126)
		(width 0.1651)
		(layer "In11.Cu")
		(net "P5E_PEX2_STN4_TX_DN<75>")
	)
	(segment
		(start 281.873706 -339.295486)
		(end 282.303982 -339.049614)
		(width 0.1651)
		(layer "In11.Cu")
		(net "P5E_PEX2_STN4_TX_DN<75>")
	)
	(segment
		(start 289.634422 -349.831914)
		(end 289.954462 -349.511874)
		(width 0.13462)
		(layer "F.Cu")
		(net "P5E_PEX2_STN4_TX_DP<69>")
	)
	(segment
		(start 289.954462 -349.511874)
		(end 289.954462 -348.88043)
		(width 0.13462)
		(layer "F.Cu")
		(net "P5E_PEX2_STN4_TX_DP<69>")
	)
	(segment
		(start 289.954462 -348.88043)
		(end 289.659822 -348.58579)
		(width 0.13462)
		(layer "F.Cu")
		(net "P5E_PEX2_STN4_TX_DP<69>")
	)
	(segment
		(start 297.22064 -337.680808)
		(end 297.673776 -337.481418)
		(width 0.1651)
		(layer "In11.Cu")
		(net "P5E_PEX2_STN4_TX_DP<69>")
	)
	(segment
		(start 289.659822 -348.58579)
		(end 289.950652 -348.29496)
		(width 0.1651)
		(layer "In11.Cu")
		(net "P5E_PEX2_STN4_TX_DP<69>")
	)
	(segment
		(start 291.505132 -341.071708)
		(end 292.329362 -340.247478)
		(width 0.1651)
		(layer "In11.Cu")
		(net "P5E_PEX2_STN4_TX_DP<69>")
	)
	(segment
		(start 326.177148 -318.158368)
		(end 324.749414 -316.730634)
		(width 0.1651)
		(layer "In11.Cu")
		(net "P5E_PEX2_STN4_TX_DP<69>")
	)
	(segment
		(start 327.01484 -320.18097)
		(end 327.014586 -320.180716)
		(width 0.1651)
		(layer "In11.Cu")
		(net "P5E_PEX2_STN4_TX_DP<69>")
	)
	(segment
		(start 315.80328 -309.770018)
		(end 309.555388 -309.770018)
		(width 0.1143)
		(layer "In11.Cu")
		(net "P5E_PEX2_STN4_TX_DP<69>")
	)
	(segment
		(start 325.69658 -324.5231)
		(end 327.01484 -321.98564)
		(width 0.1651)
		(layer "In11.Cu")
		(net "P5E_PEX2_STN4_TX_DP<69>")
	)
	(segment
		(start 289.950652 -348.29496)
		(end 289.950652 -347.667834)
		(width 0.1651)
		(layer "In11.Cu")
		(net "P5E_PEX2_STN4_TX_DP<69>")
	)
	(segment
		(start 297.723306 -337.354418)
		(end 298.20997 -337.140296)
		(width 0.1651)
		(layer "In11.Cu")
		(net "P5E_PEX2_STN4_TX_DP<69>")
	)
	(segment
		(start 327.014586 -320.180716)
		(end 326.177148 -318.158368)
		(width 0.1651)
		(layer "In11.Cu")
		(net "P5E_PEX2_STN4_TX_DP<69>")
	)
	(segment
		(start 309.215282 -309.199788)
		(end 308.949852 -309.199788)
		(width 0.1143)
		(layer "In11.Cu")
		(net "P5E_PEX2_STN4_TX_DP<69>")
	)
	(segment
		(start 309.555388 -309.770018)
		(end 309.329582 -309.544212)
		(width 0.1143)
		(layer "In11.Cu")
		(net "P5E_PEX2_STN4_TX_DP<69>")
	)
	(segment
		(start 315.877448 -309.815738)
		(end 315.849 -309.815738)
		(width 0.1143)
		(layer "In11.Cu")
		(net "P5E_PEX2_STN4_TX_DP<69>")
	)
	(segment
		(start 315.849 -309.815738)
		(end 315.80328 -309.770018)
		(width 0.1143)
		(layer "In11.Cu")
		(net "P5E_PEX2_STN4_TX_DP<69>")
	)
	(segment
		(start 324.602348 -325.629016)
		(end 325.69658 -324.5231)
		(width 0.1651)
		(layer "In11.Cu")
		(net "P5E_PEX2_STN4_TX_DP<69>")
	)
	(segment
		(start 292.329362 -340.247478)
		(end 295.903142 -338.26069)
		(width 0.1651)
		(layer "In11.Cu")
		(net "P5E_PEX2_STN4_TX_DP<69>")
	)
	(segment
		(start 296.616374 -337.821778)
		(end 297.070018 -337.622134)
		(width 0.1651)
		(layer "In11.Cu")
		(net "P5E_PEX2_STN4_TX_DP<69>")
	)
	(segment
		(start 298.336716 -337.189572)
		(end 324.602348 -325.629016)
		(width 0.1651)
		(layer "In11.Cu")
		(net "P5E_PEX2_STN4_TX_DP<69>")
	)
	(segment
		(start 297.673776 -337.481418)
		(end 297.723306 -337.354418)
		(width 0.1651)
		(layer "In11.Cu")
		(net "P5E_PEX2_STN4_TX_DP<69>")
	)
	(segment
		(start 309.329582 -309.544212)
		(end 309.329582 -309.314088)
		(width 0.1143)
		(layer "In11.Cu")
		(net "P5E_PEX2_STN4_TX_DP<69>")
	)
	(segment
		(start 321.696588 -315.465968)
		(end 316.046358 -309.815738)
		(width 0.1651)
		(layer "In11.Cu")
		(net "P5E_PEX2_STN4_TX_DP<69>")
	)
	(segment
		(start 316.046358 -309.815738)
		(end 315.877448 -309.815738)
		(width 0.1651)
		(layer "In11.Cu")
		(net "P5E_PEX2_STN4_TX_DP<69>")
	)
	(segment
		(start 296.557954 -337.972654)
		(end 296.616374 -337.821778)
		(width 0.1651)
		(layer "In11.Cu")
		(net "P5E_PEX2_STN4_TX_DP<69>")
	)
	(segment
		(start 295.903142 -338.26069)
		(end 296.557954 -337.972654)
		(width 0.1651)
		(layer "In11.Cu")
		(net "P5E_PEX2_STN4_TX_DP<69>")
	)
	(segment
		(start 298.20997 -337.140296)
		(end 298.336716 -337.189572)
		(width 0.1651)
		(layer "In11.Cu")
		(net "P5E_PEX2_STN4_TX_DP<69>")
	)
	(segment
		(start 291.505132 -346.113354)
		(end 291.505132 -341.071708)
		(width 0.1651)
		(layer "In11.Cu")
		(net "P5E_PEX2_STN4_TX_DP<69>")
	)
	(segment
		(start 289.950652 -347.667834)
		(end 291.505132 -346.113354)
		(width 0.1651)
		(layer "In11.Cu")
		(net "P5E_PEX2_STN4_TX_DP<69>")
	)
	(segment
		(start 297.070018 -337.622134)
		(end 297.22064 -337.680808)
		(width 0.1651)
		(layer "In11.Cu")
		(net "P5E_PEX2_STN4_TX_DP<69>")
	)
	(segment
		(start 324.749414 -316.730634)
		(end 321.696588 -315.465968)
		(width 0.1651)
		(layer "In11.Cu")
		(net "P5E_PEX2_STN4_TX_DP<69>")
	)
	(segment
		(start 309.329582 -309.314088)
		(end 309.215282 -309.199788)
		(width 0.1143)
		(layer "In11.Cu")
		(net "P5E_PEX2_STN4_TX_DP<69>")
	)
	(segment
		(start 327.01484 -321.98564)
		(end 327.01484 -320.18097)
		(width 0.1651)
		(layer "In11.Cu")
		(net "P5E_PEX2_STN4_TX_DP<69>")
	)
	(segment
		(start 295.02989 -214.418418)
		(end 295.52519 -213.923118)
		(width 0.13208)
		(layer "F.Cu")
		(net "SPI_BIC1_MOSI_LS23_R1")
	)
	(via
		(at 295.02989 -214.418418)
		(size 0.508)
		(drill 0.254)
		(layers "F.Cu" "B.Cu")
		(net "SPI_BIC1_MOSI_LS23_R1")
	)
	(segment
		(start 260.088634 -219.577666)
		(end 260.088634 -221.925896)
		(width 0.13208)
		(layer "B.Cu")
		(net "SPI_BIC1_MOSI_LS23_R1")
	)
	(segment
		(start 259.461254 -221.925896)
		(end 259.461254 -219.577666)
		(width 0.13208)
		(layer "B.Cu")
		(net "SPI_BIC1_MOSI_LS23_R1")
	)
	(segment
		(start 261.224014 -221.431358)
		(end 260.835394 -221.431358)
		(width 0.13208)
		(layer "B.Cu")
		(net "SPI_BIC1_MOSI_LS23_R1")
	)
	(segment
		(start 259.580634 -222.045276)
		(end 259.461254 -221.925896)
		(width 0.13208)
		(layer "B.Cu")
		(net "SPI_BIC1_MOSI_LS23_R1")
	)
	(segment
		(start 283.604462 -220.27388)
		(end 266.65428 -220.27388)
		(width 0.13208)
		(layer "B.Cu")
		(net "SPI_BIC1_MOSI_LS23_R1")
	)
	(segment
		(start 251.302774 -220.525086)
		(end 251.302774 -221.403164)
		(width 0.13208)
		(layer "B.Cu")
		(net "SPI_BIC1_MOSI_LS23_R1")
	)
	(segment
		(start 261.462774 -219.458286)
		(end 261.343394 -219.577666)
		(width 0.13208)
		(layer "B.Cu")
		(net "SPI_BIC1_MOSI_LS23_R1")
	)
	(segment
		(start 252.418596 -219.409264)
		(end 251.302774 -220.525086)
		(width 0.13208)
		(layer "B.Cu")
		(net "SPI_BIC1_MOSI_LS23_R1")
	)
	(segment
		(start 294.282114 -215.850978)
		(end 283.604462 -220.27388)
		(width 0.13208)
		(layer "B.Cu")
		(net "SPI_BIC1_MOSI_LS23_R1")
	)
	(segment
		(start 261.343394 -219.577666)
		(end 261.343394 -221.311978)
		(width 0.13208)
		(layer "B.Cu")
		(net "SPI_BIC1_MOSI_LS23_R1")
	)
	(segment
		(start 259.292852 -219.409264)
		(end 252.418596 -219.409264)
		(width 0.13208)
		(layer "B.Cu")
		(net "SPI_BIC1_MOSI_LS23_R1")
	)
	(segment
		(start 266.65428 -220.27388)
		(end 266.489688 -220.109288)
		(width 0.13208)
		(layer "B.Cu")
		(net "SPI_BIC1_MOSI_LS23_R1")
	)
	(segment
		(start 264.09523 -219.85351)
		(end 262.13943 -219.85351)
		(width 0.13208)
		(layer "B.Cu")
		(net "SPI_BIC1_MOSI_LS23_R1")
	)
	(segment
		(start 264.351008 -220.109288)
		(end 264.09523 -219.85351)
		(width 0.13208)
		(layer "B.Cu")
		(net "SPI_BIC1_MOSI_LS23_R1")
	)
	(segment
		(start 260.596634 -219.458286)
		(end 260.208014 -219.458286)
		(width 0.13208)
		(layer "B.Cu")
		(net "SPI_BIC1_MOSI_LS23_R1")
	)
	(segment
		(start 260.716014 -219.577666)
		(end 260.596634 -219.458286)
		(width 0.13208)
		(layer "B.Cu")
		(net "SPI_BIC1_MOSI_LS23_R1")
	)
	(segment
		(start 295.02989 -215.103202)
		(end 294.282114 -215.850978)
		(width 0.13208)
		(layer "B.Cu")
		(net "SPI_BIC1_MOSI_LS23_R1")
	)
	(segment
		(start 253.505716 -223.606106)
		(end 253.505716 -224.341182)
		(width 0.13208)
		(layer "B.Cu")
		(net "SPI_BIC1_MOSI_LS23_R1")
	)
	(segment
		(start 260.208014 -219.458286)
		(end 260.088634 -219.577666)
		(width 0.13208)
		(layer "B.Cu")
		(net "SPI_BIC1_MOSI_LS23_R1")
	)
	(segment
		(start 295.02989 -214.418418)
		(end 295.02989 -215.103202)
		(width 0.13208)
		(layer "B.Cu")
		(net "SPI_BIC1_MOSI_LS23_R1")
	)
	(segment
		(start 261.343394 -221.311978)
		(end 261.224014 -221.431358)
		(width 0.13208)
		(layer "B.Cu")
		(net "SPI_BIC1_MOSI_LS23_R1")
	)
	(segment
		(start 260.088634 -221.925896)
		(end 259.969254 -222.045276)
		(width 0.13208)
		(layer "B.Cu")
		(net "SPI_BIC1_MOSI_LS23_R1")
	)
	(segment
		(start 266.489688 -220.109288)
		(end 264.351008 -220.109288)
		(width 0.13208)
		(layer "B.Cu")
		(net "SPI_BIC1_MOSI_LS23_R1")
	)
	(segment
		(start 260.835394 -221.431358)
		(end 260.716014 -221.311978)
		(width 0.13208)
		(layer "B.Cu")
		(net "SPI_BIC1_MOSI_LS23_R1")
	)
	(segment
		(start 259.969254 -222.045276)
		(end 259.580634 -222.045276)
		(width 0.13208)
		(layer "B.Cu")
		(net "SPI_BIC1_MOSI_LS23_R1")
	)
	(segment
		(start 262.13943 -219.85351)
		(end 262.01243 -219.72651)
		(width 0.13208)
		(layer "B.Cu")
		(net "SPI_BIC1_MOSI_LS23_R1")
	)
	(segment
		(start 261.885176 -219.458286)
		(end 261.462774 -219.458286)
		(width 0.13208)
		(layer "B.Cu")
		(net "SPI_BIC1_MOSI_LS23_R1")
	)
	(segment
		(start 259.461254 -219.577666)
		(end 259.292852 -219.409264)
		(width 0.13208)
		(layer "B.Cu")
		(net "SPI_BIC1_MOSI_LS23_R1")
	)
	(segment
		(start 262.01243 -219.58554)
		(end 261.885176 -219.458286)
		(width 0.13208)
		(layer "B.Cu")
		(net "SPI_BIC1_MOSI_LS23_R1")
	)
	(segment
		(start 262.01243 -219.72651)
		(end 262.01243 -219.58554)
		(width 0.13208)
		(layer "B.Cu")
		(net "SPI_BIC1_MOSI_LS23_R1")
	)
	(segment
		(start 260.716014 -221.311978)
		(end 260.716014 -219.577666)
		(width 0.13208)
		(layer "B.Cu")
		(net "SPI_BIC1_MOSI_LS23_R1")
	)
	(segment
		(start 251.302774 -221.403164)
		(end 253.505716 -223.606106)
		(width 0.13208)
		(layer "B.Cu")
		(net "SPI_BIC1_MOSI_LS23_R1")
	)
	(segment
		(start 148.107908 -194.852798)
		(end 165.930834 -194.852798)
		(width 0.13208)
		(layer "F.Cu")
		(net "SPI_BIC1_MOSI_LS01_R2")
	)
	(via
		(at 148.107908 -194.852798)
		(size 0.508)
		(drill 0.254)
		(layers "F.Cu" "B.Cu")
		(net "SPI_BIC1_MOSI_LS01_R2")
	)
	(via
		(at 137.405872 -223.10344)
		(size 0.508)
		(drill 0.254)
		(layers "F.Cu" "B.Cu")
		(net "SPI_BIC1_MOSI_LS01_R2")
	)
	(segment
		(start 137.405872 -224.341182)
		(end 137.405872 -223.10344)
		(width 0.13208)
		(layer "B.Cu")
		(net "SPI_BIC1_MOSI_LS01_R2")
	)
	(segment
		(start 145.5674 -201.878184)
		(end 145.5674 -209.7278)
		(width 0.15494)
		(layer "In9.Cu")
		(net "SPI_BIC1_MOSI_LS01_R2")
	)
	(segment
		(start 144.3228 -213.747858)
		(end 143.7132 -214.357458)
		(width 0.15494)
		(layer "In9.Cu")
		(net "SPI_BIC1_MOSI_LS01_R2")
	)
	(segment
		(start 136.351518 -219.609924)
		(end 136.351518 -219.800424)
		(width 0.15494)
		(layer "In9.Cu")
		(net "SPI_BIC1_MOSI_LS01_R2")
	)
	(segment
		(start 144.3228 -210.9724)
		(end 144.3228 -213.747858)
		(width 0.15494)
		(layer "In9.Cu")
		(net "SPI_BIC1_MOSI_LS01_R2")
	)
	(segment
		(start 136.351518 -219.800424)
		(end 137.763758 -221.212664)
		(width 0.15494)
		(layer "In9.Cu")
		(net "SPI_BIC1_MOSI_LS01_R2")
	)
	(segment
		(start 138.218164 -220.758258)
		(end 136.805924 -219.346018)
		(width 0.15494)
		(layer "In9.Cu")
		(net "SPI_BIC1_MOSI_LS01_R2")
	)
	(segment
		(start 137.763758 -221.403164)
		(end 137.405872 -221.76105)
		(width 0.15494)
		(layer "In9.Cu")
		(net "SPI_BIC1_MOSI_LS01_R2")
	)
	(segment
		(start 137.763758 -221.212664)
		(end 137.763758 -221.403164)
		(width 0.15494)
		(layer "In9.Cu")
		(net "SPI_BIC1_MOSI_LS01_R2")
	)
	(segment
		(start 145.5674 -209.7278)
		(end 144.3228 -210.9724)
		(width 0.15494)
		(layer "In9.Cu")
		(net "SPI_BIC1_MOSI_LS01_R2")
	)
	(segment
		(start 139.492228 -220.214698)
		(end 137.824464 -218.546934)
		(width 0.15494)
		(layer "In9.Cu")
		(net "SPI_BIC1_MOSI_LS01_R2")
	)
	(segment
		(start 137.370058 -219.00134)
		(end 138.67257 -220.303852)
		(width 0.15494)
		(layer "In9.Cu")
		(net "SPI_BIC1_MOSI_LS01_R2")
	)
	(segment
		(start 148.107908 -197.144894)
		(end 146.771106 -198.481696)
		(width 0.15494)
		(layer "In9.Cu")
		(net "SPI_BIC1_MOSI_LS01_R2")
	)
	(segment
		(start 139.906502 -220.214698)
		(end 139.492228 -220.214698)
		(width 0.15494)
		(layer "In9.Cu")
		(net "SPI_BIC1_MOSI_LS01_R2")
	)
	(segment
		(start 146.771106 -200.674478)
		(end 145.5674 -201.878184)
		(width 0.15494)
		(layer "In9.Cu")
		(net "SPI_BIC1_MOSI_LS01_R2")
	)
	(segment
		(start 143.7132 -216.408)
		(end 139.906502 -220.214698)
		(width 0.15494)
		(layer "In9.Cu")
		(net "SPI_BIC1_MOSI_LS01_R2")
	)
	(segment
		(start 143.7132 -214.357458)
		(end 143.7132 -216.408)
		(width 0.15494)
		(layer "In9.Cu")
		(net "SPI_BIC1_MOSI_LS01_R2")
	)
	(segment
		(start 137.633964 -218.546934)
		(end 137.370058 -218.81084)
		(width 0.15494)
		(layer "In9.Cu")
		(net "SPI_BIC1_MOSI_LS01_R2")
	)
	(segment
		(start 138.67257 -220.494352)
		(end 138.408664 -220.758258)
		(width 0.15494)
		(layer "In9.Cu")
		(net "SPI_BIC1_MOSI_LS01_R2")
	)
	(segment
		(start 148.107908 -194.852798)
		(end 148.107908 -197.144894)
		(width 0.15494)
		(layer "In9.Cu")
		(net "SPI_BIC1_MOSI_LS01_R2")
	)
	(segment
		(start 138.408664 -220.758258)
		(end 138.218164 -220.758258)
		(width 0.15494)
		(layer "In9.Cu")
		(net "SPI_BIC1_MOSI_LS01_R2")
	)
	(segment
		(start 146.771106 -198.481696)
		(end 146.771106 -200.674478)
		(width 0.15494)
		(layer "In9.Cu")
		(net "SPI_BIC1_MOSI_LS01_R2")
	)
	(segment
		(start 138.67257 -220.303852)
		(end 138.67257 -220.494352)
		(width 0.15494)
		(layer "In9.Cu")
		(net "SPI_BIC1_MOSI_LS01_R2")
	)
	(segment
		(start 137.824464 -218.546934)
		(end 137.633964 -218.546934)
		(width 0.15494)
		(layer "In9.Cu")
		(net "SPI_BIC1_MOSI_LS01_R2")
	)
	(segment
		(start 137.405872 -221.76105)
		(end 137.405872 -223.10344)
		(width 0.15494)
		(layer "In9.Cu")
		(net "SPI_BIC1_MOSI_LS01_R2")
	)
	(segment
		(start 136.615424 -219.346018)
		(end 136.351518 -219.609924)
		(width 0.15494)
		(layer "In9.Cu")
		(net "SPI_BIC1_MOSI_LS01_R2")
	)
	(segment
		(start 137.370058 -218.81084)
		(end 137.370058 -219.00134)
		(width 0.15494)
		(layer "In9.Cu")
		(net "SPI_BIC1_MOSI_LS01_R2")
	)
	(segment
		(start 136.805924 -219.346018)
		(end 136.615424 -219.346018)
		(width 0.15494)
		(layer "In9.Cu")
		(net "SPI_BIC1_MOSI_LS01_R2")
	)
	(segment
		(start 293.49319 -213.923118)
		(end 293.49319 -214.96655)
		(width 0.13208)
		(layer "F.Cu")
		(net "SPI_BIC1_MISO_LS23_R1")
	)
	(segment
		(start 293.49319 -214.96655)
		(end 292.920166 -215.539574)
		(width 0.13208)
		(layer "F.Cu")
		(net "SPI_BIC1_MISO_LS23_R1")
	)
	(via
		(at 292.920166 -215.539574)
		(size 0.508)
		(drill 0.254)
		(layers "F.Cu" "B.Cu")
		(net "SPI_BIC1_MISO_LS23_R1")
	)
	(segment
		(start 251.705364 -223.351344)
		(end 251.600716 -223.455992)
		(width 0.13208)
		(layer "B.Cu")
		(net "SPI_BIC1_MISO_LS23_R1")
	)
	(segment
		(start 266.3952 -219.39758)
		(end 266.196572 -219.596208)
		(width 0.13208)
		(layer "B.Cu")
		(net "SPI_BIC1_MISO_LS23_R1")
	)
	(segment
		(start 268.27734 -218.907868)
		(end 268.15796 -218.788488)
		(width 0.13208)
		(layer "B.Cu")
		(net "SPI_BIC1_MISO_LS23_R1")
	)
	(segment
		(start 269.5321 -217.822526)
		(end 269.41272 -217.703146)
		(width 0.13208)
		(layer "B.Cu")
		(net "SPI_BIC1_MISO_LS23_R1")
	)
	(segment
		(start 267.02258 -219.574618)
		(end 267.02258 -218.595194)
		(width 0.13208)
		(layer "B.Cu")
		(net "SPI_BIC1_MISO_LS23_R1")
	)
	(segment
		(start 270.78686 -219.574618)
		(end 270.78686 -217.857324)
		(width 0.13208)
		(layer "B.Cu")
		(net "SPI_BIC1_MISO_LS23_R1")
	)
	(segment
		(start 267.64996 -218.907868)
		(end 267.64996 -219.574618)
		(width 0.13208)
		(layer "B.Cu")
		(net "SPI_BIC1_MISO_LS23_R1")
	)
	(segment
		(start 268.90472 -219.574618)
		(end 268.78534 -219.693998)
		(width 0.13208)
		(layer "B.Cu")
		(net "SPI_BIC1_MISO_LS23_R1")
	)
	(segment
		(start 270.66748 -217.737944)
		(end 270.27886 -217.737944)
		(width 0.13208)
		(layer "B.Cu")
		(net "SPI_BIC1_MISO_LS23_R1")
	)
	(segment
		(start 269.0241 -217.703146)
		(end 268.90472 -217.822526)
		(width 0.13208)
		(layer "B.Cu")
		(net "SPI_BIC1_MISO_LS23_R1")
	)
	(segment
		(start 292.920166 -215.539574)
		(end 282.890468 -219.693998)
		(width 0.13208)
		(layer "B.Cu")
		(net "SPI_BIC1_MISO_LS23_R1")
	)
	(segment
		(start 270.90624 -219.693998)
		(end 270.78686 -219.574618)
		(width 0.13208)
		(layer "B.Cu")
		(net "SPI_BIC1_MISO_LS23_R1")
	)
	(segment
		(start 266.51458 -218.475814)
		(end 266.3952 -218.595194)
		(width 0.13208)
		(layer "B.Cu")
		(net "SPI_BIC1_MISO_LS23_R1")
	)
	(segment
		(start 268.15796 -218.788488)
		(end 267.76934 -218.788488)
		(width 0.13208)
		(layer "B.Cu")
		(net "SPI_BIC1_MISO_LS23_R1")
	)
	(segment
		(start 262.997188 -217.581988)
		(end 253.449328 -217.581988)
		(width 0.13208)
		(layer "B.Cu")
		(net "SPI_BIC1_MISO_LS23_R1")
	)
	(segment
		(start 251.600716 -223.455992)
		(end 251.600716 -224.341182)
		(width 0.13208)
		(layer "B.Cu")
		(net "SPI_BIC1_MISO_LS23_R1")
	)
	(segment
		(start 268.27734 -219.574618)
		(end 268.27734 -218.907868)
		(width 0.13208)
		(layer "B.Cu")
		(net "SPI_BIC1_MISO_LS23_R1")
	)
	(segment
		(start 266.196572 -219.596208)
		(end 265.011408 -219.596208)
		(width 0.13208)
		(layer "B.Cu")
		(net "SPI_BIC1_MISO_LS23_R1")
	)
	(segment
		(start 270.78686 -217.857324)
		(end 270.66748 -217.737944)
		(width 0.13208)
		(layer "B.Cu")
		(net "SPI_BIC1_MISO_LS23_R1")
	)
	(segment
		(start 270.15948 -217.857324)
		(end 270.15948 -219.574618)
		(width 0.13208)
		(layer "B.Cu")
		(net "SPI_BIC1_MISO_LS23_R1")
	)
	(segment
		(start 267.14196 -219.693998)
		(end 267.02258 -219.574618)
		(width 0.13208)
		(layer "B.Cu")
		(net "SPI_BIC1_MISO_LS23_R1")
	)
	(segment
		(start 268.78534 -219.693998)
		(end 268.39672 -219.693998)
		(width 0.13208)
		(layer "B.Cu")
		(net "SPI_BIC1_MISO_LS23_R1")
	)
	(segment
		(start 268.39672 -219.693998)
		(end 268.27734 -219.574618)
		(width 0.13208)
		(layer "B.Cu")
		(net "SPI_BIC1_MISO_LS23_R1")
	)
	(segment
		(start 251.705364 -222.783654)
		(end 251.705364 -223.351344)
		(width 0.13208)
		(layer "B.Cu")
		(net "SPI_BIC1_MISO_LS23_R1")
	)
	(segment
		(start 250.677934 -220.353382)
		(end 250.677934 -221.756224)
		(width 0.13208)
		(layer "B.Cu")
		(net "SPI_BIC1_MISO_LS23_R1")
	)
	(segment
		(start 250.677934 -221.756224)
		(end 251.705364 -222.783654)
		(width 0.13208)
		(layer "B.Cu")
		(net "SPI_BIC1_MISO_LS23_R1")
	)
	(segment
		(start 267.02258 -218.595194)
		(end 266.9032 -218.475814)
		(width 0.13208)
		(layer "B.Cu")
		(net "SPI_BIC1_MISO_LS23_R1")
	)
	(segment
		(start 267.53058 -219.693998)
		(end 267.14196 -219.693998)
		(width 0.13208)
		(layer "B.Cu")
		(net "SPI_BIC1_MISO_LS23_R1")
	)
	(segment
		(start 270.0401 -219.693998)
		(end 269.65148 -219.693998)
		(width 0.13208)
		(layer "B.Cu")
		(net "SPI_BIC1_MISO_LS23_R1")
	)
	(segment
		(start 266.9032 -218.475814)
		(end 266.51458 -218.475814)
		(width 0.13208)
		(layer "B.Cu")
		(net "SPI_BIC1_MISO_LS23_R1")
	)
	(segment
		(start 269.41272 -217.703146)
		(end 269.0241 -217.703146)
		(width 0.13208)
		(layer "B.Cu")
		(net "SPI_BIC1_MISO_LS23_R1")
	)
	(segment
		(start 253.449328 -217.581988)
		(end 250.677934 -220.353382)
		(width 0.13208)
		(layer "B.Cu")
		(net "SPI_BIC1_MISO_LS23_R1")
	)
	(segment
		(start 269.5321 -219.574618)
		(end 269.5321 -217.822526)
		(width 0.13208)
		(layer "B.Cu")
		(net "SPI_BIC1_MISO_LS23_R1")
	)
	(segment
		(start 282.890468 -219.693998)
		(end 270.90624 -219.693998)
		(width 0.13208)
		(layer "B.Cu")
		(net "SPI_BIC1_MISO_LS23_R1")
	)
	(segment
		(start 265.011408 -219.596208)
		(end 262.997188 -217.581988)
		(width 0.13208)
		(layer "B.Cu")
		(net "SPI_BIC1_MISO_LS23_R1")
	)
	(segment
		(start 270.15948 -219.574618)
		(end 270.0401 -219.693998)
		(width 0.13208)
		(layer "B.Cu")
		(net "SPI_BIC1_MISO_LS23_R1")
	)
	(segment
		(start 270.27886 -217.737944)
		(end 270.15948 -217.857324)
		(width 0.13208)
		(layer "B.Cu")
		(net "SPI_BIC1_MISO_LS23_R1")
	)
	(segment
		(start 267.76934 -218.788488)
		(end 267.64996 -218.907868)
		(width 0.13208)
		(layer "B.Cu")
		(net "SPI_BIC1_MISO_LS23_R1")
	)
	(segment
		(start 269.65148 -219.693998)
		(end 269.5321 -219.574618)
		(width 0.13208)
		(layer "B.Cu")
		(net "SPI_BIC1_MISO_LS23_R1")
	)
	(segment
		(start 267.64996 -219.574618)
		(end 267.53058 -219.693998)
		(width 0.13208)
		(layer "B.Cu")
		(net "SPI_BIC1_MISO_LS23_R1")
	)
	(segment
		(start 266.3952 -218.595194)
		(end 266.3952 -219.39758)
		(width 0.13208)
		(layer "B.Cu")
		(net "SPI_BIC1_MISO_LS23_R1")
	)
	(segment
		(start 268.90472 -217.822526)
		(end 268.90472 -219.574618)
		(width 0.13208)
		(layer "B.Cu")
		(net "SPI_BIC1_MISO_LS23_R1")
	)
	(segment
		(start 148.821648 -197.73138)
		(end 165.761416 -197.73138)
		(width 0.13208)
		(layer "F.Cu")
		(net "SPI_BIC1_CLK_LS01_R2")
	)
	(segment
		(start 165.761416 -197.73138)
		(end 165.930834 -197.900798)
		(width 0.13208)
		(layer "F.Cu")
		(net "SPI_BIC1_CLK_LS01_R2")
	)
	(via
		(at 136.468866 -228.077522)
		(size 0.508)
		(drill 0.254)
		(layers "F.Cu" "B.Cu")
		(net "SPI_BIC1_CLK_LS01_R2")
	)
	(via
		(at 148.821648 -197.73138)
		(size 0.508)
		(drill 0.254)
		(layers "F.Cu" "B.Cu")
		(net "SPI_BIC1_CLK_LS01_R2")
	)
	(segment
		(start 136.468866 -228.590602)
		(end 136.468866 -228.077522)
		(width 0.13208)
		(layer "B.Cu")
		(net "SPI_BIC1_CLK_LS01_R2")
	)
	(segment
		(start 136.770872 -229.827582)
		(end 136.770872 -228.892608)
		(width 0.13208)
		(layer "B.Cu")
		(net "SPI_BIC1_CLK_LS01_R2")
	)
	(segment
		(start 136.770872 -228.892608)
		(end 136.468866 -228.590602)
		(width 0.13208)
		(layer "B.Cu")
		(net "SPI_BIC1_CLK_LS01_R2")
	)
	(segment
		(start 149.932136 -198.841868)
		(end 148.821648 -197.73138)
		(width 0.15494)
		(layer "In9.Cu")
		(net "SPI_BIC1_CLK_LS01_R2")
	)
	(segment
		(start 136.468866 -228.077522)
		(end 136.666478 -228.077522)
		(width 0.15494)
		(layer "In9.Cu")
		(net "SPI_BIC1_CLK_LS01_R2")
	)
	(segment
		(start 140.748004 -223.130618)
		(end 140.748004 -221.328996)
		(width 0.15494)
		(layer "In9.Cu")
		(net "SPI_BIC1_CLK_LS01_R2")
	)
	(segment
		(start 140.748004 -221.328996)
		(end 144.7038 -217.3732)
		(width 0.15494)
		(layer "In9.Cu")
		(net "SPI_BIC1_CLK_LS01_R2")
	)
	(segment
		(start 146.9898 -215.0872)
		(end 149.661372 -212.415628)
		(width 0.15494)
		(layer "In9.Cu")
		(net "SPI_BIC1_CLK_LS01_R2")
	)
	(segment
		(start 144.7038 -217.3732)
		(end 145.034 -217.3732)
		(width 0.15494)
		(layer "In9.Cu")
		(net "SPI_BIC1_CLK_LS01_R2")
	)
	(segment
		(start 136.666478 -228.077522)
		(end 140.136118 -224.607882)
		(width 0.15494)
		(layer "In9.Cu")
		(net "SPI_BIC1_CLK_LS01_R2")
	)
	(segment
		(start 140.136118 -224.607882)
		(end 140.748004 -223.130618)
		(width 0.15494)
		(layer "In9.Cu")
		(net "SPI_BIC1_CLK_LS01_R2")
	)
	(segment
		(start 150.63978 -200.550018)
		(end 149.932136 -198.841868)
		(width 0.15494)
		(layer "In9.Cu")
		(net "SPI_BIC1_CLK_LS01_R2")
	)
	(segment
		(start 146.9898 -215.4174)
		(end 146.9898 -215.0872)
		(width 0.15494)
		(layer "In9.Cu")
		(net "SPI_BIC1_CLK_LS01_R2")
	)
	(segment
		(start 145.034 -217.3732)
		(end 146.9898 -215.4174)
		(width 0.15494)
		(layer "In9.Cu")
		(net "SPI_BIC1_CLK_LS01_R2")
	)
	(segment
		(start 150.63978 -210.053682)
		(end 150.63978 -200.550018)
		(width 0.15494)
		(layer "In9.Cu")
		(net "SPI_BIC1_CLK_LS01_R2")
	)
	(segment
		(start 149.661372 -212.415628)
		(end 150.63978 -210.053682)
		(width 0.15494)
		(layer "In9.Cu")
		(net "SPI_BIC1_CLK_LS01_R2")
	)
	(segment
		(start 301.121064 -214.438992)
		(end 300.60519 -213.923118)
		(width 0.13208)
		(layer "F.Cu")
		(net "SPI_BIC1_CS0_LS23_R1_N")
	)
	(via
		(at 301.121064 -214.438992)
		(size 0.508)
		(drill 0.254)
		(layers "F.Cu" "B.Cu")
		(net "SPI_BIC1_CS0_LS23_R1_N")
	)
	(segment
		(start 258.247134 -231.688894)
		(end 255.087882 -232.997248)
		(width 0.13208)
		(layer "B.Cu")
		(net "SPI_BIC1_CS0_LS23_R1_N")
	)
	(segment
		(start 258.38404 -231.646984)
		(end 258.315968 -231.675178)
		(width 0.13208)
		(layer "B.Cu")
		(net "SPI_BIC1_CS0_LS23_R1_N")
	)
	(segment
		(start 297.231562 -217.037666)
		(end 265.273536 -230.276654)
		(width 0.13208)
		(layer "B.Cu")
		(net "SPI_BIC1_CS0_LS23_R1_N")
	)
	(segment
		(start 250.965716 -231.243378)
		(end 250.965716 -229.827582)
		(width 0.13208)
		(layer "B.Cu")
		(net "SPI_BIC1_CS0_LS23_R1_N")
	)
	(segment
		(start 252.719586 -232.997248)
		(end 250.965716 -231.243378)
		(width 0.13208)
		(layer "B.Cu")
		(net "SPI_BIC1_CS0_LS23_R1_N")
	)
	(segment
		(start 255.087882 -232.997248)
		(end 252.719586 -232.997248)
		(width 0.13208)
		(layer "B.Cu")
		(net "SPI_BIC1_CS0_LS23_R1_N")
	)
	(segment
		(start 258.315968 -231.675178)
		(end 258.247134 -231.688894)
		(width 0.13208)
		(layer "B.Cu")
		(net "SPI_BIC1_CS0_LS23_R1_N")
	)
	(segment
		(start 301.121064 -214.438992)
		(end 297.231562 -217.037666)
		(width 0.13208)
		(layer "B.Cu")
		(net "SPI_BIC1_CS0_LS23_R1_N")
	)
	(segment
		(start 265.273536 -230.276654)
		(end 258.38404 -231.646984)
		(width 0.13208)
		(layer "B.Cu")
		(net "SPI_BIC1_CS0_LS23_R1_N")
	)
	(segment
		(start 165.930834 -199.932798)
		(end 150.331932 -199.932798)
		(width 0.13208)
		(layer "F.Cu")
		(net "SPI_BIC1_CS0_LS01_R2_N")
	)
	(segment
		(start 150.331932 -199.932798)
		(end 149.519386 -200.745344)
		(width 0.13208)
		(layer "F.Cu")
		(net "SPI_BIC1_CS0_LS01_R2_N")
	)
	(via
		(at 149.519386 -200.745344)
		(size 0.508)
		(drill 0.254)
		(layers "F.Cu" "B.Cu")
		(net "SPI_BIC1_CS0_LS01_R2_N")
	)
	(via
		(at 134.35965 -228.179884)
		(size 0.508)
		(drill 0.254)
		(layers "F.Cu" "B.Cu")
		(net "SPI_BIC1_CS0_LS01_R2_N")
	)
	(segment
		(start 134.35965 -228.179884)
		(end 134.35965 -228.704648)
		(width 0.13208)
		(layer "B.Cu")
		(net "SPI_BIC1_CS0_LS01_R2_N")
	)
	(segment
		(start 134.865872 -229.21087)
		(end 134.865872 -229.827582)
		(width 0.13208)
		(layer "B.Cu")
		(net "SPI_BIC1_CS0_LS01_R2_N")
	)
	(segment
		(start 134.35965 -228.704648)
		(end 134.865872 -229.21087)
		(width 0.13208)
		(layer "B.Cu")
		(net "SPI_BIC1_CS0_LS01_R2_N")
	)
	(segment
		(start 135.810752 -227.088954)
		(end 135.810752 -226.46386)
		(width 0.15494)
		(layer "In9.Cu")
		(net "SPI_BIC1_CS0_LS01_R2_N")
	)
	(segment
		(start 135.960612 -226.314)
		(end 137.316464 -226.314)
		(width 0.15494)
		(layer "In9.Cu")
		(net "SPI_BIC1_CS0_LS01_R2_N")
	)
	(segment
		(start 135.810752 -226.46386)
		(end 135.960612 -226.314)
		(width 0.15494)
		(layer "In9.Cu")
		(net "SPI_BIC1_CS0_LS01_R2_N")
	)
	(segment
		(start 135.168132 -227.088954)
		(end 135.302752 -227.223574)
		(width 0.15494)
		(layer "In9.Cu")
		(net "SPI_BIC1_CS0_LS01_R2_N")
	)
	(segment
		(start 137.316464 -226.314)
		(end 139.695936 -223.934528)
		(width 0.15494)
		(layer "In9.Cu")
		(net "SPI_BIC1_CS0_LS01_R2_N")
	)
	(segment
		(start 134.35965 -226.4664)
		(end 134.48665 -226.3394)
		(width 0.15494)
		(layer "In9.Cu")
		(net "SPI_BIC1_CS0_LS01_R2_N")
	)
	(segment
		(start 147.186904 -212.804502)
		(end 148.926804 -208.60385)
		(width 0.15494)
		(layer "In9.Cu")
		(net "SPI_BIC1_CS0_LS01_R2_N")
	)
	(segment
		(start 139.695936 -223.934528)
		(end 140.07846 -223.011492)
		(width 0.15494)
		(layer "In9.Cu")
		(net "SPI_BIC1_CS0_LS01_R2_N")
	)
	(segment
		(start 134.48665 -226.3394)
		(end 135.041132 -226.3394)
		(width 0.15494)
		(layer "In9.Cu")
		(net "SPI_BIC1_CS0_LS01_R2_N")
	)
	(segment
		(start 135.676132 -227.223574)
		(end 135.810752 -227.088954)
		(width 0.15494)
		(layer "In9.Cu")
		(net "SPI_BIC1_CS0_LS01_R2_N")
	)
	(segment
		(start 147.480782 -204.669898)
		(end 147.480782 -201.591418)
		(width 0.15494)
		(layer "In9.Cu")
		(net "SPI_BIC1_CS0_LS01_R2_N")
	)
	(segment
		(start 134.35965 -228.179884)
		(end 134.35965 -226.4664)
		(width 0.15494)
		(layer "In9.Cu")
		(net "SPI_BIC1_CS0_LS01_R2_N")
	)
	(segment
		(start 144.653 -216.458546)
		(end 145.0086 -216.458546)
		(width 0.15494)
		(layer "In9.Cu")
		(net "SPI_BIC1_CS0_LS01_R2_N")
	)
	(segment
		(start 146.400266 -213.17458)
		(end 146.543522 -212.82914)
		(width 0.15494)
		(layer "In9.Cu")
		(net "SPI_BIC1_CS0_LS01_R2_N")
	)
	(segment
		(start 146.142964 -215.324182)
		(end 146.838162 -213.646766)
		(width 0.15494)
		(layer "In9.Cu")
		(net "SPI_BIC1_CS0_LS01_R2_N")
	)
	(segment
		(start 148.6408 -200.4314)
		(end 149.205442 -200.4314)
		(width 0.15494)
		(layer "In9.Cu")
		(net "SPI_BIC1_CS0_LS01_R2_N")
	)
	(segment
		(start 147.480782 -201.591418)
		(end 148.6408 -200.4314)
		(width 0.15494)
		(layer "In9.Cu")
		(net "SPI_BIC1_CS0_LS01_R2_N")
	)
	(segment
		(start 135.302752 -227.223574)
		(end 135.676132 -227.223574)
		(width 0.15494)
		(layer "In9.Cu")
		(net "SPI_BIC1_CS0_LS01_R2_N")
	)
	(segment
		(start 140.07846 -221.033086)
		(end 144.653 -216.458546)
		(width 0.15494)
		(layer "In9.Cu")
		(net "SPI_BIC1_CS0_LS01_R2_N")
	)
	(segment
		(start 146.473164 -213.350094)
		(end 146.400266 -213.17458)
		(width 0.15494)
		(layer "In9.Cu")
		(net "SPI_BIC1_CS0_LS01_R2_N")
	)
	(segment
		(start 145.0086 -216.458546)
		(end 146.142964 -215.324182)
		(width 0.15494)
		(layer "In9.Cu")
		(net "SPI_BIC1_CS0_LS01_R2_N")
	)
	(segment
		(start 148.926804 -208.60385)
		(end 148.926804 -206.11592)
		(width 0.15494)
		(layer "In9.Cu")
		(net "SPI_BIC1_CS0_LS01_R2_N")
	)
	(segment
		(start 149.205442 -200.4314)
		(end 149.519386 -200.745344)
		(width 0.15494)
		(layer "In9.Cu")
		(net "SPI_BIC1_CS0_LS01_R2_N")
	)
	(segment
		(start 146.838162 -213.646766)
		(end 146.765264 -213.471252)
		(width 0.15494)
		(layer "In9.Cu")
		(net "SPI_BIC1_CS0_LS01_R2_N")
	)
	(segment
		(start 135.168132 -226.4664)
		(end 135.168132 -227.088954)
		(width 0.15494)
		(layer "In9.Cu")
		(net "SPI_BIC1_CS0_LS01_R2_N")
	)
	(segment
		(start 146.765264 -213.471252)
		(end 146.473164 -213.350094)
		(width 0.15494)
		(layer "In9.Cu")
		(net "SPI_BIC1_CS0_LS01_R2_N")
	)
	(segment
		(start 148.926804 -206.11592)
		(end 147.480782 -204.669898)
		(width 0.15494)
		(layer "In9.Cu")
		(net "SPI_BIC1_CS0_LS01_R2_N")
	)
	(segment
		(start 135.041132 -226.3394)
		(end 135.168132 -226.4664)
		(width 0.15494)
		(layer "In9.Cu")
		(net "SPI_BIC1_CS0_LS01_R2_N")
	)
	(segment
		(start 146.71929 -212.756242)
		(end 147.01139 -212.8774)
		(width 0.15494)
		(layer "In9.Cu")
		(net "SPI_BIC1_CS0_LS01_R2_N")
	)
	(segment
		(start 146.543522 -212.82914)
		(end 146.71929 -212.756242)
		(width 0.15494)
		(layer "In9.Cu")
		(net "SPI_BIC1_CS0_LS01_R2_N")
	)
	(segment
		(start 140.07846 -223.011492)
		(end 140.07846 -221.033086)
		(width 0.15494)
		(layer "In9.Cu")
		(net "SPI_BIC1_CS0_LS01_R2_N")
	)
	(segment
		(start 147.01139 -212.8774)
		(end 147.186904 -212.804502)
		(width 0.15494)
		(layer "In9.Cu")
		(net "SPI_BIC1_CS0_LS01_R2_N")
	)
	(segment
		(start 280.627582 -343.365582)
		(end 280.627582 -342.734138)
		(width 0.13462)
		(layer "F.Cu")
		(net "P5E_PEX2_STN4_TX_DP<74>")
	)
	(segment
		(start 280.307542 -343.685622)
		(end 280.627582 -343.365582)
		(width 0.13462)
		(layer "F.Cu")
		(net "P5E_PEX2_STN4_TX_DP<74>")
	)
	(segment
		(start 280.627582 -342.734138)
		(end 280.332942 -342.439498)
		(width 0.13462)
		(layer "F.Cu")
		(net "P5E_PEX2_STN4_TX_DP<74>")
	)
	(segment
		(start 280.623772 -342.148668)
		(end 280.623772 -341.401908)
		(width 0.1651)
		(layer "In11.Cu")
		(net "P5E_PEX2_STN4_TX_DP<74>")
	)
	(segment
		(start 285.315914 -338.110322)
		(end 285.315914 -338.110576)
		(width 0.1651)
		(layer "In11.Cu")
		(net "P5E_PEX2_STN4_TX_DP<74>")
	)
	(segment
		(start 285.315914 -338.110576)
		(end 307.8226 -325.16318)
		(width 0.1651)
		(layer "In11.Cu")
		(net "P5E_PEX2_STN4_TX_DP<74>")
	)
	(segment
		(start 280.332942 -342.439498)
		(end 280.623772 -342.148668)
		(width 0.1651)
		(layer "In11.Cu")
		(net "P5E_PEX2_STN4_TX_DP<74>")
	)
	(segment
		(start 310.279542 -313.59475)
		(end 310.49468 -313.379612)
		(width 0.1143)
		(layer "In11.Cu")
		(net "P5E_PEX2_STN4_TX_DP<74>")
	)
	(segment
		(start 310.233822 -320.043556)
		(end 310.233822 -320.021458)
		(width 0.1143)
		(layer "In11.Cu")
		(net "P5E_PEX2_STN4_TX_DP<74>")
	)
	(segment
		(start 282.018232 -340.007448)
		(end 285.315914 -338.110322)
		(width 0.1651)
		(layer "In11.Cu")
		(net "P5E_PEX2_STN4_TX_DP<74>")
	)
	(segment
		(start 310.849772 -313.265312)
		(end 310.849772 -312.999882)
		(width 0.1143)
		(layer "In11.Cu")
		(net "P5E_PEX2_STN4_TX_DP<74>")
	)
	(segment
		(start 310.233822 -320.021458)
		(end 310.279542 -319.975738)
		(width 0.1143)
		(layer "In11.Cu")
		(net "P5E_PEX2_STN4_TX_DP<74>")
	)
	(segment
		(start 310.135016 -322.850764)
		(end 310.233822 -322.612258)
		(width 0.1651)
		(layer "In11.Cu")
		(net "P5E_PEX2_STN4_TX_DP<74>")
	)
	(segment
		(start 280.623772 -341.401908)
		(end 282.018232 -340.007448)
		(width 0.1651)
		(layer "In11.Cu")
		(net "P5E_PEX2_STN4_TX_DP<74>")
	)
	(segment
		(start 307.8226 -325.16318)
		(end 310.135016 -322.850764)
		(width 0.1651)
		(layer "In11.Cu")
		(net "P5E_PEX2_STN4_TX_DP<74>")
	)
	(segment
		(start 310.735472 -313.379612)
		(end 310.849772 -313.265312)
		(width 0.1143)
		(layer "In11.Cu")
		(net "P5E_PEX2_STN4_TX_DP<74>")
	)
	(segment
		(start 310.233822 -322.612258)
		(end 310.233822 -320.043556)
		(width 0.1651)
		(layer "In11.Cu")
		(net "P5E_PEX2_STN4_TX_DP<74>")
	)
	(segment
		(start 310.279542 -319.975738)
		(end 310.279542 -313.59475)
		(width 0.1143)
		(layer "In11.Cu")
		(net "P5E_PEX2_STN4_TX_DP<74>")
	)
	(segment
		(start 310.49468 -313.379612)
		(end 310.735472 -313.379612)
		(width 0.1143)
		(layer "In11.Cu")
		(net "P5E_PEX2_STN4_TX_DP<74>")
	)
	(segment
		(start 295.549066 -216.096596)
		(end 297.55719 -214.088472)
		(width 0.13208)
		(layer "F.Cu")
		(net "SPI_BIC1_CLK_LS23_R1")
	)
	(segment
		(start 297.55719 -214.088472)
		(end 297.55719 -213.923118)
		(width 0.13208)
		(layer "F.Cu")
		(net "SPI_BIC1_CLK_LS23_R1")
	)
	(via
		(at 295.549066 -216.096596)
		(size 0.508)
		(drill 0.254)
		(layers "F.Cu" "B.Cu")
		(net "SPI_BIC1_CLK_LS23_R1")
	)
	(segment
		(start 259.173726 -224.35566)
		(end 258.083558 -224.35566)
		(width 0.13208)
		(layer "B.Cu")
		(net "SPI_BIC1_CLK_LS23_R1")
	)
	(segment
		(start 264.085832 -220.749368)
		(end 263.830054 -220.49359)
		(width 0.13208)
		(layer "B.Cu")
		(net "SPI_BIC1_CLK_LS23_R1")
	)
	(segment
		(start 260.886194 -222.643192)
		(end 259.173726 -224.35566)
		(width 0.13208)
		(layer "B.Cu")
		(net "SPI_BIC1_CLK_LS23_R1")
	)
	(segment
		(start 256.28473 -226.154488)
		(end 256.28473 -230.305356)
		(width 0.13208)
		(layer "B.Cu")
		(net "SPI_BIC1_CLK_LS23_R1")
	)
	(segment
		(start 263.830054 -220.49359)
		(end 262.28421 -220.49359)
		(width 0.13208)
		(layer "B.Cu")
		(net "SPI_BIC1_CLK_LS23_R1")
	)
	(segment
		(start 256.28473 -230.305356)
		(end 256.279142 -230.310944)
		(width 0.13208)
		(layer "B.Cu")
		(net "SPI_BIC1_CLK_LS23_R1")
	)
	(segment
		(start 256.279142 -230.31958)
		(end 255.749552 -230.84917)
		(width 0.13208)
		(layer "B.Cu")
		(net "SPI_BIC1_CLK_LS23_R1")
	)
	(segment
		(start 255.740916 -230.84917)
		(end 255.017016 -231.57307)
		(width 0.13208)
		(layer "B.Cu")
		(net "SPI_BIC1_CLK_LS23_R1")
	)
	(segment
		(start 252.870716 -231.09555)
		(end 252.870716 -229.827582)
		(width 0.13208)
		(layer "B.Cu")
		(net "SPI_BIC1_CLK_LS23_R1")
	)
	(segment
		(start 266.389104 -220.91396)
		(end 266.224512 -220.749368)
		(width 0.13208)
		(layer "B.Cu")
		(net "SPI_BIC1_CLK_LS23_R1")
	)
	(segment
		(start 256.279142 -230.310944)
		(end 256.279142 -230.31958)
		(width 0.13208)
		(layer "B.Cu")
		(net "SPI_BIC1_CLK_LS23_R1")
	)
	(segment
		(start 262.28421 -220.49359)
		(end 261.990078 -220.787722)
		(width 0.13208)
		(layer "B.Cu")
		(net "SPI_BIC1_CLK_LS23_R1")
	)
	(segment
		(start 258.083558 -224.35566)
		(end 256.28473 -226.154488)
		(width 0.13208)
		(layer "B.Cu")
		(net "SPI_BIC1_CLK_LS23_R1")
	)
	(segment
		(start 266.224512 -220.749368)
		(end 264.085832 -220.749368)
		(width 0.13208)
		(layer "B.Cu")
		(net "SPI_BIC1_CLK_LS23_R1")
	)
	(segment
		(start 253.348236 -231.57307)
		(end 252.870716 -231.09555)
		(width 0.13208)
		(layer "B.Cu")
		(net "SPI_BIC1_CLK_LS23_R1")
	)
	(segment
		(start 261.990078 -221.89186)
		(end 261.238746 -222.643192)
		(width 0.13208)
		(layer "B.Cu")
		(net "SPI_BIC1_CLK_LS23_R1")
	)
	(segment
		(start 283.91866 -220.91396)
		(end 266.389104 -220.91396)
		(width 0.13208)
		(layer "B.Cu")
		(net "SPI_BIC1_CLK_LS23_R1")
	)
	(segment
		(start 261.990078 -220.787722)
		(end 261.990078 -221.89186)
		(width 0.13208)
		(layer "B.Cu")
		(net "SPI_BIC1_CLK_LS23_R1")
	)
	(segment
		(start 255.749552 -230.84917)
		(end 255.740916 -230.84917)
		(width 0.13208)
		(layer "B.Cu")
		(net "SPI_BIC1_CLK_LS23_R1")
	)
	(segment
		(start 261.238746 -222.643192)
		(end 260.886194 -222.643192)
		(width 0.13208)
		(layer "B.Cu")
		(net "SPI_BIC1_CLK_LS23_R1")
	)
	(segment
		(start 295.549066 -216.096596)
		(end 283.91866 -220.91396)
		(width 0.13208)
		(layer "B.Cu")
		(net "SPI_BIC1_CLK_LS23_R1")
	)
	(segment
		(start 255.017016 -231.57307)
		(end 253.348236 -231.57307)
		(width 0.13208)
		(layer "B.Cu")
		(net "SPI_BIC1_CLK_LS23_R1")
	)
	(segment
		(start 146.880834 -193.943224)
		(end 163.212272 -193.943224)
		(width 0.13208)
		(layer "F.Cu")
		(net "SPI_BIC1_MISO_LS01_R2")
	)
	(segment
		(start 163.212272 -193.943224)
		(end 163.318698 -193.836798)
		(width 0.13208)
		(layer "F.Cu")
		(net "SPI_BIC1_MISO_LS01_R2")
	)
	(segment
		(start 163.318698 -193.836798)
		(end 165.930834 -193.836798)
		(width 0.13208)
		(layer "F.Cu")
		(net "SPI_BIC1_MISO_LS01_R2")
	)
	(via
		(at 146.880834 -193.943224)
		(size 0.508)
		(drill 0.254)
		(layers "F.Cu" "B.Cu")
		(net "SPI_BIC1_MISO_LS01_R2")
	)
	(via
		(at 135.500872 -223.147382)
		(size 0.508)
		(drill 0.254)
		(layers "F.Cu" "B.Cu")
		(net "SPI_BIC1_MISO_LS01_R2")
	)
	(segment
		(start 135.500872 -224.341182)
		(end 135.500872 -223.147382)
		(width 0.13208)
		(layer "B.Cu")
		(net "SPI_BIC1_MISO_LS01_R2")
	)
	(segment
		(start 140.741908 -218.490038)
		(end 140.530834 -218.490038)
		(width 0.15494)
		(layer "In9.Cu")
		(net "SPI_BIC1_MISO_LS01_R2")
	)
	(segment
		(start 144.907 -201.676254)
		(end 144.907 -207.645)
		(width 0.15494)
		(layer "In9.Cu")
		(net "SPI_BIC1_MISO_LS01_R2")
	)
	(segment
		(start 143.3322 -210.3374)
		(end 143.714216 -210.719416)
		(width 0.15494)
		(layer "In9.Cu")
		(net "SPI_BIC1_MISO_LS01_R2")
	)
	(segment
		(start 140.530834 -218.490038)
		(end 139.345162 -217.304366)
		(width 0.15494)
		(layer "In9.Cu")
		(net "SPI_BIC1_MISO_LS01_R2")
	)
	(segment
		(start 139.764008 -219.43314)
		(end 139.573508 -219.43314)
		(width 0.15494)
		(layer "In9.Cu")
		(net "SPI_BIC1_MISO_LS01_R2")
	)
	(segment
		(start 143.714216 -213.564216)
		(end 143.14932 -214.129112)
		(width 0.15494)
		(layer "In9.Cu")
		(net "SPI_BIC1_MISO_LS01_R2")
	)
	(segment
		(start 146.223228 -198.533766)
		(end 146.223228 -200.360026)
		(width 0.15494)
		(layer "In9.Cu")
		(net "SPI_BIC1_MISO_LS01_R2")
	)
	(segment
		(start 145.171668 -195.65239)
		(end 145.171668 -197.482206)
		(width 0.15494)
		(layer "In9.Cu")
		(net "SPI_BIC1_MISO_LS01_R2")
	)
	(segment
		(start 139.345162 -217.304366)
		(end 139.113514 -217.304366)
		(width 0.15494)
		(layer "In9.Cu")
		(net "SPI_BIC1_MISO_LS01_R2")
	)
	(segment
		(start 143.14932 -216.082626)
		(end 140.741908 -218.490038)
		(width 0.15494)
		(layer "In9.Cu")
		(net "SPI_BIC1_MISO_LS01_R2")
	)
	(segment
		(start 139.573508 -219.43314)
		(end 137.774426 -217.634058)
		(width 0.15494)
		(layer "In9.Cu")
		(net "SPI_BIC1_MISO_LS01_R2")
	)
	(segment
		(start 146.223228 -200.360026)
		(end 144.907 -201.676254)
		(width 0.15494)
		(layer "In9.Cu")
		(net "SPI_BIC1_MISO_LS01_R2")
	)
	(segment
		(start 138.82878 -217.5891)
		(end 138.82878 -217.7796)
		(width 0.15494)
		(layer "In9.Cu")
		(net "SPI_BIC1_MISO_LS01_R2")
	)
	(segment
		(start 143.14932 -214.129112)
		(end 143.14932 -216.082626)
		(width 0.15494)
		(layer "In9.Cu")
		(net "SPI_BIC1_MISO_LS01_R2")
	)
	(segment
		(start 137.381742 -217.634058)
		(end 135.500872 -219.514928)
		(width 0.15494)
		(layer "In9.Cu")
		(net "SPI_BIC1_MISO_LS01_R2")
	)
	(segment
		(start 138.82878 -217.7796)
		(end 140.027914 -218.978734)
		(width 0.15494)
		(layer "In9.Cu")
		(net "SPI_BIC1_MISO_LS01_R2")
	)
	(segment
		(start 139.113514 -217.304366)
		(end 138.82878 -217.5891)
		(width 0.15494)
		(layer "In9.Cu")
		(net "SPI_BIC1_MISO_LS01_R2")
	)
	(segment
		(start 140.027914 -219.169234)
		(end 139.764008 -219.43314)
		(width 0.15494)
		(layer "In9.Cu")
		(net "SPI_BIC1_MISO_LS01_R2")
	)
	(segment
		(start 144.907 -207.645)
		(end 143.3322 -209.2198)
		(width 0.15494)
		(layer "In9.Cu")
		(net "SPI_BIC1_MISO_LS01_R2")
	)
	(segment
		(start 143.714216 -210.719416)
		(end 143.714216 -213.564216)
		(width 0.15494)
		(layer "In9.Cu")
		(net "SPI_BIC1_MISO_LS01_R2")
	)
	(segment
		(start 137.774426 -217.634058)
		(end 137.381742 -217.634058)
		(width 0.15494)
		(layer "In9.Cu")
		(net "SPI_BIC1_MISO_LS01_R2")
	)
	(segment
		(start 145.171668 -197.482206)
		(end 146.223228 -198.533766)
		(width 0.15494)
		(layer "In9.Cu")
		(net "SPI_BIC1_MISO_LS01_R2")
	)
	(segment
		(start 143.3322 -209.2198)
		(end 143.3322 -210.3374)
		(width 0.15494)
		(layer "In9.Cu")
		(net "SPI_BIC1_MISO_LS01_R2")
	)
	(segment
		(start 140.027914 -218.978734)
		(end 140.027914 -219.169234)
		(width 0.15494)
		(layer "In9.Cu")
		(net "SPI_BIC1_MISO_LS01_R2")
	)
	(segment
		(start 135.500872 -219.514928)
		(end 135.500872 -223.147382)
		(width 0.15494)
		(layer "In9.Cu")
		(net "SPI_BIC1_MISO_LS01_R2")
	)
	(segment
		(start 146.880834 -193.943224)
		(end 145.171668 -195.65239)
		(width 0.15494)
		(layer "In9.Cu")
		(net "SPI_BIC1_MISO_LS01_R2")
	)
	(segment
		(start 117.12575 -125.899926)
		(end 117.558312 -125.899926)
		(width 0.13208)
		(layer "F.Cu")
		(net "PWRGD_P3V3")
	)
	(segment
		(start 116.534692 -125.904752)
		(end 115.47094 -125.904752)
		(width 0.13208)
		(layer "F.Cu")
		(net "PWRGD_P3V3")
	)
	(segment
		(start 116.827808 -126.197868)
		(end 116.534692 -125.904752)
		(width 0.13208)
		(layer "F.Cu")
		(net "PWRGD_P3V3")
	)
	(segment
		(start 117.558312 -126.915926)
		(end 117.558312 -125.899926)
		(width 0.13208)
		(layer "F.Cu")
		(net "PWRGD_P3V3")
	)
	(segment
		(start 116.827808 -126.197868)
		(end 117.12575 -125.899926)
		(width 0.13208)
		(layer "F.Cu")
		(net "PWRGD_P3V3")
	)
	(via
		(at 116.827808 -126.197868)
		(size 0.508)
		(drill 0.254)
		(layers "F.Cu" "B.Cu")
		(net "PWRGD_P3V3")
	)
	(segment
		(start 116.821966 -124.883926)
		(end 117.558312 -124.883926)
		(width 0.13208)
		(layer "F.Cu")
		(net "P3V3_SS")
	)
	(segment
		(start 115.47094 -125.40488)
		(end 116.301012 -125.40488)
		(width 0.13208)
		(layer "F.Cu")
		(net "P3V3_SS")
	)
	(segment
		(start 116.301012 -125.40488)
		(end 116.821966 -124.883926)
		(width 0.13208)
		(layer "F.Cu")
		(net "P3V3_SS")
	)
	(via
		(at 116.821966 -124.883926)
		(size 0.508)
		(drill 0.254)
		(layers "F.Cu" "B.Cu")
		(net "P3V3_SS")
	)
	(segment
		(start 117.114574 -127.931926)
		(end 117.558312 -127.931926)
		(width 0.13208)
		(layer "F.Cu")
		(net "P3V3_OCP")
	)
	(segment
		(start 116.976398 -127.79375)
		(end 117.114574 -127.931926)
		(width 0.13208)
		(layer "F.Cu")
		(net "P3V3_OCP")
	)
	(segment
		(start 116.976398 -127.48387)
		(end 116.976398 -127.79375)
		(width 0.13208)
		(layer "F.Cu")
		(net "P3V3_OCP")
	)
	(segment
		(start 116.234718 -126.404878)
		(end 115.47094 -126.404878)
		(width 0.13208)
		(layer "F.Cu")
		(net "P3V3_OCP")
	)
	(segment
		(start 116.976398 -127.146558)
		(end 116.234718 -126.404878)
		(width 0.13208)
		(layer "F.Cu")
		(net "P3V3_OCP")
	)
	(segment
		(start 116.976398 -127.48387)
		(end 116.976398 -127.146558)
		(width 0.13208)
		(layer "F.Cu")
		(net "P3V3_OCP")
	)
	(via
		(at 116.976398 -127.48387)
		(size 0.508)
		(drill 0.254)
		(layers "F.Cu" "B.Cu")
		(net "P3V3_OCP")
	)
	(segment
		(start 286.845502 -355.026722)
		(end 286.550862 -354.732082)
		(width 0.13462)
		(layer "F.Cu")
		(net "P5E_PEX2_STN4_TX_DP<70>")
	)
	(segment
		(start 286.845502 -355.658166)
		(end 286.845502 -355.026722)
		(width 0.13462)
		(layer "F.Cu")
		(net "P5E_PEX2_STN4_TX_DP<70>")
	)
	(segment
		(start 286.525462 -355.978206)
		(end 286.845502 -355.658166)
		(width 0.13462)
		(layer "F.Cu")
		(net "P5E_PEX2_STN4_TX_DP<70>")
	)
	(segment
		(start 313.965336 -312.049922)
		(end 313.699906 -312.049922)
		(width 0.1143)
		(layer "In11.Cu")
		(net "P5E_PEX2_STN4_TX_DP<70>")
	)
	(segment
		(start 314.97778 -318.1096)
		(end 315.0235 -318.06388)
		(width 0.1143)
		(layer "In11.Cu")
		(net "P5E_PEX2_STN4_TX_DP<70>")
	)
	(segment
		(start 315.0235 -318.06388)
		(end 315.0235 -312.854594)
		(width 0.1143)
		(layer "In11.Cu")
		(net "P5E_PEX2_STN4_TX_DP<70>")
	)
	(segment
		(start 286.550862 -354.732082)
		(end 286.841692 -354.441252)
		(width 0.1651)
		(layer "In11.Cu")
		(net "P5E_PEX2_STN4_TX_DP<70>")
	)
	(segment
		(start 288.396172 -341.64524)
		(end 289.023044 -341.018368)
		(width 0.1651)
		(layer "In11.Cu")
		(net "P5E_PEX2_STN4_TX_DP<70>")
	)
	(segment
		(start 309.466742 -329.063858)
		(end 313.447684 -325.082662)
		(width 0.1651)
		(layer "In11.Cu")
		(net "P5E_PEX2_STN4_TX_DP<70>")
	)
	(segment
		(start 314.079636 -312.164222)
		(end 313.965336 -312.049922)
		(width 0.1143)
		(layer "In11.Cu")
		(net "P5E_PEX2_STN4_TX_DP<70>")
	)
	(segment
		(start 315.0235 -312.854594)
		(end 314.799726 -312.63082)
		(width 0.1143)
		(layer "In11.Cu")
		(net "P5E_PEX2_STN4_TX_DP<70>")
	)
	(segment
		(start 286.841692 -353.814126)
		(end 288.396172 -352.259646)
		(width 0.1651)
		(layer "In11.Cu")
		(net "P5E_PEX2_STN4_TX_DP<70>")
	)
	(segment
		(start 314.799726 -312.63082)
		(end 314.305442 -312.63082)
		(width 0.1143)
		(layer "In11.Cu")
		(net "P5E_PEX2_STN4_TX_DP<70>")
	)
	(segment
		(start 314.079636 -312.405014)
		(end 314.079636 -312.164222)
		(width 0.1143)
		(layer "In11.Cu")
		(net "P5E_PEX2_STN4_TX_DP<70>")
	)
	(segment
		(start 314.97778 -318.138048)
		(end 314.97778 -318.1096)
		(width 0.1143)
		(layer "In11.Cu")
		(net "P5E_PEX2_STN4_TX_DP<70>")
	)
	(segment
		(start 313.447684 -325.082662)
		(end 314.97778 -322.22059)
		(width 0.1651)
		(layer "In11.Cu")
		(net "P5E_PEX2_STN4_TX_DP<70>")
	)
	(segment
		(start 289.023044 -341.018368)
		(end 309.466742 -329.063858)
		(width 0.1651)
		(layer "In11.Cu")
		(net "P5E_PEX2_STN4_TX_DP<70>")
	)
	(segment
		(start 288.396172 -352.259646)
		(end 288.396172 -341.64524)
		(width 0.1651)
		(layer "In11.Cu")
		(net "P5E_PEX2_STN4_TX_DP<70>")
	)
	(segment
		(start 286.841692 -354.441252)
		(end 286.841692 -353.814126)
		(width 0.1651)
		(layer "In11.Cu")
		(net "P5E_PEX2_STN4_TX_DP<70>")
	)
	(segment
		(start 314.97778 -322.22059)
		(end 314.97778 -318.138048)
		(width 0.1651)
		(layer "In11.Cu")
		(net "P5E_PEX2_STN4_TX_DP<70>")
	)
	(segment
		(start 314.305442 -312.63082)
		(end 314.079636 -312.405014)
		(width 0.1143)
		(layer "In11.Cu")
		(net "P5E_PEX2_STN4_TX_DP<70>")
	)
	(segment
		(start 336.493866 -224.786952)
		(end 336.09407 -225.186748)
		(width 0.13208)
		(layer "F.Cu")
		(net "PWRGD_P3V3_R")
	)
	(segment
		(start 122.29719 -111.122968)
		(end 122.29719 -111.7346)
		(width 0.13208)
		(layer "F.Cu")
		(net "PWRGD_P3V3_R")
	)
	(segment
		(start 118.358412 -126.915926)
		(end 119.013732 -126.915926)
		(width 0.13208)
		(layer "F.Cu")
		(net "PWRGD_P3V3_R")
	)
	(via
		(at 119.013732 -126.915926)
		(size 0.508)
		(drill 0.254)
		(layers "F.Cu" "B.Cu")
		(net "PWRGD_P3V3_R")
	)
	(via
		(at 122.29719 -111.7346)
		(size 0.508)
		(drill 0.254)
		(layers "F.Cu" "B.Cu")
		(net "PWRGD_P3V3_R")
	)
	(via
		(at 336.09407 -225.186748)
		(size 0.4572)
		(drill 0.254)
		(layers "F.Cu" "B.Cu")
		(net "PWRGD_P3V3_R")
	)
	(via
		(at 120.308116 -208.593436)
		(size 0.508)
		(drill 0.254)
		(layers "F.Cu" "B.Cu")
		(net "PWRGD_P3V3_R")
	)
	(segment
		(start 119.81434 -145.380202)
		(end 119.81434 -167.132762)
		(width 0.15494)
		(layer "In7.Cu")
		(net "PWRGD_P3V3_R")
	)
	(segment
		(start 120.9548 -168.273222)
		(end 120.9548 -182.734712)
		(width 0.15494)
		(layer "In7.Cu")
		(net "PWRGD_P3V3_R")
	)
	(segment
		(start 120.202198 -144.992344)
		(end 119.81434 -145.380202)
		(width 0.15494)
		(layer "In7.Cu")
		(net "PWRGD_P3V3_R")
	)
	(segment
		(start 112.243108 -191.446404)
		(end 112.243108 -199.620632)
		(width 0.15494)
		(layer "In7.Cu")
		(net "PWRGD_P3V3_R")
	)
	(segment
		(start 112.243108 -199.620632)
		(end 120.308116 -207.68564)
		(width 0.15494)
		(layer "In7.Cu")
		(net "PWRGD_P3V3_R")
	)
	(segment
		(start 120.9548 -182.734712)
		(end 112.243108 -191.446404)
		(width 0.15494)
		(layer "In7.Cu")
		(net "PWRGD_P3V3_R")
	)
	(segment
		(start 120.308116 -207.68564)
		(end 120.308116 -208.593436)
		(width 0.15494)
		(layer "In7.Cu")
		(net "PWRGD_P3V3_R")
	)
	(segment
		(start 120.202198 -128.104392)
		(end 120.202198 -144.992344)
		(width 0.15494)
		(layer "In7.Cu")
		(net "PWRGD_P3V3_R")
	)
	(segment
		(start 119.013732 -126.915926)
		(end 120.202198 -128.104392)
		(width 0.15494)
		(layer "In7.Cu")
		(net "PWRGD_P3V3_R")
	)
	(segment
		(start 119.81434 -167.132762)
		(end 120.9548 -168.273222)
		(width 0.15494)
		(layer "In7.Cu")
		(net "PWRGD_P3V3_R")
	)
	(segment
		(start 120.8278 -125.101858)
		(end 119.013732 -126.915926)
		(width 0.15494)
		(layer "In9.Cu")
		(net "PWRGD_P3V3_R")
	)
	(segment
		(start 120.8278 -113.20399)
		(end 120.8278 -125.101858)
		(width 0.15494)
		(layer "In9.Cu")
		(net "PWRGD_P3V3_R")
	)
	(segment
		(start 122.29719 -111.7346)
		(end 120.8278 -113.20399)
		(width 0.15494)
		(layer "In9.Cu")
		(net "PWRGD_P3V3_R")
	)
	(segment
		(start 267.077698 -223.165162)
		(end 267.80744 -223.894904)
		(width 0.15494)
		(layer "In15.Cu")
		(net "PWRGD_P3V3_R")
	)
	(segment
		(start 250.176284 -219.89542)
		(end 250.707144 -219.36456)
		(width 0.15494)
		(layer "In15.Cu")
		(net "PWRGD_P3V3_R")
	)
	(segment
		(start 205.892146 -224.9678)
		(end 208.154778 -224.9678)
		(width 0.15494)
		(layer "In15.Cu")
		(net "PWRGD_P3V3_R")
	)
	(segment
		(start 235.21162 -227.221796)
		(end 235.81106 -227.821236)
		(width 0.15494)
		(layer "In15.Cu")
		(net "PWRGD_P3V3_R")
	)
	(segment
		(start 126.420118 -220.293438)
		(end 128.167638 -220.293438)
		(width 0.15494)
		(layer "In15.Cu")
		(net "PWRGD_P3V3_R")
	)
	(segment
		(start 267.80744 -223.894904)
		(end 320.745866 -223.894904)
		(width 0.15494)
		(layer "In15.Cu")
		(net "PWRGD_P3V3_R")
	)
	(segment
		(start 260.684772 -220.455236)
		(end 263.394698 -223.165162)
		(width 0.15494)
		(layer "In15.Cu")
		(net "PWRGD_P3V3_R")
	)
	(segment
		(start 328.364596 -227.601526)
		(end 329.382882 -226.58324)
		(width 0.15494)
		(layer "In15.Cu")
		(net "PWRGD_P3V3_R")
	)
	(segment
		(start 208.154778 -224.9678)
		(end 209.125058 -225.93808)
		(width 0.15494)
		(layer "In15.Cu")
		(net "PWRGD_P3V3_R")
	)
	(segment
		(start 209.125058 -225.93808)
		(end 209.73415 -225.93808)
		(width 0.15494)
		(layer "In15.Cu")
		(net "PWRGD_P3V3_R")
	)
	(segment
		(start 335.0514 -225.5774)
		(end 335.703418 -225.5774)
		(width 0.0889)
		(layer "In15.Cu")
		(net "PWRGD_P3V3_R")
	)
	(segment
		(start 215.218264 -228.55174)
		(end 216.022936 -228.55174)
		(width 0.15494)
		(layer "In15.Cu")
		(net "PWRGD_P3V3_R")
	)
	(segment
		(start 120.308116 -212.352128)
		(end 126.136908 -218.18092)
		(width 0.15494)
		(layer "In15.Cu")
		(net "PWRGD_P3V3_R")
	)
	(segment
		(start 128.167638 -220.293438)
		(end 128.61036 -219.850716)
		(width 0.15494)
		(layer "In15.Cu")
		(net "PWRGD_P3V3_R")
	)
	(segment
		(start 212.14461 -228.34854)
		(end 215.015064 -228.34854)
		(width 0.15494)
		(layer "In15.Cu")
		(net "PWRGD_P3V3_R")
	)
	(segment
		(start 260.2357 -220.455236)
		(end 260.684772 -220.455236)
		(width 0.15494)
		(layer "In15.Cu")
		(net "PWRGD_P3V3_R")
	)
	(segment
		(start 126.136908 -218.18092)
		(end 126.136908 -220.010228)
		(width 0.15494)
		(layer "In15.Cu")
		(net "PWRGD_P3V3_R")
	)
	(segment
		(start 248.268998 -219.89542)
		(end 250.176284 -219.89542)
		(width 0.15494)
		(layer "In15.Cu")
		(net "PWRGD_P3V3_R")
	)
	(segment
		(start 237.742984 -226.8982)
		(end 241.266218 -226.8982)
		(width 0.15494)
		(layer "In15.Cu")
		(net "PWRGD_P3V3_R")
	)
	(segment
		(start 329.382882 -226.58324)
		(end 334.04556 -226.58324)
		(width 0.15494)
		(layer "In15.Cu")
		(net "PWRGD_P3V3_R")
	)
	(segment
		(start 228.722682 -227.866448)
		(end 229.367334 -227.221796)
		(width 0.15494)
		(layer "In15.Cu")
		(net "PWRGD_P3V3_R")
	)
	(segment
		(start 204.37094 -223.446594)
		(end 205.892146 -224.9678)
		(width 0.15494)
		(layer "In15.Cu")
		(net "PWRGD_P3V3_R")
	)
	(segment
		(start 142.093442 -219.170504)
		(end 158.44393 -219.170504)
		(width 0.15494)
		(layer "In15.Cu")
		(net "PWRGD_P3V3_R")
	)
	(segment
		(start 162.72002 -223.446594)
		(end 204.37094 -223.446594)
		(width 0.15494)
		(layer "In15.Cu")
		(net "PWRGD_P3V3_R")
	)
	(segment
		(start 263.394698 -223.165162)
		(end 267.077698 -223.165162)
		(width 0.15494)
		(layer "In15.Cu")
		(net "PWRGD_P3V3_R")
	)
	(segment
		(start 209.73415 -225.93808)
		(end 212.14461 -228.34854)
		(width 0.15494)
		(layer "In15.Cu")
		(net "PWRGD_P3V3_R")
	)
	(segment
		(start 325.916544 -227.35794)
		(end 326.16013 -227.601526)
		(width 0.15494)
		(layer "In15.Cu")
		(net "PWRGD_P3V3_R")
	)
	(segment
		(start 227.67671 -227.221796)
		(end 228.321362 -227.866448)
		(width 0.15494)
		(layer "In15.Cu")
		(net "PWRGD_P3V3_R")
	)
	(segment
		(start 259.145024 -219.36456)
		(end 260.2357 -220.455236)
		(width 0.15494)
		(layer "In15.Cu")
		(net "PWRGD_P3V3_R")
	)
	(segment
		(start 235.81106 -227.821236)
		(end 236.819948 -227.821236)
		(width 0.15494)
		(layer "In15.Cu")
		(net "PWRGD_P3V3_R")
	)
	(segment
		(start 334.04556 -226.58324)
		(end 335.0514 -225.5774)
		(width 0.15494)
		(layer "In15.Cu")
		(net "PWRGD_P3V3_R")
	)
	(segment
		(start 241.266218 -226.8982)
		(end 248.268998 -219.89542)
		(width 0.15494)
		(layer "In15.Cu")
		(net "PWRGD_P3V3_R")
	)
	(segment
		(start 128.61036 -219.850716)
		(end 141.41323 -219.850716)
		(width 0.15494)
		(layer "In15.Cu")
		(net "PWRGD_P3V3_R")
	)
	(segment
		(start 215.015064 -228.34854)
		(end 215.218264 -228.55174)
		(width 0.15494)
		(layer "In15.Cu")
		(net "PWRGD_P3V3_R")
	)
	(segment
		(start 141.41323 -219.850716)
		(end 142.093442 -219.170504)
		(width 0.15494)
		(layer "In15.Cu")
		(net "PWRGD_P3V3_R")
	)
	(segment
		(start 120.308116 -208.593436)
		(end 120.308116 -212.352128)
		(width 0.15494)
		(layer "In15.Cu")
		(net "PWRGD_P3V3_R")
	)
	(segment
		(start 229.367334 -227.221796)
		(end 235.21162 -227.221796)
		(width 0.15494)
		(layer "In15.Cu")
		(net "PWRGD_P3V3_R")
	)
	(segment
		(start 126.136908 -220.010228)
		(end 126.420118 -220.293438)
		(width 0.15494)
		(layer "In15.Cu")
		(net "PWRGD_P3V3_R")
	)
	(segment
		(start 216.022936 -228.55174)
		(end 217.35288 -227.221796)
		(width 0.15494)
		(layer "In15.Cu")
		(net "PWRGD_P3V3_R")
	)
	(segment
		(start 158.44393 -219.170504)
		(end 162.72002 -223.446594)
		(width 0.15494)
		(layer "In15.Cu")
		(net "PWRGD_P3V3_R")
	)
	(segment
		(start 335.703418 -225.5774)
		(end 336.09407 -225.186748)
		(width 0.0889)
		(layer "In15.Cu")
		(net "PWRGD_P3V3_R")
	)
	(segment
		(start 228.321362 -227.866448)
		(end 228.722682 -227.866448)
		(width 0.15494)
		(layer "In15.Cu")
		(net "PWRGD_P3V3_R")
	)
	(segment
		(start 324.208902 -227.35794)
		(end 325.916544 -227.35794)
		(width 0.15494)
		(layer "In15.Cu")
		(net "PWRGD_P3V3_R")
	)
	(segment
		(start 250.707144 -219.36456)
		(end 259.145024 -219.36456)
		(width 0.15494)
		(layer "In15.Cu")
		(net "PWRGD_P3V3_R")
	)
	(segment
		(start 320.745866 -223.894904)
		(end 324.208902 -227.35794)
		(width 0.15494)
		(layer "In15.Cu")
		(net "PWRGD_P3V3_R")
	)
	(segment
		(start 326.16013 -227.601526)
		(end 328.364596 -227.601526)
		(width 0.15494)
		(layer "In15.Cu")
		(net "PWRGD_P3V3_R")
	)
	(segment
		(start 217.35288 -227.221796)
		(end 227.67671 -227.221796)
		(width 0.15494)
		(layer "In15.Cu")
		(net "PWRGD_P3V3_R")
	)
	(segment
		(start 236.819948 -227.821236)
		(end 237.742984 -226.8982)
		(width 0.15494)
		(layer "In15.Cu")
		(net "PWRGD_P3V3_R")
	)
	(segment
		(start 294.50919 -209.694018)
		(end 294.50919 -208.443068)
		(width 0.13208)
		(layer "F.Cu")
		(net "SPI_BIC1_MISO_LS23")
	)
	(segment
		(start 294.905938 -206.903574)
		(end 294.905938 -205.318868)
		(width 0.13208)
		(layer "F.Cu")
		(net "SPI_BIC1_MISO_LS23")
	)
	(segment
		(start 294.50919 -208.443068)
		(end 294.50919 -207.300322)
		(width 0.13208)
		(layer "F.Cu")
		(net "SPI_BIC1_MISO_LS23")
	)
	(segment
		(start 294.50919 -207.300322)
		(end 294.905938 -206.903574)
		(width 0.13208)
		(layer "F.Cu")
		(net "SPI_BIC1_MISO_LS23")
	)
	(via
		(at 294.50919 -208.443068)
		(size 0.762)
		(drill 0.381)
		(layers "F.Cu" "B.Cu")
		(net "SPI_BIC1_MISO_LS23")
	)
	(segment
		(start 294.76319 -195.762118)
		(end 294.76319 -197.013068)
		(width 0.13208)
		(layer "F.Cu")
		(net "SPI_BIC1_MOSI_R4")
	)
	(segment
		(start 295.025826 -198.372476)
		(end 295.378378 -198.725028)
		(width 0.13208)
		(layer "F.Cu")
		(net "SPI_BIC1_MOSI_R4")
	)
	(segment
		(start 294.76319 -197.738492)
		(end 295.025826 -198.372476)
		(width 0.13208)
		(layer "F.Cu")
		(net "SPI_BIC1_MOSI_R4")
	)
	(segment
		(start 294.76319 -197.013068)
		(end 294.76319 -197.738492)
		(width 0.13208)
		(layer "F.Cu")
		(net "SPI_BIC1_MOSI_R4")
	)
	(segment
		(start 295.378378 -198.725028)
		(end 295.555924 -199.15378)
		(width 0.13208)
		(layer "F.Cu")
		(net "SPI_BIC1_MOSI_R4")
	)
	(segment
		(start 295.555924 -199.15378)
		(end 295.555924 -199.718676)
		(width 0.13208)
		(layer "F.Cu")
		(net "SPI_BIC1_MOSI_R4")
	)
	(via
		(at 294.76319 -197.013068)
		(size 0.762)
		(drill 0.381)
		(layers "F.Cu" "B.Cu")
		(net "SPI_BIC1_MOSI_R4")
	)
	(segment
		(start 274.409662 -342.734138)
		(end 274.115022 -342.439498)
		(width 0.13462)
		(layer "F.Cu")
		(net "P5E_PEX2_STN4_TX_DP<77>")
	)
	(segment
		(start 274.089622 -343.685622)
		(end 274.409662 -343.365582)
		(width 0.13462)
		(layer "F.Cu")
		(net "P5E_PEX2_STN4_TX_DP<77>")
	)
	(segment
		(start 274.409662 -343.365582)
		(end 274.409662 -342.734138)
		(width 0.13462)
		(layer "F.Cu")
		(net "P5E_PEX2_STN4_TX_DP<77>")
	)
	(segment
		(start 307.999892 -311.365392)
		(end 307.885592 -311.479692)
		(width 0.1143)
		(layer "In11.Cu")
		(net "P5E_PEX2_STN4_TX_DP<77>")
	)
	(segment
		(start 274.405852 -342.148668)
		(end 274.115022 -342.439498)
		(width 0.1651)
		(layer "In11.Cu")
		(net "P5E_PEX2_STN4_TX_DP<77>")
	)
	(segment
		(start 307.885592 -311.479692)
		(end 307.6448 -311.479692)
		(width 0.1143)
		(layer "In11.Cu")
		(net "P5E_PEX2_STN4_TX_DP<77>")
	)
	(segment
		(start 274.405852 -340.998048)
		(end 274.405852 -342.148668)
		(width 0.1651)
		(layer "In11.Cu")
		(net "P5E_PEX2_STN4_TX_DP<77>")
	)
	(segment
		(start 275.865336 -339.53831)
		(end 274.405852 -340.998048)
		(width 0.1651)
		(layer "In11.Cu")
		(net "P5E_PEX2_STN4_TX_DP<77>")
	)
	(segment
		(start 307.6448 -311.479692)
		(end 307.429662 -311.69483)
		(width 0.1143)
		(layer "In11.Cu")
		(net "P5E_PEX2_STN4_TX_DP<77>")
	)
	(segment
		(start 307.429662 -320.001138)
		(end 307.383942 -320.046858)
		(width 0.1143)
		(layer "In11.Cu")
		(net "P5E_PEX2_STN4_TX_DP<77>")
	)
	(segment
		(start 306.240688 -322.624958)
		(end 275.865336 -339.53831)
		(width 0.1651)
		(layer "In11.Cu")
		(net "P5E_PEX2_STN4_TX_DP<77>")
	)
	(segment
		(start 307.383942 -321.481704)
		(end 306.240688 -322.624958)
		(width 0.1651)
		(layer "In11.Cu")
		(net "P5E_PEX2_STN4_TX_DP<77>")
	)
	(segment
		(start 307.999892 -311.099962)
		(end 307.999892 -311.365392)
		(width 0.1143)
		(layer "In11.Cu")
		(net "P5E_PEX2_STN4_TX_DP<77>")
	)
	(segment
		(start 307.429662 -311.69483)
		(end 307.429662 -320.001138)
		(width 0.1143)
		(layer "In11.Cu")
		(net "P5E_PEX2_STN4_TX_DP<77>")
	)
	(segment
		(start 307.383942 -320.068956)
		(end 307.383942 -321.481704)
		(width 0.1651)
		(layer "In11.Cu")
		(net "P5E_PEX2_STN4_TX_DP<77>")
	)
	(segment
		(start 307.383942 -320.046858)
		(end 307.383942 -320.068956)
		(width 0.1143)
		(layer "In11.Cu")
		(net "P5E_PEX2_STN4_TX_DP<77>")
	)
	(segment
		(start 300.60519 -208.443068)
		(end 300.60519 -209.694018)
		(width 0.13208)
		(layer "F.Cu")
		(net "SPI_BIC1_CS0_LS23_N")
	)
	(segment
		(start 296.85615 -205.318868)
		(end 296.85615 -206.284068)
		(width 0.13208)
		(layer "F.Cu")
		(net "SPI_BIC1_CS0_LS23_N")
	)
	(segment
		(start 299.46219 -207.300068)
		(end 300.60519 -208.443068)
		(width 0.13208)
		(layer "F.Cu")
		(net "SPI_BIC1_CS0_LS23_N")
	)
	(segment
		(start 297.87215 -207.300068)
		(end 299.46219 -207.300068)
		(width 0.13208)
		(layer "F.Cu")
		(net "SPI_BIC1_CS0_LS23_N")
	)
	(segment
		(start 296.85615 -206.284068)
		(end 297.87215 -207.300068)
		(width 0.13208)
		(layer "F.Cu")
		(net "SPI_BIC1_CS0_LS23_N")
	)
	(via
		(at 300.60519 -208.443068)
		(size 0.762)
		(drill 0.381)
		(layers "F.Cu" "B.Cu")
		(net "SPI_BIC1_CS0_LS23_N")
	)
	(segment
		(start 295.77919 -195.762118)
		(end 295.90619 -195.889118)
		(width 0.13208)
		(layer "F.Cu")
		(net "SPI_BIC1_CLK_R4")
	)
	(segment
		(start 296.206164 -198.202042)
		(end 296.206164 -199.718676)
		(width 0.13208)
		(layer "F.Cu")
		(net "SPI_BIC1_CLK_R4")
	)
	(segment
		(start 295.90619 -197.902068)
		(end 296.206164 -198.202042)
		(width 0.13208)
		(layer "F.Cu")
		(net "SPI_BIC1_CLK_R4")
	)
	(segment
		(start 295.90619 -195.889118)
		(end 295.90619 -197.902068)
		(width 0.13208)
		(layer "F.Cu")
		(net "SPI_BIC1_CLK_R4")
	)
	(via
		(at 295.90619 -197.902068)
		(size 0.762)
		(drill 0.381)
		(layers "F.Cu" "B.Cu")
		(net "SPI_BIC1_CLK_R4")
	)
	(segment
		(start 296.206164 -206.711042)
		(end 297.81119 -208.316068)
		(width 0.13208)
		(layer "F.Cu")
		(net "SPI_BIC1_CLK_LS23")
	)
	(segment
		(start 296.206164 -205.318868)
		(end 296.206164 -206.711042)
		(width 0.13208)
		(layer "F.Cu")
		(net "SPI_BIC1_CLK_LS23")
	)
	(segment
		(start 298.57319 -208.316068)
		(end 298.57319 -209.694018)
		(width 0.13208)
		(layer "F.Cu")
		(net "SPI_BIC1_CLK_LS23")
	)
	(segment
		(start 297.81119 -208.316068)
		(end 298.57319 -208.316068)
		(width 0.13208)
		(layer "F.Cu")
		(net "SPI_BIC1_CLK_LS23")
	)
	(via
		(at 298.57319 -208.316068)
		(size 0.762)
		(drill 0.381)
		(layers "F.Cu" "B.Cu")
		(net "SPI_BIC1_CLK_LS23")
	)
	(segment
		(start 296.85615 -199.718676)
		(end 296.85615 -198.283068)
		(width 0.13208)
		(layer "F.Cu")
		(net "SPI_BIC1_CS0_R3_N")
	)
	(segment
		(start 296.92219 -198.217028)
		(end 296.92219 -197.013068)
		(width 0.13208)
		(layer "F.Cu")
		(net "SPI_BIC1_CS0_R3_N")
	)
	(segment
		(start 296.92219 -195.85559)
		(end 296.79519 -195.72859)
		(width 0.13208)
		(layer "F.Cu")
		(net "SPI_BIC1_CS0_R3_N")
	)
	(segment
		(start 296.85615 -198.283068)
		(end 296.92219 -198.217028)
		(width 0.13208)
		(layer "F.Cu")
		(net "SPI_BIC1_CS0_R3_N")
	)
	(segment
		(start 296.92219 -197.013068)
		(end 296.92219 -195.85559)
		(width 0.13208)
		(layer "F.Cu")
		(net "SPI_BIC1_CS0_R3_N")
	)
	(via
		(at 296.92219 -197.013068)
		(size 0.762)
		(drill 0.381)
		(layers "F.Cu" "B.Cu")
		(net "SPI_BIC1_CS0_R3_N")
	)
	(segment
		(start 274.409662 -355.658166)
		(end 274.409662 -355.026722)
		(width 0.13462)
		(layer "F.Cu")
		(net "P5E_PEX2_STN4_TX_DP<76>")
	)
	(segment
		(start 274.089622 -355.978206)
		(end 274.409662 -355.658166)
		(width 0.13462)
		(layer "F.Cu")
		(net "P5E_PEX2_STN4_TX_DP<76>")
	)
	(segment
		(start 274.409662 -355.026722)
		(end 274.115022 -354.732082)
		(width 0.13462)
		(layer "F.Cu")
		(net "P5E_PEX2_STN4_TX_DP<76>")
	)
	(segment
		(start 308.379622 -313.59475)
		(end 308.379622 -319.945258)
		(width 0.1143)
		(layer "In11.Cu")
		(net "P5E_PEX2_STN4_TX_DP<76>")
	)
	(segment
		(start 306.684934 -323.537326)
		(end 277.086568 -340.250272)
		(width 0.1651)
		(layer "In11.Cu")
		(net "P5E_PEX2_STN4_TX_DP<76>")
	)
	(segment
		(start 308.949852 -313.265312)
		(end 308.835552 -313.379612)
		(width 0.1143)
		(layer "In11.Cu")
		(net "P5E_PEX2_STN4_TX_DP<76>")
	)
	(segment
		(start 308.379622 -319.945258)
		(end 308.333902 -319.990978)
		(width 0.1143)
		(layer "In11.Cu")
		(net "P5E_PEX2_STN4_TX_DP<76>")
	)
	(segment
		(start 308.333902 -321.888358)
		(end 306.684934 -323.537326)
		(width 0.1651)
		(layer "In11.Cu")
		(net "P5E_PEX2_STN4_TX_DP<76>")
	)
	(segment
		(start 275.960332 -341.376508)
		(end 275.960332 -352.259646)
		(width 0.1651)
		(layer "In11.Cu")
		(net "P5E_PEX2_STN4_TX_DP<76>")
	)
	(segment
		(start 308.333902 -320.013076)
		(end 308.333902 -321.888358)
		(width 0.1651)
		(layer "In11.Cu")
		(net "P5E_PEX2_STN4_TX_DP<76>")
	)
	(segment
		(start 308.59476 -313.379612)
		(end 308.379622 -313.59475)
		(width 0.1143)
		(layer "In11.Cu")
		(net "P5E_PEX2_STN4_TX_DP<76>")
	)
	(segment
		(start 274.405852 -353.814126)
		(end 274.405852 -354.441252)
		(width 0.1651)
		(layer "In11.Cu")
		(net "P5E_PEX2_STN4_TX_DP<76>")
	)
	(segment
		(start 308.835552 -313.379612)
		(end 308.59476 -313.379612)
		(width 0.1143)
		(layer "In11.Cu")
		(net "P5E_PEX2_STN4_TX_DP<76>")
	)
	(segment
		(start 308.333902 -319.990978)
		(end 308.333902 -320.013076)
		(width 0.1143)
		(layer "In11.Cu")
		(net "P5E_PEX2_STN4_TX_DP<76>")
	)
	(segment
		(start 275.960332 -352.259646)
		(end 274.405852 -353.814126)
		(width 0.1651)
		(layer "In11.Cu")
		(net "P5E_PEX2_STN4_TX_DP<76>")
	)
	(segment
		(start 308.949852 -312.999882)
		(end 308.949852 -313.265312)
		(width 0.1143)
		(layer "In11.Cu")
		(net "P5E_PEX2_STN4_TX_DP<76>")
	)
	(segment
		(start 274.405852 -354.441252)
		(end 274.115022 -354.732082)
		(width 0.1651)
		(layer "In11.Cu")
		(net "P5E_PEX2_STN4_TX_DP<76>")
	)
	(segment
		(start 277.086568 -340.250272)
		(end 275.960332 -341.376508)
		(width 0.1651)
		(layer "In11.Cu")
		(net "P5E_PEX2_STN4_TX_DP<76>")
	)
	(segment
		(start 296.54119 -208.443068)
		(end 295.555924 -207.457802)
		(width 0.13208)
		(layer "F.Cu")
		(net "SPI_BIC1_MOSI_LS23")
	)
	(segment
		(start 296.54119 -209.694018)
		(end 296.54119 -208.443068)
		(width 0.13208)
		(layer "F.Cu")
		(net "SPI_BIC1_MOSI_LS23")
	)
	(segment
		(start 295.555924 -207.457802)
		(end 295.555924 -205.318868)
		(width 0.13208)
		(layer "F.Cu")
		(net "SPI_BIC1_MOSI_LS23")
	)
	(via
		(at 296.54119 -208.443068)
		(size 0.762)
		(drill 0.381)
		(layers "F.Cu" "B.Cu")
		(net "SPI_BIC1_MOSI_LS23")
	)
	(segment
		(start 294.905938 -199.247252)
		(end 294.905938 -199.718676)
		(width 0.13208)
		(layer "F.Cu")
		(net "SPI_BIC1_MISO_R4")
	)
	(segment
		(start 294.774112 -198.92899)
		(end 294.905938 -199.247252)
		(width 0.13208)
		(layer "F.Cu")
		(net "SPI_BIC1_MISO_R4")
	)
	(segment
		(start 293.74719 -195.762118)
		(end 293.74719 -197.902068)
		(width 0.13208)
		(layer "F.Cu")
		(net "SPI_BIC1_MISO_R4")
	)
	(segment
		(start 293.74719 -197.902068)
		(end 294.774112 -198.92899)
		(width 0.13208)
		(layer "F.Cu")
		(net "SPI_BIC1_MISO_R4")
	)
	(via
		(at 293.74719 -197.902068)
		(size 0.762)
		(drill 0.381)
		(layers "F.Cu" "B.Cu")
		(net "SPI_BIC1_MISO_R4")
	)
	(segment
		(start 296.54119 -213.123018)
		(end 296.54119 -211.872068)
		(width 0.13208)
		(layer "F.Cu")
		(net "SPI_BIC1_MOSI_LS23_R")
	)
	(segment
		(start 296.54119 -211.872068)
		(end 296.54119 -210.494118)
		(width 0.13208)
		(layer "F.Cu")
		(net "SPI_BIC1_MOSI_LS23_R")
	)
	(segment
		(start 295.52519 -213.123018)
		(end 296.54119 -213.123018)
		(width 0.13208)
		(layer "F.Cu")
		(net "SPI_BIC1_MOSI_LS23_R")
	)
	(via
		(at 296.54119 -211.872068)
		(size 0.762)
		(drill 0.381)
		(layers "F.Cu" "B.Cu")
		(net "SPI_BIC1_MOSI_LS23_R")
	)
	(segment
		(start 274.683982 -355.026722)
		(end 274.978622 -354.732082)
		(width 0.13462)
		(layer "F.Cu")
		(net "P5E_PEX2_STN4_TX_DN<76>")
	)
	(segment
		(start 274.683982 -355.658166)
		(end 274.683982 -355.026722)
		(width 0.13462)
		(layer "F.Cu")
		(net "P5E_PEX2_STN4_TX_DN<76>")
	)
	(segment
		(start 275.004022 -355.978206)
		(end 274.683982 -355.658166)
		(width 0.13462)
		(layer "F.Cu")
		(net "P5E_PEX2_STN4_TX_DN<76>")
	)
	(segment
		(start 280.12517 -338.858606)
		(end 280.280872 -338.901786)
		(width 0.1651)
		(layer "In11.Cu")
		(net "P5E_PEX2_STN4_TX_DN<76>")
	)
	(segment
		(start 308.570122 -319.945258)
		(end 308.570122 -313.673744)
		(width 0.1143)
		(layer "In11.Cu")
		(net "P5E_PEX2_STN4_TX_DN<76>")
	)
	(segment
		(start 276.242272 -341.493348)
		(end 277.25878 -340.47684)
		(width 0.1651)
		(layer "In11.Cu")
		(net "P5E_PEX2_STN4_TX_DN<76>")
	)
	(segment
		(start 280.755598 -338.502498)
		(end 306.857146 -323.763894)
		(width 0.1651)
		(layer "In11.Cu")
		(net "P5E_PEX2_STN4_TX_DN<76>")
	)
	(segment
		(start 279.219152 -339.501226)
		(end 279.650698 -339.25764)
		(width 0.1651)
		(layer "In11.Cu")
		(net "P5E_PEX2_STN4_TX_DN<76>")
	)
	(segment
		(start 280.755598 -338.502244)
		(end 280.755598 -338.502498)
		(width 0.1651)
		(layer "In11.Cu")
		(net "P5E_PEX2_STN4_TX_DN<76>")
	)
	(segment
		(start 306.857146 -323.763894)
		(end 308.615842 -322.005198)
		(width 0.1651)
		(layer "In11.Cu")
		(net "P5E_PEX2_STN4_TX_DN<76>")
	)
	(segment
		(start 274.687792 -353.930966)
		(end 276.242272 -352.376486)
		(width 0.1651)
		(layer "In11.Cu")
		(net "P5E_PEX2_STN4_TX_DN<76>")
	)
	(segment
		(start 308.615842 -322.005198)
		(end 308.615842 -320.013076)
		(width 0.1651)
		(layer "In11.Cu")
		(net "P5E_PEX2_STN4_TX_DN<76>")
	)
	(segment
		(start 279.693878 -339.101684)
		(end 279.693878 -339.101938)
		(width 0.1651)
		(layer "In11.Cu")
		(net "P5E_PEX2_STN4_TX_DN<76>")
	)
	(segment
		(start 308.570122 -313.673744)
		(end 308.673754 -313.570112)
		(width 0.1143)
		(layer "In11.Cu")
		(net "P5E_PEX2_STN4_TX_DN<76>")
	)
	(segment
		(start 274.978622 -354.732082)
		(end 274.687792 -354.441252)
		(width 0.1651)
		(layer "In11.Cu")
		(net "P5E_PEX2_STN4_TX_DN<76>")
	)
	(segment
		(start 278.001476 -340.057486)
		(end 278.157178 -340.10092)
		(width 0.1651)
		(layer "In11.Cu")
		(net "P5E_PEX2_STN4_TX_DN<76>")
	)
	(segment
		(start 279.06345 -339.458046)
		(end 279.219152 -339.501226)
		(width 0.1651)
		(layer "In11.Cu")
		(net "P5E_PEX2_STN4_TX_DN<76>")
	)
	(segment
		(start 308.673754 -313.570112)
		(end 308.835552 -313.570112)
		(width 0.1143)
		(layer "In11.Cu")
		(net "P5E_PEX2_STN4_TX_DN<76>")
	)
	(segment
		(start 308.615842 -320.013076)
		(end 308.615842 -319.990978)
		(width 0.1143)
		(layer "In11.Cu")
		(net "P5E_PEX2_STN4_TX_DN<76>")
	)
	(segment
		(start 280.712418 -338.657946)
		(end 280.755598 -338.502244)
		(width 0.1651)
		(layer "In11.Cu")
		(net "P5E_PEX2_STN4_TX_DN<76>")
	)
	(segment
		(start 274.687792 -354.441252)
		(end 274.687792 -353.930966)
		(width 0.1651)
		(layer "In11.Cu")
		(net "P5E_PEX2_STN4_TX_DN<76>")
	)
	(segment
		(start 276.242272 -352.376486)
		(end 276.242272 -341.493348)
		(width 0.1651)
		(layer "In11.Cu")
		(net "P5E_PEX2_STN4_TX_DN<76>")
	)
	(segment
		(start 308.949852 -313.684412)
		(end 308.949852 -313.949842)
		(width 0.1143)
		(layer "In11.Cu")
		(net "P5E_PEX2_STN4_TX_DN<76>")
	)
	(segment
		(start 278.632158 -339.701378)
		(end 279.06345 -339.458046)
		(width 0.1651)
		(layer "In11.Cu")
		(net "P5E_PEX2_STN4_TX_DN<76>")
	)
	(segment
		(start 278.588724 -339.85708)
		(end 278.632158 -339.701378)
		(width 0.1651)
		(layer "In11.Cu")
		(net "P5E_PEX2_STN4_TX_DN<76>")
	)
	(segment
		(start 279.650698 -339.25764)
		(end 279.693878 -339.101684)
		(width 0.1651)
		(layer "In11.Cu")
		(net "P5E_PEX2_STN4_TX_DN<76>")
	)
	(segment
		(start 279.693878 -339.101938)
		(end 280.12517 -338.858606)
		(width 0.1651)
		(layer "In11.Cu")
		(net "P5E_PEX2_STN4_TX_DN<76>")
	)
	(segment
		(start 308.835552 -313.570112)
		(end 308.949852 -313.684412)
		(width 0.1143)
		(layer "In11.Cu")
		(net "P5E_PEX2_STN4_TX_DN<76>")
	)
	(segment
		(start 280.280872 -338.901786)
		(end 280.712418 -338.657946)
		(width 0.1651)
		(layer "In11.Cu")
		(net "P5E_PEX2_STN4_TX_DN<76>")
	)
	(segment
		(start 308.615842 -319.990978)
		(end 308.570122 -319.945258)
		(width 0.1143)
		(layer "In11.Cu")
		(net "P5E_PEX2_STN4_TX_DN<76>")
	)
	(segment
		(start 278.157178 -340.10092)
		(end 278.588724 -339.85708)
		(width 0.1651)
		(layer "In11.Cu")
		(net "P5E_PEX2_STN4_TX_DN<76>")
	)
	(segment
		(start 277.25878 -340.47684)
		(end 278.001476 -340.057486)
		(width 0.1651)
		(layer "In11.Cu")
		(net "P5E_PEX2_STN4_TX_DN<76>")
	)
	(segment
		(start 298.57319 -213.123018)
		(end 298.57319 -211.745068)
		(width 0.13208)
		(layer "F.Cu")
		(net "SPI_BIC1_CLK_LS23_R")
	)
	(segment
		(start 297.55719 -213.123018)
		(end 298.57319 -213.123018)
		(width 0.13208)
		(layer "F.Cu")
		(net "SPI_BIC1_CLK_LS23_R")
	)
	(segment
		(start 298.57319 -211.745068)
		(end 298.57319 -210.494118)
		(width 0.13208)
		(layer "F.Cu")
		(net "SPI_BIC1_CLK_LS23_R")
	)
	(via
		(at 298.57319 -211.745068)
		(size 0.762)
		(drill 0.381)
		(layers "F.Cu" "B.Cu")
		(net "SPI_BIC1_CLK_LS23_R")
	)
	(segment
		(start 284.010862 -349.511874)
		(end 284.010862 -348.88043)
		(width 0.13462)
		(layer "F.Cu")
		(net "P5E_PEX2_STN4_TX_DN<72>")
	)
	(segment
		(start 284.330902 -349.831914)
		(end 284.010862 -349.511874)
		(width 0.13462)
		(layer "F.Cu")
		(net "P5E_PEX2_STN4_TX_DN<72>")
	)
	(segment
		(start 284.010862 -348.88043)
		(end 284.305502 -348.58579)
		(width 0.13462)
		(layer "F.Cu")
		(net "P5E_PEX2_STN4_TX_DN<72>")
	)
	(segment
		(start 308.920388 -327.232772)
		(end 312.018934 -324.134226)
		(width 0.1651)
		(layer "In11.Cu")
		(net "P5E_PEX2_STN4_TX_DN<72>")
	)
	(segment
		(start 284.305502 -348.58579)
		(end 284.014672 -348.29496)
		(width 0.1651)
		(layer "In11.Cu")
		(net "P5E_PEX2_STN4_TX_DN<72>")
	)
	(segment
		(start 312.018934 -324.134226)
		(end 312.415936 -323.175884)
		(width 0.1651)
		(layer "In11.Cu")
		(net "P5E_PEX2_STN4_TX_DN<72>")
	)
	(segment
		(start 290.513516 -338.117688)
		(end 290.55441 -337.961224)
		(width 0.1651)
		(layer "In11.Cu")
		(net "P5E_PEX2_STN4_TX_DN<72>")
	)
	(segment
		(start 284.014672 -347.784674)
		(end 285.569152 -346.230194)
		(width 0.1651)
		(layer "In11.Cu")
		(net "P5E_PEX2_STN4_TX_DN<72>")
	)
	(segment
		(start 288.876486 -338.941664)
		(end 289.032696 -338.982558)
		(width 0.1651)
		(layer "In11.Cu")
		(net "P5E_PEX2_STN4_TX_DN<72>")
	)
	(segment
		(start 286.839914 -340.131146)
		(end 288.876486 -338.941664)
		(width 0.1651)
		(layer "In11.Cu")
		(net "P5E_PEX2_STN4_TX_DN<72>")
	)
	(segment
		(start 289.460686 -338.732622)
		(end 289.50158 -338.576158)
		(width 0.1651)
		(layer "In11.Cu")
		(net "P5E_PEX2_STN4_TX_DN<72>")
	)
	(segment
		(start 312.415936 -319.935352)
		(end 312.370216 -319.889632)
		(width 0.1143)
		(layer "In11.Cu")
		(net "P5E_PEX2_STN4_TX_DN<72>")
	)
	(segment
		(start 312.749692 -313.684412)
		(end 312.749692 -313.949842)
		(width 0.1143)
		(layer "In11.Cu")
		(net "P5E_PEX2_STN4_TX_DN<72>")
	)
	(segment
		(start 285.569152 -346.230194)
		(end 285.569152 -341.401908)
		(width 0.1651)
		(layer "In11.Cu")
		(net "P5E_PEX2_STN4_TX_DN<72>")
	)
	(segment
		(start 312.415936 -323.175884)
		(end 312.415936 -319.9638)
		(width 0.1651)
		(layer "In11.Cu")
		(net "P5E_PEX2_STN4_TX_DN<72>")
	)
	(segment
		(start 312.370216 -319.889632)
		(end 312.370216 -313.67349)
		(width 0.1143)
		(layer "In11.Cu")
		(net "P5E_PEX2_STN4_TX_DN<72>")
	)
	(segment
		(start 312.370216 -313.67349)
		(end 312.473594 -313.570112)
		(width 0.1143)
		(layer "In11.Cu")
		(net "P5E_PEX2_STN4_TX_DN<72>")
	)
	(segment
		(start 285.569152 -341.401908)
		(end 286.839914 -340.131146)
		(width 0.1651)
		(layer "In11.Cu")
		(net "P5E_PEX2_STN4_TX_DN<72>")
	)
	(segment
		(start 312.415936 -319.9638)
		(end 312.415936 -319.935352)
		(width 0.1143)
		(layer "In11.Cu")
		(net "P5E_PEX2_STN4_TX_DN<72>")
	)
	(segment
		(start 312.635392 -313.570112)
		(end 312.749692 -313.684412)
		(width 0.1143)
		(layer "In11.Cu")
		(net "P5E_PEX2_STN4_TX_DN<72>")
	)
	(segment
		(start 312.473594 -313.570112)
		(end 312.635392 -313.570112)
		(width 0.1143)
		(layer "In11.Cu")
		(net "P5E_PEX2_STN4_TX_DN<72>")
	)
	(segment
		(start 290.55441 -337.961478)
		(end 308.920388 -327.232772)
		(width 0.1651)
		(layer "In11.Cu")
		(net "P5E_PEX2_STN4_TX_DN<72>")
	)
	(segment
		(start 289.032696 -338.982558)
		(end 289.460686 -338.732622)
		(width 0.1651)
		(layer "In11.Cu")
		(net "P5E_PEX2_STN4_TX_DN<72>")
	)
	(segment
		(start 290.085526 -338.367624)
		(end 290.513516 -338.117688)
		(width 0.1651)
		(layer "In11.Cu")
		(net "P5E_PEX2_STN4_TX_DN<72>")
	)
	(segment
		(start 289.929062 -338.32673)
		(end 290.085526 -338.367624)
		(width 0.1651)
		(layer "In11.Cu")
		(net "P5E_PEX2_STN4_TX_DN<72>")
	)
	(segment
		(start 290.55441 -337.961224)
		(end 290.55441 -337.961478)
		(width 0.1651)
		(layer "In11.Cu")
		(net "P5E_PEX2_STN4_TX_DN<72>")
	)
	(segment
		(start 284.014672 -348.29496)
		(end 284.014672 -347.784674)
		(width 0.1651)
		(layer "In11.Cu")
		(net "P5E_PEX2_STN4_TX_DN<72>")
	)
	(segment
		(start 289.50158 -338.576158)
		(end 289.50158 -338.576412)
		(width 0.1651)
		(layer "In11.Cu")
		(net "P5E_PEX2_STN4_TX_DN<72>")
	)
	(segment
		(start 289.50158 -338.576412)
		(end 289.929062 -338.32673)
		(width 0.1651)
		(layer "In11.Cu")
		(net "P5E_PEX2_STN4_TX_DN<72>")
	)
	(segment
		(start 294.50919 -211.872068)
		(end 294.50919 -210.494118)
		(width 0.13208)
		(layer "F.Cu")
		(net "SPI_BIC1_MISO_LS23_R")
	)
	(segment
		(start 293.49319 -213.123018)
		(end 294.50919 -213.123018)
		(width 0.13208)
		(layer "F.Cu")
		(net "SPI_BIC1_MISO_LS23_R")
	)
	(segment
		(start 294.50919 -213.123018)
		(end 294.50919 -211.872068)
		(width 0.13208)
		(layer "F.Cu")
		(net "SPI_BIC1_MISO_LS23_R")
	)
	(via
		(at 294.50919 -211.872068)
		(size 0.762)
		(drill 0.381)
		(layers "F.Cu" "B.Cu")
		(net "SPI_BIC1_MISO_LS23_R")
	)
	(segment
		(start 296.446702 -349.511874)
		(end 296.446702 -348.88043)
		(width 0.13462)
		(layer "F.Cu")
		(net "P5E_PEX2_STN4_TX_DN<66>")
	)
	(segment
		(start 296.766742 -349.831914)
		(end 296.446702 -349.511874)
		(width 0.13462)
		(layer "F.Cu")
		(net "P5E_PEX2_STN4_TX_DN<66>")
	)
	(segment
		(start 296.446702 -348.88043)
		(end 296.741342 -348.58579)
		(width 0.13462)
		(layer "F.Cu")
		(net "P5E_PEX2_STN4_TX_DN<66>")
	)
	(segment
		(start 328.388726 -326.36333)
		(end 330.22286 -322.71589)
		(width 0.1651)
		(layer "In11.Cu")
		(net "P5E_PEX2_STN4_TX_DN<66>")
	)
	(segment
		(start 298.097448 -341.677752)
		(end 299.441108 -340.334092)
		(width 0.1651)
		(layer "In11.Cu")
		(net "P5E_PEX2_STN4_TX_DN<66>")
	)
	(segment
		(start 317.660528 -306.941728)
		(end 316.557152 -306.722272)
		(width 0.1651)
		(layer "In11.Cu")
		(net "P5E_PEX2_STN4_TX_DN<66>")
	)
	(segment
		(start 315.902848 -306.683918)
		(end 315.8744 -306.683918)
		(width 0.1143)
		(layer "In11.Cu")
		(net "P5E_PEX2_STN4_TX_DN<66>")
	)
	(segment
		(start 330.22286 -322.71589)
		(end 330.22286 -319.366138)
		(width 0.1651)
		(layer "In11.Cu")
		(net "P5E_PEX2_STN4_TX_DN<66>")
	)
	(segment
		(start 315.82868 -306.729638)
		(end 307.74513 -306.729638)
		(width 0.1143)
		(layer "In11.Cu")
		(net "P5E_PEX2_STN4_TX_DN<66>")
	)
	(segment
		(start 296.450512 -347.784674)
		(end 298.004992 -346.230194)
		(width 0.1651)
		(layer "In11.Cu")
		(net "P5E_PEX2_STN4_TX_DN<66>")
	)
	(segment
		(start 307.734462 -306.349908)
		(end 307.999892 -306.349908)
		(width 0.1143)
		(layer "In11.Cu")
		(net "P5E_PEX2_STN4_TX_DN<66>")
	)
	(segment
		(start 330.22286 -319.366138)
		(end 329.027282 -316.479682)
		(width 0.1651)
		(layer "In11.Cu")
		(net "P5E_PEX2_STN4_TX_DN<66>")
	)
	(segment
		(start 316.168532 -306.683918)
		(end 315.902848 -306.683918)
		(width 0.1651)
		(layer "In11.Cu")
		(net "P5E_PEX2_STN4_TX_DN<66>")
	)
	(segment
		(start 307.63083 -306.45354)
		(end 307.734462 -306.349908)
		(width 0.1143)
		(layer "In11.Cu")
		(net "P5E_PEX2_STN4_TX_DN<66>")
	)
	(segment
		(start 299.441108 -340.334092)
		(end 326.22744 -328.647552)
		(width 0.1651)
		(layer "In11.Cu")
		(net "P5E_PEX2_STN4_TX_DN<66>")
	)
	(segment
		(start 298.004992 -346.230194)
		(end 298.004992 -341.901018)
		(width 0.1651)
		(layer "In11.Cu")
		(net "P5E_PEX2_STN4_TX_DN<66>")
	)
	(segment
		(start 296.741342 -348.58579)
		(end 296.450512 -348.29496)
		(width 0.1651)
		(layer "In11.Cu")
		(net "P5E_PEX2_STN4_TX_DN<66>")
	)
	(segment
		(start 326.556116 -314.008516)
		(end 323.434202 -312.715402)
		(width 0.1651)
		(layer "In11.Cu")
		(net "P5E_PEX2_STN4_TX_DN<66>")
	)
	(segment
		(start 326.22744 -328.647552)
		(end 328.388726 -326.36333)
		(width 0.1651)
		(layer "In11.Cu")
		(net "P5E_PEX2_STN4_TX_DN<66>")
	)
	(segment
		(start 323.434202 -312.715402)
		(end 317.660528 -306.941728)
		(width 0.1651)
		(layer "In11.Cu")
		(net "P5E_PEX2_STN4_TX_DN<66>")
	)
	(segment
		(start 315.8744 -306.683918)
		(end 315.82868 -306.729638)
		(width 0.1143)
		(layer "In11.Cu")
		(net "P5E_PEX2_STN4_TX_DN<66>")
	)
	(segment
		(start 298.004992 -341.901018)
		(end 298.097448 -341.677752)
		(width 0.1651)
		(layer "In11.Cu")
		(net "P5E_PEX2_STN4_TX_DN<66>")
	)
	(segment
		(start 296.450512 -348.29496)
		(end 296.450512 -347.784674)
		(width 0.1651)
		(layer "In11.Cu")
		(net "P5E_PEX2_STN4_TX_DN<66>")
	)
	(segment
		(start 316.557152 -306.722272)
		(end 316.168532 -306.683918)
		(width 0.1651)
		(layer "In11.Cu")
		(net "P5E_PEX2_STN4_TX_DN<66>")
	)
	(segment
		(start 329.027282 -316.479682)
		(end 326.556116 -314.008516)
		(width 0.1651)
		(layer "In11.Cu")
		(net "P5E_PEX2_STN4_TX_DN<66>")
	)
	(segment
		(start 307.74513 -306.729638)
		(end 307.63083 -306.615338)
		(width 0.1143)
		(layer "In11.Cu")
		(net "P5E_PEX2_STN4_TX_DN<66>")
	)
	(segment
		(start 307.63083 -306.615338)
		(end 307.63083 -306.45354)
		(width 0.1143)
		(layer "In11.Cu")
		(net "P5E_PEX2_STN4_TX_DN<66>")
	)
	(segment
		(start 300.60519 -213.123018)
		(end 300.60519 -211.872068)
		(width 0.13208)
		(layer "F.Cu")
		(net "SPI_BIC1_CS0_LS23_R_N")
	)
	(segment
		(start 300.60519 -211.872068)
		(end 300.60519 -210.494118)
		(width 0.13208)
		(layer "F.Cu")
		(net "SPI_BIC1_CS0_LS23_R_N")
	)
	(segment
		(start 299.58919 -213.123018)
		(end 300.60519 -213.123018)
		(width 0.13208)
		(layer "F.Cu")
		(net "SPI_BIC1_CS0_LS23_R_N")
	)
	(via
		(at 300.60519 -211.872068)
		(size 0.762)
		(drill 0.381)
		(layers "F.Cu" "B.Cu")
		(net "SPI_BIC1_CS0_LS23_R_N")
	)
	(segment
		(start 280.901902 -343.365582)
		(end 280.901902 -342.734138)
		(width 0.13462)
		(layer "F.Cu")
		(net "P5E_PEX2_STN4_TX_DN<74>")
	)
	(segment
		(start 281.221942 -343.685622)
		(end 280.901902 -343.365582)
		(width 0.13462)
		(layer "F.Cu")
		(net "P5E_PEX2_STN4_TX_DN<74>")
	)
	(segment
		(start 280.901902 -342.734138)
		(end 281.196542 -342.439498)
		(width 0.13462)
		(layer "F.Cu")
		(net "P5E_PEX2_STN4_TX_DN<74>")
	)
	(segment
		(start 284.357826 -339.118956)
		(end 284.399736 -338.962746)
		(width 0.1651)
		(layer "In11.Cu")
		(net "P5E_PEX2_STN4_TX_DN<74>")
	)
	(segment
		(start 285.45663 -338.354924)
		(end 307.995574 -325.388986)
		(width 0.1651)
		(layer "In11.Cu")
		(net "P5E_PEX2_STN4_TX_DN<74>")
	)
	(segment
		(start 284.984952 -338.758022)
		(end 285.41472 -338.51088)
		(width 0.1651)
		(layer "In11.Cu")
		(net "P5E_PEX2_STN4_TX_DN<74>")
	)
	(segment
		(start 310.515762 -322.668392)
		(end 310.515762 -320.043556)
		(width 0.1651)
		(layer "In11.Cu")
		(net "P5E_PEX2_STN4_TX_DN<74>")
	)
	(segment
		(start 310.470042 -319.975738)
		(end 310.470042 -313.673744)
		(width 0.1143)
		(layer "In11.Cu")
		(net "P5E_PEX2_STN4_TX_DN<74>")
	)
	(segment
		(start 283.772102 -339.323934)
		(end 283.928058 -339.366098)
		(width 0.1651)
		(layer "In11.Cu")
		(net "P5E_PEX2_STN4_TX_DN<74>")
	)
	(segment
		(start 283.300678 -339.726778)
		(end 283.342842 -339.570822)
		(width 0.1651)
		(layer "In11.Cu")
		(net "P5E_PEX2_STN4_TX_DN<74>")
	)
	(segment
		(start 280.905712 -341.518748)
		(end 282.191206 -340.233254)
		(width 0.1651)
		(layer "In11.Cu")
		(net "P5E_PEX2_STN4_TX_DN<74>")
	)
	(segment
		(start 285.45663 -338.35467)
		(end 285.45663 -338.354924)
		(width 0.1651)
		(layer "In11.Cu")
		(net "P5E_PEX2_STN4_TX_DN<74>")
	)
	(segment
		(start 310.573674 -313.570112)
		(end 310.735472 -313.570112)
		(width 0.1143)
		(layer "In11.Cu")
		(net "P5E_PEX2_STN4_TX_DN<74>")
	)
	(segment
		(start 283.928058 -339.366098)
		(end 284.357826 -339.118956)
		(width 0.1651)
		(layer "In11.Cu")
		(net "P5E_PEX2_STN4_TX_DN<74>")
	)
	(segment
		(start 310.470042 -313.673744)
		(end 310.573674 -313.570112)
		(width 0.1143)
		(layer "In11.Cu")
		(net "P5E_PEX2_STN4_TX_DN<74>")
	)
	(segment
		(start 281.196542 -342.439498)
		(end 280.905712 -342.148668)
		(width 0.1651)
		(layer "In11.Cu")
		(net "P5E_PEX2_STN4_TX_DN<74>")
	)
	(segment
		(start 310.849772 -313.684412)
		(end 310.849772 -313.949842)
		(width 0.1143)
		(layer "In11.Cu")
		(net "P5E_PEX2_STN4_TX_DN<74>")
	)
	(segment
		(start 307.995574 -325.388986)
		(end 310.37403 -323.01053)
		(width 0.1651)
		(layer "In11.Cu")
		(net "P5E_PEX2_STN4_TX_DN<74>")
	)
	(segment
		(start 310.515762 -320.021458)
		(end 310.470042 -319.975738)
		(width 0.1143)
		(layer "In11.Cu")
		(net "P5E_PEX2_STN4_TX_DN<74>")
	)
	(segment
		(start 310.515762 -320.043556)
		(end 310.515762 -320.021458)
		(width 0.1143)
		(layer "In11.Cu")
		(net "P5E_PEX2_STN4_TX_DN<74>")
	)
	(segment
		(start 285.41472 -338.51088)
		(end 285.45663 -338.35467)
		(width 0.1651)
		(layer "In11.Cu")
		(net "P5E_PEX2_STN4_TX_DN<74>")
	)
	(segment
		(start 283.342842 -339.570822)
		(end 283.772102 -339.323934)
		(width 0.1651)
		(layer "In11.Cu")
		(net "P5E_PEX2_STN4_TX_DN<74>")
	)
	(segment
		(start 280.905712 -342.148668)
		(end 280.905712 -341.518748)
		(width 0.1651)
		(layer "In11.Cu")
		(net "P5E_PEX2_STN4_TX_DN<74>")
	)
	(segment
		(start 284.828996 -338.715858)
		(end 284.984952 -338.758022)
		(width 0.1651)
		(layer "In11.Cu")
		(net "P5E_PEX2_STN4_TX_DN<74>")
	)
	(segment
		(start 310.735472 -313.570112)
		(end 310.849772 -313.684412)
		(width 0.1143)
		(layer "In11.Cu")
		(net "P5E_PEX2_STN4_TX_DN<74>")
	)
	(segment
		(start 282.191206 -340.233254)
		(end 282.714954 -339.93201)
		(width 0.1651)
		(layer "In11.Cu")
		(net "P5E_PEX2_STN4_TX_DN<74>")
	)
	(segment
		(start 282.714954 -339.93201)
		(end 282.871164 -339.974174)
		(width 0.1651)
		(layer "In11.Cu")
		(net "P5E_PEX2_STN4_TX_DN<74>")
	)
	(segment
		(start 310.37403 -323.01053)
		(end 310.515762 -322.668392)
		(width 0.1651)
		(layer "In11.Cu")
		(net "P5E_PEX2_STN4_TX_DN<74>")
	)
	(segment
		(start 284.399736 -338.962746)
		(end 284.828996 -338.715858)
		(width 0.1651)
		(layer "In11.Cu")
		(net "P5E_PEX2_STN4_TX_DN<74>")
	)
	(segment
		(start 282.871164 -339.974174)
		(end 283.300678 -339.726778)
		(width 0.1651)
		(layer "In11.Cu")
		(net "P5E_PEX2_STN4_TX_DN<74>")
	)
	(segment
		(start 268.191742 -343.365582)
		(end 268.191742 -342.734138)
		(width 0.13462)
		(layer "F.Cu")
		(net "P5E_PEX2_STN4_TX_DP<79>")
	)
	(segment
		(start 267.871702 -343.685622)
		(end 268.191742 -343.365582)
		(width 0.13462)
		(layer "F.Cu")
		(net "P5E_PEX2_STN4_TX_DP<79>")
	)
	(segment
		(start 268.191742 -342.734138)
		(end 267.897102 -342.439498)
		(width 0.13462)
		(layer "F.Cu")
		(net "P5E_PEX2_STN4_TX_DP<79>")
	)
	(segment
		(start 305.483768 -320.644012)
		(end 305.126644 -321.001136)
		(width 0.1651)
		(layer "In11.Cu")
		(net "P5E_PEX2_STN4_TX_DP<79>")
	)
	(segment
		(start 305.744626 -311.479692)
		(end 305.529488 -311.69483)
		(width 0.1143)
		(layer "In11.Cu")
		(net "P5E_PEX2_STN4_TX_DP<79>")
	)
	(segment
		(start 268.187932 -342.148668)
		(end 267.897102 -342.439498)
		(width 0.1651)
		(layer "In11.Cu")
		(net "P5E_PEX2_STN4_TX_DP<79>")
	)
	(segment
		(start 305.985418 -311.479692)
		(end 305.744626 -311.479692)
		(width 0.1143)
		(layer "In11.Cu")
		(net "P5E_PEX2_STN4_TX_DP<79>")
	)
	(segment
		(start 306.099718 -311.365392)
		(end 305.985418 -311.479692)
		(width 0.1143)
		(layer "In11.Cu")
		(net "P5E_PEX2_STN4_TX_DP<79>")
	)
	(segment
		(start 305.483768 -320.090038)
		(end 305.483768 -320.644012)
		(width 0.1651)
		(layer "In11.Cu")
		(net "P5E_PEX2_STN4_TX_DP<79>")
	)
	(segment
		(start 305.126644 -321.001136)
		(end 269.145258 -340.335108)
		(width 0.1651)
		(layer "In11.Cu")
		(net "P5E_PEX2_STN4_TX_DP<79>")
	)
	(segment
		(start 306.099718 -311.099962)
		(end 306.099718 -311.365392)
		(width 0.1143)
		(layer "In11.Cu")
		(net "P5E_PEX2_STN4_TX_DP<79>")
	)
	(segment
		(start 305.529488 -311.69483)
		(end 305.529488 -320.02222)
		(width 0.1143)
		(layer "In11.Cu")
		(net "P5E_PEX2_STN4_TX_DP<79>")
	)
	(segment
		(start 305.483768 -320.06794)
		(end 305.483768 -320.090038)
		(width 0.1143)
		(layer "In11.Cu")
		(net "P5E_PEX2_STN4_TX_DP<79>")
	)
	(segment
		(start 268.187932 -341.292688)
		(end 268.187932 -342.148668)
		(width 0.1651)
		(layer "In11.Cu")
		(net "P5E_PEX2_STN4_TX_DP<79>")
	)
	(segment
		(start 305.529488 -320.02222)
		(end 305.483768 -320.06794)
		(width 0.1143)
		(layer "In11.Cu")
		(net "P5E_PEX2_STN4_TX_DP<79>")
	)
	(segment
		(start 269.145258 -340.335108)
		(end 268.187932 -341.292688)
		(width 0.1651)
		(layer "In11.Cu")
		(net "P5E_PEX2_STN4_TX_DP<79>")
	)
	(segment
		(start 280.307542 -355.978206)
		(end 280.627582 -355.658166)
		(width 0.13462)
		(layer "F.Cu")
		(net "P5E_PEX2_STN4_TX_DP<73>")
	)
	(segment
		(start 280.627582 -355.658166)
		(end 280.627582 -355.026722)
		(width 0.13462)
		(layer "F.Cu")
		(net "P5E_PEX2_STN4_TX_DP<73>")
	)
	(segment
		(start 280.627582 -355.026722)
		(end 280.332942 -354.732082)
		(width 0.13462)
		(layer "F.Cu")
		(net "P5E_PEX2_STN4_TX_DP<73>")
	)
	(segment
		(start 283.06649 -340.688676)
		(end 308.121812 -326.245474)
		(width 0.1651)
		(layer "In11.Cu")
		(net "P5E_PEX2_STN4_TX_DP<73>")
	)
	(segment
		(start 311.183782 -322.902834)
		(end 311.183782 -320.007996)
		(width 0.1651)
		(layer "In11.Cu")
		(net "P5E_PEX2_STN4_TX_DP<73>")
	)
	(segment
		(start 311.229502 -319.940178)
		(end 311.229502 -311.7342)
		(width 0.1143)
		(layer "In11.Cu")
		(net "P5E_PEX2_STN4_TX_DP<73>")
	)
	(segment
		(start 311.48401 -311.479692)
		(end 311.685432 -311.479692)
		(width 0.1143)
		(layer "In11.Cu")
		(net "P5E_PEX2_STN4_TX_DP<73>")
	)
	(segment
		(start 311.685432 -311.479692)
		(end 311.799732 -311.365392)
		(width 0.1143)
		(layer "In11.Cu")
		(net "P5E_PEX2_STN4_TX_DP<73>")
	)
	(segment
		(start 311.183782 -319.985898)
		(end 311.229502 -319.940178)
		(width 0.1143)
		(layer "In11.Cu")
		(net "P5E_PEX2_STN4_TX_DP<73>")
	)
	(segment
		(start 280.623772 -353.814126)
		(end 282.178252 -352.259646)
		(width 0.1651)
		(layer "In11.Cu")
		(net "P5E_PEX2_STN4_TX_DP<73>")
	)
	(segment
		(start 308.121812 -326.245474)
		(end 310.985154 -323.382386)
		(width 0.1651)
		(layer "In11.Cu")
		(net "P5E_PEX2_STN4_TX_DP<73>")
	)
	(segment
		(start 280.332942 -354.732082)
		(end 280.623772 -354.441252)
		(width 0.1651)
		(layer "In11.Cu")
		(net "P5E_PEX2_STN4_TX_DP<73>")
	)
	(segment
		(start 311.229502 -311.7342)
		(end 311.48401 -311.479692)
		(width 0.1143)
		(layer "In11.Cu")
		(net "P5E_PEX2_STN4_TX_DP<73>")
	)
	(segment
		(start 311.183782 -320.007996)
		(end 311.183782 -319.985898)
		(width 0.1143)
		(layer "In11.Cu")
		(net "P5E_PEX2_STN4_TX_DP<73>")
	)
	(segment
		(start 282.178252 -352.259646)
		(end 282.178252 -341.576914)
		(width 0.1651)
		(layer "In11.Cu")
		(net "P5E_PEX2_STN4_TX_DP<73>")
	)
	(segment
		(start 311.799732 -311.365392)
		(end 311.799732 -311.099962)
		(width 0.1143)
		(layer "In11.Cu")
		(net "P5E_PEX2_STN4_TX_DP<73>")
	)
	(segment
		(start 282.178252 -341.576914)
		(end 283.06649 -340.688676)
		(width 0.1651)
		(layer "In11.Cu")
		(net "P5E_PEX2_STN4_TX_DP<73>")
	)
	(segment
		(start 310.985154 -323.382386)
		(end 311.183782 -322.902834)
		(width 0.1651)
		(layer "In11.Cu")
		(net "P5E_PEX2_STN4_TX_DP<73>")
	)
	(segment
		(start 280.623772 -354.441252)
		(end 280.623772 -353.814126)
		(width 0.1651)
		(layer "In11.Cu")
		(net "P5E_PEX2_STN4_TX_DP<73>")
	)
	(segment
		(start 166.249858 -290.199826)
		(end 165.774878 -289.724846)
		(width 0.13208)
		(layer "F.Cu")
		(net "VDDA_SENSE")
	)
	(segment
		(start 282.349702 -290.199826)
		(end 281.874722 -289.724846)
		(width 0.13208)
		(layer "F.Cu")
		(net "VDDA_SENSE")
	)
	(segment
		(start 398.4498 -290.199826)
		(end 397.97482 -289.724846)
		(width 0.13208)
		(layer "F.Cu")
		(net "VDDA_SENSE")
	)
	(segment
		(start 50.14976 -290.199826)
		(end 49.67478 -289.724846)
		(width 0.13208)
		(layer "F.Cu")
		(net "VDDA_SENSE")
	)
	(via
		(at 389.118094 -266.915646)
		(size 0.508)
		(drill 0.254)
		(layers "F.Cu" "B.Cu")
		(net "VDDA_SENSE")
	)
	(via
		(at 281.874722 -289.724846)
		(size 0.4064)
		(drill 0.2032)
		(layers "F.Cu" "B.Cu")
		(net "VDDA_SENSE")
	)
	(via
		(at 40.799258 -267.604494)
		(size 0.508)
		(drill 0.254)
		(layers "F.Cu" "B.Cu")
		(net "VDDA_SENSE")
	)
	(via
		(at 165.774878 -289.724846)
		(size 0.4064)
		(drill 0.2032)
		(layers "F.Cu" "B.Cu")
		(net "VDDA_SENSE")
	)
	(via
		(at 397.97482 -289.724846)
		(size 0.4064)
		(drill 0.2032)
		(layers "F.Cu" "B.Cu")
		(net "VDDA_SENSE")
	)
	(via
		(at 49.67478 -289.724846)
		(size 0.4064)
		(drill 0.2032)
		(layers "F.Cu" "B.Cu")
		(net "VDDA_SENSE")
	)
	(via
		(at 157.855666 -261.742428)
		(size 0.508)
		(drill 0.254)
		(layers "F.Cu" "B.Cu")
		(net "VDDA_SENSE")
	)
	(via
		(at 274.29714 -265.497056)
		(size 0.508)
		(drill 0.254)
		(layers "F.Cu" "B.Cu")
		(net "VDDA_SENSE")
	)
	(segment
		(start 392.672824 -280.233374)
		(end 391.799826 -279.360376)
		(width 0.13208)
		(layer "B.Cu")
		(net "VDDA_SENSE")
	)
	(segment
		(start 277.093426 -281.0764)
		(end 277.093426 -280.448258)
		(width 0.13208)
		(layer "B.Cu")
		(net "VDDA_SENSE")
	)
	(segment
		(start 393.1666 -280.360374)
		(end 393.0396 -280.233374)
		(width 0.13208)
		(layer "B.Cu")
		(net "VDDA_SENSE")
	)
	(segment
		(start 389.715756 -266.915646)
		(end 389.118094 -266.915646)
		(width 0.13208)
		(layer "B.Cu")
		(net "VDDA_SENSE")
	)
	(segment
		(start 396.914116 -281.2034)
		(end 393.3952 -281.2034)
		(width 0.13208)
		(layer "B.Cu")
		(net "VDDA_SENSE")
	)
	(segment
		(start 164.739574 -281.2288)
		(end 161.205926 -281.2288)
		(width 0.13208)
		(layer "B.Cu")
		(net "VDDA_SENSE")
	)
	(segment
		(start 44.0182 -277.1648)
		(end 44.2722 -277.4188)
		(width 0.13208)
		(layer "B.Cu")
		(net "VDDA_SENSE")
	)
	(segment
		(start 277.093426 -280.448258)
		(end 276.928326 -280.283158)
		(width 0.13208)
		(layer "B.Cu")
		(net "VDDA_SENSE")
	)
	(segment
		(start 397.110458 -281.399742)
		(end 396.914116 -281.2034)
		(width 0.13208)
		(layer "B.Cu")
		(net "VDDA_SENSE")
	)
	(segment
		(start 393.0396 -280.233374)
		(end 392.672824 -280.233374)
		(width 0.13208)
		(layer "B.Cu")
		(net "VDDA_SENSE")
	)
	(segment
		(start 165.299898 -282.723844)
		(end 164.8968 -282.320746)
		(width 0.13208)
		(layer "B.Cu")
		(net "VDDA_SENSE")
	)
	(segment
		(start 397.97482 -289.433)
		(end 398.362424 -289.045396)
		(width 0.13208)
		(layer "B.Cu")
		(net "VDDA_SENSE")
	)
	(segment
		(start 281.399742 -287.067498)
		(end 281.399742 -282.829)
		(width 0.13208)
		(layer "B.Cu")
		(net "VDDA_SENSE")
	)
	(segment
		(start 282.262326 -289.045396)
		(end 282.262326 -287.499044)
		(width 0.13208)
		(layer "B.Cu")
		(net "VDDA_SENSE")
	)
	(segment
		(start 49.1998 -282.575)
		(end 49.1998 -287.071054)
		(width 0.13208)
		(layer "B.Cu")
		(net "VDDA_SENSE")
	)
	(segment
		(start 397.97482 -289.724846)
		(end 397.97482 -289.433)
		(width 0.13208)
		(layer "B.Cu")
		(net "VDDA_SENSE")
	)
	(segment
		(start 275.699728 -266.899644)
		(end 274.29714 -265.497056)
		(width 0.13208)
		(layer "B.Cu")
		(net "VDDA_SENSE")
	)
	(segment
		(start 281.874722 -289.724846)
		(end 281.874722 -289.433)
		(width 0.13208)
		(layer "B.Cu")
		(net "VDDA_SENSE")
	)
	(segment
		(start 50.0888 -287.553654)
		(end 50.0888 -289.310826)
		(width 0.13208)
		(layer "B.Cu")
		(net "VDDA_SENSE")
	)
	(segment
		(start 44.2722 -277.4188)
		(end 48.4124 -277.4188)
		(width 0.13208)
		(layer "B.Cu")
		(net "VDDA_SENSE")
	)
	(segment
		(start 281.399742 -282.829)
		(end 280.8986 -282.327858)
		(width 0.13208)
		(layer "B.Cu")
		(net "VDDA_SENSE")
	)
	(segment
		(start 393.1666 -280.9748)
		(end 393.1666 -280.360374)
		(width 0.13208)
		(layer "B.Cu")
		(net "VDDA_SENSE")
	)
	(segment
		(start 277.220426 -281.2034)
		(end 277.093426 -281.0764)
		(width 0.13208)
		(layer "B.Cu")
		(net "VDDA_SENSE")
	)
	(segment
		(start 275.699728 -279.858978)
		(end 275.699728 -266.899644)
		(width 0.13208)
		(layer "B.Cu")
		(net "VDDA_SENSE")
	)
	(segment
		(start 49.870614 -287.335468)
		(end 50.0888 -287.553654)
		(width 0.13208)
		(layer "B.Cu")
		(net "VDDA_SENSE")
	)
	(segment
		(start 43.499786 -271.78)
		(end 44.0182 -272.298414)
		(width 0.13208)
		(layer "B.Cu")
		(net "VDDA_SENSE")
	)
	(segment
		(start 164.8968 -281.386026)
		(end 164.739574 -281.2288)
		(width 0.13208)
		(layer "B.Cu")
		(net "VDDA_SENSE")
	)
	(segment
		(start 165.567868 -287.335468)
		(end 165.299898 -287.067498)
		(width 0.13208)
		(layer "B.Cu")
		(net "VDDA_SENSE")
	)
	(segment
		(start 41.556432 -267.604494)
		(end 43.499786 -269.547848)
		(width 0.13208)
		(layer "B.Cu")
		(net "VDDA_SENSE")
	)
	(segment
		(start 50.0888 -289.310826)
		(end 49.67478 -289.724846)
		(width 0.13208)
		(layer "B.Cu")
		(net "VDDA_SENSE")
	)
	(segment
		(start 49.464214 -287.335468)
		(end 49.870614 -287.335468)
		(width 0.13208)
		(layer "B.Cu")
		(net "VDDA_SENSE")
	)
	(segment
		(start 282.262326 -287.499044)
		(end 282.09875 -287.335468)
		(width 0.13208)
		(layer "B.Cu")
		(net "VDDA_SENSE")
	)
	(segment
		(start 397.76781 -287.335468)
		(end 397.49984 -287.067498)
		(width 0.13208)
		(layer "B.Cu")
		(net "VDDA_SENSE")
	)
	(segment
		(start 276.123908 -280.283158)
		(end 275.699728 -279.858978)
		(width 0.13208)
		(layer "B.Cu")
		(net "VDDA_SENSE")
	)
	(segment
		(start 398.362424 -289.045396)
		(end 398.362424 -287.499044)
		(width 0.13208)
		(layer "B.Cu")
		(net "VDDA_SENSE")
	)
	(segment
		(start 398.198848 -287.335468)
		(end 397.76781 -287.335468)
		(width 0.13208)
		(layer "B.Cu")
		(net "VDDA_SENSE")
	)
	(segment
		(start 48.7172 -282.0924)
		(end 49.1998 -282.575)
		(width 0.13208)
		(layer "B.Cu")
		(net "VDDA_SENSE")
	)
	(segment
		(start 398.362424 -287.499044)
		(end 398.198848 -287.335468)
		(width 0.13208)
		(layer "B.Cu")
		(net "VDDA_SENSE")
	)
	(segment
		(start 165.774878 -289.724846)
		(end 165.774878 -289.433)
		(width 0.13208)
		(layer "B.Cu")
		(net "VDDA_SENSE")
	)
	(segment
		(start 48.4124 -277.4188)
		(end 48.7172 -277.7236)
		(width 0.13208)
		(layer "B.Cu")
		(net "VDDA_SENSE")
	)
	(segment
		(start 40.799258 -267.604494)
		(end 41.556432 -267.604494)
		(width 0.13208)
		(layer "B.Cu")
		(net "VDDA_SENSE")
	)
	(segment
		(start 161.036 -264.922762)
		(end 157.855666 -261.742428)
		(width 0.13208)
		(layer "B.Cu")
		(net "VDDA_SENSE")
	)
	(segment
		(start 161.036 -281.058874)
		(end 161.036 -264.922762)
		(width 0.13208)
		(layer "B.Cu")
		(net "VDDA_SENSE")
	)
	(segment
		(start 165.998906 -287.335468)
		(end 165.567868 -287.335468)
		(width 0.13208)
		(layer "B.Cu")
		(net "VDDA_SENSE")
	)
	(segment
		(start 43.499786 -269.547848)
		(end 43.499786 -271.78)
		(width 0.13208)
		(layer "B.Cu")
		(net "VDDA_SENSE")
	)
	(segment
		(start 166.162482 -289.045396)
		(end 166.162482 -287.499044)
		(width 0.13208)
		(layer "B.Cu")
		(net "VDDA_SENSE")
	)
	(segment
		(start 44.0182 -272.298414)
		(end 44.0182 -277.1648)
		(width 0.13208)
		(layer "B.Cu")
		(net "VDDA_SENSE")
	)
	(segment
		(start 280.7716 -281.2034)
		(end 277.220426 -281.2034)
		(width 0.13208)
		(layer "B.Cu")
		(net "VDDA_SENSE")
	)
	(segment
		(start 397.110458 -282.302458)
		(end 397.110458 -281.399742)
		(width 0.13208)
		(layer "B.Cu")
		(net "VDDA_SENSE")
	)
	(segment
		(start 391.799826 -268.999716)
		(end 389.715756 -266.915646)
		(width 0.13208)
		(layer "B.Cu")
		(net "VDDA_SENSE")
	)
	(segment
		(start 397.49984 -287.067498)
		(end 397.49984 -282.69184)
		(width 0.13208)
		(layer "B.Cu")
		(net "VDDA_SENSE")
	)
	(segment
		(start 281.874722 -289.433)
		(end 282.262326 -289.045396)
		(width 0.13208)
		(layer "B.Cu")
		(net "VDDA_SENSE")
	)
	(segment
		(start 280.8986 -282.327858)
		(end 280.8986 -281.3304)
		(width 0.13208)
		(layer "B.Cu")
		(net "VDDA_SENSE")
	)
	(segment
		(start 276.928326 -280.283158)
		(end 276.123908 -280.283158)
		(width 0.13208)
		(layer "B.Cu")
		(net "VDDA_SENSE")
	)
	(segment
		(start 282.09875 -287.335468)
		(end 281.667712 -287.335468)
		(width 0.13208)
		(layer "B.Cu")
		(net "VDDA_SENSE")
	)
	(segment
		(start 164.8968 -282.320746)
		(end 164.8968 -281.386026)
		(width 0.13208)
		(layer "B.Cu")
		(net "VDDA_SENSE")
	)
	(segment
		(start 397.49984 -282.69184)
		(end 397.110458 -282.302458)
		(width 0.13208)
		(layer "B.Cu")
		(net "VDDA_SENSE")
	)
	(segment
		(start 165.299898 -287.067498)
		(end 165.299898 -282.723844)
		(width 0.13208)
		(layer "B.Cu")
		(net "VDDA_SENSE")
	)
	(segment
		(start 166.162482 -287.499044)
		(end 165.998906 -287.335468)
		(width 0.13208)
		(layer "B.Cu")
		(net "VDDA_SENSE")
	)
	(segment
		(start 48.7172 -277.7236)
		(end 48.7172 -282.0924)
		(width 0.13208)
		(layer "B.Cu")
		(net "VDDA_SENSE")
	)
	(segment
		(start 281.667712 -287.335468)
		(end 281.399742 -287.067498)
		(width 0.13208)
		(layer "B.Cu")
		(net "VDDA_SENSE")
	)
	(segment
		(start 391.799826 -279.360376)
		(end 391.799826 -268.999716)
		(width 0.13208)
		(layer "B.Cu")
		(net "VDDA_SENSE")
	)
	(segment
		(start 161.205926 -281.2288)
		(end 161.036 -281.058874)
		(width 0.13208)
		(layer "B.Cu")
		(net "VDDA_SENSE")
	)
	(segment
		(start 393.3952 -281.2034)
		(end 393.1666 -280.9748)
		(width 0.13208)
		(layer "B.Cu")
		(net "VDDA_SENSE")
	)
	(segment
		(start 280.8986 -281.3304)
		(end 280.7716 -281.2034)
		(width 0.13208)
		(layer "B.Cu")
		(net "VDDA_SENSE")
	)
	(segment
		(start 49.1998 -287.071054)
		(end 49.464214 -287.335468)
		(width 0.13208)
		(layer "B.Cu")
		(net "VDDA_SENSE")
	)
	(segment
		(start 165.774878 -289.433)
		(end 166.162482 -289.045396)
		(width 0.13208)
		(layer "B.Cu")
		(net "VDDA_SENSE")
	)
	(segment
		(start 313.671204 -262.066786)
		(end 319.34785 -262.066786)
		(width 0.15494)
		(layer "In13.Cu")
		(net "VDDA_SENSE")
	)
	(segment
		(start 159.498792 -258.122166)
		(end 159.478472 -258.142486)
		(width 0.15494)
		(layer "In13.Cu")
		(net "VDDA_SENSE")
	)
	(segment
		(start 384.029458 -263.462262)
		(end 386.682996 -266.1158)
		(width 0.15494)
		(layer "In13.Cu")
		(net "VDDA_SENSE")
	)
	(segment
		(start 275.106638 -265.497056)
		(end 279.473914 -261.12978)
		(width 0.15494)
		(layer "In13.Cu")
		(net "VDDA_SENSE")
	)
	(segment
		(start 112.534192 -245.783354)
		(end 137.437114 -245.783354)
		(width 0.15494)
		(layer "In13.Cu")
		(net "VDDA_SENSE")
	)
	(segment
		(start 157.451552 -247.342152)
		(end 159.498792 -249.389392)
		(width 0.15494)
		(layer "In13.Cu")
		(net "VDDA_SENSE")
	)
	(segment
		(start 274.29714 -265.497056)
		(end 270.891762 -265.497056)
		(width 0.15494)
		(layer "In13.Cu")
		(net "VDDA_SENSE")
	)
	(segment
		(start 370.766086 -263.462262)
		(end 384.029458 -263.462262)
		(width 0.15494)
		(layer "In13.Cu")
		(net "VDDA_SENSE")
	)
	(segment
		(start 162.776662 -261.742428)
		(end 157.855666 -261.742428)
		(width 0.15494)
		(layer "In13.Cu")
		(net "VDDA_SENSE")
	)
	(segment
		(start 266.967208 -263.790684)
		(end 252.46584 -263.790684)
		(width 0.15494)
		(layer "In13.Cu")
		(net "VDDA_SENSE")
	)
	(segment
		(start 350.063054 -250.7996)
		(end 353.796346 -250.7996)
		(width 0.15494)
		(layer "In13.Cu")
		(net "VDDA_SENSE")
	)
	(segment
		(start 355.371146 -249.2248)
		(end 362.700062 -249.2248)
		(width 0.15494)
		(layer "In13.Cu")
		(net "VDDA_SENSE")
	)
	(segment
		(start 231.180132 -255.914906)
		(end 230.359966 -255.09474)
		(width 0.15494)
		(layer "In13.Cu")
		(net "VDDA_SENSE")
	)
	(segment
		(start 138.67257 -247.01881)
		(end 149.661626 -247.01881)
		(width 0.15494)
		(layer "In13.Cu")
		(net "VDDA_SENSE")
	)
	(segment
		(start 41.615868 -267.604494)
		(end 49.216564 -260.003798)
		(width 0.15494)
		(layer "In13.Cu")
		(net "VDDA_SENSE")
	)
	(segment
		(start 340.562946 -259.3848)
		(end 346.328746 -253.619)
		(width 0.15494)
		(layer "In13.Cu")
		(net "VDDA_SENSE")
	)
	(segment
		(start 319.36817 -262.046466)
		(end 319.438528 -262.046466)
		(width 0.15494)
		(layer "In13.Cu")
		(net "VDDA_SENSE")
	)
	(segment
		(start 209.856324 -256.3368)
		(end 168.18229 -256.3368)
		(width 0.15494)
		(layer "In13.Cu")
		(net "VDDA_SENSE")
	)
	(segment
		(start 319.34785 -262.066786)
		(end 319.36817 -262.046466)
		(width 0.15494)
		(layer "In13.Cu")
		(net "VDDA_SENSE")
	)
	(segment
		(start 220.617542 -255.09474)
		(end 219.984574 -254.461772)
		(width 0.15494)
		(layer "In13.Cu")
		(net "VDDA_SENSE")
	)
	(segment
		(start 319.438528 -262.046466)
		(end 320.328544 -261.15645)
		(width 0.15494)
		(layer "In13.Cu")
		(net "VDDA_SENSE")
	)
	(segment
		(start 270.891762 -265.497056)
		(end 268.843506 -263.4488)
		(width 0.15494)
		(layer "In13.Cu")
		(net "VDDA_SENSE")
	)
	(segment
		(start 369.022122 -255.54686)
		(end 369.022122 -261.718298)
		(width 0.15494)
		(layer "In13.Cu")
		(net "VDDA_SENSE")
	)
	(segment
		(start 252.46584 -263.790684)
		(end 244.590062 -255.914906)
		(width 0.15494)
		(layer "In13.Cu")
		(net "VDDA_SENSE")
	)
	(segment
		(start 268.843506 -263.4488)
		(end 267.309092 -263.4488)
		(width 0.15494)
		(layer "In13.Cu")
		(net "VDDA_SENSE")
	)
	(segment
		(start 40.799258 -267.604494)
		(end 41.615868 -267.604494)
		(width 0.15494)
		(layer "In13.Cu")
		(net "VDDA_SENSE")
	)
	(segment
		(start 159.498792 -249.389392)
		(end 159.498792 -258.122166)
		(width 0.15494)
		(layer "In13.Cu")
		(net "VDDA_SENSE")
	)
	(segment
		(start 369.022122 -261.718298)
		(end 370.766086 -263.462262)
		(width 0.15494)
		(layer "In13.Cu")
		(net "VDDA_SENSE")
	)
	(segment
		(start 159.478472 -258.475734)
		(end 157.855666 -260.09854)
		(width 0.15494)
		(layer "In13.Cu")
		(net "VDDA_SENSE")
	)
	(segment
		(start 149.984968 -247.342152)
		(end 157.451552 -247.342152)
		(width 0.15494)
		(layer "In13.Cu")
		(net "VDDA_SENSE")
	)
	(segment
		(start 168.18229 -256.3368)
		(end 162.776662 -261.742428)
		(width 0.15494)
		(layer "In13.Cu")
		(net "VDDA_SENSE")
	)
	(segment
		(start 312.03519 -263.7028)
		(end 313.671204 -262.066786)
		(width 0.15494)
		(layer "In13.Cu")
		(net "VDDA_SENSE")
	)
	(segment
		(start 388.505446 -266.915646)
		(end 389.118094 -266.915646)
		(width 0.15494)
		(layer "In13.Cu")
		(net "VDDA_SENSE")
	)
	(segment
		(start 157.855666 -260.09854)
		(end 157.855666 -261.742428)
		(width 0.15494)
		(layer "In13.Cu")
		(net "VDDA_SENSE")
	)
	(segment
		(start 332.896972 -261.15645)
		(end 334.668622 -259.3848)
		(width 0.15494)
		(layer "In13.Cu")
		(net "VDDA_SENSE")
	)
	(segment
		(start 320.328544 -261.15645)
		(end 332.896972 -261.15645)
		(width 0.15494)
		(layer "In13.Cu")
		(net "VDDA_SENSE")
	)
	(segment
		(start 299.999146 -263.7028)
		(end 312.03519 -263.7028)
		(width 0.15494)
		(layer "In13.Cu")
		(net "VDDA_SENSE")
	)
	(segment
		(start 219.984574 -254.461772)
		(end 211.731352 -254.461772)
		(width 0.15494)
		(layer "In13.Cu")
		(net "VDDA_SENSE")
	)
	(segment
		(start 98.313748 -260.003798)
		(end 112.534192 -245.783354)
		(width 0.15494)
		(layer "In13.Cu")
		(net "VDDA_SENSE")
	)
	(segment
		(start 387.7056 -266.1158)
		(end 388.505446 -266.915646)
		(width 0.15494)
		(layer "In13.Cu")
		(net "VDDA_SENSE")
	)
	(segment
		(start 230.359966 -255.09474)
		(end 220.617542 -255.09474)
		(width 0.15494)
		(layer "In13.Cu")
		(net "VDDA_SENSE")
	)
	(segment
		(start 211.731352 -254.461772)
		(end 209.856324 -256.3368)
		(width 0.15494)
		(layer "In13.Cu")
		(net "VDDA_SENSE")
	)
	(segment
		(start 347.243654 -253.619)
		(end 350.063054 -250.7996)
		(width 0.15494)
		(layer "In13.Cu")
		(net "VDDA_SENSE")
	)
	(segment
		(start 334.668622 -259.3848)
		(end 340.562946 -259.3848)
		(width 0.15494)
		(layer "In13.Cu")
		(net "VDDA_SENSE")
	)
	(segment
		(start 137.437114 -245.783354)
		(end 138.67257 -247.01881)
		(width 0.15494)
		(layer "In13.Cu")
		(net "VDDA_SENSE")
	)
	(segment
		(start 279.473914 -261.12978)
		(end 297.426126 -261.12978)
		(width 0.15494)
		(layer "In13.Cu")
		(net "VDDA_SENSE")
	)
	(segment
		(start 346.328746 -253.619)
		(end 347.243654 -253.619)
		(width 0.15494)
		(layer "In13.Cu")
		(net "VDDA_SENSE")
	)
	(segment
		(start 353.796346 -250.7996)
		(end 355.371146 -249.2248)
		(width 0.15494)
		(layer "In13.Cu")
		(net "VDDA_SENSE")
	)
	(segment
		(start 297.426126 -261.12978)
		(end 299.999146 -263.7028)
		(width 0.15494)
		(layer "In13.Cu")
		(net "VDDA_SENSE")
	)
	(segment
		(start 49.216564 -260.003798)
		(end 98.313748 -260.003798)
		(width 0.15494)
		(layer "In13.Cu")
		(net "VDDA_SENSE")
	)
	(segment
		(start 274.29714 -265.497056)
		(end 275.106638 -265.497056)
		(width 0.15494)
		(layer "In13.Cu")
		(net "VDDA_SENSE")
	)
	(segment
		(start 159.478472 -258.142486)
		(end 159.478472 -258.475734)
		(width 0.15494)
		(layer "In13.Cu")
		(net "VDDA_SENSE")
	)
	(segment
		(start 267.309092 -263.4488)
		(end 266.967208 -263.790684)
		(width 0.15494)
		(layer "In13.Cu")
		(net "VDDA_SENSE")
	)
	(segment
		(start 244.590062 -255.914906)
		(end 231.180132 -255.914906)
		(width 0.15494)
		(layer "In13.Cu")
		(net "VDDA_SENSE")
	)
	(segment
		(start 386.682996 -266.1158)
		(end 387.7056 -266.1158)
		(width 0.15494)
		(layer "In13.Cu")
		(net "VDDA_SENSE")
	)
	(segment
		(start 149.661626 -247.01881)
		(end 149.984968 -247.342152)
		(width 0.15494)
		(layer "In13.Cu")
		(net "VDDA_SENSE")
	)
	(segment
		(start 362.700062 -249.2248)
		(end 369.022122 -255.54686)
		(width 0.15494)
		(layer "In13.Cu")
		(net "VDDA_SENSE")
	)
	(segment
		(start 293.337742 -355.026722)
		(end 293.632382 -354.732082)
		(width 0.13462)
		(layer "F.Cu")
		(net "P5E_PEX2_STN4_TX_DN<67>")
	)
	(segment
		(start 293.657782 -355.978206)
		(end 293.337742 -355.658166)
		(width 0.13462)
		(layer "F.Cu")
		(net "P5E_PEX2_STN4_TX_DN<67>")
	)
	(segment
		(start 293.337742 -355.658166)
		(end 293.337742 -355.026722)
		(width 0.13462)
		(layer "F.Cu")
		(net "P5E_PEX2_STN4_TX_DN<67>")
	)
	(segment
		(start 295.439338 -341.292688)
		(end 296.518076 -340.555072)
		(width 0.1651)
		(layer "In11.Cu")
		(net "P5E_PEX2_STN4_TX_DN<67>")
	)
	(segment
		(start 315.902848 -307.633878)
		(end 315.8744 -307.633878)
		(width 0.1143)
		(layer "In11.Cu")
		(net "P5E_PEX2_STN4_TX_DN<67>")
	)
	(segment
		(start 317.190374 -307.843174)
		(end 316.13856 -307.633878)
		(width 0.1651)
		(layer "In11.Cu")
		(net "P5E_PEX2_STN4_TX_DN<67>")
	)
	(segment
		(start 309.53075 -307.565298)
		(end 309.53075 -307.4035)
		(width 0.1143)
		(layer "In11.Cu")
		(net "P5E_PEX2_STN4_TX_DN<67>")
	)
	(segment
		(start 326.007222 -314.833762)
		(end 322.889626 -313.542426)
		(width 0.1651)
		(layer "In11.Cu")
		(net "P5E_PEX2_STN4_TX_DN<67>")
	)
	(segment
		(start 325.742554 -327.729088)
		(end 327.54951 -325.855076)
		(width 0.1651)
		(layer "In11.Cu")
		(net "P5E_PEX2_STN4_TX_DN<67>")
	)
	(segment
		(start 295.439338 -341.292434)
		(end 295.439338 -341.292688)
		(width 0.1651)
		(layer "In11.Cu")
		(net "P5E_PEX2_STN4_TX_DN<67>")
	)
	(segment
		(start 293.341552 -353.930966)
		(end 294.896032 -352.376486)
		(width 0.1651)
		(layer "In11.Cu")
		(net "P5E_PEX2_STN4_TX_DN<67>")
	)
	(segment
		(start 296.518076 -340.555072)
		(end 325.742554 -327.729088)
		(width 0.1651)
		(layer "In11.Cu")
		(net "P5E_PEX2_STN4_TX_DN<67>")
	)
	(segment
		(start 329.25766 -322.49237)
		(end 329.25766 -319.640458)
		(width 0.1651)
		(layer "In11.Cu")
		(net "P5E_PEX2_STN4_TX_DN<67>")
	)
	(segment
		(start 315.8744 -307.633878)
		(end 315.82868 -307.679598)
		(width 0.1143)
		(layer "In11.Cu")
		(net "P5E_PEX2_STN4_TX_DN<67>")
	)
	(segment
		(start 322.889626 -313.542426)
		(end 317.190374 -307.843174)
		(width 0.1651)
		(layer "In11.Cu")
		(net "P5E_PEX2_STN4_TX_DN<67>")
	)
	(segment
		(start 309.64505 -307.679598)
		(end 309.53075 -307.565298)
		(width 0.1143)
		(layer "In11.Cu")
		(net "P5E_PEX2_STN4_TX_DN<67>")
	)
	(segment
		(start 315.82868 -307.679598)
		(end 309.64505 -307.679598)
		(width 0.1143)
		(layer "In11.Cu")
		(net "P5E_PEX2_STN4_TX_DN<67>")
	)
	(segment
		(start 329.25766 -319.640458)
		(end 328.157078 -316.983618)
		(width 0.1651)
		(layer "In11.Cu")
		(net "P5E_PEX2_STN4_TX_DN<67>")
	)
	(segment
		(start 316.13856 -307.633878)
		(end 315.902848 -307.633878)
		(width 0.1651)
		(layer "In11.Cu")
		(net "P5E_PEX2_STN4_TX_DN<67>")
	)
	(segment
		(start 328.157078 -316.983618)
		(end 326.007222 -314.833762)
		(width 0.1651)
		(layer "In11.Cu")
		(net "P5E_PEX2_STN4_TX_DN<67>")
	)
	(segment
		(start 327.54951 -325.855076)
		(end 329.25766 -322.49237)
		(width 0.1651)
		(layer "In11.Cu")
		(net "P5E_PEX2_STN4_TX_DN<67>")
	)
	(segment
		(start 293.632382 -354.732082)
		(end 293.341552 -354.441252)
		(width 0.1651)
		(layer "In11.Cu")
		(net "P5E_PEX2_STN4_TX_DN<67>")
	)
	(segment
		(start 295.102026 -341.52332)
		(end 295.439338 -341.292434)
		(width 0.1651)
		(layer "In11.Cu")
		(net "P5E_PEX2_STN4_TX_DN<67>")
	)
	(segment
		(start 309.634382 -307.299868)
		(end 309.899812 -307.299868)
		(width 0.1143)
		(layer "In11.Cu")
		(net "P5E_PEX2_STN4_TX_DN<67>")
	)
	(segment
		(start 294.896032 -352.376486)
		(end 294.896032 -341.913464)
		(width 0.1651)
		(layer "In11.Cu")
		(net "P5E_PEX2_STN4_TX_DN<67>")
	)
	(segment
		(start 309.53075 -307.4035)
		(end 309.634382 -307.299868)
		(width 0.1143)
		(layer "In11.Cu")
		(net "P5E_PEX2_STN4_TX_DN<67>")
	)
	(segment
		(start 294.896032 -341.913464)
		(end 295.102026 -341.52332)
		(width 0.1651)
		(layer "In11.Cu")
		(net "P5E_PEX2_STN4_TX_DN<67>")
	)
	(segment
		(start 293.341552 -354.441252)
		(end 293.341552 -353.930966)
		(width 0.1651)
		(layer "In11.Cu")
		(net "P5E_PEX2_STN4_TX_DN<67>")
	)
	(segment
		(start 268.786102 -343.685622)
		(end 268.466062 -343.365582)
		(width 0.13462)
		(layer "F.Cu")
		(net "P5E_PEX2_STN4_TX_DN<79>")
	)
	(segment
		(start 268.466062 -343.365582)
		(end 268.466062 -342.734138)
		(width 0.13462)
		(layer "F.Cu")
		(net "P5E_PEX2_STN4_TX_DN<79>")
	)
	(segment
		(start 268.466062 -342.734138)
		(end 268.760702 -342.439498)
		(width 0.13462)
		(layer "F.Cu")
		(net "P5E_PEX2_STN4_TX_DN<79>")
	)
	(segment
		(start 305.719988 -320.02222)
		(end 305.719988 -311.773824)
		(width 0.1143)
		(layer "In11.Cu")
		(net "P5E_PEX2_STN4_TX_DN<79>")
	)
	(segment
		(start 305.296824 -321.22999)
		(end 305.765708 -320.760852)
		(width 0.1651)
		(layer "In11.Cu")
		(net "P5E_PEX2_STN4_TX_DN<79>")
	)
	(segment
		(start 268.469872 -342.148668)
		(end 268.469872 -341.409528)
		(width 0.1651)
		(layer "In11.Cu")
		(net "P5E_PEX2_STN4_TX_DN<79>")
	)
	(segment
		(start 305.765708 -320.090038)
		(end 305.765708 -320.06794)
		(width 0.1143)
		(layer "In11.Cu")
		(net "P5E_PEX2_STN4_TX_DN<79>")
	)
	(segment
		(start 272.537936 -338.832698)
		(end 305.296824 -321.22999)
		(width 0.1651)
		(layer "In11.Cu")
		(net "P5E_PEX2_STN4_TX_DN<79>")
	)
	(segment
		(start 269.906496 -340.376256)
		(end 270.342868 -340.14156)
		(width 0.1651)
		(layer "In11.Cu")
		(net "P5E_PEX2_STN4_TX_DN<79>")
	)
	(segment
		(start 268.760702 -342.439498)
		(end 268.469872 -342.148668)
		(width 0.1651)
		(layer "In11.Cu")
		(net "P5E_PEX2_STN4_TX_DN<79>")
	)
	(segment
		(start 306.099718 -311.784492)
		(end 306.099718 -312.049922)
		(width 0.1143)
		(layer "In11.Cu")
		(net "P5E_PEX2_STN4_TX_DN<79>")
	)
	(segment
		(start 268.469872 -341.409528)
		(end 269.315438 -340.563962)
		(width 0.1651)
		(layer "In11.Cu")
		(net "P5E_PEX2_STN4_TX_DN<79>")
	)
	(segment
		(start 305.765708 -320.06794)
		(end 305.719988 -320.02222)
		(width 0.1143)
		(layer "In11.Cu")
		(net "P5E_PEX2_STN4_TX_DN<79>")
	)
	(segment
		(start 270.825722 -339.752686)
		(end 270.980662 -339.799168)
		(width 0.1651)
		(layer "In11.Cu")
		(net "P5E_PEX2_STN4_TX_DN<79>")
	)
	(segment
		(start 305.765708 -320.760852)
		(end 305.765708 -320.090038)
		(width 0.1651)
		(layer "In11.Cu")
		(net "P5E_PEX2_STN4_TX_DN<79>")
	)
	(segment
		(start 271.899888 -339.175598)
		(end 272.054828 -339.22208)
		(width 0.1651)
		(layer "In11.Cu")
		(net "P5E_PEX2_STN4_TX_DN<79>")
	)
	(segment
		(start 271.46377 -339.409786)
		(end 271.899888 -339.175598)
		(width 0.1651)
		(layer "In11.Cu")
		(net "P5E_PEX2_STN4_TX_DN<79>")
	)
	(segment
		(start 270.980662 -339.799168)
		(end 271.417034 -339.564472)
		(width 0.1651)
		(layer "In11.Cu")
		(net "P5E_PEX2_STN4_TX_DN<79>")
	)
	(segment
		(start 269.751556 -340.329774)
		(end 269.906496 -340.376256)
		(width 0.1651)
		(layer "In11.Cu")
		(net "P5E_PEX2_STN4_TX_DN<79>")
	)
	(segment
		(start 271.417034 -339.564472)
		(end 271.46377 -339.409786)
		(width 0.1651)
		(layer "In11.Cu")
		(net "P5E_PEX2_STN4_TX_DN<79>")
	)
	(segment
		(start 269.315438 -340.563962)
		(end 269.751556 -340.329774)
		(width 0.1651)
		(layer "In11.Cu")
		(net "P5E_PEX2_STN4_TX_DN<79>")
	)
	(segment
		(start 272.054828 -339.22208)
		(end 272.4912 -338.987384)
		(width 0.1651)
		(layer "In11.Cu")
		(net "P5E_PEX2_STN4_TX_DN<79>")
	)
	(segment
		(start 270.342868 -340.14156)
		(end 270.389604 -339.986874)
		(width 0.1651)
		(layer "In11.Cu")
		(net "P5E_PEX2_STN4_TX_DN<79>")
	)
	(segment
		(start 305.985418 -311.670192)
		(end 306.099718 -311.784492)
		(width 0.1143)
		(layer "In11.Cu")
		(net "P5E_PEX2_STN4_TX_DN<79>")
	)
	(segment
		(start 305.719988 -311.773824)
		(end 305.82362 -311.670192)
		(width 0.1143)
		(layer "In11.Cu")
		(net "P5E_PEX2_STN4_TX_DN<79>")
	)
	(segment
		(start 305.82362 -311.670192)
		(end 305.985418 -311.670192)
		(width 0.1143)
		(layer "In11.Cu")
		(net "P5E_PEX2_STN4_TX_DN<79>")
	)
	(segment
		(start 272.4912 -338.987384)
		(end 272.537936 -338.832698)
		(width 0.1651)
		(layer "In11.Cu")
		(net "P5E_PEX2_STN4_TX_DN<79>")
	)
	(segment
		(start 270.389604 -339.986874)
		(end 270.825722 -339.752686)
		(width 0.1651)
		(layer "In11.Cu")
		(net "P5E_PEX2_STN4_TX_DN<79>")
	)
	(segment
		(start 271.300702 -349.511874)
		(end 271.300702 -348.88043)
		(width 0.13462)
		(layer "F.Cu")
		(net "P5E_PEX2_STN4_TX_DP<78>")
	)
	(segment
		(start 270.980662 -349.831914)
		(end 271.300702 -349.511874)
		(width 0.13462)
		(layer "F.Cu")
		(net "P5E_PEX2_STN4_TX_DP<78>")
	)
	(segment
		(start 271.300702 -348.88043)
		(end 271.006062 -348.58579)
		(width 0.13462)
		(layer "F.Cu")
		(net "P5E_PEX2_STN4_TX_DP<78>")
	)
	(segment
		(start 306.433982 -320.051938)
		(end 306.433982 -320.074036)
		(width 0.1143)
		(layer "In11.Cu")
		(net "P5E_PEX2_STN4_TX_DP<78>")
	)
	(segment
		(start 269.742412 -341.714328)
		(end 269.742412 -346.230194)
		(width 0.1651)
		(layer "In11.Cu")
		(net "P5E_PEX2_STN4_TX_DP<78>")
	)
	(segment
		(start 306.479702 -313.59475)
		(end 306.479702 -320.006218)
		(width 0.1143)
		(layer "In11.Cu")
		(net "P5E_PEX2_STN4_TX_DP<78>")
	)
	(segment
		(start 306.935632 -313.379612)
		(end 306.69484 -313.379612)
		(width 0.1143)
		(layer "In11.Cu")
		(net "P5E_PEX2_STN4_TX_DP<78>")
	)
	(segment
		(start 306.433982 -320.074036)
		(end 306.433982 -321.062858)
		(width 0.1651)
		(layer "In11.Cu")
		(net "P5E_PEX2_STN4_TX_DP<78>")
	)
	(segment
		(start 270.49603 -340.96071)
		(end 269.742412 -341.714328)
		(width 0.1651)
		(layer "In11.Cu")
		(net "P5E_PEX2_STN4_TX_DP<78>")
	)
	(segment
		(start 306.433982 -321.062858)
		(end 305.713384 -321.783456)
		(width 0.1651)
		(layer "In11.Cu")
		(net "P5E_PEX2_STN4_TX_DP<78>")
	)
	(segment
		(start 306.479702 -320.006218)
		(end 306.433982 -320.051938)
		(width 0.1143)
		(layer "In11.Cu")
		(net "P5E_PEX2_STN4_TX_DP<78>")
	)
	(segment
		(start 306.69484 -313.379612)
		(end 306.479702 -313.59475)
		(width 0.1143)
		(layer "In11.Cu")
		(net "P5E_PEX2_STN4_TX_DP<78>")
	)
	(segment
		(start 307.049932 -313.265312)
		(end 306.935632 -313.379612)
		(width 0.1143)
		(layer "In11.Cu")
		(net "P5E_PEX2_STN4_TX_DP<78>")
	)
	(segment
		(start 269.742412 -346.230194)
		(end 271.296892 -347.784674)
		(width 0.1651)
		(layer "In11.Cu")
		(net "P5E_PEX2_STN4_TX_DP<78>")
	)
	(segment
		(start 271.296892 -348.29496)
		(end 271.006062 -348.58579)
		(width 0.1651)
		(layer "In11.Cu")
		(net "P5E_PEX2_STN4_TX_DP<78>")
	)
	(segment
		(start 305.713384 -321.783456)
		(end 270.49603 -340.96071)
		(width 0.1651)
		(layer "In11.Cu")
		(net "P5E_PEX2_STN4_TX_DP<78>")
	)
	(segment
		(start 271.296892 -347.784674)
		(end 271.296892 -348.29496)
		(width 0.1651)
		(layer "In11.Cu")
		(net "P5E_PEX2_STN4_TX_DP<78>")
	)
	(segment
		(start 307.049932 -312.999882)
		(end 307.049932 -313.265312)
		(width 0.1143)
		(layer "In11.Cu")
		(net "P5E_PEX2_STN4_TX_DP<78>")
	)
	(segment
		(start 299.555662 -342.734138)
		(end 299.850302 -342.439498)
		(width 0.13462)
		(layer "F.Cu")
		(net "P5E_PEX2_STN4_TX_DN<65>")
	)
	(segment
		(start 299.875702 -343.685622)
		(end 299.555662 -343.365582)
		(width 0.13462)
		(layer "F.Cu")
		(net "P5E_PEX2_STN4_TX_DN<65>")
	)
	(segment
		(start 299.555662 -343.365582)
		(end 299.555662 -342.734138)
		(width 0.13462)
		(layer "F.Cu")
		(net "P5E_PEX2_STN4_TX_DN<65>")
	)
	(segment
		(start 319.745868 -306.762912)
		(end 317.275718 -305.7398)
		(width 0.1651)
		(layer "In11.Cu")
		(net "P5E_PEX2_STN4_TX_DN<65>")
	)
	(segment
		(start 309.53075 -305.665378)
		(end 309.53075 -305.50358)
		(width 0.1143)
		(layer "In11.Cu")
		(net "P5E_PEX2_STN4_TX_DN<65>")
	)
	(segment
		(start 326.146414 -330.128118)
		(end 329.243436 -326.902064)
		(width 0.1651)
		(layer "In11.Cu")
		(net "P5E_PEX2_STN4_TX_DN<65>")
	)
	(segment
		(start 309.53075 -305.50358)
		(end 309.634382 -305.399948)
		(width 0.1143)
		(layer "In11.Cu")
		(net "P5E_PEX2_STN4_TX_DN<65>")
	)
	(segment
		(start 329.92695 -316.01537)
		(end 327.30059 -313.38901)
		(width 0.1651)
		(layer "In11.Cu")
		(net "P5E_PEX2_STN4_TX_DN<65>")
	)
	(segment
		(start 299.559472 -342.148668)
		(end 299.559472 -341.660988)
		(width 0.1651)
		(layer "In11.Cu")
		(net "P5E_PEX2_STN4_TX_DN<65>")
	)
	(segment
		(start 299.559472 -341.660988)
		(end 299.746162 -341.474298)
		(width 0.1651)
		(layer "In11.Cu")
		(net "P5E_PEX2_STN4_TX_DN<65>")
	)
	(segment
		(start 329.243436 -326.902064)
		(end 331.19822 -322.976748)
		(width 0.1651)
		(layer "In11.Cu")
		(net "P5E_PEX2_STN4_TX_DN<65>")
	)
	(segment
		(start 327.30059 -313.38901)
		(end 319.745868 -306.762912)
		(width 0.1651)
		(layer "In11.Cu")
		(net "P5E_PEX2_STN4_TX_DN<65>")
	)
	(segment
		(start 299.746162 -341.474298)
		(end 326.146414 -330.128118)
		(width 0.1651)
		(layer "In11.Cu")
		(net "P5E_PEX2_STN4_TX_DN<65>")
	)
	(segment
		(start 315.865764 -305.7398)
		(end 315.837316 -305.7398)
		(width 0.1143)
		(layer "In11.Cu")
		(net "P5E_PEX2_STN4_TX_DN<65>")
	)
	(segment
		(start 309.634382 -305.399948)
		(end 309.899812 -305.399948)
		(width 0.1143)
		(layer "In11.Cu")
		(net "P5E_PEX2_STN4_TX_DN<65>")
	)
	(segment
		(start 331.19822 -319.084452)
		(end 329.92695 -316.01537)
		(width 0.1651)
		(layer "In11.Cu")
		(net "P5E_PEX2_STN4_TX_DN<65>")
	)
	(segment
		(start 299.850302 -342.439498)
		(end 299.559472 -342.148668)
		(width 0.1651)
		(layer "In11.Cu")
		(net "P5E_PEX2_STN4_TX_DN<65>")
	)
	(segment
		(start 317.275718 -305.7398)
		(end 315.865764 -305.7398)
		(width 0.1651)
		(layer "In11.Cu")
		(net "P5E_PEX2_STN4_TX_DN<65>")
	)
	(segment
		(start 315.837316 -305.7398)
		(end 315.791596 -305.78552)
		(width 0.1143)
		(layer "In11.Cu")
		(net "P5E_PEX2_STN4_TX_DN<65>")
	)
	(segment
		(start 331.19822 -322.976748)
		(end 331.19822 -319.084452)
		(width 0.1651)
		(layer "In11.Cu")
		(net "P5E_PEX2_STN4_TX_DN<65>")
	)
	(segment
		(start 309.650892 -305.78552)
		(end 309.53075 -305.665378)
		(width 0.1143)
		(layer "In11.Cu")
		(net "P5E_PEX2_STN4_TX_DN<65>")
	)
	(segment
		(start 315.791596 -305.78552)
		(end 309.650892 -305.78552)
		(width 0.1143)
		(layer "In11.Cu")
		(net "P5E_PEX2_STN4_TX_DN<65>")
	)
	(segment
		(start 38.280848 -356.831646)
		(end 37.960808 -356.511606)
		(width 0.13462)
		(layer "F.Cu")
		(net "P5E_PEX0_STN4_TX_C_DP<70>")
	)
	(segment
		(start 38.280848 -357.46309)
		(end 38.280848 -356.831646)
		(width 0.13462)
		(layer "F.Cu")
		(net "P5E_PEX0_STN4_TX_C_DP<70>")
	)
	(segment
		(start 37.986208 -357.75773)
		(end 38.280848 -357.46309)
		(width 0.13462)
		(layer "F.Cu")
		(net "P5E_PEX0_STN4_TX_C_DP<70>")
	)
	(segment
		(start 32.26054 -366.688624)
		(end 32.555434 -366.29086)
		(width 0.1651)
		(layer "In11.Cu")
		(net "P5E_PEX0_STN4_TX_C_DP<70>")
	)
	(segment
		(start 36.277042 -361.101894)
		(end 36.572444 -360.703876)
		(width 0.1651)
		(layer "In11.Cu")
		(net "P5E_PEX0_STN4_TX_C_DP<70>")
	)
	(segment
		(start 32.10052 -366.712246)
		(end 32.26054 -366.688624)
		(width 0.1651)
		(layer "In11.Cu")
		(net "P5E_PEX0_STN4_TX_C_DP<70>")
	)
	(segment
		(start 32.98698 -365.7092)
		(end 32.986726 -365.7092)
		(width 0.1651)
		(layer "In11.Cu")
		(net "P5E_PEX0_STN4_TX_C_DP<70>")
	)
	(segment
		(start 31.002478 -369.277392)
		(end 31.5341 -367.668048)
		(width 0.1651)
		(layer "In11.Cu")
		(net "P5E_PEX0_STN4_TX_C_DP<70>")
	)
	(segment
		(start 33.553146 -364.753398)
		(end 33.713166 -364.729776)
		(width 0.1651)
		(layer "In11.Cu")
		(net "P5E_PEX0_STN4_TX_C_DP<70>")
	)
	(segment
		(start 33.257998 -365.15167)
		(end 33.553146 -364.753398)
		(width 0.1651)
		(layer "In11.Cu")
		(net "P5E_PEX0_STN4_TX_C_DP<70>")
	)
	(segment
		(start 36.298124 -361.24388)
		(end 36.277042 -361.101894)
		(width 0.1651)
		(layer "In11.Cu")
		(net "P5E_PEX0_STN4_TX_C_DP<70>")
	)
	(segment
		(start 34.854642 -363.020102)
		(end 35.150044 -362.62183)
		(width 0.1651)
		(layer "In11.Cu")
		(net "P5E_PEX0_STN4_TX_C_DP<70>")
	)
	(segment
		(start 30.109922 -371.590062)
		(end 30.109922 -371.972078)
		(width 0.1651)
		(layer "In11.Cu")
		(net "P5E_PEX0_STN4_TX_C_DP<70>")
	)
	(segment
		(start 34.875724 -363.162088)
		(end 34.854642 -363.020102)
		(width 0.1651)
		(layer "In11.Cu")
		(net "P5E_PEX0_STN4_TX_C_DP<70>")
	)
	(segment
		(start 32.555434 -366.29086)
		(end 32.531812 -366.131094)
		(width 0.1651)
		(layer "In11.Cu")
		(net "P5E_PEX0_STN4_TX_C_DP<70>")
	)
	(segment
		(start 33.713166 -364.729776)
		(end 34.875724 -363.162088)
		(width 0.1651)
		(layer "In11.Cu")
		(net "P5E_PEX0_STN4_TX_C_DP<70>")
	)
	(segment
		(start 35.586924 -362.202984)
		(end 35.565842 -362.060998)
		(width 0.1651)
		(layer "In11.Cu")
		(net "P5E_PEX0_STN4_TX_C_DP<70>")
	)
	(segment
		(start 38.276784 -358.576118)
		(end 38.277038 -358.575864)
		(width 0.1651)
		(layer "In11.Cu")
		(net "P5E_PEX0_STN4_TX_C_DP<70>")
	)
	(segment
		(start 37.42563 -359.723944)
		(end 38.276784 -358.576118)
		(width 0.1651)
		(layer "In11.Cu")
		(net "P5E_PEX0_STN4_TX_C_DP<70>")
	)
	(segment
		(start 38.277038 -358.04856)
		(end 37.986208 -357.75773)
		(width 0.1651)
		(layer "In11.Cu")
		(net "P5E_PEX0_STN4_TX_C_DP<70>")
	)
	(segment
		(start 31.002478 -371.75694)
		(end 31.002478 -369.277392)
		(width 0.1651)
		(layer "In11.Cu")
		(net "P5E_PEX0_STN4_TX_C_DP<70>")
	)
	(segment
		(start 30.236922 -372.099078)
		(end 30.66034 -372.099078)
		(width 0.1651)
		(layer "In11.Cu")
		(net "P5E_PEX0_STN4_TX_C_DP<70>")
	)
	(segment
		(start 35.861244 -361.662726)
		(end 36.00323 -361.641644)
		(width 0.1651)
		(layer "In11.Cu")
		(net "P5E_PEX0_STN4_TX_C_DP<70>")
	)
	(segment
		(start 36.988242 -360.143044)
		(end 37.283644 -359.745026)
		(width 0.1651)
		(layer "In11.Cu")
		(net "P5E_PEX0_STN4_TX_C_DP<70>")
	)
	(segment
		(start 33.28162 -365.311436)
		(end 33.257998 -365.15167)
		(width 0.1651)
		(layer "In11.Cu")
		(net "P5E_PEX0_STN4_TX_C_DP<70>")
	)
	(segment
		(start 38.277038 -358.575864)
		(end 38.277038 -358.04856)
		(width 0.1651)
		(layer "In11.Cu")
		(net "P5E_PEX0_STN4_TX_C_DP<70>")
	)
	(segment
		(start 31.5341 -367.668048)
		(end 31.828994 -367.270284)
		(width 0.1651)
		(layer "In11.Cu")
		(net "P5E_PEX0_STN4_TX_C_DP<70>")
	)
	(segment
		(start 37.009324 -360.28503)
		(end 36.988242 -360.143044)
		(width 0.1651)
		(layer "In11.Cu")
		(net "P5E_PEX0_STN4_TX_C_DP<70>")
	)
	(segment
		(start 35.150044 -362.62183)
		(end 35.29203 -362.600748)
		(width 0.1651)
		(layer "In11.Cu")
		(net "P5E_PEX0_STN4_TX_C_DP<70>")
	)
	(segment
		(start 31.805372 -367.110518)
		(end 32.10052 -366.712246)
		(width 0.1651)
		(layer "In11.Cu")
		(net "P5E_PEX0_STN4_TX_C_DP<70>")
	)
	(segment
		(start 32.82696 -365.732822)
		(end 32.98698 -365.7092)
		(width 0.1651)
		(layer "In11.Cu")
		(net "P5E_PEX0_STN4_TX_C_DP<70>")
	)
	(segment
		(start 32.986726 -365.7092)
		(end 33.28162 -365.311436)
		(width 0.1651)
		(layer "In11.Cu")
		(net "P5E_PEX0_STN4_TX_C_DP<70>")
	)
	(segment
		(start 31.828994 -367.270284)
		(end 31.805372 -367.110518)
		(width 0.1651)
		(layer "In11.Cu")
		(net "P5E_PEX0_STN4_TX_C_DP<70>")
	)
	(segment
		(start 32.531812 -366.131094)
		(end 32.82696 -365.732822)
		(width 0.1651)
		(layer "In11.Cu")
		(net "P5E_PEX0_STN4_TX_C_DP<70>")
	)
	(segment
		(start 37.283644 -359.745026)
		(end 37.425884 -359.723944)
		(width 0.1651)
		(layer "In11.Cu")
		(net "P5E_PEX0_STN4_TX_C_DP<70>")
	)
	(segment
		(start 36.71443 -360.682794)
		(end 37.009324 -360.28503)
		(width 0.1651)
		(layer "In11.Cu")
		(net "P5E_PEX0_STN4_TX_C_DP<70>")
	)
	(segment
		(start 30.109922 -371.972078)
		(end 30.236922 -372.099078)
		(width 0.1651)
		(layer "In11.Cu")
		(net "P5E_PEX0_STN4_TX_C_DP<70>")
	)
	(segment
		(start 36.572444 -360.703876)
		(end 36.71443 -360.682794)
		(width 0.1651)
		(layer "In11.Cu")
		(net "P5E_PEX0_STN4_TX_C_DP<70>")
	)
	(segment
		(start 35.565842 -362.060998)
		(end 35.861244 -361.662726)
		(width 0.1651)
		(layer "In11.Cu")
		(net "P5E_PEX0_STN4_TX_C_DP<70>")
	)
	(segment
		(start 37.425884 -359.723944)
		(end 37.42563 -359.723944)
		(width 0.1651)
		(layer "In11.Cu")
		(net "P5E_PEX0_STN4_TX_C_DP<70>")
	)
	(segment
		(start 30.66034 -372.099078)
		(end 31.002478 -371.75694)
		(width 0.1651)
		(layer "In11.Cu")
		(net "P5E_PEX0_STN4_TX_C_DP<70>")
	)
	(segment
		(start 36.00323 -361.641644)
		(end 36.298124 -361.24388)
		(width 0.1651)
		(layer "In11.Cu")
		(net "P5E_PEX0_STN4_TX_C_DP<70>")
	)
	(segment
		(start 35.29203 -362.600748)
		(end 35.586924 -362.202984)
		(width 0.1651)
		(layer "In11.Cu")
		(net "P5E_PEX0_STN4_TX_C_DP<70>")
	)
	(segment
		(start 280.901902 -355.026722)
		(end 281.196542 -354.732082)
		(width 0.13462)
		(layer "F.Cu")
		(net "P5E_PEX2_STN4_TX_DN<73>")
	)
	(segment
		(start 280.901902 -355.658166)
		(end 280.901902 -355.026722)
		(width 0.13462)
		(layer "F.Cu")
		(net "P5E_PEX2_STN4_TX_DN<73>")
	)
	(segment
		(start 281.221942 -355.978206)
		(end 280.901902 -355.658166)
		(width 0.13462)
		(layer "F.Cu")
		(net "P5E_PEX2_STN4_TX_DN<73>")
	)
	(segment
		(start 285.35249 -339.696298)
		(end 285.352744 -339.696552)
		(width 0.1651)
		(layer "In11.Cu")
		(net "P5E_PEX2_STN4_TX_DN<73>")
	)
	(segment
		(start 285.31058 -339.852508)
		(end 285.35249 -339.696298)
		(width 0.1651)
		(layer "In11.Cu")
		(net "P5E_PEX2_STN4_TX_DN<73>")
	)
	(segment
		(start 283.239718 -340.914482)
		(end 283.668724 -340.66734)
		(width 0.1651)
		(layer "In11.Cu")
		(net "P5E_PEX2_STN4_TX_DN<73>")
	)
	(segment
		(start 284.254194 -340.4616)
		(end 284.296104 -340.30539)
		(width 0.1651)
		(layer "In11.Cu")
		(net "P5E_PEX2_STN4_TX_DN<73>")
	)
	(segment
		(start 285.352744 -339.696552)
		(end 308.294786 -326.47128)
		(width 0.1651)
		(layer "In11.Cu")
		(net "P5E_PEX2_STN4_TX_DN<73>")
	)
	(segment
		(start 311.799732 -311.784492)
		(end 311.799732 -312.049922)
		(width 0.1143)
		(layer "In11.Cu")
		(net "P5E_PEX2_STN4_TX_DN<73>")
	)
	(segment
		(start 311.465722 -319.985898)
		(end 311.420002 -319.940178)
		(width 0.1143)
		(layer "In11.Cu")
		(net "P5E_PEX2_STN4_TX_DN<73>")
	)
	(segment
		(start 284.88132 -340.100158)
		(end 285.31058 -339.852508)
		(width 0.1651)
		(layer "In11.Cu")
		(net "P5E_PEX2_STN4_TX_DN<73>")
	)
	(segment
		(start 311.224168 -323.542152)
		(end 311.444386 -323.01053)
		(width 0.1651)
		(layer "In11.Cu")
		(net "P5E_PEX2_STN4_TX_DN<73>")
	)
	(segment
		(start 311.420002 -319.940178)
		(end 311.420002 -311.813194)
		(width 0.1143)
		(layer "In11.Cu")
		(net "P5E_PEX2_STN4_TX_DN<73>")
	)
	(segment
		(start 283.668724 -340.66734)
		(end 283.824934 -340.70925)
		(width 0.1651)
		(layer "In11.Cu")
		(net "P5E_PEX2_STN4_TX_DN<73>")
	)
	(segment
		(start 284.72511 -340.058248)
		(end 284.88132 -340.100158)
		(width 0.1651)
		(layer "In11.Cu")
		(net "P5E_PEX2_STN4_TX_DN<73>")
	)
	(segment
		(start 282.460192 -352.376486)
		(end 282.460192 -341.693754)
		(width 0.1651)
		(layer "In11.Cu")
		(net "P5E_PEX2_STN4_TX_DN<73>")
	)
	(segment
		(start 311.444386 -323.01053)
		(end 311.465722 -322.989194)
		(width 0.1651)
		(layer "In11.Cu")
		(net "P5E_PEX2_STN4_TX_DN<73>")
	)
	(segment
		(start 311.563004 -311.670192)
		(end 311.685432 -311.670192)
		(width 0.1143)
		(layer "In11.Cu")
		(net "P5E_PEX2_STN4_TX_DN<73>")
	)
	(segment
		(start 280.905712 -354.441252)
		(end 280.905712 -353.930966)
		(width 0.1651)
		(layer "In11.Cu")
		(net "P5E_PEX2_STN4_TX_DN<73>")
	)
	(segment
		(start 281.196542 -354.732082)
		(end 280.905712 -354.441252)
		(width 0.1651)
		(layer "In11.Cu")
		(net "P5E_PEX2_STN4_TX_DN<73>")
	)
	(segment
		(start 283.824934 -340.70925)
		(end 284.254194 -340.4616)
		(width 0.1651)
		(layer "In11.Cu")
		(net "P5E_PEX2_STN4_TX_DN<73>")
	)
	(segment
		(start 282.460192 -341.693754)
		(end 283.239718 -340.914482)
		(width 0.1651)
		(layer "In11.Cu")
		(net "P5E_PEX2_STN4_TX_DN<73>")
	)
	(segment
		(start 311.465722 -320.007996)
		(end 311.465722 -319.985898)
		(width 0.1143)
		(layer "In11.Cu")
		(net "P5E_PEX2_STN4_TX_DN<73>")
	)
	(segment
		(start 284.296104 -340.30539)
		(end 284.72511 -340.058248)
		(width 0.1651)
		(layer "In11.Cu")
		(net "P5E_PEX2_STN4_TX_DN<73>")
	)
	(segment
		(start 311.685432 -311.670192)
		(end 311.799732 -311.784492)
		(width 0.1143)
		(layer "In11.Cu")
		(net "P5E_PEX2_STN4_TX_DN<73>")
	)
	(segment
		(start 311.420002 -311.813194)
		(end 311.563004 -311.670192)
		(width 0.1143)
		(layer "In11.Cu")
		(net "P5E_PEX2_STN4_TX_DN<73>")
	)
	(segment
		(start 311.465722 -322.989194)
		(end 311.465722 -320.007996)
		(width 0.1651)
		(layer "In11.Cu")
		(net "P5E_PEX2_STN4_TX_DN<73>")
	)
	(segment
		(start 308.294786 -326.47128)
		(end 311.224168 -323.542152)
		(width 0.1651)
		(layer "In11.Cu")
		(net "P5E_PEX2_STN4_TX_DN<73>")
	)
	(segment
		(start 280.905712 -353.930966)
		(end 282.460192 -352.376486)
		(width 0.1651)
		(layer "In11.Cu")
		(net "P5E_PEX2_STN4_TX_DN<73>")
	)
	(segment
		(start 26.119328 -356.831646)
		(end 26.439368 -356.511606)
		(width 0.13462)
		(layer "F.Cu")
		(net "P5E_PEX0_STN4_TX_C_DN<76>")
	)
	(segment
		(start 26.413968 -357.75773)
		(end 26.119328 -357.46309)
		(width 0.13462)
		(layer "F.Cu")
		(net "P5E_PEX0_STN4_TX_C_DN<76>")
	)
	(segment
		(start 26.119328 -357.46309)
		(end 26.119328 -356.831646)
		(width 0.13462)
		(layer "F.Cu")
		(net "P5E_PEX0_STN4_TX_C_DN<76>")
	)
	(segment
		(start 22.780244 -381.627888)
		(end 22.997668 -368.137186)
		(width 0.1651)
		(layer "In11.Cu")
		(net "P5E_PEX0_STN4_TX_C_DN<76>")
	)
	(segment
		(start 22.997668 -368.137186)
		(end 24.548846 -361.94492)
		(width 0.1651)
		(layer "In11.Cu")
		(net "P5E_PEX0_STN4_TX_C_DN<76>")
	)
	(segment
		(start 26.123138 -358.04856)
		(end 26.413968 -357.75773)
		(width 0.1651)
		(layer "In11.Cu")
		(net "P5E_PEX0_STN4_TX_C_DN<76>")
	)
	(segment
		(start 29.053028 -390.30529)
		(end 25.692608 -388.91337)
		(width 0.1651)
		(layer "In11.Cu")
		(net "P5E_PEX0_STN4_TX_C_DN<76>")
	)
	(segment
		(start 24.045672 -387.266434)
		(end 22.780244 -384.211576)
		(width 0.1651)
		(layer "In11.Cu")
		(net "P5E_PEX0_STN4_TX_C_DN<76>")
	)
	(segment
		(start 26.123138 -359.000044)
		(end 26.123138 -358.04856)
		(width 0.1651)
		(layer "In11.Cu")
		(net "P5E_PEX0_STN4_TX_C_DN<76>")
	)
	(segment
		(start 35.68446 -397.873982)
		(end 35.68446 -394.94206)
		(width 0.1651)
		(layer "In11.Cu")
		(net "P5E_PEX0_STN4_TX_C_DN<76>")
	)
	(segment
		(start 35.177222 -398.38122)
		(end 35.68446 -397.873982)
		(width 0.1651)
		(layer "In11.Cu")
		(net "P5E_PEX0_STN4_TX_C_DN<76>")
	)
	(segment
		(start 25.692608 -388.91337)
		(end 24.045672 -387.266434)
		(width 0.1651)
		(layer "In11.Cu")
		(net "P5E_PEX0_STN4_TX_C_DN<76>")
	)
	(segment
		(start 34.636964 -398.38122)
		(end 35.177222 -398.38122)
		(width 0.1651)
		(layer "In11.Cu")
		(net "P5E_PEX0_STN4_TX_C_DN<76>")
	)
	(segment
		(start 34.509964 -398.50822)
		(end 34.636964 -398.38122)
		(width 0.1651)
		(layer "In11.Cu")
		(net "P5E_PEX0_STN4_TX_C_DN<76>")
	)
	(segment
		(start 22.780244 -384.211576)
		(end 22.780244 -381.627888)
		(width 0.1651)
		(layer "In11.Cu")
		(net "P5E_PEX0_STN4_TX_C_DN<76>")
	)
	(segment
		(start 34.509964 -398.890236)
		(end 34.509964 -398.50822)
		(width 0.1651)
		(layer "In11.Cu")
		(net "P5E_PEX0_STN4_TX_C_DN<76>")
	)
	(segment
		(start 24.548846 -361.94492)
		(end 26.123138 -359.000044)
		(width 0.1651)
		(layer "In11.Cu")
		(net "P5E_PEX0_STN4_TX_C_DN<76>")
	)
	(segment
		(start 35.68446 -394.94206)
		(end 35.0647 -394.3223)
		(width 0.1651)
		(layer "In11.Cu")
		(net "P5E_PEX0_STN4_TX_C_DN<76>")
	)
	(segment
		(start 35.0647 -394.3223)
		(end 29.053028 -390.30529)
		(width 0.1651)
		(layer "In11.Cu")
		(net "P5E_PEX0_STN4_TX_C_DN<76>")
	)
	(segment
		(start 82.184494 -316.799722)
		(end 82.449924 -316.799722)
		(width 0.1143)
		(layer "In15.Cu")
		(net "P5E_PEX0_STN4_RX_DN<71>")
	)
	(segment
		(start 27.910028 -379.590046)
		(end 27.910028 -379.20803)
		(width 0.1651)
		(layer "In15.Cu")
		(net "P5E_PEX0_STN4_RX_DN<71>")
	)
	(segment
		(start 78.045056 -327.46569)
		(end 80.63611 -324.874636)
		(width 0.1651)
		(layer "In15.Cu")
		(net "P5E_PEX0_STN4_RX_DN<71>")
	)
	(segment
		(start 80.63611 -324.874636)
		(end 82.115914 -321.30238)
		(width 0.1651)
		(layer "In15.Cu")
		(net "P5E_PEX0_STN4_RX_DN<71>")
	)
	(segment
		(start 28.375356 -379.08103)
		(end 29.06776 -378.388626)
		(width 0.1651)
		(layer "In15.Cu")
		(net "P5E_PEX0_STN4_RX_DN<71>")
	)
	(segment
		(start 45.474636 -337.047078)
		(end 69.35597 -331.064616)
		(width 0.1651)
		(layer "In15.Cu")
		(net "P5E_PEX0_STN4_RX_DN<71>")
	)
	(segment
		(start 82.070194 -319.05448)
		(end 82.070194 -316.914022)
		(width 0.1143)
		(layer "In15.Cu")
		(net "P5E_PEX0_STN4_RX_DN<71>")
	)
	(segment
		(start 33.895538 -358.62641)
		(end 33.895538 -341.770208)
		(width 0.1651)
		(layer "In15.Cu")
		(net "P5E_PEX0_STN4_RX_DN<71>")
	)
	(segment
		(start 82.115914 -319.128648)
		(end 82.115914 -319.1002)
		(width 0.1143)
		(layer "In15.Cu")
		(net "P5E_PEX0_STN4_RX_DN<71>")
	)
	(segment
		(start 33.895538 -341.770208)
		(end 34.605214 -341.060532)
		(width 0.1651)
		(layer "In15.Cu")
		(net "P5E_PEX0_STN4_RX_DN<71>")
	)
	(segment
		(start 28.037028 -379.08103)
		(end 28.375356 -379.08103)
		(width 0.1651)
		(layer "In15.Cu")
		(net "P5E_PEX0_STN4_RX_DN<71>")
	)
	(segment
		(start 27.910028 -379.20803)
		(end 28.037028 -379.08103)
		(width 0.1651)
		(layer "In15.Cu")
		(net "P5E_PEX0_STN4_RX_DN<71>")
	)
	(segment
		(start 34.605214 -341.060532)
		(end 41.066212 -338.384388)
		(width 0.1651)
		(layer "In15.Cu")
		(net "P5E_PEX0_STN4_RX_DN<71>")
	)
	(segment
		(start 41.066212 -338.384388)
		(end 45.474636 -337.047078)
		(width 0.1651)
		(layer "In15.Cu")
		(net "P5E_PEX0_STN4_RX_DN<71>")
	)
	(segment
		(start 82.070194 -316.914022)
		(end 82.184494 -316.799722)
		(width 0.1143)
		(layer "In15.Cu")
		(net "P5E_PEX0_STN4_RX_DN<71>")
	)
	(segment
		(start 82.115914 -321.30238)
		(end 82.115914 -319.128648)
		(width 0.1651)
		(layer "In15.Cu")
		(net "P5E_PEX0_STN4_RX_DN<71>")
	)
	(segment
		(start 69.35597 -331.064616)
		(end 78.045056 -327.46569)
		(width 0.1651)
		(layer "In15.Cu")
		(net "P5E_PEX0_STN4_RX_DN<71>")
	)
	(segment
		(start 29.06776 -378.388626)
		(end 29.06776 -368.833146)
		(width 0.1651)
		(layer "In15.Cu")
		(net "P5E_PEX0_STN4_RX_DN<71>")
	)
	(segment
		(start 29.06776 -368.833146)
		(end 33.895538 -358.62641)
		(width 0.1651)
		(layer "In15.Cu")
		(net "P5E_PEX0_STN4_RX_DN<71>")
	)
	(segment
		(start 82.115914 -319.1002)
		(end 82.070194 -319.05448)
		(width 0.1143)
		(layer "In15.Cu")
		(net "P5E_PEX0_STN4_RX_DN<71>")
	)
	(segment
		(start 287.439862 -355.978206)
		(end 287.119822 -355.658166)
		(width 0.13462)
		(layer "F.Cu")
		(net "P5E_PEX2_STN4_TX_DN<70>")
	)
	(segment
		(start 287.119822 -355.026722)
		(end 287.414462 -354.732082)
		(width 0.13462)
		(layer "F.Cu")
		(net "P5E_PEX2_STN4_TX_DN<70>")
	)
	(segment
		(start 287.119822 -355.658166)
		(end 287.119822 -355.026722)
		(width 0.13462)
		(layer "F.Cu")
		(net "P5E_PEX2_STN4_TX_DN<70>")
	)
	(segment
		(start 314.270136 -312.164222)
		(end 314.384436 -312.049922)
		(width 0.1143)
		(layer "In11.Cu")
		(net "P5E_PEX2_STN4_TX_DN<70>")
	)
	(segment
		(start 315.25972 -322.291456)
		(end 315.25972 -318.138048)
		(width 0.1651)
		(layer "In11.Cu")
		(net "P5E_PEX2_STN4_TX_DN<70>")
	)
	(segment
		(start 315.25972 -318.1096)
		(end 315.214 -318.06388)
		(width 0.1143)
		(layer "In11.Cu")
		(net "P5E_PEX2_STN4_TX_DN<70>")
	)
	(segment
		(start 309.640478 -329.288902)
		(end 313.676792 -325.252588)
		(width 0.1651)
		(layer "In11.Cu")
		(net "P5E_PEX2_STN4_TX_DN<70>")
	)
	(segment
		(start 315.214 -312.7756)
		(end 314.87872 -312.44032)
		(width 0.1143)
		(layer "In11.Cu")
		(net "P5E_PEX2_STN4_TX_DN<70>")
	)
	(segment
		(start 289.19678 -341.243412)
		(end 309.640478 -329.288902)
		(width 0.1651)
		(layer "In11.Cu")
		(net "P5E_PEX2_STN4_TX_DN<70>")
	)
	(segment
		(start 314.384436 -312.44032)
		(end 314.270136 -312.32602)
		(width 0.1143)
		(layer "In11.Cu")
		(net "P5E_PEX2_STN4_TX_DN<70>")
	)
	(segment
		(start 315.25972 -318.138048)
		(end 315.25972 -318.1096)
		(width 0.1143)
		(layer "In11.Cu")
		(net "P5E_PEX2_STN4_TX_DN<70>")
	)
	(segment
		(start 288.678112 -352.376486)
		(end 288.678112 -341.76208)
		(width 0.1651)
		(layer "In11.Cu")
		(net "P5E_PEX2_STN4_TX_DN<70>")
	)
	(segment
		(start 288.678112 -341.76208)
		(end 289.19678 -341.243412)
		(width 0.1651)
		(layer "In11.Cu")
		(net "P5E_PEX2_STN4_TX_DN<70>")
	)
	(segment
		(start 314.270136 -312.32602)
		(end 314.270136 -312.164222)
		(width 0.1143)
		(layer "In11.Cu")
		(net "P5E_PEX2_STN4_TX_DN<70>")
	)
	(segment
		(start 315.214 -318.06388)
		(end 315.214 -312.7756)
		(width 0.1143)
		(layer "In11.Cu")
		(net "P5E_PEX2_STN4_TX_DN<70>")
	)
	(segment
		(start 314.384436 -312.049922)
		(end 314.649866 -312.049922)
		(width 0.1143)
		(layer "In11.Cu")
		(net "P5E_PEX2_STN4_TX_DN<70>")
	)
	(segment
		(start 287.123632 -354.441252)
		(end 287.123632 -353.930966)
		(width 0.1651)
		(layer "In11.Cu")
		(net "P5E_PEX2_STN4_TX_DN<70>")
	)
	(segment
		(start 314.87872 -312.44032)
		(end 314.384436 -312.44032)
		(width 0.1143)
		(layer "In11.Cu")
		(net "P5E_PEX2_STN4_TX_DN<70>")
	)
	(segment
		(start 313.676792 -325.252588)
		(end 315.25972 -322.291456)
		(width 0.1651)
		(layer "In11.Cu")
		(net "P5E_PEX2_STN4_TX_DN<70>")
	)
	(segment
		(start 287.414462 -354.732082)
		(end 287.123632 -354.441252)
		(width 0.1651)
		(layer "In11.Cu")
		(net "P5E_PEX2_STN4_TX_DN<70>")
	)
	(segment
		(start 287.123632 -353.930966)
		(end 288.678112 -352.376486)
		(width 0.1651)
		(layer "In11.Cu")
		(net "P5E_PEX2_STN4_TX_DN<70>")
	)
	(segment
		(start 93.230446 -327.392792)
		(end 95.11792 -326.008746)
		(width 0.1651)
		(layer "In15.Cu")
		(net "P5E_PEX0_STN4_RX_DN<66>")
	)
	(segment
		(start 44.78655 -363.64164)
		(end 49.121314 -358.859328)
		(width 0.1651)
		(layer "In15.Cu")
		(net "P5E_PEX0_STN4_RX_DN<66>")
	)
	(segment
		(start 96.784922 -322.946776)
		(end 97.1169 -319.161668)
		(width 0.1651)
		(layer "In15.Cu")
		(net "P5E_PEX0_STN4_RX_DN<66>")
	)
	(segment
		(start 49.440338 -358.031796)
		(end 49.440338 -354.176076)
		(width 0.1651)
		(layer "In15.Cu")
		(net "P5E_PEX0_STN4_RX_DN<66>")
	)
	(segment
		(start 82.070194 -306.438808)
		(end 82.159094 -306.349908)
		(width 0.1143)
		(layer "In15.Cu")
		(net "P5E_PEX0_STN4_RX_DN<66>")
	)
	(segment
		(start 58.43651 -341.00389)
		(end 59.904884 -339.535516)
		(width 0.1651)
		(layer "In15.Cu")
		(net "P5E_PEX0_STN4_RX_DN<66>")
	)
	(segment
		(start 49.663096 -353.638104)
		(end 49.911 -353.3902)
		(width 0.1651)
		(layer "In15.Cu")
		(net "P5E_PEX0_STN4_RX_DN<66>")
	)
	(segment
		(start 83.6168 -306.683918)
		(end 83.57108 -306.729638)
		(width 0.1143)
		(layer "In15.Cu")
		(net "P5E_PEX0_STN4_RX_DN<66>")
	)
	(segment
		(start 49.440338 -354.176076)
		(end 49.663096 -353.638104)
		(width 0.1651)
		(layer "In15.Cu")
		(net "P5E_PEX0_STN4_RX_DN<66>")
	)
	(segment
		(start 82.159094 -306.349908)
		(end 82.449924 -306.349908)
		(width 0.1143)
		(layer "In15.Cu")
		(net "P5E_PEX0_STN4_RX_DN<66>")
	)
	(segment
		(start 89.11717 -308.265322)
		(end 86.158832 -306.683918)
		(width 0.1651)
		(layer "In15.Cu")
		(net "P5E_PEX0_STN4_RX_DN<66>")
	)
	(segment
		(start 38.910006 -380.308104)
		(end 39.037006 -380.181104)
		(width 0.1651)
		(layer "In15.Cu")
		(net "P5E_PEX0_STN4_RX_DN<66>")
	)
	(segment
		(start 97.1169 -319.161668)
		(end 95.74657 -315.853826)
		(width 0.1651)
		(layer "In15.Cu")
		(net "P5E_PEX0_STN4_RX_DN<66>")
	)
	(segment
		(start 86.158832 -306.683918)
		(end 83.645248 -306.683918)
		(width 0.1651)
		(layer "In15.Cu")
		(net "P5E_PEX0_STN4_RX_DN<66>")
	)
	(segment
		(start 82.235294 -306.729638)
		(end 82.070194 -306.564538)
		(width 0.1143)
		(layer "In15.Cu")
		(net "P5E_PEX0_STN4_RX_DN<66>")
	)
	(segment
		(start 64.501522 -337.631786)
		(end 79.486252 -333.085948)
		(width 0.1651)
		(layer "In15.Cu")
		(net "P5E_PEX0_STN4_RX_DN<66>")
	)
	(segment
		(start 93.815662 -312.964068)
		(end 89.11717 -308.265322)
		(width 0.1651)
		(layer "In15.Cu")
		(net "P5E_PEX0_STN4_RX_DN<66>")
	)
	(segment
		(start 39.387526 -380.181104)
		(end 40.066976 -379.501654)
		(width 0.1651)
		(layer "In15.Cu")
		(net "P5E_PEX0_STN4_RX_DN<66>")
	)
	(segment
		(start 52.253642 -352.571558)
		(end 58.43651 -341.00389)
		(width 0.1651)
		(layer "In15.Cu")
		(net "P5E_PEX0_STN4_RX_DN<66>")
	)
	(segment
		(start 44.786804 -363.641894)
		(end 44.78655 -363.64164)
		(width 0.1651)
		(layer "In15.Cu")
		(net "P5E_PEX0_STN4_RX_DN<66>")
	)
	(segment
		(start 79.486252 -333.085948)
		(end 93.230446 -327.392792)
		(width 0.1651)
		(layer "In15.Cu")
		(net "P5E_PEX0_STN4_RX_DN<66>")
	)
	(segment
		(start 95.905828 -325.0692)
		(end 96.784922 -322.946776)
		(width 0.1651)
		(layer "In15.Cu")
		(net "P5E_PEX0_STN4_RX_DN<66>")
	)
	(segment
		(start 49.121314 -358.859328)
		(end 49.440338 -358.031796)
		(width 0.1651)
		(layer "In15.Cu")
		(net "P5E_PEX0_STN4_RX_DN<66>")
	)
	(segment
		(start 95.74657 -315.853826)
		(end 93.815662 -312.964068)
		(width 0.1651)
		(layer "In15.Cu")
		(net "P5E_PEX0_STN4_RX_DN<66>")
	)
	(segment
		(start 83.645248 -306.683918)
		(end 83.6168 -306.683918)
		(width 0.1143)
		(layer "In15.Cu")
		(net "P5E_PEX0_STN4_RX_DN<66>")
	)
	(segment
		(start 59.904884 -339.535516)
		(end 64.501522 -337.631786)
		(width 0.1651)
		(layer "In15.Cu")
		(net "P5E_PEX0_STN4_RX_DN<66>")
	)
	(segment
		(start 40.383714 -368.499898)
		(end 44.786804 -363.641894)
		(width 0.1651)
		(layer "In15.Cu")
		(net "P5E_PEX0_STN4_RX_DN<66>")
	)
	(segment
		(start 51.912012 -352.913188)
		(end 52.253642 -352.571558)
		(width 0.1651)
		(layer "In15.Cu")
		(net "P5E_PEX0_STN4_RX_DN<66>")
	)
	(segment
		(start 40.066976 -369.320826)
		(end 40.383714 -368.499898)
		(width 0.1651)
		(layer "In15.Cu")
		(net "P5E_PEX0_STN4_RX_DN<66>")
	)
	(segment
		(start 40.066976 -379.501654)
		(end 40.066976 -369.320826)
		(width 0.1651)
		(layer "In15.Cu")
		(net "P5E_PEX0_STN4_RX_DN<66>")
	)
	(segment
		(start 95.11792 -326.008746)
		(end 95.905828 -325.0692)
		(width 0.1651)
		(layer "In15.Cu")
		(net "P5E_PEX0_STN4_RX_DN<66>")
	)
	(segment
		(start 38.910006 -380.69012)
		(end 38.910006 -380.308104)
		(width 0.1651)
		(layer "In15.Cu")
		(net "P5E_PEX0_STN4_RX_DN<66>")
	)
	(segment
		(start 83.57108 -306.729638)
		(end 82.235294 -306.729638)
		(width 0.1143)
		(layer "In15.Cu")
		(net "P5E_PEX0_STN4_RX_DN<66>")
	)
	(segment
		(start 39.037006 -380.181104)
		(end 39.387526 -380.181104)
		(width 0.1651)
		(layer "In15.Cu")
		(net "P5E_PEX0_STN4_RX_DN<66>")
	)
	(segment
		(start 82.070194 -306.564538)
		(end 82.070194 -306.438808)
		(width 0.1143)
		(layer "In15.Cu")
		(net "P5E_PEX0_STN4_RX_DN<66>")
	)
	(segment
		(start 50.760376 -353.3902)
		(end 51.912012 -352.913188)
		(width 0.1651)
		(layer "In15.Cu")
		(net "P5E_PEX0_STN4_RX_DN<66>")
	)
	(segment
		(start 49.911 -353.3902)
		(end 50.760376 -353.3902)
		(width 0.1651)
		(layer "In15.Cu")
		(net "P5E_PEX0_STN4_RX_DN<66>")
	)
	(segment
		(start 275.004022 -343.685622)
		(end 274.683982 -343.365582)
		(width 0.13462)
		(layer "F.Cu")
		(net "P5E_PEX2_STN4_TX_DN<77>")
	)
	(segment
		(start 274.683982 -343.365582)
		(end 274.683982 -342.734138)
		(width 0.13462)
		(layer "F.Cu")
		(net "P5E_PEX2_STN4_TX_DN<77>")
	)
	(segment
		(start 274.683982 -342.734138)
		(end 274.978622 -342.439498)
		(width 0.13462)
		(layer "F.Cu")
		(net "P5E_PEX2_STN4_TX_DN<77>")
	)
	(segment
		(start 306.412392 -322.852288)
		(end 279.627838 -337.766152)
		(width 0.1651)
		(layer "In11.Cu")
		(net "P5E_PEX2_STN4_TX_DN<77>")
	)
	(segment
		(start 277.929594 -338.711794)
		(end 277.497032 -338.952586)
		(width 0.1651)
		(layer "In11.Cu")
		(net "P5E_PEX2_STN4_TX_DN<77>")
	)
	(segment
		(start 277.019766 -339.349334)
		(end 276.864318 -339.305138)
		(width 0.1651)
		(layer "In11.Cu")
		(net "P5E_PEX2_STN4_TX_DN<77>")
	)
	(segment
		(start 307.885592 -311.670192)
		(end 307.723794 -311.670192)
		(width 0.1143)
		(layer "In11.Cu")
		(net "P5E_PEX2_STN4_TX_DN<77>")
	)
	(segment
		(start 277.452836 -339.108034)
		(end 277.019766 -339.349334)
		(width 0.1651)
		(layer "In11.Cu")
		(net "P5E_PEX2_STN4_TX_DN<77>")
	)
	(segment
		(start 274.687792 -342.148668)
		(end 274.978622 -342.439498)
		(width 0.1651)
		(layer "In11.Cu")
		(net "P5E_PEX2_STN4_TX_DN<77>")
	)
	(segment
		(start 307.665882 -320.068956)
		(end 307.665882 -321.598544)
		(width 0.1651)
		(layer "In11.Cu")
		(net "P5E_PEX2_STN4_TX_DN<77>")
	)
	(segment
		(start 307.999892 -311.784492)
		(end 307.885592 -311.670192)
		(width 0.1143)
		(layer "In11.Cu")
		(net "P5E_PEX2_STN4_TX_DN<77>")
	)
	(segment
		(start 307.723794 -311.670192)
		(end 307.620162 -311.773824)
		(width 0.1143)
		(layer "In11.Cu")
		(net "P5E_PEX2_STN4_TX_DN<77>")
	)
	(segment
		(start 278.518112 -338.51469)
		(end 278.085042 -338.75599)
		(width 0.1651)
		(layer "In11.Cu")
		(net "P5E_PEX2_STN4_TX_DN<77>")
	)
	(segment
		(start 279.150572 -338.1629)
		(end 278.995124 -338.118704)
		(width 0.1651)
		(layer "In11.Cu")
		(net "P5E_PEX2_STN4_TX_DN<77>")
	)
	(segment
		(start 279.627838 -337.766152)
		(end 279.583642 -337.9216)
		(width 0.1651)
		(layer "In11.Cu")
		(net "P5E_PEX2_STN4_TX_DN<77>")
	)
	(segment
		(start 278.562308 -338.359242)
		(end 278.518112 -338.51469)
		(width 0.1651)
		(layer "In11.Cu")
		(net "P5E_PEX2_STN4_TX_DN<77>")
	)
	(segment
		(start 274.687792 -341.114888)
		(end 274.687792 -342.148668)
		(width 0.1651)
		(layer "In11.Cu")
		(net "P5E_PEX2_STN4_TX_DN<77>")
	)
	(segment
		(start 278.562562 -338.359496)
		(end 278.562308 -338.359242)
		(width 0.1651)
		(layer "In11.Cu")
		(net "P5E_PEX2_STN4_TX_DN<77>")
	)
	(segment
		(start 307.620162 -320.001138)
		(end 307.665882 -320.046858)
		(width 0.1143)
		(layer "In11.Cu")
		(net "P5E_PEX2_STN4_TX_DN<77>")
	)
	(segment
		(start 278.085042 -338.75599)
		(end 277.929594 -338.711794)
		(width 0.1651)
		(layer "In11.Cu")
		(net "P5E_PEX2_STN4_TX_DN<77>")
	)
	(segment
		(start 307.665882 -320.046858)
		(end 307.665882 -320.068956)
		(width 0.1143)
		(layer "In11.Cu")
		(net "P5E_PEX2_STN4_TX_DN<77>")
	)
	(segment
		(start 307.999892 -312.049922)
		(end 307.999892 -311.784492)
		(width 0.1143)
		(layer "In11.Cu")
		(net "P5E_PEX2_STN4_TX_DN<77>")
	)
	(segment
		(start 307.665882 -321.598544)
		(end 306.412392 -322.852288)
		(width 0.1651)
		(layer "In11.Cu")
		(net "P5E_PEX2_STN4_TX_DN<77>")
	)
	(segment
		(start 275.362416 -340.440264)
		(end 274.687792 -341.114888)
		(width 0.1651)
		(layer "In11.Cu")
		(net "P5E_PEX2_STN4_TX_DN<77>")
	)
	(segment
		(start 276.03704 -339.76564)
		(end 275.362162 -340.440264)
		(width 0.1651)
		(layer "In11.Cu")
		(net "P5E_PEX2_STN4_TX_DN<77>")
	)
	(segment
		(start 279.583642 -337.9216)
		(end 279.150572 -338.1629)
		(width 0.1651)
		(layer "In11.Cu")
		(net "P5E_PEX2_STN4_TX_DN<77>")
	)
	(segment
		(start 276.864318 -339.305138)
		(end 276.03704 -339.76564)
		(width 0.1651)
		(layer "In11.Cu")
		(net "P5E_PEX2_STN4_TX_DN<77>")
	)
	(segment
		(start 307.620162 -311.773824)
		(end 307.620162 -320.001138)
		(width 0.1143)
		(layer "In11.Cu")
		(net "P5E_PEX2_STN4_TX_DN<77>")
	)
	(segment
		(start 277.497032 -338.952586)
		(end 277.452836 -339.108034)
		(width 0.1651)
		(layer "In11.Cu")
		(net "P5E_PEX2_STN4_TX_DN<77>")
	)
	(segment
		(start 275.362162 -340.440264)
		(end 275.362416 -340.440264)
		(width 0.1651)
		(layer "In11.Cu")
		(net "P5E_PEX2_STN4_TX_DN<77>")
	)
	(segment
		(start 278.995124 -338.118704)
		(end 278.562562 -338.359496)
		(width 0.1651)
		(layer "In11.Cu")
		(net "P5E_PEX2_STN4_TX_DN<77>")
	)
	(segment
		(start 213.17966 -181.208426)
		(end 213.17966 -180.243226)
		(width 0.13208)
		(layer "F.Cu")
		(net "SEL_FLASH_PEX2_BUF_R")
	)
	(segment
		(start 213.17966 -180.243226)
		(end 212.363812 -180.243226)
		(width 0.13208)
		(layer "F.Cu")
		(net "SEL_FLASH_PEX2_BUF_R")
	)
	(via
		(at 212.363812 -180.243226)
		(size 0.508)
		(drill 0.254)
		(layers "F.Cu" "B.Cu")
		(net "SEL_FLASH_PEX2_BUF_R")
	)
	(via
		(at 291.836348 -189.802262)
		(size 0.508)
		(drill 0.254)
		(layers "F.Cu" "B.Cu")
		(net "SEL_FLASH_PEX2_BUF_R")
	)
	(via
		(at 260.836664 -182.821326)
		(size 0.508)
		(drill 0.254)
		(layers "F.Cu" "B.Cu")
		(net "SEL_FLASH_PEX2_BUF_R")
	)
	(via
		(at 249.626882 -231.13873)
		(size 0.508)
		(drill 0.254)
		(layers "F.Cu" "B.Cu")
		(net "SEL_FLASH_PEX2_BUF_R")
	)
	(segment
		(start 249.695716 -230.703374)
		(end 249.695716 -229.827582)
		(width 0.13208)
		(layer "B.Cu")
		(net "SEL_FLASH_PEX2_BUF_R")
	)
	(segment
		(start 249.626882 -230.772208)
		(end 249.695716 -230.703374)
		(width 0.13208)
		(layer "B.Cu")
		(net "SEL_FLASH_PEX2_BUF_R")
	)
	(segment
		(start 294.871902 -195.442332)
		(end 293.497254 -194.067684)
		(width 0.13208)
		(layer "B.Cu")
		(net "SEL_FLASH_PEX2_BUF_R")
	)
	(segment
		(start 293.497254 -194.067684)
		(end 293.497254 -191.463168)
		(width 0.13208)
		(layer "B.Cu")
		(net "SEL_FLASH_PEX2_BUF_R")
	)
	(segment
		(start 294.871902 -196.149722)
		(end 294.871902 -195.442332)
		(width 0.13208)
		(layer "B.Cu")
		(net "SEL_FLASH_PEX2_BUF_R")
	)
	(segment
		(start 293.497254 -191.463168)
		(end 291.836348 -189.802262)
		(width 0.13208)
		(layer "B.Cu")
		(net "SEL_FLASH_PEX2_BUF_R")
	)
	(segment
		(start 249.626882 -231.13873)
		(end 249.626882 -230.772208)
		(width 0.13208)
		(layer "B.Cu")
		(net "SEL_FLASH_PEX2_BUF_R")
	)
	(segment
		(start 252.454664 -209.600546)
		(end 252.454664 -206.980536)
		(width 0.15494)
		(layer "In5.Cu")
		(net "SEL_FLASH_PEX2_BUF_R")
	)
	(segment
		(start 253.0602 -206.375)
		(end 253.0602 -201.60615)
		(width 0.15494)
		(layer "In5.Cu")
		(net "SEL_FLASH_PEX2_BUF_R")
	)
	(segment
		(start 260.979412 -182.964074)
		(end 260.836664 -182.821326)
		(width 0.15494)
		(layer "In5.Cu")
		(net "SEL_FLASH_PEX2_BUF_R")
	)
	(segment
		(start 249.626882 -231.13873)
		(end 249.646186 -231.13873)
		(width 0.15494)
		(layer "In5.Cu")
		(net "SEL_FLASH_PEX2_BUF_R")
	)
	(segment
		(start 253.0602 -201.60615)
		(end 256.338832 -198.327518)
		(width 0.15494)
		(layer "In5.Cu")
		(net "SEL_FLASH_PEX2_BUF_R")
	)
	(segment
		(start 250.2916 -230.493316)
		(end 250.2916 -227.6094)
		(width 0.15494)
		(layer "In5.Cu")
		(net "SEL_FLASH_PEX2_BUF_R")
	)
	(segment
		(start 251.535184 -213.214204)
		(end 253.03861 -211.710778)
		(width 0.15494)
		(layer "In5.Cu")
		(net "SEL_FLASH_PEX2_BUF_R")
	)
	(segment
		(start 250.2916 -227.6094)
		(end 249.809 -227.1268)
		(width 0.15494)
		(layer "In5.Cu")
		(net "SEL_FLASH_PEX2_BUF_R")
	)
	(segment
		(start 260.979412 -188.907674)
		(end 260.979412 -182.964074)
		(width 0.15494)
		(layer "In5.Cu")
		(net "SEL_FLASH_PEX2_BUF_R")
	)
	(segment
		(start 249.809 -227.1268)
		(end 249.809 -221.379034)
		(width 0.15494)
		(layer "In5.Cu")
		(net "SEL_FLASH_PEX2_BUF_R")
	)
	(segment
		(start 248.733818 -218.783154)
		(end 248.733818 -214.764366)
		(width 0.15494)
		(layer "In5.Cu")
		(net "SEL_FLASH_PEX2_BUF_R")
	)
	(segment
		(start 259.338064 -190.549022)
		(end 260.979412 -188.907674)
		(width 0.15494)
		(layer "In5.Cu")
		(net "SEL_FLASH_PEX2_BUF_R")
	)
	(segment
		(start 253.03861 -210.184492)
		(end 252.454664 -209.600546)
		(width 0.15494)
		(layer "In5.Cu")
		(net "SEL_FLASH_PEX2_BUF_R")
	)
	(segment
		(start 259.338064 -194.105784)
		(end 259.338064 -190.549022)
		(width 0.15494)
		(layer "In5.Cu")
		(net "SEL_FLASH_PEX2_BUF_R")
	)
	(segment
		(start 249.809 -221.379034)
		(end 248.733818 -218.783154)
		(width 0.15494)
		(layer "In5.Cu")
		(net "SEL_FLASH_PEX2_BUF_R")
	)
	(segment
		(start 256.338832 -197.105016)
		(end 259.338064 -194.105784)
		(width 0.15494)
		(layer "In5.Cu")
		(net "SEL_FLASH_PEX2_BUF_R")
	)
	(segment
		(start 253.03861 -211.710778)
		(end 253.03861 -210.184492)
		(width 0.15494)
		(layer "In5.Cu")
		(net "SEL_FLASH_PEX2_BUF_R")
	)
	(segment
		(start 248.733818 -214.764366)
		(end 250.28398 -213.214204)
		(width 0.15494)
		(layer "In5.Cu")
		(net "SEL_FLASH_PEX2_BUF_R")
	)
	(segment
		(start 256.338832 -198.327518)
		(end 256.338832 -197.105016)
		(width 0.15494)
		(layer "In5.Cu")
		(net "SEL_FLASH_PEX2_BUF_R")
	)
	(segment
		(start 252.454664 -206.980536)
		(end 253.0602 -206.375)
		(width 0.15494)
		(layer "In5.Cu")
		(net "SEL_FLASH_PEX2_BUF_R")
	)
	(segment
		(start 249.646186 -231.13873)
		(end 250.2916 -230.493316)
		(width 0.15494)
		(layer "In5.Cu")
		(net "SEL_FLASH_PEX2_BUF_R")
	)
	(segment
		(start 250.28398 -213.214204)
		(end 251.535184 -213.214204)
		(width 0.15494)
		(layer "In5.Cu")
		(net "SEL_FLASH_PEX2_BUF_R")
	)
	(segment
		(start 224.160588 -181.25821)
		(end 224.650046 -180.768752)
		(width 0.15494)
		(layer "In13.Cu")
		(net "SEL_FLASH_PEX2_BUF_R")
	)
	(segment
		(start 254.30607 -179.886356)
		(end 257.19913 -179.886356)
		(width 0.15494)
		(layer "In13.Cu")
		(net "SEL_FLASH_PEX2_BUF_R")
	)
	(segment
		(start 275.528532 -189.802262)
		(end 291.836348 -189.802262)
		(width 0.15494)
		(layer "In13.Cu")
		(net "SEL_FLASH_PEX2_BUF_R")
	)
	(segment
		(start 223.229678 -181.25821)
		(end 224.160588 -181.25821)
		(width 0.15494)
		(layer "In13.Cu")
		(net "SEL_FLASH_PEX2_BUF_R")
	)
	(segment
		(start 239.898174 -178.6382)
		(end 240.112042 -178.424332)
		(width 0.15494)
		(layer "In13.Cu")
		(net "SEL_FLASH_PEX2_BUF_R")
	)
	(segment
		(start 257.19913 -179.886356)
		(end 260.1341 -182.821326)
		(width 0.15494)
		(layer "In13.Cu")
		(net "SEL_FLASH_PEX2_BUF_R")
	)
	(segment
		(start 228.6 -178.1556)
		(end 229.889304 -178.1556)
		(width 0.15494)
		(layer "In13.Cu")
		(net "SEL_FLASH_PEX2_BUF_R")
	)
	(segment
		(start 231.516936 -177.89652)
		(end 232.258616 -178.6382)
		(width 0.15494)
		(layer "In13.Cu")
		(net "SEL_FLASH_PEX2_BUF_R")
	)
	(segment
		(start 252.864366 -178.444652)
		(end 254.30607 -179.886356)
		(width 0.15494)
		(layer "In13.Cu")
		(net "SEL_FLASH_PEX2_BUF_R")
	)
	(segment
		(start 260.1341 -182.821326)
		(end 260.836664 -182.821326)
		(width 0.15494)
		(layer "In13.Cu")
		(net "SEL_FLASH_PEX2_BUF_R")
	)
	(segment
		(start 229.889304 -178.1556)
		(end 230.148384 -177.89652)
		(width 0.15494)
		(layer "In13.Cu")
		(net "SEL_FLASH_PEX2_BUF_R")
	)
	(segment
		(start 240.112042 -178.424332)
		(end 252.137418 -178.424332)
		(width 0.15494)
		(layer "In13.Cu")
		(net "SEL_FLASH_PEX2_BUF_R")
	)
	(segment
		(start 268.547596 -182.821326)
		(end 275.528532 -189.802262)
		(width 0.15494)
		(layer "In13.Cu")
		(net "SEL_FLASH_PEX2_BUF_R")
	)
	(segment
		(start 232.258616 -178.6382)
		(end 239.898174 -178.6382)
		(width 0.15494)
		(layer "In13.Cu")
		(net "SEL_FLASH_PEX2_BUF_R")
	)
	(segment
		(start 260.836664 -182.821326)
		(end 268.547596 -182.821326)
		(width 0.15494)
		(layer "In13.Cu")
		(net "SEL_FLASH_PEX2_BUF_R")
	)
	(segment
		(start 224.650046 -180.768752)
		(end 225.986848 -180.768752)
		(width 0.15494)
		(layer "In13.Cu")
		(net "SEL_FLASH_PEX2_BUF_R")
	)
	(segment
		(start 220.368368 -184.11952)
		(end 223.229678 -181.25821)
		(width 0.15494)
		(layer "In13.Cu")
		(net "SEL_FLASH_PEX2_BUF_R")
	)
	(segment
		(start 230.148384 -177.89652)
		(end 231.516936 -177.89652)
		(width 0.15494)
		(layer "In13.Cu")
		(net "SEL_FLASH_PEX2_BUF_R")
	)
	(segment
		(start 252.157738 -178.444652)
		(end 252.864366 -178.444652)
		(width 0.15494)
		(layer "In13.Cu")
		(net "SEL_FLASH_PEX2_BUF_R")
	)
	(segment
		(start 225.986848 -180.768752)
		(end 228.6 -178.1556)
		(width 0.15494)
		(layer "In13.Cu")
		(net "SEL_FLASH_PEX2_BUF_R")
	)
	(segment
		(start 216.240106 -184.11952)
		(end 220.368368 -184.11952)
		(width 0.15494)
		(layer "In13.Cu")
		(net "SEL_FLASH_PEX2_BUF_R")
	)
	(segment
		(start 212.363812 -180.243226)
		(end 216.240106 -184.11952)
		(width 0.15494)
		(layer "In13.Cu")
		(net "SEL_FLASH_PEX2_BUF_R")
	)
	(segment
		(start 252.137418 -178.424332)
		(end 252.157738 -178.444652)
		(width 0.15494)
		(layer "In13.Cu")
		(net "SEL_FLASH_PEX2_BUF_R")
	)
	(segment
		(start 36.88969 -358.560878)
		(end 37.004498 -358.102662)
		(width 0.1651)
		(layer "In15.Cu")
		(net "P5E_PEX0_STN4_RX_DN<70>")
	)
	(segment
		(start 83.533742 -310.936386)
		(end 83.513676 -310.91632)
		(width 0.1143)
		(layer "In15.Cu")
		(net "P5E_PEX0_STN4_RX_DN<70>")
	)
	(segment
		(start 84.40674 -311.809384)
		(end 83.533742 -310.936386)
		(width 0.1651)
		(layer "In15.Cu")
		(net "P5E_PEX0_STN4_RX_DN<70>")
	)
	(segment
		(start 81.504028 -325.375778)
		(end 83.989164 -319.376806)
		(width 0.1651)
		(layer "In15.Cu")
		(net "P5E_PEX0_STN4_RX_DN<70>")
	)
	(segment
		(start 83.989164 -319.376806)
		(end 84.40674 -317.278004)
		(width 0.1651)
		(layer "In15.Cu")
		(net "P5E_PEX0_STN4_RX_DN<70>")
	)
	(segment
		(start 37.311584 -341.402162)
		(end 37.936678 -340.777068)
		(width 0.1651)
		(layer "In15.Cu")
		(net "P5E_PEX0_STN4_RX_DN<70>")
	)
	(segment
		(start 69.592952 -332.003908)
		(end 78.611476 -328.26833)
		(width 0.1651)
		(layer "In15.Cu")
		(net "P5E_PEX0_STN4_RX_DN<70>")
	)
	(segment
		(start 30.109922 -380.308104)
		(end 30.236922 -380.181104)
		(width 0.1651)
		(layer "In15.Cu")
		(net "P5E_PEX0_STN4_RX_DN<70>")
	)
	(segment
		(start 31.266892 -369.080034)
		(end 36.88969 -358.560878)
		(width 0.1651)
		(layer "In15.Cu")
		(net "P5E_PEX0_STN4_RX_DN<70>")
	)
	(segment
		(start 41.568624 -339.272626)
		(end 46.279308 -337.843622)
		(width 0.1651)
		(layer "In15.Cu")
		(net "P5E_PEX0_STN4_RX_DN<70>")
	)
	(segment
		(start 46.279308 -337.843622)
		(end 69.592952 -332.003908)
		(width 0.1651)
		(layer "In15.Cu")
		(net "P5E_PEX0_STN4_RX_DN<70>")
	)
	(segment
		(start 30.109922 -380.69012)
		(end 30.109922 -380.308104)
		(width 0.1651)
		(layer "In15.Cu")
		(net "P5E_PEX0_STN4_RX_DN<70>")
	)
	(segment
		(start 82.070194 -310.238648)
		(end 82.159094 -310.149748)
		(width 0.1143)
		(layer "In15.Cu")
		(net "P5E_PEX0_STN4_RX_DN<70>")
	)
	(segment
		(start 82.070194 -310.364378)
		(end 82.070194 -310.238648)
		(width 0.1143)
		(layer "In15.Cu")
		(net "P5E_PEX0_STN4_RX_DN<70>")
	)
	(segment
		(start 83.449414 -310.91632)
		(end 83.062572 -310.529478)
		(width 0.1143)
		(layer "In15.Cu")
		(net "P5E_PEX0_STN4_RX_DN<70>")
	)
	(segment
		(start 37.936678 -340.777068)
		(end 41.568624 -339.272626)
		(width 0.1651)
		(layer "In15.Cu")
		(net "P5E_PEX0_STN4_RX_DN<70>")
	)
	(segment
		(start 82.235294 -310.529478)
		(end 82.070194 -310.364378)
		(width 0.1143)
		(layer "In15.Cu")
		(net "P5E_PEX0_STN4_RX_DN<70>")
	)
	(segment
		(start 30.236922 -380.181104)
		(end 30.587442 -380.181104)
		(width 0.1651)
		(layer "In15.Cu")
		(net "P5E_PEX0_STN4_RX_DN<70>")
	)
	(segment
		(start 37.004498 -342.143334)
		(end 37.311584 -341.402162)
		(width 0.1651)
		(layer "In15.Cu")
		(net "P5E_PEX0_STN4_RX_DN<70>")
	)
	(segment
		(start 82.159094 -310.149748)
		(end 82.449924 -310.149748)
		(width 0.1143)
		(layer "In15.Cu")
		(net "P5E_PEX0_STN4_RX_DN<70>")
	)
	(segment
		(start 83.062572 -310.529478)
		(end 82.235294 -310.529478)
		(width 0.1143)
		(layer "In15.Cu")
		(net "P5E_PEX0_STN4_RX_DN<70>")
	)
	(segment
		(start 84.40674 -317.278004)
		(end 84.40674 -311.809384)
		(width 0.1651)
		(layer "In15.Cu")
		(net "P5E_PEX0_STN4_RX_DN<70>")
	)
	(segment
		(start 30.587442 -380.181104)
		(end 31.266892 -379.501654)
		(width 0.1651)
		(layer "In15.Cu")
		(net "P5E_PEX0_STN4_RX_DN<70>")
	)
	(segment
		(start 83.513676 -310.91632)
		(end 83.449414 -310.91632)
		(width 0.1143)
		(layer "In15.Cu")
		(net "P5E_PEX0_STN4_RX_DN<70>")
	)
	(segment
		(start 37.004498 -358.102662)
		(end 37.004498 -342.143334)
		(width 0.1651)
		(layer "In15.Cu")
		(net "P5E_PEX0_STN4_RX_DN<70>")
	)
	(segment
		(start 31.266892 -379.501654)
		(end 31.266892 -369.080034)
		(width 0.1651)
		(layer "In15.Cu")
		(net "P5E_PEX0_STN4_RX_DN<70>")
	)
	(segment
		(start 78.611476 -328.26833)
		(end 81.504028 -325.375778)
		(width 0.1651)
		(layer "In15.Cu")
		(net "P5E_PEX0_STN4_RX_DN<70>")
	)
	(segment
		(start 299.281342 -342.734138)
		(end 298.986702 -342.439498)
		(width 0.13462)
		(layer "F.Cu")
		(net "P5E_PEX2_STN4_TX_DP<65>")
	)
	(segment
		(start 299.281342 -343.365582)
		(end 299.281342 -342.734138)
		(width 0.13462)
		(layer "F.Cu")
		(net "P5E_PEX2_STN4_TX_DP<65>")
	)
	(segment
		(start 298.961302 -343.685622)
		(end 299.281342 -343.365582)
		(width 0.13462)
		(layer "F.Cu")
		(net "P5E_PEX2_STN4_TX_DP<65>")
	)
	(segment
		(start 300.506384 -340.716108)
		(end 300.44644 -340.866476)
		(width 0.1651)
		(layer "In11.Cu")
		(net "P5E_PEX2_STN4_TX_DP<65>")
	)
	(segment
		(start 300.44644 -340.866476)
		(end 299.585126 -341.236554)
		(width 0.1651)
		(layer "In11.Cu")
		(net "P5E_PEX2_STN4_TX_DP<65>")
	)
	(segment
		(start 309.571898 -305.97602)
		(end 315.791596 -305.97602)
		(width 0.1143)
		(layer "In11.Cu")
		(net "P5E_PEX2_STN4_TX_DP<65>")
	)
	(segment
		(start 330.301854 -317.657734)
		(end 330.916026 -319.140586)
		(width 0.1651)
		(layer "In11.Cu")
		(net "P5E_PEX2_STN4_TX_DP<65>")
	)
	(segment
		(start 308.949852 -305.399948)
		(end 309.215282 -305.399948)
		(width 0.1143)
		(layer "In11.Cu")
		(net "P5E_PEX2_STN4_TX_DP<65>")
	)
	(segment
		(start 309.34025 -305.524916)
		(end 309.34025 -305.744372)
		(width 0.1143)
		(layer "In11.Cu")
		(net "P5E_PEX2_STN4_TX_DP<65>")
	)
	(segment
		(start 317.219584 -306.02174)
		(end 319.594738 -307.005736)
		(width 0.1651)
		(layer "In11.Cu")
		(net "P5E_PEX2_STN4_TX_DP<65>")
	)
	(segment
		(start 330.301854 -317.65748)
		(end 330.301854 -317.657734)
		(width 0.1651)
		(layer "In11.Cu")
		(net "P5E_PEX2_STN4_TX_DP<65>")
	)
	(segment
		(start 319.594738 -307.005736)
		(end 327.107804 -313.595004)
		(width 0.1651)
		(layer "In11.Cu")
		(net "P5E_PEX2_STN4_TX_DP<65>")
	)
	(segment
		(start 301.11192 -340.580218)
		(end 300.961806 -340.520528)
		(width 0.1651)
		(layer "In11.Cu")
		(net "P5E_PEX2_STN4_TX_DP<65>")
	)
	(segment
		(start 329.010264 -326.737726)
		(end 325.982584 -329.891644)
		(width 0.1651)
		(layer "In11.Cu")
		(net "P5E_PEX2_STN4_TX_DP<65>")
	)
	(segment
		(start 299.277532 -342.148668)
		(end 298.986702 -342.439498)
		(width 0.1651)
		(layer "In11.Cu")
		(net "P5E_PEX2_STN4_TX_DP<65>")
	)
	(segment
		(start 330.91628 -319.14084)
		(end 330.91628 -322.9102)
		(width 0.1651)
		(layer "In11.Cu")
		(net "P5E_PEX2_STN4_TX_DP<65>")
	)
	(segment
		(start 299.277532 -341.544148)
		(end 299.277532 -342.148668)
		(width 0.1651)
		(layer "In11.Cu")
		(net "P5E_PEX2_STN4_TX_DP<65>")
	)
	(segment
		(start 329.687936 -316.175136)
		(end 330.301854 -317.65748)
		(width 0.1651)
		(layer "In11.Cu")
		(net "P5E_PEX2_STN4_TX_DP<65>")
	)
	(segment
		(start 327.107804 -313.595004)
		(end 329.687936 -316.175136)
		(width 0.1651)
		(layer "In11.Cu")
		(net "P5E_PEX2_STN4_TX_DP<65>")
	)
	(segment
		(start 315.791596 -305.97602)
		(end 315.837316 -306.02174)
		(width 0.1143)
		(layer "In11.Cu")
		(net "P5E_PEX2_STN4_TX_DP<65>")
	)
	(segment
		(start 330.91628 -322.9102)
		(end 329.010264 -326.737726)
		(width 0.1651)
		(layer "In11.Cu")
		(net "P5E_PEX2_STN4_TX_DP<65>")
	)
	(segment
		(start 309.215282 -305.399948)
		(end 309.34025 -305.524916)
		(width 0.1143)
		(layer "In11.Cu")
		(net "P5E_PEX2_STN4_TX_DP<65>")
	)
	(segment
		(start 330.916026 -319.140586)
		(end 330.91628 -319.14084)
		(width 0.1651)
		(layer "In11.Cu")
		(net "P5E_PEX2_STN4_TX_DP<65>")
	)
	(segment
		(start 299.585126 -341.236554)
		(end 299.277532 -341.544148)
		(width 0.1651)
		(layer "In11.Cu")
		(net "P5E_PEX2_STN4_TX_DP<65>")
	)
	(segment
		(start 315.865764 -306.02174)
		(end 317.219584 -306.02174)
		(width 0.1651)
		(layer "In11.Cu")
		(net "P5E_PEX2_STN4_TX_DP<65>")
	)
	(segment
		(start 309.34025 -305.744372)
		(end 309.571898 -305.97602)
		(width 0.1143)
		(layer "In11.Cu")
		(net "P5E_PEX2_STN4_TX_DP<65>")
	)
	(segment
		(start 315.837316 -306.02174)
		(end 315.865764 -306.02174)
		(width 0.1143)
		(layer "In11.Cu")
		(net "P5E_PEX2_STN4_TX_DP<65>")
	)
	(segment
		(start 325.982584 -329.891644)
		(end 301.11192 -340.580218)
		(width 0.1651)
		(layer "In11.Cu")
		(net "P5E_PEX2_STN4_TX_DP<65>")
	)
	(segment
		(start 300.961806 -340.520528)
		(end 300.506384 -340.716108)
		(width 0.1651)
		(layer "In11.Cu")
		(net "P5E_PEX2_STN4_TX_DP<65>")
	)
	(segment
		(start 22.4155 -385.078732)
		(end 21.480018 -375.578116)
		(width 0.1651)
		(layer "In15.Cu")
		(net "P5E_PEX0_STN4_RX_DP<76>")
	)
	(segment
		(start 24.588216 -388.534402)
		(end 23.322788 -387.268974)
		(width 0.1651)
		(layer "In15.Cu")
		(net "P5E_PEX0_STN4_RX_DP<76>")
	)
	(segment
		(start 34.221166 -394.28674)
		(end 34.095436 -394.28674)
		(width 0.1651)
		(layer "In15.Cu")
		(net "P5E_PEX0_STN4_RX_DP<76>")
	)
	(segment
		(start 35.384994 -396.092172)
		(end 34.93135 -394.996924)
		(width 0.1651)
		(layer "In15.Cu")
		(net "P5E_PEX0_STN4_RX_DP<76>")
	)
	(segment
		(start 34.509964 -405.390096)
		(end 34.509964 -405.772112)
		(width 0.1651)
		(layer "In15.Cu")
		(net "P5E_PEX0_STN4_RX_DP<76>")
	)
	(segment
		(start 76.405486 -318.129666)
		(end 76.63561 -318.129666)
		(width 0.1143)
		(layer "In15.Cu")
		(net "P5E_PEX0_STN4_RX_DP<76>")
	)
	(segment
		(start 18.03146 -352.331528)
		(end 18.03146 -342.350852)
		(width 0.1651)
		(layer "In15.Cu")
		(net "P5E_PEX0_STN4_RX_DP<76>")
	)
	(segment
		(start 23.322788 -387.268974)
		(end 22.4155 -385.078732)
		(width 0.1651)
		(layer "In15.Cu")
		(net "P5E_PEX0_STN4_RX_DP<76>")
	)
	(segment
		(start 18.03146 -342.350852)
		(end 18.44421 -341.35441)
		(width 0.1651)
		(layer "In15.Cu")
		(net "P5E_PEX0_STN4_RX_DP<76>")
	)
	(segment
		(start 34.93135 -394.996924)
		(end 34.221166 -394.28674)
		(width 0.1651)
		(layer "In15.Cu")
		(net "P5E_PEX0_STN4_RX_DP<76>")
	)
	(segment
		(start 75.123802 -323.14261)
		(end 76.13396 -322.132452)
		(width 0.1651)
		(layer "In15.Cu")
		(net "P5E_PEX0_STN4_RX_DP<76>")
	)
	(segment
		(start 34.870644 -405.899112)
		(end 35.384994 -405.384762)
		(width 0.1651)
		(layer "In15.Cu")
		(net "P5E_PEX0_STN4_RX_DP<76>")
	)
	(segment
		(start 34.095436 -394.28674)
		(end 33.75406 -393.945364)
		(width 0.1651)
		(layer "In15.Cu")
		(net "P5E_PEX0_STN4_RX_DP<76>")
	)
	(segment
		(start 33.75406 -393.945364)
		(end 33.75406 -393.819634)
		(width 0.1651)
		(layer "In15.Cu")
		(net "P5E_PEX0_STN4_RX_DP<76>")
	)
	(segment
		(start 76.17968 -319.84188)
		(end 76.17968 -318.355472)
		(width 0.1143)
		(layer "In15.Cu")
		(net "P5E_PEX0_STN4_RX_DP<76>")
	)
	(segment
		(start 21.480018 -375.578116)
		(end 18.03146 -352.331528)
		(width 0.1651)
		(layer "In15.Cu")
		(net "P5E_PEX0_STN4_RX_DP<76>")
	)
	(segment
		(start 33.078928 -393.144502)
		(end 29.52877 -391.246106)
		(width 0.1651)
		(layer "In15.Cu")
		(net "P5E_PEX0_STN4_RX_DP<76>")
	)
	(segment
		(start 76.63561 -318.129666)
		(end 76.74991 -318.015366)
		(width 0.1143)
		(layer "In15.Cu")
		(net "P5E_PEX0_STN4_RX_DP<76>")
	)
	(segment
		(start 35.384994 -405.384762)
		(end 35.384994 -396.092172)
		(width 0.1651)
		(layer "In15.Cu")
		(net "P5E_PEX0_STN4_RX_DP<76>")
	)
	(segment
		(start 27.206702 -390.284208)
		(end 24.588216 -388.534402)
		(width 0.1651)
		(layer "In15.Cu")
		(net "P5E_PEX0_STN4_RX_DP<76>")
	)
	(segment
		(start 76.17968 -318.355472)
		(end 76.405486 -318.129666)
		(width 0.1143)
		(layer "In15.Cu")
		(net "P5E_PEX0_STN4_RX_DP<76>")
	)
	(segment
		(start 68.259706 -325.985886)
		(end 75.123802 -323.14261)
		(width 0.1651)
		(layer "In15.Cu")
		(net "P5E_PEX0_STN4_RX_DP<76>")
	)
	(segment
		(start 34.636964 -405.899112)
		(end 34.870644 -405.899112)
		(width 0.1651)
		(layer "In15.Cu")
		(net "P5E_PEX0_STN4_RX_DP<76>")
	)
	(segment
		(start 18.44421 -341.35441)
		(end 18.91792 -340.8807)
		(width 0.1651)
		(layer "In15.Cu")
		(net "P5E_PEX0_STN4_RX_DP<76>")
	)
	(segment
		(start 29.52877 -391.246106)
		(end 27.206702 -390.284208)
		(width 0.1651)
		(layer "In15.Cu")
		(net "P5E_PEX0_STN4_RX_DP<76>")
	)
	(segment
		(start 23.299166 -338.938362)
		(end 33.669224 -335.083404)
		(width 0.1651)
		(layer "In15.Cu")
		(net "P5E_PEX0_STN4_RX_DP<76>")
	)
	(segment
		(start 76.74991 -318.015366)
		(end 76.74991 -317.749936)
		(width 0.1143)
		(layer "In15.Cu")
		(net "P5E_PEX0_STN4_RX_DP<76>")
	)
	(segment
		(start 33.75406 -393.819634)
		(end 33.078928 -393.144502)
		(width 0.1651)
		(layer "In15.Cu")
		(net "P5E_PEX0_STN4_RX_DP<76>")
	)
	(segment
		(start 18.91792 -340.8807)
		(end 23.299166 -338.938362)
		(width 0.1651)
		(layer "In15.Cu")
		(net "P5E_PEX0_STN4_RX_DP<76>")
	)
	(segment
		(start 41.864026 -332.597506)
		(end 55.061866 -329.291696)
		(width 0.1651)
		(layer "In15.Cu")
		(net "P5E_PEX0_STN4_RX_DP<76>")
	)
	(segment
		(start 76.13396 -322.132452)
		(end 76.13396 -319.916048)
		(width 0.1651)
		(layer "In15.Cu")
		(net "P5E_PEX0_STN4_RX_DP<76>")
	)
	(segment
		(start 55.06212 -329.291696)
		(end 68.259706 -325.985886)
		(width 0.1651)
		(layer "In15.Cu")
		(net "P5E_PEX0_STN4_RX_DP<76>")
	)
	(segment
		(start 76.13396 -319.8876)
		(end 76.17968 -319.84188)
		(width 0.1143)
		(layer "In15.Cu")
		(net "P5E_PEX0_STN4_RX_DP<76>")
	)
	(segment
		(start 34.509964 -405.772112)
		(end 34.636964 -405.899112)
		(width 0.1651)
		(layer "In15.Cu")
		(net "P5E_PEX0_STN4_RX_DP<76>")
	)
	(segment
		(start 33.669224 -335.083404)
		(end 41.864026 -332.597506)
		(width 0.1651)
		(layer "In15.Cu")
		(net "P5E_PEX0_STN4_RX_DP<76>")
	)
	(segment
		(start 76.13396 -319.916048)
		(end 76.13396 -319.8876)
		(width 0.1143)
		(layer "In15.Cu")
		(net "P5E_PEX0_STN4_RX_DP<76>")
	)
	(segment
		(start 55.061866 -329.291696)
		(end 55.06212 -329.291696)
		(width 0.1651)
		(layer "In15.Cu")
		(net "P5E_PEX0_STN4_RX_DP<76>")
	)
	(segment
		(start 277.518622 -348.88043)
		(end 277.223982 -348.58579)
		(width 0.13462)
		(layer "F.Cu")
		(net "P5E_PEX2_STN4_TX_DP<75>")
	)
	(segment
		(start 277.518622 -349.511874)
		(end 277.518622 -348.88043)
		(width 0.13462)
		(layer "F.Cu")
		(net "P5E_PEX2_STN4_TX_DP<75>")
	)
	(segment
		(start 277.198582 -349.831914)
		(end 277.518622 -349.511874)
		(width 0.13462)
		(layer "F.Cu")
		(net "P5E_PEX2_STN4_TX_DP<75>")
	)
	(segment
		(start 309.329582 -319.955418)
		(end 309.283862 -320.001138)
		(width 0.1143)
		(layer "In11.Cu")
		(net "P5E_PEX2_STN4_TX_DP<75>")
	)
	(segment
		(start 277.514812 -348.29496)
		(end 277.223982 -348.58579)
		(width 0.1651)
		(layer "In11.Cu")
		(net "P5E_PEX2_STN4_TX_DP<75>")
	)
	(segment
		(start 280.80716 -339.44814)
		(end 279.069292 -341.186008)
		(width 0.1651)
		(layer "In11.Cu")
		(net "P5E_PEX2_STN4_TX_DP<75>")
	)
	(segment
		(start 277.514812 -347.667834)
		(end 277.514812 -348.29496)
		(width 0.1651)
		(layer "In11.Cu")
		(net "P5E_PEX2_STN4_TX_DP<75>")
	)
	(segment
		(start 307.198014 -324.378066)
		(end 280.80716 -339.44814)
		(width 0.1651)
		(layer "In11.Cu")
		(net "P5E_PEX2_STN4_TX_DP<75>")
	)
	(segment
		(start 309.54472 -311.479692)
		(end 309.329582 -311.69483)
		(width 0.1143)
		(layer "In11.Cu")
		(net "P5E_PEX2_STN4_TX_DP<75>")
	)
	(segment
		(start 309.899812 -311.099962)
		(end 309.899812 -311.365392)
		(width 0.1143)
		(layer "In11.Cu")
		(net "P5E_PEX2_STN4_TX_DP<75>")
	)
	(segment
		(start 309.255414 -322.320666)
		(end 307.198014 -324.378066)
		(width 0.1651)
		(layer "In11.Cu")
		(net "P5E_PEX2_STN4_TX_DP<75>")
	)
	(segment
		(start 309.899812 -311.365392)
		(end 309.785512 -311.479692)
		(width 0.1143)
		(layer "In11.Cu")
		(net "P5E_PEX2_STN4_TX_DP<75>")
	)
	(segment
		(start 279.069292 -341.186008)
		(end 279.069292 -346.113354)
		(width 0.1651)
		(layer "In11.Cu")
		(net "P5E_PEX2_STN4_TX_DP<75>")
	)
	(segment
		(start 279.069292 -346.113354)
		(end 277.514812 -347.667834)
		(width 0.1651)
		(layer "In11.Cu")
		(net "P5E_PEX2_STN4_TX_DP<75>")
	)
	(segment
		(start 309.785512 -311.479692)
		(end 309.54472 -311.479692)
		(width 0.1143)
		(layer "In11.Cu")
		(net "P5E_PEX2_STN4_TX_DP<75>")
	)
	(segment
		(start 309.283862 -320.001138)
		(end 309.283862 -320.023236)
		(width 0.1143)
		(layer "In11.Cu")
		(net "P5E_PEX2_STN4_TX_DP<75>")
	)
	(segment
		(start 309.329582 -311.69483)
		(end 309.329582 -319.955418)
		(width 0.1143)
		(layer "In11.Cu")
		(net "P5E_PEX2_STN4_TX_DP<75>")
	)
	(segment
		(start 309.283862 -322.252086)
		(end 309.255414 -322.320666)
		(width 0.1651)
		(layer "In11.Cu")
		(net "P5E_PEX2_STN4_TX_DP<75>")
	)
	(segment
		(start 309.283862 -320.023236)
		(end 309.283862 -322.252086)
		(width 0.1651)
		(layer "In11.Cu")
		(net "P5E_PEX2_STN4_TX_DP<75>")
	)
	(segment
		(start 23.010368 -350.685354)
		(end 23.330408 -350.365314)
		(width 0.13462)
		(layer "F.Cu")
		(net "P5E_PEX0_STN4_TX_C_DN<78>")
	)
	(segment
		(start 23.010368 -351.316798)
		(end 23.010368 -350.685354)
		(width 0.13462)
		(layer "F.Cu")
		(net "P5E_PEX0_STN4_TX_C_DN<78>")
	)
	(segment
		(start 23.305008 -351.611438)
		(end 23.010368 -351.316798)
		(width 0.13462)
		(layer "F.Cu")
		(net "P5E_PEX0_STN4_TX_C_DN<78>")
	)
	(segment
		(start 21.486114 -354.065586)
		(end 23.014178 -352.537522)
		(width 0.1651)
		(layer "In11.Cu")
		(net "P5E_PEX0_STN4_TX_C_DN<78>")
	)
	(segment
		(start 20.689316 -384.15595)
		(end 20.689316 -381.611378)
		(width 0.1651)
		(layer "In11.Cu")
		(net "P5E_PEX0_STN4_TX_C_DN<78>")
	)
	(segment
		(start 30.109922 -398.50822)
		(end 30.236922 -398.38122)
		(width 0.1651)
		(layer "In11.Cu")
		(net "P5E_PEX0_STN4_TX_C_DN<78>")
	)
	(segment
		(start 30.77718 -398.38122)
		(end 31.284418 -397.873982)
		(width 0.1651)
		(layer "In11.Cu")
		(net "P5E_PEX0_STN4_TX_C_DN<78>")
	)
	(segment
		(start 23.014178 -351.902268)
		(end 23.305008 -351.611438)
		(width 0.1651)
		(layer "In11.Cu")
		(net "P5E_PEX0_STN4_TX_C_DN<78>")
	)
	(segment
		(start 20.90674 -365.85779)
		(end 21.486114 -354.065586)
		(width 0.1651)
		(layer "In11.Cu")
		(net "P5E_PEX0_STN4_TX_C_DN<78>")
	)
	(segment
		(start 31.284418 -395.016228)
		(end 24.682958 -390.605264)
		(width 0.1651)
		(layer "In11.Cu")
		(net "P5E_PEX0_STN4_TX_C_DN<78>")
	)
	(segment
		(start 23.014178 -352.537522)
		(end 23.014178 -351.902268)
		(width 0.1651)
		(layer "In11.Cu")
		(net "P5E_PEX0_STN4_TX_C_DN<78>")
	)
	(segment
		(start 24.682958 -390.605264)
		(end 22.425914 -388.34822)
		(width 0.1651)
		(layer "In11.Cu")
		(net "P5E_PEX0_STN4_TX_C_DN<78>")
	)
	(segment
		(start 30.109922 -398.890236)
		(end 30.109922 -398.50822)
		(width 0.1651)
		(layer "In11.Cu")
		(net "P5E_PEX0_STN4_TX_C_DN<78>")
	)
	(segment
		(start 20.90674 -368.106452)
		(end 20.90674 -365.85779)
		(width 0.1651)
		(layer "In11.Cu")
		(net "P5E_PEX0_STN4_TX_C_DN<78>")
	)
	(segment
		(start 31.284418 -397.873982)
		(end 31.284418 -395.016228)
		(width 0.1651)
		(layer "In11.Cu")
		(net "P5E_PEX0_STN4_TX_C_DN<78>")
	)
	(segment
		(start 30.236922 -398.38122)
		(end 30.77718 -398.38122)
		(width 0.1651)
		(layer "In11.Cu")
		(net "P5E_PEX0_STN4_TX_C_DN<78>")
	)
	(segment
		(start 22.425914 -388.34822)
		(end 20.689316 -384.15595)
		(width 0.1651)
		(layer "In11.Cu")
		(net "P5E_PEX0_STN4_TX_C_DN<78>")
	)
	(segment
		(start 20.689316 -381.611378)
		(end 20.90674 -368.106452)
		(width 0.1651)
		(layer "In11.Cu")
		(net "P5E_PEX0_STN4_TX_C_DN<78>")
	)
	(segment
		(start 299.281342 -355.658166)
		(end 299.281342 -355.026722)
		(width 0.13462)
		(layer "F.Cu")
		(net "P5E_PEX2_STN4_TX_DP<64>")
	)
	(segment
		(start 298.961302 -355.978206)
		(end 299.281342 -355.658166)
		(width 0.13462)
		(layer "F.Cu")
		(net "P5E_PEX2_STN4_TX_DP<64>")
	)
	(segment
		(start 299.281342 -355.026722)
		(end 298.986702 -354.732082)
		(width 0.13462)
		(layer "F.Cu")
		(net "P5E_PEX2_STN4_TX_DP<64>")
	)
	(segment
		(start 298.986702 -354.732082)
		(end 299.277532 -354.441252)
		(width 0.1651)
		(layer "In11.Cu")
		(net "P5E_PEX2_STN4_TX_DP<64>")
	)
	(segment
		(start 317.438024 -305.054)
		(end 315.852048 -305.054)
		(width 0.1651)
		(layer "In11.Cu")
		(net "P5E_PEX2_STN4_TX_DP<64>")
	)
	(segment
		(start 299.277532 -354.441252)
		(end 299.277532 -353.670616)
		(width 0.1651)
		(layer "In11.Cu")
		(net "P5E_PEX2_STN4_TX_DP<64>")
	)
	(segment
		(start 326.261476 -330.980034)
		(end 329.742038 -327.465436)
		(width 0.1651)
		(layer "In11.Cu")
		(net "P5E_PEX2_STN4_TX_DP<64>")
	)
	(segment
		(start 327.701656 -312.756296)
		(end 320.15684 -306.180236)
		(width 0.1651)
		(layer "In11.Cu")
		(net "P5E_PEX2_STN4_TX_DP<64>")
	)
	(segment
		(start 315.852048 -305.054)
		(end 315.8236 -305.054)
		(width 0.1143)
		(layer "In11.Cu")
		(net "P5E_PEX2_STN4_TX_DP<64>")
	)
	(segment
		(start 331.90434 -318.926972)
		(end 330.512674 -315.567314)
		(width 0.1651)
		(layer "In11.Cu")
		(net "P5E_PEX2_STN4_TX_DP<64>")
	)
	(segment
		(start 315.8236 -305.054)
		(end 315.77788 -305.00828)
		(width 0.1143)
		(layer "In11.Cu")
		(net "P5E_PEX2_STN4_TX_DP<64>")
	)
	(segment
		(start 320.15684 -306.180236)
		(end 317.438024 -305.054)
		(width 0.1651)
		(layer "In11.Cu")
		(net "P5E_PEX2_STN4_TX_DP<64>")
	)
	(segment
		(start 299.277532 -353.670616)
		(end 309.979314 -342.32215)
		(width 0.1651)
		(layer "In11.Cu")
		(net "P5E_PEX2_STN4_TX_DP<64>")
	)
	(segment
		(start 307.44033 -304.574702)
		(end 307.315362 -304.449734)
		(width 0.1143)
		(layer "In11.Cu")
		(net "P5E_PEX2_STN4_TX_DP<64>")
	)
	(segment
		(start 307.315362 -304.449734)
		(end 307.049932 -304.449734)
		(width 0.1143)
		(layer "In11.Cu")
		(net "P5E_PEX2_STN4_TX_DP<64>")
	)
	(segment
		(start 307.666136 -305.00828)
		(end 307.44033 -304.782474)
		(width 0.1143)
		(layer "In11.Cu")
		(net "P5E_PEX2_STN4_TX_DP<64>")
	)
	(segment
		(start 329.741784 -327.465436)
		(end 331.90434 -323.130672)
		(width 0.1651)
		(layer "In11.Cu")
		(net "P5E_PEX2_STN4_TX_DP<64>")
	)
	(segment
		(start 329.742038 -327.465436)
		(end 329.741784 -327.465436)
		(width 0.1651)
		(layer "In11.Cu")
		(net "P5E_PEX2_STN4_TX_DP<64>")
	)
	(segment
		(start 315.77788 -305.00828)
		(end 307.666136 -305.00828)
		(width 0.1143)
		(layer "In11.Cu")
		(net "P5E_PEX2_STN4_TX_DP<64>")
	)
	(segment
		(start 331.90434 -323.130672)
		(end 331.90434 -318.926972)
		(width 0.1651)
		(layer "In11.Cu")
		(net "P5E_PEX2_STN4_TX_DP<64>")
	)
	(segment
		(start 307.44033 -304.782474)
		(end 307.44033 -304.574702)
		(width 0.1143)
		(layer "In11.Cu")
		(net "P5E_PEX2_STN4_TX_DP<64>")
	)
	(segment
		(start 330.512674 -315.567314)
		(end 327.701656 -312.756296)
		(width 0.1651)
		(layer "In11.Cu")
		(net "P5E_PEX2_STN4_TX_DP<64>")
	)
	(segment
		(start 309.979314 -342.32215)
		(end 326.261476 -330.980034)
		(width 0.1651)
		(layer "In11.Cu")
		(net "P5E_PEX2_STN4_TX_DP<64>")
	)
	(segment
		(start 29.228288 -350.685354)
		(end 29.548328 -350.365314)
		(width 0.13462)
		(layer "F.Cu")
		(net "P5E_PEX0_STN4_TX_C_DN<75>")
	)
	(segment
		(start 29.228288 -351.316798)
		(end 29.228288 -350.685354)
		(width 0.13462)
		(layer "F.Cu")
		(net "P5E_PEX0_STN4_TX_C_DN<75>")
	)
	(segment
		(start 29.522928 -351.611438)
		(end 29.228288 -351.316798)
		(width 0.13462)
		(layer "F.Cu")
		(net "P5E_PEX0_STN4_TX_C_DN<75>")
	)
	(segment
		(start 24.907494 -364.911386)
		(end 27.677618 -359.055416)
		(width 0.1651)
		(layer "In11.Cu")
		(net "P5E_PEX0_STN4_TX_C_DN<75>")
	)
	(segment
		(start 31.462218 -390.269222)
		(end 26.233374 -388.103364)
		(width 0.1651)
		(layer "In11.Cu")
		(net "P5E_PEX0_STN4_TX_C_DN<75>")
	)
	(segment
		(start 27.677618 -359.055416)
		(end 27.677618 -354.092002)
		(width 0.1651)
		(layer "In11.Cu")
		(net "P5E_PEX0_STN4_TX_C_DN<75>")
	)
	(segment
		(start 26.233374 -388.103364)
		(end 24.855678 -386.725668)
		(width 0.1651)
		(layer "In11.Cu")
		(net "P5E_PEX0_STN4_TX_C_DN<75>")
	)
	(segment
		(start 36.710112 -397.408146)
		(end 36.837112 -397.281146)
		(width 0.1651)
		(layer "In11.Cu")
		(net "P5E_PEX0_STN4_TX_C_DN<75>")
	)
	(segment
		(start 37.276278 -394.153898)
		(end 31.462218 -390.269222)
		(width 0.1651)
		(layer "In11.Cu")
		(net "P5E_PEX0_STN4_TX_C_DN<75>")
	)
	(segment
		(start 36.710112 -397.790162)
		(end 36.710112 -397.408146)
		(width 0.1651)
		(layer "In11.Cu")
		(net "P5E_PEX0_STN4_TX_C_DN<75>")
	)
	(segment
		(start 23.989284 -368.999008)
		(end 24.907494 -364.911386)
		(width 0.1651)
		(layer "In11.Cu")
		(net "P5E_PEX0_STN4_TX_C_DN<75>")
	)
	(segment
		(start 29.232098 -351.902268)
		(end 29.522928 -351.611438)
		(width 0.1651)
		(layer "In11.Cu")
		(net "P5E_PEX0_STN4_TX_C_DN<75>")
	)
	(segment
		(start 23.785576 -381.634238)
		(end 23.989284 -368.999008)
		(width 0.1651)
		(layer "In11.Cu")
		(net "P5E_PEX0_STN4_TX_C_DN<75>")
	)
	(segment
		(start 37.884354 -394.761974)
		(end 37.276278 -394.153898)
		(width 0.1651)
		(layer "In11.Cu")
		(net "P5E_PEX0_STN4_TX_C_DN<75>")
	)
	(segment
		(start 36.837112 -397.281146)
		(end 37.350192 -397.281146)
		(width 0.1651)
		(layer "In11.Cu")
		(net "P5E_PEX0_STN4_TX_C_DN<75>")
	)
	(segment
		(start 23.785576 -384.142234)
		(end 23.785576 -381.634238)
		(width 0.1651)
		(layer "In11.Cu")
		(net "P5E_PEX0_STN4_TX_C_DN<75>")
	)
	(segment
		(start 37.884354 -396.746984)
		(end 37.884354 -394.761974)
		(width 0.1651)
		(layer "In11.Cu")
		(net "P5E_PEX0_STN4_TX_C_DN<75>")
	)
	(segment
		(start 27.677618 -354.092002)
		(end 29.232098 -352.537522)
		(width 0.1651)
		(layer "In11.Cu")
		(net "P5E_PEX0_STN4_TX_C_DN<75>")
	)
	(segment
		(start 24.855678 -386.725668)
		(end 23.785576 -384.142234)
		(width 0.1651)
		(layer "In11.Cu")
		(net "P5E_PEX0_STN4_TX_C_DN<75>")
	)
	(segment
		(start 37.350192 -397.281146)
		(end 37.884354 -396.746984)
		(width 0.1651)
		(layer "In11.Cu")
		(net "P5E_PEX0_STN4_TX_C_DN<75>")
	)
	(segment
		(start 29.232098 -352.537522)
		(end 29.232098 -351.902268)
		(width 0.1651)
		(layer "In11.Cu")
		(net "P5E_PEX0_STN4_TX_C_DN<75>")
	)
	(segment
		(start 41.93921 -332.86954)
		(end 68.348352 -326.254364)
		(width 0.1651)
		(layer "In15.Cu")
		(net "P5E_PEX0_STN4_RX_DN<76>")
	)
	(segment
		(start 27.340306 -390.034272)
		(end 24.768048 -388.315454)
		(width 0.1651)
		(layer "In15.Cu")
		(net "P5E_PEX0_STN4_RX_DN<76>")
	)
	(segment
		(start 68.348352 -326.254364)
		(end 75.283568 -323.381624)
		(width 0.1651)
		(layer "In15.Cu")
		(net "P5E_PEX0_STN4_RX_DN<76>")
	)
	(segment
		(start 23.561802 -387.109208)
		(end 22.692106 -385.00939)
		(width 0.1651)
		(layer "In15.Cu")
		(net "P5E_PEX0_STN4_RX_DN<76>")
	)
	(segment
		(start 76.63561 -318.320166)
		(end 76.74991 -318.434466)
		(width 0.1143)
		(layer "In15.Cu")
		(net "P5E_PEX0_STN4_RX_DN<76>")
	)
	(segment
		(start 35.170364 -394.837158)
		(end 33.248854 -392.915394)
		(width 0.1651)
		(layer "In15.Cu")
		(net "P5E_PEX0_STN4_RX_DN<76>")
	)
	(segment
		(start 76.37018 -318.434466)
		(end 76.48448 -318.320166)
		(width 0.1143)
		(layer "In15.Cu")
		(net "P5E_PEX0_STN4_RX_DN<76>")
	)
	(segment
		(start 34.509964 -406.308052)
		(end 34.636964 -406.181052)
		(width 0.1651)
		(layer "In15.Cu")
		(net "P5E_PEX0_STN4_RX_DN<76>")
	)
	(segment
		(start 18.3134 -352.3107)
		(end 18.3134 -342.406986)
		(width 0.1651)
		(layer "In15.Cu")
		(net "P5E_PEX0_STN4_RX_DN<76>")
	)
	(segment
		(start 35.666934 -396.036038)
		(end 35.170364 -394.837158)
		(width 0.1651)
		(layer "In15.Cu")
		(net "P5E_PEX0_STN4_RX_DN<76>")
	)
	(segment
		(start 76.4159 -322.249292)
		(end 76.4159 -319.916048)
		(width 0.1651)
		(layer "In15.Cu")
		(net "P5E_PEX0_STN4_RX_DN<76>")
	)
	(segment
		(start 75.283568 -323.381624)
		(end 76.4159 -322.249292)
		(width 0.1651)
		(layer "In15.Cu")
		(net "P5E_PEX0_STN4_RX_DN<76>")
	)
	(segment
		(start 76.74991 -318.434466)
		(end 76.74991 -318.699896)
		(width 0.1143)
		(layer "In15.Cu")
		(net "P5E_PEX0_STN4_RX_DN<76>")
	)
	(segment
		(start 34.987484 -406.181052)
		(end 35.666934 -405.501602)
		(width 0.1651)
		(layer "In15.Cu")
		(net "P5E_PEX0_STN4_RX_DN<76>")
	)
	(segment
		(start 76.4159 -319.916048)
		(end 76.4159 -319.8876)
		(width 0.1143)
		(layer "In15.Cu")
		(net "P5E_PEX0_STN4_RX_DN<76>")
	)
	(segment
		(start 18.683224 -341.514176)
		(end 19.080226 -341.117174)
		(width 0.1651)
		(layer "In15.Cu")
		(net "P5E_PEX0_STN4_RX_DN<76>")
	)
	(segment
		(start 35.666934 -405.501602)
		(end 35.666934 -396.036038)
		(width 0.1651)
		(layer "In15.Cu")
		(net "P5E_PEX0_STN4_RX_DN<76>")
	)
	(segment
		(start 33.248854 -392.915394)
		(end 29.64942 -390.990836)
		(width 0.1651)
		(layer "In15.Cu")
		(net "P5E_PEX0_STN4_RX_DN<76>")
	)
	(segment
		(start 76.4159 -319.8876)
		(end 76.37018 -319.84188)
		(width 0.1143)
		(layer "In15.Cu")
		(net "P5E_PEX0_STN4_RX_DN<76>")
	)
	(segment
		(start 23.405592 -339.199728)
		(end 33.759394 -335.350866)
		(width 0.1651)
		(layer "In15.Cu")
		(net "P5E_PEX0_STN4_RX_DN<76>")
	)
	(segment
		(start 24.768048 -388.315454)
		(end 23.561802 -387.109208)
		(width 0.1651)
		(layer "In15.Cu")
		(net "P5E_PEX0_STN4_RX_DN<76>")
	)
	(segment
		(start 34.636964 -406.181052)
		(end 34.987484 -406.181052)
		(width 0.1651)
		(layer "In15.Cu")
		(net "P5E_PEX0_STN4_RX_DN<76>")
	)
	(segment
		(start 33.759394 -335.350866)
		(end 41.93921 -332.86954)
		(width 0.1651)
		(layer "In15.Cu")
		(net "P5E_PEX0_STN4_RX_DN<76>")
	)
	(segment
		(start 76.37018 -319.84188)
		(end 76.37018 -318.434466)
		(width 0.1143)
		(layer "In15.Cu")
		(net "P5E_PEX0_STN4_RX_DN<76>")
	)
	(segment
		(start 18.3134 -342.406986)
		(end 18.683224 -341.514176)
		(width 0.1651)
		(layer "In15.Cu")
		(net "P5E_PEX0_STN4_RX_DN<76>")
	)
	(segment
		(start 22.692106 -385.00939)
		(end 21.759926 -375.543572)
		(width 0.1651)
		(layer "In15.Cu")
		(net "P5E_PEX0_STN4_RX_DN<76>")
	)
	(segment
		(start 29.64942 -390.990836)
		(end 27.340306 -390.034272)
		(width 0.1651)
		(layer "In15.Cu")
		(net "P5E_PEX0_STN4_RX_DN<76>")
	)
	(segment
		(start 19.080226 -341.117174)
		(end 23.405592 -339.199728)
		(width 0.1651)
		(layer "In15.Cu")
		(net "P5E_PEX0_STN4_RX_DN<76>")
	)
	(segment
		(start 76.48448 -318.320166)
		(end 76.63561 -318.320166)
		(width 0.1143)
		(layer "In15.Cu")
		(net "P5E_PEX0_STN4_RX_DN<76>")
	)
	(segment
		(start 34.509964 -406.690068)
		(end 34.509964 -406.308052)
		(width 0.1651)
		(layer "In15.Cu")
		(net "P5E_PEX0_STN4_RX_DN<76>")
	)
	(segment
		(start 21.759926 -375.543572)
		(end 18.3134 -352.3107)
		(width 0.1651)
		(layer "In15.Cu")
		(net "P5E_PEX0_STN4_RX_DN<76>")
	)
	(segment
		(start 7.641082 -57.457848)
		(end 7.641082 -57.16397)
		(width 0.13208)
		(layer "F.Cu")
		(net "PWRGD_P3V3_SSD0")
	)
	(segment
		(start 8.179054 -59.177936)
		(end 8.179054 -58.71972)
		(width 0.13208)
		(layer "F.Cu")
		(net "PWRGD_P3V3_SSD0")
	)
	(segment
		(start 8.02513 -58.565796)
		(end 8.02513 -57.867296)
		(width 0.13208)
		(layer "F.Cu")
		(net "PWRGD_P3V3_SSD0")
	)
	(segment
		(start 8.02513 -57.841896)
		(end 7.641082 -57.457848)
		(width 0.13208)
		(layer "F.Cu")
		(net "PWRGD_P3V3_SSD0")
	)
	(segment
		(start 7.648194 -59.343544)
		(end 7.813802 -59.177936)
		(width 0.13208)
		(layer "F.Cu")
		(net "PWRGD_P3V3_SSD0")
	)
	(segment
		(start 7.813802 -59.177936)
		(end 8.179054 -59.177936)
		(width 0.13208)
		(layer "F.Cu")
		(net "PWRGD_P3V3_SSD0")
	)
	(segment
		(start 7.811008 -61.386974)
		(end 7.648194 -61.22416)
		(width 0.13208)
		(layer "F.Cu")
		(net "PWRGD_P3V3_SSD0")
	)
	(segment
		(start 7.648194 -61.22416)
		(end 7.648194 -59.343544)
		(width 0.13208)
		(layer "F.Cu")
		(net "PWRGD_P3V3_SSD0")
	)
	(segment
		(start 8.179054 -58.71972)
		(end 8.02513 -58.565796)
		(width 0.13208)
		(layer "F.Cu")
		(net "PWRGD_P3V3_SSD0")
	)
	(segment
		(start 8.02513 -57.867296)
		(end 8.02513 -57.841896)
		(width 0.13208)
		(layer "F.Cu")
		(net "PWRGD_P3V3_SSD0")
	)
	(via
		(at 8.02513 -57.867296)
		(size 0.508)
		(drill 0.254)
		(layers "F.Cu" "B.Cu")
		(net "PWRGD_P3V3_SSD0")
	)
	(segment
		(start 36.486338 -337.386676)
		(end 44.038012 -335.09585)
		(width 0.1651)
		(layer "In15.Cu")
		(net "P5E_PEX0_STN4_RX_DP<73>")
	)
	(segment
		(start 27.395678 -357.968296)
		(end 27.395678 -342.118696)
		(width 0.1651)
		(layer "In15.Cu")
		(net "P5E_PEX0_STN4_RX_DP<73>")
	)
	(segment
		(start 44.038012 -335.09585)
		(end 68.858384 -328.878438)
		(width 0.1651)
		(layer "In15.Cu")
		(net "P5E_PEX0_STN4_RX_DP<73>")
	)
	(segment
		(start 38.937184 -392.436096)
		(end 38.817042 -392.472672)
		(width 0.1651)
		(layer "In15.Cu")
		(net "P5E_PEX0_STN4_RX_DP<73>")
	)
	(segment
		(start 37.808916 -391.933684)
		(end 37.382958 -391.7061)
		(width 0.1651)
		(layer "In15.Cu")
		(net "P5E_PEX0_STN4_RX_DP<73>")
	)
	(segment
		(start 41.2369 -404.799038)
		(end 41.458388 -404.799038)
		(width 0.1651)
		(layer "In15.Cu")
		(net "P5E_PEX0_STN4_RX_DP<73>")
	)
	(segment
		(start 41.1099 -404.672038)
		(end 41.2369 -404.799038)
		(width 0.1651)
		(layer "In15.Cu")
		(net "P5E_PEX0_STN4_RX_DP<73>")
	)
	(segment
		(start 41.985692 -404.271734)
		(end 41.985692 -395.292834)
		(width 0.1651)
		(layer "In15.Cu")
		(net "P5E_PEX0_STN4_RX_DP<73>")
	)
	(segment
		(start 37.346382 -391.585704)
		(end 36.920932 -391.358374)
		(width 0.1651)
		(layer "In15.Cu")
		(net "P5E_PEX0_STN4_RX_DP<73>")
	)
	(segment
		(start 68.858384 -328.878438)
		(end 72.815958 -327.239122)
		(width 0.1651)
		(layer "In15.Cu")
		(net "P5E_PEX0_STN4_RX_DP<73>")
	)
	(segment
		(start 35.239198 -390.459468)
		(end 28.540964 -387.685026)
		(width 0.1651)
		(layer "In15.Cu")
		(net "P5E_PEX0_STN4_RX_DP<73>")
	)
	(segment
		(start 78.98384 -323.069712)
		(end 78.98384 -319.916048)
		(width 0.1651)
		(layer "In15.Cu")
		(net "P5E_PEX0_STN4_RX_DP<73>")
	)
	(segment
		(start 72.815958 -327.239122)
		(end 72.816212 -327.239122)
		(width 0.1651)
		(layer "In15.Cu")
		(net "P5E_PEX0_STN4_RX_DP<73>")
	)
	(segment
		(start 25.32126 -384.380486)
		(end 24.798782 -373.74195)
		(width 0.1651)
		(layer "In15.Cu")
		(net "P5E_PEX0_STN4_RX_DP<73>")
	)
	(segment
		(start 38.817042 -392.472672)
		(end 38.391084 -392.245088)
		(width 0.1651)
		(layer "In15.Cu")
		(net "P5E_PEX0_STN4_RX_DP<73>")
	)
	(segment
		(start 37.382958 -391.7061)
		(end 37.346382 -391.585704)
		(width 0.1651)
		(layer "In15.Cu")
		(net "P5E_PEX0_STN4_RX_DP<73>")
	)
	(segment
		(start 78.98384 -319.916048)
		(end 78.98384 -319.8876)
		(width 0.1143)
		(layer "In15.Cu")
		(net "P5E_PEX0_STN4_RX_DP<73>")
	)
	(segment
		(start 79.02956 -319.84188)
		(end 79.02956 -316.455298)
		(width 0.1143)
		(layer "In15.Cu")
		(net "P5E_PEX0_STN4_RX_DP<73>")
	)
	(segment
		(start 78.98384 -319.8876)
		(end 79.02956 -319.84188)
		(width 0.1143)
		(layer "In15.Cu")
		(net "P5E_PEX0_STN4_RX_DP<73>")
	)
	(segment
		(start 78.757526 -323.616066)
		(end 78.98384 -323.069712)
		(width 0.1651)
		(layer "In15.Cu")
		(net "P5E_PEX0_STN4_RX_DP<73>")
	)
	(segment
		(start 27.620722 -341.575644)
		(end 28.502864 -340.693502)
		(width 0.1651)
		(layer "In15.Cu")
		(net "P5E_PEX0_STN4_RX_DP<73>")
	)
	(segment
		(start 37.929058 -391.897362)
		(end 37.808916 -391.933684)
		(width 0.1651)
		(layer "In15.Cu")
		(net "P5E_PEX0_STN4_RX_DP<73>")
	)
	(segment
		(start 72.816212 -327.239122)
		(end 76.773532 -325.60006)
		(width 0.1651)
		(layer "In15.Cu")
		(net "P5E_PEX0_STN4_RX_DP<73>")
	)
	(segment
		(start 24.798782 -373.74195)
		(end 24.78786 -373.630698)
		(width 0.1651)
		(layer "In15.Cu")
		(net "P5E_PEX0_STN4_RX_DP<73>")
	)
	(segment
		(start 76.773532 -325.60006)
		(end 78.757526 -323.616066)
		(width 0.1651)
		(layer "In15.Cu")
		(net "P5E_PEX0_STN4_RX_DP<73>")
	)
	(segment
		(start 24.78786 -373.630698)
		(end 24.78786 -369.580414)
		(width 0.1651)
		(layer "In15.Cu")
		(net "P5E_PEX0_STN4_RX_DP<73>")
	)
	(segment
		(start 28.502864 -340.693502)
		(end 36.486338 -337.386676)
		(width 0.1651)
		(layer "In15.Cu")
		(net "P5E_PEX0_STN4_RX_DP<73>")
	)
	(segment
		(start 41.985692 -395.292834)
		(end 41.776396 -394.787374)
		(width 0.1651)
		(layer "In15.Cu")
		(net "P5E_PEX0_STN4_RX_DP<73>")
	)
	(segment
		(start 38.391084 -392.245088)
		(end 38.354508 -392.124692)
		(width 0.1651)
		(layer "In15.Cu")
		(net "P5E_PEX0_STN4_RX_DP<73>")
	)
	(segment
		(start 41.458388 -404.799038)
		(end 41.985692 -404.271734)
		(width 0.1651)
		(layer "In15.Cu")
		(net "P5E_PEX0_STN4_RX_DP<73>")
	)
	(segment
		(start 26.443686 -386.283454)
		(end 25.873456 -385.713224)
		(width 0.1651)
		(layer "In15.Cu")
		(net "P5E_PEX0_STN4_RX_DP<73>")
	)
	(segment
		(start 27.395678 -342.118696)
		(end 27.620722 -341.575644)
		(width 0.1651)
		(layer "In15.Cu")
		(net "P5E_PEX0_STN4_RX_DP<73>")
	)
	(segment
		(start 36.920932 -391.358374)
		(end 36.800536 -391.394696)
		(width 0.1651)
		(layer "In15.Cu")
		(net "P5E_PEX0_STN4_RX_DP<73>")
	)
	(segment
		(start 24.78786 -369.580414)
		(end 27.395678 -357.968296)
		(width 0.1651)
		(layer "In15.Cu")
		(net "P5E_PEX0_STN4_RX_DP<73>")
	)
	(segment
		(start 41.1099 -404.290022)
		(end 41.1099 -404.672038)
		(width 0.1651)
		(layer "In15.Cu")
		(net "P5E_PEX0_STN4_RX_DP<73>")
	)
	(segment
		(start 25.873456 -385.713224)
		(end 25.32126 -384.380486)
		(width 0.1651)
		(layer "In15.Cu")
		(net "P5E_PEX0_STN4_RX_DP<73>")
	)
	(segment
		(start 36.374578 -391.167112)
		(end 36.338002 -391.046716)
		(width 0.1651)
		(layer "In15.Cu")
		(net "P5E_PEX0_STN4_RX_DP<73>")
	)
	(segment
		(start 79.02956 -316.455298)
		(end 79.255366 -316.229492)
		(width 0.1143)
		(layer "In15.Cu")
		(net "P5E_PEX0_STN4_RX_DP<73>")
	)
	(segment
		(start 41.776396 -394.787374)
		(end 39.984426 -392.995658)
		(width 0.1651)
		(layer "In15.Cu")
		(net "P5E_PEX0_STN4_RX_DP<73>")
	)
	(segment
		(start 39.984426 -392.995658)
		(end 38.937184 -392.436096)
		(width 0.1651)
		(layer "In15.Cu")
		(net "P5E_PEX0_STN4_RX_DP<73>")
	)
	(segment
		(start 79.48549 -316.229492)
		(end 79.59979 -316.115192)
		(width 0.1143)
		(layer "In15.Cu")
		(net "P5E_PEX0_STN4_RX_DP<73>")
	)
	(segment
		(start 28.540964 -387.685026)
		(end 26.443686 -386.283454)
		(width 0.1651)
		(layer "In15.Cu")
		(net "P5E_PEX0_STN4_RX_DP<73>")
	)
	(segment
		(start 36.338002 -391.046716)
		(end 35.239198 -390.459468)
		(width 0.1651)
		(layer "In15.Cu")
		(net "P5E_PEX0_STN4_RX_DP<73>")
	)
	(segment
		(start 38.354508 -392.124692)
		(end 37.929058 -391.897362)
		(width 0.1651)
		(layer "In15.Cu")
		(net "P5E_PEX0_STN4_RX_DP<73>")
	)
	(segment
		(start 79.255366 -316.229492)
		(end 79.48549 -316.229492)
		(width 0.1143)
		(layer "In15.Cu")
		(net "P5E_PEX0_STN4_RX_DP<73>")
	)
	(segment
		(start 36.800536 -391.394696)
		(end 36.374578 -391.167112)
		(width 0.1651)
		(layer "In15.Cu")
		(net "P5E_PEX0_STN4_RX_DP<73>")
	)
	(segment
		(start 79.59979 -316.115192)
		(end 79.59979 -315.849762)
		(width 0.1143)
		(layer "In15.Cu")
		(net "P5E_PEX0_STN4_RX_DP<73>")
	)
	(segment
		(start 29.228288 -348.88043)
		(end 29.522928 -348.58579)
		(width 0.13462)
		(layer "F.Cu")
		(net "P5E_PEX0_STN4_TX_DN<75>")
	)
	(segment
		(start 29.548328 -349.831914)
		(end 29.228288 -349.511874)
		(width 0.13462)
		(layer "F.Cu")
		(net "P5E_PEX0_STN4_TX_DN<75>")
	)
	(segment
		(start 29.228288 -349.511874)
		(end 29.228288 -348.88043)
		(width 0.13462)
		(layer "F.Cu")
		(net "P5E_PEX0_STN4_TX_DN<75>")
	)
	(segment
		(start 29.522928 -348.58579)
		(end 29.232098 -348.29496)
		(width 0.1651)
		(layer "In11.Cu")
		(net "P5E_PEX0_STN4_TX_DN<75>")
	)
	(segment
		(start 74.36866 -325.244206)
		(end 75.799696 -324.479412)
		(width 0.1651)
		(layer "In11.Cu")
		(net "P5E_PEX0_STN4_TX_DN<75>")
	)
	(segment
		(start 77.36586 -320.265552)
		(end 77.32014 -320.219832)
		(width 0.1143)
		(layer "In11.Cu")
		(net "P5E_PEX0_STN4_TX_DN<75>")
	)
	(segment
		(start 77.36586 -320.294)
		(end 77.36586 -320.265552)
		(width 0.1143)
		(layer "In11.Cu")
		(net "P5E_PEX0_STN4_TX_DN<75>")
	)
	(segment
		(start 77.48524 -311.670192)
		(end 77.61097 -311.670192)
		(width 0.1143)
		(layer "In11.Cu")
		(net "P5E_PEX0_STN4_TX_DN<75>")
	)
	(segment
		(start 75.799696 -324.479412)
		(end 76.439014 -323.840094)
		(width 0.1651)
		(layer "In11.Cu")
		(net "P5E_PEX0_STN4_TX_DN<75>")
	)
	(segment
		(start 29.232098 -348.29496)
		(end 29.232098 -347.736922)
		(width 0.1651)
		(layer "In11.Cu")
		(net "P5E_PEX0_STN4_TX_DN<75>")
	)
	(segment
		(start 77.61097 -311.670192)
		(end 77.69987 -311.759092)
		(width 0.1143)
		(layer "In11.Cu")
		(net "P5E_PEX0_STN4_TX_DN<75>")
	)
	(segment
		(start 32.130492 -338.760308)
		(end 41.92905 -333.522828)
		(width 0.1651)
		(layer "In11.Cu")
		(net "P5E_PEX0_STN4_TX_DN<75>")
	)
	(segment
		(start 77.32014 -311.835292)
		(end 77.48524 -311.670192)
		(width 0.1143)
		(layer "In11.Cu")
		(net "P5E_PEX0_STN4_TX_DN<75>")
	)
	(segment
		(start 76.439014 -323.840094)
		(end 77.36586 -321.601592)
		(width 0.1651)
		(layer "In11.Cu")
		(net "P5E_PEX0_STN4_TX_DN<75>")
	)
	(segment
		(start 30.786578 -346.182442)
		(end 30.786578 -340.104222)
		(width 0.1651)
		(layer "In11.Cu")
		(net "P5E_PEX0_STN4_TX_DN<75>")
	)
	(segment
		(start 29.232098 -347.736922)
		(end 30.786578 -346.182442)
		(width 0.1651)
		(layer "In11.Cu")
		(net "P5E_PEX0_STN4_TX_DN<75>")
	)
	(segment
		(start 30.786578 -340.104222)
		(end 32.130492 -338.760308)
		(width 0.1651)
		(layer "In11.Cu")
		(net "P5E_PEX0_STN4_TX_DN<75>")
	)
	(segment
		(start 53.422296 -329.410314)
		(end 74.36866 -325.244206)
		(width 0.1651)
		(layer "In11.Cu")
		(net "P5E_PEX0_STN4_TX_DN<75>")
	)
	(segment
		(start 77.36586 -321.601592)
		(end 77.36586 -320.294)
		(width 0.1651)
		(layer "In11.Cu")
		(net "P5E_PEX0_STN4_TX_DN<75>")
	)
	(segment
		(start 77.69987 -311.759092)
		(end 77.69987 -312.049922)
		(width 0.1143)
		(layer "In11.Cu")
		(net "P5E_PEX0_STN4_TX_DN<75>")
	)
	(segment
		(start 41.92905 -333.522828)
		(end 53.422296 -329.410314)
		(width 0.1651)
		(layer "In11.Cu")
		(net "P5E_PEX0_STN4_TX_DN<75>")
	)
	(segment
		(start 77.32014 -320.219832)
		(end 77.32014 -311.835292)
		(width 0.1143)
		(layer "In11.Cu")
		(net "P5E_PEX0_STN4_TX_DN<75>")
	)
	(segment
		(start 8.140954 -57.16397)
		(end 8.140954 -57.233566)
		(width 0.2032)
		(layer "F.Cu")
		(net "P3V3_SSD0_SS")
	)
	(segment
		(start 9.19099 -58.449718)
		(end 9.195054 -58.453782)
		(width 0.2032)
		(layer "F.Cu")
		(net "P3V3_SSD0_SS")
	)
	(segment
		(start 9.195054 -58.453782)
		(end 9.195054 -59.177936)
		(width 0.2032)
		(layer "F.Cu")
		(net "P3V3_SSD0_SS")
	)
	(segment
		(start 8.140954 -57.233566)
		(end 9.073388 -58.166)
		(width 0.2032)
		(layer "F.Cu")
		(net "P3V3_SSD0_SS")
	)
	(segment
		(start 9.073388 -58.166)
		(end 9.19099 -58.449718)
		(width 0.2032)
		(layer "F.Cu")
		(net "P3V3_SSD0_SS")
	)
	(via
		(at 9.19099 -58.449718)
		(size 0.508)
		(drill 0.254)
		(layers "F.Cu" "B.Cu")
		(net "P3V3_SSD0_SS")
	)
	(segment
		(start 44.498768 -356.831646)
		(end 44.178728 -356.511606)
		(width 0.13462)
		(layer "F.Cu")
		(net "P5E_PEX0_STN4_TX_C_DP<67>")
	)
	(segment
		(start 44.498768 -357.46309)
		(end 44.498768 -356.831646)
		(width 0.13462)
		(layer "F.Cu")
		(net "P5E_PEX0_STN4_TX_C_DP<67>")
	)
	(segment
		(start 44.204128 -357.75773)
		(end 44.498768 -357.46309)
		(width 0.13462)
		(layer "F.Cu")
		(net "P5E_PEX0_STN4_TX_C_DP<67>")
	)
	(segment
		(start 40.509952 -364.651544)
		(end 40.785034 -364.23981)
		(width 0.1651)
		(layer "In11.Cu")
		(net "P5E_PEX0_STN4_TX_C_DP<67>")
	)
	(segment
		(start 38.721284 -367.123218)
		(end 38.99662 -366.710976)
		(width 0.1651)
		(layer "In11.Cu")
		(net "P5E_PEX0_STN4_TX_C_DP<67>")
	)
	(segment
		(start 43.679364 -359.907078)
		(end 43.647868 -359.748582)
		(width 0.1651)
		(layer "In11.Cu")
		(net "P5E_PEX0_STN4_TX_C_DP<67>")
	)
	(segment
		(start 42.568368 -361.364276)
		(end 42.726864 -361.33278)
		(width 0.1651)
		(layer "In11.Cu")
		(net "P5E_PEX0_STN4_TX_C_DP<67>")
	)
	(segment
		(start 43.404282 -360.318812)
		(end 43.679364 -359.907078)
		(width 0.1651)
		(layer "In11.Cu")
		(net "P5E_PEX0_STN4_TX_C_DP<67>")
	)
	(segment
		(start 36.837112 -370.999258)
		(end 37.172646 -370.999258)
		(width 0.1651)
		(layer "In11.Cu")
		(net "P5E_PEX0_STN4_TX_C_DP<67>")
	)
	(segment
		(start 41.065704 -363.661706)
		(end 41.18737 -363.637576)
		(width 0.1651)
		(layer "In11.Cu")
		(net "P5E_PEX0_STN4_TX_C_DP<67>")
	)
	(segment
		(start 44.0817 -359.305098)
		(end 44.081446 -359.305098)
		(width 0.1651)
		(layer "In11.Cu")
		(net "P5E_PEX0_STN4_TX_C_DP<67>")
	)
	(segment
		(start 38.99662 -366.710976)
		(end 39.155116 -366.67948)
		(width 0.1651)
		(layer "In11.Cu")
		(net "P5E_PEX0_STN4_TX_C_DP<67>")
	)
	(segment
		(start 37.690044 -368.841274)
		(end 37.753544 -368.777774)
		(width 0.1651)
		(layer "In11.Cu")
		(net "P5E_PEX0_STN4_TX_C_DP<67>")
	)
	(segment
		(start 39.398702 -366.10925)
		(end 39.674038 -365.697008)
		(width 0.1651)
		(layer "In11.Cu")
		(net "P5E_PEX0_STN4_TX_C_DP<67>")
	)
	(segment
		(start 44.49445 -358.687116)
		(end 44.494958 -358.686608)
		(width 0.1651)
		(layer "In11.Cu")
		(net "P5E_PEX0_STN4_TX_C_DP<67>")
	)
	(segment
		(start 38.75278 -367.281714)
		(end 38.721284 -367.123218)
		(width 0.1651)
		(layer "In11.Cu")
		(net "P5E_PEX0_STN4_TX_C_DP<67>")
	)
	(segment
		(start 43.245786 -360.350308)
		(end 43.404282 -360.318812)
		(width 0.1651)
		(layer "In11.Cu")
		(net "P5E_PEX0_STN4_TX_C_DP<67>")
	)
	(segment
		(start 40.351456 -364.68304)
		(end 40.509952 -364.651544)
		(width 0.1651)
		(layer "In11.Cu")
		(net "P5E_PEX0_STN4_TX_C_DP<67>")
	)
	(segment
		(start 43.923204 -359.336594)
		(end 44.0817 -359.305098)
		(width 0.1651)
		(layer "In11.Cu")
		(net "P5E_PEX0_STN4_TX_C_DP<67>")
	)
	(segment
		(start 38.04412 -368.136932)
		(end 38.319456 -367.724944)
		(width 0.1651)
		(layer "In11.Cu")
		(net "P5E_PEX0_STN4_TX_C_DP<67>")
	)
	(segment
		(start 40.785034 -364.23981)
		(end 40.76065 -364.118144)
		(width 0.1651)
		(layer "In11.Cu")
		(net "P5E_PEX0_STN4_TX_C_DP<67>")
	)
	(segment
		(start 42.97045 -360.76255)
		(end 43.245786 -360.350308)
		(width 0.1651)
		(layer "In11.Cu")
		(net "P5E_PEX0_STN4_TX_C_DP<67>")
	)
	(segment
		(start 44.081446 -359.305098)
		(end 44.49445 -358.687116)
		(width 0.1651)
		(layer "In11.Cu")
		(net "P5E_PEX0_STN4_TX_C_DP<67>")
	)
	(segment
		(start 40.07612 -365.095282)
		(end 40.351456 -364.68304)
		(width 0.1651)
		(layer "In11.Cu")
		(net "P5E_PEX0_STN4_TX_C_DP<67>")
	)
	(segment
		(start 44.494958 -358.686608)
		(end 44.494958 -358.04856)
		(width 0.1651)
		(layer "In11.Cu")
		(net "P5E_PEX0_STN4_TX_C_DP<67>")
	)
	(segment
		(start 43.001946 -360.921046)
		(end 42.97045 -360.76255)
		(width 0.1651)
		(layer "In11.Cu")
		(net "P5E_PEX0_STN4_TX_C_DP<67>")
	)
	(segment
		(start 38.075616 -368.295428)
		(end 38.04412 -368.136932)
		(width 0.1651)
		(layer "In11.Cu")
		(net "P5E_PEX0_STN4_TX_C_DP<67>")
	)
	(segment
		(start 38.319456 -367.724944)
		(end 38.477952 -367.693448)
		(width 0.1651)
		(layer "In11.Cu")
		(net "P5E_PEX0_STN4_TX_C_DP<67>")
	)
	(segment
		(start 41.18737 -363.637576)
		(end 42.324528 -361.935014)
		(width 0.1651)
		(layer "In11.Cu")
		(net "P5E_PEX0_STN4_TX_C_DP<67>")
	)
	(segment
		(start 37.172646 -370.999258)
		(end 37.690044 -370.48186)
		(width 0.1651)
		(layer "In11.Cu")
		(net "P5E_PEX0_STN4_TX_C_DP<67>")
	)
	(segment
		(start 39.832534 -365.665512)
		(end 40.107616 -365.253778)
		(width 0.1651)
		(layer "In11.Cu")
		(net "P5E_PEX0_STN4_TX_C_DP<67>")
	)
	(segment
		(start 42.293032 -361.776518)
		(end 42.568368 -361.364276)
		(width 0.1651)
		(layer "In11.Cu")
		(net "P5E_PEX0_STN4_TX_C_DP<67>")
	)
	(segment
		(start 36.710112 -370.489988)
		(end 36.710112 -370.872258)
		(width 0.1651)
		(layer "In11.Cu")
		(net "P5E_PEX0_STN4_TX_C_DP<67>")
	)
	(segment
		(start 43.647868 -359.748582)
		(end 43.923204 -359.336594)
		(width 0.1651)
		(layer "In11.Cu")
		(net "P5E_PEX0_STN4_TX_C_DP<67>")
	)
	(segment
		(start 39.430198 -366.267746)
		(end 39.398702 -366.10925)
		(width 0.1651)
		(layer "In11.Cu")
		(net "P5E_PEX0_STN4_TX_C_DP<67>")
	)
	(segment
		(start 39.155116 -366.67948)
		(end 39.430198 -366.267746)
		(width 0.1651)
		(layer "In11.Cu")
		(net "P5E_PEX0_STN4_TX_C_DP<67>")
	)
	(segment
		(start 38.477952 -367.693448)
		(end 38.477698 -367.693448)
		(width 0.1651)
		(layer "In11.Cu")
		(net "P5E_PEX0_STN4_TX_C_DP<67>")
	)
	(segment
		(start 39.674038 -365.697008)
		(end 39.832534 -365.665512)
		(width 0.1651)
		(layer "In11.Cu")
		(net "P5E_PEX0_STN4_TX_C_DP<67>")
	)
	(segment
		(start 40.107616 -365.253778)
		(end 40.07612 -365.095282)
		(width 0.1651)
		(layer "In11.Cu")
		(net "P5E_PEX0_STN4_TX_C_DP<67>")
	)
	(segment
		(start 44.494958 -358.04856)
		(end 44.204128 -357.75773)
		(width 0.1651)
		(layer "In11.Cu")
		(net "P5E_PEX0_STN4_TX_C_DP<67>")
	)
	(segment
		(start 42.324528 -361.935014)
		(end 42.293032 -361.776518)
		(width 0.1651)
		(layer "In11.Cu")
		(net "P5E_PEX0_STN4_TX_C_DP<67>")
	)
	(segment
		(start 40.76065 -364.118144)
		(end 41.065704 -363.661706)
		(width 0.1651)
		(layer "In11.Cu")
		(net "P5E_PEX0_STN4_TX_C_DP<67>")
	)
	(segment
		(start 42.726864 -361.33278)
		(end 43.001946 -360.921046)
		(width 0.1651)
		(layer "In11.Cu")
		(net "P5E_PEX0_STN4_TX_C_DP<67>")
	)
	(segment
		(start 36.710112 -370.872258)
		(end 36.837112 -370.999258)
		(width 0.1651)
		(layer "In11.Cu")
		(net "P5E_PEX0_STN4_TX_C_DP<67>")
	)
	(segment
		(start 37.753544 -368.777774)
		(end 38.075616 -368.295428)
		(width 0.1651)
		(layer "In11.Cu")
		(net "P5E_PEX0_STN4_TX_C_DP<67>")
	)
	(segment
		(start 38.477698 -367.693448)
		(end 38.75278 -367.281714)
		(width 0.1651)
		(layer "In11.Cu")
		(net "P5E_PEX0_STN4_TX_C_DP<67>")
	)
	(segment
		(start 37.690044 -370.48186)
		(end 37.690044 -368.841274)
		(width 0.1651)
		(layer "In11.Cu")
		(net "P5E_PEX0_STN4_TX_C_DP<67>")
	)
	(segment
		(start 32.337248 -342.734138)
		(end 32.631888 -342.439498)
		(width 0.13462)
		(layer "F.Cu")
		(net "P5E_PEX0_STN4_TX_DN<74>")
	)
	(segment
		(start 32.337248 -343.365582)
		(end 32.337248 -342.734138)
		(width 0.13462)
		(layer "F.Cu")
		(net "P5E_PEX0_STN4_TX_DN<74>")
	)
	(segment
		(start 32.657288 -343.685622)
		(end 32.337248 -343.365582)
		(width 0.13462)
		(layer "F.Cu")
		(net "P5E_PEX0_STN4_TX_DN<74>")
	)
	(segment
		(start 32.341058 -342.148668)
		(end 32.341058 -340.353142)
		(width 0.1651)
		(layer "In11.Cu")
		(net "P5E_PEX0_STN4_TX_DN<74>")
	)
	(segment
		(start 78.2701 -313.735212)
		(end 78.4352 -313.570112)
		(width 0.1143)
		(layer "In11.Cu")
		(net "P5E_PEX0_STN4_TX_DN<74>")
	)
	(segment
		(start 78.64983 -313.659012)
		(end 78.64983 -313.949842)
		(width 0.1143)
		(layer "In11.Cu")
		(net "P5E_PEX0_STN4_TX_DN<74>")
	)
	(segment
		(start 42.483024 -334.384904)
		(end 53.963316 -330.276708)
		(width 0.1651)
		(layer "In11.Cu")
		(net "P5E_PEX0_STN4_TX_DN<74>")
	)
	(segment
		(start 78.31582 -320.294)
		(end 78.31582 -320.265552)
		(width 0.1143)
		(layer "In11.Cu")
		(net "P5E_PEX0_STN4_TX_DN<74>")
	)
	(segment
		(start 74.878692 -326.116696)
		(end 76.323952 -325.344282)
		(width 0.1651)
		(layer "In11.Cu")
		(net "P5E_PEX0_STN4_TX_DN<74>")
	)
	(segment
		(start 78.31582 -320.265552)
		(end 78.2701 -320.219832)
		(width 0.1143)
		(layer "In11.Cu")
		(net "P5E_PEX0_STN4_TX_DN<74>")
	)
	(segment
		(start 32.341058 -340.353142)
		(end 33.517078 -339.177122)
		(width 0.1651)
		(layer "In11.Cu")
		(net "P5E_PEX0_STN4_TX_DN<74>")
	)
	(segment
		(start 42.483024 -334.38465)
		(end 42.483024 -334.384904)
		(width 0.1651)
		(layer "In11.Cu")
		(net "P5E_PEX0_STN4_TX_DN<74>")
	)
	(segment
		(start 77.247242 -324.420992)
		(end 78.31582 -321.84086)
		(width 0.1651)
		(layer "In11.Cu")
		(net "P5E_PEX0_STN4_TX_DN<74>")
	)
	(segment
		(start 53.963316 -330.276708)
		(end 74.878692 -326.116696)
		(width 0.1651)
		(layer "In11.Cu")
		(net "P5E_PEX0_STN4_TX_DN<74>")
	)
	(segment
		(start 32.631888 -342.439498)
		(end 32.341058 -342.148668)
		(width 0.1651)
		(layer "In11.Cu")
		(net "P5E_PEX0_STN4_TX_DN<74>")
	)
	(segment
		(start 78.31582 -321.84086)
		(end 78.31582 -320.294)
		(width 0.1651)
		(layer "In11.Cu")
		(net "P5E_PEX0_STN4_TX_DN<74>")
	)
	(segment
		(start 78.2701 -320.219832)
		(end 78.2701 -313.735212)
		(width 0.1143)
		(layer "In11.Cu")
		(net "P5E_PEX0_STN4_TX_DN<74>")
	)
	(segment
		(start 78.4352 -313.570112)
		(end 78.56093 -313.570112)
		(width 0.1143)
		(layer "In11.Cu")
		(net "P5E_PEX0_STN4_TX_DN<74>")
	)
	(segment
		(start 78.56093 -313.570112)
		(end 78.64983 -313.659012)
		(width 0.1143)
		(layer "In11.Cu")
		(net "P5E_PEX0_STN4_TX_DN<74>")
	)
	(segment
		(start 76.323952 -325.344282)
		(end 77.247242 -324.420992)
		(width 0.1651)
		(layer "In11.Cu")
		(net "P5E_PEX0_STN4_TX_DN<74>")
	)
	(segment
		(start 33.517078 -339.177122)
		(end 42.483024 -334.38465)
		(width 0.1651)
		(layer "In11.Cu")
		(net "P5E_PEX0_STN4_TX_DN<74>")
	)
	(segment
		(start 299.555662 -355.658166)
		(end 299.555662 -355.026722)
		(width 0.13462)
		(layer "F.Cu")
		(net "P5E_PEX2_STN4_TX_DN<64>")
	)
	(segment
		(start 299.875702 -355.978206)
		(end 299.555662 -355.658166)
		(width 0.13462)
		(layer "F.Cu")
		(net "P5E_PEX2_STN4_TX_DN<64>")
	)
	(segment
		(start 299.555662 -355.026722)
		(end 299.850302 -354.732082)
		(width 0.13462)
		(layer "F.Cu")
		(net "P5E_PEX2_STN4_TX_DN<64>")
	)
	(segment
		(start 327.894188 -312.550048)
		(end 320.307462 -305.937158)
		(width 0.1651)
		(layer "In11.Cu")
		(net "P5E_PEX2_STN4_TX_DN<64>")
	)
	(segment
		(start 315.852048 -304.77206)
		(end 315.8236 -304.77206)
		(width 0.1143)
		(layer "In11.Cu")
		(net "P5E_PEX2_STN4_TX_DN<64>")
	)
	(segment
		(start 332.18628 -318.870838)
		(end 330.751688 -315.407548)
		(width 0.1651)
		(layer "In11.Cu")
		(net "P5E_PEX2_STN4_TX_DN<64>")
	)
	(segment
		(start 299.850302 -354.732082)
		(end 299.559472 -354.441252)
		(width 0.1651)
		(layer "In11.Cu")
		(net "P5E_PEX2_STN4_TX_DN<64>")
	)
	(segment
		(start 326.443848 -331.196696)
		(end 329.974194 -327.631806)
		(width 0.1651)
		(layer "In11.Cu")
		(net "P5E_PEX2_STN4_TX_DN<64>")
	)
	(segment
		(start 317.494158 -304.77206)
		(end 315.852048 -304.77206)
		(width 0.1651)
		(layer "In11.Cu")
		(net "P5E_PEX2_STN4_TX_DN<64>")
	)
	(segment
		(start 299.559472 -353.78263)
		(end 310.16448 -342.53678)
		(width 0.1651)
		(layer "In11.Cu")
		(net "P5E_PEX2_STN4_TX_DN<64>")
	)
	(segment
		(start 307.734462 -304.449734)
		(end 307.999892 -304.449734)
		(width 0.1143)
		(layer "In11.Cu")
		(net "P5E_PEX2_STN4_TX_DN<64>")
	)
	(segment
		(start 299.559472 -354.441252)
		(end 299.559472 -353.78263)
		(width 0.1651)
		(layer "In11.Cu")
		(net "P5E_PEX2_STN4_TX_DN<64>")
	)
	(segment
		(start 315.8236 -304.77206)
		(end 315.77788 -304.81778)
		(width 0.1143)
		(layer "In11.Cu")
		(net "P5E_PEX2_STN4_TX_DN<64>")
	)
	(segment
		(start 307.63083 -304.553366)
		(end 307.734462 -304.449734)
		(width 0.1143)
		(layer "In11.Cu")
		(net "P5E_PEX2_STN4_TX_DN<64>")
	)
	(segment
		(start 310.16448 -342.53678)
		(end 326.443848 -331.196696)
		(width 0.1651)
		(layer "In11.Cu")
		(net "P5E_PEX2_STN4_TX_DN<64>")
	)
	(segment
		(start 330.751688 -315.407548)
		(end 327.894188 -312.550048)
		(width 0.1651)
		(layer "In11.Cu")
		(net "P5E_PEX2_STN4_TX_DN<64>")
	)
	(segment
		(start 307.74513 -304.81778)
		(end 307.63083 -304.70348)
		(width 0.1143)
		(layer "In11.Cu")
		(net "P5E_PEX2_STN4_TX_DN<64>")
	)
	(segment
		(start 320.307462 -305.937158)
		(end 317.494158 -304.77206)
		(width 0.1651)
		(layer "In11.Cu")
		(net "P5E_PEX2_STN4_TX_DN<64>")
	)
	(segment
		(start 329.974194 -327.631806)
		(end 332.18628 -323.19722)
		(width 0.1651)
		(layer "In11.Cu")
		(net "P5E_PEX2_STN4_TX_DN<64>")
	)
	(segment
		(start 315.77788 -304.81778)
		(end 307.74513 -304.81778)
		(width 0.1143)
		(layer "In11.Cu")
		(net "P5E_PEX2_STN4_TX_DN<64>")
	)
	(segment
		(start 332.18628 -323.19722)
		(end 332.18628 -318.870838)
		(width 0.1651)
		(layer "In11.Cu")
		(net "P5E_PEX2_STN4_TX_DN<64>")
	)
	(segment
		(start 307.63083 -304.70348)
		(end 307.63083 -304.553366)
		(width 0.1143)
		(layer "In11.Cu")
		(net "P5E_PEX2_STN4_TX_DN<64>")
	)
	(segment
		(start 7.140956 -58.364628)
		(end 6.94436 -58.561224)
		(width 0.13208)
		(layer "F.Cu")
		(net "P3V3_SSD0_OCP")
	)
	(segment
		(start 7.140956 -57.16397)
		(end 7.140956 -58.364628)
		(width 0.13208)
		(layer "F.Cu")
		(net "P3V3_SSD0_OCP")
	)
	(segment
		(start 6.94436 -59.012582)
		(end 6.94436 -58.561224)
		(width 0.13208)
		(layer "F.Cu")
		(net "P3V3_SSD0_OCP")
	)
	(segment
		(start 7.103364 -59.171586)
		(end 6.94436 -59.012582)
		(width 0.13208)
		(layer "F.Cu")
		(net "P3V3_SSD0_OCP")
	)
	(via
		(at 6.94436 -58.561224)
		(size 0.508)
		(drill 0.254)
		(layers "F.Cu" "B.Cu")
		(net "P3V3_SSD0_OCP")
	)
	(segment
		(start 73.899776 -316.115192)
		(end 73.899776 -315.849762)
		(width 0.1143)
		(layer "In15.Cu")
		(net "P5E_PEX0_STN4_RX_DP<79>")
	)
	(segment
		(start 25.501854 -392.724894)
		(end 25.477216 -392.60145)
		(width 0.1651)
		(layer "In15.Cu")
		(net "P5E_PEX0_STN4_RX_DP<79>")
	)
	(segment
		(start 24.95296 -392.357864)
		(end 24.551386 -392.08964)
		(width 0.1651)
		(layer "In15.Cu")
		(net "P5E_PEX0_STN4_RX_DP<79>")
	)
	(segment
		(start 22.679406 -390.731756)
		(end 20.818602 -388.870952)
		(width 0.1651)
		(layer "In15.Cu")
		(net "P5E_PEX0_STN4_RX_DP<79>")
	)
	(segment
		(start 23.576534 -391.331196)
		(end 22.679406 -390.731756)
		(width 0.1651)
		(layer "In15.Cu")
		(net "P5E_PEX0_STN4_RX_DP<79>")
	)
	(segment
		(start 15.9639 -339.728302)
		(end 17.361154 -338.331048)
		(width 0.1651)
		(layer "In15.Cu")
		(net "P5E_PEX0_STN4_RX_DP<79>")
	)
	(segment
		(start 73.329546 -316.455298)
		(end 73.555352 -316.229492)
		(width 0.1143)
		(layer "In15.Cu")
		(net "P5E_PEX0_STN4_RX_DP<79>")
	)
	(segment
		(start 27.805888 -393.989814)
		(end 27.146504 -393.716764)
		(width 0.1651)
		(layer "In15.Cu")
		(net "P5E_PEX0_STN4_RX_DP<79>")
	)
	(segment
		(start 28.037028 -404.799038)
		(end 28.258516 -404.799038)
		(width 0.1651)
		(layer "In15.Cu")
		(net "P5E_PEX0_STN4_RX_DP<79>")
	)
	(segment
		(start 23.600918 -391.454386)
		(end 23.576534 -391.331196)
		(width 0.1651)
		(layer "In15.Cu")
		(net "P5E_PEX0_STN4_RX_DP<79>")
	)
	(segment
		(start 28.258516 -404.799038)
		(end 28.78582 -404.271734)
		(width 0.1651)
		(layer "In15.Cu")
		(net "P5E_PEX0_STN4_RX_DP<79>")
	)
	(segment
		(start 73.283826 -320.553334)
		(end 73.283826 -319.916048)
		(width 0.1651)
		(layer "In15.Cu")
		(net "P5E_PEX0_STN4_RX_DP<79>")
	)
	(segment
		(start 73.094342 -320.836798)
		(end 73.283826 -320.553334)
		(width 0.1651)
		(layer "In15.Cu")
		(net "P5E_PEX0_STN4_RX_DP<79>")
	)
	(segment
		(start 24.125682 -391.698226)
		(end 24.002492 -391.722864)
		(width 0.1651)
		(layer "In15.Cu")
		(net "P5E_PEX0_STN4_RX_DP<79>")
	)
	(segment
		(start 15.12824 -341.745824)
		(end 15.9639 -339.728302)
		(width 0.1651)
		(layer "In15.Cu")
		(net "P5E_PEX0_STN4_RX_DP<79>")
	)
	(segment
		(start 24.526748 -391.966196)
		(end 24.125682 -391.698226)
		(width 0.1651)
		(layer "In15.Cu")
		(net "P5E_PEX0_STN4_RX_DP<79>")
	)
	(segment
		(start 27.910028 -404.672038)
		(end 28.037028 -404.799038)
		(width 0.1651)
		(layer "In15.Cu")
		(net "P5E_PEX0_STN4_RX_DP<79>")
	)
	(segment
		(start 27.146504 -393.716764)
		(end 26.026618 -392.96848)
		(width 0.1651)
		(layer "In15.Cu")
		(net "P5E_PEX0_STN4_RX_DP<79>")
	)
	(segment
		(start 28.219146 -333.540862)
		(end 40.52189 -329.809094)
		(width 0.1651)
		(layer "In15.Cu")
		(net "P5E_PEX0_STN4_RX_DP<79>")
	)
	(segment
		(start 28.560776 -394.744702)
		(end 27.805888 -393.989814)
		(width 0.1651)
		(layer "In15.Cu")
		(net "P5E_PEX0_STN4_RX_DP<79>")
	)
	(segment
		(start 27.910028 -404.290022)
		(end 27.910028 -404.672038)
		(width 0.1651)
		(layer "In15.Cu")
		(net "P5E_PEX0_STN4_RX_DP<79>")
	)
	(segment
		(start 68.12788 -322.894198)
		(end 73.094342 -320.836798)
		(width 0.1651)
		(layer "In15.Cu")
		(net "P5E_PEX0_STN4_RX_DP<79>")
	)
	(segment
		(start 24.002492 -391.722864)
		(end 23.600918 -391.454386)
		(width 0.1651)
		(layer "In15.Cu")
		(net "P5E_PEX0_STN4_RX_DP<79>")
	)
	(segment
		(start 73.283826 -319.916048)
		(end 73.283826 -319.8876)
		(width 0.1143)
		(layer "In15.Cu")
		(net "P5E_PEX0_STN4_RX_DP<79>")
	)
	(segment
		(start 18.50644 -337.565746)
		(end 28.219146 -333.540862)
		(width 0.1651)
		(layer "In15.Cu")
		(net "P5E_PEX0_STN4_RX_DP<79>")
	)
	(segment
		(start 24.551386 -392.08964)
		(end 24.526748 -391.966196)
		(width 0.1651)
		(layer "In15.Cu")
		(net "P5E_PEX0_STN4_RX_DP<79>")
	)
	(segment
		(start 19.517614 -385.730242)
		(end 18.727674 -377.712224)
		(width 0.1651)
		(layer "In15.Cu")
		(net "P5E_PEX0_STN4_RX_DP<79>")
	)
	(segment
		(start 28.78582 -404.271734)
		(end 28.78582 -395.288008)
		(width 0.1651)
		(layer "In15.Cu")
		(net "P5E_PEX0_STN4_RX_DP<79>")
	)
	(segment
		(start 18.727928 -377.712224)
		(end 15.12824 -353.445826)
		(width 0.1651)
		(layer "In15.Cu")
		(net "P5E_PEX0_STN4_RX_DP<79>")
	)
	(segment
		(start 17.361154 -338.331048)
		(end 18.50644 -337.565746)
		(width 0.1651)
		(layer "In15.Cu")
		(net "P5E_PEX0_STN4_RX_DP<79>")
	)
	(segment
		(start 25.07615 -392.33348)
		(end 24.95296 -392.357864)
		(width 0.1651)
		(layer "In15.Cu")
		(net "P5E_PEX0_STN4_RX_DP<79>")
	)
	(segment
		(start 73.785476 -316.229492)
		(end 73.899776 -316.115192)
		(width 0.1143)
		(layer "In15.Cu")
		(net "P5E_PEX0_STN4_RX_DP<79>")
	)
	(segment
		(start 28.78582 -395.288008)
		(end 28.560776 -394.744702)
		(width 0.1651)
		(layer "In15.Cu")
		(net "P5E_PEX0_STN4_RX_DP<79>")
	)
	(segment
		(start 73.283826 -319.8876)
		(end 73.329546 -319.84188)
		(width 0.1143)
		(layer "In15.Cu")
		(net "P5E_PEX0_STN4_RX_DP<79>")
	)
	(segment
		(start 73.329546 -319.84188)
		(end 73.329546 -316.455298)
		(width 0.1143)
		(layer "In15.Cu")
		(net "P5E_PEX0_STN4_RX_DP<79>")
	)
	(segment
		(start 26.026618 -392.96848)
		(end 25.903428 -392.993118)
		(width 0.1651)
		(layer "In15.Cu")
		(net "P5E_PEX0_STN4_RX_DP<79>")
	)
	(segment
		(start 18.727674 -377.712224)
		(end 18.727928 -377.712224)
		(width 0.1651)
		(layer "In15.Cu")
		(net "P5E_PEX0_STN4_RX_DP<79>")
	)
	(segment
		(start 73.555352 -316.229492)
		(end 73.785476 -316.229492)
		(width 0.1143)
		(layer "In15.Cu")
		(net "P5E_PEX0_STN4_RX_DP<79>")
	)
	(segment
		(start 40.52189 -329.809094)
		(end 68.12788 -322.894198)
		(width 0.1651)
		(layer "In15.Cu")
		(net "P5E_PEX0_STN4_RX_DP<79>")
	)
	(segment
		(start 25.477216 -392.60145)
		(end 25.07615 -392.33348)
		(width 0.1651)
		(layer "In15.Cu")
		(net "P5E_PEX0_STN4_RX_DP<79>")
	)
	(segment
		(start 15.12824 -353.445826)
		(end 15.12824 -341.745824)
		(width 0.1651)
		(layer "In15.Cu")
		(net "P5E_PEX0_STN4_RX_DP<79>")
	)
	(segment
		(start 20.818602 -388.870952)
		(end 19.517614 -385.730242)
		(width 0.1651)
		(layer "In15.Cu")
		(net "P5E_PEX0_STN4_RX_DP<79>")
	)
	(segment
		(start 25.903428 -392.993118)
		(end 25.501854 -392.724894)
		(width 0.1651)
		(layer "In15.Cu")
		(net "P5E_PEX0_STN4_RX_DP<79>")
	)
	(segment
		(start 33.94456 -336.332068)
		(end 41.692322 -333.981806)
		(width 0.1651)
		(layer "In15.Cu")
		(net "P5E_PEX0_STN4_RX_DN<75>")
	)
	(segment
		(start 41.692322 -333.981806)
		(end 68.352162 -327.303638)
		(width 0.1651)
		(layer "In15.Cu")
		(net "P5E_PEX0_STN4_RX_DN<75>")
	)
	(segment
		(start 77.36586 -322.653914)
		(end 77.36586 -319.916048)
		(width 0.1651)
		(layer "In15.Cu")
		(net "P5E_PEX0_STN4_RX_DN<75>")
	)
	(segment
		(start 24.439118 -386.617718)
		(end 23.66264 -384.74269)
		(width 0.1651)
		(layer "In15.Cu")
		(net "P5E_PEX0_STN4_RX_DN<75>")
	)
	(segment
		(start 77.355192 -322.679568)
		(end 77.36586 -322.653914)
		(width 0.1651)
		(layer "In15.Cu")
		(net "P5E_PEX0_STN4_RX_DN<75>")
	)
	(segment
		(start 21.459698 -342.244934)
		(end 21.77161 -341.491824)
		(width 0.1651)
		(layer "In15.Cu")
		(net "P5E_PEX0_STN4_RX_DN<75>")
	)
	(segment
		(start 28.30957 -338.426806)
		(end 33.94456 -336.332068)
		(width 0.1651)
		(layer "In15.Cu")
		(net "P5E_PEX0_STN4_RX_DN<75>")
	)
	(segment
		(start 77.32014 -316.534292)
		(end 77.43444 -316.419992)
		(width 0.1143)
		(layer "In15.Cu")
		(net "P5E_PEX0_STN4_RX_DN<75>")
	)
	(segment
		(start 30.039818 -390.115044)
		(end 27.827732 -389.198866)
		(width 0.1651)
		(layer "In15.Cu")
		(net "P5E_PEX0_STN4_RX_DN<75>")
	)
	(segment
		(start 22.071076 -341.192358)
		(end 28.30957 -338.426806)
		(width 0.1651)
		(layer "In15.Cu")
		(net "P5E_PEX0_STN4_RX_DN<75>")
	)
	(segment
		(start 36.837112 -405.080978)
		(end 37.17544 -405.080978)
		(width 0.1651)
		(layer "In15.Cu")
		(net "P5E_PEX0_STN4_RX_DN<75>")
	)
	(segment
		(start 37.867844 -395.081252)
		(end 37.567362 -394.483082)
		(width 0.1651)
		(layer "In15.Cu")
		(net "P5E_PEX0_STN4_RX_DN<75>")
	)
	(segment
		(start 68.352162 -327.303638)
		(end 75.827128 -324.207632)
		(width 0.1651)
		(layer "In15.Cu")
		(net "P5E_PEX0_STN4_RX_DN<75>")
	)
	(segment
		(start 77.36586 -319.916048)
		(end 77.36586 -319.8876)
		(width 0.1143)
		(layer "In15.Cu")
		(net "P5E_PEX0_STN4_RX_DN<75>")
	)
	(segment
		(start 36.710112 -405.589994)
		(end 36.710112 -405.207978)
		(width 0.1651)
		(layer "In15.Cu")
		(net "P5E_PEX0_STN4_RX_DN<75>")
	)
	(segment
		(start 21.77161 -341.491824)
		(end 22.071076 -341.192358)
		(width 0.1651)
		(layer "In15.Cu")
		(net "P5E_PEX0_STN4_RX_DN<75>")
	)
	(segment
		(start 25.39365 -387.57225)
		(end 24.439118 -386.617718)
		(width 0.1651)
		(layer "In15.Cu")
		(net "P5E_PEX0_STN4_RX_DN<75>")
	)
	(segment
		(start 77.32014 -319.84188)
		(end 77.32014 -316.534292)
		(width 0.1143)
		(layer "In15.Cu")
		(net "P5E_PEX0_STN4_RX_DN<75>")
	)
	(segment
		(start 37.867844 -404.388574)
		(end 37.867844 -395.081252)
		(width 0.1651)
		(layer "In15.Cu")
		(net "P5E_PEX0_STN4_RX_DN<75>")
	)
	(segment
		(start 77.36586 -319.8876)
		(end 77.32014 -319.84188)
		(width 0.1143)
		(layer "In15.Cu")
		(net "P5E_PEX0_STN4_RX_DN<75>")
	)
	(segment
		(start 77.69987 -316.534292)
		(end 77.69987 -316.799722)
		(width 0.1143)
		(layer "In15.Cu")
		(net "P5E_PEX0_STN4_RX_DN<75>")
	)
	(segment
		(start 36.710112 -405.207978)
		(end 36.837112 -405.080978)
		(width 0.1651)
		(layer "In15.Cu")
		(net "P5E_PEX0_STN4_RX_DN<75>")
	)
	(segment
		(start 23.268432 -376.718322)
		(end 21.459698 -358.354122)
		(width 0.1651)
		(layer "In15.Cu")
		(net "P5E_PEX0_STN4_RX_DN<75>")
	)
	(segment
		(start 37.17544 -405.080978)
		(end 37.867844 -404.388574)
		(width 0.1651)
		(layer "In15.Cu")
		(net "P5E_PEX0_STN4_RX_DN<75>")
	)
	(segment
		(start 77.58557 -316.419992)
		(end 77.69987 -316.534292)
		(width 0.1143)
		(layer "In15.Cu")
		(net "P5E_PEX0_STN4_RX_DN<75>")
	)
	(segment
		(start 37.567362 -394.483082)
		(end 34.079434 -392.274298)
		(width 0.1651)
		(layer "In15.Cu")
		(net "P5E_PEX0_STN4_RX_DN<75>")
	)
	(segment
		(start 27.827732 -389.198866)
		(end 25.39365 -387.57225)
		(width 0.1651)
		(layer "In15.Cu")
		(net "P5E_PEX0_STN4_RX_DN<75>")
	)
	(segment
		(start 23.66264 -384.74269)
		(end 23.268432 -376.718322)
		(width 0.1651)
		(layer "In15.Cu")
		(net "P5E_PEX0_STN4_RX_DN<75>")
	)
	(segment
		(start 75.827128 -324.207632)
		(end 77.355192 -322.679568)
		(width 0.1651)
		(layer "In15.Cu")
		(net "P5E_PEX0_STN4_RX_DN<75>")
	)
	(segment
		(start 77.43444 -316.419992)
		(end 77.58557 -316.419992)
		(width 0.1143)
		(layer "In15.Cu")
		(net "P5E_PEX0_STN4_RX_DN<75>")
	)
	(segment
		(start 34.079434 -392.274298)
		(end 30.039818 -390.115044)
		(width 0.1651)
		(layer "In15.Cu")
		(net "P5E_PEX0_STN4_RX_DN<75>")
	)
	(segment
		(start 21.459698 -358.354122)
		(end 21.459698 -342.244934)
		(width 0.1651)
		(layer "In15.Cu")
		(net "P5E_PEX0_STN4_RX_DN<75>")
	)
	(segment
		(start 31.742888 -355.978206)
		(end 32.062928 -355.658166)
		(width 0.13462)
		(layer "F.Cu")
		(net "P5E_PEX0_STN4_TX_DP<73>")
	)
	(segment
		(start 32.062928 -355.026722)
		(end 31.768288 -354.732082)
		(width 0.13462)
		(layer "F.Cu")
		(net "P5E_PEX0_STN4_TX_DP<73>")
	)
	(segment
		(start 32.062928 -355.658166)
		(end 32.062928 -355.026722)
		(width 0.13462)
		(layer "F.Cu")
		(net "P5E_PEX0_STN4_TX_DP<73>")
	)
	(segment
		(start 79.02956 -320.219832)
		(end 79.02956 -311.756298)
		(width 0.1143)
		(layer "In11.Cu")
		(net "P5E_PEX0_STN4_TX_DP<73>")
	)
	(segment
		(start 32.059118 -354.441252)
		(end 32.059118 -353.657662)
		(width 0.1651)
		(layer "In11.Cu")
		(net "P5E_PEX0_STN4_TX_DP<73>")
	)
	(segment
		(start 77.92339 -324.750176)
		(end 78.98384 -322.19011)
		(width 0.1651)
		(layer "In11.Cu")
		(net "P5E_PEX0_STN4_TX_DP<73>")
	)
	(segment
		(start 33.613598 -352.103182)
		(end 33.613598 -341.171276)
		(width 0.1651)
		(layer "In11.Cu")
		(net "P5E_PEX0_STN4_TX_DP<73>")
	)
	(segment
		(start 78.98384 -322.19011)
		(end 78.98384 -320.294)
		(width 0.1651)
		(layer "In11.Cu")
		(net "P5E_PEX0_STN4_TX_DP<73>")
	)
	(segment
		(start 79.51089 -311.479692)
		(end 79.59979 -311.390792)
		(width 0.1143)
		(layer "In11.Cu")
		(net "P5E_PEX0_STN4_TX_DP<73>")
	)
	(segment
		(start 42.614088 -335.150968)
		(end 48.687482 -332.977744)
		(width 0.1651)
		(layer "In11.Cu")
		(net "P5E_PEX0_STN4_TX_DP<73>")
	)
	(segment
		(start 54.760622 -330.804774)
		(end 75.29322 -326.720708)
		(width 0.1651)
		(layer "In11.Cu")
		(net "P5E_PEX0_STN4_TX_DP<73>")
	)
	(segment
		(start 36.21151 -338.57311)
		(end 42.614088 -335.150968)
		(width 0.1651)
		(layer "In11.Cu")
		(net "P5E_PEX0_STN4_TX_DP<73>")
	)
	(segment
		(start 31.768288 -354.732082)
		(end 32.059118 -354.441252)
		(width 0.1651)
		(layer "In11.Cu")
		(net "P5E_PEX0_STN4_TX_DP<73>")
	)
	(segment
		(start 48.687482 -332.977744)
		(end 54.760622 -330.804774)
		(width 0.1651)
		(layer "In11.Cu")
		(net "P5E_PEX0_STN4_TX_DP<73>")
	)
	(segment
		(start 75.29322 -326.720708)
		(end 75.292966 -326.720708)
		(width 0.1651)
		(layer "In11.Cu")
		(net "P5E_PEX0_STN4_TX_DP<73>")
	)
	(segment
		(start 33.613598 -341.171276)
		(end 36.21151 -338.57311)
		(width 0.1651)
		(layer "In11.Cu")
		(net "P5E_PEX0_STN4_TX_DP<73>")
	)
	(segment
		(start 79.306166 -311.479692)
		(end 79.51089 -311.479692)
		(width 0.1143)
		(layer "In11.Cu")
		(net "P5E_PEX0_STN4_TX_DP<73>")
	)
	(segment
		(start 78.98384 -320.265552)
		(end 79.02956 -320.219832)
		(width 0.1143)
		(layer "In11.Cu")
		(net "P5E_PEX0_STN4_TX_DP<73>")
	)
	(segment
		(start 79.59979 -311.390792)
		(end 79.59979 -311.099962)
		(width 0.1143)
		(layer "In11.Cu")
		(net "P5E_PEX0_STN4_TX_DP<73>")
	)
	(segment
		(start 75.292966 -326.720708)
		(end 76.710794 -325.962772)
		(width 0.1651)
		(layer "In11.Cu")
		(net "P5E_PEX0_STN4_TX_DP<73>")
	)
	(segment
		(start 76.710794 -325.962772)
		(end 77.92339 -324.750176)
		(width 0.1651)
		(layer "In11.Cu")
		(net "P5E_PEX0_STN4_TX_DP<73>")
	)
	(segment
		(start 79.02956 -311.756298)
		(end 79.306166 -311.479692)
		(width 0.1143)
		(layer "In11.Cu")
		(net "P5E_PEX0_STN4_TX_DP<73>")
	)
	(segment
		(start 78.98384 -320.294)
		(end 78.98384 -320.265552)
		(width 0.1143)
		(layer "In11.Cu")
		(net "P5E_PEX0_STN4_TX_DP<73>")
	)
	(segment
		(start 32.059118 -353.657662)
		(end 33.613598 -352.103182)
		(width 0.1651)
		(layer "In11.Cu")
		(net "P5E_PEX0_STN4_TX_DP<73>")
	)
	(segment
		(start 290.228782 -349.511874)
		(end 290.228782 -348.88043)
		(width 0.13462)
		(layer "F.Cu")
		(net "P5E_PEX2_STN4_TX_DN<69>")
	)
	(segment
		(start 290.548822 -349.831914)
		(end 290.228782 -349.511874)
		(width 0.13462)
		(layer "F.Cu")
		(net "P5E_PEX2_STN4_TX_DN<69>")
	)
	(segment
		(start 290.228782 -348.88043)
		(end 290.523422 -348.58579)
		(width 0.13462)
		(layer "F.Cu")
		(net "P5E_PEX2_STN4_TX_DN<69>")
	)
	(segment
		(start 291.787072 -341.188548)
		(end 292.500812 -340.474808)
		(width 0.1651)
		(layer "In11.Cu")
		(net "P5E_PEX2_STN4_TX_DN<69>")
	)
	(segment
		(start 291.787072 -346.230194)
		(end 291.787072 -341.188548)
		(width 0.1651)
		(layer "In11.Cu")
		(net "P5E_PEX2_STN4_TX_DN<69>")
	)
	(segment
		(start 324.90918 -316.49162)
		(end 321.856354 -315.226954)
		(width 0.1651)
		(layer "In11.Cu")
		(net "P5E_PEX2_STN4_TX_DN<69>")
	)
	(segment
		(start 309.634382 -309.579518)
		(end 309.520082 -309.465218)
		(width 0.1143)
		(layer "In11.Cu")
		(net "P5E_PEX2_STN4_TX_DN<69>")
	)
	(segment
		(start 309.634382 -309.199788)
		(end 309.899812 -309.199788)
		(width 0.1143)
		(layer "In11.Cu")
		(net "P5E_PEX2_STN4_TX_DN<69>")
	)
	(segment
		(start 315.80328 -309.579518)
		(end 309.634382 -309.579518)
		(width 0.1143)
		(layer "In11.Cu")
		(net "P5E_PEX2_STN4_TX_DN<69>")
	)
	(segment
		(start 315.849 -309.533798)
		(end 315.80328 -309.579518)
		(width 0.1143)
		(layer "In11.Cu")
		(net "P5E_PEX2_STN4_TX_DN<69>")
	)
	(segment
		(start 321.856354 -315.226954)
		(end 316.163198 -309.533798)
		(width 0.1651)
		(layer "In11.Cu")
		(net "P5E_PEX2_STN4_TX_DN<69>")
	)
	(segment
		(start 309.520082 -309.465218)
		(end 309.520082 -309.314088)
		(width 0.1143)
		(layer "In11.Cu")
		(net "P5E_PEX2_STN4_TX_DN<69>")
	)
	(segment
		(start 316.163198 -309.533798)
		(end 315.877448 -309.533798)
		(width 0.1651)
		(layer "In11.Cu")
		(net "P5E_PEX2_STN4_TX_DN<69>")
	)
	(segment
		(start 309.520082 -309.314088)
		(end 309.634382 -309.199788)
		(width 0.1143)
		(layer "In11.Cu")
		(net "P5E_PEX2_STN4_TX_DN<69>")
	)
	(segment
		(start 315.877448 -309.533798)
		(end 315.849 -309.533798)
		(width 0.1143)
		(layer "In11.Cu")
		(net "P5E_PEX2_STN4_TX_DN<69>")
	)
	(segment
		(start 326.416162 -317.998602)
		(end 324.90918 -316.49162)
		(width 0.1651)
		(layer "In11.Cu")
		(net "P5E_PEX2_STN4_TX_DN<69>")
	)
	(segment
		(start 290.232592 -347.784674)
		(end 291.787072 -346.230194)
		(width 0.1651)
		(layer "In11.Cu")
		(net "P5E_PEX2_STN4_TX_DN<69>")
	)
	(segment
		(start 327.29678 -320.124582)
		(end 326.416162 -317.998602)
		(width 0.1651)
		(layer "In11.Cu")
		(net "P5E_PEX2_STN4_TX_DN<69>")
	)
	(segment
		(start 292.500812 -340.474808)
		(end 296.028872 -338.513674)
		(width 0.1651)
		(layer "In11.Cu")
		(net "P5E_PEX2_STN4_TX_DN<69>")
	)
	(segment
		(start 327.29678 -322.054728)
		(end 327.29678 -320.124582)
		(width 0.1651)
		(layer "In11.Cu")
		(net "P5E_PEX2_STN4_TX_DN<69>")
	)
	(segment
		(start 290.232592 -348.29496)
		(end 290.232592 -347.784674)
		(width 0.1651)
		(layer "In11.Cu")
		(net "P5E_PEX2_STN4_TX_DN<69>")
	)
	(segment
		(start 325.927212 -324.691248)
		(end 327.29678 -322.054728)
		(width 0.1651)
		(layer "In11.Cu")
		(net "P5E_PEX2_STN4_TX_DN<69>")
	)
	(segment
		(start 324.765162 -325.865744)
		(end 325.927212 -324.691248)
		(width 0.1651)
		(layer "In11.Cu")
		(net "P5E_PEX2_STN4_TX_DN<69>")
	)
	(segment
		(start 296.028872 -338.513674)
		(end 324.765162 -325.865744)
		(width 0.1651)
		(layer "In11.Cu")
		(net "P5E_PEX2_STN4_TX_DN<69>")
	)
	(segment
		(start 290.523422 -348.58579)
		(end 290.232592 -348.29496)
		(width 0.1651)
		(layer "In11.Cu")
		(net "P5E_PEX2_STN4_TX_DN<69>")
	)
	(segment
		(start 340.493858 -223.987106)
		(end 340.094062 -224.386902)
		(width 0.13208)
		(layer "F.Cu")
		(net "PWRGD_P3V3_SSD0_R")
	)
	(segment
		(start 4.319524 -72.90689)
		(end 3.936746 -73.289668)
		(width 0.13208)
		(layer "F.Cu")
		(net "PWRGD_P3V3_SSD0_R")
	)
	(segment
		(start 4.84505 -72.90689)
		(end 4.319524 -72.90689)
		(width 0.13208)
		(layer "F.Cu")
		(net "PWRGD_P3V3_SSD0_R")
	)
	(segment
		(start 8.611108 -61.386974)
		(end 8.611108 -62.051438)
		(width 0.13208)
		(layer "F.Cu")
		(net "PWRGD_P3V3_SSD0_R")
	)
	(segment
		(start 3.48361 -66.567812)
		(end 3.48361 -65.882774)
		(width 0.13208)
		(layer "F.Cu")
		(net "PWRGD_P3V3_SSD0_R")
	)
	(via
		(at 3.48361 -65.882774)
		(size 0.508)
		(drill 0.254)
		(layers "F.Cu" "B.Cu")
		(net "PWRGD_P3V3_SSD0_R")
	)
	(via
		(at 28.83027 -202.401424)
		(size 0.508)
		(drill 0.254)
		(layers "F.Cu" "B.Cu")
		(net "PWRGD_P3V3_SSD0_R")
	)
	(via
		(at 3.936746 -73.289668)
		(size 0.508)
		(drill 0.254)
		(layers "F.Cu" "B.Cu")
		(net "PWRGD_P3V3_SSD0_R")
	)
	(via
		(at 340.094062 -224.386902)
		(size 0.4572)
		(drill 0.254)
		(layers "F.Cu" "B.Cu")
		(net "PWRGD_P3V3_SSD0_R")
	)
	(via
		(at 8.611108 -62.051438)
		(size 0.508)
		(drill 0.254)
		(layers "F.Cu" "B.Cu")
		(net "PWRGD_P3V3_SSD0_R")
	)
	(segment
		(start 27.372056 -96.242886)
		(end 27.372056 -78.45044)
		(width 0.15494)
		(layer "In5.Cu")
		(net "PWRGD_P3V3_SSD0_R")
	)
	(segment
		(start 6.825488 -73.303638)
		(end 3.950716 -73.303638)
		(width 0.15494)
		(layer "In5.Cu")
		(net "PWRGD_P3V3_SSD0_R")
	)
	(segment
		(start 4.26212 -65.104264)
		(end 3.48361 -65.882774)
		(width 0.15494)
		(layer "In5.Cu")
		(net "PWRGD_P3V3_SSD0_R")
	)
	(segment
		(start 24.689308 -98.925634)
		(end 27.372056 -96.242886)
		(width 0.15494)
		(layer "In5.Cu")
		(net "PWRGD_P3V3_SSD0_R")
	)
	(segment
		(start 6.980682 -62.051438)
		(end 4.26212 -64.77)
		(width 0.15494)
		(layer "In5.Cu")
		(net "PWRGD_P3V3_SSD0_R")
	)
	(segment
		(start 4.26212 -64.77)
		(end 4.26212 -65.104264)
		(width 0.15494)
		(layer "In5.Cu")
		(net "PWRGD_P3V3_SSD0_R")
	)
	(segment
		(start 3.950716 -73.303638)
		(end 3.936746 -73.289668)
		(width 0.15494)
		(layer "In5.Cu")
		(net "PWRGD_P3V3_SSD0_R")
	)
	(segment
		(start 24.861012 -193.189606)
		(end 24.861012 -166.440358)
		(width 0.15494)
		(layer "In5.Cu")
		(net "PWRGD_P3V3_SSD0_R")
	)
	(segment
		(start 2.68859 -72.041512)
		(end 3.936746 -73.289668)
		(width 0.15494)
		(layer "In5.Cu")
		(net "PWRGD_P3V3_SSD0_R")
	)
	(segment
		(start 3.23088 -66.135504)
		(end 3.23088 -70.47992)
		(width 0.15494)
		(layer "In5.Cu")
		(net "PWRGD_P3V3_SSD0_R")
	)
	(segment
		(start 19.088354 -77.4573)
		(end 11.531854 -69.9008)
		(width 0.15494)
		(layer "In5.Cu")
		(net "PWRGD_P3V3_SSD0_R")
	)
	(segment
		(start 3.23088 -70.47992)
		(end 2.68859 -71.02221)
		(width 0.15494)
		(layer "In5.Cu")
		(net "PWRGD_P3V3_SSD0_R")
	)
	(segment
		(start 24.689308 -166.02583)
		(end 24.689308 -98.925634)
		(width 0.15494)
		(layer "In5.Cu")
		(net "PWRGD_P3V3_SSD0_R")
	)
	(segment
		(start 28.83027 -202.401424)
		(end 28.83027 -197.158864)
		(width 0.15494)
		(layer "In5.Cu")
		(net "PWRGD_P3V3_SSD0_R")
	)
	(segment
		(start 27.372056 -78.45044)
		(end 26.378916 -77.4573)
		(width 0.15494)
		(layer "In5.Cu")
		(net "PWRGD_P3V3_SSD0_R")
	)
	(segment
		(start 2.68859 -71.02221)
		(end 2.68859 -72.041512)
		(width 0.15494)
		(layer "In5.Cu")
		(net "PWRGD_P3V3_SSD0_R")
	)
	(segment
		(start 28.83027 -197.158864)
		(end 24.861012 -193.189606)
		(width 0.15494)
		(layer "In5.Cu")
		(net "PWRGD_P3V3_SSD0_R")
	)
	(segment
		(start 8.611108 -62.051438)
		(end 6.980682 -62.051438)
		(width 0.15494)
		(layer "In5.Cu")
		(net "PWRGD_P3V3_SSD0_R")
	)
	(segment
		(start 8.5598 -70.129654)
		(end 8.5598 -71.569326)
		(width 0.15494)
		(layer "In5.Cu")
		(net "PWRGD_P3V3_SSD0_R")
	)
	(segment
		(start 24.861012 -166.440358)
		(end 24.689308 -166.02583)
		(width 0.15494)
		(layer "In5.Cu")
		(net "PWRGD_P3V3_SSD0_R")
	)
	(segment
		(start 3.48361 -65.882774)
		(end 3.23088 -66.135504)
		(width 0.15494)
		(layer "In5.Cu")
		(net "PWRGD_P3V3_SSD0_R")
	)
	(segment
		(start 26.378916 -77.4573)
		(end 19.088354 -77.4573)
		(width 0.15494)
		(layer "In5.Cu")
		(net "PWRGD_P3V3_SSD0_R")
	)
	(segment
		(start 8.5598 -71.569326)
		(end 6.825488 -73.303638)
		(width 0.15494)
		(layer "In5.Cu")
		(net "PWRGD_P3V3_SSD0_R")
	)
	(segment
		(start 11.531854 -69.9008)
		(end 8.788654 -69.9008)
		(width 0.15494)
		(layer "In5.Cu")
		(net "PWRGD_P3V3_SSD0_R")
	)
	(segment
		(start 8.788654 -69.9008)
		(end 8.5598 -70.129654)
		(width 0.15494)
		(layer "In5.Cu")
		(net "PWRGD_P3V3_SSD0_R")
	)
	(segment
		(start 267.67155 -225.044)
		(end 267.436092 -225.044)
		(width 0.15494)
		(layer "In15.Cu")
		(net "PWRGD_P3V3_SSD0_R")
	)
	(segment
		(start 221.19209 -229.62616)
		(end 214.772494 -229.62616)
		(width 0.15494)
		(layer "In15.Cu")
		(net "PWRGD_P3V3_SSD0_R")
	)
	(segment
		(start 31.62427 -201.93)
		(end 31.16961 -201.47534)
		(width 0.15494)
		(layer "In15.Cu")
		(net "PWRGD_P3V3_SSD0_R")
	)
	(segment
		(start 252.095762 -222.579692)
		(end 250.647708 -222.579692)
		(width 0.15494)
		(layer "In15.Cu")
		(net "PWRGD_P3V3_SSD0_R")
	)
	(segment
		(start 338.50834 -227.928424)
		(end 331.473302 -227.928424)
		(width 0.15494)
		(layer "In15.Cu")
		(net "PWRGD_P3V3_SSD0_R")
	)
	(segment
		(start 229.168452 -228.940868)
		(end 221.877382 -228.940868)
		(width 0.15494)
		(layer "In15.Cu")
		(net "PWRGD_P3V3_SSD0_R")
	)
	(segment
		(start 291.403278 -228.560122)
		(end 290.2204 -229.743)
		(width 0.15494)
		(layer "In15.Cu")
		(net "PWRGD_P3V3_SSD0_R")
	)
	(segment
		(start 131.70916 -221.431612)
		(end 129.698496 -223.442276)
		(width 0.15494)
		(layer "In15.Cu")
		(net "PWRGD_P3V3_SSD0_R")
	)
	(segment
		(start 143.78559 -220.549978)
		(end 142.823184 -221.512384)
		(width 0.15494)
		(layer "In15.Cu")
		(net "PWRGD_P3V3_SSD0_R")
	)
	(segment
		(start 331.177392 -228.224334)
		(end 331.177392 -228.506782)
		(width 0.15494)
		(layer "In15.Cu")
		(net "PWRGD_P3V3_SSD0_R")
	)
	(segment
		(start 118.016782 -213.410292)
		(end 118.016782 -210.929728)
		(width 0.15494)
		(layer "In15.Cu")
		(net "PWRGD_P3V3_SSD0_R")
	)
	(segment
		(start 250.647708 -222.579692)
		(end 249.3264 -223.901)
		(width 0.15494)
		(layer "In15.Cu")
		(net "PWRGD_P3V3_SSD0_R")
	)
	(segment
		(start 238.188754 -227.97262)
		(end 237.265718 -228.895656)
		(width 0.15494)
		(layer "In15.Cu")
		(net "PWRGD_P3V3_SSD0_R")
	)
	(segment
		(start 214.589614 -229.44328)
		(end 193.8401 -229.44328)
		(width 0.15494)
		(layer "In15.Cu")
		(net "PWRGD_P3V3_SSD0_R")
	)
	(segment
		(start 128.048766 -223.442276)
		(end 118.016782 -213.410292)
		(width 0.15494)
		(layer "In15.Cu")
		(net "PWRGD_P3V3_SSD0_R")
	)
	(segment
		(start 96.718628 -201.93)
		(end 31.62427 -201.93)
		(width 0.15494)
		(layer "In15.Cu")
		(net "PWRGD_P3V3_SSD0_R")
	)
	(segment
		(start 229.813104 -228.296216)
		(end 229.168452 -228.940868)
		(width 0.15494)
		(layer "In15.Cu")
		(net "PWRGD_P3V3_SSD0_R")
	)
	(segment
		(start 256.704592 -220.43898)
		(end 254.236474 -220.43898)
		(width 0.15494)
		(layer "In15.Cu")
		(net "PWRGD_P3V3_SSD0_R")
	)
	(segment
		(start 235.36529 -228.895656)
		(end 234.76585 -228.296216)
		(width 0.15494)
		(layer "In15.Cu")
		(net "PWRGD_P3V3_SSD0_R")
	)
	(segment
		(start 214.772494 -229.62616)
		(end 214.589614 -229.44328)
		(width 0.15494)
		(layer "In15.Cu")
		(net "PWRGD_P3V3_SSD0_R")
	)
	(segment
		(start 156.491178 -220.549978)
		(end 143.78559 -220.549978)
		(width 0.15494)
		(layer "In15.Cu")
		(net "PWRGD_P3V3_SSD0_R")
	)
	(segment
		(start 261.388606 -222.67926)
		(end 259.124196 -222.67926)
		(width 0.15494)
		(layer "In15.Cu")
		(net "PWRGD_P3V3_SSD0_R")
	)
	(segment
		(start 272.37055 -229.743)
		(end 267.67155 -225.044)
		(width 0.15494)
		(layer "In15.Cu")
		(net "PWRGD_P3V3_SSD0_R")
	)
	(segment
		(start 241.711988 -227.97262)
		(end 238.188754 -227.97262)
		(width 0.15494)
		(layer "In15.Cu")
		(net "PWRGD_P3V3_SSD0_R")
	)
	(segment
		(start 141.927834 -221.512384)
		(end 139.980162 -223.460056)
		(width 0.15494)
		(layer "In15.Cu")
		(net "PWRGD_P3V3_SSD0_R")
	)
	(segment
		(start 160.655254 -224.714054)
		(end 156.491178 -220.549978)
		(width 0.15494)
		(layer "In15.Cu")
		(net "PWRGD_P3V3_SSD0_R")
	)
	(segment
		(start 259.124196 -222.67926)
		(end 258.511802 -223.291654)
		(width 0.15494)
		(layer "In15.Cu")
		(net "PWRGD_P3V3_SSD0_R")
	)
	(segment
		(start 237.265718 -228.895656)
		(end 235.36529 -228.895656)
		(width 0.15494)
		(layer "In15.Cu")
		(net "PWRGD_P3V3_SSD0_R")
	)
	(segment
		(start 290.2204 -229.743)
		(end 272.37055 -229.743)
		(width 0.15494)
		(layer "In15.Cu")
		(net "PWRGD_P3V3_SSD0_R")
	)
	(segment
		(start 267.436092 -225.044)
		(end 266.631674 -224.239582)
		(width 0.15494)
		(layer "In15.Cu")
		(net "PWRGD_P3V3_SSD0_R")
	)
	(segment
		(start 262.948928 -224.239582)
		(end 261.388606 -222.67926)
		(width 0.15494)
		(layer "In15.Cu")
		(net "PWRGD_P3V3_SSD0_R")
	)
	(segment
		(start 254.236474 -220.43898)
		(end 252.095762 -222.579692)
		(width 0.15494)
		(layer "In15.Cu")
		(net "PWRGD_P3V3_SSD0_R")
	)
	(segment
		(start 340.094062 -224.386902)
		(end 339.719158 -224.761806)
		(width 0.0889)
		(layer "In15.Cu")
		(net "PWRGD_P3V3_SSD0_R")
	)
	(segment
		(start 339.821266 -227.2284)
		(end 339.821266 -227.635816)
		(width 0.15494)
		(layer "In15.Cu")
		(net "PWRGD_P3V3_SSD0_R")
	)
	(segment
		(start 328.36739 -229.40264)
		(end 328.35723 -229.4128)
		(width 0.15494)
		(layer "In15.Cu")
		(net "PWRGD_P3V3_SSD0_R")
	)
	(segment
		(start 111.430054 -204.343)
		(end 102.54615 -204.343)
		(width 0.15494)
		(layer "In15.Cu")
		(net "PWRGD_P3V3_SSD0_R")
	)
	(segment
		(start 331.177392 -228.506782)
		(end 330.281534 -229.40264)
		(width 0.15494)
		(layer "In15.Cu")
		(net "PWRGD_P3V3_SSD0_R")
	)
	(segment
		(start 138.476482 -222.659702)
		(end 137.248392 -221.431612)
		(width 0.15494)
		(layer "In15.Cu")
		(net "PWRGD_P3V3_SSD0_R")
	)
	(segment
		(start 331.473302 -227.928424)
		(end 331.177392 -228.224334)
		(width 0.15494)
		(layer "In15.Cu")
		(net "PWRGD_P3V3_SSD0_R")
	)
	(segment
		(start 142.823184 -221.512384)
		(end 141.927834 -221.512384)
		(width 0.15494)
		(layer "In15.Cu")
		(net "PWRGD_P3V3_SSD0_R")
	)
	(segment
		(start 31.16961 -201.47534)
		(end 29.756354 -201.47534)
		(width 0.15494)
		(layer "In15.Cu")
		(net "PWRGD_P3V3_SSD0_R")
	)
	(segment
		(start 339.719158 -227.126292)
		(end 339.821266 -227.2284)
		(width 0.0889)
		(layer "In15.Cu")
		(net "PWRGD_P3V3_SSD0_R")
	)
	(segment
		(start 266.631674 -224.239582)
		(end 262.948928 -224.239582)
		(width 0.15494)
		(layer "In15.Cu")
		(net "PWRGD_P3V3_SSD0_R")
	)
	(segment
		(start 339.821266 -227.635816)
		(end 339.462618 -227.994464)
		(width 0.15494)
		(layer "In15.Cu")
		(net "PWRGD_P3V3_SSD0_R")
	)
	(segment
		(start 249.3264 -223.901)
		(end 245.783608 -223.901)
		(width 0.15494)
		(layer "In15.Cu")
		(net "PWRGD_P3V3_SSD0_R")
	)
	(segment
		(start 306.304696 -228.743256)
		(end 305.192176 -227.630736)
		(width 0.15494)
		(layer "In15.Cu")
		(net "PWRGD_P3V3_SSD0_R")
	)
	(segment
		(start 137.248392 -221.431612)
		(end 131.70916 -221.431612)
		(width 0.15494)
		(layer "In15.Cu")
		(net "PWRGD_P3V3_SSD0_R")
	)
	(segment
		(start 323.381116 -228.743256)
		(end 306.304696 -228.743256)
		(width 0.15494)
		(layer "In15.Cu")
		(net "PWRGD_P3V3_SSD0_R")
	)
	(segment
		(start 139.123674 -223.460056)
		(end 138.476482 -222.812864)
		(width 0.15494)
		(layer "In15.Cu")
		(net "PWRGD_P3V3_SSD0_R")
	)
	(segment
		(start 328.35723 -229.4128)
		(end 326.999346 -229.4128)
		(width 0.15494)
		(layer "In15.Cu")
		(net "PWRGD_P3V3_SSD0_R")
	)
	(segment
		(start 234.76585 -228.296216)
		(end 229.813104 -228.296216)
		(width 0.15494)
		(layer "In15.Cu")
		(net "PWRGD_P3V3_SSD0_R")
	)
	(segment
		(start 257.7084 -221.442788)
		(end 256.704592 -220.43898)
		(width 0.15494)
		(layer "In15.Cu")
		(net "PWRGD_P3V3_SSD0_R")
	)
	(segment
		(start 139.980162 -223.460056)
		(end 139.123674 -223.460056)
		(width 0.15494)
		(layer "In15.Cu")
		(net "PWRGD_P3V3_SSD0_R")
	)
	(segment
		(start 258.511802 -223.291654)
		(end 257.995166 -223.291654)
		(width 0.15494)
		(layer "In15.Cu")
		(net "PWRGD_P3V3_SSD0_R")
	)
	(segment
		(start 330.281534 -229.40264)
		(end 328.36739 -229.40264)
		(width 0.15494)
		(layer "In15.Cu")
		(net "PWRGD_P3V3_SSD0_R")
	)
	(segment
		(start 339.719158 -224.761806)
		(end 339.719158 -227.126292)
		(width 0.0889)
		(layer "In15.Cu")
		(net "PWRGD_P3V3_SSD0_R")
	)
	(segment
		(start 129.698496 -223.442276)
		(end 128.048766 -223.442276)
		(width 0.15494)
		(layer "In15.Cu")
		(net "PWRGD_P3V3_SSD0_R")
	)
	(segment
		(start 102.54615 -204.343)
		(end 96.718628 -201.93)
		(width 0.15494)
		(layer "In15.Cu")
		(net "PWRGD_P3V3_SSD0_R")
	)
	(segment
		(start 118.016782 -210.929728)
		(end 111.430054 -204.343)
		(width 0.15494)
		(layer "In15.Cu")
		(net "PWRGD_P3V3_SSD0_R")
	)
	(segment
		(start 138.476482 -222.812864)
		(end 138.476482 -222.659702)
		(width 0.15494)
		(layer "In15.Cu")
		(net "PWRGD_P3V3_SSD0_R")
	)
	(segment
		(start 189.110874 -224.714054)
		(end 160.655254 -224.714054)
		(width 0.15494)
		(layer "In15.Cu")
		(net "PWRGD_P3V3_SSD0_R")
	)
	(segment
		(start 305.192176 -227.630736)
		(end 301.39132 -227.630736)
		(width 0.15494)
		(layer "In15.Cu")
		(net "PWRGD_P3V3_SSD0_R")
	)
	(segment
		(start 339.462618 -227.994464)
		(end 338.57438 -227.994464)
		(width 0.15494)
		(layer "In15.Cu")
		(net "PWRGD_P3V3_SSD0_R")
	)
	(segment
		(start 257.995166 -223.291654)
		(end 257.7084 -223.004888)
		(width 0.15494)
		(layer "In15.Cu")
		(net "PWRGD_P3V3_SSD0_R")
	)
	(segment
		(start 326.465946 -228.8794)
		(end 323.51726 -228.8794)
		(width 0.15494)
		(layer "In15.Cu")
		(net "PWRGD_P3V3_SSD0_R")
	)
	(segment
		(start 257.7084 -223.004888)
		(end 257.7084 -221.442788)
		(width 0.15494)
		(layer "In15.Cu")
		(net "PWRGD_P3V3_SSD0_R")
	)
	(segment
		(start 300.461934 -228.560122)
		(end 291.403278 -228.560122)
		(width 0.15494)
		(layer "In15.Cu")
		(net "PWRGD_P3V3_SSD0_R")
	)
	(segment
		(start 193.8401 -229.44328)
		(end 189.110874 -224.714054)
		(width 0.15494)
		(layer "In15.Cu")
		(net "PWRGD_P3V3_SSD0_R")
	)
	(segment
		(start 323.51726 -228.8794)
		(end 323.381116 -228.743256)
		(width 0.15494)
		(layer "In15.Cu")
		(net "PWRGD_P3V3_SSD0_R")
	)
	(segment
		(start 29.756354 -201.47534)
		(end 28.83027 -202.401424)
		(width 0.15494)
		(layer "In15.Cu")
		(net "PWRGD_P3V3_SSD0_R")
	)
	(segment
		(start 245.783608 -223.901)
		(end 241.711988 -227.97262)
		(width 0.15494)
		(layer "In15.Cu")
		(net "PWRGD_P3V3_SSD0_R")
	)
	(segment
		(start 221.877382 -228.940868)
		(end 221.19209 -229.62616)
		(width 0.15494)
		(layer "In15.Cu")
		(net "PWRGD_P3V3_SSD0_R")
	)
	(segment
		(start 338.57438 -227.994464)
		(end 338.50834 -227.928424)
		(width 0.15494)
		(layer "In15.Cu")
		(net "PWRGD_P3V3_SSD0_R")
	)
	(segment
		(start 301.39132 -227.630736)
		(end 300.461934 -228.560122)
		(width 0.15494)
		(layer "In15.Cu")
		(net "PWRGD_P3V3_SSD0_R")
	)
	(segment
		(start 326.999346 -229.4128)
		(end 326.465946 -228.8794)
		(width 0.15494)
		(layer "In15.Cu")
		(net "PWRGD_P3V3_SSD0_R")
	)
	(segment
		(start 51.285648 -345.465146)
		(end 50.991008 -345.170506)
		(width 0.13462)
		(layer "F.Cu")
		(net "P5E_PEX0_STN4_TX_C_DN<65>")
	)
	(segment
		(start 50.991008 -345.170506)
		(end 50.991008 -344.539062)
		(width 0.13462)
		(layer "F.Cu")
		(net "P5E_PEX0_STN4_TX_C_DN<65>")
	)
	(segment
		(start 50.991008 -344.539062)
		(end 51.311048 -344.219022)
		(width 0.13462)
		(layer "F.Cu")
		(net "P5E_PEX0_STN4_TX_C_DN<65>")
	)
	(segment
		(start 50.994818 -346.438982)
		(end 50.994818 -345.755976)
		(width 0.1651)
		(layer "In11.Cu")
		(net "P5E_PEX0_STN4_TX_C_DN<65>")
	)
	(segment
		(start 49.440338 -358.153716)
		(end 49.440338 -347.993462)
		(width 0.1651)
		(layer "In11.Cu")
		(net "P5E_PEX0_STN4_TX_C_DN<65>")
	)
	(segment
		(start 42.371772 -370.5987)
		(end 42.371772 -369.14836)
		(width 0.1651)
		(layer "In11.Cu")
		(net "P5E_PEX0_STN4_TX_C_DN<65>")
	)
	(segment
		(start 49.440338 -347.993462)
		(end 50.994818 -346.438982)
		(width 0.1651)
		(layer "In11.Cu")
		(net "P5E_PEX0_STN4_TX_C_DN<65>")
	)
	(segment
		(start 41.2369 -371.281198)
		(end 41.689274 -371.281198)
		(width 0.1651)
		(layer "In11.Cu")
		(net "P5E_PEX0_STN4_TX_C_DN<65>")
	)
	(segment
		(start 41.1099 -371.790214)
		(end 41.1099 -371.408198)
		(width 0.1651)
		(layer "In11.Cu")
		(net "P5E_PEX0_STN4_TX_C_DN<65>")
	)
	(segment
		(start 41.1099 -371.408198)
		(end 41.2369 -371.281198)
		(width 0.1651)
		(layer "In11.Cu")
		(net "P5E_PEX0_STN4_TX_C_DN<65>")
	)
	(segment
		(start 42.371772 -369.14836)
		(end 43.52798 -366.3569)
		(width 0.1651)
		(layer "In11.Cu")
		(net "P5E_PEX0_STN4_TX_C_DN<65>")
	)
	(segment
		(start 41.689274 -371.281198)
		(end 42.371772 -370.5987)
		(width 0.1651)
		(layer "In11.Cu")
		(net "P5E_PEX0_STN4_TX_C_DN<65>")
	)
	(segment
		(start 43.52798 -366.3569)
		(end 48.806608 -359.925366)
		(width 0.1651)
		(layer "In11.Cu")
		(net "P5E_PEX0_STN4_TX_C_DN<65>")
	)
	(segment
		(start 50.994818 -345.755976)
		(end 51.285648 -345.465146)
		(width 0.1651)
		(layer "In11.Cu")
		(net "P5E_PEX0_STN4_TX_C_DN<65>")
	)
	(segment
		(start 48.806608 -359.925366)
		(end 49.440338 -358.153716)
		(width 0.1651)
		(layer "In11.Cu")
		(net "P5E_PEX0_STN4_TX_C_DN<65>")
	)
	(segment
		(start 287.439862 -343.685622)
		(end 287.119822 -343.365582)
		(width 0.13462)
		(layer "F.Cu")
		(net "P5E_PEX2_STN4_TX_DN<71>")
	)
	(segment
		(start 287.119822 -343.365582)
		(end 287.119822 -342.734138)
		(width 0.13462)
		(layer "F.Cu")
		(net "P5E_PEX2_STN4_TX_DN<71>")
	)
	(segment
		(start 287.119822 -342.734138)
		(end 287.414462 -342.439498)
		(width 0.13462)
		(layer "F.Cu")
		(net "P5E_PEX2_STN4_TX_DN<71>")
	)
	(segment
		(start 314.315856 -321.887342)
		(end 314.315856 -319.052448)
		(width 0.1651)
		(layer "In11.Cu")
		(net "P5E_PEX2_STN4_TX_DN<71>")
	)
	(segment
		(start 314.315856 -319.052448)
		(end 314.315856 -319.024)
		(width 0.1143)
		(layer "In11.Cu")
		(net "P5E_PEX2_STN4_TX_DN<71>")
	)
	(segment
		(start 287.123632 -341.620348)
		(end 288.012632 -340.731348)
		(width 0.1651)
		(layer "In11.Cu")
		(net "P5E_PEX2_STN4_TX_DN<71>")
	)
	(segment
		(start 314.315856 -319.024)
		(end 314.270136 -318.97828)
		(width 0.1143)
		(layer "In11.Cu")
		(net "P5E_PEX2_STN4_TX_DN<71>")
	)
	(segment
		(start 312.80989 -324.70471)
		(end 314.315856 -321.887342)
		(width 0.1651)
		(layer "In11.Cu")
		(net "P5E_PEX2_STN4_TX_DN<71>")
	)
	(segment
		(start 314.384436 -314.899802)
		(end 314.649866 -314.899802)
		(width 0.1143)
		(layer "In11.Cu")
		(net "P5E_PEX2_STN4_TX_DN<71>")
	)
	(segment
		(start 288.012632 -340.731348)
		(end 309.105808 -328.408792)
		(width 0.1651)
		(layer "In11.Cu")
		(net "P5E_PEX2_STN4_TX_DN<71>")
	)
	(segment
		(start 309.105808 -328.408792)
		(end 312.80989 -324.70471)
		(width 0.1651)
		(layer "In11.Cu")
		(net "P5E_PEX2_STN4_TX_DN<71>")
	)
	(segment
		(start 314.270136 -318.97828)
		(end 314.270136 -315.014102)
		(width 0.1143)
		(layer "In11.Cu")
		(net "P5E_PEX2_STN4_TX_DN<71>")
	)
	(segment
		(start 287.414462 -342.439498)
		(end 287.123632 -342.148668)
		(width 0.1651)
		(layer "In11.Cu")
		(net "P5E_PEX2_STN4_TX_DN<71>")
	)
	(segment
		(start 287.123632 -342.148668)
		(end 287.123632 -341.620348)
		(width 0.1651)
		(layer "In11.Cu")
		(net "P5E_PEX2_STN4_TX_DN<71>")
	)
	(segment
		(start 314.270136 -315.014102)
		(end 314.384436 -314.899802)
		(width 0.1143)
		(layer "In11.Cu")
		(net "P5E_PEX2_STN4_TX_DN<71>")
	)
	(via
		(at 40.778938 -266.517882)
		(size 0.508)
		(drill 0.254)
		(layers "F.Cu" "B.Cu")
		(net "SPI_PEX0_SDIO3_R")
	)
	(via
		(at 22.86 -221.332806)
		(size 0.508)
		(drill 0.254)
		(layers "F.Cu" "B.Cu")
		(net "SPI_PEX0_SDIO3_R")
	)
	(segment
		(start 39.991284 -267.305536)
		(end 40.778938 -266.517882)
		(width 0.13208)
		(layer "B.Cu")
		(net "SPI_PEX0_SDIO3_R")
	)
	(segment
		(start 38.668452 -287.00349)
		(end 38.668452 -270.433292)
		(width 0.13208)
		(layer "B.Cu")
		(net "SPI_PEX0_SDIO3_R")
	)
	(segment
		(start 38.984428 -287.319466)
		(end 38.668452 -287.00349)
		(width 0.13208)
		(layer "B.Cu")
		(net "SPI_PEX0_SDIO3_R")
	)
	(segment
		(start 39.699946 -287.533842)
		(end 39.48557 -287.319466)
		(width 0.13208)
		(layer "B.Cu")
		(net "SPI_PEX0_SDIO3_R")
	)
	(segment
		(start 39.991284 -269.11046)
		(end 39.991284 -267.305536)
		(width 0.13208)
		(layer "B.Cu")
		(net "SPI_PEX0_SDIO3_R")
	)
	(segment
		(start 22.86 -221.332806)
		(end 24.120348 -221.332806)
		(width 0.13208)
		(layer "B.Cu")
		(net "SPI_PEX0_SDIO3_R")
	)
	(segment
		(start 39.48557 -287.319466)
		(end 38.984428 -287.319466)
		(width 0.13208)
		(layer "B.Cu")
		(net "SPI_PEX0_SDIO3_R")
	)
	(segment
		(start 39.699946 -288.374836)
		(end 39.699946 -287.533842)
		(width 0.13208)
		(layer "B.Cu")
		(net "SPI_PEX0_SDIO3_R")
	)
	(segment
		(start 38.668452 -270.433292)
		(end 39.991284 -269.11046)
		(width 0.13208)
		(layer "B.Cu")
		(net "SPI_PEX0_SDIO3_R")
	)
	(segment
		(start 23.943564 -221.902782)
		(end 23.373588 -221.332806)
		(width 0.15494)
		(layer "In5.Cu")
		(net "SPI_PEX0_SDIO3_R")
	)
	(segment
		(start 23.026116 -263.614662)
		(end 20.130516 -260.719062)
		(width 0.15494)
		(layer "In5.Cu")
		(net "SPI_PEX0_SDIO3_R")
	)
	(segment
		(start 40.549576 -265.87704)
		(end 39.699946 -265.02741)
		(width 0.15494)
		(layer "In5.Cu")
		(net "SPI_PEX0_SDIO3_R")
	)
	(segment
		(start 39.699946 -263.754108)
		(end 38.611048 -262.66521)
		(width 0.15494)
		(layer "In5.Cu")
		(net "SPI_PEX0_SDIO3_R")
	)
	(segment
		(start 44.121832 -265.87704)
		(end 40.549576 -265.87704)
		(width 0.15494)
		(layer "In5.Cu")
		(net "SPI_PEX0_SDIO3_R")
	)
	(segment
		(start 39.699946 -265.02741)
		(end 39.699946 -263.754108)
		(width 0.15494)
		(layer "In5.Cu")
		(net "SPI_PEX0_SDIO3_R")
	)
	(segment
		(start 20.130516 -245.377716)
		(end 23.943564 -241.564668)
		(width 0.15494)
		(layer "In5.Cu")
		(net "SPI_PEX0_SDIO3_R")
	)
	(segment
		(start 44.130468 -266.517882)
		(end 44.257468 -266.390882)
		(width 0.15494)
		(layer "In5.Cu")
		(net "SPI_PEX0_SDIO3_R")
	)
	(segment
		(start 23.943564 -241.564668)
		(end 23.943564 -221.902782)
		(width 0.15494)
		(layer "In5.Cu")
		(net "SPI_PEX0_SDIO3_R")
	)
	(segment
		(start 26.030936 -263.614662)
		(end 23.026116 -263.614662)
		(width 0.15494)
		(layer "In5.Cu")
		(net "SPI_PEX0_SDIO3_R")
	)
	(segment
		(start 20.130516 -260.719062)
		(end 20.130516 -245.377716)
		(width 0.15494)
		(layer "In5.Cu")
		(net "SPI_PEX0_SDIO3_R")
	)
	(segment
		(start 44.257468 -266.390882)
		(end 44.257468 -266.012676)
		(width 0.15494)
		(layer "In5.Cu")
		(net "SPI_PEX0_SDIO3_R")
	)
	(segment
		(start 27.28976 -263.0932)
		(end 26.030936 -263.614662)
		(width 0.15494)
		(layer "In5.Cu")
		(net "SPI_PEX0_SDIO3_R")
	)
	(segment
		(start 36.064444 -262.66521)
		(end 35.636454 -263.0932)
		(width 0.15494)
		(layer "In5.Cu")
		(net "SPI_PEX0_SDIO3_R")
	)
	(segment
		(start 35.636454 -263.0932)
		(end 27.28976 -263.0932)
		(width 0.15494)
		(layer "In5.Cu")
		(net "SPI_PEX0_SDIO3_R")
	)
	(segment
		(start 40.778938 -266.517882)
		(end 44.130468 -266.517882)
		(width 0.15494)
		(layer "In5.Cu")
		(net "SPI_PEX0_SDIO3_R")
	)
	(segment
		(start 44.257468 -266.012676)
		(end 44.121832 -265.87704)
		(width 0.15494)
		(layer "In5.Cu")
		(net "SPI_PEX0_SDIO3_R")
	)
	(segment
		(start 23.373588 -221.332806)
		(end 22.86 -221.332806)
		(width 0.15494)
		(layer "In5.Cu")
		(net "SPI_PEX0_SDIO3_R")
	)
	(segment
		(start 38.611048 -262.66521)
		(end 36.064444 -262.66521)
		(width 0.15494)
		(layer "In5.Cu")
		(net "SPI_PEX0_SDIO3_R")
	)
	(segment
		(start 22.736048 -350.685354)
		(end 22.416008 -350.365314)
		(width 0.13462)
		(layer "F.Cu")
		(net "P5E_PEX0_STN4_TX_C_DP<78>")
	)
	(segment
		(start 22.441408 -351.611438)
		(end 22.736048 -351.316798)
		(width 0.13462)
		(layer "F.Cu")
		(net "P5E_PEX0_STN4_TX_C_DP<78>")
	)
	(segment
		(start 22.736048 -351.316798)
		(end 22.736048 -350.685354)
		(width 0.13462)
		(layer "F.Cu")
		(net "P5E_PEX0_STN4_TX_C_DP<78>")
	)
	(segment
		(start 20.6248 -365.850678)
		(end 21.209762 -353.943158)
		(width 0.1651)
		(layer "In11.Cu")
		(net "P5E_PEX0_STN4_TX_C_DP<78>")
	)
	(segment
		(start 31.002478 -397.757142)
		(end 31.002478 -395.167104)
		(width 0.1651)
		(layer "In11.Cu")
		(net "P5E_PEX0_STN4_TX_C_DP<78>")
	)
	(segment
		(start 22.732238 -351.902268)
		(end 22.441408 -351.611438)
		(width 0.1651)
		(layer "In11.Cu")
		(net "P5E_PEX0_STN4_TX_C_DP<78>")
	)
	(segment
		(start 21.209762 -353.943158)
		(end 22.732238 -352.420682)
		(width 0.1651)
		(layer "In11.Cu")
		(net "P5E_PEX0_STN4_TX_C_DP<78>")
	)
	(segment
		(start 30.590744 -394.892022)
		(end 30.467554 -394.91666)
		(width 0.1651)
		(layer "In11.Cu")
		(net "P5E_PEX0_STN4_TX_C_DP<78>")
	)
	(segment
		(start 31.002478 -395.167104)
		(end 30.590744 -394.892022)
		(width 0.1651)
		(layer "In11.Cu")
		(net "P5E_PEX0_STN4_TX_C_DP<78>")
	)
	(segment
		(start 30.030928 -394.51788)
		(end 29.619194 -394.242798)
		(width 0.1651)
		(layer "In11.Cu")
		(net "P5E_PEX0_STN4_TX_C_DP<78>")
	)
	(segment
		(start 30.236922 -398.09928)
		(end 30.66034 -398.09928)
		(width 0.1651)
		(layer "In11.Cu")
		(net "P5E_PEX0_STN4_TX_C_DP<78>")
	)
	(segment
		(start 30.109922 -397.97228)
		(end 30.236922 -398.09928)
		(width 0.1651)
		(layer "In11.Cu")
		(net "P5E_PEX0_STN4_TX_C_DP<78>")
	)
	(segment
		(start 29.496004 -394.267436)
		(end 29.083762 -393.991846)
		(width 0.1651)
		(layer "In11.Cu")
		(net "P5E_PEX0_STN4_TX_C_DP<78>")
	)
	(segment
		(start 30.109922 -397.59001)
		(end 30.109922 -397.97228)
		(width 0.1651)
		(layer "In11.Cu")
		(net "P5E_PEX0_STN4_TX_C_DP<78>")
	)
	(segment
		(start 22.732238 -352.420682)
		(end 22.732238 -351.902268)
		(width 0.1651)
		(layer "In11.Cu")
		(net "P5E_PEX0_STN4_TX_C_DP<78>")
	)
	(segment
		(start 30.467554 -394.91666)
		(end 30.055312 -394.64107)
		(width 0.1651)
		(layer "In11.Cu")
		(net "P5E_PEX0_STN4_TX_C_DP<78>")
	)
	(segment
		(start 20.407376 -384.212084)
		(end 20.407376 -381.609092)
		(width 0.1651)
		(layer "In11.Cu")
		(net "P5E_PEX0_STN4_TX_C_DP<78>")
	)
	(segment
		(start 20.6248 -368.104166)
		(end 20.6248 -365.850678)
		(width 0.1651)
		(layer "In11.Cu")
		(net "P5E_PEX0_STN4_TX_C_DP<78>")
	)
	(segment
		(start 30.055312 -394.64107)
		(end 30.030928 -394.51788)
		(width 0.1651)
		(layer "In11.Cu")
		(net "P5E_PEX0_STN4_TX_C_DP<78>")
	)
	(segment
		(start 29.059378 -393.868656)
		(end 24.503126 -390.824212)
		(width 0.1651)
		(layer "In11.Cu")
		(net "P5E_PEX0_STN4_TX_C_DP<78>")
	)
	(segment
		(start 29.083762 -393.991846)
		(end 29.059378 -393.868656)
		(width 0.1651)
		(layer "In11.Cu")
		(net "P5E_PEX0_STN4_TX_C_DP<78>")
	)
	(segment
		(start 20.407376 -381.609092)
		(end 20.6248 -368.104166)
		(width 0.1651)
		(layer "In11.Cu")
		(net "P5E_PEX0_STN4_TX_C_DP<78>")
	)
	(segment
		(start 22.1869 -388.507986)
		(end 20.407376 -384.212084)
		(width 0.1651)
		(layer "In11.Cu")
		(net "P5E_PEX0_STN4_TX_C_DP<78>")
	)
	(segment
		(start 29.619194 -394.242798)
		(end 29.496004 -394.267436)
		(width 0.1651)
		(layer "In11.Cu")
		(net "P5E_PEX0_STN4_TX_C_DP<78>")
	)
	(segment
		(start 30.66034 -398.09928)
		(end 31.002478 -397.757142)
		(width 0.1651)
		(layer "In11.Cu")
		(net "P5E_PEX0_STN4_TX_C_DP<78>")
	)
	(segment
		(start 24.503126 -390.824212)
		(end 22.1869 -388.507986)
		(width 0.1651)
		(layer "In11.Cu")
		(net "P5E_PEX0_STN4_TX_C_DP<78>")
	)
	(segment
		(start 41.389808 -349.511874)
		(end 41.389808 -348.88043)
		(width 0.13462)
		(layer "F.Cu")
		(net "P5E_PEX0_STN4_TX_DP<69>")
	)
	(segment
		(start 41.389808 -348.88043)
		(end 41.095168 -348.58579)
		(width 0.13462)
		(layer "F.Cu")
		(net "P5E_PEX0_STN4_TX_DP<69>")
	)
	(segment
		(start 41.069768 -349.831914)
		(end 41.389808 -349.511874)
		(width 0.13462)
		(layer "F.Cu")
		(net "P5E_PEX0_STN4_TX_DP<69>")
	)
	(segment
		(start 42.940478 -341.806276)
		(end 43.362626 -340.787228)
		(width 0.1651)
		(layer "In11.Cu")
		(net "P5E_PEX0_STN4_TX_DP<69>")
	)
	(segment
		(start 91.732862 -325.287132)
		(end 92.726002 -324.756018)
		(width 0.1651)
		(layer "In11.Cu")
		(net "P5E_PEX0_STN4_TX_DP<69>")
	)
	(segment
		(start 77.12964 -309.497476)
		(end 77.12964 -309.288688)
		(width 0.1143)
		(layer "In11.Cu")
		(net "P5E_PEX0_STN4_TX_DP<69>")
	)
	(segment
		(start 43.362626 -340.787228)
		(end 45.335698 -338.813902)
		(width 0.1651)
		(layer "In11.Cu")
		(net "P5E_PEX0_STN4_TX_DP<69>")
	)
	(segment
		(start 92.387166 -316.803278)
		(end 89.581228 -315.640974)
		(width 0.1651)
		(layer "In11.Cu")
		(net "P5E_PEX0_STN4_TX_DP<69>")
	)
	(segment
		(start 83.614006 -309.83174)
		(end 83.568286 -309.78602)
		(width 0.1143)
		(layer "In11.Cu")
		(net "P5E_PEX0_STN4_TX_DP<69>")
	)
	(segment
		(start 83.642454 -309.83174)
		(end 83.614006 -309.83174)
		(width 0.1143)
		(layer "In11.Cu")
		(net "P5E_PEX0_STN4_TX_DP<69>")
	)
	(segment
		(start 56.444134 -334.416908)
		(end 78.447138 -330.040742)
		(width 0.1651)
		(layer "In11.Cu")
		(net "P5E_PEX0_STN4_TX_DP<69>")
	)
	(segment
		(start 41.095168 -348.58579)
		(end 41.385998 -348.29496)
		(width 0.1651)
		(layer "In11.Cu")
		(net "P5E_PEX0_STN4_TX_DP<69>")
	)
	(segment
		(start 77.04074 -309.199788)
		(end 76.74991 -309.199788)
		(width 0.1143)
		(layer "In11.Cu")
		(net "P5E_PEX0_STN4_TX_DP<69>")
	)
	(segment
		(start 92.726002 -324.756018)
		(end 93.677232 -323.805042)
		(width 0.1651)
		(layer "In11.Cu")
		(net "P5E_PEX0_STN4_TX_DP<69>")
	)
	(segment
		(start 93.747082 -318.163194)
		(end 92.387166 -316.803278)
		(width 0.1651)
		(layer "In11.Cu")
		(net "P5E_PEX0_STN4_TX_DP<69>")
	)
	(segment
		(start 41.385998 -348.29496)
		(end 41.385998 -347.620082)
		(width 0.1651)
		(layer "In11.Cu")
		(net "P5E_PEX0_STN4_TX_DP<69>")
	)
	(segment
		(start 89.581228 -315.640974)
		(end 83.771994 -309.83174)
		(width 0.1651)
		(layer "In11.Cu")
		(net "P5E_PEX0_STN4_TX_DP<69>")
	)
	(segment
		(start 83.568286 -309.78602)
		(end 77.418184 -309.78602)
		(width 0.1143)
		(layer "In11.Cu")
		(net "P5E_PEX0_STN4_TX_DP<69>")
	)
	(segment
		(start 45.335698 -338.813902)
		(end 47.7266 -337.536028)
		(width 0.1651)
		(layer "In11.Cu")
		(net "P5E_PEX0_STN4_TX_DP<69>")
	)
	(segment
		(start 94.482158 -319.937892)
		(end 93.747082 -318.163194)
		(width 0.1651)
		(layer "In11.Cu")
		(net "P5E_PEX0_STN4_TX_DP<69>")
	)
	(segment
		(start 42.940478 -346.065602)
		(end 42.940478 -341.806276)
		(width 0.1651)
		(layer "In11.Cu")
		(net "P5E_PEX0_STN4_TX_DP<69>")
	)
	(segment
		(start 94.482158 -321.861688)
		(end 94.482158 -319.937892)
		(width 0.1651)
		(layer "In11.Cu")
		(net "P5E_PEX0_STN4_TX_DP<69>")
	)
	(segment
		(start 83.771994 -309.83174)
		(end 83.642454 -309.83174)
		(width 0.1651)
		(layer "In11.Cu")
		(net "P5E_PEX0_STN4_TX_DP<69>")
	)
	(segment
		(start 77.418184 -309.78602)
		(end 77.12964 -309.497476)
		(width 0.1143)
		(layer "In11.Cu")
		(net "P5E_PEX0_STN4_TX_DP<69>")
	)
	(segment
		(start 47.7266 -337.536028)
		(end 56.444134 -334.416908)
		(width 0.1651)
		(layer "In11.Cu")
		(net "P5E_PEX0_STN4_TX_DP<69>")
	)
	(segment
		(start 78.447138 -330.040742)
		(end 91.732862 -325.287132)
		(width 0.1651)
		(layer "In11.Cu")
		(net "P5E_PEX0_STN4_TX_DP<69>")
	)
	(segment
		(start 77.12964 -309.288688)
		(end 77.04074 -309.199788)
		(width 0.1143)
		(layer "In11.Cu")
		(net "P5E_PEX0_STN4_TX_DP<69>")
	)
	(segment
		(start 93.677232 -323.805042)
		(end 94.482158 -321.861688)
		(width 0.1651)
		(layer "In11.Cu")
		(net "P5E_PEX0_STN4_TX_DP<69>")
	)
	(segment
		(start 41.385998 -347.620082)
		(end 42.940478 -346.065602)
		(width 0.1651)
		(layer "In11.Cu")
		(net "P5E_PEX0_STN4_TX_DP<69>")
	)
	(segment
		(start 283.416502 -349.831914)
		(end 283.736542 -349.511874)
		(width 0.13462)
		(layer "F.Cu")
		(net "P5E_PEX2_STN4_TX_DP<72>")
	)
	(segment
		(start 283.736542 -349.511874)
		(end 283.736542 -348.88043)
		(width 0.13462)
		(layer "F.Cu")
		(net "P5E_PEX2_STN4_TX_DP<72>")
	)
	(segment
		(start 283.736542 -348.88043)
		(end 283.441902 -348.58579)
		(width 0.13462)
		(layer "F.Cu")
		(net "P5E_PEX2_STN4_TX_DP<72>")
	)
	(segment
		(start 312.179716 -313.594496)
		(end 312.3946 -313.379612)
		(width 0.1143)
		(layer "In11.Cu")
		(net "P5E_PEX2_STN4_TX_DP<72>")
	)
	(segment
		(start 283.732732 -348.29496)
		(end 283.732732 -347.667834)
		(width 0.1651)
		(layer "In11.Cu")
		(net "P5E_PEX2_STN4_TX_DP<72>")
	)
	(segment
		(start 312.749692 -313.265312)
		(end 312.749692 -312.999882)
		(width 0.1143)
		(layer "In11.Cu")
		(net "P5E_PEX2_STN4_TX_DP<72>")
	)
	(segment
		(start 286.666178 -339.906102)
		(end 308.746652 -327.007728)
		(width 0.1651)
		(layer "In11.Cu")
		(net "P5E_PEX2_STN4_TX_DP<72>")
	)
	(segment
		(start 312.179716 -319.889632)
		(end 312.179716 -313.594496)
		(width 0.1143)
		(layer "In11.Cu")
		(net "P5E_PEX2_STN4_TX_DP<72>")
	)
	(segment
		(start 312.133996 -319.935352)
		(end 312.179716 -319.889632)
		(width 0.1143)
		(layer "In11.Cu")
		(net "P5E_PEX2_STN4_TX_DP<72>")
	)
	(segment
		(start 308.746652 -327.007728)
		(end 311.77992 -323.97446)
		(width 0.1651)
		(layer "In11.Cu")
		(net "P5E_PEX2_STN4_TX_DP<72>")
	)
	(segment
		(start 312.133996 -323.11975)
		(end 312.133996 -319.9638)
		(width 0.1651)
		(layer "In11.Cu")
		(net "P5E_PEX2_STN4_TX_DP<72>")
	)
	(segment
		(start 311.77992 -323.97446)
		(end 312.133996 -323.11975)
		(width 0.1651)
		(layer "In11.Cu")
		(net "P5E_PEX2_STN4_TX_DP<72>")
	)
	(segment
		(start 312.635392 -313.379612)
		(end 312.749692 -313.265312)
		(width 0.1143)
		(layer "In11.Cu")
		(net "P5E_PEX2_STN4_TX_DP<72>")
	)
	(segment
		(start 283.732732 -347.667834)
		(end 285.287212 -346.113354)
		(width 0.1651)
		(layer "In11.Cu")
		(net "P5E_PEX2_STN4_TX_DP<72>")
	)
	(segment
		(start 285.287212 -341.285068)
		(end 286.666178 -339.906102)
		(width 0.1651)
		(layer "In11.Cu")
		(net "P5E_PEX2_STN4_TX_DP<72>")
	)
	(segment
		(start 312.133996 -319.9638)
		(end 312.133996 -319.935352)
		(width 0.1143)
		(layer "In11.Cu")
		(net "P5E_PEX2_STN4_TX_DP<72>")
	)
	(segment
		(start 283.441902 -348.58579)
		(end 283.732732 -348.29496)
		(width 0.1651)
		(layer "In11.Cu")
		(net "P5E_PEX2_STN4_TX_DP<72>")
	)
	(segment
		(start 285.287212 -346.113354)
		(end 285.287212 -341.285068)
		(width 0.1651)
		(layer "In11.Cu")
		(net "P5E_PEX2_STN4_TX_DP<72>")
	)
	(segment
		(start 312.3946 -313.379612)
		(end 312.635392 -313.379612)
		(width 0.1143)
		(layer "In11.Cu")
		(net "P5E_PEX2_STN4_TX_DP<72>")
	)
	(via
		(at 37.23513 -267.578078)
		(size 0.508)
		(drill 0.254)
		(layers "F.Cu" "B.Cu")
		(net "SPI_PEX0_SDIO2_R")
	)
	(via
		(at 15.230348 -231.203754)
		(size 0.508)
		(drill 0.254)
		(layers "F.Cu" "B.Cu")
		(net "SPI_PEX0_SDIO2_R")
	)
	(segment
		(start 39.38016 -293.04996)
		(end 39.718996 -293.388796)
		(width 0.13208)
		(layer "B.Cu")
		(net "SPI_PEX0_SDIO2_R")
	)
	(segment
		(start 38.99916 -293.04996)
		(end 39.38016 -293.04996)
		(width 0.13208)
		(layer "B.Cu")
		(net "SPI_PEX0_SDIO2_R")
	)
	(segment
		(start 38.345618 -292.065964)
		(end 38.722046 -292.442392)
		(width 0.13208)
		(layer "B.Cu")
		(net "SPI_PEX0_SDIO2_R")
	)
	(segment
		(start 38.722046 -292.442392)
		(end 38.722046 -292.772846)
		(width 0.13208)
		(layer "B.Cu")
		(net "SPI_PEX0_SDIO2_R")
	)
	(segment
		(start 38.722046 -292.772846)
		(end 38.99916 -293.04996)
		(width 0.13208)
		(layer "B.Cu")
		(net "SPI_PEX0_SDIO2_R")
	)
	(segment
		(start 35.837368 -268.97584)
		(end 35.837368 -291.75837)
		(width 0.13208)
		(layer "B.Cu")
		(net "SPI_PEX0_SDIO2_R")
	)
	(segment
		(start 39.718996 -293.388796)
		(end 39.718996 -294.8051)
		(width 0.13208)
		(layer "B.Cu")
		(net "SPI_PEX0_SDIO2_R")
	)
	(segment
		(start 36.144962 -292.065964)
		(end 38.345618 -292.065964)
		(width 0.13208)
		(layer "B.Cu")
		(net "SPI_PEX0_SDIO2_R")
	)
	(segment
		(start 37.23513 -267.578078)
		(end 35.837368 -268.97584)
		(width 0.13208)
		(layer "B.Cu")
		(net "SPI_PEX0_SDIO2_R")
	)
	(segment
		(start 35.837368 -291.75837)
		(end 36.144962 -292.065964)
		(width 0.13208)
		(layer "B.Cu")
		(net "SPI_PEX0_SDIO2_R")
	)
	(segment
		(start 15.230348 -229.997)
		(end 15.230348 -231.203754)
		(width 0.13208)
		(layer "B.Cu")
		(net "SPI_PEX0_SDIO2_R")
	)
	(segment
		(start 37.06622 -273.110706)
		(end 37.23513 -272.941796)
		(width 0.15494)
		(layer "In5.Cu")
		(net "SPI_PEX0_SDIO2_R")
	)
	(segment
		(start 34.736532 -267.476732)
		(end 34.736532 -266.192)
		(width 0.15494)
		(layer "In5.Cu")
		(net "SPI_PEX0_SDIO2_R")
	)
	(segment
		(start 34.601912 -267.611352)
		(end 34.736532 -267.476732)
		(width 0.15494)
		(layer "In5.Cu")
		(net "SPI_PEX0_SDIO2_R")
	)
	(segment
		(start 33.837372 -266.192)
		(end 33.837372 -267.476732)
		(width 0.15494)
		(layer "In5.Cu")
		(net "SPI_PEX0_SDIO2_R")
	)
	(segment
		(start 35.362896 -273.110706)
		(end 37.06622 -273.110706)
		(width 0.15494)
		(layer "In5.Cu")
		(net "SPI_PEX0_SDIO2_R")
	)
	(segment
		(start 33.971992 -267.611352)
		(end 34.601912 -267.611352)
		(width 0.15494)
		(layer "In5.Cu")
		(net "SPI_PEX0_SDIO2_R")
	)
	(segment
		(start 28.3083 -266.0396)
		(end 33.684972 -266.0396)
		(width 0.15494)
		(layer "In5.Cu")
		(net "SPI_PEX0_SDIO2_R")
	)
	(segment
		(start 35.170872 -272.918682)
		(end 35.362896 -273.110706)
		(width 0.15494)
		(layer "In5.Cu")
		(net "SPI_PEX0_SDIO2_R")
	)
	(segment
		(start 33.837372 -267.476732)
		(end 33.971992 -267.611352)
		(width 0.15494)
		(layer "In5.Cu")
		(net "SPI_PEX0_SDIO2_R")
	)
	(segment
		(start 33.684972 -266.0396)
		(end 33.837372 -266.192)
		(width 0.15494)
		(layer "In5.Cu")
		(net "SPI_PEX0_SDIO2_R")
	)
	(segment
		(start 35.170872 -271.605248)
		(end 35.170872 -272.918682)
		(width 0.15494)
		(layer "In5.Cu")
		(net "SPI_PEX0_SDIO2_R")
	)
	(segment
		(start 34.871152 -266.05738)
		(end 35.80638 -266.05738)
		(width 0.15494)
		(layer "In5.Cu")
		(net "SPI_PEX0_SDIO2_R")
	)
	(segment
		(start 35.80638 -266.05738)
		(end 36.00069 -266.25169)
		(width 0.15494)
		(layer "In5.Cu")
		(net "SPI_PEX0_SDIO2_R")
	)
	(segment
		(start 35.284918 -271.491202)
		(end 35.170872 -271.605248)
		(width 0.15494)
		(layer "In5.Cu")
		(net "SPI_PEX0_SDIO2_R")
	)
	(segment
		(start 15.230348 -241.734086)
		(end 17.074388 -243.579142)
		(width 0.15494)
		(layer "In5.Cu")
		(net "SPI_PEX0_SDIO2_R")
	)
	(segment
		(start 37.23513 -272.941796)
		(end 37.23513 -267.578078)
		(width 0.15494)
		(layer "In5.Cu")
		(net "SPI_PEX0_SDIO2_R")
	)
	(segment
		(start 36.00069 -271.263364)
		(end 35.772852 -271.491202)
		(width 0.15494)
		(layer "In5.Cu")
		(net "SPI_PEX0_SDIO2_R")
	)
	(segment
		(start 17.074388 -243.579142)
		(end 17.074388 -262.845042)
		(width 0.15494)
		(layer "In5.Cu")
		(net "SPI_PEX0_SDIO2_R")
	)
	(segment
		(start 34.736532 -266.192)
		(end 34.871152 -266.05738)
		(width 0.15494)
		(layer "In5.Cu")
		(net "SPI_PEX0_SDIO2_R")
	)
	(segment
		(start 17.074388 -262.845042)
		(end 21.157946 -266.9286)
		(width 0.15494)
		(layer "In5.Cu")
		(net "SPI_PEX0_SDIO2_R")
	)
	(segment
		(start 15.230348 -231.203754)
		(end 15.230348 -241.734086)
		(width 0.15494)
		(layer "In5.Cu")
		(net "SPI_PEX0_SDIO2_R")
	)
	(segment
		(start 26.162 -266.9286)
		(end 28.3083 -266.0396)
		(width 0.15494)
		(layer "In5.Cu")
		(net "SPI_PEX0_SDIO2_R")
	)
	(segment
		(start 35.772852 -271.491202)
		(end 35.284918 -271.491202)
		(width 0.15494)
		(layer "In5.Cu")
		(net "SPI_PEX0_SDIO2_R")
	)
	(segment
		(start 21.157946 -266.9286)
		(end 26.162 -266.9286)
		(width 0.15494)
		(layer "In5.Cu")
		(net "SPI_PEX0_SDIO2_R")
	)
	(segment
		(start 36.00069 -266.25169)
		(end 36.00069 -271.263364)
		(width 0.15494)
		(layer "In5.Cu")
		(net "SPI_PEX0_SDIO2_R")
	)
	(segment
		(start 81.879694 -308.581552)
		(end 81.879694 -308.338728)
		(width 0.1143)
		(layer "In15.Cu")
		(net "P5E_PEX0_STN4_RX_DP<68>")
	)
	(segment
		(start 34.509964 -379.772164)
		(end 34.636964 -379.899164)
		(width 0.1651)
		(layer "In15.Cu")
		(net "P5E_PEX0_STN4_RX_DP<68>")
	)
	(segment
		(start 90.372184 -313.495182)
		(end 90.21064 -313.495182)
		(width 0.1651)
		(layer "In15.Cu")
		(net "P5E_PEX0_STN4_RX_DP<68>")
	)
	(segment
		(start 83.57108 -308.820058)
		(end 82.1182 -308.820058)
		(width 0.1143)
		(layer "In15.Cu")
		(net "P5E_PEX0_STN4_RX_DP<68>")
	)
	(segment
		(start 91.557602 -314.6806)
		(end 91.21648 -314.339478)
		(width 0.1651)
		(layer "In15.Cu")
		(net "P5E_PEX0_STN4_RX_DP<68>")
	)
	(segment
		(start 90.713306 -313.997848)
		(end 90.713306 -313.836304)
		(width 0.1651)
		(layer "In15.Cu")
		(net "P5E_PEX0_STN4_RX_DP<68>")
	)
	(segment
		(start 89.366344 -312.650886)
		(end 89.024714 -312.309256)
		(width 0.1651)
		(layer "In15.Cu")
		(net "P5E_PEX0_STN4_RX_DP<68>")
	)
	(segment
		(start 93.599 -324.365366)
		(end 94.024196 -323.857874)
		(width 0.1651)
		(layer "In15.Cu")
		(net "P5E_PEX0_STN4_RX_DP<68>")
	)
	(segment
		(start 35.936936 -368.31524)
		(end 36.909756 -367.003584)
		(width 0.1651)
		(layer "In15.Cu")
		(net "P5E_PEX0_STN4_RX_DP<68>")
	)
	(segment
		(start 89.86901 -312.992008)
		(end 89.527888 -312.650886)
		(width 0.1651)
		(layer "In15.Cu")
		(net "P5E_PEX0_STN4_RX_DP<68>")
	)
	(segment
		(start 91.557602 -314.842144)
		(end 91.557602 -314.6806)
		(width 0.1651)
		(layer "In15.Cu")
		(net "P5E_PEX0_STN4_RX_DP<68>")
	)
	(segment
		(start 89.86901 -313.153552)
		(end 89.86901 -312.992008)
		(width 0.1651)
		(layer "In15.Cu")
		(net "P5E_PEX0_STN4_RX_DP<68>")
	)
	(segment
		(start 38.77818 -364.484666)
		(end 42.714164 -358.594152)
		(width 0.1651)
		(layer "In15.Cu")
		(net "P5E_PEX0_STN4_RX_DP<68>")
	)
	(segment
		(start 94.024196 -323.857874)
		(end 94.600522 -322.466208)
		(width 0.1651)
		(layer "In15.Cu")
		(net "P5E_PEX0_STN4_RX_DP<68>")
	)
	(segment
		(start 44.478448 -340.186518)
		(end 47.916592 -339.143594)
		(width 0.1651)
		(layer "In15.Cu")
		(net "P5E_PEX0_STN4_RX_DP<68>")
	)
	(segment
		(start 34.636964 -379.899164)
		(end 34.870644 -379.899164)
		(width 0.1651)
		(layer "In15.Cu")
		(net "P5E_PEX0_STN4_RX_DP<68>")
	)
	(segment
		(start 36.909756 -367.003584)
		(end 36.885626 -366.840262)
		(width 0.1651)
		(layer "In15.Cu")
		(net "P5E_PEX0_STN4_RX_DP<68>")
	)
	(segment
		(start 43.24477 -341.420196)
		(end 44.478448 -340.186518)
		(width 0.1651)
		(layer "In15.Cu")
		(net "P5E_PEX0_STN4_RX_DP<68>")
	)
	(segment
		(start 89.024714 -312.147712)
		(end 86.539578 -309.662576)
		(width 0.1651)
		(layer "In15.Cu")
		(net "P5E_PEX0_STN4_RX_DP<68>")
	)
	(segment
		(start 82.1182 -308.820058)
		(end 81.879694 -308.581552)
		(width 0.1143)
		(layer "In15.Cu")
		(net "P5E_PEX0_STN4_RX_DP<68>")
	)
	(segment
		(start 91.899232 -315.183774)
		(end 91.557602 -314.842144)
		(width 0.1651)
		(layer "In15.Cu")
		(net "P5E_PEX0_STN4_RX_DP<68>")
	)
	(segment
		(start 92.190316 -325.398638)
		(end 93.599 -324.365366)
		(width 0.1651)
		(layer "In15.Cu")
		(net "P5E_PEX0_STN4_RX_DP<68>")
	)
	(segment
		(start 92.060776 -315.183774)
		(end 91.899232 -315.183774)
		(width 0.1651)
		(layer "In15.Cu")
		(net "P5E_PEX0_STN4_RX_DP<68>")
	)
	(segment
		(start 91.054936 -314.339478)
		(end 90.713306 -313.997848)
		(width 0.1651)
		(layer "In15.Cu")
		(net "P5E_PEX0_STN4_RX_DP<68>")
	)
	(segment
		(start 81.879694 -308.338728)
		(end 81.790794 -308.249828)
		(width 0.1143)
		(layer "In15.Cu")
		(net "P5E_PEX0_STN4_RX_DP<68>")
	)
	(segment
		(start 78.718156 -330.979018)
		(end 92.190316 -325.398638)
		(width 0.1651)
		(layer "In15.Cu")
		(net "P5E_PEX0_STN4_RX_DP<68>")
	)
	(segment
		(start 42.714164 -358.594152)
		(end 42.940478 -358.047798)
		(width 0.1651)
		(layer "In15.Cu")
		(net "P5E_PEX0_STN4_RX_DP<68>")
	)
	(segment
		(start 89.024714 -312.309256)
		(end 89.024714 -312.147712)
		(width 0.1651)
		(layer "In15.Cu")
		(net "P5E_PEX0_STN4_RX_DP<68>")
	)
	(segment
		(start 81.790794 -308.249828)
		(end 81.499964 -308.249828)
		(width 0.1143)
		(layer "In15.Cu")
		(net "P5E_PEX0_STN4_RX_DP<68>")
	)
	(segment
		(start 34.870644 -379.899164)
		(end 35.384994 -379.384814)
		(width 0.1651)
		(layer "In15.Cu")
		(net "P5E_PEX0_STN4_RX_DP<68>")
	)
	(segment
		(start 35.384994 -379.384814)
		(end 35.384994 -369.648232)
		(width 0.1651)
		(layer "In15.Cu")
		(net "P5E_PEX0_STN4_RX_DP<68>")
	)
	(segment
		(start 83.645248 -308.865778)
		(end 83.6168 -308.865778)
		(width 0.1143)
		(layer "In15.Cu")
		(net "P5E_PEX0_STN4_RX_DP<68>")
	)
	(segment
		(start 93.633036 -316.756034)
		(end 92.060776 -315.183774)
		(width 0.1651)
		(layer "In15.Cu")
		(net "P5E_PEX0_STN4_RX_DP<68>")
	)
	(segment
		(start 90.713306 -313.836304)
		(end 90.372184 -313.495182)
		(width 0.1651)
		(layer "In15.Cu")
		(net "P5E_PEX0_STN4_RX_DP<68>")
	)
	(segment
		(start 34.509964 -379.390148)
		(end 34.509964 -379.772164)
		(width 0.1651)
		(layer "In15.Cu")
		(net "P5E_PEX0_STN4_RX_DP<68>")
	)
	(segment
		(start 37.173408 -366.45215)
		(end 37.33673 -366.42802)
		(width 0.1651)
		(layer "In15.Cu")
		(net "P5E_PEX0_STN4_RX_DP<68>")
	)
	(segment
		(start 94.600522 -322.466208)
		(end 94.844616 -319.680844)
		(width 0.1651)
		(layer "In15.Cu")
		(net "P5E_PEX0_STN4_RX_DP<68>")
	)
	(segment
		(start 42.940478 -342.154764)
		(end 43.24477 -341.420196)
		(width 0.1651)
		(layer "In15.Cu")
		(net "P5E_PEX0_STN4_RX_DP<68>")
	)
	(segment
		(start 83.6168 -308.865778)
		(end 83.57108 -308.820058)
		(width 0.1143)
		(layer "In15.Cu")
		(net "P5E_PEX0_STN4_RX_DP<68>")
	)
	(segment
		(start 94.844616 -319.680844)
		(end 93.633036 -316.756034)
		(width 0.1651)
		(layer "In15.Cu")
		(net "P5E_PEX0_STN4_RX_DP<68>")
	)
	(segment
		(start 89.527888 -312.650886)
		(end 89.366344 -312.650886)
		(width 0.1651)
		(layer "In15.Cu")
		(net "P5E_PEX0_STN4_RX_DP<68>")
	)
	(segment
		(start 91.21648 -314.339478)
		(end 91.054936 -314.339478)
		(width 0.1651)
		(layer "In15.Cu")
		(net "P5E_PEX0_STN4_RX_DP<68>")
	)
	(segment
		(start 47.916592 -339.143594)
		(end 70.221348 -333.556356)
		(width 0.1651)
		(layer "In15.Cu")
		(net "P5E_PEX0_STN4_RX_DP<68>")
	)
	(segment
		(start 70.221348 -333.556356)
		(end 78.718156 -330.979018)
		(width 0.1651)
		(layer "In15.Cu")
		(net "P5E_PEX0_STN4_RX_DP<68>")
	)
	(segment
		(start 90.21064 -313.495182)
		(end 89.86901 -313.153552)
		(width 0.1651)
		(layer "In15.Cu")
		(net "P5E_PEX0_STN4_RX_DP<68>")
	)
	(segment
		(start 86.539578 -309.662576)
		(end 85.347302 -308.865778)
		(width 0.1651)
		(layer "In15.Cu")
		(net "P5E_PEX0_STN4_RX_DP<68>")
	)
	(segment
		(start 36.885626 -366.840262)
		(end 37.173408 -366.45215)
		(width 0.1651)
		(layer "In15.Cu")
		(net "P5E_PEX0_STN4_RX_DP<68>")
	)
	(segment
		(start 42.940478 -358.047798)
		(end 42.940478 -342.154764)
		(width 0.1651)
		(layer "In15.Cu")
		(net "P5E_PEX0_STN4_RX_DP<68>")
	)
	(segment
		(start 85.347302 -308.865778)
		(end 83.645248 -308.865778)
		(width 0.1651)
		(layer "In15.Cu")
		(net "P5E_PEX0_STN4_RX_DP<68>")
	)
	(segment
		(start 35.384994 -369.648232)
		(end 35.936936 -368.31524)
		(width 0.1651)
		(layer "In15.Cu")
		(net "P5E_PEX0_STN4_RX_DP<68>")
	)
	(segment
		(start 37.33673 -366.42802)
		(end 38.77818 -364.484666)
		(width 0.1651)
		(layer "In15.Cu")
		(net "P5E_PEX0_STN4_RX_DP<68>")
	)
	(segment
		(start 37.960808 -343.685622)
		(end 38.280848 -343.365582)
		(width 0.13462)
		(layer "F.Cu")
		(net "P5E_PEX0_STN4_TX_DP<71>")
	)
	(segment
		(start 38.280848 -342.734138)
		(end 37.986208 -342.439498)
		(width 0.13462)
		(layer "F.Cu")
		(net "P5E_PEX0_STN4_TX_DP<71>")
	)
	(segment
		(start 38.280848 -343.365582)
		(end 38.280848 -342.734138)
		(width 0.13462)
		(layer "F.Cu")
		(net "P5E_PEX0_STN4_TX_DP<71>")
	)
	(segment
		(start 38.277038 -340.920832)
		(end 38.316916 -340.85403)
		(width 0.1651)
		(layer "In11.Cu")
		(net "P5E_PEX0_STN4_TX_DP<71>")
	)
	(segment
		(start 81.790794 -314.899802)
		(end 81.499964 -314.899802)
		(width 0.1143)
		(layer "In11.Cu")
		(net "P5E_PEX0_STN4_TX_DP<71>")
	)
	(segment
		(start 81.833974 -322.625974)
		(end 81.833974 -319.151)
		(width 0.1651)
		(layer "In11.Cu")
		(net "P5E_PEX0_STN4_TX_DP<71>")
	)
	(segment
		(start 55.670704 -332.622398)
		(end 76.055728 -328.567796)
		(width 0.1651)
		(layer "In11.Cu")
		(net "P5E_PEX0_STN4_TX_DP<71>")
	)
	(segment
		(start 39.193216 -339.392514)
		(end 44.140628 -336.74812)
		(width 0.1651)
		(layer "In11.Cu")
		(net "P5E_PEX0_STN4_TX_DP<71>")
	)
	(segment
		(start 76.055728 -328.567796)
		(end 77.923898 -327.569322)
		(width 0.1651)
		(layer "In11.Cu")
		(net "P5E_PEX0_STN4_TX_DP<71>")
	)
	(segment
		(start 38.316916 -340.85403)
		(end 38.31717 -340.85403)
		(width 0.1651)
		(layer "In11.Cu")
		(net "P5E_PEX0_STN4_TX_DP<71>")
	)
	(segment
		(start 77.924406 -327.569068)
		(end 78.839314 -326.653906)
		(width 0.1651)
		(layer "In11.Cu")
		(net "P5E_PEX0_STN4_TX_DP<71>")
	)
	(segment
		(start 44.140628 -336.74812)
		(end 55.670704 -332.622398)
		(width 0.1651)
		(layer "In11.Cu")
		(net "P5E_PEX0_STN4_TX_DP<71>")
	)
	(segment
		(start 81.833974 -319.122552)
		(end 81.879694 -319.076832)
		(width 0.1143)
		(layer "In11.Cu")
		(net "P5E_PEX0_STN4_TX_DP<71>")
	)
	(segment
		(start 38.31717 -340.85403)
		(end 39.193216 -339.392514)
		(width 0.1651)
		(layer "In11.Cu")
		(net "P5E_PEX0_STN4_TX_DP<71>")
	)
	(segment
		(start 81.879694 -314.988702)
		(end 81.790794 -314.899802)
		(width 0.1143)
		(layer "In11.Cu")
		(net "P5E_PEX0_STN4_TX_DP<71>")
	)
	(segment
		(start 81.879694 -319.076832)
		(end 81.879694 -314.988702)
		(width 0.1143)
		(layer "In11.Cu")
		(net "P5E_PEX0_STN4_TX_DP<71>")
	)
	(segment
		(start 81.833974 -319.151)
		(end 81.833974 -319.122552)
		(width 0.1143)
		(layer "In11.Cu")
		(net "P5E_PEX0_STN4_TX_DP<71>")
	)
	(segment
		(start 78.839314 -326.653906)
		(end 79.754222 -325.738998)
		(width 0.1651)
		(layer "In11.Cu")
		(net "P5E_PEX0_STN4_TX_DP<71>")
	)
	(segment
		(start 77.923898 -327.569322)
		(end 77.924406 -327.569068)
		(width 0.1651)
		(layer "In11.Cu")
		(net "P5E_PEX0_STN4_TX_DP<71>")
	)
	(segment
		(start 37.986208 -342.439498)
		(end 38.277038 -342.148668)
		(width 0.1651)
		(layer "In11.Cu")
		(net "P5E_PEX0_STN4_TX_DP<71>")
	)
	(segment
		(start 79.754222 -325.738998)
		(end 81.833974 -322.625974)
		(width 0.1651)
		(layer "In11.Cu")
		(net "P5E_PEX0_STN4_TX_DP<71>")
	)
	(segment
		(start 38.277038 -342.148668)
		(end 38.277038 -340.920832)
		(width 0.1651)
		(layer "In11.Cu")
		(net "P5E_PEX0_STN4_TX_DP<71>")
	)
	(segment
		(start 50.716688 -345.170506)
		(end 50.716688 -344.539062)
		(width 0.13462)
		(layer "F.Cu")
		(net "P5E_PEX0_STN4_TX_C_DP<65>")
	)
	(segment
		(start 50.716688 -344.539062)
		(end 50.396648 -344.219022)
		(width 0.13462)
		(layer "F.Cu")
		(net "P5E_PEX0_STN4_TX_C_DP<65>")
	)
	(segment
		(start 50.422048 -345.465146)
		(end 50.716688 -345.170506)
		(width 0.13462)
		(layer "F.Cu")
		(net "P5E_PEX0_STN4_TX_C_DP<65>")
	)
	(segment
		(start 43.023028 -366.839246)
		(end 42.873422 -366.900968)
		(width 0.1651)
		(layer "In11.Cu")
		(net "P5E_PEX0_STN4_TX_C_DP<65>")
	)
	(segment
		(start 44.501054 -364.546388)
		(end 44.517056 -364.70717)
		(width 0.1651)
		(layer "In11.Cu")
		(net "P5E_PEX0_STN4_TX_C_DP<65>")
	)
	(segment
		(start 48.557434 -359.784142)
		(end 47.83709 -360.661966)
		(width 0.1651)
		(layer "In11.Cu")
		(net "P5E_PEX0_STN4_TX_C_DP<65>")
	)
	(segment
		(start 42.089832 -370.48186)
		(end 41.572434 -370.999258)
		(width 0.1651)
		(layer "In11.Cu")
		(net "P5E_PEX0_STN4_TX_C_DP<65>")
	)
	(segment
		(start 43.743372 -365.650018)
		(end 43.283378 -366.210342)
		(width 0.1651)
		(layer "In11.Cu")
		(net "P5E_PEX0_STN4_TX_C_DP<65>")
	)
	(segment
		(start 49.158398 -347.876622)
		(end 49.158398 -355.84765)
		(width 0.1651)
		(layer "In11.Cu")
		(net "P5E_PEX0_STN4_TX_C_DP<65>")
	)
	(segment
		(start 50.712878 -346.322142)
		(end 49.158398 -347.876622)
		(width 0.1651)
		(layer "In11.Cu")
		(net "P5E_PEX0_STN4_TX_C_DP<65>")
	)
	(segment
		(start 41.572434 -370.999258)
		(end 41.2369 -370.999258)
		(width 0.1651)
		(layer "In11.Cu")
		(net "P5E_PEX0_STN4_TX_C_DP<65>")
	)
	(segment
		(start 45.58919 -363.220508)
		(end 45.274738 -363.603794)
		(width 0.1651)
		(layer "In11.Cu")
		(net "P5E_PEX0_STN4_TX_C_DP<65>")
	)
	(segment
		(start 49.158398 -356.57155)
		(end 49.158398 -358.104694)
		(width 0.1651)
		(layer "In11.Cu")
		(net "P5E_PEX0_STN4_TX_C_DP<65>")
	)
	(segment
		(start 47.004732 -361.556046)
		(end 46.69028 -361.939332)
		(width 0.1651)
		(layer "In11.Cu")
		(net "P5E_PEX0_STN4_TX_C_DP<65>")
	)
	(segment
		(start 47.729902 -360.67238)
		(end 47.41545 -361.055666)
		(width 0.1651)
		(layer "In11.Cu")
		(net "P5E_PEX0_STN4_TX_C_DP<65>")
	)
	(segment
		(start 41.2369 -370.999258)
		(end 41.1099 -370.872258)
		(width 0.1651)
		(layer "In11.Cu")
		(net "P5E_PEX0_STN4_TX_C_DP<65>")
	)
	(segment
		(start 42.279316 -368.634772)
		(end 42.089832 -369.092226)
		(width 0.1651)
		(layer "In11.Cu")
		(net "P5E_PEX0_STN4_TX_C_DP<65>")
	)
	(segment
		(start 47.83709 -360.661966)
		(end 47.729902 -360.67238)
		(width 0.1651)
		(layer "In11.Cu")
		(net "P5E_PEX0_STN4_TX_C_DP<65>")
	)
	(segment
		(start 42.089832 -369.092226)
		(end 42.089832 -370.48186)
		(width 0.1651)
		(layer "In11.Cu")
		(net "P5E_PEX0_STN4_TX_C_DP<65>")
	)
	(segment
		(start 49.044098 -356.45725)
		(end 49.158398 -356.57155)
		(width 0.1651)
		(layer "In11.Cu")
		(net "P5E_PEX0_STN4_TX_C_DP<65>")
	)
	(segment
		(start 42.55643 -367.965736)
		(end 42.406824 -368.027458)
		(width 0.1651)
		(layer "In11.Cu")
		(net "P5E_PEX0_STN4_TX_C_DP<65>")
	)
	(segment
		(start 42.21734 -368.48542)
		(end 42.279316 -368.634772)
		(width 0.1651)
		(layer "In11.Cu")
		(net "P5E_PEX0_STN4_TX_C_DP<65>")
	)
	(segment
		(start 42.745914 -367.508282)
		(end 42.55643 -367.965736)
		(width 0.1651)
		(layer "In11.Cu")
		(net "P5E_PEX0_STN4_TX_C_DP<65>")
	)
	(segment
		(start 45.29074 -363.764576)
		(end 44.976542 -364.147354)
		(width 0.1651)
		(layer "In11.Cu")
		(net "P5E_PEX0_STN4_TX_C_DP<65>")
	)
	(segment
		(start 49.158398 -355.84765)
		(end 49.044098 -355.96195)
		(width 0.1651)
		(layer "In11.Cu")
		(net "P5E_PEX0_STN4_TX_C_DP<65>")
	)
	(segment
		(start 44.815506 -364.163102)
		(end 44.501054 -364.546388)
		(width 0.1651)
		(layer "In11.Cu")
		(net "P5E_PEX0_STN4_TX_C_DP<65>")
	)
	(segment
		(start 44.202858 -365.089948)
		(end 44.042076 -365.10595)
		(width 0.1651)
		(layer "In11.Cu")
		(net "P5E_PEX0_STN4_TX_C_DP<65>")
	)
	(segment
		(start 43.283378 -366.210342)
		(end 43.023028 -366.839246)
		(width 0.1651)
		(layer "In11.Cu")
		(net "P5E_PEX0_STN4_TX_C_DP<65>")
	)
	(segment
		(start 41.1099 -370.872258)
		(end 41.1099 -370.489988)
		(width 0.1651)
		(layer "In11.Cu")
		(net "P5E_PEX0_STN4_TX_C_DP<65>")
	)
	(segment
		(start 46.700694 -362.04652)
		(end 45.750226 -363.20476)
		(width 0.1651)
		(layer "In11.Cu")
		(net "P5E_PEX0_STN4_TX_C_DP<65>")
	)
	(segment
		(start 45.274738 -363.603794)
		(end 45.29074 -363.764576)
		(width 0.1651)
		(layer "In11.Cu")
		(net "P5E_PEX0_STN4_TX_C_DP<65>")
	)
	(segment
		(start 44.976542 -364.147354)
		(end 44.815506 -364.163102)
		(width 0.1651)
		(layer "In11.Cu")
		(net "P5E_PEX0_STN4_TX_C_DP<65>")
	)
	(segment
		(start 43.72737 -365.488982)
		(end 43.743372 -365.650018)
		(width 0.1651)
		(layer "In11.Cu")
		(net "P5E_PEX0_STN4_TX_C_DP<65>")
	)
	(segment
		(start 46.69028 -361.939332)
		(end 46.700694 -362.04652)
		(width 0.1651)
		(layer "In11.Cu")
		(net "P5E_PEX0_STN4_TX_C_DP<65>")
	)
	(segment
		(start 47.11192 -361.545632)
		(end 47.004732 -361.556046)
		(width 0.1651)
		(layer "In11.Cu")
		(net "P5E_PEX0_STN4_TX_C_DP<65>")
	)
	(segment
		(start 42.683938 -367.35893)
		(end 42.745914 -367.508282)
		(width 0.1651)
		(layer "In11.Cu")
		(net "P5E_PEX0_STN4_TX_C_DP<65>")
	)
	(segment
		(start 50.422048 -345.465146)
		(end 50.712878 -345.755976)
		(width 0.1651)
		(layer "In11.Cu")
		(net "P5E_PEX0_STN4_TX_C_DP<65>")
	)
	(segment
		(start 45.750226 -363.20476)
		(end 45.58919 -363.220508)
		(width 0.1651)
		(layer "In11.Cu")
		(net "P5E_PEX0_STN4_TX_C_DP<65>")
	)
	(segment
		(start 44.517056 -364.70717)
		(end 44.202858 -365.089948)
		(width 0.1651)
		(layer "In11.Cu")
		(net "P5E_PEX0_STN4_TX_C_DP<65>")
	)
	(segment
		(start 47.426118 -361.162854)
		(end 47.11192 -361.545632)
		(width 0.1651)
		(layer "In11.Cu")
		(net "P5E_PEX0_STN4_TX_C_DP<65>")
	)
	(segment
		(start 42.873422 -366.900968)
		(end 42.683938 -367.35893)
		(width 0.1651)
		(layer "In11.Cu")
		(net "P5E_PEX0_STN4_TX_C_DP<65>")
	)
	(segment
		(start 49.044098 -355.96195)
		(end 49.044098 -356.45725)
		(width 0.1651)
		(layer "In11.Cu")
		(net "P5E_PEX0_STN4_TX_C_DP<65>")
	)
	(segment
		(start 44.042076 -365.10595)
		(end 43.72737 -365.488982)
		(width 0.1651)
		(layer "In11.Cu")
		(net "P5E_PEX0_STN4_TX_C_DP<65>")
	)
	(segment
		(start 49.158398 -358.104694)
		(end 48.557434 -359.784142)
		(width 0.1651)
		(layer "In11.Cu")
		(net "P5E_PEX0_STN4_TX_C_DP<65>")
	)
	(segment
		(start 47.41545 -361.055666)
		(end 47.426118 -361.162854)
		(width 0.1651)
		(layer "In11.Cu")
		(net "P5E_PEX0_STN4_TX_C_DP<65>")
	)
	(segment
		(start 50.712878 -345.755976)
		(end 50.712878 -346.322142)
		(width 0.1651)
		(layer "In11.Cu")
		(net "P5E_PEX0_STN4_TX_C_DP<65>")
	)
	(segment
		(start 42.406824 -368.027458)
		(end 42.21734 -368.48542)
		(width 0.1651)
		(layer "In11.Cu")
		(net "P5E_PEX0_STN4_TX_C_DP<65>")
	)
	(segment
		(start 96.507808 -322.878958)
		(end 96.668844 -321.042284)
		(width 0.1651)
		(layer "In15.Cu")
		(net "P5E_PEX0_STN4_RX_DP<66>")
	)
	(segment
		(start 50.704242 -353.10826)
		(end 51.751992 -352.674174)
		(width 0.1651)
		(layer "In15.Cu")
		(net "P5E_PEX0_STN4_RX_DP<66>")
	)
	(segment
		(start 44.577762 -363.452156)
		(end 48.876966 -358.708706)
		(width 0.1651)
		(layer "In15.Cu")
		(net "P5E_PEX0_STN4_RX_DP<66>")
	)
	(segment
		(start 48.876966 -358.708706)
		(end 49.158398 -357.979218)
		(width 0.1651)
		(layer "In15.Cu")
		(net "P5E_PEX0_STN4_RX_DP<66>")
	)
	(segment
		(start 51.752246 -352.674174)
		(end 52.024534 -352.401632)
		(width 0.1651)
		(layer "In15.Cu")
		(net "P5E_PEX0_STN4_RX_DP<66>")
	)
	(segment
		(start 81.879694 -306.643532)
		(end 81.879694 -306.438808)
		(width 0.1143)
		(layer "In15.Cu")
		(net "P5E_PEX0_STN4_RX_DP<66>")
	)
	(segment
		(start 81.879694 -306.438808)
		(end 81.790794 -306.349908)
		(width 0.1143)
		(layer "In15.Cu")
		(net "P5E_PEX0_STN4_RX_DP<66>")
	)
	(segment
		(start 41.694354 -366.63376)
		(end 41.68648 -366.472216)
		(width 0.1651)
		(layer "In15.Cu")
		(net "P5E_PEX0_STN4_RX_DP<66>")
	)
	(segment
		(start 42.495978 -365.749078)
		(end 42.488104 -365.587534)
		(width 0.1651)
		(layer "In15.Cu")
		(net "P5E_PEX0_STN4_RX_DP<66>")
	)
	(segment
		(start 41.68648 -366.472216)
		(end 42.010838 -366.11433)
		(width 0.1651)
		(layer "In15.Cu")
		(net "P5E_PEX0_STN4_RX_DP<66>")
	)
	(segment
		(start 83.6168 -306.965858)
		(end 83.57108 -306.920138)
		(width 0.1143)
		(layer "In15.Cu")
		(net "P5E_PEX0_STN4_RX_DP<66>")
	)
	(segment
		(start 81.790794 -306.349908)
		(end 81.499964 -306.349908)
		(width 0.1143)
		(layer "In15.Cu")
		(net "P5E_PEX0_STN4_RX_DP<66>")
	)
	(segment
		(start 51.751992 -352.674174)
		(end 51.752246 -352.674174)
		(width 0.1651)
		(layer "In15.Cu")
		(net "P5E_PEX0_STN4_RX_DP<66>")
	)
	(segment
		(start 96.668844 -321.042284)
		(end 96.669098 -321.042538)
		(width 0.1651)
		(layer "In15.Cu")
		(net "P5E_PEX0_STN4_RX_DP<66>")
	)
	(segment
		(start 83.645248 -306.965858)
		(end 83.6168 -306.965858)
		(width 0.1143)
		(layer "In15.Cu")
		(net "P5E_PEX0_STN4_RX_DP<66>")
	)
	(segment
		(start 88.154256 -308.200298)
		(end 87.728552 -307.97246)
		(width 0.1651)
		(layer "In15.Cu")
		(net "P5E_PEX0_STN4_RX_DP<66>")
	)
	(segment
		(start 49.158398 -357.979218)
		(end 49.158398 -354.119942)
		(width 0.1651)
		(layer "In15.Cu")
		(net "P5E_PEX0_STN4_RX_DP<66>")
	)
	(segment
		(start 39.785036 -379.384814)
		(end 39.785036 -369.268248)
		(width 0.1651)
		(layer "In15.Cu")
		(net "P5E_PEX0_STN4_RX_DP<66>")
	)
	(segment
		(start 52.024534 -352.401632)
		(end 58.207402 -340.833964)
		(width 0.1651)
		(layer "In15.Cu")
		(net "P5E_PEX0_STN4_RX_DP<66>")
	)
	(segment
		(start 42.812462 -365.229648)
		(end 42.974006 -365.221774)
		(width 0.1651)
		(layer "In15.Cu")
		(net "P5E_PEX0_STN4_RX_DP<66>")
	)
	(segment
		(start 44.415964 -363.460284)
		(end 44.577508 -363.45241)
		(width 0.1651)
		(layer "In15.Cu")
		(net "P5E_PEX0_STN4_RX_DP<66>")
	)
	(segment
		(start 44.09948 -363.979714)
		(end 44.091606 -363.81817)
		(width 0.1651)
		(layer "In15.Cu")
		(net "P5E_PEX0_STN4_RX_DP<66>")
	)
	(segment
		(start 43.289982 -364.702852)
		(end 43.61434 -364.344966)
		(width 0.1651)
		(layer "In15.Cu")
		(net "P5E_PEX0_STN4_RX_DP<66>")
	)
	(segment
		(start 94.92361 -325.801228)
		(end 95.661988 -324.921118)
		(width 0.1651)
		(layer "In15.Cu")
		(net "P5E_PEX0_STN4_RX_DP<66>")
	)
	(segment
		(start 49.158398 -354.119942)
		(end 49.424082 -353.478338)
		(width 0.1651)
		(layer "In15.Cu")
		(net "P5E_PEX0_STN4_RX_DP<66>")
	)
	(segment
		(start 43.61434 -364.344966)
		(end 43.775884 -364.337092)
		(width 0.1651)
		(layer "In15.Cu")
		(net "P5E_PEX0_STN4_RX_DP<66>")
	)
	(segment
		(start 39.785036 -369.268248)
		(end 40.139366 -368.349276)
		(width 0.1651)
		(layer "In15.Cu")
		(net "P5E_PEX0_STN4_RX_DP<66>")
	)
	(segment
		(start 87.728552 -307.97246)
		(end 87.681562 -307.817774)
		(width 0.1651)
		(layer "In15.Cu")
		(net "P5E_PEX0_STN4_RX_DP<66>")
	)
	(segment
		(start 88.947244 -308.49443)
		(end 88.309196 -308.153308)
		(width 0.1651)
		(layer "In15.Cu")
		(net "P5E_PEX0_STN4_RX_DP<66>")
	)
	(segment
		(start 88.309196 -308.153308)
		(end 88.308942 -308.153308)
		(width 0.1651)
		(layer "In15.Cu")
		(net "P5E_PEX0_STN4_RX_DP<66>")
	)
	(segment
		(start 41.6941 -366.63376)
		(end 41.694354 -366.63376)
		(width 0.1651)
		(layer "In15.Cu")
		(net "P5E_PEX0_STN4_RX_DP<66>")
	)
	(segment
		(start 64.406272 -337.365848)
		(end 79.391002 -332.82001)
		(width 0.1651)
		(layer "In15.Cu")
		(net "P5E_PEX0_STN4_RX_DP<66>")
	)
	(segment
		(start 95.661988 -324.921118)
		(end 96.507808 -322.878958)
		(width 0.1651)
		(layer "In15.Cu")
		(net "P5E_PEX0_STN4_RX_DP<66>")
	)
	(segment
		(start 79.391002 -332.82001)
		(end 93.091 -327.145142)
		(width 0.1651)
		(layer "In15.Cu")
		(net "P5E_PEX0_STN4_RX_DP<66>")
	)
	(segment
		(start 82.1563 -306.920138)
		(end 81.879694 -306.643532)
		(width 0.1143)
		(layer "In15.Cu")
		(net "P5E_PEX0_STN4_RX_DP<66>")
	)
	(segment
		(start 49.79416 -353.10826)
		(end 50.704242 -353.10826)
		(width 0.1651)
		(layer "In15.Cu")
		(net "P5E_PEX0_STN4_RX_DP<66>")
	)
	(segment
		(start 40.139366 -368.349276)
		(end 41.6941 -366.63376)
		(width 0.1651)
		(layer "In15.Cu")
		(net "P5E_PEX0_STN4_RX_DP<66>")
	)
	(segment
		(start 93.091 -327.145142)
		(end 94.92361 -325.801228)
		(width 0.1651)
		(layer "In15.Cu")
		(net "P5E_PEX0_STN4_RX_DP<66>")
	)
	(segment
		(start 83.57108 -306.920138)
		(end 82.1563 -306.920138)
		(width 0.1143)
		(layer "In15.Cu")
		(net "P5E_PEX0_STN4_RX_DP<66>")
	)
	(segment
		(start 44.091606 -363.81817)
		(end 44.415964 -363.460284)
		(width 0.1651)
		(layer "In15.Cu")
		(net "P5E_PEX0_STN4_RX_DP<66>")
	)
	(segment
		(start 43.297856 -364.864396)
		(end 43.289982 -364.702852)
		(width 0.1651)
		(layer "In15.Cu")
		(net "P5E_PEX0_STN4_RX_DP<66>")
	)
	(segment
		(start 42.172128 -366.106456)
		(end 42.495978 -365.749078)
		(width 0.1651)
		(layer "In15.Cu")
		(net "P5E_PEX0_STN4_RX_DP<66>")
	)
	(segment
		(start 49.424082 -353.478338)
		(end 49.79416 -353.10826)
		(width 0.1651)
		(layer "In15.Cu")
		(net "P5E_PEX0_STN4_RX_DP<66>")
	)
	(segment
		(start 95.496634 -315.98743)
		(end 93.596714 -313.1439)
		(width 0.1651)
		(layer "In15.Cu")
		(net "P5E_PEX0_STN4_RX_DP<66>")
	)
	(segment
		(start 42.488104 -365.587534)
		(end 42.812462 -365.229648)
		(width 0.1651)
		(layer "In15.Cu")
		(net "P5E_PEX0_STN4_RX_DP<66>")
	)
	(segment
		(start 39.270686 -379.899164)
		(end 39.785036 -379.384814)
		(width 0.1651)
		(layer "In15.Cu")
		(net "P5E_PEX0_STN4_RX_DP<66>")
	)
	(segment
		(start 39.037006 -379.899164)
		(end 39.270686 -379.899164)
		(width 0.1651)
		(layer "In15.Cu")
		(net "P5E_PEX0_STN4_RX_DP<66>")
	)
	(segment
		(start 44.577508 -363.45241)
		(end 44.577762 -363.452156)
		(width 0.1651)
		(layer "In15.Cu")
		(net "P5E_PEX0_STN4_RX_DP<66>")
	)
	(segment
		(start 38.910006 -379.772164)
		(end 39.037006 -379.899164)
		(width 0.1651)
		(layer "In15.Cu")
		(net "P5E_PEX0_STN4_RX_DP<66>")
	)
	(segment
		(start 96.669098 -321.042538)
		(end 96.82988 -319.205864)
		(width 0.1651)
		(layer "In15.Cu")
		(net "P5E_PEX0_STN4_RX_DP<66>")
	)
	(segment
		(start 42.974006 -365.221774)
		(end 43.297856 -364.864396)
		(width 0.1651)
		(layer "In15.Cu")
		(net "P5E_PEX0_STN4_RX_DP<66>")
	)
	(segment
		(start 59.745118 -339.296502)
		(end 64.406272 -337.365848)
		(width 0.1651)
		(layer "In15.Cu")
		(net "P5E_PEX0_STN4_RX_DP<66>")
	)
	(segment
		(start 86.087966 -306.965858)
		(end 83.645248 -306.965858)
		(width 0.1651)
		(layer "In15.Cu")
		(net "P5E_PEX0_STN4_RX_DP<66>")
	)
	(segment
		(start 96.82988 -319.205864)
		(end 95.496634 -315.98743)
		(width 0.1651)
		(layer "In15.Cu")
		(net "P5E_PEX0_STN4_RX_DP<66>")
	)
	(segment
		(start 38.910006 -379.390148)
		(end 38.910006 -379.772164)
		(width 0.1651)
		(layer "In15.Cu")
		(net "P5E_PEX0_STN4_RX_DP<66>")
	)
	(segment
		(start 93.596714 -313.1439)
		(end 88.947244 -308.49443)
		(width 0.1651)
		(layer "In15.Cu")
		(net "P5E_PEX0_STN4_RX_DP<66>")
	)
	(segment
		(start 58.207402 -340.833964)
		(end 59.745118 -339.296502)
		(width 0.1651)
		(layer "In15.Cu")
		(net "P5E_PEX0_STN4_RX_DP<66>")
	)
	(segment
		(start 42.010838 -366.11433)
		(end 42.172128 -366.106456)
		(width 0.1651)
		(layer "In15.Cu")
		(net "P5E_PEX0_STN4_RX_DP<66>")
	)
	(segment
		(start 88.308942 -308.153308)
		(end 88.154256 -308.200298)
		(width 0.1651)
		(layer "In15.Cu")
		(net "P5E_PEX0_STN4_RX_DP<66>")
	)
	(segment
		(start 87.681562 -307.817774)
		(end 86.087966 -306.965858)
		(width 0.1651)
		(layer "In15.Cu")
		(net "P5E_PEX0_STN4_RX_DP<66>")
	)
	(segment
		(start 43.775884 -364.337092)
		(end 43.77563 -364.337092)
		(width 0.1651)
		(layer "In15.Cu")
		(net "P5E_PEX0_STN4_RX_DP<66>")
	)
	(segment
		(start 43.77563 -364.337092)
		(end 44.09948 -363.979714)
		(width 0.1651)
		(layer "In15.Cu")
		(net "P5E_PEX0_STN4_RX_DP<66>")
	)
	(segment
		(start 51.481736 -359.744264)
		(end 52.507134 -358.20985)
		(width 0.1651)
		(layer "In15.Cu")
		(net "P5E_PEX0_STN4_RX_DN<65>")
	)
	(segment
		(start 80.758284 -333.710026)
		(end 93.369384 -328.486516)
		(width 0.1651)
		(layer "In15.Cu")
		(net "P5E_PEX0_STN4_RX_DN<65>")
	)
	(segment
		(start 86.569042 -305.815746)
		(end 86.37143 -305.733958)
		(width 0.1651)
		(layer "In15.Cu")
		(net "P5E_PEX0_STN4_RX_DN<65>")
	)
	(segment
		(start 96.736154 -325.587106)
		(end 97.736914 -323.171312)
		(width 0.1651)
		(layer "In15.Cu")
		(net "P5E_PEX0_STN4_RX_DN<65>")
	)
	(segment
		(start 95.79864 -326.705214)
		(end 96.736154 -325.587106)
		(width 0.1651)
		(layer "In15.Cu")
		(net "P5E_PEX0_STN4_RX_DN<65>")
	)
	(segment
		(start 41.2369 -379.08103)
		(end 41.575228 -379.08103)
		(width 0.1651)
		(layer "In15.Cu")
		(net "P5E_PEX0_STN4_RX_DN<65>")
	)
	(segment
		(start 83.6168 -305.733958)
		(end 83.57108 -305.779678)
		(width 0.1143)
		(layer "In15.Cu")
		(net "P5E_PEX0_STN4_RX_DN<65>")
	)
	(segment
		(start 42.267632 -378.388626)
		(end 42.267632 -369.532662)
		(width 0.1651)
		(layer "In15.Cu")
		(net "P5E_PEX0_STN4_RX_DN<65>")
	)
	(segment
		(start 94.622874 -312.410094)
		(end 89.704164 -307.49113)
		(width 0.1651)
		(layer "In15.Cu")
		(net "P5E_PEX0_STN4_RX_DN<65>")
	)
	(segment
		(start 80.17002 -305.614578)
		(end 80.17002 -305.488848)
		(width 0.1143)
		(layer "In15.Cu")
		(net "P5E_PEX0_STN4_RX_DN<65>")
	)
	(segment
		(start 42.267632 -369.532662)
		(end 42.673778 -368.552222)
		(width 0.1651)
		(layer "In15.Cu")
		(net "P5E_PEX0_STN4_RX_DN<65>")
	)
	(segment
		(start 86.37143 -305.733958)
		(end 83.645248 -305.733958)
		(width 0.1651)
		(layer "In15.Cu")
		(net "P5E_PEX0_STN4_RX_DN<65>")
	)
	(segment
		(start 96.776032 -315.632592)
		(end 94.622874 -312.410094)
		(width 0.1651)
		(layer "In15.Cu")
		(net "P5E_PEX0_STN4_RX_DN<65>")
	)
	(segment
		(start 59.510676 -341.30107)
		(end 60.473844 -340.337902)
		(width 0.1651)
		(layer "In15.Cu")
		(net "P5E_PEX0_STN4_RX_DN<65>")
	)
	(segment
		(start 80.33512 -305.779678)
		(end 80.17002 -305.614578)
		(width 0.1143)
		(layer "In15.Cu")
		(net "P5E_PEX0_STN4_RX_DN<65>")
	)
	(segment
		(start 41.1099 -379.590046)
		(end 41.1099 -379.20803)
		(width 0.1651)
		(layer "In15.Cu")
		(net "P5E_PEX0_STN4_RX_DN<65>")
	)
	(segment
		(start 60.473844 -340.337902)
		(end 64.757554 -338.563712)
		(width 0.1651)
		(layer "In15.Cu")
		(net "P5E_PEX0_STN4_RX_DN<65>")
	)
	(segment
		(start 41.1099 -379.20803)
		(end 41.2369 -379.08103)
		(width 0.1651)
		(layer "In15.Cu")
		(net "P5E_PEX0_STN4_RX_DN<65>")
	)
	(segment
		(start 42.673778 -368.552222)
		(end 51.481736 -359.744264)
		(width 0.1651)
		(layer "In15.Cu")
		(net "P5E_PEX0_STN4_RX_DN<65>")
	)
	(segment
		(start 93.369384 -328.486516)
		(end 95.79864 -326.705214)
		(width 0.1651)
		(layer "In15.Cu")
		(net "P5E_PEX0_STN4_RX_DN<65>")
	)
	(segment
		(start 80.25892 -305.399948)
		(end 80.54975 -305.399948)
		(width 0.1143)
		(layer "In15.Cu")
		(net "P5E_PEX0_STN4_RX_DN<65>")
	)
	(segment
		(start 97.736914 -323.171312)
		(end 98.114358 -318.862964)
		(width 0.1651)
		(layer "In15.Cu")
		(net "P5E_PEX0_STN4_RX_DN<65>")
	)
	(segment
		(start 98.114358 -318.862964)
		(end 96.776032 -315.632592)
		(width 0.1651)
		(layer "In15.Cu")
		(net "P5E_PEX0_STN4_RX_DN<65>")
	)
	(segment
		(start 52.507134 -358.20985)
		(end 59.510676 -341.30107)
		(width 0.1651)
		(layer "In15.Cu")
		(net "P5E_PEX0_STN4_RX_DN<65>")
	)
	(segment
		(start 41.575228 -379.08103)
		(end 42.267632 -378.388626)
		(width 0.1651)
		(layer "In15.Cu")
		(net "P5E_PEX0_STN4_RX_DN<65>")
	)
	(segment
		(start 80.17002 -305.488848)
		(end 80.25892 -305.399948)
		(width 0.1143)
		(layer "In15.Cu")
		(net "P5E_PEX0_STN4_RX_DN<65>")
	)
	(segment
		(start 89.704164 -307.49113)
		(end 86.569042 -305.815746)
		(width 0.1651)
		(layer "In15.Cu")
		(net "P5E_PEX0_STN4_RX_DN<65>")
	)
	(segment
		(start 64.757554 -338.563712)
		(end 80.758284 -333.710026)
		(width 0.1651)
		(layer "In15.Cu")
		(net "P5E_PEX0_STN4_RX_DN<65>")
	)
	(segment
		(start 83.645248 -305.733958)
		(end 83.6168 -305.733958)
		(width 0.1143)
		(layer "In15.Cu")
		(net "P5E_PEX0_STN4_RX_DN<65>")
	)
	(segment
		(start 83.57108 -305.779678)
		(end 80.33512 -305.779678)
		(width 0.1143)
		(layer "In15.Cu")
		(net "P5E_PEX0_STN4_RX_DN<65>")
	)
	(segment
		(start 26.119328 -343.365582)
		(end 26.119328 -342.734138)
		(width 0.13462)
		(layer "F.Cu")
		(net "P5E_PEX0_STN4_TX_DN<77>")
	)
	(segment
		(start 26.119328 -342.734138)
		(end 26.413968 -342.439498)
		(width 0.13462)
		(layer "F.Cu")
		(net "P5E_PEX0_STN4_TX_DN<77>")
	)
	(segment
		(start 26.439368 -343.685622)
		(end 26.119328 -343.365582)
		(width 0.13462)
		(layer "F.Cu")
		(net "P5E_PEX0_STN4_TX_DN<77>")
	)
	(segment
		(start 74.64933 -322.713096)
		(end 74.879708 -322.482718)
		(width 0.1651)
		(layer "In11.Cu")
		(net "P5E_PEX0_STN4_TX_DN<77>")
	)
	(segment
		(start 75.42022 -320.219832)
		(end 75.42022 -311.835292)
		(width 0.1143)
		(layer "In11.Cu")
		(net "P5E_PEX0_STN4_TX_DN<77>")
	)
	(segment
		(start 26.771854 -339.343746)
		(end 40.975788 -331.751686)
		(width 0.1651)
		(layer "In11.Cu")
		(net "P5E_PEX0_STN4_TX_DN<77>")
	)
	(segment
		(start 75.71105 -311.670192)
		(end 75.79995 -311.759092)
		(width 0.1143)
		(layer "In11.Cu")
		(net "P5E_PEX0_STN4_TX_DN<77>")
	)
	(segment
		(start 75.46594 -320.294)
		(end 75.46594 -320.265552)
		(width 0.1143)
		(layer "In11.Cu")
		(net "P5E_PEX0_STN4_TX_DN<77>")
	)
	(segment
		(start 75.58532 -311.670192)
		(end 75.71105 -311.670192)
		(width 0.1143)
		(layer "In11.Cu")
		(net "P5E_PEX0_STN4_TX_DN<77>")
	)
	(segment
		(start 40.975788 -331.751686)
		(end 52.996338 -327.450704)
		(width 0.1651)
		(layer "In11.Cu")
		(net "P5E_PEX0_STN4_TX_DN<77>")
	)
	(segment
		(start 26.123138 -342.148668)
		(end 26.123138 -339.992462)
		(width 0.1651)
		(layer "In11.Cu")
		(net "P5E_PEX0_STN4_TX_DN<77>")
	)
	(segment
		(start 74.879708 -322.482718)
		(end 75.46594 -321.067176)
		(width 0.1651)
		(layer "In11.Cu")
		(net "P5E_PEX0_STN4_TX_DN<77>")
	)
	(segment
		(start 73.36536 -323.399404)
		(end 74.64933 -322.713096)
		(width 0.1651)
		(layer "In11.Cu")
		(net "P5E_PEX0_STN4_TX_DN<77>")
	)
	(segment
		(start 75.46594 -320.265552)
		(end 75.42022 -320.219832)
		(width 0.1143)
		(layer "In11.Cu")
		(net "P5E_PEX0_STN4_TX_DN<77>")
	)
	(segment
		(start 75.46594 -321.067176)
		(end 75.46594 -320.294)
		(width 0.1651)
		(layer "In11.Cu")
		(net "P5E_PEX0_STN4_TX_DN<77>")
	)
	(segment
		(start 52.996338 -327.450704)
		(end 73.36536 -323.399404)
		(width 0.1651)
		(layer "In11.Cu")
		(net "P5E_PEX0_STN4_TX_DN<77>")
	)
	(segment
		(start 75.42022 -311.835292)
		(end 75.58532 -311.670192)
		(width 0.1143)
		(layer "In11.Cu")
		(net "P5E_PEX0_STN4_TX_DN<77>")
	)
	(segment
		(start 26.413968 -342.439498)
		(end 26.123138 -342.148668)
		(width 0.1651)
		(layer "In11.Cu")
		(net "P5E_PEX0_STN4_TX_DN<77>")
	)
	(segment
		(start 26.123138 -339.992462)
		(end 26.771854 -339.343746)
		(width 0.1651)
		(layer "In11.Cu")
		(net "P5E_PEX0_STN4_TX_DN<77>")
	)
	(segment
		(start 75.79995 -311.759092)
		(end 75.79995 -312.049922)
		(width 0.1143)
		(layer "In11.Cu")
		(net "P5E_PEX0_STN4_TX_DN<77>")
	)
	(segment
		(start 97.566734 -326.10933)
		(end 98.688652 -323.401182)
		(width 0.1651)
		(layer "In15.Cu")
		(net "P5E_PEX0_STN4_RX_DN<64>")
	)
	(segment
		(start 98.688652 -323.401182)
		(end 99.099878 -318.703198)
		(width 0.1651)
		(layer "In15.Cu")
		(net "P5E_PEX0_STN4_RX_DN<64>")
	)
	(segment
		(start 43.310048 -380.69012)
		(end 43.310048 -380.308104)
		(width 0.1651)
		(layer "In15.Cu")
		(net "P5E_PEX0_STN4_RX_DN<64>")
	)
	(segment
		(start 96.484694 -327.399396)
		(end 97.566734 -326.10933)
		(width 0.1651)
		(layer "In15.Cu")
		(net "P5E_PEX0_STN4_RX_DN<64>")
	)
	(segment
		(start 95.411544 -311.802018)
		(end 90.33891 -306.72913)
		(width 0.1651)
		(layer "In15.Cu")
		(net "P5E_PEX0_STN4_RX_DN<64>")
	)
	(segment
		(start 43.787568 -380.181104)
		(end 44.45889 -379.509782)
		(width 0.1651)
		(layer "In15.Cu")
		(net "P5E_PEX0_STN4_RX_DN<64>")
	)
	(segment
		(start 86.622128 -304.783744)
		(end 83.645248 -304.783744)
		(width 0.1651)
		(layer "In15.Cu")
		(net "P5E_PEX0_STN4_RX_DN<64>")
	)
	(segment
		(start 44.93006 -368.40414)
		(end 48.86071 -364.473744)
		(width 0.1651)
		(layer "In15.Cu")
		(net "P5E_PEX0_STN4_RX_DN<64>")
	)
	(segment
		(start 61.0362 -341.1474)
		(end 64.977772 -339.514688)
		(width 0.1651)
		(layer "In15.Cu")
		(net "P5E_PEX0_STN4_RX_DN<64>")
	)
	(segment
		(start 44.45889 -369.541552)
		(end 44.93006 -368.40414)
		(width 0.1651)
		(layer "In15.Cu")
		(net "P5E_PEX0_STN4_RX_DN<64>")
	)
	(segment
		(start 43.437048 -380.181104)
		(end 43.787568 -380.181104)
		(width 0.1651)
		(layer "In15.Cu")
		(net "P5E_PEX0_STN4_RX_DN<64>")
	)
	(segment
		(start 99.099878 -318.703198)
		(end 97.593912 -315.06795)
		(width 0.1651)
		(layer "In15.Cu")
		(net "P5E_PEX0_STN4_RX_DN<64>")
	)
	(segment
		(start 93.76537 -329.393042)
		(end 96.484694 -327.399396)
		(width 0.1651)
		(layer "In15.Cu")
		(net "P5E_PEX0_STN4_RX_DN<64>")
	)
	(segment
		(start 90.33891 -306.72913)
		(end 86.963758 -304.925222)
		(width 0.1651)
		(layer "In15.Cu")
		(net "P5E_PEX0_STN4_RX_DN<64>")
	)
	(segment
		(start 52.301648 -360.280458)
		(end 53.508148 -358.475026)
		(width 0.1651)
		(layer "In15.Cu")
		(net "P5E_PEX0_STN4_RX_DN<64>")
	)
	(segment
		(start 60.437776 -341.745824)
		(end 61.0362 -341.1474)
		(width 0.1651)
		(layer "In15.Cu")
		(net "P5E_PEX0_STN4_RX_DN<64>")
	)
	(segment
		(start 82.070194 -304.664364)
		(end 82.070194 -304.538634)
		(width 0.1143)
		(layer "In15.Cu")
		(net "P5E_PEX0_STN4_RX_DN<64>")
	)
	(segment
		(start 64.977772 -339.514688)
		(end 81.237582 -334.582262)
		(width 0.1651)
		(layer "In15.Cu")
		(net "P5E_PEX0_STN4_RX_DN<64>")
	)
	(segment
		(start 44.45889 -379.509782)
		(end 44.45889 -369.541552)
		(width 0.1651)
		(layer "In15.Cu")
		(net "P5E_PEX0_STN4_RX_DN<64>")
	)
	(segment
		(start 86.963758 -304.925222)
		(end 86.622128 -304.783744)
		(width 0.1651)
		(layer "In15.Cu")
		(net "P5E_PEX0_STN4_RX_DN<64>")
	)
	(segment
		(start 82.159094 -304.449734)
		(end 82.449924 -304.449734)
		(width 0.1143)
		(layer "In15.Cu")
		(net "P5E_PEX0_STN4_RX_DN<64>")
	)
	(segment
		(start 83.57108 -304.829464)
		(end 82.235294 -304.829464)
		(width 0.1143)
		(layer "In15.Cu")
		(net "P5E_PEX0_STN4_RX_DN<64>")
	)
	(segment
		(start 43.310048 -380.308104)
		(end 43.437048 -380.181104)
		(width 0.1651)
		(layer "In15.Cu")
		(net "P5E_PEX0_STN4_RX_DN<64>")
	)
	(segment
		(start 83.645248 -304.783744)
		(end 83.6168 -304.783744)
		(width 0.1143)
		(layer "In15.Cu")
		(net "P5E_PEX0_STN4_RX_DN<64>")
	)
	(segment
		(start 83.6168 -304.783744)
		(end 83.57108 -304.829464)
		(width 0.1143)
		(layer "In15.Cu")
		(net "P5E_PEX0_STN4_RX_DN<64>")
	)
	(segment
		(start 97.593912 -315.06795)
		(end 95.411544 -311.802018)
		(width 0.1651)
		(layer "In15.Cu")
		(net "P5E_PEX0_STN4_RX_DN<64>")
	)
	(segment
		(start 48.86071 -364.473744)
		(end 52.301648 -360.280458)
		(width 0.1651)
		(layer "In15.Cu")
		(net "P5E_PEX0_STN4_RX_DN<64>")
	)
	(segment
		(start 82.235294 -304.829464)
		(end 82.070194 -304.664364)
		(width 0.1143)
		(layer "In15.Cu")
		(net "P5E_PEX0_STN4_RX_DN<64>")
	)
	(segment
		(start 82.070194 -304.538634)
		(end 82.159094 -304.449734)
		(width 0.1143)
		(layer "In15.Cu")
		(net "P5E_PEX0_STN4_RX_DN<64>")
	)
	(segment
		(start 53.508148 -358.475026)
		(end 60.437776 -341.745824)
		(width 0.1651)
		(layer "In15.Cu")
		(net "P5E_PEX0_STN4_RX_DN<64>")
	)
	(segment
		(start 81.237582 -334.582262)
		(end 93.76537 -329.393042)
		(width 0.1651)
		(layer "In15.Cu")
		(net "P5E_PEX0_STN4_RX_DN<64>")
	)
	(segment
		(start 364.132368 -222.32493)
		(end 363.282738 -222.32493)
		(width 0.13208)
		(layer "F.Cu")
		(net "SPI_PEX3_SDIO0_MUX_R")
	)
	(segment
		(start 364.500922 -222.172276)
		(end 364.132368 -222.32493)
		(width 0.13208)
		(layer "F.Cu")
		(net "SPI_PEX3_SDIO0_MUX_R")
	)
	(via
		(at 364.500922 -222.172276)
		(size 0.508)
		(drill 0.254)
		(layers "F.Cu" "B.Cu")
		(net "SPI_PEX3_SDIO0_MUX_R")
	)
	(segment
		(start 367.538762 -221.92361)
		(end 366.79505 -221.179898)
		(width 0.13208)
		(layer "B.Cu")
		(net "SPI_PEX3_SDIO0_MUX_R")
	)
	(segment
		(start 365.4933 -221.179898)
		(end 364.500922 -222.172276)
		(width 0.13208)
		(layer "B.Cu")
		(net "SPI_PEX3_SDIO0_MUX_R")
	)
	(segment
		(start 367.538762 -222.214186)
		(end 367.538762 -221.92361)
		(width 0.13208)
		(layer "B.Cu")
		(net "SPI_PEX3_SDIO0_MUX_R")
	)
	(segment
		(start 366.79505 -221.179898)
		(end 365.4933 -221.179898)
		(width 0.13208)
		(layer "B.Cu")
		(net "SPI_PEX3_SDIO0_MUX_R")
	)
	(segment
		(start 34.877248 -351.611438)
		(end 35.171888 -351.316798)
		(width 0.13462)
		(layer "F.Cu")
		(net "P5E_PEX0_STN4_TX_C_DP<72>")
	)
	(segment
		(start 35.171888 -351.316798)
		(end 35.171888 -350.685354)
		(width 0.13462)
		(layer "F.Cu")
		(net "P5E_PEX0_STN4_TX_C_DP<72>")
	)
	(segment
		(start 35.171888 -350.685354)
		(end 34.851848 -350.365314)
		(width 0.13462)
		(layer "F.Cu")
		(net "P5E_PEX0_STN4_TX_C_DP<72>")
	)
	(segment
		(start 35.168078 -351.902268)
		(end 34.877248 -351.611438)
		(width 0.1651)
		(layer "In11.Cu")
		(net "P5E_PEX0_STN4_TX_C_DP<72>")
	)
	(segment
		(start 43.437048 -398.09928)
		(end 43.860466 -398.09928)
		(width 0.1651)
		(layer "In11.Cu")
		(net "P5E_PEX0_STN4_TX_C_DP<72>")
	)
	(segment
		(start 27.046428 -385.262882)
		(end 26.399236 -383.70002)
		(width 0.1651)
		(layer "In11.Cu")
		(net "P5E_PEX0_STN4_TX_C_DP<72>")
	)
	(segment
		(start 44.20235 -395.603222)
		(end 43.82389 -394.690346)
		(width 0.1651)
		(layer "In11.Cu")
		(net "P5E_PEX0_STN4_TX_C_DP<72>")
	)
	(segment
		(start 41.44899 -393.20724)
		(end 41.424606 -393.08405)
		(width 0.1651)
		(layer "In11.Cu")
		(net "P5E_PEX0_STN4_TX_C_DP<72>")
	)
	(segment
		(start 43.310048 -397.97228)
		(end 43.437048 -398.09928)
		(width 0.1651)
		(layer "In11.Cu")
		(net "P5E_PEX0_STN4_TX_C_DP<72>")
	)
	(segment
		(start 27.696668 -385.913122)
		(end 27.046428 -385.262882)
		(width 0.1651)
		(layer "In11.Cu")
		(net "P5E_PEX0_STN4_TX_C_DP<72>")
	)
	(segment
		(start 26.399236 -383.70002)
		(end 26.399236 -381.658114)
		(width 0.1651)
		(layer "In11.Cu")
		(net "P5E_PEX0_STN4_TX_C_DP<72>")
	)
	(segment
		(start 43.860466 -398.09928)
		(end 44.20235 -397.757396)
		(width 0.1651)
		(layer "In11.Cu")
		(net "P5E_PEX0_STN4_TX_C_DP<72>")
	)
	(segment
		(start 40.453564 -392.43381)
		(end 35.606736 -389.18896)
		(width 0.1651)
		(layer "In11.Cu")
		(net "P5E_PEX0_STN4_TX_C_DP<72>")
	)
	(segment
		(start 33.613598 -358.673654)
		(end 33.613598 -353.975162)
		(width 0.1651)
		(layer "In11.Cu")
		(net "P5E_PEX0_STN4_TX_C_DP<72>")
	)
	(segment
		(start 41.424606 -393.08405)
		(end 41.013126 -392.808714)
		(width 0.1651)
		(layer "In11.Cu")
		(net "P5E_PEX0_STN4_TX_C_DP<72>")
	)
	(segment
		(start 26.592784 -369.67541)
		(end 26.882598 -368.746786)
		(width 0.1651)
		(layer "In11.Cu")
		(net "P5E_PEX0_STN4_TX_C_DP<72>")
	)
	(segment
		(start 40.889936 -392.833098)
		(end 40.477948 -392.557254)
		(width 0.1651)
		(layer "In11.Cu")
		(net "P5E_PEX0_STN4_TX_C_DP<72>")
	)
	(segment
		(start 26.399236 -381.658114)
		(end 26.592784 -369.67541)
		(width 0.1651)
		(layer "In11.Cu")
		(net "P5E_PEX0_STN4_TX_C_DP<72>")
	)
	(segment
		(start 26.882598 -368.746786)
		(end 33.613598 -358.673654)
		(width 0.1651)
		(layer "In11.Cu")
		(net "P5E_PEX0_STN4_TX_C_DP<72>")
	)
	(segment
		(start 44.20235 -397.757396)
		(end 44.20235 -395.603222)
		(width 0.1651)
		(layer "In11.Cu")
		(net "P5E_PEX0_STN4_TX_C_DP<72>")
	)
	(segment
		(start 40.477948 -392.557254)
		(end 40.453564 -392.43381)
		(width 0.1651)
		(layer "In11.Cu")
		(net "P5E_PEX0_STN4_TX_C_DP<72>")
	)
	(segment
		(start 41.013126 -392.808714)
		(end 40.889936 -392.833098)
		(width 0.1651)
		(layer "In11.Cu")
		(net "P5E_PEX0_STN4_TX_C_DP<72>")
	)
	(segment
		(start 33.613598 -353.975162)
		(end 35.168078 -352.420682)
		(width 0.1651)
		(layer "In11.Cu")
		(net "P5E_PEX0_STN4_TX_C_DP<72>")
	)
	(segment
		(start 41.984168 -393.4587)
		(end 41.860978 -393.483084)
		(width 0.1651)
		(layer "In11.Cu")
		(net "P5E_PEX0_STN4_TX_C_DP<72>")
	)
	(segment
		(start 35.606736 -389.18896)
		(end 27.696668 -385.913122)
		(width 0.1651)
		(layer "In11.Cu")
		(net "P5E_PEX0_STN4_TX_C_DP<72>")
	)
	(segment
		(start 43.310048 -397.59001)
		(end 43.310048 -397.97228)
		(width 0.1651)
		(layer "In11.Cu")
		(net "P5E_PEX0_STN4_TX_C_DP<72>")
	)
	(segment
		(start 43.82389 -394.690346)
		(end 41.984168 -393.4587)
		(width 0.1651)
		(layer "In11.Cu")
		(net "P5E_PEX0_STN4_TX_C_DP<72>")
	)
	(segment
		(start 41.860978 -393.483084)
		(end 41.44899 -393.20724)
		(width 0.1651)
		(layer "In11.Cu")
		(net "P5E_PEX0_STN4_TX_C_DP<72>")
	)
	(segment
		(start 35.168078 -352.420682)
		(end 35.168078 -351.902268)
		(width 0.1651)
		(layer "In11.Cu")
		(net "P5E_PEX0_STN4_TX_C_DP<72>")
	)
	(segment
		(start 310.233822 -323.20484)
		(end 310.233822 -319.941448)
		(width 0.1651)
		(layer "In15.Cu")
		(net "P5E_PEX2_STN4_RX_DP<74>")
	)
	(segment
		(start 291.169852 -358.828594)
		(end 291.505132 -358.019096)
		(width 0.1651)
		(layer "In15.Cu")
		(net "P5E_PEX2_STN4_RX_DP<74>")
	)
	(segment
		(start 284.202124 -385.083812)
		(end 283.711904 -372.417086)
		(width 0.1651)
		(layer "In15.Cu")
		(net "P5E_PEX2_STN4_RX_DP<74>")
	)
	(segment
		(start 284.30601 -368.499136)
		(end 285.107888 -367.153698)
		(width 0.1651)
		(layer "In15.Cu")
		(net "P5E_PEX2_STN4_RX_DP<74>")
	)
	(segment
		(start 298.616878 -405.899112)
		(end 299.047154 -405.899112)
		(width 0.1651)
		(layer "In15.Cu")
		(net "P5E_PEX2_STN4_RX_DP<74>")
	)
	(segment
		(start 310.279542 -318.344804)
		(end 310.49468 -318.129666)
		(width 0.1143)
		(layer "In15.Cu")
		(net "P5E_PEX2_STN4_RX_DP<74>")
	)
	(segment
		(start 294.74668 -392.024616)
		(end 294.317674 -391.776458)
		(width 0.1651)
		(layer "In15.Cu")
		(net "P5E_PEX2_STN4_RX_DP<74>")
	)
	(segment
		(start 310.279542 -319.86728)
		(end 310.279542 -318.344804)
		(width 0.1143)
		(layer "In15.Cu")
		(net "P5E_PEX2_STN4_RX_DP<74>")
	)
	(segment
		(start 291.505132 -342.138508)
		(end 291.875464 -341.263986)
		(width 0.1651)
		(layer "In15.Cu")
		(net "P5E_PEX2_STN4_RX_DP<74>")
	)
	(segment
		(start 287.329372 -388.52983)
		(end 284.91688 -386.865876)
		(width 0.1651)
		(layer "In15.Cu")
		(net "P5E_PEX2_STN4_RX_DP<74>")
	)
	(segment
		(start 294.285162 -391.655046)
		(end 293.294308 -391.08253)
		(width 0.1651)
		(layer "In15.Cu")
		(net "P5E_PEX2_STN4_RX_DP<74>")
	)
	(segment
		(start 310.082184 -323.570854)
		(end 310.233822 -323.20484)
		(width 0.1651)
		(layer "In15.Cu")
		(net "P5E_PEX2_STN4_RX_DP<74>")
	)
	(segment
		(start 294.868092 -391.992104)
		(end 294.74668 -392.024616)
		(width 0.1651)
		(layer "In15.Cu")
		(net "P5E_PEX2_STN4_RX_DP<74>")
	)
	(segment
		(start 310.233822 -319.913)
		(end 310.279542 -319.86728)
		(width 0.1143)
		(layer "In15.Cu")
		(net "P5E_PEX2_STN4_RX_DP<74>")
	)
	(segment
		(start 310.849772 -318.015366)
		(end 310.849772 -317.749936)
		(width 0.1143)
		(layer "In15.Cu")
		(net "P5E_PEX2_STN4_RX_DP<74>")
	)
	(segment
		(start 284.91688 -386.865876)
		(end 284.202124 -385.083812)
		(width 0.1651)
		(layer "In15.Cu")
		(net "P5E_PEX2_STN4_RX_DP<74>")
	)
	(segment
		(start 310.233822 -319.941448)
		(end 310.233822 -319.913)
		(width 0.1143)
		(layer "In15.Cu")
		(net "P5E_PEX2_STN4_RX_DP<74>")
	)
	(segment
		(start 299.047154 -405.899112)
		(end 299.33392 -405.612346)
		(width 0.1651)
		(layer "In15.Cu")
		(net "P5E_PEX2_STN4_RX_DP<74>")
	)
	(segment
		(start 297.822874 -393.699238)
		(end 294.868092 -391.992104)
		(width 0.1651)
		(layer "In15.Cu")
		(net "P5E_PEX2_STN4_RX_DP<74>")
	)
	(segment
		(start 293.294308 -391.08253)
		(end 287.329372 -388.52983)
		(width 0.1651)
		(layer "In15.Cu")
		(net "P5E_PEX2_STN4_RX_DP<74>")
	)
	(segment
		(start 310.49468 -318.129666)
		(end 310.735472 -318.129666)
		(width 0.1143)
		(layer "In15.Cu")
		(net "P5E_PEX2_STN4_RX_DP<74>")
	)
	(segment
		(start 285.107888 -367.153698)
		(end 291.169852 -358.828594)
		(width 0.1651)
		(layer "In15.Cu")
		(net "P5E_PEX2_STN4_RX_DP<74>")
	)
	(segment
		(start 298.489878 -405.390096)
		(end 298.489878 -405.772112)
		(width 0.1651)
		(layer "In15.Cu")
		(net "P5E_PEX2_STN4_RX_DP<74>")
	)
	(segment
		(start 299.33392 -396.190724)
		(end 298.692062 -394.521436)
		(width 0.1651)
		(layer "In15.Cu")
		(net "P5E_PEX2_STN4_RX_DP<74>")
	)
	(segment
		(start 298.489878 -405.772112)
		(end 298.616878 -405.899112)
		(width 0.1651)
		(layer "In15.Cu")
		(net "P5E_PEX2_STN4_RX_DP<74>")
	)
	(segment
		(start 283.711904 -372.417086)
		(end 284.30601 -368.499136)
		(width 0.1651)
		(layer "In15.Cu")
		(net "P5E_PEX2_STN4_RX_DP<74>")
	)
	(segment
		(start 299.33392 -405.612346)
		(end 299.33392 -396.190724)
		(width 0.1651)
		(layer "In15.Cu")
		(net "P5E_PEX2_STN4_RX_DP<74>")
	)
	(segment
		(start 291.505132 -358.019096)
		(end 291.505132 -342.138508)
		(width 0.1651)
		(layer "In15.Cu")
		(net "P5E_PEX2_STN4_RX_DP<74>")
	)
	(segment
		(start 291.875464 -341.263986)
		(end 310.082184 -323.570854)
		(width 0.1651)
		(layer "In15.Cu")
		(net "P5E_PEX2_STN4_RX_DP<74>")
	)
	(segment
		(start 310.735472 -318.129666)
		(end 310.849772 -318.015366)
		(width 0.1143)
		(layer "In15.Cu")
		(net "P5E_PEX2_STN4_RX_DP<74>")
	)
	(segment
		(start 294.317674 -391.776458)
		(end 294.285162 -391.655046)
		(width 0.1651)
		(layer "In15.Cu")
		(net "P5E_PEX2_STN4_RX_DP<74>")
	)
	(segment
		(start 298.692062 -394.521436)
		(end 297.822874 -393.699238)
		(width 0.1651)
		(layer "In15.Cu")
		(net "P5E_PEX2_STN4_RX_DP<74>")
	)
	(segment
		(start 38.849808 -345.465146)
		(end 38.555168 -345.170506)
		(width 0.13462)
		(layer "F.Cu")
		(net "P5E_PEX0_STN4_TX_C_DN<71>")
	)
	(segment
		(start 38.555168 -344.539062)
		(end 38.875208 -344.219022)
		(width 0.13462)
		(layer "F.Cu")
		(net "P5E_PEX0_STN4_TX_C_DN<71>")
	)
	(segment
		(start 38.555168 -345.170506)
		(end 38.555168 -344.539062)
		(width 0.13462)
		(layer "F.Cu")
		(net "P5E_PEX0_STN4_TX_C_DN<71>")
	)
	(segment
		(start 38.558978 -345.755976)
		(end 38.849808 -345.465146)
		(width 0.1651)
		(layer "In11.Cu")
		(net "P5E_PEX0_STN4_TX_C_DN<71>")
	)
	(segment
		(start 28.037028 -371.281198)
		(end 28.489402 -371.281198)
		(width 0.1651)
		(layer "In11.Cu")
		(net "P5E_PEX0_STN4_TX_C_DN<71>")
	)
	(segment
		(start 38.558978 -346.438982)
		(end 38.558978 -345.755976)
		(width 0.1651)
		(layer "In11.Cu")
		(net "P5E_PEX0_STN4_TX_C_DN<71>")
	)
	(segment
		(start 27.910028 -371.790214)
		(end 27.910028 -371.408198)
		(width 0.1651)
		(layer "In11.Cu")
		(net "P5E_PEX0_STN4_TX_C_DN<71>")
	)
	(segment
		(start 29.1719 -368.229388)
		(end 36.6776 -359.08361)
		(width 0.1651)
		(layer "In11.Cu")
		(net "P5E_PEX0_STN4_TX_C_DN<71>")
	)
	(segment
		(start 29.1719 -370.5987)
		(end 29.1719 -368.229388)
		(width 0.1651)
		(layer "In11.Cu")
		(net "P5E_PEX0_STN4_TX_C_DN<71>")
	)
	(segment
		(start 37.004498 -358.169972)
		(end 37.004498 -347.993462)
		(width 0.1651)
		(layer "In11.Cu")
		(net "P5E_PEX0_STN4_TX_C_DN<71>")
	)
	(segment
		(start 37.004498 -347.993462)
		(end 38.558978 -346.438982)
		(width 0.1651)
		(layer "In11.Cu")
		(net "P5E_PEX0_STN4_TX_C_DN<71>")
	)
	(segment
		(start 27.910028 -371.408198)
		(end 28.037028 -371.281198)
		(width 0.1651)
		(layer "In11.Cu")
		(net "P5E_PEX0_STN4_TX_C_DN<71>")
	)
	(segment
		(start 36.6776 -359.08361)
		(end 37.004498 -358.169972)
		(width 0.1651)
		(layer "In11.Cu")
		(net "P5E_PEX0_STN4_TX_C_DN<71>")
	)
	(segment
		(start 28.489402 -371.281198)
		(end 29.1719 -370.5987)
		(width 0.1651)
		(layer "In11.Cu")
		(net "P5E_PEX0_STN4_TX_C_DN<71>")
	)
	(segment
		(start 48.202088 -349.831914)
		(end 47.882048 -349.511874)
		(width 0.13462)
		(layer "F.Cu")
		(net "P5E_PEX0_STN4_TX_DN<66>")
	)
	(segment
		(start 47.882048 -348.88043)
		(end 48.176688 -348.58579)
		(width 0.13462)
		(layer "F.Cu")
		(net "P5E_PEX0_STN4_TX_DN<66>")
	)
	(segment
		(start 47.882048 -349.511874)
		(end 47.882048 -348.88043)
		(width 0.13462)
		(layer "F.Cu")
		(net "P5E_PEX0_STN4_TX_DN<66>")
	)
	(segment
		(start 96.41586 -316.380876)
		(end 94.16923 -314.134246)
		(width 0.1651)
		(layer "In11.Cu")
		(net "P5E_PEX0_STN4_TX_DN<66>")
	)
	(segment
		(start 97.629218 -319.310766)
		(end 96.41586 -316.380876)
		(width 0.1651)
		(layer "In11.Cu")
		(net "P5E_PEX0_STN4_TX_DN<66>")
	)
	(segment
		(start 75.42022 -306.564538)
		(end 75.42022 -306.438808)
		(width 0.1143)
		(layer "In11.Cu")
		(net "P5E_PEX0_STN4_TX_DN<66>")
	)
	(segment
		(start 79.292958 -333.082138)
		(end 94.222316 -327.740264)
		(width 0.1651)
		(layer "In11.Cu")
		(net "P5E_PEX0_STN4_TX_DN<66>")
	)
	(segment
		(start 83.6168 -306.67706)
		(end 83.57108 -306.72278)
		(width 0.1143)
		(layer "In11.Cu")
		(net "P5E_PEX0_STN4_TX_DN<66>")
	)
	(segment
		(start 84.437474 -306.728622)
		(end 83.913218 -306.67706)
		(width 0.1651)
		(layer "In11.Cu")
		(net "P5E_PEX0_STN4_TX_DN<66>")
	)
	(segment
		(start 58.1025 -337.297014)
		(end 79.292958 -333.082138)
		(width 0.1651)
		(layer "In11.Cu")
		(net "P5E_PEX0_STN4_TX_DN<66>")
	)
	(segment
		(start 85.92566 -307.34508)
		(end 84.437474 -306.728622)
		(width 0.1651)
		(layer "In11.Cu")
		(net "P5E_PEX0_STN4_TX_DN<66>")
	)
	(segment
		(start 83.913218 -306.67706)
		(end 83.645248 -306.67706)
		(width 0.1651)
		(layer "In11.Cu")
		(net "P5E_PEX0_STN4_TX_DN<66>")
	)
	(segment
		(start 50.590958 -339.984842)
		(end 58.1025 -337.297014)
		(width 0.1651)
		(layer "In11.Cu")
		(net "P5E_PEX0_STN4_TX_DN<66>")
	)
	(segment
		(start 47.885858 -348.29496)
		(end 47.885858 -347.736922)
		(width 0.1651)
		(layer "In11.Cu")
		(net "P5E_PEX0_STN4_TX_DN<66>")
	)
	(segment
		(start 49.78654 -340.78926)
		(end 50.590958 -339.984842)
		(width 0.1651)
		(layer "In11.Cu")
		(net "P5E_PEX0_STN4_TX_DN<66>")
	)
	(segment
		(start 49.440338 -346.182442)
		(end 49.440338 -341.62492)
		(width 0.1651)
		(layer "In11.Cu")
		(net "P5E_PEX0_STN4_TX_DN<66>")
	)
	(segment
		(start 47.885858 -347.736922)
		(end 49.440338 -346.182442)
		(width 0.1651)
		(layer "In11.Cu")
		(net "P5E_PEX0_STN4_TX_DN<66>")
	)
	(segment
		(start 75.50912 -306.349908)
		(end 75.79995 -306.349908)
		(width 0.1143)
		(layer "In11.Cu")
		(net "P5E_PEX0_STN4_TX_DN<66>")
	)
	(segment
		(start 75.42022 -306.438808)
		(end 75.50912 -306.349908)
		(width 0.1143)
		(layer "In11.Cu")
		(net "P5E_PEX0_STN4_TX_DN<66>")
	)
	(segment
		(start 94.222316 -327.740264)
		(end 96.32569 -325.636636)
		(width 0.1651)
		(layer "In11.Cu")
		(net "P5E_PEX0_STN4_TX_DN<66>")
	)
	(segment
		(start 83.645248 -306.67706)
		(end 83.6168 -306.67706)
		(width 0.1143)
		(layer "In11.Cu")
		(net "P5E_PEX0_STN4_TX_DN<66>")
	)
	(segment
		(start 97.629218 -322.489322)
		(end 97.629218 -319.310766)
		(width 0.1651)
		(layer "In11.Cu")
		(net "P5E_PEX0_STN4_TX_DN<66>")
	)
	(segment
		(start 48.176688 -348.58579)
		(end 47.885858 -348.29496)
		(width 0.1651)
		(layer "In11.Cu")
		(net "P5E_PEX0_STN4_TX_DN<66>")
	)
	(segment
		(start 94.16923 -314.134246)
		(end 91.68638 -313.1058)
		(width 0.1651)
		(layer "In11.Cu")
		(net "P5E_PEX0_STN4_TX_DN<66>")
	)
	(segment
		(start 75.578462 -306.72278)
		(end 75.42022 -306.564538)
		(width 0.1143)
		(layer "In11.Cu")
		(net "P5E_PEX0_STN4_TX_DN<66>")
	)
	(segment
		(start 83.57108 -306.72278)
		(end 75.578462 -306.72278)
		(width 0.1143)
		(layer "In11.Cu")
		(net "P5E_PEX0_STN4_TX_DN<66>")
	)
	(segment
		(start 91.68638 -313.1058)
		(end 85.92566 -307.34508)
		(width 0.1651)
		(layer "In11.Cu")
		(net "P5E_PEX0_STN4_TX_DN<66>")
	)
	(segment
		(start 49.440338 -341.62492)
		(end 49.78654 -340.78926)
		(width 0.1651)
		(layer "In11.Cu")
		(net "P5E_PEX0_STN4_TX_DN<66>")
	)
	(segment
		(start 96.32569 -325.636636)
		(end 97.629218 -322.489322)
		(width 0.1651)
		(layer "In11.Cu")
		(net "P5E_PEX0_STN4_TX_DN<66>")
	)
	(segment
		(start 299.875702 -344.219022)
		(end 299.555662 -344.539062)
		(width 0.13462)
		(layer "F.Cu")
		(net "P5E_PEX2_STN4_TX_C_DN<65>")
	)
	(segment
		(start 299.555662 -344.539062)
		(end 299.555662 -345.170506)
		(width 0.13462)
		(layer "F.Cu")
		(net "P5E_PEX2_STN4_TX_C_DN<65>")
	)
	(segment
		(start 299.555662 -345.170506)
		(end 299.850302 -345.465146)
		(width 0.13462)
		(layer "F.Cu")
		(net "P5E_PEX2_STN4_TX_C_DN<65>")
	)
	(segment
		(start 301.815754 -368.7699)
		(end 301.815754 -370.829332)
		(width 0.1651)
		(layer "In11.Cu")
		(net "P5E_PEX2_STN4_TX_C_DN<65>")
	)
	(segment
		(start 299.850302 -345.465146)
		(end 299.559472 -345.755976)
		(width 0.1651)
		(layer "In11.Cu")
		(net "P5E_PEX2_STN4_TX_C_DN<65>")
	)
	(segment
		(start 301.815754 -370.829332)
		(end 301.363888 -371.281198)
		(width 0.1651)
		(layer "In11.Cu")
		(net "P5E_PEX2_STN4_TX_C_DN<65>")
	)
	(segment
		(start 300.816772 -371.281198)
		(end 300.689772 -371.408198)
		(width 0.1651)
		(layer "In11.Cu")
		(net "P5E_PEX2_STN4_TX_C_DN<65>")
	)
	(segment
		(start 298.004992 -347.881194)
		(end 298.004992 -358.88422)
		(width 0.1651)
		(layer "In11.Cu")
		(net "P5E_PEX2_STN4_TX_C_DN<65>")
	)
	(segment
		(start 300.689772 -371.408198)
		(end 300.689772 -371.790214)
		(width 0.1651)
		(layer "In11.Cu")
		(net "P5E_PEX2_STN4_TX_C_DN<65>")
	)
	(segment
		(start 301.363888 -371.281198)
		(end 300.816772 -371.281198)
		(width 0.1651)
		(layer "In11.Cu")
		(net "P5E_PEX2_STN4_TX_C_DN<65>")
	)
	(segment
		(start 299.559472 -346.326714)
		(end 298.004992 -347.881194)
		(width 0.1651)
		(layer "In11.Cu")
		(net "P5E_PEX2_STN4_TX_C_DN<65>")
	)
	(segment
		(start 298.004992 -358.88422)
		(end 301.815754 -368.7699)
		(width 0.1651)
		(layer "In11.Cu")
		(net "P5E_PEX2_STN4_TX_C_DN<65>")
	)
	(segment
		(start 299.559472 -345.755976)
		(end 299.559472 -346.326714)
		(width 0.1651)
		(layer "In11.Cu")
		(net "P5E_PEX2_STN4_TX_C_DN<65>")
	)
	(segment
		(start 28.79979 -394.584936)
		(end 27.965654 -393.7508)
		(width 0.1651)
		(layer "In15.Cu")
		(net "P5E_PEX0_STN4_RX_DN<79>")
	)
	(segment
		(start 73.634346 -316.419992)
		(end 73.785476 -316.419992)
		(width 0.1143)
		(layer "In15.Cu")
		(net "P5E_PEX0_STN4_RX_DN<79>")
	)
	(segment
		(start 40.597074 -330.081128)
		(end 68.216526 -323.162676)
		(width 0.1651)
		(layer "In15.Cu")
		(net "P5E_PEX0_STN4_RX_DN<79>")
	)
	(segment
		(start 73.520046 -316.534292)
		(end 73.634346 -316.419992)
		(width 0.1143)
		(layer "In15.Cu")
		(net "P5E_PEX0_STN4_RX_DN<79>")
	)
	(segment
		(start 29.06776 -404.388574)
		(end 29.06776 -395.231874)
		(width 0.1651)
		(layer "In15.Cu")
		(net "P5E_PEX0_STN4_RX_DN<79>")
	)
	(segment
		(start 73.520046 -319.84188)
		(end 73.520046 -316.534292)
		(width 0.1143)
		(layer "In15.Cu")
		(net "P5E_PEX0_STN4_RX_DN<79>")
	)
	(segment
		(start 28.037028 -405.080978)
		(end 28.375356 -405.080978)
		(width 0.1651)
		(layer "In15.Cu")
		(net "P5E_PEX0_STN4_RX_DN<79>")
	)
	(segment
		(start 68.216526 -323.162676)
		(end 73.281286 -321.064636)
		(width 0.1651)
		(layer "In15.Cu")
		(net "P5E_PEX0_STN4_RX_DN<79>")
	)
	(segment
		(start 17.540986 -338.549996)
		(end 18.640044 -337.815682)
		(width 0.1651)
		(layer "In15.Cu")
		(net "P5E_PEX0_STN4_RX_DN<79>")
	)
	(segment
		(start 18.640044 -337.815682)
		(end 28.314396 -333.8068)
		(width 0.1651)
		(layer "In15.Cu")
		(net "P5E_PEX0_STN4_RX_DN<79>")
	)
	(segment
		(start 15.41018 -353.424998)
		(end 15.41018 -341.801958)
		(width 0.1651)
		(layer "In15.Cu")
		(net "P5E_PEX0_STN4_RX_DN<79>")
	)
	(segment
		(start 27.280108 -393.466828)
		(end 22.859238 -390.512808)
		(width 0.1651)
		(layer "In15.Cu")
		(net "P5E_PEX0_STN4_RX_DN<79>")
	)
	(segment
		(start 73.281286 -321.064636)
		(end 73.565766 -320.638932)
		(width 0.1651)
		(layer "In15.Cu")
		(net "P5E_PEX0_STN4_RX_DN<79>")
	)
	(segment
		(start 22.859238 -390.512808)
		(end 21.057616 -388.711186)
		(width 0.1651)
		(layer "In15.Cu")
		(net "P5E_PEX0_STN4_RX_DN<79>")
	)
	(segment
		(start 29.06776 -395.231874)
		(end 28.79979 -394.584936)
		(width 0.1651)
		(layer "In15.Cu")
		(net "P5E_PEX0_STN4_RX_DN<79>")
	)
	(segment
		(start 27.910028 -405.589994)
		(end 27.910028 -405.207978)
		(width 0.1651)
		(layer "In15.Cu")
		(net "P5E_PEX0_STN4_RX_DN<79>")
	)
	(segment
		(start 16.202914 -339.888068)
		(end 17.540986 -338.549996)
		(width 0.1651)
		(layer "In15.Cu")
		(net "P5E_PEX0_STN4_RX_DN<79>")
	)
	(segment
		(start 73.565766 -319.8876)
		(end 73.520046 -319.84188)
		(width 0.1143)
		(layer "In15.Cu")
		(net "P5E_PEX0_STN4_RX_DN<79>")
	)
	(segment
		(start 73.785476 -316.419992)
		(end 73.899776 -316.534292)
		(width 0.1143)
		(layer "In15.Cu")
		(net "P5E_PEX0_STN4_RX_DN<79>")
	)
	(segment
		(start 73.899776 -316.534292)
		(end 73.899776 -316.799722)
		(width 0.1143)
		(layer "In15.Cu")
		(net "P5E_PEX0_STN4_RX_DN<79>")
	)
	(segment
		(start 28.375356 -405.080978)
		(end 29.06776 -404.388574)
		(width 0.1651)
		(layer "In15.Cu")
		(net "P5E_PEX0_STN4_RX_DN<79>")
	)
	(segment
		(start 27.910028 -405.207978)
		(end 28.037028 -405.080978)
		(width 0.1651)
		(layer "In15.Cu")
		(net "P5E_PEX0_STN4_RX_DN<79>")
	)
	(segment
		(start 73.565766 -319.916048)
		(end 73.565766 -319.8876)
		(width 0.1143)
		(layer "In15.Cu")
		(net "P5E_PEX0_STN4_RX_DN<79>")
	)
	(segment
		(start 21.057616 -388.711186)
		(end 19.79422 -385.6609)
		(width 0.1651)
		(layer "In15.Cu")
		(net "P5E_PEX0_STN4_RX_DN<79>")
	)
	(segment
		(start 27.965654 -393.7508)
		(end 27.280108 -393.466828)
		(width 0.1651)
		(layer "In15.Cu")
		(net "P5E_PEX0_STN4_RX_DN<79>")
	)
	(segment
		(start 19.79422 -385.6609)
		(end 19.007836 -377.67768)
		(width 0.1651)
		(layer "In15.Cu")
		(net "P5E_PEX0_STN4_RX_DN<79>")
	)
	(segment
		(start 73.565766 -320.638932)
		(end 73.565766 -319.916048)
		(width 0.1651)
		(layer "In15.Cu")
		(net "P5E_PEX0_STN4_RX_DN<79>")
	)
	(segment
		(start 19.007836 -377.67768)
		(end 15.41018 -353.424998)
		(width 0.1651)
		(layer "In15.Cu")
		(net "P5E_PEX0_STN4_RX_DN<79>")
	)
	(segment
		(start 28.314396 -333.8068)
		(end 40.597074 -330.081128)
		(width 0.1651)
		(layer "In15.Cu")
		(net "P5E_PEX0_STN4_RX_DN<79>")
	)
	(segment
		(start 15.41018 -341.801958)
		(end 16.202914 -339.888068)
		(width 0.1651)
		(layer "In15.Cu")
		(net "P5E_PEX0_STN4_RX_DN<79>")
	)
	(segment
		(start 19.901408 -342.734138)
		(end 20.196048 -342.439498)
		(width 0.13462)
		(layer "F.Cu")
		(net "P5E_PEX0_STN4_TX_DN<79>")
	)
	(segment
		(start 20.221448 -343.685622)
		(end 19.901408 -343.365582)
		(width 0.13462)
		(layer "F.Cu")
		(net "P5E_PEX0_STN4_TX_DN<79>")
	)
	(segment
		(start 19.901408 -343.365582)
		(end 19.901408 -342.734138)
		(width 0.13462)
		(layer "F.Cu")
		(net "P5E_PEX0_STN4_TX_DN<79>")
	)
	(segment
		(start 40.033448 -329.996038)
		(end 52.210462 -325.638922)
		(width 0.1651)
		(layer "In11.Cu")
		(net "P5E_PEX0_STN4_TX_DN<79>")
	)
	(segment
		(start 73.565766 -320.265552)
		(end 73.520046 -320.219832)
		(width 0.1143)
		(layer "In11.Cu")
		(net "P5E_PEX0_STN4_TX_DN<79>")
	)
	(segment
		(start 73.685146 -311.670192)
		(end 73.810876 -311.670192)
		(width 0.1143)
		(layer "In11.Cu")
		(net "P5E_PEX0_STN4_TX_DN<79>")
	)
	(segment
		(start 73.565766 -320.294)
		(end 73.565766 -320.265552)
		(width 0.1143)
		(layer "In11.Cu")
		(net "P5E_PEX0_STN4_TX_DN<79>")
	)
	(segment
		(start 72.577706 -321.587622)
		(end 73.27646 -321.214242)
		(width 0.1651)
		(layer "In11.Cu")
		(net "P5E_PEX0_STN4_TX_DN<79>")
	)
	(segment
		(start 73.899776 -311.759092)
		(end 73.899776 -312.049922)
		(width 0.1143)
		(layer "In11.Cu")
		(net "P5E_PEX0_STN4_TX_DN<79>")
	)
	(segment
		(start 73.565766 -320.515234)
		(end 73.565766 -320.294)
		(width 0.1651)
		(layer "In11.Cu")
		(net "P5E_PEX0_STN4_TX_DN<79>")
	)
	(segment
		(start 19.905218 -342.148668)
		(end 19.905218 -341.337646)
		(width 0.1651)
		(layer "In11.Cu")
		(net "P5E_PEX0_STN4_TX_DN<79>")
	)
	(segment
		(start 73.520046 -320.219832)
		(end 73.520046 -311.835292)
		(width 0.1143)
		(layer "In11.Cu")
		(net "P5E_PEX0_STN4_TX_DN<79>")
	)
	(segment
		(start 19.905218 -341.337646)
		(end 20.419314 -340.480142)
		(width 0.1651)
		(layer "In11.Cu")
		(net "P5E_PEX0_STN4_TX_DN<79>")
	)
	(segment
		(start 73.27646 -321.214242)
		(end 73.565766 -320.515234)
		(width 0.1651)
		(layer "In11.Cu")
		(net "P5E_PEX0_STN4_TX_DN<79>")
	)
	(segment
		(start 73.520046 -311.835292)
		(end 73.685146 -311.670192)
		(width 0.1143)
		(layer "In11.Cu")
		(net "P5E_PEX0_STN4_TX_DN<79>")
	)
	(segment
		(start 20.419314 -340.480142)
		(end 40.033448 -329.996038)
		(width 0.1651)
		(layer "In11.Cu")
		(net "P5E_PEX0_STN4_TX_DN<79>")
	)
	(segment
		(start 20.196048 -342.439498)
		(end 19.905218 -342.148668)
		(width 0.1651)
		(layer "In11.Cu")
		(net "P5E_PEX0_STN4_TX_DN<79>")
	)
	(segment
		(start 73.810876 -311.670192)
		(end 73.899776 -311.759092)
		(width 0.1143)
		(layer "In11.Cu")
		(net "P5E_PEX0_STN4_TX_DN<79>")
	)
	(segment
		(start 52.210462 -325.638922)
		(end 72.577706 -321.587622)
		(width 0.1651)
		(layer "In11.Cu")
		(net "P5E_PEX0_STN4_TX_DN<79>")
	)
	(segment
		(start 279.477216 -386.003038)
		(end 281.09291 -389.71347)
		(width 0.1651)
		(layer "In15.Cu")
		(net "P5E_PEX2_STN4_RX_DN<79>")
	)
	(segment
		(start 276.242272 -360.674666)
		(end 279.477216 -386.003038)
		(width 0.1651)
		(layer "In15.Cu")
		(net "P5E_PEX2_STN4_RX_DN<79>")
	)
	(segment
		(start 305.765708 -319.941448)
		(end 305.765708 -321.207892)
		(width 0.1651)
		(layer "In15.Cu")
		(net "P5E_PEX2_STN4_RX_DN<79>")
	)
	(segment
		(start 288.3154 -394.5382)
		(end 288.615882 -395.3256)
		(width 0.1651)
		(layer "In15.Cu")
		(net "P5E_PEX2_STN4_RX_DN<79>")
	)
	(segment
		(start 288.615882 -395.3256)
		(end 288.615882 -404.629112)
		(width 0.1651)
		(layer "In15.Cu")
		(net "P5E_PEX2_STN4_RX_DN<79>")
	)
	(segment
		(start 305.82362 -316.419992)
		(end 305.719988 -316.523624)
		(width 0.1143)
		(layer "In15.Cu")
		(net "P5E_PEX2_STN4_RX_DN<79>")
	)
	(segment
		(start 306.099718 -316.799722)
		(end 306.099718 -316.534292)
		(width 0.1143)
		(layer "In15.Cu")
		(net "P5E_PEX2_STN4_RX_DN<79>")
	)
	(segment
		(start 287.548828 -393.800076)
		(end 288.3154 -394.5382)
		(width 0.1651)
		(layer "In15.Cu")
		(net "P5E_PEX2_STN4_RX_DN<79>")
	)
	(segment
		(start 305.17084 -321.80276)
		(end 276.606 -341.249)
		(width 0.1651)
		(layer "In15.Cu")
		(net "P5E_PEX2_STN4_RX_DN<79>")
	)
	(segment
		(start 305.719988 -319.86728)
		(end 305.765708 -319.913)
		(width 0.1143)
		(layer "In15.Cu")
		(net "P5E_PEX2_STN4_RX_DN<79>")
	)
	(segment
		(start 306.099718 -316.534292)
		(end 305.985418 -316.419992)
		(width 0.1143)
		(layer "In15.Cu")
		(net "P5E_PEX2_STN4_RX_DN<79>")
	)
	(segment
		(start 287.6169 -405.080978)
		(end 287.4899 -405.207978)
		(width 0.1651)
		(layer "In15.Cu")
		(net "P5E_PEX2_STN4_RX_DN<79>")
	)
	(segment
		(start 281.09291 -389.71347)
		(end 284.896814 -392.603228)
		(width 0.1651)
		(layer "In15.Cu")
		(net "P5E_PEX2_STN4_RX_DN<79>")
	)
	(segment
		(start 288.164016 -405.080978)
		(end 287.6169 -405.080978)
		(width 0.1651)
		(layer "In15.Cu")
		(net "P5E_PEX2_STN4_RX_DN<79>")
	)
	(segment
		(start 287.4899 -405.207978)
		(end 287.4899 -405.589994)
		(width 0.1651)
		(layer "In15.Cu")
		(net "P5E_PEX2_STN4_RX_DN<79>")
	)
	(segment
		(start 305.719988 -316.523624)
		(end 305.719988 -319.86728)
		(width 0.1143)
		(layer "In15.Cu")
		(net "P5E_PEX2_STN4_RX_DN<79>")
	)
	(segment
		(start 276.424136 -341.629746)
		(end 276.424136 -341.63)
		(width 0.1651)
		(layer "In15.Cu")
		(net "P5E_PEX2_STN4_RX_DN<79>")
	)
	(segment
		(start 284.896814 -392.603228)
		(end 287.548828 -393.800076)
		(width 0.1651)
		(layer "In15.Cu")
		(net "P5E_PEX2_STN4_RX_DN<79>")
	)
	(segment
		(start 276.242272 -342.011)
		(end 276.242272 -360.674666)
		(width 0.1651)
		(layer "In15.Cu")
		(net "P5E_PEX2_STN4_RX_DN<79>")
	)
	(segment
		(start 305.765708 -319.913)
		(end 305.765708 -319.941448)
		(width 0.1143)
		(layer "In15.Cu")
		(net "P5E_PEX2_STN4_RX_DN<79>")
	)
	(segment
		(start 305.765708 -321.207892)
		(end 305.17084 -321.80276)
		(width 0.1651)
		(layer "In15.Cu")
		(net "P5E_PEX2_STN4_RX_DN<79>")
	)
	(segment
		(start 276.424136 -341.63)
		(end 276.242272 -342.011)
		(width 0.1651)
		(layer "In15.Cu")
		(net "P5E_PEX2_STN4_RX_DN<79>")
	)
	(segment
		(start 276.606 -341.249)
		(end 276.424136 -341.629746)
		(width 0.1651)
		(layer "In15.Cu")
		(net "P5E_PEX2_STN4_RX_DN<79>")
	)
	(segment
		(start 305.985418 -316.419992)
		(end 305.82362 -316.419992)
		(width 0.1143)
		(layer "In15.Cu")
		(net "P5E_PEX2_STN4_RX_DN<79>")
	)
	(segment
		(start 288.615882 -404.629112)
		(end 288.164016 -405.080978)
		(width 0.1651)
		(layer "In15.Cu")
		(net "P5E_PEX2_STN4_RX_DN<79>")
	)
	(segment
		(start 43.916092 -366.749584)
		(end 44.257722 -366.407954)
		(width 0.1651)
		(layer "In15.Cu")
		(net "P5E_PEX0_STN4_RX_DP<65>")
	)
	(segment
		(start 45.604684 -365.222536)
		(end 45.604684 -365.060992)
		(width 0.1651)
		(layer "In15.Cu")
		(net "P5E_PEX0_STN4_RX_DP<65>")
	)
	(segment
		(start 41.2369 -378.79909)
		(end 41.458388 -378.79909)
		(width 0.1651)
		(layer "In15.Cu")
		(net "P5E_PEX0_STN4_RX_DP<65>")
	)
	(segment
		(start 46.44898 -364.37824)
		(end 46.44898 -364.216696)
		(width 0.1651)
		(layer "In15.Cu")
		(net "P5E_PEX0_STN4_RX_DP<65>")
	)
	(segment
		(start 42.434764 -368.392456)
		(end 43.07205 -367.75517)
		(width 0.1651)
		(layer "In15.Cu")
		(net "P5E_PEX0_STN4_RX_DP<65>")
	)
	(segment
		(start 45.263562 -365.563658)
		(end 45.604684 -365.222536)
		(width 0.1651)
		(layer "In15.Cu")
		(net "P5E_PEX0_STN4_RX_DP<65>")
	)
	(segment
		(start 48.137572 -362.528104)
		(end 48.479202 -362.186474)
		(width 0.1651)
		(layer "In15.Cu")
		(net "P5E_PEX0_STN4_RX_DP<65>")
	)
	(segment
		(start 44.257722 -366.407954)
		(end 44.419266 -366.407954)
		(width 0.1651)
		(layer "In15.Cu")
		(net "P5E_PEX0_STN4_RX_DP<65>")
	)
	(segment
		(start 79.89062 -305.399948)
		(end 79.59979 -305.399948)
		(width 0.1143)
		(layer "In15.Cu")
		(net "P5E_PEX0_STN4_RX_DP<65>")
	)
	(segment
		(start 41.1099 -378.290074)
		(end 41.1099 -378.67209)
		(width 0.1651)
		(layer "In15.Cu")
		(net "P5E_PEX0_STN4_RX_DP<65>")
	)
	(segment
		(start 93.229938 -328.238866)
		(end 95.60433 -326.497696)
		(width 0.1651)
		(layer "In15.Cu")
		(net "P5E_PEX0_STN4_RX_DP<65>")
	)
	(segment
		(start 45.102018 -365.563658)
		(end 45.263562 -365.563658)
		(width 0.1651)
		(layer "In15.Cu")
		(net "P5E_PEX0_STN4_RX_DP<65>")
	)
	(segment
		(start 80.256126 -305.970178)
		(end 79.97952 -305.693572)
		(width 0.1143)
		(layer "In15.Cu")
		(net "P5E_PEX0_STN4_RX_DP<65>")
	)
	(segment
		(start 43.57497 -367.25225)
		(end 43.916092 -366.911128)
		(width 0.1651)
		(layer "In15.Cu")
		(net "P5E_PEX0_STN4_RX_DP<65>")
	)
	(segment
		(start 79.97952 -305.488848)
		(end 79.89062 -305.399948)
		(width 0.1143)
		(layer "In15.Cu")
		(net "P5E_PEX0_STN4_RX_DP<65>")
	)
	(segment
		(start 95.60433 -326.497696)
		(end 96.492314 -325.439024)
		(width 0.1651)
		(layer "In15.Cu")
		(net "P5E_PEX0_STN4_RX_DP<65>")
	)
	(segment
		(start 46.107858 -364.719362)
		(end 46.44898 -364.37824)
		(width 0.1651)
		(layer "In15.Cu")
		(net "P5E_PEX0_STN4_RX_DP<65>")
	)
	(segment
		(start 48.640746 -362.186474)
		(end 51.262788 -359.564432)
		(width 0.1651)
		(layer "In15.Cu")
		(net "P5E_PEX0_STN4_RX_DP<65>")
	)
	(segment
		(start 43.916092 -366.911128)
		(end 43.916092 -366.749584)
		(width 0.1651)
		(layer "In15.Cu")
		(net "P5E_PEX0_STN4_RX_DP<65>")
	)
	(segment
		(start 83.645248 -306.015898)
		(end 83.6168 -306.015898)
		(width 0.1143)
		(layer "In15.Cu")
		(net "P5E_PEX0_STN4_RX_DP<65>")
	)
	(segment
		(start 46.952154 -363.875066)
		(end 47.293276 -363.533944)
		(width 0.1651)
		(layer "In15.Cu")
		(net "P5E_PEX0_STN4_RX_DP<65>")
	)
	(segment
		(start 96.526096 -315.766196)
		(end 94.403926 -312.589926)
		(width 0.1651)
		(layer "In15.Cu")
		(net "P5E_PEX0_STN4_RX_DP<65>")
	)
	(segment
		(start 80.663034 -333.444088)
		(end 93.229938 -328.238866)
		(width 0.1651)
		(layer "In15.Cu")
		(net "P5E_PEX0_STN4_RX_DP<65>")
	)
	(segment
		(start 45.946314 -364.719362)
		(end 46.107858 -364.719362)
		(width 0.1651)
		(layer "In15.Cu")
		(net "P5E_PEX0_STN4_RX_DP<65>")
	)
	(segment
		(start 47.293276 -363.3724)
		(end 47.634906 -363.03077)
		(width 0.1651)
		(layer "In15.Cu")
		(net "P5E_PEX0_STN4_RX_DP<65>")
	)
	(segment
		(start 41.985692 -369.476528)
		(end 42.434764 -368.392456)
		(width 0.1651)
		(layer "In15.Cu")
		(net "P5E_PEX0_STN4_RX_DP<65>")
	)
	(segment
		(start 44.419266 -366.407954)
		(end 44.760388 -366.066832)
		(width 0.1651)
		(layer "In15.Cu")
		(net "P5E_PEX0_STN4_RX_DP<65>")
	)
	(segment
		(start 64.662304 -338.297774)
		(end 80.663034 -333.444088)
		(width 0.1651)
		(layer "In15.Cu")
		(net "P5E_PEX0_STN4_RX_DP<65>")
	)
	(segment
		(start 79.97952 -305.693572)
		(end 79.97952 -305.488848)
		(width 0.1143)
		(layer "In15.Cu")
		(net "P5E_PEX0_STN4_RX_DP<65>")
	)
	(segment
		(start 97.4598 -323.103494)
		(end 97.827338 -318.90716)
		(width 0.1651)
		(layer "In15.Cu")
		(net "P5E_PEX0_STN4_RX_DP<65>")
	)
	(segment
		(start 44.760388 -366.066832)
		(end 44.760388 -365.905288)
		(width 0.1651)
		(layer "In15.Cu")
		(net "P5E_PEX0_STN4_RX_DP<65>")
	)
	(segment
		(start 41.1099 -378.67209)
		(end 41.2369 -378.79909)
		(width 0.1651)
		(layer "In15.Cu")
		(net "P5E_PEX0_STN4_RX_DP<65>")
	)
	(segment
		(start 52.257198 -358.076246)
		(end 59.271662 -341.141304)
		(width 0.1651)
		(layer "In15.Cu")
		(net "P5E_PEX0_STN4_RX_DP<65>")
	)
	(segment
		(start 96.492314 -325.439024)
		(end 97.4598 -323.103494)
		(width 0.1651)
		(layer "In15.Cu")
		(net "P5E_PEX0_STN4_RX_DP<65>")
	)
	(segment
		(start 59.271662 -341.141304)
		(end 60.314078 -340.098888)
		(width 0.1651)
		(layer "In15.Cu")
		(net "P5E_PEX0_STN4_RX_DP<65>")
	)
	(segment
		(start 45.604684 -365.060992)
		(end 45.946314 -364.719362)
		(width 0.1651)
		(layer "In15.Cu")
		(net "P5E_PEX0_STN4_RX_DP<65>")
	)
	(segment
		(start 46.44898 -364.216696)
		(end 46.79061 -363.875066)
		(width 0.1651)
		(layer "In15.Cu")
		(net "P5E_PEX0_STN4_RX_DP<65>")
	)
	(segment
		(start 47.293276 -363.533944)
		(end 47.293276 -363.3724)
		(width 0.1651)
		(layer "In15.Cu")
		(net "P5E_PEX0_STN4_RX_DP<65>")
	)
	(segment
		(start 41.458388 -378.79909)
		(end 41.985692 -378.271786)
		(width 0.1651)
		(layer "In15.Cu")
		(net "P5E_PEX0_STN4_RX_DP<65>")
	)
	(segment
		(start 41.985692 -378.271786)
		(end 41.985692 -369.476528)
		(width 0.1651)
		(layer "In15.Cu")
		(net "P5E_PEX0_STN4_RX_DP<65>")
	)
	(segment
		(start 47.79645 -363.03077)
		(end 48.137572 -362.689648)
		(width 0.1651)
		(layer "In15.Cu")
		(net "P5E_PEX0_STN4_RX_DP<65>")
	)
	(segment
		(start 51.262788 -359.564432)
		(end 52.257198 -358.076246)
		(width 0.1651)
		(layer "In15.Cu")
		(net "P5E_PEX0_STN4_RX_DP<65>")
	)
	(segment
		(start 83.57108 -305.970178)
		(end 80.256126 -305.970178)
		(width 0.1143)
		(layer "In15.Cu")
		(net "P5E_PEX0_STN4_RX_DP<65>")
	)
	(segment
		(start 46.79061 -363.875066)
		(end 46.952154 -363.875066)
		(width 0.1651)
		(layer "In15.Cu")
		(net "P5E_PEX0_STN4_RX_DP<65>")
	)
	(segment
		(start 89.534238 -307.720238)
		(end 86.448138 -306.071016)
		(width 0.1651)
		(layer "In15.Cu")
		(net "P5E_PEX0_STN4_RX_DP<65>")
	)
	(segment
		(start 43.413426 -367.25225)
		(end 43.57497 -367.25225)
		(width 0.1651)
		(layer "In15.Cu")
		(net "P5E_PEX0_STN4_RX_DP<65>")
	)
	(segment
		(start 83.6168 -306.015898)
		(end 83.57108 -305.970178)
		(width 0.1143)
		(layer "In15.Cu")
		(net "P5E_PEX0_STN4_RX_DP<65>")
	)
	(segment
		(start 44.760388 -365.905288)
		(end 45.102018 -365.563658)
		(width 0.1651)
		(layer "In15.Cu")
		(net "P5E_PEX0_STN4_RX_DP<65>")
	)
	(segment
		(start 86.448138 -306.071016)
		(end 86.315296 -306.015898)
		(width 0.1651)
		(layer "In15.Cu")
		(net "P5E_PEX0_STN4_RX_DP<65>")
	)
	(segment
		(start 43.07205 -367.75517)
		(end 43.07205 -367.593626)
		(width 0.1651)
		(layer "In15.Cu")
		(net "P5E_PEX0_STN4_RX_DP<65>")
	)
	(segment
		(start 60.314078 -340.098888)
		(end 64.662304 -338.297774)
		(width 0.1651)
		(layer "In15.Cu")
		(net "P5E_PEX0_STN4_RX_DP<65>")
	)
	(segment
		(start 47.634906 -363.03077)
		(end 47.79645 -363.03077)
		(width 0.1651)
		(layer "In15.Cu")
		(net "P5E_PEX0_STN4_RX_DP<65>")
	)
	(segment
		(start 48.137572 -362.689648)
		(end 48.137572 -362.528104)
		(width 0.1651)
		(layer "In15.Cu")
		(net "P5E_PEX0_STN4_RX_DP<65>")
	)
	(segment
		(start 48.479202 -362.186474)
		(end 48.640746 -362.186474)
		(width 0.1651)
		(layer "In15.Cu")
		(net "P5E_PEX0_STN4_RX_DP<65>")
	)
	(segment
		(start 43.07205 -367.593626)
		(end 43.413426 -367.25225)
		(width 0.1651)
		(layer "In15.Cu")
		(net "P5E_PEX0_STN4_RX_DP<65>")
	)
	(segment
		(start 97.827338 -318.90716)
		(end 96.526096 -315.766196)
		(width 0.1651)
		(layer "In15.Cu")
		(net "P5E_PEX0_STN4_RX_DP<65>")
	)
	(segment
		(start 94.403926 -312.589926)
		(end 89.534238 -307.720238)
		(width 0.1651)
		(layer "In15.Cu")
		(net "P5E_PEX0_STN4_RX_DP<65>")
	)
	(segment
		(start 86.315296 -306.015898)
		(end 83.645248 -306.015898)
		(width 0.1651)
		(layer "In15.Cu")
		(net "P5E_PEX0_STN4_RX_DP<65>")
	)
	(segment
		(start 306.337462 -345.807792)
		(end 306.337208 -345.808554)
		(width 0.1651)
		(layer "In15.Cu")
		(net "P5E_PEX2_STN4_RX_DP<70>")
	)
	(segment
		(start 314.079636 -310.50484)
		(end 314.294774 -310.719978)
		(width 0.1143)
		(layer "In15.Cu")
		(net "P5E_PEX2_STN4_RX_DP<70>")
	)
	(segment
		(start 290.533836 -369.69192)
		(end 290.533836 -379.612398)
		(width 0.1651)
		(layer "In15.Cu")
		(net "P5E_PEX2_STN4_RX_DP<70>")
	)
	(segment
		(start 293.432738 -366.455706)
		(end 293.289228 -366.44834)
		(width 0.1651)
		(layer "In15.Cu")
		(net "P5E_PEX2_STN4_RX_DP<70>")
	)
	(segment
		(start 292.920928 -366.780064)
		(end 292.913562 -366.923574)
		(width 0.1651)
		(layer "In15.Cu")
		(net "P5E_PEX2_STN4_RX_DP<70>")
	)
	(segment
		(start 290.94303 -368.699542)
		(end 290.533836 -369.69192)
		(width 0.1651)
		(layer "In15.Cu")
		(net "P5E_PEX2_STN4_RX_DP<70>")
	)
	(segment
		(start 294.176196 -365.649002)
		(end 293.807896 -365.980726)
		(width 0.1651)
		(layer "In15.Cu")
		(net "P5E_PEX2_STN4_RX_DP<70>")
	)
	(segment
		(start 315.324744 -310.999124)
		(end 315.34481 -311.01919)
		(width 0.1143)
		(layer "In15.Cu")
		(net "P5E_PEX2_STN4_RX_DP<70>")
	)
	(segment
		(start 306.29733 -345.721432)
		(end 306.337462 -345.807792)
		(width 0.1651)
		(layer "In15.Cu")
		(net "P5E_PEX2_STN4_RX_DP<70>")
	)
	(segment
		(start 315.324744 -310.934862)
		(end 315.324744 -310.999124)
		(width 0.1143)
		(layer "In15.Cu")
		(net "P5E_PEX2_STN4_RX_DP<70>")
	)
	(segment
		(start 290.533836 -379.612398)
		(end 290.24707 -379.899164)
		(width 0.1651)
		(layer "In15.Cu")
		(net "P5E_PEX2_STN4_RX_DP<70>")
	)
	(segment
		(start 306.337208 -345.808554)
		(end 306.168044 -346.27312)
		(width 0.1651)
		(layer "In15.Cu")
		(net "P5E_PEX2_STN4_RX_DP<70>")
	)
	(segment
		(start 306.484528 -345.208352)
		(end 306.29733 -345.721432)
		(width 0.1651)
		(layer "In15.Cu")
		(net "P5E_PEX2_STN4_RX_DP<70>")
	)
	(segment
		(start 315.315854 -321.174364)
		(end 306.568094 -345.175078)
		(width 0.1651)
		(layer "In15.Cu")
		(net "P5E_PEX2_STN4_RX_DP<70>")
	)
	(segment
		(start 293.289228 -366.44834)
		(end 292.920928 -366.780064)
		(width 0.1651)
		(layer "In15.Cu")
		(net "P5E_PEX2_STN4_RX_DP<70>")
	)
	(segment
		(start 293.80053 -366.124236)
		(end 293.432738 -366.455706)
		(width 0.1651)
		(layer "In15.Cu")
		(net "P5E_PEX2_STN4_RX_DP<70>")
	)
	(segment
		(start 314.294774 -310.719978)
		(end 315.10986 -310.719978)
		(width 0.1143)
		(layer "In15.Cu")
		(net "P5E_PEX2_STN4_RX_DP<70>")
	)
	(segment
		(start 306.054252 -346.326206)
		(end 305.884326 -346.791788)
		(width 0.1651)
		(layer "In15.Cu")
		(net "P5E_PEX2_STN4_RX_DP<70>")
	)
	(segment
		(start 305.537362 -348.003622)
		(end 301.44339 -359.236264)
		(width 0.1651)
		(layer "In15.Cu")
		(net "P5E_PEX2_STN4_RX_DP<70>")
	)
	(segment
		(start 315.34481 -311.01919)
		(end 316.43066 -312.10504)
		(width 0.1651)
		(layer "In15.Cu")
		(net "P5E_PEX2_STN4_RX_DP<70>")
	)
	(segment
		(start 316.43066 -316.526164)
		(end 315.315854 -321.174364)
		(width 0.1651)
		(layer "In15.Cu")
		(net "P5E_PEX2_STN4_RX_DP<70>")
	)
	(segment
		(start 289.816794 -379.899164)
		(end 289.689794 -379.772164)
		(width 0.1651)
		(layer "In15.Cu")
		(net "P5E_PEX2_STN4_RX_DP<70>")
	)
	(segment
		(start 313.699906 -310.149748)
		(end 313.965336 -310.149748)
		(width 0.1143)
		(layer "In15.Cu")
		(net "P5E_PEX2_STN4_RX_DP<70>")
	)
	(segment
		(start 295.206674 -364.85703)
		(end 295.063164 -364.849664)
		(width 0.1651)
		(layer "In15.Cu")
		(net "P5E_PEX2_STN4_RX_DP<70>")
	)
	(segment
		(start 295.063164 -364.849664)
		(end 294.694864 -365.181388)
		(width 0.1651)
		(layer "In15.Cu")
		(net "P5E_PEX2_STN4_RX_DP<70>")
	)
	(segment
		(start 313.965336 -310.149748)
		(end 314.079636 -310.264048)
		(width 0.1143)
		(layer "In15.Cu")
		(net "P5E_PEX2_STN4_RX_DP<70>")
	)
	(segment
		(start 305.884326 -346.791788)
		(end 305.937412 -346.90558)
		(width 0.1651)
		(layer "In15.Cu")
		(net "P5E_PEX2_STN4_RX_DP<70>")
	)
	(segment
		(start 290.24707 -379.899164)
		(end 289.816794 -379.899164)
		(width 0.1651)
		(layer "In15.Cu")
		(net "P5E_PEX2_STN4_RX_DP<70>")
	)
	(segment
		(start 301.44339 -359.236264)
		(end 295.206674 -364.85703)
		(width 0.1651)
		(layer "In15.Cu")
		(net "P5E_PEX2_STN4_RX_DP<70>")
	)
	(segment
		(start 316.43066 -312.10504)
		(end 316.43066 -316.526164)
		(width 0.1651)
		(layer "In15.Cu")
		(net "P5E_PEX2_STN4_RX_DP<70>")
	)
	(segment
		(start 306.568094 -345.175078)
		(end 306.484528 -345.208352)
		(width 0.1651)
		(layer "In15.Cu")
		(net "P5E_PEX2_STN4_RX_DP<70>")
	)
	(segment
		(start 315.10986 -310.719978)
		(end 315.324744 -310.934862)
		(width 0.1143)
		(layer "In15.Cu")
		(net "P5E_PEX2_STN4_RX_DP<70>")
	)
	(segment
		(start 305.937412 -346.90558)
		(end 305.767994 -347.370908)
		(width 0.1651)
		(layer "In15.Cu")
		(net "P5E_PEX2_STN4_RX_DP<70>")
	)
	(segment
		(start 305.484276 -347.88983)
		(end 305.537362 -348.003622)
		(width 0.1651)
		(layer "In15.Cu")
		(net "P5E_PEX2_STN4_RX_DP<70>")
	)
	(segment
		(start 292.913562 -366.923574)
		(end 290.94303 -368.699542)
		(width 0.1651)
		(layer "In15.Cu")
		(net "P5E_PEX2_STN4_RX_DP<70>")
	)
	(segment
		(start 294.319706 -365.656368)
		(end 294.176196 -365.649002)
		(width 0.1651)
		(layer "In15.Cu")
		(net "P5E_PEX2_STN4_RX_DP<70>")
	)
	(segment
		(start 305.767994 -347.370908)
		(end 305.653948 -347.423994)
		(width 0.1651)
		(layer "In15.Cu")
		(net "P5E_PEX2_STN4_RX_DP<70>")
	)
	(segment
		(start 314.079636 -310.264048)
		(end 314.079636 -310.50484)
		(width 0.1143)
		(layer "In15.Cu")
		(net "P5E_PEX2_STN4_RX_DP<70>")
	)
	(segment
		(start 294.694864 -365.181388)
		(end 294.687498 -365.324898)
		(width 0.1651)
		(layer "In15.Cu")
		(net "P5E_PEX2_STN4_RX_DP<70>")
	)
	(segment
		(start 306.168044 -346.27312)
		(end 306.168298 -346.27312)
		(width 0.1651)
		(layer "In15.Cu")
		(net "P5E_PEX2_STN4_RX_DP<70>")
	)
	(segment
		(start 306.168298 -346.27312)
		(end 306.054252 -346.326206)
		(width 0.1651)
		(layer "In15.Cu")
		(net "P5E_PEX2_STN4_RX_DP<70>")
	)
	(segment
		(start 293.807896 -365.980726)
		(end 293.80053 -366.124236)
		(width 0.1651)
		(layer "In15.Cu")
		(net "P5E_PEX2_STN4_RX_DP<70>")
	)
	(segment
		(start 289.689794 -379.772164)
		(end 289.689794 -379.390148)
		(width 0.1651)
		(layer "In15.Cu")
		(net "P5E_PEX2_STN4_RX_DP<70>")
	)
	(segment
		(start 294.687498 -365.324898)
		(end 294.319706 -365.656368)
		(width 0.1651)
		(layer "In15.Cu")
		(net "P5E_PEX2_STN4_RX_DP<70>")
	)
	(segment
		(start 305.653948 -347.423994)
		(end 305.484276 -347.88983)
		(width 0.1651)
		(layer "In15.Cu")
		(net "P5E_PEX2_STN4_RX_DP<70>")
	)
	(segment
		(start 41.664128 -350.685354)
		(end 41.984168 -350.365314)
		(width 0.13462)
		(layer "F.Cu")
		(net "P5E_PEX0_STN4_TX_C_DN<69>")
	)
	(segment
		(start 41.664128 -351.316798)
		(end 41.664128 -350.685354)
		(width 0.13462)
		(layer "F.Cu")
		(net "P5E_PEX0_STN4_TX_C_DN<69>")
	)
	(segment
		(start 41.958768 -351.611438)
		(end 41.664128 -351.316798)
		(width 0.13462)
		(layer "F.Cu")
		(net "P5E_PEX0_STN4_TX_C_DN<69>")
	)
	(segment
		(start 32.889444 -371.281198)
		(end 33.571942 -370.5987)
		(width 0.1651)
		(layer "In11.Cu")
		(net "P5E_PEX0_STN4_TX_C_DN<69>")
	)
	(segment
		(start 32.31007 -371.790214)
		(end 32.31007 -371.408198)
		(width 0.1651)
		(layer "In11.Cu")
		(net "P5E_PEX0_STN4_TX_C_DN<69>")
	)
	(segment
		(start 41.667938 -351.902268)
		(end 41.958768 -351.611438)
		(width 0.1651)
		(layer "In11.Cu")
		(net "P5E_PEX0_STN4_TX_C_DN<69>")
	)
	(segment
		(start 32.31007 -371.408198)
		(end 32.43707 -371.281198)
		(width 0.1651)
		(layer "In11.Cu")
		(net "P5E_PEX0_STN4_TX_C_DN<69>")
	)
	(segment
		(start 34.036 -367.953036)
		(end 40.113458 -358.85755)
		(width 0.1651)
		(layer "In11.Cu")
		(net "P5E_PEX0_STN4_TX_C_DN<69>")
	)
	(segment
		(start 40.113458 -358.85755)
		(end 40.113458 -354.092002)
		(width 0.1651)
		(layer "In11.Cu")
		(net "P5E_PEX0_STN4_TX_C_DN<69>")
	)
	(segment
		(start 33.571942 -369.481862)
		(end 34.036 -367.953036)
		(width 0.1651)
		(layer "In11.Cu")
		(net "P5E_PEX0_STN4_TX_C_DN<69>")
	)
	(segment
		(start 32.43707 -371.281198)
		(end 32.889444 -371.281198)
		(width 0.1651)
		(layer "In11.Cu")
		(net "P5E_PEX0_STN4_TX_C_DN<69>")
	)
	(segment
		(start 40.113458 -354.092002)
		(end 41.667938 -352.537522)
		(width 0.1651)
		(layer "In11.Cu")
		(net "P5E_PEX0_STN4_TX_C_DN<69>")
	)
	(segment
		(start 41.667938 -352.537522)
		(end 41.667938 -351.902268)
		(width 0.1651)
		(layer "In11.Cu")
		(net "P5E_PEX0_STN4_TX_C_DN<69>")
	)
	(segment
		(start 33.571942 -370.5987)
		(end 33.571942 -369.481862)
		(width 0.1651)
		(layer "In11.Cu")
		(net "P5E_PEX0_STN4_TX_C_DN<69>")
	)
	(segment
		(start 22.736048 -348.88043)
		(end 22.441408 -348.58579)
		(width 0.13462)
		(layer "F.Cu")
		(net "P5E_PEX0_STN4_TX_DP<78>")
	)
	(segment
		(start 22.416008 -349.831914)
		(end 22.736048 -349.511874)
		(width 0.13462)
		(layer "F.Cu")
		(net "P5E_PEX0_STN4_TX_DP<78>")
	)
	(segment
		(start 22.736048 -349.511874)
		(end 22.736048 -348.88043)
		(width 0.13462)
		(layer "F.Cu")
		(net "P5E_PEX0_STN4_TX_DP<78>")
	)
	(segment
		(start 40.073834 -330.76007)
		(end 46.369478 -328.507598)
		(width 0.1651)
		(layer "In11.Cu")
		(net "P5E_PEX0_STN4_TX_DP<78>")
	)
	(segment
		(start 74.76109 -313.379612)
		(end 74.84999 -313.290712)
		(width 0.1143)
		(layer "In11.Cu")
		(net "P5E_PEX0_STN4_TX_DP<78>")
	)
	(segment
		(start 74.27976 -313.656218)
		(end 74.556366 -313.379612)
		(width 0.1143)
		(layer "In11.Cu")
		(net "P5E_PEX0_STN4_TX_DP<78>")
	)
	(segment
		(start 74.556366 -313.379612)
		(end 74.76109 -313.379612)
		(width 0.1143)
		(layer "In11.Cu")
		(net "P5E_PEX0_STN4_TX_DP<78>")
	)
	(segment
		(start 22.732238 -347.620082)
		(end 24.286718 -346.065602)
		(width 0.1651)
		(layer "In11.Cu")
		(net "P5E_PEX0_STN4_TX_DP<78>")
	)
	(segment
		(start 74.27976 -320.219832)
		(end 74.27976 -313.656218)
		(width 0.1143)
		(layer "In11.Cu")
		(net "P5E_PEX0_STN4_TX_DP<78>")
	)
	(segment
		(start 25.407874 -338.599272)
		(end 40.073834 -330.76007)
		(width 0.1651)
		(layer "In11.Cu")
		(net "P5E_PEX0_STN4_TX_DP<78>")
	)
	(segment
		(start 74.23404 -320.265552)
		(end 74.27976 -320.219832)
		(width 0.1143)
		(layer "In11.Cu")
		(net "P5E_PEX0_STN4_TX_DP<78>")
	)
	(segment
		(start 74.23404 -320.802762)
		(end 74.23404 -320.294)
		(width 0.1651)
		(layer "In11.Cu")
		(net "P5E_PEX0_STN4_TX_DP<78>")
	)
	(segment
		(start 74.84999 -313.290712)
		(end 74.84999 -312.999882)
		(width 0.1143)
		(layer "In11.Cu")
		(net "P5E_PEX0_STN4_TX_DP<78>")
	)
	(segment
		(start 74.23404 -320.294)
		(end 74.23404 -320.265552)
		(width 0.1143)
		(layer "In11.Cu")
		(net "P5E_PEX0_STN4_TX_DP<78>")
	)
	(segment
		(start 52.665884 -326.254618)
		(end 72.943466 -322.221606)
		(width 0.1651)
		(layer "In11.Cu")
		(net "P5E_PEX0_STN4_TX_DP<78>")
	)
	(segment
		(start 73.846182 -321.739006)
		(end 74.23404 -320.802762)
		(width 0.1651)
		(layer "In11.Cu")
		(net "P5E_PEX0_STN4_TX_DP<78>")
	)
	(segment
		(start 46.369478 -328.507598)
		(end 46.369986 -328.507344)
		(width 0.1651)
		(layer "In11.Cu")
		(net "P5E_PEX0_STN4_TX_DP<78>")
	)
	(segment
		(start 22.441408 -348.58579)
		(end 22.732238 -348.29496)
		(width 0.1651)
		(layer "In11.Cu")
		(net "P5E_PEX0_STN4_TX_DP<78>")
	)
	(segment
		(start 72.943466 -322.221606)
		(end 73.846182 -321.739006)
		(width 0.1651)
		(layer "In11.Cu")
		(net "P5E_PEX0_STN4_TX_DP<78>")
	)
	(segment
		(start 24.286718 -339.720682)
		(end 25.407874 -338.599272)
		(width 0.1651)
		(layer "In11.Cu")
		(net "P5E_PEX0_STN4_TX_DP<78>")
	)
	(segment
		(start 22.732238 -348.29496)
		(end 22.732238 -347.620082)
		(width 0.1651)
		(layer "In11.Cu")
		(net "P5E_PEX0_STN4_TX_DP<78>")
	)
	(segment
		(start 46.369986 -328.507344)
		(end 52.665884 -326.254618)
		(width 0.1651)
		(layer "In11.Cu")
		(net "P5E_PEX0_STN4_TX_DP<78>")
	)
	(segment
		(start 24.286718 -346.065602)
		(end 24.286718 -339.720682)
		(width 0.1651)
		(layer "In11.Cu")
		(net "P5E_PEX0_STN4_TX_DP<78>")
	)
	(segment
		(start 306.715922 -319.941448)
		(end 306.715922 -319.913)
		(width 0.1143)
		(layer "In15.Cu")
		(net "P5E_PEX2_STN4_RX_DN<78>")
	)
	(segment
		(start 306.773834 -318.320166)
		(end 306.935632 -318.320166)
		(width 0.1143)
		(layer "In15.Cu")
		(net "P5E_PEX2_STN4_RX_DN<78>")
	)
	(segment
		(start 290.815776 -405.729186)
		(end 290.815776 -396.494)
		(width 0.1651)
		(layer "In15.Cu")
		(net "P5E_PEX2_STN4_RX_DN<78>")
	)
	(segment
		(start 281.856434 -389.064754)
		(end 280.511504 -385.8133)
		(width 0.1651)
		(layer "In15.Cu")
		(net "P5E_PEX2_STN4_RX_DN<78>")
	)
	(segment
		(start 290.815776 -396.494)
		(end 290.5252 -395.5034)
		(width 0.1651)
		(layer "In15.Cu")
		(net "P5E_PEX2_STN4_RX_DN<78>")
	)
	(segment
		(start 306.715922 -321.629278)
		(end 306.715922 -319.941448)
		(width 0.1651)
		(layer "In15.Cu")
		(net "P5E_PEX2_STN4_RX_DN<78>")
	)
	(segment
		(start 306.935632 -318.320166)
		(end 307.049932 -318.434466)
		(width 0.1143)
		(layer "In15.Cu")
		(net "P5E_PEX2_STN4_RX_DN<78>")
	)
	(segment
		(start 289.689794 -406.690068)
		(end 289.689794 -406.308052)
		(width 0.1651)
		(layer "In15.Cu")
		(net "P5E_PEX2_STN4_RX_DN<78>")
	)
	(segment
		(start 307.049932 -318.434466)
		(end 307.049932 -318.699896)
		(width 0.1143)
		(layer "In15.Cu")
		(net "P5E_PEX2_STN4_RX_DN<78>")
	)
	(segment
		(start 279.616916 -341.350346)
		(end 279.8826 -341.0204)
		(width 0.1651)
		(layer "In15.Cu")
		(net "P5E_PEX2_STN4_RX_DN<78>")
	)
	(segment
		(start 280.511504 -385.8133)
		(end 279.351232 -359.394252)
		(width 0.1651)
		(layer "In15.Cu")
		(net "P5E_PEX2_STN4_RX_DN<78>")
	)
	(segment
		(start 289.3568 -394.0048)
		(end 287.680654 -392.684)
		(width 0.1651)
		(layer "In15.Cu")
		(net "P5E_PEX2_STN4_RX_DN<78>")
	)
	(segment
		(start 306.715922 -319.913)
		(end 306.670202 -319.86728)
		(width 0.1143)
		(layer "In15.Cu")
		(net "P5E_PEX2_STN4_RX_DN<78>")
	)
	(segment
		(start 279.616916 -341.3506)
		(end 279.616916 -341.350346)
		(width 0.1651)
		(layer "In15.Cu")
		(net "P5E_PEX2_STN4_RX_DN<78>")
	)
	(segment
		(start 279.351232 -341.6808)
		(end 279.616916 -341.3506)
		(width 0.1651)
		(layer "In15.Cu")
		(net "P5E_PEX2_STN4_RX_DN<78>")
	)
	(segment
		(start 279.8826 -341.0204)
		(end 305.78044 -322.565014)
		(width 0.1651)
		(layer "In15.Cu")
		(net "P5E_PEX2_STN4_RX_DN<78>")
	)
	(segment
		(start 290.5252 -395.5034)
		(end 289.3568 -394.0048)
		(width 0.1651)
		(layer "In15.Cu")
		(net "P5E_PEX2_STN4_RX_DN<78>")
	)
	(segment
		(start 289.689794 -406.308052)
		(end 289.816794 -406.181052)
		(width 0.1651)
		(layer "In15.Cu")
		(net "P5E_PEX2_STN4_RX_DN<78>")
	)
	(segment
		(start 306.670202 -319.86728)
		(end 306.670202 -318.423798)
		(width 0.1143)
		(layer "In15.Cu")
		(net "P5E_PEX2_STN4_RX_DN<78>")
	)
	(segment
		(start 279.351232 -359.394252)
		(end 279.351232 -341.6808)
		(width 0.1651)
		(layer "In15.Cu")
		(net "P5E_PEX2_STN4_RX_DN<78>")
	)
	(segment
		(start 289.816794 -406.181052)
		(end 290.36391 -406.181052)
		(width 0.1651)
		(layer "In15.Cu")
		(net "P5E_PEX2_STN4_RX_DN<78>")
	)
	(segment
		(start 285.16834 -391.555986)
		(end 281.856434 -389.064754)
		(width 0.1651)
		(layer "In15.Cu")
		(net "P5E_PEX2_STN4_RX_DN<78>")
	)
	(segment
		(start 305.78044 -322.565014)
		(end 306.715922 -321.629278)
		(width 0.1651)
		(layer "In15.Cu")
		(net "P5E_PEX2_STN4_RX_DN<78>")
	)
	(segment
		(start 306.670202 -318.423798)
		(end 306.773834 -318.320166)
		(width 0.1143)
		(layer "In15.Cu")
		(net "P5E_PEX2_STN4_RX_DN<78>")
	)
	(segment
		(start 290.36391 -406.181052)
		(end 290.815776 -405.729186)
		(width 0.1651)
		(layer "In15.Cu")
		(net "P5E_PEX2_STN4_RX_DN<78>")
	)
	(segment
		(start 287.680654 -392.684)
		(end 285.16834 -391.555986)
		(width 0.1651)
		(layer "In15.Cu")
		(net "P5E_PEX2_STN4_RX_DN<78>")
	)
	(segment
		(start 32.062928 -344.539062)
		(end 31.742888 -344.219022)
		(width 0.13462)
		(layer "F.Cu")
		(net "P5E_PEX0_STN4_TX_C_DP<74>")
	)
	(segment
		(start 31.768288 -345.465146)
		(end 32.062928 -345.170506)
		(width 0.13462)
		(layer "F.Cu")
		(net "P5E_PEX0_STN4_TX_C_DP<74>")
	)
	(segment
		(start 32.062928 -345.170506)
		(end 32.062928 -344.539062)
		(width 0.13462)
		(layer "F.Cu")
		(net "P5E_PEX0_STN4_TX_C_DP<74>")
	)
	(segment
		(start 24.689562 -369.209574)
		(end 25.809448 -365.518954)
		(width 0.1651)
		(layer "In11.Cu")
		(net "P5E_PEX0_STN4_TX_C_DP<74>")
	)
	(segment
		(start 24.489156 -384.08102)
		(end 24.489156 -381.642366)
		(width 0.1651)
		(layer "In11.Cu")
		(net "P5E_PEX0_STN4_TX_C_DP<74>")
	)
	(segment
		(start 26.614628 -387.532626)
		(end 25.42667 -386.344668)
		(width 0.1651)
		(layer "In11.Cu")
		(net "P5E_PEX0_STN4_TX_C_DP<74>")
	)
	(segment
		(start 39.037006 -398.09928)
		(end 39.460424 -398.09928)
		(width 0.1651)
		(layer "In11.Cu")
		(net "P5E_PEX0_STN4_TX_C_DP<74>")
	)
	(segment
		(start 36.935918 -392.93038)
		(end 36.911534 -392.80719)
		(width 0.1651)
		(layer "In11.Cu")
		(net "P5E_PEX0_STN4_TX_C_DP<74>")
	)
	(segment
		(start 30.504638 -358.492298)
		(end 30.504638 -347.876622)
		(width 0.1651)
		(layer "In11.Cu")
		(net "P5E_PEX0_STN4_TX_C_DP<74>")
	)
	(segment
		(start 25.809448 -365.518954)
		(end 30.504638 -358.492298)
		(width 0.1651)
		(layer "In11.Cu")
		(net "P5E_PEX0_STN4_TX_C_DP<74>")
	)
	(segment
		(start 39.278814 -394.389102)
		(end 38.4429 -393.830556)
		(width 0.1651)
		(layer "In11.Cu")
		(net "P5E_PEX0_STN4_TX_C_DP<74>")
	)
	(segment
		(start 37.883084 -393.456414)
		(end 37.47135 -393.181332)
		(width 0.1651)
		(layer "In11.Cu")
		(net "P5E_PEX0_STN4_TX_C_DP<74>")
	)
	(segment
		(start 30.504638 -347.876622)
		(end 32.059118 -346.322142)
		(width 0.1651)
		(layer "In11.Cu")
		(net "P5E_PEX0_STN4_TX_C_DP<74>")
	)
	(segment
		(start 37.34816 -393.20597)
		(end 36.935918 -392.93038)
		(width 0.1651)
		(layer "In11.Cu")
		(net "P5E_PEX0_STN4_TX_C_DP<74>")
	)
	(segment
		(start 24.489156 -381.642366)
		(end 24.689562 -369.209574)
		(width 0.1651)
		(layer "In11.Cu")
		(net "P5E_PEX0_STN4_TX_C_DP<74>")
	)
	(segment
		(start 32.93618 -390.151112)
		(end 26.614628 -387.532626)
		(width 0.1651)
		(layer "In11.Cu")
		(net "P5E_PEX0_STN4_TX_C_DP<74>")
	)
	(segment
		(start 32.059118 -345.755976)
		(end 31.768288 -345.465146)
		(width 0.1651)
		(layer "In11.Cu")
		(net "P5E_PEX0_STN4_TX_C_DP<74>")
	)
	(segment
		(start 32.059118 -346.322142)
		(end 32.059118 -345.755976)
		(width 0.1651)
		(layer "In11.Cu")
		(net "P5E_PEX0_STN4_TX_C_DP<74>")
	)
	(segment
		(start 38.910006 -397.97228)
		(end 39.037006 -398.09928)
		(width 0.1651)
		(layer "In11.Cu")
		(net "P5E_PEX0_STN4_TX_C_DP<74>")
	)
	(segment
		(start 39.460424 -398.09928)
		(end 39.802308 -397.757396)
		(width 0.1651)
		(layer "In11.Cu")
		(net "P5E_PEX0_STN4_TX_C_DP<74>")
	)
	(segment
		(start 36.911534 -392.80719)
		(end 32.93618 -390.151112)
		(width 0.1651)
		(layer "In11.Cu")
		(net "P5E_PEX0_STN4_TX_C_DP<74>")
	)
	(segment
		(start 39.802308 -397.757396)
		(end 39.802308 -394.912596)
		(width 0.1651)
		(layer "In11.Cu")
		(net "P5E_PEX0_STN4_TX_C_DP<74>")
	)
	(segment
		(start 39.802308 -394.912596)
		(end 39.278814 -394.389102)
		(width 0.1651)
		(layer "In11.Cu")
		(net "P5E_PEX0_STN4_TX_C_DP<74>")
	)
	(segment
		(start 38.4429 -393.830556)
		(end 38.31971 -393.855194)
		(width 0.1651)
		(layer "In11.Cu")
		(net "P5E_PEX0_STN4_TX_C_DP<74>")
	)
	(segment
		(start 37.907468 -393.579858)
		(end 37.883084 -393.456414)
		(width 0.1651)
		(layer "In11.Cu")
		(net "P5E_PEX0_STN4_TX_C_DP<74>")
	)
	(segment
		(start 37.47135 -393.181332)
		(end 37.34816 -393.20597)
		(width 0.1651)
		(layer "In11.Cu")
		(net "P5E_PEX0_STN4_TX_C_DP<74>")
	)
	(segment
		(start 38.31971 -393.855194)
		(end 37.907468 -393.579858)
		(width 0.1651)
		(layer "In11.Cu")
		(net "P5E_PEX0_STN4_TX_C_DP<74>")
	)
	(segment
		(start 25.42667 -386.344668)
		(end 24.489156 -384.08102)
		(width 0.1651)
		(layer "In11.Cu")
		(net "P5E_PEX0_STN4_TX_C_DP<74>")
	)
	(segment
		(start 38.910006 -397.59001)
		(end 38.910006 -397.97228)
		(width 0.1651)
		(layer "In11.Cu")
		(net "P5E_PEX0_STN4_TX_C_DP<74>")
	)
	(segment
		(start 270.980662 -350.365314)
		(end 271.300702 -350.685354)
		(width 0.13462)
		(layer "F.Cu")
		(net "P5E_PEX2_STN4_TX_C_DP<78>")
	)
	(segment
		(start 271.300702 -351.316798)
		(end 271.006062 -351.611438)
		(width 0.13462)
		(layer "F.Cu")
		(net "P5E_PEX2_STN4_TX_C_DP<78>")
	)
	(segment
		(start 271.300702 -350.685354)
		(end 271.300702 -351.316798)
		(width 0.13462)
		(layer "F.Cu")
		(net "P5E_PEX2_STN4_TX_C_DP<78>")
	)
	(segment
		(start 290.254944 -395.473428)
		(end 290.533836 -395.882622)
		(width 0.1651)
		(layer "In11.Cu")
		(net "P5E_PEX2_STN4_TX_C_DP<78>")
	)
	(segment
		(start 290.096194 -395.443456)
		(end 290.254944 -395.473428)
		(width 0.1651)
		(layer "In11.Cu")
		(net "P5E_PEX2_STN4_TX_C_DP<78>")
	)
	(segment
		(start 286.154622 -392.630406)
		(end 286.61233 -392.820144)
		(width 0.1651)
		(layer "In11.Cu")
		(net "P5E_PEX2_STN4_TX_C_DP<78>")
	)
	(segment
		(start 271.006062 -351.611438)
		(end 271.296892 -351.902268)
		(width 0.1651)
		(layer "In11.Cu")
		(net "P5E_PEX2_STN4_TX_C_DP<78>")
	)
	(segment
		(start 277.769828 -375.783348)
		(end 277.732744 -375.88444)
		(width 0.1651)
		(layer "In11.Cu")
		(net "P5E_PEX2_STN4_TX_C_DP<78>")
	)
	(segment
		(start 287.219136 -392.947906)
		(end 287.280858 -393.097512)
		(width 0.1651)
		(layer "In11.Cu")
		(net "P5E_PEX2_STN4_TX_C_DP<78>")
	)
	(segment
		(start 286.761682 -392.758168)
		(end 287.219136 -392.947906)
		(width 0.1651)
		(layer "In11.Cu")
		(net "P5E_PEX2_STN4_TX_C_DP<78>")
	)
	(segment
		(start 290.533836 -395.882622)
		(end 290.533836 -397.812514)
		(width 0.1651)
		(layer "In11.Cu")
		(net "P5E_PEX2_STN4_TX_C_DP<78>")
	)
	(segment
		(start 289.816794 -398.09928)
		(end 289.689794 -397.97228)
		(width 0.1651)
		(layer "In11.Cu")
		(net "P5E_PEX2_STN4_TX_C_DP<78>")
	)
	(segment
		(start 278.214582 -376.921014)
		(end 278.423624 -377.370594)
		(width 0.1651)
		(layer "In11.Cu")
		(net "P5E_PEX2_STN4_TX_C_DP<78>")
	)
	(segment
		(start 285.635446 -392.291062)
		(end 286.0929 -392.4808)
		(width 0.1651)
		(layer "In11.Cu")
		(net "P5E_PEX2_STN4_TX_C_DP<78>")
	)
	(segment
		(start 271.296892 -352.356166)
		(end 269.742412 -353.910646)
		(width 0.1651)
		(layer "In11.Cu")
		(net "P5E_PEX2_STN4_TX_C_DP<78>")
	)
	(segment
		(start 284.50921 -391.823702)
		(end 284.966664 -392.01344)
		(width 0.1651)
		(layer "In11.Cu")
		(net "P5E_PEX2_STN4_TX_C_DP<78>")
	)
	(segment
		(start 290.533836 -397.812514)
		(end 290.24707 -398.09928)
		(width 0.1651)
		(layer "In11.Cu")
		(net "P5E_PEX2_STN4_TX_C_DP<78>")
	)
	(segment
		(start 278.043132 -376.37085)
		(end 278.251666 -376.819922)
		(width 0.1651)
		(layer "In11.Cu")
		(net "P5E_PEX2_STN4_TX_C_DP<78>")
	)
	(segment
		(start 269.742412 -358.51084)
		(end 277.769828 -375.783348)
		(width 0.1651)
		(layer "In11.Cu")
		(net "P5E_PEX2_STN4_TX_C_DP<78>")
	)
	(segment
		(start 280.30932 -386.511292)
		(end 281.610562 -389.075676)
		(width 0.1651)
		(layer "In11.Cu")
		(net "P5E_PEX2_STN4_TX_C_DP<78>")
	)
	(segment
		(start 287.887918 -393.225274)
		(end 289.052 -393.708128)
		(width 0.1651)
		(layer "In11.Cu")
		(net "P5E_PEX2_STN4_TX_C_DP<78>")
	)
	(segment
		(start 289.689794 -397.97228)
		(end 289.689794 -397.59001)
		(width 0.1651)
		(layer "In11.Cu")
		(net "P5E_PEX2_STN4_TX_C_DP<78>")
	)
	(segment
		(start 285.028386 -392.163046)
		(end 285.486094 -392.352784)
		(width 0.1651)
		(layer "In11.Cu")
		(net "P5E_PEX2_STN4_TX_C_DP<78>")
	)
	(segment
		(start 269.742412 -353.910646)
		(end 269.742412 -358.51084)
		(width 0.1651)
		(layer "In11.Cu")
		(net "P5E_PEX2_STN4_TX_C_DP<78>")
	)
	(segment
		(start 289.817048 -395.033754)
		(end 290.096194 -395.443456)
		(width 0.1651)
		(layer "In11.Cu")
		(net "P5E_PEX2_STN4_TX_C_DP<78>")
	)
	(segment
		(start 278.524716 -377.407424)
		(end 279.35174 -379.186948)
		(width 0.1651)
		(layer "In11.Cu")
		(net "P5E_PEX2_STN4_TX_C_DP<78>")
	)
	(segment
		(start 289.052 -393.708128)
		(end 289.84702 -394.875004)
		(width 0.1651)
		(layer "In11.Cu")
		(net "P5E_PEX2_STN4_TX_C_DP<78>")
	)
	(segment
		(start 278.423624 -377.370594)
		(end 278.524716 -377.407424)
		(width 0.1651)
		(layer "In11.Cu")
		(net "P5E_PEX2_STN4_TX_C_DP<78>")
	)
	(segment
		(start 287.280858 -393.097512)
		(end 287.738566 -393.28725)
		(width 0.1651)
		(layer "In11.Cu")
		(net "P5E_PEX2_STN4_TX_C_DP<78>")
	)
	(segment
		(start 271.296892 -351.902268)
		(end 271.296892 -352.356166)
		(width 0.1651)
		(layer "In11.Cu")
		(net "P5E_PEX2_STN4_TX_C_DP<78>")
	)
	(segment
		(start 279.35174 -379.186948)
		(end 280.30932 -386.511292)
		(width 0.1651)
		(layer "In11.Cu")
		(net "P5E_PEX2_STN4_TX_C_DP<78>")
	)
	(segment
		(start 289.84702 -394.875004)
		(end 289.817048 -395.033754)
		(width 0.1651)
		(layer "In11.Cu")
		(net "P5E_PEX2_STN4_TX_C_DP<78>")
	)
	(segment
		(start 277.941786 -376.33402)
		(end 278.043132 -376.37085)
		(width 0.1651)
		(layer "In11.Cu")
		(net "P5E_PEX2_STN4_TX_C_DP<78>")
	)
	(segment
		(start 277.732744 -375.88444)
		(end 277.941786 -376.33402)
		(width 0.1651)
		(layer "In11.Cu")
		(net "P5E_PEX2_STN4_TX_C_DP<78>")
	)
	(segment
		(start 281.610562 -389.075676)
		(end 284.50921 -391.823702)
		(width 0.1651)
		(layer "In11.Cu")
		(net "P5E_PEX2_STN4_TX_C_DP<78>")
	)
	(segment
		(start 278.251666 -376.819922)
		(end 278.214582 -376.921014)
		(width 0.1651)
		(layer "In11.Cu")
		(net "P5E_PEX2_STN4_TX_C_DP<78>")
	)
	(segment
		(start 286.0929 -392.4808)
		(end 286.154622 -392.630406)
		(width 0.1651)
		(layer "In11.Cu")
		(net "P5E_PEX2_STN4_TX_C_DP<78>")
	)
	(segment
		(start 284.966664 -392.01344)
		(end 285.028386 -392.163046)
		(width 0.1651)
		(layer "In11.Cu")
		(net "P5E_PEX2_STN4_TX_C_DP<78>")
	)
	(segment
		(start 290.24707 -398.09928)
		(end 289.816794 -398.09928)
		(width 0.1651)
		(layer "In11.Cu")
		(net "P5E_PEX2_STN4_TX_C_DP<78>")
	)
	(segment
		(start 286.61233 -392.820144)
		(end 286.761682 -392.758168)
		(width 0.1651)
		(layer "In11.Cu")
		(net "P5E_PEX2_STN4_TX_C_DP<78>")
	)
	(segment
		(start 287.738566 -393.28725)
		(end 287.887918 -393.225274)
		(width 0.1651)
		(layer "In11.Cu")
		(net "P5E_PEX2_STN4_TX_C_DP<78>")
	)
	(segment
		(start 285.486094 -392.352784)
		(end 285.635446 -392.291062)
		(width 0.1651)
		(layer "In11.Cu")
		(net "P5E_PEX2_STN4_TX_C_DP<78>")
	)
	(segment
		(start 35.365436 -393.527788)
		(end 34.957512 -393.26947)
		(width 0.1651)
		(layer "In15.Cu")
		(net "P5E_PEX0_STN4_RX_DP<75>")
	)
	(segment
		(start 77.355446 -316.229492)
		(end 77.58557 -316.229492)
		(width 0.1143)
		(layer "In15.Cu")
		(net "P5E_PEX0_STN4_RX_DP<75>")
	)
	(segment
		(start 36.837112 -404.799038)
		(end 37.0586 -404.799038)
		(width 0.1651)
		(layer "In15.Cu")
		(net "P5E_PEX0_STN4_RX_DP<75>")
	)
	(segment
		(start 37.585904 -404.271734)
		(end 37.585904 -395.148308)
		(width 0.1651)
		(layer "In15.Cu")
		(net "P5E_PEX0_STN4_RX_DP<75>")
	)
	(segment
		(start 23.044404 -379.72238)
		(end 23.020782 -379.240034)
		(width 0.1651)
		(layer "In15.Cu")
		(net "P5E_PEX0_STN4_RX_DP<75>")
	)
	(segment
		(start 28.203144 -338.16544)
		(end 33.85439 -336.064606)
		(width 0.1651)
		(layer "In15.Cu")
		(net "P5E_PEX0_STN4_RX_DP<75>")
	)
	(segment
		(start 24.200104 -386.777484)
		(end 23.38324 -384.805428)
		(width 0.1651)
		(layer "In15.Cu")
		(net "P5E_PEX0_STN4_RX_DP<75>")
	)
	(segment
		(start 37.0586 -404.799038)
		(end 37.585904 -404.271734)
		(width 0.1651)
		(layer "In15.Cu")
		(net "P5E_PEX0_STN4_RX_DP<75>")
	)
	(segment
		(start 36.710112 -404.672038)
		(end 36.837112 -404.799038)
		(width 0.1651)
		(layer "In15.Cu")
		(net "P5E_PEX0_STN4_RX_DP<75>")
	)
	(segment
		(start 35.92322 -393.881102)
		(end 35.895788 -393.75842)
		(width 0.1651)
		(layer "In15.Cu")
		(net "P5E_PEX0_STN4_RX_DP<75>")
	)
	(segment
		(start 37.585904 -395.148308)
		(end 37.34943 -394.67917)
		(width 0.1651)
		(layer "In15.Cu")
		(net "P5E_PEX0_STN4_RX_DP<75>")
	)
	(segment
		(start 34.93008 -393.146788)
		(end 33.937448 -392.518138)
		(width 0.1651)
		(layer "In15.Cu")
		(net "P5E_PEX0_STN4_RX_DP<75>")
	)
	(segment
		(start 77.69987 -316.115192)
		(end 77.69987 -315.849762)
		(width 0.1143)
		(layer "In15.Cu")
		(net "P5E_PEX0_STN4_RX_DP<75>")
	)
	(segment
		(start 21.532596 -341.332058)
		(end 21.90877 -340.955884)
		(width 0.1651)
		(layer "In15.Cu")
		(net "P5E_PEX0_STN4_RX_DP<75>")
	)
	(segment
		(start 77.12964 -316.455298)
		(end 77.355446 -316.229492)
		(width 0.1143)
		(layer "In15.Cu")
		(net "P5E_PEX0_STN4_RX_DP<75>")
	)
	(segment
		(start 23.38324 -384.805428)
		(end 23.137876 -379.806708)
		(width 0.1651)
		(layer "In15.Cu")
		(net "P5E_PEX0_STN4_RX_DP<75>")
	)
	(segment
		(start 21.177758 -358.368092)
		(end 21.177758 -342.1888)
		(width 0.1651)
		(layer "In15.Cu")
		(net "P5E_PEX0_STN4_RX_DP<75>")
	)
	(segment
		(start 35.488118 -393.500356)
		(end 35.365436 -393.527788)
		(width 0.1651)
		(layer "In15.Cu")
		(net "P5E_PEX0_STN4_RX_DP<75>")
	)
	(segment
		(start 21.90877 -340.955884)
		(end 28.203144 -338.16544)
		(width 0.1651)
		(layer "In15.Cu")
		(net "P5E_PEX0_STN4_RX_DP<75>")
	)
	(segment
		(start 34.957512 -393.26947)
		(end 34.93008 -393.146788)
		(width 0.1651)
		(layer "In15.Cu")
		(net "P5E_PEX0_STN4_RX_DP<75>")
	)
	(segment
		(start 77.58557 -316.229492)
		(end 77.69987 -316.115192)
		(width 0.1143)
		(layer "In15.Cu")
		(net "P5E_PEX0_STN4_RX_DP<75>")
	)
	(segment
		(start 27.694128 -389.448802)
		(end 25.213818 -387.791198)
		(width 0.1651)
		(layer "In15.Cu")
		(net "P5E_PEX0_STN4_RX_DP<75>")
	)
	(segment
		(start 25.213818 -387.791198)
		(end 24.200104 -386.777484)
		(width 0.1651)
		(layer "In15.Cu")
		(net "P5E_PEX0_STN4_RX_DP<75>")
	)
	(segment
		(start 37.34943 -394.67917)
		(end 36.453826 -394.111988)
		(width 0.1651)
		(layer "In15.Cu")
		(net "P5E_PEX0_STN4_RX_DP<75>")
	)
	(segment
		(start 22.987 -376.73915)
		(end 21.177758 -358.368092)
		(width 0.1651)
		(layer "In15.Cu")
		(net "P5E_PEX0_STN4_RX_DP<75>")
	)
	(segment
		(start 36.331144 -394.13942)
		(end 35.92322 -393.881102)
		(width 0.1651)
		(layer "In15.Cu")
		(net "P5E_PEX0_STN4_RX_DP<75>")
	)
	(segment
		(start 33.85439 -336.064606)
		(end 41.617138 -333.709772)
		(width 0.1651)
		(layer "In15.Cu")
		(net "P5E_PEX0_STN4_RX_DP<75>")
	)
	(segment
		(start 54.940454 -330.372466)
		(end 54.940708 -330.372466)
		(width 0.1651)
		(layer "In15.Cu")
		(net "P5E_PEX0_STN4_RX_DP<75>")
	)
	(segment
		(start 77.08392 -319.916048)
		(end 77.08392 -319.8876)
		(width 0.1143)
		(layer "In15.Cu")
		(net "P5E_PEX0_STN4_RX_DP<75>")
	)
	(segment
		(start 33.937448 -392.518138)
		(end 29.919168 -390.370314)
		(width 0.1651)
		(layer "In15.Cu")
		(net "P5E_PEX0_STN4_RX_DP<75>")
	)
	(segment
		(start 35.895788 -393.75842)
		(end 35.488118 -393.500356)
		(width 0.1651)
		(layer "In15.Cu")
		(net "P5E_PEX0_STN4_RX_DP<75>")
	)
	(segment
		(start 23.10511 -379.14707)
		(end 22.987 -376.73915)
		(width 0.1651)
		(layer "In15.Cu")
		(net "P5E_PEX0_STN4_RX_DP<75>")
	)
	(segment
		(start 36.453826 -394.111988)
		(end 36.331144 -394.13942)
		(width 0.1651)
		(layer "In15.Cu")
		(net "P5E_PEX0_STN4_RX_DP<75>")
	)
	(segment
		(start 75.667362 -323.968618)
		(end 77.08392 -322.55206)
		(width 0.1651)
		(layer "In15.Cu")
		(net "P5E_PEX0_STN4_RX_DP<75>")
	)
	(segment
		(start 36.710112 -404.290022)
		(end 36.710112 -404.672038)
		(width 0.1651)
		(layer "In15.Cu")
		(net "P5E_PEX0_STN4_RX_DP<75>")
	)
	(segment
		(start 77.08392 -322.55206)
		(end 77.08392 -319.916048)
		(width 0.1651)
		(layer "In15.Cu")
		(net "P5E_PEX0_STN4_RX_DP<75>")
	)
	(segment
		(start 29.919168 -390.370314)
		(end 27.694128 -389.448802)
		(width 0.1651)
		(layer "In15.Cu")
		(net "P5E_PEX0_STN4_RX_DP<75>")
	)
	(segment
		(start 77.08392 -319.8876)
		(end 77.12964 -319.84188)
		(width 0.1143)
		(layer "In15.Cu")
		(net "P5E_PEX0_STN4_RX_DP<75>")
	)
	(segment
		(start 23.137876 -379.806708)
		(end 23.044404 -379.72238)
		(width 0.1651)
		(layer "In15.Cu")
		(net "P5E_PEX0_STN4_RX_DP<75>")
	)
	(segment
		(start 21.177758 -342.1888)
		(end 21.532596 -341.332058)
		(width 0.1651)
		(layer "In15.Cu")
		(net "P5E_PEX0_STN4_RX_DP<75>")
	)
	(segment
		(start 77.12964 -319.84188)
		(end 77.12964 -316.455298)
		(width 0.1143)
		(layer "In15.Cu")
		(net "P5E_PEX0_STN4_RX_DP<75>")
	)
	(segment
		(start 23.020782 -379.240034)
		(end 23.10511 -379.14707)
		(width 0.1651)
		(layer "In15.Cu")
		(net "P5E_PEX0_STN4_RX_DP<75>")
	)
	(segment
		(start 54.940708 -330.372466)
		(end 68.263516 -327.03516)
		(width 0.1651)
		(layer "In15.Cu")
		(net "P5E_PEX0_STN4_RX_DP<75>")
	)
	(segment
		(start 68.263516 -327.03516)
		(end 75.667362 -323.968618)
		(width 0.1651)
		(layer "In15.Cu")
		(net "P5E_PEX0_STN4_RX_DP<75>")
	)
	(segment
		(start 41.617138 -333.709772)
		(end 54.940454 -330.372466)
		(width 0.1651)
		(layer "In15.Cu")
		(net "P5E_PEX0_STN4_RX_DP<75>")
	)
	(segment
		(start 25.845008 -343.365582)
		(end 25.845008 -342.734138)
		(width 0.13462)
		(layer "F.Cu")
		(net "P5E_PEX0_STN4_TX_DP<77>")
	)
	(segment
		(start 25.845008 -342.734138)
		(end 25.550368 -342.439498)
		(width 0.13462)
		(layer "F.Cu")
		(net "P5E_PEX0_STN4_TX_DP<77>")
	)
	(segment
		(start 25.524968 -343.685622)
		(end 25.845008 -343.365582)
		(width 0.13462)
		(layer "F.Cu")
		(net "P5E_PEX0_STN4_TX_DP<77>")
	)
	(segment
		(start 73.269348 -323.130926)
		(end 74.479404 -322.483988)
		(width 0.1651)
		(layer "In11.Cu")
		(net "P5E_PEX0_STN4_TX_DP<77>")
	)
	(segment
		(start 75.184 -320.265552)
		(end 75.22972 -320.219832)
		(width 0.1143)
		(layer "In11.Cu")
		(net "P5E_PEX0_STN4_TX_DP<77>")
	)
	(segment
		(start 75.184 -320.294)
		(end 75.184 -320.265552)
		(width 0.1143)
		(layer "In11.Cu")
		(net "P5E_PEX0_STN4_TX_DP<77>")
	)
	(segment
		(start 25.841198 -339.875622)
		(end 26.601928 -339.114638)
		(width 0.1651)
		(layer "In11.Cu")
		(net "P5E_PEX0_STN4_TX_DP<77>")
	)
	(segment
		(start 52.9209 -327.178162)
		(end 73.269348 -323.130926)
		(width 0.1651)
		(layer "In11.Cu")
		(net "P5E_PEX0_STN4_TX_DP<77>")
	)
	(segment
		(start 74.640694 -322.322952)
		(end 75.184 -321.011042)
		(width 0.1651)
		(layer "In11.Cu")
		(net "P5E_PEX0_STN4_TX_DP<77>")
	)
	(segment
		(start 75.71105 -311.479692)
		(end 75.79995 -311.390792)
		(width 0.1143)
		(layer "In11.Cu")
		(net "P5E_PEX0_STN4_TX_DP<77>")
	)
	(segment
		(start 75.22972 -320.219832)
		(end 75.22972 -311.756298)
		(width 0.1143)
		(layer "In11.Cu")
		(net "P5E_PEX0_STN4_TX_DP<77>")
	)
	(segment
		(start 75.184 -321.011042)
		(end 75.184 -320.294)
		(width 0.1651)
		(layer "In11.Cu")
		(net "P5E_PEX0_STN4_TX_DP<77>")
	)
	(segment
		(start 25.841198 -342.148668)
		(end 25.841198 -339.875622)
		(width 0.1651)
		(layer "In11.Cu")
		(net "P5E_PEX0_STN4_TX_DP<77>")
	)
	(segment
		(start 75.22972 -311.756298)
		(end 75.506326 -311.479692)
		(width 0.1143)
		(layer "In11.Cu")
		(net "P5E_PEX0_STN4_TX_DP<77>")
	)
	(segment
		(start 25.550368 -342.439498)
		(end 25.841198 -342.148668)
		(width 0.1651)
		(layer "In11.Cu")
		(net "P5E_PEX0_STN4_TX_DP<77>")
	)
	(segment
		(start 75.79995 -311.390792)
		(end 75.79995 -311.099962)
		(width 0.1143)
		(layer "In11.Cu")
		(net "P5E_PEX0_STN4_TX_DP<77>")
	)
	(segment
		(start 26.601928 -339.114638)
		(end 40.861234 -331.493114)
		(width 0.1651)
		(layer "In11.Cu")
		(net "P5E_PEX0_STN4_TX_DP<77>")
	)
	(segment
		(start 40.861234 -331.493114)
		(end 52.9209 -327.178162)
		(width 0.1651)
		(layer "In11.Cu")
		(net "P5E_PEX0_STN4_TX_DP<77>")
	)
	(segment
		(start 75.506326 -311.479692)
		(end 75.71105 -311.479692)
		(width 0.1143)
		(layer "In11.Cu")
		(net "P5E_PEX0_STN4_TX_DP<77>")
	)
	(segment
		(start 74.479404 -322.483988)
		(end 74.640694 -322.322952)
		(width 0.1651)
		(layer "In11.Cu")
		(net "P5E_PEX0_STN4_TX_DP<77>")
	)
	(segment
		(start 295.852342 -350.365314)
		(end 296.172382 -350.685354)
		(width 0.13462)
		(layer "F.Cu")
		(net "P5E_PEX2_STN4_TX_C_DP<66>")
	)
	(segment
		(start 296.172382 -350.685354)
		(end 296.172382 -351.316798)
		(width 0.13462)
		(layer "F.Cu")
		(net "P5E_PEX2_STN4_TX_C_DP<66>")
	)
	(segment
		(start 296.172382 -351.316798)
		(end 295.877742 -351.611438)
		(width 0.13462)
		(layer "F.Cu")
		(net "P5E_PEX2_STN4_TX_C_DP<66>")
	)
	(segment
		(start 298.402248 -367.142776)
		(end 298.61637 -367.589562)
		(width 0.1651)
		(layer "In11.Cu")
		(net "P5E_PEX2_STN4_TX_C_DP<66>")
	)
	(segment
		(start 297.563032 -365.389922)
		(end 297.715432 -365.44377)
		(width 0.1651)
		(layer "In11.Cu")
		(net "P5E_PEX2_STN4_TX_C_DP<66>")
	)
	(segment
		(start 298.089574 -366.489742)
		(end 298.241974 -366.54359)
		(width 0.1651)
		(layer "In11.Cu")
		(net "P5E_PEX2_STN4_TX_C_DP<66>")
	)
	(segment
		(start 296.349674 -362.590842)
		(end 296.295826 -362.743242)
		(width 0.1651)
		(layer "In11.Cu")
		(net "P5E_PEX2_STN4_TX_C_DP<66>")
	)
	(segment
		(start 297.18889 -364.34395)
		(end 297.402758 -364.790482)
		(width 0.1651)
		(layer "In11.Cu")
		(net "P5E_PEX2_STN4_TX_C_DP<66>")
	)
	(segment
		(start 296.662348 -363.24413)
		(end 296.876216 -363.690662)
		(width 0.1651)
		(layer "In11.Cu")
		(net "P5E_PEX2_STN4_TX_C_DP<66>")
	)
	(segment
		(start 296.168572 -351.902268)
		(end 296.168572 -352.356166)
		(width 0.1651)
		(layer "In11.Cu")
		(net "P5E_PEX2_STN4_TX_C_DP<66>")
	)
	(segment
		(start 295.877742 -351.611438)
		(end 296.168572 -351.902268)
		(width 0.1651)
		(layer "In11.Cu")
		(net "P5E_PEX2_STN4_TX_C_DP<66>")
	)
	(segment
		(start 296.295826 -362.743242)
		(end 296.509948 -363.190282)
		(width 0.1651)
		(layer "In11.Cu")
		(net "P5E_PEX2_STN4_TX_C_DP<66>")
	)
	(segment
		(start 298.455842 -366.990122)
		(end 298.402248 -367.142776)
		(width 0.1651)
		(layer "In11.Cu")
		(net "P5E_PEX2_STN4_TX_C_DP<66>")
	)
	(segment
		(start 297.03649 -364.290102)
		(end 297.18889 -364.34395)
		(width 0.1651)
		(layer "In11.Cu")
		(net "P5E_PEX2_STN4_TX_C_DP<66>")
	)
	(segment
		(start 295.983406 -362.090462)
		(end 296.135806 -362.14431)
		(width 0.1651)
		(layer "In11.Cu")
		(net "P5E_PEX2_STN4_TX_C_DP<66>")
	)
	(segment
		(start 297.402758 -364.790482)
		(end 297.34891 -364.942882)
		(width 0.1651)
		(layer "In11.Cu")
		(net "P5E_PEX2_STN4_TX_C_DP<66>")
	)
	(segment
		(start 297.875452 -366.042702)
		(end 298.089574 -366.489742)
		(width 0.1651)
		(layer "In11.Cu")
		(net "P5E_PEX2_STN4_TX_C_DP<66>")
	)
	(segment
		(start 294.614092 -353.910646)
		(end 294.614092 -358.966262)
		(width 0.1651)
		(layer "In11.Cu")
		(net "P5E_PEX2_STN4_TX_C_DP<66>")
	)
	(segment
		(start 299.33392 -368.824002)
		(end 299.33392 -371.812312)
		(width 0.1651)
		(layer "In11.Cu")
		(net "P5E_PEX2_STN4_TX_C_DP<66>")
	)
	(segment
		(start 296.135806 -362.14431)
		(end 296.349674 -362.590842)
		(width 0.1651)
		(layer "In11.Cu")
		(net "P5E_PEX2_STN4_TX_C_DP<66>")
	)
	(segment
		(start 299.047154 -372.099078)
		(end 298.616878 -372.099078)
		(width 0.1651)
		(layer "In11.Cu")
		(net "P5E_PEX2_STN4_TX_C_DP<66>")
	)
	(segment
		(start 295.822878 -361.491022)
		(end 295.769284 -361.643422)
		(width 0.1651)
		(layer "In11.Cu")
		(net "P5E_PEX2_STN4_TX_C_DP<66>")
	)
	(segment
		(start 298.489878 -371.972078)
		(end 298.489878 -371.590062)
		(width 0.1651)
		(layer "In11.Cu")
		(net "P5E_PEX2_STN4_TX_C_DP<66>")
	)
	(segment
		(start 296.876216 -363.690662)
		(end 296.822368 -363.843062)
		(width 0.1651)
		(layer "In11.Cu")
		(net "P5E_PEX2_STN4_TX_C_DP<66>")
	)
	(segment
		(start 296.509948 -363.190282)
		(end 296.662348 -363.24413)
		(width 0.1651)
		(layer "In11.Cu")
		(net "P5E_PEX2_STN4_TX_C_DP<66>")
	)
	(segment
		(start 295.769284 -361.643422)
		(end 295.983406 -362.090462)
		(width 0.1651)
		(layer "In11.Cu")
		(net "P5E_PEX2_STN4_TX_C_DP<66>")
	)
	(segment
		(start 297.34891 -364.942882)
		(end 297.563032 -365.389922)
		(width 0.1651)
		(layer "In11.Cu")
		(net "P5E_PEX2_STN4_TX_C_DP<66>")
	)
	(segment
		(start 298.616878 -372.099078)
		(end 298.489878 -371.972078)
		(width 0.1651)
		(layer "In11.Cu")
		(net "P5E_PEX2_STN4_TX_C_DP<66>")
	)
	(segment
		(start 297.715432 -365.44377)
		(end 297.9293 -365.890302)
		(width 0.1651)
		(layer "In11.Cu")
		(net "P5E_PEX2_STN4_TX_C_DP<66>")
	)
	(segment
		(start 296.822368 -363.843062)
		(end 297.03649 -364.290102)
		(width 0.1651)
		(layer "In11.Cu")
		(net "P5E_PEX2_STN4_TX_C_DP<66>")
	)
	(segment
		(start 298.241974 -366.54359)
		(end 298.455842 -366.990122)
		(width 0.1651)
		(layer "In11.Cu")
		(net "P5E_PEX2_STN4_TX_C_DP<66>")
	)
	(segment
		(start 298.76877 -367.64341)
		(end 299.33392 -368.824002)
		(width 0.1651)
		(layer "In11.Cu")
		(net "P5E_PEX2_STN4_TX_C_DP<66>")
	)
	(segment
		(start 299.33392 -371.812312)
		(end 299.047154 -372.099078)
		(width 0.1651)
		(layer "In11.Cu")
		(net "P5E_PEX2_STN4_TX_C_DP<66>")
	)
	(segment
		(start 297.9293 -365.890302)
		(end 297.875452 -366.042702)
		(width 0.1651)
		(layer "In11.Cu")
		(net "P5E_PEX2_STN4_TX_C_DP<66>")
	)
	(segment
		(start 296.168572 -352.356166)
		(end 294.614092 -353.910646)
		(width 0.1651)
		(layer "In11.Cu")
		(net "P5E_PEX2_STN4_TX_C_DP<66>")
	)
	(segment
		(start 298.61637 -367.589562)
		(end 298.76877 -367.64341)
		(width 0.1651)
		(layer "In11.Cu")
		(net "P5E_PEX2_STN4_TX_C_DP<66>")
	)
	(segment
		(start 294.614092 -358.966262)
		(end 295.822878 -361.491022)
		(width 0.1651)
		(layer "In11.Cu")
		(net "P5E_PEX2_STN4_TX_C_DP<66>")
	)
	(segment
		(start 26.413968 -345.465146)
		(end 26.119328 -345.170506)
		(width 0.13462)
		(layer "F.Cu")
		(net "P5E_PEX0_STN4_TX_C_DN<77>")
	)
	(segment
		(start 26.119328 -344.539062)
		(end 26.439368 -344.219022)
		(width 0.13462)
		(layer "F.Cu")
		(net "P5E_PEX0_STN4_TX_C_DN<77>")
	)
	(segment
		(start 26.119328 -345.170506)
		(end 26.119328 -344.539062)
		(width 0.13462)
		(layer "F.Cu")
		(net "P5E_PEX0_STN4_TX_C_DN<77>")
	)
	(segment
		(start 23.488142 -360.47426)
		(end 24.568658 -358.45242)
		(width 0.1651)
		(layer "In11.Cu")
		(net "P5E_PEX0_STN4_TX_C_DN<77>")
	)
	(segment
		(start 33.484312 -396.746984)
		(end 33.484312 -394.748512)
		(width 0.1651)
		(layer "In11.Cu")
		(net "P5E_PEX0_STN4_TX_C_DN<77>")
	)
	(segment
		(start 27.913838 -390.867392)
		(end 25.151588 -389.723122)
		(width 0.1651)
		(layer "In11.Cu")
		(net "P5E_PEX0_STN4_TX_C_DN<77>")
	)
	(segment
		(start 24.568658 -347.993462)
		(end 26.123138 -346.438982)
		(width 0.1651)
		(layer "In11.Cu")
		(net "P5E_PEX0_STN4_TX_C_DN<77>")
	)
	(segment
		(start 21.825204 -381.620014)
		(end 22.042628 -368.1222)
		(width 0.1651)
		(layer "In11.Cu")
		(net "P5E_PEX0_STN4_TX_C_DN<77>")
	)
	(segment
		(start 32.95015 -397.281146)
		(end 33.484312 -396.746984)
		(width 0.1651)
		(layer "In11.Cu")
		(net "P5E_PEX0_STN4_TX_C_DN<77>")
	)
	(segment
		(start 26.123138 -345.755976)
		(end 26.413968 -345.465146)
		(width 0.1651)
		(layer "In11.Cu")
		(net "P5E_PEX0_STN4_TX_C_DN<77>")
	)
	(segment
		(start 32.31007 -397.408146)
		(end 32.43707 -397.281146)
		(width 0.1651)
		(layer "In11.Cu")
		(net "P5E_PEX0_STN4_TX_C_DN<77>")
	)
	(segment
		(start 33.484312 -394.748512)
		(end 33.005268 -394.269468)
		(width 0.1651)
		(layer "In11.Cu")
		(net "P5E_PEX0_STN4_TX_C_DN<77>")
	)
	(segment
		(start 26.123138 -346.438982)
		(end 26.123138 -345.755976)
		(width 0.1651)
		(layer "In11.Cu")
		(net "P5E_PEX0_STN4_TX_C_DN<77>")
	)
	(segment
		(start 22.042628 -367.741454)
		(end 23.488142 -360.47426)
		(width 0.1651)
		(layer "In11.Cu")
		(net "P5E_PEX0_STN4_TX_C_DN<77>")
	)
	(segment
		(start 32.31007 -397.790162)
		(end 32.31007 -397.408146)
		(width 0.1651)
		(layer "In11.Cu")
		(net "P5E_PEX0_STN4_TX_C_DN<77>")
	)
	(segment
		(start 33.005268 -394.269468)
		(end 27.913838 -390.867392)
		(width 0.1651)
		(layer "In11.Cu")
		(net "P5E_PEX0_STN4_TX_C_DN<77>")
	)
	(segment
		(start 22.042628 -368.1222)
		(end 22.042628 -367.741454)
		(width 0.1651)
		(layer "In11.Cu")
		(net "P5E_PEX0_STN4_TX_C_DN<77>")
	)
	(segment
		(start 32.43707 -397.281146)
		(end 32.95015 -397.281146)
		(width 0.1651)
		(layer "In11.Cu")
		(net "P5E_PEX0_STN4_TX_C_DN<77>")
	)
	(segment
		(start 23.235666 -387.8072)
		(end 21.825204 -384.402076)
		(width 0.1651)
		(layer "In11.Cu")
		(net "P5E_PEX0_STN4_TX_C_DN<77>")
	)
	(segment
		(start 24.568658 -358.45242)
		(end 24.568658 -347.993462)
		(width 0.1651)
		(layer "In11.Cu")
		(net "P5E_PEX0_STN4_TX_C_DN<77>")
	)
	(segment
		(start 25.151588 -389.723122)
		(end 23.235666 -387.8072)
		(width 0.1651)
		(layer "In11.Cu")
		(net "P5E_PEX0_STN4_TX_C_DN<77>")
	)
	(segment
		(start 21.825204 -384.402076)
		(end 21.825204 -381.620014)
		(width 0.1651)
		(layer "In11.Cu")
		(net "P5E_PEX0_STN4_TX_C_DN<77>")
	)
	(segment
		(start 50.716688 -355.658166)
		(end 50.716688 -355.026722)
		(width 0.13462)
		(layer "F.Cu")
		(net "P5E_PEX0_STN4_TX_DP<64>")
	)
	(segment
		(start 50.716688 -355.026722)
		(end 50.422048 -354.732082)
		(width 0.13462)
		(layer "F.Cu")
		(net "P5E_PEX0_STN4_TX_DP<64>")
	)
	(segment
		(start 50.396648 -355.978206)
		(end 50.716688 -355.658166)
		(width 0.13462)
		(layer "F.Cu")
		(net "P5E_PEX0_STN4_TX_DP<64>")
	)
	(segment
		(start 97.78238 -315.32576)
		(end 95.294196 -312.837576)
		(width 0.1651)
		(layer "In11.Cu")
		(net "P5E_PEX0_STN4_TX_DP<64>")
	)
	(segment
		(start 75.14082 -304.449734)
		(end 74.84999 -304.449734)
		(width 0.1143)
		(layer "In11.Cu")
		(net "P5E_PEX0_STN4_TX_DP<64>")
	)
	(segment
		(start 84.862416 -305.065684)
		(end 83.670648 -305.065684)
		(width 0.1651)
		(layer "In11.Cu")
		(net "P5E_PEX0_STN4_TX_DP<64>")
	)
	(segment
		(start 83.6422 -305.065684)
		(end 83.59648 -305.019964)
		(width 0.1143)
		(layer "In11.Cu")
		(net "P5E_PEX0_STN4_TX_DP<64>")
	)
	(segment
		(start 75.22972 -304.743358)
		(end 75.22972 -304.538634)
		(width 0.1143)
		(layer "In11.Cu")
		(net "P5E_PEX0_STN4_TX_DP<64>")
	)
	(segment
		(start 75.22972 -304.538634)
		(end 75.14082 -304.449734)
		(width 0.1143)
		(layer "In11.Cu")
		(net "P5E_PEX0_STN4_TX_DP<64>")
	)
	(segment
		(start 83.59648 -305.019964)
		(end 75.506326 -305.019964)
		(width 0.1143)
		(layer "In11.Cu")
		(net "P5E_PEX0_STN4_TX_DP<64>")
	)
	(segment
		(start 75.506326 -305.019964)
		(end 75.22972 -304.743358)
		(width 0.1143)
		(layer "In11.Cu")
		(net "P5E_PEX0_STN4_TX_DP<64>")
	)
	(segment
		(start 88.40089 -306.531518)
		(end 84.862416 -305.065684)
		(width 0.1651)
		(layer "In11.Cu")
		(net "P5E_PEX0_STN4_TX_DP<64>")
	)
	(segment
		(start 52.287424 -352.083116)
		(end 58.19394 -343.243408)
		(width 0.1651)
		(layer "In11.Cu")
		(net "P5E_PEX0_STN4_TX_DP<64>")
	)
	(segment
		(start 78.891638 -334.956404)
		(end 95.22587 -329.111864)
		(width 0.1651)
		(layer "In11.Cu")
		(net "P5E_PEX0_STN4_TX_DP<64>")
	)
	(segment
		(start 50.712878 -353.657662)
		(end 52.287424 -352.083116)
		(width 0.1651)
		(layer "In11.Cu")
		(net "P5E_PEX0_STN4_TX_DP<64>")
	)
	(segment
		(start 50.712878 -354.441252)
		(end 50.712878 -353.657662)
		(width 0.1651)
		(layer "In11.Cu")
		(net "P5E_PEX0_STN4_TX_DP<64>")
	)
	(segment
		(start 62.145926 -340.000082)
		(end 65.677542 -338.537296)
		(width 0.1651)
		(layer "In11.Cu")
		(net "P5E_PEX0_STN4_TX_DP<64>")
	)
	(segment
		(start 83.670648 -305.065684)
		(end 83.6422 -305.065684)
		(width 0.1143)
		(layer "In11.Cu")
		(net "P5E_PEX0_STN4_TX_DP<64>")
	)
	(segment
		(start 58.19394 -343.243408)
		(end 62.145926 -340.000082)
		(width 0.1651)
		(layer "In11.Cu")
		(net "P5E_PEX0_STN4_TX_DP<64>")
	)
	(segment
		(start 95.294196 -312.837576)
		(end 94.291658 -312.422286)
		(width 0.1651)
		(layer "In11.Cu")
		(net "P5E_PEX0_STN4_TX_DP<64>")
	)
	(segment
		(start 50.422048 -354.732082)
		(end 50.712878 -354.441252)
		(width 0.1651)
		(layer "In11.Cu")
		(net "P5E_PEX0_STN4_TX_DP<64>")
	)
	(segment
		(start 97.655634 -326.681592)
		(end 99.257358 -322.814442)
		(width 0.1651)
		(layer "In11.Cu")
		(net "P5E_PEX0_STN4_TX_DP<64>")
	)
	(segment
		(start 95.22587 -329.111864)
		(end 97.655634 -326.681592)
		(width 0.1651)
		(layer "In11.Cu")
		(net "P5E_PEX0_STN4_TX_DP<64>")
	)
	(segment
		(start 74.79665 -335.770728)
		(end 78.891638 -334.956404)
		(width 0.1651)
		(layer "In11.Cu")
		(net "P5E_PEX0_STN4_TX_DP<64>")
	)
	(segment
		(start 94.291658 -312.422286)
		(end 88.40089 -306.531518)
		(width 0.1651)
		(layer "In11.Cu")
		(net "P5E_PEX0_STN4_TX_DP<64>")
	)
	(segment
		(start 99.257358 -322.814442)
		(end 99.257358 -318.88684)
		(width 0.1651)
		(layer "In11.Cu")
		(net "P5E_PEX0_STN4_TX_DP<64>")
	)
	(segment
		(start 65.677542 -338.537296)
		(end 74.79665 -335.770728)
		(width 0.1651)
		(layer "In11.Cu")
		(net "P5E_PEX0_STN4_TX_DP<64>")
	)
	(segment
		(start 99.257358 -318.88684)
		(end 97.78238 -315.32576)
		(width 0.1651)
		(layer "In11.Cu")
		(net "P5E_PEX0_STN4_TX_DP<64>")
	)
	(segment
		(start 295.215818 -369.7478)
		(end 295.527222 -368.908838)
		(width 0.1651)
		(layer "In15.Cu")
		(net "P5E_PEX2_STN4_RX_DN<68>")
	)
	(segment
		(start 305.933602 -354.449634)
		(end 311.026302 -340.739984)
		(width 0.1651)
		(layer "In15.Cu")
		(net "P5E_PEX2_STN4_RX_DN<68>")
	)
	(segment
		(start 314.384436 -308.249828)
		(end 314.649866 -308.249828)
		(width 0.1143)
		(layer "In15.Cu")
		(net "P5E_PEX2_STN4_RX_DN<68>")
	)
	(segment
		(start 294.089836 -380.69012)
		(end 294.089836 -380.308104)
		(width 0.1651)
		(layer "In15.Cu")
		(net "P5E_PEX2_STN4_RX_DN<68>")
	)
	(segment
		(start 326.545956 -317.866776)
		(end 317.263018 -308.583838)
		(width 0.1651)
		(layer "In15.Cu")
		(net "P5E_PEX2_STN4_RX_DN<68>")
	)
	(segment
		(start 315.77788 -308.629558)
		(end 314.373768 -308.629558)
		(width 0.1143)
		(layer "In15.Cu")
		(net "P5E_PEX2_STN4_RX_DN<68>")
	)
	(segment
		(start 314.270136 -308.364128)
		(end 314.384436 -308.249828)
		(width 0.1143)
		(layer "In15.Cu")
		(net "P5E_PEX2_STN4_RX_DN<68>")
	)
	(segment
		(start 295.527222 -368.908838)
		(end 303.901856 -359.91927)
		(width 0.1651)
		(layer "In15.Cu")
		(net "P5E_PEX2_STN4_RX_DN<68>")
	)
	(segment
		(start 315.852048 -308.583838)
		(end 315.8236 -308.583838)
		(width 0.1143)
		(layer "In15.Cu")
		(net "P5E_PEX2_STN4_RX_DN<68>")
	)
	(segment
		(start 317.263018 -308.583838)
		(end 315.852048 -308.583838)
		(width 0.1651)
		(layer "In15.Cu")
		(net "P5E_PEX2_STN4_RX_DN<68>")
	)
	(segment
		(start 327.02754 -321.999356)
		(end 327.02754 -319.029334)
		(width 0.1651)
		(layer "In15.Cu")
		(net "P5E_PEX2_STN4_RX_DN<68>")
	)
	(segment
		(start 305.933094 -354.451158)
		(end 305.933602 -354.449634)
		(width 0.1651)
		(layer "In15.Cu")
		(net "P5E_PEX2_STN4_RX_DN<68>")
	)
	(segment
		(start 295.215818 -379.729238)
		(end 295.215818 -369.7478)
		(width 0.1651)
		(layer "In15.Cu")
		(net "P5E_PEX2_STN4_RX_DN<68>")
	)
	(segment
		(start 303.901856 -359.91927)
		(end 305.933094 -354.451158)
		(width 0.1651)
		(layer "In15.Cu")
		(net "P5E_PEX2_STN4_RX_DN<68>")
	)
	(segment
		(start 314.270136 -308.525926)
		(end 314.270136 -308.364128)
		(width 0.1143)
		(layer "In15.Cu")
		(net "P5E_PEX2_STN4_RX_DN<68>")
	)
	(segment
		(start 294.763952 -380.181104)
		(end 295.215818 -379.729238)
		(width 0.1651)
		(layer "In15.Cu")
		(net "P5E_PEX2_STN4_RX_DN<68>")
	)
	(segment
		(start 327.02754 -319.029334)
		(end 326.545956 -317.866776)
		(width 0.1651)
		(layer "In15.Cu")
		(net "P5E_PEX2_STN4_RX_DN<68>")
	)
	(segment
		(start 315.8236 -308.583838)
		(end 315.77788 -308.629558)
		(width 0.1143)
		(layer "In15.Cu")
		(net "P5E_PEX2_STN4_RX_DN<68>")
	)
	(segment
		(start 311.026302 -340.739984)
		(end 326.385936 -323.548756)
		(width 0.1651)
		(layer "In15.Cu")
		(net "P5E_PEX2_STN4_RX_DN<68>")
	)
	(segment
		(start 326.385936 -323.548756)
		(end 327.02754 -321.999356)
		(width 0.1651)
		(layer "In15.Cu")
		(net "P5E_PEX2_STN4_RX_DN<68>")
	)
	(segment
		(start 294.216836 -380.181104)
		(end 294.763952 -380.181104)
		(width 0.1651)
		(layer "In15.Cu")
		(net "P5E_PEX2_STN4_RX_DN<68>")
	)
	(segment
		(start 294.089836 -380.308104)
		(end 294.216836 -380.181104)
		(width 0.1651)
		(layer "In15.Cu")
		(net "P5E_PEX2_STN4_RX_DN<68>")
	)
	(segment
		(start 314.373768 -308.629558)
		(end 314.270136 -308.525926)
		(width 0.1143)
		(layer "In15.Cu")
		(net "P5E_PEX2_STN4_RX_DN<68>")
	)
	(segment
		(start 28.953968 -350.685354)
		(end 28.633928 -350.365314)
		(width 0.13462)
		(layer "F.Cu")
		(net "P5E_PEX0_STN4_TX_C_DP<75>")
	)
	(segment
		(start 28.953968 -351.316798)
		(end 28.953968 -350.685354)
		(width 0.13462)
		(layer "F.Cu")
		(net "P5E_PEX0_STN4_TX_C_DP<75>")
	)
	(segment
		(start 28.659328 -351.611438)
		(end 28.953968 -351.316798)
		(width 0.13462)
		(layer "F.Cu")
		(net "P5E_PEX0_STN4_TX_C_DP<75>")
	)
	(segment
		(start 24.639016 -364.81893)
		(end 27.395678 -358.991916)
		(width 0.1651)
		(layer "In11.Cu")
		(net "P5E_PEX0_STN4_TX_C_DP<75>")
	)
	(segment
		(start 36.837112 -396.999206)
		(end 37.233352 -396.999206)
		(width 0.1651)
		(layer "In11.Cu")
		(net "P5E_PEX0_STN4_TX_C_DP<75>")
	)
	(segment
		(start 35.324288 -393.188698)
		(end 35.201098 -393.213336)
		(width 0.1651)
		(layer "In11.Cu")
		(net "P5E_PEX0_STN4_TX_C_DP<75>")
	)
	(segment
		(start 37.233352 -396.999206)
		(end 37.602414 -396.630144)
		(width 0.1651)
		(layer "In11.Cu")
		(net "P5E_PEX0_STN4_TX_C_DP<75>")
	)
	(segment
		(start 34.764472 -392.814556)
		(end 31.328614 -390.519158)
		(width 0.1651)
		(layer "In11.Cu")
		(net "P5E_PEX0_STN4_TX_C_DP<75>")
	)
	(segment
		(start 35.201098 -393.213336)
		(end 34.788856 -392.938)
		(width 0.1651)
		(layer "In11.Cu")
		(net "P5E_PEX0_STN4_TX_C_DP<75>")
	)
	(segment
		(start 35.736022 -393.46378)
		(end 35.324288 -393.188698)
		(width 0.1651)
		(layer "In11.Cu")
		(net "P5E_PEX0_STN4_TX_C_DP<75>")
	)
	(segment
		(start 23.503636 -384.198368)
		(end 23.503636 -381.631952)
		(width 0.1651)
		(layer "In11.Cu")
		(net "P5E_PEX0_STN4_TX_C_DP<75>")
	)
	(segment
		(start 28.950158 -352.420682)
		(end 28.950158 -351.902268)
		(width 0.1651)
		(layer "In11.Cu")
		(net "P5E_PEX0_STN4_TX_C_DP<75>")
	)
	(segment
		(start 23.707598 -368.96548)
		(end 24.639016 -364.81893)
		(width 0.1651)
		(layer "In11.Cu")
		(net "P5E_PEX0_STN4_TX_C_DP<75>")
	)
	(segment
		(start 36.172648 -393.86256)
		(end 35.76066 -393.587224)
		(width 0.1651)
		(layer "In11.Cu")
		(net "P5E_PEX0_STN4_TX_C_DP<75>")
	)
	(segment
		(start 37.096446 -394.372846)
		(end 36.296092 -393.838176)
		(width 0.1651)
		(layer "In11.Cu")
		(net "P5E_PEX0_STN4_TX_C_DP<75>")
	)
	(segment
		(start 37.602414 -396.630144)
		(end 37.602414 -394.878814)
		(width 0.1651)
		(layer "In11.Cu")
		(net "P5E_PEX0_STN4_TX_C_DP<75>")
	)
	(segment
		(start 23.503636 -381.631952)
		(end 23.707598 -368.96548)
		(width 0.1651)
		(layer "In11.Cu")
		(net "P5E_PEX0_STN4_TX_C_DP<75>")
	)
	(segment
		(start 34.788856 -392.938)
		(end 34.764472 -392.814556)
		(width 0.1651)
		(layer "In11.Cu")
		(net "P5E_PEX0_STN4_TX_C_DP<75>")
	)
	(segment
		(start 27.395678 -353.975162)
		(end 28.950158 -352.420682)
		(width 0.1651)
		(layer "In11.Cu")
		(net "P5E_PEX0_STN4_TX_C_DP<75>")
	)
	(segment
		(start 36.710112 -396.49019)
		(end 36.710112 -396.872206)
		(width 0.1651)
		(layer "In11.Cu")
		(net "P5E_PEX0_STN4_TX_C_DP<75>")
	)
	(segment
		(start 36.296092 -393.838176)
		(end 36.172648 -393.86256)
		(width 0.1651)
		(layer "In11.Cu")
		(net "P5E_PEX0_STN4_TX_C_DP<75>")
	)
	(segment
		(start 36.710112 -396.872206)
		(end 36.837112 -396.999206)
		(width 0.1651)
		(layer "In11.Cu")
		(net "P5E_PEX0_STN4_TX_C_DP<75>")
	)
	(segment
		(start 37.602414 -394.878814)
		(end 37.096446 -394.372846)
		(width 0.1651)
		(layer "In11.Cu")
		(net "P5E_PEX0_STN4_TX_C_DP<75>")
	)
	(segment
		(start 26.073608 -388.342378)
		(end 24.616664 -386.885434)
		(width 0.1651)
		(layer "In11.Cu")
		(net "P5E_PEX0_STN4_TX_C_DP<75>")
	)
	(segment
		(start 35.76066 -393.587224)
		(end 35.736022 -393.46378)
		(width 0.1651)
		(layer "In11.Cu")
		(net "P5E_PEX0_STN4_TX_C_DP<75>")
	)
	(segment
		(start 27.395678 -358.991916)
		(end 27.395678 -353.975162)
		(width 0.1651)
		(layer "In11.Cu")
		(net "P5E_PEX0_STN4_TX_C_DP<75>")
	)
	(segment
		(start 24.616664 -386.885434)
		(end 23.503636 -384.198368)
		(width 0.1651)
		(layer "In11.Cu")
		(net "P5E_PEX0_STN4_TX_C_DP<75>")
	)
	(segment
		(start 28.950158 -351.902268)
		(end 28.659328 -351.611438)
		(width 0.1651)
		(layer "In11.Cu")
		(net "P5E_PEX0_STN4_TX_C_DP<75>")
	)
	(segment
		(start 31.328614 -390.519158)
		(end 26.073608 -388.342378)
		(width 0.1651)
		(layer "In11.Cu")
		(net "P5E_PEX0_STN4_TX_C_DP<75>")
	)
	(segment
		(start 304.015902 -368.935)
		(end 304.3936 -368.046)
		(width 0.1651)
		(layer "In15.Cu")
		(net "P5E_PEX2_STN4_RX_DN<64>")
	)
	(segment
		(start 319.151 -356.4382)
		(end 320.1924 -356.0064)
		(width 0.1651)
		(layer "In15.Cu")
		(net "P5E_PEX2_STN4_RX_DN<64>")
	)
	(segment
		(start 314.373768 -304.829464)
		(end 314.270136 -304.725832)
		(width 0.1143)
		(layer "In15.Cu")
		(net "P5E_PEX2_STN4_RX_DN<64>")
	)
	(segment
		(start 304.3936 -368.046)
		(end 315.214 -356.6668)
		(width 0.1651)
		(layer "In15.Cu")
		(net "P5E_PEX2_STN4_RX_DN<64>")
	)
	(segment
		(start 315.8236 -356.4382)
		(end 319.151 -356.4382)
		(width 0.1651)
		(layer "In15.Cu")
		(net "P5E_PEX2_STN4_RX_DN<64>")
	)
	(segment
		(start 314.384436 -304.449734)
		(end 314.649866 -304.449734)
		(width 0.1143)
		(layer "In15.Cu")
		(net "P5E_PEX2_STN4_RX_DN<64>")
	)
	(segment
		(start 315.77788 -304.829464)
		(end 314.373768 -304.829464)
		(width 0.1143)
		(layer "In15.Cu")
		(net "P5E_PEX2_STN4_RX_DN<64>")
	)
	(segment
		(start 314.270136 -304.725832)
		(end 314.270136 -304.564034)
		(width 0.1143)
		(layer "In15.Cu")
		(net "P5E_PEX2_STN4_RX_DN<64>")
	)
	(segment
		(start 304.015902 -379.729238)
		(end 304.015902 -368.935)
		(width 0.1651)
		(layer "In15.Cu")
		(net "P5E_PEX2_STN4_RX_DN<64>")
	)
	(segment
		(start 320.847974 -354.938838)
		(end 320.847974 -342.214454)
		(width 0.1651)
		(layer "In15.Cu")
		(net "P5E_PEX2_STN4_RX_DN<64>")
	)
	(segment
		(start 329.89266 -315.792358)
		(end 326.488044 -310.696864)
		(width 0.1651)
		(layer "In15.Cu")
		(net "P5E_PEX2_STN4_RX_DN<64>")
	)
	(segment
		(start 320.9798 -341.376)
		(end 330.0857 -325.288402)
		(width 0.1651)
		(layer "In15.Cu")
		(net "P5E_PEX2_STN4_RX_DN<64>")
	)
	(segment
		(start 320.847974 -342.214454)
		(end 320.9798 -341.376)
		(width 0.1651)
		(layer "In15.Cu")
		(net "P5E_PEX2_STN4_RX_DN<64>")
	)
	(segment
		(start 302.88992 -380.308104)
		(end 303.01692 -380.181104)
		(width 0.1651)
		(layer "In15.Cu")
		(net "P5E_PEX2_STN4_RX_DN<64>")
	)
	(segment
		(start 314.270136 -304.564034)
		(end 314.384436 -304.449734)
		(width 0.1143)
		(layer "In15.Cu")
		(net "P5E_PEX2_STN4_RX_DN<64>")
	)
	(segment
		(start 330.93914 -318.318388)
		(end 329.89266 -315.792358)
		(width 0.1651)
		(layer "In15.Cu")
		(net "P5E_PEX2_STN4_RX_DN<64>")
	)
	(segment
		(start 315.214 -356.6668)
		(end 315.8236 -356.4382)
		(width 0.1651)
		(layer "In15.Cu")
		(net "P5E_PEX2_STN4_RX_DN<64>")
	)
	(segment
		(start 315.852048 -304.783744)
		(end 315.8236 -304.783744)
		(width 0.1143)
		(layer "In15.Cu")
		(net "P5E_PEX2_STN4_RX_DN<64>")
	)
	(segment
		(start 315.8236 -304.783744)
		(end 315.77788 -304.829464)
		(width 0.1143)
		(layer "In15.Cu")
		(net "P5E_PEX2_STN4_RX_DN<64>")
	)
	(segment
		(start 326.488044 -310.696864)
		(end 322.466462 -306.675282)
		(width 0.1651)
		(layer "In15.Cu")
		(net "P5E_PEX2_STN4_RX_DN<64>")
	)
	(segment
		(start 330.0857 -325.288402)
		(end 330.93914 -323.2277)
		(width 0.1651)
		(layer "In15.Cu")
		(net "P5E_PEX2_STN4_RX_DN<64>")
	)
	(segment
		(start 303.564036 -380.181104)
		(end 304.015902 -379.729238)
		(width 0.1651)
		(layer "In15.Cu")
		(net "P5E_PEX2_STN4_RX_DN<64>")
	)
	(segment
		(start 320.1924 -356.0064)
		(end 320.556636 -355.642164)
		(width 0.1651)
		(layer "In15.Cu")
		(net "P5E_PEX2_STN4_RX_DN<64>")
	)
	(segment
		(start 330.93914 -323.2277)
		(end 330.93914 -318.318388)
		(width 0.1651)
		(layer "In15.Cu")
		(net "P5E_PEX2_STN4_RX_DN<64>")
	)
	(segment
		(start 320.556636 -355.642164)
		(end 320.847974 -354.938838)
		(width 0.1651)
		(layer "In15.Cu")
		(net "P5E_PEX2_STN4_RX_DN<64>")
	)
	(segment
		(start 303.01692 -380.181104)
		(end 303.564036 -380.181104)
		(width 0.1651)
		(layer "In15.Cu")
		(net "P5E_PEX2_STN4_RX_DN<64>")
	)
	(segment
		(start 322.466462 -306.675282)
		(end 318.927988 -304.783744)
		(width 0.1651)
		(layer "In15.Cu")
		(net "P5E_PEX2_STN4_RX_DN<64>")
	)
	(segment
		(start 318.927988 -304.783744)
		(end 315.852048 -304.783744)
		(width 0.1651)
		(layer "In15.Cu")
		(net "P5E_PEX2_STN4_RX_DN<64>")
	)
	(segment
		(start 302.88992 -380.69012)
		(end 302.88992 -380.308104)
		(width 0.1651)
		(layer "In15.Cu")
		(net "P5E_PEX2_STN4_RX_DN<64>")
	)
	(segment
		(start 25.550368 -357.75773)
		(end 25.845008 -357.46309)
		(width 0.13462)
		(layer "F.Cu")
		(net "P5E_PEX0_STN4_TX_C_DP<76>")
	)
	(segment
		(start 25.845008 -356.831646)
		(end 25.524968 -356.511606)
		(width 0.13462)
		(layer "F.Cu")
		(net "P5E_PEX0_STN4_TX_C_DP<76>")
	)
	(segment
		(start 25.845008 -357.46309)
		(end 25.845008 -356.831646)
		(width 0.13462)
		(layer "F.Cu")
		(net "P5E_PEX0_STN4_TX_C_DP<76>")
	)
	(segment
		(start 22.498304 -381.625602)
		(end 22.716236 -368.100102)
		(width 0.1651)
		(layer "In11.Cu")
		(net "P5E_PEX0_STN4_TX_C_DP<76>")
	)
	(segment
		(start 22.498304 -384.26771)
		(end 22.498304 -381.625602)
		(width 0.1651)
		(layer "In11.Cu")
		(net "P5E_PEX0_STN4_TX_C_DP<76>")
	)
	(segment
		(start 33.378394 -393.64158)
		(end 32.966152 -393.36599)
		(width 0.1651)
		(layer "In11.Cu")
		(net "P5E_PEX0_STN4_TX_C_DP<76>")
	)
	(segment
		(start 32.966152 -393.36599)
		(end 32.941768 -393.2428)
		(width 0.1651)
		(layer "In11.Cu")
		(net "P5E_PEX0_STN4_TX_C_DP<76>")
	)
	(segment
		(start 34.349944 -394.290804)
		(end 33.937702 -394.015214)
		(width 0.1651)
		(layer "In11.Cu")
		(net "P5E_PEX0_STN4_TX_C_DP<76>")
	)
	(segment
		(start 35.060382 -398.09928)
		(end 35.40252 -397.757142)
		(width 0.1651)
		(layer "In11.Cu")
		(net "P5E_PEX0_STN4_TX_C_DP<76>")
	)
	(segment
		(start 34.884868 -394.541248)
		(end 34.473134 -394.266166)
		(width 0.1651)
		(layer "In11.Cu")
		(net "P5E_PEX0_STN4_TX_C_DP<76>")
	)
	(segment
		(start 25.532842 -389.152384)
		(end 23.806658 -387.4262)
		(width 0.1651)
		(layer "In11.Cu")
		(net "P5E_PEX0_STN4_TX_C_DP<76>")
	)
	(segment
		(start 22.716236 -368.100102)
		(end 24.28367 -361.842558)
		(width 0.1651)
		(layer "In11.Cu")
		(net "P5E_PEX0_STN4_TX_C_DP<76>")
	)
	(segment
		(start 33.913318 -393.892024)
		(end 33.501584 -393.616942)
		(width 0.1651)
		(layer "In11.Cu")
		(net "P5E_PEX0_STN4_TX_C_DP<76>")
	)
	(segment
		(start 33.501584 -393.616942)
		(end 33.378394 -393.64158)
		(width 0.1651)
		(layer "In11.Cu")
		(net "P5E_PEX0_STN4_TX_C_DP<76>")
	)
	(segment
		(start 25.841198 -358.04856)
		(end 25.550368 -357.75773)
		(width 0.1651)
		(layer "In11.Cu")
		(net "P5E_PEX0_STN4_TX_C_DP<76>")
	)
	(segment
		(start 24.28367 -361.842558)
		(end 25.841198 -358.929178)
		(width 0.1651)
		(layer "In11.Cu")
		(net "P5E_PEX0_STN4_TX_C_DP<76>")
	)
	(segment
		(start 34.509964 -397.59001)
		(end 34.509964 -397.97228)
		(width 0.1651)
		(layer "In11.Cu")
		(net "P5E_PEX0_STN4_TX_C_DP<76>")
	)
	(segment
		(start 35.40252 -397.757142)
		(end 35.40252 -395.0589)
		(width 0.1651)
		(layer "In11.Cu")
		(net "P5E_PEX0_STN4_TX_C_DP<76>")
	)
	(segment
		(start 34.509964 -397.97228)
		(end 34.636964 -398.09928)
		(width 0.1651)
		(layer "In11.Cu")
		(net "P5E_PEX0_STN4_TX_C_DP<76>")
	)
	(segment
		(start 25.841198 -358.929178)
		(end 25.841198 -358.04856)
		(width 0.1651)
		(layer "In11.Cu")
		(net "P5E_PEX0_STN4_TX_C_DP<76>")
	)
	(segment
		(start 34.473134 -394.266166)
		(end 34.349944 -394.290804)
		(width 0.1651)
		(layer "In11.Cu")
		(net "P5E_PEX0_STN4_TX_C_DP<76>")
	)
	(segment
		(start 33.937702 -394.015214)
		(end 33.913318 -393.892024)
		(width 0.1651)
		(layer "In11.Cu")
		(net "P5E_PEX0_STN4_TX_C_DP<76>")
	)
	(segment
		(start 32.941768 -393.2428)
		(end 28.919424 -390.555226)
		(width 0.1651)
		(layer "In11.Cu")
		(net "P5E_PEX0_STN4_TX_C_DP<76>")
	)
	(segment
		(start 34.636964 -398.09928)
		(end 35.060382 -398.09928)
		(width 0.1651)
		(layer "In11.Cu")
		(net "P5E_PEX0_STN4_TX_C_DP<76>")
	)
	(segment
		(start 35.40252 -395.0589)
		(end 34.884868 -394.541248)
		(width 0.1651)
		(layer "In11.Cu")
		(net "P5E_PEX0_STN4_TX_C_DP<76>")
	)
	(segment
		(start 28.919424 -390.555226)
		(end 25.532842 -389.152384)
		(width 0.1651)
		(layer "In11.Cu")
		(net "P5E_PEX0_STN4_TX_C_DP<76>")
	)
	(segment
		(start 23.806658 -387.4262)
		(end 22.498304 -384.26771)
		(width 0.1651)
		(layer "In11.Cu")
		(net "P5E_PEX0_STN4_TX_C_DP<76>")
	)
	(segment
		(start 19.627088 -343.365582)
		(end 19.627088 -342.734138)
		(width 0.13462)
		(layer "F.Cu")
		(net "P5E_PEX0_STN4_TX_DP<79>")
	)
	(segment
		(start 19.627088 -342.734138)
		(end 19.332448 -342.439498)
		(width 0.13462)
		(layer "F.Cu")
		(net "P5E_PEX0_STN4_TX_DP<79>")
	)
	(segment
		(start 19.307048 -343.685622)
		(end 19.627088 -343.365582)
		(width 0.13462)
		(layer "F.Cu")
		(net "P5E_PEX0_STN4_TX_DP<79>")
	)
	(segment
		(start 72.481694 -321.319144)
		(end 73.054464 -321.013074)
		(width 0.1651)
		(layer "In11.Cu")
		(net "P5E_PEX0_STN4_TX_DP<79>")
	)
	(segment
		(start 19.623278 -341.259414)
		(end 20.217384 -340.268052)
		(width 0.1651)
		(layer "In11.Cu")
		(net "P5E_PEX0_STN4_TX_DP<79>")
	)
	(segment
		(start 20.217384 -340.268052)
		(end 39.918894 -329.737466)
		(width 0.1651)
		(layer "In11.Cu")
		(net "P5E_PEX0_STN4_TX_DP<79>")
	)
	(segment
		(start 39.918894 -329.737466)
		(end 46.026578 -327.55205)
		(width 0.1651)
		(layer "In11.Cu")
		(net "P5E_PEX0_STN4_TX_DP<79>")
	)
	(segment
		(start 73.810876 -311.479692)
		(end 73.899776 -311.390792)
		(width 0.1143)
		(layer "In11.Cu")
		(net "P5E_PEX0_STN4_TX_DP<79>")
	)
	(segment
		(start 46.026832 -327.551796)
		(end 52.135024 -325.36638)
		(width 0.1651)
		(layer "In11.Cu")
		(net "P5E_PEX0_STN4_TX_DP<79>")
	)
	(segment
		(start 73.283826 -320.4591)
		(end 73.283826 -320.294)
		(width 0.1651)
		(layer "In11.Cu")
		(net "P5E_PEX0_STN4_TX_DP<79>")
	)
	(segment
		(start 73.899776 -311.390792)
		(end 73.899776 -311.099962)
		(width 0.1143)
		(layer "In11.Cu")
		(net "P5E_PEX0_STN4_TX_DP<79>")
	)
	(segment
		(start 46.027086 -327.551796)
		(end 46.026832 -327.551796)
		(width 0.1651)
		(layer "In11.Cu")
		(net "P5E_PEX0_STN4_TX_DP<79>")
	)
	(segment
		(start 73.329546 -311.756298)
		(end 73.606152 -311.479692)
		(width 0.1143)
		(layer "In11.Cu")
		(net "P5E_PEX0_STN4_TX_DP<79>")
	)
	(segment
		(start 73.054464 -321.013074)
		(end 73.283826 -320.4591)
		(width 0.1651)
		(layer "In11.Cu")
		(net "P5E_PEX0_STN4_TX_DP<79>")
	)
	(segment
		(start 73.329546 -320.219832)
		(end 73.329546 -311.756298)
		(width 0.1143)
		(layer "In11.Cu")
		(net "P5E_PEX0_STN4_TX_DP<79>")
	)
	(segment
		(start 46.026578 -327.55205)
		(end 46.027086 -327.551796)
		(width 0.1651)
		(layer "In11.Cu")
		(net "P5E_PEX0_STN4_TX_DP<79>")
	)
	(segment
		(start 19.332448 -342.439498)
		(end 19.623278 -342.148668)
		(width 0.1651)
		(layer "In11.Cu")
		(net "P5E_PEX0_STN4_TX_DP<79>")
	)
	(segment
		(start 73.606152 -311.479692)
		(end 73.810876 -311.479692)
		(width 0.1143)
		(layer "In11.Cu")
		(net "P5E_PEX0_STN4_TX_DP<79>")
	)
	(segment
		(start 73.283826 -320.294)
		(end 73.283826 -320.265552)
		(width 0.1143)
		(layer "In11.Cu")
		(net "P5E_PEX0_STN4_TX_DP<79>")
	)
	(segment
		(start 73.283826 -320.265552)
		(end 73.329546 -320.219832)
		(width 0.1143)
		(layer "In11.Cu")
		(net "P5E_PEX0_STN4_TX_DP<79>")
	)
	(segment
		(start 19.623278 -342.148668)
		(end 19.623278 -341.259414)
		(width 0.1651)
		(layer "In11.Cu")
		(net "P5E_PEX0_STN4_TX_DP<79>")
	)
	(segment
		(start 52.135024 -325.36638)
		(end 72.481694 -321.319144)
		(width 0.1651)
		(layer "In11.Cu")
		(net "P5E_PEX0_STN4_TX_DP<79>")
	)
	(segment
		(start 286.845502 -357.46309)
		(end 286.550862 -357.75773)
		(width 0.13462)
		(layer "F.Cu")
		(net "P5E_PEX2_STN4_TX_C_DP<70>")
	)
	(segment
		(start 286.525462 -356.511606)
		(end 286.845502 -356.831646)
		(width 0.13462)
		(layer "F.Cu")
		(net "P5E_PEX2_STN4_TX_C_DP<70>")
	)
	(segment
		(start 286.845502 -356.831646)
		(end 286.845502 -357.46309)
		(width 0.13462)
		(layer "F.Cu")
		(net "P5E_PEX2_STN4_TX_C_DP<70>")
	)
	(segment
		(start 289.08248 -365.298736)
		(end 289.254692 -365.763302)
		(width 0.1651)
		(layer "In11.Cu")
		(net "P5E_PEX2_STN4_TX_C_DP<70>")
	)
	(segment
		(start 290.25088 -368.116866)
		(end 290.533836 -368.87912)
		(width 0.1651)
		(layer "In11.Cu")
		(net "P5E_PEX2_STN4_TX_C_DP<70>")
	)
	(segment
		(start 288.725356 -364.008924)
		(end 288.658046 -364.155736)
		(width 0.1651)
		(layer "In11.Cu")
		(net "P5E_PEX2_STN4_TX_C_DP<70>")
	)
	(segment
		(start 289.679126 -366.906302)
		(end 289.826446 -366.973612)
		(width 0.1651)
		(layer "In11.Cu")
		(net "P5E_PEX2_STN4_TX_C_DP<70>")
	)
	(segment
		(start 288.300922 -362.865924)
		(end 288.233612 -363.012736)
		(width 0.1651)
		(layer "In11.Cu")
		(net "P5E_PEX2_STN4_TX_C_DP<70>")
	)
	(segment
		(start 289.689794 -371.972078)
		(end 289.689794 -371.590062)
		(width 0.1651)
		(layer "In11.Cu")
		(net "P5E_PEX2_STN4_TX_C_DP<70>")
	)
	(segment
		(start 290.103814 -368.049556)
		(end 290.25088 -368.116866)
		(width 0.1651)
		(layer "In11.Cu")
		(net "P5E_PEX2_STN4_TX_C_DP<70>")
	)
	(segment
		(start 286.550862 -357.75773)
		(end 286.841692 -358.04856)
		(width 0.1651)
		(layer "In11.Cu")
		(net "P5E_PEX2_STN4_TX_C_DP<70>")
	)
	(segment
		(start 288.977578 -364.687612)
		(end 289.14979 -365.151924)
		(width 0.1651)
		(layer "In11.Cu")
		(net "P5E_PEX2_STN4_TX_C_DP<70>")
	)
	(segment
		(start 289.254692 -365.763302)
		(end 289.402012 -365.830612)
		(width 0.1651)
		(layer "In11.Cu")
		(net "P5E_PEX2_STN4_TX_C_DP<70>")
	)
	(segment
		(start 289.931348 -367.58499)
		(end 290.103814 -368.049556)
		(width 0.1651)
		(layer "In11.Cu")
		(net "P5E_PEX2_STN4_TX_C_DP<70>")
	)
	(segment
		(start 288.233612 -363.012736)
		(end 288.405824 -363.477302)
		(width 0.1651)
		(layer "In11.Cu")
		(net "P5E_PEX2_STN4_TX_C_DP<70>")
	)
	(segment
		(start 289.998658 -367.437924)
		(end 289.931348 -367.58499)
		(width 0.1651)
		(layer "In11.Cu")
		(net "P5E_PEX2_STN4_TX_C_DP<70>")
	)
	(segment
		(start 288.658046 -364.155736)
		(end 288.830258 -364.620302)
		(width 0.1651)
		(layer "In11.Cu")
		(net "P5E_PEX2_STN4_TX_C_DP<70>")
	)
	(segment
		(start 289.402012 -365.830612)
		(end 289.574224 -366.294924)
		(width 0.1651)
		(layer "In11.Cu")
		(net "P5E_PEX2_STN4_TX_C_DP<70>")
	)
	(segment
		(start 289.816794 -372.099078)
		(end 289.689794 -371.972078)
		(width 0.1651)
		(layer "In11.Cu")
		(net "P5E_PEX2_STN4_TX_C_DP<70>")
	)
	(segment
		(start 287.902904 -361.794298)
		(end 287.8582 -361.892088)
		(width 0.1651)
		(layer "In11.Cu")
		(net "P5E_PEX2_STN4_TX_C_DP<70>")
	)
	(segment
		(start 289.506914 -366.441736)
		(end 289.679126 -366.906302)
		(width 0.1651)
		(layer "In11.Cu")
		(net "P5E_PEX2_STN4_TX_C_DP<70>")
	)
	(segment
		(start 288.12871 -362.401612)
		(end 288.300922 -362.865924)
		(width 0.1651)
		(layer "In11.Cu")
		(net "P5E_PEX2_STN4_TX_C_DP<70>")
	)
	(segment
		(start 286.841692 -358.93502)
		(end 287.902904 -361.794298)
		(width 0.1651)
		(layer "In11.Cu")
		(net "P5E_PEX2_STN4_TX_C_DP<70>")
	)
	(segment
		(start 290.24707 -372.099078)
		(end 289.816794 -372.099078)
		(width 0.1651)
		(layer "In11.Cu")
		(net "P5E_PEX2_STN4_TX_C_DP<70>")
	)
	(segment
		(start 286.841692 -358.04856)
		(end 286.841692 -358.93502)
		(width 0.1651)
		(layer "In11.Cu")
		(net "P5E_PEX2_STN4_TX_C_DP<70>")
	)
	(segment
		(start 289.14979 -365.151924)
		(end 289.08248 -365.298736)
		(width 0.1651)
		(layer "In11.Cu")
		(net "P5E_PEX2_STN4_TX_C_DP<70>")
	)
	(segment
		(start 289.574224 -366.294924)
		(end 289.506914 -366.441736)
		(width 0.1651)
		(layer "In11.Cu")
		(net "P5E_PEX2_STN4_TX_C_DP<70>")
	)
	(segment
		(start 288.030666 -362.356908)
		(end 288.12871 -362.401612)
		(width 0.1651)
		(layer "In11.Cu")
		(net "P5E_PEX2_STN4_TX_C_DP<70>")
	)
	(segment
		(start 288.553144 -363.544612)
		(end 288.725356 -364.008924)
		(width 0.1651)
		(layer "In11.Cu")
		(net "P5E_PEX2_STN4_TX_C_DP<70>")
	)
	(segment
		(start 287.8582 -361.892088)
		(end 288.030666 -362.356908)
		(width 0.1651)
		(layer "In11.Cu")
		(net "P5E_PEX2_STN4_TX_C_DP<70>")
	)
	(segment
		(start 290.533836 -371.812312)
		(end 290.24707 -372.099078)
		(width 0.1651)
		(layer "In11.Cu")
		(net "P5E_PEX2_STN4_TX_C_DP<70>")
	)
	(segment
		(start 290.533836 -368.87912)
		(end 290.533836 -371.812312)
		(width 0.1651)
		(layer "In11.Cu")
		(net "P5E_PEX2_STN4_TX_C_DP<70>")
	)
	(segment
		(start 288.405824 -363.477302)
		(end 288.553144 -363.544612)
		(width 0.1651)
		(layer "In11.Cu")
		(net "P5E_PEX2_STN4_TX_C_DP<70>")
	)
	(segment
		(start 288.830258 -364.620302)
		(end 288.977578 -364.687612)
		(width 0.1651)
		(layer "In11.Cu")
		(net "P5E_PEX2_STN4_TX_C_DP<70>")
	)
	(segment
		(start 289.826446 -366.973612)
		(end 289.998658 -367.437924)
		(width 0.1651)
		(layer "In11.Cu")
		(net "P5E_PEX2_STN4_TX_C_DP<70>")
	)
	(segment
		(start 292.73119 -198.156068)
		(end 292.73119 -197.013068)
		(width 0.13208)
		(layer "F.Cu")
		(net "SPI_BIC1_LS23_EN_R_N")
	)
	(segment
		(start 293.605966 -199.718676)
		(end 293.605966 -199.030844)
		(width 0.13208)
		(layer "F.Cu")
		(net "SPI_BIC1_LS23_EN_R_N")
	)
	(segment
		(start 293.605966 -199.030844)
		(end 292.73119 -198.156068)
		(width 0.13208)
		(layer "F.Cu")
		(net "SPI_BIC1_LS23_EN_R_N")
	)
	(segment
		(start 292.73119 -197.013068)
		(end 292.73119 -195.762118)
		(width 0.13208)
		(layer "F.Cu")
		(net "SPI_BIC1_LS23_EN_R_N")
	)
	(via
		(at 292.73119 -197.013068)
		(size 0.762)
		(drill 0.381)
		(layers "F.Cu" "B.Cu")
		(net "SPI_BIC1_LS23_EN_R_N")
	)
	(segment
		(start 29.319474 -392.387328)
		(end 28.456128 -391.840466)
		(width 0.1651)
		(layer "In15.Cu")
		(net "P5E_PEX0_STN4_RX_DP<77>")
	)
	(segment
		(start 32.860234 -394.629894)
		(end 31.809436 -393.964414)
		(width 0.1651)
		(layer "In15.Cu")
		(net "P5E_PEX0_STN4_RX_DP<77>")
	)
	(segment
		(start 55.452772 -328.150474)
		(end 55.453026 -328.150474)
		(width 0.1651)
		(layer "In15.Cu")
		(net "P5E_PEX0_STN4_RX_DP<77>")
	)
	(segment
		(start 33.185862 -395.416278)
		(end 32.860234 -394.629894)
		(width 0.1651)
		(layer "In15.Cu")
		(net "P5E_PEX0_STN4_RX_DP<77>")
	)
	(segment
		(start 29.877766 -392.74115)
		(end 29.755084 -392.768582)
		(width 0.1651)
		(layer "In15.Cu")
		(net "P5E_PEX0_STN4_RX_DP<77>")
	)
	(segment
		(start 17.06372 -352.739706)
		(end 17.06372 -342.14943)
		(width 0.1651)
		(layer "In15.Cu")
		(net "P5E_PEX0_STN4_RX_DP<77>")
	)
	(segment
		(start 75.79995 -316.115192)
		(end 75.79995 -315.849762)
		(width 0.1143)
		(layer "In15.Cu")
		(net "P5E_PEX0_STN4_RX_DP<77>")
	)
	(segment
		(start 68.25107 -324.94474)
		(end 74.570336 -322.32727)
		(width 0.1651)
		(layer "In15.Cu")
		(net "P5E_PEX0_STN4_RX_DP<77>")
	)
	(segment
		(start 33.185862 -404.271734)
		(end 33.185862 -395.416278)
		(width 0.1651)
		(layer "In15.Cu")
		(net "P5E_PEX0_STN4_RX_DP<77>")
	)
	(segment
		(start 74.570336 -322.32727)
		(end 75.184 -321.713606)
		(width 0.1651)
		(layer "In15.Cu")
		(net "P5E_PEX0_STN4_RX_DP<77>")
	)
	(segment
		(start 32.43707 -404.799038)
		(end 32.658558 -404.799038)
		(width 0.1651)
		(layer "In15.Cu")
		(net "P5E_PEX0_STN4_RX_DP<77>")
	)
	(segment
		(start 29.755084 -392.768582)
		(end 29.34716 -392.51001)
		(width 0.1651)
		(layer "In15.Cu")
		(net "P5E_PEX0_STN4_RX_DP<77>")
	)
	(segment
		(start 29.34716 -392.51001)
		(end 29.319728 -392.387328)
		(width 0.1651)
		(layer "In15.Cu")
		(net "P5E_PEX0_STN4_RX_DP<77>")
	)
	(segment
		(start 30.312868 -393.121896)
		(end 30.285436 -392.999214)
		(width 0.1651)
		(layer "In15.Cu")
		(net "P5E_PEX0_STN4_RX_DP<77>")
	)
	(segment
		(start 21.44776 -385.327652)
		(end 20.55876 -376.302016)
		(width 0.1651)
		(layer "In15.Cu")
		(net "P5E_PEX0_STN4_RX_DP<77>")
	)
	(segment
		(start 17.06372 -342.14943)
		(end 17.617694 -340.81212)
		(width 0.1651)
		(layer "In15.Cu")
		(net "P5E_PEX0_STN4_RX_DP<77>")
	)
	(segment
		(start 75.22972 -319.84188)
		(end 75.22972 -316.455298)
		(width 0.1143)
		(layer "In15.Cu")
		(net "P5E_PEX0_STN4_RX_DP<77>")
	)
	(segment
		(start 32.31007 -404.672038)
		(end 32.43707 -404.799038)
		(width 0.1651)
		(layer "In15.Cu")
		(net "P5E_PEX0_STN4_RX_DP<77>")
	)
	(segment
		(start 75.22972 -316.455298)
		(end 75.455526 -316.229492)
		(width 0.1143)
		(layer "In15.Cu")
		(net "P5E_PEX0_STN4_RX_DP<77>")
	)
	(segment
		(start 28.456128 -391.840466)
		(end 26.759662 -391.137902)
		(width 0.1651)
		(layer "In15.Cu")
		(net "P5E_PEX0_STN4_RX_DP<77>")
	)
	(segment
		(start 31.27883 -393.733528)
		(end 31.251144 -393.610846)
		(width 0.1651)
		(layer "In15.Cu")
		(net "P5E_PEX0_STN4_RX_DP<77>")
	)
	(segment
		(start 30.843474 -393.352782)
		(end 30.720792 -393.380214)
		(width 0.1651)
		(layer "In15.Cu")
		(net "P5E_PEX0_STN4_RX_DP<77>")
	)
	(segment
		(start 75.455526 -316.229492)
		(end 75.68565 -316.229492)
		(width 0.1143)
		(layer "In15.Cu")
		(net "P5E_PEX0_STN4_RX_DP<77>")
	)
	(segment
		(start 32.658558 -404.799038)
		(end 33.185862 -404.271734)
		(width 0.1651)
		(layer "In15.Cu")
		(net "P5E_PEX0_STN4_RX_DP<77>")
	)
	(segment
		(start 31.251144 -393.610846)
		(end 30.843474 -393.352782)
		(width 0.1651)
		(layer "In15.Cu")
		(net "P5E_PEX0_STN4_RX_DP<77>")
	)
	(segment
		(start 32.31007 -404.290022)
		(end 32.31007 -404.672038)
		(width 0.1651)
		(layer "In15.Cu")
		(net "P5E_PEX0_STN4_RX_DP<77>")
	)
	(segment
		(start 29.319728 -392.387328)
		(end 29.319474 -392.387328)
		(width 0.1651)
		(layer "In15.Cu")
		(net "P5E_PEX0_STN4_RX_DP<77>")
	)
	(segment
		(start 18.302478 -340.127336)
		(end 18.9611 -339.732112)
		(width 0.1651)
		(layer "In15.Cu")
		(net "P5E_PEX0_STN4_RX_DP<77>")
	)
	(segment
		(start 31.809436 -393.964414)
		(end 31.686754 -393.991846)
		(width 0.1651)
		(layer "In15.Cu")
		(net "P5E_PEX0_STN4_RX_DP<77>")
	)
	(segment
		(start 23.935944 -389.250936)
		(end 22.46249 -387.777482)
		(width 0.1651)
		(layer "In15.Cu")
		(net "P5E_PEX0_STN4_RX_DP<77>")
	)
	(segment
		(start 42.654474 -331.356208)
		(end 55.452772 -328.150474)
		(width 0.1651)
		(layer "In15.Cu")
		(net "P5E_PEX0_STN4_RX_DP<77>")
	)
	(segment
		(start 31.686754 -393.991846)
		(end 31.27883 -393.733528)
		(width 0.1651)
		(layer "In15.Cu")
		(net "P5E_PEX0_STN4_RX_DP<77>")
	)
	(segment
		(start 55.453026 -328.150474)
		(end 68.25107 -324.94474)
		(width 0.1651)
		(layer "In15.Cu")
		(net "P5E_PEX0_STN4_RX_DP<77>")
	)
	(segment
		(start 75.184 -321.713606)
		(end 75.184 -319.916048)
		(width 0.1651)
		(layer "In15.Cu")
		(net "P5E_PEX0_STN4_RX_DP<77>")
	)
	(segment
		(start 26.759662 -391.137902)
		(end 23.935944 -389.250936)
		(width 0.1651)
		(layer "In15.Cu")
		(net "P5E_PEX0_STN4_RX_DP<77>")
	)
	(segment
		(start 18.9611 -339.732112)
		(end 27.45486 -335.96707)
		(width 0.1651)
		(layer "In15.Cu")
		(net "P5E_PEX0_STN4_RX_DP<77>")
	)
	(segment
		(start 30.285436 -392.999214)
		(end 29.877766 -392.74115)
		(width 0.1651)
		(layer "In15.Cu")
		(net "P5E_PEX0_STN4_RX_DP<77>")
	)
	(segment
		(start 75.184 -319.916048)
		(end 75.184 -319.8876)
		(width 0.1143)
		(layer "In15.Cu")
		(net "P5E_PEX0_STN4_RX_DP<77>")
	)
	(segment
		(start 30.720792 -393.380214)
		(end 30.312868 -393.121896)
		(width 0.1651)
		(layer "In15.Cu")
		(net "P5E_PEX0_STN4_RX_DP<77>")
	)
	(segment
		(start 22.46249 -387.777482)
		(end 21.44776 -385.327652)
		(width 0.1651)
		(layer "In15.Cu")
		(net "P5E_PEX0_STN4_RX_DP<77>")
	)
	(segment
		(start 17.617694 -340.81212)
		(end 18.302478 -340.127336)
		(width 0.1651)
		(layer "In15.Cu")
		(net "P5E_PEX0_STN4_RX_DP<77>")
	)
	(segment
		(start 27.45486 -335.96707)
		(end 42.654474 -331.356208)
		(width 0.1651)
		(layer "In15.Cu")
		(net "P5E_PEX0_STN4_RX_DP<77>")
	)
	(segment
		(start 20.55876 -376.302016)
		(end 17.06372 -352.739706)
		(width 0.1651)
		(layer "In15.Cu")
		(net "P5E_PEX0_STN4_RX_DP<77>")
	)
	(segment
		(start 75.184 -319.8876)
		(end 75.22972 -319.84188)
		(width 0.1143)
		(layer "In15.Cu")
		(net "P5E_PEX0_STN4_RX_DP<77>")
	)
	(segment
		(start 75.68565 -316.229492)
		(end 75.79995 -316.115192)
		(width 0.1143)
		(layer "In15.Cu")
		(net "P5E_PEX0_STN4_RX_DP<77>")
	)
	(segment
		(start 307.620162 -316.523624)
		(end 307.620162 -319.86728)
		(width 0.1143)
		(layer "In15.Cu")
		(net "P5E_PEX2_STN4_RX_DN<77>")
	)
	(segment
		(start 293.015924 -404.629112)
		(end 292.564058 -405.080978)
		(width 0.1651)
		(layer "In15.Cu")
		(net "P5E_PEX2_STN4_RX_DN<77>")
	)
	(segment
		(start 291.889942 -405.207978)
		(end 291.889942 -405.589994)
		(width 0.1651)
		(layer "In15.Cu")
		(net "P5E_PEX2_STN4_RX_DN<77>")
	)
	(segment
		(start 283.2354 -340.741)
		(end 282.460192 -341.668608)
		(width 0.1651)
		(layer "In15.Cu")
		(net "P5E_PEX2_STN4_RX_DN<77>")
	)
	(segment
		(start 307.665882 -322.050918)
		(end 306.147216 -323.569584)
		(width 0.1651)
		(layer "In15.Cu")
		(net "P5E_PEX2_STN4_RX_DN<77>")
	)
	(segment
		(start 292.74008 -394.579348)
		(end 293.015924 -395.097)
		(width 0.1651)
		(layer "In15.Cu")
		(net "P5E_PEX2_STN4_RX_DN<77>")
	)
	(segment
		(start 285.763716 -390.760458)
		(end 287.8328 -391.6426)
		(width 0.1651)
		(layer "In15.Cu")
		(net "P5E_PEX2_STN4_RX_DN<77>")
	)
	(segment
		(start 292.564058 -405.080978)
		(end 292.016942 -405.080978)
		(width 0.1651)
		(layer "In15.Cu")
		(net "P5E_PEX2_STN4_RX_DN<77>")
	)
	(segment
		(start 307.999892 -316.799722)
		(end 307.999892 -316.534292)
		(width 0.1143)
		(layer "In15.Cu")
		(net "P5E_PEX2_STN4_RX_DN<77>")
	)
	(segment
		(start 293.015924 -395.097)
		(end 293.015924 -404.629112)
		(width 0.1651)
		(layer "In15.Cu")
		(net "P5E_PEX2_STN4_RX_DN<77>")
	)
	(segment
		(start 281.524964 -385.680458)
		(end 282.659582 -388.461504)
		(width 0.1651)
		(layer "In15.Cu")
		(net "P5E_PEX2_STN4_RX_DN<77>")
	)
	(segment
		(start 307.620162 -319.86728)
		(end 307.665882 -319.913)
		(width 0.1143)
		(layer "In15.Cu")
		(net "P5E_PEX2_STN4_RX_DN<77>")
	)
	(segment
		(start 307.723794 -316.419992)
		(end 307.620162 -316.523624)
		(width 0.1143)
		(layer "In15.Cu")
		(net "P5E_PEX2_STN4_RX_DN<77>")
	)
	(segment
		(start 306.147216 -323.569584)
		(end 283.2354 -340.741)
		(width 0.1651)
		(layer "In15.Cu")
		(net "P5E_PEX2_STN4_RX_DN<77>")
	)
	(segment
		(start 280.97226 -372.28272)
		(end 281.524964 -385.680458)
		(width 0.1651)
		(layer "In15.Cu")
		(net "P5E_PEX2_STN4_RX_DN<77>")
	)
	(segment
		(start 282.460192 -341.668608)
		(end 282.460192 -358.415336)
		(width 0.1651)
		(layer "In15.Cu")
		(net "P5E_PEX2_STN4_RX_DN<77>")
	)
	(segment
		(start 292.016942 -405.080978)
		(end 291.889942 -405.207978)
		(width 0.1651)
		(layer "In15.Cu")
		(net "P5E_PEX2_STN4_RX_DN<77>")
	)
	(segment
		(start 307.665882 -319.913)
		(end 307.665882 -319.941448)
		(width 0.1143)
		(layer "In15.Cu")
		(net "P5E_PEX2_STN4_RX_DN<77>")
	)
	(segment
		(start 307.999892 -316.534292)
		(end 307.885592 -316.419992)
		(width 0.1143)
		(layer "In15.Cu")
		(net "P5E_PEX2_STN4_RX_DN<77>")
	)
	(segment
		(start 307.885592 -316.419992)
		(end 307.723794 -316.419992)
		(width 0.1143)
		(layer "In15.Cu")
		(net "P5E_PEX2_STN4_RX_DN<77>")
	)
	(segment
		(start 282.659582 -388.461504)
		(end 285.763716 -390.760458)
		(width 0.1651)
		(layer "In15.Cu")
		(net "P5E_PEX2_STN4_RX_DN<77>")
	)
	(segment
		(start 282.460192 -358.415336)
		(end 280.97226 -372.28272)
		(width 0.1651)
		(layer "In15.Cu")
		(net "P5E_PEX2_STN4_RX_DN<77>")
	)
	(segment
		(start 307.665882 -319.941448)
		(end 307.665882 -322.050918)
		(width 0.1651)
		(layer "In15.Cu")
		(net "P5E_PEX2_STN4_RX_DN<77>")
	)
	(segment
		(start 287.8328 -391.6426)
		(end 292.74008 -394.579348)
		(width 0.1651)
		(layer "In15.Cu")
		(net "P5E_PEX2_STN4_RX_DN<77>")
	)
	(segment
		(start 292.73119 -194.962018)
		(end 292.73119 -194.196208)
		(width 0.13208)
		(layer "F.Cu")
		(net "SPI_BIC1_LS23_EN_N")
	)
	(via
		(at 292.73119 -194.196208)
		(size 0.508)
		(drill 0.254)
		(layers "F.Cu" "B.Cu")
		(net "SPI_BIC1_LS23_EN_N")
	)
	(segment
		(start 287.4645 -195.290186)
		(end 288.892996 -193.86169)
		(width 0.13208)
		(layer "B.Cu")
		(net "SPI_BIC1_LS23_EN_N")
	)
	(segment
		(start 287.462722 -195.291964)
		(end 287.4645 -195.290186)
		(width 0.13208)
		(layer "B.Cu")
		(net "SPI_BIC1_LS23_EN_N")
	)
	(segment
		(start 288.892996 -193.86169)
		(end 292.396672 -193.86169)
		(width 0.13208)
		(layer "B.Cu")
		(net "SPI_BIC1_LS23_EN_N")
	)
	(segment
		(start 292.396672 -193.86169)
		(end 292.73119 -194.196208)
		(width 0.13208)
		(layer "B.Cu")
		(net "SPI_BIC1_LS23_EN_N")
	)
	(segment
		(start 287.462722 -197.910196)
		(end 287.462722 -195.291964)
		(width 0.13208)
		(layer "B.Cu")
		(net "SPI_BIC1_LS23_EN_N")
	)
	(segment
		(start 37.098224 -393.154154)
		(end 37.07384 -393.03071)
		(width 0.1651)
		(layer "In15.Cu")
		(net "P5E_PEX0_STN4_RX_DP<74>")
	)
	(segment
		(start 78.305406 -318.129666)
		(end 78.53553 -318.129666)
		(width 0.1143)
		(layer "In15.Cu")
		(net "P5E_PEX0_STN4_RX_DP<74>")
	)
	(segment
		(start 38.910006 -405.772112)
		(end 39.037006 -405.899112)
		(width 0.1651)
		(layer "In15.Cu")
		(net "P5E_PEX0_STN4_RX_DP<74>")
	)
	(segment
		(start 38.910006 -405.390096)
		(end 38.910006 -405.772112)
		(width 0.1651)
		(layer "In15.Cu")
		(net "P5E_PEX0_STN4_RX_DP<74>")
	)
	(segment
		(start 24.529288 -341.492078)
		(end 25.325578 -340.695788)
		(width 0.1651)
		(layer "In15.Cu")
		(net "P5E_PEX0_STN4_RX_DP<74>")
	)
	(segment
		(start 78.0796 -319.84188)
		(end 78.0796 -318.355472)
		(width 0.1143)
		(layer "In15.Cu")
		(net "P5E_PEX0_STN4_RX_DP<74>")
	)
	(segment
		(start 37.622988 -393.397994)
		(end 37.499798 -393.422378)
		(width 0.1651)
		(layer "In15.Cu")
		(net "P5E_PEX0_STN4_RX_DP<74>")
	)
	(segment
		(start 78.64983 -318.015366)
		(end 78.64983 -317.749936)
		(width 0.1143)
		(layer "In15.Cu")
		(net "P5E_PEX0_STN4_RX_DP<74>")
	)
	(segment
		(start 78.03388 -319.916048)
		(end 78.03388 -319.8876)
		(width 0.1143)
		(layer "In15.Cu")
		(net "P5E_PEX0_STN4_RX_DP<74>")
	)
	(segment
		(start 35.560254 -392.019536)
		(end 32.484568 -390.375902)
		(width 0.1651)
		(layer "In15.Cu")
		(net "P5E_PEX0_STN4_RX_DP<74>")
	)
	(segment
		(start 23.712932 -371.637306)
		(end 24.286718 -359.97134)
		(width 0.1651)
		(layer "In15.Cu")
		(net "P5E_PEX0_STN4_RX_DP<74>")
	)
	(segment
		(start 76.226924 -324.777862)
		(end 77.945742 -323.059044)
		(width 0.1651)
		(layer "In15.Cu")
		(net "P5E_PEX0_STN4_RX_DP<74>")
	)
	(segment
		(start 43.575478 -334.214978)
		(end 68.540884 -327.961498)
		(width 0.1651)
		(layer "In15.Cu")
		(net "P5E_PEX0_STN4_RX_DP<74>")
	)
	(segment
		(start 77.945742 -323.059044)
		(end 78.03388 -322.846192)
		(width 0.1651)
		(layer "In15.Cu")
		(net "P5E_PEX0_STN4_RX_DP<74>")
	)
	(segment
		(start 25.011126 -386.2197)
		(end 24.35098 -384.626104)
		(width 0.1651)
		(layer "In15.Cu")
		(net "P5E_PEX0_STN4_RX_DP<74>")
	)
	(segment
		(start 39.037006 -405.899112)
		(end 39.270686 -405.899112)
		(width 0.1651)
		(layer "In15.Cu")
		(net "P5E_PEX0_STN4_RX_DP<74>")
	)
	(segment
		(start 25.325578 -340.695788)
		(end 33.844992 -337.166712)
		(width 0.1651)
		(layer "In15.Cu")
		(net "P5E_PEX0_STN4_RX_DP<74>")
	)
	(segment
		(start 72.383904 -326.36968)
		(end 72.384158 -326.369426)
		(width 0.1651)
		(layer "In15.Cu")
		(net "P5E_PEX0_STN4_RX_DP<74>")
	)
	(segment
		(start 68.540884 -327.961498)
		(end 72.383904 -326.36968)
		(width 0.1651)
		(layer "In15.Cu")
		(net "P5E_PEX0_STN4_RX_DP<74>")
	)
	(segment
		(start 24.286718 -342.077548)
		(end 24.529288 -341.492078)
		(width 0.1651)
		(layer "In15.Cu")
		(net "P5E_PEX0_STN4_RX_DP<74>")
	)
	(segment
		(start 78.03388 -319.8876)
		(end 78.0796 -319.84188)
		(width 0.1143)
		(layer "In15.Cu")
		(net "P5E_PEX0_STN4_RX_DP<74>")
	)
	(segment
		(start 39.207186 -394.456412)
		(end 37.622988 -393.397994)
		(width 0.1651)
		(layer "In15.Cu")
		(net "P5E_PEX0_STN4_RX_DP<74>")
	)
	(segment
		(start 24.286718 -359.97134)
		(end 24.286718 -342.077548)
		(width 0.1651)
		(layer "In15.Cu")
		(net "P5E_PEX0_STN4_RX_DP<74>")
	)
	(segment
		(start 33.844992 -337.166712)
		(end 43.575478 -334.214978)
		(width 0.1651)
		(layer "In15.Cu")
		(net "P5E_PEX0_STN4_RX_DP<74>")
	)
	(segment
		(start 37.499798 -393.422378)
		(end 37.098224 -393.154154)
		(width 0.1651)
		(layer "In15.Cu")
		(net "P5E_PEX0_STN4_RX_DP<74>")
	)
	(segment
		(start 78.0796 -318.355472)
		(end 78.305406 -318.129666)
		(width 0.1143)
		(layer "In15.Cu")
		(net "P5E_PEX0_STN4_RX_DP<74>")
	)
	(segment
		(start 28.100528 -388.559802)
		(end 25.841706 -387.05028)
		(width 0.1651)
		(layer "In15.Cu")
		(net "P5E_PEX0_STN4_RX_DP<74>")
	)
	(segment
		(start 32.484568 -390.375902)
		(end 28.100528 -388.559802)
		(width 0.1651)
		(layer "In15.Cu")
		(net "P5E_PEX0_STN4_RX_DP<74>")
	)
	(segment
		(start 78.03388 -322.846192)
		(end 78.03388 -319.916048)
		(width 0.1651)
		(layer "In15.Cu")
		(net "P5E_PEX0_STN4_RX_DP<74>")
	)
	(segment
		(start 78.53553 -318.129666)
		(end 78.64983 -318.015366)
		(width 0.1143)
		(layer "In15.Cu")
		(net "P5E_PEX0_STN4_RX_DP<74>")
	)
	(segment
		(start 37.07384 -393.03071)
		(end 35.560254 -392.019536)
		(width 0.1651)
		(layer "In15.Cu")
		(net "P5E_PEX0_STN4_RX_DP<74>")
	)
	(segment
		(start 39.270686 -405.899112)
		(end 39.785036 -405.384762)
		(width 0.1651)
		(layer "In15.Cu")
		(net "P5E_PEX0_STN4_RX_DP<74>")
	)
	(segment
		(start 25.841706 -387.05028)
		(end 25.011126 -386.2197)
		(width 0.1651)
		(layer "In15.Cu")
		(net "P5E_PEX0_STN4_RX_DP<74>")
	)
	(segment
		(start 72.384158 -326.369426)
		(end 76.226924 -324.777862)
		(width 0.1651)
		(layer "In15.Cu")
		(net "P5E_PEX0_STN4_RX_DP<74>")
	)
	(segment
		(start 39.785036 -405.384762)
		(end 39.785036 -395.851634)
		(width 0.1651)
		(layer "In15.Cu")
		(net "P5E_PEX0_STN4_RX_DP<74>")
	)
	(segment
		(start 39.785036 -395.851634)
		(end 39.207186 -394.456412)
		(width 0.1651)
		(layer "In15.Cu")
		(net "P5E_PEX0_STN4_RX_DP<74>")
	)
	(segment
		(start 24.35098 -384.626104)
		(end 23.712932 -371.637306)
		(width 0.1651)
		(layer "In15.Cu")
		(net "P5E_PEX0_STN4_RX_DP<74>")
	)
	(segment
		(start 277.198582 -350.365314)
		(end 277.518622 -350.685354)
		(width 0.13462)
		(layer "F.Cu")
		(net "P5E_PEX2_STN4_TX_C_DP<75>")
	)
	(segment
		(start 277.518622 -350.685354)
		(end 277.518622 -351.316798)
		(width 0.13462)
		(layer "F.Cu")
		(net "P5E_PEX2_STN4_TX_C_DP<75>")
	)
	(segment
		(start 277.518622 -351.316798)
		(end 277.223982 -351.611438)
		(width 0.13462)
		(layer "F.Cu")
		(net "P5E_PEX2_STN4_TX_C_DP<75>")
	)
	(segment
		(start 293.58463 -392.391646)
		(end 293.617142 -392.549888)
		(width 0.1651)
		(layer "In11.Cu")
		(net "P5E_PEX2_STN4_TX_C_DP<75>")
	)
	(segment
		(start 296.731182 -394.470128)
		(end 297.134026 -395.12367)
		(width 0.1651)
		(layer "In11.Cu")
		(net "P5E_PEX2_STN4_TX_C_DP<75>")
	)
	(segment
		(start 280.77033 -373.834914)
		(end 280.923746 -374.306084)
		(width 0.1651)
		(layer "In11.Cu")
		(net "P5E_PEX2_STN4_TX_C_DP<75>")
	)
	(segment
		(start 275.960332 -353.910646)
		(end 275.960332 -358.786938)
		(width 0.1651)
		(layer "In11.Cu")
		(net "P5E_PEX2_STN4_TX_C_DP<75>")
	)
	(segment
		(start 296.065448 -394.16736)
		(end 296.223944 -394.135102)
		(width 0.1651)
		(layer "In11.Cu")
		(net "P5E_PEX2_STN4_TX_C_DP<75>")
	)
	(segment
		(start 297.134026 -395.12367)
		(end 297.134026 -396.71244)
		(width 0.1651)
		(layer "In11.Cu")
		(net "P5E_PEX2_STN4_TX_C_DP<75>")
	)
	(segment
		(start 296.289984 -396.872206)
		(end 296.289984 -396.49019)
		(width 0.1651)
		(layer "In11.Cu")
		(net "P5E_PEX2_STN4_TX_C_DP<75>")
	)
	(segment
		(start 294.188896 -392.790934)
		(end 294.602154 -393.06373)
		(width 0.1651)
		(layer "In11.Cu")
		(net "P5E_PEX2_STN4_TX_C_DP<75>")
	)
	(segment
		(start 283.166312 -385.444492)
		(end 283.990796 -387.174486)
		(width 0.1651)
		(layer "In11.Cu")
		(net "P5E_PEX2_STN4_TX_C_DP<75>")
	)
	(segment
		(start 295.619678 -393.735814)
		(end 295.651936 -393.89431)
		(width 0.1651)
		(layer "In11.Cu")
		(net "P5E_PEX2_STN4_TX_C_DP<75>")
	)
	(segment
		(start 293.617142 -392.549888)
		(end 294.030654 -392.823192)
		(width 0.1651)
		(layer "In11.Cu")
		(net "P5E_PEX2_STN4_TX_C_DP<75>")
	)
	(segment
		(start 281.398218 -375.473976)
		(end 282.262834 -378.12726)
		(width 0.1651)
		(layer "In11.Cu")
		(net "P5E_PEX2_STN4_TX_C_DP<75>")
	)
	(segment
		(start 296.223944 -394.135102)
		(end 296.731182 -394.470128)
		(width 0.1651)
		(layer "In11.Cu")
		(net "P5E_PEX2_STN4_TX_C_DP<75>")
	)
	(segment
		(start 294.602154 -393.06373)
		(end 294.634666 -393.221972)
		(width 0.1651)
		(layer "In11.Cu")
		(net "P5E_PEX2_STN4_TX_C_DP<75>")
	)
	(segment
		(start 296.416984 -396.999206)
		(end 296.289984 -396.872206)
		(width 0.1651)
		(layer "In11.Cu")
		(net "P5E_PEX2_STN4_TX_C_DP<75>")
	)
	(segment
		(start 277.514812 -352.356166)
		(end 275.960332 -353.910646)
		(width 0.1651)
		(layer "In11.Cu")
		(net "P5E_PEX2_STN4_TX_C_DP<75>")
	)
	(segment
		(start 281.28595 -375.41708)
		(end 281.398218 -375.473976)
		(width 0.1651)
		(layer "In11.Cu")
		(net "P5E_PEX2_STN4_TX_C_DP<75>")
	)
	(segment
		(start 281.18943 -374.833896)
		(end 281.132534 -374.94591)
		(width 0.1651)
		(layer "In11.Cu")
		(net "P5E_PEX2_STN4_TX_C_DP<75>")
	)
	(segment
		(start 296.84726 -396.999206)
		(end 296.416984 -396.999206)
		(width 0.1651)
		(layer "In11.Cu")
		(net "P5E_PEX2_STN4_TX_C_DP<75>")
	)
	(segment
		(start 277.514812 -351.902268)
		(end 277.514812 -352.356166)
		(width 0.1651)
		(layer "In11.Cu")
		(net "P5E_PEX2_STN4_TX_C_DP<75>")
	)
	(segment
		(start 295.20642 -393.463018)
		(end 295.619678 -393.735814)
		(width 0.1651)
		(layer "In11.Cu")
		(net "P5E_PEX2_STN4_TX_C_DP<75>")
	)
	(segment
		(start 295.048178 -393.495276)
		(end 295.20642 -393.463018)
		(width 0.1651)
		(layer "In11.Cu")
		(net "P5E_PEX2_STN4_TX_C_DP<75>")
	)
	(segment
		(start 295.651936 -393.89431)
		(end 296.065448 -394.16736)
		(width 0.1651)
		(layer "In11.Cu")
		(net "P5E_PEX2_STN4_TX_C_DP<75>")
	)
	(segment
		(start 297.134026 -396.71244)
		(end 296.84726 -396.999206)
		(width 0.1651)
		(layer "In11.Cu")
		(net "P5E_PEX2_STN4_TX_C_DP<75>")
	)
	(segment
		(start 281.036014 -374.36298)
		(end 281.18943 -374.833896)
		(width 0.1651)
		(layer "In11.Cu")
		(net "P5E_PEX2_STN4_TX_C_DP<75>")
	)
	(segment
		(start 280.923746 -374.306084)
		(end 281.036014 -374.36298)
		(width 0.1651)
		(layer "In11.Cu")
		(net "P5E_PEX2_STN4_TX_C_DP<75>")
	)
	(segment
		(start 280.827226 -373.7229)
		(end 280.77033 -373.834914)
		(width 0.1651)
		(layer "In11.Cu")
		(net "P5E_PEX2_STN4_TX_C_DP<75>")
	)
	(segment
		(start 275.960332 -358.786938)
		(end 280.827226 -373.7229)
		(width 0.1651)
		(layer "In11.Cu")
		(net "P5E_PEX2_STN4_TX_C_DP<75>")
	)
	(segment
		(start 281.132534 -374.94591)
		(end 281.28595 -375.41708)
		(width 0.1651)
		(layer "In11.Cu")
		(net "P5E_PEX2_STN4_TX_C_DP<75>")
	)
	(segment
		(start 294.030654 -392.823192)
		(end 294.188896 -392.790934)
		(width 0.1651)
		(layer "In11.Cu")
		(net "P5E_PEX2_STN4_TX_C_DP<75>")
	)
	(segment
		(start 277.223982 -351.611438)
		(end 277.514812 -351.902268)
		(width 0.1651)
		(layer "In11.Cu")
		(net "P5E_PEX2_STN4_TX_C_DP<75>")
	)
	(segment
		(start 282.262834 -378.12726)
		(end 283.166312 -385.444492)
		(width 0.1651)
		(layer "In11.Cu")
		(net "P5E_PEX2_STN4_TX_C_DP<75>")
	)
	(segment
		(start 292.21176 -391.484612)
		(end 293.58463 -392.391646)
		(width 0.1651)
		(layer "In11.Cu")
		(net "P5E_PEX2_STN4_TX_C_DP<75>")
	)
	(segment
		(start 294.634666 -393.221972)
		(end 295.048178 -393.495276)
		(width 0.1651)
		(layer "In11.Cu")
		(net "P5E_PEX2_STN4_TX_C_DP<75>")
	)
	(segment
		(start 285.741872 -388.866126)
		(end 292.21176 -391.484612)
		(width 0.1651)
		(layer "In11.Cu")
		(net "P5E_PEX2_STN4_TX_C_DP<75>")
	)
	(segment
		(start 283.990796 -387.174486)
		(end 285.741872 -388.866126)
		(width 0.1651)
		(layer "In11.Cu")
		(net "P5E_PEX2_STN4_TX_C_DP<75>")
	)
	(segment
		(start 49.501552 -363.24794)
		(end 49.807622 -362.875068)
		(width 0.1651)
		(layer "In15.Cu")
		(net "P5E_PEX0_STN4_RX_DP<64>")
	)
	(segment
		(start 97.322894 -325.961248)
		(end 98.411538 -323.333364)
		(width 0.1651)
		(layer "In15.Cu")
		(net "P5E_PEX0_STN4_RX_DP<64>")
	)
	(segment
		(start 43.310048 -379.772164)
		(end 43.437048 -379.899164)
		(width 0.1651)
		(layer "In15.Cu")
		(net "P5E_PEX0_STN4_RX_DP<64>")
	)
	(segment
		(start 49.052226 -363.63529)
		(end 49.35855 -363.26191)
		(width 0.1651)
		(layer "In15.Cu")
		(net "P5E_PEX0_STN4_RX_DP<64>")
	)
	(segment
		(start 81.790794 -304.449734)
		(end 81.499964 -304.449734)
		(width 0.1143)
		(layer "In15.Cu")
		(net "P5E_PEX0_STN4_RX_DP<64>")
	)
	(segment
		(start 45.85843 -367.07699)
		(end 45.85843 -366.933226)
		(width 0.1651)
		(layer "In15.Cu")
		(net "P5E_PEX0_STN4_RX_DP<64>")
	)
	(segment
		(start 45.032168 -367.903252)
		(end 45.032168 -367.759488)
		(width 0.1651)
		(layer "In15.Cu")
		(net "P5E_PEX0_STN4_RX_DP<64>")
	)
	(segment
		(start 49.35855 -363.26191)
		(end 49.501552 -363.24794)
		(width 0.1651)
		(layer "In15.Cu")
		(net "P5E_PEX0_STN4_RX_DP<64>")
	)
	(segment
		(start 43.670728 -379.899164)
		(end 44.17695 -379.392942)
		(width 0.1651)
		(layer "In15.Cu")
		(net "P5E_PEX0_STN4_RX_DP<64>")
	)
	(segment
		(start 60.198762 -341.586058)
		(end 60.876434 -340.908386)
		(width 0.1651)
		(layer "In15.Cu")
		(net "P5E_PEX0_STN4_RX_DP<64>")
	)
	(segment
		(start 50.099976 -362.358686)
		(end 50.242978 -362.344716)
		(width 0.1651)
		(layer "In15.Cu")
		(net "P5E_PEX0_STN4_RX_DP<64>")
	)
	(segment
		(start 81.879694 -304.538634)
		(end 81.790794 -304.449734)
		(width 0.1143)
		(layer "In15.Cu")
		(net "P5E_PEX0_STN4_RX_DP<64>")
	)
	(segment
		(start 50.242978 -362.344716)
		(end 50.242724 -362.344716)
		(width 0.1651)
		(layer "In15.Cu")
		(net "P5E_PEX0_STN4_RX_DP<64>")
	)
	(segment
		(start 98.612198 -321.040252)
		(end 98.612452 -321.040252)
		(width 0.1651)
		(layer "In15.Cu")
		(net "P5E_PEX0_STN4_RX_DP<64>")
	)
	(segment
		(start 46.684692 -366.250728)
		(end 46.684692 -366.106964)
		(width 0.1651)
		(layer "In15.Cu")
		(net "P5E_PEX0_STN4_RX_DP<64>")
	)
	(segment
		(start 47.510954 -365.280702)
		(end 47.852584 -364.939326)
		(width 0.1651)
		(layer "In15.Cu")
		(net "P5E_PEX0_STN4_RX_DP<64>")
	)
	(segment
		(start 43.437048 -379.899164)
		(end 43.670728 -379.899164)
		(width 0.1651)
		(layer "In15.Cu")
		(net "P5E_PEX0_STN4_RX_DP<64>")
	)
	(segment
		(start 45.85843 -366.933226)
		(end 46.20006 -366.59185)
		(width 0.1651)
		(layer "In15.Cu")
		(net "P5E_PEX0_STN4_RX_DP<64>")
	)
	(segment
		(start 45.032168 -367.759488)
		(end 45.373798 -367.418112)
		(width 0.1651)
		(layer "In15.Cu")
		(net "P5E_PEX0_STN4_RX_DP<64>")
	)
	(segment
		(start 64.882522 -339.24875)
		(end 81.142332 -334.316324)
		(width 0.1651)
		(layer "In15.Cu")
		(net "P5E_PEX0_STN4_RX_DP<64>")
	)
	(segment
		(start 98.812858 -318.747394)
		(end 97.343976 -315.201554)
		(width 0.1651)
		(layer "In15.Cu")
		(net "P5E_PEX0_STN4_RX_DP<64>")
	)
	(segment
		(start 83.645248 -305.065684)
		(end 83.6168 -305.065684)
		(width 0.1143)
		(layer "In15.Cu")
		(net "P5E_PEX0_STN4_RX_DP<64>")
	)
	(segment
		(start 98.411538 -323.333364)
		(end 98.612198 -321.040252)
		(width 0.1651)
		(layer "In15.Cu")
		(net "P5E_PEX0_STN4_RX_DP<64>")
	)
	(segment
		(start 49.807622 -362.875068)
		(end 49.793398 -362.732066)
		(width 0.1651)
		(layer "In15.Cu")
		(net "P5E_PEX0_STN4_RX_DP<64>")
	)
	(segment
		(start 45.373798 -367.418112)
		(end 45.517308 -367.418112)
		(width 0.1651)
		(layer "In15.Cu")
		(net "P5E_PEX0_STN4_RX_DP<64>")
	)
	(segment
		(start 46.20006 -366.59185)
		(end 46.34357 -366.59185)
		(width 0.1651)
		(layer "In15.Cu")
		(net "P5E_PEX0_STN4_RX_DP<64>")
	)
	(segment
		(start 45.517308 -367.418112)
		(end 45.85843 -367.07699)
		(width 0.1651)
		(layer "In15.Cu")
		(net "P5E_PEX0_STN4_RX_DP<64>")
	)
	(segment
		(start 47.852584 -364.939326)
		(end 47.996094 -364.939326)
		(width 0.1651)
		(layer "In15.Cu")
		(net "P5E_PEX0_STN4_RX_DP<64>")
	)
	(segment
		(start 43.310048 -379.390148)
		(end 43.310048 -379.772164)
		(width 0.1651)
		(layer "In15.Cu")
		(net "P5E_PEX0_STN4_RX_DP<64>")
	)
	(segment
		(start 44.17695 -369.485418)
		(end 44.691046 -368.244374)
		(width 0.1651)
		(layer "In15.Cu")
		(net "P5E_PEX0_STN4_RX_DP<64>")
	)
	(segment
		(start 96.290384 -327.191878)
		(end 97.322894 -325.961248)
		(width 0.1651)
		(layer "In15.Cu")
		(net "P5E_PEX0_STN4_RX_DP<64>")
	)
	(segment
		(start 97.343976 -315.201554)
		(end 95.192596 -311.98185)
		(width 0.1651)
		(layer "In15.Cu")
		(net "P5E_PEX0_STN4_RX_DP<64>")
	)
	(segment
		(start 46.684692 -366.106964)
		(end 47.026322 -365.765588)
		(width 0.1651)
		(layer "In15.Cu")
		(net "P5E_PEX0_STN4_RX_DP<64>")
	)
	(segment
		(start 60.876434 -340.908386)
		(end 64.882522 -339.24875)
		(width 0.1651)
		(layer "In15.Cu")
		(net "P5E_PEX0_STN4_RX_DP<64>")
	)
	(segment
		(start 47.169832 -365.765588)
		(end 47.510954 -365.424466)
		(width 0.1651)
		(layer "In15.Cu")
		(net "P5E_PEX0_STN4_RX_DP<64>")
	)
	(segment
		(start 47.510954 -365.424466)
		(end 47.510954 -365.280702)
		(width 0.1651)
		(layer "In15.Cu")
		(net "P5E_PEX0_STN4_RX_DP<64>")
	)
	(segment
		(start 81.142332 -334.316324)
		(end 93.625924 -329.145392)
		(width 0.1651)
		(layer "In15.Cu")
		(net "P5E_PEX0_STN4_RX_DP<64>")
	)
	(segment
		(start 52.074826 -360.11231)
		(end 53.258212 -358.341422)
		(width 0.1651)
		(layer "In15.Cu")
		(net "P5E_PEX0_STN4_RX_DP<64>")
	)
	(segment
		(start 53.258212 -358.341422)
		(end 60.198762 -341.586058)
		(width 0.1651)
		(layer "In15.Cu")
		(net "P5E_PEX0_STN4_RX_DP<64>")
	)
	(segment
		(start 47.026322 -365.765588)
		(end 47.169832 -365.765588)
		(width 0.1651)
		(layer "In15.Cu")
		(net "P5E_PEX0_STN4_RX_DP<64>")
	)
	(segment
		(start 83.57108 -305.019964)
		(end 82.1563 -305.019964)
		(width 0.1143)
		(layer "In15.Cu")
		(net "P5E_PEX0_STN4_RX_DP<64>")
	)
	(segment
		(start 46.34357 -366.59185)
		(end 46.684692 -366.250728)
		(width 0.1651)
		(layer "In15.Cu")
		(net "P5E_PEX0_STN4_RX_DP<64>")
	)
	(segment
		(start 98.612452 -321.040252)
		(end 98.812858 -318.747394)
		(width 0.1651)
		(layer "In15.Cu")
		(net "P5E_PEX0_STN4_RX_DP<64>")
	)
	(segment
		(start 49.06645 -363.778292)
		(end 49.052226 -363.63529)
		(width 0.1651)
		(layer "In15.Cu")
		(net "P5E_PEX0_STN4_RX_DP<64>")
	)
	(segment
		(start 86.843108 -305.180492)
		(end 86.565994 -305.065684)
		(width 0.1651)
		(layer "In15.Cu")
		(net "P5E_PEX0_STN4_RX_DP<64>")
	)
	(segment
		(start 90.168984 -306.958238)
		(end 86.843108 -305.180492)
		(width 0.1651)
		(layer "In15.Cu")
		(net "P5E_PEX0_STN4_RX_DP<64>")
	)
	(segment
		(start 86.565994 -305.065684)
		(end 83.645248 -305.065684)
		(width 0.1651)
		(layer "In15.Cu")
		(net "P5E_PEX0_STN4_RX_DP<64>")
	)
	(segment
		(start 47.996094 -364.939326)
		(end 48.651414 -364.284006)
		(width 0.1651)
		(layer "In15.Cu")
		(net "P5E_PEX0_STN4_RX_DP<64>")
	)
	(segment
		(start 50.242724 -362.344716)
		(end 52.074826 -360.11231)
		(width 0.1651)
		(layer "In15.Cu")
		(net "P5E_PEX0_STN4_RX_DP<64>")
	)
	(segment
		(start 82.1563 -305.019964)
		(end 81.879694 -304.743358)
		(width 0.1143)
		(layer "In15.Cu")
		(net "P5E_PEX0_STN4_RX_DP<64>")
	)
	(segment
		(start 44.17695 -379.392942)
		(end 44.17695 -369.485418)
		(width 0.1651)
		(layer "In15.Cu")
		(net "P5E_PEX0_STN4_RX_DP<64>")
	)
	(segment
		(start 95.192596 -311.98185)
		(end 90.168984 -306.958238)
		(width 0.1651)
		(layer "In15.Cu")
		(net "P5E_PEX0_STN4_RX_DP<64>")
	)
	(segment
		(start 83.6168 -305.065684)
		(end 83.57108 -305.019964)
		(width 0.1143)
		(layer "In15.Cu")
		(net "P5E_PEX0_STN4_RX_DP<64>")
	)
	(segment
		(start 44.691046 -368.244374)
		(end 45.032168 -367.903252)
		(width 0.1651)
		(layer "In15.Cu")
		(net "P5E_PEX0_STN4_RX_DP<64>")
	)
	(segment
		(start 48.651414 -364.284006)
		(end 49.06645 -363.778292)
		(width 0.1651)
		(layer "In15.Cu")
		(net "P5E_PEX0_STN4_RX_DP<64>")
	)
	(segment
		(start 49.793398 -362.732066)
		(end 50.099976 -362.358686)
		(width 0.1651)
		(layer "In15.Cu")
		(net "P5E_PEX0_STN4_RX_DP<64>")
	)
	(segment
		(start 81.879694 -304.743358)
		(end 81.879694 -304.538634)
		(width 0.1143)
		(layer "In15.Cu")
		(net "P5E_PEX0_STN4_RX_DP<64>")
	)
	(segment
		(start 93.625924 -329.145392)
		(end 96.290384 -327.191878)
		(width 0.1651)
		(layer "In15.Cu")
		(net "P5E_PEX0_STN4_RX_DP<64>")
	)
	(segment
		(start 279.202642 -386.07873)
		(end 275.960332 -360.6927)
		(width 0.1651)
		(layer "In15.Cu")
		(net "P5E_PEX2_STN4_RX_DP<79>")
	)
	(segment
		(start 282.825952 -391.495788)
		(end 282.808934 -391.371328)
		(width 0.1651)
		(layer "In15.Cu")
		(net "P5E_PEX2_STN4_RX_DP<79>")
	)
	(segment
		(start 276.384258 -341.058754)
		(end 304.990246 -321.584574)
		(width 0.1651)
		(layer "In15.Cu")
		(net "P5E_PEX2_STN4_RX_DP<79>")
	)
	(segment
		(start 283.345128 -391.778744)
		(end 283.220414 -391.795762)
		(width 0.1651)
		(layer "In15.Cu")
		(net "P5E_PEX2_STN4_RX_DP<79>")
	)
	(segment
		(start 288.074354 -394.697712)
		(end 287.3883 -394.037058)
		(width 0.1651)
		(layer "In15.Cu")
		(net "P5E_PEX2_STN4_RX_DP<79>")
	)
	(segment
		(start 286.459676 -393.618212)
		(end 286.342074 -393.662662)
		(width 0.1651)
		(layer "In15.Cu")
		(net "P5E_PEX2_STN4_RX_DP<79>")
	)
	(segment
		(start 287.4899 -404.290022)
		(end 287.4899 -404.672038)
		(width 0.1651)
		(layer "In15.Cu")
		(net "P5E_PEX2_STN4_RX_DP<79>")
	)
	(segment
		(start 287.3883 -394.037058)
		(end 286.459676 -393.618212)
		(width 0.1651)
		(layer "In15.Cu")
		(net "P5E_PEX2_STN4_RX_DP<79>")
	)
	(segment
		(start 287.4899 -404.672038)
		(end 287.6169 -404.799038)
		(width 0.1651)
		(layer "In15.Cu")
		(net "P5E_PEX2_STN4_RX_DP<79>")
	)
	(segment
		(start 284.27553 -392.485626)
		(end 284.150816 -392.502644)
		(width 0.1651)
		(layer "In15.Cu")
		(net "P5E_PEX2_STN4_RX_DP<79>")
	)
	(segment
		(start 305.744626 -316.229492)
		(end 305.985418 -316.229492)
		(width 0.1143)
		(layer "In15.Cu")
		(net "P5E_PEX2_STN4_RX_DP<79>")
	)
	(segment
		(start 287.6169 -404.799038)
		(end 288.047176 -404.799038)
		(width 0.1651)
		(layer "In15.Cu")
		(net "P5E_PEX2_STN4_RX_DP<79>")
	)
	(segment
		(start 275.960332 -360.6927)
		(end 275.960332 -341.946992)
		(width 0.1651)
		(layer "In15.Cu")
		(net "P5E_PEX2_STN4_RX_DP<79>")
	)
	(segment
		(start 288.333942 -404.512272)
		(end 288.333942 -395.37767)
		(width 0.1651)
		(layer "In15.Cu")
		(net "P5E_PEX2_STN4_RX_DP<79>")
	)
	(segment
		(start 284.751526 -392.847322)
		(end 284.27553 -392.485626)
		(width 0.1651)
		(layer "In15.Cu")
		(net "P5E_PEX2_STN4_RX_DP<79>")
	)
	(segment
		(start 280.863802 -389.893556)
		(end 279.202642 -386.07873)
		(width 0.1651)
		(layer "In15.Cu")
		(net "P5E_PEX2_STN4_RX_DP<79>")
	)
	(segment
		(start 283.220414 -391.795762)
		(end 282.825952 -391.495788)
		(width 0.1651)
		(layer "In15.Cu")
		(net "P5E_PEX2_STN4_RX_DP<79>")
	)
	(segment
		(start 305.985418 -316.229492)
		(end 306.099718 -316.115192)
		(width 0.1143)
		(layer "In15.Cu")
		(net "P5E_PEX2_STN4_RX_DP<79>")
	)
	(segment
		(start 305.529488 -319.86728)
		(end 305.529488 -316.44463)
		(width 0.1143)
		(layer "In15.Cu")
		(net "P5E_PEX2_STN4_RX_DP<79>")
	)
	(segment
		(start 284.150816 -392.502644)
		(end 283.7561 -392.20267)
		(width 0.1651)
		(layer "In15.Cu")
		(net "P5E_PEX2_STN4_RX_DP<79>")
	)
	(segment
		(start 305.483768 -319.941448)
		(end 305.483768 -319.913)
		(width 0.1143)
		(layer "In15.Cu")
		(net "P5E_PEX2_STN4_RX_DP<79>")
	)
	(segment
		(start 306.099718 -316.115192)
		(end 306.099718 -315.849762)
		(width 0.1143)
		(layer "In15.Cu")
		(net "P5E_PEX2_STN4_RX_DP<79>")
	)
	(segment
		(start 305.483768 -321.091052)
		(end 305.483768 -319.941448)
		(width 0.1651)
		(layer "In15.Cu")
		(net "P5E_PEX2_STN4_RX_DP<79>")
	)
	(segment
		(start 282.808934 -391.371328)
		(end 280.863802 -389.893556)
		(width 0.1651)
		(layer "In15.Cu")
		(net "P5E_PEX2_STN4_RX_DP<79>")
	)
	(segment
		(start 285.845758 -393.341098)
		(end 284.751526 -392.847322)
		(width 0.1651)
		(layer "In15.Cu")
		(net "P5E_PEX2_STN4_RX_DP<79>")
	)
	(segment
		(start 305.529488 -316.44463)
		(end 305.744626 -316.229492)
		(width 0.1143)
		(layer "In15.Cu")
		(net "P5E_PEX2_STN4_RX_DP<79>")
	)
	(segment
		(start 283.7561 -392.20267)
		(end 283.739336 -392.07821)
		(width 0.1651)
		(layer "In15.Cu")
		(net "P5E_PEX2_STN4_RX_DP<79>")
	)
	(segment
		(start 288.047176 -404.799038)
		(end 288.333942 -404.512272)
		(width 0.1651)
		(layer "In15.Cu")
		(net "P5E_PEX2_STN4_RX_DP<79>")
	)
	(segment
		(start 275.960332 -341.946992)
		(end 276.384258 -341.058754)
		(width 0.1651)
		(layer "In15.Cu")
		(net "P5E_PEX2_STN4_RX_DP<79>")
	)
	(segment
		(start 288.333942 -395.37767)
		(end 288.074354 -394.697712)
		(width 0.1651)
		(layer "In15.Cu")
		(net "P5E_PEX2_STN4_RX_DP<79>")
	)
	(segment
		(start 283.739336 -392.07821)
		(end 283.345128 -391.778744)
		(width 0.1651)
		(layer "In15.Cu")
		(net "P5E_PEX2_STN4_RX_DP<79>")
	)
	(segment
		(start 286.342074 -393.662662)
		(end 285.890208 -393.4587)
		(width 0.1651)
		(layer "In15.Cu")
		(net "P5E_PEX2_STN4_RX_DP<79>")
	)
	(segment
		(start 304.990246 -321.584574)
		(end 305.483768 -321.091052)
		(width 0.1651)
		(layer "In15.Cu")
		(net "P5E_PEX2_STN4_RX_DP<79>")
	)
	(segment
		(start 285.890208 -393.4587)
		(end 285.845758 -393.341098)
		(width 0.1651)
		(layer "In15.Cu")
		(net "P5E_PEX2_STN4_RX_DP<79>")
	)
	(segment
		(start 305.483768 -319.913)
		(end 305.529488 -319.86728)
		(width 0.1143)
		(layer "In15.Cu")
		(net "P5E_PEX2_STN4_RX_DP<79>")
	)
	(segment
		(start 48.176688 -351.611438)
		(end 47.882048 -351.316798)
		(width 0.13462)
		(layer "F.Cu")
		(net "P5E_PEX0_STN4_TX_C_DN<66>")
	)
	(segment
		(start 47.882048 -351.316798)
		(end 47.882048 -350.685354)
		(width 0.13462)
		(layer "F.Cu")
		(net "P5E_PEX0_STN4_TX_C_DN<66>")
	)
	(segment
		(start 47.882048 -350.685354)
		(end 48.202088 -350.365314)
		(width 0.13462)
		(layer "F.Cu")
		(net "P5E_PEX0_STN4_TX_C_DN<66>")
	)
	(segment
		(start 39.577264 -372.381018)
		(end 40.084248 -371.874034)
		(width 0.1651)
		(layer "In11.Cu")
		(net "P5E_PEX0_STN4_TX_C_DN<66>")
	)
	(segment
		(start 47.885858 -351.902268)
		(end 48.176688 -351.611438)
		(width 0.1651)
		(layer "In11.Cu")
		(net "P5E_PEX0_STN4_TX_C_DN<66>")
	)
	(segment
		(start 39.037006 -372.381018)
		(end 39.577264 -372.381018)
		(width 0.1651)
		(layer "In11.Cu")
		(net "P5E_PEX0_STN4_TX_C_DN<66>")
	)
	(segment
		(start 38.910006 -372.508018)
		(end 39.037006 -372.381018)
		(width 0.1651)
		(layer "In11.Cu")
		(net "P5E_PEX0_STN4_TX_C_DN<66>")
	)
	(segment
		(start 40.084248 -368.454686)
		(end 46.331378 -359.105708)
		(width 0.1651)
		(layer "In11.Cu")
		(net "P5E_PEX0_STN4_TX_C_DN<66>")
	)
	(segment
		(start 40.084248 -371.874034)
		(end 40.084248 -368.454686)
		(width 0.1651)
		(layer "In11.Cu")
		(net "P5E_PEX0_STN4_TX_C_DN<66>")
	)
	(segment
		(start 46.331378 -359.105708)
		(end 46.331378 -354.092002)
		(width 0.1651)
		(layer "In11.Cu")
		(net "P5E_PEX0_STN4_TX_C_DN<66>")
	)
	(segment
		(start 38.910006 -372.890034)
		(end 38.910006 -372.508018)
		(width 0.1651)
		(layer "In11.Cu")
		(net "P5E_PEX0_STN4_TX_C_DN<66>")
	)
	(segment
		(start 46.331378 -354.092002)
		(end 47.885858 -352.537522)
		(width 0.1651)
		(layer "In11.Cu")
		(net "P5E_PEX0_STN4_TX_C_DN<66>")
	)
	(segment
		(start 47.885858 -352.537522)
		(end 47.885858 -351.902268)
		(width 0.1651)
		(layer "In11.Cu")
		(net "P5E_PEX0_STN4_TX_C_DN<66>")
	)
	(segment
		(start 44.498768 -355.026722)
		(end 44.204128 -354.732082)
		(width 0.13462)
		(layer "F.Cu")
		(net "P5E_PEX0_STN4_TX_DP<67>")
	)
	(segment
		(start 44.178728 -355.978206)
		(end 44.498768 -355.658166)
		(width 0.13462)
		(layer "F.Cu")
		(net "P5E_PEX0_STN4_TX_DP<67>")
	)
	(segment
		(start 44.498768 -355.658166)
		(end 44.498768 -355.026722)
		(width 0.13462)
		(layer "F.Cu")
		(net "P5E_PEX0_STN4_TX_DP<67>")
	)
	(segment
		(start 83.6168 -307.92674)
		(end 83.57108 -307.88102)
		(width 0.1143)
		(layer "In11.Cu")
		(net "P5E_PEX0_STN4_TX_DP<67>")
	)
	(segment
		(start 83.645248 -307.92674)
		(end 83.6168 -307.92674)
		(width 0.1143)
		(layer "In11.Cu")
		(net "P5E_PEX0_STN4_TX_DP<67>")
	)
	(segment
		(start 77.12964 -307.597556)
		(end 77.12964 -307.388768)
		(width 0.1143)
		(layer "In11.Cu")
		(net "P5E_PEX0_STN4_TX_DP<67>")
	)
	(segment
		(start 77.413104 -307.88102)
		(end 77.12964 -307.597556)
		(width 0.1143)
		(layer "In11.Cu")
		(net "P5E_PEX0_STN4_TX_DP<67>")
	)
	(segment
		(start 83.83143 -307.92674)
		(end 83.645248 -307.92674)
		(width 0.1651)
		(layer "In11.Cu")
		(net "P5E_PEX0_STN4_TX_DP<67>")
	)
	(segment
		(start 77.12964 -307.388768)
		(end 77.04074 -307.299868)
		(width 0.1143)
		(layer "In11.Cu")
		(net "P5E_PEX0_STN4_TX_DP<67>")
	)
	(segment
		(start 46.389544 -341.087202)
		(end 47.22495 -340.251796)
		(width 0.1651)
		(layer "In11.Cu")
		(net "P5E_PEX0_STN4_TX_DP<67>")
	)
	(segment
		(start 44.494958 -354.441252)
		(end 44.494958 -353.657662)
		(width 0.1651)
		(layer "In11.Cu")
		(net "P5E_PEX0_STN4_TX_DP<67>")
	)
	(segment
		(start 95.366586 -317.081154)
		(end 93.468698 -315.183266)
		(width 0.1651)
		(layer "In11.Cu")
		(net "P5E_PEX0_STN4_TX_DP<67>")
	)
	(segment
		(start 57.699656 -336.115152)
		(end 78.957424 -331.887322)
		(width 0.1651)
		(layer "In11.Cu")
		(net "P5E_PEX0_STN4_TX_DP<67>")
	)
	(segment
		(start 78.957424 -331.887322)
		(end 93.500194 -326.684132)
		(width 0.1651)
		(layer "In11.Cu")
		(net "P5E_PEX0_STN4_TX_DP<67>")
	)
	(segment
		(start 83.57108 -307.88102)
		(end 77.413104 -307.88102)
		(width 0.1143)
		(layer "In11.Cu")
		(net "P5E_PEX0_STN4_TX_DP<67>")
	)
	(segment
		(start 95.296482 -324.887844)
		(end 96.392238 -322.242434)
		(width 0.1651)
		(layer "In11.Cu")
		(net "P5E_PEX0_STN4_TX_DP<67>")
	)
	(segment
		(start 44.494958 -353.657662)
		(end 46.049438 -352.103182)
		(width 0.1651)
		(layer "In11.Cu")
		(net "P5E_PEX0_STN4_TX_DP<67>")
	)
	(segment
		(start 49.42459 -339.076284)
		(end 57.699656 -336.115152)
		(width 0.1651)
		(layer "In11.Cu")
		(net "P5E_PEX0_STN4_TX_DP<67>")
	)
	(segment
		(start 96.392238 -319.5574)
		(end 95.366586 -317.081154)
		(width 0.1651)
		(layer "In11.Cu")
		(net "P5E_PEX0_STN4_TX_DP<67>")
	)
	(segment
		(start 93.500194 -326.684132)
		(end 95.296482 -324.887844)
		(width 0.1651)
		(layer "In11.Cu")
		(net "P5E_PEX0_STN4_TX_DP<67>")
	)
	(segment
		(start 44.204128 -354.732082)
		(end 44.494958 -354.441252)
		(width 0.1651)
		(layer "In11.Cu")
		(net "P5E_PEX0_STN4_TX_DP<67>")
	)
	(segment
		(start 46.049438 -341.908638)
		(end 46.389544 -341.087202)
		(width 0.1651)
		(layer "In11.Cu")
		(net "P5E_PEX0_STN4_TX_DP<67>")
	)
	(segment
		(start 84.323174 -308.02453)
		(end 83.83143 -307.92674)
		(width 0.1651)
		(layer "In11.Cu")
		(net "P5E_PEX0_STN4_TX_DP<67>")
	)
	(segment
		(start 77.04074 -307.299868)
		(end 76.74991 -307.299868)
		(width 0.1143)
		(layer "In11.Cu")
		(net "P5E_PEX0_STN4_TX_DP<67>")
	)
	(segment
		(start 47.22495 -340.251796)
		(end 49.42459 -339.076284)
		(width 0.1651)
		(layer "In11.Cu")
		(net "P5E_PEX0_STN4_TX_DP<67>")
	)
	(segment
		(start 85.122766 -308.355746)
		(end 84.323174 -308.02453)
		(width 0.1651)
		(layer "In11.Cu")
		(net "P5E_PEX0_STN4_TX_DP<67>")
	)
	(segment
		(start 96.392238 -322.242434)
		(end 96.392238 -319.5574)
		(width 0.1651)
		(layer "In11.Cu")
		(net "P5E_PEX0_STN4_TX_DP<67>")
	)
	(segment
		(start 93.468698 -315.183266)
		(end 90.876374 -314.109354)
		(width 0.1651)
		(layer "In11.Cu")
		(net "P5E_PEX0_STN4_TX_DP<67>")
	)
	(segment
		(start 46.049438 -352.103182)
		(end 46.049438 -341.908638)
		(width 0.1651)
		(layer "In11.Cu")
		(net "P5E_PEX0_STN4_TX_DP<67>")
	)
	(segment
		(start 90.876374 -314.109354)
		(end 85.122766 -308.355746)
		(width 0.1651)
		(layer "In11.Cu")
		(net "P5E_PEX0_STN4_TX_DP<67>")
	)
	(segment
		(start 314.39739 -316.799722)
		(end 314.649866 -316.799722)
		(width 0.1143)
		(layer "In15.Cu")
		(net "P5E_PEX2_STN4_RX_DN<71>")
	)
	(segment
		(start 314.315856 -318.9732)
		(end 314.270136 -318.92748)
		(width 0.1143)
		(layer "In15.Cu")
		(net "P5E_PEX2_STN4_RX_DN<71>")
	)
	(segment
		(start 288.615882 -369.316)
		(end 289.0266 -368.7064)
		(width 0.1651)
		(layer "In15.Cu")
		(net "P5E_PEX2_STN4_RX_DN<71>")
	)
	(segment
		(start 300.818804 -358.72674)
		(end 314.315856 -321.405504)
		(width 0.1651)
		(layer "In15.Cu")
		(net "P5E_PEX2_STN4_RX_DN<71>")
	)
	(segment
		(start 314.315856 -321.405504)
		(end 314.315856 -319.001648)
		(width 0.1651)
		(layer "In15.Cu")
		(net "P5E_PEX2_STN4_RX_DN<71>")
	)
	(segment
		(start 288.164016 -379.08103)
		(end 288.615882 -378.629164)
		(width 0.1651)
		(layer "In15.Cu")
		(net "P5E_PEX2_STN4_RX_DN<71>")
	)
	(segment
		(start 287.6169 -379.08103)
		(end 288.164016 -379.08103)
		(width 0.1651)
		(layer "In15.Cu")
		(net "P5E_PEX2_STN4_RX_DN<71>")
	)
	(segment
		(start 289.0266 -368.7064)
		(end 300.818804 -358.72674)
		(width 0.1651)
		(layer "In15.Cu")
		(net "P5E_PEX2_STN4_RX_DN<71>")
	)
	(segment
		(start 287.4899 -379.20803)
		(end 287.6169 -379.08103)
		(width 0.1651)
		(layer "In15.Cu")
		(net "P5E_PEX2_STN4_RX_DN<71>")
	)
	(segment
		(start 314.315856 -319.001648)
		(end 314.315856 -318.9732)
		(width 0.1143)
		(layer "In15.Cu")
		(net "P5E_PEX2_STN4_RX_DN<71>")
	)
	(segment
		(start 288.615882 -378.629164)
		(end 288.615882 -369.316)
		(width 0.1651)
		(layer "In15.Cu")
		(net "P5E_PEX2_STN4_RX_DN<71>")
	)
	(segment
		(start 287.4899 -379.590046)
		(end 287.4899 -379.20803)
		(width 0.1651)
		(layer "In15.Cu")
		(net "P5E_PEX2_STN4_RX_DN<71>")
	)
	(segment
		(start 314.270136 -318.92748)
		(end 314.270136 -316.926976)
		(width 0.1143)
		(layer "In15.Cu")
		(net "P5E_PEX2_STN4_RX_DN<71>")
	)
	(segment
		(start 314.270136 -316.926976)
		(end 314.39739 -316.799722)
		(width 0.1143)
		(layer "In15.Cu")
		(net "P5E_PEX2_STN4_RX_DN<71>")
	)
	(segment
		(start 38.04539 -368.173762)
		(end 38.72738 -367.342674)
		(width 0.1651)
		(layer "In15.Cu")
		(net "P5E_PEX0_STN4_RX_DP<67>")
	)
	(segment
		(start 36.710112 -378.67209)
		(end 36.837112 -378.79909)
		(width 0.1651)
		(layer "In15.Cu")
		(net "P5E_PEX0_STN4_RX_DP<67>")
	)
	(segment
		(start 43.272202 -361.804966)
		(end 43.256454 -361.644184)
		(width 0.1651)
		(layer "In15.Cu")
		(net "P5E_PEX0_STN4_RX_DP<67>")
	)
	(segment
		(start 37.0586 -378.79909)
		(end 37.585904 -378.271786)
		(width 0.1651)
		(layer "In15.Cu")
		(net "P5E_PEX0_STN4_RX_DP<67>")
	)
	(segment
		(start 45.472096 -359.124758)
		(end 45.886624 -358.503982)
		(width 0.1651)
		(layer "In15.Cu")
		(net "P5E_PEX0_STN4_RX_DP<67>")
	)
	(segment
		(start 94.264988 -325.098918)
		(end 94.822518 -324.4342)
		(width 0.1651)
		(layer "In15.Cu")
		(net "P5E_PEX0_STN4_RX_DP<67>")
	)
	(segment
		(start 43.72356 -361.255056)
		(end 45.472096 -359.124758)
		(width 0.1651)
		(layer "In15.Cu")
		(net "P5E_PEX0_STN4_RX_DP<67>")
	)
	(segment
		(start 79.89062 -307.299868)
		(end 79.59979 -307.299868)
		(width 0.1143)
		(layer "In15.Cu")
		(net "P5E_PEX0_STN4_RX_DP<67>")
	)
	(segment
		(start 83.57108 -307.870098)
		(end 80.256126 -307.870098)
		(width 0.1143)
		(layer "In15.Cu")
		(net "P5E_PEX0_STN4_RX_DP<67>")
	)
	(segment
		(start 37.585904 -369.458494)
		(end 38.04539 -368.173762)
		(width 0.1651)
		(layer "In15.Cu")
		(net "P5E_PEX0_STN4_RX_DP<67>")
	)
	(segment
		(start 38.72738 -367.342674)
		(end 38.711632 -367.181892)
		(width 0.1651)
		(layer "In15.Cu")
		(net "P5E_PEX0_STN4_RX_DP<67>")
	)
	(segment
		(start 83.645248 -307.915818)
		(end 83.6168 -307.915818)
		(width 0.1143)
		(layer "In15.Cu")
		(net "P5E_PEX0_STN4_RX_DP<67>")
	)
	(segment
		(start 83.6168 -307.915818)
		(end 83.57108 -307.870098)
		(width 0.1143)
		(layer "In15.Cu")
		(net "P5E_PEX0_STN4_RX_DP<67>")
	)
	(segment
		(start 42.80535 -362.193586)
		(end 42.966132 -362.177838)
		(width 0.1651)
		(layer "In15.Cu")
		(net "P5E_PEX0_STN4_RX_DP<67>")
	)
	(segment
		(start 40.999918 -364.57382)
		(end 40.98417 -364.412784)
		(width 0.1651)
		(layer "In15.Cu")
		(net "P5E_PEX0_STN4_RX_DP<67>")
	)
	(segment
		(start 70.510908 -334.501744)
		(end 78.862682 -331.973682)
		(width 0.1651)
		(layer "In15.Cu")
		(net "P5E_PEX0_STN4_RX_DP<67>")
	)
	(segment
		(start 39.775638 -365.88573)
		(end 39.93642 -365.869728)
		(width 0.1651)
		(layer "In15.Cu")
		(net "P5E_PEX0_STN4_RX_DP<67>")
	)
	(segment
		(start 40.24249 -365.496856)
		(end 40.226742 -365.33582)
		(width 0.1651)
		(layer "In15.Cu")
		(net "P5E_PEX0_STN4_RX_DP<67>")
	)
	(segment
		(start 42.514774 -362.727748)
		(end 42.499026 -362.566966)
		(width 0.1651)
		(layer "In15.Cu")
		(net "P5E_PEX0_STN4_RX_DP<67>")
	)
	(segment
		(start 42.966132 -362.177838)
		(end 43.272202 -361.804966)
		(width 0.1651)
		(layer "In15.Cu")
		(net "P5E_PEX0_STN4_RX_DP<67>")
	)
	(segment
		(start 95.829374 -319.532508)
		(end 94.460822 -316.228222)
		(width 0.1651)
		(layer "In15.Cu")
		(net "P5E_PEX0_STN4_RX_DP<67>")
	)
	(segment
		(start 85.650578 -307.915818)
		(end 83.645248 -307.915818)
		(width 0.1651)
		(layer "In15.Cu")
		(net "P5E_PEX0_STN4_RX_DP<67>")
	)
	(segment
		(start 95.5548 -322.666106)
		(end 95.829374 -319.532508)
		(width 0.1651)
		(layer "In15.Cu")
		(net "P5E_PEX0_STN4_RX_DP<67>")
	)
	(segment
		(start 43.562778 -361.270804)
		(end 43.72356 -361.255056)
		(width 0.1651)
		(layer "In15.Cu")
		(net "P5E_PEX0_STN4_RX_DP<67>")
	)
	(segment
		(start 40.533066 -364.962694)
		(end 40.693848 -364.946692)
		(width 0.1651)
		(layer "In15.Cu")
		(net "P5E_PEX0_STN4_RX_DP<67>")
	)
	(segment
		(start 43.256454 -361.644184)
		(end 43.562778 -361.270804)
		(width 0.1651)
		(layer "In15.Cu")
		(net "P5E_PEX0_STN4_RX_DP<67>")
	)
	(segment
		(start 79.97952 -307.593492)
		(end 79.97952 -307.388768)
		(width 0.1143)
		(layer "In15.Cu")
		(net "P5E_PEX0_STN4_RX_DP<67>")
	)
	(segment
		(start 38.711632 -367.181892)
		(end 39.017956 -366.808512)
		(width 0.1651)
		(layer "In15.Cu")
		(net "P5E_PEX0_STN4_RX_DP<67>")
	)
	(segment
		(start 41.741598 -363.490002)
		(end 42.047922 -363.116622)
		(width 0.1651)
		(layer "In15.Cu")
		(net "P5E_PEX0_STN4_RX_DP<67>")
	)
	(segment
		(start 36.837112 -378.79909)
		(end 37.0586 -378.79909)
		(width 0.1651)
		(layer "In15.Cu")
		(net "P5E_PEX0_STN4_RX_DP<67>")
	)
	(segment
		(start 42.208704 -363.10062)
		(end 42.514774 -362.727748)
		(width 0.1651)
		(layer "In15.Cu")
		(net "P5E_PEX0_STN4_RX_DP<67>")
	)
	(segment
		(start 36.710112 -378.290074)
		(end 36.710112 -378.67209)
		(width 0.1651)
		(layer "In15.Cu")
		(net "P5E_PEX0_STN4_RX_DP<67>")
	)
	(segment
		(start 39.46906 -366.258856)
		(end 39.775638 -365.88573)
		(width 0.1651)
		(layer "In15.Cu")
		(net "P5E_PEX0_STN4_RX_DP<67>")
	)
	(segment
		(start 42.047922 -363.116622)
		(end 42.208704 -363.10062)
		(width 0.1651)
		(layer "In15.Cu")
		(net "P5E_PEX0_STN4_RX_DP<67>")
	)
	(segment
		(start 37.585904 -378.271786)
		(end 37.585904 -369.458494)
		(width 0.1651)
		(layer "In15.Cu")
		(net "P5E_PEX0_STN4_RX_DP<67>")
	)
	(segment
		(start 94.822518 -324.4342)
		(end 95.5548 -322.666106)
		(width 0.1651)
		(layer "In15.Cu")
		(net "P5E_PEX0_STN4_RX_DP<67>")
	)
	(segment
		(start 39.017956 -366.808512)
		(end 39.178992 -366.792764)
		(width 0.1651)
		(layer "In15.Cu")
		(net "P5E_PEX0_STN4_RX_DP<67>")
	)
	(segment
		(start 39.178992 -366.792764)
		(end 39.485062 -366.419892)
		(width 0.1651)
		(layer "In15.Cu")
		(net "P5E_PEX0_STN4_RX_DP<67>")
	)
	(segment
		(start 42.499026 -362.566966)
		(end 42.80535 -362.193586)
		(width 0.1651)
		(layer "In15.Cu")
		(net "P5E_PEX0_STN4_RX_DP<67>")
	)
	(segment
		(start 45.886624 -358.503982)
		(end 46.049438 -357.968042)
		(width 0.1651)
		(layer "In15.Cu")
		(net "P5E_PEX0_STN4_RX_DP<67>")
	)
	(segment
		(start 40.98417 -364.412784)
		(end 41.290494 -364.039658)
		(width 0.1651)
		(layer "In15.Cu")
		(net "P5E_PEX0_STN4_RX_DP<67>")
	)
	(segment
		(start 79.97952 -307.388768)
		(end 79.89062 -307.299868)
		(width 0.1143)
		(layer "In15.Cu")
		(net "P5E_PEX0_STN4_RX_DP<67>")
	)
	(segment
		(start 46.049438 -357.968042)
		(end 46.049438 -341.36076)
		(width 0.1651)
		(layer "In15.Cu")
		(net "P5E_PEX0_STN4_RX_DP<67>")
	)
	(segment
		(start 78.862682 -331.973682)
		(end 92.714064 -326.236584)
		(width 0.1651)
		(layer "In15.Cu")
		(net "P5E_PEX0_STN4_RX_DP<67>")
	)
	(segment
		(start 87.151718 -308.919118)
		(end 85.650578 -307.915818)
		(width 0.1651)
		(layer "In15.Cu")
		(net "P5E_PEX0_STN4_RX_DP<67>")
	)
	(segment
		(start 50.269902 -339.552534)
		(end 70.510908 -334.501744)
		(width 0.1651)
		(layer "In15.Cu")
		(net "P5E_PEX0_STN4_RX_DP<67>")
	)
	(segment
		(start 46.810422 -340.599776)
		(end 50.269902 -339.552534)
		(width 0.1651)
		(layer "In15.Cu")
		(net "P5E_PEX0_STN4_RX_DP<67>")
	)
	(segment
		(start 46.049438 -341.36076)
		(end 46.810422 -340.599776)
		(width 0.1651)
		(layer "In15.Cu")
		(net "P5E_PEX0_STN4_RX_DP<67>")
	)
	(segment
		(start 39.93642 -365.869728)
		(end 40.24249 -365.496856)
		(width 0.1651)
		(layer "In15.Cu")
		(net "P5E_PEX0_STN4_RX_DP<67>")
	)
	(segment
		(start 41.290494 -364.039658)
		(end 41.451276 -364.023656)
		(width 0.1651)
		(layer "In15.Cu")
		(net "P5E_PEX0_STN4_RX_DP<67>")
	)
	(segment
		(start 92.714064 -326.236584)
		(end 94.264988 -325.098918)
		(width 0.1651)
		(layer "In15.Cu")
		(net "P5E_PEX0_STN4_RX_DP<67>")
	)
	(segment
		(start 39.485062 -366.419892)
		(end 39.46906 -366.258856)
		(width 0.1651)
		(layer "In15.Cu")
		(net "P5E_PEX0_STN4_RX_DP<67>")
	)
	(segment
		(start 41.757346 -363.650784)
		(end 41.741598 -363.490002)
		(width 0.1651)
		(layer "In15.Cu")
		(net "P5E_PEX0_STN4_RX_DP<67>")
	)
	(segment
		(start 40.226742 -365.33582)
		(end 40.533066 -364.962694)
		(width 0.1651)
		(layer "In15.Cu")
		(net "P5E_PEX0_STN4_RX_DP<67>")
	)
	(segment
		(start 94.460822 -316.228222)
		(end 87.151718 -308.919118)
		(width 0.1651)
		(layer "In15.Cu")
		(net "P5E_PEX0_STN4_RX_DP<67>")
	)
	(segment
		(start 80.256126 -307.870098)
		(end 79.97952 -307.593492)
		(width 0.1143)
		(layer "In15.Cu")
		(net "P5E_PEX0_STN4_RX_DP<67>")
	)
	(segment
		(start 41.451276 -364.023656)
		(end 41.757346 -363.650784)
		(width 0.1651)
		(layer "In15.Cu")
		(net "P5E_PEX0_STN4_RX_DP<67>")
	)
	(segment
		(start 40.693848 -364.946692)
		(end 40.999918 -364.57382)
		(width 0.1651)
		(layer "In15.Cu")
		(net "P5E_PEX0_STN4_RX_DP<67>")
	)
	(segment
		(start 41.984168 -349.831914)
		(end 41.664128 -349.511874)
		(width 0.13462)
		(layer "F.Cu")
		(net "P5E_PEX0_STN4_TX_DN<69>")
	)
	(segment
		(start 41.664128 -348.88043)
		(end 41.958768 -348.58579)
		(width 0.13462)
		(layer "F.Cu")
		(net "P5E_PEX0_STN4_TX_DN<69>")
	)
	(segment
		(start 41.664128 -349.511874)
		(end 41.664128 -348.88043)
		(width 0.13462)
		(layer "F.Cu")
		(net "P5E_PEX0_STN4_TX_DN<69>")
	)
	(segment
		(start 56.519572 -334.68945)
		(end 78.522576 -330.313284)
		(width 0.1651)
		(layer "In11.Cu")
		(net "P5E_PEX0_STN4_TX_DN<69>")
	)
	(segment
		(start 83.642454 -309.5498)
		(end 83.614006 -309.5498)
		(width 0.1143)
		(layer "In11.Cu")
		(net "P5E_PEX0_STN4_TX_DN<69>")
	)
	(segment
		(start 83.614006 -309.5498)
		(end 83.568286 -309.59552)
		(width 0.1143)
		(layer "In11.Cu")
		(net "P5E_PEX0_STN4_TX_DN<69>")
	)
	(segment
		(start 41.667938 -347.736922)
		(end 43.222418 -346.182442)
		(width 0.1651)
		(layer "In11.Cu")
		(net "P5E_PEX0_STN4_TX_DN<69>")
	)
	(segment
		(start 41.667938 -348.29496)
		(end 41.667938 -347.736922)
		(width 0.1651)
		(layer "In11.Cu")
		(net "P5E_PEX0_STN4_TX_DN<69>")
	)
	(segment
		(start 92.546932 -316.564264)
		(end 89.740994 -315.40196)
		(width 0.1651)
		(layer "In11.Cu")
		(net "P5E_PEX0_STN4_TX_DN<69>")
	)
	(segment
		(start 47.841154 -337.7946)
		(end 56.519572 -334.68945)
		(width 0.1651)
		(layer "In11.Cu")
		(net "P5E_PEX0_STN4_TX_DN<69>")
	)
	(segment
		(start 92.895928 -324.985126)
		(end 93.916246 -323.964808)
		(width 0.1651)
		(layer "In11.Cu")
		(net "P5E_PEX0_STN4_TX_DN<69>")
	)
	(segment
		(start 94.764098 -321.917822)
		(end 94.764098 -319.881758)
		(width 0.1651)
		(layer "In11.Cu")
		(net "P5E_PEX0_STN4_TX_DN<69>")
	)
	(segment
		(start 89.740994 -315.40196)
		(end 83.888834 -309.5498)
		(width 0.1651)
		(layer "In11.Cu")
		(net "P5E_PEX0_STN4_TX_DN<69>")
	)
	(segment
		(start 43.60164 -340.946994)
		(end 45.505624 -339.04301)
		(width 0.1651)
		(layer "In11.Cu")
		(net "P5E_PEX0_STN4_TX_DN<69>")
	)
	(segment
		(start 77.497178 -309.59552)
		(end 77.32014 -309.418482)
		(width 0.1143)
		(layer "In11.Cu")
		(net "P5E_PEX0_STN4_TX_DN<69>")
	)
	(segment
		(start 83.888834 -309.5498)
		(end 83.642454 -309.5498)
		(width 0.1651)
		(layer "In11.Cu")
		(net "P5E_PEX0_STN4_TX_DN<69>")
	)
	(segment
		(start 93.916246 -323.964808)
		(end 94.764098 -321.917822)
		(width 0.1651)
		(layer "In11.Cu")
		(net "P5E_PEX0_STN4_TX_DN<69>")
	)
	(segment
		(start 91.84767 -325.545704)
		(end 92.895928 -324.985126)
		(width 0.1651)
		(layer "In11.Cu")
		(net "P5E_PEX0_STN4_TX_DN<69>")
	)
	(segment
		(start 93.986096 -318.003428)
		(end 92.546932 -316.564264)
		(width 0.1651)
		(layer "In11.Cu")
		(net "P5E_PEX0_STN4_TX_DN<69>")
	)
	(segment
		(start 77.32014 -309.418482)
		(end 77.32014 -309.288688)
		(width 0.1143)
		(layer "In11.Cu")
		(net "P5E_PEX0_STN4_TX_DN<69>")
	)
	(segment
		(start 78.522576 -330.313284)
		(end 91.84767 -325.545704)
		(width 0.1651)
		(layer "In11.Cu")
		(net "P5E_PEX0_STN4_TX_DN<69>")
	)
	(segment
		(start 77.32014 -309.288688)
		(end 77.40904 -309.199788)
		(width 0.1143)
		(layer "In11.Cu")
		(net "P5E_PEX0_STN4_TX_DN<69>")
	)
	(segment
		(start 41.958768 -348.58579)
		(end 41.667938 -348.29496)
		(width 0.1651)
		(layer "In11.Cu")
		(net "P5E_PEX0_STN4_TX_DN<69>")
	)
	(segment
		(start 45.505624 -339.04301)
		(end 47.841154 -337.7946)
		(width 0.1651)
		(layer "In11.Cu")
		(net "P5E_PEX0_STN4_TX_DN<69>")
	)
	(segment
		(start 77.40904 -309.199788)
		(end 77.69987 -309.199788)
		(width 0.1143)
		(layer "In11.Cu")
		(net "P5E_PEX0_STN4_TX_DN<69>")
	)
	(segment
		(start 94.764098 -319.881758)
		(end 93.986096 -318.003428)
		(width 0.1651)
		(layer "In11.Cu")
		(net "P5E_PEX0_STN4_TX_DN<69>")
	)
	(segment
		(start 83.568286 -309.59552)
		(end 77.497178 -309.59552)
		(width 0.1143)
		(layer "In11.Cu")
		(net "P5E_PEX0_STN4_TX_DN<69>")
	)
	(segment
		(start 43.222418 -346.182442)
		(end 43.222418 -341.86241)
		(width 0.1651)
		(layer "In11.Cu")
		(net "P5E_PEX0_STN4_TX_DN<69>")
	)
	(segment
		(start 43.222418 -341.86241)
		(end 43.60164 -340.946994)
		(width 0.1651)
		(layer "In11.Cu")
		(net "P5E_PEX0_STN4_TX_DN<69>")
	)
	(segment
		(start 275.004022 -344.219022)
		(end 274.683982 -344.539062)
		(width 0.13462)
		(layer "F.Cu")
		(net "P5E_PEX2_STN4_TX_C_DN<77>")
	)
	(segment
		(start 274.683982 -344.539062)
		(end 274.683982 -345.170506)
		(width 0.13462)
		(layer "F.Cu")
		(net "P5E_PEX2_STN4_TX_C_DN<77>")
	)
	(segment
		(start 274.683982 -345.170506)
		(end 274.978622 -345.465146)
		(width 0.13462)
		(layer "F.Cu")
		(net "P5E_PEX2_STN4_TX_C_DN<77>")
	)
	(segment
		(start 292.016942 -397.281146)
		(end 292.564058 -397.281146)
		(width 0.1651)
		(layer "In11.Cu")
		(net "P5E_PEX2_STN4_TX_C_DN<77>")
	)
	(segment
		(start 273.133312 -347.881194)
		(end 274.687792 -346.326714)
		(width 0.1651)
		(layer "In11.Cu")
		(net "P5E_PEX2_STN4_TX_C_DN<77>")
	)
	(segment
		(start 291.889942 -397.790162)
		(end 291.889942 -397.408146)
		(width 0.1651)
		(layer "In11.Cu")
		(net "P5E_PEX2_STN4_TX_C_DN<77>")
	)
	(segment
		(start 292.564058 -397.281146)
		(end 293.015924 -396.82928)
		(width 0.1651)
		(layer "In11.Cu")
		(net "P5E_PEX2_STN4_TX_C_DN<77>")
	)
	(segment
		(start 273.133312 -358.7242)
		(end 273.133312 -347.881194)
		(width 0.1651)
		(layer "In11.Cu")
		(net "P5E_PEX2_STN4_TX_C_DN<77>")
	)
	(segment
		(start 281.543506 -386.139182)
		(end 280.575258 -378.819918)
		(width 0.1651)
		(layer "In11.Cu")
		(net "P5E_PEX2_STN4_TX_C_DN<77>")
	)
	(segment
		(start 291.889942 -397.408146)
		(end 292.016942 -397.281146)
		(width 0.1651)
		(layer "In11.Cu")
		(net "P5E_PEX2_STN4_TX_C_DN<77>")
	)
	(segment
		(start 274.687792 -345.755976)
		(end 274.978622 -345.465146)
		(width 0.1651)
		(layer "In11.Cu")
		(net "P5E_PEX2_STN4_TX_C_DN<77>")
	)
	(segment
		(start 274.687792 -346.326714)
		(end 274.687792 -345.755976)
		(width 0.1651)
		(layer "In11.Cu")
		(net "P5E_PEX2_STN4_TX_C_DN<77>")
	)
	(segment
		(start 293.015924 -394.8557)
		(end 291.276786 -393.091162)
		(width 0.1651)
		(layer "In11.Cu")
		(net "P5E_PEX2_STN4_TX_C_DN<77>")
	)
	(segment
		(start 293.015924 -396.82928)
		(end 293.015924 -394.8557)
		(width 0.1651)
		(layer "In11.Cu")
		(net "P5E_PEX2_STN4_TX_C_DN<77>")
	)
	(segment
		(start 282.55468 -388.17804)
		(end 281.543506 -386.139182)
		(width 0.1651)
		(layer "In11.Cu")
		(net "P5E_PEX2_STN4_TX_C_DN<77>")
	)
	(segment
		(start 280.575258 -378.819918)
		(end 273.133312 -358.7242)
		(width 0.1651)
		(layer "In11.Cu")
		(net "P5E_PEX2_STN4_TX_C_DN<77>")
	)
	(segment
		(start 285.09468 -390.618726)
		(end 282.55468 -388.17804)
		(width 0.1651)
		(layer "In11.Cu")
		(net "P5E_PEX2_STN4_TX_C_DN<77>")
	)
	(segment
		(start 291.276786 -393.091162)
		(end 285.09468 -390.618726)
		(width 0.1651)
		(layer "In11.Cu")
		(net "P5E_PEX2_STN4_TX_C_DN<77>")
	)
	(segment
		(start 35.446208 -350.685354)
		(end 35.766248 -350.365314)
		(width 0.13462)
		(layer "F.Cu")
		(net "P5E_PEX0_STN4_TX_C_DN<72>")
	)
	(segment
		(start 35.740848 -351.611438)
		(end 35.446208 -351.316798)
		(width 0.13462)
		(layer "F.Cu")
		(net "P5E_PEX0_STN4_TX_C_DN<72>")
	)
	(segment
		(start 35.446208 -351.316798)
		(end 35.446208 -350.685354)
		(width 0.13462)
		(layer "F.Cu")
		(net "P5E_PEX0_STN4_TX_C_DN<72>")
	)
	(segment
		(start 43.310048 -398.890236)
		(end 43.310048 -398.50822)
		(width 0.1651)
		(layer "In11.Cu")
		(net "P5E_PEX0_STN4_TX_C_DN<72>")
	)
	(segment
		(start 43.310048 -398.50822)
		(end 43.437048 -398.38122)
		(width 0.1651)
		(layer "In11.Cu")
		(net "P5E_PEX0_STN4_TX_C_DN<72>")
	)
	(segment
		(start 35.450018 -352.537522)
		(end 35.450018 -351.902268)
		(width 0.1651)
		(layer "In11.Cu")
		(net "P5E_PEX0_STN4_TX_C_DN<72>")
	)
	(segment
		(start 35.74034 -388.939024)
		(end 27.856434 -385.674108)
		(width 0.1651)
		(layer "In11.Cu")
		(net "P5E_PEX0_STN4_TX_C_DN<72>")
	)
	(segment
		(start 26.681176 -381.6604)
		(end 26.874216 -369.720622)
		(width 0.1651)
		(layer "In11.Cu")
		(net "P5E_PEX0_STN4_TX_C_DN<72>")
	)
	(segment
		(start 26.874216 -369.720622)
		(end 27.139646 -368.869722)
		(width 0.1651)
		(layer "In11.Cu")
		(net "P5E_PEX0_STN4_TX_C_DN<72>")
	)
	(segment
		(start 26.681176 -383.643886)
		(end 26.681176 -381.6604)
		(width 0.1651)
		(layer "In11.Cu")
		(net "P5E_PEX0_STN4_TX_C_DN<72>")
	)
	(segment
		(start 33.895538 -358.759252)
		(end 33.895538 -354.092002)
		(width 0.1651)
		(layer "In11.Cu")
		(net "P5E_PEX0_STN4_TX_C_DN<72>")
	)
	(segment
		(start 35.450018 -351.902268)
		(end 35.740848 -351.611438)
		(width 0.1651)
		(layer "In11.Cu")
		(net "P5E_PEX0_STN4_TX_C_DN<72>")
	)
	(segment
		(start 44.48429 -395.547088)
		(end 44.051982 -394.503402)
		(width 0.1651)
		(layer "In11.Cu")
		(net "P5E_PEX0_STN4_TX_C_DN<72>")
	)
	(segment
		(start 44.48429 -397.874236)
		(end 44.48429 -395.547088)
		(width 0.1651)
		(layer "In11.Cu")
		(net "P5E_PEX0_STN4_TX_C_DN<72>")
	)
	(segment
		(start 27.139646 -368.869722)
		(end 33.895538 -358.759252)
		(width 0.1651)
		(layer "In11.Cu")
		(net "P5E_PEX0_STN4_TX_C_DN<72>")
	)
	(segment
		(start 33.895538 -354.092002)
		(end 35.450018 -352.537522)
		(width 0.1651)
		(layer "In11.Cu")
		(net "P5E_PEX0_STN4_TX_C_DN<72>")
	)
	(segment
		(start 27.285442 -385.103116)
		(end 26.681176 -383.643886)
		(width 0.1651)
		(layer "In11.Cu")
		(net "P5E_PEX0_STN4_TX_C_DN<72>")
	)
	(segment
		(start 44.051982 -394.503402)
		(end 35.74034 -388.939024)
		(width 0.1651)
		(layer "In11.Cu")
		(net "P5E_PEX0_STN4_TX_C_DN<72>")
	)
	(segment
		(start 43.437048 -398.38122)
		(end 43.977306 -398.38122)
		(width 0.1651)
		(layer "In11.Cu")
		(net "P5E_PEX0_STN4_TX_C_DN<72>")
	)
	(segment
		(start 43.977306 -398.38122)
		(end 44.48429 -397.874236)
		(width 0.1651)
		(layer "In11.Cu")
		(net "P5E_PEX0_STN4_TX_C_DN<72>")
	)
	(segment
		(start 27.856434 -385.674108)
		(end 27.285442 -385.103116)
		(width 0.1651)
		(layer "In11.Cu")
		(net "P5E_PEX0_STN4_TX_C_DN<72>")
	)
	(segment
		(start 280.307542 -356.511606)
		(end 280.627582 -356.831646)
		(width 0.13462)
		(layer "F.Cu")
		(net "P5E_PEX2_STN4_TX_C_DP<73>")
	)
	(segment
		(start 280.627582 -357.46309)
		(end 280.332942 -357.75773)
		(width 0.13462)
		(layer "F.Cu")
		(net "P5E_PEX2_STN4_TX_C_DP<73>")
	)
	(segment
		(start 280.627582 -356.831646)
		(end 280.627582 -357.46309)
		(width 0.13462)
		(layer "F.Cu")
		(net "P5E_PEX2_STN4_TX_C_DP<73>")
	)
	(segment
		(start 301.533814 -395.142466)
		(end 301.157894 -394.345414)
		(width 0.1651)
		(layer "In11.Cu")
		(net "P5E_PEX2_STN4_TX_C_DP<73>")
	)
	(segment
		(start 285.69285 -386.051044)
		(end 285.178754 -385.067302)
		(width 0.1651)
		(layer "In11.Cu")
		(net "P5E_PEX2_STN4_TX_C_DP<73>")
	)
	(segment
		(start 298.627292 -392.713718)
		(end 298.504356 -392.740134)
		(width 0.1651)
		(layer "In11.Cu")
		(net "P5E_PEX2_STN4_TX_C_DP<73>")
	)
	(segment
		(start 300.068234 -393.64285)
		(end 299.652182 -393.374626)
		(width 0.1651)
		(layer "In11.Cu")
		(net "P5E_PEX2_STN4_TX_C_DP<73>")
	)
	(segment
		(start 297.645328 -392.080496)
		(end 297.522392 -392.106912)
		(width 0.1651)
		(layer "In11.Cu")
		(net "P5E_PEX2_STN4_TX_C_DP<73>")
	)
	(segment
		(start 280.623772 -358.04856)
		(end 280.332942 -357.75773)
		(width 0.1651)
		(layer "In11.Cu")
		(net "P5E_PEX2_STN4_TX_C_DP<73>")
	)
	(segment
		(start 301.247048 -396.999206)
		(end 301.533814 -396.71244)
		(width 0.1651)
		(layer "In11.Cu")
		(net "P5E_PEX2_STN4_TX_C_DP<73>")
	)
	(segment
		(start 299.652182 -393.374626)
		(end 299.494194 -393.408662)
		(width 0.1651)
		(layer "In11.Cu")
		(net "P5E_PEX2_STN4_TX_C_DP<73>")
	)
	(segment
		(start 299.043344 -392.981942)
		(end 298.627292 -392.713718)
		(width 0.1651)
		(layer "In11.Cu")
		(net "P5E_PEX2_STN4_TX_C_DP<73>")
	)
	(segment
		(start 300.689772 -396.872206)
		(end 300.816772 -396.999206)
		(width 0.1651)
		(layer "In11.Cu")
		(net "P5E_PEX2_STN4_TX_C_DP<73>")
	)
	(segment
		(start 298.087796 -392.471402)
		(end 298.06138 -392.34872)
		(width 0.1651)
		(layer "In11.Cu")
		(net "P5E_PEX2_STN4_TX_C_DP<73>")
	)
	(segment
		(start 298.06138 -392.34872)
		(end 297.645328 -392.080496)
		(width 0.1651)
		(layer "In11.Cu")
		(net "P5E_PEX2_STN4_TX_C_DP<73>")
	)
	(segment
		(start 300.689772 -396.49019)
		(end 300.689772 -396.872206)
		(width 0.1651)
		(layer "In11.Cu")
		(net "P5E_PEX2_STN4_TX_C_DP<73>")
	)
	(segment
		(start 300.51883 -394.06957)
		(end 300.102524 -393.800838)
		(width 0.1651)
		(layer "In11.Cu")
		(net "P5E_PEX2_STN4_TX_C_DP<73>")
	)
	(segment
		(start 301.533814 -396.71244)
		(end 301.533814 -395.142466)
		(width 0.1651)
		(layer "In11.Cu")
		(net "P5E_PEX2_STN4_TX_C_DP<73>")
	)
	(segment
		(start 280.623772 -358.885998)
		(end 280.623772 -358.04856)
		(width 0.1651)
		(layer "In11.Cu")
		(net "P5E_PEX2_STN4_TX_C_DP<73>")
	)
	(segment
		(start 284.615128 -379.432058)
		(end 280.623772 -358.885998)
		(width 0.1651)
		(layer "In11.Cu")
		(net "P5E_PEX2_STN4_TX_C_DP<73>")
	)
	(segment
		(start 297.105832 -391.83818)
		(end 297.079416 -391.715498)
		(width 0.1651)
		(layer "In11.Cu")
		(net "P5E_PEX2_STN4_TX_C_DP<73>")
	)
	(segment
		(start 298.504356 -392.740134)
		(end 298.087796 -392.471402)
		(width 0.1651)
		(layer "In11.Cu")
		(net "P5E_PEX2_STN4_TX_C_DP<73>")
	)
	(segment
		(start 297.522392 -392.106912)
		(end 297.105832 -391.83818)
		(width 0.1651)
		(layer "In11.Cu")
		(net "P5E_PEX2_STN4_TX_C_DP<73>")
	)
	(segment
		(start 299.077634 -393.13993)
		(end 299.043344 -392.981942)
		(width 0.1651)
		(layer "In11.Cu")
		(net "P5E_PEX2_STN4_TX_C_DP<73>")
	)
	(segment
		(start 285.178754 -385.067302)
		(end 284.615128 -379.432058)
		(width 0.1651)
		(layer "In11.Cu")
		(net "P5E_PEX2_STN4_TX_C_DP<73>")
	)
	(segment
		(start 295.198546 -390.502648)
		(end 286.840168 -387.175502)
		(width 0.1651)
		(layer "In11.Cu")
		(net "P5E_PEX2_STN4_TX_C_DP<73>")
	)
	(segment
		(start 300.676818 -394.03528)
		(end 300.51883 -394.06957)
		(width 0.1651)
		(layer "In11.Cu")
		(net "P5E_PEX2_STN4_TX_C_DP<73>")
	)
	(segment
		(start 297.079416 -391.715498)
		(end 295.198546 -390.502648)
		(width 0.1651)
		(layer "In11.Cu")
		(net "P5E_PEX2_STN4_TX_C_DP<73>")
	)
	(segment
		(start 300.102524 -393.800838)
		(end 300.068234 -393.64285)
		(width 0.1651)
		(layer "In11.Cu")
		(net "P5E_PEX2_STN4_TX_C_DP<73>")
	)
	(segment
		(start 286.840168 -387.175502)
		(end 285.69285 -386.051044)
		(width 0.1651)
		(layer "In11.Cu")
		(net "P5E_PEX2_STN4_TX_C_DP<73>")
	)
	(segment
		(start 301.157894 -394.345414)
		(end 300.676818 -394.03528)
		(width 0.1651)
		(layer "In11.Cu")
		(net "P5E_PEX2_STN4_TX_C_DP<73>")
	)
	(segment
		(start 300.816772 -396.999206)
		(end 301.247048 -396.999206)
		(width 0.1651)
		(layer "In11.Cu")
		(net "P5E_PEX2_STN4_TX_C_DP<73>")
	)
	(segment
		(start 299.494194 -393.408662)
		(end 299.077634 -393.13993)
		(width 0.1651)
		(layer "In11.Cu")
		(net "P5E_PEX2_STN4_TX_C_DP<73>")
	)
	(segment
		(start 77.330554 -326.412606)
		(end 79.572866 -324.170294)
		(width 0.1651)
		(layer "In15.Cu")
		(net "P5E_PEX0_STN4_RX_DP<72>")
	)
	(segment
		(start 43.437048 -405.899112)
		(end 43.670728 -405.899112)
		(width 0.1651)
		(layer "In15.Cu")
		(net "P5E_PEX0_STN4_RX_DP<72>")
	)
	(segment
		(start 79.572866 -324.170294)
		(end 79.9338 -323.299074)
		(width 0.1651)
		(layer "In15.Cu")
		(net "P5E_PEX0_STN4_RX_DP<72>")
	)
	(segment
		(start 44.185078 -396.46606)
		(end 43.927776 -395.84503)
		(width 0.1651)
		(layer "In15.Cu")
		(net "P5E_PEX0_STN4_RX_DP<72>")
	)
	(segment
		(start 43.670728 -405.899112)
		(end 44.185078 -405.384762)
		(width 0.1651)
		(layer "In15.Cu")
		(net "P5E_PEX0_STN4_RX_DP<72>")
	)
	(segment
		(start 43.927776 -395.84503)
		(end 43.211242 -394.772642)
		(width 0.1651)
		(layer "In15.Cu")
		(net "P5E_PEX0_STN4_RX_DP<72>")
	)
	(segment
		(start 38.074854 -390.868408)
		(end 38.033198 -390.730994)
		(width 0.1651)
		(layer "In15.Cu")
		(net "P5E_PEX0_STN4_RX_DP<72>")
	)
	(segment
		(start 38.638226 -391.05459)
		(end 38.500812 -391.096246)
		(width 0.1651)
		(layer "In15.Cu")
		(net "P5E_PEX0_STN4_RX_DP<72>")
	)
	(segment
		(start 44.185078 -405.384762)
		(end 44.185078 -396.46606)
		(width 0.1651)
		(layer "In15.Cu")
		(net "P5E_PEX0_STN4_RX_DP<72>")
	)
	(segment
		(start 40.181784 -391.879582)
		(end 38.638226 -391.05459)
		(width 0.1651)
		(layer "In15.Cu")
		(net "P5E_PEX0_STN4_RX_DP<72>")
	)
	(segment
		(start 43.211242 -394.772642)
		(end 40.592756 -392.154156)
		(width 0.1651)
		(layer "In15.Cu")
		(net "P5E_PEX0_STN4_RX_DP<72>")
	)
	(segment
		(start 40.081454 -337.327494)
		(end 44.37253 -336.025744)
		(width 0.1651)
		(layer "In15.Cu")
		(net "P5E_PEX0_STN4_RX_DP<72>")
	)
	(segment
		(start 43.310048 -405.390096)
		(end 43.310048 -405.772112)
		(width 0.1651)
		(layer "In15.Cu")
		(net "P5E_PEX0_STN4_RX_DP<72>")
	)
	(segment
		(start 30.504638 -342.090756)
		(end 30.735016 -341.53475)
		(width 0.1651)
		(layer "In15.Cu")
		(net "P5E_PEX0_STN4_RX_DP<72>")
	)
	(segment
		(start 29.016452 -386.841746)
		(end 27.070304 -385.541266)
		(width 0.1651)
		(layer "In15.Cu")
		(net "P5E_PEX0_STN4_RX_DP<72>")
	)
	(segment
		(start 44.37253 -336.025744)
		(end 69.039232 -329.846686)
		(width 0.1651)
		(layer "In15.Cu")
		(net "P5E_PEX0_STN4_RX_DP<72>")
	)
	(segment
		(start 79.9338 -319.8876)
		(end 79.97952 -319.84188)
		(width 0.1143)
		(layer "In15.Cu")
		(net "P5E_PEX0_STN4_RX_DP<72>")
	)
	(segment
		(start 69.039232 -329.846686)
		(end 77.330554 -326.412606)
		(width 0.1651)
		(layer "In15.Cu")
		(net "P5E_PEX0_STN4_RX_DP<72>")
	)
	(segment
		(start 30.504638 -358.831642)
		(end 30.504638 -342.090756)
		(width 0.1651)
		(layer "In15.Cu")
		(net "P5E_PEX0_STN4_RX_DP<72>")
	)
	(segment
		(start 80.205326 -318.129666)
		(end 80.43545 -318.129666)
		(width 0.1143)
		(layer "In15.Cu")
		(net "P5E_PEX0_STN4_RX_DP<72>")
	)
	(segment
		(start 26.365962 -384.353816)
		(end 25.75306 -371.875558)
		(width 0.1651)
		(layer "In15.Cu")
		(net "P5E_PEX0_STN4_RX_DP<72>")
	)
	(segment
		(start 38.500812 -391.096246)
		(end 38.074854 -390.868408)
		(width 0.1651)
		(layer "In15.Cu")
		(net "P5E_PEX0_STN4_RX_DP<72>")
	)
	(segment
		(start 36.74872 -390.044432)
		(end 29.016452 -386.841746)
		(width 0.1651)
		(layer "In15.Cu")
		(net "P5E_PEX0_STN4_RX_DP<72>")
	)
	(segment
		(start 30.735016 -341.53475)
		(end 31.308548 -340.961218)
		(width 0.1651)
		(layer "In15.Cu")
		(net "P5E_PEX0_STN4_RX_DP<72>")
	)
	(segment
		(start 79.9338 -319.916048)
		(end 79.9338 -319.8876)
		(width 0.1143)
		(layer "In15.Cu")
		(net "P5E_PEX0_STN4_RX_DP<72>")
	)
	(segment
		(start 43.310048 -405.772112)
		(end 43.437048 -405.899112)
		(width 0.1651)
		(layer "In15.Cu")
		(net "P5E_PEX0_STN4_RX_DP<72>")
	)
	(segment
		(start 26.707592 -385.178554)
		(end 26.365962 -384.353816)
		(width 0.1651)
		(layer "In15.Cu")
		(net "P5E_PEX0_STN4_RX_DP<72>")
	)
	(segment
		(start 80.54975 -318.015366)
		(end 80.54975 -317.749936)
		(width 0.1143)
		(layer "In15.Cu")
		(net "P5E_PEX0_STN4_RX_DP<72>")
	)
	(segment
		(start 25.75306 -370.30279)
		(end 30.504638 -358.831642)
		(width 0.1651)
		(layer "In15.Cu")
		(net "P5E_PEX0_STN4_RX_DP<72>")
	)
	(segment
		(start 80.43545 -318.129666)
		(end 80.54975 -318.015366)
		(width 0.1143)
		(layer "In15.Cu")
		(net "P5E_PEX0_STN4_RX_DP<72>")
	)
	(segment
		(start 27.070304 -385.541266)
		(end 26.707592 -385.178554)
		(width 0.1651)
		(layer "In15.Cu")
		(net "P5E_PEX0_STN4_RX_DP<72>")
	)
	(segment
		(start 25.75306 -371.875558)
		(end 25.75306 -370.30279)
		(width 0.1651)
		(layer "In15.Cu")
		(net "P5E_PEX0_STN4_RX_DP<72>")
	)
	(segment
		(start 40.592756 -392.154156)
		(end 40.181784 -391.879582)
		(width 0.1651)
		(layer "In15.Cu")
		(net "P5E_PEX0_STN4_RX_DP<72>")
	)
	(segment
		(start 38.033198 -390.730994)
		(end 36.74872 -390.044432)
		(width 0.1651)
		(layer "In15.Cu")
		(net "P5E_PEX0_STN4_RX_DP<72>")
	)
	(segment
		(start 79.97952 -318.355472)
		(end 80.205326 -318.129666)
		(width 0.1143)
		(layer "In15.Cu")
		(net "P5E_PEX0_STN4_RX_DP<72>")
	)
	(segment
		(start 79.9338 -323.299074)
		(end 79.9338 -319.916048)
		(width 0.1651)
		(layer "In15.Cu")
		(net "P5E_PEX0_STN4_RX_DP<72>")
	)
	(segment
		(start 79.97952 -319.84188)
		(end 79.97952 -318.355472)
		(width 0.1143)
		(layer "In15.Cu")
		(net "P5E_PEX0_STN4_RX_DP<72>")
	)
	(segment
		(start 31.308548 -340.961218)
		(end 40.081454 -337.327494)
		(width 0.1651)
		(layer "In15.Cu")
		(net "P5E_PEX0_STN4_RX_DP<72>")
	)
	(segment
		(start 281.221942 -356.511606)
		(end 280.901902 -356.831646)
		(width 0.13462)
		(layer "F.Cu")
		(net "P5E_PEX2_STN4_TX_C_DN<73>")
	)
	(segment
		(start 280.901902 -357.46309)
		(end 281.196542 -357.75773)
		(width 0.13462)
		(layer "F.Cu")
		(net "P5E_PEX2_STN4_TX_C_DN<73>")
	)
	(segment
		(start 280.901902 -356.831646)
		(end 280.901902 -357.46309)
		(width 0.13462)
		(layer "F.Cu")
		(net "P5E_PEX2_STN4_TX_C_DN<73>")
	)
	(segment
		(start 285.922212 -385.880864)
		(end 285.45409 -384.985006)
		(width 0.1651)
		(layer "In11.Cu")
		(net "P5E_PEX2_STN4_TX_C_DN<73>")
	)
	(segment
		(start 286.99714 -386.934456)
		(end 285.922212 -385.880864)
		(width 0.1651)
		(layer "In11.Cu")
		(net "P5E_PEX2_STN4_TX_C_DN<73>")
	)
	(segment
		(start 285.45409 -384.985006)
		(end 284.894528 -379.39091)
		(width 0.1651)
		(layer "In11.Cu")
		(net "P5E_PEX2_STN4_TX_C_DN<73>")
	)
	(segment
		(start 301.815754 -396.82928)
		(end 301.815754 -395.07922)
		(width 0.1651)
		(layer "In11.Cu")
		(net "P5E_PEX2_STN4_TX_C_DN<73>")
	)
	(segment
		(start 300.689772 -397.790162)
		(end 300.689772 -397.408146)
		(width 0.1651)
		(layer "In11.Cu")
		(net "P5E_PEX2_STN4_TX_C_DN<73>")
	)
	(segment
		(start 300.816772 -397.281146)
		(end 301.363888 -397.281146)
		(width 0.1651)
		(layer "In11.Cu")
		(net "P5E_PEX2_STN4_TX_C_DN<73>")
	)
	(segment
		(start 301.815754 -395.07922)
		(end 301.37862 -394.15212)
		(width 0.1651)
		(layer "In11.Cu")
		(net "P5E_PEX2_STN4_TX_C_DN<73>")
	)
	(segment
		(start 280.905712 -358.85882)
		(end 280.905712 -358.04856)
		(width 0.1651)
		(layer "In11.Cu")
		(net "P5E_PEX2_STN4_TX_C_DN<73>")
	)
	(segment
		(start 301.37862 -394.15212)
		(end 295.32834 -390.25068)
		(width 0.1651)
		(layer "In11.Cu")
		(net "P5E_PEX2_STN4_TX_C_DN<73>")
	)
	(segment
		(start 295.32834 -390.25068)
		(end 286.99714 -386.934456)
		(width 0.1651)
		(layer "In11.Cu")
		(net "P5E_PEX2_STN4_TX_C_DN<73>")
	)
	(segment
		(start 300.689772 -397.408146)
		(end 300.816772 -397.281146)
		(width 0.1651)
		(layer "In11.Cu")
		(net "P5E_PEX2_STN4_TX_C_DN<73>")
	)
	(segment
		(start 301.363888 -397.281146)
		(end 301.815754 -396.82928)
		(width 0.1651)
		(layer "In11.Cu")
		(net "P5E_PEX2_STN4_TX_C_DN<73>")
	)
	(segment
		(start 284.894528 -379.39091)
		(end 280.905712 -358.85882)
		(width 0.1651)
		(layer "In11.Cu")
		(net "P5E_PEX2_STN4_TX_C_DN<73>")
	)
	(segment
		(start 280.905712 -358.04856)
		(end 281.196542 -357.75773)
		(width 0.1651)
		(layer "In11.Cu")
		(net "P5E_PEX2_STN4_TX_C_DN<73>")
	)
	(segment
		(start 19.901408 -345.170506)
		(end 19.901408 -344.539062)
		(width 0.13462)
		(layer "F.Cu")
		(net "P5E_PEX0_STN4_TX_C_DN<79>")
	)
	(segment
		(start 20.196048 -345.465146)
		(end 19.901408 -345.170506)
		(width 0.13462)
		(layer "F.Cu")
		(net "P5E_PEX0_STN4_TX_C_DN<79>")
	)
	(segment
		(start 19.901408 -344.539062)
		(end 20.221448 -344.219022)
		(width 0.13462)
		(layer "F.Cu")
		(net "P5E_PEX0_STN4_TX_C_DN<79>")
	)
	(segment
		(start 28.550108 -397.281146)
		(end 29.08427 -396.746984)
		(width 0.1651)
		(layer "In11.Cu")
		(net "P5E_PEX0_STN4_TX_C_DN<79>")
	)
	(segment
		(start 18.350738 -347.993462)
		(end 19.905218 -346.438982)
		(width 0.1651)
		(layer "In11.Cu")
		(net "P5E_PEX0_STN4_TX_C_DN<79>")
	)
	(segment
		(start 28.363418 -394.250418)
		(end 24.16937 -391.442702)
		(width 0.1651)
		(layer "In11.Cu")
		(net "P5E_PEX0_STN4_TX_C_DN<79>")
	)
	(segment
		(start 19.249136 -374.679464)
		(end 18.350738 -354.753672)
		(width 0.1651)
		(layer "In11.Cu")
		(net "P5E_PEX0_STN4_TX_C_DN<79>")
	)
	(segment
		(start 19.905218 -346.438982)
		(end 19.905218 -345.755976)
		(width 0.1651)
		(layer "In11.Cu")
		(net "P5E_PEX0_STN4_TX_C_DN<79>")
	)
	(segment
		(start 29.08427 -396.746984)
		(end 29.08427 -394.97127)
		(width 0.1651)
		(layer "In11.Cu")
		(net "P5E_PEX0_STN4_TX_C_DN<79>")
	)
	(segment
		(start 24.16937 -391.442702)
		(end 21.616416 -388.889748)
		(width 0.1651)
		(layer "In11.Cu")
		(net "P5E_PEX0_STN4_TX_C_DN<79>")
	)
	(segment
		(start 18.350738 -354.753672)
		(end 18.350738 -347.993462)
		(width 0.1651)
		(layer "In11.Cu")
		(net "P5E_PEX0_STN4_TX_C_DN<79>")
	)
	(segment
		(start 27.910028 -397.408146)
		(end 28.037028 -397.281146)
		(width 0.1651)
		(layer "In11.Cu")
		(net "P5E_PEX0_STN4_TX_C_DN<79>")
	)
	(segment
		(start 29.08427 -394.97127)
		(end 28.363418 -394.250418)
		(width 0.1651)
		(layer "In11.Cu")
		(net "P5E_PEX0_STN4_TX_C_DN<79>")
	)
	(segment
		(start 21.616416 -388.889748)
		(end 19.67865 -384.212084)
		(width 0.1651)
		(layer "In11.Cu")
		(net "P5E_PEX0_STN4_TX_C_DN<79>")
	)
	(segment
		(start 19.905218 -345.755976)
		(end 20.196048 -345.465146)
		(width 0.1651)
		(layer "In11.Cu")
		(net "P5E_PEX0_STN4_TX_C_DN<79>")
	)
	(segment
		(start 28.037028 -397.281146)
		(end 28.550108 -397.281146)
		(width 0.1651)
		(layer "In11.Cu")
		(net "P5E_PEX0_STN4_TX_C_DN<79>")
	)
	(segment
		(start 19.67865 -384.212084)
		(end 19.249136 -374.679464)
		(width 0.1651)
		(layer "In11.Cu")
		(net "P5E_PEX0_STN4_TX_C_DN<79>")
	)
	(segment
		(start 27.910028 -397.790162)
		(end 27.910028 -397.408146)
		(width 0.1651)
		(layer "In11.Cu")
		(net "P5E_PEX0_STN4_TX_C_DN<79>")
	)
	(segment
		(start 312.369962 -305.676046)
		(end 312.369962 -305.514248)
		(width 0.1143)
		(layer "In15.Cu")
		(net "P5E_PEX2_STN4_RX_DN<65>")
	)
	(segment
		(start 317.739014 -351.97669)
		(end 317.739014 -342.11895)
		(width 0.1651)
		(layer "In15.Cu")
		(net "P5E_PEX2_STN4_RX_DN<65>")
	)
	(segment
		(start 301.815754 -369.3414)
		(end 302.3108 -368.0206)
		(width 0.1651)
		(layer "In15.Cu")
		(net "P5E_PEX2_STN4_RX_DN<65>")
	)
	(segment
		(start 315.8236 -305.733958)
		(end 315.77788 -305.779678)
		(width 0.1143)
		(layer "In15.Cu")
		(net "P5E_PEX2_STN4_RX_DN<65>")
	)
	(segment
		(start 322.005706 -307.586126)
		(end 318.540384 -305.733958)
		(width 0.1651)
		(layer "In15.Cu")
		(net "P5E_PEX2_STN4_RX_DN<65>")
	)
	(segment
		(start 315.341 -353.568)
		(end 317.20282 -352.79838)
		(width 0.1651)
		(layer "In15.Cu")
		(net "P5E_PEX2_STN4_RX_DN<65>")
	)
	(segment
		(start 317.739014 -342.11895)
		(end 317.9572 -341.2998)
		(width 0.1651)
		(layer "In15.Cu")
		(net "P5E_PEX2_STN4_RX_DN<65>")
	)
	(segment
		(start 315.852048 -305.733958)
		(end 315.8236 -305.733958)
		(width 0.1143)
		(layer "In15.Cu")
		(net "P5E_PEX2_STN4_RX_DN<65>")
	)
	(segment
		(start 317.9572 -341.2998)
		(end 329.009502 -325.247)
		(width 0.1651)
		(layer "In15.Cu")
		(net "P5E_PEX2_STN4_RX_DN<65>")
	)
	(segment
		(start 312.369962 -305.514248)
		(end 312.484262 -305.399948)
		(width 0.1143)
		(layer "In15.Cu")
		(net "P5E_PEX2_STN4_RX_DN<65>")
	)
	(segment
		(start 329.97394 -318.51727)
		(end 329.015598 -316.203838)
		(width 0.1651)
		(layer "In15.Cu")
		(net "P5E_PEX2_STN4_RX_DN<65>")
	)
	(segment
		(start 312.484262 -305.399948)
		(end 312.749692 -305.399948)
		(width 0.1143)
		(layer "In15.Cu")
		(net "P5E_PEX2_STN4_RX_DN<65>")
	)
	(segment
		(start 325.778368 -311.358788)
		(end 322.005706 -307.586126)
		(width 0.1651)
		(layer "In15.Cu")
		(net "P5E_PEX2_STN4_RX_DN<65>")
	)
	(segment
		(start 329.009502 -325.247)
		(end 329.97394 -322.918582)
		(width 0.1651)
		(layer "In15.Cu")
		(net "P5E_PEX2_STN4_RX_DN<65>")
	)
	(segment
		(start 329.015598 -316.203838)
		(end 325.778368 -311.358788)
		(width 0.1651)
		(layer "In15.Cu")
		(net "P5E_PEX2_STN4_RX_DN<65>")
	)
	(segment
		(start 317.20282 -352.79838)
		(end 317.537338 -352.463862)
		(width 0.1651)
		(layer "In15.Cu")
		(net "P5E_PEX2_STN4_RX_DN<65>")
	)
	(segment
		(start 300.816772 -379.08103)
		(end 301.363888 -379.08103)
		(width 0.1651)
		(layer "In15.Cu")
		(net "P5E_PEX2_STN4_RX_DN<65>")
	)
	(segment
		(start 315.77788 -305.779678)
		(end 312.473594 -305.779678)
		(width 0.1143)
		(layer "In15.Cu")
		(net "P5E_PEX2_STN4_RX_DN<65>")
	)
	(segment
		(start 301.815754 -378.629164)
		(end 301.815754 -369.3414)
		(width 0.1651)
		(layer "In15.Cu")
		(net "P5E_PEX2_STN4_RX_DN<65>")
	)
	(segment
		(start 302.3108 -368.0206)
		(end 315.0108 -353.7966)
		(width 0.1651)
		(layer "In15.Cu")
		(net "P5E_PEX2_STN4_RX_DN<65>")
	)
	(segment
		(start 329.97394 -322.918582)
		(end 329.97394 -318.51727)
		(width 0.1651)
		(layer "In15.Cu")
		(net "P5E_PEX2_STN4_RX_DN<65>")
	)
	(segment
		(start 300.689772 -379.20803)
		(end 300.816772 -379.08103)
		(width 0.1651)
		(layer "In15.Cu")
		(net "P5E_PEX2_STN4_RX_DN<65>")
	)
	(segment
		(start 317.537338 -352.463862)
		(end 317.739014 -351.97669)
		(width 0.1651)
		(layer "In15.Cu")
		(net "P5E_PEX2_STN4_RX_DN<65>")
	)
	(segment
		(start 315.0108 -353.7966)
		(end 315.341 -353.568)
		(width 0.1651)
		(layer "In15.Cu")
		(net "P5E_PEX2_STN4_RX_DN<65>")
	)
	(segment
		(start 312.473594 -305.779678)
		(end 312.369962 -305.676046)
		(width 0.1143)
		(layer "In15.Cu")
		(net "P5E_PEX2_STN4_RX_DN<65>")
	)
	(segment
		(start 300.689772 -379.590046)
		(end 300.689772 -379.20803)
		(width 0.1651)
		(layer "In15.Cu")
		(net "P5E_PEX2_STN4_RX_DN<65>")
	)
	(segment
		(start 318.540384 -305.733958)
		(end 315.852048 -305.733958)
		(width 0.1651)
		(layer "In15.Cu")
		(net "P5E_PEX2_STN4_RX_DN<65>")
	)
	(segment
		(start 301.363888 -379.08103)
		(end 301.815754 -378.629164)
		(width 0.1651)
		(layer "In15.Cu")
		(net "P5E_PEX2_STN4_RX_DN<65>")
	)
	(segment
		(start 73.576434 -329.01128)
		(end 73.576688 -329.011026)
		(width 0.1651)
		(layer "In15.Cu")
		(net "P5E_PEX0_STN4_RX_DP<71>")
	)
	(segment
		(start 32.085026 -361.794298)
		(end 33.613598 -358.56291)
		(width 0.1651)
		(layer "In15.Cu")
		(net "P5E_PEX0_STN4_RX_DP<71>")
	)
	(segment
		(start 29.951426 -366.068356)
		(end 30.086554 -366.019842)
		(width 0.1651)
		(layer "In15.Cu")
		(net "P5E_PEX0_STN4_RX_DP<71>")
	)
	(segment
		(start 30.743906 -364.391956)
		(end 30.950662 -363.955584)
		(width 0.1651)
		(layer "In15.Cu")
		(net "P5E_PEX0_STN4_RX_DP<71>")
	)
	(segment
		(start 81.765394 -316.799722)
		(end 81.499964 -316.799722)
		(width 0.1143)
		(layer "In15.Cu")
		(net "P5E_PEX0_STN4_RX_DP<71>")
	)
	(segment
		(start 81.879694 -319.05448)
		(end 81.879694 -316.914022)
		(width 0.1143)
		(layer "In15.Cu")
		(net "P5E_PEX0_STN4_RX_DP<71>")
	)
	(segment
		(start 81.879694 -316.914022)
		(end 81.765394 -316.799722)
		(width 0.1143)
		(layer "In15.Cu")
		(net "P5E_PEX0_STN4_RX_DP<71>")
	)
	(segment
		(start 29.79293 -366.64011)
		(end 29.793184 -366.64011)
		(width 0.1651)
		(layer "In15.Cu")
		(net "P5E_PEX0_STN4_RX_DP<71>")
	)
	(segment
		(start 30.086554 -366.019842)
		(end 30.292802 -365.583724)
		(width 0.1651)
		(layer "In15.Cu")
		(net "P5E_PEX0_STN4_RX_DP<71>")
	)
	(segment
		(start 73.576688 -329.011026)
		(end 77.88529 -327.226676)
		(width 0.1651)
		(layer "In15.Cu")
		(net "P5E_PEX0_STN4_RX_DP<71>")
	)
	(segment
		(start 45.399452 -336.775044)
		(end 69.267324 -330.796138)
		(width 0.1651)
		(layer "In15.Cu")
		(net "P5E_PEX0_STN4_RX_DP<71>")
	)
	(segment
		(start 33.613598 -341.653368)
		(end 34.445448 -340.821518)
		(width 0.1651)
		(layer "In15.Cu")
		(net "P5E_PEX0_STN4_RX_DP<71>")
	)
	(segment
		(start 31.791656 -362.414566)
		(end 31.743142 -362.279184)
		(width 0.1651)
		(layer "In15.Cu")
		(net "P5E_PEX0_STN4_RX_DP<71>")
	)
	(segment
		(start 28.258516 -378.79909)
		(end 28.78582 -378.271786)
		(width 0.1651)
		(layer "In15.Cu")
		(net "P5E_PEX0_STN4_RX_DP<71>")
	)
	(segment
		(start 28.78582 -378.271786)
		(end 28.78582 -368.769646)
		(width 0.1651)
		(layer "In15.Cu")
		(net "P5E_PEX0_STN4_RX_DP<71>")
	)
	(segment
		(start 31.243524 -363.33557)
		(end 31.45028 -362.899198)
		(width 0.1651)
		(layer "In15.Cu")
		(net "P5E_PEX0_STN4_RX_DP<71>")
	)
	(segment
		(start 29.245052 -367.561114)
		(end 29.451554 -367.124742)
		(width 0.1651)
		(layer "In15.Cu")
		(net "P5E_PEX0_STN4_RX_DP<71>")
	)
	(segment
		(start 27.910028 -378.290074)
		(end 27.910028 -378.67209)
		(width 0.1651)
		(layer "In15.Cu")
		(net "P5E_PEX0_STN4_RX_DP<71>")
	)
	(segment
		(start 29.293312 -367.696496)
		(end 29.245052 -367.561114)
		(width 0.1651)
		(layer "In15.Cu")
		(net "P5E_PEX0_STN4_RX_DP<71>")
	)
	(segment
		(start 29.74467 -366.504728)
		(end 29.951426 -366.068356)
		(width 0.1651)
		(layer "In15.Cu")
		(net "P5E_PEX0_STN4_RX_DP<71>")
	)
	(segment
		(start 31.45028 -362.899198)
		(end 31.585408 -362.850684)
		(width 0.1651)
		(layer "In15.Cu")
		(net "P5E_PEX0_STN4_RX_DP<71>")
	)
	(segment
		(start 81.833974 -321.246246)
		(end 81.833974 -319.128648)
		(width 0.1651)
		(layer "In15.Cu")
		(net "P5E_PEX0_STN4_RX_DP<71>")
	)
	(segment
		(start 30.950662 -363.955584)
		(end 31.08579 -363.90707)
		(width 0.1651)
		(layer "In15.Cu")
		(net "P5E_PEX0_STN4_RX_DP<71>")
	)
	(segment
		(start 29.793184 -366.64011)
		(end 29.74467 -366.504728)
		(width 0.1651)
		(layer "In15.Cu")
		(net "P5E_PEX0_STN4_RX_DP<71>")
	)
	(segment
		(start 69.267324 -330.796138)
		(end 73.576434 -329.01128)
		(width 0.1651)
		(layer "In15.Cu")
		(net "P5E_PEX0_STN4_RX_DP<71>")
	)
	(segment
		(start 30.292802 -365.583724)
		(end 30.244288 -365.448342)
		(width 0.1651)
		(layer "In15.Cu")
		(net "P5E_PEX0_STN4_RX_DP<71>")
	)
	(segment
		(start 29.586682 -367.076228)
		(end 29.79293 -366.64011)
		(width 0.1651)
		(layer "In15.Cu")
		(net "P5E_PEX0_STN4_RX_DP<71>")
	)
	(segment
		(start 34.445448 -340.821518)
		(end 40.970962 -338.11845)
		(width 0.1651)
		(layer "In15.Cu")
		(net "P5E_PEX0_STN4_RX_DP<71>")
	)
	(segment
		(start 31.08579 -363.90707)
		(end 31.292038 -363.470952)
		(width 0.1651)
		(layer "In15.Cu")
		(net "P5E_PEX0_STN4_RX_DP<71>")
	)
	(segment
		(start 29.451554 -367.124742)
		(end 29.586936 -367.076228)
		(width 0.1651)
		(layer "In15.Cu")
		(net "P5E_PEX0_STN4_RX_DP<71>")
	)
	(segment
		(start 31.949898 -361.842812)
		(end 32.085026 -361.794298)
		(width 0.1651)
		(layer "In15.Cu")
		(net "P5E_PEX0_STN4_RX_DP<71>")
	)
	(segment
		(start 30.244288 -365.448342)
		(end 30.451044 -365.01197)
		(width 0.1651)
		(layer "In15.Cu")
		(net "P5E_PEX0_STN4_RX_DP<71>")
	)
	(segment
		(start 30.586172 -364.963456)
		(end 30.79242 -364.527338)
		(width 0.1651)
		(layer "In15.Cu")
		(net "P5E_PEX0_STN4_RX_DP<71>")
	)
	(segment
		(start 28.037028 -378.79909)
		(end 28.258516 -378.79909)
		(width 0.1651)
		(layer "In15.Cu")
		(net "P5E_PEX0_STN4_RX_DP<71>")
	)
	(segment
		(start 81.833974 -319.128648)
		(end 81.833974 -319.1002)
		(width 0.1143)
		(layer "In15.Cu")
		(net "P5E_PEX0_STN4_RX_DP<71>")
	)
	(segment
		(start 28.78582 -368.769646)
		(end 29.293312 -367.696496)
		(width 0.1651)
		(layer "In15.Cu")
		(net "P5E_PEX0_STN4_RX_DP<71>")
	)
	(segment
		(start 29.586936 -367.076228)
		(end 29.586682 -367.076228)
		(width 0.1651)
		(layer "In15.Cu")
		(net "P5E_PEX0_STN4_RX_DP<71>")
	)
	(segment
		(start 27.910028 -378.67209)
		(end 28.037028 -378.79909)
		(width 0.1651)
		(layer "In15.Cu")
		(net "P5E_PEX0_STN4_RX_DP<71>")
	)
	(segment
		(start 40.970962 -338.11845)
		(end 45.399452 -336.775044)
		(width 0.1651)
		(layer "In15.Cu")
		(net "P5E_PEX0_STN4_RX_DP<71>")
	)
	(segment
		(start 31.743142 -362.279184)
		(end 31.949898 -361.842812)
		(width 0.1651)
		(layer "In15.Cu")
		(net "P5E_PEX0_STN4_RX_DP<71>")
	)
	(segment
		(start 81.833974 -319.1002)
		(end 81.879694 -319.05448)
		(width 0.1143)
		(layer "In15.Cu")
		(net "P5E_PEX0_STN4_RX_DP<71>")
	)
	(segment
		(start 77.88529 -327.226676)
		(end 80.397096 -324.71487)
		(width 0.1651)
		(layer "In15.Cu")
		(net "P5E_PEX0_STN4_RX_DP<71>")
	)
	(segment
		(start 30.451044 -365.01197)
		(end 30.586172 -364.963456)
		(width 0.1651)
		(layer "In15.Cu")
		(net "P5E_PEX0_STN4_RX_DP<71>")
	)
	(segment
		(start 31.585408 -362.850684)
		(end 31.791656 -362.414566)
		(width 0.1651)
		(layer "In15.Cu")
		(net "P5E_PEX0_STN4_RX_DP<71>")
	)
	(segment
		(start 30.79242 -364.527338)
		(end 30.743906 -364.391956)
		(width 0.1651)
		(layer "In15.Cu")
		(net "P5E_PEX0_STN4_RX_DP<71>")
	)
	(segment
		(start 33.613598 -358.56291)
		(end 33.613598 -341.653368)
		(width 0.1651)
		(layer "In15.Cu")
		(net "P5E_PEX0_STN4_RX_DP<71>")
	)
	(segment
		(start 31.292038 -363.470952)
		(end 31.243524 -363.33557)
		(width 0.1651)
		(layer "In15.Cu")
		(net "P5E_PEX0_STN4_RX_DP<71>")
	)
	(segment
		(start 80.397096 -324.71487)
		(end 81.833974 -321.246246)
		(width 0.1651)
		(layer "In15.Cu")
		(net "P5E_PEX0_STN4_RX_DP<71>")
	)
	(segment
		(start 50.396648 -343.685622)
		(end 50.716688 -343.365582)
		(width 0.13462)
		(layer "F.Cu")
		(net "P5E_PEX0_STN4_TX_DP<65>")
	)
	(segment
		(start 50.716688 -342.734138)
		(end 50.422048 -342.439498)
		(width 0.13462)
		(layer "F.Cu")
		(net "P5E_PEX0_STN4_TX_DP<65>")
	)
	(segment
		(start 50.716688 -343.365582)
		(end 50.716688 -342.734138)
		(width 0.13462)
		(layer "F.Cu")
		(net "P5E_PEX0_STN4_TX_DP<65>")
	)
	(segment
		(start 77.12964 -305.697636)
		(end 77.12964 -305.488848)
		(width 0.1143)
		(layer "In11.Cu")
		(net "P5E_PEX0_STN4_TX_DP<65>")
	)
	(segment
		(start 50.712878 -342.148668)
		(end 50.712878 -341.089742)
		(width 0.1651)
		(layer "In11.Cu")
		(net "P5E_PEX0_STN4_TX_DP<65>")
	)
	(segment
		(start 98.302318 -322.623942)
		(end 98.302318 -319.175638)
		(width 0.1651)
		(layer "In11.Cu")
		(net "P5E_PEX0_STN4_TX_DP<65>")
	)
	(segment
		(start 51.34991 -340.45271)
		(end 58.011568 -338.067396)
		(width 0.1651)
		(layer "In11.Cu")
		(net "P5E_PEX0_STN4_TX_DP<65>")
	)
	(segment
		(start 98.302318 -319.175638)
		(end 96.987106 -316.00013)
		(width 0.1651)
		(layer "In11.Cu")
		(net "P5E_PEX0_STN4_TX_DP<65>")
	)
	(segment
		(start 77.408024 -305.97602)
		(end 77.12964 -305.697636)
		(width 0.1143)
		(layer "In11.Cu")
		(net "P5E_PEX0_STN4_TX_DP<65>")
	)
	(segment
		(start 83.5914 -306.02174)
		(end 83.54568 -305.97602)
		(width 0.1143)
		(layer "In11.Cu")
		(net "P5E_PEX0_STN4_TX_DP<65>")
	)
	(segment
		(start 77.04074 -305.399948)
		(end 76.74991 -305.399948)
		(width 0.1143)
		(layer "In11.Cu")
		(net "P5E_PEX0_STN4_TX_DP<65>")
	)
	(segment
		(start 87.885524 -307.366924)
		(end 84.63788 -306.02174)
		(width 0.1651)
		(layer "In11.Cu")
		(net "P5E_PEX0_STN4_TX_DP<65>")
	)
	(segment
		(start 79.066136 -333.879444)
		(end 94.70263 -328.283824)
		(width 0.1651)
		(layer "In11.Cu")
		(net "P5E_PEX0_STN4_TX_DP<65>")
	)
	(segment
		(start 50.422048 -342.439498)
		(end 50.712878 -342.148668)
		(width 0.1651)
		(layer "In11.Cu")
		(net "P5E_PEX0_STN4_TX_DP<65>")
	)
	(segment
		(start 83.619848 -306.02174)
		(end 83.5914 -306.02174)
		(width 0.1143)
		(layer "In11.Cu")
		(net "P5E_PEX0_STN4_TX_DP<65>")
	)
	(segment
		(start 77.12964 -305.488848)
		(end 77.04074 -305.399948)
		(width 0.1143)
		(layer "In11.Cu")
		(net "P5E_PEX0_STN4_TX_DP<65>")
	)
	(segment
		(start 50.712878 -341.089742)
		(end 51.34991 -340.45271)
		(width 0.1651)
		(layer "In11.Cu")
		(net "P5E_PEX0_STN4_TX_DP<65>")
	)
	(segment
		(start 94.70263 -328.283824)
		(end 96.845628 -326.140826)
		(width 0.1651)
		(layer "In11.Cu")
		(net "P5E_PEX0_STN4_TX_DP<65>")
	)
	(segment
		(start 93.750892 -313.232292)
		(end 87.885524 -307.366924)
		(width 0.1651)
		(layer "In11.Cu")
		(net "P5E_PEX0_STN4_TX_DP<65>")
	)
	(segment
		(start 58.011568 -338.067396)
		(end 79.066136 -333.879444)
		(width 0.1651)
		(layer "In11.Cu")
		(net "P5E_PEX0_STN4_TX_DP<65>")
	)
	(segment
		(start 96.845628 -326.140826)
		(end 98.302318 -322.623942)
		(width 0.1651)
		(layer "In11.Cu")
		(net "P5E_PEX0_STN4_TX_DP<65>")
	)
	(segment
		(start 84.63788 -306.02174)
		(end 83.619848 -306.02174)
		(width 0.1651)
		(layer "In11.Cu")
		(net "P5E_PEX0_STN4_TX_DP<65>")
	)
	(segment
		(start 96.987106 -316.00013)
		(end 94.550484 -313.563508)
		(width 0.1651)
		(layer "In11.Cu")
		(net "P5E_PEX0_STN4_TX_DP<65>")
	)
	(segment
		(start 94.550484 -313.563508)
		(end 93.750892 -313.232292)
		(width 0.1651)
		(layer "In11.Cu")
		(net "P5E_PEX0_STN4_TX_DP<65>")
	)
	(segment
		(start 83.54568 -305.97602)
		(end 77.408024 -305.97602)
		(width 0.1143)
		(layer "In11.Cu")
		(net "P5E_PEX0_STN4_TX_DP<65>")
	)
	(segment
		(start 315.77788 -307.870098)
		(end 312.3946 -307.870098)
		(width 0.1143)
		(layer "In15.Cu")
		(net "P5E_PEX2_STN4_RX_DP<67>")
	)
	(segment
		(start 327.7108 -318.899032)
		(end 327.062846 -317.334646)
		(width 0.1651)
		(layer "In15.Cu")
		(net "P5E_PEX2_STN4_RX_DP<67>")
	)
	(segment
		(start 306.282344 -355.491034)
		(end 306.4129 -355.430582)
		(width 0.1651)
		(layer "In15.Cu")
		(net "P5E_PEX2_STN4_RX_DP<67>")
	)
	(segment
		(start 298.855892 -366.850168)
		(end 298.845732 -366.706912)
		(width 0.1651)
		(layer "In15.Cu")
		(net "P5E_PEX2_STN4_RX_DP<67>")
	)
	(segment
		(start 306.112164 -355.956362)
		(end 306.282344 -355.491034)
		(width 0.1651)
		(layer "In15.Cu")
		(net "P5E_PEX2_STN4_RX_DP<67>")
	)
	(segment
		(start 298.063158 -367.608612)
		(end 298.388024 -367.234216)
		(width 0.1651)
		(layer "In15.Cu")
		(net "P5E_PEX2_STN4_RX_DP<67>")
	)
	(segment
		(start 312.179462 -307.414168)
		(end 312.065162 -307.299868)
		(width 0.1143)
		(layer "In15.Cu")
		(net "P5E_PEX2_STN4_RX_DP<67>")
	)
	(segment
		(start 300.096428 -365.420656)
		(end 304.695606 -360.121708)
		(width 0.1651)
		(layer "In15.Cu")
		(net "P5E_PEX2_STN4_RX_DP<67>")
	)
	(segment
		(start 296.84726 -378.79909)
		(end 297.134026 -378.512324)
		(width 0.1651)
		(layer "In15.Cu")
		(net "P5E_PEX2_STN4_RX_DP<67>")
	)
	(segment
		(start 324.30466 -326.947022)
		(end 324.636892 -326.57923)
		(width 0.1651)
		(layer "In15.Cu")
		(net "P5E_PEX2_STN4_RX_DP<67>")
	)
	(segment
		(start 306.4129 -355.430582)
		(end 311.650634 -341.122508)
		(width 0.1651)
		(layer "In15.Cu")
		(net "P5E_PEX2_STN4_RX_DP<67>")
	)
	(segment
		(start 305.461416 -357.7336)
		(end 305.591972 -357.672894)
		(width 0.1651)
		(layer "In15.Cu")
		(net "P5E_PEX2_STN4_RX_DP<67>")
	)
	(segment
		(start 326.9615 -324.154546)
		(end 327.7108 -322.345558)
		(width 0.1651)
		(layer "In15.Cu")
		(net "P5E_PEX2_STN4_RX_DP<67>")
	)
	(segment
		(start 305.762152 -357.20782)
		(end 305.7017 -357.077518)
		(width 0.1651)
		(layer "In15.Cu")
		(net "P5E_PEX2_STN4_RX_DP<67>")
	)
	(segment
		(start 298.388024 -367.234216)
		(end 298.53128 -367.224056)
		(width 0.1651)
		(layer "In15.Cu")
		(net "P5E_PEX2_STN4_RX_DP<67>")
	)
	(segment
		(start 305.87188 -356.61219)
		(end 306.002436 -356.551738)
		(width 0.1651)
		(layer "In15.Cu")
		(net "P5E_PEX2_STN4_RX_DP<67>")
	)
	(segment
		(start 299.638466 -365.948468)
		(end 299.628306 -365.805212)
		(width 0.1651)
		(layer "In15.Cu")
		(net "P5E_PEX2_STN4_RX_DP<67>")
	)
	(segment
		(start 324.780402 -326.571864)
		(end 326.9615 -324.154546)
		(width 0.1651)
		(layer "In15.Cu")
		(net "P5E_PEX2_STN4_RX_DP<67>")
	)
	(segment
		(start 312.065162 -307.299868)
		(end 311.799732 -307.299868)
		(width 0.1143)
		(layer "In15.Cu")
		(net "P5E_PEX2_STN4_RX_DP<67>")
	)
	(segment
		(start 312.179462 -307.65496)
		(end 312.179462 -307.414168)
		(width 0.1143)
		(layer "In15.Cu")
		(net "P5E_PEX2_STN4_RX_DP<67>")
	)
	(segment
		(start 304.695606 -360.121708)
		(end 305.351688 -358.32923)
		(width 0.1651)
		(layer "In15.Cu")
		(net "P5E_PEX2_STN4_RX_DP<67>")
	)
	(segment
		(start 323.980302 -327.45807)
		(end 324.312026 -327.090532)
		(width 0.1651)
		(layer "In15.Cu")
		(net "P5E_PEX2_STN4_RX_DP<67>")
	)
	(segment
		(start 296.416984 -378.79909)
		(end 296.84726 -378.79909)
		(width 0.1651)
		(layer "In15.Cu")
		(net "P5E_PEX2_STN4_RX_DP<67>")
	)
	(segment
		(start 299.313854 -366.322356)
		(end 299.638466 -365.948468)
		(width 0.1651)
		(layer "In15.Cu")
		(net "P5E_PEX2_STN4_RX_DP<67>")
	)
	(segment
		(start 299.953172 -365.430816)
		(end 300.096428 -365.420656)
		(width 0.1651)
		(layer "In15.Cu")
		(net "P5E_PEX2_STN4_RX_DP<67>")
	)
	(segment
		(start 298.845732 -366.706912)
		(end 299.170598 -366.332516)
		(width 0.1651)
		(layer "In15.Cu")
		(net "P5E_PEX2_STN4_RX_DP<67>")
	)
	(segment
		(start 315.852048 -307.915818)
		(end 315.8236 -307.915818)
		(width 0.1143)
		(layer "In15.Cu")
		(net "P5E_PEX2_STN4_RX_DP<67>")
	)
	(segment
		(start 327.7108 -322.345558)
		(end 327.7108 -318.899032)
		(width 0.1651)
		(layer "In15.Cu")
		(net "P5E_PEX2_STN4_RX_DP<67>")
	)
	(segment
		(start 315.8236 -307.915818)
		(end 315.77788 -307.870098)
		(width 0.1143)
		(layer "In15.Cu")
		(net "P5E_PEX2_STN4_RX_DP<67>")
	)
	(segment
		(start 297.373294 -368.558318)
		(end 298.073318 -367.751868)
		(width 0.1651)
		(layer "In15.Cu")
		(net "P5E_PEX2_STN4_RX_DP<67>")
	)
	(segment
		(start 327.062846 -317.334646)
		(end 317.644018 -307.915818)
		(width 0.1651)
		(layer "In15.Cu")
		(net "P5E_PEX2_STN4_RX_DP<67>")
	)
	(segment
		(start 305.591972 -357.672894)
		(end 305.762152 -357.20782)
		(width 0.1651)
		(layer "In15.Cu")
		(net "P5E_PEX2_STN4_RX_DP<67>")
	)
	(segment
		(start 297.134026 -369.104418)
		(end 297.373294 -368.558318)
		(width 0.1651)
		(layer "In15.Cu")
		(net "P5E_PEX2_STN4_RX_DP<67>")
	)
	(segment
		(start 311.650634 -341.122508)
		(end 323.51218 -327.976992)
		(width 0.1651)
		(layer "In15.Cu")
		(net "P5E_PEX2_STN4_RX_DP<67>")
	)
	(segment
		(start 296.289984 -378.290074)
		(end 296.289984 -378.67209)
		(width 0.1651)
		(layer "In15.Cu")
		(net "P5E_PEX2_STN4_RX_DP<67>")
	)
	(segment
		(start 324.312026 -327.090532)
		(end 324.30466 -326.947022)
		(width 0.1651)
		(layer "In15.Cu")
		(net "P5E_PEX2_STN4_RX_DP<67>")
	)
	(segment
		(start 317.644018 -307.915818)
		(end 315.852048 -307.915818)
		(width 0.1651)
		(layer "In15.Cu")
		(net "P5E_PEX2_STN4_RX_DP<67>")
	)
	(segment
		(start 306.172616 -356.086664)
		(end 306.112164 -355.956362)
		(width 0.1651)
		(layer "In15.Cu")
		(net "P5E_PEX2_STN4_RX_DP<67>")
	)
	(segment
		(start 299.628306 -365.805212)
		(end 299.953172 -365.430816)
		(width 0.1651)
		(layer "In15.Cu")
		(net "P5E_PEX2_STN4_RX_DP<67>")
	)
	(segment
		(start 299.170598 -366.332516)
		(end 299.313854 -366.322356)
		(width 0.1651)
		(layer "In15.Cu")
		(net "P5E_PEX2_STN4_RX_DP<67>")
	)
	(segment
		(start 298.53128 -367.224056)
		(end 298.855892 -366.850168)
		(width 0.1651)
		(layer "In15.Cu")
		(net "P5E_PEX2_STN4_RX_DP<67>")
	)
	(segment
		(start 312.3946 -307.870098)
		(end 312.179462 -307.65496)
		(width 0.1143)
		(layer "In15.Cu")
		(net "P5E_PEX2_STN4_RX_DP<67>")
	)
	(segment
		(start 323.504814 -327.833482)
		(end 323.836792 -327.465436)
		(width 0.1651)
		(layer "In15.Cu")
		(net "P5E_PEX2_STN4_RX_DP<67>")
	)
	(segment
		(start 305.7017 -357.077518)
		(end 305.87188 -356.61219)
		(width 0.1651)
		(layer "In15.Cu")
		(net "P5E_PEX2_STN4_RX_DP<67>")
	)
	(segment
		(start 305.351688 -358.32923)
		(end 305.291236 -358.198928)
		(width 0.1651)
		(layer "In15.Cu")
		(net "P5E_PEX2_STN4_RX_DP<67>")
	)
	(segment
		(start 298.073318 -367.751868)
		(end 298.063158 -367.608612)
		(width 0.1651)
		(layer "In15.Cu")
		(net "P5E_PEX2_STN4_RX_DP<67>")
	)
	(segment
		(start 297.134026 -378.512324)
		(end 297.134026 -369.104418)
		(width 0.1651)
		(layer "In15.Cu")
		(net "P5E_PEX2_STN4_RX_DP<67>")
	)
	(segment
		(start 296.289984 -378.67209)
		(end 296.416984 -378.79909)
		(width 0.1651)
		(layer "In15.Cu")
		(net "P5E_PEX2_STN4_RX_DP<67>")
	)
	(segment
		(start 323.836792 -327.465436)
		(end 323.980302 -327.45807)
		(width 0.1651)
		(layer "In15.Cu")
		(net "P5E_PEX2_STN4_RX_DP<67>")
	)
	(segment
		(start 305.291236 -358.198928)
		(end 305.461416 -357.7336)
		(width 0.1651)
		(layer "In15.Cu")
		(net "P5E_PEX2_STN4_RX_DP<67>")
	)
	(segment
		(start 324.636892 -326.57923)
		(end 324.780402 -326.571864)
		(width 0.1651)
		(layer "In15.Cu")
		(net "P5E_PEX2_STN4_RX_DP<67>")
	)
	(segment
		(start 306.002436 -356.551738)
		(end 306.172616 -356.086664)
		(width 0.1651)
		(layer "In15.Cu")
		(net "P5E_PEX2_STN4_RX_DP<67>")
	)
	(segment
		(start 323.51218 -327.976992)
		(end 323.504814 -327.833482)
		(width 0.1651)
		(layer "In15.Cu")
		(net "P5E_PEX2_STN4_RX_DP<67>")
	)
	(segment
		(start 78.99654 -323.775832)
		(end 79.26578 -323.125846)
		(width 0.1651)
		(layer "In15.Cu")
		(net "P5E_PEX0_STN4_RX_DN<73>")
	)
	(segment
		(start 25.60066 -384.317748)
		(end 25.080214 -373.721122)
		(width 0.1651)
		(layer "In15.Cu")
		(net "P5E_PEX0_STN4_RX_DN<73>")
	)
	(segment
		(start 79.22006 -316.534292)
		(end 79.33436 -316.419992)
		(width 0.1143)
		(layer "In15.Cu")
		(net "P5E_PEX0_STN4_RX_DN<73>")
	)
	(segment
		(start 79.26578 -323.125846)
		(end 79.26578 -319.916048)
		(width 0.1651)
		(layer "In15.Cu")
		(net "P5E_PEX0_STN4_RX_DN<73>")
	)
	(segment
		(start 79.33436 -316.419992)
		(end 79.48549 -316.419992)
		(width 0.1143)
		(layer "In15.Cu")
		(net "P5E_PEX0_STN4_RX_DN<73>")
	)
	(segment
		(start 79.48549 -316.419992)
		(end 79.59979 -316.534292)
		(width 0.1143)
		(layer "In15.Cu")
		(net "P5E_PEX0_STN4_RX_DN<73>")
	)
	(segment
		(start 41.1099 -405.589994)
		(end 41.1099 -405.207978)
		(width 0.1651)
		(layer "In15.Cu")
		(net "P5E_PEX0_STN4_RX_DN<73>")
	)
	(segment
		(start 41.575228 -405.080978)
		(end 42.267632 -404.388574)
		(width 0.1651)
		(layer "In15.Cu")
		(net "P5E_PEX0_STN4_RX_DN<73>")
	)
	(segment
		(start 28.674568 -387.43509)
		(end 26.623518 -386.064506)
		(width 0.1651)
		(layer "In15.Cu")
		(net "P5E_PEX0_STN4_RX_DN<73>")
	)
	(segment
		(start 42.01541 -394.627608)
		(end 40.154352 -392.76655)
		(width 0.1651)
		(layer "In15.Cu")
		(net "P5E_PEX0_STN4_RX_DN<73>")
	)
	(segment
		(start 35.359848 -390.204198)
		(end 28.674568 -387.43509)
		(width 0.1651)
		(layer "In15.Cu")
		(net "P5E_PEX0_STN4_RX_DN<73>")
	)
	(segment
		(start 42.267632 -395.2367)
		(end 42.01541 -394.627608)
		(width 0.1651)
		(layer "In15.Cu")
		(net "P5E_PEX0_STN4_RX_DN<73>")
	)
	(segment
		(start 26.11247 -385.553458)
		(end 25.60066 -384.317748)
		(width 0.1651)
		(layer "In15.Cu")
		(net "P5E_PEX0_STN4_RX_DN<73>")
	)
	(segment
		(start 27.677618 -357.999792)
		(end 27.677618 -342.17483)
		(width 0.1651)
		(layer "In15.Cu")
		(net "P5E_PEX0_STN4_RX_DN<73>")
	)
	(segment
		(start 25.0698 -369.61191)
		(end 27.677618 -357.999792)
		(width 0.1651)
		(layer "In15.Cu")
		(net "P5E_PEX0_STN4_RX_DN<73>")
	)
	(segment
		(start 79.26578 -319.8876)
		(end 79.22006 -319.84188)
		(width 0.1143)
		(layer "In15.Cu")
		(net "P5E_PEX0_STN4_RX_DN<73>")
	)
	(segment
		(start 41.2369 -405.080978)
		(end 41.575228 -405.080978)
		(width 0.1651)
		(layer "In15.Cu")
		(net "P5E_PEX0_STN4_RX_DN<73>")
	)
	(segment
		(start 79.26578 -319.916048)
		(end 79.26578 -319.8876)
		(width 0.1143)
		(layer "In15.Cu")
		(net "P5E_PEX0_STN4_RX_DN<73>")
	)
	(segment
		(start 25.080214 -373.721122)
		(end 25.0698 -373.616474)
		(width 0.1651)
		(layer "In15.Cu")
		(net "P5E_PEX0_STN4_RX_DN<73>")
	)
	(segment
		(start 36.581588 -337.652614)
		(end 44.113196 -335.367884)
		(width 0.1651)
		(layer "In15.Cu")
		(net "P5E_PEX0_STN4_RX_DN<73>")
	)
	(segment
		(start 79.59979 -316.534292)
		(end 79.59979 -316.799722)
		(width 0.1143)
		(layer "In15.Cu")
		(net "P5E_PEX0_STN4_RX_DN<73>")
	)
	(segment
		(start 40.154352 -392.76655)
		(end 35.359848 -390.204198)
		(width 0.1651)
		(layer "In15.Cu")
		(net "P5E_PEX0_STN4_RX_DN<73>")
	)
	(segment
		(start 27.677618 -342.17483)
		(end 27.859736 -341.73541)
		(width 0.1651)
		(layer "In15.Cu")
		(net "P5E_PEX0_STN4_RX_DN<73>")
	)
	(segment
		(start 79.22006 -319.84188)
		(end 79.22006 -316.534292)
		(width 0.1143)
		(layer "In15.Cu")
		(net "P5E_PEX0_STN4_RX_DN<73>")
	)
	(segment
		(start 42.267632 -404.388574)
		(end 42.267632 -395.2367)
		(width 0.1651)
		(layer "In15.Cu")
		(net "P5E_PEX0_STN4_RX_DN<73>")
	)
	(segment
		(start 44.113196 -335.367884)
		(end 68.94703 -329.146916)
		(width 0.1651)
		(layer "In15.Cu")
		(net "P5E_PEX0_STN4_RX_DN<73>")
	)
	(segment
		(start 28.66263 -340.932516)
		(end 36.581588 -337.652614)
		(width 0.1651)
		(layer "In15.Cu")
		(net "P5E_PEX0_STN4_RX_DN<73>")
	)
	(segment
		(start 26.623518 -386.064506)
		(end 26.11247 -385.553458)
		(width 0.1651)
		(layer "In15.Cu")
		(net "P5E_PEX0_STN4_RX_DN<73>")
	)
	(segment
		(start 68.94703 -329.146916)
		(end 76.933298 -325.839074)
		(width 0.1651)
		(layer "In15.Cu")
		(net "P5E_PEX0_STN4_RX_DN<73>")
	)
	(segment
		(start 41.1099 -405.207978)
		(end 41.2369 -405.080978)
		(width 0.1651)
		(layer "In15.Cu")
		(net "P5E_PEX0_STN4_RX_DN<73>")
	)
	(segment
		(start 76.933298 -325.839074)
		(end 78.99654 -323.775832)
		(width 0.1651)
		(layer "In15.Cu")
		(net "P5E_PEX0_STN4_RX_DN<73>")
	)
	(segment
		(start 25.0698 -373.616474)
		(end 25.0698 -369.61191)
		(width 0.1651)
		(layer "In15.Cu")
		(net "P5E_PEX0_STN4_RX_DN<73>")
	)
	(segment
		(start 27.859736 -341.73541)
		(end 28.66263 -340.932516)
		(width 0.1651)
		(layer "In15.Cu")
		(net "P5E_PEX0_STN4_RX_DN<73>")
	)
	(segment
		(start 299.61586 -369.5446)
		(end 300.1772 -368.4016)
		(width 0.1651)
		(layer "In15.Cu")
		(net "P5E_PEX2_STN4_RX_DN<66>")
	)
	(segment
		(start 314.630054 -351.745804)
		(end 314.630054 -342.11895)
		(width 0.1651)
		(layer "In15.Cu")
		(net "P5E_PEX2_STN4_RX_DN<66>")
	)
	(segment
		(start 318.28486 -306.683918)
		(end 315.852048 -306.683918)
		(width 0.1651)
		(layer "In15.Cu")
		(net "P5E_PEX2_STN4_RX_DN<66>")
	)
	(segment
		(start 315.77788 -306.729638)
		(end 314.373768 -306.729638)
		(width 0.1143)
		(layer "In15.Cu")
		(net "P5E_PEX2_STN4_RX_DN<66>")
	)
	(segment
		(start 314.9854 -341.0966)
		(end 328.092054 -324.783704)
		(width 0.1651)
		(layer "In15.Cu")
		(net "P5E_PEX2_STN4_RX_DN<66>")
	)
	(segment
		(start 321.393566 -308.345586)
		(end 318.28486 -306.683918)
		(width 0.1651)
		(layer "In15.Cu")
		(net "P5E_PEX2_STN4_RX_DN<66>")
	)
	(segment
		(start 328.98334 -318.657478)
		(end 328.2315 -316.842394)
		(width 0.1651)
		(layer "In15.Cu")
		(net "P5E_PEX2_STN4_RX_DN<66>")
	)
	(segment
		(start 328.092054 -324.783704)
		(end 328.98334 -322.631308)
		(width 0.1651)
		(layer "In15.Cu")
		(net "P5E_PEX2_STN4_RX_DN<66>")
	)
	(segment
		(start 315.8236 -306.683918)
		(end 315.77788 -306.729638)
		(width 0.1143)
		(layer "In15.Cu")
		(net "P5E_PEX2_STN4_RX_DN<66>")
	)
	(segment
		(start 314.270136 -306.626006)
		(end 314.270136 -306.464208)
		(width 0.1143)
		(layer "In15.Cu")
		(net "P5E_PEX2_STN4_RX_DN<66>")
	)
	(segment
		(start 324.8914 -311.84342)
		(end 321.393566 -308.345586)
		(width 0.1651)
		(layer "In15.Cu")
		(net "P5E_PEX2_STN4_RX_DN<66>")
	)
	(segment
		(start 298.616878 -380.181104)
		(end 299.163994 -380.181104)
		(width 0.1651)
		(layer "In15.Cu")
		(net "P5E_PEX2_STN4_RX_DN<66>")
	)
	(segment
		(start 298.489878 -380.69012)
		(end 298.489878 -380.308104)
		(width 0.1651)
		(layer "In15.Cu")
		(net "P5E_PEX2_STN4_RX_DN<66>")
	)
	(segment
		(start 314.307474 -352.590862)
		(end 314.630054 -351.745804)
		(width 0.1651)
		(layer "In15.Cu")
		(net "P5E_PEX2_STN4_RX_DN<66>")
	)
	(segment
		(start 314.384436 -306.349908)
		(end 314.649866 -306.349908)
		(width 0.1143)
		(layer "In15.Cu")
		(net "P5E_PEX2_STN4_RX_DN<66>")
	)
	(segment
		(start 314.630054 -342.11895)
		(end 314.9854 -341.0966)
		(width 0.1651)
		(layer "In15.Cu")
		(net "P5E_PEX2_STN4_RX_DN<66>")
	)
	(segment
		(start 300.1772 -368.4016)
		(end 314.307474 -352.590862)
		(width 0.1651)
		(layer "In15.Cu")
		(net "P5E_PEX2_STN4_RX_DN<66>")
	)
	(segment
		(start 328.2315 -316.842394)
		(end 324.8914 -311.84342)
		(width 0.1651)
		(layer "In15.Cu")
		(net "P5E_PEX2_STN4_RX_DN<66>")
	)
	(segment
		(start 314.373768 -306.729638)
		(end 314.270136 -306.626006)
		(width 0.1143)
		(layer "In15.Cu")
		(net "P5E_PEX2_STN4_RX_DN<66>")
	)
	(segment
		(start 314.270136 -306.464208)
		(end 314.384436 -306.349908)
		(width 0.1143)
		(layer "In15.Cu")
		(net "P5E_PEX2_STN4_RX_DN<66>")
	)
	(segment
		(start 299.61586 -379.729238)
		(end 299.61586 -369.5446)
		(width 0.1651)
		(layer "In15.Cu")
		(net "P5E_PEX2_STN4_RX_DN<66>")
	)
	(segment
		(start 298.489878 -380.308104)
		(end 298.616878 -380.181104)
		(width 0.1651)
		(layer "In15.Cu")
		(net "P5E_PEX2_STN4_RX_DN<66>")
	)
	(segment
		(start 299.163994 -380.181104)
		(end 299.61586 -379.729238)
		(width 0.1651)
		(layer "In15.Cu")
		(net "P5E_PEX2_STN4_RX_DN<66>")
	)
	(segment
		(start 315.852048 -306.683918)
		(end 315.8236 -306.683918)
		(width 0.1143)
		(layer "In15.Cu")
		(net "P5E_PEX2_STN4_RX_DN<66>")
	)
	(segment
		(start 328.98334 -322.631308)
		(end 328.98334 -318.657478)
		(width 0.1651)
		(layer "In15.Cu")
		(net "P5E_PEX2_STN4_RX_DN<66>")
	)
	(segment
		(start 17.34566 -342.205564)
		(end 17.856708 -340.971886)
		(width 0.1651)
		(layer "In15.Cu")
		(net "P5E_PEX0_STN4_RX_DN<77>")
	)
	(segment
		(start 75.46594 -321.830446)
		(end 75.46594 -319.916048)
		(width 0.1651)
		(layer "In15.Cu")
		(net "P5E_PEX0_STN4_RX_DN<77>")
	)
	(segment
		(start 75.46594 -319.916048)
		(end 75.46594 -319.8876)
		(width 0.1143)
		(layer "In15.Cu")
		(net "P5E_PEX0_STN4_RX_DN<77>")
	)
	(segment
		(start 19.091402 -339.983064)
		(end 27.553412 -336.231992)
		(width 0.1651)
		(layer "In15.Cu")
		(net "P5E_PEX0_STN4_RX_DN<77>")
	)
	(segment
		(start 33.467802 -395.360144)
		(end 33.086548 -394.439394)
		(width 0.1651)
		(layer "In15.Cu")
		(net "P5E_PEX0_STN4_RX_DN<77>")
	)
	(segment
		(start 75.42022 -319.84188)
		(end 75.42022 -316.534292)
		(width 0.1143)
		(layer "In15.Cu")
		(net "P5E_PEX0_STN4_RX_DN<77>")
	)
	(segment
		(start 20.838668 -376.267472)
		(end 17.34566 -352.718878)
		(width 0.1651)
		(layer "In15.Cu")
		(net "P5E_PEX0_STN4_RX_DN<77>")
	)
	(segment
		(start 68.339716 -325.213218)
		(end 74.730102 -322.566284)
		(width 0.1651)
		(layer "In15.Cu")
		(net "P5E_PEX0_STN4_RX_DN<77>")
	)
	(segment
		(start 75.79995 -316.534292)
		(end 75.79995 -316.799722)
		(width 0.1143)
		(layer "In15.Cu")
		(net "P5E_PEX0_STN4_RX_DN<77>")
	)
	(segment
		(start 75.42022 -316.534292)
		(end 75.53452 -316.419992)
		(width 0.1143)
		(layer "In15.Cu")
		(net "P5E_PEX0_STN4_RX_DN<77>")
	)
	(segment
		(start 28.58643 -391.58926)
		(end 26.893266 -390.887966)
		(width 0.1651)
		(layer "In15.Cu")
		(net "P5E_PEX0_STN4_RX_DN<77>")
	)
	(segment
		(start 33.467802 -404.388574)
		(end 33.467802 -395.360144)
		(width 0.1651)
		(layer "In15.Cu")
		(net "P5E_PEX0_STN4_RX_DN<77>")
	)
	(segment
		(start 42.729658 -331.628242)
		(end 68.339716 -325.213218)
		(width 0.1651)
		(layer "In15.Cu")
		(net "P5E_PEX0_STN4_RX_DN<77>")
	)
	(segment
		(start 17.856708 -340.971886)
		(end 18.47723 -340.351364)
		(width 0.1651)
		(layer "In15.Cu")
		(net "P5E_PEX0_STN4_RX_DN<77>")
	)
	(segment
		(start 24.115776 -389.031988)
		(end 22.701504 -387.617716)
		(width 0.1651)
		(layer "In15.Cu")
		(net "P5E_PEX0_STN4_RX_DN<77>")
	)
	(segment
		(start 26.893266 -390.887966)
		(end 24.115776 -389.031988)
		(width 0.1651)
		(layer "In15.Cu")
		(net "P5E_PEX0_STN4_RX_DN<77>")
	)
	(segment
		(start 27.553412 -336.231992)
		(end 42.729658 -331.628242)
		(width 0.1651)
		(layer "In15.Cu")
		(net "P5E_PEX0_STN4_RX_DN<77>")
	)
	(segment
		(start 32.31007 -405.589994)
		(end 32.31007 -405.207978)
		(width 0.1651)
		(layer "In15.Cu")
		(net "P5E_PEX0_STN4_RX_DN<77>")
	)
	(segment
		(start 18.47723 -340.351364)
		(end 19.091402 -339.983064)
		(width 0.1651)
		(layer "In15.Cu")
		(net "P5E_PEX0_STN4_RX_DN<77>")
	)
	(segment
		(start 17.34566 -352.718878)
		(end 17.34566 -342.205564)
		(width 0.1651)
		(layer "In15.Cu")
		(net "P5E_PEX0_STN4_RX_DN<77>")
	)
	(segment
		(start 75.53452 -316.419992)
		(end 75.68565 -316.419992)
		(width 0.1143)
		(layer "In15.Cu")
		(net "P5E_PEX0_STN4_RX_DN<77>")
	)
	(segment
		(start 32.31007 -405.207978)
		(end 32.43707 -405.080978)
		(width 0.1651)
		(layer "In15.Cu")
		(net "P5E_PEX0_STN4_RX_DN<77>")
	)
	(segment
		(start 75.46594 -319.8876)
		(end 75.42022 -319.84188)
		(width 0.1143)
		(layer "In15.Cu")
		(net "P5E_PEX0_STN4_RX_DN<77>")
	)
	(segment
		(start 74.730102 -322.566284)
		(end 75.46594 -321.830446)
		(width 0.1651)
		(layer "In15.Cu")
		(net "P5E_PEX0_STN4_RX_DN<77>")
	)
	(segment
		(start 32.43707 -405.080978)
		(end 32.775398 -405.080978)
		(width 0.1651)
		(layer "In15.Cu")
		(net "P5E_PEX0_STN4_RX_DN<77>")
	)
	(segment
		(start 33.086548 -394.439394)
		(end 28.58643 -391.58926)
		(width 0.1651)
		(layer "In15.Cu")
		(net "P5E_PEX0_STN4_RX_DN<77>")
	)
	(segment
		(start 21.724366 -385.25831)
		(end 20.838668 -376.267472)
		(width 0.1651)
		(layer "In15.Cu")
		(net "P5E_PEX0_STN4_RX_DN<77>")
	)
	(segment
		(start 32.775398 -405.080978)
		(end 33.467802 -404.388574)
		(width 0.1651)
		(layer "In15.Cu")
		(net "P5E_PEX0_STN4_RX_DN<77>")
	)
	(segment
		(start 22.701504 -387.617716)
		(end 21.724366 -385.25831)
		(width 0.1651)
		(layer "In15.Cu")
		(net "P5E_PEX0_STN4_RX_DN<77>")
	)
	(segment
		(start 75.68565 -316.419992)
		(end 75.79995 -316.534292)
		(width 0.1143)
		(layer "In15.Cu")
		(net "P5E_PEX0_STN4_RX_DN<77>")
	)
	(segment
		(start 310.470042 -318.423798)
		(end 310.573674 -318.320166)
		(width 0.1143)
		(layer "In15.Cu")
		(net "P5E_PEX2_STN4_RX_DN<74>")
	)
	(segment
		(start 310.515762 -319.941448)
		(end 310.515762 -319.913)
		(width 0.1143)
		(layer "In15.Cu")
		(net "P5E_PEX2_STN4_RX_DN<74>")
	)
	(segment
		(start 310.515762 -323.260974)
		(end 310.515762 -319.941448)
		(width 0.1651)
		(layer "In15.Cu")
		(net "P5E_PEX2_STN4_RX_DN<74>")
	)
	(segment
		(start 299.163994 -406.181052)
		(end 299.61586 -405.729186)
		(width 0.1651)
		(layer "In15.Cu")
		(net "P5E_PEX2_STN4_RX_DN<74>")
	)
	(segment
		(start 283.99486 -372.432834)
		(end 284.576774 -368.596164)
		(width 0.1651)
		(layer "In15.Cu")
		(net "P5E_PEX2_STN4_RX_DN<74>")
	)
	(segment
		(start 293.4208 -390.8298)
		(end 287.466278 -388.281672)
		(width 0.1651)
		(layer "In15.Cu")
		(net "P5E_PEX2_STN4_RX_DN<74>")
	)
	(segment
		(start 297.9928 -393.4714)
		(end 293.4208 -390.8298)
		(width 0.1651)
		(layer "In15.Cu")
		(net "P5E_PEX2_STN4_RX_DN<74>")
	)
	(segment
		(start 285.3436 -367.3094)
		(end 291.417502 -358.967532)
		(width 0.1651)
		(layer "In15.Cu")
		(net "P5E_PEX2_STN4_RX_DN<74>")
	)
	(segment
		(start 285.147004 -386.68198)
		(end 284.482032 -385.024122)
		(width 0.1651)
		(layer "In15.Cu")
		(net "P5E_PEX2_STN4_RX_DN<74>")
	)
	(segment
		(start 310.573674 -318.320166)
		(end 310.735472 -318.320166)
		(width 0.1143)
		(layer "In15.Cu")
		(net "P5E_PEX2_STN4_RX_DN<74>")
	)
	(segment
		(start 299.61586 -405.729186)
		(end 299.61586 -396.1384)
		(width 0.1651)
		(layer "In15.Cu")
		(net "P5E_PEX2_STN4_RX_DN<74>")
	)
	(segment
		(start 298.489878 -406.308052)
		(end 298.616878 -406.181052)
		(width 0.1651)
		(layer "In15.Cu")
		(net "P5E_PEX2_STN4_RX_DN<74>")
	)
	(segment
		(start 291.787072 -342.195912)
		(end 291.95014 -341.811102)
		(width 0.1651)
		(layer "In15.Cu")
		(net "P5E_PEX2_STN4_RX_DN<74>")
	)
	(segment
		(start 298.616878 -406.181052)
		(end 299.163994 -406.181052)
		(width 0.1651)
		(layer "In15.Cu")
		(net "P5E_PEX2_STN4_RX_DN<74>")
	)
	(segment
		(start 291.787072 -358.07523)
		(end 291.787072 -342.195912)
		(width 0.1651)
		(layer "In15.Cu")
		(net "P5E_PEX2_STN4_RX_DN<74>")
	)
	(segment
		(start 310.32069 -323.732652)
		(end 310.515762 -323.260974)
		(width 0.1651)
		(layer "In15.Cu")
		(net "P5E_PEX2_STN4_RX_DN<74>")
	)
	(segment
		(start 291.417502 -358.967532)
		(end 291.787072 -358.07523)
		(width 0.1651)
		(layer "In15.Cu")
		(net "P5E_PEX2_STN4_RX_DN<74>")
	)
	(segment
		(start 310.735472 -318.320166)
		(end 310.849772 -318.434466)
		(width 0.1143)
		(layer "In15.Cu")
		(net "P5E_PEX2_STN4_RX_DN<74>")
	)
	(segment
		(start 292.112954 -341.426546)
		(end 310.32069 -323.732652)
		(width 0.1651)
		(layer "In15.Cu")
		(net "P5E_PEX2_STN4_RX_DN<74>")
	)
	(segment
		(start 310.470042 -319.86728)
		(end 310.470042 -318.423798)
		(width 0.1143)
		(layer "In15.Cu")
		(net "P5E_PEX2_STN4_RX_DN<74>")
	)
	(segment
		(start 310.515762 -319.913)
		(end 310.470042 -319.86728)
		(width 0.1143)
		(layer "In15.Cu")
		(net "P5E_PEX2_STN4_RX_DN<74>")
	)
	(segment
		(start 291.950394 -341.810594)
		(end 292.112954 -341.426546)
		(width 0.1651)
		(layer "In15.Cu")
		(net "P5E_PEX2_STN4_RX_DN<74>")
	)
	(segment
		(start 291.95014 -341.811102)
		(end 291.950394 -341.810594)
		(width 0.1651)
		(layer "In15.Cu")
		(net "P5E_PEX2_STN4_RX_DN<74>")
	)
	(segment
		(start 284.482032 -385.024122)
		(end 283.99486 -372.432834)
		(width 0.1651)
		(layer "In15.Cu")
		(net "P5E_PEX2_STN4_RX_DN<74>")
	)
	(segment
		(start 284.576774 -368.596164)
		(end 285.3436 -367.3094)
		(width 0.1651)
		(layer "In15.Cu")
		(net "P5E_PEX2_STN4_RX_DN<74>")
	)
	(segment
		(start 310.849772 -318.434466)
		(end 310.849772 -318.699896)
		(width 0.1143)
		(layer "In15.Cu")
		(net "P5E_PEX2_STN4_RX_DN<74>")
	)
	(segment
		(start 298.489878 -406.690068)
		(end 298.489878 -406.308052)
		(width 0.1651)
		(layer "In15.Cu")
		(net "P5E_PEX2_STN4_RX_DN<74>")
	)
	(segment
		(start 299.61586 -396.1384)
		(end 298.9326 -394.3604)
		(width 0.1651)
		(layer "In15.Cu")
		(net "P5E_PEX2_STN4_RX_DN<74>")
	)
	(segment
		(start 298.9326 -394.3604)
		(end 297.9928 -393.4714)
		(width 0.1651)
		(layer "In15.Cu")
		(net "P5E_PEX2_STN4_RX_DN<74>")
	)
	(segment
		(start 287.466278 -388.281672)
		(end 285.147004 -386.68198)
		(width 0.1651)
		(layer "In15.Cu")
		(net "P5E_PEX2_STN4_RX_DN<74>")
	)
	(segment
		(start 33.113726 -365.026702)
		(end 33.341056 -364.601252)
		(width 0.1651)
		(layer "In15.Cu")
		(net "P5E_PEX0_STN4_RX_DP<70>")
	)
	(segment
		(start 30.109922 -379.390148)
		(end 30.109922 -379.772164)
		(width 0.1651)
		(layer "In15.Cu")
		(net "P5E_PEX0_STN4_RX_DP<70>")
	)
	(segment
		(start 81.879694 -310.443372)
		(end 81.879694 -310.238648)
		(width 0.1143)
		(layer "In15.Cu")
		(net "P5E_PEX0_STN4_RX_DP<70>")
	)
	(segment
		(start 30.470602 -379.899164)
		(end 30.984952 -379.384814)
		(width 0.1651)
		(layer "In15.Cu")
		(net "P5E_PEX0_STN4_RX_DP<70>")
	)
	(segment
		(start 30.984952 -369.009168)
		(end 31.688532 -367.692686)
		(width 0.1651)
		(layer "In15.Cu")
		(net "P5E_PEX0_STN4_RX_DP<70>")
	)
	(segment
		(start 32.012128 -367.087658)
		(end 32.239458 -366.662208)
		(width 0.1651)
		(layer "In15.Cu")
		(net "P5E_PEX0_STN4_RX_DP<70>")
	)
	(segment
		(start 33.664652 -363.99597)
		(end 33.891982 -363.57052)
		(width 0.1651)
		(layer "In15.Cu")
		(net "P5E_PEX0_STN4_RX_DP<70>")
	)
	(segment
		(start 69.504306 -331.73543)
		(end 78.45171 -328.029316)
		(width 0.1651)
		(layer "In15.Cu")
		(net "P5E_PEX0_STN4_RX_DP<70>")
	)
	(segment
		(start 36.722558 -358.067864)
		(end 36.722558 -342.0872)
		(width 0.1651)
		(layer "In15.Cu")
		(net "P5E_PEX0_STN4_RX_DP<70>")
	)
	(segment
		(start 30.109922 -379.772164)
		(end 30.236922 -379.899164)
		(width 0.1651)
		(layer "In15.Cu")
		(net "P5E_PEX0_STN4_RX_DP<70>")
	)
	(segment
		(start 32.790384 -365.63173)
		(end 32.748728 -365.494316)
		(width 0.1651)
		(layer "In15.Cu")
		(net "P5E_PEX0_STN4_RX_DP<70>")
	)
	(segment
		(start 33.11398 -365.026702)
		(end 33.113726 -365.026702)
		(width 0.1651)
		(layer "In15.Cu")
		(net "P5E_PEX0_STN4_RX_DP<70>")
	)
	(segment
		(start 34.215324 -362.965492)
		(end 36.624514 -358.458516)
		(width 0.1651)
		(layer "In15.Cu")
		(net "P5E_PEX0_STN4_RX_DP<70>")
	)
	(segment
		(start 83.334352 -311.135776)
		(end 83.314286 -311.11571)
		(width 0.1143)
		(layer "In15.Cu")
		(net "P5E_PEX0_STN4_RX_DP<70>")
	)
	(segment
		(start 82.983578 -310.719978)
		(end 82.1563 -310.719978)
		(width 0.1143)
		(layer "In15.Cu")
		(net "P5E_PEX0_STN4_RX_DP<70>")
	)
	(segment
		(start 33.891982 -363.57052)
		(end 33.850326 -363.433106)
		(width 0.1651)
		(layer "In15.Cu")
		(net "P5E_PEX0_STN4_RX_DP<70>")
	)
	(segment
		(start 41.473374 -339.006688)
		(end 46.204124 -337.571588)
		(width 0.1651)
		(layer "In15.Cu")
		(net "P5E_PEX0_STN4_RX_DP<70>")
	)
	(segment
		(start 32.42564 -366.098836)
		(end 32.563054 -366.05718)
		(width 0.1651)
		(layer "In15.Cu")
		(net "P5E_PEX0_STN4_RX_DP<70>")
	)
	(segment
		(start 33.664906 -363.996224)
		(end 33.664652 -363.99597)
		(width 0.1651)
		(layer "In15.Cu")
		(net "P5E_PEX0_STN4_RX_DP<70>")
	)
	(segment
		(start 32.239458 -366.662208)
		(end 32.197802 -366.524794)
		(width 0.1651)
		(layer "In15.Cu")
		(net "P5E_PEX0_STN4_RX_DP<70>")
	)
	(segment
		(start 31.688532 -367.692686)
		(end 31.646876 -367.555272)
		(width 0.1651)
		(layer "In15.Cu")
		(net "P5E_PEX0_STN4_RX_DP<70>")
	)
	(segment
		(start 32.976566 -365.068358)
		(end 33.11398 -365.026702)
		(width 0.1651)
		(layer "In15.Cu")
		(net "P5E_PEX0_STN4_RX_DP<70>")
	)
	(segment
		(start 33.299654 -364.463838)
		(end 33.527492 -364.03788)
		(width 0.1651)
		(layer "In15.Cu")
		(net "P5E_PEX0_STN4_RX_DP<70>")
	)
	(segment
		(start 33.34131 -364.601252)
		(end 33.299654 -364.463838)
		(width 0.1651)
		(layer "In15.Cu")
		(net "P5E_PEX0_STN4_RX_DP<70>")
	)
	(segment
		(start 30.984952 -379.384814)
		(end 30.984952 -369.009168)
		(width 0.1651)
		(layer "In15.Cu")
		(net "P5E_PEX0_STN4_RX_DP<70>")
	)
	(segment
		(start 46.204124 -337.571588)
		(end 69.504306 -331.73543)
		(width 0.1651)
		(layer "In15.Cu")
		(net "P5E_PEX0_STN4_RX_DP<70>")
	)
	(segment
		(start 81.879694 -310.238648)
		(end 81.790794 -310.149748)
		(width 0.1143)
		(layer "In15.Cu")
		(net "P5E_PEX0_STN4_RX_DP<70>")
	)
	(segment
		(start 33.850326 -363.433106)
		(end 34.078164 -363.007148)
		(width 0.1651)
		(layer "In15.Cu")
		(net "P5E_PEX0_STN4_RX_DP<70>")
	)
	(segment
		(start 84.1248 -317.250064)
		(end 84.1248 -311.926224)
		(width 0.1651)
		(layer "In15.Cu")
		(net "P5E_PEX0_STN4_RX_DP<70>")
	)
	(segment
		(start 36.722558 -342.0872)
		(end 37.07257 -341.242396)
		(width 0.1651)
		(layer "In15.Cu")
		(net "P5E_PEX0_STN4_RX_DP<70>")
	)
	(segment
		(start 30.236922 -379.899164)
		(end 30.470602 -379.899164)
		(width 0.1651)
		(layer "In15.Cu")
		(net "P5E_PEX0_STN4_RX_DP<70>")
	)
	(segment
		(start 37.776912 -340.538054)
		(end 41.473374 -339.006688)
		(width 0.1651)
		(layer "In15.Cu")
		(net "P5E_PEX0_STN4_RX_DP<70>")
	)
	(segment
		(start 36.624514 -358.458516)
		(end 36.722558 -358.067864)
		(width 0.1651)
		(layer "In15.Cu")
		(net "P5E_PEX0_STN4_RX_DP<70>")
	)
	(segment
		(start 32.563054 -366.05718)
		(end 32.790384 -365.63173)
		(width 0.1651)
		(layer "In15.Cu")
		(net "P5E_PEX0_STN4_RX_DP<70>")
	)
	(segment
		(start 84.1248 -311.926224)
		(end 83.334352 -311.135776)
		(width 0.1651)
		(layer "In15.Cu")
		(net "P5E_PEX0_STN4_RX_DP<70>")
	)
	(segment
		(start 34.078164 -363.007148)
		(end 34.215324 -362.965492)
		(width 0.1651)
		(layer "In15.Cu")
		(net "P5E_PEX0_STN4_RX_DP<70>")
	)
	(segment
		(start 33.527492 -364.03788)
		(end 33.664906 -363.996224)
		(width 0.1651)
		(layer "In15.Cu")
		(net "P5E_PEX0_STN4_RX_DP<70>")
	)
	(segment
		(start 78.45171 -328.029316)
		(end 81.265014 -325.216012)
		(width 0.1651)
		(layer "In15.Cu")
		(net "P5E_PEX0_STN4_RX_DP<70>")
	)
	(segment
		(start 82.1563 -310.719978)
		(end 81.879694 -310.443372)
		(width 0.1143)
		(layer "In15.Cu")
		(net "P5E_PEX0_STN4_RX_DP<70>")
	)
	(segment
		(start 83.314286 -311.050686)
		(end 82.983578 -310.719978)
		(width 0.1143)
		(layer "In15.Cu")
		(net "P5E_PEX0_STN4_RX_DP<70>")
	)
	(segment
		(start 33.341056 -364.601252)
		(end 33.34131 -364.601252)
		(width 0.1651)
		(layer "In15.Cu")
		(net "P5E_PEX0_STN4_RX_DP<70>")
	)
	(segment
		(start 81.265014 -325.216012)
		(end 83.717892 -319.29451)
		(width 0.1651)
		(layer "In15.Cu")
		(net "P5E_PEX0_STN4_RX_DP<70>")
	)
	(segment
		(start 37.07257 -341.242396)
		(end 37.776912 -340.538054)
		(width 0.1651)
		(layer "In15.Cu")
		(net "P5E_PEX0_STN4_RX_DP<70>")
	)
	(segment
		(start 83.717892 -319.29451)
		(end 84.1248 -317.250064)
		(width 0.1651)
		(layer "In15.Cu")
		(net "P5E_PEX0_STN4_RX_DP<70>")
	)
	(segment
		(start 31.646876 -367.555272)
		(end 31.874714 -367.129314)
		(width 0.1651)
		(layer "In15.Cu")
		(net "P5E_PEX0_STN4_RX_DP<70>")
	)
	(segment
		(start 81.790794 -310.149748)
		(end 81.499964 -310.149748)
		(width 0.1143)
		(layer "In15.Cu")
		(net "P5E_PEX0_STN4_RX_DP<70>")
	)
	(segment
		(start 32.197802 -366.524794)
		(end 32.42564 -366.098836)
		(width 0.1651)
		(layer "In15.Cu")
		(net "P5E_PEX0_STN4_RX_DP<70>")
	)
	(segment
		(start 31.874714 -367.129314)
		(end 32.012128 -367.087658)
		(width 0.1651)
		(layer "In15.Cu")
		(net "P5E_PEX0_STN4_RX_DP<70>")
	)
	(segment
		(start 32.748728 -365.494316)
		(end 32.976566 -365.068358)
		(width 0.1651)
		(layer "In15.Cu")
		(net "P5E_PEX0_STN4_RX_DP<70>")
	)
	(segment
		(start 83.314286 -311.11571)
		(end 83.314286 -311.050686)
		(width 0.1143)
		(layer "In15.Cu")
		(net "P5E_PEX0_STN4_RX_DP<70>")
	)
	(segment
		(start 23.330408 -349.831914)
		(end 23.010368 -349.511874)
		(width 0.13462)
		(layer "F.Cu")
		(net "P5E_PEX0_STN4_TX_DN<78>")
	)
	(segment
		(start 23.010368 -349.511874)
		(end 23.010368 -348.88043)
		(width 0.13462)
		(layer "F.Cu")
		(net "P5E_PEX0_STN4_TX_DN<78>")
	)
	(segment
		(start 23.010368 -348.88043)
		(end 23.305008 -348.58579)
		(width 0.13462)
		(layer "F.Cu")
		(net "P5E_PEX0_STN4_TX_DN<78>")
	)
	(segment
		(start 74.47026 -313.735212)
		(end 74.63536 -313.570112)
		(width 0.1143)
		(layer "In11.Cu")
		(net "P5E_PEX0_STN4_TX_DN<78>")
	)
	(segment
		(start 73.039478 -322.490084)
		(end 74.068178 -321.940174)
		(width 0.1651)
		(layer "In11.Cu")
		(net "P5E_PEX0_STN4_TX_DN<78>")
	)
	(segment
		(start 23.014178 -348.29496)
		(end 23.014178 -347.736922)
		(width 0.1651)
		(layer "In11.Cu")
		(net "P5E_PEX0_STN4_TX_DN<78>")
	)
	(segment
		(start 74.51598 -320.294)
		(end 74.51598 -320.265552)
		(width 0.1143)
		(layer "In11.Cu")
		(net "P5E_PEX0_STN4_TX_DN<78>")
	)
	(segment
		(start 40.188388 -331.018642)
		(end 52.741322 -326.52716)
		(width 0.1651)
		(layer "In11.Cu")
		(net "P5E_PEX0_STN4_TX_DN<78>")
	)
	(segment
		(start 74.63536 -313.570112)
		(end 74.76109 -313.570112)
		(width 0.1143)
		(layer "In11.Cu")
		(net "P5E_PEX0_STN4_TX_DN<78>")
	)
	(segment
		(start 74.51598 -320.265552)
		(end 74.47026 -320.219832)
		(width 0.1143)
		(layer "In11.Cu")
		(net "P5E_PEX0_STN4_TX_DN<78>")
	)
	(segment
		(start 52.741322 -326.52716)
		(end 73.039478 -322.490084)
		(width 0.1651)
		(layer "In11.Cu")
		(net "P5E_PEX0_STN4_TX_DN<78>")
	)
	(segment
		(start 74.47026 -320.219832)
		(end 74.47026 -313.735212)
		(width 0.1143)
		(layer "In11.Cu")
		(net "P5E_PEX0_STN4_TX_DN<78>")
	)
	(segment
		(start 23.305008 -348.58579)
		(end 23.014178 -348.29496)
		(width 0.1651)
		(layer "In11.Cu")
		(net "P5E_PEX0_STN4_TX_DN<78>")
	)
	(segment
		(start 74.068178 -321.940174)
		(end 74.51598 -320.858896)
		(width 0.1651)
		(layer "In11.Cu")
		(net "P5E_PEX0_STN4_TX_DN<78>")
	)
	(segment
		(start 74.84999 -313.659012)
		(end 74.84999 -313.949842)
		(width 0.1143)
		(layer "In11.Cu")
		(net "P5E_PEX0_STN4_TX_DN<78>")
	)
	(segment
		(start 74.76109 -313.570112)
		(end 74.84999 -313.659012)
		(width 0.1143)
		(layer "In11.Cu")
		(net "P5E_PEX0_STN4_TX_DN<78>")
	)
	(segment
		(start 25.5778 -338.82838)
		(end 40.188388 -331.018642)
		(width 0.1651)
		(layer "In11.Cu")
		(net "P5E_PEX0_STN4_TX_DN<78>")
	)
	(segment
		(start 24.568658 -339.837522)
		(end 25.5778 -338.82838)
		(width 0.1651)
		(layer "In11.Cu")
		(net "P5E_PEX0_STN4_TX_DN<78>")
	)
	(segment
		(start 23.014178 -347.736922)
		(end 24.568658 -346.182442)
		(width 0.1651)
		(layer "In11.Cu")
		(net "P5E_PEX0_STN4_TX_DN<78>")
	)
	(segment
		(start 24.568658 -346.182442)
		(end 24.568658 -339.837522)
		(width 0.1651)
		(layer "In11.Cu")
		(net "P5E_PEX0_STN4_TX_DN<78>")
	)
	(segment
		(start 74.51598 -320.858896)
		(end 74.51598 -320.294)
		(width 0.1651)
		(layer "In11.Cu")
		(net "P5E_PEX0_STN4_TX_DN<78>")
	)
	(segment
		(start 303.53 -394.7414)
		(end 301.3964 -392.557)
		(width 0.1651)
		(layer "In15.Cu")
		(net "P5E_PEX2_STN4_RX_DN<72>")
	)
	(segment
		(start 286.857694 -385.398518)
		(end 286.436562 -384.527298)
		(width 0.1651)
		(layer "In15.Cu")
		(net "P5E_PEX2_STN4_RX_DN<72>")
	)
	(segment
		(start 312.415682 -319.941448)
		(end 312.415682 -319.913)
		(width 0.1143)
		(layer "In15.Cu")
		(net "P5E_PEX2_STN4_RX_DN<72>")
	)
	(segment
		(start 303.01692 -406.181052)
		(end 303.564036 -406.181052)
		(width 0.1651)
		(layer "In15.Cu")
		(net "P5E_PEX2_STN4_RX_DN<72>")
	)
	(segment
		(start 297.502326 -359.113074)
		(end 298.004992 -357.899462)
		(width 0.1651)
		(layer "In15.Cu")
		(net "P5E_PEX2_STN4_RX_DN<72>")
	)
	(segment
		(start 304.015902 -405.729186)
		(end 304.015902 -396.0368)
		(width 0.1651)
		(layer "In15.Cu")
		(net "P5E_PEX2_STN4_RX_DN<72>")
	)
	(segment
		(start 299.1358 -391.16)
		(end 288.3408 -386.461)
		(width 0.1651)
		(layer "In15.Cu")
		(net "P5E_PEX2_STN4_RX_DN<72>")
	)
	(segment
		(start 312.369962 -319.86728)
		(end 312.369962 -318.423798)
		(width 0.1143)
		(layer "In15.Cu")
		(net "P5E_PEX2_STN4_RX_DN<72>")
	)
	(segment
		(start 298.62526 -340.67369)
		(end 298.62526 -340.673436)
		(width 0.1651)
		(layer "In15.Cu")
		(net "P5E_PEX2_STN4_RX_DN<72>")
	)
	(segment
		(start 298.374308 -341.116666)
		(end 298.62526 -340.67369)
		(width 0.1651)
		(layer "In15.Cu")
		(net "P5E_PEX2_STN4_RX_DN<72>")
	)
	(segment
		(start 286.436562 -384.527298)
		(end 285.97606 -372.509034)
		(width 0.1651)
		(layer "In15.Cu")
		(net "P5E_PEX2_STN4_RX_DN<72>")
	)
	(segment
		(start 298.62526 -340.673436)
		(end 298.875958 -340.230968)
		(width 0.1651)
		(layer "In15.Cu")
		(net "P5E_PEX2_STN4_RX_DN<72>")
	)
	(segment
		(start 312.473594 -318.320166)
		(end 312.635392 -318.320166)
		(width 0.1143)
		(layer "In15.Cu")
		(net "P5E_PEX2_STN4_RX_DN<72>")
	)
	(segment
		(start 304.015902 -396.0368)
		(end 303.53 -394.7414)
		(width 0.1651)
		(layer "In15.Cu")
		(net "P5E_PEX2_STN4_RX_DN<72>")
	)
	(segment
		(start 303.564036 -406.181052)
		(end 304.015902 -405.729186)
		(width 0.1651)
		(layer "In15.Cu")
		(net "P5E_PEX2_STN4_RX_DN<72>")
	)
	(segment
		(start 302.88992 -406.308052)
		(end 303.01692 -406.181052)
		(width 0.1651)
		(layer "In15.Cu")
		(net "P5E_PEX2_STN4_RX_DN<72>")
	)
	(segment
		(start 285.97606 -372.509034)
		(end 286.385 -369.4684)
		(width 0.1651)
		(layer "In15.Cu")
		(net "P5E_PEX2_STN4_RX_DN<72>")
	)
	(segment
		(start 298.004992 -342.1634)
		(end 298.373546 -341.122762)
		(width 0.1651)
		(layer "In15.Cu")
		(net "P5E_PEX2_STN4_RX_DN<72>")
	)
	(segment
		(start 311.956196 -324.874636)
		(end 312.415682 -323.764656)
		(width 0.1651)
		(layer "In15.Cu")
		(net "P5E_PEX2_STN4_RX_DN<72>")
	)
	(segment
		(start 298.875958 -340.230968)
		(end 311.956196 -324.874636)
		(width 0.1651)
		(layer "In15.Cu")
		(net "P5E_PEX2_STN4_RX_DN<72>")
	)
	(segment
		(start 298.373038 -341.118698)
		(end 298.374308 -341.116666)
		(width 0.1651)
		(layer "In15.Cu")
		(net "P5E_PEX2_STN4_RX_DN<72>")
	)
	(segment
		(start 301.3964 -392.557)
		(end 299.1358 -391.16)
		(width 0.1651)
		(layer "In15.Cu")
		(net "P5E_PEX2_STN4_RX_DN<72>")
	)
	(segment
		(start 286.385 -369.4684)
		(end 286.9438 -368.554)
		(width 0.1651)
		(layer "In15.Cu")
		(net "P5E_PEX2_STN4_RX_DN<72>")
	)
	(segment
		(start 286.9438 -368.554)
		(end 297.3578 -359.2576)
		(width 0.1651)
		(layer "In15.Cu")
		(net "P5E_PEX2_STN4_RX_DN<72>")
	)
	(segment
		(start 288.3408 -386.461)
		(end 286.857694 -385.398518)
		(width 0.1651)
		(layer "In15.Cu")
		(net "P5E_PEX2_STN4_RX_DN<72>")
	)
	(segment
		(start 312.749692 -318.434466)
		(end 312.749692 -318.699896)
		(width 0.1143)
		(layer "In15.Cu")
		(net "P5E_PEX2_STN4_RX_DN<72>")
	)
	(segment
		(start 298.373546 -341.122762)
		(end 298.3738 -341.122)
		(width 0.1651)
		(layer "In15.Cu")
		(net "P5E_PEX2_STN4_RX_DN<72>")
	)
	(segment
		(start 312.415682 -319.913)
		(end 312.369962 -319.86728)
		(width 0.1143)
		(layer "In15.Cu")
		(net "P5E_PEX2_STN4_RX_DN<72>")
	)
	(segment
		(start 297.3578 -359.2576)
		(end 297.502326 -359.113074)
		(width 0.1651)
		(layer "In15.Cu")
		(net "P5E_PEX2_STN4_RX_DN<72>")
	)
	(segment
		(start 298.004992 -357.899462)
		(end 298.004992 -342.1634)
		(width 0.1651)
		(layer "In15.Cu")
		(net "P5E_PEX2_STN4_RX_DN<72>")
	)
	(segment
		(start 302.88992 -406.690068)
		(end 302.88992 -406.308052)
		(width 0.1651)
		(layer "In15.Cu")
		(net "P5E_PEX2_STN4_RX_DN<72>")
	)
	(segment
		(start 312.415682 -323.764656)
		(end 312.415682 -319.941448)
		(width 0.1651)
		(layer "In15.Cu")
		(net "P5E_PEX2_STN4_RX_DN<72>")
	)
	(segment
		(start 312.635392 -318.320166)
		(end 312.749692 -318.434466)
		(width 0.1143)
		(layer "In15.Cu")
		(net "P5E_PEX2_STN4_RX_DN<72>")
	)
	(segment
		(start 312.369962 -318.423798)
		(end 312.473594 -318.320166)
		(width 0.1143)
		(layer "In15.Cu")
		(net "P5E_PEX2_STN4_RX_DN<72>")
	)
	(segment
		(start 298.3738 -341.122)
		(end 298.373038 -341.118698)
		(width 0.1651)
		(layer "In15.Cu")
		(net "P5E_PEX2_STN4_RX_DN<72>")
	)
	(segment
		(start 32.337248 -344.539062)
		(end 32.657288 -344.219022)
		(width 0.13462)
		(layer "F.Cu")
		(net "P5E_PEX0_STN4_TX_C_DN<74>")
	)
	(segment
		(start 32.631888 -345.465146)
		(end 32.337248 -345.170506)
		(width 0.13462)
		(layer "F.Cu")
		(net "P5E_PEX0_STN4_TX_C_DN<74>")
	)
	(segment
		(start 32.337248 -345.170506)
		(end 32.337248 -344.539062)
		(width 0.13462)
		(layer "F.Cu")
		(net "P5E_PEX0_STN4_TX_C_DN<74>")
	)
	(segment
		(start 39.577264 -398.38122)
		(end 40.084248 -397.874236)
		(width 0.1651)
		(layer "In11.Cu")
		(net "P5E_PEX0_STN4_TX_C_DN<74>")
	)
	(segment
		(start 40.084248 -397.874236)
		(end 40.084248 -394.795756)
		(width 0.1651)
		(layer "In11.Cu")
		(net "P5E_PEX0_STN4_TX_C_DN<74>")
	)
	(segment
		(start 32.341058 -345.755976)
		(end 32.631888 -345.465146)
		(width 0.1651)
		(layer "In11.Cu")
		(net "P5E_PEX0_STN4_TX_C_DN<74>")
	)
	(segment
		(start 38.910006 -398.50822)
		(end 39.037006 -398.38122)
		(width 0.1651)
		(layer "In11.Cu")
		(net "P5E_PEX0_STN4_TX_C_DN<74>")
	)
	(segment
		(start 38.910006 -398.890236)
		(end 38.910006 -398.50822)
		(width 0.1651)
		(layer "In11.Cu")
		(net "P5E_PEX0_STN4_TX_C_DN<74>")
	)
	(segment
		(start 40.084248 -394.795756)
		(end 39.458646 -394.170154)
		(width 0.1651)
		(layer "In11.Cu")
		(net "P5E_PEX0_STN4_TX_C_DN<74>")
	)
	(segment
		(start 33.069784 -389.901176)
		(end 26.774394 -387.293612)
		(width 0.1651)
		(layer "In11.Cu")
		(net "P5E_PEX0_STN4_TX_C_DN<74>")
	)
	(segment
		(start 24.970994 -369.25377)
		(end 26.067258 -365.640874)
		(width 0.1651)
		(layer "In11.Cu")
		(net "P5E_PEX0_STN4_TX_C_DN<74>")
	)
	(segment
		(start 25.665684 -386.184902)
		(end 24.771096 -384.024886)
		(width 0.1651)
		(layer "In11.Cu")
		(net "P5E_PEX0_STN4_TX_C_DN<74>")
	)
	(segment
		(start 32.341058 -346.438982)
		(end 32.341058 -345.755976)
		(width 0.1651)
		(layer "In11.Cu")
		(net "P5E_PEX0_STN4_TX_C_DN<74>")
	)
	(segment
		(start 26.774394 -387.293612)
		(end 25.665684 -386.184902)
		(width 0.1651)
		(layer "In11.Cu")
		(net "P5E_PEX0_STN4_TX_C_DN<74>")
	)
	(segment
		(start 39.458646 -394.170154)
		(end 33.069784 -389.901176)
		(width 0.1651)
		(layer "In11.Cu")
		(net "P5E_PEX0_STN4_TX_C_DN<74>")
	)
	(segment
		(start 39.037006 -398.38122)
		(end 39.577264 -398.38122)
		(width 0.1651)
		(layer "In11.Cu")
		(net "P5E_PEX0_STN4_TX_C_DN<74>")
	)
	(segment
		(start 26.067258 -365.640874)
		(end 30.786578 -358.577896)
		(width 0.1651)
		(layer "In11.Cu")
		(net "P5E_PEX0_STN4_TX_C_DN<74>")
	)
	(segment
		(start 24.771096 -381.644652)
		(end 24.970994 -369.25377)
		(width 0.1651)
		(layer "In11.Cu")
		(net "P5E_PEX0_STN4_TX_C_DN<74>")
	)
	(segment
		(start 24.771096 -384.024886)
		(end 24.771096 -381.644652)
		(width 0.1651)
		(layer "In11.Cu")
		(net "P5E_PEX0_STN4_TX_C_DN<74>")
	)
	(segment
		(start 30.786578 -358.577896)
		(end 30.786578 -347.993462)
		(width 0.1651)
		(layer "In11.Cu")
		(net "P5E_PEX0_STN4_TX_C_DN<74>")
	)
	(segment
		(start 30.786578 -347.993462)
		(end 32.341058 -346.438982)
		(width 0.1651)
		(layer "In11.Cu")
		(net "P5E_PEX0_STN4_TX_C_DN<74>")
	)
	(segment
		(start 287.439862 -344.219022)
		(end 287.119822 -344.539062)
		(width 0.13462)
		(layer "F.Cu")
		(net "P5E_PEX2_STN4_TX_C_DN<71>")
	)
	(segment
		(start 287.119822 -344.539062)
		(end 287.119822 -345.170506)
		(width 0.13462)
		(layer "F.Cu")
		(net "P5E_PEX2_STN4_TX_C_DN<71>")
	)
	(segment
		(start 287.119822 -345.170506)
		(end 287.414462 -345.465146)
		(width 0.13462)
		(layer "F.Cu")
		(net "P5E_PEX2_STN4_TX_C_DN<71>")
	)
	(segment
		(start 285.569152 -347.881194)
		(end 285.569152 -358.90708)
		(width 0.1651)
		(layer "In11.Cu")
		(net "P5E_PEX2_STN4_TX_C_DN<71>")
	)
	(segment
		(start 287.414462 -345.465146)
		(end 287.123632 -345.755976)
		(width 0.1651)
		(layer "In11.Cu")
		(net "P5E_PEX2_STN4_TX_C_DN<71>")
	)
	(segment
		(start 287.6169 -371.281198)
		(end 287.4899 -371.408198)
		(width 0.1651)
		(layer "In11.Cu")
		(net "P5E_PEX2_STN4_TX_C_DN<71>")
	)
	(segment
		(start 288.615882 -370.829332)
		(end 288.164016 -371.281198)
		(width 0.1651)
		(layer "In11.Cu")
		(net "P5E_PEX2_STN4_TX_C_DN<71>")
	)
	(segment
		(start 285.569152 -358.90708)
		(end 288.615882 -368.82832)
		(width 0.1651)
		(layer "In11.Cu")
		(net "P5E_PEX2_STN4_TX_C_DN<71>")
	)
	(segment
		(start 288.615882 -368.82832)
		(end 288.615882 -370.829332)
		(width 0.1651)
		(layer "In11.Cu")
		(net "P5E_PEX2_STN4_TX_C_DN<71>")
	)
	(segment
		(start 287.4899 -371.408198)
		(end 287.4899 -371.790214)
		(width 0.1651)
		(layer "In11.Cu")
		(net "P5E_PEX2_STN4_TX_C_DN<71>")
	)
	(segment
		(start 287.123632 -345.755976)
		(end 287.123632 -346.326714)
		(width 0.1651)
		(layer "In11.Cu")
		(net "P5E_PEX2_STN4_TX_C_DN<71>")
	)
	(segment
		(start 288.164016 -371.281198)
		(end 287.6169 -371.281198)
		(width 0.1651)
		(layer "In11.Cu")
		(net "P5E_PEX2_STN4_TX_C_DN<71>")
	)
	(segment
		(start 287.123632 -346.326714)
		(end 285.569152 -347.881194)
		(width 0.1651)
		(layer "In11.Cu")
		(net "P5E_PEX2_STN4_TX_C_DN<71>")
	)
	(segment
		(start 82.197194 -308.629558)
		(end 82.070194 -308.502558)
		(width 0.1143)
		(layer "In15.Cu")
		(net "P5E_PEX0_STN4_RX_DN<68>")
	)
	(segment
		(start 78.813406 -331.244956)
		(end 92.329762 -325.646288)
		(width 0.1651)
		(layer "In15.Cu")
		(net "P5E_PEX0_STN4_RX_DN<68>")
	)
	(segment
		(start 86.71941 -309.443628)
		(end 85.4329 -308.583838)
		(width 0.1651)
		(layer "In15.Cu")
		(net "P5E_PEX0_STN4_RX_DN<68>")
	)
	(segment
		(start 34.509964 -380.69012)
		(end 34.509964 -380.308104)
		(width 0.1651)
		(layer "In15.Cu")
		(net "P5E_PEX0_STN4_RX_DN<68>")
	)
	(segment
		(start 85.4329 -308.583838)
		(end 83.645248 -308.583838)
		(width 0.1651)
		(layer "In15.Cu")
		(net "P5E_PEX0_STN4_RX_DN<68>")
	)
	(segment
		(start 92.329762 -325.646288)
		(end 93.79331 -324.57263)
		(width 0.1651)
		(layer "In15.Cu")
		(net "P5E_PEX0_STN4_RX_DN<68>")
	)
	(segment
		(start 35.666934 -369.704366)
		(end 36.184332 -368.455448)
		(width 0.1651)
		(layer "In15.Cu")
		(net "P5E_PEX0_STN4_RX_DN<68>")
	)
	(segment
		(start 43.222418 -342.210898)
		(end 43.483784 -341.579962)
		(width 0.1651)
		(layer "In15.Cu")
		(net "P5E_PEX0_STN4_RX_DN<68>")
	)
	(segment
		(start 83.645248 -308.583838)
		(end 83.6168 -308.583838)
		(width 0.1143)
		(layer "In15.Cu")
		(net "P5E_PEX0_STN4_RX_DN<68>")
	)
	(segment
		(start 44.6278 -340.435946)
		(end 47.991776 -339.415628)
		(width 0.1651)
		(layer "In15.Cu")
		(net "P5E_PEX0_STN4_RX_DN<68>")
	)
	(segment
		(start 34.509964 -380.308104)
		(end 34.636964 -380.181104)
		(width 0.1651)
		(layer "In15.Cu")
		(net "P5E_PEX0_STN4_RX_DN<68>")
	)
	(segment
		(start 43.222418 -358.103932)
		(end 43.222418 -342.210898)
		(width 0.1651)
		(layer "In15.Cu")
		(net "P5E_PEX0_STN4_RX_DN<68>")
	)
	(segment
		(start 47.991776 -339.415628)
		(end 70.296532 -333.82839)
		(width 0.1651)
		(layer "In15.Cu")
		(net "P5E_PEX0_STN4_RX_DN<68>")
	)
	(segment
		(start 34.987484 -380.181104)
		(end 35.666934 -379.501654)
		(width 0.1651)
		(layer "In15.Cu")
		(net "P5E_PEX0_STN4_RX_DN<68>")
	)
	(segment
		(start 93.87205 -316.596268)
		(end 86.71941 -309.443628)
		(width 0.1651)
		(layer "In15.Cu")
		(net "P5E_PEX0_STN4_RX_DN<68>")
	)
	(segment
		(start 83.6168 -308.583838)
		(end 83.57108 -308.629558)
		(width 0.1143)
		(layer "In15.Cu")
		(net "P5E_PEX0_STN4_RX_DN<68>")
	)
	(segment
		(start 43.483784 -341.579962)
		(end 44.6278 -340.435946)
		(width 0.1651)
		(layer "In15.Cu")
		(net "P5E_PEX0_STN4_RX_DN<68>")
	)
	(segment
		(start 95.131636 -319.636648)
		(end 93.87205 -316.596268)
		(width 0.1651)
		(layer "In15.Cu")
		(net "P5E_PEX0_STN4_RX_DN<68>")
	)
	(segment
		(start 35.666934 -379.501654)
		(end 35.666934 -369.704366)
		(width 0.1651)
		(layer "In15.Cu")
		(net "P5E_PEX0_STN4_RX_DN<68>")
	)
	(segment
		(start 34.636964 -380.181104)
		(end 34.987484 -380.181104)
		(width 0.1651)
		(layer "In15.Cu")
		(net "P5E_PEX0_STN4_RX_DN<68>")
	)
	(segment
		(start 39.009066 -364.647226)
		(end 42.9641 -358.727756)
		(width 0.1651)
		(layer "In15.Cu")
		(net "P5E_PEX0_STN4_RX_DN<68>")
	)
	(segment
		(start 94.877636 -322.534026)
		(end 95.131636 -319.636648)
		(width 0.1651)
		(layer "In15.Cu")
		(net "P5E_PEX0_STN4_RX_DN<68>")
	)
	(segment
		(start 94.26829 -324.005956)
		(end 94.877636 -322.534026)
		(width 0.1651)
		(layer "In15.Cu")
		(net "P5E_PEX0_STN4_RX_DN<68>")
	)
	(segment
		(start 82.070194 -308.502558)
		(end 82.070194 -308.338728)
		(width 0.1143)
		(layer "In15.Cu")
		(net "P5E_PEX0_STN4_RX_DN<68>")
	)
	(segment
		(start 83.57108 -308.629558)
		(end 82.197194 -308.629558)
		(width 0.1143)
		(layer "In15.Cu")
		(net "P5E_PEX0_STN4_RX_DN<68>")
	)
	(segment
		(start 70.296532 -333.82839)
		(end 78.813406 -331.244956)
		(width 0.1651)
		(layer "In15.Cu")
		(net "P5E_PEX0_STN4_RX_DN<68>")
	)
	(segment
		(start 36.184332 -368.455448)
		(end 39.009066 -364.647226)
		(width 0.1651)
		(layer "In15.Cu")
		(net "P5E_PEX0_STN4_RX_DN<68>")
	)
	(segment
		(start 82.159094 -308.249828)
		(end 82.449924 -308.249828)
		(width 0.1143)
		(layer "In15.Cu")
		(net "P5E_PEX0_STN4_RX_DN<68>")
	)
	(segment
		(start 93.79331 -324.57263)
		(end 94.26829 -324.005956)
		(width 0.1651)
		(layer "In15.Cu")
		(net "P5E_PEX0_STN4_RX_DN<68>")
	)
	(segment
		(start 42.9641 -358.727756)
		(end 43.222418 -358.103932)
		(width 0.1651)
		(layer "In15.Cu")
		(net "P5E_PEX0_STN4_RX_DN<68>")
	)
	(segment
		(start 82.070194 -308.338728)
		(end 82.159094 -308.249828)
		(width 0.1143)
		(layer "In15.Cu")
		(net "P5E_PEX0_STN4_RX_DN<68>")
	)
	(segment
		(start 35.446208 -348.88043)
		(end 35.740848 -348.58579)
		(width 0.13462)
		(layer "F.Cu")
		(net "P5E_PEX0_STN4_TX_DN<72>")
	)
	(segment
		(start 35.446208 -349.511874)
		(end 35.446208 -348.88043)
		(width 0.13462)
		(layer "F.Cu")
		(net "P5E_PEX0_STN4_TX_DN<72>")
	)
	(segment
		(start 35.766248 -349.831914)
		(end 35.446208 -349.511874)
		(width 0.13462)
		(layer "F.Cu")
		(net "P5E_PEX0_STN4_TX_DN<72>")
	)
	(segment
		(start 75.908662 -327.860152)
		(end 77.452728 -327.034906)
		(width 0.1651)
		(layer "In11.Cu")
		(net "P5E_PEX0_STN4_TX_DN<72>")
	)
	(segment
		(start 43.292776 -336.274664)
		(end 55.419498 -331.935328)
		(width 0.1651)
		(layer "In11.Cu")
		(net "P5E_PEX0_STN4_TX_DN<72>")
	)
	(segment
		(start 80.33512 -313.570112)
		(end 80.46085 -313.570112)
		(width 0.1143)
		(layer "In11.Cu")
		(net "P5E_PEX0_STN4_TX_DN<72>")
	)
	(segment
		(start 79.066136 -325.421244)
		(end 80.21574 -322.645786)
		(width 0.1651)
		(layer "In11.Cu")
		(net "P5E_PEX0_STN4_TX_DN<72>")
	)
	(segment
		(start 80.54975 -313.659012)
		(end 80.54975 -313.949842)
		(width 0.1143)
		(layer "In11.Cu")
		(net "P5E_PEX0_STN4_TX_DN<72>")
	)
	(segment
		(start 35.450018 -347.736922)
		(end 37.004498 -346.182442)
		(width 0.1651)
		(layer "In11.Cu")
		(net "P5E_PEX0_STN4_TX_DN<72>")
	)
	(segment
		(start 35.450018 -348.29496)
		(end 35.450018 -347.736922)
		(width 0.1651)
		(layer "In11.Cu")
		(net "P5E_PEX0_STN4_TX_DN<72>")
	)
	(segment
		(start 43.292776 -336.27441)
		(end 43.292776 -336.274664)
		(width 0.1651)
		(layer "In11.Cu")
		(net "P5E_PEX0_STN4_TX_DN<72>")
	)
	(segment
		(start 55.419498 -331.935328)
		(end 75.908662 -327.860152)
		(width 0.1651)
		(layer "In11.Cu")
		(net "P5E_PEX0_STN4_TX_DN<72>")
	)
	(segment
		(start 37.004498 -341.101172)
		(end 38.297358 -338.944458)
		(width 0.1651)
		(layer "In11.Cu")
		(net "P5E_PEX0_STN4_TX_DN<72>")
	)
	(segment
		(start 35.740848 -348.58579)
		(end 35.450018 -348.29496)
		(width 0.1651)
		(layer "In11.Cu")
		(net "P5E_PEX0_STN4_TX_DN<72>")
	)
	(segment
		(start 80.46085 -313.570112)
		(end 80.54975 -313.659012)
		(width 0.1143)
		(layer "In11.Cu")
		(net "P5E_PEX0_STN4_TX_DN<72>")
	)
	(segment
		(start 80.21574 -320.265552)
		(end 80.17002 -320.219832)
		(width 0.1143)
		(layer "In11.Cu")
		(net "P5E_PEX0_STN4_TX_DN<72>")
	)
	(segment
		(start 77.452728 -327.034906)
		(end 79.066136 -325.421244)
		(width 0.1651)
		(layer "In11.Cu")
		(net "P5E_PEX0_STN4_TX_DN<72>")
	)
	(segment
		(start 80.17002 -320.219832)
		(end 80.17002 -313.735212)
		(width 0.1143)
		(layer "In11.Cu")
		(net "P5E_PEX0_STN4_TX_DN<72>")
	)
	(segment
		(start 80.17002 -313.735212)
		(end 80.33512 -313.570112)
		(width 0.1143)
		(layer "In11.Cu")
		(net "P5E_PEX0_STN4_TX_DN<72>")
	)
	(segment
		(start 37.004498 -346.182442)
		(end 37.004498 -341.101172)
		(width 0.1651)
		(layer "In11.Cu")
		(net "P5E_PEX0_STN4_TX_DN<72>")
	)
	(segment
		(start 80.21574 -322.645786)
		(end 80.21574 -320.294)
		(width 0.1651)
		(layer "In11.Cu")
		(net "P5E_PEX0_STN4_TX_DN<72>")
	)
	(segment
		(start 38.297358 -338.944458)
		(end 43.292776 -336.27441)
		(width 0.1651)
		(layer "In11.Cu")
		(net "P5E_PEX0_STN4_TX_DN<72>")
	)
	(segment
		(start 80.21574 -320.294)
		(end 80.21574 -320.265552)
		(width 0.1143)
		(layer "In11.Cu")
		(net "P5E_PEX0_STN4_TX_DN<72>")
	)
	(segment
		(start 268.191742 -344.539062)
		(end 268.191742 -345.170506)
		(width 0.13462)
		(layer "F.Cu")
		(net "P5E_PEX2_STN4_TX_C_DP<79>")
	)
	(segment
		(start 268.191742 -345.170506)
		(end 267.897102 -345.465146)
		(width 0.13462)
		(layer "F.Cu")
		(net "P5E_PEX2_STN4_TX_C_DP<79>")
	)
	(segment
		(start 267.871702 -344.219022)
		(end 268.191742 -344.539062)
		(width 0.13462)
		(layer "F.Cu")
		(net "P5E_PEX2_STN4_TX_C_DP<79>")
	)
	(segment
		(start 286.333692 -393.797282)
		(end 286.218884 -393.84859)
		(width 0.1651)
		(layer "In11.Cu")
		(net "P5E_PEX2_STN4_TX_C_DP<79>")
	)
	(segment
		(start 287.4899 -396.49019)
		(end 287.4899 -396.872206)
		(width 0.1651)
		(layer "In11.Cu")
		(net "P5E_PEX2_STN4_TX_C_DP<79>")
	)
	(segment
		(start 284.013656 -392.691874)
		(end 283.852112 -392.698986)
		(width 0.1651)
		(layer "In11.Cu")
		(net "P5E_PEX2_STN4_TX_C_DP<79>")
	)
	(segment
		(start 282.216098 -391.043922)
		(end 282.054554 -391.05078)
		(width 0.1651)
		(layer "In11.Cu")
		(net "P5E_PEX2_STN4_TX_C_DP<79>")
	)
	(segment
		(start 288.333942 -396.71244)
		(end 288.333942 -394.939266)
		(width 0.1651)
		(layer "In11.Cu")
		(net "P5E_PEX2_STN4_TX_C_DP<79>")
	)
	(segment
		(start 285.704788 -393.556236)
		(end 284.418278 -393.062968)
		(width 0.1651)
		(layer "In11.Cu")
		(net "P5E_PEX2_STN4_TX_C_DP<79>")
	)
	(segment
		(start 268.187932 -346.209874)
		(end 268.187932 -345.755976)
		(width 0.1651)
		(layer "In11.Cu")
		(net "P5E_PEX2_STN4_TX_C_DP<79>")
	)
	(segment
		(start 268.724888 -359.042716)
		(end 266.633452 -352.310446)
		(width 0.1651)
		(layer "In11.Cu")
		(net "P5E_PEX2_STN4_TX_C_DP<79>")
	)
	(segment
		(start 283.11475 -391.867898)
		(end 282.953206 -391.874756)
		(width 0.1651)
		(layer "In11.Cu")
		(net "P5E_PEX2_STN4_TX_C_DP<79>")
	)
	(segment
		(start 285.756096 -393.671044)
		(end 285.704788 -393.556236)
		(width 0.1651)
		(layer "In11.Cu")
		(net "P5E_PEX2_STN4_TX_C_DP<79>")
	)
	(segment
		(start 280.952448 -389.885174)
		(end 279.222454 -386.546852)
		(width 0.1651)
		(layer "In11.Cu")
		(net "P5E_PEX2_STN4_TX_C_DP<79>")
	)
	(segment
		(start 268.733524 -359.060496)
		(end 268.724888 -359.042716)
		(width 0.1651)
		(layer "In11.Cu")
		(net "P5E_PEX2_STN4_TX_C_DP<79>")
	)
	(segment
		(start 286.218884 -393.84859)
		(end 285.756096 -393.671044)
		(width 0.1651)
		(layer "In11.Cu")
		(net "P5E_PEX2_STN4_TX_C_DP<79>")
	)
	(segment
		(start 287.4899 -396.872206)
		(end 287.6169 -396.999206)
		(width 0.1651)
		(layer "In11.Cu")
		(net "P5E_PEX2_STN4_TX_C_DP<79>")
	)
	(segment
		(start 288.333942 -394.939266)
		(end 288.0106 -394.44041)
		(width 0.1651)
		(layer "In11.Cu")
		(net "P5E_PEX2_STN4_TX_C_DP<79>")
	)
	(segment
		(start 283.852112 -392.698986)
		(end 283.48686 -392.36396)
		(width 0.1651)
		(layer "In11.Cu")
		(net "P5E_PEX2_STN4_TX_C_DP<79>")
	)
	(segment
		(start 278.330152 -379.41885)
		(end 268.733524 -359.060496)
		(width 0.1651)
		(layer "In11.Cu")
		(net "P5E_PEX2_STN4_TX_C_DP<79>")
	)
	(segment
		(start 286.847026 -394.089382)
		(end 286.795972 -393.974574)
		(width 0.1651)
		(layer "In11.Cu")
		(net "P5E_PEX2_STN4_TX_C_DP<79>")
	)
	(segment
		(start 287.309814 -394.266928)
		(end 286.847026 -394.089382)
		(width 0.1651)
		(layer "In11.Cu")
		(net "P5E_PEX2_STN4_TX_C_DP<79>")
	)
	(segment
		(start 282.953206 -391.874756)
		(end 282.587954 -391.53973)
		(width 0.1651)
		(layer "In11.Cu")
		(net "P5E_PEX2_STN4_TX_C_DP<79>")
	)
	(segment
		(start 287.6169 -396.999206)
		(end 288.047176 -396.999206)
		(width 0.1651)
		(layer "In11.Cu")
		(net "P5E_PEX2_STN4_TX_C_DP<79>")
	)
	(segment
		(start 283.48686 -392.36396)
		(end 283.479748 -392.202416)
		(width 0.1651)
		(layer "In11.Cu")
		(net "P5E_PEX2_STN4_TX_C_DP<79>")
	)
	(segment
		(start 284.418278 -393.062968)
		(end 284.013656 -392.691874)
		(width 0.1651)
		(layer "In11.Cu")
		(net "P5E_PEX2_STN4_TX_C_DP<79>")
	)
	(segment
		(start 282.587954 -391.53973)
		(end 282.581096 -391.37844)
		(width 0.1651)
		(layer "In11.Cu")
		(net "P5E_PEX2_STN4_TX_C_DP<79>")
	)
	(segment
		(start 282.054554 -391.05078)
		(end 281.689302 -390.715754)
		(width 0.1651)
		(layer "In11.Cu")
		(net "P5E_PEX2_STN4_TX_C_DP<79>")
	)
	(segment
		(start 287.424622 -394.215874)
		(end 287.309814 -394.266928)
		(width 0.1651)
		(layer "In11.Cu")
		(net "P5E_PEX2_STN4_TX_C_DP<79>")
	)
	(segment
		(start 266.633452 -352.310446)
		(end 266.633452 -347.764354)
		(width 0.1651)
		(layer "In11.Cu")
		(net "P5E_PEX2_STN4_TX_C_DP<79>")
	)
	(segment
		(start 279.222454 -386.546598)
		(end 278.330152 -379.41885)
		(width 0.1651)
		(layer "In11.Cu")
		(net "P5E_PEX2_STN4_TX_C_DP<79>")
	)
	(segment
		(start 288.0106 -394.44041)
		(end 287.424622 -394.215874)
		(width 0.1651)
		(layer "In11.Cu")
		(net "P5E_PEX2_STN4_TX_C_DP<79>")
	)
	(segment
		(start 288.047176 -396.999206)
		(end 288.333942 -396.71244)
		(width 0.1651)
		(layer "In11.Cu")
		(net "P5E_PEX2_STN4_TX_C_DP<79>")
	)
	(segment
		(start 281.682444 -390.554464)
		(end 280.952448 -389.885174)
		(width 0.1651)
		(layer "In11.Cu")
		(net "P5E_PEX2_STN4_TX_C_DP<79>")
	)
	(segment
		(start 281.689302 -390.715754)
		(end 281.682444 -390.554464)
		(width 0.1651)
		(layer "In11.Cu")
		(net "P5E_PEX2_STN4_TX_C_DP<79>")
	)
	(segment
		(start 268.187932 -345.755976)
		(end 267.897102 -345.465146)
		(width 0.1651)
		(layer "In11.Cu")
		(net "P5E_PEX2_STN4_TX_C_DP<79>")
	)
	(segment
		(start 282.581096 -391.37844)
		(end 282.216098 -391.043922)
		(width 0.1651)
		(layer "In11.Cu")
		(net "P5E_PEX2_STN4_TX_C_DP<79>")
	)
	(segment
		(start 283.479748 -392.202416)
		(end 283.11475 -391.867898)
		(width 0.1651)
		(layer "In11.Cu")
		(net "P5E_PEX2_STN4_TX_C_DP<79>")
	)
	(segment
		(start 286.795972 -393.974574)
		(end 286.333692 -393.797282)
		(width 0.1651)
		(layer "In11.Cu")
		(net "P5E_PEX2_STN4_TX_C_DP<79>")
	)
	(segment
		(start 266.633452 -347.764354)
		(end 268.187932 -346.209874)
		(width 0.1651)
		(layer "In11.Cu")
		(net "P5E_PEX2_STN4_TX_C_DP<79>")
	)
	(segment
		(start 279.222454 -386.546852)
		(end 279.222454 -386.546598)
		(width 0.1651)
		(layer "In11.Cu")
		(net "P5E_PEX2_STN4_TX_C_DP<79>")
	)
	(segment
		(start 19.627088 -345.170506)
		(end 19.627088 -344.539062)
		(width 0.13462)
		(layer "F.Cu")
		(net "P5E_PEX0_STN4_TX_C_DP<79>")
	)
	(segment
		(start 19.332448 -345.465146)
		(end 19.627088 -345.170506)
		(width 0.13462)
		(layer "F.Cu")
		(net "P5E_PEX0_STN4_TX_C_DP<79>")
	)
	(segment
		(start 19.627088 -344.539062)
		(end 19.307048 -344.219022)
		(width 0.13462)
		(layer "F.Cu")
		(net "P5E_PEX0_STN4_TX_C_DP<79>")
	)
	(segment
		(start 27.770582 -394.19276)
		(end 27.647138 -394.217398)
		(width 0.1651)
		(layer "In11.Cu")
		(net "P5E_PEX0_STN4_TX_C_DP<79>")
	)
	(segment
		(start 26.239978 -393.168124)
		(end 23.989538 -391.66165)
		(width 0.1651)
		(layer "In11.Cu")
		(net "P5E_PEX0_STN4_TX_C_DP<79>")
	)
	(segment
		(start 23.989538 -391.66165)
		(end 21.377402 -389.049514)
		(width 0.1651)
		(layer "In11.Cu")
		(net "P5E_PEX0_STN4_TX_C_DP<79>")
	)
	(segment
		(start 28.037028 -396.999206)
		(end 28.433268 -396.999206)
		(width 0.1651)
		(layer "In11.Cu")
		(net "P5E_PEX0_STN4_TX_C_DP<79>")
	)
	(segment
		(start 28.80233 -396.630144)
		(end 28.80233 -395.08811)
		(width 0.1651)
		(layer "In11.Cu")
		(net "P5E_PEX0_STN4_TX_C_DP<79>")
	)
	(segment
		(start 18.068798 -354.760276)
		(end 18.068798 -347.876622)
		(width 0.1651)
		(layer "In11.Cu")
		(net "P5E_PEX0_STN4_TX_C_DP<79>")
	)
	(segment
		(start 26.67635 -393.567158)
		(end 26.264362 -393.291314)
		(width 0.1651)
		(layer "In11.Cu")
		(net "P5E_PEX0_STN4_TX_C_DP<79>")
	)
	(segment
		(start 28.183586 -394.469366)
		(end 27.770582 -394.19276)
		(width 0.1651)
		(layer "In11.Cu")
		(net "P5E_PEX0_STN4_TX_C_DP<79>")
	)
	(segment
		(start 27.910028 -396.872206)
		(end 28.037028 -396.999206)
		(width 0.1651)
		(layer "In11.Cu")
		(net "P5E_PEX0_STN4_TX_C_DP<79>")
	)
	(segment
		(start 19.623278 -346.322142)
		(end 19.623278 -345.755976)
		(width 0.1651)
		(layer "In11.Cu")
		(net "P5E_PEX0_STN4_TX_C_DP<79>")
	)
	(segment
		(start 19.623278 -345.755976)
		(end 19.332448 -345.465146)
		(width 0.1651)
		(layer "In11.Cu")
		(net "P5E_PEX0_STN4_TX_C_DP<79>")
	)
	(segment
		(start 27.235404 -393.941554)
		(end 27.21102 -393.81811)
		(width 0.1651)
		(layer "In11.Cu")
		(net "P5E_PEX0_STN4_TX_C_DP<79>")
	)
	(segment
		(start 28.433268 -396.999206)
		(end 28.80233 -396.630144)
		(width 0.1651)
		(layer "In11.Cu")
		(net "P5E_PEX0_STN4_TX_C_DP<79>")
	)
	(segment
		(start 21.377402 -389.049514)
		(end 19.398996 -384.274314)
		(width 0.1651)
		(layer "In11.Cu")
		(net "P5E_PEX0_STN4_TX_C_DP<79>")
	)
	(segment
		(start 27.910028 -396.49019)
		(end 27.910028 -396.872206)
		(width 0.1651)
		(layer "In11.Cu")
		(net "P5E_PEX0_STN4_TX_C_DP<79>")
	)
	(segment
		(start 27.647138 -394.217398)
		(end 27.235404 -393.941554)
		(width 0.1651)
		(layer "In11.Cu")
		(net "P5E_PEX0_STN4_TX_C_DP<79>")
	)
	(segment
		(start 18.068798 -347.876622)
		(end 19.623278 -346.322142)
		(width 0.1651)
		(layer "In11.Cu")
		(net "P5E_PEX0_STN4_TX_C_DP<79>")
	)
	(segment
		(start 26.264362 -393.291314)
		(end 26.239978 -393.168124)
		(width 0.1651)
		(layer "In11.Cu")
		(net "P5E_PEX0_STN4_TX_C_DP<79>")
	)
	(segment
		(start 27.21102 -393.81811)
		(end 26.79954 -393.542774)
		(width 0.1651)
		(layer "In11.Cu")
		(net "P5E_PEX0_STN4_TX_C_DP<79>")
	)
	(segment
		(start 19.398996 -384.274314)
		(end 18.068798 -354.760276)
		(width 0.1651)
		(layer "In11.Cu")
		(net "P5E_PEX0_STN4_TX_C_DP<79>")
	)
	(segment
		(start 28.80233 -395.08811)
		(end 28.183586 -394.469366)
		(width 0.1651)
		(layer "In11.Cu")
		(net "P5E_PEX0_STN4_TX_C_DP<79>")
	)
	(segment
		(start 26.79954 -393.542774)
		(end 26.67635 -393.567158)
		(width 0.1651)
		(layer "In11.Cu")
		(net "P5E_PEX0_STN4_TX_C_DP<79>")
	)
	(segment
		(start 292.743382 -356.511606)
		(end 293.063422 -356.831646)
		(width 0.13462)
		(layer "F.Cu")
		(net "P5E_PEX2_STN4_TX_C_DP<67>")
	)
	(segment
		(start 293.063422 -357.46309)
		(end 292.768782 -357.75773)
		(width 0.13462)
		(layer "F.Cu")
		(net "P5E_PEX2_STN4_TX_C_DP<67>")
	)
	(segment
		(start 293.063422 -356.831646)
		(end 293.063422 -357.46309)
		(width 0.13462)
		(layer "F.Cu")
		(net "P5E_PEX2_STN4_TX_C_DP<67>")
	)
	(segment
		(start 294.747442 -362.985812)
		(end 294.559482 -362.527596)
		(width 0.1651)
		(layer "In11.Cu")
		(net "P5E_PEX2_STN4_TX_C_DP<67>")
	)
	(segment
		(start 294.006016 -361.361736)
		(end 293.78402 -360.820208)
		(width 0.1651)
		(layer "In11.Cu")
		(net "P5E_PEX2_STN4_TX_C_DP<67>")
	)
	(segment
		(start 296.289984 -370.872258)
		(end 296.416984 -370.999258)
		(width 0.1651)
		(layer "In11.Cu")
		(net "P5E_PEX2_STN4_TX_C_DP<67>")
	)
	(segment
		(start 295.798494 -365.849408)
		(end 295.610534 -365.390938)
		(width 0.1651)
		(layer "In11.Cu")
		(net "P5E_PEX2_STN4_TX_C_DP<67>")
	)
	(segment
		(start 294.22217 -362.006896)
		(end 294.284654 -361.857798)
		(width 0.1651)
		(layer "In11.Cu")
		(net "P5E_PEX2_STN4_TX_C_DP<67>")
	)
	(segment
		(start 293.78402 -360.820208)
		(end 293.821866 -360.729784)
		(width 0.1651)
		(layer "In11.Cu")
		(net "P5E_PEX2_STN4_TX_C_DP<67>")
	)
	(segment
		(start 296.84726 -370.999258)
		(end 297.134026 -370.712492)
		(width 0.1651)
		(layer "In11.Cu")
		(net "P5E_PEX2_STN4_TX_C_DP<67>")
	)
	(segment
		(start 295.673018 -365.24184)
		(end 295.485058 -364.783624)
		(width 0.1651)
		(layer "In11.Cu")
		(net "P5E_PEX2_STN4_TX_C_DP<67>")
	)
	(segment
		(start 293.059612 -358.04856)
		(end 292.768782 -357.75773)
		(width 0.1651)
		(layer "In11.Cu")
		(net "P5E_PEX2_STN4_TX_C_DP<67>")
	)
	(segment
		(start 294.872918 -363.59338)
		(end 294.684958 -363.13491)
		(width 0.1651)
		(layer "In11.Cu")
		(net "P5E_PEX2_STN4_TX_C_DP<67>")
	)
	(segment
		(start 293.059612 -358.871266)
		(end 293.059612 -358.04856)
		(width 0.1651)
		(layer "In11.Cu")
		(net "P5E_PEX2_STN4_TX_C_DP<67>")
	)
	(segment
		(start 296.073322 -366.518952)
		(end 296.135806 -366.369854)
		(width 0.1651)
		(layer "In11.Cu")
		(net "P5E_PEX2_STN4_TX_C_DP<67>")
	)
	(segment
		(start 297.134026 -368.802666)
		(end 296.873422 -368.167666)
		(width 0.1651)
		(layer "In11.Cu")
		(net "P5E_PEX2_STN4_TX_C_DP<67>")
	)
	(segment
		(start 294.559482 -362.527596)
		(end 294.41013 -362.465366)
		(width 0.1651)
		(layer "In11.Cu")
		(net "P5E_PEX2_STN4_TX_C_DP<67>")
	)
	(segment
		(start 296.289984 -370.489988)
		(end 296.289984 -370.872258)
		(width 0.1651)
		(layer "In11.Cu")
		(net "P5E_PEX2_STN4_TX_C_DP<67>")
	)
	(segment
		(start 295.147746 -364.262924)
		(end 295.21023 -364.113826)
		(width 0.1651)
		(layer "In11.Cu")
		(net "P5E_PEX2_STN4_TX_C_DP<67>")
	)
	(segment
		(start 296.416984 -370.999258)
		(end 296.84726 -370.999258)
		(width 0.1651)
		(layer "In11.Cu")
		(net "P5E_PEX2_STN4_TX_C_DP<67>")
	)
	(segment
		(start 296.598594 -367.497868)
		(end 296.410634 -367.039652)
		(width 0.1651)
		(layer "In11.Cu")
		(net "P5E_PEX2_STN4_TX_C_DP<67>")
	)
	(segment
		(start 296.410634 -367.039652)
		(end 296.261282 -366.977422)
		(width 0.1651)
		(layer "In11.Cu")
		(net "P5E_PEX2_STN4_TX_C_DP<67>")
	)
	(segment
		(start 295.02227 -363.65561)
		(end 294.872918 -363.59338)
		(width 0.1651)
		(layer "In11.Cu")
		(net "P5E_PEX2_STN4_TX_C_DP<67>")
	)
	(segment
		(start 294.284654 -361.857798)
		(end 294.096694 -361.399582)
		(width 0.1651)
		(layer "In11.Cu")
		(net "P5E_PEX2_STN4_TX_C_DP<67>")
	)
	(segment
		(start 296.724324 -368.105436)
		(end 296.536364 -367.646966)
		(width 0.1651)
		(layer "In11.Cu")
		(net "P5E_PEX2_STN4_TX_C_DP<67>")
	)
	(segment
		(start 294.684958 -363.13491)
		(end 294.747442 -362.985812)
		(width 0.1651)
		(layer "In11.Cu")
		(net "P5E_PEX2_STN4_TX_C_DP<67>")
	)
	(segment
		(start 294.41013 -362.465366)
		(end 294.22217 -362.006896)
		(width 0.1651)
		(layer "In11.Cu")
		(net "P5E_PEX2_STN4_TX_C_DP<67>")
	)
	(segment
		(start 295.947846 -365.911638)
		(end 295.798494 -365.849408)
		(width 0.1651)
		(layer "In11.Cu")
		(net "P5E_PEX2_STN4_TX_C_DP<67>")
	)
	(segment
		(start 295.335706 -364.721394)
		(end 295.147746 -364.262924)
		(width 0.1651)
		(layer "In11.Cu")
		(net "P5E_PEX2_STN4_TX_C_DP<67>")
	)
	(segment
		(start 295.485058 -364.783624)
		(end 295.335706 -364.721394)
		(width 0.1651)
		(layer "In11.Cu")
		(net "P5E_PEX2_STN4_TX_C_DP<67>")
	)
	(segment
		(start 296.261282 -366.977422)
		(end 296.073322 -366.518952)
		(width 0.1651)
		(layer "In11.Cu")
		(net "P5E_PEX2_STN4_TX_C_DP<67>")
	)
	(segment
		(start 296.135806 -366.369854)
		(end 295.947846 -365.911638)
		(width 0.1651)
		(layer "In11.Cu")
		(net "P5E_PEX2_STN4_TX_C_DP<67>")
	)
	(segment
		(start 297.134026 -370.712492)
		(end 297.134026 -368.802666)
		(width 0.1651)
		(layer "In11.Cu")
		(net "P5E_PEX2_STN4_TX_C_DP<67>")
	)
	(segment
		(start 296.873676 -368.167666)
		(end 296.724324 -368.105436)
		(width 0.1651)
		(layer "In11.Cu")
		(net "P5E_PEX2_STN4_TX_C_DP<67>")
	)
	(segment
		(start 296.873422 -368.167666)
		(end 296.873676 -368.167666)
		(width 0.1651)
		(layer "In11.Cu")
		(net "P5E_PEX2_STN4_TX_C_DP<67>")
	)
	(segment
		(start 295.610534 -365.390938)
		(end 295.673018 -365.24184)
		(width 0.1651)
		(layer "In11.Cu")
		(net "P5E_PEX2_STN4_TX_C_DP<67>")
	)
	(segment
		(start 296.536364 -367.646966)
		(end 296.598594 -367.497868)
		(width 0.1651)
		(layer "In11.Cu")
		(net "P5E_PEX2_STN4_TX_C_DP<67>")
	)
	(segment
		(start 294.096694 -361.399582)
		(end 294.006016 -361.361736)
		(width 0.1651)
		(layer "In11.Cu")
		(net "P5E_PEX2_STN4_TX_C_DP<67>")
	)
	(segment
		(start 295.21023 -364.113826)
		(end 295.02227 -363.65561)
		(width 0.1651)
		(layer "In11.Cu")
		(net "P5E_PEX2_STN4_TX_C_DP<67>")
	)
	(segment
		(start 293.821866 -360.729784)
		(end 293.059612 -358.871266)
		(width 0.1651)
		(layer "In11.Cu")
		(net "P5E_PEX2_STN4_TX_C_DP<67>")
	)
	(segment
		(start 94.699836 -316.068456)
		(end 87.33155 -308.70017)
		(width 0.1651)
		(layer "In15.Cu")
		(net "P5E_PEX0_STN4_RX_DN<67>")
	)
	(segment
		(start 37.867844 -369.507516)
		(end 38.294564 -368.314986)
		(width 0.1651)
		(layer "In15.Cu")
		(net "P5E_PEX0_STN4_RX_DN<67>")
	)
	(segment
		(start 87.33155 -308.70017)
		(end 85.736176 -307.633878)
		(width 0.1651)
		(layer "In15.Cu")
		(net "P5E_PEX0_STN4_RX_DN<67>")
	)
	(segment
		(start 80.17002 -307.514498)
		(end 80.17002 -307.388768)
		(width 0.1143)
		(layer "In15.Cu")
		(net "P5E_PEX0_STN4_RX_DN<67>")
	)
	(segment
		(start 46.331378 -341.4776)
		(end 46.959774 -340.849204)
		(width 0.1651)
		(layer "In15.Cu")
		(net "P5E_PEX0_STN4_RX_DN<67>")
	)
	(segment
		(start 94.459298 -325.306436)
		(end 95.066612 -324.582282)
		(width 0.1651)
		(layer "In15.Cu")
		(net "P5E_PEX0_STN4_RX_DN<67>")
	)
	(segment
		(start 46.144434 -358.625902)
		(end 46.331378 -358.009952)
		(width 0.1651)
		(layer "In15.Cu")
		(net "P5E_PEX0_STN4_RX_DN<67>")
	)
	(segment
		(start 46.959774 -340.849204)
		(end 50.345086 -339.824568)
		(width 0.1651)
		(layer "In15.Cu")
		(net "P5E_PEX0_STN4_RX_DN<67>")
	)
	(segment
		(start 85.736176 -307.633878)
		(end 83.645248 -307.633878)
		(width 0.1651)
		(layer "In15.Cu")
		(net "P5E_PEX0_STN4_RX_DN<67>")
	)
	(segment
		(start 96.116394 -319.488312)
		(end 94.699836 -316.068456)
		(width 0.1651)
		(layer "In15.Cu")
		(net "P5E_PEX0_STN4_RX_DN<67>")
	)
	(segment
		(start 80.25892 -307.299868)
		(end 80.54975 -307.299868)
		(width 0.1143)
		(layer "In15.Cu")
		(net "P5E_PEX0_STN4_RX_DN<67>")
	)
	(segment
		(start 70.586092 -334.773778)
		(end 78.957678 -332.23962)
		(width 0.1651)
		(layer "In15.Cu")
		(net "P5E_PEX0_STN4_RX_DN<67>")
	)
	(segment
		(start 78.957678 -332.23962)
		(end 92.85351 -326.484234)
		(width 0.1651)
		(layer "In15.Cu")
		(net "P5E_PEX0_STN4_RX_DN<67>")
	)
	(segment
		(start 36.837112 -379.08103)
		(end 37.17544 -379.08103)
		(width 0.1651)
		(layer "In15.Cu")
		(net "P5E_PEX0_STN4_RX_DN<67>")
	)
	(segment
		(start 80.33512 -307.679598)
		(end 80.17002 -307.514498)
		(width 0.1143)
		(layer "In15.Cu")
		(net "P5E_PEX0_STN4_RX_DN<67>")
	)
	(segment
		(start 37.17544 -379.08103)
		(end 37.867844 -378.388626)
		(width 0.1651)
		(layer "In15.Cu")
		(net "P5E_PEX0_STN4_RX_DN<67>")
	)
	(segment
		(start 50.345086 -339.824568)
		(end 70.586092 -334.773778)
		(width 0.1651)
		(layer "In15.Cu")
		(net "P5E_PEX0_STN4_RX_DN<67>")
	)
	(segment
		(start 36.710112 -379.590046)
		(end 36.710112 -379.20803)
		(width 0.1651)
		(layer "In15.Cu")
		(net "P5E_PEX0_STN4_RX_DN<67>")
	)
	(segment
		(start 37.867844 -378.388626)
		(end 37.867844 -369.507516)
		(width 0.1651)
		(layer "In15.Cu")
		(net "P5E_PEX0_STN4_RX_DN<67>")
	)
	(segment
		(start 38.294564 -368.314986)
		(end 45.698918 -359.292906)
		(width 0.1651)
		(layer "In15.Cu")
		(net "P5E_PEX0_STN4_RX_DN<67>")
	)
	(segment
		(start 83.645248 -307.633878)
		(end 83.6168 -307.633878)
		(width 0.1143)
		(layer "In15.Cu")
		(net "P5E_PEX0_STN4_RX_DN<67>")
	)
	(segment
		(start 83.57108 -307.679598)
		(end 80.33512 -307.679598)
		(width 0.1143)
		(layer "In15.Cu")
		(net "P5E_PEX0_STN4_RX_DN<67>")
	)
	(segment
		(start 36.710112 -379.20803)
		(end 36.837112 -379.08103)
		(width 0.1651)
		(layer "In15.Cu")
		(net "P5E_PEX0_STN4_RX_DN<67>")
	)
	(segment
		(start 95.831914 -322.733924)
		(end 96.116394 -319.488312)
		(width 0.1651)
		(layer "In15.Cu")
		(net "P5E_PEX0_STN4_RX_DN<67>")
	)
	(segment
		(start 95.066612 -324.582282)
		(end 95.831914 -322.733924)
		(width 0.1651)
		(layer "In15.Cu")
		(net "P5E_PEX0_STN4_RX_DN<67>")
	)
	(segment
		(start 45.698918 -359.292906)
		(end 46.144434 -358.625902)
		(width 0.1651)
		(layer "In15.Cu")
		(net "P5E_PEX0_STN4_RX_DN<67>")
	)
	(segment
		(start 46.331378 -358.009952)
		(end 46.331378 -341.4776)
		(width 0.1651)
		(layer "In15.Cu")
		(net "P5E_PEX0_STN4_RX_DN<67>")
	)
	(segment
		(start 80.17002 -307.388768)
		(end 80.25892 -307.299868)
		(width 0.1143)
		(layer "In15.Cu")
		(net "P5E_PEX0_STN4_RX_DN<67>")
	)
	(segment
		(start 92.85351 -326.484234)
		(end 94.459298 -325.306436)
		(width 0.1651)
		(layer "In15.Cu")
		(net "P5E_PEX0_STN4_RX_DN<67>")
	)
	(segment
		(start 83.6168 -307.633878)
		(end 83.57108 -307.679598)
		(width 0.1143)
		(layer "In15.Cu")
		(net "P5E_PEX0_STN4_RX_DN<67>")
	)
	(segment
		(start 284.080712 -387.454394)
		(end 283.235146 -385.312158)
		(width 0.1651)
		(layer "In15.Cu")
		(net "P5E_PEX2_STN4_RX_DP<75>")
	)
	(segment
		(start 309.54472 -316.229492)
		(end 309.785512 -316.229492)
		(width 0.1143)
		(layer "In15.Cu")
		(net "P5E_PEX2_STN4_RX_DP<75>")
	)
	(segment
		(start 309.899812 -316.115192)
		(end 309.899812 -315.849762)
		(width 0.1143)
		(layer "In15.Cu")
		(net "P5E_PEX2_STN4_RX_DP<75>")
	)
	(segment
		(start 292.375082 -391.86739)
		(end 286.66567 -389.289798)
		(width 0.1651)
		(layer "In15.Cu")
		(net "P5E_PEX2_STN4_RX_DP<75>")
	)
	(segment
		(start 309.283862 -319.913)
		(end 309.329582 -319.86728)
		(width 0.1143)
		(layer "In15.Cu")
		(net "P5E_PEX2_STN4_RX_DP<75>")
	)
	(segment
		(start 283.343858 -368.29111)
		(end 288.35985 -358.030018)
		(width 0.1651)
		(layer "In15.Cu")
		(net "P5E_PEX2_STN4_RX_DP<75>")
	)
	(segment
		(start 293.145718 -392.436096)
		(end 293.115492 -392.313922)
		(width 0.1651)
		(layer "In15.Cu")
		(net "P5E_PEX2_STN4_RX_DP<75>")
	)
	(segment
		(start 294.570404 -393.295886)
		(end 294.146224 -393.039854)
		(width 0.1651)
		(layer "In15.Cu")
		(net "P5E_PEX2_STN4_RX_DP<75>")
	)
	(segment
		(start 309.329582 -316.44463)
		(end 309.54472 -316.229492)
		(width 0.1143)
		(layer "In15.Cu")
		(net "P5E_PEX2_STN4_RX_DP<75>")
	)
	(segment
		(start 288.396172 -341.579454)
		(end 289.103054 -340.721696)
		(width 0.1651)
		(layer "In15.Cu")
		(net "P5E_PEX2_STN4_RX_DP<75>")
	)
	(segment
		(start 309.17261 -322.91401)
		(end 309.283862 -322.645278)
		(width 0.1651)
		(layer "In15.Cu")
		(net "P5E_PEX2_STN4_RX_DP<75>")
	)
	(segment
		(start 293.692072 -392.661902)
		(end 293.569898 -392.692128)
		(width 0.1651)
		(layer "In15.Cu")
		(net "P5E_PEX2_STN4_RX_DP<75>")
	)
	(segment
		(start 306.931314 -325.155052)
		(end 309.17261 -322.91401)
		(width 0.1651)
		(layer "In15.Cu")
		(net "P5E_PEX2_STN4_RX_DP<75>")
	)
	(segment
		(start 297.134026 -404.512272)
		(end 297.134026 -395.328902)
		(width 0.1651)
		(layer "In15.Cu")
		(net "P5E_PEX2_STN4_RX_DP<75>")
	)
	(segment
		(start 309.329582 -319.86728)
		(end 309.329582 -316.44463)
		(width 0.1143)
		(layer "In15.Cu")
		(net "P5E_PEX2_STN4_RX_DP<75>")
	)
	(segment
		(start 296.825924 -394.552678)
		(end 295.693084 -393.869164)
		(width 0.1651)
		(layer "In15.Cu")
		(net "P5E_PEX2_STN4_RX_DP<75>")
	)
	(segment
		(start 288.35985 -358.030018)
		(end 288.396172 -357.873808)
		(width 0.1651)
		(layer "In15.Cu")
		(net "P5E_PEX2_STN4_RX_DP<75>")
	)
	(segment
		(start 309.283862 -322.645278)
		(end 309.283862 -319.941448)
		(width 0.1651)
		(layer "In15.Cu")
		(net "P5E_PEX2_STN4_RX_DP<75>")
	)
	(segment
		(start 295.571164 -393.89939)
		(end 295.14673 -393.643358)
		(width 0.1651)
		(layer "In15.Cu")
		(net "P5E_PEX2_STN4_RX_DP<75>")
	)
	(segment
		(start 295.14673 -393.643358)
		(end 295.116504 -393.521438)
		(width 0.1651)
		(layer "In15.Cu")
		(net "P5E_PEX2_STN4_RX_DP<75>")
	)
	(segment
		(start 294.692578 -393.26566)
		(end 294.570404 -393.295886)
		(width 0.1651)
		(layer "In15.Cu")
		(net "P5E_PEX2_STN4_RX_DP<75>")
	)
	(segment
		(start 296.289984 -404.290022)
		(end 296.289984 -404.672038)
		(width 0.1651)
		(layer "In15.Cu")
		(net "P5E_PEX2_STN4_RX_DP<75>")
	)
	(segment
		(start 296.416984 -404.799038)
		(end 296.84726 -404.799038)
		(width 0.1651)
		(layer "In15.Cu")
		(net "P5E_PEX2_STN4_RX_DP<75>")
	)
	(segment
		(start 282.721304 -372.41734)
		(end 283.343858 -368.29111)
		(width 0.1651)
		(layer "In15.Cu")
		(net "P5E_PEX2_STN4_RX_DP<75>")
	)
	(segment
		(start 286.66567 -389.289798)
		(end 284.080712 -387.454394)
		(width 0.1651)
		(layer "In15.Cu")
		(net "P5E_PEX2_STN4_RX_DP<75>")
	)
	(segment
		(start 283.235146 -385.312158)
		(end 282.721304 -372.41734)
		(width 0.1651)
		(layer "In15.Cu")
		(net "P5E_PEX2_STN4_RX_DP<75>")
	)
	(segment
		(start 295.693084 -393.869164)
		(end 295.571164 -393.89939)
		(width 0.1651)
		(layer "In15.Cu")
		(net "P5E_PEX2_STN4_RX_DP<75>")
	)
	(segment
		(start 296.289984 -404.672038)
		(end 296.416984 -404.799038)
		(width 0.1651)
		(layer "In15.Cu")
		(net "P5E_PEX2_STN4_RX_DP<75>")
	)
	(segment
		(start 294.146224 -393.039854)
		(end 294.115998 -392.91768)
		(width 0.1651)
		(layer "In15.Cu")
		(net "P5E_PEX2_STN4_RX_DP<75>")
	)
	(segment
		(start 295.116504 -393.521438)
		(end 294.692578 -393.26566)
		(width 0.1651)
		(layer "In15.Cu")
		(net "P5E_PEX2_STN4_RX_DP<75>")
	)
	(segment
		(start 309.283862 -319.941448)
		(end 309.283862 -319.913)
		(width 0.1143)
		(layer "In15.Cu")
		(net "P5E_PEX2_STN4_RX_DP<75>")
	)
	(segment
		(start 294.115998 -392.91768)
		(end 293.692072 -392.661902)
		(width 0.1651)
		(layer "In15.Cu")
		(net "P5E_PEX2_STN4_RX_DP<75>")
	)
	(segment
		(start 293.569898 -392.692128)
		(end 293.145718 -392.436096)
		(width 0.1651)
		(layer "In15.Cu")
		(net "P5E_PEX2_STN4_RX_DP<75>")
	)
	(segment
		(start 309.785512 -316.229492)
		(end 309.899812 -316.115192)
		(width 0.1143)
		(layer "In15.Cu")
		(net "P5E_PEX2_STN4_RX_DP<75>")
	)
	(segment
		(start 296.84726 -404.799038)
		(end 297.134026 -404.512272)
		(width 0.1651)
		(layer "In15.Cu")
		(net "P5E_PEX2_STN4_RX_DP<75>")
	)
	(segment
		(start 289.103054 -340.721696)
		(end 306.931314 -325.155052)
		(width 0.1651)
		(layer "In15.Cu")
		(net "P5E_PEX2_STN4_RX_DP<75>")
	)
	(segment
		(start 293.115492 -392.313922)
		(end 292.375082 -391.86739)
		(width 0.1651)
		(layer "In15.Cu")
		(net "P5E_PEX2_STN4_RX_DP<75>")
	)
	(segment
		(start 297.134026 -395.328902)
		(end 296.825924 -394.552678)
		(width 0.1651)
		(layer "In15.Cu")
		(net "P5E_PEX2_STN4_RX_DP<75>")
	)
	(segment
		(start 288.396172 -357.873808)
		(end 288.396172 -341.579454)
		(width 0.1651)
		(layer "In15.Cu")
		(net "P5E_PEX2_STN4_RX_DP<75>")
	)
	(segment
		(start 44.498768 -344.539062)
		(end 44.178728 -344.219022)
		(width 0.13462)
		(layer "F.Cu")
		(net "P5E_PEX0_STN4_TX_C_DP<68>")
	)
	(segment
		(start 44.498768 -345.170506)
		(end 44.498768 -344.539062)
		(width 0.13462)
		(layer "F.Cu")
		(net "P5E_PEX0_STN4_TX_C_DP<68>")
	)
	(segment
		(start 44.204128 -345.465146)
		(end 44.498768 -345.170506)
		(width 0.13462)
		(layer "F.Cu")
		(net "P5E_PEX0_STN4_TX_C_DP<68>")
	)
	(segment
		(start 40.34028 -361.504484)
		(end 40.453818 -361.493308)
		(width 0.1651)
		(layer "In11.Cu")
		(net "P5E_PEX0_STN4_TX_C_DP<68>")
	)
	(segment
		(start 38.13302 -364.32109)
		(end 38.447218 -363.938312)
		(width 0.1651)
		(layer "In11.Cu")
		(net "P5E_PEX0_STN4_TX_C_DP<68>")
	)
	(segment
		(start 37.673534 -364.880906)
		(end 37.657532 -364.720124)
		(width 0.1651)
		(layer "In11.Cu")
		(net "P5E_PEX0_STN4_TX_C_DP<68>")
	)
	(segment
		(start 42.420032 -358.957626)
		(end 42.545 -358.94518)
		(width 0.1651)
		(layer "In11.Cu")
		(net "P5E_PEX0_STN4_TX_C_DP<68>")
	)
	(segment
		(start 35.40252 -369.404138)
		(end 35.865308 -368.110516)
		(width 0.1651)
		(layer "In11.Cu")
		(net "P5E_PEX0_STN4_TX_C_DP<68>")
	)
	(segment
		(start 38.745668 -363.394244)
		(end 38.906704 -363.378496)
		(width 0.1651)
		(layer "In11.Cu")
		(net "P5E_PEX0_STN4_TX_C_DP<68>")
	)
	(segment
		(start 35.40252 -371.75694)
		(end 35.40252 -369.404138)
		(width 0.1651)
		(layer "In11.Cu")
		(net "P5E_PEX0_STN4_TX_C_DP<68>")
	)
	(segment
		(start 42.940478 -347.876622)
		(end 44.494958 -346.322142)
		(width 0.1651)
		(layer "In11.Cu")
		(net "P5E_PEX0_STN4_TX_C_DP<68>")
	)
	(segment
		(start 35.970718 -367.514124)
		(end 36.100766 -367.452656)
		(width 0.1651)
		(layer "In11.Cu")
		(net "P5E_PEX0_STN4_TX_C_DP<68>")
	)
	(segment
		(start 34.509964 -371.590062)
		(end 34.509964 -371.972078)
		(width 0.1651)
		(layer "In11.Cu")
		(net "P5E_PEX0_STN4_TX_C_DP<68>")
	)
	(segment
		(start 35.80384 -367.980722)
		(end 35.970718 -367.514124)
		(width 0.1651)
		(layer "In11.Cu")
		(net "P5E_PEX0_STN4_TX_C_DP<68>")
	)
	(segment
		(start 36.884102 -365.662464)
		(end 37.198554 -365.279432)
		(width 0.1651)
		(layer "In11.Cu")
		(net "P5E_PEX0_STN4_TX_C_DP<68>")
	)
	(segment
		(start 42.10558 -359.340658)
		(end 42.420032 -358.957626)
		(width 0.1651)
		(layer "In11.Cu")
		(net "P5E_PEX0_STN4_TX_C_DP<68>")
	)
	(segment
		(start 38.431216 -363.77753)
		(end 38.745668 -363.394244)
		(width 0.1651)
		(layer "In11.Cu")
		(net "P5E_PEX0_STN4_TX_C_DP<68>")
	)
	(segment
		(start 38.447218 -363.938312)
		(end 38.431216 -363.77753)
		(width 0.1651)
		(layer "In11.Cu")
		(net "P5E_PEX0_STN4_TX_C_DP<68>")
	)
	(segment
		(start 36.89985 -365.8235)
		(end 36.884102 -365.662464)
		(width 0.1651)
		(layer "In11.Cu")
		(net "P5E_PEX0_STN4_TX_C_DP<68>")
	)
	(segment
		(start 37.971984 -364.336838)
		(end 38.13302 -364.32109)
		(width 0.1651)
		(layer "In11.Cu")
		(net "P5E_PEX0_STN4_TX_C_DP<68>")
	)
	(segment
		(start 41.376346 -360.369104)
		(end 41.364154 -360.244136)
		(width 0.1651)
		(layer "In11.Cu")
		(net "P5E_PEX0_STN4_TX_C_DP<68>")
	)
	(segment
		(start 36.100766 -367.452656)
		(end 36.516564 -366.290606)
		(width 0.1651)
		(layer "In11.Cu")
		(net "P5E_PEX0_STN4_TX_C_DP<68>")
	)
	(segment
		(start 41.803574 -359.848658)
		(end 42.117772 -359.46588)
		(width 0.1651)
		(layer "In11.Cu")
		(net "P5E_PEX0_STN4_TX_C_DP<68>")
	)
	(segment
		(start 37.359336 -365.263684)
		(end 37.673534 -364.880906)
		(width 0.1651)
		(layer "In11.Cu")
		(net "P5E_PEX0_STN4_TX_C_DP<68>")
	)
	(segment
		(start 39.2049 -362.834936)
		(end 39.519352 -362.45165)
		(width 0.1651)
		(layer "In11.Cu")
		(net "P5E_PEX0_STN4_TX_C_DP<68>")
	)
	(segment
		(start 34.509964 -371.972078)
		(end 34.636964 -372.099078)
		(width 0.1651)
		(layer "In11.Cu")
		(net "P5E_PEX0_STN4_TX_C_DP<68>")
	)
	(segment
		(start 34.636964 -372.099078)
		(end 35.060382 -372.099078)
		(width 0.1651)
		(layer "In11.Cu")
		(net "P5E_PEX0_STN4_TX_C_DP<68>")
	)
	(segment
		(start 42.940478 -358.463342)
		(end 42.940478 -347.876622)
		(width 0.1651)
		(layer "In11.Cu")
		(net "P5E_PEX0_STN4_TX_C_DP<68>")
	)
	(segment
		(start 37.657532 -364.720124)
		(end 37.971984 -364.336838)
		(width 0.1651)
		(layer "In11.Cu")
		(net "P5E_PEX0_STN4_TX_C_DP<68>")
	)
	(segment
		(start 38.906704 -363.378496)
		(end 39.220902 -362.995718)
		(width 0.1651)
		(layer "In11.Cu")
		(net "P5E_PEX0_STN4_TX_C_DP<68>")
	)
	(segment
		(start 39.220902 -362.995718)
		(end 39.2049 -362.834936)
		(width 0.1651)
		(layer "In11.Cu")
		(net "P5E_PEX0_STN4_TX_C_DP<68>")
	)
	(segment
		(start 44.494958 -346.322142)
		(end 44.494958 -345.755976)
		(width 0.1651)
		(layer "In11.Cu")
		(net "P5E_PEX0_STN4_TX_C_DP<68>")
	)
	(segment
		(start 35.060382 -372.099078)
		(end 35.40252 -371.75694)
		(width 0.1651)
		(layer "In11.Cu")
		(net "P5E_PEX0_STN4_TX_C_DP<68>")
	)
	(segment
		(start 37.198554 -365.279432)
		(end 37.359336 -365.263684)
		(width 0.1651)
		(layer "In11.Cu")
		(net "P5E_PEX0_STN4_TX_C_DP<68>")
	)
	(segment
		(start 41.678606 -359.86085)
		(end 41.803574 -359.848658)
		(width 0.1651)
		(layer "In11.Cu")
		(net "P5E_PEX0_STN4_TX_C_DP<68>")
	)
	(segment
		(start 39.983156 -361.939586)
		(end 40.34028 -361.504484)
		(width 0.1651)
		(layer "In11.Cu")
		(net "P5E_PEX0_STN4_TX_C_DP<68>")
	)
	(segment
		(start 39.994332 -362.053124)
		(end 39.983156 -361.939586)
		(width 0.1651)
		(layer "In11.Cu")
		(net "P5E_PEX0_STN4_TX_C_DP<68>")
	)
	(segment
		(start 44.494958 -345.755976)
		(end 44.204128 -345.465146)
		(width 0.1651)
		(layer "In11.Cu")
		(net "P5E_PEX0_STN4_TX_C_DP<68>")
	)
	(segment
		(start 42.545 -358.94518)
		(end 42.940478 -358.463342)
		(width 0.1651)
		(layer "In11.Cu")
		(net "P5E_PEX0_STN4_TX_C_DP<68>")
	)
	(segment
		(start 39.519352 -362.45165)
		(end 39.680388 -362.435902)
		(width 0.1651)
		(layer "In11.Cu")
		(net "P5E_PEX0_STN4_TX_C_DP<68>")
	)
	(segment
		(start 40.453818 -361.493308)
		(end 41.376346 -360.369104)
		(width 0.1651)
		(layer "In11.Cu")
		(net "P5E_PEX0_STN4_TX_C_DP<68>")
	)
	(segment
		(start 41.364154 -360.244136)
		(end 41.678606 -359.86085)
		(width 0.1651)
		(layer "In11.Cu")
		(net "P5E_PEX0_STN4_TX_C_DP<68>")
	)
	(segment
		(start 35.865308 -368.110516)
		(end 35.80384 -367.980722)
		(width 0.1651)
		(layer "In11.Cu")
		(net "P5E_PEX0_STN4_TX_C_DP<68>")
	)
	(segment
		(start 39.680388 -362.435902)
		(end 39.994332 -362.053124)
		(width 0.1651)
		(layer "In11.Cu")
		(net "P5E_PEX0_STN4_TX_C_DP<68>")
	)
	(segment
		(start 42.117772 -359.46588)
		(end 42.10558 -359.340658)
		(width 0.1651)
		(layer "In11.Cu")
		(net "P5E_PEX0_STN4_TX_C_DP<68>")
	)
	(segment
		(start 36.516564 -366.290606)
		(end 36.89985 -365.8235)
		(width 0.1651)
		(layer "In11.Cu")
		(net "P5E_PEX0_STN4_TX_C_DP<68>")
	)
	(segment
		(start 38.875208 -343.685622)
		(end 38.555168 -343.365582)
		(width 0.13462)
		(layer "F.Cu")
		(net "P5E_PEX0_STN4_TX_DN<71>")
	)
	(segment
		(start 38.555168 -343.365582)
		(end 38.555168 -342.734138)
		(width 0.13462)
		(layer "F.Cu")
		(net "P5E_PEX0_STN4_TX_DN<71>")
	)
	(segment
		(start 38.555168 -342.734138)
		(end 38.849808 -342.439498)
		(width 0.13462)
		(layer "F.Cu")
		(net "P5E_PEX0_STN4_TX_DN<71>")
	)
	(segment
		(start 79.97317 -325.91883)
		(end 82.115914 -322.711572)
		(width 0.1651)
		(layer "In11.Cu")
		(net "P5E_PEX0_STN4_TX_DN<71>")
	)
	(segment
		(start 38.558978 -342.148668)
		(end 38.558978 -340.999064)
		(width 0.1651)
		(layer "In11.Cu")
		(net "P5E_PEX0_STN4_TX_DN<71>")
	)
	(segment
		(start 76.15174 -328.836274)
		(end 78.093824 -327.79843)
		(width 0.1651)
		(layer "In11.Cu")
		(net "P5E_PEX0_STN4_TX_DN<71>")
	)
	(segment
		(start 78.123796 -327.768458)
		(end 78.123796 -327.768712)
		(width 0.1651)
		(layer "In11.Cu")
		(net "P5E_PEX0_STN4_TX_DN<71>")
	)
	(segment
		(start 82.159094 -314.899802)
		(end 82.449924 -314.899802)
		(width 0.1143)
		(layer "In11.Cu")
		(net "P5E_PEX0_STN4_TX_DN<71>")
	)
	(segment
		(start 39.395146 -339.604604)
		(end 44.255182 -337.006692)
		(width 0.1651)
		(layer "In11.Cu")
		(net "P5E_PEX0_STN4_TX_DN<71>")
	)
	(segment
		(start 38.558978 -340.999064)
		(end 39.395146 -339.604604)
		(width 0.1651)
		(layer "In11.Cu")
		(net "P5E_PEX0_STN4_TX_DN<71>")
	)
	(segment
		(start 38.849808 -342.439498)
		(end 38.558978 -342.148668)
		(width 0.1651)
		(layer "In11.Cu")
		(net "P5E_PEX0_STN4_TX_DN<71>")
	)
	(segment
		(start 82.115914 -319.151)
		(end 82.115914 -319.122552)
		(width 0.1143)
		(layer "In11.Cu")
		(net "P5E_PEX0_STN4_TX_DN<71>")
	)
	(segment
		(start 82.115914 -319.122552)
		(end 82.070194 -319.076832)
		(width 0.1143)
		(layer "In11.Cu")
		(net "P5E_PEX0_STN4_TX_DN<71>")
	)
	(segment
		(start 82.070194 -319.076832)
		(end 82.070194 -314.988702)
		(width 0.1143)
		(layer "In11.Cu")
		(net "P5E_PEX0_STN4_TX_DN<71>")
	)
	(segment
		(start 78.123796 -327.768712)
		(end 79.97317 -325.91883)
		(width 0.1651)
		(layer "In11.Cu")
		(net "P5E_PEX0_STN4_TX_DN<71>")
	)
	(segment
		(start 55.746142 -332.89494)
		(end 76.15174 -328.836274)
		(width 0.1651)
		(layer "In11.Cu")
		(net "P5E_PEX0_STN4_TX_DN<71>")
	)
	(segment
		(start 82.115914 -322.711572)
		(end 82.115914 -319.151)
		(width 0.1651)
		(layer "In11.Cu")
		(net "P5E_PEX0_STN4_TX_DN<71>")
	)
	(segment
		(start 44.255182 -337.006692)
		(end 55.746142 -332.89494)
		(width 0.1651)
		(layer "In11.Cu")
		(net "P5E_PEX0_STN4_TX_DN<71>")
	)
	(segment
		(start 78.093824 -327.79843)
		(end 78.123796 -327.768458)
		(width 0.1651)
		(layer "In11.Cu")
		(net "P5E_PEX0_STN4_TX_DN<71>")
	)
	(segment
		(start 82.070194 -314.988702)
		(end 82.159094 -314.899802)
		(width 0.1143)
		(layer "In11.Cu")
		(net "P5E_PEX0_STN4_TX_DN<71>")
	)
	(segment
		(start 284.330902 -350.365314)
		(end 284.010862 -350.685354)
		(width 0.13462)
		(layer "F.Cu")
		(net "P5E_PEX2_STN4_TX_C_DN<72>")
	)
	(segment
		(start 284.010862 -350.685354)
		(end 284.010862 -351.316798)
		(width 0.13462)
		(layer "F.Cu")
		(net "P5E_PEX2_STN4_TX_C_DN<72>")
	)
	(segment
		(start 284.010862 -351.316798)
		(end 284.305502 -351.611438)
		(width 0.13462)
		(layer "F.Cu")
		(net "P5E_PEX2_STN4_TX_C_DN<72>")
	)
	(segment
		(start 286.854138 -385.39674)
		(end 286.437832 -384.53695)
		(width 0.1651)
		(layer "In11.Cu")
		(net "P5E_PEX2_STN4_TX_C_DN<72>")
	)
	(segment
		(start 284.014672 -352.473006)
		(end 284.014672 -351.902268)
		(width 0.1651)
		(layer "In11.Cu")
		(net "P5E_PEX2_STN4_TX_C_DN<72>")
	)
	(segment
		(start 296.78376 -389.75538)
		(end 287.60928 -386.11556)
		(width 0.1651)
		(layer "In11.Cu")
		(net "P5E_PEX2_STN4_TX_C_DN<72>")
	)
	(segment
		(start 285.966408 -379.410214)
		(end 282.460192 -358.8131)
		(width 0.1651)
		(layer "In11.Cu")
		(net "P5E_PEX2_STN4_TX_C_DN<72>")
	)
	(segment
		(start 304.015902 -397.929354)
		(end 304.015902 -395.71422)
		(width 0.1651)
		(layer "In11.Cu")
		(net "P5E_PEX2_STN4_TX_C_DN<72>")
	)
	(segment
		(start 287.60928 -386.11556)
		(end 286.854138 -385.39674)
		(width 0.1651)
		(layer "In11.Cu")
		(net "P5E_PEX2_STN4_TX_C_DN<72>")
	)
	(segment
		(start 286.437832 -384.53695)
		(end 285.966408 -379.410214)
		(width 0.1651)
		(layer "In11.Cu")
		(net "P5E_PEX2_STN4_TX_C_DN<72>")
	)
	(segment
		(start 302.88992 -398.890236)
		(end 302.88992 -398.50822)
		(width 0.1651)
		(layer "In11.Cu")
		(net "P5E_PEX2_STN4_TX_C_DN<72>")
	)
	(segment
		(start 302.88992 -398.50822)
		(end 303.01692 -398.38122)
		(width 0.1651)
		(layer "In11.Cu")
		(net "P5E_PEX2_STN4_TX_C_DN<72>")
	)
	(segment
		(start 282.460192 -358.8131)
		(end 282.460192 -354.027486)
		(width 0.1651)
		(layer "In11.Cu")
		(net "P5E_PEX2_STN4_TX_C_DN<72>")
	)
	(segment
		(start 284.014672 -351.902268)
		(end 284.305502 -351.611438)
		(width 0.1651)
		(layer "In11.Cu")
		(net "P5E_PEX2_STN4_TX_C_DN<72>")
	)
	(segment
		(start 282.460192 -354.027486)
		(end 284.014672 -352.473006)
		(width 0.1651)
		(layer "In11.Cu")
		(net "P5E_PEX2_STN4_TX_C_DN<72>")
	)
	(segment
		(start 304.015902 -395.71422)
		(end 303.272444 -393.971526)
		(width 0.1651)
		(layer "In11.Cu")
		(net "P5E_PEX2_STN4_TX_C_DN<72>")
	)
	(segment
		(start 303.564036 -398.38122)
		(end 304.015902 -397.929354)
		(width 0.1651)
		(layer "In11.Cu")
		(net "P5E_PEX2_STN4_TX_C_DN<72>")
	)
	(segment
		(start 303.272444 -393.971526)
		(end 296.78376 -389.75538)
		(width 0.1651)
		(layer "In11.Cu")
		(net "P5E_PEX2_STN4_TX_C_DN<72>")
	)
	(segment
		(start 303.01692 -398.38122)
		(end 303.564036 -398.38122)
		(width 0.1651)
		(layer "In11.Cu")
		(net "P5E_PEX2_STN4_TX_C_DN<72>")
	)
	(segment
		(start 45.067728 -357.75773)
		(end 44.773088 -357.46309)
		(width 0.13462)
		(layer "F.Cu")
		(net "P5E_PEX0_STN4_TX_C_DN<67>")
	)
	(segment
		(start 44.773088 -356.831646)
		(end 45.093128 -356.511606)
		(width 0.13462)
		(layer "F.Cu")
		(net "P5E_PEX0_STN4_TX_C_DN<67>")
	)
	(segment
		(start 44.773088 -357.46309)
		(end 44.773088 -356.831646)
		(width 0.13462)
		(layer "F.Cu")
		(net "P5E_PEX0_STN4_TX_C_DN<67>")
	)
	(segment
		(start 44.776898 -358.04856)
		(end 45.067728 -357.75773)
		(width 0.1651)
		(layer "In11.Cu")
		(net "P5E_PEX0_STN4_TX_C_DN<67>")
	)
	(segment
		(start 37.972492 -368.957606)
		(end 44.713398 -358.866948)
		(width 0.1651)
		(layer "In11.Cu")
		(net "P5E_PEX0_STN4_TX_C_DN<67>")
	)
	(segment
		(start 37.971984 -370.5987)
		(end 37.971984 -368.958114)
		(width 0.1651)
		(layer "In11.Cu")
		(net "P5E_PEX0_STN4_TX_C_DN<67>")
	)
	(segment
		(start 36.710112 -371.790214)
		(end 36.710112 -371.408198)
		(width 0.1651)
		(layer "In11.Cu")
		(net "P5E_PEX0_STN4_TX_C_DN<67>")
	)
	(segment
		(start 44.713398 -358.866948)
		(end 44.776898 -358.803448)
		(width 0.1651)
		(layer "In11.Cu")
		(net "P5E_PEX0_STN4_TX_C_DN<67>")
	)
	(segment
		(start 37.289486 -371.281198)
		(end 37.971984 -370.5987)
		(width 0.1651)
		(layer "In11.Cu")
		(net "P5E_PEX0_STN4_TX_C_DN<67>")
	)
	(segment
		(start 36.837112 -371.281198)
		(end 37.289486 -371.281198)
		(width 0.1651)
		(layer "In11.Cu")
		(net "P5E_PEX0_STN4_TX_C_DN<67>")
	)
	(segment
		(start 37.971984 -368.958114)
		(end 37.972492 -368.957606)
		(width 0.1651)
		(layer "In11.Cu")
		(net "P5E_PEX0_STN4_TX_C_DN<67>")
	)
	(segment
		(start 44.776898 -358.803448)
		(end 44.776898 -358.04856)
		(width 0.1651)
		(layer "In11.Cu")
		(net "P5E_PEX0_STN4_TX_C_DN<67>")
	)
	(segment
		(start 36.710112 -371.408198)
		(end 36.837112 -371.281198)
		(width 0.1651)
		(layer "In11.Cu")
		(net "P5E_PEX0_STN4_TX_C_DN<67>")
	)
	(segment
		(start 44.178728 -343.685622)
		(end 44.498768 -343.365582)
		(width 0.13462)
		(layer "F.Cu")
		(net "P5E_PEX0_STN4_TX_DP<68>")
	)
	(segment
		(start 44.498768 -342.734138)
		(end 44.204128 -342.439498)
		(width 0.13462)
		(layer "F.Cu")
		(net "P5E_PEX0_STN4_TX_DP<68>")
	)
	(segment
		(start 44.498768 -343.365582)
		(end 44.498768 -342.734138)
		(width 0.13462)
		(layer "F.Cu")
		(net "P5E_PEX0_STN4_TX_DP<68>")
	)
	(segment
		(start 93.264228 -325.569072)
		(end 94.48673 -324.34657)
		(width 0.1651)
		(layer "In11.Cu")
		(net "P5E_PEX0_STN4_TX_DP<68>")
	)
	(segment
		(start 44.494958 -341.135462)
		(end 44.577254 -341.052912)
		(width 0.1651)
		(layer "In11.Cu")
		(net "P5E_PEX0_STN4_TX_DP<68>")
	)
	(segment
		(start 47.918878 -338.556092)
		(end 57.16778 -335.24698)
		(width 0.1651)
		(layer "In11.Cu")
		(net "P5E_PEX0_STN4_TX_DP<68>")
	)
	(segment
		(start 46.104048 -339.526118)
		(end 47.918878 -338.556092)
		(width 0.1651)
		(layer "In11.Cu")
		(net "P5E_PEX0_STN4_TX_DP<68>")
	)
	(segment
		(start 83.59648 -308.820058)
		(end 75.506326 -308.820058)
		(width 0.1143)
		(layer "In11.Cu")
		(net "P5E_PEX0_STN4_TX_DP<68>")
	)
	(segment
		(start 44.577254 -341.052912)
		(end 44.577508 -341.052912)
		(width 0.1651)
		(layer "In11.Cu")
		(net "P5E_PEX0_STN4_TX_DP<68>")
	)
	(segment
		(start 90.306398 -314.907422)
		(end 84.57438 -309.175404)
		(width 0.1651)
		(layer "In11.Cu")
		(net "P5E_PEX0_STN4_TX_DP<68>")
	)
	(segment
		(start 75.22972 -308.338728)
		(end 75.14082 -308.249828)
		(width 0.1143)
		(layer "In11.Cu")
		(net "P5E_PEX0_STN4_TX_DP<68>")
	)
	(segment
		(start 75.506326 -308.820058)
		(end 75.22972 -308.543452)
		(width 0.1143)
		(layer "In11.Cu")
		(net "P5E_PEX0_STN4_TX_DP<68>")
	)
	(segment
		(start 94.556834 -317.622174)
		(end 92.927678 -315.993018)
		(width 0.1651)
		(layer "In11.Cu")
		(net "P5E_PEX0_STN4_TX_DP<68>")
	)
	(segment
		(start 78.70317 -330.963778)
		(end 92.218256 -326.128126)
		(width 0.1651)
		(layer "In11.Cu")
		(net "P5E_PEX0_STN4_TX_DP<68>")
	)
	(segment
		(start 95.437198 -322.051934)
		(end 95.437198 -319.747646)
		(width 0.1651)
		(layer "In11.Cu")
		(net "P5E_PEX0_STN4_TX_DP<68>")
	)
	(segment
		(start 44.494958 -342.148668)
		(end 44.494958 -341.135462)
		(width 0.1651)
		(layer "In11.Cu")
		(net "P5E_PEX0_STN4_TX_DP<68>")
	)
	(segment
		(start 83.670648 -308.865778)
		(end 83.6422 -308.865778)
		(width 0.1143)
		(layer "In11.Cu")
		(net "P5E_PEX0_STN4_TX_DP<68>")
	)
	(segment
		(start 95.437198 -319.747646)
		(end 94.556834 -317.622174)
		(width 0.1651)
		(layer "In11.Cu")
		(net "P5E_PEX0_STN4_TX_DP<68>")
	)
	(segment
		(start 92.218256 -326.128126)
		(end 93.264228 -325.569072)
		(width 0.1651)
		(layer "In11.Cu")
		(net "P5E_PEX0_STN4_TX_DP<68>")
	)
	(segment
		(start 94.48673 -324.34657)
		(end 95.437198 -322.051934)
		(width 0.1651)
		(layer "In11.Cu")
		(net "P5E_PEX0_STN4_TX_DP<68>")
	)
	(segment
		(start 92.927678 -315.993018)
		(end 90.306398 -314.907422)
		(width 0.1651)
		(layer "In11.Cu")
		(net "P5E_PEX0_STN4_TX_DP<68>")
	)
	(segment
		(start 83.826858 -308.865778)
		(end 83.670648 -308.865778)
		(width 0.1651)
		(layer "In11.Cu")
		(net "P5E_PEX0_STN4_TX_DP<68>")
	)
	(segment
		(start 75.22972 -308.543452)
		(end 75.22972 -308.338728)
		(width 0.1143)
		(layer "In11.Cu")
		(net "P5E_PEX0_STN4_TX_DP<68>")
	)
	(segment
		(start 75.14082 -308.249828)
		(end 74.84999 -308.249828)
		(width 0.1143)
		(layer "In11.Cu")
		(net "P5E_PEX0_STN4_TX_DP<68>")
	)
	(segment
		(start 44.577508 -341.052912)
		(end 46.104048 -339.526118)
		(width 0.1651)
		(layer "In11.Cu")
		(net "P5E_PEX0_STN4_TX_DP<68>")
	)
	(segment
		(start 57.16778 -335.24698)
		(end 78.70317 -330.963778)
		(width 0.1651)
		(layer "In11.Cu")
		(net "P5E_PEX0_STN4_TX_DP<68>")
	)
	(segment
		(start 84.57438 -309.175404)
		(end 83.826858 -308.865778)
		(width 0.1651)
		(layer "In11.Cu")
		(net "P5E_PEX0_STN4_TX_DP<68>")
	)
	(segment
		(start 83.6422 -308.865778)
		(end 83.59648 -308.820058)
		(width 0.1143)
		(layer "In11.Cu")
		(net "P5E_PEX0_STN4_TX_DP<68>")
	)
	(segment
		(start 44.204128 -342.439498)
		(end 44.494958 -342.148668)
		(width 0.1651)
		(layer "In11.Cu")
		(net "P5E_PEX0_STN4_TX_DP<68>")
	)
	(segment
		(start 327.30186 -317.17488)
		(end 317.760858 -307.633878)
		(width 0.1651)
		(layer "In15.Cu")
		(net "P5E_PEX2_STN4_RX_DN<67>")
	)
	(segment
		(start 297.614594 -368.710972)
		(end 304.942748 -360.267504)
		(width 0.1651)
		(layer "In15.Cu")
		(net "P5E_PEX2_STN4_RX_DN<67>")
	)
	(segment
		(start 312.369962 -307.575966)
		(end 312.369962 -307.414168)
		(width 0.1143)
		(layer "In15.Cu")
		(net "P5E_PEX2_STN4_RX_DN<67>")
	)
	(segment
		(start 315.852048 -307.633878)
		(end 315.8236 -307.633878)
		(width 0.1143)
		(layer "In15.Cu")
		(net "P5E_PEX2_STN4_RX_DN<67>")
	)
	(segment
		(start 296.289984 -379.590046)
		(end 296.289984 -379.20803)
		(width 0.1651)
		(layer "In15.Cu")
		(net "P5E_PEX2_STN4_RX_DN<67>")
	)
	(segment
		(start 315.8236 -307.633878)
		(end 315.77788 -307.679598)
		(width 0.1143)
		(layer "In15.Cu")
		(net "P5E_PEX2_STN4_RX_DN<67>")
	)
	(segment
		(start 304.942748 -360.267504)
		(end 311.89676 -341.270844)
		(width 0.1651)
		(layer "In15.Cu")
		(net "P5E_PEX2_STN4_RX_DN<67>")
	)
	(segment
		(start 312.484262 -307.299868)
		(end 312.749692 -307.299868)
		(width 0.1143)
		(layer "In15.Cu")
		(net "P5E_PEX2_STN4_RX_DN<67>")
	)
	(segment
		(start 315.77788 -307.679598)
		(end 312.473594 -307.679598)
		(width 0.1143)
		(layer "In15.Cu")
		(net "P5E_PEX2_STN4_RX_DN<67>")
	)
	(segment
		(start 296.289984 -379.20803)
		(end 296.416984 -379.08103)
		(width 0.1651)
		(layer "In15.Cu")
		(net "P5E_PEX2_STN4_RX_DN<67>")
	)
	(segment
		(start 312.369962 -307.414168)
		(end 312.484262 -307.299868)
		(width 0.1143)
		(layer "In15.Cu")
		(net "P5E_PEX2_STN4_RX_DN<67>")
	)
	(segment
		(start 327.99274 -318.842898)
		(end 327.30186 -317.17488)
		(width 0.1651)
		(layer "In15.Cu")
		(net "P5E_PEX2_STN4_RX_DN<67>")
	)
	(segment
		(start 327.99274 -322.401692)
		(end 327.99274 -318.842898)
		(width 0.1651)
		(layer "In15.Cu")
		(net "P5E_PEX2_STN4_RX_DN<67>")
	)
	(segment
		(start 296.9641 -379.08103)
		(end 297.415966 -378.629164)
		(width 0.1651)
		(layer "In15.Cu")
		(net "P5E_PEX2_STN4_RX_DN<67>")
	)
	(segment
		(start 311.89676 -341.270844)
		(end 327.203562 -324.307454)
		(width 0.1651)
		(layer "In15.Cu")
		(net "P5E_PEX2_STN4_RX_DN<67>")
	)
	(segment
		(start 317.760858 -307.633878)
		(end 315.852048 -307.633878)
		(width 0.1651)
		(layer "In15.Cu")
		(net "P5E_PEX2_STN4_RX_DN<67>")
	)
	(segment
		(start 312.473594 -307.679598)
		(end 312.369962 -307.575966)
		(width 0.1143)
		(layer "In15.Cu")
		(net "P5E_PEX2_STN4_RX_DN<67>")
	)
	(segment
		(start 297.415966 -369.1636)
		(end 297.614594 -368.710972)
		(width 0.1651)
		(layer "In15.Cu")
		(net "P5E_PEX2_STN4_RX_DN<67>")
	)
	(segment
		(start 296.416984 -379.08103)
		(end 296.9641 -379.08103)
		(width 0.1651)
		(layer "In15.Cu")
		(net "P5E_PEX2_STN4_RX_DN<67>")
	)
	(segment
		(start 327.203562 -324.307454)
		(end 327.99274 -322.401692)
		(width 0.1651)
		(layer "In15.Cu")
		(net "P5E_PEX2_STN4_RX_DN<67>")
	)
	(segment
		(start 297.415966 -378.629164)
		(end 297.415966 -369.1636)
		(width 0.1651)
		(layer "In15.Cu")
		(net "P5E_PEX2_STN4_RX_DN<67>")
	)
	(segment
		(start 80.17002 -309.414926)
		(end 80.17002 -309.288688)
		(width 0.1143)
		(layer "In15.Cu")
		(net "P5E_PEX0_STN4_RX_DN<69>")
	)
	(segment
		(start 40.113458 -357.918512)
		(end 40.113458 -342.148414)
		(width 0.1651)
		(layer "In15.Cu")
		(net "P5E_PEX0_STN4_RX_DN<69>")
	)
	(segment
		(start 32.31007 -379.20803)
		(end 32.43707 -379.08103)
		(width 0.1651)
		(layer "In15.Cu")
		(net "P5E_PEX0_STN4_RX_DN<69>")
	)
	(segment
		(start 32.31007 -379.590046)
		(end 32.31007 -379.20803)
		(width 0.1651)
		(layer "In15.Cu")
		(net "P5E_PEX0_STN4_RX_DN<69>")
	)
	(segment
		(start 85.37194 -317.421006)
		(end 85.37194 -310.568594)
		(width 0.1651)
		(layer "In15.Cu")
		(net "P5E_PEX0_STN4_RX_DN<69>")
	)
	(segment
		(start 32.775398 -379.08103)
		(end 33.467802 -378.388626)
		(width 0.1651)
		(layer "In15.Cu")
		(net "P5E_PEX0_STN4_RX_DN<69>")
	)
	(segment
		(start 69.881242 -332.91907)
		(end 79.181452 -329.067414)
		(width 0.1651)
		(layer "In15.Cu")
		(net "P5E_PEX0_STN4_RX_DN<69>")
	)
	(segment
		(start 39.385494 -359.350056)
		(end 40.001952 -358.321864)
		(width 0.1651)
		(layer "In15.Cu")
		(net "P5E_PEX0_STN4_RX_DN<69>")
	)
	(segment
		(start 80.334612 -309.579518)
		(end 80.17002 -309.414926)
		(width 0.1143)
		(layer "In15.Cu")
		(net "P5E_PEX0_STN4_RX_DN<69>")
	)
	(segment
		(start 32.43707 -379.08103)
		(end 32.775398 -379.08103)
		(width 0.1651)
		(layer "In15.Cu")
		(net "P5E_PEX0_STN4_RX_DN<69>")
	)
	(segment
		(start 84.337144 -309.533798)
		(end 83.645248 -309.533798)
		(width 0.1651)
		(layer "In15.Cu")
		(net "P5E_PEX0_STN4_RX_DN<69>")
	)
	(segment
		(start 40.323516 -341.64143)
		(end 41.127172 -340.837774)
		(width 0.1651)
		(layer "In15.Cu")
		(net "P5E_PEX0_STN4_RX_DN<69>")
	)
	(segment
		(start 47.241206 -338.59089)
		(end 69.881242 -332.91907)
		(width 0.1651)
		(layer "In15.Cu")
		(net "P5E_PEX0_STN4_RX_DN<69>")
	)
	(segment
		(start 33.467802 -378.388626)
		(end 33.467802 -368.664998)
		(width 0.1651)
		(layer "In15.Cu")
		(net "P5E_PEX0_STN4_RX_DN<69>")
	)
	(segment
		(start 85.37194 -310.568594)
		(end 84.337144 -309.533798)
		(width 0.1651)
		(layer "In15.Cu")
		(net "P5E_PEX0_STN4_RX_DN<69>")
	)
	(segment
		(start 83.645248 -309.533798)
		(end 83.6168 -309.533798)
		(width 0.1143)
		(layer "In15.Cu")
		(net "P5E_PEX0_STN4_RX_DN<69>")
	)
	(segment
		(start 44.666408 -339.37194)
		(end 47.241206 -338.59089)
		(width 0.1651)
		(layer "In15.Cu")
		(net "P5E_PEX0_STN4_RX_DN<69>")
	)
	(segment
		(start 40.001952 -358.321864)
		(end 40.113458 -357.918512)
		(width 0.1651)
		(layer "In15.Cu")
		(net "P5E_PEX0_STN4_RX_DN<69>")
	)
	(segment
		(start 40.113458 -342.148414)
		(end 40.323516 -341.64143)
		(width 0.1651)
		(layer "In15.Cu")
		(net "P5E_PEX0_STN4_RX_DN<69>")
	)
	(segment
		(start 80.17002 -309.288688)
		(end 80.25892 -309.199788)
		(width 0.1143)
		(layer "In15.Cu")
		(net "P5E_PEX0_STN4_RX_DN<69>")
	)
	(segment
		(start 80.25892 -309.199788)
		(end 80.54975 -309.199788)
		(width 0.1143)
		(layer "In15.Cu")
		(net "P5E_PEX0_STN4_RX_DN<69>")
	)
	(segment
		(start 82.34426 -325.904606)
		(end 84.922614 -319.679828)
		(width 0.1651)
		(layer "In15.Cu")
		(net "P5E_PEX0_STN4_RX_DN<69>")
	)
	(segment
		(start 41.127172 -340.837774)
		(end 44.666408 -339.37194)
		(width 0.1651)
		(layer "In15.Cu")
		(net "P5E_PEX0_STN4_RX_DN<69>")
	)
	(segment
		(start 33.467802 -368.664998)
		(end 36.716716 -363.802422)
		(width 0.1651)
		(layer "In15.Cu")
		(net "P5E_PEX0_STN4_RX_DN<69>")
	)
	(segment
		(start 79.181452 -329.067414)
		(end 82.34426 -325.904606)
		(width 0.1651)
		(layer "In15.Cu")
		(net "P5E_PEX0_STN4_RX_DN<69>")
	)
	(segment
		(start 84.922614 -319.679828)
		(end 85.37194 -317.421006)
		(width 0.1651)
		(layer "In15.Cu")
		(net "P5E_PEX0_STN4_RX_DN<69>")
	)
	(segment
		(start 39.385748 -359.350056)
		(end 39.385494 -359.350056)
		(width 0.1651)
		(layer "In15.Cu")
		(net "P5E_PEX0_STN4_RX_DN<69>")
	)
	(segment
		(start 83.6168 -309.533798)
		(end 83.57108 -309.579518)
		(width 0.1143)
		(layer "In15.Cu")
		(net "P5E_PEX0_STN4_RX_DN<69>")
	)
	(segment
		(start 36.716716 -363.802422)
		(end 39.385748 -359.350056)
		(width 0.1651)
		(layer "In15.Cu")
		(net "P5E_PEX0_STN4_RX_DN<69>")
	)
	(segment
		(start 83.57108 -309.579518)
		(end 80.334612 -309.579518)
		(width 0.1143)
		(layer "In15.Cu")
		(net "P5E_PEX0_STN4_RX_DN<69>")
	)
	(segment
		(start 278.112982 -350.365314)
		(end 277.792942 -350.685354)
		(width 0.13462)
		(layer "F.Cu")
		(net "P5E_PEX2_STN4_TX_C_DN<75>")
	)
	(segment
		(start 277.792942 -351.316798)
		(end 278.087582 -351.611438)
		(width 0.13462)
		(layer "F.Cu")
		(net "P5E_PEX2_STN4_TX_C_DN<75>")
	)
	(segment
		(start 277.792942 -350.685354)
		(end 277.792942 -351.316798)
		(width 0.13462)
		(layer "F.Cu")
		(net "P5E_PEX2_STN4_TX_C_DN<75>")
	)
	(segment
		(start 276.242272 -354.027486)
		(end 277.796752 -352.473006)
		(width 0.1651)
		(layer "In11.Cu")
		(net "P5E_PEX2_STN4_TX_C_DN<75>")
	)
	(segment
		(start 276.242272 -358.74198)
		(end 276.242272 -354.027486)
		(width 0.1651)
		(layer "In11.Cu")
		(net "P5E_PEX2_STN4_TX_C_DN<75>")
	)
	(segment
		(start 283.440632 -385.364482)
		(end 282.53944 -378.065792)
		(width 0.1651)
		(layer "In11.Cu")
		(net "P5E_PEX2_STN4_TX_C_DN<75>")
	)
	(segment
		(start 277.796752 -351.902268)
		(end 278.087582 -351.611438)
		(width 0.1651)
		(layer "In11.Cu")
		(net "P5E_PEX2_STN4_TX_C_DN<75>")
	)
	(segment
		(start 292.34384 -391.23366)
		(end 285.89859 -388.62508)
		(width 0.1651)
		(layer "In11.Cu")
		(net "P5E_PEX2_STN4_TX_C_DN<75>")
	)
	(segment
		(start 297.415966 -396.82928)
		(end 297.415966 -395.04366)
		(width 0.1651)
		(layer "In11.Cu")
		(net "P5E_PEX2_STN4_TX_C_DN<75>")
	)
	(segment
		(start 296.289984 -397.408146)
		(end 296.416984 -397.281146)
		(width 0.1651)
		(layer "In11.Cu")
		(net "P5E_PEX2_STN4_TX_C_DN<75>")
	)
	(segment
		(start 282.53944 -378.065792)
		(end 276.242272 -358.74198)
		(width 0.1651)
		(layer "In11.Cu")
		(net "P5E_PEX2_STN4_TX_C_DN<75>")
	)
	(segment
		(start 284.22346 -387.0071)
		(end 283.440632 -385.364482)
		(width 0.1651)
		(layer "In11.Cu")
		(net "P5E_PEX2_STN4_TX_C_DN<75>")
	)
	(segment
		(start 285.89859 -388.62508)
		(end 284.22346 -387.0071)
		(width 0.1651)
		(layer "In11.Cu")
		(net "P5E_PEX2_STN4_TX_C_DN<75>")
	)
	(segment
		(start 296.416984 -397.281146)
		(end 296.9641 -397.281146)
		(width 0.1651)
		(layer "In11.Cu")
		(net "P5E_PEX2_STN4_TX_C_DN<75>")
	)
	(segment
		(start 297.415966 -395.04366)
		(end 296.9387 -394.26896)
		(width 0.1651)
		(layer "In11.Cu")
		(net "P5E_PEX2_STN4_TX_C_DN<75>")
	)
	(segment
		(start 277.796752 -352.473006)
		(end 277.796752 -351.902268)
		(width 0.1651)
		(layer "In11.Cu")
		(net "P5E_PEX2_STN4_TX_C_DN<75>")
	)
	(segment
		(start 296.9641 -397.281146)
		(end 297.415966 -396.82928)
		(width 0.1651)
		(layer "In11.Cu")
		(net "P5E_PEX2_STN4_TX_C_DN<75>")
	)
	(segment
		(start 296.9387 -394.26896)
		(end 292.34384 -391.23366)
		(width 0.1651)
		(layer "In11.Cu")
		(net "P5E_PEX2_STN4_TX_C_DN<75>")
	)
	(segment
		(start 296.289984 -397.790162)
		(end 296.289984 -397.408146)
		(width 0.1651)
		(layer "In11.Cu")
		(net "P5E_PEX2_STN4_TX_C_DN<75>")
	)
	(segment
		(start 21.64334 -388.326884)
		(end 20.48002 -385.518406)
		(width 0.1651)
		(layer "In15.Cu")
		(net "P5E_PEX0_STN4_RX_DP<78>")
	)
	(segment
		(start 30.984952 -405.384762)
		(end 30.984952 -396.033498)
		(width 0.1651)
		(layer "In15.Cu")
		(net "P5E_PEX0_STN4_RX_DP<78>")
	)
	(segment
		(start 16.09598 -341.936578)
		(end 16.78305 -340.277958)
		(width 0.1651)
		(layer "In15.Cu")
		(net "P5E_PEX0_STN4_RX_DP<78>")
	)
	(segment
		(start 73.670668 -321.662552)
		(end 74.23404 -321.09918)
		(width 0.1651)
		(layer "In15.Cu")
		(net "P5E_PEX0_STN4_RX_DP<78>")
	)
	(segment
		(start 68.300854 -323.88683)
		(end 73.670668 -321.662552)
		(width 0.1651)
		(layer "In15.Cu")
		(net "P5E_PEX0_STN4_RX_DP<78>")
	)
	(segment
		(start 29.511244 -394.099796)
		(end 28.444444 -393.032996)
		(width 0.1651)
		(layer "In15.Cu")
		(net "P5E_PEX0_STN4_RX_DP<78>")
	)
	(segment
		(start 30.763718 -395.499336)
		(end 30.4673 -395.055852)
		(width 0.1651)
		(layer "In15.Cu")
		(net "P5E_PEX0_STN4_RX_DP<78>")
	)
	(segment
		(start 30.109922 -405.772112)
		(end 30.236922 -405.899112)
		(width 0.1651)
		(layer "In15.Cu")
		(net "P5E_PEX0_STN4_RX_DP<78>")
	)
	(segment
		(start 30.4673 -395.055852)
		(end 29.978604 -394.567156)
		(width 0.1651)
		(layer "In15.Cu")
		(net "P5E_PEX0_STN4_RX_DP<78>")
	)
	(segment
		(start 23.307294 -389.990838)
		(end 21.64334 -388.326884)
		(width 0.1651)
		(layer "In15.Cu")
		(net "P5E_PEX0_STN4_RX_DP<78>")
	)
	(segment
		(start 30.984952 -396.033498)
		(end 30.763718 -395.499336)
		(width 0.1651)
		(layer "In15.Cu")
		(net "P5E_PEX0_STN4_RX_DP<78>")
	)
	(segment
		(start 17.779238 -339.28177)
		(end 18.314416 -338.960968)
		(width 0.1651)
		(layer "In15.Cu")
		(net "P5E_PEX0_STN4_RX_DP<78>")
	)
	(segment
		(start 74.23404 -321.09918)
		(end 74.23404 -319.916048)
		(width 0.1651)
		(layer "In15.Cu")
		(net "P5E_PEX0_STN4_RX_DP<78>")
	)
	(segment
		(start 74.27976 -318.355472)
		(end 74.505566 -318.129666)
		(width 0.1143)
		(layer "In15.Cu")
		(net "P5E_PEX0_STN4_RX_DP<78>")
	)
	(segment
		(start 30.470602 -405.899112)
		(end 30.984952 -405.384762)
		(width 0.1651)
		(layer "In15.Cu")
		(net "P5E_PEX0_STN4_RX_DP<78>")
	)
	(segment
		(start 74.23404 -319.8876)
		(end 74.27976 -319.84188)
		(width 0.1143)
		(layer "In15.Cu")
		(net "P5E_PEX0_STN4_RX_DP<78>")
	)
	(segment
		(start 74.27976 -319.84188)
		(end 74.27976 -318.355472)
		(width 0.1143)
		(layer "In15.Cu")
		(net "P5E_PEX0_STN4_RX_DP<78>")
	)
	(segment
		(start 16.78305 -340.277958)
		(end 17.779238 -339.28177)
		(width 0.1651)
		(layer "In15.Cu")
		(net "P5E_PEX0_STN4_RX_DP<78>")
	)
	(segment
		(start 19.643852 -377.030234)
		(end 16.09598 -353.112578)
		(width 0.1651)
		(layer "In15.Cu")
		(net "P5E_PEX0_STN4_RX_DP<78>")
	)
	(segment
		(start 27.426412 -334.92694)
		(end 43.254676 -330.135992)
		(width 0.1651)
		(layer "In15.Cu")
		(net "P5E_PEX0_STN4_RX_DP<78>")
	)
	(segment
		(start 74.73569 -318.129666)
		(end 74.84999 -318.015366)
		(width 0.1143)
		(layer "In15.Cu")
		(net "P5E_PEX0_STN4_RX_DP<78>")
	)
	(segment
		(start 43.254676 -330.135992)
		(end 68.300854 -323.88683)
		(width 0.1651)
		(layer "In15.Cu")
		(net "P5E_PEX0_STN4_RX_DP<78>")
	)
	(segment
		(start 29.852874 -394.567156)
		(end 29.511244 -394.225526)
		(width 0.1651)
		(layer "In15.Cu")
		(net "P5E_PEX0_STN4_RX_DP<78>")
	)
	(segment
		(start 74.84999 -318.015366)
		(end 74.84999 -317.749936)
		(width 0.1143)
		(layer "In15.Cu")
		(net "P5E_PEX0_STN4_RX_DP<78>")
	)
	(segment
		(start 18.314416 -338.960968)
		(end 27.426412 -334.92694)
		(width 0.1651)
		(layer "In15.Cu")
		(net "P5E_PEX0_STN4_RX_DP<78>")
	)
	(segment
		(start 29.978604 -394.567156)
		(end 29.852874 -394.567156)
		(width 0.1651)
		(layer "In15.Cu")
		(net "P5E_PEX0_STN4_RX_DP<78>")
	)
	(segment
		(start 16.09598 -353.112578)
		(end 16.09598 -341.936578)
		(width 0.1651)
		(layer "In15.Cu")
		(net "P5E_PEX0_STN4_RX_DP<78>")
	)
	(segment
		(start 20.48002 -385.518406)
		(end 19.643852 -377.030234)
		(width 0.1651)
		(layer "In15.Cu")
		(net "P5E_PEX0_STN4_RX_DP<78>")
	)
	(segment
		(start 26.906728 -392.395964)
		(end 23.307294 -389.990838)
		(width 0.1651)
		(layer "In15.Cu")
		(net "P5E_PEX0_STN4_RX_DP<78>")
	)
	(segment
		(start 29.511244 -394.225526)
		(end 29.511244 -394.099796)
		(width 0.1651)
		(layer "In15.Cu")
		(net "P5E_PEX0_STN4_RX_DP<78>")
	)
	(segment
		(start 30.109922 -405.390096)
		(end 30.109922 -405.772112)
		(width 0.1651)
		(layer "In15.Cu")
		(net "P5E_PEX0_STN4_RX_DP<78>")
	)
	(segment
		(start 28.444444 -393.032996)
		(end 26.906728 -392.395964)
		(width 0.1651)
		(layer "In15.Cu")
		(net "P5E_PEX0_STN4_RX_DP<78>")
	)
	(segment
		(start 74.505566 -318.129666)
		(end 74.73569 -318.129666)
		(width 0.1143)
		(layer "In15.Cu")
		(net "P5E_PEX0_STN4_RX_DP<78>")
	)
	(segment
		(start 30.236922 -405.899112)
		(end 30.470602 -405.899112)
		(width 0.1651)
		(layer "In15.Cu")
		(net "P5E_PEX0_STN4_RX_DP<78>")
	)
	(segment
		(start 74.23404 -319.916048)
		(end 74.23404 -319.8876)
		(width 0.1143)
		(layer "In15.Cu")
		(net "P5E_PEX0_STN4_RX_DP<78>")
	)
	(segment
		(start 44.773088 -355.658166)
		(end 44.773088 -355.026722)
		(width 0.13462)
		(layer "F.Cu")
		(net "P5E_PEX0_STN4_TX_DN<67>")
	)
	(segment
		(start 44.773088 -355.026722)
		(end 45.067728 -354.732082)
		(width 0.13462)
		(layer "F.Cu")
		(net "P5E_PEX0_STN4_TX_DN<67>")
	)
	(segment
		(start 45.093128 -355.978206)
		(end 44.773088 -355.658166)
		(width 0.13462)
		(layer "F.Cu")
		(net "P5E_PEX0_STN4_TX_DN<67>")
	)
	(segment
		(start 46.628558 -341.246968)
		(end 47.394876 -340.480904)
		(width 0.1651)
		(layer "In11.Cu")
		(net "P5E_PEX0_STN4_TX_DN<67>")
	)
	(segment
		(start 79.032862 -332.159864)
		(end 93.65488 -326.92848)
		(width 0.1651)
		(layer "In11.Cu")
		(net "P5E_PEX0_STN4_TX_DN<67>")
	)
	(segment
		(start 57.775094 -336.387694)
		(end 79.032862 -332.159864)
		(width 0.1651)
		(layer "In11.Cu")
		(net "P5E_PEX0_STN4_TX_DN<67>")
	)
	(segment
		(start 91.03614 -313.87034)
		(end 85.282532 -308.116732)
		(width 0.1651)
		(layer "In11.Cu")
		(net "P5E_PEX0_STN4_TX_DN<67>")
	)
	(segment
		(start 83.6168 -307.6448)
		(end 83.57108 -307.69052)
		(width 0.1143)
		(layer "In11.Cu")
		(net "P5E_PEX0_STN4_TX_DN<67>")
	)
	(segment
		(start 84.40547 -307.753258)
		(end 83.85937 -307.6448)
		(width 0.1651)
		(layer "In11.Cu")
		(net "P5E_PEX0_STN4_TX_DN<67>")
	)
	(segment
		(start 95.6056 -316.921388)
		(end 93.628464 -314.944252)
		(width 0.1651)
		(layer "In11.Cu")
		(net "P5E_PEX0_STN4_TX_DN<67>")
	)
	(segment
		(start 93.65488 -326.92848)
		(end 95.535496 -325.04761)
		(width 0.1651)
		(layer "In11.Cu")
		(net "P5E_PEX0_STN4_TX_DN<67>")
	)
	(segment
		(start 44.776898 -353.774502)
		(end 46.331378 -352.220022)
		(width 0.1651)
		(layer "In11.Cu")
		(net "P5E_PEX0_STN4_TX_DN<67>")
	)
	(segment
		(start 96.674178 -322.298568)
		(end 96.674178 -319.501266)
		(width 0.1651)
		(layer "In11.Cu")
		(net "P5E_PEX0_STN4_TX_DN<67>")
	)
	(segment
		(start 77.32014 -307.388768)
		(end 77.40904 -307.299868)
		(width 0.1143)
		(layer "In11.Cu")
		(net "P5E_PEX0_STN4_TX_DN<67>")
	)
	(segment
		(start 49.539144 -339.334856)
		(end 57.775094 -336.387694)
		(width 0.1651)
		(layer "In11.Cu")
		(net "P5E_PEX0_STN4_TX_DN<67>")
	)
	(segment
		(start 95.535496 -325.04761)
		(end 96.674178 -322.298568)
		(width 0.1651)
		(layer "In11.Cu")
		(net "P5E_PEX0_STN4_TX_DN<67>")
	)
	(segment
		(start 83.57108 -307.69052)
		(end 77.492098 -307.69052)
		(width 0.1143)
		(layer "In11.Cu")
		(net "P5E_PEX0_STN4_TX_DN<67>")
	)
	(segment
		(start 46.331378 -341.964772)
		(end 46.628558 -341.246968)
		(width 0.1651)
		(layer "In11.Cu")
		(net "P5E_PEX0_STN4_TX_DN<67>")
	)
	(segment
		(start 83.645248 -307.6448)
		(end 83.6168 -307.6448)
		(width 0.1143)
		(layer "In11.Cu")
		(net "P5E_PEX0_STN4_TX_DN<67>")
	)
	(segment
		(start 77.40904 -307.299868)
		(end 77.69987 -307.299868)
		(width 0.1143)
		(layer "In11.Cu")
		(net "P5E_PEX0_STN4_TX_DN<67>")
	)
	(segment
		(start 47.394876 -340.480904)
		(end 49.539144 -339.334856)
		(width 0.1651)
		(layer "In11.Cu")
		(net "P5E_PEX0_STN4_TX_DN<67>")
	)
	(segment
		(start 77.492098 -307.69052)
		(end 77.32014 -307.518562)
		(width 0.1143)
		(layer "In11.Cu")
		(net "P5E_PEX0_STN4_TX_DN<67>")
	)
	(segment
		(start 45.067728 -354.732082)
		(end 44.776898 -354.441252)
		(width 0.1651)
		(layer "In11.Cu")
		(net "P5E_PEX0_STN4_TX_DN<67>")
	)
	(segment
		(start 83.85937 -307.6448)
		(end 83.645248 -307.6448)
		(width 0.1651)
		(layer "In11.Cu")
		(net "P5E_PEX0_STN4_TX_DN<67>")
	)
	(segment
		(start 93.628464 -314.944252)
		(end 91.03614 -313.87034)
		(width 0.1651)
		(layer "In11.Cu")
		(net "P5E_PEX0_STN4_TX_DN<67>")
	)
	(segment
		(start 96.674178 -319.501266)
		(end 95.6056 -316.921388)
		(width 0.1651)
		(layer "In11.Cu")
		(net "P5E_PEX0_STN4_TX_DN<67>")
	)
	(segment
		(start 85.282532 -308.116732)
		(end 84.40547 -307.753258)
		(width 0.1651)
		(layer "In11.Cu")
		(net "P5E_PEX0_STN4_TX_DN<67>")
	)
	(segment
		(start 77.32014 -307.518562)
		(end 77.32014 -307.388768)
		(width 0.1143)
		(layer "In11.Cu")
		(net "P5E_PEX0_STN4_TX_DN<67>")
	)
	(segment
		(start 46.331378 -352.220022)
		(end 46.331378 -341.964772)
		(width 0.1651)
		(layer "In11.Cu")
		(net "P5E_PEX0_STN4_TX_DN<67>")
	)
	(segment
		(start 44.776898 -354.441252)
		(end 44.776898 -353.774502)
		(width 0.1651)
		(layer "In11.Cu")
		(net "P5E_PEX0_STN4_TX_DN<67>")
	)
	(segment
		(start 296.289984 -405.589994)
		(end 296.289984 -405.207978)
		(width 0.1651)
		(layer "In15.Cu")
		(net "P5E_PEX2_STN4_RX_DN<75>")
	)
	(segment
		(start 297.415966 -404.629112)
		(end 297.415966 -395.2748)
		(width 0.1651)
		(layer "In15.Cu")
		(net "P5E_PEX2_STN4_RX_DN<75>")
	)
	(segment
		(start 296.289984 -405.207978)
		(end 296.416984 -405.080978)
		(width 0.1651)
		(layer "In15.Cu")
		(net "P5E_PEX2_STN4_RX_DN<75>")
	)
	(segment
		(start 309.565802 -319.913)
		(end 309.520082 -319.86728)
		(width 0.1143)
		(layer "In15.Cu")
		(net "P5E_PEX2_STN4_RX_DN<75>")
	)
	(segment
		(start 286.80664 -389.043926)
		(end 284.31236 -387.272784)
		(width 0.1651)
		(layer "In15.Cu")
		(net "P5E_PEX2_STN4_RX_DN<75>")
	)
	(segment
		(start 309.565802 -322.701412)
		(end 309.565802 -319.941448)
		(width 0.1651)
		(layer "In15.Cu")
		(net "P5E_PEX2_STN4_RX_DN<75>")
	)
	(segment
		(start 289.306 -340.9188)
		(end 298.21505 -333.14005)
		(width 0.1651)
		(layer "In15.Cu")
		(net "P5E_PEX2_STN4_RX_DN<75>")
	)
	(segment
		(start 297.053 -394.360146)
		(end 292.5064 -391.6172)
		(width 0.1651)
		(layer "In15.Cu")
		(net "P5E_PEX2_STN4_RX_DN<75>")
	)
	(segment
		(start 296.9641 -405.080978)
		(end 297.415966 -404.629112)
		(width 0.1651)
		(layer "In15.Cu")
		(net "P5E_PEX2_STN4_RX_DN<75>")
	)
	(segment
		(start 283.515054 -385.25323)
		(end 283.00426 -372.432834)
		(width 0.1651)
		(layer "In15.Cu")
		(net "P5E_PEX2_STN4_RX_DN<75>")
	)
	(segment
		(start 288.678112 -341.6808)
		(end 289.306 -340.9188)
		(width 0.1651)
		(layer "In15.Cu")
		(net "P5E_PEX2_STN4_RX_DN<75>")
	)
	(segment
		(start 309.623714 -316.419992)
		(end 309.785512 -316.419992)
		(width 0.1143)
		(layer "In15.Cu")
		(net "P5E_PEX2_STN4_RX_DN<75>")
	)
	(segment
		(start 307.1241 -325.3613)
		(end 309.411624 -323.073776)
		(width 0.1651)
		(layer "In15.Cu")
		(net "P5E_PEX2_STN4_RX_DN<75>")
	)
	(segment
		(start 297.415966 -395.2748)
		(end 297.053 -394.3604)
		(width 0.1651)
		(layer "In15.Cu")
		(net "P5E_PEX2_STN4_RX_DN<75>")
	)
	(segment
		(start 283.00426 -372.432834)
		(end 283.6164 -368.3762)
		(width 0.1651)
		(layer "In15.Cu")
		(net "P5E_PEX2_STN4_RX_DN<75>")
	)
	(segment
		(start 298.215304 -333.139796)
		(end 307.1241 -325.3613)
		(width 0.1651)
		(layer "In15.Cu")
		(net "P5E_PEX2_STN4_RX_DN<75>")
	)
	(segment
		(start 298.21505 -333.14005)
		(end 298.215304 -333.139796)
		(width 0.1651)
		(layer "In15.Cu")
		(net "P5E_PEX2_STN4_RX_DN<75>")
	)
	(segment
		(start 309.520082 -316.523624)
		(end 309.623714 -316.419992)
		(width 0.1143)
		(layer "In15.Cu")
		(net "P5E_PEX2_STN4_RX_DN<75>")
	)
	(segment
		(start 309.520082 -319.86728)
		(end 309.520082 -316.523624)
		(width 0.1143)
		(layer "In15.Cu")
		(net "P5E_PEX2_STN4_RX_DN<75>")
	)
	(segment
		(start 297.053 -394.3604)
		(end 297.053 -394.360146)
		(width 0.1651)
		(layer "In15.Cu")
		(net "P5E_PEX2_STN4_RX_DN<75>")
	)
	(segment
		(start 283.6164 -368.3762)
		(end 288.627566 -358.125014)
		(width 0.1651)
		(layer "In15.Cu")
		(net "P5E_PEX2_STN4_RX_DN<75>")
	)
	(segment
		(start 292.5064 -391.6172)
		(end 286.80664 -389.043926)
		(width 0.1651)
		(layer "In15.Cu")
		(net "P5E_PEX2_STN4_RX_DN<75>")
	)
	(segment
		(start 309.565802 -319.941448)
		(end 309.565802 -319.913)
		(width 0.1143)
		(layer "In15.Cu")
		(net "P5E_PEX2_STN4_RX_DN<75>")
	)
	(segment
		(start 288.678112 -357.906066)
		(end 288.678112 -341.6808)
		(width 0.1651)
		(layer "In15.Cu")
		(net "P5E_PEX2_STN4_RX_DN<75>")
	)
	(segment
		(start 284.31236 -387.272784)
		(end 283.515054 -385.25323)
		(width 0.1651)
		(layer "In15.Cu")
		(net "P5E_PEX2_STN4_RX_DN<75>")
	)
	(segment
		(start 309.411624 -323.073776)
		(end 309.565802 -322.701412)
		(width 0.1651)
		(layer "In15.Cu")
		(net "P5E_PEX2_STN4_RX_DN<75>")
	)
	(segment
		(start 288.627566 -358.125014)
		(end 288.678112 -357.906066)
		(width 0.1651)
		(layer "In15.Cu")
		(net "P5E_PEX2_STN4_RX_DN<75>")
	)
	(segment
		(start 296.416984 -405.080978)
		(end 296.9641 -405.080978)
		(width 0.1651)
		(layer "In15.Cu")
		(net "P5E_PEX2_STN4_RX_DN<75>")
	)
	(segment
		(start 309.899812 -316.534292)
		(end 309.899812 -316.799722)
		(width 0.1143)
		(layer "In15.Cu")
		(net "P5E_PEX2_STN4_RX_DN<75>")
	)
	(segment
		(start 309.785512 -316.419992)
		(end 309.899812 -316.534292)
		(width 0.1143)
		(layer "In15.Cu")
		(net "P5E_PEX2_STN4_RX_DN<75>")
	)
	(segment
		(start 39.435024 -394.269468)
		(end 35.705542 -391.77722)
		(width 0.1651)
		(layer "In15.Cu")
		(net "P5E_PEX0_STN4_RX_DN<74>")
	)
	(segment
		(start 68.62953 -328.229976)
		(end 76.38669 -325.016876)
		(width 0.1651)
		(layer "In15.Cu")
		(net "P5E_PEX0_STN4_RX_DN<74>")
	)
	(segment
		(start 40.066976 -405.501602)
		(end 40.066976 -395.7955)
		(width 0.1651)
		(layer "In15.Cu")
		(net "P5E_PEX0_STN4_RX_DN<74>")
	)
	(segment
		(start 78.53553 -318.320166)
		(end 78.64983 -318.434466)
		(width 0.1143)
		(layer "In15.Cu")
		(net "P5E_PEX0_STN4_RX_DN<74>")
	)
	(segment
		(start 78.184756 -323.21881)
		(end 78.31582 -322.902326)
		(width 0.1651)
		(layer "In15.Cu")
		(net "P5E_PEX0_STN4_RX_DN<74>")
	)
	(segment
		(start 78.31582 -319.916048)
		(end 78.31582 -319.8876)
		(width 0.1143)
		(layer "In15.Cu")
		(net "P5E_PEX0_STN4_RX_DN<74>")
	)
	(segment
		(start 35.705542 -391.77722)
		(end 32.605218 -390.120632)
		(width 0.1651)
		(layer "In15.Cu")
		(net "P5E_PEX0_STN4_RX_DN<74>")
	)
	(segment
		(start 40.066976 -395.7955)
		(end 39.435024 -394.269468)
		(width 0.1651)
		(layer "In15.Cu")
		(net "P5E_PEX0_STN4_RX_DN<74>")
	)
	(segment
		(start 25.485344 -340.934802)
		(end 33.940242 -337.43265)
		(width 0.1651)
		(layer "In15.Cu")
		(net "P5E_PEX0_STN4_RX_DN<74>")
	)
	(segment
		(start 78.31582 -319.8876)
		(end 78.2701 -319.84188)
		(width 0.1143)
		(layer "In15.Cu")
		(net "P5E_PEX0_STN4_RX_DN<74>")
	)
	(segment
		(start 28.234132 -388.309866)
		(end 26.021538 -386.831332)
		(width 0.1651)
		(layer "In15.Cu")
		(net "P5E_PEX0_STN4_RX_DN<74>")
	)
	(segment
		(start 78.2701 -319.84188)
		(end 78.2701 -318.434466)
		(width 0.1143)
		(layer "In15.Cu")
		(net "P5E_PEX0_STN4_RX_DN<74>")
	)
	(segment
		(start 26.021538 -386.831332)
		(end 25.25014 -386.059934)
		(width 0.1651)
		(layer "In15.Cu")
		(net "P5E_PEX0_STN4_RX_DN<74>")
	)
	(segment
		(start 32.605218 -390.120632)
		(end 28.234132 -388.309866)
		(width 0.1651)
		(layer "In15.Cu")
		(net "P5E_PEX0_STN4_RX_DN<74>")
	)
	(segment
		(start 33.940242 -337.43265)
		(end 43.650662 -334.487012)
		(width 0.1651)
		(layer "In15.Cu")
		(net "P5E_PEX0_STN4_RX_DN<74>")
	)
	(segment
		(start 38.910006 -406.308052)
		(end 39.037006 -406.181052)
		(width 0.1651)
		(layer "In15.Cu")
		(net "P5E_PEX0_STN4_RX_DN<74>")
	)
	(segment
		(start 24.568658 -359.978452)
		(end 24.568658 -342.133682)
		(width 0.1651)
		(layer "In15.Cu")
		(net "P5E_PEX0_STN4_RX_DN<74>")
	)
	(segment
		(start 43.650662 -334.487012)
		(end 68.62953 -328.229976)
		(width 0.1651)
		(layer "In15.Cu")
		(net "P5E_PEX0_STN4_RX_DN<74>")
	)
	(segment
		(start 78.64983 -318.434466)
		(end 78.64983 -318.699896)
		(width 0.1143)
		(layer "In15.Cu")
		(net "P5E_PEX0_STN4_RX_DN<74>")
	)
	(segment
		(start 24.63038 -384.563366)
		(end 23.99538 -371.637306)
		(width 0.1651)
		(layer "In15.Cu")
		(net "P5E_PEX0_STN4_RX_DN<74>")
	)
	(segment
		(start 38.910006 -406.690068)
		(end 38.910006 -406.308052)
		(width 0.1651)
		(layer "In15.Cu")
		(net "P5E_PEX0_STN4_RX_DN<74>")
	)
	(segment
		(start 78.3844 -318.320166)
		(end 78.53553 -318.320166)
		(width 0.1143)
		(layer "In15.Cu")
		(net "P5E_PEX0_STN4_RX_DN<74>")
	)
	(segment
		(start 39.037006 -406.181052)
		(end 39.387526 -406.181052)
		(width 0.1651)
		(layer "In15.Cu")
		(net "P5E_PEX0_STN4_RX_DN<74>")
	)
	(segment
		(start 23.99538 -371.637306)
		(end 24.568658 -359.978452)
		(width 0.1651)
		(layer "In15.Cu")
		(net "P5E_PEX0_STN4_RX_DN<74>")
	)
	(segment
		(start 76.38669 -325.016876)
		(end 78.184756 -323.21881)
		(width 0.1651)
		(layer "In15.Cu")
		(net "P5E_PEX0_STN4_RX_DN<74>")
	)
	(segment
		(start 39.387526 -406.181052)
		(end 40.066976 -405.501602)
		(width 0.1651)
		(layer "In15.Cu")
		(net "P5E_PEX0_STN4_RX_DN<74>")
	)
	(segment
		(start 24.768302 -341.651844)
		(end 25.485344 -340.934802)
		(width 0.1651)
		(layer "In15.Cu")
		(net "P5E_PEX0_STN4_RX_DN<74>")
	)
	(segment
		(start 25.25014 -386.059934)
		(end 24.63038 -384.563366)
		(width 0.1651)
		(layer "In15.Cu")
		(net "P5E_PEX0_STN4_RX_DN<74>")
	)
	(segment
		(start 78.2701 -318.434466)
		(end 78.3844 -318.320166)
		(width 0.1143)
		(layer "In15.Cu")
		(net "P5E_PEX0_STN4_RX_DN<74>")
	)
	(segment
		(start 78.31582 -322.902326)
		(end 78.31582 -319.916048)
		(width 0.1651)
		(layer "In15.Cu")
		(net "P5E_PEX0_STN4_RX_DN<74>")
	)
	(segment
		(start 24.568658 -342.133682)
		(end 24.768302 -341.651844)
		(width 0.1651)
		(layer "In15.Cu")
		(net "P5E_PEX0_STN4_RX_DN<74>")
	)
	(segment
		(start 51.311048 -343.685622)
		(end 50.991008 -343.365582)
		(width 0.13462)
		(layer "F.Cu")
		(net "P5E_PEX0_STN4_TX_DN<65>")
	)
	(segment
		(start 50.991008 -343.365582)
		(end 50.991008 -342.734138)
		(width 0.13462)
		(layer "F.Cu")
		(net "P5E_PEX0_STN4_TX_DN<65>")
	)
	(segment
		(start 50.991008 -342.734138)
		(end 51.285648 -342.439498)
		(width 0.13462)
		(layer "F.Cu")
		(net "P5E_PEX0_STN4_TX_DN<65>")
	)
	(segment
		(start 94.71025 -313.324494)
		(end 93.910658 -312.993278)
		(width 0.1651)
		(layer "In11.Cu")
		(net "P5E_PEX0_STN4_TX_DN<65>")
	)
	(segment
		(start 51.285648 -342.439498)
		(end 50.994818 -342.148668)
		(width 0.1651)
		(layer "In11.Cu")
		(net "P5E_PEX0_STN4_TX_DN<65>")
	)
	(segment
		(start 58.087006 -338.339938)
		(end 79.141574 -334.151986)
		(width 0.1651)
		(layer "In11.Cu")
		(net "P5E_PEX0_STN4_TX_DN<65>")
	)
	(segment
		(start 51.504596 -340.696804)
		(end 58.087006 -338.339938)
		(width 0.1651)
		(layer "In11.Cu")
		(net "P5E_PEX0_STN4_TX_DN<65>")
	)
	(segment
		(start 77.40904 -305.399948)
		(end 77.69987 -305.399948)
		(width 0.1143)
		(layer "In11.Cu")
		(net "P5E_PEX0_STN4_TX_DN<65>")
	)
	(segment
		(start 98.584258 -319.119504)
		(end 97.22612 -315.840364)
		(width 0.1651)
		(layer "In11.Cu")
		(net "P5E_PEX0_STN4_TX_DN<65>")
	)
	(segment
		(start 79.141574 -334.151986)
		(end 94.857316 -328.527918)
		(width 0.1651)
		(layer "In11.Cu")
		(net "P5E_PEX0_STN4_TX_DN<65>")
	)
	(segment
		(start 50.994818 -341.206582)
		(end 51.504596 -340.696804)
		(width 0.1651)
		(layer "In11.Cu")
		(net "P5E_PEX0_STN4_TX_DN<65>")
	)
	(segment
		(start 50.994818 -342.148668)
		(end 50.994818 -341.206582)
		(width 0.1651)
		(layer "In11.Cu")
		(net "P5E_PEX0_STN4_TX_DN<65>")
	)
	(segment
		(start 94.857316 -328.527918)
		(end 97.084642 -326.300592)
		(width 0.1651)
		(layer "In11.Cu")
		(net "P5E_PEX0_STN4_TX_DN<65>")
	)
	(segment
		(start 97.084642 -326.300592)
		(end 98.584258 -322.680076)
		(width 0.1651)
		(layer "In11.Cu")
		(net "P5E_PEX0_STN4_TX_DN<65>")
	)
	(segment
		(start 77.32014 -305.618642)
		(end 77.32014 -305.488848)
		(width 0.1143)
		(layer "In11.Cu")
		(net "P5E_PEX0_STN4_TX_DN<65>")
	)
	(segment
		(start 83.5914 -305.7398)
		(end 83.54568 -305.78552)
		(width 0.1143)
		(layer "In11.Cu")
		(net "P5E_PEX0_STN4_TX_DN<65>")
	)
	(segment
		(start 83.619848 -305.7398)
		(end 83.5914 -305.7398)
		(width 0.1143)
		(layer "In11.Cu")
		(net "P5E_PEX0_STN4_TX_DN<65>")
	)
	(segment
		(start 77.487018 -305.78552)
		(end 77.32014 -305.618642)
		(width 0.1143)
		(layer "In11.Cu")
		(net "P5E_PEX0_STN4_TX_DN<65>")
	)
	(segment
		(start 98.584258 -322.680076)
		(end 98.584258 -319.119504)
		(width 0.1651)
		(layer "In11.Cu")
		(net "P5E_PEX0_STN4_TX_DN<65>")
	)
	(segment
		(start 88.04529 -307.12791)
		(end 84.694014 -305.7398)
		(width 0.1651)
		(layer "In11.Cu")
		(net "P5E_PEX0_STN4_TX_DN<65>")
	)
	(segment
		(start 97.22612 -315.840364)
		(end 94.71025 -313.324494)
		(width 0.1651)
		(layer "In11.Cu")
		(net "P5E_PEX0_STN4_TX_DN<65>")
	)
	(segment
		(start 93.910658 -312.993278)
		(end 88.04529 -307.12791)
		(width 0.1651)
		(layer "In11.Cu")
		(net "P5E_PEX0_STN4_TX_DN<65>")
	)
	(segment
		(start 84.694014 -305.7398)
		(end 83.619848 -305.7398)
		(width 0.1651)
		(layer "In11.Cu")
		(net "P5E_PEX0_STN4_TX_DN<65>")
	)
	(segment
		(start 83.54568 -305.78552)
		(end 77.487018 -305.78552)
		(width 0.1143)
		(layer "In11.Cu")
		(net "P5E_PEX0_STN4_TX_DN<65>")
	)
	(segment
		(start 77.32014 -305.488848)
		(end 77.40904 -305.399948)
		(width 0.1143)
		(layer "In11.Cu")
		(net "P5E_PEX0_STN4_TX_DN<65>")
	)
	(segment
		(start 268.466062 -344.539062)
		(end 268.466062 -345.170506)
		(width 0.13462)
		(layer "F.Cu")
		(net "P5E_PEX2_STN4_TX_C_DN<79>")
	)
	(segment
		(start 268.466062 -345.170506)
		(end 268.760702 -345.465146)
		(width 0.13462)
		(layer "F.Cu")
		(net "P5E_PEX2_STN4_TX_C_DN<79>")
	)
	(segment
		(start 268.786102 -344.219022)
		(end 268.466062 -344.539062)
		(width 0.13462)
		(layer "F.Cu")
		(net "P5E_PEX2_STN4_TX_C_DN<79>")
	)
	(segment
		(start 279.496012 -386.461508)
		(end 278.604472 -379.339094)
		(width 0.1651)
		(layer "In11.Cu")
		(net "P5E_PEX2_STN4_TX_C_DN<79>")
	)
	(segment
		(start 266.915392 -347.881194)
		(end 268.469872 -346.326714)
		(width 0.1651)
		(layer "In11.Cu")
		(net "P5E_PEX2_STN4_TX_C_DN<79>")
	)
	(segment
		(start 268.469872 -345.755976)
		(end 268.760702 -345.465146)
		(width 0.1651)
		(layer "In11.Cu")
		(net "P5E_PEX2_STN4_TX_C_DN<79>")
	)
	(segment
		(start 268.98854 -358.9401)
		(end 266.915392 -352.26752)
		(width 0.1651)
		(layer "In11.Cu")
		(net "P5E_PEX2_STN4_TX_C_DN<79>")
	)
	(segment
		(start 288.19729 -394.210032)
		(end 284.569408 -392.818874)
		(width 0.1651)
		(layer "In11.Cu")
		(net "P5E_PEX2_STN4_TX_C_DN<79>")
	)
	(segment
		(start 278.604472 -379.339094)
		(end 268.98854 -358.9401)
		(width 0.1651)
		(layer "In11.Cu")
		(net "P5E_PEX2_STN4_TX_C_DN<79>")
	)
	(segment
		(start 287.4899 -397.790162)
		(end 287.4899 -397.408146)
		(width 0.1651)
		(layer "In11.Cu")
		(net "P5E_PEX2_STN4_TX_C_DN<79>")
	)
	(segment
		(start 266.915392 -352.26752)
		(end 266.915392 -347.881194)
		(width 0.1651)
		(layer "In11.Cu")
		(net "P5E_PEX2_STN4_TX_C_DN<79>")
	)
	(segment
		(start 284.569408 -392.818874)
		(end 281.180032 -389.71093)
		(width 0.1651)
		(layer "In11.Cu")
		(net "P5E_PEX2_STN4_TX_C_DN<79>")
	)
	(segment
		(start 288.164016 -397.281146)
		(end 288.615882 -396.82928)
		(width 0.1651)
		(layer "In11.Cu")
		(net "P5E_PEX2_STN4_TX_C_DN<79>")
	)
	(segment
		(start 268.469872 -346.326714)
		(end 268.469872 -345.755976)
		(width 0.1651)
		(layer "In11.Cu")
		(net "P5E_PEX2_STN4_TX_C_DN<79>")
	)
	(segment
		(start 288.615882 -396.82928)
		(end 288.615882 -394.8557)
		(width 0.1651)
		(layer "In11.Cu")
		(net "P5E_PEX2_STN4_TX_C_DN<79>")
	)
	(segment
		(start 288.615882 -394.8557)
		(end 288.19729 -394.210032)
		(width 0.1651)
		(layer "In11.Cu")
		(net "P5E_PEX2_STN4_TX_C_DN<79>")
	)
	(segment
		(start 281.180032 -389.71093)
		(end 279.496012 -386.461508)
		(width 0.1651)
		(layer "In11.Cu")
		(net "P5E_PEX2_STN4_TX_C_DN<79>")
	)
	(segment
		(start 287.6169 -397.281146)
		(end 288.164016 -397.281146)
		(width 0.1651)
		(layer "In11.Cu")
		(net "P5E_PEX2_STN4_TX_C_DN<79>")
	)
	(segment
		(start 287.4899 -397.408146)
		(end 287.6169 -397.281146)
		(width 0.1651)
		(layer "In11.Cu")
		(net "P5E_PEX2_STN4_TX_C_DN<79>")
	)
	(segment
		(start 32.337248 -357.46309)
		(end 32.337248 -356.831646)
		(width 0.13462)
		(layer "F.Cu")
		(net "P5E_PEX0_STN4_TX_C_DN<73>")
	)
	(segment
		(start 32.631888 -357.75773)
		(end 32.337248 -357.46309)
		(width 0.13462)
		(layer "F.Cu")
		(net "P5E_PEX0_STN4_TX_C_DN<73>")
	)
	(segment
		(start 32.337248 -356.831646)
		(end 32.657288 -356.511606)
		(width 0.13462)
		(layer "F.Cu")
		(net "P5E_PEX0_STN4_TX_C_DN<73>")
	)
	(segment
		(start 25.726136 -383.83464)
		(end 25.726136 -381.652526)
		(width 0.1651)
		(layer "In11.Cu")
		(net "P5E_PEX0_STN4_TX_C_DN<73>")
	)
	(segment
		(start 25.92197 -369.526312)
		(end 26.446226 -367.846864)
		(width 0.1651)
		(layer "In11.Cu")
		(net "P5E_PEX0_STN4_TX_C_DN<73>")
	)
	(segment
		(start 41.1099 -397.408146)
		(end 41.2369 -397.281146)
		(width 0.1651)
		(layer "In11.Cu")
		(net "P5E_PEX0_STN4_TX_C_DN<73>")
	)
	(segment
		(start 25.726136 -381.652526)
		(end 25.92197 -369.526312)
		(width 0.1651)
		(layer "In11.Cu")
		(net "P5E_PEX0_STN4_TX_C_DN<73>")
	)
	(segment
		(start 42.284142 -395.083284)
		(end 41.930574 -394.421868)
		(width 0.1651)
		(layer "In11.Cu")
		(net "P5E_PEX0_STN4_TX_C_DN<73>")
	)
	(segment
		(start 41.1099 -397.790162)
		(end 41.1099 -397.408146)
		(width 0.1651)
		(layer "In11.Cu")
		(net "P5E_PEX0_STN4_TX_C_DN<73>")
	)
	(segment
		(start 26.47569 -385.644136)
		(end 25.726136 -383.83464)
		(width 0.1651)
		(layer "In11.Cu")
		(net "P5E_PEX0_STN4_TX_C_DN<73>")
	)
	(segment
		(start 41.74998 -397.281146)
		(end 42.284142 -396.746984)
		(width 0.1651)
		(layer "In11.Cu")
		(net "P5E_PEX0_STN4_TX_C_DN<73>")
	)
	(segment
		(start 41.930574 -394.421868)
		(end 34.510472 -389.464042)
		(width 0.1651)
		(layer "In11.Cu")
		(net "P5E_PEX0_STN4_TX_C_DN<73>")
	)
	(segment
		(start 41.2369 -397.281146)
		(end 41.74998 -397.281146)
		(width 0.1651)
		(layer "In11.Cu")
		(net "P5E_PEX0_STN4_TX_C_DN<73>")
	)
	(segment
		(start 27.315414 -386.48386)
		(end 26.47569 -385.644136)
		(width 0.1651)
		(layer "In11.Cu")
		(net "P5E_PEX0_STN4_TX_C_DN<73>")
	)
	(segment
		(start 32.341058 -359.024682)
		(end 32.341058 -358.04856)
		(width 0.1651)
		(layer "In11.Cu")
		(net "P5E_PEX0_STN4_TX_C_DN<73>")
	)
	(segment
		(start 42.284142 -396.746984)
		(end 42.284142 -395.083284)
		(width 0.1651)
		(layer "In11.Cu")
		(net "P5E_PEX0_STN4_TX_C_DN<73>")
	)
	(segment
		(start 26.446226 -367.846864)
		(end 32.341058 -359.024682)
		(width 0.1651)
		(layer "In11.Cu")
		(net "P5E_PEX0_STN4_TX_C_DN<73>")
	)
	(segment
		(start 32.341058 -358.04856)
		(end 32.631888 -357.75773)
		(width 0.1651)
		(layer "In11.Cu")
		(net "P5E_PEX0_STN4_TX_C_DN<73>")
	)
	(segment
		(start 34.510472 -389.464042)
		(end 27.315414 -386.48386)
		(width 0.1651)
		(layer "In11.Cu")
		(net "P5E_PEX0_STN4_TX_C_DN<73>")
	)
	(segment
		(start 307.6448 -316.229492)
		(end 307.885592 -316.229492)
		(width 0.1143)
		(layer "In15.Cu")
		(net "P5E_PEX2_STN4_RX_DP<77>")
	)
	(segment
		(start 282.631388 -341.023956)
		(end 283.040074 -340.535006)
		(width 0.1651)
		(layer "In15.Cu")
		(net "P5E_PEX2_STN4_RX_DP<77>")
	)
	(segment
		(start 290.748974 -393.71651)
		(end 290.324032 -393.462256)
		(width 0.1651)
		(layer "In15.Cu")
		(net "P5E_PEX2_STN4_RX_DP<77>")
	)
	(segment
		(start 290.324032 -393.462256)
		(end 290.202112 -393.492736)
		(width 0.1651)
		(layer "In15.Cu")
		(net "P5E_PEX2_STN4_RX_DP<77>")
	)
	(segment
		(start 288.774124 -392.638026)
		(end 288.74339 -392.516106)
		(width 0.1651)
		(layer "In15.Cu")
		(net "P5E_PEX2_STN4_RX_DP<77>")
	)
	(segment
		(start 307.429662 -316.44463)
		(end 307.6448 -316.229492)
		(width 0.1143)
		(layer "In15.Cu")
		(net "P5E_PEX2_STN4_RX_DP<77>")
	)
	(segment
		(start 282.428188 -388.641336)
		(end 281.245056 -385.741418)
		(width 0.1651)
		(layer "In15.Cu")
		(net "P5E_PEX2_STN4_RX_DP<77>")
	)
	(segment
		(start 307.429662 -319.86728)
		(end 307.429662 -316.44463)
		(width 0.1143)
		(layer "In15.Cu")
		(net "P5E_PEX2_STN4_RX_DP<77>")
	)
	(segment
		(start 291.889942 -404.672038)
		(end 292.016942 -404.799038)
		(width 0.1651)
		(layer "In15.Cu")
		(net "P5E_PEX2_STN4_RX_DP<77>")
	)
	(segment
		(start 292.016942 -404.799038)
		(end 292.447218 -404.799038)
		(width 0.1651)
		(layer "In15.Cu")
		(net "P5E_PEX2_STN4_RX_DP<77>")
	)
	(segment
		(start 307.383942 -319.941448)
		(end 307.383942 -319.913)
		(width 0.1143)
		(layer "In15.Cu")
		(net "P5E_PEX2_STN4_RX_DP<77>")
	)
	(segment
		(start 292.733984 -395.167612)
		(end 292.52799 -394.781024)
		(width 0.1651)
		(layer "In15.Cu")
		(net "P5E_PEX2_STN4_RX_DP<77>")
	)
	(segment
		(start 292.733984 -404.512272)
		(end 292.733984 -395.167612)
		(width 0.1651)
		(layer "In15.Cu")
		(net "P5E_PEX2_STN4_RX_DP<77>")
	)
	(segment
		(start 292.52799 -394.781024)
		(end 291.326824 -394.062204)
		(width 0.1651)
		(layer "In15.Cu")
		(net "P5E_PEX2_STN4_RX_DP<77>")
	)
	(segment
		(start 290.779454 -393.83843)
		(end 290.748974 -393.71651)
		(width 0.1651)
		(layer "In15.Cu")
		(net "P5E_PEX2_STN4_RX_DP<77>")
	)
	(segment
		(start 291.889942 -404.290022)
		(end 291.889942 -404.672038)
		(width 0.1651)
		(layer "In15.Cu")
		(net "P5E_PEX2_STN4_RX_DP<77>")
	)
	(segment
		(start 307.885592 -316.229492)
		(end 307.999892 -316.115192)
		(width 0.1143)
		(layer "In15.Cu")
		(net "P5E_PEX2_STN4_RX_DP<77>")
	)
	(segment
		(start 282.178252 -358.400096)
		(end 282.178252 -341.477092)
		(width 0.1651)
		(layer "In15.Cu")
		(net "P5E_PEX2_STN4_RX_DP<77>")
	)
	(segment
		(start 280.689558 -372.273322)
		(end 282.178252 -358.400096)
		(width 0.1651)
		(layer "In15.Cu")
		(net "P5E_PEX2_STN4_RX_DP<77>")
	)
	(segment
		(start 307.383942 -319.913)
		(end 307.429662 -319.86728)
		(width 0.1143)
		(layer "In15.Cu")
		(net "P5E_PEX2_STN4_RX_DP<77>")
	)
	(segment
		(start 307.383942 -321.934078)
		(end 307.383942 -319.941448)
		(width 0.1651)
		(layer "In15.Cu")
		(net "P5E_PEX2_STN4_RX_DP<77>")
	)
	(segment
		(start 291.326824 -394.062204)
		(end 291.204904 -394.092938)
		(width 0.1651)
		(layer "In15.Cu")
		(net "P5E_PEX2_STN4_RX_DP<77>")
	)
	(segment
		(start 285.622492 -391.006838)
		(end 282.428188 -388.641336)
		(width 0.1651)
		(layer "In15.Cu")
		(net "P5E_PEX2_STN4_RX_DP<77>")
	)
	(segment
		(start 288.74339 -392.516106)
		(end 287.70453 -391.894568)
		(width 0.1651)
		(layer "In15.Cu")
		(net "P5E_PEX2_STN4_RX_DP<77>")
	)
	(segment
		(start 289.746182 -393.116308)
		(end 289.32124 -392.862054)
		(width 0.1651)
		(layer "In15.Cu")
		(net "P5E_PEX2_STN4_RX_DP<77>")
	)
	(segment
		(start 281.245056 -385.741418)
		(end 280.689558 -372.273322)
		(width 0.1651)
		(layer "In15.Cu")
		(net "P5E_PEX2_STN4_RX_DP<77>")
	)
	(segment
		(start 290.202112 -393.492736)
		(end 289.776662 -393.238228)
		(width 0.1651)
		(layer "In15.Cu")
		(net "P5E_PEX2_STN4_RX_DP<77>")
	)
	(segment
		(start 287.70453 -391.894568)
		(end 285.622492 -391.006838)
		(width 0.1651)
		(layer "In15.Cu")
		(net "P5E_PEX2_STN4_RX_DP<77>")
	)
	(segment
		(start 292.447218 -404.799038)
		(end 292.733984 -404.512272)
		(width 0.1651)
		(layer "In15.Cu")
		(net "P5E_PEX2_STN4_RX_DP<77>")
	)
	(segment
		(start 291.204904 -394.092938)
		(end 290.779454 -393.83843)
		(width 0.1651)
		(layer "In15.Cu")
		(net "P5E_PEX2_STN4_RX_DP<77>")
	)
	(segment
		(start 289.776662 -393.238228)
		(end 289.746182 -393.116308)
		(width 0.1651)
		(layer "In15.Cu")
		(net "P5E_PEX2_STN4_RX_DP<77>")
	)
	(segment
		(start 305.96205 -323.35597)
		(end 307.383942 -321.934078)
		(width 0.1651)
		(layer "In15.Cu")
		(net "P5E_PEX2_STN4_RX_DP<77>")
	)
	(segment
		(start 283.040074 -340.535006)
		(end 305.96205 -323.35597)
		(width 0.1651)
		(layer "In15.Cu")
		(net "P5E_PEX2_STN4_RX_DP<77>")
	)
	(segment
		(start 282.178252 -341.477092)
		(end 282.631388 -341.023956)
		(width 0.1651)
		(layer "In15.Cu")
		(net "P5E_PEX2_STN4_RX_DP<77>")
	)
	(segment
		(start 289.19932 -392.892788)
		(end 288.774124 -392.638026)
		(width 0.1651)
		(layer "In15.Cu")
		(net "P5E_PEX2_STN4_RX_DP<77>")
	)
	(segment
		(start 289.32124 -392.862054)
		(end 289.19932 -392.892788)
		(width 0.1651)
		(layer "In15.Cu")
		(net "P5E_PEX2_STN4_RX_DP<77>")
	)
	(segment
		(start 307.999892 -316.115192)
		(end 307.999892 -315.849762)
		(width 0.1143)
		(layer "In15.Cu")
		(net "P5E_PEX2_STN4_RX_DP<77>")
	)
	(segment
		(start 32.062928 -356.831646)
		(end 31.742888 -356.511606)
		(width 0.13462)
		(layer "F.Cu")
		(net "P5E_PEX0_STN4_TX_C_DP<73>")
	)
	(segment
		(start 32.062928 -357.46309)
		(end 32.062928 -356.831646)
		(width 0.13462)
		(layer "F.Cu")
		(net "P5E_PEX0_STN4_TX_C_DP<73>")
	)
	(segment
		(start 31.768288 -357.75773)
		(end 32.062928 -357.46309)
		(width 0.13462)
		(layer "F.Cu")
		(net "P5E_PEX0_STN4_TX_C_DP<73>")
	)
	(segment
		(start 25.640538 -369.4811)
		(end 26.189178 -367.723928)
		(width 0.1651)
		(layer "In11.Cu")
		(net "P5E_PEX0_STN4_TX_C_DP<73>")
	)
	(segment
		(start 39.48938 -393.130024)
		(end 39.077646 -392.854942)
		(width 0.1651)
		(layer "In11.Cu")
		(net "P5E_PEX0_STN4_TX_C_DP<73>")
	)
	(segment
		(start 39.513764 -393.253214)
		(end 39.48938 -393.130024)
		(width 0.1651)
		(layer "In11.Cu")
		(net "P5E_PEX0_STN4_TX_C_DP<73>")
	)
	(segment
		(start 41.1099 -396.872206)
		(end 41.2369 -396.999206)
		(width 0.1651)
		(layer "In11.Cu")
		(net "P5E_PEX0_STN4_TX_C_DP<73>")
	)
	(segment
		(start 41.2369 -396.999206)
		(end 41.63314 -396.999206)
		(width 0.1651)
		(layer "In11.Cu")
		(net "P5E_PEX0_STN4_TX_C_DP<73>")
	)
	(segment
		(start 26.189178 -367.723928)
		(end 32.059118 -358.939084)
		(width 0.1651)
		(layer "In11.Cu")
		(net "P5E_PEX0_STN4_TX_C_DP<73>")
	)
	(segment
		(start 25.444196 -383.890774)
		(end 25.444196 -381.65024)
		(width 0.1651)
		(layer "In11.Cu")
		(net "P5E_PEX0_STN4_TX_C_DP<73>")
	)
	(segment
		(start 32.059118 -358.939084)
		(end 32.059118 -358.04856)
		(width 0.1651)
		(layer "In11.Cu")
		(net "P5E_PEX0_STN4_TX_C_DP<73>")
	)
	(segment
		(start 26.236676 -385.803902)
		(end 25.444196 -383.890774)
		(width 0.1651)
		(layer "In11.Cu")
		(net "P5E_PEX0_STN4_TX_C_DP<73>")
	)
	(segment
		(start 39.926006 -393.528804)
		(end 39.513764 -393.253214)
		(width 0.1651)
		(layer "In11.Cu")
		(net "P5E_PEX0_STN4_TX_C_DP<73>")
	)
	(segment
		(start 41.714928 -394.617194)
		(end 40.049196 -393.504166)
		(width 0.1651)
		(layer "In11.Cu")
		(net "P5E_PEX0_STN4_TX_C_DP<73>")
	)
	(segment
		(start 39.077646 -392.854942)
		(end 38.954456 -392.87958)
		(width 0.1651)
		(layer "In11.Cu")
		(net "P5E_PEX0_STN4_TX_C_DP<73>")
	)
	(segment
		(start 32.059118 -358.04856)
		(end 31.768288 -357.75773)
		(width 0.1651)
		(layer "In11.Cu")
		(net "P5E_PEX0_STN4_TX_C_DP<73>")
	)
	(segment
		(start 42.002202 -395.15415)
		(end 41.714928 -394.617194)
		(width 0.1651)
		(layer "In11.Cu")
		(net "P5E_PEX0_STN4_TX_C_DP<73>")
	)
	(segment
		(start 38.954456 -392.87958)
		(end 38.542214 -392.60399)
		(width 0.1651)
		(layer "In11.Cu")
		(net "P5E_PEX0_STN4_TX_C_DP<73>")
	)
	(segment
		(start 27.155648 -386.722874)
		(end 26.236676 -385.803902)
		(width 0.1651)
		(layer "In11.Cu")
		(net "P5E_PEX0_STN4_TX_C_DP<73>")
	)
	(segment
		(start 38.542214 -392.60399)
		(end 38.51783 -392.4808)
		(width 0.1651)
		(layer "In11.Cu")
		(net "P5E_PEX0_STN4_TX_C_DP<73>")
	)
	(segment
		(start 38.51783 -392.4808)
		(end 34.376868 -389.713978)
		(width 0.1651)
		(layer "In11.Cu")
		(net "P5E_PEX0_STN4_TX_C_DP<73>")
	)
	(segment
		(start 42.002202 -396.630144)
		(end 42.002202 -395.15415)
		(width 0.1651)
		(layer "In11.Cu")
		(net "P5E_PEX0_STN4_TX_C_DP<73>")
	)
	(segment
		(start 41.63314 -396.999206)
		(end 42.002202 -396.630144)
		(width 0.1651)
		(layer "In11.Cu")
		(net "P5E_PEX0_STN4_TX_C_DP<73>")
	)
	(segment
		(start 41.1099 -396.49019)
		(end 41.1099 -396.872206)
		(width 0.1651)
		(layer "In11.Cu")
		(net "P5E_PEX0_STN4_TX_C_DP<73>")
	)
	(segment
		(start 34.376868 -389.713978)
		(end 27.155648 -386.722874)
		(width 0.1651)
		(layer "In11.Cu")
		(net "P5E_PEX0_STN4_TX_C_DP<73>")
	)
	(segment
		(start 25.444196 -381.65024)
		(end 25.640538 -369.4811)
		(width 0.1651)
		(layer "In11.Cu")
		(net "P5E_PEX0_STN4_TX_C_DP<73>")
	)
	(segment
		(start 40.049196 -393.504166)
		(end 39.926006 -393.528804)
		(width 0.1651)
		(layer "In11.Cu")
		(net "P5E_PEX0_STN4_TX_C_DP<73>")
	)
	(segment
		(start 289.634422 -350.365314)
		(end 289.954462 -350.685354)
		(width 0.13462)
		(layer "F.Cu")
		(net "P5E_PEX2_STN4_TX_C_DP<69>")
	)
	(segment
		(start 289.954462 -350.685354)
		(end 289.954462 -351.316798)
		(width 0.13462)
		(layer "F.Cu")
		(net "P5E_PEX2_STN4_TX_C_DP<69>")
	)
	(segment
		(start 289.954462 -351.316798)
		(end 289.659822 -351.611438)
		(width 0.13462)
		(layer "F.Cu")
		(net "P5E_PEX2_STN4_TX_C_DP<69>")
	)
	(segment
		(start 288.396172 -358.961436)
		(end 288.396172 -353.910646)
		(width 0.1651)
		(layer "In11.Cu")
		(net "P5E_PEX2_STN4_TX_C_DP<69>")
	)
	(segment
		(start 289.950652 -352.356166)
		(end 289.950652 -351.902268)
		(width 0.1651)
		(layer "In11.Cu")
		(net "P5E_PEX2_STN4_TX_C_DP<69>")
	)
	(segment
		(start 292.447218 -370.999258)
		(end 292.733984 -370.712492)
		(width 0.1651)
		(layer "In11.Cu")
		(net "P5E_PEX2_STN4_TX_C_DP<69>")
	)
	(segment
		(start 289.577018 -361.92206)
		(end 289.635438 -361.771438)
		(width 0.1651)
		(layer "In11.Cu")
		(net "P5E_PEX2_STN4_TX_C_DP<69>")
	)
	(segment
		(start 292.038024 -367.4999)
		(end 292.096698 -367.349278)
		(width 0.1651)
		(layer "In11.Cu")
		(net "P5E_PEX2_STN4_TX_C_DP<69>")
	)
	(segment
		(start 289.950652 -351.902268)
		(end 289.659822 -351.611438)
		(width 0.1651)
		(layer "In11.Cu")
		(net "P5E_PEX2_STN4_TX_C_DP<69>")
	)
	(segment
		(start 291.546026 -366.384332)
		(end 291.604446 -366.23371)
		(width 0.1651)
		(layer "In11.Cu")
		(net "P5E_PEX2_STN4_TX_C_DP<69>")
	)
	(segment
		(start 290.76142 -364.606586)
		(end 290.561522 -364.153196)
		(width 0.1651)
		(layer "In11.Cu")
		(net "P5E_PEX2_STN4_TX_C_DP<69>")
	)
	(segment
		(start 291.404548 -365.780574)
		(end 291.253672 -365.722154)
		(width 0.1651)
		(layer "In11.Cu")
		(net "P5E_PEX2_STN4_TX_C_DP<69>")
	)
	(segment
		(start 292.733984 -368.793776)
		(end 292.388798 -368.01171)
		(width 0.1651)
		(layer "In11.Cu")
		(net "P5E_PEX2_STN4_TX_C_DP<69>")
	)
	(segment
		(start 290.269168 -363.491018)
		(end 290.06927 -363.037628)
		(width 0.1651)
		(layer "In11.Cu")
		(net "P5E_PEX2_STN4_TX_C_DP<69>")
	)
	(segment
		(start 292.016942 -370.999258)
		(end 292.447218 -370.999258)
		(width 0.1651)
		(layer "In11.Cu")
		(net "P5E_PEX2_STN4_TX_C_DP<69>")
	)
	(segment
		(start 290.12769 -362.887006)
		(end 289.928046 -362.43387)
		(width 0.1651)
		(layer "In11.Cu")
		(net "P5E_PEX2_STN4_TX_C_DP<69>")
	)
	(segment
		(start 292.389052 -368.01171)
		(end 292.238176 -367.95329)
		(width 0.1651)
		(layer "In11.Cu")
		(net "P5E_PEX2_STN4_TX_C_DP<69>")
	)
	(segment
		(start 291.253672 -365.722154)
		(end 291.053774 -365.268764)
		(width 0.1651)
		(layer "In11.Cu")
		(net "P5E_PEX2_STN4_TX_C_DP<69>")
	)
	(segment
		(start 291.889942 -370.872258)
		(end 292.016942 -370.999258)
		(width 0.1651)
		(layer "In11.Cu")
		(net "P5E_PEX2_STN4_TX_C_DP<69>")
	)
	(segment
		(start 292.733984 -370.712492)
		(end 292.733984 -368.793776)
		(width 0.1651)
		(layer "In11.Cu")
		(net "P5E_PEX2_STN4_TX_C_DP<69>")
	)
	(segment
		(start 291.889942 -370.489988)
		(end 291.889942 -370.872258)
		(width 0.1651)
		(layer "In11.Cu")
		(net "P5E_PEX2_STN4_TX_C_DP<69>")
	)
	(segment
		(start 289.776916 -362.37545)
		(end 289.577018 -361.92206)
		(width 0.1651)
		(layer "In11.Cu")
		(net "P5E_PEX2_STN4_TX_C_DP<69>")
	)
	(segment
		(start 292.096698 -367.349278)
		(end 291.8968 -366.896142)
		(width 0.1651)
		(layer "In11.Cu")
		(net "P5E_PEX2_STN4_TX_C_DP<69>")
	)
	(segment
		(start 290.561522 -364.153196)
		(end 290.619942 -364.002574)
		(width 0.1651)
		(layer "In11.Cu")
		(net "P5E_PEX2_STN4_TX_C_DP<69>")
	)
	(segment
		(start 291.053774 -365.268764)
		(end 291.112194 -365.118142)
		(width 0.1651)
		(layer "In11.Cu")
		(net "P5E_PEX2_STN4_TX_C_DP<69>")
	)
	(segment
		(start 291.745924 -366.837722)
		(end 291.546026 -366.384332)
		(width 0.1651)
		(layer "In11.Cu")
		(net "P5E_PEX2_STN4_TX_C_DP<69>")
	)
	(segment
		(start 289.635438 -361.771438)
		(end 288.396172 -358.961436)
		(width 0.1651)
		(layer "In11.Cu")
		(net "P5E_PEX2_STN4_TX_C_DP<69>")
	)
	(segment
		(start 288.396172 -353.910646)
		(end 289.950652 -352.356166)
		(width 0.1651)
		(layer "In11.Cu")
		(net "P5E_PEX2_STN4_TX_C_DP<69>")
	)
	(segment
		(start 291.112194 -365.118142)
		(end 290.912296 -364.665006)
		(width 0.1651)
		(layer "In11.Cu")
		(net "P5E_PEX2_STN4_TX_C_DP<69>")
	)
	(segment
		(start 290.619942 -364.002574)
		(end 290.420044 -363.549438)
		(width 0.1651)
		(layer "In11.Cu")
		(net "P5E_PEX2_STN4_TX_C_DP<69>")
	)
	(segment
		(start 290.420044 -363.549438)
		(end 290.269168 -363.491018)
		(width 0.1651)
		(layer "In11.Cu")
		(net "P5E_PEX2_STN4_TX_C_DP<69>")
	)
	(segment
		(start 290.912296 -364.665006)
		(end 290.76142 -364.606586)
		(width 0.1651)
		(layer "In11.Cu")
		(net "P5E_PEX2_STN4_TX_C_DP<69>")
	)
	(segment
		(start 291.8968 -366.896142)
		(end 291.745924 -366.837722)
		(width 0.1651)
		(layer "In11.Cu")
		(net "P5E_PEX2_STN4_TX_C_DP<69>")
	)
	(segment
		(start 292.388798 -368.01171)
		(end 292.389052 -368.01171)
		(width 0.1651)
		(layer "In11.Cu")
		(net "P5E_PEX2_STN4_TX_C_DP<69>")
	)
	(segment
		(start 292.238176 -367.95329)
		(end 292.038024 -367.4999)
		(width 0.1651)
		(layer "In11.Cu")
		(net "P5E_PEX2_STN4_TX_C_DP<69>")
	)
	(segment
		(start 291.604446 -366.23371)
		(end 291.404548 -365.780574)
		(width 0.1651)
		(layer "In11.Cu")
		(net "P5E_PEX2_STN4_TX_C_DP<69>")
	)
	(segment
		(start 289.928046 -362.43387)
		(end 289.776916 -362.37545)
		(width 0.1651)
		(layer "In11.Cu")
		(net "P5E_PEX2_STN4_TX_C_DP<69>")
	)
	(segment
		(start 290.06927 -363.037628)
		(end 290.12769 -362.887006)
		(width 0.1651)
		(layer "In11.Cu")
		(net "P5E_PEX2_STN4_TX_C_DP<69>")
	)
	(segment
		(start 26.035 -370.358924)
		(end 30.786578 -358.887776)
		(width 0.1651)
		(layer "In15.Cu")
		(net "P5E_PEX0_STN4_RX_DN<72>")
	)
	(segment
		(start 80.54975 -318.434466)
		(end 80.54975 -318.699896)
		(width 0.1143)
		(layer "In15.Cu")
		(net "P5E_PEX0_STN4_RX_DN<72>")
	)
	(segment
		(start 69.127878 -330.115164)
		(end 77.49032 -326.65162)
		(width 0.1651)
		(layer "In15.Cu")
		(net "P5E_PEX0_STN4_RX_DN<72>")
	)
	(segment
		(start 79.81188 -324.33006)
		(end 80.21574 -323.355208)
		(width 0.1651)
		(layer "In15.Cu")
		(net "P5E_PEX0_STN4_RX_DN<72>")
	)
	(segment
		(start 36.86937 -389.789162)
		(end 29.150056 -386.59181)
		(width 0.1651)
		(layer "In15.Cu")
		(net "P5E_PEX0_STN4_RX_DN<72>")
	)
	(segment
		(start 40.772588 -391.935208)
		(end 40.327072 -391.637266)
		(width 0.1651)
		(layer "In15.Cu")
		(net "P5E_PEX0_STN4_RX_DN<72>")
	)
	(segment
		(start 30.97403 -341.694516)
		(end 31.468314 -341.200232)
		(width 0.1651)
		(layer "In15.Cu")
		(net "P5E_PEX0_STN4_RX_DN<72>")
	)
	(segment
		(start 77.49032 -326.65162)
		(end 79.81188 -324.33006)
		(width 0.1651)
		(layer "In15.Cu")
		(net "P5E_PEX0_STN4_RX_DN<72>")
	)
	(segment
		(start 80.28432 -318.320166)
		(end 80.43545 -318.320166)
		(width 0.1143)
		(layer "In15.Cu")
		(net "P5E_PEX0_STN4_RX_DN<72>")
	)
	(segment
		(start 43.310048 -406.308052)
		(end 43.437048 -406.181052)
		(width 0.1651)
		(layer "In15.Cu")
		(net "P5E_PEX0_STN4_RX_DN<72>")
	)
	(segment
		(start 80.43545 -318.320166)
		(end 80.54975 -318.434466)
		(width 0.1143)
		(layer "In15.Cu")
		(net "P5E_PEX0_STN4_RX_DN<72>")
	)
	(segment
		(start 44.447714 -336.297778)
		(end 69.127878 -330.115164)
		(width 0.1651)
		(layer "In15.Cu")
		(net "P5E_PEX0_STN4_RX_DN<72>")
	)
	(segment
		(start 44.467018 -396.409926)
		(end 44.177712 -395.711426)
		(width 0.1651)
		(layer "In15.Cu")
		(net "P5E_PEX0_STN4_RX_DN<72>")
	)
	(segment
		(start 43.787568 -406.181052)
		(end 44.467018 -405.501602)
		(width 0.1651)
		(layer "In15.Cu")
		(net "P5E_PEX0_STN4_RX_DN<72>")
	)
	(segment
		(start 80.21574 -319.916048)
		(end 80.21574 -319.8876)
		(width 0.1143)
		(layer "In15.Cu")
		(net "P5E_PEX0_STN4_RX_DN<72>")
	)
	(segment
		(start 30.786578 -342.14689)
		(end 30.97403 -341.694516)
		(width 0.1651)
		(layer "In15.Cu")
		(net "P5E_PEX0_STN4_RX_DN<72>")
	)
	(segment
		(start 26.035 -371.868446)
		(end 26.035 -370.358924)
		(width 0.1651)
		(layer "In15.Cu")
		(net "P5E_PEX0_STN4_RX_DN<72>")
	)
	(segment
		(start 43.43019 -394.59281)
		(end 40.772588 -391.935208)
		(width 0.1651)
		(layer "In15.Cu")
		(net "P5E_PEX0_STN4_RX_DN<72>")
	)
	(segment
		(start 27.250136 -385.322318)
		(end 26.946606 -385.018788)
		(width 0.1651)
		(layer "In15.Cu")
		(net "P5E_PEX0_STN4_RX_DN<72>")
	)
	(segment
		(start 31.468314 -341.200232)
		(end 40.176704 -337.593432)
		(width 0.1651)
		(layer "In15.Cu")
		(net "P5E_PEX0_STN4_RX_DN<72>")
	)
	(segment
		(start 43.310048 -406.690068)
		(end 43.310048 -406.308052)
		(width 0.1651)
		(layer "In15.Cu")
		(net "P5E_PEX0_STN4_RX_DN<72>")
	)
	(segment
		(start 80.21574 -319.8876)
		(end 80.17002 -319.84188)
		(width 0.1143)
		(layer "In15.Cu")
		(net "P5E_PEX0_STN4_RX_DN<72>")
	)
	(segment
		(start 30.786578 -358.887776)
		(end 30.786578 -342.14689)
		(width 0.1651)
		(layer "In15.Cu")
		(net "P5E_PEX0_STN4_RX_DN<72>")
	)
	(segment
		(start 80.21574 -323.355208)
		(end 80.21574 -319.916048)
		(width 0.1651)
		(layer "In15.Cu")
		(net "P5E_PEX0_STN4_RX_DN<72>")
	)
	(segment
		(start 80.17002 -318.434466)
		(end 80.28432 -318.320166)
		(width 0.1143)
		(layer "In15.Cu")
		(net "P5E_PEX0_STN4_RX_DN<72>")
	)
	(segment
		(start 40.327072 -391.637266)
		(end 36.86937 -389.789162)
		(width 0.1651)
		(layer "In15.Cu")
		(net "P5E_PEX0_STN4_RX_DN<72>")
	)
	(segment
		(start 26.946606 -385.018788)
		(end 26.645362 -384.291078)
		(width 0.1651)
		(layer "In15.Cu")
		(net "P5E_PEX0_STN4_RX_DN<72>")
	)
	(segment
		(start 43.437048 -406.181052)
		(end 43.787568 -406.181052)
		(width 0.1651)
		(layer "In15.Cu")
		(net "P5E_PEX0_STN4_RX_DN<72>")
	)
	(segment
		(start 44.467018 -405.501602)
		(end 44.467018 -396.409926)
		(width 0.1651)
		(layer "In15.Cu")
		(net "P5E_PEX0_STN4_RX_DN<72>")
	)
	(segment
		(start 26.645362 -384.291078)
		(end 26.035 -371.868446)
		(width 0.1651)
		(layer "In15.Cu")
		(net "P5E_PEX0_STN4_RX_DN<72>")
	)
	(segment
		(start 40.176704 -337.593432)
		(end 44.447714 -336.297778)
		(width 0.1651)
		(layer "In15.Cu")
		(net "P5E_PEX0_STN4_RX_DN<72>")
	)
	(segment
		(start 80.17002 -319.84188)
		(end 80.17002 -318.434466)
		(width 0.1143)
		(layer "In15.Cu")
		(net "P5E_PEX0_STN4_RX_DN<72>")
	)
	(segment
		(start 29.150056 -386.59181)
		(end 27.250136 -385.322318)
		(width 0.1651)
		(layer "In15.Cu")
		(net "P5E_PEX0_STN4_RX_DN<72>")
	)
	(segment
		(start 44.177712 -395.711426)
		(end 43.43019 -394.59281)
		(width 0.1651)
		(layer "In15.Cu")
		(net "P5E_PEX0_STN4_RX_DN<72>")
	)
	(segment
		(start 51.311048 -355.978206)
		(end 50.991008 -355.658166)
		(width 0.13462)
		(layer "F.Cu")
		(net "P5E_PEX0_STN4_TX_DN<64>")
	)
	(segment
		(start 50.991008 -355.658166)
		(end 50.991008 -355.026722)
		(width 0.13462)
		(layer "F.Cu")
		(net "P5E_PEX0_STN4_TX_DN<64>")
	)
	(segment
		(start 50.991008 -355.026722)
		(end 51.285648 -354.732082)
		(width 0.13462)
		(layer "F.Cu")
		(net "P5E_PEX0_STN4_TX_DN<64>")
	)
	(segment
		(start 88.560656 -306.292504)
		(end 84.91855 -304.783744)
		(width 0.1651)
		(layer "In11.Cu")
		(net "P5E_PEX0_STN4_TX_DN<64>")
	)
	(segment
		(start 75.42022 -304.664364)
		(end 75.42022 -304.538634)
		(width 0.1143)
		(layer "In11.Cu")
		(net "P5E_PEX0_STN4_TX_DN<64>")
	)
	(segment
		(start 83.670648 -304.783744)
		(end 83.6422 -304.783744)
		(width 0.1143)
		(layer "In11.Cu")
		(net "P5E_PEX0_STN4_TX_DN<64>")
	)
	(segment
		(start 62.292484 -340.244684)
		(end 65.772792 -338.803234)
		(width 0.1651)
		(layer "In11.Cu")
		(net "P5E_PEX0_STN4_TX_DN<64>")
	)
	(segment
		(start 52.506372 -352.262948)
		(end 58.405268 -343.434924)
		(width 0.1651)
		(layer "In11.Cu")
		(net "P5E_PEX0_STN4_TX_DN<64>")
	)
	(segment
		(start 74.86523 -336.044794)
		(end 78.967076 -335.228946)
		(width 0.1651)
		(layer "In11.Cu")
		(net "P5E_PEX0_STN4_TX_DN<64>")
	)
	(segment
		(start 65.772792 -338.803234)
		(end 74.86523 -336.044794)
		(width 0.1651)
		(layer "In11.Cu")
		(net "P5E_PEX0_STN4_TX_DN<64>")
	)
	(segment
		(start 95.453962 -312.598562)
		(end 94.451424 -312.183272)
		(width 0.1651)
		(layer "In11.Cu")
		(net "P5E_PEX0_STN4_TX_DN<64>")
	)
	(segment
		(start 58.405268 -343.434924)
		(end 62.292484 -340.244684)
		(width 0.1651)
		(layer "In11.Cu")
		(net "P5E_PEX0_STN4_TX_DN<64>")
	)
	(segment
		(start 75.58532 -304.829464)
		(end 75.42022 -304.664364)
		(width 0.1143)
		(layer "In11.Cu")
		(net "P5E_PEX0_STN4_TX_DN<64>")
	)
	(segment
		(start 51.285648 -354.732082)
		(end 50.994818 -354.441252)
		(width 0.1651)
		(layer "In11.Cu")
		(net "P5E_PEX0_STN4_TX_DN<64>")
	)
	(segment
		(start 75.42022 -304.538634)
		(end 75.50912 -304.449734)
		(width 0.1143)
		(layer "In11.Cu")
		(net "P5E_PEX0_STN4_TX_DN<64>")
	)
	(segment
		(start 83.59648 -304.829464)
		(end 75.58532 -304.829464)
		(width 0.1143)
		(layer "In11.Cu")
		(net "P5E_PEX0_STN4_TX_DN<64>")
	)
	(segment
		(start 94.451424 -312.183272)
		(end 88.560656 -306.292504)
		(width 0.1651)
		(layer "In11.Cu")
		(net "P5E_PEX0_STN4_TX_DN<64>")
	)
	(segment
		(start 84.91855 -304.783744)
		(end 83.670648 -304.783744)
		(width 0.1651)
		(layer "In11.Cu")
		(net "P5E_PEX0_STN4_TX_DN<64>")
	)
	(segment
		(start 95.380556 -329.356212)
		(end 97.894648 -326.841358)
		(width 0.1651)
		(layer "In11.Cu")
		(net "P5E_PEX0_STN4_TX_DN<64>")
	)
	(segment
		(start 98.021394 -315.165994)
		(end 95.453962 -312.598562)
		(width 0.1651)
		(layer "In11.Cu")
		(net "P5E_PEX0_STN4_TX_DN<64>")
	)
	(segment
		(start 75.50912 -304.449734)
		(end 75.79995 -304.449734)
		(width 0.1143)
		(layer "In11.Cu")
		(net "P5E_PEX0_STN4_TX_DN<64>")
	)
	(segment
		(start 50.994818 -354.441252)
		(end 50.994818 -353.774502)
		(width 0.1651)
		(layer "In11.Cu")
		(net "P5E_PEX0_STN4_TX_DN<64>")
	)
	(segment
		(start 99.539298 -322.870576)
		(end 99.539298 -318.830706)
		(width 0.1651)
		(layer "In11.Cu")
		(net "P5E_PEX0_STN4_TX_DN<64>")
	)
	(segment
		(start 50.994818 -353.774502)
		(end 52.506372 -352.262948)
		(width 0.1651)
		(layer "In11.Cu")
		(net "P5E_PEX0_STN4_TX_DN<64>")
	)
	(segment
		(start 97.894648 -326.841358)
		(end 99.539298 -322.870576)
		(width 0.1651)
		(layer "In11.Cu")
		(net "P5E_PEX0_STN4_TX_DN<64>")
	)
	(segment
		(start 83.6422 -304.783744)
		(end 83.59648 -304.829464)
		(width 0.1143)
		(layer "In11.Cu")
		(net "P5E_PEX0_STN4_TX_DN<64>")
	)
	(segment
		(start 78.967076 -335.228946)
		(end 95.380556 -329.356212)
		(width 0.1651)
		(layer "In11.Cu")
		(net "P5E_PEX0_STN4_TX_DN<64>")
	)
	(segment
		(start 99.539298 -318.830706)
		(end 98.021394 -315.165994)
		(width 0.1651)
		(layer "In11.Cu")
		(net "P5E_PEX0_STN4_TX_DN<64>")
	)
	(segment
		(start 314.649866 -310.149748)
		(end 314.384436 -310.149748)
		(width 0.1143)
		(layer "In15.Cu")
		(net "P5E_PEX2_STN4_RX_DN<70>")
	)
	(segment
		(start 315.586364 -321.255898)
		(end 301.684436 -359.398824)
		(width 0.1651)
		(layer "In15.Cu")
		(net "P5E_PEX2_STN4_RX_DN<70>")
	)
	(segment
		(start 315.524134 -310.799734)
		(end 315.5442 -310.8198)
		(width 0.1143)
		(layer "In15.Cu")
		(net "P5E_PEX2_STN4_RX_DN<70>")
	)
	(segment
		(start 315.188854 -310.529478)
		(end 315.45911 -310.799734)
		(width 0.1143)
		(layer "In15.Cu")
		(net "P5E_PEX2_STN4_RX_DN<70>")
	)
	(segment
		(start 315.45911 -310.799734)
		(end 315.524134 -310.799734)
		(width 0.1143)
		(layer "In15.Cu")
		(net "P5E_PEX2_STN4_RX_DN<70>")
	)
	(segment
		(start 291.17925 -368.86642)
		(end 290.815776 -369.7478)
		(width 0.1651)
		(layer "In15.Cu")
		(net "P5E_PEX2_STN4_RX_DN<70>")
	)
	(segment
		(start 314.384436 -310.149748)
		(end 314.270136 -310.264048)
		(width 0.1143)
		(layer "In15.Cu")
		(net "P5E_PEX2_STN4_RX_DN<70>")
	)
	(segment
		(start 290.815776 -379.729238)
		(end 290.36391 -380.181104)
		(width 0.1651)
		(layer "In15.Cu")
		(net "P5E_PEX2_STN4_RX_DN<70>")
	)
	(segment
		(start 314.270136 -310.264048)
		(end 314.270136 -310.425846)
		(width 0.1143)
		(layer "In15.Cu")
		(net "P5E_PEX2_STN4_RX_DN<70>")
	)
	(segment
		(start 301.684436 -359.398824)
		(end 291.17925 -368.86642)
		(width 0.1651)
		(layer "In15.Cu")
		(net "P5E_PEX2_STN4_RX_DN<70>")
	)
	(segment
		(start 289.816794 -380.181104)
		(end 289.689794 -380.308104)
		(width 0.1651)
		(layer "In15.Cu")
		(net "P5E_PEX2_STN4_RX_DN<70>")
	)
	(segment
		(start 290.815776 -369.7478)
		(end 290.815776 -379.729238)
		(width 0.1651)
		(layer "In15.Cu")
		(net "P5E_PEX2_STN4_RX_DN<70>")
	)
	(segment
		(start 314.373768 -310.529478)
		(end 315.188854 -310.529478)
		(width 0.1143)
		(layer "In15.Cu")
		(net "P5E_PEX2_STN4_RX_DN<70>")
	)
	(segment
		(start 316.7126 -316.559692)
		(end 315.586364 -321.255898)
		(width 0.1651)
		(layer "In15.Cu")
		(net "P5E_PEX2_STN4_RX_DN<70>")
	)
	(segment
		(start 314.270136 -310.425846)
		(end 314.373768 -310.529478)
		(width 0.1143)
		(layer "In15.Cu")
		(net "P5E_PEX2_STN4_RX_DN<70>")
	)
	(segment
		(start 289.689794 -380.308104)
		(end 289.689794 -380.69012)
		(width 0.1651)
		(layer "In15.Cu")
		(net "P5E_PEX2_STN4_RX_DN<70>")
	)
	(segment
		(start 315.5442 -310.8198)
		(end 316.7126 -311.9882)
		(width 0.1651)
		(layer "In15.Cu")
		(net "P5E_PEX2_STN4_RX_DN<70>")
	)
	(segment
		(start 290.36391 -380.181104)
		(end 289.816794 -380.181104)
		(width 0.1651)
		(layer "In15.Cu")
		(net "P5E_PEX2_STN4_RX_DN<70>")
	)
	(segment
		(start 316.7126 -311.9882)
		(end 316.7126 -316.559692)
		(width 0.1651)
		(layer "In15.Cu")
		(net "P5E_PEX2_STN4_RX_DN<70>")
	)
	(segment
		(start 41.389808 -350.685354)
		(end 41.069768 -350.365314)
		(width 0.13462)
		(layer "F.Cu")
		(net "P5E_PEX0_STN4_TX_C_DP<69>")
	)
	(segment
		(start 41.095168 -351.611438)
		(end 41.389808 -351.316798)
		(width 0.13462)
		(layer "F.Cu")
		(net "P5E_PEX0_STN4_TX_C_DP<69>")
	)
	(segment
		(start 41.389808 -351.316798)
		(end 41.389808 -350.685354)
		(width 0.13462)
		(layer "F.Cu")
		(net "P5E_PEX0_STN4_TX_C_DP<69>")
	)
	(segment
		(start 38.82009 -360.285538)
		(end 39.095172 -359.873804)
		(width 0.1651)
		(layer "In11.Cu")
		(net "P5E_PEX0_STN4_TX_C_DP<69>")
	)
	(segment
		(start 35.408108 -365.3917)
		(end 35.376612 -365.233204)
		(width 0.1651)
		(layer "In11.Cu")
		(net "P5E_PEX0_STN4_TX_C_DP<69>")
	)
	(segment
		(start 38.661594 -360.317034)
		(end 38.82009 -360.285538)
		(width 0.1651)
		(layer "In11.Cu")
		(net "P5E_PEX0_STN4_TX_C_DP<69>")
	)
	(segment
		(start 34.021776 -367.260886)
		(end 34.297112 -366.848898)
		(width 0.1651)
		(layer "In11.Cu")
		(net "P5E_PEX0_STN4_TX_C_DP<69>")
	)
	(segment
		(start 38.417754 -360.887772)
		(end 38.386258 -360.729022)
		(width 0.1651)
		(layer "In11.Cu")
		(net "P5E_PEX0_STN4_TX_C_DP<69>")
	)
	(segment
		(start 38.386258 -360.729022)
		(end 38.661594 -360.317034)
		(width 0.1651)
		(layer "In11.Cu")
		(net "P5E_PEX0_STN4_TX_C_DP<69>")
	)
	(segment
		(start 34.699194 -366.246918)
		(end 34.97453 -365.83493)
		(width 0.1651)
		(layer "In11.Cu")
		(net "P5E_PEX0_STN4_TX_C_DP<69>")
	)
	(segment
		(start 39.497762 -359.27157)
		(end 39.831518 -358.771952)
		(width 0.1651)
		(layer "In11.Cu")
		(net "P5E_PEX0_STN4_TX_C_DP<69>")
	)
	(segment
		(start 36.085526 -364.377732)
		(end 36.05403 -364.219236)
		(width 0.1651)
		(layer "In11.Cu")
		(net "P5E_PEX0_STN4_TX_C_DP<69>")
	)
	(segment
		(start 32.43707 -370.999258)
		(end 32.772604 -370.999258)
		(width 0.1651)
		(layer "In11.Cu")
		(net "P5E_PEX0_STN4_TX_C_DP<69>")
	)
	(segment
		(start 34.053272 -367.419382)
		(end 34.021776 -367.260886)
		(width 0.1651)
		(layer "In11.Cu")
		(net "P5E_PEX0_STN4_TX_C_DP<69>")
	)
	(segment
		(start 34.73069 -366.405414)
		(end 34.699194 -366.246918)
		(width 0.1651)
		(layer "In11.Cu")
		(net "P5E_PEX0_STN4_TX_C_DP<69>")
	)
	(segment
		(start 34.455608 -366.817148)
		(end 34.73069 -366.405414)
		(width 0.1651)
		(layer "In11.Cu")
		(net "P5E_PEX0_STN4_TX_C_DP<69>")
	)
	(segment
		(start 39.063676 -359.715308)
		(end 39.339012 -359.303066)
		(width 0.1651)
		(layer "In11.Cu")
		(net "P5E_PEX0_STN4_TX_C_DP<69>")
	)
	(segment
		(start 32.772604 -370.999258)
		(end 33.290002 -370.48186)
		(width 0.1651)
		(layer "In11.Cu")
		(net "P5E_PEX0_STN4_TX_C_DP<69>")
	)
	(segment
		(start 36.762944 -363.364018)
		(end 36.731448 -363.205522)
		(width 0.1651)
		(layer "In11.Cu")
		(net "P5E_PEX0_STN4_TX_C_DP<69>")
	)
	(segment
		(start 33.290002 -370.48186)
		(end 33.290002 -369.439952)
		(width 0.1651)
		(layer "In11.Cu")
		(net "P5E_PEX0_STN4_TX_C_DP<69>")
	)
	(segment
		(start 37.16528 -362.762038)
		(end 37.740336 -361.901486)
		(width 0.1651)
		(layer "In11.Cu")
		(net "P5E_PEX0_STN4_TX_C_DP<69>")
	)
	(segment
		(start 36.731448 -363.205522)
		(end 37.006784 -362.793534)
		(width 0.1651)
		(layer "In11.Cu")
		(net "P5E_PEX0_STN4_TX_C_DP<69>")
	)
	(segment
		(start 32.31007 -370.872258)
		(end 32.43707 -370.999258)
		(width 0.1651)
		(layer "In11.Cu")
		(net "P5E_PEX0_STN4_TX_C_DP<69>")
	)
	(segment
		(start 35.133026 -365.803434)
		(end 35.408108 -365.3917)
		(width 0.1651)
		(layer "In11.Cu")
		(net "P5E_PEX0_STN4_TX_C_DP<69>")
	)
	(segment
		(start 37.006784 -362.793534)
		(end 37.16528 -362.762038)
		(width 0.1651)
		(layer "In11.Cu")
		(net "P5E_PEX0_STN4_TX_C_DP<69>")
	)
	(segment
		(start 37.708586 -361.74299)
		(end 37.984176 -361.331002)
		(width 0.1651)
		(layer "In11.Cu")
		(net "P5E_PEX0_STN4_TX_C_DP<69>")
	)
	(segment
		(start 33.290002 -369.439952)
		(end 33.77819 -367.831116)
		(width 0.1651)
		(layer "In11.Cu")
		(net "P5E_PEX0_STN4_TX_C_DP<69>")
	)
	(segment
		(start 35.651948 -364.821216)
		(end 35.810444 -364.789466)
		(width 0.1651)
		(layer "In11.Cu")
		(net "P5E_PEX0_STN4_TX_C_DP<69>")
	)
	(segment
		(start 35.810444 -364.789466)
		(end 36.085526 -364.377732)
		(width 0.1651)
		(layer "In11.Cu")
		(net "P5E_PEX0_STN4_TX_C_DP<69>")
	)
	(segment
		(start 38.142672 -361.299506)
		(end 38.417754 -360.887772)
		(width 0.1651)
		(layer "In11.Cu")
		(net "P5E_PEX0_STN4_TX_C_DP<69>")
	)
	(segment
		(start 34.297112 -366.848898)
		(end 34.455608 -366.817148)
		(width 0.1651)
		(layer "In11.Cu")
		(net "P5E_PEX0_STN4_TX_C_DP<69>")
	)
	(segment
		(start 39.339012 -359.303066)
		(end 39.497762 -359.27157)
		(width 0.1651)
		(layer "In11.Cu")
		(net "P5E_PEX0_STN4_TX_C_DP<69>")
	)
	(segment
		(start 36.05403 -364.219236)
		(end 36.329366 -363.807248)
		(width 0.1651)
		(layer "In11.Cu")
		(net "P5E_PEX0_STN4_TX_C_DP<69>")
	)
	(segment
		(start 37.740336 -361.901486)
		(end 37.708586 -361.74299)
		(width 0.1651)
		(layer "In11.Cu")
		(net "P5E_PEX0_STN4_TX_C_DP<69>")
	)
	(segment
		(start 36.329366 -363.807248)
		(end 36.487862 -363.775752)
		(width 0.1651)
		(layer "In11.Cu")
		(net "P5E_PEX0_STN4_TX_C_DP<69>")
	)
	(segment
		(start 37.984176 -361.331002)
		(end 38.142672 -361.299506)
		(width 0.1651)
		(layer "In11.Cu")
		(net "P5E_PEX0_STN4_TX_C_DP<69>")
	)
	(segment
		(start 36.487862 -363.775752)
		(end 36.762944 -363.364018)
		(width 0.1651)
		(layer "In11.Cu")
		(net "P5E_PEX0_STN4_TX_C_DP<69>")
	)
	(segment
		(start 35.376612 -365.233204)
		(end 35.651948 -364.821216)
		(width 0.1651)
		(layer "In11.Cu")
		(net "P5E_PEX0_STN4_TX_C_DP<69>")
	)
	(segment
		(start 39.831518 -358.771952)
		(end 39.831518 -353.975162)
		(width 0.1651)
		(layer "In11.Cu")
		(net "P5E_PEX0_STN4_TX_C_DP<69>")
	)
	(segment
		(start 34.97453 -365.83493)
		(end 35.133026 -365.803434)
		(width 0.1651)
		(layer "In11.Cu")
		(net "P5E_PEX0_STN4_TX_C_DP<69>")
	)
	(segment
		(start 33.77819 -367.831116)
		(end 34.053272 -367.419382)
		(width 0.1651)
		(layer "In11.Cu")
		(net "P5E_PEX0_STN4_TX_C_DP<69>")
	)
	(segment
		(start 39.831518 -353.975162)
		(end 41.385998 -352.420682)
		(width 0.1651)
		(layer "In11.Cu")
		(net "P5E_PEX0_STN4_TX_C_DP<69>")
	)
	(segment
		(start 41.385998 -351.902268)
		(end 41.095168 -351.611438)
		(width 0.1651)
		(layer "In11.Cu")
		(net "P5E_PEX0_STN4_TX_C_DP<69>")
	)
	(segment
		(start 41.385998 -352.420682)
		(end 41.385998 -351.902268)
		(width 0.1651)
		(layer "In11.Cu")
		(net "P5E_PEX0_STN4_TX_C_DP<69>")
	)
	(segment
		(start 32.31007 -370.489988)
		(end 32.31007 -370.872258)
		(width 0.1651)
		(layer "In11.Cu")
		(net "P5E_PEX0_STN4_TX_C_DP<69>")
	)
	(segment
		(start 39.095172 -359.873804)
		(end 39.063676 -359.715308)
		(width 0.1651)
		(layer "In11.Cu")
		(net "P5E_PEX0_STN4_TX_C_DP<69>")
	)
	(segment
		(start 32.062928 -342.734138)
		(end 31.768288 -342.439498)
		(width 0.13462)
		(layer "F.Cu")
		(net "P5E_PEX0_STN4_TX_DP<74>")
	)
	(segment
		(start 31.742888 -343.685622)
		(end 32.062928 -343.365582)
		(width 0.13462)
		(layer "F.Cu")
		(net "P5E_PEX0_STN4_TX_DP<74>")
	)
	(segment
		(start 32.062928 -343.365582)
		(end 32.062928 -342.734138)
		(width 0.13462)
		(layer "F.Cu")
		(net "P5E_PEX0_STN4_TX_DP<74>")
	)
	(segment
		(start 78.03388 -321.784726)
		(end 78.03388 -320.294)
		(width 0.1651)
		(layer "In11.Cu")
		(net "P5E_PEX0_STN4_TX_DP<74>")
	)
	(segment
		(start 78.03388 -320.294)
		(end 78.03388 -320.265552)
		(width 0.1143)
		(layer "In11.Cu")
		(net "P5E_PEX0_STN4_TX_DP<74>")
	)
	(segment
		(start 78.64983 -313.290712)
		(end 78.64983 -312.999882)
		(width 0.1143)
		(layer "In11.Cu")
		(net "P5E_PEX0_STN4_TX_DP<74>")
	)
	(segment
		(start 74.782426 -325.848218)
		(end 76.154026 -325.115174)
		(width 0.1651)
		(layer "In11.Cu")
		(net "P5E_PEX0_STN4_TX_DP<74>")
	)
	(segment
		(start 78.0796 -320.219832)
		(end 78.0796 -313.656218)
		(width 0.1143)
		(layer "In11.Cu")
		(net "P5E_PEX0_STN4_TX_DP<74>")
	)
	(segment
		(start 74.78268 -325.848218)
		(end 74.782426 -325.848218)
		(width 0.1651)
		(layer "In11.Cu")
		(net "P5E_PEX0_STN4_TX_DP<74>")
	)
	(segment
		(start 76.154026 -325.115174)
		(end 77.008228 -324.261226)
		(width 0.1651)
		(layer "In11.Cu")
		(net "P5E_PEX0_STN4_TX_DP<74>")
	)
	(segment
		(start 32.059118 -342.148668)
		(end 32.059118 -340.236302)
		(width 0.1651)
		(layer "In11.Cu")
		(net "P5E_PEX0_STN4_TX_DP<74>")
	)
	(segment
		(start 78.0796 -313.656218)
		(end 78.356206 -313.379612)
		(width 0.1143)
		(layer "In11.Cu")
		(net "P5E_PEX0_STN4_TX_DP<74>")
	)
	(segment
		(start 42.36847 -334.126078)
		(end 53.887878 -330.004166)
		(width 0.1651)
		(layer "In11.Cu")
		(net "P5E_PEX0_STN4_TX_DP<74>")
	)
	(segment
		(start 78.356206 -313.379612)
		(end 78.56093 -313.379612)
		(width 0.1143)
		(layer "In11.Cu")
		(net "P5E_PEX0_STN4_TX_DP<74>")
	)
	(segment
		(start 78.56093 -313.379612)
		(end 78.64983 -313.290712)
		(width 0.1143)
		(layer "In11.Cu")
		(net "P5E_PEX0_STN4_TX_DP<74>")
	)
	(segment
		(start 31.768288 -342.439498)
		(end 32.059118 -342.148668)
		(width 0.1651)
		(layer "In11.Cu")
		(net "P5E_PEX0_STN4_TX_DP<74>")
	)
	(segment
		(start 77.008228 -324.261226)
		(end 78.03388 -321.784726)
		(width 0.1651)
		(layer "In11.Cu")
		(net "P5E_PEX0_STN4_TX_DP<74>")
	)
	(segment
		(start 32.059118 -340.236302)
		(end 33.347152 -338.948014)
		(width 0.1651)
		(layer "In11.Cu")
		(net "P5E_PEX0_STN4_TX_DP<74>")
	)
	(segment
		(start 78.03388 -320.265552)
		(end 78.0796 -320.219832)
		(width 0.1143)
		(layer "In11.Cu")
		(net "P5E_PEX0_STN4_TX_DP<74>")
	)
	(segment
		(start 53.887878 -330.004166)
		(end 74.78268 -325.848218)
		(width 0.1651)
		(layer "In11.Cu")
		(net "P5E_PEX0_STN4_TX_DP<74>")
	)
	(segment
		(start 33.347152 -338.948014)
		(end 42.36847 -334.126078)
		(width 0.1651)
		(layer "In11.Cu")
		(net "P5E_PEX0_STN4_TX_DP<74>")
	)
	(segment
		(start 301.498 -394.5128)
		(end 301.498254 -394.5128)
		(width 0.1651)
		(layer "In15.Cu")
		(net "P5E_PEX2_STN4_RX_DN<73>")
	)
	(segment
		(start 285.927292 -386.014214)
		(end 285.470854 -384.722116)
		(width 0.1651)
		(layer "In15.Cu")
		(net "P5E_PEX2_STN4_RX_DN<73>")
	)
	(segment
		(start 285.470854 -384.722116)
		(end 285.005526 -372.362476)
		(width 0.1651)
		(layer "In15.Cu")
		(net "P5E_PEX2_STN4_RX_DN<73>")
	)
	(segment
		(start 311.465722 -323.511926)
		(end 311.465722 -319.941448)
		(width 0.1651)
		(layer "In15.Cu")
		(net "P5E_PEX2_STN4_RX_DN<73>")
	)
	(segment
		(start 294.896032 -342.0618)
		(end 295.3004 -341.0204)
		(width 0.1651)
		(layer "In15.Cu")
		(net "P5E_PEX2_STN4_RX_DN<73>")
	)
	(segment
		(start 311.465722 -319.913)
		(end 311.420002 -319.86728)
		(width 0.1143)
		(layer "In15.Cu")
		(net "P5E_PEX2_STN4_RX_DN<73>")
	)
	(segment
		(start 295.299892 -341.01659)
		(end 295.305988 -341.00643)
		(width 0.1651)
		(layer "In15.Cu")
		(net "P5E_PEX2_STN4_RX_DN<73>")
	)
	(segment
		(start 295.305988 -341.00643)
		(end 295.56202 -340.602062)
		(width 0.1651)
		(layer "In15.Cu")
		(net "P5E_PEX2_STN4_RX_DN<73>")
	)
	(segment
		(start 300.816772 -405.080978)
		(end 301.363888 -405.080978)
		(width 0.1651)
		(layer "In15.Cu")
		(net "P5E_PEX2_STN4_RX_DN<73>")
	)
	(segment
		(start 300.689772 -405.207978)
		(end 300.816772 -405.080978)
		(width 0.1651)
		(layer "In15.Cu")
		(net "P5E_PEX2_STN4_RX_DN<73>")
	)
	(segment
		(start 295.300908 -341.019638)
		(end 295.299892 -341.01659)
		(width 0.1651)
		(layer "In15.Cu")
		(net "P5E_PEX2_STN4_RX_DN<73>")
	)
	(segment
		(start 300.689772 -405.589994)
		(end 300.689772 -405.207978)
		(width 0.1651)
		(layer "In15.Cu")
		(net "P5E_PEX2_STN4_RX_DN<73>")
	)
	(segment
		(start 286.1818 -367.8936)
		(end 294.455088 -359.043732)
		(width 0.1651)
		(layer "In15.Cu")
		(net "P5E_PEX2_STN4_RX_DN<73>")
	)
	(segment
		(start 301.498254 -394.5128)
		(end 299.7962 -392.7856)
		(width 0.1651)
		(layer "In15.Cu")
		(net "P5E_PEX2_STN4_RX_DN<73>")
	)
	(segment
		(start 311.420002 -316.523624)
		(end 311.523634 -316.419992)
		(width 0.1143)
		(layer "In15.Cu")
		(net "P5E_PEX2_STN4_RX_DN<73>")
	)
	(segment
		(start 285.482538 -369.002056)
		(end 286.1818 -367.8936)
		(width 0.1651)
		(layer "In15.Cu")
		(net "P5E_PEX2_STN4_RX_DN<73>")
	)
	(segment
		(start 299.7962 -392.7856)
		(end 298.2214 -391.8204)
		(width 0.1651)
		(layer "In15.Cu")
		(net "P5E_PEX2_STN4_RX_DN<73>")
	)
	(segment
		(start 301.815754 -395.478)
		(end 301.498 -394.5128)
		(width 0.1651)
		(layer "In15.Cu")
		(net "P5E_PEX2_STN4_RX_DN<73>")
	)
	(segment
		(start 285.005526 -372.362476)
		(end 285.482538 -369.002056)
		(width 0.1651)
		(layer "In15.Cu")
		(net "P5E_PEX2_STN4_RX_DN<73>")
	)
	(segment
		(start 287.9598 -387.4516)
		(end 285.927292 -386.014214)
		(width 0.1651)
		(layer "In15.Cu")
		(net "P5E_PEX2_STN4_RX_DN<73>")
	)
	(segment
		(start 311.465722 -319.941448)
		(end 311.465722 -319.913)
		(width 0.1143)
		(layer "In15.Cu")
		(net "P5E_PEX2_STN4_RX_DN<73>")
	)
	(segment
		(start 311.799732 -316.534292)
		(end 311.799732 -316.799722)
		(width 0.1143)
		(layer "In15.Cu")
		(net "P5E_PEX2_STN4_RX_DN<73>")
	)
	(segment
		(start 311.523634 -316.419992)
		(end 311.685432 -316.419992)
		(width 0.1143)
		(layer "In15.Cu")
		(net "P5E_PEX2_STN4_RX_DN<73>")
	)
	(segment
		(start 311.685432 -316.419992)
		(end 311.799732 -316.534292)
		(width 0.1143)
		(layer "In15.Cu")
		(net "P5E_PEX2_STN4_RX_DN<73>")
	)
	(segment
		(start 311.420002 -319.86728)
		(end 311.420002 -316.523624)
		(width 0.1143)
		(layer "In15.Cu")
		(net "P5E_PEX2_STN4_RX_DN<73>")
	)
	(segment
		(start 301.363888 -405.080978)
		(end 301.815754 -404.629112)
		(width 0.1651)
		(layer "In15.Cu")
		(net "P5E_PEX2_STN4_RX_DN<73>")
	)
	(segment
		(start 294.896032 -357.978964)
		(end 294.896032 -342.0618)
		(width 0.1651)
		(layer "In15.Cu")
		(net "P5E_PEX2_STN4_RX_DN<73>")
	)
	(segment
		(start 295.56202 -340.602062)
		(end 311.092088 -324.414388)
		(width 0.1651)
		(layer "In15.Cu")
		(net "P5E_PEX2_STN4_RX_DN<73>")
	)
	(segment
		(start 295.3004 -341.0204)
		(end 295.300908 -341.019638)
		(width 0.1651)
		(layer "In15.Cu")
		(net "P5E_PEX2_STN4_RX_DN<73>")
	)
	(segment
		(start 294.455088 -359.043732)
		(end 294.896032 -357.978964)
		(width 0.1651)
		(layer "In15.Cu")
		(net "P5E_PEX2_STN4_RX_DN<73>")
	)
	(segment
		(start 301.815754 -404.629112)
		(end 301.815754 -395.478)
		(width 0.1651)
		(layer "In15.Cu")
		(net "P5E_PEX2_STN4_RX_DN<73>")
	)
	(segment
		(start 311.092088 -324.414388)
		(end 311.465722 -323.511926)
		(width 0.1651)
		(layer "In15.Cu")
		(net "P5E_PEX2_STN4_RX_DN<73>")
	)
	(segment
		(start 298.2214 -391.8204)
		(end 287.9598 -387.4516)
		(width 0.1651)
		(layer "In15.Cu")
		(net "P5E_PEX2_STN4_RX_DN<73>")
	)
	(segment
		(start 38.280848 -345.170506)
		(end 38.280848 -344.539062)
		(width 0.13462)
		(layer "F.Cu")
		(net "P5E_PEX0_STN4_TX_C_DP<71>")
	)
	(segment
		(start 38.280848 -344.539062)
		(end 37.960808 -344.219022)
		(width 0.13462)
		(layer "F.Cu")
		(net "P5E_PEX0_STN4_TX_C_DP<71>")
	)
	(segment
		(start 37.986208 -345.465146)
		(end 38.280848 -345.170506)
		(width 0.13462)
		(layer "F.Cu")
		(net "P5E_PEX0_STN4_TX_C_DP<71>")
	)
	(segment
		(start 31.12643 -365.40313)
		(end 31.440628 -365.020352)
		(width 0.1651)
		(layer "In11.Cu")
		(net "P5E_PEX0_STN4_TX_C_DP<71>")
	)
	(segment
		(start 34.953702 -360.55935)
		(end 35.114484 -360.543602)
		(width 0.1651)
		(layer "In11.Cu")
		(net "P5E_PEX0_STN4_TX_C_DP<71>")
	)
	(segment
		(start 31.900114 -364.460536)
		(end 32.214312 -364.077758)
		(width 0.1651)
		(layer "In11.Cu")
		(net "P5E_PEX0_STN4_TX_C_DP<71>")
	)
	(segment
		(start 31.424626 -364.85957)
		(end 31.739078 -364.476284)
		(width 0.1651)
		(layer "In11.Cu")
		(net "P5E_PEX0_STN4_TX_C_DP<71>")
	)
	(segment
		(start 36.722558 -358.12095)
		(end 36.722558 -347.876622)
		(width 0.1651)
		(layer "In11.Cu")
		(net "P5E_PEX0_STN4_TX_C_DP<71>")
	)
	(segment
		(start 32.673544 -363.517942)
		(end 33.881314 -362.046012)
		(width 0.1651)
		(layer "In11.Cu")
		(net "P5E_PEX0_STN4_TX_C_DP<71>")
	)
	(segment
		(start 35.41268 -359.999788)
		(end 35.727132 -359.616756)
		(width 0.1651)
		(layer "In11.Cu")
		(net "P5E_PEX0_STN4_TX_C_DP<71>")
	)
	(segment
		(start 36.428426 -358.942386)
		(end 36.722558 -358.12095)
		(width 0.1651)
		(layer "In11.Cu")
		(net "P5E_PEX0_STN4_TX_C_DP<71>")
	)
	(segment
		(start 33.865566 -361.88523)
		(end 34.180018 -361.501944)
		(width 0.1651)
		(layer "In11.Cu")
		(net "P5E_PEX0_STN4_TX_C_DP<71>")
	)
	(segment
		(start 28.88996 -368.128296)
		(end 30.666944 -365.962946)
		(width 0.1651)
		(layer "In11.Cu")
		(net "P5E_PEX0_STN4_TX_C_DP<71>")
	)
	(segment
		(start 36.722558 -347.876622)
		(end 38.277038 -346.322142)
		(width 0.1651)
		(layer "In11.Cu")
		(net "P5E_PEX0_STN4_TX_C_DP<71>")
	)
	(segment
		(start 30.965394 -365.419132)
		(end 31.12643 -365.40313)
		(width 0.1651)
		(layer "In11.Cu")
		(net "P5E_PEX0_STN4_TX_C_DP<71>")
	)
	(segment
		(start 28.372562 -370.999258)
		(end 28.88996 -370.48186)
		(width 0.1651)
		(layer "In11.Cu")
		(net "P5E_PEX0_STN4_TX_C_DP<71>")
	)
	(segment
		(start 34.654998 -361.103418)
		(end 34.63925 -360.942636)
		(width 0.1651)
		(layer "In11.Cu")
		(net "P5E_PEX0_STN4_TX_C_DP<71>")
	)
	(segment
		(start 31.739078 -364.476284)
		(end 31.900114 -364.460536)
		(width 0.1651)
		(layer "In11.Cu")
		(net "P5E_PEX0_STN4_TX_C_DP<71>")
	)
	(segment
		(start 35.428682 -360.160824)
		(end 35.41268 -359.999788)
		(width 0.1651)
		(layer "In11.Cu")
		(net "P5E_PEX0_STN4_TX_C_DP<71>")
	)
	(segment
		(start 28.037028 -370.999258)
		(end 28.372562 -370.999258)
		(width 0.1651)
		(layer "In11.Cu")
		(net "P5E_PEX0_STN4_TX_C_DP<71>")
	)
	(segment
		(start 27.910028 -370.489988)
		(end 27.910028 -370.872258)
		(width 0.1651)
		(layer "In11.Cu")
		(net "P5E_PEX0_STN4_TX_C_DP<71>")
	)
	(segment
		(start 28.88996 -370.48186)
		(end 28.88996 -368.128296)
		(width 0.1651)
		(layer "In11.Cu")
		(net "P5E_PEX0_STN4_TX_C_DP<71>")
	)
	(segment
		(start 30.666944 -365.962946)
		(end 30.650942 -365.802164)
		(width 0.1651)
		(layer "In11.Cu")
		(net "P5E_PEX0_STN4_TX_C_DP<71>")
	)
	(segment
		(start 27.910028 -370.872258)
		(end 28.037028 -370.999258)
		(width 0.1651)
		(layer "In11.Cu")
		(net "P5E_PEX0_STN4_TX_C_DP<71>")
	)
	(segment
		(start 32.19831 -363.916976)
		(end 32.512762 -363.53369)
		(width 0.1651)
		(layer "In11.Cu")
		(net "P5E_PEX0_STN4_TX_C_DP<71>")
	)
	(segment
		(start 38.277038 -346.322142)
		(end 38.277038 -345.755976)
		(width 0.1651)
		(layer "In11.Cu")
		(net "P5E_PEX0_STN4_TX_C_DP<71>")
	)
	(segment
		(start 33.881314 -362.046012)
		(end 33.865566 -361.88523)
		(width 0.1651)
		(layer "In11.Cu")
		(net "P5E_PEX0_STN4_TX_C_DP<71>")
	)
	(segment
		(start 30.650942 -365.802164)
		(end 30.965394 -365.419132)
		(width 0.1651)
		(layer "In11.Cu")
		(net "P5E_PEX0_STN4_TX_C_DP<71>")
	)
	(segment
		(start 34.63925 -360.942636)
		(end 34.953702 -360.55935)
		(width 0.1651)
		(layer "In11.Cu")
		(net "P5E_PEX0_STN4_TX_C_DP<71>")
	)
	(segment
		(start 38.277038 -345.755976)
		(end 37.986208 -345.465146)
		(width 0.1651)
		(layer "In11.Cu")
		(net "P5E_PEX0_STN4_TX_C_DP<71>")
	)
	(segment
		(start 34.180018 -361.501944)
		(end 34.3408 -361.486196)
		(width 0.1651)
		(layer "In11.Cu")
		(net "P5E_PEX0_STN4_TX_C_DP<71>")
	)
	(segment
		(start 31.440628 -365.020352)
		(end 31.424626 -364.85957)
		(width 0.1651)
		(layer "In11.Cu")
		(net "P5E_PEX0_STN4_TX_C_DP<71>")
	)
	(segment
		(start 35.114484 -360.543602)
		(end 35.428682 -360.160824)
		(width 0.1651)
		(layer "In11.Cu")
		(net "P5E_PEX0_STN4_TX_C_DP<71>")
	)
	(segment
		(start 32.214312 -364.077758)
		(end 32.19831 -363.916976)
		(width 0.1651)
		(layer "In11.Cu")
		(net "P5E_PEX0_STN4_TX_C_DP<71>")
	)
	(segment
		(start 35.888168 -359.600754)
		(end 36.428426 -358.942386)
		(width 0.1651)
		(layer "In11.Cu")
		(net "P5E_PEX0_STN4_TX_C_DP<71>")
	)
	(segment
		(start 34.3408 -361.486196)
		(end 34.654998 -361.103418)
		(width 0.1651)
		(layer "In11.Cu")
		(net "P5E_PEX0_STN4_TX_C_DP<71>")
	)
	(segment
		(start 35.727132 -359.616756)
		(end 35.888168 -359.600754)
		(width 0.1651)
		(layer "In11.Cu")
		(net "P5E_PEX0_STN4_TX_C_DP<71>")
	)
	(segment
		(start 32.512762 -363.53369)
		(end 32.673544 -363.517942)
		(width 0.1651)
		(layer "In11.Cu")
		(net "P5E_PEX0_STN4_TX_C_DP<71>")
	)
	(segment
		(start 298.961302 -344.219022)
		(end 299.281342 -344.539062)
		(width 0.13462)
		(layer "F.Cu")
		(net "P5E_PEX2_STN4_TX_C_DP<65>")
	)
	(segment
		(start 299.281342 -344.539062)
		(end 299.281342 -345.170506)
		(width 0.13462)
		(layer "F.Cu")
		(net "P5E_PEX2_STN4_TX_C_DP<65>")
	)
	(segment
		(start 299.281342 -345.170506)
		(end 298.986702 -345.465146)
		(width 0.13462)
		(layer "F.Cu")
		(net "P5E_PEX2_STN4_TX_C_DP<65>")
	)
	(segment
		(start 300.816772 -370.999258)
		(end 301.247048 -370.999258)
		(width 0.1651)
		(layer "In11.Cu")
		(net "P5E_PEX2_STN4_TX_C_DP<65>")
	)
	(segment
		(start 300.63694 -366.814608)
		(end 300.458886 -366.352074)
		(width 0.1651)
		(layer "In11.Cu")
		(net "P5E_PEX2_STN4_TX_C_DP<65>")
	)
	(segment
		(start 299.03039 -362.329476)
		(end 298.882562 -362.263944)
		(width 0.1651)
		(layer "In11.Cu")
		(net "P5E_PEX2_STN4_TX_C_DP<65>")
	)
	(segment
		(start 297.723052 -358.936798)
		(end 297.723052 -347.764354)
		(width 0.1651)
		(layer "In11.Cu")
		(net "P5E_PEX2_STN4_TX_C_DP<65>")
	)
	(segment
		(start 299.277532 -346.209874)
		(end 299.277532 -345.755976)
		(width 0.1651)
		(layer "In11.Cu")
		(net "P5E_PEX2_STN4_TX_C_DP<65>")
	)
	(segment
		(start 301.533814 -368.822478)
		(end 301.22368 -368.017806)
		(width 0.1651)
		(layer "In11.Cu")
		(net "P5E_PEX2_STN4_TX_C_DP<65>")
	)
	(segment
		(start 300.897544 -367.48974)
		(end 300.963076 -367.342166)
		(width 0.1651)
		(layer "In11.Cu")
		(net "P5E_PEX2_STN4_TX_C_DP<65>")
	)
	(segment
		(start 298.358814 -360.587036)
		(end 297.723052 -358.936798)
		(width 0.1651)
		(layer "In11.Cu")
		(net "P5E_PEX2_STN4_TX_C_DP<65>")
	)
	(segment
		(start 300.346364 -365.742474)
		(end 300.198282 -365.676942)
		(width 0.1651)
		(layer "In11.Cu")
		(net "P5E_PEX2_STN4_TX_C_DP<65>")
	)
	(segment
		(start 299.208444 -362.791502)
		(end 299.03039 -362.329476)
		(width 0.1651)
		(layer "In11.Cu")
		(net "P5E_PEX2_STN4_TX_C_DP<65>")
	)
	(segment
		(start 300.458886 -366.352074)
		(end 300.524418 -366.2045)
		(width 0.1651)
		(layer "In11.Cu")
		(net "P5E_PEX2_STN4_TX_C_DP<65>")
	)
	(segment
		(start 298.493688 -361.148122)
		(end 298.315126 -360.685588)
		(width 0.1651)
		(layer "In11.Cu")
		(net "P5E_PEX2_STN4_TX_C_DP<65>")
	)
	(segment
		(start 301.247048 -370.999258)
		(end 301.533814 -370.712492)
		(width 0.1651)
		(layer "In11.Cu")
		(net "P5E_PEX2_STN4_TX_C_DP<65>")
	)
	(segment
		(start 301.533814 -370.712492)
		(end 301.533814 -368.822478)
		(width 0.1651)
		(layer "In11.Cu")
		(net "P5E_PEX2_STN4_TX_C_DP<65>")
	)
	(segment
		(start 300.689772 -370.872258)
		(end 300.816772 -370.999258)
		(width 0.1651)
		(layer "In11.Cu")
		(net "P5E_PEX2_STN4_TX_C_DP<65>")
	)
	(segment
		(start 300.020228 -365.214408)
		(end 300.08576 -365.066834)
		(width 0.1651)
		(layer "In11.Cu")
		(net "P5E_PEX2_STN4_TX_C_DP<65>")
	)
	(segment
		(start 297.723052 -347.764354)
		(end 299.277532 -346.209874)
		(width 0.1651)
		(layer "In11.Cu")
		(net "P5E_PEX2_STN4_TX_C_DP<65>")
	)
	(segment
		(start 299.759624 -364.539276)
		(end 299.58157 -364.076742)
		(width 0.1651)
		(layer "In11.Cu")
		(net "P5E_PEX2_STN4_TX_C_DP<65>")
	)
	(segment
		(start 300.785022 -366.88014)
		(end 300.63694 -366.814608)
		(width 0.1651)
		(layer "In11.Cu")
		(net "P5E_PEX2_STN4_TX_C_DP<65>")
	)
	(segment
		(start 299.32122 -363.40161)
		(end 299.142912 -362.939076)
		(width 0.1651)
		(layer "In11.Cu")
		(net "P5E_PEX2_STN4_TX_C_DP<65>")
	)
	(segment
		(start 298.591986 -361.19181)
		(end 298.493688 -361.148122)
		(width 0.1651)
		(layer "In11.Cu")
		(net "P5E_PEX2_STN4_TX_C_DP<65>")
	)
	(segment
		(start 301.075598 -367.952274)
		(end 300.897544 -367.48974)
		(width 0.1651)
		(layer "In11.Cu")
		(net "P5E_PEX2_STN4_TX_C_DP<65>")
	)
	(segment
		(start 298.704254 -361.80141)
		(end 298.77004 -361.653836)
		(width 0.1651)
		(layer "In11.Cu")
		(net "P5E_PEX2_STN4_TX_C_DP<65>")
	)
	(segment
		(start 298.315126 -360.685588)
		(end 298.358814 -360.587036)
		(width 0.1651)
		(layer "In11.Cu")
		(net "P5E_PEX2_STN4_TX_C_DP<65>")
	)
	(segment
		(start 299.469048 -363.467142)
		(end 299.32122 -363.40161)
		(width 0.1651)
		(layer "In11.Cu")
		(net "P5E_PEX2_STN4_TX_C_DP<65>")
	)
	(segment
		(start 300.689772 -370.489988)
		(end 300.689772 -370.872258)
		(width 0.1651)
		(layer "In11.Cu")
		(net "P5E_PEX2_STN4_TX_C_DP<65>")
	)
	(segment
		(start 300.198282 -365.676942)
		(end 300.020228 -365.214408)
		(width 0.1651)
		(layer "In11.Cu")
		(net "P5E_PEX2_STN4_TX_C_DP<65>")
	)
	(segment
		(start 299.142912 -362.939076)
		(end 299.208444 -362.791502)
		(width 0.1651)
		(layer "In11.Cu")
		(net "P5E_PEX2_STN4_TX_C_DP<65>")
	)
	(segment
		(start 299.647102 -363.929168)
		(end 299.469048 -363.467142)
		(width 0.1651)
		(layer "In11.Cu")
		(net "P5E_PEX2_STN4_TX_C_DP<65>")
	)
	(segment
		(start 300.524418 -366.2045)
		(end 300.346364 -365.742474)
		(width 0.1651)
		(layer "In11.Cu")
		(net "P5E_PEX2_STN4_TX_C_DP<65>")
	)
	(segment
		(start 301.22368 -368.017806)
		(end 301.075598 -367.952274)
		(width 0.1651)
		(layer "In11.Cu")
		(net "P5E_PEX2_STN4_TX_C_DP<65>")
	)
	(segment
		(start 298.882562 -362.263944)
		(end 298.704254 -361.80141)
		(width 0.1651)
		(layer "In11.Cu")
		(net "P5E_PEX2_STN4_TX_C_DP<65>")
	)
	(segment
		(start 300.963076 -367.342166)
		(end 300.785022 -366.88014)
		(width 0.1651)
		(layer "In11.Cu")
		(net "P5E_PEX2_STN4_TX_C_DP<65>")
	)
	(segment
		(start 298.77004 -361.653836)
		(end 298.591986 -361.19181)
		(width 0.1651)
		(layer "In11.Cu")
		(net "P5E_PEX2_STN4_TX_C_DP<65>")
	)
	(segment
		(start 299.907706 -364.604808)
		(end 299.759624 -364.539276)
		(width 0.1651)
		(layer "In11.Cu")
		(net "P5E_PEX2_STN4_TX_C_DP<65>")
	)
	(segment
		(start 299.277532 -345.755976)
		(end 298.986702 -345.465146)
		(width 0.1651)
		(layer "In11.Cu")
		(net "P5E_PEX2_STN4_TX_C_DP<65>")
	)
	(segment
		(start 300.08576 -365.066834)
		(end 299.907706 -364.604808)
		(width 0.1651)
		(layer "In11.Cu")
		(net "P5E_PEX2_STN4_TX_C_DP<65>")
	)
	(segment
		(start 299.58157 -364.076742)
		(end 299.647102 -363.929168)
		(width 0.1651)
		(layer "In11.Cu")
		(net "P5E_PEX2_STN4_TX_C_DP<65>")
	)
	(segment
		(start 47.607728 -351.316798)
		(end 47.607728 -350.685354)
		(width 0.13462)
		(layer "F.Cu")
		(net "P5E_PEX0_STN4_TX_C_DP<66>")
	)
	(segment
		(start 47.607728 -350.685354)
		(end 47.287688 -350.365314)
		(width 0.13462)
		(layer "F.Cu")
		(net "P5E_PEX0_STN4_TX_C_DP<66>")
	)
	(segment
		(start 47.313088 -351.611438)
		(end 47.607728 -351.316798)
		(width 0.13462)
		(layer "F.Cu")
		(net "P5E_PEX0_STN4_TX_C_DP<66>")
	)
	(segment
		(start 42.469562 -364.377478)
		(end 42.311066 -364.408974)
		(width 0.1651)
		(layer "In11.Cu")
		(net "P5E_PEX0_STN4_TX_C_DP<66>")
	)
	(segment
		(start 43.480482 -362.864908)
		(end 43.339512 -362.892848)
		(width 0.1651)
		(layer "In11.Cu")
		(net "P5E_PEX0_STN4_TX_C_DP<66>")
	)
	(segment
		(start 43.092116 -363.445806)
		(end 42.469562 -364.377478)
		(width 0.1651)
		(layer "In11.Cu")
		(net "P5E_PEX0_STN4_TX_C_DP<66>")
	)
	(segment
		(start 44.778676 -360.921808)
		(end 44.673012 -360.94289)
		(width 0.1651)
		(layer "In11.Cu")
		(net "P5E_PEX0_STN4_TX_C_DP<66>")
	)
	(segment
		(start 40.98798 -366.411764)
		(end 40.712644 -366.823752)
		(width 0.1651)
		(layer "In11.Cu")
		(net "P5E_PEX0_STN4_TX_C_DP<66>")
	)
	(segment
		(start 44.143676 -361.872276)
		(end 44.002706 -361.900216)
		(width 0.1651)
		(layer "In11.Cu")
		(net "P5E_PEX0_STN4_TX_C_DP<66>")
	)
	(segment
		(start 43.72737 -362.312204)
		(end 43.75531 -362.453174)
		(width 0.1651)
		(layer "In11.Cu")
		(net "P5E_PEX0_STN4_TX_C_DP<66>")
	)
	(segment
		(start 44.002706 -361.900216)
		(end 43.72737 -362.312204)
		(width 0.1651)
		(layer "In11.Cu")
		(net "P5E_PEX0_STN4_TX_C_DP<66>")
	)
	(segment
		(start 47.313088 -351.611438)
		(end 47.603918 -351.902268)
		(width 0.1651)
		(layer "In11.Cu")
		(net "P5E_PEX0_STN4_TX_C_DP<66>")
	)
	(segment
		(start 45.456094 -359.908094)
		(end 45.297598 -359.93959)
		(width 0.1651)
		(layer "In11.Cu")
		(net "P5E_PEX0_STN4_TX_C_DP<66>")
	)
	(segment
		(start 42.067226 -364.979458)
		(end 41.792144 -365.391192)
		(width 0.1651)
		(layer "In11.Cu")
		(net "P5E_PEX0_STN4_TX_C_DP<66>")
	)
	(segment
		(start 46.049438 -353.975162)
		(end 46.049438 -359.02011)
		(width 0.1651)
		(layer "In11.Cu")
		(net "P5E_PEX0_STN4_TX_C_DP<66>")
	)
	(segment
		(start 47.603918 -352.420682)
		(end 46.049438 -353.975162)
		(width 0.1651)
		(layer "In11.Cu")
		(net "P5E_PEX0_STN4_TX_C_DP<66>")
	)
	(segment
		(start 40.07739 -367.957354)
		(end 39.802308 -368.369088)
		(width 0.1651)
		(layer "In11.Cu")
		(net "P5E_PEX0_STN4_TX_C_DP<66>")
	)
	(segment
		(start 40.465502 -367.376456)
		(end 40.465756 -367.376456)
		(width 0.1651)
		(layer "In11.Cu")
		(net "P5E_PEX0_STN4_TX_C_DP<66>")
	)
	(segment
		(start 43.063922 -363.304836)
		(end 43.092116 -363.445806)
		(width 0.1651)
		(layer "In11.Cu")
		(net "P5E_PEX0_STN4_TX_C_DP<66>")
	)
	(segment
		(start 42.03573 -364.820962)
		(end 42.067226 -364.979458)
		(width 0.1651)
		(layer "In11.Cu")
		(net "P5E_PEX0_STN4_TX_C_DP<66>")
	)
	(segment
		(start 41.792398 -365.391192)
		(end 41.651428 -365.419132)
		(width 0.1651)
		(layer "In11.Cu")
		(net "P5E_PEX0_STN4_TX_C_DP<66>")
	)
	(segment
		(start 43.339512 -362.892848)
		(end 43.063922 -363.304836)
		(width 0.1651)
		(layer "In11.Cu")
		(net "P5E_PEX0_STN4_TX_C_DP<66>")
	)
	(segment
		(start 40.04945 -367.816384)
		(end 40.07739 -367.957354)
		(width 0.1651)
		(layer "In11.Cu")
		(net "P5E_PEX0_STN4_TX_C_DP<66>")
	)
	(segment
		(start 39.460424 -372.099078)
		(end 39.037006 -372.099078)
		(width 0.1651)
		(layer "In11.Cu")
		(net "P5E_PEX0_STN4_TX_C_DP<66>")
	)
	(segment
		(start 39.037006 -372.099078)
		(end 38.910006 -371.972078)
		(width 0.1651)
		(layer "In11.Cu")
		(net "P5E_PEX0_STN4_TX_C_DP<66>")
	)
	(segment
		(start 45.297598 -359.93959)
		(end 45.022262 -360.351578)
		(width 0.1651)
		(layer "In11.Cu")
		(net "P5E_PEX0_STN4_TX_C_DP<66>")
	)
	(segment
		(start 44.418504 -361.460542)
		(end 44.143422 -361.872276)
		(width 0.1651)
		(layer "In11.Cu")
		(net "P5E_PEX0_STN4_TX_C_DP<66>")
	)
	(segment
		(start 40.740584 -366.964722)
		(end 40.465502 -367.376456)
		(width 0.1651)
		(layer "In11.Cu")
		(net "P5E_PEX0_STN4_TX_C_DP<66>")
	)
	(segment
		(start 44.143422 -361.872276)
		(end 44.143676 -361.872276)
		(width 0.1651)
		(layer "In11.Cu")
		(net "P5E_PEX0_STN4_TX_C_DP<66>")
	)
	(segment
		(start 41.376092 -365.83112)
		(end 41.404032 -365.97209)
		(width 0.1651)
		(layer "In11.Cu")
		(net "P5E_PEX0_STN4_TX_C_DP<66>")
	)
	(segment
		(start 44.673012 -360.94289)
		(end 44.397422 -361.354878)
		(width 0.1651)
		(layer "In11.Cu")
		(net "P5E_PEX0_STN4_TX_C_DP<66>")
	)
	(segment
		(start 45.053758 -360.510074)
		(end 44.778676 -360.921808)
		(width 0.1651)
		(layer "In11.Cu")
		(net "P5E_PEX0_STN4_TX_C_DP<66>")
	)
	(segment
		(start 39.802308 -371.757194)
		(end 39.460424 -372.099078)
		(width 0.1651)
		(layer "In11.Cu")
		(net "P5E_PEX0_STN4_TX_C_DP<66>")
	)
	(segment
		(start 39.802308 -368.369088)
		(end 39.802308 -371.757194)
		(width 0.1651)
		(layer "In11.Cu")
		(net "P5E_PEX0_STN4_TX_C_DP<66>")
	)
	(segment
		(start 40.465756 -367.376456)
		(end 40.324786 -367.404396)
		(width 0.1651)
		(layer "In11.Cu")
		(net "P5E_PEX0_STN4_TX_C_DP<66>")
	)
	(segment
		(start 41.651428 -365.419132)
		(end 41.376092 -365.83112)
		(width 0.1651)
		(layer "In11.Cu")
		(net "P5E_PEX0_STN4_TX_C_DP<66>")
	)
	(segment
		(start 40.712644 -366.823752)
		(end 40.740584 -366.964722)
		(width 0.1651)
		(layer "In11.Cu")
		(net "P5E_PEX0_STN4_TX_C_DP<66>")
	)
	(segment
		(start 40.324786 -367.404396)
		(end 40.04945 -367.816384)
		(width 0.1651)
		(layer "In11.Cu")
		(net "P5E_PEX0_STN4_TX_C_DP<66>")
	)
	(segment
		(start 42.311066 -364.408974)
		(end 42.03573 -364.820962)
		(width 0.1651)
		(layer "In11.Cu")
		(net "P5E_PEX0_STN4_TX_C_DP<66>")
	)
	(segment
		(start 43.480228 -362.864908)
		(end 43.480482 -362.864908)
		(width 0.1651)
		(layer "In11.Cu")
		(net "P5E_PEX0_STN4_TX_C_DP<66>")
	)
	(segment
		(start 41.792144 -365.391192)
		(end 41.792398 -365.391192)
		(width 0.1651)
		(layer "In11.Cu")
		(net "P5E_PEX0_STN4_TX_C_DP<66>")
	)
	(segment
		(start 38.910006 -371.972078)
		(end 38.910006 -371.590062)
		(width 0.1651)
		(layer "In11.Cu")
		(net "P5E_PEX0_STN4_TX_C_DP<66>")
	)
	(segment
		(start 45.022262 -360.351578)
		(end 45.053758 -360.510074)
		(width 0.1651)
		(layer "In11.Cu")
		(net "P5E_PEX0_STN4_TX_C_DP<66>")
	)
	(segment
		(start 47.603918 -351.902268)
		(end 47.603918 -352.420682)
		(width 0.1651)
		(layer "In11.Cu")
		(net "P5E_PEX0_STN4_TX_C_DP<66>")
	)
	(segment
		(start 41.404032 -365.97209)
		(end 41.12895 -366.383824)
		(width 0.1651)
		(layer "In11.Cu")
		(net "P5E_PEX0_STN4_TX_C_DP<66>")
	)
	(segment
		(start 43.75531 -362.453174)
		(end 43.480228 -362.864908)
		(width 0.1651)
		(layer "In11.Cu")
		(net "P5E_PEX0_STN4_TX_C_DP<66>")
	)
	(segment
		(start 46.049438 -359.02011)
		(end 45.456094 -359.908094)
		(width 0.1651)
		(layer "In11.Cu")
		(net "P5E_PEX0_STN4_TX_C_DP<66>")
	)
	(segment
		(start 41.12895 -366.383824)
		(end 40.98798 -366.411764)
		(width 0.1651)
		(layer "In11.Cu")
		(net "P5E_PEX0_STN4_TX_C_DP<66>")
	)
	(segment
		(start 44.397422 -361.354878)
		(end 44.418504 -361.460542)
		(width 0.1651)
		(layer "In11.Cu")
		(net "P5E_PEX0_STN4_TX_C_DP<66>")
	)
	(segment
		(start 25.845008 -355.658166)
		(end 25.845008 -355.026722)
		(width 0.13462)
		(layer "F.Cu")
		(net "P5E_PEX0_STN4_TX_DP<76>")
	)
	(segment
		(start 25.845008 -355.026722)
		(end 25.550368 -354.732082)
		(width 0.13462)
		(layer "F.Cu")
		(net "P5E_PEX0_STN4_TX_DP<76>")
	)
	(segment
		(start 25.524968 -355.978206)
		(end 25.845008 -355.658166)
		(width 0.13462)
		(layer "F.Cu")
		(net "P5E_PEX0_STN4_TX_DP<76>")
	)
	(segment
		(start 27.395678 -352.103182)
		(end 27.395678 -340.599522)
		(width 0.1651)
		(layer "In11.Cu")
		(net "P5E_PEX0_STN4_TX_DP<76>")
	)
	(segment
		(start 25.841198 -354.441252)
		(end 25.841198 -353.657662)
		(width 0.1651)
		(layer "In11.Cu")
		(net "P5E_PEX0_STN4_TX_DP<76>")
	)
	(segment
		(start 27.477974 -340.516972)
		(end 27.478228 -340.516972)
		(width 0.1651)
		(layer "In11.Cu")
		(net "P5E_PEX0_STN4_TX_DP<76>")
	)
	(segment
		(start 27.478228 -340.516972)
		(end 29.030422 -338.964524)
		(width 0.1651)
		(layer "In11.Cu")
		(net "P5E_PEX0_STN4_TX_DP<76>")
	)
	(segment
		(start 75.39863 -323.075808)
		(end 76.13396 -321.300348)
		(width 0.1651)
		(layer "In11.Cu")
		(net "P5E_PEX0_STN4_TX_DP<76>")
	)
	(segment
		(start 53.296058 -328.117962)
		(end 73.474326 -324.104508)
		(width 0.1651)
		(layer "In11.Cu")
		(net "P5E_PEX0_STN4_TX_DP<76>")
	)
	(segment
		(start 76.13396 -321.300348)
		(end 76.13396 -320.294)
		(width 0.1651)
		(layer "In11.Cu")
		(net "P5E_PEX0_STN4_TX_DP<76>")
	)
	(segment
		(start 76.17968 -313.656218)
		(end 76.456286 -313.379612)
		(width 0.1143)
		(layer "In11.Cu")
		(net "P5E_PEX0_STN4_TX_DP<76>")
	)
	(segment
		(start 76.456286 -313.379612)
		(end 76.66101 -313.379612)
		(width 0.1143)
		(layer "In11.Cu")
		(net "P5E_PEX0_STN4_TX_DP<76>")
	)
	(segment
		(start 76.74991 -313.290712)
		(end 76.74991 -312.999882)
		(width 0.1143)
		(layer "In11.Cu")
		(net "P5E_PEX0_STN4_TX_DP<76>")
	)
	(segment
		(start 76.17968 -320.219832)
		(end 76.17968 -313.656218)
		(width 0.1143)
		(layer "In11.Cu")
		(net "P5E_PEX0_STN4_TX_DP<76>")
	)
	(segment
		(start 76.66101 -313.379612)
		(end 76.74991 -313.290712)
		(width 0.1143)
		(layer "In11.Cu")
		(net "P5E_PEX0_STN4_TX_DP<76>")
	)
	(segment
		(start 27.395678 -340.599522)
		(end 27.477974 -340.516972)
		(width 0.1651)
		(layer "In11.Cu")
		(net "P5E_PEX0_STN4_TX_DP<76>")
	)
	(segment
		(start 76.13396 -320.294)
		(end 76.13396 -320.265552)
		(width 0.1143)
		(layer "In11.Cu")
		(net "P5E_PEX0_STN4_TX_DP<76>")
	)
	(segment
		(start 76.13396 -320.265552)
		(end 76.17968 -320.219832)
		(width 0.1143)
		(layer "In11.Cu")
		(net "P5E_PEX0_STN4_TX_DP<76>")
	)
	(segment
		(start 41.27754 -332.418436)
		(end 53.296058 -328.117962)
		(width 0.1651)
		(layer "In11.Cu")
		(net "P5E_PEX0_STN4_TX_DP<76>")
	)
	(segment
		(start 25.550368 -354.732082)
		(end 25.841198 -354.441252)
		(width 0.1651)
		(layer "In11.Cu")
		(net "P5E_PEX0_STN4_TX_DP<76>")
	)
	(segment
		(start 73.474326 -324.104508)
		(end 75.39863 -323.075808)
		(width 0.1651)
		(layer "In11.Cu")
		(net "P5E_PEX0_STN4_TX_DP<76>")
	)
	(segment
		(start 29.030422 -338.964524)
		(end 41.27754 -332.418436)
		(width 0.1651)
		(layer "In11.Cu")
		(net "P5E_PEX0_STN4_TX_DP<76>")
	)
	(segment
		(start 25.841198 -353.657662)
		(end 27.395678 -352.103182)
		(width 0.1651)
		(layer "In11.Cu")
		(net "P5E_PEX0_STN4_TX_DP<76>")
	)
	(segment
		(start 280.627582 -345.170506)
		(end 280.332942 -345.465146)
		(width 0.13462)
		(layer "F.Cu")
		(net "P5E_PEX2_STN4_TX_C_DP<74>")
	)
	(segment
		(start 280.627582 -344.539062)
		(end 280.627582 -345.170506)
		(width 0.13462)
		(layer "F.Cu")
		(net "P5E_PEX2_STN4_TX_C_DP<74>")
	)
	(segment
		(start 280.307542 -344.219022)
		(end 280.627582 -344.539062)
		(width 0.13462)
		(layer "F.Cu")
		(net "P5E_PEX2_STN4_TX_C_DP<74>")
	)
	(segment
		(start 296.898822 -393.119102)
		(end 296.775124 -393.141962)
		(width 0.1651)
		(layer "In11.Cu")
		(net "P5E_PEX2_STN4_TX_C_DP<74>")
	)
	(segment
		(start 298.684442 -394.676376)
		(end 298.354496 -394.120116)
		(width 0.1651)
		(layer "In11.Cu")
		(net "P5E_PEX2_STN4_TX_C_DP<74>")
	)
	(segment
		(start 293.032434 -390.845294)
		(end 292.983666 -390.72947)
		(width 0.1651)
		(layer "In11.Cu")
		(net "P5E_PEX2_STN4_TX_C_DP<74>")
	)
	(segment
		(start 293.491412 -391.032492)
		(end 293.032434 -390.845294)
		(width 0.1651)
		(layer "In11.Cu")
		(net "P5E_PEX2_STN4_TX_C_DP<74>")
	)
	(segment
		(start 280.623772 -345.755976)
		(end 280.332942 -345.465146)
		(width 0.1651)
		(layer "In11.Cu")
		(net "P5E_PEX2_STN4_TX_C_DP<74>")
	)
	(segment
		(start 299.047154 -398.09928)
		(end 299.33392 -397.812514)
		(width 0.1651)
		(layer "In11.Cu")
		(net "P5E_PEX2_STN4_TX_C_DP<74>")
	)
	(segment
		(start 295.403778 -392.19886)
		(end 295.380918 -392.075162)
		(width 0.1651)
		(layer "In11.Cu")
		(net "P5E_PEX2_STN4_TX_C_DP<74>")
	)
	(segment
		(start 293.607236 -390.983724)
		(end 293.491412 -391.032492)
		(width 0.1651)
		(layer "In11.Cu")
		(net "P5E_PEX2_STN4_TX_C_DP<74>")
	)
	(segment
		(start 298.354496 -394.120116)
		(end 297.861482 -393.781026)
		(width 0.1651)
		(layer "In11.Cu")
		(net "P5E_PEX2_STN4_TX_C_DP<74>")
	)
	(segment
		(start 299.33392 -397.812514)
		(end 299.33392 -395.770862)
		(width 0.1651)
		(layer "In11.Cu")
		(net "P5E_PEX2_STN4_TX_C_DP<74>")
	)
	(segment
		(start 292.983666 -390.72947)
		(end 292.983666 -390.729724)
		(width 0.1651)
		(layer "In11.Cu")
		(net "P5E_PEX2_STN4_TX_C_DP<74>")
	)
	(segment
		(start 297.329606 -393.522962)
		(end 297.306746 -393.399518)
		(width 0.1651)
		(layer "In11.Cu")
		(net "P5E_PEX2_STN4_TX_C_DP<74>")
	)
	(segment
		(start 298.616878 -398.09928)
		(end 299.047154 -398.09928)
		(width 0.1651)
		(layer "In11.Cu")
		(net "P5E_PEX2_STN4_TX_C_DP<74>")
	)
	(segment
		(start 296.366692 -392.861038)
		(end 296.343832 -392.73734)
		(width 0.1651)
		(layer "In11.Cu")
		(net "P5E_PEX2_STN4_TX_C_DP<74>")
	)
	(segment
		(start 280.623772 -346.209874)
		(end 280.623772 -345.755976)
		(width 0.1651)
		(layer "In11.Cu")
		(net "P5E_PEX2_STN4_TX_C_DP<74>")
	)
	(segment
		(start 292.983666 -390.729724)
		(end 286.267144 -387.991858)
		(width 0.1651)
		(layer "In11.Cu")
		(net "P5E_PEX2_STN4_TX_C_DP<74>")
	)
	(segment
		(start 294.065706 -391.170668)
		(end 293.607236 -390.983724)
		(width 0.1651)
		(layer "In11.Cu")
		(net "P5E_PEX2_STN4_TX_C_DP<74>")
	)
	(segment
		(start 298.489878 -397.97228)
		(end 298.616878 -398.09928)
		(width 0.1651)
		(layer "In11.Cu")
		(net "P5E_PEX2_STN4_TX_C_DP<74>")
	)
	(segment
		(start 284.160722 -385.246118)
		(end 283.411422 -378.894086)
		(width 0.1651)
		(layer "In11.Cu")
		(net "P5E_PEX2_STN4_TX_C_DP<74>")
	)
	(segment
		(start 284.779212 -386.535168)
		(end 284.160722 -385.246118)
		(width 0.1651)
		(layer "In11.Cu")
		(net "P5E_PEX2_STN4_TX_C_DP<74>")
	)
	(segment
		(start 283.411422 -378.894086)
		(end 279.069292 -358.866186)
		(width 0.1651)
		(layer "In11.Cu")
		(net "P5E_PEX2_STN4_TX_C_DP<74>")
	)
	(segment
		(start 297.737784 -393.803886)
		(end 297.329606 -393.522962)
		(width 0.1651)
		(layer "In11.Cu")
		(net "P5E_PEX2_STN4_TX_C_DP<74>")
	)
	(segment
		(start 296.343832 -392.73734)
		(end 295.935908 -392.456924)
		(width 0.1651)
		(layer "In11.Cu")
		(net "P5E_PEX2_STN4_TX_C_DP<74>")
	)
	(segment
		(start 298.897548 -395.259306)
		(end 298.644564 -394.833094)
		(width 0.1651)
		(layer "In11.Cu")
		(net "P5E_PEX2_STN4_TX_C_DP<74>")
	)
	(segment
		(start 296.775124 -393.141962)
		(end 296.366692 -392.861038)
		(width 0.1651)
		(layer "In11.Cu")
		(net "P5E_PEX2_STN4_TX_C_DP<74>")
	)
	(segment
		(start 299.33392 -395.770862)
		(end 299.054012 -395.299184)
		(width 0.1651)
		(layer "In11.Cu")
		(net "P5E_PEX2_STN4_TX_C_DP<74>")
	)
	(segment
		(start 297.306746 -393.399518)
		(end 296.898822 -393.119102)
		(width 0.1651)
		(layer "In11.Cu")
		(net "P5E_PEX2_STN4_TX_C_DP<74>")
	)
	(segment
		(start 298.644564 -394.833094)
		(end 298.684442 -394.676376)
		(width 0.1651)
		(layer "In11.Cu")
		(net "P5E_PEX2_STN4_TX_C_DP<74>")
	)
	(segment
		(start 298.489878 -397.59001)
		(end 298.489878 -397.97228)
		(width 0.1651)
		(layer "In11.Cu")
		(net "P5E_PEX2_STN4_TX_C_DP<74>")
	)
	(segment
		(start 279.069292 -358.866186)
		(end 279.069292 -347.764354)
		(width 0.1651)
		(layer "In11.Cu")
		(net "P5E_PEX2_STN4_TX_C_DP<74>")
	)
	(segment
		(start 279.069292 -347.764354)
		(end 280.623772 -346.209874)
		(width 0.1651)
		(layer "In11.Cu")
		(net "P5E_PEX2_STN4_TX_C_DP<74>")
	)
	(segment
		(start 299.054012 -395.299184)
		(end 298.897548 -395.259306)
		(width 0.1651)
		(layer "In11.Cu")
		(net "P5E_PEX2_STN4_TX_C_DP<74>")
	)
	(segment
		(start 286.267144 -387.991858)
		(end 284.779212 -386.535168)
		(width 0.1651)
		(layer "In11.Cu")
		(net "P5E_PEX2_STN4_TX_C_DP<74>")
	)
	(segment
		(start 295.81221 -392.479784)
		(end 295.403778 -392.19886)
		(width 0.1651)
		(layer "In11.Cu")
		(net "P5E_PEX2_STN4_TX_C_DP<74>")
	)
	(segment
		(start 297.861482 -393.781026)
		(end 297.737784 -393.803886)
		(width 0.1651)
		(layer "In11.Cu")
		(net "P5E_PEX2_STN4_TX_C_DP<74>")
	)
	(segment
		(start 295.380918 -392.075162)
		(end 294.065706 -391.170668)
		(width 0.1651)
		(layer "In11.Cu")
		(net "P5E_PEX2_STN4_TX_C_DP<74>")
	)
	(segment
		(start 295.935908 -392.456924)
		(end 295.81221 -392.479784)
		(width 0.1651)
		(layer "In11.Cu")
		(net "P5E_PEX2_STN4_TX_C_DP<74>")
	)
	(segment
		(start 50.991008 -356.831646)
		(end 51.311048 -356.511606)
		(width 0.13462)
		(layer "F.Cu")
		(net "P5E_PEX0_STN4_TX_C_DN<64>")
	)
	(segment
		(start 51.285648 -357.75773)
		(end 50.991008 -357.46309)
		(width 0.13462)
		(layer "F.Cu")
		(net "P5E_PEX0_STN4_TX_C_DN<64>")
	)
	(segment
		(start 50.991008 -357.46309)
		(end 50.991008 -356.831646)
		(width 0.13462)
		(layer "F.Cu")
		(net "P5E_PEX0_STN4_TX_C_DN<64>")
	)
	(segment
		(start 43.977306 -372.381018)
		(end 44.48429 -371.874034)
		(width 0.1651)
		(layer "In11.Cu")
		(net "P5E_PEX0_STN4_TX_C_DN<64>")
	)
	(segment
		(start 44.48429 -369.582446)
		(end 44.87672 -368.289586)
		(width 0.1651)
		(layer "In11.Cu")
		(net "P5E_PEX0_STN4_TX_C_DN<64>")
	)
	(segment
		(start 43.437048 -372.381018)
		(end 43.977306 -372.381018)
		(width 0.1651)
		(layer "In11.Cu")
		(net "P5E_PEX0_STN4_TX_C_DN<64>")
	)
	(segment
		(start 43.310048 -372.890034)
		(end 43.310048 -372.508018)
		(width 0.1651)
		(layer "In11.Cu")
		(net "P5E_PEX0_STN4_TX_C_DN<64>")
	)
	(segment
		(start 50.994818 -359.132886)
		(end 50.994818 -358.04856)
		(width 0.1651)
		(layer "In11.Cu")
		(net "P5E_PEX0_STN4_TX_C_DN<64>")
	)
	(segment
		(start 44.87672 -368.289586)
		(end 50.994818 -359.132886)
		(width 0.1651)
		(layer "In11.Cu")
		(net "P5E_PEX0_STN4_TX_C_DN<64>")
	)
	(segment
		(start 50.994818 -358.04856)
		(end 51.285648 -357.75773)
		(width 0.1651)
		(layer "In11.Cu")
		(net "P5E_PEX0_STN4_TX_C_DN<64>")
	)
	(segment
		(start 43.310048 -372.508018)
		(end 43.437048 -372.381018)
		(width 0.1651)
		(layer "In11.Cu")
		(net "P5E_PEX0_STN4_TX_C_DN<64>")
	)
	(segment
		(start 44.48429 -371.874034)
		(end 44.48429 -369.582446)
		(width 0.1651)
		(layer "In11.Cu")
		(net "P5E_PEX0_STN4_TX_C_DN<64>")
	)
	(segment
		(start 45.093128 -343.685622)
		(end 44.773088 -343.365582)
		(width 0.13462)
		(layer "F.Cu")
		(net "P5E_PEX0_STN4_TX_DN<68>")
	)
	(segment
		(start 44.773088 -342.734138)
		(end 45.067728 -342.439498)
		(width 0.13462)
		(layer "F.Cu")
		(net "P5E_PEX0_STN4_TX_DN<68>")
	)
	(segment
		(start 44.773088 -343.365582)
		(end 44.773088 -342.734138)
		(width 0.13462)
		(layer "F.Cu")
		(net "P5E_PEX0_STN4_TX_DN<68>")
	)
	(segment
		(start 95.719138 -322.108068)
		(end 95.719138 -319.691512)
		(width 0.1651)
		(layer "In11.Cu")
		(net "P5E_PEX0_STN4_TX_DN<68>")
	)
	(segment
		(start 44.776898 -342.148668)
		(end 44.776898 -341.252302)
		(width 0.1651)
		(layer "In11.Cu")
		(net "P5E_PEX0_STN4_TX_DN<68>")
	)
	(segment
		(start 90.466164 -314.668408)
		(end 84.734146 -308.93639)
		(width 0.1651)
		(layer "In11.Cu")
		(net "P5E_PEX0_STN4_TX_DN<68>")
	)
	(segment
		(start 94.725744 -324.506336)
		(end 95.719138 -322.108068)
		(width 0.1651)
		(layer "In11.Cu")
		(net "P5E_PEX0_STN4_TX_DN<68>")
	)
	(segment
		(start 83.6422 -308.583838)
		(end 83.59648 -308.629558)
		(width 0.1143)
		(layer "In11.Cu")
		(net "P5E_PEX0_STN4_TX_DN<68>")
	)
	(segment
		(start 93.434154 -325.79818)
		(end 94.725744 -324.506336)
		(width 0.1651)
		(layer "In11.Cu")
		(net "P5E_PEX0_STN4_TX_DN<68>")
	)
	(segment
		(start 57.243218 -335.519522)
		(end 78.778608 -331.23632)
		(width 0.1651)
		(layer "In11.Cu")
		(net "P5E_PEX0_STN4_TX_DN<68>")
	)
	(segment
		(start 46.273974 -339.755226)
		(end 48.033432 -338.814664)
		(width 0.1651)
		(layer "In11.Cu")
		(net "P5E_PEX0_STN4_TX_DN<68>")
	)
	(segment
		(start 95.719138 -319.691512)
		(end 94.795848 -317.462408)
		(width 0.1651)
		(layer "In11.Cu")
		(net "P5E_PEX0_STN4_TX_DN<68>")
	)
	(segment
		(start 78.778608 -331.23632)
		(end 92.33281 -326.386698)
		(width 0.1651)
		(layer "In11.Cu")
		(net "P5E_PEX0_STN4_TX_DN<68>")
	)
	(segment
		(start 75.42022 -308.338728)
		(end 75.50912 -308.249828)
		(width 0.1143)
		(layer "In11.Cu")
		(net "P5E_PEX0_STN4_TX_DN<68>")
	)
	(segment
		(start 83.670648 -308.583838)
		(end 83.6422 -308.583838)
		(width 0.1143)
		(layer "In11.Cu")
		(net "P5E_PEX0_STN4_TX_DN<68>")
	)
	(segment
		(start 93.087444 -315.754004)
		(end 90.466164 -314.668408)
		(width 0.1651)
		(layer "In11.Cu")
		(net "P5E_PEX0_STN4_TX_DN<68>")
	)
	(segment
		(start 75.42022 -308.464458)
		(end 75.42022 -308.338728)
		(width 0.1143)
		(layer "In11.Cu")
		(net "P5E_PEX0_STN4_TX_DN<68>")
	)
	(segment
		(start 94.795848 -317.462408)
		(end 93.087444 -315.754004)
		(width 0.1651)
		(layer "In11.Cu")
		(net "P5E_PEX0_STN4_TX_DN<68>")
	)
	(segment
		(start 48.033432 -338.814664)
		(end 57.243218 -335.519522)
		(width 0.1651)
		(layer "In11.Cu")
		(net "P5E_PEX0_STN4_TX_DN<68>")
	)
	(segment
		(start 83.59648 -308.629558)
		(end 75.58532 -308.629558)
		(width 0.1143)
		(layer "In11.Cu")
		(net "P5E_PEX0_STN4_TX_DN<68>")
	)
	(segment
		(start 84.734146 -308.93639)
		(end 83.882992 -308.583838)
		(width 0.1651)
		(layer "In11.Cu")
		(net "P5E_PEX0_STN4_TX_DN<68>")
	)
	(segment
		(start 44.776898 -341.252302)
		(end 46.273974 -339.755226)
		(width 0.1651)
		(layer "In11.Cu")
		(net "P5E_PEX0_STN4_TX_DN<68>")
	)
	(segment
		(start 83.882992 -308.583838)
		(end 83.670648 -308.583838)
		(width 0.1651)
		(layer "In11.Cu")
		(net "P5E_PEX0_STN4_TX_DN<68>")
	)
	(segment
		(start 45.067728 -342.439498)
		(end 44.776898 -342.148668)
		(width 0.1651)
		(layer "In11.Cu")
		(net "P5E_PEX0_STN4_TX_DN<68>")
	)
	(segment
		(start 75.58532 -308.629558)
		(end 75.42022 -308.464458)
		(width 0.1143)
		(layer "In11.Cu")
		(net "P5E_PEX0_STN4_TX_DN<68>")
	)
	(segment
		(start 92.33281 -326.386698)
		(end 93.434154 -325.79818)
		(width 0.1651)
		(layer "In11.Cu")
		(net "P5E_PEX0_STN4_TX_DN<68>")
	)
	(segment
		(start 75.50912 -308.249828)
		(end 75.79995 -308.249828)
		(width 0.1143)
		(layer "In11.Cu")
		(net "P5E_PEX0_STN4_TX_DN<68>")
	)
	(segment
		(start 294.933878 -379.612398)
		(end 294.933878 -369.697)
		(width 0.1651)
		(layer "In15.Cu")
		(net "P5E_PEX2_STN4_RX_DP<68>")
	)
	(segment
		(start 298.040806 -365.79683)
		(end 298.035726 -365.653066)
		(width 0.1651)
		(layer "In15.Cu")
		(net "P5E_PEX2_STN4_RX_DP<68>")
	)
	(segment
		(start 326.7456 -319.085468)
		(end 326.306942 -318.026542)
		(width 0.1651)
		(layer "In15.Cu")
		(net "P5E_PEX2_STN4_RX_DP<68>")
	)
	(segment
		(start 326.14362 -323.39661)
		(end 326.7456 -321.943222)
		(width 0.1651)
		(layer "In15.Cu")
		(net "P5E_PEX2_STN4_RX_DP<68>")
	)
	(segment
		(start 306.197254 -352.638614)
		(end 306.36972 -352.174048)
		(width 0.1651)
		(layer "In15.Cu")
		(net "P5E_PEX2_STN4_RX_DP<68>")
	)
	(segment
		(start 296.413174 -367.544096)
		(end 296.40784 -367.400332)
		(width 0.1651)
		(layer "In15.Cu")
		(net "P5E_PEX2_STN4_RX_DP<68>")
	)
	(segment
		(start 294.089836 -379.772164)
		(end 294.216836 -379.899164)
		(width 0.1651)
		(layer "In15.Cu")
		(net "P5E_PEX2_STN4_RX_DP<68>")
	)
	(segment
		(start 296.889424 -367.03254)
		(end 297.22699 -366.670336)
		(width 0.1651)
		(layer "In15.Cu")
		(net "P5E_PEX2_STN4_RX_DP<68>")
	)
	(segment
		(start 305.669442 -354.351082)
		(end 305.669188 -354.351082)
		(width 0.1651)
		(layer "In15.Cu")
		(net "P5E_PEX2_STN4_RX_DP<68>")
	)
	(segment
		(start 296.745914 -367.03762)
		(end 296.889424 -367.03254)
		(width 0.1651)
		(layer "In15.Cu")
		(net "P5E_PEX2_STN4_RX_DP<68>")
	)
	(segment
		(start 305.8414 -353.888548)
		(end 305.781456 -353.757738)
		(width 0.1651)
		(layer "In15.Cu")
		(net "P5E_PEX2_STN4_RX_DP<68>")
	)
	(segment
		(start 310.780176 -340.591902)
		(end 310.78043 -340.591902)
		(width 0.1651)
		(layer "In15.Cu")
		(net "P5E_PEX2_STN4_RX_DP<68>")
	)
	(segment
		(start 297.70324 -366.159034)
		(end 298.040806 -365.79683)
		(width 0.1651)
		(layer "In15.Cu")
		(net "P5E_PEX2_STN4_RX_DP<68>")
	)
	(segment
		(start 310.78043 -340.591902)
		(end 326.14362 -323.39661)
		(width 0.1651)
		(layer "In15.Cu")
		(net "P5E_PEX2_STN4_RX_DP<68>")
	)
	(segment
		(start 313.965336 -308.249828)
		(end 313.699906 -308.249828)
		(width 0.1143)
		(layer "In15.Cu")
		(net "P5E_PEX2_STN4_RX_DP<68>")
	)
	(segment
		(start 306.50053 -352.114358)
		(end 306.500022 -352.114104)
		(width 0.1651)
		(layer "In15.Cu")
		(net "P5E_PEX2_STN4_RX_DP<68>")
	)
	(segment
		(start 305.953922 -353.293172)
		(end 306.084732 -353.233482)
		(width 0.1651)
		(layer "In15.Cu")
		(net "P5E_PEX2_STN4_RX_DP<68>")
	)
	(segment
		(start 305.781456 -353.757738)
		(end 305.953922 -353.293172)
		(width 0.1651)
		(layer "In15.Cu")
		(net "P5E_PEX2_STN4_RX_DP<68>")
	)
	(segment
		(start 315.852048 -308.865778)
		(end 315.8236 -308.865778)
		(width 0.1143)
		(layer "In15.Cu")
		(net "P5E_PEX2_STN4_RX_DP<68>")
	)
	(segment
		(start 298.035726 -365.653066)
		(end 298.373546 -365.290608)
		(width 0.1651)
		(layer "In15.Cu")
		(net "P5E_PEX2_STN4_RX_DP<68>")
	)
	(segment
		(start 294.089836 -379.390148)
		(end 294.089836 -379.772164)
		(width 0.1651)
		(layer "In15.Cu")
		(net "P5E_PEX2_STN4_RX_DP<68>")
	)
	(segment
		(start 306.257198 -352.769424)
		(end 306.197254 -352.638614)
		(width 0.1651)
		(layer "In15.Cu")
		(net "P5E_PEX2_STN4_RX_DP<68>")
	)
	(segment
		(start 297.22191 -366.526572)
		(end 297.55973 -366.164114)
		(width 0.1651)
		(layer "In15.Cu")
		(net "P5E_PEX2_STN4_RX_DP<68>")
	)
	(segment
		(start 326.306942 -318.026542)
		(end 317.146178 -308.865778)
		(width 0.1651)
		(layer "In15.Cu")
		(net "P5E_PEX2_STN4_RX_DP<68>")
	)
	(segment
		(start 326.7456 -321.943222)
		(end 326.7456 -319.085468)
		(width 0.1651)
		(layer "In15.Cu")
		(net "P5E_PEX2_STN4_RX_DP<68>")
	)
	(segment
		(start 314.294774 -308.820058)
		(end 314.079636 -308.60492)
		(width 0.1143)
		(layer "In15.Cu")
		(net "P5E_PEX2_STN4_RX_DP<68>")
	)
	(segment
		(start 294.647112 -379.899164)
		(end 294.933878 -379.612398)
		(width 0.1651)
		(layer "In15.Cu")
		(net "P5E_PEX2_STN4_RX_DP<68>")
	)
	(segment
		(start 305.668934 -354.352606)
		(end 305.669442 -354.351082)
		(width 0.1651)
		(layer "In15.Cu")
		(net "P5E_PEX2_STN4_RX_DP<68>")
	)
	(segment
		(start 306.084732 -353.233482)
		(end 306.084224 -353.233482)
		(width 0.1651)
		(layer "In15.Cu")
		(net "P5E_PEX2_STN4_RX_DP<68>")
	)
	(segment
		(start 303.657 -359.76814)
		(end 305.425348 -355.007672)
		(width 0.1651)
		(layer "In15.Cu")
		(net "P5E_PEX2_STN4_RX_DP<68>")
	)
	(segment
		(start 317.146178 -308.865778)
		(end 315.852048 -308.865778)
		(width 0.1651)
		(layer "In15.Cu")
		(net "P5E_PEX2_STN4_RX_DP<68>")
	)
	(segment
		(start 297.22699 -366.670336)
		(end 297.22191 -366.526572)
		(width 0.1651)
		(layer "In15.Cu")
		(net "P5E_PEX2_STN4_RX_DP<68>")
	)
	(segment
		(start 294.933878 -369.697)
		(end 295.282366 -368.757708)
		(width 0.1651)
		(layer "In15.Cu")
		(net "P5E_PEX2_STN4_RX_DP<68>")
	)
	(segment
		(start 305.669188 -354.351082)
		(end 305.840892 -353.888294)
		(width 0.1651)
		(layer "In15.Cu")
		(net "P5E_PEX2_STN4_RX_DP<68>")
	)
	(segment
		(start 315.77788 -308.820058)
		(end 314.294774 -308.820058)
		(width 0.1143)
		(layer "In15.Cu")
		(net "P5E_PEX2_STN4_RX_DP<68>")
	)
	(segment
		(start 298.517056 -365.285528)
		(end 303.657 -359.76814)
		(width 0.1651)
		(layer "In15.Cu")
		(net "P5E_PEX2_STN4_RX_DP<68>")
	)
	(segment
		(start 296.40784 -367.400332)
		(end 296.745914 -367.03762)
		(width 0.1651)
		(layer "In15.Cu")
		(net "P5E_PEX2_STN4_RX_DP<68>")
	)
	(segment
		(start 294.216836 -379.899164)
		(end 294.647112 -379.899164)
		(width 0.1651)
		(layer "In15.Cu")
		(net "P5E_PEX2_STN4_RX_DP<68>")
	)
	(segment
		(start 306.084224 -353.233482)
		(end 306.25669 -352.76917)
		(width 0.1651)
		(layer "In15.Cu")
		(net "P5E_PEX2_STN4_RX_DP<68>")
	)
	(segment
		(start 306.25669 -352.76917)
		(end 306.257198 -352.769424)
		(width 0.1651)
		(layer "In15.Cu")
		(net "P5E_PEX2_STN4_RX_DP<68>")
	)
	(segment
		(start 306.36972 -352.174048)
		(end 306.50053 -352.114358)
		(width 0.1651)
		(layer "In15.Cu")
		(net "P5E_PEX2_STN4_RX_DP<68>")
	)
	(segment
		(start 314.079636 -308.364128)
		(end 313.965336 -308.249828)
		(width 0.1143)
		(layer "In15.Cu")
		(net "P5E_PEX2_STN4_RX_DP<68>")
	)
	(segment
		(start 306.500022 -352.114104)
		(end 310.780176 -340.591902)
		(width 0.1651)
		(layer "In15.Cu")
		(net "P5E_PEX2_STN4_RX_DP<68>")
	)
	(segment
		(start 315.8236 -308.865778)
		(end 315.77788 -308.820058)
		(width 0.1143)
		(layer "In15.Cu")
		(net "P5E_PEX2_STN4_RX_DP<68>")
	)
	(segment
		(start 297.55973 -366.164114)
		(end 297.70324 -366.159034)
		(width 0.1651)
		(layer "In15.Cu")
		(net "P5E_PEX2_STN4_RX_DP<68>")
	)
	(segment
		(start 305.53787 -354.412296)
		(end 305.668934 -354.352606)
		(width 0.1651)
		(layer "In15.Cu")
		(net "P5E_PEX2_STN4_RX_DP<68>")
	)
	(segment
		(start 295.282366 -368.757708)
		(end 296.413174 -367.544096)
		(width 0.1651)
		(layer "In15.Cu")
		(net "P5E_PEX2_STN4_RX_DP<68>")
	)
	(segment
		(start 298.373546 -365.290608)
		(end 298.517056 -365.285528)
		(width 0.1651)
		(layer "In15.Cu")
		(net "P5E_PEX2_STN4_RX_DP<68>")
	)
	(segment
		(start 305.840892 -353.888294)
		(end 305.8414 -353.888548)
		(width 0.1651)
		(layer "In15.Cu")
		(net "P5E_PEX2_STN4_RX_DP<68>")
	)
	(segment
		(start 314.079636 -308.60492)
		(end 314.079636 -308.364128)
		(width 0.1143)
		(layer "In15.Cu")
		(net "P5E_PEX2_STN4_RX_DP<68>")
	)
	(segment
		(start 305.365404 -354.876862)
		(end 305.53787 -354.412296)
		(width 0.1651)
		(layer "In15.Cu")
		(net "P5E_PEX2_STN4_RX_DP<68>")
	)
	(segment
		(start 305.425348 -355.007672)
		(end 305.365404 -354.876862)
		(width 0.1651)
		(layer "In15.Cu")
		(net "P5E_PEX2_STN4_RX_DP<68>")
	)
	(segment
		(start 27.040332 -392.146028)
		(end 23.487126 -389.77189)
		(width 0.1651)
		(layer "In15.Cu")
		(net "P5E_PEX0_STN4_RX_DN<78>")
	)
	(segment
		(start 74.51598 -321.21602)
		(end 74.51598 -319.916048)
		(width 0.1651)
		(layer "In15.Cu")
		(net "P5E_PEX0_STN4_RX_DN<78>")
	)
	(segment
		(start 74.47026 -319.84188)
		(end 74.47026 -318.434466)
		(width 0.1143)
		(layer "In15.Cu")
		(net "P5E_PEX0_STN4_RX_DN<78>")
	)
	(segment
		(start 17.95399 -339.505798)
		(end 18.444464 -339.21192)
		(width 0.1651)
		(layer "In15.Cu")
		(net "P5E_PEX0_STN4_RX_DN<78>")
	)
	(segment
		(start 21.882354 -388.167118)
		(end 20.756626 -385.449064)
		(width 0.1651)
		(layer "In15.Cu")
		(net "P5E_PEX0_STN4_RX_DN<78>")
	)
	(segment
		(start 30.587442 -406.181052)
		(end 31.266892 -405.501602)
		(width 0.1651)
		(layer "In15.Cu")
		(net "P5E_PEX0_STN4_RX_DN<78>")
	)
	(segment
		(start 20.756626 -385.449064)
		(end 19.92376 -376.99569)
		(width 0.1651)
		(layer "In15.Cu")
		(net "P5E_PEX0_STN4_RX_DN<78>")
	)
	(segment
		(start 16.37792 -353.09175)
		(end 16.37792 -341.992712)
		(width 0.1651)
		(layer "In15.Cu")
		(net "P5E_PEX0_STN4_RX_DN<78>")
	)
	(segment
		(start 31.266892 -395.977364)
		(end 31.013654 -395.365732)
		(width 0.1651)
		(layer "In15.Cu")
		(net "P5E_PEX0_STN4_RX_DN<78>")
	)
	(segment
		(start 68.3895 -324.155308)
		(end 73.830434 -321.901566)
		(width 0.1651)
		(layer "In15.Cu")
		(net "P5E_PEX0_STN4_RX_DN<78>")
	)
	(segment
		(start 28.60421 -392.793982)
		(end 27.040332 -392.146028)
		(width 0.1651)
		(layer "In15.Cu")
		(net "P5E_PEX0_STN4_RX_DN<78>")
	)
	(segment
		(start 18.444464 -339.21192)
		(end 27.52471 -335.191862)
		(width 0.1651)
		(layer "In15.Cu")
		(net "P5E_PEX0_STN4_RX_DN<78>")
	)
	(segment
		(start 74.58456 -318.320166)
		(end 74.73569 -318.320166)
		(width 0.1143)
		(layer "In15.Cu")
		(net "P5E_PEX0_STN4_RX_DN<78>")
	)
	(segment
		(start 30.109922 -406.308052)
		(end 30.236922 -406.181052)
		(width 0.1651)
		(layer "In15.Cu")
		(net "P5E_PEX0_STN4_RX_DN<78>")
	)
	(segment
		(start 74.73569 -318.320166)
		(end 74.84999 -318.434466)
		(width 0.1143)
		(layer "In15.Cu")
		(net "P5E_PEX0_STN4_RX_DN<78>")
	)
	(segment
		(start 74.51598 -319.916048)
		(end 74.51598 -319.8876)
		(width 0.1143)
		(layer "In15.Cu")
		(net "P5E_PEX0_STN4_RX_DN<78>")
	)
	(segment
		(start 31.013654 -395.365732)
		(end 30.686248 -394.87602)
		(width 0.1651)
		(layer "In15.Cu")
		(net "P5E_PEX0_STN4_RX_DN<78>")
	)
	(segment
		(start 74.47026 -318.434466)
		(end 74.58456 -318.320166)
		(width 0.1143)
		(layer "In15.Cu")
		(net "P5E_PEX0_STN4_RX_DN<78>")
	)
	(segment
		(start 30.109922 -406.690068)
		(end 30.109922 -406.308052)
		(width 0.1651)
		(layer "In15.Cu")
		(net "P5E_PEX0_STN4_RX_DN<78>")
	)
	(segment
		(start 74.84999 -318.434466)
		(end 74.84999 -318.699896)
		(width 0.1143)
		(layer "In15.Cu")
		(net "P5E_PEX0_STN4_RX_DN<78>")
	)
	(segment
		(start 19.92376 -376.99569)
		(end 16.37792 -353.09175)
		(width 0.1651)
		(layer "In15.Cu")
		(net "P5E_PEX0_STN4_RX_DN<78>")
	)
	(segment
		(start 43.32986 -330.408026)
		(end 68.3895 -324.155308)
		(width 0.1651)
		(layer "In15.Cu")
		(net "P5E_PEX0_STN4_RX_DN<78>")
	)
	(segment
		(start 31.266892 -405.501602)
		(end 31.266892 -395.977364)
		(width 0.1651)
		(layer "In15.Cu")
		(net "P5E_PEX0_STN4_RX_DN<78>")
	)
	(segment
		(start 16.37792 -341.992712)
		(end 17.022064 -340.437724)
		(width 0.1651)
		(layer "In15.Cu")
		(net "P5E_PEX0_STN4_RX_DN<78>")
	)
	(segment
		(start 74.51598 -319.8876)
		(end 74.47026 -319.84188)
		(width 0.1143)
		(layer "In15.Cu")
		(net "P5E_PEX0_STN4_RX_DN<78>")
	)
	(segment
		(start 23.487126 -389.77189)
		(end 21.882354 -388.167118)
		(width 0.1651)
		(layer "In15.Cu")
		(net "P5E_PEX0_STN4_RX_DN<78>")
	)
	(segment
		(start 27.52471 -335.191862)
		(end 43.32986 -330.408026)
		(width 0.1651)
		(layer "In15.Cu")
		(net "P5E_PEX0_STN4_RX_DN<78>")
	)
	(segment
		(start 30.686248 -394.87602)
		(end 28.60421 -392.793982)
		(width 0.1651)
		(layer "In15.Cu")
		(net "P5E_PEX0_STN4_RX_DN<78>")
	)
	(segment
		(start 73.830434 -321.901566)
		(end 74.51598 -321.21602)
		(width 0.1651)
		(layer "In15.Cu")
		(net "P5E_PEX0_STN4_RX_DN<78>")
	)
	(segment
		(start 30.236922 -406.181052)
		(end 30.587442 -406.181052)
		(width 0.1651)
		(layer "In15.Cu")
		(net "P5E_PEX0_STN4_RX_DN<78>")
	)
	(segment
		(start 17.022064 -340.437724)
		(end 17.95399 -339.505798)
		(width 0.1651)
		(layer "In15.Cu")
		(net "P5E_PEX0_STN4_RX_DN<78>")
	)
	(segment
		(start 296.446702 -351.316798)
		(end 296.741342 -351.611438)
		(width 0.13462)
		(layer "F.Cu")
		(net "P5E_PEX2_STN4_TX_C_DN<66>")
	)
	(segment
		(start 296.766742 -350.365314)
		(end 296.446702 -350.685354)
		(width 0.13462)
		(layer "F.Cu")
		(net "P5E_PEX2_STN4_TX_C_DN<66>")
	)
	(segment
		(start 296.446702 -350.685354)
		(end 296.446702 -351.316798)
		(width 0.13462)
		(layer "F.Cu")
		(net "P5E_PEX2_STN4_TX_C_DN<66>")
	)
	(segment
		(start 299.61586 -368.75974)
		(end 299.61586 -371.929152)
		(width 0.1651)
		(layer "In11.Cu")
		(net "P5E_PEX2_STN4_TX_C_DN<66>")
	)
	(segment
		(start 296.450512 -351.902268)
		(end 296.450512 -352.473006)
		(width 0.1651)
		(layer "In11.Cu")
		(net "P5E_PEX2_STN4_TX_C_DN<66>")
	)
	(segment
		(start 299.163994 -372.381018)
		(end 298.616878 -372.381018)
		(width 0.1651)
		(layer "In11.Cu")
		(net "P5E_PEX2_STN4_TX_C_DN<66>")
	)
	(segment
		(start 294.896032 -354.027486)
		(end 294.896032 -358.902)
		(width 0.1651)
		(layer "In11.Cu")
		(net "P5E_PEX2_STN4_TX_C_DN<66>")
	)
	(segment
		(start 294.896032 -358.902)
		(end 299.61586 -368.75974)
		(width 0.1651)
		(layer "In11.Cu")
		(net "P5E_PEX2_STN4_TX_C_DN<66>")
	)
	(segment
		(start 299.61586 -371.929152)
		(end 299.163994 -372.381018)
		(width 0.1651)
		(layer "In11.Cu")
		(net "P5E_PEX2_STN4_TX_C_DN<66>")
	)
	(segment
		(start 296.741342 -351.611438)
		(end 296.450512 -351.902268)
		(width 0.1651)
		(layer "In11.Cu")
		(net "P5E_PEX2_STN4_TX_C_DN<66>")
	)
	(segment
		(start 298.489878 -372.508018)
		(end 298.489878 -372.890034)
		(width 0.1651)
		(layer "In11.Cu")
		(net "P5E_PEX2_STN4_TX_C_DN<66>")
	)
	(segment
		(start 296.450512 -352.473006)
		(end 294.896032 -354.027486)
		(width 0.1651)
		(layer "In11.Cu")
		(net "P5E_PEX2_STN4_TX_C_DN<66>")
	)
	(segment
		(start 298.616878 -372.381018)
		(end 298.489878 -372.508018)
		(width 0.1651)
		(layer "In11.Cu")
		(net "P5E_PEX2_STN4_TX_C_DN<66>")
	)
	(segment
		(start 188.099954 -303.499774)
		(end 188.574934 -303.974754)
		(width 0.249936)
		(layer "F.Cu")
		(net "Net_5231")
	)
	(via
		(at 188.574934 -303.974754)
		(size 0.4064)
		(drill 0.2032)
		(layers "F.Cu" "B.Cu")
		(net "Net_5231")
	)
	(segment
		(start 152.94991 -292.099746)
		(end 152.47493 -291.624766)
		(width 0.13208)
		(layer "F.Cu")
		(net "Net_5232")
	)
	(via
		(at 152.47493 -291.624766)
		(size 0.4064)
		(drill 0.2032)
		(layers "F.Cu" "B.Cu")
		(net "Net_5232")
	)
	(segment
		(start 153.89987 -292.099746)
		(end 153.42489 -291.624766)
		(width 0.13208)
		(layer "F.Cu")
		(net "Net_5233")
	)
	(via
		(at 153.42489 -291.624766)
		(size 0.4064)
		(drill 0.2032)
		(layers "F.Cu" "B.Cu")
		(net "Net_5233")
	)
	(segment
		(start 188.099954 -289.249866)
		(end 188.574934 -288.774886)
		(width 0.13208)
		(layer "F.Cu")
		(net "Net_5236")
	)
	(via
		(at 188.574934 -288.774886)
		(size 0.4064)
		(drill 0.2032)
		(layers "F.Cu" "B.Cu")
		(net "Net_5236")
	)
	(segment
		(start 189.049914 -292.099746)
		(end 189.524894 -291.624766)
		(width 0.13208)
		(layer "F.Cu")
		(net "Net_5238")
	)
	(via
		(at 189.524894 -291.624766)
		(size 0.4064)
		(drill 0.2032)
		(layers "F.Cu" "B.Cu")
		(net "Net_5238")
	)
	(segment
		(start 166.249858 -283.549852)
		(end 165.774878 -283.074872)
		(width 0.13208)
		(layer "F.Cu")
		(net "Net_5244")
	)
	(via
		(at 165.774878 -283.074872)
		(size 0.4064)
		(drill 0.2032)
		(layers "F.Cu" "B.Cu")
		(net "Net_5244")
	)
	(segment
		(start 170.049952 -283.549852)
		(end 169.574972 -283.074872)
		(width 0.13208)
		(layer "F.Cu")
		(net "Net_5245")
	)
	(via
		(at 169.574972 -283.074872)
		(size 0.4064)
		(drill 0.2032)
		(layers "F.Cu" "B.Cu")
		(net "Net_5245")
	)
	(segment
		(start 169.099992 -283.549852)
		(end 168.625012 -283.074872)
		(width 0.13208)
		(layer "F.Cu")
		(net "Net_5249")
	)
	(via
		(at 168.625012 -283.074872)
		(size 0.4064)
		(drill 0.2032)
		(layers "F.Cu" "B.Cu")
		(net "Net_5249")
	)
	(segment
		(start 165.299898 -283.549852)
		(end 164.824918 -283.074872)
		(width 0.13208)
		(layer "F.Cu")
		(net "Net_5250")
	)
	(via
		(at 164.824918 -283.074872)
		(size 0.4064)
		(drill 0.2032)
		(layers "F.Cu" "B.Cu")
		(net "Net_5250")
	)
	(segment
		(start 167.200072 -283.549852)
		(end 166.725092 -283.074872)
		(width 0.13208)
		(layer "F.Cu")
		(net "Net_5253")
	)
	(via
		(at 166.725092 -283.074872)
		(size 0.4064)
		(drill 0.2032)
		(layers "F.Cu" "B.Cu")
		(net "Net_5253")
	)
	(segment
		(start 168.150032 -283.549852)
		(end 167.675052 -283.074872)
		(width 0.13208)
		(layer "F.Cu")
		(net "Net_5254")
	)
	(via
		(at 167.675052 -283.074872)
		(size 0.4064)
		(drill 0.2032)
		(layers "F.Cu" "B.Cu")
		(net "Net_5254")
	)
	(segment
		(start 163.399978 -283.549852)
		(end 162.924998 -283.074872)
		(width 0.13208)
		(layer "F.Cu")
		(net "Net_5258")
	)
	(via
		(at 162.924998 -283.074872)
		(size 0.4064)
		(drill 0.2032)
		(layers "F.Cu" "B.Cu")
		(net "Net_5258")
	)
	(segment
		(start 164.349938 -283.549852)
		(end 163.874958 -283.074872)
		(width 0.13208)
		(layer "F.Cu")
		(net "Net_5259")
	)
	(via
		(at 163.874958 -283.074872)
		(size 0.4064)
		(drill 0.2032)
		(layers "F.Cu" "B.Cu")
		(net "Net_5259")
	)
	(segment
		(start 186.200034 -282.599892)
		(end 186.675014 -283.074872)
		(width 0.13208)
		(layer "F.Cu")
		(net "Net_5263")
	)
	(via
		(at 186.675014 -283.074872)
		(size 0.4064)
		(drill 0.2032)
		(layers "F.Cu" "B.Cu")
		(net "Net_5263")
	)
	(segment
		(start 185.250074 -283.549852)
		(end 185.725054 -283.074872)
		(width 0.13208)
		(layer "F.Cu")
		(net "Net_5264")
	)
	(via
		(at 185.725054 -283.074872)
		(size 0.4064)
		(drill 0.2032)
		(layers "F.Cu" "B.Cu")
		(net "Net_5264")
	)
	(segment
		(start 187.149994 -282.599892)
		(end 187.624974 -283.074872)
		(width 0.13208)
		(layer "F.Cu")
		(net "Net_5267")
	)
	(via
		(at 187.624974 -283.074872)
		(size 0.4064)
		(drill 0.2032)
		(layers "F.Cu" "B.Cu")
		(net "Net_5267")
	)
	(segment
		(start 188.099954 -290.199826)
		(end 188.574934 -289.724846)
		(width 0.13208)
		(layer "F.Cu")
		(net "Net_5269")
	)
	(via
		(at 188.574934 -289.724846)
		(size 0.4064)
		(drill 0.2032)
		(layers "F.Cu" "B.Cu")
		(net "Net_5269")
	)
	(segment
		(start 180.50002 -308.249828)
		(end 180.02504 -308.724808)
		(width 0.127)
		(layer "F.Cu")
		(net "Net_5272")
	)
	(via
		(at 180.02504 -308.724808)
		(size 0.4064)
		(drill 0.2032)
		(layers "F.Cu" "B.Cu")
		(net "Net_5272")
	)
	(segment
		(start 184.29986 -308.249828)
		(end 183.82488 -308.724808)
		(width 0.127)
		(layer "F.Cu")
		(net "Net_5281")
	)
	(via
		(at 183.82488 -308.724808)
		(size 0.4064)
		(drill 0.2032)
		(layers "F.Cu" "B.Cu")
		(net "Net_5281")
	)
	(segment
		(start 182.39994 -308.249828)
		(end 181.92496 -308.724808)
		(width 0.127)
		(layer "F.Cu")
		(net "Net_5283")
	)
	(via
		(at 181.92496 -308.724808)
		(size 0.4064)
		(drill 0.2032)
		(layers "F.Cu" "B.Cu")
		(net "Net_5283")
	)
	(segment
		(start 171.949872 -283.549852)
		(end 171.474892 -283.074872)
		(width 0.13208)
		(layer "F.Cu")
		(net "Net_5284")
	)
	(via
		(at 171.474892 -283.074872)
		(size 0.4064)
		(drill 0.2032)
		(layers "F.Cu" "B.Cu")
		(net "Net_5284")
	)
	(segment
		(start 172.900086 -283.549852)
		(end 172.425106 -283.074872)
		(width 0.13208)
		(layer "F.Cu")
		(net "Net_5285")
	)
	(via
		(at 172.425106 -283.074872)
		(size 0.4064)
		(drill 0.2032)
		(layers "F.Cu" "B.Cu")
		(net "Net_5285")
	)
	(segment
		(start 173.850046 -283.549852)
		(end 173.375066 -283.074872)
		(width 0.13208)
		(layer "F.Cu")
		(net "Net_5287")
	)
	(via
		(at 173.375066 -283.074872)
		(size 0.4064)
		(drill 0.2032)
		(layers "F.Cu" "B.Cu")
		(net "Net_5287")
	)
	(segment
		(start 172.900086 -309.199788)
		(end 172.425106 -308.724808)
		(width 0.127)
		(layer "F.Cu")
		(net "Net_5289")
	)
	(via
		(at 172.425106 -308.724808)
		(size 0.4064)
		(drill 0.2032)
		(layers "F.Cu" "B.Cu")
		(net "Net_5289")
	)
	(segment
		(start 172.900086 -308.249828)
		(end 172.425106 -307.774848)
		(width 0.127)
		(layer "F.Cu")
		(net "Net_5291")
	)
	(via
		(at 172.425106 -307.774848)
		(size 0.4064)
		(drill 0.2032)
		(layers "F.Cu" "B.Cu")
		(net "Net_5291")
	)
	(segment
		(start 173.850046 -308.249828)
		(end 173.375066 -307.774848)
		(width 0.127)
		(layer "F.Cu")
		(net "Net_5292")
	)
	(via
		(at 173.375066 -307.774848)
		(size 0.4064)
		(drill 0.2032)
		(layers "F.Cu" "B.Cu")
		(net "Net_5292")
	)
	(segment
		(start 173.850046 -309.199788)
		(end 174.325026 -308.724808)
		(width 0.13208)
		(layer "F.Cu")
		(net "Net_5293")
	)
	(via
		(at 174.325026 -308.724808)
		(size 0.4064)
		(drill 0.2032)
		(layers "F.Cu" "B.Cu")
		(net "Net_5293")
	)
	(segment
		(start 174.800006 -308.249828)
		(end 174.325026 -307.774848)
		(width 0.127)
		(layer "F.Cu")
		(net "Net_5294")
	)
	(via
		(at 174.325026 -307.774848)
		(size 0.4064)
		(drill 0.2032)
		(layers "F.Cu" "B.Cu")
		(net "Net_5294")
	)
	(segment
		(start 187.149994 -308.249828)
		(end 186.675014 -308.724808)
		(width 0.127)
		(layer "F.Cu")
		(net "Net_5299")
	)
	(via
		(at 186.675014 -308.724808)
		(size 0.4064)
		(drill 0.2032)
		(layers "F.Cu" "B.Cu")
		(net "Net_5299")
	)
	(segment
		(start 186.200034 -308.249828)
		(end 185.725054 -308.724808)
		(width 0.127)
		(layer "F.Cu")
		(net "Net_5300")
	)
	(via
		(at 185.725054 -308.724808)
		(size 0.4064)
		(drill 0.2032)
		(layers "F.Cu" "B.Cu")
		(net "Net_5300")
	)
	(segment
		(start 158.649924 -291.149786)
		(end 158.174944 -290.674806)
		(width 0.13208)
		(layer "F.Cu")
		(net "Net_5302")
	)
	(via
		(at 158.174944 -290.674806)
		(size 0.4064)
		(drill 0.2032)
		(layers "F.Cu" "B.Cu")
		(net "Net_5302")
	)
	(segment
		(start 159.599884 -292.099746)
		(end 159.124904 -291.624766)
		(width 0.13208)
		(layer "F.Cu")
		(net "Net_5303")
	)
	(via
		(at 159.124904 -291.624766)
		(size 0.4064)
		(drill 0.2032)
		(layers "F.Cu" "B.Cu")
		(net "Net_5303")
	)
	(segment
		(start 304.199798 -303.499774)
		(end 304.674778 -303.974754)
		(width 0.249936)
		(layer "F.Cu")
		(net "Net_5321")
	)
	(via
		(at 304.674778 -303.974754)
		(size 0.4064)
		(drill 0.2032)
		(layers "F.Cu" "B.Cu")
		(net "Net_5321")
	)
	(segment
		(start 269.049754 -292.099746)
		(end 268.574774 -291.624766)
		(width 0.13208)
		(layer "F.Cu")
		(net "Net_5322")
	)
	(via
		(at 268.574774 -291.624766)
		(size 0.4064)
		(drill 0.2032)
		(layers "F.Cu" "B.Cu")
		(net "Net_5322")
	)
	(segment
		(start 269.999714 -292.099746)
		(end 269.524734 -291.624766)
		(width 0.13208)
		(layer "F.Cu")
		(net "Net_5323")
	)
	(via
		(at 269.524734 -291.624766)
		(size 0.4064)
		(drill 0.2032)
		(layers "F.Cu" "B.Cu")
		(net "Net_5323")
	)
	(segment
		(start 304.199798 -289.249866)
		(end 304.674778 -288.774886)
		(width 0.13208)
		(layer "F.Cu")
		(net "Net_5326")
	)
	(via
		(at 304.674778 -288.774886)
		(size 0.4064)
		(drill 0.2032)
		(layers "F.Cu" "B.Cu")
		(net "Net_5326")
	)
	(segment
		(start 305.149758 -292.099746)
		(end 305.624738 -291.624766)
		(width 0.13208)
		(layer "F.Cu")
		(net "Net_5328")
	)
	(via
		(at 305.624738 -291.624766)
		(size 0.4064)
		(drill 0.2032)
		(layers "F.Cu" "B.Cu")
		(net "Net_5328")
	)
	(segment
		(start 282.349702 -283.549852)
		(end 281.874722 -283.074872)
		(width 0.13208)
		(layer "F.Cu")
		(net "Net_5334")
	)
	(via
		(at 281.874722 -283.074872)
		(size 0.4064)
		(drill 0.2032)
		(layers "F.Cu" "B.Cu")
		(net "Net_5334")
	)
	(segment
		(start 286.149796 -283.549852)
		(end 285.674816 -283.074872)
		(width 0.13208)
		(layer "F.Cu")
		(net "Net_5335")
	)
	(via
		(at 285.674816 -283.074872)
		(size 0.4064)
		(drill 0.2032)
		(layers "F.Cu" "B.Cu")
		(net "Net_5335")
	)
	(segment
		(start 285.199836 -283.549852)
		(end 284.724856 -283.074872)
		(width 0.13208)
		(layer "F.Cu")
		(net "Net_5339")
	)
	(via
		(at 284.724856 -283.074872)
		(size 0.4064)
		(drill 0.2032)
		(layers "F.Cu" "B.Cu")
		(net "Net_5339")
	)
	(segment
		(start 281.399742 -283.549852)
		(end 280.924762 -283.074872)
		(width 0.13208)
		(layer "F.Cu")
		(net "Net_5340")
	)
	(via
		(at 280.924762 -283.074872)
		(size 0.4064)
		(drill 0.2032)
		(layers "F.Cu" "B.Cu")
		(net "Net_5340")
	)
	(segment
		(start 283.299916 -283.549852)
		(end 282.824936 -283.074872)
		(width 0.13208)
		(layer "F.Cu")
		(net "Net_5343")
	)
	(via
		(at 282.824936 -283.074872)
		(size 0.4064)
		(drill 0.2032)
		(layers "F.Cu" "B.Cu")
		(net "Net_5343")
	)
	(segment
		(start 284.249876 -283.549852)
		(end 283.774896 -283.074872)
		(width 0.13208)
		(layer "F.Cu")
		(net "Net_5344")
	)
	(via
		(at 283.774896 -283.074872)
		(size 0.4064)
		(drill 0.2032)
		(layers "F.Cu" "B.Cu")
		(net "Net_5344")
	)
	(segment
		(start 279.499822 -283.549852)
		(end 279.024842 -283.074872)
		(width 0.13208)
		(layer "F.Cu")
		(net "Net_5348")
	)
	(via
		(at 279.024842 -283.074872)
		(size 0.4064)
		(drill 0.2032)
		(layers "F.Cu" "B.Cu")
		(net "Net_5348")
	)
	(segment
		(start 280.449782 -283.549852)
		(end 279.974802 -283.074872)
		(width 0.13208)
		(layer "F.Cu")
		(net "Net_5349")
	)
	(via
		(at 279.974802 -283.074872)
		(size 0.4064)
		(drill 0.2032)
		(layers "F.Cu" "B.Cu")
		(net "Net_5349")
	)
	(segment
		(start 302.299878 -282.599892)
		(end 302.774858 -283.074872)
		(width 0.13208)
		(layer "F.Cu")
		(net "Net_5353")
	)
	(via
		(at 302.774858 -283.074872)
		(size 0.4064)
		(drill 0.2032)
		(layers "F.Cu" "B.Cu")
		(net "Net_5353")
	)
	(segment
		(start 301.349918 -283.549852)
		(end 301.824898 -283.074872)
		(width 0.13208)
		(layer "F.Cu")
		(net "Net_5354")
	)
	(via
		(at 301.824898 -283.074872)
		(size 0.4064)
		(drill 0.2032)
		(layers "F.Cu" "B.Cu")
		(net "Net_5354")
	)
	(segment
		(start 303.249838 -282.599892)
		(end 303.724818 -283.074872)
		(width 0.13208)
		(layer "F.Cu")
		(net "Net_5357")
	)
	(via
		(at 303.724818 -283.074872)
		(size 0.4064)
		(drill 0.2032)
		(layers "F.Cu" "B.Cu")
		(net "Net_5357")
	)
	(segment
		(start 304.199798 -290.199826)
		(end 304.674778 -289.724846)
		(width 0.13208)
		(layer "F.Cu")
		(net "Net_5359")
	)
	(via
		(at 304.674778 -289.724846)
		(size 0.4064)
		(drill 0.2032)
		(layers "F.Cu" "B.Cu")
		(net "Net_5359")
	)
	(segment
		(start 296.599864 -308.249828)
		(end 296.124884 -308.724808)
		(width 0.127)
		(layer "F.Cu")
		(net "Net_5362")
	)
	(via
		(at 296.124884 -308.724808)
		(size 0.4064)
		(drill 0.2032)
		(layers "F.Cu" "B.Cu")
		(net "Net_5362")
	)
	(segment
		(start 300.399704 -308.249828)
		(end 299.924724 -308.724808)
		(width 0.127)
		(layer "F.Cu")
		(net "Net_5371")
	)
	(via
		(at 299.924724 -308.724808)
		(size 0.4064)
		(drill 0.2032)
		(layers "F.Cu" "B.Cu")
		(net "Net_5371")
	)
	(segment
		(start 298.499784 -308.249828)
		(end 298.024804 -308.724808)
		(width 0.127)
		(layer "F.Cu")
		(net "Net_5373")
	)
	(via
		(at 298.024804 -308.724808)
		(size 0.4064)
		(drill 0.2032)
		(layers "F.Cu" "B.Cu")
		(net "Net_5373")
	)
	(segment
		(start 288.049716 -283.549852)
		(end 287.574736 -283.074872)
		(width 0.13208)
		(layer "F.Cu")
		(net "Net_5374")
	)
	(via
		(at 287.574736 -283.074872)
		(size 0.4064)
		(drill 0.2032)
		(layers "F.Cu" "B.Cu")
		(net "Net_5374")
	)
	(segment
		(start 288.99993 -283.549852)
		(end 288.52495 -283.074872)
		(width 0.13208)
		(layer "F.Cu")
		(net "Net_5375")
	)
	(via
		(at 288.52495 -283.074872)
		(size 0.4064)
		(drill 0.2032)
		(layers "F.Cu" "B.Cu")
		(net "Net_5375")
	)
	(segment
		(start 289.94989 -283.549852)
		(end 289.47491 -283.074872)
		(width 0.13208)
		(layer "F.Cu")
		(net "Net_5377")
	)
	(via
		(at 289.47491 -283.074872)
		(size 0.4064)
		(drill 0.2032)
		(layers "F.Cu" "B.Cu")
		(net "Net_5377")
	)
	(segment
		(start 288.99993 -309.199788)
		(end 288.52495 -308.724808)
		(width 0.127)
		(layer "F.Cu")
		(net "Net_5379")
	)
	(via
		(at 288.52495 -308.724808)
		(size 0.4064)
		(drill 0.2032)
		(layers "F.Cu" "B.Cu")
		(net "Net_5379")
	)
	(segment
		(start 288.99993 -308.249828)
		(end 288.52495 -307.774848)
		(width 0.127)
		(layer "F.Cu")
		(net "Net_5381")
	)
	(via
		(at 288.52495 -307.774848)
		(size 0.4064)
		(drill 0.2032)
		(layers "F.Cu" "B.Cu")
		(net "Net_5381")
	)
	(segment
		(start 289.94989 -308.249828)
		(end 289.47491 -307.774848)
		(width 0.127)
		(layer "F.Cu")
		(net "Net_5382")
	)
	(via
		(at 289.47491 -307.774848)
		(size 0.4064)
		(drill 0.2032)
		(layers "F.Cu" "B.Cu")
		(net "Net_5382")
	)
	(segment
		(start 289.94989 -309.199788)
		(end 290.42487 -308.724808)
		(width 0.13208)
		(layer "F.Cu")
		(net "Net_5383")
	)
	(via
		(at 290.42487 -308.724808)
		(size 0.4064)
		(drill 0.2032)
		(layers "F.Cu" "B.Cu")
		(net "Net_5383")
	)
	(segment
		(start 290.89985 -308.249828)
		(end 290.42487 -307.774848)
		(width 0.127)
		(layer "F.Cu")
		(net "Net_5384")
	)
	(via
		(at 290.42487 -307.774848)
		(size 0.4064)
		(drill 0.2032)
		(layers "F.Cu" "B.Cu")
		(net "Net_5384")
	)
	(segment
		(start 303.249838 -308.249828)
		(end 302.774858 -308.724808)
		(width 0.127)
		(layer "F.Cu")
		(net "Net_5389")
	)
	(via
		(at 302.774858 -308.724808)
		(size 0.4064)
		(drill 0.2032)
		(layers "F.Cu" "B.Cu")
		(net "Net_5389")
	)
	(segment
		(start 302.299878 -308.249828)
		(end 301.824898 -308.724808)
		(width 0.127)
		(layer "F.Cu")
		(net "Net_5390")
	)
	(via
		(at 301.824898 -308.724808)
		(size 0.4064)
		(drill 0.2032)
		(layers "F.Cu" "B.Cu")
		(net "Net_5390")
	)
	(segment
		(start 274.749768 -291.149786)
		(end 274.274788 -290.674806)
		(width 0.13208)
		(layer "F.Cu")
		(net "Net_5392")
	)
	(via
		(at 274.274788 -290.674806)
		(size 0.4064)
		(drill 0.2032)
		(layers "F.Cu" "B.Cu")
		(net "Net_5392")
	)
	(segment
		(start 275.699728 -292.099746)
		(end 275.224748 -291.624766)
		(width 0.13208)
		(layer "F.Cu")
		(net "Net_5393")
	)
	(via
		(at 275.224748 -291.624766)
		(size 0.4064)
		(drill 0.2032)
		(layers "F.Cu" "B.Cu")
		(net "Net_5393")
	)
	(segment
		(start 385.149852 -293.99992)
		(end 384.674872 -293.52494)
		(width 0.13208)
		(layer "F.Cu")
		(net "Net_5406")
	)
	(via
		(at 384.674872 -293.52494)
		(size 0.4064)
		(drill 0.2032)
		(layers "F.Cu" "B.Cu")
		(net "Net_5406")
	)
	(segment
		(start 386.099812 -293.99992)
		(end 385.624832 -293.52494)
		(width 0.13208)
		(layer "F.Cu")
		(net "Net_5407")
	)
	(via
		(at 385.624832 -293.52494)
		(size 0.4064)
		(drill 0.2032)
		(layers "F.Cu" "B.Cu")
		(net "Net_5407")
	)
	(segment
		(start 420.299896 -303.499774)
		(end 420.774876 -303.974754)
		(width 0.249936)
		(layer "F.Cu")
		(net "Net_5411")
	)
	(via
		(at 420.774876 -303.974754)
		(size 0.4064)
		(drill 0.2032)
		(layers "F.Cu" "B.Cu")
		(net "Net_5411")
	)
	(segment
		(start 385.149852 -292.099746)
		(end 384.674872 -291.624766)
		(width 0.13208)
		(layer "F.Cu")
		(net "Net_5412")
	)
	(via
		(at 384.674872 -291.624766)
		(size 0.4064)
		(drill 0.2032)
		(layers "F.Cu" "B.Cu")
		(net "Net_5412")
	)
	(segment
		(start 386.099812 -292.099746)
		(end 385.624832 -291.624766)
		(width 0.13208)
		(layer "F.Cu")
		(net "Net_5413")
	)
	(via
		(at 385.624832 -291.624766)
		(size 0.4064)
		(drill 0.2032)
		(layers "F.Cu" "B.Cu")
		(net "Net_5413")
	)
	(segment
		(start 420.299896 -289.249866)
		(end 420.774876 -288.774886)
		(width 0.13208)
		(layer "F.Cu")
		(net "Net_5416")
	)
	(via
		(at 420.774876 -288.774886)
		(size 0.4064)
		(drill 0.2032)
		(layers "F.Cu" "B.Cu")
		(net "Net_5416")
	)
	(segment
		(start 421.249856 -292.099746)
		(end 421.724836 -291.624766)
		(width 0.13208)
		(layer "F.Cu")
		(net "Net_5418")
	)
	(via
		(at 421.724836 -291.624766)
		(size 0.4064)
		(drill 0.2032)
		(layers "F.Cu" "B.Cu")
		(net "Net_5418")
	)
	(segment
		(start 398.4498 -283.549852)
		(end 397.97482 -283.074872)
		(width 0.13208)
		(layer "F.Cu")
		(net "Net_5424")
	)
	(via
		(at 397.97482 -283.074872)
		(size 0.4064)
		(drill 0.2032)
		(layers "F.Cu" "B.Cu")
		(net "Net_5424")
	)
	(segment
		(start 402.249894 -283.549852)
		(end 401.774914 -283.074872)
		(width 0.13208)
		(layer "F.Cu")
		(net "Net_5425")
	)
	(via
		(at 401.774914 -283.074872)
		(size 0.4064)
		(drill 0.2032)
		(layers "F.Cu" "B.Cu")
		(net "Net_5425")
	)
	(segment
		(start 401.299934 -283.549852)
		(end 400.824954 -283.074872)
		(width 0.13208)
		(layer "F.Cu")
		(net "Net_5429")
	)
	(via
		(at 400.824954 -283.074872)
		(size 0.4064)
		(drill 0.2032)
		(layers "F.Cu" "B.Cu")
		(net "Net_5429")
	)
	(segment
		(start 397.49984 -283.549852)
		(end 397.02486 -283.074872)
		(width 0.13208)
		(layer "F.Cu")
		(net "Net_5430")
	)
	(via
		(at 397.02486 -283.074872)
		(size 0.4064)
		(drill 0.2032)
		(layers "F.Cu" "B.Cu")
		(net "Net_5430")
	)
	(segment
		(start 399.400014 -283.549852)
		(end 398.925034 -283.074872)
		(width 0.13208)
		(layer "F.Cu")
		(net "Net_5433")
	)
	(via
		(at 398.925034 -283.074872)
		(size 0.4064)
		(drill 0.2032)
		(layers "F.Cu" "B.Cu")
		(net "Net_5433")
	)
	(segment
		(start 400.349974 -283.549852)
		(end 399.874994 -283.074872)
		(width 0.13208)
		(layer "F.Cu")
		(net "Net_5434")
	)
	(via
		(at 399.874994 -283.074872)
		(size 0.4064)
		(drill 0.2032)
		(layers "F.Cu" "B.Cu")
		(net "Net_5434")
	)
	(segment
		(start 395.59992 -283.549852)
		(end 395.12494 -283.074872)
		(width 0.13208)
		(layer "F.Cu")
		(net "Net_5438")
	)
	(via
		(at 395.12494 -283.074872)
		(size 0.4064)
		(drill 0.2032)
		(layers "F.Cu" "B.Cu")
		(net "Net_5438")
	)
	(segment
		(start 396.54988 -283.549852)
		(end 396.0749 -283.074872)
		(width 0.13208)
		(layer "F.Cu")
		(net "Net_5439")
	)
	(via
		(at 396.0749 -283.074872)
		(size 0.4064)
		(drill 0.2032)
		(layers "F.Cu" "B.Cu")
		(net "Net_5439")
	)
	(segment
		(start 415.549842 -282.599892)
		(end 416.024822 -283.074872)
		(width 0.13208)
		(layer "F.Cu")
		(net "Net_5440")
	)
	(via
		(at 416.024822 -283.074872)
		(size 0.4064)
		(drill 0.2032)
		(layers "F.Cu" "B.Cu")
		(net "Net_5440")
	)
	(segment
		(start 415.549842 -283.549852)
		(end 416.024822 -284.024832)
		(width 0.13208)
		(layer "F.Cu")
		(net "Net_5442")
	)
	(via
		(at 416.024822 -284.024832)
		(size 0.4064)
		(drill 0.2032)
		(layers "F.Cu" "B.Cu")
		(net "Net_5442")
	)
	(segment
		(start 418.399976 -282.599892)
		(end 418.874956 -283.074872)
		(width 0.13208)
		(layer "F.Cu")
		(net "Net_5443")
	)
	(via
		(at 418.874956 -283.074872)
		(size 0.4064)
		(drill 0.2032)
		(layers "F.Cu" "B.Cu")
		(net "Net_5443")
	)
	(segment
		(start 417.450016 -283.549852)
		(end 417.924996 -283.074872)
		(width 0.13208)
		(layer "F.Cu")
		(net "Net_5444")
	)
	(via
		(at 417.924996 -283.074872)
		(size 0.4064)
		(drill 0.2032)
		(layers "F.Cu" "B.Cu")
		(net "Net_5444")
	)
	(segment
		(start 419.349936 -282.599892)
		(end 419.824916 -283.074872)
		(width 0.13208)
		(layer "F.Cu")
		(net "Net_5447")
	)
	(via
		(at 419.824916 -283.074872)
		(size 0.4064)
		(drill 0.2032)
		(layers "F.Cu" "B.Cu")
		(net "Net_5447")
	)
	(segment
		(start 420.299896 -290.199826)
		(end 420.774876 -289.724846)
		(width 0.13208)
		(layer "F.Cu")
		(net "Net_5449")
	)
	(via
		(at 420.774876 -289.724846)
		(size 0.4064)
		(drill 0.2032)
		(layers "F.Cu" "B.Cu")
		(net "Net_5449")
	)
	(segment
		(start 420.299896 -288.299906)
		(end 420.774876 -287.824926)
		(width 0.13208)
		(layer "F.Cu")
		(net "Net_5450")
	)
	(via
		(at 420.774876 -287.824926)
		(size 0.4064)
		(drill 0.2032)
		(layers "F.Cu" "B.Cu")
		(net "Net_5450")
	)
	(segment
		(start 412.699962 -308.249828)
		(end 412.224982 -308.724808)
		(width 0.127)
		(layer "F.Cu")
		(net "Net_5452")
	)
	(via
		(at 412.224982 -308.724808)
		(size 0.4064)
		(drill 0.2032)
		(layers "F.Cu" "B.Cu")
		(net "Net_5452")
	)
	(segment
		(start 416.499802 -308.249828)
		(end 416.024822 -308.724808)
		(width 0.127)
		(layer "F.Cu")
		(net "Net_5461")
	)
	(via
		(at 416.024822 -308.724808)
		(size 0.4064)
		(drill 0.2032)
		(layers "F.Cu" "B.Cu")
		(net "Net_5461")
	)
	(segment
		(start 414.599882 -308.249828)
		(end 414.124902 -308.724808)
		(width 0.127)
		(layer "F.Cu")
		(net "Net_5463")
	)
	(via
		(at 414.124902 -308.724808)
		(size 0.4064)
		(drill 0.2032)
		(layers "F.Cu" "B.Cu")
		(net "Net_5463")
	)
	(segment
		(start 404.149814 -283.549852)
		(end 403.674834 -283.074872)
		(width 0.13208)
		(layer "F.Cu")
		(net "Net_5464")
	)
	(via
		(at 403.674834 -283.074872)
		(size 0.4064)
		(drill 0.2032)
		(layers "F.Cu" "B.Cu")
		(net "Net_5464")
	)
	(segment
		(start 405.100028 -283.549852)
		(end 404.625048 -283.074872)
		(width 0.13208)
		(layer "F.Cu")
		(net "Net_5465")
	)
	(via
		(at 404.625048 -283.074872)
		(size 0.4064)
		(drill 0.2032)
		(layers "F.Cu" "B.Cu")
		(net "Net_5465")
	)
	(segment
		(start 406.049988 -283.549852)
		(end 405.575008 -283.074872)
		(width 0.13208)
		(layer "F.Cu")
		(net "Net_5467")
	)
	(via
		(at 405.575008 -283.074872)
		(size 0.4064)
		(drill 0.2032)
		(layers "F.Cu" "B.Cu")
		(net "Net_5467")
	)
	(segment
		(start 405.100028 -309.199788)
		(end 404.625048 -308.724808)
		(width 0.127)
		(layer "F.Cu")
		(net "Net_5469")
	)
	(via
		(at 404.625048 -308.724808)
		(size 0.4064)
		(drill 0.2032)
		(layers "F.Cu" "B.Cu")
		(net "Net_5469")
	)
	(segment
		(start 405.100028 -308.249828)
		(end 404.625048 -307.774848)
		(width 0.127)
		(layer "F.Cu")
		(net "Net_5471")
	)
	(via
		(at 404.625048 -307.774848)
		(size 0.4064)
		(drill 0.2032)
		(layers "F.Cu" "B.Cu")
		(net "Net_5471")
	)
	(segment
		(start 406.049988 -308.249828)
		(end 405.575008 -307.774848)
		(width 0.127)
		(layer "F.Cu")
		(net "Net_5472")
	)
	(via
		(at 405.575008 -307.774848)
		(size 0.4064)
		(drill 0.2032)
		(layers "F.Cu" "B.Cu")
		(net "Net_5472")
	)
	(segment
		(start 406.049988 -309.199788)
		(end 406.524968 -308.724808)
		(width 0.13208)
		(layer "F.Cu")
		(net "Net_5473")
	)
	(via
		(at 406.524968 -308.724808)
		(size 0.4064)
		(drill 0.2032)
		(layers "F.Cu" "B.Cu")
		(net "Net_5473")
	)
	(segment
		(start 406.999948 -308.249828)
		(end 406.524968 -307.774848)
		(width 0.127)
		(layer "F.Cu")
		(net "Net_5474")
	)
	(via
		(at 406.524968 -307.774848)
		(size 0.4064)
		(drill 0.2032)
		(layers "F.Cu" "B.Cu")
		(net "Net_5474")
	)
	(segment
		(start 419.349936 -308.249828)
		(end 418.874956 -308.724808)
		(width 0.127)
		(layer "F.Cu")
		(net "Net_5479")
	)
	(via
		(at 418.874956 -308.724808)
		(size 0.4064)
		(drill 0.2032)
		(layers "F.Cu" "B.Cu")
		(net "Net_5479")
	)
	(segment
		(start 418.399976 -308.249828)
		(end 417.924996 -308.724808)
		(width 0.127)
		(layer "F.Cu")
		(net "Net_5480")
	)
	(via
		(at 417.924996 -308.724808)
		(size 0.4064)
		(drill 0.2032)
		(layers "F.Cu" "B.Cu")
		(net "Net_5480")
	)
	(segment
		(start 390.849866 -291.149786)
		(end 390.374886 -290.674806)
		(width 0.13208)
		(layer "F.Cu")
		(net "Net_5482")
	)
	(via
		(at 390.374886 -290.674806)
		(size 0.4064)
		(drill 0.2032)
		(layers "F.Cu" "B.Cu")
		(net "Net_5482")
	)
	(segment
		(start 391.799826 -292.099746)
		(end 391.324846 -291.624766)
		(width 0.13208)
		(layer "F.Cu")
		(net "Net_5483")
	)
	(via
		(at 391.324846 -291.624766)
		(size 0.4064)
		(drill 0.2032)
		(layers "F.Cu" "B.Cu")
		(net "Net_5483")
	)
	(segment
		(start 390.849866 -298.74972)
		(end 391.324846 -299.2247)
		(width 0.13208)
		(layer "F.Cu")
		(net "Net_5486")
	)
	(via
		(at 391.324846 -299.2247)
		(size 0.4064)
		(drill 0.2032)
		(layers "F.Cu" "B.Cu")
		(net "Net_5486")
	)
	(segment
		(start 390.849866 -296.8498)
		(end 391.324846 -297.32478)
		(width 0.13208)
		(layer "F.Cu")
		(net "Net_5487")
	)
	(via
		(at 391.324846 -297.32478)
		(size 0.4064)
		(drill 0.2032)
		(layers "F.Cu" "B.Cu")
		(net "Net_5487")
	)
	(segment
		(start 390.849866 -297.79976)
		(end 391.324846 -298.27474)
		(width 0.13208)
		(layer "F.Cu")
		(net "Net_5488")
	)
	(via
		(at 391.324846 -298.27474)
		(size 0.4064)
		(drill 0.2032)
		(layers "F.Cu" "B.Cu")
		(net "Net_5488")
	)
	(segment
		(start 407.89225 -85.20557)
		(end 406.289002 -85.20557)
		(width 0.4572)
		(layer "F.Cu")
		(net "P3V3")
	)
	(segment
		(start 145.565876 -191.378586)
		(end 145.281396 -191.094106)
		(width 0.4572)
		(layer "F.Cu")
		(net "P3V3")
	)
	(segment
		(start 122.423174 -164.300408)
		(end 122.21591 -164.093144)
		(width 0.4572)
		(layer "F.Cu")
		(net "P3V3")
	)
	(segment
		(start 329.03795 -85.598)
		(end 328.65695 -85.979)
		(width 0.381)
		(layer "F.Cu")
		(net "P3V3")
	)
	(segment
		(start 118.358412 -125.899926)
		(end 119.013732 -125.899926)
		(width 0.381)
		(layer "F.Cu")
		(net "P3V3")
	)
	(segment
		(start 242.4938 -212.7758)
		(end 242.02009 -212.30209)
		(width 0.4572)
		(layer "F.Cu")
		(net "P3V3")
	)
	(segment
		(start 144.389856 -191.744346)
		(end 144.389856 -191.493902)
		(width 0.4572)
		(layer "F.Cu")
		(net "P3V3")
	)
	(segment
		(start 220.851222 -140.894562)
		(end 220.241622 -140.894562)
		(width 0.4572)
		(layer "F.Cu")
		(net "P3V3")
	)
	(segment
		(start 268.802866 -93.542104)
		(end 269.412466 -93.542104)
		(width 0.4572)
		(layer "F.Cu")
		(net "P3V3")
	)
	(segment
		(start 408.52598 -85.3186)
		(end 408.00528 -85.3186)
		(width 0.4572)
		(layer "F.Cu")
		(net "P3V3")
	)
	(segment
		(start 182.022242 -178.425602)
		(end 181.28996 -178.425602)
		(width 0.4064)
		(layer "F.Cu")
		(net "P3V3")
	)
	(segment
		(start 327.221596 -83.261454)
		(end 328.041 -82.44205)
		(width 0.4572)
		(layer "F.Cu")
		(net "P3V3")
	)
	(segment
		(start 124.32919 -111.122968)
		(end 124.32919 -111.735362)
		(width 0.4572)
		(layer "F.Cu")
		(net "P3V3")
	)
	(segment
		(start 248.8057 -86.098888)
		(end 248.1961 -86.098888)
		(width 0.4572)
		(layer "F.Cu")
		(net "P3V3")
	)
	(segment
		(start 122.423174 -164.837872)
		(end 122.423174 -164.300408)
		(width 0.4572)
		(layer "F.Cu")
		(net "P3V3")
	)
	(segment
		(start 130.970528 -190.358522)
		(end 130.917188 -190.411862)
		(width 0.4572)
		(layer "F.Cu")
		(net "P3V3")
	)
	(segment
		(start 182.243476 -178.425602)
		(end 182.022242 -178.425602)
		(width 0.4572)
		(layer "F.Cu")
		(net "P3V3")
	)
	(segment
		(start 408.418538 -84.410804)
		(end 408.615388 -84.607654)
		(width 0.4572)
		(layer "F.Cu")
		(net "P3V3")
	)
	(segment
		(start 260.540246 -76.879704)
		(end 260.540246 -76.270104)
		(width 0.4572)
		(layer "F.Cu")
		(net "P3V3")
	)
	(segment
		(start 228.582474 -136.269222)
		(end 228.582474 -135.659622)
		(width 0.4572)
		(layer "F.Cu")
		(net "P3V3")
	)
	(segment
		(start 248.93143 -92.496386)
		(end 248.93143 -93.105986)
		(width 0.4572)
		(layer "F.Cu")
		(net "P3V3")
	)
	(segment
		(start 336.551778 -94.221554)
		(end 336.551778 -93.554296)
		(width 0.4572)
		(layer "F.Cu")
		(net "P3V3")
	)
	(segment
		(start 220.851222 -145.974562)
		(end 220.241622 -145.974562)
		(width 0.4572)
		(layer "F.Cu")
		(net "P3V3")
	)
	(segment
		(start 106.787188 -92.768928)
		(end 106.787188 -93.436186)
		(width 0.4572)
		(layer "F.Cu")
		(net "P3V3")
	)
	(segment
		(start 257.20929 -76.879704)
		(end 257.20929 -76.270104)
		(width 0.4572)
		(layer "F.Cu")
		(net "P3V3")
	)
	(segment
		(start 182.94604 -177.723038)
		(end 182.243476 -178.425602)
		(width 0.4572)
		(layer "F.Cu")
		(net "P3V3")
	)
	(segment
		(start 236.023658 -144.672812)
		(end 236.633258 -144.672812)
		(width 0.4572)
		(layer "F.Cu")
		(net "P3V3")
	)
	(segment
		(start 145.924016 -191.378586)
		(end 145.565876 -191.378586)
		(width 0.4572)
		(layer "F.Cu")
		(net "P3V3")
	)
	(segment
		(start 332.783688 -93.460824)
		(end 334.401922 -93.460824)
		(width 0.4572)
		(layer "F.Cu")
		(net "P3V3")
	)
	(segment
		(start 408.00528 -85.3186)
		(end 407.89225 -85.20557)
		(width 0.4572)
		(layer "F.Cu")
		(net "P3V3")
	)
	(segment
		(start 181.28996 -178.425602)
		(end 181.213506 -178.349148)
		(width 0.4064)
		(layer "F.Cu")
		(net "P3V3")
	)
	(segment
		(start 128.218438 -188.479176)
		(end 129.310384 -189.571122)
		(width 0.4572)
		(layer "F.Cu")
		(net "P3V3")
	)
	(segment
		(start 328.65695 -85.979)
		(end 328.422 -85.979)
		(width 0.381)
		(layer "F.Cu")
		(net "P3V3")
	)
	(segment
		(start 242.02009 -212.30209)
		(end 242.02009 -212.27034)
		(width 0.4572)
		(layer "F.Cu")
		(net "P3V3")
	)
	(segment
		(start 242.006882 -212.257132)
		(end 242.006882 -211.672932)
		(width 0.4572)
		(layer "F.Cu")
		(net "P3V3")
	)
	(segment
		(start 259.24129 -76.879704)
		(end 259.24129 -76.270104)
		(width 0.4572)
		(layer "F.Cu")
		(net "P3V3")
	)
	(segment
		(start 326.49668 -83.261454)
		(end 327.221596 -83.261454)
		(width 0.4572)
		(layer "F.Cu")
		(net "P3V3")
	)
	(segment
		(start 242.02009 -212.27034)
		(end 242.006882 -212.257132)
		(width 0.4572)
		(layer "F.Cu")
		(net "P3V3")
	)
	(segment
		(start 145.281396 -191.094106)
		(end 144.789652 -191.094106)
		(width 0.4572)
		(layer "F.Cu")
		(net "P3V3")
	)
	(segment
		(start 129.310384 -191.280288)
		(end 130.819906 -191.280288)
		(width 0.4572)
		(layer "F.Cu")
		(net "P3V3")
	)
	(segment
		(start 236.023658 -146.704812)
		(end 236.633258 -146.704812)
		(width 0.4572)
		(layer "F.Cu")
		(net "P3V3")
	)
	(segment
		(start 226.550982 -156.398722)
		(end 226.550982 -157.008322)
		(width 0.4572)
		(layer "F.Cu")
		(net "P3V3")
	)
	(segment
		(start 130.819906 -191.280288)
		(end 130.917188 -191.37757)
		(width 0.4572)
		(layer "F.Cu")
		(net "P3V3")
	)
	(segment
		(start 181.213506 -178.349148)
		(end 181.199028 -178.349148)
		(width 0.4064)
		(layer "F.Cu")
		(net "P3V3")
	)
	(segment
		(start 129.310384 -191.95161)
		(end 129.310384 -191.280288)
		(width 0.4572)
		(layer "F.Cu")
		(net "P3V3")
	)
	(segment
		(start 236.023658 -145.688812)
		(end 236.633258 -145.688812)
		(width 0.4572)
		(layer "F.Cu")
		(net "P3V3")
	)
	(segment
		(start 254.177292 -76.879704)
		(end 254.177292 -76.270104)
		(width 0.4572)
		(layer "F.Cu")
		(net "P3V3")
	)
	(segment
		(start 128.218438 -183.503824)
		(end 128.218438 -188.479176)
		(width 0.4572)
		(layer "F.Cu")
		(net "P3V3")
	)
	(segment
		(start 129.310384 -189.571122)
		(end 129.310384 -191.280288)
		(width 0.4572)
		(layer "F.Cu")
		(net "P3V3")
	)
	(segment
		(start 226.804474 -136.269222)
		(end 226.804474 -135.659622)
		(width 0.4572)
		(layer "F.Cu")
		(net "P3V3")
	)
	(segment
		(start 127.69977 -166.407846)
		(end 127.69977 -167.054276)
		(width 0.4572)
		(layer "F.Cu")
		(net "P3V3")
	)
	(segment
		(start 127.719328 -183.004714)
		(end 128.218438 -183.503824)
		(width 0.4572)
		(layer "F.Cu")
		(net "P3V3")
	)
	(segment
		(start 144.389856 -191.493902)
		(end 144.789652 -191.094106)
		(width 0.4572)
		(layer "F.Cu")
		(net "P3V3")
	)
	(segment
		(start 248.8057 -84.320888)
		(end 248.1961 -84.320888)
		(width 0.4572)
		(layer "F.Cu")
		(net "P3V3")
	)
	(segment
		(start 104.728772 -92.766896)
		(end 104.728772 -93.447362)
		(width 0.4572)
		(layer "F.Cu")
		(net "P3V3")
	)
	(segment
		(start 130.917188 -190.411862)
		(end 130.917188 -191.37757)
		(width 0.4572)
		(layer "F.Cu")
		(net "P3V3")
	)
	(segment
		(start 411.447488 -87.440008)
		(end 411.447488 -86.424008)
		(width 0.4572)
		(layer "F.Cu")
		(net "P3V3")
	)
	(segment
		(start 268.9352 -78.885796)
		(end 273.449034 -78.885796)
		(width 0.4572)
		(layer "F.Cu")
		(net "P3V3")
	)
	(segment
		(start 268.906498 -87.251286)
		(end 269.592298 -87.251286)
		(width 0.4572)
		(layer "F.Cu")
		(net "P3V3")
	)
	(segment
		(start 123.31319 -111.122968)
		(end 123.31319 -111.735362)
		(width 0.4572)
		(layer "F.Cu")
		(net "P3V3")
	)
	(segment
		(start 268.802866 -90.462354)
		(end 269.412466 -90.462354)
		(width 0.4572)
		(layer "F.Cu")
		(net "P3V3")
	)
	(segment
		(start 220.811852 -139.641834)
		(end 220.202252 -139.641834)
		(width 0.4572)
		(layer "F.Cu")
		(net "P3V3")
	)
	(segment
		(start 408.615388 -84.607654)
		(end 408.615388 -85.408008)
		(width 0.4572)
		(layer "F.Cu")
		(net "P3V3")
	)
	(segment
		(start 236.023658 -141.640814)
		(end 236.633258 -141.640814)
		(width 0.4572)
		(layer "F.Cu")
		(net "P3V3")
	)
	(segment
		(start 412.933388 -84.938108)
		(end 413.842708 -84.938108)
		(width 0.4572)
		(layer "F.Cu")
		(net "P3V3")
	)
	(segment
		(start 329.03795 -82.65795)
		(end 329.03795 -82.931)
		(width 0.4572)
		(layer "F.Cu")
		(net "P3V3")
	)
	(segment
		(start 328.041 -82.44205)
		(end 328.52995 -82.44205)
		(width 0.4572)
		(layer "F.Cu")
		(net "P3V3")
	)
	(segment
		(start 261.528306 -76.879704)
		(end 261.528306 -76.235814)
		(width 0.4572)
		(layer "F.Cu")
		(net "P3V3")
	)
	(segment
		(start 408.615388 -85.408008)
		(end 408.52598 -85.3186)
		(width 0.4572)
		(layer "F.Cu")
		(net "P3V3")
	)
	(segment
		(start 411.447488 -86.424008)
		(end 412.933388 -84.938108)
		(width 0.4572)
		(layer "F.Cu")
		(net "P3V3")
	)
	(segment
		(start 258.22529 -76.879704)
		(end 258.22529 -76.270104)
		(width 0.4572)
		(layer "F.Cu")
		(net "P3V3")
	)
	(segment
		(start 265.5951 -76.879704)
		(end 265.5951 -76.223622)
		(width 0.4572)
		(layer "F.Cu")
		(net "P3V3")
	)
	(segment
		(start 328.52995 -82.44205)
		(end 328.676 -82.296)
		(width 0.4572)
		(layer "F.Cu")
		(net "P3V3")
	)
	(segment
		(start 220.851222 -149.054312)
		(end 220.241622 -149.054312)
		(width 0.4572)
		(layer "F.Cu")
		(net "P3V3")
	)
	(segment
		(start 334.401922 -93.460824)
		(end 334.493362 -93.552264)
		(width 0.4572)
		(layer "F.Cu")
		(net "P3V3")
	)
	(segment
		(start 328.676 -82.296)
		(end 329.03795 -82.65795)
		(width 0.4572)
		(layer "F.Cu")
		(net "P3V3")
	)
	(segment
		(start 236.023658 -147.720812)
		(end 236.633258 -147.720812)
		(width 0.381)
		(layer "F.Cu")
		(net "P3V3")
	)
	(via
		(at 106.787188 -93.436186)
		(size 0.508)
		(drill 0.254)
		(layers "F.Cu" "B.Cu")
		(net "P3V3")
	)
	(via
		(at 236.633258 -145.688812)
		(size 0.508)
		(drill 0.254)
		(layers "F.Cu" "B.Cu")
		(net "P3V3")
	)
	(via
		(at 236.633258 -146.704812)
		(size 0.508)
		(drill 0.254)
		(layers "F.Cu" "B.Cu")
		(net "P3V3")
	)
	(via
		(at 105.22585 -126.357126)
		(size 0.508)
		(drill 0.254)
		(layers "F.Cu" "B.Cu")
		(net "P3V3")
	)
	(via
		(at 108.021882 -346.461842)
		(size 0.508)
		(drill 0.254)
		(layers "F.Cu" "B.Cu")
		(net "P3V3")
	)
	(via
		(at 104.728772 -93.447362)
		(size 0.508)
		(drill 0.254)
		(layers "F.Cu" "B.Cu")
		(net "P3V3")
	)
	(via
		(at 101.589586 -343.446862)
		(size 0.508)
		(drill 0.254)
		(layers "F.Cu" "B.Cu")
		(net "P3V3")
	)
	(via
		(at 220.241622 -145.974562)
		(size 0.508)
		(drill 0.254)
		(layers "F.Cu" "B.Cu")
		(net "P3V3")
	)
	(via
		(at 119.013732 -125.899926)
		(size 0.508)
		(drill 0.254)
		(layers "F.Cu" "B.Cu")
		(net "P3V3")
	)
	(via
		(at 96.586294 -286.941768)
		(size 0.508)
		(drill 0.254)
		(layers "F.Cu" "B.Cu")
		(net "P3V3")
	)
	(via
		(at 122.21591 -164.093144)
		(size 0.508)
		(drill 0.254)
		(layers "F.Cu" "B.Cu")
		(net "P3V3")
	)
	(via
		(at 226.804474 -135.659622)
		(size 0.508)
		(drill 0.254)
		(layers "F.Cu" "B.Cu")
		(net "P3V3")
	)
	(via
		(at 102.449122 -80.050132)
		(size 0.508)
		(drill 0.254)
		(layers "F.Cu" "B.Cu")
		(net "P3V3")
	)
	(via
		(at 110.701074 -126.726442)
		(size 0.508)
		(drill 0.254)
		(layers "F.Cu" "B.Cu")
		(net "P3V3")
	)
	(via
		(at 111.415576 -127.117094)
		(size 0.508)
		(drill 0.254)
		(layers "F.Cu" "B.Cu")
		(net "P3V3")
	)
	(via
		(at 127.719328 -183.004714)
		(size 0.508)
		(drill 0.254)
		(layers "F.Cu" "B.Cu")
		(net "P3V3")
	)
	(via
		(at 92.20581 -180.43271)
		(size 0.508)
		(drill 0.254)
		(layers "F.Cu" "B.Cu")
		(net "P3V3")
	)
	(via
		(at 236.633258 -144.672812)
		(size 0.508)
		(drill 0.254)
		(layers "F.Cu" "B.Cu")
		(net "P3V3")
	)
	(via
		(at 118.071392 -121.03989)
		(size 0.508)
		(drill 0.254)
		(layers "F.Cu" "B.Cu")
		(net "P3V3")
	)
	(via
		(at 108.634022 -126.731522)
		(size 0.508)
		(drill 0.254)
		(layers "F.Cu" "B.Cu")
		(net "P3V3")
	)
	(via
		(at 220.202252 -139.641834)
		(size 0.508)
		(drill 0.254)
		(layers "F.Cu" "B.Cu")
		(net "P3V3")
	)
	(via
		(at 408.418538 -84.410804)
		(size 0.508)
		(drill 0.254)
		(layers "F.Cu" "B.Cu")
		(net "P3V3")
	)
	(via
		(at 248.1961 -86.098888)
		(size 0.508)
		(drill 0.254)
		(layers "F.Cu" "B.Cu")
		(net "P3V3")
	)
	(via
		(at 258.22529 -76.270104)
		(size 0.508)
		(drill 0.254)
		(layers "F.Cu" "B.Cu")
		(net "P3V3")
	)
	(via
		(at 124.32919 -111.735362)
		(size 0.508)
		(drill 0.254)
		(layers "F.Cu" "B.Cu")
		(net "P3V3")
	)
	(via
		(at 269.412466 -93.542104)
		(size 0.508)
		(drill 0.254)
		(layers "F.Cu" "B.Cu")
		(net "P3V3")
	)
	(via
		(at 105.22585 -125.722126)
		(size 0.508)
		(drill 0.254)
		(layers "F.Cu" "B.Cu")
		(net "P3V3")
	)
	(via
		(at 111.616236 -335.881726)
		(size 0.508)
		(drill 0.254)
		(layers "F.Cu" "B.Cu")
		(net "P3V3")
	)
	(via
		(at 220.241622 -140.894562)
		(size 0.508)
		(drill 0.254)
		(layers "F.Cu" "B.Cu")
		(net "P3V3")
	)
	(via
		(at 129.310384 -191.280288)
		(size 0.508)
		(drill 0.254)
		(layers "F.Cu" "B.Cu")
		(net "P3V3")
	)
	(via
		(at 259.24129 -76.270104)
		(size 0.508)
		(drill 0.254)
		(layers "F.Cu" "B.Cu")
		(net "P3V3")
	)
	(via
		(at 226.550982 -157.008322)
		(size 0.508)
		(drill 0.254)
		(layers "F.Cu" "B.Cu")
		(net "P3V3")
	)
	(via
		(at 328.676 -82.296)
		(size 0.508)
		(drill 0.254)
		(layers "F.Cu" "B.Cu")
		(net "P3V3")
	)
	(via
		(at 101.240336 -333.614522)
		(size 0.508)
		(drill 0.254)
		(layers "F.Cu" "B.Cu")
		(net "P3V3")
	)
	(via
		(at 242.4938 -212.7758)
		(size 0.508)
		(drill 0.254)
		(layers "F.Cu" "B.Cu")
		(net "P3V3")
	)
	(via
		(at 222.593154 -153.675842)
		(size 0.508)
		(drill 0.254)
		(layers "F.Cu" "B.Cu")
		(net "P3V3")
	)
	(via
		(at 110.690406 -127.38735)
		(size 0.508)
		(drill 0.254)
		(layers "F.Cu" "B.Cu")
		(net "P3V3")
	)
	(via
		(at 261.528306 -76.235814)
		(size 0.508)
		(drill 0.254)
		(layers "F.Cu" "B.Cu")
		(net "P3V3")
	)
	(via
		(at 269.592298 -87.251286)
		(size 0.508)
		(drill 0.254)
		(layers "F.Cu" "B.Cu")
		(net "P3V3")
	)
	(via
		(at 118.833392 -121.03989)
		(size 0.508)
		(drill 0.254)
		(layers "F.Cu" "B.Cu")
		(net "P3V3")
	)
	(via
		(at 107.881674 -125.781816)
		(size 0.508)
		(drill 0.254)
		(layers "F.Cu" "B.Cu")
		(net "P3V3")
	)
	(via
		(at 251.56668 -85.840316)
		(size 0.508)
		(drill 0.254)
		(layers "F.Cu" "B.Cu")
		(net "P3V3")
	)
	(via
		(at 123.31319 -111.735362)
		(size 0.508)
		(drill 0.254)
		(layers "F.Cu" "B.Cu")
		(net "P3V3")
	)
	(via
		(at 114.631216 -329.44943)
		(size 0.508)
		(drill 0.254)
		(layers "F.Cu" "B.Cu")
		(net "P3V3")
	)
	(via
		(at 266.719304 -77.600048)
		(size 0.508)
		(drill 0.254)
		(layers "F.Cu" "B.Cu")
		(net "P3V3")
	)
	(via
		(at 106.4514 -356.1588)
		(size 0.508)
		(drill 0.254)
		(layers "F.Cu" "B.Cu")
		(net "P3V3")
	)
	(via
		(at 332.783688 -93.460824)
		(size 0.508)
		(drill 0.254)
		(layers "F.Cu" "B.Cu")
		(net "P3V3")
	)
	(via
		(at 235.191046 -154.651202)
		(size 0.508)
		(drill 0.254)
		(layers "F.Cu" "B.Cu")
		(net "P3V3")
	)
	(via
		(at 336.551778 -94.221554)
		(size 0.508)
		(drill 0.254)
		(layers "F.Cu" "B.Cu")
		(net "P3V3")
	)
	(via
		(at 138.995658 -172.287946)
		(size 0.508)
		(drill 0.254)
		(layers "F.Cu" "B.Cu")
		(net "P3V3")
	)
	(via
		(at 139.008104 -171.582334)
		(size 0.508)
		(drill 0.254)
		(layers "F.Cu" "B.Cu")
		(net "P3V3")
	)
	(via
		(at 226.428046 -139.030202)
		(size 0.508)
		(drill 0.254)
		(layers "F.Cu" "B.Cu")
		(net "P3V3")
	)
	(via
		(at 127.181356 -180.02377)
		(size 0.508)
		(drill 0.254)
		(layers "F.Cu" "B.Cu")
		(net "P3V3")
	)
	(via
		(at 128.261364 -172.236892)
		(size 0.508)
		(drill 0.254)
		(layers "F.Cu" "B.Cu")
		(net "P3V3")
	)
	(via
		(at 228.582474 -135.659622)
		(size 0.508)
		(drill 0.254)
		(layers "F.Cu" "B.Cu")
		(net "P3V3")
	)
	(via
		(at 105.22585 -126.992126)
		(size 0.508)
		(drill 0.254)
		(layers "F.Cu" "B.Cu")
		(net "P3V3")
	)
	(via
		(at 265.5951 -76.223622)
		(size 0.508)
		(drill 0.254)
		(layers "F.Cu" "B.Cu")
		(net "P3V3")
	)
	(via
		(at 269.412466 -90.462354)
		(size 0.508)
		(drill 0.254)
		(layers "F.Cu" "B.Cu")
		(net "P3V3")
	)
	(via
		(at 331.705712 -80.8355)
		(size 0.508)
		(drill 0.254)
		(layers "F.Cu" "B.Cu")
		(net "P3V3")
	)
	(via
		(at 413.842708 -84.938108)
		(size 0.508)
		(drill 0.254)
		(layers "F.Cu" "B.Cu")
		(net "P3V3")
	)
	(via
		(at 257.20929 -76.270104)
		(size 0.508)
		(drill 0.254)
		(layers "F.Cu" "B.Cu")
		(net "P3V3")
	)
	(via
		(at 248.93143 -93.105986)
		(size 0.508)
		(drill 0.254)
		(layers "F.Cu" "B.Cu")
		(net "P3V3")
	)
	(via
		(at 260.540246 -76.270104)
		(size 0.508)
		(drill 0.254)
		(layers "F.Cu" "B.Cu")
		(net "P3V3")
	)
	(via
		(at 105.22585 -125.087126)
		(size 0.508)
		(drill 0.254)
		(layers "F.Cu" "B.Cu")
		(net "P3V3")
	)
	(via
		(at 182.022242 -178.425602)
		(size 0.508)
		(drill 0.254)
		(layers "F.Cu" "B.Cu")
		(net "P3V3")
	)
	(via
		(at 257.095752 -112.628934)
		(size 0.508)
		(drill 0.254)
		(layers "F.Cu" "B.Cu")
		(net "P3V3")
	)
	(via
		(at 107.881674 -125.146816)
		(size 0.508)
		(drill 0.254)
		(layers "F.Cu" "B.Cu")
		(net "P3V3")
	)
	(via
		(at 129.64795 -173.544484)
		(size 0.508)
		(drill 0.254)
		(layers "F.Cu" "B.Cu")
		(net "P3V3")
	)
	(via
		(at 220.241622 -149.054312)
		(size 0.508)
		(drill 0.254)
		(layers "F.Cu" "B.Cu")
		(net "P3V3")
	)
	(via
		(at 235.191046 -155.540202)
		(size 0.508)
		(drill 0.254)
		(layers "F.Cu" "B.Cu")
		(net "P3V3")
	)
	(via
		(at 144.789652 -191.094106)
		(size 0.508)
		(drill 0.254)
		(layers "F.Cu" "B.Cu")
		(net "P3V3")
	)
	(via
		(at 107.881674 -126.416816)
		(size 0.508)
		(drill 0.254)
		(layers "F.Cu" "B.Cu")
		(net "P3V3")
	)
	(via
		(at 92.935298 -180.423566)
		(size 0.508)
		(drill 0.254)
		(layers "F.Cu" "B.Cu")
		(net "P3V3")
	)
	(via
		(at 98.14941 -335.69783)
		(size 0.508)
		(drill 0.254)
		(layers "F.Cu" "B.Cu")
		(net "P3V3")
	)
	(via
		(at 103.084122 -80.050132)
		(size 0.508)
		(drill 0.254)
		(layers "F.Cu" "B.Cu")
		(net "P3V3")
	)
	(via
		(at 227.063046 -139.030202)
		(size 0.508)
		(drill 0.254)
		(layers "F.Cu" "B.Cu")
		(net "P3V3")
	)
	(via
		(at 222.593154 -154.564842)
		(size 0.508)
		(drill 0.254)
		(layers "F.Cu" "B.Cu")
		(net "P3V3")
	)
	(via
		(at 108.602272 -127.508762)
		(size 0.508)
		(drill 0.254)
		(layers "F.Cu" "B.Cu")
		(net "P3V3")
	)
	(via
		(at 99.489514 -336.98561)
		(size 0.508)
		(drill 0.254)
		(layers "F.Cu" "B.Cu")
		(net "P3V3")
	)
	(via
		(at 236.633258 -147.720812)
		(size 0.508)
		(drill 0.254)
		(layers "F.Cu" "B.Cu")
		(net "P3V3")
	)
	(via
		(at 137.256266 -182.82539)
		(size 0.508)
		(drill 0.254)
		(layers "F.Cu" "B.Cu")
		(net "P3V3")
	)
	(via
		(at 96.11614 -287.419542)
		(size 0.508)
		(drill 0.254)
		(layers "F.Cu" "B.Cu")
		(net "P3V3")
	)
	(via
		(at 130.917188 -191.37757)
		(size 0.508)
		(drill 0.254)
		(layers "F.Cu" "B.Cu")
		(net "P3V3")
	)
	(via
		(at 127.69977 -167.054276)
		(size 0.508)
		(drill 0.254)
		(layers "F.Cu" "B.Cu")
		(net "P3V3")
	)
	(via
		(at 107.0102 -359.5116)
		(size 0.508)
		(drill 0.254)
		(layers "F.Cu" "B.Cu")
		(net "P3V3")
	)
	(via
		(at 107.881674 -127.051816)
		(size 0.508)
		(drill 0.254)
		(layers "F.Cu" "B.Cu")
		(net "P3V3")
	)
	(via
		(at 332.340712 -80.8355)
		(size 0.508)
		(drill 0.254)
		(layers "F.Cu" "B.Cu")
		(net "P3V3")
	)
	(via
		(at 273.449034 -78.885796)
		(size 0.508)
		(drill 0.254)
		(layers "F.Cu" "B.Cu")
		(net "P3V3")
	)
	(via
		(at 328.422 -85.979)
		(size 0.508)
		(drill 0.254)
		(layers "F.Cu" "B.Cu")
		(net "P3V3")
	)
	(via
		(at 251.56668 -86.475316)
		(size 0.508)
		(drill 0.254)
		(layers "F.Cu" "B.Cu")
		(net "P3V3")
	)
	(via
		(at 248.1961 -84.320888)
		(size 0.508)
		(drill 0.254)
		(layers "F.Cu" "B.Cu")
		(net "P3V3")
	)
	(via
		(at 236.633258 -141.640814)
		(size 0.508)
		(drill 0.254)
		(layers "F.Cu" "B.Cu")
		(net "P3V3")
	)
	(via
		(at 106.9848 -360.1466)
		(size 0.508)
		(drill 0.254)
		(layers "F.Cu" "B.Cu")
		(net "P3V3")
	)
	(via
		(at 266.741656 -76.897992)
		(size 0.508)
		(drill 0.254)
		(layers "F.Cu" "B.Cu")
		(net "P3V3")
	)
	(via
		(at 254.177292 -76.270104)
		(size 0.508)
		(drill 0.254)
		(layers "F.Cu" "B.Cu")
		(net "P3V3")
	)
	(segment
		(start 110.86719 -335.881726)
		(end 111.616236 -335.881726)
		(width 0.4572)
		(layer "B.Cu")
		(net "P3V3")
	)
	(segment
		(start 108.021882 -347.210888)
		(end 108.021882 -346.461842)
		(width 0.4572)
		(layer "B.Cu")
		(net "P3V3")
	)
	(segment
		(start 101.963982 -333.614522)
		(end 101.240336 -333.614522)
		(width 0.4572)
		(layer "B.Cu")
		(net "P3V3")
	)
	(segment
		(start 136.883394 -182.452518)
		(end 137.256266 -182.82539)
		(width 0.4572)
		(layer "B.Cu")
		(net "P3V3")
	)
	(segment
		(start 105.754678 -356.114096)
		(end 106.406696 -356.114096)
		(width 0.4572)
		(layer "B.Cu")
		(net "P3V3")
	)
	(segment
		(start 248.940574 -92.318078)
		(end 248.940574 -93.096842)
		(width 0.4572)
		(layer "B.Cu")
		(net "P3V3")
	)
	(segment
		(start 99.489514 -335.69783)
		(end 99.489514 -336.98561)
		(width 0.4572)
		(layer "B.Cu")
		(net "P3V3")
	)
	(segment
		(start 106.406696 -356.114096)
		(end 106.4514 -356.1588)
		(width 0.4572)
		(layer "B.Cu")
		(net "P3V3")
	)
	(segment
		(start 128.470914 -183.004714)
		(end 127.719328 -183.004714)
		(width 0.4572)
		(layer "B.Cu")
		(net "P3V3")
	)
	(segment
		(start 113.914174 -329.44943)
		(end 114.631216 -329.44943)
		(width 0.4572)
		(layer "B.Cu")
		(net "P3V3")
	)
	(segment
		(start 127.840994 -180.02377)
		(end 127.181356 -180.02377)
		(width 0.4572)
		(layer "B.Cu")
		(net "P3V3")
	)
	(segment
		(start 136.403842 -182.452518)
		(end 136.883394 -182.452518)
		(width 0.4572)
		(layer "B.Cu")
		(net "P3V3")
	)
	(segment
		(start 98.14941 -335.69783)
		(end 99.489514 -335.69783)
		(width 0.4572)
		(layer "B.Cu")
		(net "P3V3")
	)
	(segment
		(start 101.589586 -344.163904)
		(end 101.589586 -343.446862)
		(width 0.4572)
		(layer "B.Cu")
		(net "P3V3")
	)
	(segment
		(start 248.940574 -93.096842)
		(end 248.93143 -93.105986)
		(width 0.4572)
		(layer "B.Cu")
		(net "P3V3")
	)
	(segment
		(start 258.752086 -114.285268)
		(end 257.095752 -112.628934)
		(width 0.4572)
		(layer "In5.Cu")
		(net "P3V3")
	)
	(segment
		(start 242.4938 -212.7758)
		(end 242.4938 -213.0044)
		(width 0.4572)
		(layer "In5.Cu")
		(net "P3V3")
	)
	(segment
		(start 253.403608 -189.687962)
		(end 253.403608 -169.443146)
		(width 0.4572)
		(layer "In5.Cu")
		(net "P3V3")
	)
	(segment
		(start 249.246644 -193.844926)
		(end 253.403608 -189.687962)
		(width 0.4572)
		(layer "In5.Cu")
		(net "P3V3")
	)
	(segment
		(start 248.910094 -209.280506)
		(end 249.90044 -209.280506)
		(width 0.4572)
		(layer "In5.Cu")
		(net "P3V3")
	)
	(segment
		(start 243.205 -213.7156)
		(end 244.475 -213.7156)
		(width 0.4572)
		(layer "In5.Cu")
		(net "P3V3")
	)
	(segment
		(start 250.292362 -208.888584)
		(end 250.292362 -206.738982)
		(width 0.4572)
		(layer "In5.Cu")
		(net "P3V3")
	)
	(segment
		(start 250.292362 -206.738982)
		(end 249.295158 -205.741778)
		(width 0.4572)
		(layer "In5.Cu")
		(net "P3V3")
	)
	(segment
		(start 258.752086 -164.094668)
		(end 258.752086 -114.285268)
		(width 0.4572)
		(layer "In5.Cu")
		(net "P3V3")
	)
	(segment
		(start 244.475 -213.7156)
		(end 248.910094 -209.280506)
		(width 0.4572)
		(layer "In5.Cu")
		(net "P3V3")
	)
	(segment
		(start 249.90044 -209.280506)
		(end 250.292362 -208.888584)
		(width 0.4572)
		(layer "In5.Cu")
		(net "P3V3")
	)
	(segment
		(start 249.295158 -205.741778)
		(end 249.295158 -194.785996)
		(width 0.4572)
		(layer "In5.Cu")
		(net "P3V3")
	)
	(segment
		(start 249.246644 -194.737482)
		(end 249.246644 -193.844926)
		(width 0.4572)
		(layer "In5.Cu")
		(net "P3V3")
	)
	(segment
		(start 249.295158 -194.785996)
		(end 249.246644 -194.737482)
		(width 0.4572)
		(layer "In5.Cu")
		(net "P3V3")
	)
	(segment
		(start 253.403608 -169.443146)
		(end 258.752086 -164.094668)
		(width 0.4572)
		(layer "In5.Cu")
		(net "P3V3")
	)
	(segment
		(start 242.4938 -213.0044)
		(end 243.205 -213.7156)
		(width 0.4572)
		(layer "In5.Cu")
		(net "P3V3")
	)
	(segment
		(start 182.570374 -178.973734)
		(end 182.022242 -178.425602)
		(width 0.4572)
		(layer "In13.Cu")
		(net "P3V3")
	)
	(segment
		(start 154.074622 -181.151022)
		(end 181.514496 -181.151022)
		(width 0.4572)
		(layer "In13.Cu")
		(net "P3V3")
	)
	(segment
		(start 182.570374 -180.095144)
		(end 182.570374 -178.973734)
		(width 0.4572)
		(layer "In13.Cu")
		(net "P3V3")
	)
	(segment
		(start 144.381982 -191.501776)
		(end 144.789652 -191.094106)
		(width 0.4572)
		(layer "In13.Cu")
		(net "P3V3")
	)
	(segment
		(start 337.4136 -101.7778)
		(end 337.4136 -100.457)
		(width 0.4572)
		(layer "In13.Cu")
		(net "P3V3")
	)
	(segment
		(start 337.185 -100.2284)
		(end 336.6262 -100.2284)
		(width 0.4572)
		(layer "In13.Cu")
		(net "P3V3")
	)
	(segment
		(start 337.4136 -100.457)
		(end 337.185 -100.2284)
		(width 0.4572)
		(layer "In13.Cu")
		(net "P3V3")
	)
	(segment
		(start 358.788462 -97.846388)
		(end 356.40645 -100.2284)
		(width 0.4572)
		(layer "In13.Cu")
		(net "P3V3")
	)
	(segment
		(start 130.917188 -191.37757)
		(end 133.012688 -189.28207)
		(width 0.4572)
		(layer "In13.Cu")
		(net "P3V3")
	)
	(segment
		(start 145.1864 -172.2628)
		(end 154.074622 -181.151022)
		(width 0.4572)
		(layer "In13.Cu")
		(net "P3V3")
	)
	(segment
		(start 140.114528 -174.064168)
		(end 141.915896 -172.2628)
		(width 0.4572)
		(layer "In13.Cu")
		(net "P3V3")
	)
	(segment
		(start 140.114528 -175.33112)
		(end 140.114528 -174.064168)
		(width 0.4572)
		(layer "In13.Cu")
		(net "P3V3")
	)
	(segment
		(start 358.788462 -96.778318)
		(end 358.788462 -97.846388)
		(width 0.4572)
		(layer "In13.Cu")
		(net "P3V3")
	)
	(segment
		(start 139.03325 -189.28207)
		(end 141.252956 -191.501776)
		(width 0.4572)
		(layer "In13.Cu")
		(net "P3V3")
	)
	(segment
		(start 356.40645 -100.2284)
		(end 341.451946 -100.2284)
		(width 0.4572)
		(layer "In13.Cu")
		(net "P3V3")
	)
	(segment
		(start 413.842708 -84.938108)
		(end 408.052016 -90.7288)
		(width 0.4572)
		(layer "In13.Cu")
		(net "P3V3")
	)
	(segment
		(start 336.6262 -100.2284)
		(end 335.6864 -99.2886)
		(width 0.4572)
		(layer "In13.Cu")
		(net "P3V3")
	)
	(segment
		(start 331.672438 -94.741238)
		(end 331.672438 -93.899482)
		(width 0.4572)
		(layer "In13.Cu")
		(net "P3V3")
	)
	(segment
		(start 367.953544 -93.61551)
		(end 366.669574 -93.61551)
		(width 0.4572)
		(layer "In13.Cu")
		(net "P3V3")
	)
	(segment
		(start 141.252956 -191.501776)
		(end 144.381982 -191.501776)
		(width 0.4572)
		(layer "In13.Cu")
		(net "P3V3")
	)
	(segment
		(start 366.669574 -93.61551)
		(end 366.212882 -93.158818)
		(width 0.4572)
		(layer "In13.Cu")
		(net "P3V3")
	)
	(segment
		(start 381.9652 -91.9988)
		(end 369.570254 -91.9988)
		(width 0.4572)
		(layer "In13.Cu")
		(net "P3V3")
	)
	(segment
		(start 366.212882 -93.158818)
		(end 362.407962 -93.158818)
		(width 0.4572)
		(layer "In13.Cu")
		(net "P3V3")
	)
	(segment
		(start 338.328 -102.6922)
		(end 337.4136 -101.7778)
		(width 0.4572)
		(layer "In13.Cu")
		(net "P3V3")
	)
	(segment
		(start 331.672438 -93.899482)
		(end 332.111096 -93.460824)
		(width 0.4572)
		(layer "In13.Cu")
		(net "P3V3")
	)
	(segment
		(start 383.2352 -90.7288)
		(end 381.9652 -91.9988)
		(width 0.4572)
		(layer "In13.Cu")
		(net "P3V3")
	)
	(segment
		(start 334.789272 -97.858072)
		(end 331.672438 -94.741238)
		(width 0.4572)
		(layer "In13.Cu")
		(net "P3V3")
	)
	(segment
		(start 332.111096 -93.460824)
		(end 332.783688 -93.460824)
		(width 0.4572)
		(layer "In13.Cu")
		(net "P3V3")
	)
	(segment
		(start 141.915896 -172.2628)
		(end 145.1864 -172.2628)
		(width 0.4572)
		(layer "In13.Cu")
		(net "P3V3")
	)
	(segment
		(start 341.451946 -100.2284)
		(end 338.988146 -102.6922)
		(width 0.4572)
		(layer "In13.Cu")
		(net "P3V3")
	)
	(segment
		(start 338.988146 -102.6922)
		(end 338.328 -102.6922)
		(width 0.4572)
		(layer "In13.Cu")
		(net "P3V3")
	)
	(segment
		(start 335.6864 -99.2886)
		(end 335.4324 -99.2886)
		(width 0.4572)
		(layer "In13.Cu")
		(net "P3V3")
	)
	(segment
		(start 408.052016 -90.7288)
		(end 383.2352 -90.7288)
		(width 0.4572)
		(layer "In13.Cu")
		(net "P3V3")
	)
	(segment
		(start 334.789272 -98.645472)
		(end 334.789272 -97.858072)
		(width 0.4572)
		(layer "In13.Cu")
		(net "P3V3")
	)
	(segment
		(start 133.012688 -189.28207)
		(end 139.03325 -189.28207)
		(width 0.4572)
		(layer "In13.Cu")
		(net "P3V3")
	)
	(segment
		(start 335.4324 -99.2886)
		(end 334.789272 -98.645472)
		(width 0.4572)
		(layer "In13.Cu")
		(net "P3V3")
	)
	(segment
		(start 362.407962 -93.158818)
		(end 358.788462 -96.778318)
		(width 0.4572)
		(layer "In13.Cu")
		(net "P3V3")
	)
	(segment
		(start 181.514496 -181.151022)
		(end 182.570374 -180.095144)
		(width 0.4572)
		(layer "In13.Cu")
		(net "P3V3")
	)
	(segment
		(start 369.570254 -91.9988)
		(end 367.953544 -93.61551)
		(width 0.4572)
		(layer "In13.Cu")
		(net "P3V3")
	)
	(segment
		(start 412.598616 -84.410804)
		(end 413.12592 -84.938108)
		(width 0.4572)
		(layer "In15.Cu")
		(net "P3V3")
	)
	(segment
		(start 408.418538 -84.410804)
		(end 412.598616 -84.410804)
		(width 0.4572)
		(layer "In15.Cu")
		(net "P3V3")
	)
	(segment
		(start 413.12592 -84.938108)
		(end 413.842708 -84.938108)
		(width 0.4572)
		(layer "In15.Cu")
		(net "P3V3")
	)
	(segment
		(start 391.799826 -293.04996)
		(end 391.324846 -292.57498)
		(width 0.13208)
		(layer "F.Cu")
		(net "SPI_PEX3_SDIO3")
	)
	(via
		(at 391.324846 -292.57498)
		(size 0.4064)
		(drill 0.2032)
		(layers "F.Cu" "B.Cu")
		(net "SPI_PEX3_SDIO3")
	)
	(via
		(at 387.999986 -290.42106)
		(size 0.6604)
		(drill 0.3302)
		(layers "F.Cu" "B.Cu")
		(net "SPI_PEX3_SDIO3")
	)
	(segment
		(start 387.999986 -290.42106)
		(end 387.999986 -289.174936)
		(width 0.13208)
		(layer "B.Cu")
		(net "SPI_PEX3_SDIO3")
	)
	(segment
		(start 389.914892 -291.378132)
		(end 389.914892 -291.718746)
		(width 0.13208)
		(layer "B.Cu")
		(net "SPI_PEX3_SDIO3")
	)
	(segment
		(start 387.999986 -290.42106)
		(end 388.675372 -291.096446)
		(width 0.13208)
		(layer "B.Cu")
		(net "SPI_PEX3_SDIO3")
	)
	(segment
		(start 390.240774 -292.044628)
		(end 390.794494 -292.044628)
		(width 0.13208)
		(layer "B.Cu")
		(net "SPI_PEX3_SDIO3")
	)
	(segment
		(start 389.633206 -291.096446)
		(end 389.914892 -291.378132)
		(width 0.13208)
		(layer "B.Cu")
		(net "SPI_PEX3_SDIO3")
	)
	(segment
		(start 390.794494 -292.044628)
		(end 391.324846 -292.57498)
		(width 0.13208)
		(layer "B.Cu")
		(net "SPI_PEX3_SDIO3")
	)
	(segment
		(start 389.914892 -291.718746)
		(end 390.240774 -292.044628)
		(width 0.13208)
		(layer "B.Cu")
		(net "SPI_PEX3_SDIO3")
	)
	(segment
		(start 388.675372 -291.096446)
		(end 389.633206 -291.096446)
		(width 0.13208)
		(layer "B.Cu")
		(net "SPI_PEX3_SDIO3")
	)
	(via
		(at 223.533716 -195.416932)
		(size 0.6604)
		(drill 0.3302)
		(layers "F.Cu" "B.Cu")
		(net "SPI_BIC1_MISO_R1")
	)
	(segment
		(start 223.533716 -195.416932)
		(end 223.533716 -194.159886)
		(width 0.13208)
		(layer "B.Cu")
		(net "SPI_BIC1_MISO_R1")
	)
	(segment
		(start 223.533716 -196.589142)
		(end 223.533716 -195.416932)
		(width 0.13208)
		(layer "B.Cu")
		(net "SPI_BIC1_MISO_R1")
	)
	(via
		(at 222.212154 -195.330318)
		(size 0.6604)
		(drill 0.3302)
		(layers "F.Cu" "B.Cu")
		(net "SPI_BIC1_MOSI_R1")
	)
	(segment
		(start 222.212154 -196.591682)
		(end 222.212154 -195.330318)
		(width 0.13208)
		(layer "B.Cu")
		(net "SPI_BIC1_MOSI_R1")
	)
	(segment
		(start 222.212154 -195.330318)
		(end 222.212154 -194.159886)
		(width 0.13208)
		(layer "B.Cu")
		(net "SPI_BIC1_MOSI_R1")
	)
	(via
		(at 225.19894 -195.432426)
		(size 0.6604)
		(drill 0.3302)
		(layers "F.Cu" "B.Cu")
		(net "SPI_BIC1_CLK_R1")
	)
	(segment
		(start 224.81794 -195.813426)
		(end 225.19894 -195.432426)
		(width 0.13208)
		(layer "B.Cu")
		(net "SPI_BIC1_CLK_R1")
	)
	(segment
		(start 225.19894 -195.432426)
		(end 225.19894 -194.159632)
		(width 0.13208)
		(layer "B.Cu")
		(net "SPI_BIC1_CLK_R1")
	)
	(segment
		(start 224.81794 -196.587872)
		(end 224.81794 -195.813426)
		(width 0.13208)
		(layer "B.Cu")
		(net "SPI_BIC1_CLK_R1")
	)
	(via
		(at 21.859494 -222.214186)
		(size 0.6604)
		(drill 0.3302)
		(layers "F.Cu" "B.Cu")
		(net "SPI_PEX0_SDIO0_MUX")
	)
	(segment
		(start 22.204172 -223.466152)
		(end 21.978112 -223.692212)
		(width 0.13208)
		(layer "B.Cu")
		(net "SPI_PEX0_SDIO0_MUX")
	)
	(segment
		(start 20.07616 -222.214186)
		(end 21.859494 -222.214186)
		(width 0.13208)
		(layer "B.Cu")
		(net "SPI_PEX0_SDIO0_MUX")
	)
	(segment
		(start 21.859494 -222.214186)
		(end 22.204172 -222.558864)
		(width 0.13208)
		(layer "B.Cu")
		(net "SPI_PEX0_SDIO0_MUX")
	)
	(segment
		(start 22.204172 -222.558864)
		(end 22.204172 -223.466152)
		(width 0.13208)
		(layer "B.Cu")
		(net "SPI_PEX0_SDIO0_MUX")
	)
	(segment
		(start 21.978112 -223.692212)
		(end 21.978112 -224.341182)
		(width 0.13208)
		(layer "B.Cu")
		(net "SPI_PEX0_SDIO0_MUX")
	)
	(via
		(at 23.184612 -226.776788)
		(size 0.6604)
		(drill 0.3302)
		(layers "F.Cu" "B.Cu")
		(net "SPI_PEX0_SDIO1_MUX")
	)
	(segment
		(start 23.184612 -226.776788)
		(end 23.212298 -226.804474)
		(width 0.13208)
		(layer "B.Cu")
		(net "SPI_PEX0_SDIO1_MUX")
	)
	(segment
		(start 20.859242 -226.465384)
		(end 22.873208 -226.465384)
		(width 0.13208)
		(layer "B.Cu")
		(net "SPI_PEX0_SDIO1_MUX")
	)
	(segment
		(start 20.073112 -224.341182)
		(end 20.073112 -225.679254)
		(width 0.13208)
		(layer "B.Cu")
		(net "SPI_PEX0_SDIO1_MUX")
	)
	(segment
		(start 22.873208 -226.465384)
		(end 23.184612 -226.776788)
		(width 0.13208)
		(layer "B.Cu")
		(net "SPI_PEX0_SDIO1_MUX")
	)
	(segment
		(start 20.073112 -225.679254)
		(end 20.859242 -226.465384)
		(width 0.13208)
		(layer "B.Cu")
		(net "SPI_PEX0_SDIO1_MUX")
	)
	(segment
		(start 23.212298 -226.804474)
		(end 23.212298 -227.94595)
		(width 0.13208)
		(layer "B.Cu")
		(net "SPI_PEX0_SDIO1_MUX")
	)
	(segment
		(start 230.66756 -212.704172)
		(end 230.497634 -212.294216)
		(width 0.13208)
		(layer "F.Cu")
		(net "SPI_BIC1_CS0_N")
	)
	(segment
		(start 230.110284 -205.35773)
		(end 230.3018 -205.820264)
		(width 0.13208)
		(layer "F.Cu")
		(net "SPI_BIC1_CS0_N")
	)
	(segment
		(start 229.858062 -211.654644)
		(end 229.858062 -208.820258)
		(width 0.13208)
		(layer "F.Cu")
		(net "SPI_BIC1_CS0_N")
	)
	(segment
		(start 229.858062 -208.820258)
		(end 229.85476 -208.816956)
		(width 0.13208)
		(layer "F.Cu")
		(net "SPI_BIC1_CS0_N")
	)
	(segment
		(start 229.85476 -208.135982)
		(end 229.594664 -207.875886)
		(width 0.13208)
		(layer "F.Cu")
		(net "SPI_BIC1_CS0_N")
	)
	(segment
		(start 229.594664 -207.875886)
		(end 229.594664 -207.42021)
		(width 0.13208)
		(layer "F.Cu")
		(net "SPI_BIC1_CS0_N")
	)
	(segment
		(start 229.85476 -208.816956)
		(end 229.85476 -208.626456)
		(width 0.13208)
		(layer "F.Cu")
		(net "SPI_BIC1_CS0_N")
	)
	(segment
		(start 229.594664 -204.84211)
		(end 230.110284 -205.35773)
		(width 0.13208)
		(layer "F.Cu")
		(net "SPI_BIC1_CS0_N")
	)
	(segment
		(start 229.85476 -208.626456)
		(end 229.85476 -208.135982)
		(width 0.13208)
		(layer "F.Cu")
		(net "SPI_BIC1_CS0_N")
	)
	(segment
		(start 230.3018 -207.165702)
		(end 230.047292 -207.42021)
		(width 0.13208)
		(layer "F.Cu")
		(net "SPI_BIC1_CS0_N")
	)
	(segment
		(start 230.047292 -207.42021)
		(end 229.594664 -207.42021)
		(width 0.13208)
		(layer "F.Cu")
		(net "SPI_BIC1_CS0_N")
	)
	(segment
		(start 230.497634 -212.294216)
		(end 229.858062 -211.654644)
		(width 0.13208)
		(layer "F.Cu")
		(net "SPI_BIC1_CS0_N")
	)
	(segment
		(start 230.3018 -205.820264)
		(end 230.3018 -207.165702)
		(width 0.13208)
		(layer "F.Cu")
		(net "SPI_BIC1_CS0_N")
	)
	(via
		(at 229.85476 -208.626456)
		(size 0.762)
		(drill 0.381)
		(layers "F.Cu" "B.Cu")
		(net "SPI_BIC1_CS0_N")
	)
	(via
		(at 224.763076 -199.333612)
		(size 0.6604)
		(drill 0.3302)
		(layers "F.Cu" "B.Cu")
		(net "SPI_BIC1_MISO_R")
	)
	(segment
		(start 224.763076 -199.333612)
		(end 224.763076 -200.584054)
		(width 0.13208)
		(layer "B.Cu")
		(net "SPI_BIC1_MISO_R")
	)
	(segment
		(start 224.763076 -199.333612)
		(end 224.369122 -198.939658)
		(width 0.13208)
		(layer "B.Cu")
		(net "SPI_BIC1_MISO_R")
	)
	(segment
		(start 223.91878 -197.389242)
		(end 223.533716 -197.389242)
		(width 0.13208)
		(layer "B.Cu")
		(net "SPI_BIC1_MISO_R")
	)
	(segment
		(start 224.161096 -197.631558)
		(end 223.91878 -197.389242)
		(width 0.13208)
		(layer "B.Cu")
		(net "SPI_BIC1_MISO_R")
	)
	(segment
		(start 224.369122 -198.939658)
		(end 224.161096 -198.4375)
		(width 0.13208)
		(layer "B.Cu")
		(net "SPI_BIC1_MISO_R")
	)
	(segment
		(start 224.161096 -198.4375)
		(end 224.161096 -197.631558)
		(width 0.13208)
		(layer "B.Cu")
		(net "SPI_BIC1_MISO_R")
	)
	(via
		(at 226.243388 -197.387972)
		(size 0.6604)
		(drill 0.3302)
		(layers "F.Cu" "B.Cu")
		(net "SPI_BIC1_CLK_R")
	)
	(segment
		(start 226.243388 -197.387972)
		(end 224.81794 -197.387972)
		(width 0.13208)
		(layer "B.Cu")
		(net "SPI_BIC1_CLK_R")
	)
	(segment
		(start 227.105464 -200.584054)
		(end 227.531422 -200.158096)
		(width 0.13208)
		(layer "B.Cu")
		(net "SPI_BIC1_CLK_R")
	)
	(segment
		(start 227.531422 -198.676006)
		(end 226.243388 -197.387972)
		(width 0.13208)
		(layer "B.Cu")
		(net "SPI_BIC1_CLK_R")
	)
	(segment
		(start 227.531422 -200.158096)
		(end 227.531422 -198.676006)
		(width 0.13208)
		(layer "B.Cu")
		(net "SPI_BIC1_CLK_R")
	)
	(segment
		(start 182.840884 -192.058798)
		(end 184.091834 -192.058798)
		(width 0.13208)
		(layer "F.Cu")
		(net "SPI_BIC1_LS01_EN_R_N")
	)
	(segment
		(start 181.697884 -192.058798)
		(end 182.840884 -192.058798)
		(width 0.13208)
		(layer "F.Cu")
		(net "SPI_BIC1_LS01_EN_R_N")
	)
	(segment
		(start 180.135276 -192.933574)
		(end 180.823108 -192.933574)
		(width 0.13208)
		(layer "F.Cu")
		(net "SPI_BIC1_LS01_EN_R_N")
	)
	(segment
		(start 180.823108 -192.933574)
		(end 181.697884 -192.058798)
		(width 0.13208)
		(layer "F.Cu")
		(net "SPI_BIC1_LS01_EN_R_N")
	)
	(via
		(at 182.840884 -192.058798)
		(size 0.762)
		(drill 0.381)
		(layers "F.Cu" "B.Cu")
		(net "SPI_BIC1_LS01_EN_R_N")
	)
	(segment
		(start 184.891934 -192.058798)
		(end 184.891934 -190.902082)
		(width 0.13208)
		(layer "F.Cu")
		(net "SPI_BIC1_LS01_EN_N")
	)
	(segment
		(start 180.208428 -190.641986)
		(end 179.594002 -190.02756)
		(width 0.13208)
		(layer "F.Cu")
		(net "SPI_BIC1_LS01_EN_N")
	)
	(segment
		(start 179.58181 -184.9247)
		(end 179.58181 -187.483496)
		(width 0.13208)
		(layer "F.Cu")
		(net "SPI_BIC1_LS01_EN_N")
	)
	(segment
		(start 184.891934 -190.902082)
		(end 184.631838 -190.641986)
		(width 0.13208)
		(layer "F.Cu")
		(net "SPI_BIC1_LS01_EN_N")
	)
	(segment
		(start 184.631838 -190.641986)
		(end 180.208428 -190.641986)
		(width 0.13208)
		(layer "F.Cu")
		(net "SPI_BIC1_LS01_EN_N")
	)
	(segment
		(start 179.594002 -190.02756)
		(end 179.594002 -187.495688)
		(width 0.13208)
		(layer "F.Cu")
		(net "SPI_BIC1_LS01_EN_N")
	)
	(segment
		(start 179.58181 -187.483496)
		(end 179.594002 -187.495688)
		(width 0.13208)
		(layer "F.Cu")
		(net "SPI_BIC1_LS01_EN_N")
	)
	(via
		(at 184.631838 -190.641986)
		(size 0.762)
		(drill 0.381)
		(layers "F.Cu" "B.Cu")
		(net "SPI_BIC1_LS01_EN_N")
	)
	(segment
		(start 233.407458 -206.372206)
		(end 233.407458 -211.676996)
		(width 0.13208)
		(layer "F.Cu")
		(net "SPI_BIC1_MISO")
	)
	(segment
		(start 232.66781 -212.558376)
		(end 232.66781 -213.104222)
		(width 0.13208)
		(layer "F.Cu")
		(net "SPI_BIC1_MISO")
	)
	(segment
		(start 233.121962 -205.916784)
		(end 233.121962 -206.08671)
		(width 0.13208)
		(layer "F.Cu")
		(net "SPI_BIC1_MISO")
	)
	(segment
		(start 233.121962 -206.08671)
		(end 233.407458 -206.372206)
		(width 0.13208)
		(layer "F.Cu")
		(net "SPI_BIC1_MISO")
	)
	(segment
		(start 233.594656 -205.44409)
		(end 233.121962 -205.916784)
		(width 0.13208)
		(layer "F.Cu")
		(net "SPI_BIC1_MISO")
	)
	(segment
		(start 233.407458 -211.676996)
		(end 232.767886 -212.316568)
		(width 0.13208)
		(layer "F.Cu")
		(net "SPI_BIC1_MISO")
	)
	(segment
		(start 232.767886 -212.316568)
		(end 232.66781 -212.558376)
		(width 0.13208)
		(layer "F.Cu")
		(net "SPI_BIC1_MISO")
	)
	(segment
		(start 232.66781 -213.104222)
		(end 232.26776 -213.504272)
		(width 0.13208)
		(layer "F.Cu")
		(net "SPI_BIC1_MISO")
	)
	(segment
		(start 234.64266 -204.84211)
		(end 233.594656 -204.84211)
		(width 0.13208)
		(layer "F.Cu")
		(net "SPI_BIC1_MISO")
	)
	(segment
		(start 233.594656 -204.84211)
		(end 233.594656 -205.44409)
		(width 0.13208)
		(layer "F.Cu")
		(net "SPI_BIC1_MISO")
	)
	(via
		(at 225.937064 -201.384154)
		(size 0.508)
		(drill 0.254)
		(layers "F.Cu" "B.Cu")
		(net "SPI_BIC1_MISO")
	)
	(via
		(at 233.121962 -206.08671)
		(size 0.508)
		(drill 0.254)
		(layers "F.Cu" "B.Cu")
		(net "SPI_BIC1_MISO")
	)
	(segment
		(start 224.763076 -201.384154)
		(end 225.937064 -201.384154)
		(width 0.13208)
		(layer "B.Cu")
		(net "SPI_BIC1_MISO")
	)
	(segment
		(start 233.5276 -204.04709)
		(end 233.5276 -203.194158)
		(width 0.15494)
		(layer "In9.Cu")
		(net "SPI_BIC1_MISO")
	)
	(segment
		(start 233.5276 -203.194158)
		(end 233.27741 -202.589892)
		(width 0.15494)
		(layer "In9.Cu")
		(net "SPI_BIC1_MISO")
	)
	(segment
		(start 227.8126 -200.496932)
		(end 225.937064 -201.384154)
		(width 0.15494)
		(layer "In9.Cu")
		(net "SPI_BIC1_MISO")
	)
	(segment
		(start 228.154992 -200.3552)
		(end 227.8126 -200.496932)
		(width 0.15494)
		(layer "In9.Cu")
		(net "SPI_BIC1_MISO")
	)
	(segment
		(start 228.850952 -200.3552)
		(end 228.154992 -200.3552)
		(width 0.15494)
		(layer "In9.Cu")
		(net "SPI_BIC1_MISO")
	)
	(segment
		(start 233.27741 -202.589892)
		(end 232.591864 -201.904346)
		(width 0.15494)
		(layer "In9.Cu")
		(net "SPI_BIC1_MISO")
	)
	(segment
		(start 232.591864 -201.904346)
		(end 228.850952 -200.3552)
		(width 0.15494)
		(layer "In9.Cu")
		(net "SPI_BIC1_MISO")
	)
	(segment
		(start 233.121962 -206.08671)
		(end 233.5276 -204.04709)
		(width 0.15494)
		(layer "In9.Cu")
		(net "SPI_BIC1_MISO")
	)
	(segment
		(start 230.602536 -211.67344)
		(end 230.602536 -210.785964)
		(width 0.13208)
		(layer "F.Cu")
		(net "SPI_BIC1_MOSI")
	)
	(segment
		(start 231.46766 -212.704172)
		(end 231.350566 -212.42147)
		(width 0.13208)
		(layer "F.Cu")
		(net "SPI_BIC1_MOSI")
	)
	(segment
		(start 231.350566 -212.42147)
		(end 230.602536 -211.67344)
		(width 0.13208)
		(layer "F.Cu")
		(net "SPI_BIC1_MOSI")
	)
	(via
		(at 223.53016 -201.384154)
		(size 0.508)
		(drill 0.254)
		(layers "F.Cu" "B.Cu")
		(net "SPI_BIC1_MOSI")
	)
	(via
		(at 230.602536 -210.785964)
		(size 0.508)
		(drill 0.254)
		(layers "F.Cu" "B.Cu")
		(net "SPI_BIC1_MOSI")
	)
	(segment
		(start 222.27413 -201.384154)
		(end 223.53016 -201.384154)
		(width 0.13208)
		(layer "B.Cu")
		(net "SPI_BIC1_MOSI")
	)
	(segment
		(start 223.53016 -203.590906)
		(end 224.332292 -204.393038)
		(width 0.15494)
		(layer "In9.Cu")
		(net "SPI_BIC1_MOSI")
	)
	(segment
		(start 229.800912 -207.005682)
		(end 229.800912 -209.98434)
		(width 0.15494)
		(layer "In9.Cu")
		(net "SPI_BIC1_MOSI")
	)
	(segment
		(start 224.332292 -204.393038)
		(end 229.525068 -204.393038)
		(width 0.15494)
		(layer "In9.Cu")
		(net "SPI_BIC1_MOSI")
	)
	(segment
		(start 230.3526 -206.453994)
		(end 229.800912 -207.005682)
		(width 0.15494)
		(layer "In9.Cu")
		(net "SPI_BIC1_MOSI")
	)
	(segment
		(start 223.53016 -201.384154)
		(end 223.53016 -203.590906)
		(width 0.15494)
		(layer "In9.Cu")
		(net "SPI_BIC1_MOSI")
	)
	(segment
		(start 229.800912 -209.98434)
		(end 230.602536 -210.785964)
		(width 0.15494)
		(layer "In9.Cu")
		(net "SPI_BIC1_MOSI")
	)
	(segment
		(start 230.3526 -205.22057)
		(end 230.3526 -206.453994)
		(width 0.15494)
		(layer "In9.Cu")
		(net "SPI_BIC1_MOSI")
	)
	(segment
		(start 229.525068 -204.393038)
		(end 230.3526 -205.22057)
		(width 0.15494)
		(layer "In9.Cu")
		(net "SPI_BIC1_MOSI")
	)
	(via
		(at 19.99869 -173.590204)
		(size 0.508)
		(drill 0.254)
		(layers "F.Cu" "B.Cu")
		(net "PWRGD_P5V_AUX")
	)
	(segment
		(start 21.334476 -173.590204)
		(end 19.99869 -173.590204)
		(width 0.13208)
		(layer "B.Cu")
		(net "PWRGD_P5V_AUX")
	)
	(segment
		(start 22.107652 -173.1772)
		(end 21.74748 -173.1772)
		(width 0.13208)
		(layer "B.Cu")
		(net "PWRGD_P5V_AUX")
	)
	(segment
		(start 21.74748 -173.1772)
		(end 21.334476 -173.590204)
		(width 0.13208)
		(layer "B.Cu")
		(net "PWRGD_P5V_AUX")
	)
	(via
		(at 20.970748 -172.729398)
		(size 0.508)
		(drill 0.254)
		(layers "F.Cu" "B.Cu")
		(net "P5V_AUX_FB")
	)
	(segment
		(start 232.505758 -206.65821)
		(end 232.505758 -211.493354)
		(width 0.13208)
		(layer "F.Cu")
		(net "SPI_BIC1_CLK")
	)
	(segment
		(start 232.591864 -204.84211)
		(end 232.591864 -205.369414)
		(width 0.13208)
		(layer "F.Cu")
		(net "SPI_BIC1_CLK")
	)
	(segment
		(start 232.505758 -211.493354)
		(end 232.295446 -212.000846)
		(width 0.13208)
		(layer "F.Cu")
		(net "SPI_BIC1_CLK")
	)
	(segment
		(start 232.083864 -206.236316)
		(end 232.505758 -206.65821)
		(width 0.13208)
		(layer "F.Cu")
		(net "SPI_BIC1_CLK")
	)
	(segment
		(start 232.295446 -212.676486)
		(end 232.26776 -212.704172)
		(width 0.13208)
		(layer "F.Cu")
		(net "SPI_BIC1_CLK")
	)
	(segment
		(start 231.502204 -204.84465)
		(end 232.589324 -204.84465)
		(width 0.13208)
		(layer "F.Cu")
		(net "SPI_BIC1_CLK")
	)
	(segment
		(start 231.499664 -204.84211)
		(end 231.502204 -204.84465)
		(width 0.13208)
		(layer "F.Cu")
		(net "SPI_BIC1_CLK")
	)
	(segment
		(start 232.083864 -205.877414)
		(end 232.083864 -206.236316)
		(width 0.13208)
		(layer "F.Cu")
		(net "SPI_BIC1_CLK")
	)
	(segment
		(start 232.295446 -212.000846)
		(end 232.295446 -212.676486)
		(width 0.13208)
		(layer "F.Cu")
		(net "SPI_BIC1_CLK")
	)
	(segment
		(start 232.589324 -204.84465)
		(end 232.591864 -204.84211)
		(width 0.13208)
		(layer "F.Cu")
		(net "SPI_BIC1_CLK")
	)
	(segment
		(start 232.591864 -205.369414)
		(end 232.083864 -205.877414)
		(width 0.13208)
		(layer "F.Cu")
		(net "SPI_BIC1_CLK")
	)
	(via
		(at 232.083864 -206.236316)
		(size 0.508)
		(drill 0.254)
		(layers "F.Cu" "B.Cu")
		(net "SPI_BIC1_CLK")
	)
	(via
		(at 228.279198 -201.241406)
		(size 0.508)
		(drill 0.254)
		(layers "F.Cu" "B.Cu")
		(net "SPI_BIC1_CLK")
	)
	(segment
		(start 228.279198 -201.241406)
		(end 227.757736 -201.241406)
		(width 0.13208)
		(layer "B.Cu")
		(net "SPI_BIC1_CLK")
	)
	(segment
		(start 227.757736 -201.241406)
		(end 227.614988 -201.384154)
		(width 0.13208)
		(layer "B.Cu")
		(net "SPI_BIC1_CLK")
	)
	(segment
		(start 227.614988 -201.384154)
		(end 227.105464 -201.384154)
		(width 0.13208)
		(layer "B.Cu")
		(net "SPI_BIC1_CLK")
	)
	(segment
		(start 232.083864 -205.926436)
		(end 231.595676 -204.747876)
		(width 0.15494)
		(layer "In9.Cu")
		(net "SPI_BIC1_CLK")
	)
	(segment
		(start 229.983538 -202.780392)
		(end 228.561392 -201.358246)
		(width 0.15494)
		(layer "In9.Cu")
		(net "SPI_BIC1_CLK")
	)
	(segment
		(start 230.234998 -203.387198)
		(end 229.983538 -202.780392)
		(width 0.15494)
		(layer "In9.Cu")
		(net "SPI_BIC1_CLK")
	)
	(segment
		(start 231.595676 -204.747876)
		(end 230.234998 -203.387198)
		(width 0.15494)
		(layer "In9.Cu")
		(net "SPI_BIC1_CLK")
	)
	(segment
		(start 232.083864 -206.236316)
		(end 232.083864 -205.926436)
		(width 0.15494)
		(layer "In9.Cu")
		(net "SPI_BIC1_CLK")
	)
	(segment
		(start 228.561392 -201.358246)
		(end 228.279198 -201.241406)
		(width 0.15494)
		(layer "In9.Cu")
		(net "SPI_BIC1_CLK")
	)
	(segment
		(start 23.326852 -172.574458)
		(end 24.646382 -172.574458)
		(width 0.13208)
		(layer "F.Cu")
		(net "SH_P5V_AUX_FB")
	)
	(via
		(at 24.646382 -172.574458)
		(size 0.762)
		(drill 0.381)
		(layers "F.Cu" "B.Cu")
		(net "SH_P5V_AUX_FB")
	)
	(via
		(at 21.55063 -167.603678)
		(size 0.508)
		(drill 0.254)
		(layers "F.Cu" "B.Cu")
		(net "SW_P12V_P5V_AUX_FLT")
	)
	(via
		(at 18.774156 -167.667178)
		(size 0.508)
		(drill 0.254)
		(layers "F.Cu" "B.Cu")
		(net "SW_P5V_AUX_BT")
	)
	(via
		(at 20.076922 -169.517314)
		(size 0.508)
		(drill 0.254)
		(layers "F.Cu" "B.Cu")
		(net "SW_P5V_AUX_BT")
	)
	(segment
		(start 20.076922 -169.517314)
		(end 19.434556 -168.874948)
		(width 0.508)
		(layer "B.Cu")
		(net "SW_P5V_AUX_BT")
	)
	(segment
		(start 19.434556 -168.327578)
		(end 18.774156 -167.667178)
		(width 0.508)
		(layer "B.Cu")
		(net "SW_P5V_AUX_BT")
	)
	(segment
		(start 19.434556 -168.874948)
		(end 19.434556 -168.327578)
		(width 0.508)
		(layer "B.Cu")
		(net "SW_P5V_AUX_BT")
	)
	(via
		(at 20.992592 -170.352466)
		(size 0.508)
		(drill 0.254)
		(layers "F.Cu" "B.Cu")
		(net "P5V_AUX_EN")
	)
	(segment
		(start 20.992592 -170.352466)
		(end 21.743924 -169.601134)
		(width 0.254)
		(layer "B.Cu")
		(net "P5V_AUX_EN")
	)
	(segment
		(start 21.743924 -169.601134)
		(end 21.743924 -168.768522)
		(width 0.254)
		(layer "B.Cu")
		(net "P5V_AUX_EN")
	)
	(segment
		(start 115.38966 -159.777176)
		(end 115.202208 -159.964628)
		(width 0.254)
		(layer "F.Cu")
		(net "SH_P3V3_AUX_FB")
	)
	(segment
		(start 115.202208 -159.964628)
		(end 115.202208 -160.471866)
		(width 0.254)
		(layer "F.Cu")
		(net "SH_P3V3_AUX_FB")
	)
	(segment
		(start 115.202208 -160.471866)
		(end 115.202208 -161.106866)
		(width 0.254)
		(layer "F.Cu")
		(net "SH_P3V3_AUX_FB")
	)
	(segment
		(start 115.202208 -162.122866)
		(end 115.202208 -161.106866)
		(width 0.254)
		(layer "F.Cu")
		(net "SH_P3V3_AUX_FB")
	)
	(via
		(at 115.202208 -160.471866)
		(size 0.508)
		(drill 0.254)
		(layers "F.Cu" "B.Cu")
		(net "SH_P3V3_AUX_FB")
	)
	(via
		(at 118.053104 -161.672524)
		(size 0.6604)
		(drill 0.3302)
		(layers "F.Cu" "B.Cu")
		(net "P3V3_AUX_VCC")
	)
	(via
		(at 107.686602 -158.947612)
		(size 0.508)
		(drill 0.254)
		(layers "F.Cu" "B.Cu")
		(net "P3V3_AUX_VCC")
	)
	(segment
		(start 109.309154 -157.32506)
		(end 113.70564 -157.32506)
		(width 0.508)
		(layer "B.Cu")
		(net "P3V3_AUX_VCC")
	)
	(segment
		(start 113.70564 -157.32506)
		(end 118.053104 -161.672524)
		(width 0.508)
		(layer "B.Cu")
		(net "P3V3_AUX_VCC")
	)
	(segment
		(start 107.686602 -158.947612)
		(end 109.309154 -157.32506)
		(width 0.508)
		(layer "B.Cu")
		(net "P3V3_AUX_VCC")
	)
	(segment
		(start 118.053104 -161.672524)
		(end 118.053104 -163.598098)
		(width 0.508)
		(layer "B.Cu")
		(net "P3V3_AUX_VCC")
	)
	(segment
		(start 113.771934 -160.220406)
		(end 114.23523 -159.75711)
		(width 0.254)
		(layer "F.Cu")
		(net "P3V3_AUX_REF")
	)
	(segment
		(start 112.37468 -160.772094)
		(end 112.898428 -160.248346)
		(width 0.1778)
		(layer "F.Cu")
		(net "P3V3_AUX_REF")
	)
	(segment
		(start 114.23523 -159.75711)
		(end 114.23523 -159.67329)
		(width 0.254)
		(layer "F.Cu")
		(net "P3V3_AUX_REF")
	)
	(segment
		(start 111.274098 -160.772094)
		(end 112.37468 -160.772094)
		(width 0.1778)
		(layer "F.Cu")
		(net "P3V3_AUX_REF")
	)
	(segment
		(start 112.898428 -160.248346)
		(end 113.018316 -160.248346)
		(width 0.1778)
		(layer "F.Cu")
		(net "P3V3_AUX_REF")
	)
	(segment
		(start 113.743994 -160.248346)
		(end 113.771934 -160.220406)
		(width 0.254)
		(layer "F.Cu")
		(net "P3V3_AUX_REF")
	)
	(segment
		(start 113.018316 -160.248346)
		(end 113.743994 -160.248346)
		(width 0.254)
		(layer "F.Cu")
		(net "P3V3_AUX_REF")
	)
	(via
		(at 113.771934 -160.220406)
		(size 0.508)
		(drill 0.254)
		(layers "F.Cu" "B.Cu")
		(net "P3V3_AUX_REF")
	)
	(segment
		(start 111.981488 -162.057842)
		(end 112.055148 -162.131502)
		(width 0.13208)
		(layer "F.Cu")
		(net "P3V3_AUX_EN")
	)
	(segment
		(start 112.631982 -162.708336)
		(end 112.055148 -162.131502)
		(width 0.13208)
		(layer "F.Cu")
		(net "P3V3_AUX_EN")
	)
	(segment
		(start 111.274098 -161.97199)
		(end 111.774224 -161.97199)
		(width 0.13208)
		(layer "F.Cu")
		(net "P3V3_AUX_EN")
	)
	(segment
		(start 111.774224 -161.97199)
		(end 111.981488 -162.057842)
		(width 0.13208)
		(layer "F.Cu")
		(net "P3V3_AUX_EN")
	)
	(segment
		(start 112.631982 -162.782504)
		(end 112.631982 -162.708336)
		(width 0.13208)
		(layer "F.Cu")
		(net "P3V3_AUX_EN")
	)
	(via
		(at 112.055148 -162.131502)
		(size 0.508)
		(drill 0.254)
		(layers "F.Cu" "B.Cu")
		(net "P3V3_AUX_EN")
	)
	(segment
		(start 114.402108 -161.106866)
		(end 114.402108 -162.122866)
		(width 0.254)
		(layer "F.Cu")
		(net "P3V3_AUX_FB")
	)
	(segment
		(start 111.274098 -161.572194)
		(end 111.966502 -161.572194)
		(width 0.1778)
		(layer "F.Cu")
		(net "P3V3_AUX_FB")
	)
	(segment
		(start 113.608866 -161.805874)
		(end 112.973866 -161.805874)
		(width 0.254)
		(layer "F.Cu")
		(net "P3V3_AUX_FB")
	)
	(segment
		(start 113.940082 -162.122866)
		(end 113.62309 -161.805874)
		(width 0.254)
		(layer "F.Cu")
		(net "P3V3_AUX_FB")
	)
	(segment
		(start 111.980472 -161.586164)
		(end 112.348772 -161.586164)
		(width 0.254)
		(layer "F.Cu")
		(net "P3V3_AUX_FB")
	)
	(segment
		(start 114.402108 -162.122866)
		(end 113.940082 -162.122866)
		(width 0.254)
		(layer "F.Cu")
		(net "P3V3_AUX_FB")
	)
	(segment
		(start 113.62309 -161.805874)
		(end 113.608866 -161.805874)
		(width 0.254)
		(layer "F.Cu")
		(net "P3V3_AUX_FB")
	)
	(segment
		(start 112.568482 -161.805874)
		(end 112.973866 -161.805874)
		(width 0.254)
		(layer "F.Cu")
		(net "P3V3_AUX_FB")
	)
	(segment
		(start 112.348772 -161.586164)
		(end 112.568482 -161.805874)
		(width 0.254)
		(layer "F.Cu")
		(net "P3V3_AUX_FB")
	)
	(segment
		(start 111.966502 -161.572194)
		(end 111.980472 -161.586164)
		(width 0.1778)
		(layer "F.Cu")
		(net "P3V3_AUX_FB")
	)
	(via
		(at 113.608866 -161.805874)
		(size 0.508)
		(drill 0.254)
		(layers "F.Cu" "B.Cu")
		(net "P3V3_AUX_FB")
	)
	(segment
		(start 113.193068 -163.271962)
		(end 113.534698 -163.41344)
		(width 0.13208)
		(layer "F.Cu")
		(net "PWRGD_P3V3_AUX")
	)
	(segment
		(start 112.290606 -163.166552)
		(end 112.54486 -163.271962)
		(width 0.13208)
		(layer "F.Cu")
		(net "PWRGD_P3V3_AUX")
	)
	(segment
		(start 114.400838 -163.217352)
		(end 114.008154 -163.217352)
		(width 0.13208)
		(layer "F.Cu")
		(net "PWRGD_P3V3_AUX")
	)
	(segment
		(start 114.008154 -163.217352)
		(end 113.534698 -163.41344)
		(width 0.13208)
		(layer "F.Cu")
		(net "PWRGD_P3V3_AUX")
	)
	(segment
		(start 111.700818 -162.576764)
		(end 112.290606 -163.166552)
		(width 0.13208)
		(layer "F.Cu")
		(net "PWRGD_P3V3_AUX")
	)
	(segment
		(start 112.54486 -163.271962)
		(end 113.193068 -163.271962)
		(width 0.13208)
		(layer "F.Cu")
		(net "PWRGD_P3V3_AUX")
	)
	(segment
		(start 111.448342 -162.472116)
		(end 111.700818 -162.576764)
		(width 0.13208)
		(layer "F.Cu")
		(net "PWRGD_P3V3_AUX")
	)
	(segment
		(start 111.274098 -162.472116)
		(end 111.448342 -162.472116)
		(width 0.13208)
		(layer "F.Cu")
		(net "PWRGD_P3V3_AUX")
	)
	(via
		(at 117.253004 -164.802058)
		(size 0.6604)
		(drill 0.3302)
		(layers "F.Cu" "B.Cu")
		(net "PWRGD_P3V3_AUX")
	)
	(via
		(at 113.534698 -163.41344)
		(size 0.508)
		(drill 0.254)
		(layers "F.Cu" "B.Cu")
		(net "PWRGD_P3V3_AUX")
	)
	(segment
		(start 113.534698 -163.41344)
		(end 114.10188 -163.41344)
		(width 0.13208)
		(layer "B.Cu")
		(net "PWRGD_P3V3_AUX")
	)
	(segment
		(start 115.490498 -164.802058)
		(end 117.253004 -164.802058)
		(width 0.13208)
		(layer "B.Cu")
		(net "PWRGD_P3V3_AUX")
	)
	(segment
		(start 114.10188 -163.41344)
		(end 115.490498 -164.802058)
		(width 0.13208)
		(layer "B.Cu")
		(net "PWRGD_P3V3_AUX")
	)
	(segment
		(start 117.253004 -163.598098)
		(end 117.253004 -164.802058)
		(width 0.13208)
		(layer "B.Cu")
		(net "PWRGD_P3V3_AUX")
	)
	(segment
		(start 112.067848 -159.677862)
		(end 112.558322 -159.677862)
		(width 0.1778)
		(layer "F.Cu")
		(net "P3V3_AUX_CS")
	)
	(segment
		(start 113.212372 -159.680148)
		(end 113.21923 -159.67329)
		(width 0.254)
		(layer "F.Cu")
		(net "P3V3_AUX_CS")
	)
	(segment
		(start 112.558576 -159.678116)
		(end 112.558576 -159.681418)
		(width 0.1778)
		(layer "F.Cu")
		(net "P3V3_AUX_CS")
	)
	(segment
		(start 112.559846 -159.680148)
		(end 113.212372 -159.680148)
		(width 0.254)
		(layer "F.Cu")
		(net "P3V3_AUX_CS")
	)
	(segment
		(start 112.558576 -159.681418)
		(end 112.559846 -159.680148)
		(width 0.254)
		(layer "F.Cu")
		(net "P3V3_AUX_CS")
	)
	(segment
		(start 111.274098 -159.971994)
		(end 111.773716 -159.971994)
		(width 0.1778)
		(layer "F.Cu")
		(net "P3V3_AUX_CS")
	)
	(segment
		(start 112.558322 -159.677862)
		(end 112.558576 -159.678116)
		(width 0.1778)
		(layer "F.Cu")
		(net "P3V3_AUX_CS")
	)
	(segment
		(start 111.773716 -159.971994)
		(end 112.067848 -159.677862)
		(width 0.1778)
		(layer "F.Cu")
		(net "P3V3_AUX_CS")
	)
	(via
		(at 112.558576 -159.681418)
		(size 0.508)
		(drill 0.254)
		(layers "F.Cu" "B.Cu")
		(net "P3V3_AUX_CS")
	)
	(segment
		(start 102.728776 -223.135698)
		(end 101.881432 -223.135698)
		(width 0.254)
		(layer "F.Cu")
		(net "P1V8_PEX_REF")
	)
	(segment
		(start 103.075232 -222.789242)
		(end 102.728776 -223.135698)
		(width 0.1778)
		(layer "F.Cu")
		(net "P1V8_PEX_REF")
	)
	(segment
		(start 104.378252 -222.706692)
		(end 103.274622 -222.706692)
		(width 0.1778)
		(layer "F.Cu")
		(net "P1V8_PEX_REF")
	)
	(segment
		(start 103.274622 -222.706692)
		(end 103.075232 -222.789242)
		(width 0.1778)
		(layer "F.Cu")
		(net "P1V8_PEX_REF")
	)
	(segment
		(start 101.477064 -223.540066)
		(end 101.881432 -223.135698)
		(width 0.254)
		(layer "F.Cu")
		(net "P1V8_PEX_REF")
	)
	(segment
		(start 101.359208 -223.824292)
		(end 101.477064 -223.540066)
		(width 0.254)
		(layer "F.Cu")
		(net "P1V8_PEX_REF")
	)
	(via
		(at 101.881432 -223.135698)
		(size 0.508)
		(drill 0.254)
		(layers "F.Cu" "B.Cu")
		(net "P1V8_PEX_REF")
	)
	(segment
		(start 104.378252 -221.906592)
		(end 103.685848 -221.906592)
		(width 0.1778)
		(layer "F.Cu")
		(net "P1V8_PEX_FB")
	)
	(segment
		(start 103.685848 -221.906592)
		(end 103.443278 -221.664022)
		(width 0.1778)
		(layer "F.Cu")
		(net "P1V8_PEX_FB")
	)
	(segment
		(start 100.583746 -221.146116)
		(end 100.429568 -221.300294)
		(width 0.13208)
		(layer "F.Cu")
		(net "P1V8_PEX_FB")
	)
	(segment
		(start 100.429568 -221.664022)
		(end 100.42906 -221.66453)
		(width 0.254)
		(layer "F.Cu")
		(net "P1V8_PEX_FB")
	)
	(segment
		(start 101.439726 -221.664022)
		(end 102.483412 -221.664022)
		(width 0.254)
		(layer "F.Cu")
		(net "P1V8_PEX_FB")
	)
	(segment
		(start 100.947474 -221.146116)
		(end 100.583746 -221.146116)
		(width 0.13208)
		(layer "F.Cu")
		(net "P1V8_PEX_FB")
	)
	(segment
		(start 103.443278 -221.664022)
		(end 102.483412 -221.664022)
		(width 0.254)
		(layer "F.Cu")
		(net "P1V8_PEX_FB")
	)
	(segment
		(start 101.439726 -221.664022)
		(end 100.429568 -221.664022)
		(width 0.254)
		(layer "F.Cu")
		(net "P1V8_PEX_FB")
	)
	(segment
		(start 100.429568 -221.300294)
		(end 100.429568 -221.664022)
		(width 0.13208)
		(layer "F.Cu")
		(net "P1V8_PEX_FB")
	)
	(via
		(at 100.947474 -221.146116)
		(size 0.508)
		(drill 0.254)
		(layers "F.Cu" "B.Cu")
		(net "P1V8_PEX_FB")
	)
	(segment
		(start 25.358344 -249.670824)
		(end 25.358344 -249.00382)
		(width 0.4572)
		(layer "F.Cu")
		(net "P1V8_PEX")
	)
	(segment
		(start 260.038596 -310.693816)
		(end 260.618478 -310.113934)
		(width 0.4572)
		(layer "F.Cu")
		(net "P1V8_PEX")
	)
	(segment
		(start 301.349918 -289.249866)
		(end 301.824898 -288.774886)
		(width 0.249936)
		(layer "F.Cu")
		(net "P1V8_PEX")
	)
	(segment
		(start 322.896484 -299.27296)
		(end 323.561456 -299.27296)
		(width 0.4572)
		(layer "F.Cu")
		(net "P1V8_PEX")
	)
	(segment
		(start 21.39061 -310.978042)
		(end 25.783286 -306.585366)
		(width 0.4572)
		(layer "F.Cu")
		(net "P1V8_PEX")
	)
	(segment
		(start 27.103832 -307.52034)
		(end 26.295604 -308.328568)
		(width 0.4572)
		(layer "F.Cu")
		(net "P1V8_PEX")
	)
	(segment
		(start 208.546446 -309.877714)
		(end 208.335626 -309.877714)
		(width 0.4572)
		(layer "F.Cu")
		(net "P1V8_PEX")
	)
	(segment
		(start 258.555236 -306.771802)
		(end 259.303774 -307.52034)
		(width 0.4572)
		(layer "F.Cu")
		(net "P1V8_PEX")
	)
	(segment
		(start 213.062566 -235.356908)
		(end 213.697566 -235.356908)
		(width 0.4572)
		(layer "F.Cu")
		(net "P1V8_PEX")
	)
	(segment
		(start 378.667772 -304.90668)
		(end 378.021088 -304.90668)
		(width 0.4572)
		(layer "F.Cu")
		(net "P1V8_PEX")
	)
	(segment
		(start 323.88937 -295.647872)
		(end 323.88937 -296.556684)
		(width 0.4572)
		(layer "F.Cu")
		(net "P1V8_PEX")
	)
	(segment
		(start 206.158592 -312.637932)
		(end 205.75016 -312.2295)
		(width 0.4572)
		(layer "F.Cu")
		(net "P1V8_PEX")
	)
	(segment
		(start 37.550344 -249.670824)
		(end 38.566344 -249.670824)
		(width 0.4572)
		(layer "F.Cu")
		(net "P1V8_PEX")
	)
	(segment
		(start 86.031578 -298.016168)
		(end 85.757766 -298.28998)
		(width 0.3556)
		(layer "F.Cu")
		(net "P1V8_PEX")
	)
	(segment
		(start 181.110636 -197.687438)
		(end 181.110636 -198.068946)
		(width 0.3556)
		(layer "F.Cu")
		(net "P1V8_PEX")
	)
	(segment
		(start 26.374344 -249.670824)
		(end 27.390344 -249.670824)
		(width 0.4572)
		(layer "F.Cu")
		(net "P1V8_PEX")
	)
	(segment
		(start 32.852614 -307.850794)
		(end 32.134302 -308.569106)
		(width 0.4572)
		(layer "F.Cu")
		(net "P1V8_PEX")
	)
	(segment
		(start 45.39996 -293.04996)
		(end 44.92498 -292.57498)
		(width 0.249936)
		(layer "F.Cu")
		(net "P1V8_PEX")
	)
	(segment
		(start 45.39996 -291.149786)
		(end 44.92498 -290.674806)
		(width 0.249936)
		(layer "F.Cu")
		(net "P1V8_PEX")
	)
	(segment
		(start 85.757766 -298.6405)
		(end 84.3407 -298.6405)
		(width 0.4572)
		(layer "F.Cu")
		(net "P1V8_PEX")
	)
	(segment
		(start 325.26605 -306.474622)
		(end 325.296276 -306.504848)
		(width 0.4572)
		(layer "F.Cu")
		(net "P1V8_PEX")
	)
	(segment
		(start 377.668536 -309.170578)
		(end 377.668536 -310.113934)
		(width 0.4572)
		(layer "F.Cu")
		(net "P1V8_PEX")
	)
	(segment
		(start 440.350148 -306.474622)
		(end 441.366148 -306.474622)
		(width 0.4572)
		(layer "F.Cu")
		(net "P1V8_PEX")
	)
	(segment
		(start 262.638286 -249.670824)
		(end 261.622286 -249.670824)
		(width 0.4572)
		(layer "F.Cu")
		(net "P1V8_PEX")
	)
	(segment
		(start 91.034108 -306.474622)
		(end 92.050108 -306.474622)
		(width 0.4572)
		(layer "F.Cu")
		(net "P1V8_PEX")
	)
	(segment
		(start 146.907758 -307.731414)
		(end 147.396454 -307.731414)
		(width 0.4572)
		(layer "F.Cu")
		(net "P1V8_PEX")
	)
	(segment
		(start 155.344114 -249.670824)
		(end 154.666442 -249.670824)
		(width 0.4572)
		(layer "F.Cu")
		(net "P1V8_PEX")
	)
	(segment
		(start 298.156122 -198.947024)
		(end 298.464224 -198.638922)
		(width 0.3556)
		(layer "F.Cu")
		(net "P1V8_PEX")
	)
	(segment
		(start 155.682442 -250.009152)
		(end 155.682442 -251.956824)
		(width 0.4572)
		(layer "F.Cu")
		(net "P1V8_PEX")
	)
	(segment
		(start 147.396454 -307.731414)
		(end 148.234146 -308.569106)
		(width 0.4572)
		(layer "F.Cu")
		(net "P1V8_PEX")
	)
	(segment
		(start 277.599902 -291.149786)
		(end 277.124922 -290.674806)
		(width 0.249936)
		(layer "F.Cu")
		(net "P1V8_PEX")
	)
	(segment
		(start 28.418536 -310.113934)
		(end 27.838654 -310.693816)
		(width 0.4572)
		(layer "F.Cu")
		(net "P1V8_PEX")
	)
	(segment
		(start 261.622286 -249.670824)
		(end 260.606286 -249.670824)
		(width 0.4572)
		(layer "F.Cu")
		(net "P1V8_PEX")
	)
	(segment
		(start 202.131676 -297.918124)
		(end 201.857864 -298.191936)
		(width 0.3556)
		(layer "F.Cu")
		(net "P1V8_PEX")
	)
	(segment
		(start 319.563242 -308.880002)
		(end 321.20205 -307.241194)
		(width 0.4572)
		(layer "F.Cu")
		(net "P1V8_PEX")
	)
	(segment
		(start 253.713488 -253.876556)
		(end 253.969266 -253.620778)
		(width 0.4572)
		(layer "F.Cu")
		(net "P1V8_PEX")
	)
	(segment
		(start 145.522442 -249.670824)
		(end 146.538442 -249.670824)
		(width 0.4572)
		(layer "F.Cu")
		(net "P1V8_PEX")
	)
	(segment
		(start 387.882384 -250.03887)
		(end 387.882384 -251.956824)
		(width 0.4572)
		(layer "F.Cu")
		(net "P1V8_PEX")
	)
	(segment
		(start 265.052556 -307.850794)
		(end 264.334244 -308.569106)
		(width 0.4572)
		(layer "F.Cu")
		(net "P1V8_PEX")
	)
	(segment
		(start 69.149976 -302.549814)
		(end 69.624956 -303.024794)
		(width 0.249936)
		(layer "F.Cu")
		(net "P1V8_PEX")
	)
	(segment
		(start 256.542286 -249.670824)
		(end 257.558286 -249.670824)
		(width 0.4572)
		(layer "F.Cu")
		(net "P1V8_PEX")
	)
	(segment
		(start 441.712096 -307.399944)
		(end 441.396374 -307.084222)
		(width 0.4572)
		(layer "F.Cu")
		(net "P1V8_PEX")
	)
	(segment
		(start 26.295604 -308.328568)
		(end 25.82799 -308.796182)
		(width 0.4572)
		(layer "F.Cu")
		(net "P1V8_PEX")
	)
	(segment
		(start 146.078956 -310.724296)
		(end 145.468594 -310.113934)
		(width 0.4572)
		(layer "F.Cu")
		(net "P1V8_PEX")
	)
	(segment
		(start 325.197724 -297.374818)
		(end 325.197724 -296.765218)
		(width 0.4572)
		(layer "F.Cu")
		(net "P1V8_PEX")
	)
	(segment
		(start 417.924996 -288.774886)
		(end 417.450016 -289.249866)
		(width 0.249936)
		(layer "F.Cu")
		(net "P1V8_PEX")
	)
	(segment
		(start 29.721048 -304.90668)
		(end 30.367732 -304.90668)
		(width 0.4572)
		(layer "F.Cu")
		(net "P1V8_PEX")
	)
	(segment
		(start 260.038596 -310.756554)
		(end 260.038596 -310.693816)
		(width 0.4572)
		(layer "F.Cu")
		(net "P1V8_PEX")
	)
	(segment
		(start 382.802384 -249.670824)
		(end 381.786384 -249.670824)
		(width 0.4572)
		(layer "F.Cu")
		(net "P1V8_PEX")
	)
	(segment
		(start 301.349918 -290.199826)
		(end 301.824898 -289.724846)
		(width 0.249936)
		(layer "F.Cu")
		(net "P1V8_PEX")
	)
	(segment
		(start 145.468594 -310.113934)
		(end 144.518634 -310.113934)
		(width 0.4572)
		(layer "F.Cu")
		(net "P1V8_PEX")
	)
	(segment
		(start 261.46252 -305.36515)
		(end 261.458964 -305.36515)
		(width 0.4572)
		(layer "F.Cu")
		(net "P1V8_PEX")
	)
	(segment
		(start 377.722384 -249.670824)
		(end 376.706384 -249.670824)
		(width 0.4572)
		(layer "F.Cu")
		(net "P1V8_PEX")
	)
	(segment
		(start 208.150206 -306.474622)
		(end 209.166206 -306.474622)
		(width 0.4572)
		(layer "F.Cu")
		(net "P1V8_PEX")
	)
	(segment
		(start 31.454344 -249.670824)
		(end 32.470344 -249.670824)
		(width 0.4572)
		(layer "F.Cu")
		(net "P1V8_PEX")
	)
	(segment
		(start 205.031594 -311.510934)
		(end 204.313028 -310.792368)
		(width 0.4572)
		(layer "F.Cu")
		(net "P1V8_PEX")
	)
	(segment
		(start 258.555236 -305.854862)
		(end 258.555236 -306.771802)
		(width 0.4572)
		(layer "F.Cu")
		(net "P1V8_PEX")
	)
	(segment
		(start 417.450016 -290.199826)
		(end 417.924996 -289.724846)
		(width 0.249936)
		(layer "F.Cu")
		(net "P1V8_PEX")
	)
	(segment
		(start 89.002108 -306.474622)
		(end 90.018108 -306.474622)
		(width 0.4572)
		(layer "F.Cu")
		(net "P1V8_PEX")
	)
	(segment
		(start 145.35912 -305.36515)
		(end 145.362676 -305.36515)
		(width 0.4572)
		(layer "F.Cu")
		(net "P1V8_PEX")
	)
	(segment
		(start 151.618442 -249.670824)
		(end 152.634442 -249.670824)
		(width 0.4572)
		(layer "F.Cu")
		(net "P1V8_PEX")
	)
	(segment
		(start 380.434342 -308.569106)
		(end 380.434088 -308.569106)
		(width 0.4572)
		(layer "F.Cu")
		(net "P1V8_PEX")
	)
	(segment
		(start 375.606564 -304.456084)
		(end 376.2629 -304.456084)
		(width 0.4572)
		(layer "F.Cu")
		(net "P1V8_PEX")
	)
	(segment
		(start 185.725054 -290.674806)
		(end 185.250074 -290.199826)
		(width 0.249936)
		(layer "F.Cu")
		(net "P1V8_PEX")
	)
	(segment
		(start 319.694306 -310.07431)
		(end 319.563242 -309.943246)
		(width 0.4572)
		(layer "F.Cu")
		(net "P1V8_PEX")
	)
	(segment
		(start 30.696916 -310.006238)
		(end 29.978858 -310.724296)
		(width 0.4572)
		(layer "F.Cu")
		(net "P1V8_PEX")
	)
	(segment
		(start 272.798286 -249.080274)
		(end 272.798286 -249.670824)
		(width 0.4572)
		(layer "F.Cu")
		(net "P1V8_PEX")
	)
	(segment
		(start 417.924996 -289.724846)
		(end 417.450016 -289.249866)
		(width 0.249936)
		(layer "F.Cu")
		(net "P1V8_PEX")
	)
	(segment
		(start 369.813586 -253.876556)
		(end 370.069364 -253.620778)
		(width 0.4572)
		(layer "F.Cu")
		(net "P1V8_PEX")
	)
	(segment
		(start 328.69505 -233.553)
		(end 328.69505 -232.918)
		(width 0.4572)
		(layer "F.Cu")
		(net "P1V8_PEX")
	)
	(segment
		(start 338.47405 -174.117)
		(end 339.09 -174.117)
		(width 0.4572)
		(layer "F.Cu")
		(net "P1V8_PEX")
	)
	(segment
		(start 26.822654 -310.756554)
		(end 27.838654 -310.756554)
		(width 0.4572)
		(layer "F.Cu")
		(net "P1V8_PEX")
	)
	(segment
		(start 263.193276 -225.481896)
		(end 258.920742 -225.481896)
		(width 0.4572)
		(layer "F.Cu")
		(net "P1V8_PEX")
	)
	(segment
		(start 301.349918 -300.649894)
		(end 301.824898 -301.124874)
		(width 0.249936)
		(layer "F.Cu")
		(net "P1V8_PEX")
	)
	(segment
		(start 380.770384 -249.670824)
		(end 379.754384 -249.670824)
		(width 0.4572)
		(layer "F.Cu")
		(net "P1V8_PEX")
	)
	(segment
		(start 87.3633 -309.943246)
		(end 87.3633 -308.880002)
		(width 0.4572)
		(layer "F.Cu")
		(net "P1V8_PEX")
	)
	(segment
		(start 24.780494 -278.443182)
		(end 21.171662 -274.83435)
		(width 0.4572)
		(layer "F.Cu")
		(net "P1V8_PEX")
	)
	(segment
		(start 142.268956 -305.59375)
		(end 143.406622 -304.456084)
		(width 0.4572)
		(layer "F.Cu")
		(net "P1V8_PEX")
	)
	(segment
		(start 30.367732 -304.90668)
		(end 30.80766 -305.346608)
		(width 0.4572)
		(layer "F.Cu")
		(net "P1V8_PEX")
	)
	(segment
		(start 140.442442 -249.670824)
		(end 141.458442 -249.670824)
		(width 0.4572)
		(layer "F.Cu")
		(net "P1V8_PEX")
	)
	(segment
		(start 265.686286 -249.670824)
		(end 264.670286 -249.670824)
		(width 0.4572)
		(layer "F.Cu")
		(net "P1V8_PEX")
	)
	(segment
		(start 92.032328 -312.48731)
		(end 91.881706 -312.637932)
		(width 0.4572)
		(layer "F.Cu")
		(net "P1V8_PEX")
	)
	(segment
		(start 258.574286 -249.670824)
		(end 257.558286 -249.670824)
		(width 0.4572)
		(layer "F.Cu")
		(net "P1V8_PEX")
	)
	(segment
		(start 93.412056 -308.912006)
		(end 92.446348 -309.877714)
		(width 0.4572)
		(layer "F.Cu")
		(net "P1V8_PEX")
	)
	(segment
		(start 93.096334 -306.504848)
		(end 93.096334 -307.084222)
		(width 0.4572)
		(layer "F.Cu")
		(net "P1V8_PEX")
	)
	(segment
		(start 207.789526 -295.647872)
		(end 207.789526 -296.556684)
		(width 0.4572)
		(layer "F.Cu")
		(net "P1V8_PEX")
	)
	(segment
		(start 26.168858 -305.59375)
		(end 27.306524 -304.456084)
		(width 0.4572)
		(layer "F.Cu")
		(net "P1V8_PEX")
	)
	(segment
		(start 89.002108 -307.241194)
		(end 89.002108 -306.474622)
		(width 0.4572)
		(layer "F.Cu")
		(net "P1V8_PEX")
	)
	(segment
		(start 141.458442 -249.670824)
		(end 142.474442 -249.670824)
		(width 0.4572)
		(layer "F.Cu")
		(net "P1V8_PEX")
	)
	(segment
		(start 146.797014 -310.006238)
		(end 146.078956 -310.724296)
		(width 0.4572)
		(layer "F.Cu")
		(net "P1V8_PEX")
	)
	(segment
		(start 29.262578 -305.36515)
		(end 29.721048 -304.90668)
		(width 0.4572)
		(layer "F.Cu")
		(net "P1V8_PEX")
	)
	(segment
		(start 181.110636 -198.068946)
		(end 181.023768 -198.155814)
		(width 0.3556)
		(layer "F.Cu")
		(net "P1V8_PEX")
	)
	(segment
		(start 417.450016 -300.649894)
		(end 417.924996 -301.124874)
		(width 0.249936)
		(layer "F.Cu")
		(net "P1V8_PEX")
	)
	(segment
		(start 324.25005 -306.474622)
		(end 325.26605 -306.474622)
		(width 0.4572)
		(layer "F.Cu")
		(net "P1V8_PEX")
	)
	(segment
		(start 161.500058 -294.94988)
		(end 161.025078 -294.4749)
		(width 0.249936)
		(layer "F.Cu")
		(net "P1V8_PEX")
	)
	(segment
		(start 301.349918 -301.599854)
		(end 301.824898 -302.074834)
		(width 0.249936)
		(layer "F.Cu")
		(net "P1V8_PEX")
	)
	(segment
		(start 365.90605 -215.011)
		(end 366.522 -215.011)
		(width 0.4572)
		(layer "F.Cu")
		(net "P1V8_PEX")
	)
	(segment
		(start 277.599902 -292.099746)
		(end 277.124922 -291.624766)
		(width 0.249936)
		(layer "F.Cu")
		(net "P1V8_PEX")
	)
	(segment
		(start 374.41505 -246.888)
		(end 374.523 -246.888)
		(width 0.4572)
		(layer "F.Cu")
		(net "P1V8_PEX")
	)
	(segment
		(start 26.101294 -278.443182)
		(end 24.780494 -278.443182)
		(width 0.4572)
		(layer "F.Cu")
		(net "P1V8_PEX")
	)
	(segment
		(start 263.007602 -307.731414)
		(end 263.007602 -305.346608)
		(width 0.4572)
		(layer "F.Cu")
		(net "P1V8_PEX")
	)
	(segment
		(start 318.23152 -297.82008)
		(end 317.957708 -298.093892)
		(width 0.3556)
		(layer "F.Cu")
		(net "P1V8_PEX")
	)
	(segment
		(start 32.470344 -249.670824)
		(end 33.486344 -249.670824)
		(width 0.4572)
		(layer "F.Cu")
		(net "P1V8_PEX")
	)
	(segment
		(start 181.023768 -198.155814)
		(end 180.40985 -198.769732)
		(width 0.4572)
		(layer "F.Cu")
		(net "P1V8_PEX")
	)
	(segment
		(start 45.39996 -292.099746)
		(end 44.92498 -291.624766)
		(width 0.249936)
		(layer "F.Cu")
		(net "P1V8_PEX")
	)
	(segment
		(start 260.606286 -249.670824)
		(end 259.590286 -249.670824)
		(width 0.4572)
		(layer "F.Cu")
		(net "P1V8_PEX")
	)
	(segment
		(start 395.59992 -291.149786)
		(end 395.12494 -290.674806)
		(width 0.249936)
		(layer "F.Cu")
		(net "P1V8_PEX")
	)
	(segment
		(start 211.030566 -237.687866)
		(end 210.469734 -237.127034)
		(width 0.4572)
		(layer "F.Cu")
		(net "P1V8_PEX")
	)
	(segment
		(start 438.318148 -306.474622)
		(end 439.334148 -306.474622)
		(width 0.4572)
		(layer "F.Cu")
		(net "P1V8_PEX")
	)
	(segment
		(start 156.698442 -249.670824)
		(end 156.02077 -249.670824)
		(width 0.4572)
		(layer "F.Cu")
		(net "P1V8_PEX")
	)
	(segment
		(start 143.20393 -307.52034)
		(end 142.395702 -308.328568)
		(width 0.4572)
		(layer "F.Cu")
		(net "P1V8_PEX")
	)
	(segment
		(start 437.302148 -307.241194)
		(end 437.302148 -306.474622)
		(width 0.4572)
		(layer "F.Cu")
		(net "P1V8_PEX")
	)
	(segment
		(start 324.64629 -309.877714)
		(end 324.43547 -309.877714)
		(width 0.4572)
		(layer "F.Cu")
		(net "P1V8_PEX")
	)
	(segment
		(start 86.031578 -296.623232)
		(end 86.031578 -298.016168)
		(width 0.3556)
		(layer "F.Cu")
		(net "P1V8_PEX")
	)
	(segment
		(start 148.952712 -307.850794)
		(end 148.2344 -308.569106)
		(width 0.4572)
		(layer "F.Cu")
		(net "P1V8_PEX")
	)
	(segment
		(start 377.668536 -310.113934)
		(end 378.278898 -310.724296)
		(width 0.4572)
		(layer "F.Cu")
		(net "P1V8_PEX")
	)
	(segment
		(start 301.824898 -289.724846)
		(end 301.349918 -289.249866)
		(width 0.249936)
		(layer "F.Cu")
		(net "P1V8_PEX")
	)
	(segment
		(start 317.5381 -298.6405)
		(end 317.338202 -298.440602)
		(width 0.4572)
		(layer "F.Cu")
		(net "P1V8_PEX")
	)
	(segment
		(start 143.938752 -310.693816)
		(end 143.938752 -310.756554)
		(width 0.4572)
		(layer "F.Cu")
		(net "P1V8_PEX")
	)
	(segment
		(start 325.611998 -307.399944)
		(end 325.611998 -308.912006)
		(width 0.4572)
		(layer "F.Cu")
		(net "P1V8_PEX")
	)
	(segment
		(start 47.29988 -300.649894)
		(end 46.8249 -301.124874)
		(width 0.381)
		(layer "F.Cu")
		(net "P1V8_PEX")
	)
	(segment
		(start 374.523 -246.888)
		(end 375.031 -247.396)
		(width 0.4572)
		(layer "F.Cu")
		(net "P1V8_PEX")
	)
	(segment
		(start 301.349918 -302.549814)
		(end 301.824898 -303.024794)
		(width 0.249936)
		(layer "F.Cu")
		(net "P1V8_PEX")
	)
	(segment
		(start 90.021156 -299.27296)
		(end 90.36177 -299.27296)
		(width 0.4572)
		(layer "F.Cu")
		(net "P1V8_PEX")
	)
	(segment
		(start 28.406344 -249.670824)
		(end 29.422344 -249.670824)
		(width 0.4572)
		(layer "F.Cu")
		(net "P1V8_PEX")
	)
	(segment
		(start 432.6636 -298.2976)
		(end 433.0065 -298.6405)
		(width 0.4572)
		(layer "F.Cu")
		(net "P1V8_PEX")
	)
	(segment
		(start 201.857864 -298.6405)
		(end 200.440798 -298.6405)
		(width 0.4572)
		(layer "F.Cu")
		(net "P1V8_PEX")
	)
	(segment
		(start 92.290138 -296.765218)
		(end 92.997782 -296.765218)
		(width 0.4572)
		(layer "F.Cu")
		(net "P1V8_PEX")
	)
	(segment
		(start 84.3407 -298.6405)
		(end 84.0232 -298.323)
		(width 0.4572)
		(layer "F.Cu")
		(net "P1V8_PEX")
	)
	(segment
		(start 142.922752 -310.756554)
		(end 143.938752 -310.756554)
		(width 0.4572)
		(layer "F.Cu")
		(net "P1V8_PEX")
	)
	(segment
		(start 45.39996 -295.89984)
		(end 44.92498 -296.37482)
		(width 0.249936)
		(layer "F.Cu")
		(net "P1V8_PEX")
	)
	(segment
		(start 39.582344 -251.956824)
		(end 39.582344 -250.091194)
		(width 0.4572)
		(layer "F.Cu")
		(net "P1V8_PEX")
	)
	(segment
		(start 270.766286 -249.670824)
		(end 269.750286 -249.670824)
		(width 0.4572)
		(layer "F.Cu")
		(net "P1V8_PEX")
	)
	(segment
		(start 205.75016 -312.2295)
		(end 205.031594 -311.510934)
		(width 0.4572)
		(layer "F.Cu")
		(net "P1V8_PEX")
	)
	(segment
		(start 386.866384 -249.670824)
		(end 387.514338 -249.670824)
		(width 0.4572)
		(layer "F.Cu")
		(net "P1V8_PEX")
	)
	(segment
		(start 93.096334 -307.084222)
		(end 93.412056 -307.399944)
		(width 0.4572)
		(layer "F.Cu")
		(net "P1V8_PEX")
	)
	(segment
		(start 259.303774 -307.52034)
		(end 258.495546 -308.328568)
		(width 0.4572)
		(layer "F.Cu")
		(net "P1V8_PEX")
	)
	(segment
		(start 376.718576 -310.113934)
		(end 376.138694 -310.693816)
		(width 0.4572)
		(layer "F.Cu")
		(net "P1V8_PEX")
	)
	(segment
		(start 277.599902 -295.89984)
		(end 277.124922 -296.37482)
		(width 0.249936)
		(layer "F.Cu")
		(net "P1V8_PEX")
	)
	(segment
		(start 320.412364 -310.792368)
		(end 319.694306 -310.07431)
		(width 0.4572)
		(layer "F.Cu")
		(net "P1V8_PEX")
	)
	(segment
		(start 144.794224 -304.800254)
		(end 145.35912 -305.36515)
		(width 0.4572)
		(layer "F.Cu")
		(net "P1V8_PEX")
	)
	(segment
		(start 146.46783 -304.90668)
		(end 146.907758 -305.346608)
		(width 0.4572)
		(layer "F.Cu")
		(net "P1V8_PEX")
	)
	(segment
		(start 27.390344 -249.670824)
		(end 28.406344 -249.670824)
		(width 0.4572)
		(layer "F.Cu")
		(net "P1V8_PEX")
	)
	(segment
		(start 29.368496 -310.113934)
		(end 28.418536 -310.113934)
		(width 0.4572)
		(layer "F.Cu")
		(net "P1V8_PEX")
	)
	(segment
		(start 267.718286 -249.670824)
		(end 266.702286 -249.670824)
		(width 0.4572)
		(layer "F.Cu")
		(net "P1V8_PEX")
	)
	(segment
		(start 299.57268 -199.372982)
		(end 299.90161 -199.044052)
		(width 0.4572)
		(layer "F.Cu")
		(net "P1V8_PEX")
	)
	(segment
		(start 18.03908 -310.978042)
		(end 21.39061 -310.978042)
		(width 0.4572)
		(layer "F.Cu")
		(net "P1V8_PEX")
	)
	(segment
		(start 69.149976 -301.599854)
		(end 69.624956 -302.074834)
		(width 0.249936)
		(layer "F.Cu")
		(net "P1V8_PEX")
	)
	(segment
		(start 69.149976 -289.249866)
		(end 69.624956 -289.724846)
		(width 0.249936)
		(layer "F.Cu")
		(net "P1V8_PEX")
	)
	(segment
		(start 374.335548 -308.588664)
		(end 374.335548 -309.969408)
		(width 0.4572)
		(layer "F.Cu")
		(net "P1V8_PEX")
	)
	(segment
		(start 395.59992 -300.649894)
		(end 395.12494 -301.124874)
		(width 0.381)
		(layer "F.Cu")
		(net "P1V8_PEX")
	)
	(segment
		(start 378.738384 -249.670824)
		(end 377.722384 -249.670824)
		(width 0.4572)
		(layer "F.Cu")
		(net "P1V8_PEX")
	)
	(segment
		(start 32.134302 -308.569106)
		(end 32.134048 -308.569106)
		(width 0.4572)
		(layer "F.Cu")
		(net "P1V8_PEX")
	)
	(segment
		(start 153.650442 -249.670824)
		(end 154.666442 -249.670824)
		(width 0.4572)
		(layer "F.Cu")
		(net "P1V8_PEX")
	)
	(segment
		(start 258.134612 -308.689502)
		(end 258.134612 -309.86857)
		(width 0.4572)
		(layer "F.Cu")
		(net "P1V8_PEX")
	)
	(segment
		(start 381.786384 -249.670824)
		(end 380.770384 -249.670824)
		(width 0.4572)
		(layer "F.Cu")
		(net "P1V8_PEX")
	)
	(segment
		(start 207.981804 -312.637932)
		(end 206.158592 -312.637932)
		(width 0.4572)
		(layer "F.Cu")
		(net "P1V8_PEX")
	)
	(segment
		(start 205.102206 -307.496718)
		(end 203.463398 -309.135526)
		(width 0.4572)
		(layer "F.Cu")
		(net "P1V8_PEX")
	)
	(segment
		(start 298.831 -199.372982)
		(end 299.57268 -199.372982)
		(width 0.4572)
		(layer "F.Cu")
		(net "P1V8_PEX")
	)
	(segment
		(start 183.169814 -185.606436)
		(end 181.063646 -185.606436)
		(width 0.4572)
		(layer "F.Cu")
		(net "P1V8_PEX")
	)
	(segment
		(start 436.51297 -310.792368)
		(end 436.512462 -310.792368)
		(width 0.4572)
		(layer "F.Cu")
		(net "P1V8_PEX")
	)
	(segment
		(start 93.412056 -307.399944)
		(end 93.412056 -308.912006)
		(width 0.4572)
		(layer "F.Cu")
		(net "P1V8_PEX")
	)
	(segment
		(start 88.212422 -310.792368)
		(end 87.494364 -310.07431)
		(width 0.4572)
		(layer "F.Cu")
		(net "P1V8_PEX")
	)
	(segment
		(start 374.335548 -309.969408)
		(end 375.122694 -310.756554)
		(width 0.4572)
		(layer "F.Cu")
		(net "P1V8_PEX")
	)
	(segment
		(start 376.60707 -304.800254)
		(end 376.994166 -304.800254)
		(width 0.4572)
		(layer "F.Cu")
		(net "P1V8_PEX")
	)
	(segment
		(start 325.611998 -308.912006)
		(end 324.64629 -309.877714)
		(width 0.4572)
		(layer "F.Cu")
		(net "P1V8_PEX")
	)
	(segment
		(start 338.47405 -151.003)
		(end 339.09 -151.003)
		(width 0.4572)
		(layer "F.Cu")
		(net "P1V8_PEX")
	)
	(segment
		(start 204.313028 -310.792368)
		(end 204.31252 -310.792368)
		(width 0.4572)
		(layer "F.Cu")
		(net "P1V8_PEX")
	)
	(segment
		(start 147.554442 -249.670824)
		(end 148.570442 -249.670824)
		(width 0.4572)
		(layer "F.Cu")
		(net "P1V8_PEX")
	)
	(segment
		(start 21.513546 -254.353314)
		(end 21.513546 -253.876556)
		(width 0.4572)
		(layer "F.Cu")
		(net "P1V8_PEX")
	)
	(segment
		(start 385.850384 -249.670824)
		(end 384.834384 -249.670824)
		(width 0.4572)
		(layer "F.Cu")
		(net "P1V8_PEX")
	)
	(segment
		(start 361.58805 -193.294)
		(end 362.204 -193.294)
		(width 0.4572)
		(layer "F.Cu")
		(net "P1V8_PEX")
	)
	(segment
		(start 369.813586 -254.353314)
		(end 369.813586 -253.876556)
		(width 0.4572)
		(layer "F.Cu")
		(net "P1V8_PEX")
	)
	(segment
		(start 262.567674 -304.90668)
		(end 261.92099 -304.90668)
		(width 0.4572)
		(layer "F.Cu")
		(net "P1V8_PEX")
	)
	(segment
		(start 209.512154 -308.912006)
		(end 208.546446 -309.877714)
		(width 0.4572)
		(layer "F.Cu")
		(net "P1V8_PEX")
	)
	(segment
		(start 209.09788 -296.765218)
		(end 209.09788 -297.374818)
		(width 0.4572)
		(layer "F.Cu")
		(net "P1V8_PEX")
	)
	(segment
		(start 433.0065 -298.6405)
		(end 434.057806 -298.6405)
		(width 0.4572)
		(layer "F.Cu")
		(net "P1V8_PEX")
	)
	(segment
		(start 47.29988 -291.149786)
		(end 46.8249 -290.674806)
		(width 0.249936)
		(layer "F.Cu")
		(net "P1V8_PEX")
	)
	(segment
		(start 258.134612 -309.86857)
		(end 259.022596 -310.756554)
		(width 0.4572)
		(layer "F.Cu")
		(net "P1V8_PEX")
	)
	(segment
		(start 440.746388 -309.877714)
		(end 441.712096 -308.912006)
		(width 0.4572)
		(layer "F.Cu")
		(net "P1V8_PEX")
	)
	(segment
		(start 439.661554 -299.27296)
		(end 438.996582 -299.27296)
		(width 0.4572)
		(layer "F.Cu")
		(net "P1V8_PEX")
	)
	(segment
		(start 260.618478 -310.113934)
		(end 261.568438 -310.113934)
		(width 0.4572)
		(layer "F.Cu")
		(net "P1V8_PEX")
	)
	(segment
		(start 90.692478 -299.603668)
		(end 91.044522 -299.251624)
		(width 0.4572)
		(layer "F.Cu")
		(net "P1V8_PEX")
	)
	(segment
		(start 25.82799 -309.76189)
		(end 26.822654 -310.756554)
		(width 0.4572)
		(layer "F.Cu")
		(net "P1V8_PEX")
	)
	(segment
		(start 417.450016 -302.549814)
		(end 417.924996 -303.024794)
		(width 0.249936)
		(layer "F.Cu")
		(net "P1V8_PEX")
	)
	(segment
		(start 203.463398 -309.943246)
		(end 203.594462 -310.07431)
		(width 0.4572)
		(layer "F.Cu")
		(net "P1V8_PEX")
	)
	(segment
		(start 209.512154 -307.399944)
		(end 209.512154 -308.912006)
		(width 0.4572)
		(layer "F.Cu")
		(net "P1V8_PEX")
	)
	(segment
		(start 91.044522 -299.251624)
		(end 91.044522 -299.024294)
		(width 0.4572)
		(layer "F.Cu")
		(net "P1V8_PEX")
	)
	(segment
		(start 69.149976 -289.249866)
		(end 69.624956 -288.774886)
		(width 0.249936)
		(layer "F.Cu")
		(net "P1V8_PEX")
	)
	(segment
		(start 161.500058 -293.04996)
		(end 161.025078 -292.57498)
		(width 0.249936)
		(layer "F.Cu")
		(net "P1V8_PEX")
	)
	(segment
		(start 376.994166 -304.800254)
		(end 377.559062 -305.36515)
		(width 0.4572)
		(layer "F.Cu")
		(net "P1V8_PEX")
	)
	(segment
		(start 439.989468 -295.647872)
		(end 439.989468 -296.556684)
		(width 0.4572)
		(layer "F.Cu")
		(net "P1V8_PEX")
	)
	(segment
		(start 21.513546 -253.876556)
		(end 21.769324 -253.620778)
		(width 0.4572)
		(layer "F.Cu")
		(net "P1V8_PEX")
	)
	(segment
		(start 438.996582 -299.27296)
		(end 438.321196 -299.27296)
		(width 0.4572)
		(layer "F.Cu")
		(net "P1V8_PEX")
	)
	(segment
		(start 262.896858 -310.005984)
		(end 262.896858 -310.006238)
		(width 0.4572)
		(layer "F.Cu")
		(net "P1V8_PEX")
	)
	(segment
		(start 145.468594 -309.170578)
		(end 146.907758 -307.731414)
		(width 0.4572)
		(layer "F.Cu")
		(net "P1V8_PEX")
	)
	(segment
		(start 142.146274 -309.980076)
		(end 142.922752 -310.756554)
		(width 0.4572)
		(layer "F.Cu")
		(net "P1V8_PEX")
	)
	(segment
		(start 317.957708 -298.6405)
		(end 317.5381 -298.6405)
		(width 0.4572)
		(layer "F.Cu")
		(net "P1V8_PEX")
	)
	(segment
		(start 145.468594 -310.113934)
		(end 145.468594 -309.170578)
		(width 0.4572)
		(layer "F.Cu")
		(net "P1V8_PEX")
	)
	(segment
		(start 200.440798 -298.6405)
		(end 200.123298 -298.323)
		(width 0.4572)
		(layer "F.Cu")
		(net "P1V8_PEX")
	)
	(segment
		(start 92.235528 -309.877714)
		(end 91.917266 -310.195976)
		(width 0.4572)
		(layer "F.Cu")
		(net "P1V8_PEX")
	)
	(segment
		(start 435.66334 -308.880002)
		(end 437.302148 -307.241194)
		(width 0.4572)
		(layer "F.Cu")
		(net "P1V8_PEX")
	)
	(segment
		(start 156.02077 -249.670824)
		(end 155.682442 -250.009152)
		(width 0.4572)
		(layer "F.Cu")
		(net "P1V8_PEX")
	)
	(segment
		(start 148.570442 -249.670824)
		(end 149.586442 -249.670824)
		(width 0.4572)
		(layer "F.Cu")
		(net "P1V8_PEX")
	)
	(segment
		(start 69.624956 -290.674806)
		(end 69.149976 -291.149786)
		(width 0.249936)
		(layer "F.Cu")
		(net "P1V8_PEX")
	)
	(segment
		(start 161.500058 -291.149786)
		(end 161.025078 -290.674806)
		(width 0.249936)
		(layer "F.Cu")
		(net "P1V8_PEX")
	)
	(segment
		(start 258.574286 -249.010424)
		(end 258.574286 -249.670824)
		(width 0.4572)
		(layer "F.Cu")
		(net "P1V8_PEX")
	)
	(segment
		(start 325.296276 -306.504848)
		(end 325.296276 -307.084222)
		(width 0.4572)
		(layer "F.Cu")
		(net "P1V8_PEX")
	)
	(segment
		(start 145.362676 -305.36515)
		(end 145.821146 -304.90668)
		(width 0.4572)
		(layer "F.Cu")
		(net "P1V8_PEX")
	)
	(segment
		(start 318.23152 -296.623232)
		(end 318.23152 -297.82008)
		(width 0.3556)
		(layer "F.Cu")
		(net "P1V8_PEX")
	)
	(segment
		(start 388.25043 -249.670824)
		(end 387.882384 -250.03887)
		(width 0.4572)
		(layer "F.Cu")
		(net "P1V8_PEX")
	)
	(segment
		(start 206.121254 -299.27296)
		(end 206.79664 -299.27296)
		(width 0.4572)
		(layer "F.Cu")
		(net "P1V8_PEX")
	)
	(segment
		(start 40.002714 -249.670824)
		(end 40.598344 -249.670824)
		(width 0.4572)
		(layer "F.Cu")
		(net "P1V8_PEX")
	)
	(segment
		(start 149.586442 -249.670824)
		(end 150.602442 -249.670824)
		(width 0.4572)
		(layer "F.Cu")
		(net "P1V8_PEX")
	)
	(segment
		(start 434.057806 -298.24934)
		(end 434.057806 -298.6405)
		(width 0.3556)
		(layer "F.Cu")
		(net "P1V8_PEX")
	)
	(segment
		(start 209.166206 -306.474622)
		(end 209.196432 -306.504848)
		(width 0.4572)
		(layer "F.Cu")
		(net "P1V8_PEX")
	)
	(segment
		(start 180.135276 -197.48373)
		(end 180.906928 -197.48373)
		(width 0.3556)
		(layer "F.Cu")
		(net "P1V8_PEX")
	)
	(segment
		(start 298.156122 -199.718676)
		(end 298.156122 -198.947024)
		(width 0.3556)
		(layer "F.Cu")
		(net "P1V8_PEX")
	)
	(segment
		(start 136.32561 -255.16459)
		(end 137.869422 -253.620778)
		(width 0.4572)
		(layer "F.Cu")
		(net "P1V8_PEX")
	)
	(segment
		(start 439.334148 -306.474622)
		(end 440.350148 -306.474622)
		(width 0.4572)
		(layer "F.Cu")
		(net "P1V8_PEX")
	)
	(segment
		(start 435.794404 -310.07431)
		(end 435.66334 -309.943246)
		(width 0.4572)
		(layer "F.Cu")
		(net "P1V8_PEX")
	)
	(segment
		(start 319.563242 -309.943246)
		(end 319.563242 -308.880002)
		(width 0.4572)
		(layer "F.Cu")
		(net "P1V8_PEX")
	)
	(segment
		(start 361.58805 -182.118)
		(end 362.204 -182.118)
		(width 0.4572)
		(layer "F.Cu")
		(net "P1V8_PEX")
	)
	(segment
		(start 31.296356 -307.731414)
		(end 32.134048 -308.569106)
		(width 0.4572)
		(layer "F.Cu")
		(net "P1V8_PEX")
	)
	(segment
		(start 150.602442 -249.670824)
		(end 151.618442 -249.670824)
		(width 0.4572)
		(layer "F.Cu")
		(net "P1V8_PEX")
	)
	(segment
		(start 325.296276 -307.084222)
		(end 325.611998 -307.399944)
		(width 0.4572)
		(layer "F.Cu")
		(net "P1V8_PEX")
	)
	(segment
		(start 144.062958 -304.456084)
		(end 144.407128 -304.800254)
		(width 0.4572)
		(layer "F.Cu")
		(net "P1V8_PEX")
	)
	(segment
		(start 441.396374 -306.504848)
		(end 441.366148 -306.474622)
		(width 0.4572)
		(layer "F.Cu")
		(net "P1V8_PEX")
	)
	(segment
		(start 25.783286 -306.585366)
		(end 26.168858 -306.585366)
		(width 0.4572)
		(layer "F.Cu")
		(net "P1V8_PEX")
	)
	(segment
		(start 377.668536 -310.113934)
		(end 376.718576 -310.113934)
		(width 0.4572)
		(layer "F.Cu")
		(net "P1V8_PEX")
	)
	(segment
		(start 207.789526 -296.556684)
		(end 207.99806 -296.765218)
		(width 0.4572)
		(layer "F.Cu")
		(net "P1V8_PEX")
	)
	(segment
		(start 378.996956 -310.005984)
		(end 378.996956 -310.006238)
		(width 0.4572)
		(layer "F.Cu")
		(net "P1V8_PEX")
	)
	(segment
		(start 142.268956 -306.585366)
		(end 142.268956 -305.59375)
		(width 0.4572)
		(layer "F.Cu")
		(net "P1V8_PEX")
	)
	(segment
		(start 373.658384 -249.670824)
		(end 373.658384 -249.00382)
		(width 0.4572)
		(layer "F.Cu")
		(net "P1V8_PEX")
	)
	(segment
		(start 380.434088 -308.569106)
		(end 379.596396 -307.731414)
		(width 0.4572)
		(layer "F.Cu")
		(net "P1V8_PEX")
	)
	(segment
		(start 27.103832 -307.52034)
		(end 26.168858 -306.585366)
		(width 0.4572)
		(layer "F.Cu")
		(net "P1V8_PEX")
	)
	(segment
		(start 271.782286 -251.956824)
		(end 271.782286 -251.158502)
		(width 0.4572)
		(layer "F.Cu")
		(net "P1V8_PEX")
	)
	(segment
		(start 185.250074 -291.149786)
		(end 185.725054 -290.674806)
		(width 0.249936)
		(layer "F.Cu")
		(net "P1V8_PEX")
	)
	(segment
		(start 129.474214 -214.540846)
		(end 129.982214 -215.048846)
		(width 0.4572)
		(layer "F.Cu")
		(net "P1V8_PEX")
	)
	(segment
		(start 365.90605 -203.835)
		(end 366.522 -203.835)
		(width 0.4572)
		(layer "F.Cu")
		(net "P1V8_PEX")
	)
	(segment
		(start 207.99806 -296.765218)
		(end 209.09788 -296.765218)
		(width 0.4572)
		(layer "F.Cu")
		(net "P1V8_PEX")
	)
	(segment
		(start 180.40985 -198.769732)
		(end 180.40985 -198.997062)
		(width 0.4572)
		(layer "F.Cu")
		(net "P1V8_PEX")
	)
	(segment
		(start 393.7 -295.89984)
		(end 393.22502 -296.37482)
		(width 0.249936)
		(layer "F.Cu")
		(net "P1V8_PEX")
	)
	(segment
		(start 210.469734 -237.127034)
		(end 209.182208 -237.127034)
		(width 0.4572)
		(layer "F.Cu")
		(net "P1V8_PEX")
	)
	(segment
		(start 439.673746 -299.285152)
		(end 439.661554 -299.27296)
		(width 0.4572)
		(layer "F.Cu")
		(net "P1V8_PEX")
	)
	(segment
		(start 321.131438 -311.510934)
		(end 320.412872 -310.792368)
		(width 0.4572)
		(layer "F.Cu")
		(net "P1V8_PEX")
	)
	(segment
		(start 185.250074 -300.649894)
		(end 185.725054 -301.124874)
		(width 0.249936)
		(layer "F.Cu")
		(net "P1V8_PEX")
	)
	(segment
		(start 129.366264 -214.540846)
		(end 129.474214 -214.540846)
		(width 0.4572)
		(layer "F.Cu")
		(net "P1V8_PEX")
	)
	(segment
		(start 30.80766 -305.346608)
		(end 30.80766 -307.731414)
		(width 0.4572)
		(layer "F.Cu")
		(net "P1V8_PEX")
	)
	(segment
		(start 69.149976 -300.649894)
		(end 69.624956 -301.124874)
		(width 0.249936)
		(layer "F.Cu")
		(net "P1V8_PEX")
	)
	(segment
		(start 92.997782 -297.374818)
		(end 92.997782 -296.765218)
		(width 0.4572)
		(layer "F.Cu")
		(net "P1V8_PEX")
	)
	(segment
		(start 379.1077 -307.731414)
		(end 379.1077 -305.346608)
		(width 0.4572)
		(layer "F.Cu")
		(net "P1V8_PEX")
	)
	(segment
		(start 322.221098 -299.27296)
		(end 322.896484 -299.27296)
		(width 0.4572)
		(layer "F.Cu")
		(net "P1V8_PEX")
	)
	(segment
		(start 180.40985 -198.997062)
		(end 180.40985 -199.677274)
		(width 0.4572)
		(layer "F.Cu")
		(net "P1V8_PEX")
	)
	(segment
		(start 259.022596 -310.756554)
		(end 260.038596 -310.756554)
		(width 0.4572)
		(layer "F.Cu")
		(net "P1V8_PEX")
	)
	(segment
		(start 25.99817 -222.063818)
		(end 25.737058 -222.32493)
		(width 0.4572)
		(layer "F.Cu")
		(net "P1V8_PEX")
	)
	(segment
		(start 375.403872 -307.52034)
		(end 374.468898 -306.585366)
		(width 0.4572)
		(layer "F.Cu")
		(net "P1V8_PEX")
	)
	(segment
		(start 146.907758 -305.346608)
		(end 146.907758 -307.731414)
		(width 0.4572)
		(layer "F.Cu")
		(net "P1V8_PEX")
	)
	(segment
		(start 136.32561 -255.586484)
		(end 136.32561 -255.16459)
		(width 0.4572)
		(layer "F.Cu")
		(net "P1V8_PEX")
	)
	(segment
		(start 26.374344 -249.670824)
		(end 26.374344 -249.00382)
		(width 0.4572)
		(layer "F.Cu")
		(net "P1V8_PEX")
	)
	(segment
		(start 92.050108 -306.474622)
		(end 93.066108 -306.474622)
		(width 0.4572)
		(layer "F.Cu")
		(net "P1V8_PEX")
	)
	(segment
		(start 146.538442 -249.670824)
		(end 147.554442 -249.670824)
		(width 0.4572)
		(layer "F.Cu")
		(net "P1V8_PEX")
	)
	(segment
		(start 320.412872 -310.792368)
		(end 320.412364 -310.792368)
		(width 0.4572)
		(layer "F.Cu")
		(net "P1V8_PEX")
	)
	(segment
		(start 34.502344 -249.670824)
		(end 35.518344 -249.670824)
		(width 0.4572)
		(layer "F.Cu")
		(net "P1V8_PEX")
	)
	(segment
		(start 93.066108 -306.474622)
		(end 93.096334 -306.504848)
		(width 0.4572)
		(layer "F.Cu")
		(net "P1V8_PEX")
	)
	(segment
		(start 321.20205 -306.474622)
		(end 322.21805 -306.474622)
		(width 0.4572)
		(layer "F.Cu")
		(net "P1V8_PEX")
	)
	(segment
		(start 262.1788 -310.724296)
		(end 261.568438 -310.113934)
		(width 0.4572)
		(layer "F.Cu")
		(net "P1V8_PEX")
	)
	(segment
		(start 271.680178 -248.953274)
		(end 272.671286 -248.953274)
		(width 0.4572)
		(layer "F.Cu")
		(net "P1V8_PEX")
	)
	(segment
		(start 39.582344 -250.091194)
		(end 39.161974 -249.670824)
		(width 0.4572)
		(layer "F.Cu")
		(net "P1V8_PEX")
	)
	(segment
		(start 180.906928 -197.48373)
		(end 181.110636 -197.687438)
		(width 0.3556)
		(layer "F.Cu")
		(net "P1V8_PEX")
	)
	(segment
		(start 439.989468 -296.556684)
		(end 440.198002 -296.765218)
		(width 0.4572)
		(layer "F.Cu")
		(net "P1V8_PEX")
	)
	(segment
		(start 201.857864 -298.191936)
		(end 201.857864 -298.6405)
		(width 0.3556)
		(layer "F.Cu")
		(net "P1V8_PEX")
	)
	(segment
		(start 272.671286 -248.953274)
		(end 272.798286 -249.080274)
		(width 0.4572)
		(layer "F.Cu")
		(net "P1V8_PEX")
	)
	(segment
		(start 279.499822 -291.149786)
		(end 279.024842 -290.674806)
		(width 0.249936)
		(layer "F.Cu")
		(net "P1V8_PEX")
	)
	(segment
		(start 258.495546 -308.328568)
		(end 258.134612 -308.689502)
		(width 0.4572)
		(layer "F.Cu")
		(net "P1V8_PEX")
	)
	(segment
		(start 185.250074 -289.249866)
		(end 185.725054 -288.774886)
		(width 0.249936)
		(layer "F.Cu")
		(net "P1V8_PEX")
	)
	(segment
		(start 183.95696 -185.606436)
		(end 183.169814 -185.606436)
		(width 0.4572)
		(layer "F.Cu")
		(net "P1V8_PEX")
	)
	(segment
		(start 376.138694 -310.693816)
		(end 376.138694 -310.756554)
		(width 0.4572)
		(layer "F.Cu")
		(net "P1V8_PEX")
	)
	(segment
		(start 205.102206 -306.474622)
		(end 205.102206 -307.496718)
		(width 0.4572)
		(layer "F.Cu")
		(net "P1V8_PEX")
	)
	(segment
		(start 379.1077 -307.731414)
		(end 377.668536 -309.170578)
		(width 0.4572)
		(layer "F.Cu")
		(net "P1V8_PEX")
	)
	(segment
		(start 209.196432 -307.084222)
		(end 209.512154 -307.399944)
		(width 0.4572)
		(layer "F.Cu")
		(net "P1V8_PEX")
	)
	(segment
		(start 28.349956 -304.456084)
		(end 29.259022 -305.36515)
		(width 0.4572)
		(layer "F.Cu")
		(net "P1V8_PEX")
	)
	(segment
		(start 268.734286 -249.670824)
		(end 267.718286 -249.670824)
		(width 0.4572)
		(layer "F.Cu")
		(net "P1V8_PEX")
	)
	(segment
		(start 209.182208 -237.127034)
		(end 209.182208 -236.3978)
		(width 0.4572)
		(layer "F.Cu")
		(net "P1V8_PEX")
	)
	(segment
		(start 269.750286 -249.670824)
		(end 268.734286 -249.670824)
		(width 0.4572)
		(layer "F.Cu")
		(net "P1V8_PEX")
	)
	(segment
		(start 338.47405 -186.055)
		(end 339.09 -186.055)
		(width 0.4572)
		(layer "F.Cu")
		(net "P1V8_PEX")
	)
	(segment
		(start 24.342344 -249.670824)
		(end 25.358344 -249.670824)
		(width 0.4572)
		(layer "F.Cu")
		(net "P1V8_PEX")
	)
	(segment
		(start 436.512462 -310.792368)
		(end 435.794404 -310.07431)
		(width 0.4572)
		(layer "F.Cu")
		(net "P1V8_PEX")
	)
	(segment
		(start 89.650062 -312.2295)
		(end 88.931496 -311.510934)
		(width 0.4572)
		(layer "F.Cu")
		(net "P1V8_PEX")
	)
	(segment
		(start 203.463398 -309.135526)
		(end 203.463398 -309.943246)
		(width 0.4572)
		(layer "F.Cu")
		(net "P1V8_PEX")
	)
	(segment
		(start 322.21805 -306.474622)
		(end 323.23405 -306.474622)
		(width 0.4572)
		(layer "F.Cu")
		(net "P1V8_PEX")
	)
	(segment
		(start 378.021088 -304.90668)
		(end 377.562618 -305.36515)
		(width 0.4572)
		(layer "F.Cu")
		(net "P1V8_PEX")
	)
	(segment
		(start 261.92099 -304.90668)
		(end 261.46252 -305.36515)
		(width 0.4572)
		(layer "F.Cu")
		(net "P1V8_PEX")
	)
	(segment
		(start 143.490442 -249.670824)
		(end 144.506442 -249.670824)
		(width 0.4572)
		(layer "F.Cu")
		(net "P1V8_PEX")
	)
	(segment
		(start 27.838654 -310.693816)
		(end 27.838654 -310.756554)
		(width 0.4572)
		(layer "F.Cu")
		(net "P1V8_PEX")
	)
	(segment
		(start 374.468898 -306.585366)
		(end 374.468898 -305.59375)
		(width 0.4572)
		(layer "F.Cu")
		(net "P1V8_PEX")
	)
	(segment
		(start 387.514338 -249.670824)
		(end 387.882384 -250.03887)
		(width 0.4572)
		(layer "F.Cu")
		(net "P1V8_PEX")
	)
	(segment
		(start 90.36177 -299.27296)
		(end 90.692478 -299.603668)
		(width 0.4572)
		(layer "F.Cu")
		(net "P1V8_PEX")
	)
	(segment
		(start 207.461612 -299.27296)
		(end 207.473804 -299.285152)
		(width 0.4572)
		(layer "F.Cu")
		(net "P1V8_PEX")
	)
	(segment
		(start 383.818384 -249.670824)
		(end 382.802384 -249.670824)
		(width 0.4572)
		(layer "F.Cu")
		(net "P1V8_PEX")
	)
	(segment
		(start 85.757766 -298.28998)
		(end 85.757766 -298.6405)
		(width 0.3556)
		(layer "F.Cu")
		(net "P1V8_PEX")
	)
	(segment
		(start 434.331618 -297.975528)
		(end 434.057806 -298.24934)
		(width 0.3556)
		(layer "F.Cu")
		(net "P1V8_PEX")
	)
	(segment
		(start 417.450016 -290.199826)
		(end 417.924996 -290.674806)
		(width 0.249936)
		(layer "F.Cu")
		(net "P1V8_PEX")
	)
	(segment
		(start 379.596396 -307.731414)
		(end 379.1077 -307.731414)
		(width 0.4572)
		(layer "F.Cu")
		(net "P1V8_PEX")
	)
	(segment
		(start 441.396374 -307.084222)
		(end 441.396374 -306.504848)
		(width 0.4572)
		(layer "F.Cu")
		(net "P1V8_PEX")
	)
	(segment
		(start 90.058494 -312.637932)
		(end 89.650062 -312.2295)
		(width 0.4572)
		(layer "F.Cu")
		(net "P1V8_PEX")
	)
	(segment
		(start 417.924996 -290.674806)
		(end 417.450016 -291.149786)
		(width 0.249936)
		(layer "F.Cu")
		(net "P1V8_PEX")
	)
	(segment
		(start 301.824898 -290.674806)
		(end 301.349918 -290.199826)
		(width 0.249936)
		(layer "F.Cu")
		(net "P1V8_PEX")
	)
	(segment
		(start 21.171662 -264.322306)
		(end 22.9743 -262.519668)
		(width 0.4572)
		(layer "F.Cu")
		(net "P1V8_PEX")
	)
	(segment
		(start 185.250074 -301.599854)
		(end 185.725054 -302.074834)
		(width 0.249936)
		(layer "F.Cu")
		(net "P1V8_PEX")
	)
	(segment
		(start 266.702286 -249.670824)
		(end 265.686286 -249.670824)
		(width 0.4572)
		(layer "F.Cu")
		(net "P1V8_PEX")
	)
	(segment
		(start 324.43547 -309.877714)
		(end 324.117208 -310.195976)
		(width 0.4572)
		(layer "F.Cu")
		(net "P1V8_PEX")
	)
	(segment
		(start 374.674384 -249.670824)
		(end 373.658384 -249.670824)
		(width 0.4572)
		(layer "F.Cu")
		(net "P1V8_PEX")
	)
	(segment
		(start 152.634442 -249.670824)
		(end 153.650442 -249.670824)
		(width 0.4572)
		(layer "F.Cu")
		(net "P1V8_PEX")
	)
	(segment
		(start 29.368496 -310.113934)
		(end 29.368496 -309.170578)
		(width 0.4572)
		(layer "F.Cu")
		(net "P1V8_PEX")
	)
	(segment
		(start 338.47405 -162.814)
		(end 339.09 -162.814)
		(width 0.4572)
		(layer "F.Cu")
		(net "P1V8_PEX")
	)
	(segment
		(start 259.431282 -304.978816)
		(end 258.555236 -305.854862)
		(width 0.4572)
		(layer "F.Cu")
		(net "P1V8_PEX")
	)
	(segment
		(start 377.562618 -305.36515)
		(end 377.559062 -305.36515)
		(width 0.4572)
		(layer "F.Cu")
		(net "P1V8_PEX")
	)
	(segment
		(start 378.996956 -310.006238)
		(end 378.278898 -310.724296)
		(width 0.4572)
		(layer "F.Cu")
		(net "P1V8_PEX")
	)
	(segment
		(start 21.171662 -274.83435)
		(end 21.171662 -264.322306)
		(width 0.4572)
		(layer "F.Cu")
		(net "P1V8_PEX")
	)
	(segment
		(start 146.797014 -310.005984)
		(end 146.797014 -310.006238)
		(width 0.4572)
		(layer "F.Cu")
		(net "P1V8_PEX")
	)
	(segment
		(start 88.21293 -310.792368)
		(end 88.212422 -310.792368)
		(width 0.4572)
		(layer "F.Cu")
		(net "P1V8_PEX")
	)
	(segment
		(start 321.20205 -307.241194)
		(end 321.20205 -306.474622)
		(width 0.4572)
		(layer "F.Cu")
		(net "P1V8_PEX")
	)
	(segment
		(start 208.132426 -312.48731)
		(end 207.981804 -312.637932)
		(width 0.4572)
		(layer "F.Cu")
		(net "P1V8_PEX")
	)
	(segment
		(start 69.624956 -289.724846)
		(end 69.149976 -290.199826)
		(width 0.249936)
		(layer "F.Cu")
		(net "P1V8_PEX")
	)
	(segment
		(start 323.561456 -299.27296)
		(end 323.573648 -299.285152)
		(width 0.4572)
		(layer "F.Cu")
		(net "P1V8_PEX")
	)
	(segment
		(start 321.850004 -312.2295)
		(end 321.131438 -311.510934)
		(width 0.4572)
		(layer "F.Cu")
		(net "P1V8_PEX")
	)
	(segment
		(start 185.250074 -302.549814)
		(end 185.725054 -303.024794)
		(width 0.249936)
		(layer "F.Cu")
		(net "P1V8_PEX")
	)
	(segment
		(start 374.674384 -249.00382)
		(end 374.674384 -249.670824)
		(width 0.4572)
		(layer "F.Cu")
		(net "P1V8_PEX")
	)
	(segment
		(start 440.217306 -310.195976)
		(end 440.535568 -309.877714)
		(width 0.4572)
		(layer "F.Cu")
		(net "P1V8_PEX")
	)
	(segment
		(start 212.046566 -235.356908)
		(end 213.062566 -235.356908)
		(width 0.4572)
		(layer "F.Cu")
		(net "P1V8_PEX")
	)
	(segment
		(start 374.468898 -305.59375)
		(end 375.606564 -304.456084)
		(width 0.4572)
		(layer "F.Cu")
		(net "P1V8_PEX")
	)
	(segment
		(start 374.595644 -308.328568)
		(end 374.335548 -308.588664)
		(width 0.4572)
		(layer "F.Cu")
		(net "P1V8_PEX")
	)
	(segment
		(start 39.161974 -249.670824)
		(end 38.566344 -249.670824)
		(width 0.4572)
		(layer "F.Cu")
		(net "P1V8_PEX")
	)
	(segment
		(start 184.319418 -185.968894)
		(end 183.95696 -185.606436)
		(width 0.4572)
		(layer "F.Cu")
		(net "P1V8_PEX")
	)
	(segment
		(start 417.450016 -301.599854)
		(end 417.924996 -302.074834)
		(width 0.249936)
		(layer "F.Cu")
		(net "P1V8_PEX")
	)
	(segment
		(start 375.403872 -307.52034)
		(end 374.595644 -308.328568)
		(width 0.4572)
		(layer "F.Cu")
		(net "P1V8_PEX")
	)
	(segment
		(start 185.250074 -289.249866)
		(end 185.725054 -289.724846)
		(width 0.249936)
		(layer "F.Cu")
		(net "P1V8_PEX")
	)
	(segment
		(start 393.7 -293.04996)
		(end 393.22502 -292.57498)
		(width 0.249936)
		(layer "F.Cu")
		(net "P1V8_PEX")
	)
	(segment
		(start 69.149976 -290.199826)
		(end 69.624956 -290.674806)
		(width 0.249936)
		(layer "F.Cu")
		(net "P1V8_PEX")
	)
	(segment
		(start 259.590286 -249.670824)
		(end 258.574286 -249.670824)
		(width 0.4572)
		(layer "F.Cu")
		(net "P1V8_PEX")
	)
	(segment
		(start 141.458442 -249.052842)
		(end 141.458442 -249.670824)
		(width 0.4572)
		(layer "F.Cu")
		(net "P1V8_PEX")
	)
	(segment
		(start 381.152654 -307.850794)
		(end 380.434342 -308.569106)
		(width 0.4572)
		(layer "F.Cu")
		(net "P1V8_PEX")
	)
	(segment
		(start 258.920742 -225.481896)
		(end 258.266692 -226.135946)
		(width 0.4572)
		(layer "F.Cu")
		(net "P1V8_PEX")
	)
	(segment
		(start 27.306524 -304.456084)
		(end 28.349956 -304.456084)
		(width 0.4572)
		(layer "F.Cu")
		(net "P1V8_PEX")
	)
	(segment
		(start 25.358344 -249.670824)
		(end 26.374344 -249.670824)
		(width 0.4572)
		(layer "F.Cu")
		(net "P1V8_PEX")
	)
	(segment
		(start 145.821146 -304.90668)
		(end 146.46783 -304.90668)
		(width 0.4572)
		(layer "F.Cu")
		(net "P1V8_PEX")
	)
	(segment
		(start 161.500058 -292.099746)
		(end 161.025078 -291.624766)
		(width 0.249936)
		(layer "F.Cu")
		(net "P1V8_PEX")
	)
	(segment
		(start 264.670286 -249.670824)
		(end 263.654286 -249.670824)
		(width 0.4572)
		(layer "F.Cu")
		(net "P1V8_PEX")
	)
	(segment
		(start 206.118206 -306.474622)
		(end 207.134206 -306.474622)
		(width 0.4572)
		(layer "F.Cu")
		(net "P1V8_PEX")
	)
	(segment
		(start 440.535568 -309.877714)
		(end 440.746388 -309.877714)
		(width 0.4572)
		(layer "F.Cu")
		(net "P1V8_PEX")
	)
	(segment
		(start 261.458964 -305.36515)
		(end 261.07263 -304.978816)
		(width 0.4572)
		(layer "F.Cu")
		(net "P1V8_PEX")
	)
	(segment
		(start 163.399978 -300.649894)
		(end 162.924998 -301.124874)
		(width 0.381)
		(layer "F.Cu")
		(net "P1V8_PEX")
	)
	(segment
		(start 202.131676 -296.623232)
		(end 202.131676 -297.918124)
		(width 0.3556)
		(layer "F.Cu")
		(net "P1V8_PEX")
	)
	(segment
		(start 26.168858 -306.585366)
		(end 26.168858 -305.59375)
		(width 0.4572)
		(layer "F.Cu")
		(net "P1V8_PEX")
	)
	(segment
		(start 29.259022 -305.36515)
		(end 29.262578 -305.36515)
		(width 0.4572)
		(layer "F.Cu")
		(net "P1V8_PEX")
	)
	(segment
		(start 263.496298 -307.731414)
		(end 263.007602 -307.731414)
		(width 0.4572)
		(layer "F.Cu")
		(net "P1V8_PEX")
	)
	(segment
		(start 143.406622 -304.456084)
		(end 144.062958 -304.456084)
		(width 0.4572)
		(layer "F.Cu")
		(net "P1V8_PEX")
	)
	(segment
		(start 30.696916 -310.005984)
		(end 30.696916 -310.006238)
		(width 0.4572)
		(layer "F.Cu")
		(net "P1V8_PEX")
	)
	(segment
		(start 298.464224 -198.638922)
		(end 299.90161 -198.638922)
		(width 0.3556)
		(layer "F.Cu")
		(net "P1V8_PEX")
	)
	(segment
		(start 142.146274 -308.577996)
		(end 142.146274 -309.980076)
		(width 0.4572)
		(layer "F.Cu")
		(net "P1V8_PEX")
	)
	(segment
		(start 144.407128 -304.800254)
		(end 144.794224 -304.800254)
		(width 0.4572)
		(layer "F.Cu")
		(net "P1V8_PEX")
	)
	(segment
		(start 373.99976 -222.32493)
		(end 374.260872 -222.063818)
		(width 0.4572)
		(layer "F.Cu")
		(net "P1V8_PEX")
	)
	(segment
		(start 376.706384 -249.670824)
		(end 375.690384 -249.670824)
		(width 0.4572)
		(layer "F.Cu")
		(net "P1V8_PEX")
	)
	(segment
		(start 299.90161 -199.044052)
		(end 299.90161 -198.638922)
		(width 0.4572)
		(layer "F.Cu")
		(net "P1V8_PEX")
	)
	(segment
		(start 437.302148 -306.474622)
		(end 438.318148 -306.474622)
		(width 0.4572)
		(layer "F.Cu")
		(net "P1V8_PEX")
	)
	(segment
		(start 142.474442 -249.670824)
		(end 142.474442 -249.032522)
		(width 0.4572)
		(layer "F.Cu")
		(net "P1V8_PEX")
	)
	(segment
		(start 440.198002 -296.765218)
		(end 441.297822 -296.765218)
		(width 0.4572)
		(layer "F.Cu")
		(net "P1V8_PEX")
	)
	(segment
		(start 142.395702 -308.328568)
		(end 142.146274 -308.577996)
		(width 0.4572)
		(layer "F.Cu")
		(net "P1V8_PEX")
	)
	(segment
		(start 393.7 -291.149786)
		(end 393.22502 -290.674806)
		(width 0.249936)
		(layer "F.Cu")
		(net "P1V8_PEX")
	)
	(segment
		(start 209.196432 -306.504848)
		(end 209.196432 -307.084222)
		(width 0.4572)
		(layer "F.Cu")
		(net "P1V8_PEX")
	)
	(segment
		(start 35.518344 -249.670824)
		(end 36.534344 -249.670824)
		(width 0.4572)
		(layer "F.Cu")
		(net "P1V8_PEX")
	)
	(segment
		(start 386.866384 -249.670824)
		(end 385.850384 -249.670824)
		(width 0.4572)
		(layer "F.Cu")
		(net "P1V8_PEX")
	)
	(segment
		(start 257.558286 -249.670824)
		(end 257.558286 -249.010424)
		(width 0.4572)
		(layer "F.Cu")
		(net "P1V8_PEX")
	)
	(segment
		(start 91.689428 -296.164508)
		(end 92.290138 -296.765218)
		(width 0.4572)
		(layer "F.Cu")
		(net "P1V8_PEX")
	)
	(segment
		(start 87.3633 -308.880002)
		(end 89.002108 -307.241194)
		(width 0.4572)
		(layer "F.Cu")
		(net "P1V8_PEX")
	)
	(segment
		(start 142.474442 -249.670824)
		(end 143.490442 -249.670824)
		(width 0.4572)
		(layer "F.Cu")
		(net "P1V8_PEX")
	)
	(segment
		(start 88.931496 -311.510934)
		(end 88.21293 -310.792368)
		(width 0.4572)
		(layer "F.Cu")
		(net "P1V8_PEX")
	)
	(segment
		(start 323.23405 -306.474622)
		(end 324.25005 -306.474622)
		(width 0.4572)
		(layer "F.Cu")
		(net "P1V8_PEX")
	)
	(segment
		(start 264.33399 -308.569106)
		(end 263.496298 -307.731414)
		(width 0.4572)
		(layer "F.Cu")
		(net "P1V8_PEX")
	)
	(segment
		(start 435.66334 -309.943246)
		(end 435.66334 -308.880002)
		(width 0.4572)
		(layer "F.Cu")
		(net "P1V8_PEX")
	)
	(segment
		(start 376.2629 -304.456084)
		(end 376.60707 -304.800254)
		(width 0.4572)
		(layer "F.Cu")
		(net "P1V8_PEX")
	)
	(segment
		(start 279.499822 -300.649894)
		(end 279.024842 -301.124874)
		(width 0.381)
		(layer "F.Cu")
		(net "P1V8_PEX")
	)
	(segment
		(start 207.134206 -306.474622)
		(end 208.150206 -306.474622)
		(width 0.4572)
		(layer "F.Cu")
		(net "P1V8_PEX")
	)
	(segment
		(start 261.568438 -310.113934)
		(end 261.568438 -309.170578)
		(width 0.4572)
		(layer "F.Cu")
		(net "P1V8_PEX")
	)
	(segment
		(start 91.881706 -312.637932)
		(end 90.058494 -312.637932)
		(width 0.4572)
		(layer "F.Cu")
		(net "P1V8_PEX")
	)
	(segment
		(start 36.534344 -249.670824)
		(end 37.550344 -249.670824)
		(width 0.4572)
		(layer "F.Cu")
		(net "P1V8_PEX")
	)
	(segment
		(start 25.82799 -308.796182)
		(end 25.82799 -309.76189)
		(width 0.4572)
		(layer "F.Cu")
		(net "P1V8_PEX")
	)
	(segment
		(start 143.20393 -307.52034)
		(end 142.268956 -306.585366)
		(width 0.4572)
		(layer "F.Cu")
		(net "P1V8_PEX")
	)
	(segment
		(start 148.2344 -308.569106)
		(end 148.234146 -308.569106)
		(width 0.4572)
		(layer "F.Cu")
		(net "P1V8_PEX")
	)
	(segment
		(start 181.063646 -185.606436)
		(end 180.38191 -184.9247)
		(width 0.4572)
		(layer "F.Cu")
		(net "P1V8_PEX")
	)
	(segment
		(start 393.7 -294.94988)
		(end 393.22502 -294.4749)
		(width 0.249936)
		(layer "F.Cu")
		(net "P1V8_PEX")
	)
	(segment
		(start 87.494364 -310.07431)
		(end 87.3633 -309.943246)
		(width 0.4572)
		(layer "F.Cu")
		(net "P1V8_PEX")
	)
	(segment
		(start 161.500058 -295.89984)
		(end 161.025078 -296.37482)
		(width 0.249936)
		(layer "F.Cu")
		(net "P1V8_PEX")
	)
	(segment
		(start 33.486344 -249.670824)
		(end 34.502344 -249.670824)
		(width 0.4572)
		(layer "F.Cu")
		(net "P1V8_PEX")
	)
	(segment
		(start 317.957708 -298.093892)
		(end 317.957708 -298.6405)
		(width 0.3556)
		(layer "F.Cu")
		(net "P1V8_PEX")
	)
	(segment
		(start 144.506442 -249.670824)
		(end 145.522442 -249.670824)
		(width 0.4572)
		(layer "F.Cu")
		(net "P1V8_PEX")
	)
	(segment
		(start 437.950102 -312.2295)
		(end 437.231536 -311.510934)
		(width 0.4572)
		(layer "F.Cu")
		(net "P1V8_PEX")
	)
	(segment
		(start 434.331618 -296.623232)
		(end 434.331618 -297.975528)
		(width 0.3556)
		(layer "F.Cu")
		(net "P1V8_PEX")
	)
	(segment
		(start 323.88937 -296.556684)
		(end 324.097904 -296.765218)
		(width 0.4572)
		(layer "F.Cu")
		(net "P1V8_PEX")
	)
	(segment
		(start 92.446348 -309.877714)
		(end 92.235528 -309.877714)
		(width 0.4572)
		(layer "F.Cu")
		(net "P1V8_PEX")
	)
	(segment
		(start 29.422344 -249.670824)
		(end 30.438344 -249.670824)
		(width 0.4572)
		(layer "F.Cu")
		(net "P1V8_PEX")
	)
	(segment
		(start 39.582344 -250.091194)
		(end 40.002714 -249.670824)
		(width 0.4572)
		(layer "F.Cu")
		(net "P1V8_PEX")
	)
	(segment
		(start 29.368496 -309.170578)
		(end 30.80766 -307.731414)
		(width 0.4572)
		(layer "F.Cu")
		(net "P1V8_PEX")
	)
	(segment
		(start 91.689428 -295.647872)
		(end 91.689428 -296.164508)
		(width 0.4572)
		(layer "F.Cu")
		(net "P1V8_PEX")
	)
	(segment
		(start 301.349918 -291.149786)
		(end 301.824898 -290.674806)
		(width 0.249936)
		(layer "F.Cu")
		(net "P1V8_PEX")
	)
	(segment
		(start 185.725054 -289.724846)
		(end 185.250074 -290.199826)
		(width 0.249936)
		(layer "F.Cu")
		(net "P1V8_PEX")
	)
	(segment
		(start 25.737058 -222.32493)
		(end 24.62022 -222.32493)
		(width 0.4572)
		(layer "F.Cu")
		(net "P1V8_PEX")
	)
	(segment
		(start 253.713488 -254.353314)
		(end 253.713488 -253.876556)
		(width 0.4572)
		(layer "F.Cu")
		(net "P1V8_PEX")
	)
	(segment
		(start 372.882922 -222.32493)
		(end 373.99976 -222.32493)
		(width 0.4572)
		(layer "F.Cu")
		(net "P1V8_PEX")
	)
	(segment
		(start 277.599902 -293.04996)
		(end 277.124922 -292.57498)
		(width 0.249936)
		(layer "F.Cu")
		(net "P1V8_PEX")
	)
	(segment
		(start 263.578086 -225.097086)
		(end 263.193276 -225.481896)
		(width 0.4572)
		(layer "F.Cu")
		(net "P1V8_PEX")
	)
	(segment
		(start 379.1077 -305.346608)
		(end 378.667772 -304.90668)
		(width 0.4572)
		(layer "F.Cu")
		(net "P1V8_PEX")
	)
	(segment
		(start 375.122694 -310.756554)
		(end 376.138694 -310.756554)
		(width 0.4572)
		(layer "F.Cu")
		(net "P1V8_PEX")
	)
	(segment
		(start 208.335626 -309.877714)
		(end 208.017364 -310.195976)
		(width 0.4572)
		(layer "F.Cu")
		(net "P1V8_PEX")
	)
	(segment
		(start 270.766286 -249.670824)
		(end 270.766286 -249.00382)
		(width 0.4572)
		(layer "F.Cu")
		(net "P1V8_PEX")
	)
	(segment
		(start 163.399978 -291.149786)
		(end 162.924998 -290.674806)
		(width 0.249936)
		(layer "F.Cu")
		(net "P1V8_PEX")
	)
	(segment
		(start 30.80766 -307.731414)
		(end 31.296356 -307.731414)
		(width 0.4572)
		(layer "F.Cu")
		(net "P1V8_PEX")
	)
	(segment
		(start 393.7 -292.099746)
		(end 393.22502 -291.624766)
		(width 0.249936)
		(layer "F.Cu")
		(net "P1V8_PEX")
	)
	(segment
		(start 261.07263 -304.978816)
		(end 259.431282 -304.978816)
		(width 0.4572)
		(layer "F.Cu")
		(net "P1V8_PEX")
	)
	(segment
		(start 263.007602 -305.346608)
		(end 262.567674 -304.90668)
		(width 0.4572)
		(layer "F.Cu")
		(net "P1V8_PEX")
	)
	(segment
		(start 372.642384 -249.670824)
		(end 373.658384 -249.670824)
		(width 0.4572)
		(layer "F.Cu")
		(net "P1V8_PEX")
	)
	(segment
		(start 45.39996 -294.94988)
		(end 44.92498 -294.4749)
		(width 0.249936)
		(layer "F.Cu")
		(net "P1V8_PEX")
	)
	(segment
		(start 375.690384 -249.670824)
		(end 374.674384 -249.670824)
		(width 0.4572)
		(layer "F.Cu")
		(net "P1V8_PEX")
	)
	(segment
		(start 263.654286 -249.670824)
		(end 262.638286 -249.670824)
		(width 0.4572)
		(layer "F.Cu")
		(net "P1V8_PEX")
	)
	(segment
		(start 90.018108 -306.474622)
		(end 91.034108 -306.474622)
		(width 0.4572)
		(layer "F.Cu")
		(net "P1V8_PEX")
	)
	(segment
		(start 205.102206 -306.474622)
		(end 206.118206 -306.474622)
		(width 0.4572)
		(layer "F.Cu")
		(net "P1V8_PEX")
	)
	(segment
		(start 30.438344 -249.670824)
		(end 31.454344 -249.670824)
		(width 0.4572)
		(layer "F.Cu")
		(net "P1V8_PEX")
	)
	(segment
		(start 206.79664 -299.27296)
		(end 207.461612 -299.27296)
		(width 0.4572)
		(layer "F.Cu")
		(net "P1V8_PEX")
	)
	(segment
		(start 155.682442 -250.009152)
		(end 155.344114 -249.670824)
		(width 0.4572)
		(layer "F.Cu")
		(net "P1V8_PEX")
	)
	(segment
		(start 270.766286 -249.670824)
		(end 272.798286 -249.670824)
		(width 0.4572)
		(layer "F.Cu")
		(net "P1V8_PEX")
	)
	(segment
		(start 324.097904 -296.765218)
		(end 325.197724 -296.765218)
		(width 0.4572)
		(layer "F.Cu")
		(net "P1V8_PEX")
	)
	(segment
		(start 379.754384 -249.670824)
		(end 378.738384 -249.670824)
		(width 0.4572)
		(layer "F.Cu")
		(net "P1V8_PEX")
	)
	(segment
		(start 204.31252 -310.792368)
		(end 203.594462 -310.07431)
		(width 0.4572)
		(layer "F.Cu")
		(net "P1V8_PEX")
	)
	(segment
		(start 29.978858 -310.724296)
		(end 29.368496 -310.113934)
		(width 0.4572)
		(layer "F.Cu")
		(net "P1V8_PEX")
	)
	(segment
		(start 317.338202 -298.440602)
		(end 317.338202 -297.95851)
		(width 0.4572)
		(layer "F.Cu")
		(net "P1V8_PEX")
	)
	(segment
		(start 262.896858 -310.006238)
		(end 262.1788 -310.724296)
		(width 0.4572)
		(layer "F.Cu")
		(net "P1V8_PEX")
	)
	(segment
		(start 384.834384 -249.670824)
		(end 383.818384 -249.670824)
		(width 0.4572)
		(layer "F.Cu")
		(net "P1V8_PEX")
	)
	(segment
		(start 441.712096 -308.912006)
		(end 441.712096 -307.399944)
		(width 0.4572)
		(layer "F.Cu")
		(net "P1V8_PEX")
	)
	(segment
		(start 437.231536 -311.510934)
		(end 436.51297 -310.792368)
		(width 0.4572)
		(layer "F.Cu")
		(net "P1V8_PEX")
	)
	(segment
		(start 277.599902 -294.94988)
		(end 277.124922 -294.4749)
		(width 0.249936)
		(layer "F.Cu")
		(net "P1V8_PEX")
	)
	(segment
		(start 144.518634 -310.113934)
		(end 143.938752 -310.693816)
		(width 0.4572)
		(layer "F.Cu")
		(net "P1V8_PEX")
	)
	(segment
		(start 388.898384 -249.670824)
		(end 388.25043 -249.670824)
		(width 0.4572)
		(layer "F.Cu")
		(net "P1V8_PEX")
	)
	(segment
		(start 264.334244 -308.569106)
		(end 264.33399 -308.569106)
		(width 0.4572)
		(layer "F.Cu")
		(net "P1V8_PEX")
	)
	(segment
		(start 261.568438 -309.170578)
		(end 263.007602 -307.731414)
		(width 0.4572)
		(layer "F.Cu")
		(net "P1V8_PEX")
	)
	(segment
		(start 441.297822 -296.765218)
		(end 441.297822 -297.374818)
		(width 0.4572)
		(layer "F.Cu")
		(net "P1V8_PEX")
	)
	(via
		(at 277.124922 -291.624766)
		(size 0.4064)
		(drill 0.2032)
		(layers "F.Cu" "B.Cu")
		(net "P1V8_PEX")
	)
	(via
		(at 297.103038 -201.15149)
		(size 0.508)
		(drill 0.254)
		(layers "F.Cu" "B.Cu")
		(net "P1V8_PEX")
	)
	(via
		(at 160.546034 -290.191698)
		(size 0.6604)
		(drill 0.3302)
		(layers "F.Cu" "B.Cu")
		(net "P1V8_PEX")
	)
	(via
		(at 209.09788 -297.374818)
		(size 0.508)
		(drill 0.254)
		(layers "F.Cu" "B.Cu")
		(net "P1V8_PEX")
	)
	(via
		(at 417.924996 -288.774886)
		(size 0.4064)
		(drill 0.2032)
		(layers "F.Cu" "B.Cu")
		(net "P1V8_PEX")
	)
	(via
		(at 183.169814 -185.606436)
		(size 0.762)
		(drill 0.381)
		(layers "F.Cu" "B.Cu")
		(net "P1V8_PEX")
	)
	(via
		(at 102.705916 -249.67438)
		(size 0.508)
		(drill 0.254)
		(layers "F.Cu" "B.Cu")
		(net "P1V8_PEX")
	)
	(via
		(at 263.578086 -225.097086)
		(size 0.508)
		(drill 0.254)
		(layers "F.Cu" "B.Cu")
		(net "P1V8_PEX")
	)
	(via
		(at 142.474442 -249.032522)
		(size 0.508)
		(drill 0.254)
		(layers "F.Cu" "B.Cu")
		(net "P1V8_PEX")
	)
	(via
		(at 185.725054 -303.024794)
		(size 0.4064)
		(drill 0.2032)
		(layers "F.Cu" "B.Cu")
		(net "P1V8_PEX")
	)
	(via
		(at 264.032746 -279.084532)
		(size 0.508)
		(drill 0.254)
		(layers "F.Cu" "B.Cu")
		(net "P1V8_PEX")
	)
	(via
		(at 26.148538 -222.807784)
		(size 0.508)
		(drill 0.254)
		(layers "F.Cu" "B.Cu")
		(net "P1V8_PEX")
	)
	(via
		(at 339.09 -174.117)
		(size 0.508)
		(drill 0.254)
		(layers "F.Cu" "B.Cu")
		(net "P1V8_PEX")
	)
	(via
		(at 208.132426 -312.48731)
		(size 0.508)
		(drill 0.254)
		(layers "F.Cu" "B.Cu")
		(net "P1V8_PEX")
	)
	(via
		(at 392.740896 -290.20008)
		(size 0.6604)
		(drill 0.3302)
		(layers "F.Cu" "B.Cu")
		(net "P1V8_PEX")
	)
	(via
		(at 209.196432 -307.084222)
		(size 0.508)
		(drill 0.254)
		(layers "F.Cu" "B.Cu")
		(net "P1V8_PEX")
	)
	(via
		(at 322.896484 -299.27296)
		(size 0.508)
		(drill 0.254)
		(layers "F.Cu" "B.Cu")
		(net "P1V8_PEX")
	)
	(via
		(at 157.195012 -257.026156)
		(size 0.508)
		(drill 0.254)
		(layers "F.Cu" "B.Cu")
		(net "P1V8_PEX")
	)
	(via
		(at 44.92498 -290.674806)
		(size 0.4064)
		(drill 0.2032)
		(layers "F.Cu" "B.Cu")
		(net "P1V8_PEX")
	)
	(via
		(at 417.924996 -301.124874)
		(size 0.4064)
		(drill 0.2032)
		(layers "F.Cu" "B.Cu")
		(net "P1V8_PEX")
	)
	(via
		(at 130.729228 -211.98586)
		(size 0.508)
		(drill 0.254)
		(layers "F.Cu" "B.Cu")
		(net "P1V8_PEX")
	)
	(via
		(at 438.996582 -299.27296)
		(size 0.508)
		(drill 0.254)
		(layers "F.Cu" "B.Cu")
		(net "P1V8_PEX")
	)
	(via
		(at 103.366316 -249.67438)
		(size 0.508)
		(drill 0.254)
		(layers "F.Cu" "B.Cu")
		(net "P1V8_PEX")
	)
	(via
		(at 185.725054 -288.774886)
		(size 0.4064)
		(drill 0.2032)
		(layers "F.Cu" "B.Cu")
		(net "P1V8_PEX")
	)
	(via
		(at 147.276058 -225.552)
		(size 0.508)
		(drill 0.254)
		(layers "F.Cu" "B.Cu")
		(net "P1V8_PEX")
	)
	(via
		(at 389.424926 -284.974792)
		(size 0.4064)
		(drill 0.2032)
		(layers "F.Cu" "B.Cu")
		(net "P1V8_PEX")
	)
	(via
		(at 104.63784 -244.414294)
		(size 0.508)
		(drill 0.254)
		(layers "F.Cu" "B.Cu")
		(net "P1V8_PEX")
	)
	(via
		(at 25.99817 -222.063818)
		(size 0.508)
		(drill 0.254)
		(layers "F.Cu" "B.Cu")
		(net "P1V8_PEX")
	)
	(via
		(at 144.52346 -214.559134)
		(size 0.508)
		(drill 0.254)
		(layers "F.Cu" "B.Cu")
		(net "P1V8_PEX")
	)
	(via
		(at 317.338202 -297.95851)
		(size 0.508)
		(drill 0.254)
		(layers "F.Cu" "B.Cu")
		(net "P1V8_PEX")
	)
	(via
		(at 105.95864 -244.414294)
		(size 0.508)
		(drill 0.254)
		(layers "F.Cu" "B.Cu")
		(net "P1V8_PEX")
	)
	(via
		(at 141.349222 -284.061154)
		(size 0.508)
		(drill 0.254)
		(layers "F.Cu" "B.Cu")
		(net "P1V8_PEX")
	)
	(via
		(at 325.296276 -307.084222)
		(size 0.508)
		(drill 0.254)
		(layers "F.Cu" "B.Cu")
		(net "P1V8_PEX")
	)
	(via
		(at 46.8249 -301.124874)
		(size 0.4064)
		(drill 0.2032)
		(layers "F.Cu" "B.Cu")
		(net "P1V8_PEX")
	)
	(via
		(at 395.12494 -290.674806)
		(size 0.4064)
		(drill 0.2032)
		(layers "F.Cu" "B.Cu")
		(net "P1V8_PEX")
	)
	(via
		(at 44.92498 -296.37482)
		(size 0.4064)
		(drill 0.2032)
		(layers "F.Cu" "B.Cu")
		(net "P1V8_PEX")
	)
	(via
		(at 277.124922 -290.674806)
		(size 0.4064)
		(drill 0.2032)
		(layers "F.Cu" "B.Cu")
		(net "P1V8_PEX")
	)
	(via
		(at 370.069364 -253.620778)
		(size 0.508)
		(drill 0.254)
		(layers "F.Cu" "B.Cu")
		(net "P1V8_PEX")
	)
	(via
		(at 185.725054 -302.074834)
		(size 0.4064)
		(drill 0.2032)
		(layers "F.Cu" "B.Cu")
		(net "P1V8_PEX")
	)
	(via
		(at 277.124922 -294.4749)
		(size 0.4064)
		(drill 0.2032)
		(layers "F.Cu" "B.Cu")
		(net "P1V8_PEX")
	)
	(via
		(at 21.769324 -253.620778)
		(size 0.508)
		(drill 0.254)
		(layers "F.Cu" "B.Cu")
		(net "P1V8_PEX")
	)
	(via
		(at 364.67923 -228.981)
		(size 0.508)
		(drill 0.254)
		(layers "F.Cu" "B.Cu")
		(net "P1V8_PEX")
	)
	(via
		(at 92.032328 -312.48731)
		(size 0.508)
		(drill 0.254)
		(layers "F.Cu" "B.Cu")
		(net "P1V8_PEX")
	)
	(via
		(at 102.660704 -247.671336)
		(size 0.508)
		(drill 0.254)
		(layers "F.Cu" "B.Cu")
		(net "P1V8_PEX")
	)
	(via
		(at 102.660704 -246.375936)
		(size 0.508)
		(drill 0.254)
		(layers "F.Cu" "B.Cu")
		(net "P1V8_PEX")
	)
	(via
		(at 393.22502 -290.674806)
		(size 0.4064)
		(drill 0.2032)
		(layers "F.Cu" "B.Cu")
		(net "P1V8_PEX")
	)
	(via
		(at 129.982214 -215.048846)
		(size 0.508)
		(drill 0.254)
		(layers "F.Cu" "B.Cu")
		(net "P1V8_PEX")
	)
	(via
		(at 69.624956 -303.024794)
		(size 0.4064)
		(drill 0.2032)
		(layers "F.Cu" "B.Cu")
		(net "P1V8_PEX")
	)
	(via
		(at 204.132942 -260.46176)
		(size 0.508)
		(drill 0.254)
		(layers "F.Cu" "B.Cu")
		(net "P1V8_PEX")
	)
	(via
		(at 301.824898 -303.024794)
		(size 0.4064)
		(drill 0.2032)
		(layers "F.Cu" "B.Cu")
		(net "P1V8_PEX")
	)
	(via
		(at 373.658384 -249.00382)
		(size 0.508)
		(drill 0.254)
		(layers "F.Cu" "B.Cu")
		(net "P1V8_PEX")
	)
	(via
		(at 102.660704 -248.331736)
		(size 0.508)
		(drill 0.254)
		(layers "F.Cu" "B.Cu")
		(net "P1V8_PEX")
	)
	(via
		(at 362.204 -182.118)
		(size 0.508)
		(drill 0.254)
		(layers "F.Cu" "B.Cu")
		(net "P1V8_PEX")
	)
	(via
		(at 69.624956 -290.674806)
		(size 0.4064)
		(drill 0.2032)
		(layers "F.Cu" "B.Cu")
		(net "P1V8_PEX")
	)
	(via
		(at 144.407128 -304.800254)
		(size 0.508)
		(drill 0.254)
		(layers "F.Cu" "B.Cu")
		(net "P1V8_PEX")
	)
	(via
		(at 41.124886 -284.974792)
		(size 0.4064)
		(drill 0.2032)
		(layers "F.Cu" "B.Cu")
		(net "P1V8_PEX")
	)
	(via
		(at 362.204 -193.294)
		(size 0.508)
		(drill 0.254)
		(layers "F.Cu" "B.Cu")
		(net "P1V8_PEX")
	)
	(via
		(at 26.408888 -248.312686)
		(size 0.508)
		(drill 0.254)
		(layers "F.Cu" "B.Cu")
		(net "P1V8_PEX")
	)
	(via
		(at 45.387006 -288.299144)
		(size 0.6604)
		(drill 0.3302)
		(layers "F.Cu" "B.Cu")
		(net "P1V8_PEX")
	)
	(via
		(at 72.474836 -284.024832)
		(size 0.4064)
		(drill 0.2032)
		(layers "F.Cu" "B.Cu")
		(net "P1V8_PEX")
	)
	(via
		(at 178.479958 -196.890386)
		(size 0.508)
		(drill 0.254)
		(layers "F.Cu" "B.Cu")
		(net "P1V8_PEX")
	)
	(via
		(at 393.22502 -296.37482)
		(size 0.4064)
		(drill 0.2032)
		(layers "F.Cu" "B.Cu")
		(net "P1V8_PEX")
	)
	(via
		(at 301.824898 -289.724846)
		(size 0.4064)
		(drill 0.2032)
		(layers "F.Cu" "B.Cu")
		(net "P1V8_PEX")
	)
	(via
		(at 132.479288 -228.981)
		(size 0.508)
		(drill 0.254)
		(layers "F.Cu" "B.Cu")
		(net "P1V8_PEX")
	)
	(via
		(at 376.60707 -304.800254)
		(size 0.508)
		(drill 0.254)
		(layers "F.Cu" "B.Cu")
		(net "P1V8_PEX")
	)
	(via
		(at 338.829396 -262.504682)
		(size 0.508)
		(drill 0.254)
		(layers "F.Cu" "B.Cu")
		(net "P1V8_PEX")
	)
	(via
		(at 432.6636 -298.2976)
		(size 0.508)
		(drill 0.254)
		(layers "F.Cu" "B.Cu")
		(net "P1V8_PEX")
	)
	(via
		(at 273.324828 -284.024832)
		(size 0.4064)
		(drill 0.2032)
		(layers "F.Cu" "B.Cu")
		(net "P1V8_PEX")
	)
	(via
		(at 257.558286 -249.010424)
		(size 0.508)
		(drill 0.254)
		(layers "F.Cu" "B.Cu")
		(net "P1V8_PEX")
	)
	(via
		(at 270.766286 -249.00382)
		(size 0.508)
		(drill 0.254)
		(layers "F.Cu" "B.Cu")
		(net "P1V8_PEX")
	)
	(via
		(at 105.29824 -244.414294)
		(size 0.508)
		(drill 0.254)
		(layers "F.Cu" "B.Cu")
		(net "P1V8_PEX")
	)
	(via
		(at 301.824898 -302.074834)
		(size 0.4064)
		(drill 0.2032)
		(layers "F.Cu" "B.Cu")
		(net "P1V8_PEX")
	)
	(via
		(at 71.524876 -284.024832)
		(size 0.4064)
		(drill 0.2032)
		(layers "F.Cu" "B.Cu")
		(net "P1V8_PEX")
	)
	(via
		(at 301.824898 -301.124874)
		(size 0.4064)
		(drill 0.2032)
		(layers "F.Cu" "B.Cu")
		(net "P1V8_PEX")
	)
	(via
		(at 248.816368 -229.323646)
		(size 0.508)
		(drill 0.254)
		(layers "F.Cu" "B.Cu")
		(net "P1V8_PEX")
	)
	(via
		(at 149.447758 -205.114144)
		(size 0.508)
		(drill 0.254)
		(layers "F.Cu" "B.Cu")
		(net "P1V8_PEX")
	)
	(via
		(at 258.266692 -226.135946)
		(size 0.508)
		(drill 0.254)
		(layers "F.Cu" "B.Cu")
		(net "P1V8_PEX")
	)
	(via
		(at 417.924996 -303.024794)
		(size 0.4064)
		(drill 0.2032)
		(layers "F.Cu" "B.Cu")
		(net "P1V8_PEX")
	)
	(via
		(at 258.311142 -222.807784)
		(size 0.508)
		(drill 0.254)
		(layers "F.Cu" "B.Cu")
		(net "P1V8_PEX")
	)
	(via
		(at 44.92498 -291.624766)
		(size 0.4064)
		(drill 0.2032)
		(layers "F.Cu" "B.Cu")
		(net "P1V8_PEX")
	)
	(via
		(at 298.831 -199.372982)
		(size 0.508)
		(drill 0.254)
		(layers "F.Cu" "B.Cu")
		(net "P1V8_PEX")
	)
	(via
		(at 390.374886 -284.024832)
		(size 0.4064)
		(drill 0.2032)
		(layers "F.Cu" "B.Cu")
		(net "P1V8_PEX")
	)
	(via
		(at 202.090274 -260.46176)
		(size 0.508)
		(drill 0.254)
		(layers "F.Cu" "B.Cu")
		(net "P1V8_PEX")
	)
	(via
		(at 271.680178 -248.953274)
		(size 0.508)
		(drill 0.254)
		(layers "F.Cu" "B.Cu")
		(net "P1V8_PEX")
	)
	(via
		(at 328.69505 -232.918)
		(size 0.508)
		(drill 0.254)
		(layers "F.Cu" "B.Cu")
		(net "P1V8_PEX")
	)
	(via
		(at 253.969266 -253.620778)
		(size 0.508)
		(drill 0.254)
		(layers "F.Cu" "B.Cu")
		(net "P1V8_PEX")
	)
	(via
		(at 389.424926 -284.024832)
		(size 0.4064)
		(drill 0.2032)
		(layers "F.Cu" "B.Cu")
		(net "P1V8_PEX")
	)
	(via
		(at 303.724818 -284.024832)
		(size 0.4064)
		(drill 0.2032)
		(layers "F.Cu" "B.Cu")
		(net "P1V8_PEX")
	)
	(via
		(at 25.358344 -249.00382)
		(size 0.508)
		(drill 0.254)
		(layers "F.Cu" "B.Cu")
		(net "P1V8_PEX")
	)
	(via
		(at 178.483514 -192.270634)
		(size 0.508)
		(drill 0.254)
		(layers "F.Cu" "B.Cu")
		(net "P1V8_PEX")
	)
	(via
		(at 31.213298 -225.552)
		(size 0.508)
		(drill 0.254)
		(layers "F.Cu" "B.Cu")
		(net "P1V8_PEX")
	)
	(via
		(at 142.05204 -226.324922)
		(size 0.508)
		(drill 0.254)
		(layers "F.Cu" "B.Cu")
		(net "P1V8_PEX")
	)
	(via
		(at 69.624956 -302.074834)
		(size 0.4064)
		(drill 0.2032)
		(layers "F.Cu" "B.Cu")
		(net "P1V8_PEX")
	)
	(via
		(at 376.571764 -224.067116)
		(size 0.508)
		(drill 0.254)
		(layers "F.Cu" "B.Cu")
		(net "P1V8_PEX")
	)
	(via
		(at 441.297822 -297.374818)
		(size 0.508)
		(drill 0.254)
		(layers "F.Cu" "B.Cu")
		(net "P1V8_PEX")
	)
	(via
		(at 393.22502 -292.57498)
		(size 0.4064)
		(drill 0.2032)
		(layers "F.Cu" "B.Cu")
		(net "P1V8_PEX")
	)
	(via
		(at 146.685254 -210.583526)
		(size 0.508)
		(drill 0.254)
		(layers "F.Cu" "B.Cu")
		(net "P1V8_PEX")
	)
	(via
		(at 339.09 -151.003)
		(size 0.508)
		(drill 0.254)
		(layers "F.Cu" "B.Cu")
		(net "P1V8_PEX")
	)
	(via
		(at 141.458442 -249.052842)
		(size 0.508)
		(drill 0.254)
		(layers "F.Cu" "B.Cu")
		(net "P1V8_PEX")
	)
	(via
		(at 417.924996 -289.724846)
		(size 0.4064)
		(drill 0.2032)
		(layers "F.Cu" "B.Cu")
		(net "P1V8_PEX")
	)
	(via
		(at 138.745214 -214.159846)
		(size 0.508)
		(drill 0.254)
		(layers "F.Cu" "B.Cu")
		(net "P1V8_PEX")
	)
	(via
		(at 69.624956 -289.724846)
		(size 0.4064)
		(drill 0.2032)
		(layers "F.Cu" "B.Cu")
		(net "P1V8_PEX")
	)
	(via
		(at 393.22502 -291.624766)
		(size 0.4064)
		(drill 0.2032)
		(layers "F.Cu" "B.Cu")
		(net "P1V8_PEX")
	)
	(via
		(at 376.526298 -221.72676)
		(size 0.508)
		(drill 0.254)
		(layers "F.Cu" "B.Cu")
		(net "P1V8_PEX")
	)
	(via
		(at 209.182208 -236.3978)
		(size 0.508)
		(drill 0.254)
		(layers "F.Cu" "B.Cu")
		(net "P1V8_PEX")
	)
	(via
		(at 206.79664 -299.27296)
		(size 0.508)
		(drill 0.254)
		(layers "F.Cu" "B.Cu")
		(net "P1V8_PEX")
	)
	(via
		(at 161.025078 -292.57498)
		(size 0.4064)
		(drill 0.2032)
		(layers "F.Cu" "B.Cu")
		(net "P1V8_PEX")
	)
	(via
		(at 301.824898 -290.674806)
		(size 0.4064)
		(drill 0.2032)
		(layers "F.Cu" "B.Cu")
		(net "P1V8_PEX")
	)
	(via
		(at 69.624956 -301.124874)
		(size 0.4064)
		(drill 0.2032)
		(layers "F.Cu" "B.Cu")
		(net "P1V8_PEX")
	)
	(via
		(at 256.428748 -183.499252)
		(size 0.508)
		(drill 0.254)
		(layers "F.Cu" "B.Cu")
		(net "P1V8_PEX")
	)
	(via
		(at 137.869422 -253.620778)
		(size 0.508)
		(drill 0.254)
		(layers "F.Cu" "B.Cu")
		(net "P1V8_PEX")
	)
	(via
		(at 22.9743 -262.519668)
		(size 0.508)
		(drill 0.254)
		(layers "F.Cu" "B.Cu")
		(net "P1V8_PEX")
	)
	(via
		(at 44.92498 -294.4749)
		(size 0.4064)
		(drill 0.2032)
		(layers "F.Cu" "B.Cu")
		(net "P1V8_PEX")
	)
	(via
		(at 277.124922 -296.37482)
		(size 0.4064)
		(drill 0.2032)
		(layers "F.Cu" "B.Cu")
		(net "P1V8_PEX")
	)
	(via
		(at 279.024842 -290.674806)
		(size 0.4064)
		(drill 0.2032)
		(layers "F.Cu" "B.Cu")
		(net "P1V8_PEX")
	)
	(via
		(at 441.396374 -307.084222)
		(size 0.508)
		(drill 0.254)
		(layers "F.Cu" "B.Cu")
		(net "P1V8_PEX")
	)
	(via
		(at 419.824916 -284.024832)
		(size 0.4064)
		(drill 0.2032)
		(layers "F.Cu" "B.Cu")
		(net "P1V8_PEX")
	)
	(via
		(at 209.338672 -241.182652)
		(size 0.508)
		(drill 0.254)
		(layers "F.Cu" "B.Cu")
		(net "P1V8_PEX")
	)
	(via
		(at 46.8249 -290.674806)
		(size 0.4064)
		(drill 0.2032)
		(layers "F.Cu" "B.Cu")
		(net "P1V8_PEX")
	)
	(via
		(at 105.124504 -248.439686)
		(size 0.508)
		(drill 0.254)
		(layers "F.Cu" "B.Cu")
		(net "P1V8_PEX")
	)
	(via
		(at 200.123298 -298.323)
		(size 0.508)
		(drill 0.254)
		(layers "F.Cu" "B.Cu")
		(net "P1V8_PEX")
	)
	(via
		(at 279.024842 -301.124874)
		(size 0.4064)
		(drill 0.2032)
		(layers "F.Cu" "B.Cu")
		(net "P1V8_PEX")
	)
	(via
		(at 185.725054 -290.674806)
		(size 0.4064)
		(drill 0.2032)
		(layers "F.Cu" "B.Cu")
		(net "P1V8_PEX")
	)
	(via
		(at 257.264154 -183.493918)
		(size 0.508)
		(drill 0.254)
		(layers "F.Cu" "B.Cu")
		(net "P1V8_PEX")
	)
	(via
		(at 178.479958 -198.287386)
		(size 0.508)
		(drill 0.254)
		(layers "F.Cu" "B.Cu")
		(net "P1V8_PEX")
	)
	(via
		(at 94.615254 -285.41853)
		(size 0.508)
		(drill 0.254)
		(layers "F.Cu" "B.Cu")
		(net "P1V8_PEX")
	)
	(via
		(at 200.4187 -260.6421)
		(size 0.508)
		(drill 0.254)
		(layers "F.Cu" "B.Cu")
		(net "P1V8_PEX")
	)
	(via
		(at 16.416528 -228.981)
		(size 0.508)
		(drill 0.254)
		(layers "F.Cu" "B.Cu")
		(net "P1V8_PEX")
	)
	(via
		(at 26.101294 -278.443182)
		(size 0.508)
		(drill 0.254)
		(layers "F.Cu" "B.Cu")
		(net "P1V8_PEX")
	)
	(via
		(at 180.40985 -199.677274)
		(size 0.508)
		(drill 0.254)
		(layers "F.Cu" "B.Cu")
		(net "P1V8_PEX")
	)
	(via
		(at 161.025078 -291.624766)
		(size 0.4064)
		(drill 0.2032)
		(layers "F.Cu" "B.Cu")
		(net "P1V8_PEX")
	)
	(via
		(at 291.06114 -204.125068)
		(size 0.508)
		(drill 0.254)
		(layers "F.Cu" "B.Cu")
		(net "P1V8_PEX")
	)
	(via
		(at 417.924996 -290.674806)
		(size 0.4064)
		(drill 0.2032)
		(layers "F.Cu" "B.Cu")
		(net "P1V8_PEX")
	)
	(via
		(at 374.260872 -222.063818)
		(size 0.508)
		(drill 0.254)
		(layers "F.Cu" "B.Cu")
		(net "P1V8_PEX")
	)
	(via
		(at 211.435442 -245.025926)
		(size 0.508)
		(drill 0.254)
		(layers "F.Cu" "B.Cu")
		(net "P1V8_PEX")
	)
	(via
		(at 41.124886 -284.024832)
		(size 0.4064)
		(drill 0.2032)
		(layers "F.Cu" "B.Cu")
		(net "P1V8_PEX")
	)
	(via
		(at 366.522 -203.835)
		(size 0.508)
		(drill 0.254)
		(layers "F.Cu" "B.Cu")
		(net "P1V8_PEX")
	)
	(via
		(at 26.374344 -249.00382)
		(size 0.508)
		(drill 0.254)
		(layers "F.Cu" "B.Cu")
		(net "P1V8_PEX")
	)
	(via
		(at 157.224984 -284.974792)
		(size 0.4064)
		(drill 0.2032)
		(layers "F.Cu" "B.Cu")
		(net "P1V8_PEX")
	)
	(via
		(at 261.568438 -310.113934)
		(size 0.508)
		(drill 0.254)
		(layers "F.Cu" "B.Cu")
		(net "P1V8_PEX")
	)
	(via
		(at 258.574286 -249.010424)
		(size 0.508)
		(drill 0.254)
		(layers "F.Cu" "B.Cu")
		(net "P1V8_PEX")
	)
	(via
		(at 417.924996 -302.074834)
		(size 0.4064)
		(drill 0.2032)
		(layers "F.Cu" "B.Cu")
		(net "P1V8_PEX")
	)
	(via
		(at 325.197724 -297.374818)
		(size 0.508)
		(drill 0.254)
		(layers "F.Cu" "B.Cu")
		(net "P1V8_PEX")
	)
	(via
		(at 142.211298 -222.807784)
		(size 0.508)
		(drill 0.254)
		(layers "F.Cu" "B.Cu")
		(net "P1V8_PEX")
	)
	(via
		(at 375.031 -247.396)
		(size 0.508)
		(drill 0.254)
		(layers "F.Cu" "B.Cu")
		(net "P1V8_PEX")
	)
	(via
		(at 25.98928 -226.324922)
		(size 0.508)
		(drill 0.254)
		(layers "F.Cu" "B.Cu")
		(net "P1V8_PEX")
	)
	(via
		(at 374.251982 -226.324922)
		(size 0.508)
		(drill 0.254)
		(layers "F.Cu" "B.Cu")
		(net "P1V8_PEX")
	)
	(via
		(at 104.464104 -248.439686)
		(size 0.508)
		(drill 0.254)
		(layers "F.Cu" "B.Cu")
		(net "P1V8_PEX")
	)
	(via
		(at 104.026716 -249.67438)
		(size 0.508)
		(drill 0.254)
		(layers "F.Cu" "B.Cu")
		(net "P1V8_PEX")
	)
	(via
		(at 90.692478 -299.603668)
		(size 0.508)
		(drill 0.254)
		(layers "F.Cu" "B.Cu")
		(net "P1V8_PEX")
	)
	(via
		(at 274.274788 -284.024832)
		(size 0.4064)
		(drill 0.2032)
		(layers "F.Cu" "B.Cu")
		(net "P1V8_PEX")
	)
	(via
		(at 69.624956 -288.774886)
		(size 0.4064)
		(drill 0.2032)
		(layers "F.Cu" "B.Cu")
		(net "P1V8_PEX")
	)
	(via
		(at 187.624974 -284.024832)
		(size 0.4064)
		(drill 0.2032)
		(layers "F.Cu" "B.Cu")
		(net "P1V8_PEX")
	)
	(via
		(at 374.674384 -249.00382)
		(size 0.508)
		(drill 0.254)
		(layers "F.Cu" "B.Cu")
		(net "P1V8_PEX")
	)
	(via
		(at 84.0232 -298.323)
		(size 0.508)
		(drill 0.254)
		(layers "F.Cu" "B.Cu")
		(net "P1V8_PEX")
	)
	(via
		(at 142.06093 -222.063818)
		(size 0.508)
		(drill 0.254)
		(layers "F.Cu" "B.Cu")
		(net "P1V8_PEX")
	)
	(via
		(at 93.096334 -307.084222)
		(size 0.508)
		(drill 0.254)
		(layers "F.Cu" "B.Cu")
		(net "P1V8_PEX")
	)
	(via
		(at 277.124922 -292.57498)
		(size 0.4064)
		(drill 0.2032)
		(layers "F.Cu" "B.Cu")
		(net "P1V8_PEX")
	)
	(via
		(at 273.324828 -284.974792)
		(size 0.4064)
		(drill 0.2032)
		(layers "F.Cu" "B.Cu")
		(net "P1V8_PEX")
	)
	(via
		(at 149.352254 -210.724496)
		(size 0.508)
		(drill 0.254)
		(layers "F.Cu" "B.Cu")
		(net "P1V8_PEX")
	)
	(via
		(at 339.09 -162.814)
		(size 0.508)
		(drill 0.254)
		(layers "F.Cu" "B.Cu")
		(net "P1V8_PEX")
	)
	(via
		(at 157.224984 -284.024832)
		(size 0.4064)
		(drill 0.2032)
		(layers "F.Cu" "B.Cu")
		(net "P1V8_PEX")
	)
	(via
		(at 339.09 -186.055)
		(size 0.508)
		(drill 0.254)
		(layers "F.Cu" "B.Cu")
		(net "P1V8_PEX")
	)
	(via
		(at 374.41124 -222.807784)
		(size 0.508)
		(drill 0.254)
		(layers "F.Cu" "B.Cu")
		(net "P1V8_PEX")
	)
	(via
		(at 276.64283 -290.199572)
		(size 0.6604)
		(drill 0.3302)
		(layers "F.Cu" "B.Cu")
		(net "P1V8_PEX")
	)
	(via
		(at 383.794 -246.507)
		(size 0.508)
		(drill 0.254)
		(layers "F.Cu" "B.Cu")
		(net "P1V8_PEX")
	)
	(via
		(at 105.784904 -248.439686)
		(size 0.508)
		(drill 0.254)
		(layers "F.Cu" "B.Cu")
		(net "P1V8_PEX")
	)
	(via
		(at 18.03908 -310.978042)
		(size 0.508)
		(drill 0.254)
		(layers "F.Cu" "B.Cu")
		(net "P1V8_PEX")
	)
	(via
		(at 44.92498 -292.57498)
		(size 0.4064)
		(drill 0.2032)
		(layers "F.Cu" "B.Cu")
		(net "P1V8_PEX")
	)
	(via
		(at 395.12494 -301.124874)
		(size 0.4064)
		(drill 0.2032)
		(layers "F.Cu" "B.Cu")
		(net "P1V8_PEX")
	)
	(via
		(at 329.13701 -285.735522)
		(size 0.508)
		(drill 0.254)
		(layers "F.Cu" "B.Cu")
		(net "P1V8_PEX")
	)
	(via
		(at 373.728996 -284.138116)
		(size 0.508)
		(drill 0.254)
		(layers "F.Cu" "B.Cu")
		(net "P1V8_PEX")
	)
	(via
		(at 304.674778 -284.024832)
		(size 0.4064)
		(drill 0.2032)
		(layers "F.Cu" "B.Cu")
		(net "P1V8_PEX")
	)
	(via
		(at 161.025078 -294.4749)
		(size 0.4064)
		(drill 0.2032)
		(layers "F.Cu" "B.Cu")
		(net "P1V8_PEX")
	)
	(via
		(at 161.025078 -290.674806)
		(size 0.4064)
		(drill 0.2032)
		(layers "F.Cu" "B.Cu")
		(net "P1V8_PEX")
	)
	(via
		(at 102.660704 -247.010936)
		(size 0.508)
		(drill 0.254)
		(layers "F.Cu" "B.Cu")
		(net "P1V8_PEX")
	)
	(via
		(at 149.43963 -202.69962)
		(size 0.508)
		(drill 0.254)
		(layers "F.Cu" "B.Cu")
		(net "P1V8_PEX")
	)
	(via
		(at 158.174944 -284.024832)
		(size 0.4064)
		(drill 0.2032)
		(layers "F.Cu" "B.Cu")
		(net "P1V8_PEX")
	)
	(via
		(at 271.782286 -251.158502)
		(size 0.508)
		(drill 0.254)
		(layers "F.Cu" "B.Cu")
		(net "P1V8_PEX")
	)
	(via
		(at 329.156822 -285.034228)
		(size 0.508)
		(drill 0.254)
		(layers "F.Cu" "B.Cu")
		(net "P1V8_PEX")
	)
	(via
		(at 162.924998 -290.674806)
		(size 0.4064)
		(drill 0.2032)
		(layers "F.Cu" "B.Cu")
		(net "P1V8_PEX")
	)
	(via
		(at 301.824898 -288.774886)
		(size 0.4064)
		(drill 0.2032)
		(layers "F.Cu" "B.Cu")
		(net "P1V8_PEX")
	)
	(via
		(at 375.778014 -244.333014)
		(size 0.508)
		(drill 0.254)
		(layers "F.Cu" "B.Cu")
		(net "P1V8_PEX")
	)
	(via
		(at 149.421088 -204.368654)
		(size 0.508)
		(drill 0.254)
		(layers "F.Cu" "B.Cu")
		(net "P1V8_PEX")
	)
	(via
		(at 393.22502 -294.4749)
		(size 0.4064)
		(drill 0.2032)
		(layers "F.Cu" "B.Cu")
		(net "P1V8_PEX")
	)
	(via
		(at 295.89095 -201.068178)
		(size 0.508)
		(drill 0.254)
		(layers "F.Cu" "B.Cu")
		(net "P1V8_PEX")
	)
	(via
		(at 257.718814 -184.006744)
		(size 0.508)
		(drill 0.254)
		(layers "F.Cu" "B.Cu")
		(net "P1V8_PEX")
	)
	(via
		(at 256.84099 -184.027826)
		(size 0.508)
		(drill 0.254)
		(layers "F.Cu" "B.Cu")
		(net "P1V8_PEX")
	)
	(via
		(at 178.483514 -193.794634)
		(size 0.508)
		(drill 0.254)
		(layers "F.Cu" "B.Cu")
		(net "P1V8_PEX")
	)
	(via
		(at 388.814818 -247.137174)
		(size 0.508)
		(drill 0.254)
		(layers "F.Cu" "B.Cu")
		(net "P1V8_PEX")
	)
	(via
		(at 25.414732 -248.323354)
		(size 0.508)
		(drill 0.254)
		(layers "F.Cu" "B.Cu")
		(net "P1V8_PEX")
	)
	(via
		(at 184.319418 -185.968894)
		(size 0.508)
		(drill 0.254)
		(layers "F.Cu" "B.Cu")
		(net "P1V8_PEX")
	)
	(via
		(at 185.725054 -289.724846)
		(size 0.4064)
		(drill 0.2032)
		(layers "F.Cu" "B.Cu")
		(net "P1V8_PEX")
	)
	(via
		(at 188.574934 -284.024832)
		(size 0.4064)
		(drill 0.2032)
		(layers "F.Cu" "B.Cu")
		(net "P1V8_PEX")
	)
	(via
		(at 420.774876 -284.024832)
		(size 0.4064)
		(drill 0.2032)
		(layers "F.Cu" "B.Cu")
		(net "P1V8_PEX")
	)
	(via
		(at 213.697566 -235.356908)
		(size 0.508)
		(drill 0.254)
		(layers "F.Cu" "B.Cu")
		(net "P1V8_PEX")
	)
	(via
		(at 258.209796 -222.132398)
		(size 0.508)
		(drill 0.254)
		(layers "F.Cu" "B.Cu")
		(net "P1V8_PEX")
	)
	(via
		(at 366.522 -215.011)
		(size 0.508)
		(drill 0.254)
		(layers "F.Cu" "B.Cu")
		(net "P1V8_PEX")
	)
	(via
		(at 185.725054 -301.124874)
		(size 0.4064)
		(drill 0.2032)
		(layers "F.Cu" "B.Cu")
		(net "P1V8_PEX")
	)
	(via
		(at 149.410674 -203.58608)
		(size 0.508)
		(drill 0.254)
		(layers "F.Cu" "B.Cu")
		(net "P1V8_PEX")
	)
	(via
		(at 161.025078 -296.37482)
		(size 0.4064)
		(drill 0.2032)
		(layers "F.Cu" "B.Cu")
		(net "P1V8_PEX")
	)
	(via
		(at 92.997782 -297.374818)
		(size 0.508)
		(drill 0.254)
		(layers "F.Cu" "B.Cu")
		(net "P1V8_PEX")
	)
	(via
		(at 162.924998 -301.124874)
		(size 0.4064)
		(drill 0.2032)
		(layers "F.Cu" "B.Cu")
		(net "P1V8_PEX")
	)
	(segment
		(start 202.814936 -248.930414)
		(end 202.814936 -245.411244)
		(width 0.3556)
		(layer "B.Cu")
		(net "P1V8_PEX")
	)
	(segment
		(start 374.985026 -247.441974)
		(end 375.031 -247.396)
		(width 0.3556)
		(layer "B.Cu")
		(net "P1V8_PEX")
	)
	(segment
		(start 69.416676 -302.074834)
		(end 69.624956 -302.074834)
		(width 0.3048)
		(layer "B.Cu")
		(net "P1V8_PEX")
	)
	(segment
		(start 289.167824 -204.125068)
		(end 286.278574 -201.235818)
		(width 0.4572)
		(layer "B.Cu")
		(net "P1V8_PEX")
	)
	(segment
		(start 144.921224 -302.951642)
		(end 144.407128 -303.465738)
		(width 0.4572)
		(layer "B.Cu")
		(net "P1V8_PEX")
	)
	(segment
		(start 185.933334 -290.674806)
		(end 185.725054 -290.674806)
		(width 0.3048)
		(layer "B.Cu")
		(net "P1V8_PEX")
	)
	(segment
		(start 200.847452 -296.514774)
		(end 200.123298 -297.238928)
		(width 0.4572)
		(layer "B.Cu")
		(net "P1V8_PEX")
	)
	(segment
		(start 203.893928 -296.514774)
		(end 200.847452 -296.514774)
		(width 0.4572)
		(layer "B.Cu")
		(net "P1V8_PEX")
	)
	(segment
		(start 375.293382 -299.526706)
		(end 375.293382 -284.620462)
		(width 0.4572)
		(layer "B.Cu")
		(net "P1V8_PEX")
	)
	(segment
		(start 202.814936 -245.411244)
		(end 203.217018 -245.009162)
		(width 0.3556)
		(layer "B.Cu")
		(net "P1V8_PEX")
	)
	(segment
		(start 69.833236 -289.724846)
		(end 69.624956 -289.724846)
		(width 0.3048)
		(layer "B.Cu")
		(net "P1V8_PEX")
	)
	(segment
		(start 320.591434 -297.559222)
		(end 325.01332 -297.559222)
		(width 0.4572)
		(layer "B.Cu")
		(net "P1V8_PEX")
	)
	(segment
		(start 377.215908 -301.891954)
		(end 377.215908 -300.345348)
		(width 0.4572)
		(layer "B.Cu")
		(net "P1V8_PEX")
	)
	(segment
		(start 389.443976 -246.761254)
		(end 389.276082 -246.761254)
		(width 0.4572)
		(layer "B.Cu")
		(net "P1V8_PEX")
	)
	(segment
		(start 278.821642 -301.0408)
		(end 278.940768 -301.0408)
		(width 0.3048)
		(layer "B.Cu")
		(net "P1V8_PEX")
	)
	(segment
		(start 199.427592 -260.489192)
		(end 199.049386 -260.110986)
		(width 0.4572)
		(layer "B.Cu")
		(net "P1V8_PEX")
	)
	(segment
		(start 377.725178 -224.692718)
		(end 377.280678 -224.248218)
		(width 0.4572)
		(layer "B.Cu")
		(net "P1V8_PEX")
	)
	(segment
		(start 339.09 -174.117)
		(end 338.523072 -174.683928)
		(width 0.4572)
		(layer "B.Cu")
		(net "P1V8_PEX")
	)
	(segment
		(start 177.823876 -193.794634)
		(end 178.483514 -193.794634)
		(width 0.4572)
		(layer "B.Cu")
		(net "P1V8_PEX")
	)
	(segment
		(start 286.278574 -201.235818)
		(end 286.278574 -195.676012)
		(width 0.4572)
		(layer "B.Cu")
		(net "P1V8_PEX")
	)
	(segment
		(start 143.415258 -300.029626)
		(end 144.314926 -300.029626)
		(width 0.4572)
		(layer "B.Cu")
		(net "P1V8_PEX")
	)
	(segment
		(start 362.204 -182.118)
		(end 361.661202 -182.118)
		(width 0.4572)
		(layer "B.Cu")
		(net "P1V8_PEX")
	)
	(segment
		(start 177.823876 -192.270634)
		(end 178.483514 -192.270634)
		(width 0.4572)
		(layer "B.Cu")
		(net "P1V8_PEX")
	)
	(segment
		(start 200.265792 -260.489192)
		(end 199.427592 -260.489192)
		(width 0.4572)
		(layer "B.Cu")
		(net "P1V8_PEX")
	)
	(segment
		(start 388.900162 -247.137174)
		(end 388.814818 -247.137174)
		(width 0.4572)
		(layer "B.Cu")
		(net "P1V8_PEX")
	)
	(segment
		(start 248.229882 -229.323646)
		(end 248.816368 -229.323646)
		(width 0.4572)
		(layer "B.Cu")
		(net "P1V8_PEX")
	)
	(segment
		(start 94.615254 -292.25113)
		(end 93.839792 -293.026592)
		(width 0.4572)
		(layer "B.Cu")
		(net "P1V8_PEX")
	)
	(segment
		(start 301.616618 -301.124874)
		(end 301.824898 -301.124874)
		(width 0.3048)
		(layer "B.Cu")
		(net "P1V8_PEX")
	)
	(segment
		(start 376.60707 -302.500792)
		(end 377.215908 -301.891954)
		(width 0.4572)
		(layer "B.Cu")
		(net "P1V8_PEX")
	)
	(segment
		(start 360.503724 -176.0093)
		(end 341.103712 -176.0093)
		(width 0.4572)
		(layer "B.Cu")
		(net "P1V8_PEX")
	)
	(segment
		(start 317.338202 -297.95851)
		(end 317.484252 -297.95851)
		(width 0.4572)
		(layer "B.Cu")
		(net "P1V8_PEX")
	)
	(segment
		(start 210.691476 -246.286528)
		(end 211.082636 -246.286528)
		(width 0.4572)
		(layer "B.Cu")
		(net "P1V8_PEX")
	)
	(segment
		(start 278.816562 -290.466526)
		(end 279.024842 -290.674806)
		(width 0.3048)
		(layer "B.Cu")
		(net "P1V8_PEX")
	)
	(segment
		(start 372.759224 -226.135946)
		(end 374.063006 -226.135946)
		(width 0.4572)
		(layer "B.Cu")
		(net "P1V8_PEX")
	)
	(segment
		(start 209.212942 -259.711698)
		(end 208.196942 -259.711698)
		(width 0.4572)
		(layer "B.Cu")
		(net "P1V8_PEX")
	)
	(segment
		(start 377.280678 -224.248218)
		(end 377.280678 -223.826832)
		(width 0.4572)
		(layer "B.Cu")
		(net "P1V8_PEX")
	)
	(segment
		(start 417.716716 -302.074834)
		(end 417.924996 -302.074834)
		(width 0.3048)
		(layer "B.Cu")
		(net "P1V8_PEX")
	)
	(segment
		(start 338.05495 -182.043324)
		(end 338.05495 -185.01995)
		(width 0.4572)
		(layer "B.Cu")
		(net "P1V8_PEX")
	)
	(segment
		(start 291.06114 -203.363068)
		(end 291.06114 -204.125068)
		(width 0.4572)
		(layer "B.Cu")
		(net "P1V8_PEX")
	)
	(segment
		(start 129.93624 -215.09482)
		(end 129.982214 -215.048846)
		(width 0.3556)
		(layer "B.Cu")
		(net "P1V8_PEX")
	)
	(segment
		(start 375.408698 -243.589302)
		(end 375.778014 -243.589302)
		(width 0.3556)
		(layer "B.Cu")
		(net "P1V8_PEX")
	)
	(segment
		(start 94.615254 -285.41853)
		(end 94.615254 -292.25113)
		(width 0.4572)
		(layer "B.Cu")
		(net "P1V8_PEX")
	)
	(segment
		(start 384.00482 -246.507)
		(end 383.794 -246.507)
		(width 0.4572)
		(layer "B.Cu")
		(net "P1V8_PEX")
	)
	(segment
		(start 375.061988 -243.936012)
		(end 375.408698 -243.589302)
		(width 0.3556)
		(layer "B.Cu")
		(net "P1V8_PEX")
	)
	(segment
		(start 130.729228 -211.98586)
		(end 130.729228 -211.242148)
		(width 0.4572)
		(layer "B.Cu")
		(net "P1V8_PEX")
	)
	(segment
		(start 302.033178 -290.674806)
		(end 301.824898 -290.674806)
		(width 0.3048)
		(layer "B.Cu")
		(net "P1V8_PEX")
	)
	(segment
		(start 433.297076 -296.806112)
		(end 432.6636 -297.439588)
		(width 0.4572)
		(layer "B.Cu")
		(net "P1V8_PEX")
	)
	(segment
		(start 339.211412 -174.117)
		(end 339.09 -174.117)
		(width 0.4572)
		(layer "B.Cu")
		(net "P1V8_PEX")
	)
	(segment
		(start 144.314926 -300.029626)
		(end 144.921224 -300.635924)
		(width 0.4572)
		(layer "B.Cu")
		(net "P1V8_PEX")
	)
	(segment
		(start 207.180942 -259.711698)
		(end 206.164942 -259.711698)
		(width 0.4572)
		(layer "B.Cu")
		(net "P1V8_PEX")
	)
	(segment
		(start 92.997782 -297.137836)
		(end 92.997782 -297.374818)
		(width 0.4572)
		(layer "B.Cu")
		(net "P1V8_PEX")
	)
	(segment
		(start 375.788682 -300.022006)
		(end 375.293382 -299.526706)
		(width 0.4572)
		(layer "B.Cu")
		(net "P1V8_PEX")
	)
	(segment
		(start 302.033178 -288.774886)
		(end 301.824898 -288.774886)
		(width 0.3048)
		(layer "B.Cu")
		(net "P1V8_PEX")
	)
	(segment
		(start 140.559282 -226.135946)
		(end 141.863064 -226.135946)
		(width 0.4572)
		(layer "B.Cu")
		(net "P1V8_PEX")
	)
	(segment
		(start 162.876992 -301.076868)
		(end 162.924998 -301.124874)
		(width 0.3048)
		(layer "B.Cu")
		(net "P1V8_PEX")
	)
	(segment
		(start 258.255516 -226.12477)
		(end 257.531108 -226.12477)
		(width 0.4572)
		(layer "B.Cu")
		(net "P1V8_PEX")
	)
	(segment
		(start 138.956034 -214.159846)
		(end 138.745214 -214.159846)
		(width 0.4572)
		(layer "B.Cu")
		(net "P1V8_PEX")
	)
	(segment
		(start 185.516774 -301.124874)
		(end 185.725054 -301.124874)
		(width 0.3048)
		(layer "B.Cu")
		(net "P1V8_PEX")
	)
	(segment
		(start 377.280678 -223.826832)
		(end 377.186952 -223.733106)
		(width 0.4572)
		(layer "B.Cu")
		(net "P1V8_PEX")
	)
	(segment
		(start 209.09788 -297.374818)
		(end 208.701894 -297.770804)
		(width 0.4572)
		(layer "B.Cu")
		(net "P1V8_PEX")
	)
	(segment
		(start 130.729228 -211.242148)
		(end 130.359912 -211.242148)
		(width 0.3556)
		(layer "B.Cu")
		(net "P1V8_PEX")
	)
	(segment
		(start 278.816562 -290.215066)
		(end 278.816562 -290.466526)
		(width 0.3048)
		(layer "B.Cu")
		(net "P1V8_PEX")
	)
	(segment
		(start 325.01332 -297.559222)
		(end 325.197724 -297.374818)
		(width 0.4572)
		(layer "B.Cu")
		(net "P1V8_PEX")
	)
	(segment
		(start 204.132942 -259.711698)
		(end 204.132942 -260.46176)
		(width 0.4572)
		(layer "B.Cu")
		(net "P1V8_PEX")
	)
	(segment
		(start 147.276058 -225.552)
		(end 147.061428 -225.76663)
		(width 0.4572)
		(layer "B.Cu")
		(net "P1V8_PEX")
	)
	(segment
		(start 200.123298 -297.238928)
		(end 200.123298 -298.323)
		(width 0.4572)
		(layer "B.Cu")
		(net "P1V8_PEX")
	)
	(segment
		(start 46.6217 -301.0408)
		(end 46.740826 -301.0408)
		(width 0.3048)
		(layer "B.Cu")
		(net "P1V8_PEX")
	)
	(segment
		(start 302.033178 -289.724846)
		(end 301.824898 -289.724846)
		(width 0.3048)
		(layer "B.Cu")
		(net "P1V8_PEX")
	)
	(segment
		(start 374.063006 -226.135946)
		(end 374.251982 -226.324922)
		(width 0.4572)
		(layer "B.Cu")
		(net "P1V8_PEX")
	)
	(segment
		(start 211.435442 -245.933722)
		(end 211.435442 -245.025926)
		(width 0.4572)
		(layer "B.Cu")
		(net "P1V8_PEX")
	)
	(segment
		(start 142.780766 -284.061154)
		(end 143.104362 -284.38475)
		(width 0.4572)
		(layer "B.Cu")
		(net "P1V8_PEX")
	)
	(segment
		(start 185.933334 -288.774886)
		(end 185.725054 -288.774886)
		(width 0.3048)
		(layer "B.Cu")
		(net "P1V8_PEX")
	)
	(segment
		(start 377.215908 -300.345348)
		(end 376.892566 -300.022006)
		(width 0.4572)
		(layer "B.Cu")
		(net "P1V8_PEX")
	)
	(segment
		(start 69.416676 -303.024794)
		(end 69.624956 -303.024794)
		(width 0.3048)
		(layer "B.Cu")
		(net "P1V8_PEX")
	)
	(segment
		(start 418.133276 -290.674806)
		(end 417.924996 -290.674806)
		(width 0.3048)
		(layer "B.Cu")
		(net "P1V8_PEX")
	)
	(segment
		(start 143.104362 -284.38475)
		(end 143.104362 -299.71873)
		(width 0.4572)
		(layer "B.Cu")
		(net "P1V8_PEX")
	)
	(segment
		(start 247.499632 -228.981)
		(end 247.887236 -228.981)
		(width 0.4572)
		(layer "B.Cu")
		(net "P1V8_PEX")
	)
	(segment
		(start 141.863064 -226.135946)
		(end 142.05204 -226.324922)
		(width 0.4572)
		(layer "B.Cu")
		(net "P1V8_PEX")
	)
	(segment
		(start 258.266692 -226.135946)
		(end 258.255516 -226.12477)
		(width 0.4572)
		(layer "B.Cu")
		(net "P1V8_PEX")
	)
	(segment
		(start 338.05495 -185.01995)
		(end 339.09 -186.055)
		(width 0.4572)
		(layer "B.Cu")
		(net "P1V8_PEX")
	)
	(segment
		(start 177.82032 -196.890386)
		(end 178.479958 -196.890386)
		(width 0.4572)
		(layer "B.Cu")
		(net "P1V8_PEX")
	)
	(segment
		(start 262.908542 -225.76663)
		(end 262.304276 -225.76663)
		(width 0.4572)
		(layer "B.Cu")
		(net "P1V8_PEX")
	)
	(segment
		(start 363.49305 -228.981)
		(end 364.67923 -228.981)
		(width 0.4572)
		(layer "B.Cu")
		(net "P1V8_PEX")
	)
	(segment
		(start 143.822674 -214.559134)
		(end 144.52346 -214.559134)
		(width 0.4572)
		(layer "B.Cu")
		(net "P1V8_PEX")
	)
	(segment
		(start 15.230348 -228.981)
		(end 16.416528 -228.981)
		(width 0.4572)
		(layer "B.Cu")
		(net "P1V8_PEX")
	)
	(segment
		(start 319.949068 -296.916856)
		(end 320.591434 -297.559222)
		(width 0.4572)
		(layer "B.Cu")
		(net "P1V8_PEX")
	)
	(segment
		(start 30.141672 -225.76663)
		(end 30.998668 -225.76663)
		(width 0.4572)
		(layer "B.Cu")
		(net "P1V8_PEX")
	)
	(segment
		(start 199.049386 -260.110986)
		(end 199.049386 -259.711698)
		(width 0.4572)
		(layer "B.Cu")
		(net "P1V8_PEX")
	)
	(segment
		(start 361.149392 -176.654968)
		(end 360.503724 -176.0093)
		(width 0.4572)
		(layer "B.Cu")
		(net "P1V8_PEX")
	)
	(segment
		(start 376.892566 -300.022006)
		(end 375.788682 -300.022006)
		(width 0.4572)
		(layer "B.Cu")
		(net "P1V8_PEX")
	)
	(segment
		(start 69.416676 -301.124874)
		(end 69.624956 -301.124874)
		(width 0.3048)
		(layer "B.Cu")
		(net "P1V8_PEX")
	)
	(segment
		(start 376.60707 -304.800254)
		(end 376.60707 -302.500792)
		(width 0.4572)
		(layer "B.Cu")
		(net "P1V8_PEX")
	)
	(segment
		(start 139.36091 -214.564722)
		(end 138.956034 -214.159846)
		(width 0.4572)
		(layer "B.Cu")
		(net "P1V8_PEX")
	)
	(segment
		(start 338.523072 -174.683928)
		(end 338.523072 -181.575202)
		(width 0.4572)
		(layer "B.Cu")
		(net "P1V8_PEX")
	)
	(segment
		(start 211.244942 -259.711698)
		(end 210.228942 -259.711698)
		(width 0.4572)
		(layer "B.Cu")
		(net "P1V8_PEX")
	)
	(segment
		(start 361.661202 -182.118)
		(end 361.149392 -181.60619)
		(width 0.4572)
		(layer "B.Cu")
		(net "P1V8_PEX")
	)
	(segment
		(start 301.616618 -303.024794)
		(end 301.824898 -303.024794)
		(width 0.3048)
		(layer "B.Cu")
		(net "P1V8_PEX")
	)
	(segment
		(start 317.484252 -297.95851)
		(end 318.525906 -296.916856)
		(width 0.4572)
		(layer "B.Cu")
		(net "P1V8_PEX")
	)
	(segment
		(start 131.293108 -228.981)
		(end 132.479288 -228.981)
		(width 0.4572)
		(layer "B.Cu")
		(net "P1V8_PEX")
	)
	(segment
		(start 209.338672 -241.182652)
		(end 208.834482 -241.182652)
		(width 0.3556)
		(layer "B.Cu")
		(net "P1V8_PEX")
	)
	(segment
		(start 141.349222 -284.061154)
		(end 142.780766 -284.061154)
		(width 0.4572)
		(layer "B.Cu")
		(net "P1V8_PEX")
	)
	(segment
		(start 436.85841 -297.73499)
		(end 435.929532 -296.806112)
		(width 0.4572)
		(layer "B.Cu")
		(net "P1V8_PEX")
	)
	(segment
		(start 374.811036 -284.138116)
		(end 373.728996 -284.138116)
		(width 0.4572)
		(layer "B.Cu")
		(net "P1V8_PEX")
	)
	(segment
		(start 384.409696 -246.911876)
		(end 384.00482 -246.507)
		(width 0.4572)
		(layer "B.Cu")
		(net "P1V8_PEX")
	)
	(segment
		(start 376.852942 -224.067116)
		(end 376.571764 -224.067116)
		(width 0.4572)
		(layer "B.Cu")
		(net "P1V8_PEX")
	)
	(segment
		(start 208.834482 -241.182652)
		(end 205.89367 -244.123464)
		(width 0.3556)
		(layer "B.Cu")
		(net "P1V8_PEX")
	)
	(segment
		(start 301.616618 -302.074834)
		(end 301.824898 -302.074834)
		(width 0.3048)
		(layer "B.Cu")
		(net "P1V8_PEX")
	)
	(segment
		(start 417.716716 -303.024794)
		(end 417.924996 -303.024794)
		(width 0.3048)
		(layer "B.Cu")
		(net "P1V8_PEX")
	)
	(segment
		(start 93.839792 -293.026592)
		(end 93.839792 -296.295826)
		(width 0.4572)
		(layer "B.Cu")
		(net "P1V8_PEX")
	)
	(segment
		(start 30.998668 -225.76663)
		(end 31.213298 -225.552)
		(width 0.4572)
		(layer "B.Cu")
		(net "P1V8_PEX")
	)
	(segment
		(start 206.164942 -259.711698)
		(end 205.148942 -259.711698)
		(width 0.4572)
		(layer "B.Cu")
		(net "P1V8_PEX")
	)
	(segment
		(start 418.133276 -289.724846)
		(end 417.924996 -289.724846)
		(width 0.3048)
		(layer "B.Cu")
		(net "P1V8_PEX")
	)
	(segment
		(start 144.407128 -303.465738)
		(end 144.407128 -304.800254)
		(width 0.4572)
		(layer "B.Cu")
		(net "P1V8_PEX")
	)
	(segment
		(start 395.040866 -301.0408)
		(end 395.12494 -301.124874)
		(width 0.3048)
		(layer "B.Cu")
		(net "P1V8_PEX")
	)
	(segment
		(start 263.578086 -225.097086)
		(end 262.908542 -225.76663)
		(width 0.4572)
		(layer "B.Cu")
		(net "P1V8_PEX")
	)
	(segment
		(start 46.740826 -301.0408)
		(end 46.8249 -301.124874)
		(width 0.3048)
		(layer "B.Cu")
		(net "P1V8_PEX")
	)
	(segment
		(start 375.778014 -243.589302)
		(end 375.778014 -244.333014)
		(width 0.4572)
		(layer "B.Cu")
		(net "P1V8_PEX")
	)
	(segment
		(start 375.293382 -284.620462)
		(end 374.811036 -284.138116)
		(width 0.4572)
		(layer "B.Cu")
		(net "P1V8_PEX")
	)
	(segment
		(start 417.716716 -301.124874)
		(end 417.924996 -301.124874)
		(width 0.3048)
		(layer "B.Cu")
		(net "P1V8_PEX")
	)
	(segment
		(start 200.4187 -260.6421)
		(end 200.265792 -260.489192)
		(width 0.4572)
		(layer "B.Cu")
		(net "P1V8_PEX")
	)
	(segment
		(start 24.496522 -226.135946)
		(end 25.800304 -226.135946)
		(width 0.4572)
		(layer "B.Cu")
		(net "P1V8_PEX")
	)
	(segment
		(start 128.986534 -215.09482)
		(end 129.93624 -215.09482)
		(width 0.3556)
		(layer "B.Cu")
		(net "P1V8_PEX")
	)
	(segment
		(start 297.103038 -201.76109)
		(end 297.103038 -201.15149)
		(width 0.4572)
		(layer "B.Cu")
		(net "P1V8_PEX")
	)
	(segment
		(start 291.06114 -204.125068)
		(end 289.167824 -204.125068)
		(width 0.4572)
		(layer "B.Cu")
		(net "P1V8_PEX")
	)
	(segment
		(start 185.516774 -303.024794)
		(end 185.725054 -303.024794)
		(width 0.3048)
		(layer "B.Cu")
		(net "P1V8_PEX")
	)
	(segment
		(start 247.887236 -228.981)
		(end 248.229882 -229.323646)
		(width 0.4572)
		(layer "B.Cu")
		(net "P1V8_PEX")
	)
	(segment
		(start 144.921224 -300.635924)
		(end 144.921224 -302.951642)
		(width 0.4572)
		(layer "B.Cu")
		(net "P1V8_PEX")
	)
	(segment
		(start 318.525906 -296.916856)
		(end 319.949068 -296.916856)
		(width 0.4572)
		(layer "B.Cu")
		(net "P1V8_PEX")
	)
	(segment
		(start 435.929532 -296.806112)
		(end 433.297076 -296.806112)
		(width 0.4572)
		(layer "B.Cu")
		(net "P1V8_PEX")
	)
	(segment
		(start 149.352254 -209.962242)
		(end 149.352254 -210.724496)
		(width 0.4572)
		(layer "B.Cu")
		(net "P1V8_PEX")
	)
	(segment
		(start 210.228942 -259.711698)
		(end 209.212942 -259.711698)
		(width 0.4572)
		(layer "B.Cu")
		(net "P1V8_PEX")
	)
	(segment
		(start 205.149958 -297.770804)
		(end 203.893928 -296.514774)
		(width 0.4572)
		(layer "B.Cu")
		(net "P1V8_PEX")
	)
	(segment
		(start 69.833236 -290.674806)
		(end 69.624956 -290.674806)
		(width 0.3048)
		(layer "B.Cu")
		(net "P1V8_PEX")
	)
	(segment
		(start 361.149392 -181.60619)
		(end 361.149392 -176.654968)
		(width 0.4572)
		(layer "B.Cu")
		(net "P1V8_PEX")
	)
	(segment
		(start 205.148942 -259.711698)
		(end 204.132942 -259.711698)
		(width 0.4572)
		(layer "B.Cu")
		(net "P1V8_PEX")
	)
	(segment
		(start 377.186952 -223.733106)
		(end 376.852942 -224.067116)
		(width 0.4572)
		(layer "B.Cu")
		(net "P1V8_PEX")
	)
	(segment
		(start 204.149452 -245.009162)
		(end 203.217018 -245.009162)
		(width 0.3556)
		(layer "B.Cu")
		(net "P1V8_PEX")
	)
	(segment
		(start 389.276082 -246.761254)
		(end 388.900162 -247.137174)
		(width 0.4572)
		(layer "B.Cu")
		(net "P1V8_PEX")
	)
	(segment
		(start 130.013202 -211.588858)
		(end 129.321814 -211.588858)
		(width 0.3556)
		(layer "B.Cu")
		(net "P1V8_PEX")
	)
	(segment
		(start 143.104362 -299.71873)
		(end 143.415258 -300.029626)
		(width 0.4572)
		(layer "B.Cu")
		(net "P1V8_PEX")
	)
	(segment
		(start 185.933334 -289.724846)
		(end 185.725054 -289.724846)
		(width 0.3048)
		(layer "B.Cu")
		(net "P1V8_PEX")
	)
	(segment
		(start 278.940768 -301.0408)
		(end 279.024842 -301.124874)
		(width 0.3048)
		(layer "B.Cu")
		(net "P1V8_PEX")
	)
	(segment
		(start 291.06114 -204.125068)
		(end 291.06114 -204.887068)
		(width 0.4572)
		(layer "B.Cu")
		(net "P1V8_PEX")
	)
	(segment
		(start 338.523072 -181.575202)
		(end 338.05495 -182.043324)
		(width 0.4572)
		(layer "B.Cu")
		(net "P1V8_PEX")
	)
	(segment
		(start 185.516774 -302.074834)
		(end 185.725054 -302.074834)
		(width 0.3048)
		(layer "B.Cu")
		(net "P1V8_PEX")
	)
	(segment
		(start 286.278574 -195.676012)
		(end 286.6644 -195.290186)
		(width 0.4572)
		(layer "B.Cu")
		(net "P1V8_PEX")
	)
	(segment
		(start 374.03532 -247.441974)
		(end 374.985026 -247.441974)
		(width 0.3556)
		(layer "B.Cu")
		(net "P1V8_PEX")
	)
	(segment
		(start 440.93765 -297.73499)
		(end 436.85841 -297.73499)
		(width 0.4572)
		(layer "B.Cu")
		(net "P1V8_PEX")
	)
	(segment
		(start 295.706038 -201.25309)
		(end 295.89095 -201.068178)
		(width 0.4572)
		(layer "B.Cu")
		(net "P1V8_PEX")
	)
	(segment
		(start 147.061428 -225.76663)
		(end 146.204432 -225.76663)
		(width 0.4572)
		(layer "B.Cu")
		(net "P1V8_PEX")
	)
	(segment
		(start 146.685254 -209.962242)
		(end 146.685254 -210.583526)
		(width 0.4572)
		(layer "B.Cu")
		(net "P1V8_PEX")
	)
	(segment
		(start 374.3706 -243.936012)
		(end 375.061988 -243.936012)
		(width 0.3556)
		(layer "B.Cu")
		(net "P1V8_PEX")
	)
	(segment
		(start 69.833236 -288.774886)
		(end 69.624956 -288.774886)
		(width 0.3048)
		(layer "B.Cu")
		(net "P1V8_PEX")
	)
	(segment
		(start 295.706038 -201.76109)
		(end 295.706038 -201.25309)
		(width 0.4572)
		(layer "B.Cu")
		(net "P1V8_PEX")
	)
	(segment
		(start 177.82032 -198.287386)
		(end 178.479958 -198.287386)
		(width 0.4572)
		(layer "B.Cu")
		(net "P1V8_PEX")
	)
	(segment
		(start 208.701894 -297.770804)
		(end 205.149958 -297.770804)
		(width 0.4572)
		(layer "B.Cu")
		(net "P1V8_PEX")
	)
	(segment
		(start 432.6636 -297.439588)
		(end 432.6636 -298.2976)
		(width 0.4572)
		(layer "B.Cu")
		(net "P1V8_PEX")
	)
	(segment
		(start 25.800304 -226.135946)
		(end 25.98928 -226.324922)
		(width 0.4572)
		(layer "B.Cu")
		(net "P1V8_PEX")
	)
	(segment
		(start 208.196942 -259.711698)
		(end 207.180942 -259.711698)
		(width 0.4572)
		(layer "B.Cu")
		(net "P1V8_PEX")
	)
	(segment
		(start 341.103712 -176.0093)
		(end 339.211412 -174.117)
		(width 0.4572)
		(layer "B.Cu")
		(net "P1V8_PEX")
	)
	(segment
		(start 162.7124 -301.076868)
		(end 162.876992 -301.076868)
		(width 0.3048)
		(layer "B.Cu")
		(net "P1V8_PEX")
	)
	(segment
		(start 211.082636 -246.286528)
		(end 211.435442 -245.933722)
		(width 0.4572)
		(layer "B.Cu")
		(net "P1V8_PEX")
	)
	(segment
		(start 202.090274 -259.711698)
		(end 202.090274 -260.46176)
		(width 0.4572)
		(layer "B.Cu")
		(net "P1V8_PEX")
	)
	(segment
		(start 377.186952 -221.066106)
		(end 376.526298 -221.72676)
		(width 0.4572)
		(layer "B.Cu")
		(net "P1V8_PEX")
	)
	(segment
		(start 93.839792 -296.295826)
		(end 92.997782 -297.137836)
		(width 0.4572)
		(layer "B.Cu")
		(net "P1V8_PEX")
	)
	(segment
		(start 394.92174 -301.0408)
		(end 395.040866 -301.0408)
		(width 0.3048)
		(layer "B.Cu")
		(net "P1V8_PEX")
	)
	(segment
		(start 130.359912 -211.242148)
		(end 130.013202 -211.588858)
		(width 0.3556)
		(layer "B.Cu")
		(net "P1V8_PEX")
	)
	(segment
		(start 205.89367 -244.123464)
		(end 205.03515 -244.123464)
		(width 0.3556)
		(layer "B.Cu")
		(net "P1V8_PEX")
	)
	(segment
		(start 418.133276 -288.774886)
		(end 417.924996 -288.774886)
		(width 0.3048)
		(layer "B.Cu")
		(net "P1V8_PEX")
	)
	(segment
		(start 441.297822 -297.374818)
		(end 440.93765 -297.73499)
		(width 0.4572)
		(layer "B.Cu")
		(net "P1V8_PEX")
	)
	(segment
		(start 205.03515 -244.123464)
		(end 204.149452 -245.009162)
		(width 0.3556)
		(layer "B.Cu")
		(net "P1V8_PEX")
	)
	(segment
		(start 20.932394 -295.568878)
		(end 20.932394 -280.059638)
		(width 0.4572)
		(layer "In5.Cu")
		(net "P1V8_PEX")
	)
	(segment
		(start 328.608182 -244.806978)
		(end 328.608182 -243.731542)
		(width 0.508)
		(layer "In5.Cu")
		(net "P1V8_PEX")
	)
	(segment
		(start 328.608182 -243.731542)
		(end 328.265536 -243.388896)
		(width 0.508)
		(layer "In5.Cu")
		(net "P1V8_PEX")
	)
	(segment
		(start 18.03908 -310.978042)
		(end 18.03908 -309.188866)
		(width 0.4572)
		(layer "In5.Cu")
		(net "P1V8_PEX")
	)
	(segment
		(start 339.09 -170.267884)
		(end 339.09 -162.814)
		(width 0.4572)
		(layer "In5.Cu")
		(net "P1V8_PEX")
	)
	(segment
		(start 209.338672 -241.578892)
		(end 209.338672 -241.182652)
		(width 0.4572)
		(layer "In5.Cu")
		(net "P1V8_PEX")
	)
	(segment
		(start 338.357464 -171.00042)
		(end 339.09 -170.267884)
		(width 0.4572)
		(layer "In5.Cu")
		(net "P1V8_PEX")
	)
	(segment
		(start 338.829396 -262.504682)
		(end 329.629008 -253.304294)
		(width 0.508)
		(layer "In5.Cu")
		(net "P1V8_PEX")
	)
	(segment
		(start 24.632666 -302.59528)
		(end 24.632666 -299.26915)
		(width 0.4572)
		(layer "In5.Cu")
		(net "P1V8_PEX")
	)
	(segment
		(start 339.09 -153.279602)
		(end 339.09 -151.003)
		(width 0.4572)
		(layer "In5.Cu")
		(net "P1V8_PEX")
	)
	(segment
		(start 337.891882 -161.615882)
		(end 337.891882 -154.47772)
		(width 0.4572)
		(layer "In5.Cu")
		(net "P1V8_PEX")
	)
	(segment
		(start 337.891882 -154.47772)
		(end 339.09 -153.279602)
		(width 0.4572)
		(layer "In5.Cu")
		(net "P1V8_PEX")
	)
	(segment
		(start 328.265536 -245.149624)
		(end 328.608182 -244.806978)
		(width 0.508)
		(layer "In5.Cu")
		(net "P1V8_PEX")
	)
	(segment
		(start 339.09 -162.814)
		(end 337.891882 -161.615882)
		(width 0.4572)
		(layer "In5.Cu")
		(net "P1V8_PEX")
	)
	(segment
		(start 329.93965 -235.1405)
		(end 328.69505 -233.8959)
		(width 0.508)
		(layer "In5.Cu")
		(net "P1V8_PEX")
	)
	(segment
		(start 328.69505 -233.8959)
		(end 328.69505 -232.918)
		(width 0.508)
		(layer "In5.Cu")
		(net "P1V8_PEX")
	)
	(segment
		(start 20.932394 -280.059638)
		(end 22.54885 -278.443182)
		(width 0.4572)
		(layer "In5.Cu")
		(net "P1V8_PEX")
	)
	(segment
		(start 328.265536 -246.238268)
		(end 328.265536 -245.149624)
		(width 0.508)
		(layer "In5.Cu")
		(net "P1V8_PEX")
	)
	(segment
		(start 18.03908 -309.188866)
		(end 24.632666 -302.59528)
		(width 0.4572)
		(layer "In5.Cu")
		(net "P1V8_PEX")
	)
	(segment
		(start 22.54885 -278.443182)
		(end 26.101294 -278.443182)
		(width 0.4572)
		(layer "In5.Cu")
		(net "P1V8_PEX")
	)
	(segment
		(start 329.93965 -236.578902)
		(end 329.93965 -235.1405)
		(width 0.508)
		(layer "In5.Cu")
		(net "P1V8_PEX")
	)
	(segment
		(start 211.36356 -244.954044)
		(end 211.36356 -243.60378)
		(width 0.4572)
		(layer "In5.Cu")
		(net "P1V8_PEX")
	)
	(segment
		(start 328.265536 -238.253016)
		(end 329.93965 -236.578902)
		(width 0.508)
		(layer "In5.Cu")
		(net "P1V8_PEX")
	)
	(segment
		(start 329.629008 -247.60174)
		(end 328.265536 -246.238268)
		(width 0.508)
		(layer "In5.Cu")
		(net "P1V8_PEX")
	)
	(segment
		(start 211.435442 -245.025926)
		(end 211.36356 -244.954044)
		(width 0.4572)
		(layer "In5.Cu")
		(net "P1V8_PEX")
	)
	(segment
		(start 338.357464 -173.384464)
		(end 338.357464 -171.00042)
		(width 0.4572)
		(layer "In5.Cu")
		(net "P1V8_PEX")
	)
	(segment
		(start 24.632666 -299.26915)
		(end 20.932394 -295.568878)
		(width 0.4572)
		(layer "In5.Cu")
		(net "P1V8_PEX")
	)
	(segment
		(start 211.36356 -243.60378)
		(end 209.338672 -241.578892)
		(width 0.4572)
		(layer "In5.Cu")
		(net "P1V8_PEX")
	)
	(segment
		(start 339.09 -174.117)
		(end 338.357464 -173.384464)
		(width 0.4572)
		(layer "In5.Cu")
		(net "P1V8_PEX")
	)
	(segment
		(start 328.265536 -243.388896)
		(end 328.265536 -238.253016)
		(width 0.508)
		(layer "In5.Cu")
		(net "P1V8_PEX")
	)
	(segment
		(start 329.629008 -253.304294)
		(end 329.629008 -247.60174)
		(width 0.508)
		(layer "In5.Cu")
		(net "P1V8_PEX")
	)
	(segment
		(start 362.204 -189.30874)
		(end 362.204 -182.118)
		(width 0.4572)
		(layer "In7.Cu")
		(net "P1V8_PEX")
	)
	(segment
		(start 360.712258 -191.802258)
		(end 360.712258 -190.800482)
		(width 0.4572)
		(layer "In7.Cu")
		(net "P1V8_PEX")
	)
	(segment
		(start 360.712258 -190.800482)
		(end 362.204 -189.30874)
		(width 0.4572)
		(layer "In7.Cu")
		(net "P1V8_PEX")
	)
	(segment
		(start 362.204 -193.294)
		(end 360.712258 -191.802258)
		(width 0.4572)
		(layer "In7.Cu")
		(net "P1V8_PEX")
	)
	(segment
		(start 93.975682 -307.084222)
		(end 95.024956 -306.034948)
		(width 0.4572)
		(layer "In11.Cu")
		(net "P1V8_PEX")
	)
	(segment
		(start 93.096334 -307.084222)
		(end 93.975682 -307.084222)
		(width 0.4572)
		(layer "In11.Cu")
		(net "P1V8_PEX")
	)
	(segment
		(start 95.024956 -306.034948)
		(end 95.024956 -298.201334)
		(width 0.4572)
		(layer "In11.Cu")
		(net "P1V8_PEX")
	)
	(segment
		(start 88.72855 -298.85386)
		(end 87.666576 -298.85386)
		(width 0.4572)
		(layer "In11.Cu")
		(net "P1V8_PEX")
	)
	(segment
		(start 85.277198 -299.4025)
		(end 84.197698 -298.323)
		(width 0.4572)
		(layer "In11.Cu")
		(net "P1V8_PEX")
	)
	(segment
		(start 94.19844 -297.374818)
		(end 92.997782 -297.374818)
		(width 0.4572)
		(layer "In11.Cu")
		(net "P1V8_PEX")
	)
	(segment
		(start 87.117936 -299.4025)
		(end 85.277198 -299.4025)
		(width 0.4572)
		(layer "In11.Cu")
		(net "P1V8_PEX")
	)
	(segment
		(start 87.666576 -298.85386)
		(end 87.117936 -299.4025)
		(width 0.4572)
		(layer "In11.Cu")
		(net "P1V8_PEX")
	)
	(segment
		(start 95.024956 -298.201334)
		(end 94.19844 -297.374818)
		(width 0.4572)
		(layer "In11.Cu")
		(net "P1V8_PEX")
	)
	(segment
		(start 91.51112 -297.374818)
		(end 92.997782 -297.374818)
		(width 0.4572)
		(layer "In11.Cu")
		(net "P1V8_PEX")
	)
	(segment
		(start 84.197698 -298.323)
		(end 84.0232 -298.323)
		(width 0.4572)
		(layer "In11.Cu")
		(net "P1V8_PEX")
	)
	(segment
		(start 90.692478 -299.603668)
		(end 90.692478 -298.19346)
		(width 0.4572)
		(layer "In11.Cu")
		(net "P1V8_PEX")
	)
	(segment
		(start 90.692478 -298.19346)
		(end 91.51112 -297.374818)
		(width 0.4572)
		(layer "In11.Cu")
		(net "P1V8_PEX")
	)
	(segment
		(start 90.692478 -299.603668)
		(end 89.478358 -299.603668)
		(width 0.4572)
		(layer "In11.Cu")
		(net "P1V8_PEX")
	)
	(segment
		(start 89.478358 -299.603668)
		(end 88.72855 -298.85386)
		(width 0.4572)
		(layer "In11.Cu")
		(net "P1V8_PEX")
	)
	(segment
		(start 261.568438 -280.279094)
		(end 261.568438 -310.113934)
		(width 0.4572)
		(layer "In13.Cu")
		(net "P1V8_PEX")
	)
	(segment
		(start 262.763 -279.084532)
		(end 261.568438 -280.279094)
		(width 0.4572)
		(layer "In13.Cu")
		(net "P1V8_PEX")
	)
	(segment
		(start 23.9776 -256.831338)
		(end 23.9776 -258.952238)
		(width 0.4572)
		(layer "In13.Cu")
		(net "P1V8_PEX")
	)
	(segment
		(start 24.685244 -260.808724)
		(end 22.9743 -262.519668)
		(width 0.4572)
		(layer "In13.Cu")
		(net "P1V8_PEX")
	)
	(segment
		(start 23.9776 -258.952238)
		(end 24.685244 -259.659882)
		(width 0.4572)
		(layer "In13.Cu")
		(net "P1V8_PEX")
	)
	(segment
		(start 24.191976 -256.616962)
		(end 23.9776 -256.831338)
		(width 0.4572)
		(layer "In13.Cu")
		(net "P1V8_PEX")
	)
	(segment
		(start 24.685244 -259.659882)
		(end 24.685244 -260.808724)
		(width 0.4572)
		(layer "In13.Cu")
		(net "P1V8_PEX")
	)
	(segment
		(start 264.032746 -279.084532)
		(end 262.763 -279.084532)
		(width 0.4572)
		(layer "In13.Cu")
		(net "P1V8_PEX")
	)
	(segment
		(start 101.303836 -219.559886)
		(end 100.661724 -219.559886)
		(width 0.381)
		(layer "F.Cu")
		(net "P1V8_PEX_VCC")
	)
	(via
		(at 100.661724 -219.559886)
		(size 0.508)
		(drill 0.254)
		(layers "F.Cu" "B.Cu")
		(net "P1V8_PEX_VCC")
	)
	(via
		(at 107.965748 -224.531174)
		(size 0.508)
		(drill 0.254)
		(layers "F.Cu" "B.Cu")
		(net "P1V8_PEX_VCC")
	)
	(segment
		(start 104.281478 -220.213428)
		(end 101.315266 -220.213428)
		(width 0.4572)
		(layer "In5.Cu")
		(net "P1V8_PEX_VCC")
	)
	(segment
		(start 107.965748 -223.897698)
		(end 104.281478 -220.213428)
		(width 0.4572)
		(layer "In5.Cu")
		(net "P1V8_PEX_VCC")
	)
	(segment
		(start 101.315266 -220.213428)
		(end 100.661724 -219.559886)
		(width 0.4572)
		(layer "In5.Cu")
		(net "P1V8_PEX_VCC")
	)
	(segment
		(start 107.965748 -224.531174)
		(end 107.965748 -223.897698)
		(width 0.4572)
		(layer "In5.Cu")
		(net "P1V8_PEX_VCC")
	)
	(via
		(at 107.468416 -226.622102)
		(size 0.762)
		(drill 0.381)
		(layers "F.Cu" "B.Cu")
		(net "SW_P1V8_PEX_PH")
	)
	(segment
		(start 102.353364 -223.849946)
		(end 102.988364 -223.849946)
		(width 0.254)
		(layer "F.Cu")
		(net "P1V8_PEX_CS")
	)
	(segment
		(start 104.378252 -223.506792)
		(end 103.787702 -223.506792)
		(width 0.1778)
		(layer "F.Cu")
		(net "P1V8_PEX_CS")
	)
	(segment
		(start 103.787702 -223.506792)
		(end 103.444548 -223.849946)
		(width 0.1778)
		(layer "F.Cu")
		(net "P1V8_PEX_CS")
	)
	(segment
		(start 103.444548 -223.849946)
		(end 102.988364 -223.849946)
		(width 0.1778)
		(layer "F.Cu")
		(net "P1V8_PEX_CS")
	)
	(via
		(at 102.988364 -223.849946)
		(size 0.508)
		(drill 0.254)
		(layers "F.Cu" "B.Cu")
		(net "P1V8_PEX_CS")
	)
	(segment
		(start 103.375968 -220.200474)
		(end 102.734872 -219.559378)
		(width 0.13208)
		(layer "F.Cu")
		(net "PWRGD_P1V8_PEX")
	)
	(segment
		(start 102.103936 -218.57589)
		(end 102.103936 -219.559886)
		(width 0.13208)
		(layer "F.Cu")
		(net "PWRGD_P1V8_PEX")
	)
	(segment
		(start 103.375968 -220.205046)
		(end 103.375968 -220.200474)
		(width 0.13208)
		(layer "F.Cu")
		(net "PWRGD_P1V8_PEX")
	)
	(segment
		(start 104.177592 -221.00667)
		(end 103.375968 -220.205046)
		(width 0.13208)
		(layer "F.Cu")
		(net "PWRGD_P1V8_PEX")
	)
	(segment
		(start 102.103936 -219.559886)
		(end 102.104444 -219.559378)
		(width 0.13208)
		(layer "F.Cu")
		(net "PWRGD_P1V8_PEX")
	)
	(segment
		(start 104.378252 -221.00667)
		(end 104.177592 -221.00667)
		(width 0.13208)
		(layer "F.Cu")
		(net "PWRGD_P1V8_PEX")
	)
	(segment
		(start 102.104444 -219.559378)
		(end 102.734872 -219.559378)
		(width 0.13208)
		(layer "F.Cu")
		(net "PWRGD_P1V8_PEX")
	)
	(via
		(at 102.734872 -219.559378)
		(size 0.508)
		(drill 0.254)
		(layers "F.Cu" "B.Cu")
		(net "PWRGD_P1V8_PEX")
	)
	(segment
		(start 100.429568 -222.464122)
		(end 100.42906 -222.46463)
		(width 0.254)
		(layer "F.Cu")
		(net "SH_P1V8_PEX_FB")
	)
	(segment
		(start 99.712526 -222.46844)
		(end 98.965258 -222.46844)
		(width 0.254)
		(layer "F.Cu")
		(net "SH_P1V8_PEX_FB")
	)
	(segment
		(start 100.42906 -222.46463)
		(end 99.716336 -222.46463)
		(width 0.254)
		(layer "F.Cu")
		(net "SH_P1V8_PEX_FB")
	)
	(segment
		(start 99.716336 -222.46463)
		(end 99.712526 -222.46844)
		(width 0.254)
		(layer "F.Cu")
		(net "SH_P1V8_PEX_FB")
	)
	(segment
		(start 101.439726 -222.464122)
		(end 100.429568 -222.464122)
		(width 0.254)
		(layer "F.Cu")
		(net "SH_P1V8_PEX_FB")
	)
	(via
		(at 99.716336 -222.46463)
		(size 0.508)
		(drill 0.254)
		(layers "F.Cu" "B.Cu")
		(net "SH_P1V8_PEX_FB")
	)
	(segment
		(start 102.943406 -220.544644)
		(end 103.31958 -220.920818)
		(width 0.13208)
		(layer "F.Cu")
		(net "P1V8_PEX_EN")
	)
	(segment
		(start 104.378252 -221.506796)
		(end 103.905558 -221.506796)
		(width 0.13208)
		(layer "F.Cu")
		(net "P1V8_PEX_EN")
	)
	(segment
		(start 102.089204 -220.544644)
		(end 102.943406 -220.544644)
		(width 0.13208)
		(layer "F.Cu")
		(net "P1V8_PEX_EN")
	)
	(segment
		(start 103.905558 -221.506796)
		(end 103.31958 -220.920818)
		(width 0.13208)
		(layer "F.Cu")
		(net "P1V8_PEX_EN")
	)
	(via
		(at 103.31958 -220.920818)
		(size 0.508)
		(drill 0.254)
		(layers "F.Cu" "B.Cu")
		(net "P1V8_PEX_EN")
	)
	(via
		(at 103.877618 -216.999566)
		(size 0.762)
		(drill 0.381)
		(layers "F.Cu" "B.Cu")
		(net "SW_P12V_P1V8_PEX_FLT")
	)
	(segment
		(start 190.424816 -408.592274)
		(end 190.226696 -408.790394)
		(width 0.13208)
		(layer "F.Cu")
		(net "A_P12V_AUX_FP_TRIGGER")
	)
	(segment
		(start 190.226696 -408.790394)
		(end 190.226696 -409.395422)
		(width 0.13208)
		(layer "F.Cu")
		(net "A_P12V_AUX_FP_TRIGGER")
	)
	(segment
		(start 190.424816 -407.601674)
		(end 190.424816 -408.592274)
		(width 0.13208)
		(layer "F.Cu")
		(net "A_P12V_AUX_FP_TRIGGER")
	)
	(segment
		(start 189.210696 -409.395422)
		(end 190.226696 -409.395422)
		(width 0.13208)
		(layer "F.Cu")
		(net "A_P12V_AUX_FP_TRIGGER")
	)
	(via
		(at 190.424816 -408.592274)
		(size 0.508)
		(drill 0.254)
		(layers "F.Cu" "B.Cu")
		(net "A_P12V_AUX_FP_TRIGGER")
	)
	(segment
		(start 190.78956 -403.06879)
		(end 190.78956 -403.375114)
		(width 0.13208)
		(layer "F.Cu")
		(net "A_P12V_AUX_ADR_TRIGGER")
	)
	(segment
		(start 190.424816 -404.012146)
		(end 190.424816 -404.981918)
		(width 0.13208)
		(layer "F.Cu")
		(net "A_P12V_AUX_ADR_TRIGGER")
	)
	(segment
		(start 189.77356 -403.06879)
		(end 190.78956 -403.06879)
		(width 0.13208)
		(layer "F.Cu")
		(net "A_P12V_AUX_ADR_TRIGGER")
	)
	(segment
		(start 190.445644 -403.71903)
		(end 190.445644 -403.991318)
		(width 0.13208)
		(layer "F.Cu")
		(net "A_P12V_AUX_ADR_TRIGGER")
	)
	(segment
		(start 190.445644 -403.991318)
		(end 190.424816 -404.012146)
		(width 0.13208)
		(layer "F.Cu")
		(net "A_P12V_AUX_ADR_TRIGGER")
	)
	(segment
		(start 190.78956 -403.375114)
		(end 190.445644 -403.71903)
		(width 0.13208)
		(layer "F.Cu")
		(net "A_P12V_AUX_ADR_TRIGGER")
	)
	(via
		(at 190.445644 -403.991318)
		(size 0.508)
		(drill 0.254)
		(layers "F.Cu" "B.Cu")
		(net "A_P12V_AUX_ADR_TRIGGER")
	)
	(segment
		(start 188.524896 -407.601674)
		(end 188.524896 -408.31516)
		(width 0.13208)
		(layer "F.Cu")
		(net "A_P12V_AUX_FPH_GATE")
	)
	(segment
		(start 186.93765 -409.3972)
		(end 186.93765 -408.0764)
		(width 0.13208)
		(layer "F.Cu")
		(net "A_P12V_AUX_FPH_GATE")
	)
	(segment
		(start 186.961018 -409.420568)
		(end 186.93765 -409.3972)
		(width 0.13208)
		(layer "F.Cu")
		(net "A_P12V_AUX_FPH_GATE")
	)
	(segment
		(start 188.524896 -408.31516)
		(end 187.796932 -409.043124)
		(width 0.13208)
		(layer "F.Cu")
		(net "A_P12V_AUX_FPH_GATE")
	)
	(segment
		(start 187.796932 -409.420568)
		(end 186.961018 -409.420568)
		(width 0.13208)
		(layer "F.Cu")
		(net "A_P12V_AUX_FPH_GATE")
	)
	(segment
		(start 187.796932 -409.043124)
		(end 187.796932 -409.420568)
		(width 0.13208)
		(layer "F.Cu")
		(net "A_P12V_AUX_FPH_GATE")
	)
	(via
		(at 186.961018 -409.420568)
		(size 0.508)
		(drill 0.254)
		(layers "F.Cu" "B.Cu")
		(net "A_P12V_AUX_FPH_GATE")
	)
	(segment
		(start 296.79519 -194.05219)
		(end 293.725346 -190.982346)
		(width 0.13208)
		(layer "F.Cu")
		(net "SPI_BIC1_CS0_R1_N")
	)
	(segment
		(start 242.274598 -193.589402)
		(end 242.274598 -193.80835)
		(width 0.13208)
		(layer "F.Cu")
		(net "SPI_BIC1_CS0_R1_N")
	)
	(segment
		(start 226.752912 -200.584054)
		(end 226.39147 -200.584054)
		(width 0.13208)
		(layer "F.Cu")
		(net "SPI_BIC1_CS0_R1_N")
	)
	(segment
		(start 284.500574 -190.982346)
		(end 276.586442 -189.408054)
		(width 0.13208)
		(layer "F.Cu")
		(net "SPI_BIC1_CS0_R1_N")
	)
	(segment
		(start 247.9294 -187.9346)
		(end 242.274598 -193.589402)
		(width 0.13208)
		(layer "F.Cu")
		(net "SPI_BIC1_CS0_R1_N")
	)
	(segment
		(start 226.39147 -200.584054)
		(end 225.999802 -200.192386)
		(width 0.13208)
		(layer "F.Cu")
		(net "SPI_BIC1_CS0_R1_N")
	)
	(segment
		(start 276.586442 -189.408054)
		(end 261.624572 -187.9346)
		(width 0.13208)
		(layer "F.Cu")
		(net "SPI_BIC1_CS0_R1_N")
	)
	(segment
		(start 293.725346 -190.982346)
		(end 284.500574 -190.982346)
		(width 0.13208)
		(layer "F.Cu")
		(net "SPI_BIC1_CS0_R1_N")
	)
	(segment
		(start 261.624572 -187.9346)
		(end 247.9294 -187.9346)
		(width 0.13208)
		(layer "F.Cu")
		(net "SPI_BIC1_CS0_R1_N")
	)
	(segment
		(start 185.200544 -196.431408)
		(end 188.466222 -197.080886)
		(width 0.13208)
		(layer "F.Cu")
		(net "SPI_BIC1_CS0_R1_N")
	)
	(segment
		(start 296.79519 -194.92849)
		(end 296.79519 -194.05219)
		(width 0.13208)
		(layer "F.Cu")
		(net "SPI_BIC1_CS0_R1_N")
	)
	(segment
		(start 184.891934 -196.122798)
		(end 185.200544 -196.431408)
		(width 0.13208)
		(layer "F.Cu")
		(net "SPI_BIC1_CS0_R1_N")
	)
	(via
		(at 242.274598 -193.80835)
		(size 0.508)
		(drill 0.254)
		(layers "F.Cu" "B.Cu")
		(net "SPI_BIC1_CS0_R1_N")
	)
	(via
		(at 188.466222 -197.080886)
		(size 0.508)
		(drill 0.254)
		(layers "F.Cu" "B.Cu")
		(net "SPI_BIC1_CS0_R1_N")
	)
	(via
		(at 225.999802 -200.192386)
		(size 0.508)
		(drill 0.254)
		(layers "F.Cu" "B.Cu")
		(net "SPI_BIC1_CS0_R1_N")
	)
	(segment
		(start 198.369936 -198.755)
		(end 197.996556 -198.755)
		(width 0.15494)
		(layer "In13.Cu")
		(net "SPI_BIC1_CS0_R1_N")
	)
	(segment
		(start 240.273078 -197.635114)
		(end 240.009172 -197.89902)
		(width 0.15494)
		(layer "In13.Cu")
		(net "SPI_BIC1_CS0_R1_N")
	)
	(segment
		(start 195.156836 -200.04024)
		(end 194.783456 -200.04024)
		(width 0.15494)
		(layer "In13.Cu")
		(net "SPI_BIC1_CS0_R1_N")
	)
	(segment
		(start 197.861936 -198.88962)
		(end 197.861936 -199.90562)
		(width 0.15494)
		(layer "In13.Cu")
		(net "SPI_BIC1_CS0_R1_N")
	)
	(segment
		(start 240.142268 -195.44538)
		(end 241.212624 -196.515736)
		(width 0.15494)
		(layer "In13.Cu")
		(net "SPI_BIC1_CS0_R1_N")
	)
	(segment
		(start 200.567036 -198.755)
		(end 200.432416 -198.88962)
		(width 0.15494)
		(layer "In13.Cu")
		(net "SPI_BIC1_CS0_R1_N")
	)
	(segment
		(start 197.084696 -198.755)
		(end 196.711316 -198.755)
		(width 0.15494)
		(layer "In13.Cu")
		(net "SPI_BIC1_CS0_R1_N")
	)
	(segment
		(start 240.009172 -197.89902)
		(end 239.818672 -197.89902)
		(width 0.15494)
		(layer "In13.Cu")
		(net "SPI_BIC1_CS0_R1_N")
	)
	(segment
		(start 201.075036 -198.88962)
		(end 200.940416 -198.755)
		(width 0.15494)
		(layer "In13.Cu")
		(net "SPI_BIC1_CS0_R1_N")
	)
	(segment
		(start 191.425576 -200.04024)
		(end 188.466222 -197.080886)
		(width 0.15494)
		(layer "In13.Cu")
		(net "SPI_BIC1_CS0_R1_N")
	)
	(segment
		(start 210.074764 -200.46569)
		(end 201.635106 -200.46569)
		(width 0.15494)
		(layer "In13.Cu")
		(net "SPI_BIC1_CS0_R1_N")
	)
	(segment
		(start 195.934076 -199.90562)
		(end 195.934076 -198.88962)
		(width 0.15494)
		(layer "In13.Cu")
		(net "SPI_BIC1_CS0_R1_N")
	)
	(segment
		(start 239.818672 -197.89902)
		(end 238.90605 -196.986398)
		(width 0.15494)
		(layer "In13.Cu")
		(net "SPI_BIC1_CS0_R1_N")
	)
	(segment
		(start 197.861936 -199.90562)
		(end 197.727316 -200.04024)
		(width 0.15494)
		(layer "In13.Cu")
		(net "SPI_BIC1_CS0_R1_N")
	)
	(segment
		(start 192.880996 -198.6534)
		(end 192.746376 -198.78802)
		(width 0.15494)
		(layer "In13.Cu")
		(net "SPI_BIC1_CS0_R1_N")
	)
	(segment
		(start 194.140836 -198.7804)
		(end 194.006216 -198.91502)
		(width 0.15494)
		(layer "In13.Cu")
		(net "SPI_BIC1_CS0_R1_N")
	)
	(segment
		(start 200.432416 -198.88962)
		(end 200.432416 -199.90562)
		(width 0.15494)
		(layer "In13.Cu")
		(net "SPI_BIC1_CS0_R1_N")
	)
	(segment
		(start 195.291456 -198.88962)
		(end 195.291456 -199.90562)
		(width 0.15494)
		(layer "In13.Cu")
		(net "SPI_BIC1_CS0_R1_N")
	)
	(segment
		(start 199.789796 -198.88962)
		(end 199.655176 -198.755)
		(width 0.15494)
		(layer "In13.Cu")
		(net "SPI_BIC1_CS0_R1_N")
	)
	(segment
		(start 197.996556 -198.755)
		(end 197.861936 -198.88962)
		(width 0.15494)
		(layer "In13.Cu")
		(net "SPI_BIC1_CS0_R1_N")
	)
	(segment
		(start 240.596674 -194.990974)
		(end 240.406174 -194.990974)
		(width 0.15494)
		(layer "In13.Cu")
		(net "SPI_BIC1_CS0_R1_N")
	)
	(segment
		(start 239.814862 -196.077586)
		(end 239.624362 -196.077586)
		(width 0.15494)
		(layer "In13.Cu")
		(net "SPI_BIC1_CS0_R1_N")
	)
	(segment
		(start 194.648836 -198.91502)
		(end 194.514216 -198.7804)
		(width 0.15494)
		(layer "In13.Cu")
		(net "SPI_BIC1_CS0_R1_N")
	)
	(segment
		(start 218.033346 -199.79132)
		(end 216.23528 -199.79132)
		(width 0.15494)
		(layer "In13.Cu")
		(net "SPI_BIC1_CS0_R1_N")
	)
	(segment
		(start 198.504556 -199.90562)
		(end 198.504556 -198.88962)
		(width 0.15494)
		(layer "In13.Cu")
		(net "SPI_BIC1_CS0_R1_N")
	)
	(segment
		(start 196.576696 -198.88962)
		(end 196.576696 -199.90562)
		(width 0.15494)
		(layer "In13.Cu")
		(net "SPI_BIC1_CS0_R1_N")
	)
	(segment
		(start 199.789796 -199.90562)
		(end 199.789796 -198.88962)
		(width 0.15494)
		(layer "In13.Cu")
		(net "SPI_BIC1_CS0_R1_N")
	)
	(segment
		(start 200.940416 -198.755)
		(end 200.567036 -198.755)
		(width 0.15494)
		(layer "In13.Cu")
		(net "SPI_BIC1_CS0_R1_N")
	)
	(segment
		(start 220.791786 -200.192386)
		(end 220.16593 -199.56653)
		(width 0.15494)
		(layer "In13.Cu")
		(net "SPI_BIC1_CS0_R1_N")
	)
	(segment
		(start 235.945172 -199.7964)
		(end 227.235004 -199.7964)
		(width 0.15494)
		(layer "In13.Cu")
		(net "SPI_BIC1_CS0_R1_N")
	)
	(segment
		(start 241.893598 -193.80835)
		(end 241.17808 -194.523868)
		(width 0.15494)
		(layer "In13.Cu")
		(net "SPI_BIC1_CS0_R1_N")
	)
	(segment
		(start 192.586356 -200.04024)
		(end 191.425576 -200.04024)
		(width 0.15494)
		(layer "In13.Cu")
		(net "SPI_BIC1_CS0_R1_N")
	)
	(segment
		(start 240.142268 -195.25488)
		(end 240.142268 -195.44538)
		(width 0.15494)
		(layer "In13.Cu")
		(net "SPI_BIC1_CS0_R1_N")
	)
	(segment
		(start 242.274598 -193.80835)
		(end 241.893598 -193.80835)
		(width 0.15494)
		(layer "In13.Cu")
		(net "SPI_BIC1_CS0_R1_N")
	)
	(segment
		(start 226.92614 -200.105264)
		(end 226.086924 -200.105264)
		(width 0.15494)
		(layer "In13.Cu")
		(net "SPI_BIC1_CS0_R1_N")
	)
	(segment
		(start 197.219316 -199.90562)
		(end 197.219316 -198.88962)
		(width 0.15494)
		(layer "In13.Cu")
		(net "SPI_BIC1_CS0_R1_N")
	)
	(segment
		(start 201.075036 -199.90562)
		(end 201.075036 -198.88962)
		(width 0.15494)
		(layer "In13.Cu")
		(net "SPI_BIC1_CS0_R1_N")
	)
	(segment
		(start 199.147176 -199.90562)
		(end 199.012556 -200.04024)
		(width 0.15494)
		(layer "In13.Cu")
		(net "SPI_BIC1_CS0_R1_N")
	)
	(segment
		(start 199.281796 -198.755)
		(end 199.147176 -198.88962)
		(width 0.15494)
		(layer "In13.Cu")
		(net "SPI_BIC1_CS0_R1_N")
	)
	(segment
		(start 239.624362 -196.077586)
		(end 239.360456 -196.341492)
		(width 0.15494)
		(layer "In13.Cu")
		(net "SPI_BIC1_CS0_R1_N")
	)
	(segment
		(start 225.999802 -200.192386)
		(end 220.791786 -200.192386)
		(width 0.15494)
		(layer "In13.Cu")
		(net "SPI_BIC1_CS0_R1_N")
	)
	(segment
		(start 192.746376 -198.78802)
		(end 192.746376 -199.88022)
		(width 0.15494)
		(layer "In13.Cu")
		(net "SPI_BIC1_CS0_R1_N")
	)
	(segment
		(start 239.360456 -196.531992)
		(end 240.273078 -197.444614)
		(width 0.15494)
		(layer "In13.Cu")
		(net "SPI_BIC1_CS0_R1_N")
	)
	(segment
		(start 239.360456 -196.341492)
		(end 239.360456 -196.531992)
		(width 0.15494)
		(layer "In13.Cu")
		(net "SPI_BIC1_CS0_R1_N")
	)
	(segment
		(start 197.353936 -200.04024)
		(end 197.219316 -199.90562)
		(width 0.15494)
		(layer "In13.Cu")
		(net "SPI_BIC1_CS0_R1_N")
	)
	(segment
		(start 240.727484 -196.990208)
		(end 239.814862 -196.077586)
		(width 0.15494)
		(layer "In13.Cu")
		(net "SPI_BIC1_CS0_R1_N")
	)
	(segment
		(start 241.212624 -196.695568)
		(end 240.917984 -196.990208)
		(width 0.15494)
		(layer "In13.Cu")
		(net "SPI_BIC1_CS0_R1_N")
	)
	(segment
		(start 194.006216 -198.91502)
		(end 194.006216 -199.90562)
		(width 0.15494)
		(layer "In13.Cu")
		(net "SPI_BIC1_CS0_R1_N")
	)
	(segment
		(start 210.60537 -200.6854)
		(end 210.074764 -200.46569)
		(width 0.15494)
		(layer "In13.Cu")
		(net "SPI_BIC1_CS0_R1_N")
	)
	(segment
		(start 216.23528 -199.79132)
		(end 215.3412 -200.6854)
		(width 0.15494)
		(layer "In13.Cu")
		(net "SPI_BIC1_CS0_R1_N")
	)
	(segment
		(start 193.388996 -199.91324)
		(end 193.388996 -198.78802)
		(width 0.15494)
		(layer "In13.Cu")
		(net "SPI_BIC1_CS0_R1_N")
	)
	(segment
		(start 197.219316 -198.88962)
		(end 197.084696 -198.755)
		(width 0.15494)
		(layer "In13.Cu")
		(net "SPI_BIC1_CS0_R1_N")
	)
	(segment
		(start 195.799456 -198.755)
		(end 195.426076 -198.755)
		(width 0.15494)
		(layer "In13.Cu")
		(net "SPI_BIC1_CS0_R1_N")
	)
	(segment
		(start 194.783456 -200.04024)
		(end 194.648836 -199.90562)
		(width 0.15494)
		(layer "In13.Cu")
		(net "SPI_BIC1_CS0_R1_N")
	)
	(segment
		(start 227.235004 -199.7964)
		(end 226.92614 -200.105264)
		(width 0.15494)
		(layer "In13.Cu")
		(net "SPI_BIC1_CS0_R1_N")
	)
	(segment
		(start 199.147176 -198.88962)
		(end 199.147176 -199.90562)
		(width 0.15494)
		(layer "In13.Cu")
		(net "SPI_BIC1_CS0_R1_N")
	)
	(segment
		(start 194.648836 -199.90562)
		(end 194.648836 -198.91502)
		(width 0.15494)
		(layer "In13.Cu")
		(net "SPI_BIC1_CS0_R1_N")
	)
	(segment
		(start 241.846862 -196.06133)
		(end 241.66703 -196.06133)
		(width 0.15494)
		(layer "In13.Cu")
		(net "SPI_BIC1_CS0_R1_N")
	)
	(segment
		(start 196.442076 -200.04024)
		(end 196.068696 -200.04024)
		(width 0.15494)
		(layer "In13.Cu")
		(net "SPI_BIC1_CS0_R1_N")
	)
	(segment
		(start 199.012556 -200.04024)
		(end 198.639176 -200.04024)
		(width 0.15494)
		(layer "In13.Cu")
		(net "SPI_BIC1_CS0_R1_N")
	)
	(segment
		(start 226.086924 -200.105264)
		(end 225.999802 -200.192386)
		(width 0.15494)
		(layer "In13.Cu")
		(net "SPI_BIC1_CS0_R1_N")
	)
	(segment
		(start 200.432416 -199.90562)
		(end 200.297796 -200.04024)
		(width 0.15494)
		(layer "In13.Cu")
		(net "SPI_BIC1_CS0_R1_N")
	)
	(segment
		(start 241.17808 -194.523868)
		(end 241.17808 -194.714368)
		(width 0.15494)
		(layer "In13.Cu")
		(net "SPI_BIC1_CS0_R1_N")
	)
	(segment
		(start 192.746376 -199.88022)
		(end 192.586356 -200.04024)
		(width 0.15494)
		(layer "In13.Cu")
		(net "SPI_BIC1_CS0_R1_N")
	)
	(segment
		(start 200.297796 -200.04024)
		(end 199.924416 -200.04024)
		(width 0.15494)
		(layer "In13.Cu")
		(net "SPI_BIC1_CS0_R1_N")
	)
	(segment
		(start 238.90605 -196.986398)
		(end 238.755174 -196.986398)
		(width 0.15494)
		(layer "In13.Cu")
		(net "SPI_BIC1_CS0_R1_N")
	)
	(segment
		(start 199.924416 -200.04024)
		(end 199.789796 -199.90562)
		(width 0.15494)
		(layer "In13.Cu")
		(net "SPI_BIC1_CS0_R1_N")
	)
	(segment
		(start 196.068696 -200.04024)
		(end 195.934076 -199.90562)
		(width 0.15494)
		(layer "In13.Cu")
		(net "SPI_BIC1_CS0_R1_N")
	)
	(segment
		(start 240.917984 -196.990208)
		(end 240.727484 -196.990208)
		(width 0.15494)
		(layer "In13.Cu")
		(net "SPI_BIC1_CS0_R1_N")
	)
	(segment
		(start 242.090702 -195.62699)
		(end 242.090702 -195.81749)
		(width 0.15494)
		(layer "In13.Cu")
		(net "SPI_BIC1_CS0_R1_N")
	)
	(segment
		(start 195.934076 -198.88962)
		(end 195.799456 -198.755)
		(width 0.15494)
		(layer "In13.Cu")
		(net "SPI_BIC1_CS0_R1_N")
	)
	(segment
		(start 195.426076 -198.755)
		(end 195.291456 -198.88962)
		(width 0.15494)
		(layer "In13.Cu")
		(net "SPI_BIC1_CS0_R1_N")
	)
	(segment
		(start 198.639176 -200.04024)
		(end 198.504556 -199.90562)
		(width 0.15494)
		(layer "In13.Cu")
		(net "SPI_BIC1_CS0_R1_N")
	)
	(segment
		(start 201.635106 -200.46569)
		(end 201.075036 -199.90562)
		(width 0.15494)
		(layer "In13.Cu")
		(net "SPI_BIC1_CS0_R1_N")
	)
	(segment
		(start 241.17808 -194.714368)
		(end 242.090702 -195.62699)
		(width 0.15494)
		(layer "In13.Cu")
		(net "SPI_BIC1_CS0_R1_N")
	)
	(segment
		(start 197.727316 -200.04024)
		(end 197.353936 -200.04024)
		(width 0.15494)
		(layer "In13.Cu")
		(net "SPI_BIC1_CS0_R1_N")
	)
	(segment
		(start 240.406174 -194.990974)
		(end 240.142268 -195.25488)
		(width 0.15494)
		(layer "In13.Cu")
		(net "SPI_BIC1_CS0_R1_N")
	)
	(segment
		(start 240.273078 -197.444614)
		(end 240.273078 -197.635114)
		(width 0.15494)
		(layer "In13.Cu")
		(net "SPI_BIC1_CS0_R1_N")
	)
	(segment
		(start 198.504556 -198.88962)
		(end 198.369936 -198.755)
		(width 0.15494)
		(layer "In13.Cu")
		(net "SPI_BIC1_CS0_R1_N")
	)
	(segment
		(start 218.57589 -199.56653)
		(end 218.033346 -199.79132)
		(width 0.15494)
		(layer "In13.Cu")
		(net "SPI_BIC1_CS0_R1_N")
	)
	(segment
		(start 193.388996 -198.78802)
		(end 193.254376 -198.6534)
		(width 0.15494)
		(layer "In13.Cu")
		(net "SPI_BIC1_CS0_R1_N")
	)
	(segment
		(start 215.3412 -200.6854)
		(end 210.60537 -200.6854)
		(width 0.15494)
		(layer "In13.Cu")
		(net "SPI_BIC1_CS0_R1_N")
	)
	(segment
		(start 194.514216 -198.7804)
		(end 194.140836 -198.7804)
		(width 0.15494)
		(layer "In13.Cu")
		(net "SPI_BIC1_CS0_R1_N")
	)
	(segment
		(start 199.655176 -198.755)
		(end 199.281796 -198.755)
		(width 0.15494)
		(layer "In13.Cu")
		(net "SPI_BIC1_CS0_R1_N")
	)
	(segment
		(start 193.254376 -198.6534)
		(end 192.880996 -198.6534)
		(width 0.15494)
		(layer "In13.Cu")
		(net "SPI_BIC1_CS0_R1_N")
	)
	(segment
		(start 193.515996 -200.04024)
		(end 193.388996 -199.91324)
		(width 0.15494)
		(layer "In13.Cu")
		(net "SPI_BIC1_CS0_R1_N")
	)
	(segment
		(start 238.755174 -196.986398)
		(end 235.945172 -199.7964)
		(width 0.15494)
		(layer "In13.Cu")
		(net "SPI_BIC1_CS0_R1_N")
	)
	(segment
		(start 194.006216 -199.90562)
		(end 193.871596 -200.04024)
		(width 0.15494)
		(layer "In13.Cu")
		(net "SPI_BIC1_CS0_R1_N")
	)
	(segment
		(start 195.291456 -199.90562)
		(end 195.156836 -200.04024)
		(width 0.15494)
		(layer "In13.Cu")
		(net "SPI_BIC1_CS0_R1_N")
	)
	(segment
		(start 242.090702 -195.81749)
		(end 241.846862 -196.06133)
		(width 0.15494)
		(layer "In13.Cu")
		(net "SPI_BIC1_CS0_R1_N")
	)
	(segment
		(start 196.711316 -198.755)
		(end 196.576696 -198.88962)
		(width 0.15494)
		(layer "In13.Cu")
		(net "SPI_BIC1_CS0_R1_N")
	)
	(segment
		(start 220.16593 -199.56653)
		(end 218.57589 -199.56653)
		(width 0.15494)
		(layer "In13.Cu")
		(net "SPI_BIC1_CS0_R1_N")
	)
	(segment
		(start 196.576696 -199.90562)
		(end 196.442076 -200.04024)
		(width 0.15494)
		(layer "In13.Cu")
		(net "SPI_BIC1_CS0_R1_N")
	)
	(segment
		(start 193.871596 -200.04024)
		(end 193.515996 -200.04024)
		(width 0.15494)
		(layer "In13.Cu")
		(net "SPI_BIC1_CS0_R1_N")
	)
	(segment
		(start 241.66703 -196.06133)
		(end 240.596674 -194.990974)
		(width 0.15494)
		(layer "In13.Cu")
		(net "SPI_BIC1_CS0_R1_N")
	)
	(segment
		(start 241.212624 -196.515736)
		(end 241.212624 -196.695568)
		(width 0.15494)
		(layer "In13.Cu")
		(net "SPI_BIC1_CS0_R1_N")
	)
	(segment
		(start 276.96287 -190.266828)
		(end 284.171898 -191.700658)
		(width 0.13208)
		(layer "F.Cu")
		(net "SPI_BIC1_CLK_R2")
	)
	(segment
		(start 250.07697 -188.595)
		(end 259.988558 -188.595)
		(width 0.13208)
		(layer "F.Cu")
		(net "SPI_BIC1_CLK_R2")
	)
	(segment
		(start 188.468 -195.106798)
		(end 184.891934 -195.106798)
		(width 0.13208)
		(layer "F.Cu")
		(net "SPI_BIC1_CLK_R2")
	)
	(segment
		(start 259.988558 -188.595)
		(end 276.96287 -190.266828)
		(width 0.13208)
		(layer "F.Cu")
		(net "SPI_BIC1_CLK_R2")
	)
	(segment
		(start 249.396504 -189.275466)
		(end 250.07697 -188.595)
		(width 0.13208)
		(layer "F.Cu")
		(net "SPI_BIC1_CLK_R2")
	)
	(segment
		(start 293.328344 -191.700658)
		(end 295.77919 -194.151504)
		(width 0.13208)
		(layer "F.Cu")
		(net "SPI_BIC1_CLK_R2")
	)
	(segment
		(start 295.77919 -194.151504)
		(end 295.77919 -194.962018)
		(width 0.13208)
		(layer "F.Cu")
		(net "SPI_BIC1_CLK_R2")
	)
	(segment
		(start 284.171898 -191.700658)
		(end 293.328344 -191.700658)
		(width 0.13208)
		(layer "F.Cu")
		(net "SPI_BIC1_CLK_R2")
	)
	(via
		(at 249.396504 -189.275466)
		(size 0.508)
		(drill 0.254)
		(layers "F.Cu" "B.Cu")
		(net "SPI_BIC1_CLK_R2")
	)
	(via
		(at 188.468 -195.106798)
		(size 0.508)
		(drill 0.254)
		(layers "F.Cu" "B.Cu")
		(net "SPI_BIC1_CLK_R2")
	)
	(via
		(at 224.386902 -193.00317)
		(size 0.508)
		(drill 0.254)
		(layers "F.Cu" "B.Cu")
		(net "SPI_BIC1_CLK_R2")
	)
	(segment
		(start 224.743264 -193.359532)
		(end 224.386902 -193.00317)
		(width 0.13208)
		(layer "B.Cu")
		(net "SPI_BIC1_CLK_R2")
	)
	(segment
		(start 225.19894 -193.359532)
		(end 224.743264 -193.359532)
		(width 0.13208)
		(layer "B.Cu")
		(net "SPI_BIC1_CLK_R2")
	)
	(segment
		(start 201.278236 -195.106798)
		(end 201.651616 -195.106798)
		(width 0.15494)
		(layer "In13.Cu")
		(net "SPI_BIC1_CLK_R2")
	)
	(segment
		(start 200.366376 -195.106798)
		(end 200.500996 -195.241418)
		(width 0.15494)
		(layer "In13.Cu")
		(net "SPI_BIC1_CLK_R2")
	)
	(segment
		(start 204.999336 -195.95338)
		(end 204.999336 -195.241418)
		(width 0.15494)
		(layer "In13.Cu")
		(net "SPI_BIC1_CLK_R2")
	)
	(segment
		(start 240.851182 -189.029848)
		(end 240.985802 -188.895228)
		(width 0.15494)
		(layer "In13.Cu")
		(net "SPI_BIC1_CLK_R2")
	)
	(segment
		(start 200.500996 -195.95338)
		(end 200.635616 -196.088)
		(width 0.15494)
		(layer "In13.Cu")
		(net "SPI_BIC1_CLK_R2")
	)
	(segment
		(start 201.008996 -196.088)
		(end 201.143616 -195.95338)
		(width 0.15494)
		(layer "In13.Cu")
		(net "SPI_BIC1_CLK_R2")
	)
	(segment
		(start 240.208562 -187.962032)
		(end 240.343182 -188.096652)
		(width 0.15494)
		(layer "In13.Cu")
		(net "SPI_BIC1_CLK_R2")
	)
	(segment
		(start 243.598192 -187.962032)
		(end 248.652792 -188.967364)
		(width 0.15494)
		(layer "In13.Cu")
		(net "SPI_BIC1_CLK_R2")
	)
	(segment
		(start 205.507336 -195.106798)
		(end 205.641956 -195.241418)
		(width 0.15494)
		(layer "In13.Cu")
		(net "SPI_BIC1_CLK_R2")
	)
	(segment
		(start 242.136422 -189.029848)
		(end 242.271042 -188.895228)
		(width 0.15494)
		(layer "In13.Cu")
		(net "SPI_BIC1_CLK_R2")
	)
	(segment
		(start 205.133956 -195.106798)
		(end 205.507336 -195.106798)
		(width 0.15494)
		(layer "In13.Cu")
		(net "SPI_BIC1_CLK_R2")
	)
	(segment
		(start 215.19388 -194.90436)
		(end 218.54414 -194.90436)
		(width 0.15494)
		(layer "In13.Cu")
		(net "SPI_BIC1_CLK_R2")
	)
	(segment
		(start 190.07201 -195.302124)
		(end 190.267336 -195.106798)
		(width 0.15494)
		(layer "In13.Cu")
		(net "SPI_BIC1_CLK_R2")
	)
	(segment
		(start 240.477802 -189.029848)
		(end 240.851182 -189.029848)
		(width 0.15494)
		(layer "In13.Cu")
		(net "SPI_BIC1_CLK_R2")
	)
	(segment
		(start 202.563476 -195.106798)
		(end 202.936856 -195.106798)
		(width 0.15494)
		(layer "In13.Cu")
		(net "SPI_BIC1_CLK_R2")
	)
	(segment
		(start 233.406188 -187.962032)
		(end 240.208562 -187.962032)
		(width 0.15494)
		(layer "In13.Cu")
		(net "SPI_BIC1_CLK_R2")
	)
	(segment
		(start 240.985802 -188.096652)
		(end 241.120422 -187.962032)
		(width 0.15494)
		(layer "In13.Cu")
		(net "SPI_BIC1_CLK_R2")
	)
	(segment
		(start 209.505296 -194.819524)
		(end 210.428586 -194.437)
		(width 0.15494)
		(layer "In13.Cu")
		(net "SPI_BIC1_CLK_R2")
	)
	(segment
		(start 201.143616 -195.241418)
		(end 201.278236 -195.106798)
		(width 0.15494)
		(layer "In13.Cu")
		(net "SPI_BIC1_CLK_R2")
	)
	(segment
		(start 203.071476 -195.95338)
		(end 203.206096 -196.088)
		(width 0.15494)
		(layer "In13.Cu")
		(net "SPI_BIC1_CLK_R2")
	)
	(segment
		(start 206.419196 -195.661026)
		(end 208.663794 -195.661026)
		(width 0.15494)
		(layer "In13.Cu")
		(net "SPI_BIC1_CLK_R2")
	)
	(segment
		(start 241.628422 -188.895228)
		(end 241.763042 -189.029848)
		(width 0.15494)
		(layer "In13.Cu")
		(net "SPI_BIC1_CLK_R2")
	)
	(segment
		(start 203.714096 -195.241418)
		(end 203.848716 -195.106798)
		(width 0.15494)
		(layer "In13.Cu")
		(net "SPI_BIC1_CLK_R2")
	)
	(segment
		(start 201.786236 -195.241418)
		(end 201.786236 -195.95338)
		(width 0.15494)
		(layer "In13.Cu")
		(net "SPI_BIC1_CLK_R2")
	)
	(segment
		(start 205.776576 -196.088)
		(end 206.149956 -196.088)
		(width 0.15494)
		(layer "In13.Cu")
		(net "SPI_BIC1_CLK_R2")
	)
	(segment
		(start 224.386902 -193.00317)
		(end 229.525576 -189.56909)
		(width 0.15494)
		(layer "In13.Cu")
		(net "SPI_BIC1_CLK_R2")
	)
	(segment
		(start 203.848716 -195.106798)
		(end 204.222096 -195.106798)
		(width 0.15494)
		(layer "In13.Cu")
		(net "SPI_BIC1_CLK_R2")
	)
	(segment
		(start 200.500996 -195.241418)
		(end 200.500996 -195.95338)
		(width 0.15494)
		(layer "In13.Cu")
		(net "SPI_BIC1_CLK_R2")
	)
	(segment
		(start 204.356716 -195.241418)
		(end 204.356716 -195.95338)
		(width 0.15494)
		(layer "In13.Cu")
		(net "SPI_BIC1_CLK_R2")
	)
	(segment
		(start 242.405662 -187.962032)
		(end 243.598192 -187.962032)
		(width 0.15494)
		(layer "In13.Cu")
		(net "SPI_BIC1_CLK_R2")
	)
	(segment
		(start 206.149956 -196.088)
		(end 206.284576 -195.95338)
		(width 0.15494)
		(layer "In13.Cu")
		(net "SPI_BIC1_CLK_R2")
	)
	(segment
		(start 248.652792 -188.967364)
		(end 249.396504 -189.275466)
		(width 0.15494)
		(layer "In13.Cu")
		(net "SPI_BIC1_CLK_R2")
	)
	(segment
		(start 210.428586 -194.437)
		(end 214.72652 -194.437)
		(width 0.15494)
		(layer "In13.Cu")
		(net "SPI_BIC1_CLK_R2")
	)
	(segment
		(start 219.1131 -194.3354)
		(end 221.169992 -194.3354)
		(width 0.15494)
		(layer "In13.Cu")
		(net "SPI_BIC1_CLK_R2")
	)
	(segment
		(start 221.169992 -194.3354)
		(end 224.386902 -193.00317)
		(width 0.15494)
		(layer "In13.Cu")
		(net "SPI_BIC1_CLK_R2")
	)
	(segment
		(start 214.72652 -194.437)
		(end 215.19388 -194.90436)
		(width 0.15494)
		(layer "In13.Cu")
		(net "SPI_BIC1_CLK_R2")
	)
	(segment
		(start 205.641956 -195.95338)
		(end 205.776576 -196.088)
		(width 0.15494)
		(layer "In13.Cu")
		(net "SPI_BIC1_CLK_R2")
	)
	(segment
		(start 202.294236 -196.088)
		(end 202.428856 -195.95338)
		(width 0.15494)
		(layer "In13.Cu")
		(net "SPI_BIC1_CLK_R2")
	)
	(segment
		(start 203.579476 -196.088)
		(end 203.714096 -195.95338)
		(width 0.15494)
		(layer "In13.Cu")
		(net "SPI_BIC1_CLK_R2")
	)
	(segment
		(start 206.284576 -195.95338)
		(end 206.284576 -195.795646)
		(width 0.15494)
		(layer "In13.Cu")
		(net "SPI_BIC1_CLK_R2")
	)
	(segment
		(start 188.468 -195.106798)
		(end 188.663326 -195.302124)
		(width 0.15494)
		(layer "In13.Cu")
		(net "SPI_BIC1_CLK_R2")
	)
	(segment
		(start 203.206096 -196.088)
		(end 203.579476 -196.088)
		(width 0.15494)
		(layer "In13.Cu")
		(net "SPI_BIC1_CLK_R2")
	)
	(segment
		(start 201.920856 -196.088)
		(end 202.294236 -196.088)
		(width 0.15494)
		(layer "In13.Cu")
		(net "SPI_BIC1_CLK_R2")
	)
	(segment
		(start 242.271042 -188.096652)
		(end 242.405662 -187.962032)
		(width 0.15494)
		(layer "In13.Cu")
		(net "SPI_BIC1_CLK_R2")
	)
	(segment
		(start 203.714096 -195.95338)
		(end 203.714096 -195.241418)
		(width 0.15494)
		(layer "In13.Cu")
		(net "SPI_BIC1_CLK_R2")
	)
	(segment
		(start 218.54414 -194.90436)
		(end 219.1131 -194.3354)
		(width 0.15494)
		(layer "In13.Cu")
		(net "SPI_BIC1_CLK_R2")
	)
	(segment
		(start 242.271042 -188.895228)
		(end 242.271042 -188.096652)
		(width 0.15494)
		(layer "In13.Cu")
		(net "SPI_BIC1_CLK_R2")
	)
	(segment
		(start 190.267336 -195.106798)
		(end 200.366376 -195.106798)
		(width 0.15494)
		(layer "In13.Cu")
		(net "SPI_BIC1_CLK_R2")
	)
	(segment
		(start 241.120422 -187.962032)
		(end 241.493802 -187.962032)
		(width 0.15494)
		(layer "In13.Cu")
		(net "SPI_BIC1_CLK_R2")
	)
	(segment
		(start 240.343182 -188.895228)
		(end 240.477802 -189.029848)
		(width 0.15494)
		(layer "In13.Cu")
		(net "SPI_BIC1_CLK_R2")
	)
	(segment
		(start 204.999336 -195.241418)
		(end 205.133956 -195.106798)
		(width 0.15494)
		(layer "In13.Cu")
		(net "SPI_BIC1_CLK_R2")
	)
	(segment
		(start 188.663326 -195.302124)
		(end 190.07201 -195.302124)
		(width 0.15494)
		(layer "In13.Cu")
		(net "SPI_BIC1_CLK_R2")
	)
	(segment
		(start 203.071476 -195.241418)
		(end 203.071476 -195.95338)
		(width 0.15494)
		(layer "In13.Cu")
		(net "SPI_BIC1_CLK_R2")
	)
	(segment
		(start 202.428856 -195.241418)
		(end 202.563476 -195.106798)
		(width 0.15494)
		(layer "In13.Cu")
		(net "SPI_BIC1_CLK_R2")
	)
	(segment
		(start 202.428856 -195.95338)
		(end 202.428856 -195.241418)
		(width 0.15494)
		(layer "In13.Cu")
		(net "SPI_BIC1_CLK_R2")
	)
	(segment
		(start 204.356716 -195.95338)
		(end 204.491336 -196.088)
		(width 0.15494)
		(layer "In13.Cu")
		(net "SPI_BIC1_CLK_R2")
	)
	(segment
		(start 201.786236 -195.95338)
		(end 201.920856 -196.088)
		(width 0.15494)
		(layer "In13.Cu")
		(net "SPI_BIC1_CLK_R2")
	)
	(segment
		(start 204.491336 -196.088)
		(end 204.864716 -196.088)
		(width 0.15494)
		(layer "In13.Cu")
		(net "SPI_BIC1_CLK_R2")
	)
	(segment
		(start 204.222096 -195.106798)
		(end 204.356716 -195.241418)
		(width 0.15494)
		(layer "In13.Cu")
		(net "SPI_BIC1_CLK_R2")
	)
	(segment
		(start 204.864716 -196.088)
		(end 204.999336 -195.95338)
		(width 0.15494)
		(layer "In13.Cu")
		(net "SPI_BIC1_CLK_R2")
	)
	(segment
		(start 240.985802 -188.895228)
		(end 240.985802 -188.096652)
		(width 0.15494)
		(layer "In13.Cu")
		(net "SPI_BIC1_CLK_R2")
	)
	(segment
		(start 241.763042 -189.029848)
		(end 242.136422 -189.029848)
		(width 0.15494)
		(layer "In13.Cu")
		(net "SPI_BIC1_CLK_R2")
	)
	(segment
		(start 200.635616 -196.088)
		(end 201.008996 -196.088)
		(width 0.15494)
		(layer "In13.Cu")
		(net "SPI_BIC1_CLK_R2")
	)
	(segment
		(start 240.343182 -188.096652)
		(end 240.343182 -188.895228)
		(width 0.15494)
		(layer "In13.Cu")
		(net "SPI_BIC1_CLK_R2")
	)
	(segment
		(start 202.936856 -195.106798)
		(end 203.071476 -195.241418)
		(width 0.15494)
		(layer "In13.Cu")
		(net "SPI_BIC1_CLK_R2")
	)
	(segment
		(start 201.651616 -195.106798)
		(end 201.786236 -195.241418)
		(width 0.15494)
		(layer "In13.Cu")
		(net "SPI_BIC1_CLK_R2")
	)
	(segment
		(start 206.284576 -195.795646)
		(end 206.419196 -195.661026)
		(width 0.15494)
		(layer "In13.Cu")
		(net "SPI_BIC1_CLK_R2")
	)
	(segment
		(start 201.143616 -195.95338)
		(end 201.143616 -195.241418)
		(width 0.15494)
		(layer "In13.Cu")
		(net "SPI_BIC1_CLK_R2")
	)
	(segment
		(start 241.493802 -187.962032)
		(end 241.628422 -188.096652)
		(width 0.15494)
		(layer "In13.Cu")
		(net "SPI_BIC1_CLK_R2")
	)
	(segment
		(start 229.525576 -189.56909)
		(end 233.406188 -187.962032)
		(width 0.15494)
		(layer "In13.Cu")
		(net "SPI_BIC1_CLK_R2")
	)
	(segment
		(start 208.663794 -195.661026)
		(end 209.505296 -194.819524)
		(width 0.15494)
		(layer "In13.Cu")
		(net "SPI_BIC1_CLK_R2")
	)
	(segment
		(start 241.628422 -188.096652)
		(end 241.628422 -188.895228)
		(width 0.15494)
		(layer "In13.Cu")
		(net "SPI_BIC1_CLK_R2")
	)
	(segment
		(start 205.641956 -195.241418)
		(end 205.641956 -195.95338)
		(width 0.15494)
		(layer "In13.Cu")
		(net "SPI_BIC1_CLK_R2")
	)
	(segment
		(start 249.45086 -190.813944)
		(end 251.000514 -190.813944)
		(width 0.13208)
		(layer "F.Cu")
		(net "SPI_BIC1_MISO_R2")
	)
	(segment
		(start 251.859034 -189.955424)
		(end 260.758432 -189.955424)
		(width 0.13208)
		(layer "F.Cu")
		(net "SPI_BIC1_MISO_R2")
	)
	(segment
		(start 251.000514 -190.813944)
		(end 251.859034 -189.955424)
		(width 0.13208)
		(layer "F.Cu")
		(net "SPI_BIC1_MISO_R2")
	)
	(segment
		(start 188.725556 -192.963038)
		(end 185.003694 -192.963038)
		(width 0.13208)
		(layer "F.Cu")
		(net "SPI_BIC1_MISO_R2")
	)
	(segment
		(start 189.3062 -193.543682)
		(end 188.725556 -192.963038)
		(width 0.13208)
		(layer "F.Cu")
		(net "SPI_BIC1_MISO_R2")
	)
	(segment
		(start 188.830712 -196.194172)
		(end 189.04331 -195.981574)
		(width 0.13208)
		(layer "F.Cu")
		(net "SPI_BIC1_MISO_R2")
	)
	(segment
		(start 272.271236 -191.08928)
		(end 282.173934 -193.05905)
		(width 0.13208)
		(layer "F.Cu")
		(net "SPI_BIC1_MISO_R2")
	)
	(segment
		(start 260.758432 -189.955424)
		(end 272.271236 -191.08928)
		(width 0.13208)
		(layer "F.Cu")
		(net "SPI_BIC1_MISO_R2")
	)
	(segment
		(start 189.3062 -195.346574)
		(end 189.3062 -193.543682)
		(width 0.13208)
		(layer "F.Cu")
		(net "SPI_BIC1_MISO_R2")
	)
	(segment
		(start 292.604952 -193.05905)
		(end 293.74719 -194.201288)
		(width 0.13208)
		(layer "F.Cu")
		(net "SPI_BIC1_MISO_R2")
	)
	(segment
		(start 189.04331 -195.981574)
		(end 189.3062 -195.346574)
		(width 0.13208)
		(layer "F.Cu")
		(net "SPI_BIC1_MISO_R2")
	)
	(segment
		(start 293.74719 -194.201288)
		(end 293.74719 -194.962018)
		(width 0.13208)
		(layer "F.Cu")
		(net "SPI_BIC1_MISO_R2")
	)
	(segment
		(start 282.173934 -193.05905)
		(end 292.604952 -193.05905)
		(width 0.13208)
		(layer "F.Cu")
		(net "SPI_BIC1_MISO_R2")
	)
	(segment
		(start 247.419876 -189.972696)
		(end 249.45086 -190.813944)
		(width 0.13208)
		(layer "F.Cu")
		(net "SPI_BIC1_MISO_R2")
	)
	(segment
		(start 247.2563 -189.80912)
		(end 247.419876 -189.972696)
		(width 0.13208)
		(layer "F.Cu")
		(net "SPI_BIC1_MISO_R2")
	)
	(segment
		(start 185.003694 -192.963038)
		(end 184.891934 -193.074798)
		(width 0.13208)
		(layer "F.Cu")
		(net "SPI_BIC1_MISO_R2")
	)
	(via
		(at 188.830712 -196.194172)
		(size 0.508)
		(drill 0.254)
		(layers "F.Cu" "B.Cu")
		(net "SPI_BIC1_MISO_R2")
	)
	(via
		(at 224.314004 -194.595496)
		(size 0.508)
		(drill 0.254)
		(layers "F.Cu" "B.Cu")
		(net "SPI_BIC1_MISO_R2")
	)
	(via
		(at 247.2563 -189.80912)
		(size 0.508)
		(drill 0.254)
		(layers "F.Cu" "B.Cu")
		(net "SPI_BIC1_MISO_R2")
	)
	(segment
		(start 224.314004 -194.595496)
		(end 224.03562 -193.923666)
		(width 0.13208)
		(layer "B.Cu")
		(net "SPI_BIC1_MISO_R2")
	)
	(segment
		(start 224.03562 -193.923666)
		(end 223.533716 -193.421762)
		(width 0.13208)
		(layer "B.Cu")
		(net "SPI_BIC1_MISO_R2")
	)
	(segment
		(start 223.533716 -193.421762)
		(end 223.533716 -193.359786)
		(width 0.13208)
		(layer "B.Cu")
		(net "SPI_BIC1_MISO_R2")
	)
	(segment
		(start 227.461064 -192.49263)
		(end 229.710234 -190.24346)
		(width 0.15494)
		(layer "In13.Cu")
		(net "SPI_BIC1_MISO_R2")
	)
	(segment
		(start 213.98992 -199.2376)
		(end 213.76132 -199.009)
		(width 0.15494)
		(layer "In13.Cu")
		(net "SPI_BIC1_MISO_R2")
	)
	(segment
		(start 224.314004 -194.595496)
		(end 227.461064 -192.49263)
		(width 0.15494)
		(layer "In13.Cu")
		(net "SPI_BIC1_MISO_R2")
	)
	(segment
		(start 229.839774 -190.156846)
		(end 233.538268 -188.624972)
		(width 0.15494)
		(layer "In13.Cu")
		(net "SPI_BIC1_MISO_R2")
	)
	(segment
		(start 224.314004 -194.595496)
		(end 222.29953 -196.60997)
		(width 0.15494)
		(layer "In13.Cu")
		(net "SPI_BIC1_MISO_R2")
	)
	(segment
		(start 220.673422 -197.283578)
		(end 219.253054 -198.703946)
		(width 0.15494)
		(layer "In13.Cu")
		(net "SPI_BIC1_MISO_R2")
	)
	(segment
		(start 219.253054 -198.703946)
		(end 217.964258 -199.2376)
		(width 0.15494)
		(layer "In13.Cu")
		(net "SPI_BIC1_MISO_R2")
	)
	(segment
		(start 213.76132 -199.009)
		(end 210.17992 -199.009)
		(width 0.15494)
		(layer "In13.Cu")
		(net "SPI_BIC1_MISO_R2")
	)
	(segment
		(start 208.413858 -199.4916)
		(end 191.835786 -196.194172)
		(width 0.15494)
		(layer "In13.Cu")
		(net "SPI_BIC1_MISO_R2")
	)
	(segment
		(start 191.835786 -196.194172)
		(end 188.830712 -196.194172)
		(width 0.15494)
		(layer "In13.Cu")
		(net "SPI_BIC1_MISO_R2")
	)
	(segment
		(start 229.710234 -190.24346)
		(end 229.839774 -190.156846)
		(width 0.15494)
		(layer "In13.Cu")
		(net "SPI_BIC1_MISO_R2")
	)
	(segment
		(start 238.896144 -188.624972)
		(end 240.922048 -190.6524)
		(width 0.15494)
		(layer "In13.Cu")
		(net "SPI_BIC1_MISO_R2")
	)
	(segment
		(start 233.538268 -188.624972)
		(end 238.896144 -188.624972)
		(width 0.15494)
		(layer "In13.Cu")
		(net "SPI_BIC1_MISO_R2")
	)
	(segment
		(start 245.22049 -190.6524)
		(end 247.2563 -189.80912)
		(width 0.15494)
		(layer "In13.Cu")
		(net "SPI_BIC1_MISO_R2")
	)
	(segment
		(start 209.69732 -199.4916)
		(end 208.413858 -199.4916)
		(width 0.15494)
		(layer "In13.Cu")
		(net "SPI_BIC1_MISO_R2")
	)
	(segment
		(start 217.964258 -199.2376)
		(end 213.98992 -199.2376)
		(width 0.15494)
		(layer "In13.Cu")
		(net "SPI_BIC1_MISO_R2")
	)
	(segment
		(start 222.29953 -196.60997)
		(end 220.673422 -197.283578)
		(width 0.15494)
		(layer "In13.Cu")
		(net "SPI_BIC1_MISO_R2")
	)
	(segment
		(start 240.922048 -190.6524)
		(end 245.22049 -190.6524)
		(width 0.15494)
		(layer "In13.Cu")
		(net "SPI_BIC1_MISO_R2")
	)
	(segment
		(start 210.17992 -199.009)
		(end 209.69732 -199.4916)
		(width 0.15494)
		(layer "In13.Cu")
		(net "SPI_BIC1_MISO_R2")
	)
	(segment
		(start 188.063124 -194.090798)
		(end 188.465968 -193.92392)
		(width 0.13208)
		(layer "F.Cu")
		(net "SPI_BIC1_MOSI_R2")
	)
	(segment
		(start 283.062426 -192.340738)
		(end 292.277546 -192.340738)
		(width 0.13208)
		(layer "F.Cu")
		(net "SPI_BIC1_MOSI_R2")
	)
	(segment
		(start 292.277546 -192.340738)
		(end 293.247572 -192.742566)
		(width 0.13208)
		(layer "F.Cu")
		(net "SPI_BIC1_MOSI_R2")
	)
	(segment
		(start 293.247572 -192.742566)
		(end 294.26535 -193.760344)
		(width 0.13208)
		(layer "F.Cu")
		(net "SPI_BIC1_MOSI_R2")
	)
	(segment
		(start 294.26535 -193.760344)
		(end 294.76319 -194.962018)
		(width 0.13208)
		(layer "F.Cu")
		(net "SPI_BIC1_MOSI_R2")
	)
	(segment
		(start 250.815094 -189.432184)
		(end 260.681978 -189.432184)
		(width 0.13208)
		(layer "F.Cu")
		(net "SPI_BIC1_MOSI_R2")
	)
	(segment
		(start 260.681978 -189.432184)
		(end 276.048216 -190.945516)
		(width 0.13208)
		(layer "F.Cu")
		(net "SPI_BIC1_MOSI_R2")
	)
	(segment
		(start 184.891934 -194.090798)
		(end 188.063124 -194.090798)
		(width 0.13208)
		(layer "F.Cu")
		(net "SPI_BIC1_MOSI_R2")
	)
	(segment
		(start 276.048216 -190.945516)
		(end 283.062426 -192.340738)
		(width 0.13208)
		(layer "F.Cu")
		(net "SPI_BIC1_MOSI_R2")
	)
	(via
		(at 188.465968 -193.92392)
		(size 0.508)
		(drill 0.254)
		(layers "F.Cu" "B.Cu")
		(net "SPI_BIC1_MOSI_R2")
	)
	(via
		(at 250.815094 -189.432184)
		(size 0.508)
		(drill 0.254)
		(layers "F.Cu" "B.Cu")
		(net "SPI_BIC1_MOSI_R2")
	)
	(via
		(at 220.80855 -193.359786)
		(size 0.508)
		(drill 0.254)
		(layers "F.Cu" "B.Cu")
		(net "SPI_BIC1_MOSI_R2")
	)
	(segment
		(start 222.212154 -193.359786)
		(end 220.80855 -193.359786)
		(width 0.13208)
		(layer "B.Cu")
		(net "SPI_BIC1_MOSI_R2")
	)
	(segment
		(start 201.498708 -192.97777)
		(end 201.498708 -191.973962)
		(width 0.15494)
		(layer "In13.Cu")
		(net "SPI_BIC1_MOSI_R2")
	)
	(segment
		(start 218.136978 -190.3984)
		(end 216.196164 -191.20231)
		(width 0.15494)
		(layer "In13.Cu")
		(net "SPI_BIC1_MOSI_R2")
	)
	(segment
		(start 202.275948 -191.839342)
		(end 202.141328 -191.973962)
		(width 0.15494)
		(layer "In13.Cu")
		(net "SPI_BIC1_MOSI_R2")
	)
	(segment
		(start 220.218 -192.769236)
		(end 220.218 -190.754)
		(width 0.15494)
		(layer "In13.Cu")
		(net "SPI_BIC1_MOSI_R2")
	)
	(segment
		(start 188.465968 -193.91249)
		(end 188.465968 -193.92392)
		(width 0.15494)
		(layer "In13.Cu")
		(net "SPI_BIC1_MOSI_R2")
	)
	(segment
		(start 208.321402 -194.927728)
		(end 206.974948 -194.927728)
		(width 0.15494)
		(layer "In13.Cu")
		(net "SPI_BIC1_MOSI_R2")
	)
	(segment
		(start 210.423506 -193.712592)
		(end 210.041236 -193.712592)
		(width 0.15494)
		(layer "In13.Cu")
		(net "SPI_BIC1_MOSI_R2")
	)
	(segment
		(start 202.783948 -192.97777)
		(end 202.783948 -191.973962)
		(width 0.15494)
		(layer "In13.Cu")
		(net "SPI_BIC1_MOSI_R2")
	)
	(segment
		(start 233.326178 -187.299092)
		(end 233.386376 -187.2742)
		(width 0.15494)
		(layer "In13.Cu")
		(net "SPI_BIC1_MOSI_R2")
	)
	(segment
		(start 202.006708 -193.11239)
		(end 201.633328 -193.11239)
		(width 0.15494)
		(layer "In13.Cu")
		(net "SPI_BIC1_MOSI_R2")
	)
	(segment
		(start 202.649328 -191.839342)
		(end 202.275948 -191.839342)
		(width 0.15494)
		(layer "In13.Cu")
		(net "SPI_BIC1_MOSI_R2")
	)
	(segment
		(start 206.974948 -194.927728)
		(end 205.15961 -193.11239)
		(width 0.15494)
		(layer "In13.Cu")
		(net "SPI_BIC1_MOSI_R2")
	)
	(segment
		(start 221.425008 -193.237104)
		(end 224.29724 -192.047114)
		(width 0.15494)
		(layer "In13.Cu")
		(net "SPI_BIC1_MOSI_R2")
	)
	(segment
		(start 243.962428 -187.2742)
		(end 249.82297 -188.44006)
		(width 0.15494)
		(layer "In13.Cu")
		(net "SPI_BIC1_MOSI_R2")
	)
	(segment
		(start 202.783948 -191.973962)
		(end 202.649328 -191.839342)
		(width 0.15494)
		(layer "In13.Cu")
		(net "SPI_BIC1_MOSI_R2")
	)
	(segment
		(start 209.179668 -194.069462)
		(end 208.321402 -194.927728)
		(width 0.15494)
		(layer "In13.Cu")
		(net "SPI_BIC1_MOSI_R2")
	)
	(segment
		(start 200.856088 -192.97777)
		(end 200.721468 -193.11239)
		(width 0.15494)
		(layer "In13.Cu")
		(net "SPI_BIC1_MOSI_R2")
	)
	(segment
		(start 229.211378 -188.981334)
		(end 233.274108 -187.299092)
		(width 0.15494)
		(layer "In13.Cu")
		(net "SPI_BIC1_MOSI_R2")
	)
	(segment
		(start 189.266068 -193.11239)
		(end 188.465968 -193.91249)
		(width 0.15494)
		(layer "In13.Cu")
		(net "SPI_BIC1_MOSI_R2")
	)
	(segment
		(start 249.82297 -188.44006)
		(end 250.815094 -189.432184)
		(width 0.15494)
		(layer "In13.Cu")
		(net "SPI_BIC1_MOSI_R2")
	)
	(segment
		(start 224.29724 -192.047114)
		(end 228.266752 -189.394846)
		(width 0.15494)
		(layer "In13.Cu")
		(net "SPI_BIC1_MOSI_R2")
	)
	(segment
		(start 220.80855 -193.359786)
		(end 220.218 -192.769236)
		(width 0.15494)
		(layer "In13.Cu")
		(net "SPI_BIC1_MOSI_R2")
	)
	(segment
		(start 233.386376 -187.2742)
		(end 243.962428 -187.2742)
		(width 0.15494)
		(layer "In13.Cu")
		(net "SPI_BIC1_MOSI_R2")
	)
	(segment
		(start 200.990708 -191.839342)
		(end 200.856088 -191.973962)
		(width 0.15494)
		(layer "In13.Cu")
		(net "SPI_BIC1_MOSI_R2")
	)
	(segment
		(start 228.266752 -189.394846)
		(end 229.123748 -189.039754)
		(width 0.15494)
		(layer "In13.Cu")
		(net "SPI_BIC1_MOSI_R2")
	)
	(segment
		(start 220.218 -190.754)
		(end 219.8624 -190.3984)
		(width 0.15494)
		(layer "In13.Cu")
		(net "SPI_BIC1_MOSI_R2")
	)
	(segment
		(start 216.196164 -191.20231)
		(end 212.933788 -191.20231)
		(width 0.15494)
		(layer "In13.Cu")
		(net "SPI_BIC1_MOSI_R2")
	)
	(segment
		(start 220.80855 -193.359786)
		(end 221.425008 -193.237104)
		(width 0.15494)
		(layer "In13.Cu")
		(net "SPI_BIC1_MOSI_R2")
	)
	(segment
		(start 233.274108 -187.299092)
		(end 233.326178 -187.299092)
		(width 0.15494)
		(layer "In13.Cu")
		(net "SPI_BIC1_MOSI_R2")
	)
	(segment
		(start 201.633328 -193.11239)
		(end 201.498708 -192.97777)
		(width 0.15494)
		(layer "In13.Cu")
		(net "SPI_BIC1_MOSI_R2")
	)
	(segment
		(start 200.856088 -191.973962)
		(end 200.856088 -192.97777)
		(width 0.15494)
		(layer "In13.Cu")
		(net "SPI_BIC1_MOSI_R2")
	)
	(segment
		(start 219.8624 -190.3984)
		(end 218.136978 -190.3984)
		(width 0.15494)
		(layer "In13.Cu")
		(net "SPI_BIC1_MOSI_R2")
	)
	(segment
		(start 201.498708 -191.973962)
		(end 201.364088 -191.839342)
		(width 0.15494)
		(layer "In13.Cu")
		(net "SPI_BIC1_MOSI_R2")
	)
	(segment
		(start 202.918568 -193.11239)
		(end 202.783948 -192.97777)
		(width 0.15494)
		(layer "In13.Cu")
		(net "SPI_BIC1_MOSI_R2")
	)
	(segment
		(start 229.123748 -189.039754)
		(end 229.211378 -188.981334)
		(width 0.15494)
		(layer "In13.Cu")
		(net "SPI_BIC1_MOSI_R2")
	)
	(segment
		(start 202.141328 -191.973962)
		(end 202.141328 -192.97777)
		(width 0.15494)
		(layer "In13.Cu")
		(net "SPI_BIC1_MOSI_R2")
	)
	(segment
		(start 202.141328 -192.97777)
		(end 202.006708 -193.11239)
		(width 0.15494)
		(layer "In13.Cu")
		(net "SPI_BIC1_MOSI_R2")
	)
	(segment
		(start 210.041236 -193.712592)
		(end 209.179668 -194.069462)
		(width 0.15494)
		(layer "In13.Cu")
		(net "SPI_BIC1_MOSI_R2")
	)
	(segment
		(start 200.721468 -193.11239)
		(end 189.266068 -193.11239)
		(width 0.15494)
		(layer "In13.Cu")
		(net "SPI_BIC1_MOSI_R2")
	)
	(segment
		(start 212.933788 -191.20231)
		(end 210.423506 -193.712592)
		(width 0.15494)
		(layer "In13.Cu")
		(net "SPI_BIC1_MOSI_R2")
	)
	(segment
		(start 201.364088 -191.839342)
		(end 200.990708 -191.839342)
		(width 0.15494)
		(layer "In13.Cu")
		(net "SPI_BIC1_MOSI_R2")
	)
	(segment
		(start 205.15961 -193.11239)
		(end 202.918568 -193.11239)
		(width 0.15494)
		(layer "In13.Cu")
		(net "SPI_BIC1_MOSI_R2")
	)
	(segment
		(start 181.570884 -196.183758)
		(end 181.636924 -196.249798)
		(width 0.13208)
		(layer "F.Cu")
		(net "SPI_BIC1_CS0_R2_N")
	)
	(segment
		(start 180.135276 -196.183758)
		(end 181.570884 -196.183758)
		(width 0.13208)
		(layer "F.Cu")
		(net "SPI_BIC1_CS0_R2_N")
	)
	(segment
		(start 181.636924 -196.249798)
		(end 182.840884 -196.249798)
		(width 0.13208)
		(layer "F.Cu")
		(net "SPI_BIC1_CS0_R2_N")
	)
	(segment
		(start 183.964834 -196.249798)
		(end 184.091834 -196.122798)
		(width 0.13208)
		(layer "F.Cu")
		(net "SPI_BIC1_CS0_R2_N")
	)
	(segment
		(start 182.840884 -196.249798)
		(end 183.964834 -196.249798)
		(width 0.13208)
		(layer "F.Cu")
		(net "SPI_BIC1_CS0_R2_N")
	)
	(via
		(at 182.840884 -196.249798)
		(size 0.762)
		(drill 0.381)
		(layers "F.Cu" "B.Cu")
		(net "SPI_BIC1_CS0_R2_N")
	)
	(segment
		(start 181.951884 -195.233798)
		(end 181.65191 -195.533772)
		(width 0.13208)
		(layer "F.Cu")
		(net "SPI_BIC1_CLK_R3")
	)
	(segment
		(start 181.65191 -195.533772)
		(end 180.135276 -195.533772)
		(width 0.13208)
		(layer "F.Cu")
		(net "SPI_BIC1_CLK_R3")
	)
	(segment
		(start 183.964834 -195.233798)
		(end 181.951884 -195.233798)
		(width 0.13208)
		(layer "F.Cu")
		(net "SPI_BIC1_CLK_R3")
	)
	(segment
		(start 184.091834 -195.106798)
		(end 183.964834 -195.233798)
		(width 0.13208)
		(layer "F.Cu")
		(net "SPI_BIC1_CLK_R3")
	)
	(via
		(at 181.951884 -195.233798)
		(size 0.762)
		(drill 0.381)
		(layers "F.Cu" "B.Cu")
		(net "SPI_BIC1_CLK_R3")
	)
	(segment
		(start 181.1528 -194.635882)
		(end 181.697884 -194.090798)
		(width 0.13208)
		(layer "F.Cu")
		(net "SPI_BIC1_MOSI_R3")
	)
	(segment
		(start 180.555138 -194.883532)
		(end 181.1528 -194.635882)
		(width 0.13208)
		(layer "F.Cu")
		(net "SPI_BIC1_MOSI_R3")
	)
	(segment
		(start 181.697884 -194.090798)
		(end 182.840884 -194.090798)
		(width 0.13208)
		(layer "F.Cu")
		(net "SPI_BIC1_MOSI_R3")
	)
	(segment
		(start 182.840884 -194.090798)
		(end 184.091834 -194.090798)
		(width 0.13208)
		(layer "F.Cu")
		(net "SPI_BIC1_MOSI_R3")
	)
	(segment
		(start 180.135276 -194.883532)
		(end 180.555138 -194.883532)
		(width 0.13208)
		(layer "F.Cu")
		(net "SPI_BIC1_MOSI_R3")
	)
	(via
		(at 182.840884 -194.090798)
		(size 0.762)
		(drill 0.381)
		(layers "F.Cu" "B.Cu")
		(net "SPI_BIC1_MOSI_R3")
	)
	(segment
		(start 181.951884 -193.074798)
		(end 180.793136 -194.233546)
		(width 0.13208)
		(layer "F.Cu")
		(net "SPI_BIC1_MISO_R3")
	)
	(segment
		(start 180.793136 -194.233546)
		(end 180.135276 -194.233546)
		(width 0.13208)
		(layer "F.Cu")
		(net "SPI_BIC1_MISO_R3")
	)
	(segment
		(start 184.091834 -193.074798)
		(end 181.951884 -193.074798)
		(width 0.13208)
		(layer "F.Cu")
		(net "SPI_BIC1_MISO_R3")
	)
	(via
		(at 181.951884 -193.074798)
		(size 0.762)
		(drill 0.381)
		(layers "F.Cu" "B.Cu")
		(net "SPI_BIC1_MISO_R3")
	)
	(segment
		(start 166.730934 -193.836798)
		(end 167.981884 -193.836798)
		(width 0.13208)
		(layer "F.Cu")
		(net "SPI_BIC1_MISO_LS01_R")
	)
	(segment
		(start 166.730934 -192.820798)
		(end 166.730934 -193.836798)
		(width 0.13208)
		(layer "F.Cu")
		(net "SPI_BIC1_MISO_LS01_R")
	)
	(segment
		(start 167.981884 -193.836798)
		(end 169.359834 -193.836798)
		(width 0.13208)
		(layer "F.Cu")
		(net "SPI_BIC1_MISO_LS01_R")
	)
	(via
		(at 167.981884 -193.836798)
		(size 0.762)
		(drill 0.381)
		(layers "F.Cu" "B.Cu")
		(net "SPI_BIC1_MISO_LS01_R")
	)
	(segment
		(start 167.981884 -195.868798)
		(end 166.730934 -195.868798)
		(width 0.13208)
		(layer "F.Cu")
		(net "SPI_BIC1_MOSI_LS01_R")
	)
	(segment
		(start 166.730934 -194.852798)
		(end 166.730934 -195.868798)
		(width 0.13208)
		(layer "F.Cu")
		(net "SPI_BIC1_MOSI_LS01_R")
	)
	(segment
		(start 169.359834 -195.868798)
		(end 167.981884 -195.868798)
		(width 0.13208)
		(layer "F.Cu")
		(net "SPI_BIC1_MOSI_LS01_R")
	)
	(via
		(at 167.981884 -195.868798)
		(size 0.762)
		(drill 0.381)
		(layers "F.Cu" "B.Cu")
		(net "SPI_BIC1_MOSI_LS01_R")
	)
	(segment
		(start 168.108884 -197.900798)
		(end 169.359834 -197.900798)
		(width 0.13208)
		(layer "F.Cu")
		(net "SPI_BIC1_CLK_LS01_R")
	)
	(segment
		(start 166.730934 -197.900798)
		(end 168.108884 -197.900798)
		(width 0.13208)
		(layer "F.Cu")
		(net "SPI_BIC1_CLK_LS01_R")
	)
	(segment
		(start 166.730934 -197.900798)
		(end 166.730934 -196.884798)
		(width 0.13208)
		(layer "F.Cu")
		(net "SPI_BIC1_CLK_LS01_R")
	)
	(via
		(at 168.108884 -197.900798)
		(size 0.762)
		(drill 0.381)
		(layers "F.Cu" "B.Cu")
		(net "SPI_BIC1_CLK_LS01_R")
	)
	(segment
		(start 166.730934 -198.916798)
		(end 166.730934 -199.932798)
		(width 0.13208)
		(layer "F.Cu")
		(net "SPI_BIC1_CS0_LS01_R_N")
	)
	(segment
		(start 169.359834 -199.932798)
		(end 167.981884 -199.932798)
		(width 0.13208)
		(layer "F.Cu")
		(net "SPI_BIC1_CS0_LS01_R_N")
	)
	(segment
		(start 167.981884 -199.932798)
		(end 166.730934 -199.932798)
		(width 0.13208)
		(layer "F.Cu")
		(net "SPI_BIC1_CS0_LS01_R_N")
	)
	(via
		(at 167.981884 -199.932798)
		(size 0.762)
		(drill 0.381)
		(layers "F.Cu" "B.Cu")
		(net "SPI_BIC1_CS0_LS01_R_N")
	)
	(segment
		(start 170.159934 -193.836798)
		(end 171.410884 -193.836798)
		(width 0.13208)
		(layer "F.Cu")
		(net "SPI_BIC1_MISO_LS01")
	)
	(segment
		(start 171.410884 -193.836798)
		(end 172.55363 -193.836798)
		(width 0.13208)
		(layer "F.Cu")
		(net "SPI_BIC1_MISO_LS01")
	)
	(segment
		(start 172.950378 -194.233546)
		(end 174.535084 -194.233546)
		(width 0.13208)
		(layer "F.Cu")
		(net "SPI_BIC1_MISO_LS01")
	)
	(segment
		(start 172.55363 -193.836798)
		(end 172.950378 -194.233546)
		(width 0.13208)
		(layer "F.Cu")
		(net "SPI_BIC1_MISO_LS01")
	)
	(via
		(at 171.410884 -193.836798)
		(size 0.762)
		(drill 0.381)
		(layers "F.Cu" "B.Cu")
		(net "SPI_BIC1_MISO_LS01")
	)
	(segment
		(start 171.410884 -195.868798)
		(end 171.344082 -195.9356)
		(width 0.13208)
		(layer "F.Cu")
		(net "SPI_BIC1_MOSI_LS01")
	)
	(segment
		(start 171.344082 -195.9356)
		(end 170.226736 -195.9356)
		(width 0.13208)
		(layer "F.Cu")
		(net "SPI_BIC1_MOSI_LS01")
	)
	(segment
		(start 170.226736 -195.9356)
		(end 170.159934 -195.868798)
		(width 0.13208)
		(layer "F.Cu")
		(net "SPI_BIC1_MOSI_LS01")
	)
	(segment
		(start 174.535084 -194.883532)
		(end 172.39615 -194.883532)
		(width 0.13208)
		(layer "F.Cu")
		(net "SPI_BIC1_MOSI_LS01")
	)
	(segment
		(start 172.39615 -194.883532)
		(end 171.410884 -195.868798)
		(width 0.13208)
		(layer "F.Cu")
		(net "SPI_BIC1_MOSI_LS01")
	)
	(via
		(at 171.410884 -195.868798)
		(size 0.762)
		(drill 0.381)
		(layers "F.Cu" "B.Cu")
		(net "SPI_BIC1_MOSI_LS01")
	)
	(segment
		(start 223.886776 -369.026186)
		(end 223.835976 -369.076986)
		(width 0.254)
		(layer "F.Cu")
		(net "AGND_HSC")
	)
	(segment
		(start 202.252326 -364.885986)
		(end 202.252326 -365.632492)
		(width 0.2286)
		(layer "F.Cu")
		(net "AGND_HSC")
	)
	(segment
		(start 198.93661 -368.19205)
		(end 199.8599 -368.19205)
		(width 0.3556)
		(layer "F.Cu")
		(net "AGND_HSC")
	)
	(segment
		(start 203.543916 -375.584974)
		(end 203.694538 -375.434352)
		(width 0.3556)
		(layer "F.Cu")
		(net "AGND_HSC")
	)
	(segment
		(start 225.252026 -371.058186)
		(end 225.867976 -371.058186)
		(width 0.254)
		(layer "F.Cu")
		(net "AGND_HSC")
	)
	(segment
		(start 213.910926 -367.019586)
		(end 213.294976 -367.019586)
		(width 0.254)
		(layer "F.Cu")
		(net "AGND_HSC")
	)
	(segment
		(start 196.79539 -369.39347)
		(end 197.504558 -369.39347)
		(width 0.254)
		(layer "F.Cu")
		(net "AGND_HSC")
	)
	(segment
		(start 224.451926 -368.010186)
		(end 223.835976 -368.010186)
		(width 0.3556)
		(layer "F.Cu")
		(net "AGND_HSC")
	)
	(segment
		(start 224.451926 -365.978186)
		(end 223.835976 -365.978186)
		(width 0.254)
		(layer "F.Cu")
		(net "AGND_HSC")
	)
	(segment
		(start 215.098376 -369.400836)
		(end 215.784176 -369.400836)
		(width 0.3556)
		(layer "F.Cu")
		(net "AGND_HSC")
	)
	(segment
		(start 227.063808 -369.207542)
		(end 226.665028 -369.606322)
		(width 0.254)
		(layer "F.Cu")
		(net "AGND_HSC")
	)
	(segment
		(start 211.911438 -369.44935)
		(end 212.434424 -369.44935)
		(width 0.3556)
		(layer "F.Cu")
		(net "AGND_HSC")
	)
	(segment
		(start 224.445576 -368.976402)
		(end 224.395792 -369.026186)
		(width 0.254)
		(layer "F.Cu")
		(net "AGND_HSC")
	)
	(segment
		(start 201.763376 -364.885986)
		(end 202.252326 -364.885986)
		(width 0.3556)
		(layer "F.Cu")
		(net "AGND_HSC")
	)
	(segment
		(start 235.127038 -370.179854)
		(end 235.127038 -370.867686)
		(width 0.254)
		(layer "F.Cu")
		(net "AGND_HSC")
	)
	(segment
		(start 203.118466 -366.498632)
		(end 203.118466 -366.719612)
		(width 0.2286)
		(layer "F.Cu")
		(net "AGND_HSC")
	)
	(segment
		(start 198.93661 -366.665764)
		(end 198.93661 -368.19205)
		(width 0.3556)
		(layer "F.Cu")
		(net "AGND_HSC")
	)
	(segment
		(start 197.548246 -363.583728)
		(end 198.164196 -363.583728)
		(width 0.3556)
		(layer "F.Cu")
		(net "AGND_HSC")
	)
	(segment
		(start 215.97747 -369.207542)
		(end 217.388948 -369.207542)
		(width 0.254)
		(layer "F.Cu")
		(net "AGND_HSC")
	)
	(segment
		(start 226.55149 -369.606322)
		(end 226.528376 -369.629436)
		(width 0.254)
		(layer "F.Cu")
		(net "AGND_HSC")
	)
	(segment
		(start 212.434424 -369.44935)
		(end 212.77199 -369.111784)
		(width 0.3556)
		(layer "F.Cu")
		(net "AGND_HSC")
	)
	(segment
		(start 200.201022 -368.533172)
		(end 201.495152 -368.533172)
		(width 0.3556)
		(layer "F.Cu")
		(net "AGND_HSC")
	)
	(segment
		(start 197.504558 -369.39347)
		(end 197.720712 -369.609624)
		(width 0.254)
		(layer "F.Cu")
		(net "AGND_HSC")
	)
	(segment
		(start 213.907624 -365.978186)
		(end 213.294976 -365.978186)
		(width 0.254)
		(layer "F.Cu")
		(net "AGND_HSC")
	)
	(segment
		(start 224.395792 -369.026186)
		(end 223.886776 -369.026186)
		(width 0.254)
		(layer "F.Cu")
		(net "AGND_HSC")
	)
	(segment
		(start 203.694538 -375.434352)
		(end 203.694538 -374.412256)
		(width 0.3556)
		(layer "F.Cu")
		(net "AGND_HSC")
	)
	(segment
		(start 213.910926 -370.321586)
		(end 213.294976 -370.321586)
		(width 0.254)
		(layer "F.Cu")
		(net "AGND_HSC")
	)
	(segment
		(start 213.910926 -368.035586)
		(end 213.294976 -368.035586)
		(width 0.254)
		(layer "F.Cu")
		(net "AGND_HSC")
	)
	(segment
		(start 199.8599 -368.19205)
		(end 200.201022 -368.533172)
		(width 0.3556)
		(layer "F.Cu")
		(net "AGND_HSC")
	)
	(segment
		(start 198.164196 -365.615728)
		(end 197.548246 -365.615728)
		(width 0.3556)
		(layer "F.Cu")
		(net "AGND_HSC")
	)
	(segment
		(start 228.056948 -369.207542)
		(end 227.063808 -369.207542)
		(width 0.254)
		(layer "F.Cu")
		(net "AGND_HSC")
	)
	(segment
		(start 224.451926 -372.074186)
		(end 223.835976 -372.074186)
		(width 0.254)
		(layer "F.Cu")
		(net "AGND_HSC")
	)
	(segment
		(start 225.252026 -374.106186)
		(end 225.867976 -374.106186)
		(width 0.254)
		(layer "F.Cu")
		(net "AGND_HSC")
	)
	(segment
		(start 215.784176 -369.400836)
		(end 215.97747 -369.207542)
		(width 0.254)
		(layer "F.Cu")
		(net "AGND_HSC")
	)
	(segment
		(start 197.720712 -369.609624)
		(end 197.720712 -370.348764)
		(width 0.254)
		(layer "F.Cu")
		(net "AGND_HSC")
	)
	(segment
		(start 198.164196 -364.599728)
		(end 197.548246 -364.599728)
		(width 0.3556)
		(layer "F.Cu")
		(net "AGND_HSC")
	)
	(segment
		(start 204.051154 -374.05564)
		(end 204.472286 -374.05564)
		(width 0.3556)
		(layer "F.Cu")
		(net "AGND_HSC")
	)
	(segment
		(start 226.665028 -369.606322)
		(end 226.55149 -369.606322)
		(width 0.254)
		(layer "F.Cu")
		(net "AGND_HSC")
	)
	(segment
		(start 226.045776 -370.321586)
		(end 226.045776 -370.112036)
		(width 0.3556)
		(layer "F.Cu")
		(net "AGND_HSC")
	)
	(segment
		(start 198.967344 -366.63503)
		(end 198.93661 -366.665764)
		(width 0.3556)
		(layer "F.Cu")
		(net "AGND_HSC")
	)
	(segment
		(start 203.694538 -374.412256)
		(end 204.051154 -374.05564)
		(width 0.3556)
		(layer "F.Cu")
		(net "AGND_HSC")
	)
	(segment
		(start 202.252326 -365.632492)
		(end 203.118466 -366.498632)
		(width 0.2286)
		(layer "F.Cu")
		(net "AGND_HSC")
	)
	(segment
		(start 198.164196 -363.583728)
		(end 198.164196 -362.567728)
		(width 0.3556)
		(layer "F.Cu")
		(net "AGND_HSC")
	)
	(segment
		(start 201.610976 -365.038386)
		(end 201.763376 -364.885986)
		(width 0.3556)
		(layer "F.Cu")
		(net "AGND_HSC")
	)
	(segment
		(start 226.045776 -370.112036)
		(end 226.528376 -369.629436)
		(width 0.3556)
		(layer "F.Cu")
		(net "AGND_HSC")
	)
	(segment
		(start 201.694034 -368.732054)
		(end 201.495152 -368.533172)
		(width 0.254)
		(layer "F.Cu")
		(net "AGND_HSC")
	)
	(segment
		(start 202.130914 -368.732054)
		(end 201.694034 -368.732054)
		(width 0.2032)
		(layer "F.Cu")
		(net "AGND_HSC")
	)
	(segment
		(start 234.899962 -373.9134)
		(end 234.899962 -374.584722)
		(width 0.254)
		(layer "F.Cu")
		(net "AGND_HSC")
	)
	(via
		(at 215.098376 -369.400836)
		(size 0.508)
		(drill 0.254)
		(layers "F.Cu" "B.Cu")
		(net "AGND_HSC")
	)
	(via
		(at 203.543916 -375.584974)
		(size 0.508)
		(drill 0.254)
		(layers "F.Cu" "B.Cu")
		(net "AGND_HSC")
	)
	(via
		(at 213.294976 -367.019586)
		(size 0.508)
		(drill 0.254)
		(layers "F.Cu" "B.Cu")
		(net "AGND_HSC")
	)
	(via
		(at 213.294976 -370.321586)
		(size 0.508)
		(drill 0.254)
		(layers "F.Cu" "B.Cu")
		(net "AGND_HSC")
	)
	(via
		(at 225.867976 -371.058186)
		(size 0.508)
		(drill 0.254)
		(layers "F.Cu" "B.Cu")
		(net "AGND_HSC")
	)
	(via
		(at 202.960478 -369.828064)
		(size 0.508)
		(drill 0.254)
		(layers "F.Cu" "B.Cu")
		(net "AGND_HSC")
	)
	(via
		(at 223.835976 -369.076986)
		(size 0.508)
		(drill 0.254)
		(layers "F.Cu" "B.Cu")
		(net "AGND_HSC")
	)
	(via
		(at 226.045776 -370.321586)
		(size 0.508)
		(drill 0.254)
		(layers "F.Cu" "B.Cu")
		(net "AGND_HSC")
	)
	(via
		(at 197.548246 -365.615728)
		(size 0.508)
		(drill 0.254)
		(layers "F.Cu" "B.Cu")
		(net "AGND_HSC")
	)
	(via
		(at 223.835976 -368.010186)
		(size 0.508)
		(drill 0.254)
		(layers "F.Cu" "B.Cu")
		(net "AGND_HSC")
	)
	(via
		(at 203.468478 -370.336064)
		(size 0.508)
		(drill 0.254)
		(layers "F.Cu" "B.Cu")
		(net "AGND_HSC")
	)
	(via
		(at 197.548246 -363.583728)
		(size 0.508)
		(drill 0.254)
		(layers "F.Cu" "B.Cu")
		(net "AGND_HSC")
	)
	(via
		(at 201.610976 -365.038386)
		(size 0.508)
		(drill 0.254)
		(layers "F.Cu" "B.Cu")
		(net "AGND_HSC")
	)
	(via
		(at 235.127038 -370.867686)
		(size 0.508)
		(drill 0.254)
		(layers "F.Cu" "B.Cu")
		(net "AGND_HSC")
	)
	(via
		(at 212.77199 -369.111784)
		(size 0.508)
		(drill 0.254)
		(layers "F.Cu" "B.Cu")
		(net "AGND_HSC")
	)
	(via
		(at 225.867976 -374.106186)
		(size 0.508)
		(drill 0.254)
		(layers "F.Cu" "B.Cu")
		(net "AGND_HSC")
	)
	(via
		(at 213.294976 -368.035586)
		(size 0.508)
		(drill 0.254)
		(layers "F.Cu" "B.Cu")
		(net "AGND_HSC")
	)
	(via
		(at 223.835976 -365.978186)
		(size 0.508)
		(drill 0.254)
		(layers "F.Cu" "B.Cu")
		(net "AGND_HSC")
	)
	(via
		(at 203.976478 -369.828064)
		(size 0.508)
		(drill 0.254)
		(layers "F.Cu" "B.Cu")
		(net "AGND_HSC")
	)
	(via
		(at 197.720712 -369.609624)
		(size 0.508)
		(drill 0.254)
		(layers "F.Cu" "B.Cu")
		(net "AGND_HSC")
	)
	(via
		(at 223.835976 -372.074186)
		(size 0.508)
		(drill 0.254)
		(layers "F.Cu" "B.Cu")
		(net "AGND_HSC")
	)
	(via
		(at 201.495152 -368.533172)
		(size 0.508)
		(drill 0.254)
		(layers "F.Cu" "B.Cu")
		(net "AGND_HSC")
	)
	(via
		(at 213.294976 -365.978186)
		(size 0.508)
		(drill 0.254)
		(layers "F.Cu" "B.Cu")
		(net "AGND_HSC")
	)
	(via
		(at 197.548246 -364.599728)
		(size 0.508)
		(drill 0.254)
		(layers "F.Cu" "B.Cu")
		(net "AGND_HSC")
	)
	(via
		(at 234.899962 -374.584722)
		(size 0.508)
		(drill 0.254)
		(layers "F.Cu" "B.Cu")
		(net "AGND_HSC")
	)
	(segment
		(start 198.152004 -365.81207)
		(end 197.955662 -365.615728)
		(width 0.4572)
		(layer "B.Cu")
		(net "AGND_HSC")
	)
	(segment
		(start 202.233022 -364.80496)
		(end 201.999596 -365.038386)
		(width 0.3556)
		(layer "B.Cu")
		(net "AGND_HSC")
	)
	(segment
		(start 197.720712 -369.386104)
		(end 196.892418 -368.55781)
		(width 0.254)
		(layer "B.Cu")
		(net "AGND_HSC")
	)
	(segment
		(start 203.543916 -375.584974)
		(end 203.707492 -375.421398)
		(width 0.254)
		(layer "B.Cu")
		(net "AGND_HSC")
	)
	(segment
		(start 198.149718 -366.339628)
		(end 198.149718 -366.332008)
		(width 0.4572)
		(layer "B.Cu")
		(net "AGND_HSC")
	)
	(segment
		(start 197.720712 -369.609624)
		(end 197.720712 -369.386104)
		(width 0.254)
		(layer "B.Cu")
		(net "AGND_HSC")
	)
	(segment
		(start 201.999596 -365.038386)
		(end 201.610976 -365.038386)
		(width 0.3556)
		(layer "B.Cu")
		(net "AGND_HSC")
	)
	(segment
		(start 197.955662 -365.615728)
		(end 197.548246 -365.615728)
		(width 0.4572)
		(layer "B.Cu")
		(net "AGND_HSC")
	)
	(segment
		(start 198.149718 -366.332008)
		(end 198.152004 -366.329722)
		(width 0.4572)
		(layer "B.Cu")
		(net "AGND_HSC")
	)
	(segment
		(start 198.152004 -366.329722)
		(end 198.152004 -365.81207)
		(width 0.4572)
		(layer "B.Cu")
		(net "AGND_HSC")
	)
	(segment
		(start 203.707492 -375.421398)
		(end 203.707492 -374.431814)
		(width 0.254)
		(layer "B.Cu")
		(net "AGND_HSC")
	)
	(segment
		(start 196.892418 -368.55781)
		(end 196.689218 -368.55781)
		(width 0.254)
		(layer "B.Cu")
		(net "AGND_HSC")
	)
	(segment
		(start 173.103794 -195.894198)
		(end 171.537884 -197.900798)
		(width 0.13208)
		(layer "F.Cu")
		(net "SPI_BIC1_CLK_LS01")
	)
	(segment
		(start 173.61535 -195.533772)
		(end 173.103794 -195.894198)
		(width 0.13208)
		(layer "F.Cu")
		(net "SPI_BIC1_CLK_LS01")
	)
	(segment
		(start 171.537884 -197.900798)
		(end 170.159934 -197.900798)
		(width 0.13208)
		(layer "F.Cu")
		(net "SPI_BIC1_CLK_LS01")
	)
	(segment
		(start 174.535084 -195.533772)
		(end 173.61535 -195.533772)
		(width 0.13208)
		(layer "F.Cu")
		(net "SPI_BIC1_CLK_LS01")
	)
	(via
		(at 171.537884 -197.900798)
		(size 0.762)
		(drill 0.381)
		(layers "F.Cu" "B.Cu")
		(net "SPI_BIC1_CLK_LS01")
	)
	(segment
		(start 173.851824 -196.183758)
		(end 173.388528 -196.647054)
		(width 0.13208)
		(layer "F.Cu")
		(net "SPI_BIC1_CS0_LS01_N")
	)
	(segment
		(start 174.535084 -196.183758)
		(end 173.851824 -196.183758)
		(width 0.13208)
		(layer "F.Cu")
		(net "SPI_BIC1_CS0_LS01_N")
	)
	(segment
		(start 172.46346 -198.880222)
		(end 171.410884 -199.932798)
		(width 0.13208)
		(layer "F.Cu")
		(net "SPI_BIC1_CS0_LS01_N")
	)
	(segment
		(start 171.410884 -199.932798)
		(end 170.159934 -199.932798)
		(width 0.13208)
		(layer "F.Cu")
		(net "SPI_BIC1_CS0_LS01_N")
	)
	(segment
		(start 173.388528 -196.647054)
		(end 172.46346 -198.880222)
		(width 0.13208)
		(layer "F.Cu")
		(net "SPI_BIC1_CS0_LS01_N")
	)
	(via
		(at 171.410884 -199.932798)
		(size 0.762)
		(drill 0.381)
		(layers "F.Cu" "B.Cu")
		(net "SPI_BIC1_CS0_LS01_N")
	)
	(segment
		(start 214.194136 -181.213506)
		(end 214.194136 -180.248306)
		(width 0.13208)
		(layer "F.Cu")
		(net "SEL_FLASH_PEX1_BUF_R")
	)
	(segment
		(start 206.191104 -180.84673)
		(end 208.873852 -178.163982)
		(width 0.13208)
		(layer "F.Cu")
		(net "SEL_FLASH_PEX1_BUF_R")
	)
	(segment
		(start 188.050678 -187.945776)
		(end 189.052708 -187.945776)
		(width 0.13208)
		(layer "F.Cu")
		(net "SEL_FLASH_PEX1_BUF_R")
	)
	(segment
		(start 210.558126 -178.506628)
		(end 213.388194 -178.506628)
		(width 0.13208)
		(layer "F.Cu")
		(net "SEL_FLASH_PEX1_BUF_R")
	)
	(segment
		(start 214.194136 -180.248306)
		(end 214.279988 -180.162454)
		(width 0.13208)
		(layer "F.Cu")
		(net "SEL_FLASH_PEX1_BUF_R")
	)
	(segment
		(start 213.388194 -178.506628)
		(end 213.707218 -178.825652)
		(width 0.13208)
		(layer "F.Cu")
		(net "SEL_FLASH_PEX1_BUF_R")
	)
	(segment
		(start 210.21548 -178.163982)
		(end 210.558126 -178.506628)
		(width 0.13208)
		(layer "F.Cu")
		(net "SEL_FLASH_PEX1_BUF_R")
	)
	(segment
		(start 214.521288 -180.162454)
		(end 214.829136 -179.854606)
		(width 0.13208)
		(layer "F.Cu")
		(net "SEL_FLASH_PEX1_BUF_R")
	)
	(segment
		(start 208.873852 -178.163982)
		(end 210.21548 -178.163982)
		(width 0.13208)
		(layer "F.Cu")
		(net "SEL_FLASH_PEX1_BUF_R")
	)
	(segment
		(start 214.279988 -180.162454)
		(end 214.521288 -180.162454)
		(width 0.13208)
		(layer "F.Cu")
		(net "SEL_FLASH_PEX1_BUF_R")
	)
	(segment
		(start 213.707218 -180.121052)
		(end 213.834472 -180.248306)
		(width 0.13208)
		(layer "F.Cu")
		(net "SEL_FLASH_PEX1_BUF_R")
	)
	(segment
		(start 213.834472 -180.248306)
		(end 214.194136 -180.248306)
		(width 0.13208)
		(layer "F.Cu")
		(net "SEL_FLASH_PEX1_BUF_R")
	)
	(segment
		(start 213.707218 -178.825652)
		(end 213.707218 -180.121052)
		(width 0.13208)
		(layer "F.Cu")
		(net "SEL_FLASH_PEX1_BUF_R")
	)
	(segment
		(start 189.052708 -187.945776)
		(end 206.191104 -180.84673)
		(width 0.13208)
		(layer "F.Cu")
		(net "SEL_FLASH_PEX1_BUF_R")
	)
	(via
		(at 133.390386 -232.109772)
		(size 0.508)
		(drill 0.254)
		(layers "F.Cu" "B.Cu")
		(net "SEL_FLASH_PEX1_BUF_R")
	)
	(via
		(at 139.722098 -210.778344)
		(size 0.508)
		(drill 0.254)
		(layers "F.Cu" "B.Cu")
		(net "SEL_FLASH_PEX1_BUF_R")
	)
	(via
		(at 217.838528 -200.50379)
		(size 0.508)
		(drill 0.254)
		(layers "F.Cu" "B.Cu")
		(net "SEL_FLASH_PEX1_BUF_R")
	)
	(via
		(at 214.829136 -179.854606)
		(size 0.508)
		(drill 0.254)
		(layers "F.Cu" "B.Cu")
		(net "SEL_FLASH_PEX1_BUF_R")
	)
	(segment
		(start 133.390386 -231.140762)
		(end 133.595872 -230.935276)
		(width 0.13208)
		(layer "B.Cu")
		(net "SEL_FLASH_PEX1_BUF_R")
	)
	(segment
		(start 133.390386 -232.109772)
		(end 133.390386 -231.140762)
		(width 0.13208)
		(layer "B.Cu")
		(net "SEL_FLASH_PEX1_BUF_R")
	)
	(segment
		(start 133.595872 -230.935276)
		(end 133.595872 -229.827582)
		(width 0.13208)
		(layer "B.Cu")
		(net "SEL_FLASH_PEX1_BUF_R")
	)
	(segment
		(start 210.668616 -188.05271)
		(end 210.459066 -187.84316)
		(width 0.15494)
		(layer "In5.Cu")
		(net "SEL_FLASH_PEX1_BUF_R")
	)
	(segment
		(start 210.459066 -187.84316)
		(end 210.459066 -187.44184)
		(width 0.15494)
		(layer "In5.Cu")
		(net "SEL_FLASH_PEX1_BUF_R")
	)
	(segment
		(start 137.114026 -220.492828)
		(end 134.566406 -223.040448)
		(width 0.15494)
		(layer "In5.Cu")
		(net "SEL_FLASH_PEX1_BUF_R")
	)
	(segment
		(start 210.459066 -187.44184)
		(end 211.330032 -186.570874)
		(width 0.15494)
		(layer "In5.Cu")
		(net "SEL_FLASH_PEX1_BUF_R")
	)
	(segment
		(start 215.640666 -180.666136)
		(end 214.829136 -179.854606)
		(width 0.15494)
		(layer "In5.Cu")
		(net "SEL_FLASH_PEX1_BUF_R")
	)
	(segment
		(start 217.838528 -200.50379)
		(end 217.071448 -199.73671)
		(width 0.15494)
		(layer "In5.Cu")
		(net "SEL_FLASH_PEX1_BUF_R")
	)
	(segment
		(start 217.071448 -199.73671)
		(end 217.071448 -192.76568)
		(width 0.15494)
		(layer "In5.Cu")
		(net "SEL_FLASH_PEX1_BUF_R")
	)
	(segment
		(start 134.566406 -224.735644)
		(end 133.390386 -225.911664)
		(width 0.15494)
		(layer "In5.Cu")
		(net "SEL_FLASH_PEX1_BUF_R")
	)
	(segment
		(start 215.640666 -183.045354)
		(end 215.640666 -180.666136)
		(width 0.15494)
		(layer "In5.Cu")
		(net "SEL_FLASH_PEX1_BUF_R")
	)
	(segment
		(start 134.566406 -223.040448)
		(end 134.566406 -224.735644)
		(width 0.15494)
		(layer "In5.Cu")
		(net "SEL_FLASH_PEX1_BUF_R")
	)
	(segment
		(start 212.115146 -186.570874)
		(end 215.640666 -183.045354)
		(width 0.15494)
		(layer "In5.Cu")
		(net "SEL_FLASH_PEX1_BUF_R")
	)
	(segment
		(start 211.28863 -188.12637)
		(end 210.846162 -188.12637)
		(width 0.15494)
		(layer "In5.Cu")
		(net "SEL_FLASH_PEX1_BUF_R")
	)
	(segment
		(start 133.390386 -225.911664)
		(end 133.390386 -232.109772)
		(width 0.15494)
		(layer "In5.Cu")
		(net "SEL_FLASH_PEX1_BUF_R")
	)
	(segment
		(start 139.722098 -211.917788)
		(end 137.114026 -214.52586)
		(width 0.15494)
		(layer "In5.Cu")
		(net "SEL_FLASH_PEX1_BUF_R")
	)
	(segment
		(start 213.357968 -189.0522)
		(end 212.21446 -189.0522)
		(width 0.15494)
		(layer "In5.Cu")
		(net "SEL_FLASH_PEX1_BUF_R")
	)
	(segment
		(start 139.722098 -210.778344)
		(end 139.722098 -211.917788)
		(width 0.15494)
		(layer "In5.Cu")
		(net "SEL_FLASH_PEX1_BUF_R")
	)
	(segment
		(start 211.330032 -186.570874)
		(end 212.115146 -186.570874)
		(width 0.15494)
		(layer "In5.Cu")
		(net "SEL_FLASH_PEX1_BUF_R")
	)
	(segment
		(start 210.846162 -188.12637)
		(end 210.668616 -188.05271)
		(width 0.15494)
		(layer "In5.Cu")
		(net "SEL_FLASH_PEX1_BUF_R")
	)
	(segment
		(start 217.071448 -192.76568)
		(end 213.357968 -189.0522)
		(width 0.15494)
		(layer "In5.Cu")
		(net "SEL_FLASH_PEX1_BUF_R")
	)
	(segment
		(start 137.114026 -214.52586)
		(end 137.114026 -220.492828)
		(width 0.15494)
		(layer "In5.Cu")
		(net "SEL_FLASH_PEX1_BUF_R")
	)
	(segment
		(start 212.21446 -189.0522)
		(end 211.28863 -188.12637)
		(width 0.15494)
		(layer "In5.Cu")
		(net "SEL_FLASH_PEX1_BUF_R")
	)
	(segment
		(start 139.722098 -210.778344)
		(end 140.449554 -211.5058)
		(width 0.15494)
		(layer "In15.Cu")
		(net "SEL_FLASH_PEX1_BUF_R")
	)
	(segment
		(start 205.23454 -201.803)
		(end 212.01888 -201.803)
		(width 0.15494)
		(layer "In15.Cu")
		(net "SEL_FLASH_PEX1_BUF_R")
	)
	(segment
		(start 182.426864 -211.88934)
		(end 183.960516 -213.422992)
		(width 0.15494)
		(layer "In15.Cu")
		(net "SEL_FLASH_PEX1_BUF_R")
	)
	(segment
		(start 212.01888 -201.803)
		(end 213.851236 -199.970644)
		(width 0.15494)
		(layer "In15.Cu")
		(net "SEL_FLASH_PEX1_BUF_R")
	)
	(segment
		(start 183.960516 -213.422992)
		(end 193.614548 -213.422992)
		(width 0.15494)
		(layer "In15.Cu")
		(net "SEL_FLASH_PEX1_BUF_R")
	)
	(segment
		(start 213.851236 -199.970644)
		(end 217.305382 -199.970644)
		(width 0.15494)
		(layer "In15.Cu")
		(net "SEL_FLASH_PEX1_BUF_R")
	)
	(segment
		(start 217.305382 -199.970644)
		(end 217.838528 -200.50379)
		(width 0.15494)
		(layer "In15.Cu")
		(net "SEL_FLASH_PEX1_BUF_R")
	)
	(segment
		(start 193.614548 -213.422992)
		(end 205.23454 -201.803)
		(width 0.15494)
		(layer "In15.Cu")
		(net "SEL_FLASH_PEX1_BUF_R")
	)
	(segment
		(start 144.1577 -211.88934)
		(end 182.426864 -211.88934)
		(width 0.15494)
		(layer "In15.Cu")
		(net "SEL_FLASH_PEX1_BUF_R")
	)
	(segment
		(start 140.449554 -211.5058)
		(end 143.77416 -211.5058)
		(width 0.15494)
		(layer "In15.Cu")
		(net "SEL_FLASH_PEX1_BUF_R")
	)
	(segment
		(start 143.77416 -211.5058)
		(end 144.1577 -211.88934)
		(width 0.15494)
		(layer "In15.Cu")
		(net "SEL_FLASH_PEX1_BUF_R")
	)
	(via
		(at 364.453932 -225.491802)
		(size 0.6604)
		(drill 0.3302)
		(layers "F.Cu" "B.Cu")
		(net "SPI_MUX_PEX3_EN_N")
	)
	(segment
		(start 364.453932 -225.491802)
		(end 364.453932 -224.337118)
		(width 0.13208)
		(layer "B.Cu")
		(net "SPI_MUX_PEX3_EN_N")
	)
	(segment
		(start 366.430814 -225.23577)
		(end 366.174782 -225.491802)
		(width 0.13208)
		(layer "B.Cu")
		(net "SPI_MUX_PEX3_EN_N")
	)
	(segment
		(start 366.174782 -225.491802)
		(end 364.453932 -225.491802)
		(width 0.13208)
		(layer "B.Cu")
		(net "SPI_MUX_PEX3_EN_N")
	)
	(segment
		(start 366.430814 -224.341182)
		(end 366.430814 -225.23577)
		(width 0.13208)
		(layer "B.Cu")
		(net "SPI_MUX_PEX3_EN_N")
	)
	(via
		(at 15.012416 -223.561148)
		(size 0.6604)
		(drill 0.3302)
		(layers "F.Cu" "B.Cu")
		(net "SPI_PEX0_CLK_MUX")
	)
	(segment
		(start 15.012416 -225.96348)
		(end 16.201136 -227.1522)
		(width 0.13208)
		(layer "B.Cu")
		(net "SPI_PEX0_CLK_MUX")
	)
	(segment
		(start 21.343112 -227.591366)
		(end 21.343112 -229.827582)
		(width 0.13208)
		(layer "B.Cu")
		(net "SPI_PEX0_CLK_MUX")
	)
	(segment
		(start 15.012416 -222.040958)
		(end 15.012416 -223.561148)
		(width 0.13208)
		(layer "B.Cu")
		(net "SPI_PEX0_CLK_MUX")
	)
	(segment
		(start 15.012416 -223.561148)
		(end 15.012416 -225.96348)
		(width 0.13208)
		(layer "B.Cu")
		(net "SPI_PEX0_CLK_MUX")
	)
	(segment
		(start 20.903946 -227.1522)
		(end 21.343112 -227.591366)
		(width 0.13208)
		(layer "B.Cu")
		(net "SPI_PEX0_CLK_MUX")
	)
	(segment
		(start 16.201136 -227.1522)
		(end 20.903946 -227.1522)
		(width 0.13208)
		(layer "B.Cu")
		(net "SPI_PEX0_CLK_MUX")
	)
	(segment
		(start 391.799826 -293.99992)
		(end 391.324846 -293.52494)
		(width 0.13208)
		(layer "F.Cu")
		(net "SPI_PEX3_SDIO2")
	)
	(via
		(at 391.324846 -293.52494)
		(size 0.508)
		(drill 0.254)
		(layers "F.Cu" "B.Cu")
		(net "SPI_PEX3_SDIO2")
	)
	(segment
		(start 389.1915 -293.9542)
		(end 388.819136 -294.326564)
		(width 0.13208)
		(layer "B.Cu")
		(net "SPI_PEX3_SDIO2")
	)
	(segment
		(start 388.819136 -294.326564)
		(end 388.819136 -294.8051)
		(width 0.13208)
		(layer "B.Cu")
		(net "SPI_PEX3_SDIO2")
	)
	(segment
		(start 390.895586 -293.9542)
		(end 389.1915 -293.9542)
		(width 0.13208)
		(layer "B.Cu")
		(net "SPI_PEX3_SDIO2")
	)
	(segment
		(start 391.324846 -293.52494)
		(end 390.895586 -293.9542)
		(width 0.13208)
		(layer "B.Cu")
		(net "SPI_PEX3_SDIO2")
	)
	(segment
		(start 391.799826 -294.94988)
		(end 391.324846 -294.4749)
		(width 0.13208)
		(layer "F.Cu")
		(net "SPI_PEX3_SDIO1")
	)
	(via
		(at 391.324846 -294.4749)
		(size 0.4064)
		(drill 0.2032)
		(layers "F.Cu" "B.Cu")
		(net "SPI_PEX3_SDIO1")
	)
	(via
		(at 391.283698 -295.498774)
		(size 0.6604)
		(drill 0.3302)
		(layers "F.Cu" "B.Cu")
		(net "SPI_PEX3_SDIO1")
	)
	(segment
		(start 390.882632 -295.89984)
		(end 391.283698 -295.498774)
		(width 0.13208)
		(layer "B.Cu")
		(net "SPI_PEX3_SDIO1")
	)
	(segment
		(start 389.131302 -296.9514)
		(end 390.182862 -295.89984)
		(width 0.13208)
		(layer "B.Cu")
		(net "SPI_PEX3_SDIO1")
	)
	(segment
		(start 388.873746 -296.9514)
		(end 389.131302 -296.9514)
		(width 0.13208)
		(layer "B.Cu")
		(net "SPI_PEX3_SDIO1")
	)
	(segment
		(start 391.283698 -295.498774)
		(end 391.324846 -295.457626)
		(width 0.13208)
		(layer "B.Cu")
		(net "SPI_PEX3_SDIO1")
	)
	(segment
		(start 391.324846 -295.457626)
		(end 391.324846 -294.4749)
		(width 0.13208)
		(layer "B.Cu")
		(net "SPI_PEX3_SDIO1")
	)
	(segment
		(start 390.182862 -295.89984)
		(end 390.882632 -295.89984)
		(width 0.13208)
		(layer "B.Cu")
		(net "SPI_PEX3_SDIO1")
	)
	(segment
		(start 390.849866 -294.94988)
		(end 390.374886 -294.4749)
		(width 0.13208)
		(layer "F.Cu")
		(net "SPI_PEX3_SDIO0")
	)
	(via
		(at 390.374886 -294.4749)
		(size 0.508)
		(drill 0.254)
		(layers "F.Cu" "B.Cu")
		(net "SPI_PEX3_SDIO0")
	)
	(segment
		(start 390.374886 -294.4749)
		(end 390.374886 -295.106852)
		(width 0.13208)
		(layer "B.Cu")
		(net "SPI_PEX3_SDIO0")
	)
	(segment
		(start 390.374886 -295.106852)
		(end 389.683498 -295.79824)
		(width 0.13208)
		(layer "B.Cu")
		(net "SPI_PEX3_SDIO0")
	)
	(segment
		(start 389.683498 -295.79824)
		(end 388.873746 -295.79824)
		(width 0.13208)
		(layer "B.Cu")
		(net "SPI_PEX3_SDIO0")
	)
	(via
		(at 222.200978 -199.328278)
		(size 0.6604)
		(drill 0.3302)
		(layers "F.Cu" "B.Cu")
		(net "SPI_BIC1_MOSI_R")
	)
	(segment
		(start 222.200978 -199.328278)
		(end 222.7834 -198.745856)
		(width 0.13208)
		(layer "B.Cu")
		(net "SPI_BIC1_MOSI_R")
	)
	(segment
		(start 222.200978 -199.90181)
		(end 222.200978 -199.328278)
		(width 0.13208)
		(layer "B.Cu")
		(net "SPI_BIC1_MOSI_R")
	)
	(segment
		(start 222.7834 -197.646798)
		(end 222.528384 -197.391782)
		(width 0.13208)
		(layer "B.Cu")
		(net "SPI_BIC1_MOSI_R")
	)
	(segment
		(start 222.27413 -200.584054)
		(end 222.27413 -199.974962)
		(width 0.13208)
		(layer "B.Cu")
		(net "SPI_BIC1_MOSI_R")
	)
	(segment
		(start 222.7834 -198.745856)
		(end 222.7834 -197.646798)
		(width 0.13208)
		(layer "B.Cu")
		(net "SPI_BIC1_MOSI_R")
	)
	(segment
		(start 222.528384 -197.391782)
		(end 222.212154 -197.391782)
		(width 0.13208)
		(layer "B.Cu")
		(net "SPI_BIC1_MOSI_R")
	)
	(segment
		(start 222.27413 -199.974962)
		(end 222.200978 -199.90181)
		(width 0.13208)
		(layer "B.Cu")
		(net "SPI_BIC1_MOSI_R")
	)
	(segment
		(start 227.001324 -201.632566)
		(end 228.840284 -202.394312)
		(width 0.13208)
		(layer "F.Cu")
		(net "SPI_BIC1_CS0_R_N")
	)
	(segment
		(start 229.570026 -202.692508)
		(end 229.997 -203.119482)
		(width 0.13208)
		(layer "F.Cu")
		(net "SPI_BIC1_CS0_R_N")
	)
	(segment
		(start 229.997 -203.885546)
		(end 229.840536 -204.04201)
		(width 0.13208)
		(layer "F.Cu")
		(net "SPI_BIC1_CS0_R_N")
	)
	(segment
		(start 229.840536 -204.04201)
		(end 229.594664 -204.04201)
		(width 0.13208)
		(layer "F.Cu")
		(net "SPI_BIC1_CS0_R_N")
	)
	(segment
		(start 228.954584 -202.437492)
		(end 229.570026 -202.692508)
		(width 0.13208)
		(layer "F.Cu")
		(net "SPI_BIC1_CS0_R_N")
	)
	(segment
		(start 229.997 -203.119482)
		(end 229.997 -203.885546)
		(width 0.13208)
		(layer "F.Cu")
		(net "SPI_BIC1_CS0_R_N")
	)
	(segment
		(start 228.840284 -202.394312)
		(end 228.911404 -202.394312)
		(width 0.13208)
		(layer "F.Cu")
		(net "SPI_BIC1_CS0_R_N")
	)
	(segment
		(start 226.752912 -201.384154)
		(end 227.001324 -201.632566)
		(width 0.13208)
		(layer "F.Cu")
		(net "SPI_BIC1_CS0_R_N")
	)
	(segment
		(start 228.911404 -202.394312)
		(end 228.954584 -202.437492)
		(width 0.13208)
		(layer "F.Cu")
		(net "SPI_BIC1_CS0_R_N")
	)
	(via
		(at 228.911404 -202.394312)
		(size 0.762)
		(drill 0.381)
		(layers "F.Cu" "B.Cu")
		(net "SPI_BIC1_CS0_R_N")
	)
	(via
		(at 38.341808 -264.18921)
		(size 0.508)
		(drill 0.254)
		(layers "F.Cu" "B.Cu")
		(net "SPI_PEX0_SDIO0_R")
	)
	(via
		(at 21.102066 -225.68281)
		(size 0.508)
		(drill 0.254)
		(layers "F.Cu" "B.Cu")
		(net "SPI_PEX0_SDIO0_R")
	)
	(segment
		(start 35.230562 -289.714686)
		(end 35.230562 -292.341554)
		(width 0.13208)
		(layer "B.Cu")
		(net "SPI_PEX0_SDIO0_R")
	)
	(segment
		(start 20.708112 -225.288856)
		(end 21.102066 -225.68281)
		(width 0.13208)
		(layer "B.Cu")
		(net "SPI_PEX0_SDIO0_R")
	)
	(segment
		(start 38.455346 -294.004492)
		(end 38.88105 -294.430196)
		(width 0.13208)
		(layer "B.Cu")
		(net "SPI_PEX0_SDIO0_R")
	)
	(segment
		(start 36.039298 -293.15029)
		(end 37.295074 -293.15029)
		(width 0.13208)
		(layer "B.Cu")
		(net "SPI_PEX0_SDIO0_R")
	)
	(segment
		(start 35.230562 -287.723072)
		(end 34.874708 -288.078926)
		(width 0.13208)
		(layer "B.Cu")
		(net "SPI_PEX0_SDIO0_R")
	)
	(segment
		(start 35.230562 -292.341554)
		(end 36.039298 -293.15029)
		(width 0.13208)
		(layer "B.Cu")
		(net "SPI_PEX0_SDIO0_R")
	)
	(segment
		(start 37.761672 -264.18921)
		(end 35.2806 -266.670282)
		(width 0.13208)
		(layer "B.Cu")
		(net "SPI_PEX0_SDIO0_R")
	)
	(segment
		(start 20.708112 -224.341182)
		(end 20.708112 -225.288856)
		(width 0.13208)
		(layer "B.Cu")
		(net "SPI_PEX0_SDIO0_R")
	)
	(segment
		(start 38.88105 -294.430196)
		(end 38.88105 -294.905684)
		(width 0.13208)
		(layer "B.Cu")
		(net "SPI_PEX0_SDIO0_R")
	)
	(segment
		(start 35.2806 -266.670282)
		(end 35.2806 -272.354802)
		(width 0.13208)
		(layer "B.Cu")
		(net "SPI_PEX0_SDIO0_R")
	)
	(segment
		(start 38.341808 -264.18921)
		(end 37.761672 -264.18921)
		(width 0.13208)
		(layer "B.Cu")
		(net "SPI_PEX0_SDIO0_R")
	)
	(segment
		(start 34.874708 -288.078926)
		(end 34.874708 -289.358832)
		(width 0.13208)
		(layer "B.Cu")
		(net "SPI_PEX0_SDIO0_R")
	)
	(segment
		(start 35.2806 -272.354802)
		(end 35.230562 -272.40484)
		(width 0.13208)
		(layer "B.Cu")
		(net "SPI_PEX0_SDIO0_R")
	)
	(segment
		(start 38.88105 -294.905684)
		(end 39.773606 -295.79824)
		(width 0.13208)
		(layer "B.Cu")
		(net "SPI_PEX0_SDIO0_R")
	)
	(segment
		(start 37.295074 -293.15029)
		(end 38.149276 -294.004492)
		(width 0.13208)
		(layer "B.Cu")
		(net "SPI_PEX0_SDIO0_R")
	)
	(segment
		(start 38.149276 -294.004492)
		(end 38.455346 -294.004492)
		(width 0.13208)
		(layer "B.Cu")
		(net "SPI_PEX0_SDIO0_R")
	)
	(segment
		(start 34.874708 -289.358832)
		(end 35.230562 -289.714686)
		(width 0.13208)
		(layer "B.Cu")
		(net "SPI_PEX0_SDIO0_R")
	)
	(segment
		(start 35.230562 -272.40484)
		(end 35.230562 -287.723072)
		(width 0.13208)
		(layer "B.Cu")
		(net "SPI_PEX0_SDIO0_R")
	)
	(segment
		(start 38.341808 -264.18921)
		(end 37.457634 -263.305036)
		(width 0.15494)
		(layer "In5.Cu")
		(net "SPI_PEX0_SDIO0_R")
	)
	(segment
		(start 37.457634 -263.305036)
		(end 36.443412 -263.305036)
		(width 0.15494)
		(layer "In5.Cu")
		(net "SPI_PEX0_SDIO0_R")
	)
	(segment
		(start 22.317202 -229.244398)
		(end 23.016972 -228.544628)
		(width 0.15494)
		(layer "In5.Cu")
		(net "SPI_PEX0_SDIO0_R")
	)
	(segment
		(start 22.6822 -264.1854)
		(end 19.594576 -261.097776)
		(width 0.15494)
		(layer "In5.Cu")
		(net "SPI_PEX0_SDIO0_R")
	)
	(segment
		(start 19.594576 -261.097776)
		(end 19.594576 -244.89537)
		(width 0.15494)
		(layer "In5.Cu")
		(net "SPI_PEX0_SDIO0_R")
	)
	(segment
		(start 36.106608 -263.64184)
		(end 27.437842 -263.64184)
		(width 0.15494)
		(layer "In5.Cu")
		(net "SPI_PEX0_SDIO0_R")
	)
	(segment
		(start 23.016972 -227.597716)
		(end 21.102066 -225.68281)
		(width 0.15494)
		(layer "In5.Cu")
		(net "SPI_PEX0_SDIO0_R")
	)
	(segment
		(start 36.443412 -263.305036)
		(end 36.106608 -263.64184)
		(width 0.15494)
		(layer "In5.Cu")
		(net "SPI_PEX0_SDIO0_R")
	)
	(segment
		(start 19.594576 -244.89537)
		(end 22.317202 -242.172744)
		(width 0.15494)
		(layer "In5.Cu")
		(net "SPI_PEX0_SDIO0_R")
	)
	(segment
		(start 27.437842 -263.64184)
		(end 26.125424 -264.1854)
		(width 0.15494)
		(layer "In5.Cu")
		(net "SPI_PEX0_SDIO0_R")
	)
	(segment
		(start 23.016972 -228.544628)
		(end 23.016972 -227.597716)
		(width 0.15494)
		(layer "In5.Cu")
		(net "SPI_PEX0_SDIO0_R")
	)
	(segment
		(start 26.125424 -264.1854)
		(end 22.6822 -264.1854)
		(width 0.15494)
		(layer "In5.Cu")
		(net "SPI_PEX0_SDIO0_R")
	)
	(segment
		(start 22.317202 -242.172744)
		(end 22.317202 -229.244398)
		(width 0.15494)
		(layer "In5.Cu")
		(net "SPI_PEX0_SDIO0_R")
	)
	(via
		(at 18.803112 -225.82251)
		(size 0.508)
		(drill 0.254)
		(layers "F.Cu" "B.Cu")
		(net "SPI_PEX0_SDIO1_R")
	)
	(via
		(at 36.73856 -264.017506)
		(size 0.508)
		(drill 0.254)
		(layers "F.Cu" "B.Cu")
		(net "SPI_PEX0_SDIO1_R")
	)
	(segment
		(start 34.739072 -289.960558)
		(end 34.739072 -292.557708)
		(width 0.13208)
		(layer "B.Cu")
		(net "SPI_PEX0_SDIO1_R")
	)
	(segment
		(start 34.268918 -289.490404)
		(end 34.739072 -289.960558)
		(width 0.13208)
		(layer "B.Cu")
		(net "SPI_PEX0_SDIO1_R")
	)
	(segment
		(start 36.73856 -264.017506)
		(end 34.739072 -266.016994)
		(width 0.13208)
		(layer "B.Cu")
		(net "SPI_PEX0_SDIO1_R")
	)
	(segment
		(start 34.739072 -266.016994)
		(end 34.739072 -287.377378)
		(width 0.13208)
		(layer "B.Cu")
		(net "SPI_PEX0_SDIO1_R")
	)
	(segment
		(start 37.254434 -295.037764)
		(end 37.63772 -295.037764)
		(width 0.13208)
		(layer "B.Cu")
		(net "SPI_PEX0_SDIO1_R")
	)
	(segment
		(start 39.672006 -296.8498)
		(end 39.773606 -296.9514)
		(width 0.13208)
		(layer "B.Cu")
		(net "SPI_PEX0_SDIO1_R")
	)
	(segment
		(start 36.005516 -293.824152)
		(end 36.708842 -293.824152)
		(width 0.13208)
		(layer "B.Cu")
		(net "SPI_PEX0_SDIO1_R")
	)
	(segment
		(start 18.803112 -224.341182)
		(end 18.803112 -225.82251)
		(width 0.13208)
		(layer "B.Cu")
		(net "SPI_PEX0_SDIO1_R")
	)
	(segment
		(start 34.268918 -287.847532)
		(end 34.268918 -289.490404)
		(width 0.13208)
		(layer "B.Cu")
		(net "SPI_PEX0_SDIO1_R")
	)
	(segment
		(start 36.905438 -294.688768)
		(end 37.254434 -295.037764)
		(width 0.13208)
		(layer "B.Cu")
		(net "SPI_PEX0_SDIO1_R")
	)
	(segment
		(start 36.905438 -294.020748)
		(end 36.905438 -294.688768)
		(width 0.13208)
		(layer "B.Cu")
		(net "SPI_PEX0_SDIO1_R")
	)
	(segment
		(start 37.63772 -295.037764)
		(end 38.76802 -296.168064)
		(width 0.13208)
		(layer "B.Cu")
		(net "SPI_PEX0_SDIO1_R")
	)
	(segment
		(start 34.739072 -287.377378)
		(end 34.268918 -287.847532)
		(width 0.13208)
		(layer "B.Cu")
		(net "SPI_PEX0_SDIO1_R")
	)
	(segment
		(start 39.142162 -296.8498)
		(end 39.672006 -296.8498)
		(width 0.13208)
		(layer "B.Cu")
		(net "SPI_PEX0_SDIO1_R")
	)
	(segment
		(start 38.76802 -296.168064)
		(end 38.76802 -296.475658)
		(width 0.13208)
		(layer "B.Cu")
		(net "SPI_PEX0_SDIO1_R")
	)
	(segment
		(start 36.708842 -293.824152)
		(end 36.905438 -294.020748)
		(width 0.13208)
		(layer "B.Cu")
		(net "SPI_PEX0_SDIO1_R")
	)
	(segment
		(start 34.739072 -292.557708)
		(end 36.005516 -293.824152)
		(width 0.13208)
		(layer "B.Cu")
		(net "SPI_PEX0_SDIO1_R")
	)
	(segment
		(start 38.76802 -296.475658)
		(end 39.142162 -296.8498)
		(width 0.13208)
		(layer "B.Cu")
		(net "SPI_PEX0_SDIO1_R")
	)
	(segment
		(start 21.463 -228.982016)
		(end 21.463 -227.8634)
		(width 0.15494)
		(layer "In5.Cu")
		(net "SPI_PEX0_SDIO1_R")
	)
	(segment
		(start 19.42211 -225.82251)
		(end 18.803112 -225.82251)
		(width 0.15494)
		(layer "In5.Cu")
		(net "SPI_PEX0_SDIO1_R")
	)
	(segment
		(start 19.058636 -244.098572)
		(end 21.235416 -241.921792)
		(width 0.15494)
		(layer "In5.Cu")
		(net "SPI_PEX0_SDIO1_R")
	)
	(segment
		(start 21.235416 -229.2096)
		(end 21.463 -228.982016)
		(width 0.15494)
		(layer "In5.Cu")
		(net "SPI_PEX0_SDIO1_R")
	)
	(segment
		(start 26.241248 -264.7696)
		(end 22.300946 -264.7696)
		(width 0.15494)
		(layer "In5.Cu")
		(net "SPI_PEX0_SDIO1_R")
	)
	(segment
		(start 22.300946 -264.7696)
		(end 19.058636 -261.52729)
		(width 0.15494)
		(layer "In5.Cu")
		(net "SPI_PEX0_SDIO1_R")
	)
	(segment
		(start 36.73856 -264.017506)
		(end 36.578286 -264.17778)
		(width 0.15494)
		(layer "In5.Cu")
		(net "SPI_PEX0_SDIO1_R")
	)
	(segment
		(start 21.463 -227.8634)
		(end 19.42211 -225.82251)
		(width 0.15494)
		(layer "In5.Cu")
		(net "SPI_PEX0_SDIO1_R")
	)
	(segment
		(start 36.578286 -264.17778)
		(end 27.669998 -264.17778)
		(width 0.15494)
		(layer "In5.Cu")
		(net "SPI_PEX0_SDIO1_R")
	)
	(segment
		(start 27.669998 -264.17778)
		(end 26.241248 -264.7696)
		(width 0.15494)
		(layer "In5.Cu")
		(net "SPI_PEX0_SDIO1_R")
	)
	(segment
		(start 19.058636 -261.52729)
		(end 19.058636 -244.098572)
		(width 0.15494)
		(layer "In5.Cu")
		(net "SPI_PEX0_SDIO1_R")
	)
	(segment
		(start 21.235416 -241.921792)
		(end 21.235416 -229.2096)
		(width 0.15494)
		(layer "In5.Cu")
		(net "SPI_PEX0_SDIO1_R")
	)
	(via
		(at 39.038022 -266.963398)
		(size 0.508)
		(drill 0.254)
		(layers "F.Cu" "B.Cu")
		(net "SPI_PEX0_CLK_R")
	)
	(via
		(at 19.355562 -228.06914)
		(size 0.508)
		(drill 0.254)
		(layers "F.Cu" "B.Cu")
		(net "SPI_PEX0_CLK_R")
	)
	(segment
		(start 19.355562 -228.06914)
		(end 19.355562 -228.491796)
		(width 0.13208)
		(layer "B.Cu")
		(net "SPI_PEX0_CLK_R")
	)
	(segment
		(start 38.938962 -291.008562)
		(end 39.65702 -291.72662)
		(width 0.13208)
		(layer "B.Cu")
		(net "SPI_PEX0_CLK_R")
	)
	(segment
		(start 20.073112 -229.209346)
		(end 20.073112 -229.827582)
		(width 0.13208)
		(layer "B.Cu")
		(net "SPI_PEX0_CLK_R")
	)
	(segment
		(start 38.938962 -290.462208)
		(end 38.938962 -291.008562)
		(width 0.13208)
		(layer "B.Cu")
		(net "SPI_PEX0_CLK_R")
	)
	(segment
		(start 39.038022 -268.580616)
		(end 37.780976 -269.837662)
		(width 0.13208)
		(layer "B.Cu")
		(net "SPI_PEX0_CLK_R")
	)
	(segment
		(start 37.780976 -269.837662)
		(end 37.780976 -287.988756)
		(width 0.13208)
		(layer "B.Cu")
		(net "SPI_PEX0_CLK_R")
	)
	(segment
		(start 38.085014 -288.292794)
		(end 38.402006 -288.292794)
		(width 0.13208)
		(layer "B.Cu")
		(net "SPI_PEX0_CLK_R")
	)
	(segment
		(start 38.6842 -288.574988)
		(end 38.6842 -290.207446)
		(width 0.13208)
		(layer "B.Cu")
		(net "SPI_PEX0_CLK_R")
	)
	(segment
		(start 38.402006 -288.292794)
		(end 38.6842 -288.574988)
		(width 0.13208)
		(layer "B.Cu")
		(net "SPI_PEX0_CLK_R")
	)
	(segment
		(start 37.780976 -287.988756)
		(end 38.085014 -288.292794)
		(width 0.13208)
		(layer "B.Cu")
		(net "SPI_PEX0_CLK_R")
	)
	(segment
		(start 19.355562 -228.491796)
		(end 20.073112 -229.209346)
		(width 0.13208)
		(layer "B.Cu")
		(net "SPI_PEX0_CLK_R")
	)
	(segment
		(start 38.6842 -290.207446)
		(end 38.938962 -290.462208)
		(width 0.13208)
		(layer "B.Cu")
		(net "SPI_PEX0_CLK_R")
	)
	(segment
		(start 39.038022 -266.963398)
		(end 39.038022 -268.580616)
		(width 0.13208)
		(layer "B.Cu")
		(net "SPI_PEX0_CLK_R")
	)
	(segment
		(start 39.038022 -267.651992)
		(end 39.04742 -267.651992)
		(width 0.15494)
		(layer "In5.Cu")
		(net "SPI_PEX0_CLK_R")
	)
	(segment
		(start 39.775638 -267.8557)
		(end 39.949628 -267.68171)
		(width 0.15494)
		(layer "In5.Cu")
		(net "SPI_PEX0_CLK_R")
	)
	(segment
		(start 39.251128 -267.8557)
		(end 39.775638 -267.8557)
		(width 0.15494)
		(layer "In5.Cu")
		(net "SPI_PEX0_CLK_R")
	)
	(segment
		(start 39.038022 -266.963398)
		(end 39.038022 -267.651992)
		(width 0.15494)
		(layer "In5.Cu")
		(net "SPI_PEX0_CLK_R")
	)
	(segment
		(start 39.04742 -267.651992)
		(end 39.251128 -267.8557)
		(width 0.15494)
		(layer "In5.Cu")
		(net "SPI_PEX0_CLK_R")
	)
	(segment
		(start 22.123654 -265.5316)
		(end 18.395696 -261.803642)
		(width 0.15494)
		(layer "In5.Cu")
		(net "SPI_PEX0_CLK_R")
	)
	(segment
		(start 39.949628 -266.974828)
		(end 38.74516 -265.77036)
		(width 0.15494)
		(layer "In5.Cu")
		(net "SPI_PEX0_CLK_R")
	)
	(segment
		(start 19.355562 -239.699038)
		(end 19.355562 -228.06914)
		(width 0.15494)
		(layer "In5.Cu")
		(net "SPI_PEX0_CLK_R")
	)
	(segment
		(start 36.73348 -265.085068)
		(end 36.143438 -264.84072)
		(width 0.15494)
		(layer "In5.Cu")
		(net "SPI_PEX0_CLK_R")
	)
	(segment
		(start 39.949628 -267.68171)
		(end 39.949628 -266.974828)
		(width 0.15494)
		(layer "In5.Cu")
		(net "SPI_PEX0_CLK_R")
	)
	(segment
		(start 18.395696 -261.803642)
		(end 18.395696 -240.658904)
		(width 0.15494)
		(layer "In5.Cu")
		(net "SPI_PEX0_CLK_R")
	)
	(segment
		(start 18.395696 -240.658904)
		(end 19.355562 -239.699038)
		(width 0.15494)
		(layer "In5.Cu")
		(net "SPI_PEX0_CLK_R")
	)
	(segment
		(start 26.21407 -265.5316)
		(end 22.123654 -265.5316)
		(width 0.15494)
		(layer "In5.Cu")
		(net "SPI_PEX0_CLK_R")
	)
	(segment
		(start 38.498526 -265.085068)
		(end 36.73348 -265.085068)
		(width 0.15494)
		(layer "In5.Cu")
		(net "SPI_PEX0_CLK_R")
	)
	(segment
		(start 38.74516 -265.331702)
		(end 38.498526 -265.085068)
		(width 0.15494)
		(layer "In5.Cu")
		(net "SPI_PEX0_CLK_R")
	)
	(segment
		(start 38.74516 -265.77036)
		(end 38.74516 -265.331702)
		(width 0.15494)
		(layer "In5.Cu")
		(net "SPI_PEX0_CLK_R")
	)
	(segment
		(start 36.143438 -264.84072)
		(end 27.882342 -264.84072)
		(width 0.15494)
		(layer "In5.Cu")
		(net "SPI_PEX0_CLK_R")
	)
	(segment
		(start 27.882342 -264.84072)
		(end 26.21407 -265.5316)
		(width 0.15494)
		(layer "In5.Cu")
		(net "SPI_PEX0_CLK_R")
	)
	(via
		(at 40.443912 -270.665702)
		(size 0.508)
		(drill 0.254)
		(layers "F.Cu" "B.Cu")
		(net "SPI_PEX0_CS_R_N")
	)
	(via
		(at 18.168112 -231.95026)
		(size 0.508)
		(drill 0.254)
		(layers "F.Cu" "B.Cu")
		(net "SPI_PEX0_CS_R_N")
	)
	(segment
		(start 39.91483 -285.38043)
		(end 40.39235 -285.38043)
		(width 0.13208)
		(layer "B.Cu")
		(net "SPI_PEX0_CS_R_N")
	)
	(segment
		(start 40.649906 -285.637986)
		(end 40.649906 -288.374836)
		(width 0.13208)
		(layer "B.Cu")
		(net "SPI_PEX0_CS_R_N")
	)
	(segment
		(start 40.443912 -270.665702)
		(end 39.6875 -271.422114)
		(width 0.13208)
		(layer "B.Cu")
		(net "SPI_PEX0_CS_R_N")
	)
	(segment
		(start 18.168112 -231.95026)
		(end 18.168112 -229.827582)
		(width 0.13208)
		(layer "B.Cu")
		(net "SPI_PEX0_CS_R_N")
	)
	(segment
		(start 39.6875 -285.1531)
		(end 39.91483 -285.38043)
		(width 0.13208)
		(layer "B.Cu")
		(net "SPI_PEX0_CS_R_N")
	)
	(segment
		(start 39.6875 -271.422114)
		(end 39.6875 -285.1531)
		(width 0.13208)
		(layer "B.Cu")
		(net "SPI_PEX0_CS_R_N")
	)
	(segment
		(start 40.39235 -285.38043)
		(end 40.649906 -285.637986)
		(width 0.13208)
		(layer "B.Cu")
		(net "SPI_PEX0_CS_R_N")
	)
	(segment
		(start 21.5646 -266.2682)
		(end 17.711928 -262.415528)
		(width 0.15494)
		(layer "In5.Cu")
		(net "SPI_PEX0_CS_R_N")
	)
	(segment
		(start 17.52854 -238.646208)
		(end 17.52854 -238.018828)
		(width 0.15494)
		(layer "In5.Cu")
		(net "SPI_PEX0_CS_R_N")
	)
	(segment
		(start 15.981172 -236.090968)
		(end 15.846552 -235.956348)
		(width 0.15494)
		(layer "In5.Cu")
		(net "SPI_PEX0_CS_R_N")
	)
	(segment
		(start 17.52854 -240.439448)
		(end 17.52854 -239.812068)
		(width 0.15494)
		(layer "In5.Cu")
		(net "SPI_PEX0_CS_R_N")
	)
	(segment
		(start 28.028392 -265.50366)
		(end 26.18232 -266.2682)
		(width 0.15494)
		(layer "In5.Cu")
		(net "SPI_PEX0_CS_R_N")
	)
	(segment
		(start 17.39392 -235.194348)
		(end 17.52854 -235.059728)
		(width 0.15494)
		(layer "In5.Cu")
		(net "SPI_PEX0_CS_R_N")
	)
	(segment
		(start 17.52854 -236.225588)
		(end 17.39392 -236.090968)
		(width 0.15494)
		(layer "In5.Cu")
		(net "SPI_PEX0_CS_R_N")
	)
	(segment
		(start 17.711928 -262.415528)
		(end 17.711928 -242.035076)
		(width 0.15494)
		(layer "In5.Cu")
		(net "SPI_PEX0_CS_R_N")
	)
	(segment
		(start 17.39392 -238.780828)
		(end 17.52854 -238.646208)
		(width 0.15494)
		(layer "In5.Cu")
		(net "SPI_PEX0_CS_R_N")
	)
	(segment
		(start 15.981172 -241.470688)
		(end 15.846552 -241.336068)
		(width 0.15494)
		(layer "In5.Cu")
		(net "SPI_PEX0_CS_R_N")
	)
	(segment
		(start 17.39392 -239.677448)
		(end 15.981172 -239.677448)
		(width 0.15494)
		(layer "In5.Cu")
		(net "SPI_PEX0_CS_R_N")
	)
	(segment
		(start 37.973 -268.19479)
		(end 37.973 -267.281152)
		(width 0.15494)
		(layer "In5.Cu")
		(net "SPI_PEX0_CS_R_N")
	)
	(segment
		(start 17.52854 -232.589832)
		(end 18.168112 -231.95026)
		(width 0.15494)
		(layer "In5.Cu")
		(net "SPI_PEX0_CS_R_N")
	)
	(segment
		(start 15.846552 -235.956348)
		(end 15.846552 -235.328968)
		(width 0.15494)
		(layer "In5.Cu")
		(net "SPI_PEX0_CS_R_N")
	)
	(segment
		(start 17.39392 -240.574068)
		(end 17.52854 -240.439448)
		(width 0.15494)
		(layer "In5.Cu")
		(net "SPI_PEX0_CS_R_N")
	)
	(segment
		(start 15.846552 -237.749588)
		(end 15.846552 -237.122208)
		(width 0.15494)
		(layer "In5.Cu")
		(net "SPI_PEX0_CS_R_N")
	)
	(segment
		(start 17.52854 -238.018828)
		(end 17.39392 -237.884208)
		(width 0.15494)
		(layer "In5.Cu")
		(net "SPI_PEX0_CS_R_N")
	)
	(segment
		(start 15.846552 -239.542828)
		(end 15.846552 -238.915448)
		(width 0.15494)
		(layer "In5.Cu")
		(net "SPI_PEX0_CS_R_N")
	)
	(segment
		(start 17.52854 -235.059728)
		(end 17.52854 -232.589832)
		(width 0.15494)
		(layer "In5.Cu")
		(net "SPI_PEX0_CS_R_N")
	)
	(segment
		(start 15.846552 -235.328968)
		(end 15.981172 -235.194348)
		(width 0.15494)
		(layer "In5.Cu")
		(net "SPI_PEX0_CS_R_N")
	)
	(segment
		(start 37.973 -267.281152)
		(end 36.405566 -265.713718)
		(width 0.15494)
		(layer "In5.Cu")
		(net "SPI_PEX0_CS_R_N")
	)
	(segment
		(start 15.981172 -237.884208)
		(end 15.846552 -237.749588)
		(width 0.15494)
		(layer "In5.Cu")
		(net "SPI_PEX0_CS_R_N")
	)
	(segment
		(start 40.443912 -270.665702)
		(end 37.973 -268.19479)
		(width 0.15494)
		(layer "In5.Cu")
		(net "SPI_PEX0_CS_R_N")
	)
	(segment
		(start 15.846552 -237.122208)
		(end 15.981172 -236.987588)
		(width 0.15494)
		(layer "In5.Cu")
		(net "SPI_PEX0_CS_R_N")
	)
	(segment
		(start 17.39392 -237.884208)
		(end 15.981172 -237.884208)
		(width 0.15494)
		(layer "In5.Cu")
		(net "SPI_PEX0_CS_R_N")
	)
	(segment
		(start 17.52854 -236.852968)
		(end 17.52854 -236.225588)
		(width 0.15494)
		(layer "In5.Cu")
		(net "SPI_PEX0_CS_R_N")
	)
	(segment
		(start 15.846552 -241.336068)
		(end 15.846552 -240.708688)
		(width 0.15494)
		(layer "In5.Cu")
		(net "SPI_PEX0_CS_R_N")
	)
	(segment
		(start 15.981172 -238.780828)
		(end 17.39392 -238.780828)
		(width 0.15494)
		(layer "In5.Cu")
		(net "SPI_PEX0_CS_R_N")
	)
	(segment
		(start 36.405566 -265.713718)
		(end 35.898328 -265.50366)
		(width 0.15494)
		(layer "In5.Cu")
		(net "SPI_PEX0_CS_R_N")
	)
	(segment
		(start 17.14754 -241.470688)
		(end 15.981172 -241.470688)
		(width 0.15494)
		(layer "In5.Cu")
		(net "SPI_PEX0_CS_R_N")
	)
	(segment
		(start 15.981172 -239.677448)
		(end 15.846552 -239.542828)
		(width 0.15494)
		(layer "In5.Cu")
		(net "SPI_PEX0_CS_R_N")
	)
	(segment
		(start 15.846552 -240.708688)
		(end 15.981172 -240.574068)
		(width 0.15494)
		(layer "In5.Cu")
		(net "SPI_PEX0_CS_R_N")
	)
	(segment
		(start 15.981172 -240.574068)
		(end 17.39392 -240.574068)
		(width 0.15494)
		(layer "In5.Cu")
		(net "SPI_PEX0_CS_R_N")
	)
	(segment
		(start 15.981172 -235.194348)
		(end 17.39392 -235.194348)
		(width 0.15494)
		(layer "In5.Cu")
		(net "SPI_PEX0_CS_R_N")
	)
	(segment
		(start 15.846552 -238.915448)
		(end 15.981172 -238.780828)
		(width 0.15494)
		(layer "In5.Cu")
		(net "SPI_PEX0_CS_R_N")
	)
	(segment
		(start 17.39392 -236.987588)
		(end 17.52854 -236.852968)
		(width 0.15494)
		(layer "In5.Cu")
		(net "SPI_PEX0_CS_R_N")
	)
	(segment
		(start 17.52854 -239.812068)
		(end 17.39392 -239.677448)
		(width 0.15494)
		(layer "In5.Cu")
		(net "SPI_PEX0_CS_R_N")
	)
	(segment
		(start 17.39392 -236.090968)
		(end 15.981172 -236.090968)
		(width 0.15494)
		(layer "In5.Cu")
		(net "SPI_PEX0_CS_R_N")
	)
	(segment
		(start 35.898328 -265.50366)
		(end 28.028392 -265.50366)
		(width 0.15494)
		(layer "In5.Cu")
		(net "SPI_PEX0_CS_R_N")
	)
	(segment
		(start 26.18232 -266.2682)
		(end 21.5646 -266.2682)
		(width 0.15494)
		(layer "In5.Cu")
		(net "SPI_PEX0_CS_R_N")
	)
	(segment
		(start 17.711928 -242.035076)
		(end 17.14754 -241.470688)
		(width 0.15494)
		(layer "In5.Cu")
		(net "SPI_PEX0_CS_R_N")
	)
	(segment
		(start 15.981172 -236.987588)
		(end 17.39392 -236.987588)
		(width 0.15494)
		(layer "In5.Cu")
		(net "SPI_PEX0_CS_R_N")
	)
	(segment
		(start 119.67972 -358.54386)
		(end 113.778792 -365.106204)
		(width 0.1651)
		(layer "In15.Cu")
		(net "P5E_PEX1_STN6_RX_DP<107>")
	)
	(segment
		(start 122.647202 -392.861038)
		(end 123.05919 -393.136374)
		(width 0.1651)
		(layer "In15.Cu")
		(net "P5E_PEX1_STN6_RX_DP<107>")
	)
	(segment
		(start 123.611894 -393.383516)
		(end 123.639834 -393.524486)
		(width 0.1651)
		(layer "In15.Cu")
		(net "P5E_PEX1_STN6_RX_DP<107>")
	)
	(segment
		(start 123.05919 -393.136374)
		(end 123.20016 -393.108434)
		(width 0.1651)
		(layer "In15.Cu")
		(net "P5E_PEX1_STN6_RX_DP<107>")
	)
	(segment
		(start 124.192792 -393.771882)
		(end 124.92228 -394.259054)
		(width 0.1651)
		(layer "In15.Cu")
		(net "P5E_PEX1_STN6_RX_DP<107>")
	)
	(segment
		(start 112.723168 -366.653318)
		(end 111.598202 -368.892328)
		(width 0.1651)
		(layer "In15.Cu")
		(net "P5E_PEX1_STN6_RX_DP<107>")
	)
	(segment
		(start 163.399978 -315.849762)
		(end 163.399978 -316.140592)
		(width 0.1143)
		(layer "In15.Cu")
		(net "P5E_PEX1_STN6_RX_DP<107>")
	)
	(segment
		(start 111.49203 -384.71221)
		(end 111.805974 -385.84251)
		(width 0.1651)
		(layer "In15.Cu")
		(net "P5E_PEX1_STN6_RX_DP<107>")
	)
	(segment
		(start 162.829748 -319.79108)
		(end 162.784028 -319.8368)
		(width 0.1143)
		(layer "In15.Cu")
		(net "P5E_PEX1_STN6_RX_DP<107>")
	)
	(segment
		(start 111.598202 -368.892328)
		(end 111.49203 -384.71221)
		(width 0.1651)
		(layer "In15.Cu")
		(net "P5E_PEX1_STN6_RX_DP<107>")
	)
	(segment
		(start 162.829748 -316.467998)
		(end 162.829748 -319.79108)
		(width 0.1143)
		(layer "In15.Cu")
		(net "P5E_PEX1_STN6_RX_DP<107>")
	)
	(segment
		(start 120.193562 -341.602314)
		(end 119.925338 -341.870538)
		(width 0.1651)
		(layer "In15.Cu")
		(net "P5E_PEX1_STN6_RX_DP<107>")
	)
	(segment
		(start 125.058678 -400.899122)
		(end 124.83719 -400.899122)
		(width 0.1651)
		(layer "In15.Cu")
		(net "P5E_PEX1_STN6_RX_DP<107>")
	)
	(segment
		(start 162.784028 -319.8368)
		(end 162.784028 -319.865248)
		(width 0.1143)
		(layer "In15.Cu")
		(net "P5E_PEX1_STN6_RX_DP<107>")
	)
	(segment
		(start 124.92228 -394.259054)
		(end 125.584966 -394.92174)
		(width 0.1651)
		(layer "In15.Cu")
		(net "P5E_PEX1_STN6_RX_DP<107>")
	)
	(segment
		(start 112.951514 -387.547866)
		(end 115.121944 -389.317738)
		(width 0.1651)
		(layer "In15.Cu")
		(net "P5E_PEX1_STN6_RX_DP<107>")
	)
	(segment
		(start 122.619008 -392.720068)
		(end 122.647202 -392.861038)
		(width 0.1651)
		(layer "In15.Cu")
		(net "P5E_PEX1_STN6_RX_DP<107>")
	)
	(segment
		(start 163.311078 -316.229492)
		(end 163.068254 -316.229492)
		(width 0.1143)
		(layer "In15.Cu")
		(net "P5E_PEX1_STN6_RX_DP<107>")
	)
	(segment
		(start 115.121944 -389.317738)
		(end 121.450608 -391.939272)
		(width 0.1651)
		(layer "In15.Cu")
		(net "P5E_PEX1_STN6_RX_DP<107>")
	)
	(segment
		(start 160.446974 -323.944996)
		(end 143.75511 -331.841094)
		(width 0.1651)
		(layer "In15.Cu")
		(net "P5E_PEX1_STN6_RX_DP<107>")
	)
	(segment
		(start 119.925338 -357.904288)
		(end 119.67972 -358.54386)
		(width 0.1651)
		(layer "In15.Cu")
		(net "P5E_PEX1_STN6_RX_DP<107>")
	)
	(segment
		(start 125.584966 -394.92174)
		(end 125.584966 -400.372834)
		(width 0.1651)
		(layer "In15.Cu")
		(net "P5E_PEX1_STN6_RX_DP<107>")
	)
	(segment
		(start 124.83719 -400.899122)
		(end 124.71019 -400.772122)
		(width 0.1651)
		(layer "In15.Cu")
		(net "P5E_PEX1_STN6_RX_DP<107>")
	)
	(segment
		(start 113.778792 -365.106204)
		(end 112.723168 -366.653318)
		(width 0.1651)
		(layer "In15.Cu")
		(net "P5E_PEX1_STN6_RX_DP<107>")
	)
	(segment
		(start 124.052076 -393.799822)
		(end 124.192792 -393.771882)
		(width 0.1651)
		(layer "In15.Cu")
		(net "P5E_PEX1_STN6_RX_DP<107>")
	)
	(segment
		(start 162.784028 -320.504312)
		(end 162.00374 -322.38823)
		(width 0.1651)
		(layer "In15.Cu")
		(net "P5E_PEX1_STN6_RX_DP<107>")
	)
	(segment
		(start 162.784028 -319.865248)
		(end 162.784028 -320.504312)
		(width 0.1651)
		(layer "In15.Cu")
		(net "P5E_PEX1_STN6_RX_DP<107>")
	)
	(segment
		(start 125.584966 -400.372834)
		(end 125.058678 -400.899122)
		(width 0.1651)
		(layer "In15.Cu")
		(net "P5E_PEX1_STN6_RX_DP<107>")
	)
	(segment
		(start 120.470422 -341.180166)
		(end 120.193562 -341.602314)
		(width 0.1651)
		(layer "In15.Cu")
		(net "P5E_PEX1_STN6_RX_DP<107>")
	)
	(segment
		(start 163.068254 -316.229492)
		(end 162.829748 -316.467998)
		(width 0.1143)
		(layer "In15.Cu")
		(net "P5E_PEX1_STN6_RX_DP<107>")
	)
	(segment
		(start 162.00374 -322.38823)
		(end 160.446974 -323.944996)
		(width 0.1651)
		(layer "In15.Cu")
		(net "P5E_PEX1_STN6_RX_DP<107>")
	)
	(segment
		(start 143.75511 -331.841094)
		(end 123.742958 -340.13013)
		(width 0.1651)
		(layer "In15.Cu")
		(net "P5E_PEX1_STN6_RX_DP<107>")
	)
	(segment
		(start 163.399978 -316.140592)
		(end 163.311078 -316.229492)
		(width 0.1143)
		(layer "In15.Cu")
		(net "P5E_PEX1_STN6_RX_DP<107>")
	)
	(segment
		(start 111.805974 -385.84251)
		(end 112.951514 -387.547866)
		(width 0.1651)
		(layer "In15.Cu")
		(net "P5E_PEX1_STN6_RX_DP<107>")
	)
	(segment
		(start 124.71019 -400.772122)
		(end 124.71019 -400.390106)
		(width 0.1651)
		(layer "In15.Cu")
		(net "P5E_PEX1_STN6_RX_DP<107>")
	)
	(segment
		(start 119.925338 -341.870538)
		(end 119.925338 -357.904288)
		(width 0.1651)
		(layer "In15.Cu")
		(net "P5E_PEX1_STN6_RX_DP<107>")
	)
	(segment
		(start 123.742958 -340.13013)
		(end 120.470422 -341.180166)
		(width 0.1651)
		(layer "In15.Cu")
		(net "P5E_PEX1_STN6_RX_DP<107>")
	)
	(segment
		(start 121.450608 -391.939272)
		(end 122.619008 -392.720068)
		(width 0.1651)
		(layer "In15.Cu")
		(net "P5E_PEX1_STN6_RX_DP<107>")
	)
	(segment
		(start 123.20016 -393.108434)
		(end 123.611894 -393.383516)
		(width 0.1651)
		(layer "In15.Cu")
		(net "P5E_PEX1_STN6_RX_DP<107>")
	)
	(segment
		(start 123.639834 -393.524486)
		(end 124.052076 -393.799822)
		(width 0.1651)
		(layer "In15.Cu")
		(net "P5E_PEX1_STN6_RX_DP<107>")
	)
	(segment
		(start 121.584212 -391.689336)
		(end 125.102112 -394.040106)
		(width 0.1651)
		(layer "In15.Cu")
		(net "P5E_PEX1_STN6_RX_DN<107>")
	)
	(segment
		(start 120.207278 -342.095582)
		(end 120.207278 -357.956612)
		(width 0.1651)
		(layer "In15.Cu")
		(net "P5E_PEX1_STN6_RX_DN<107>")
	)
	(segment
		(start 163.399978 -316.799722)
		(end 163.399978 -316.508892)
		(width 0.1143)
		(layer "In15.Cu")
		(net "P5E_PEX1_STN6_RX_DN<107>")
	)
	(segment
		(start 125.102112 -394.040106)
		(end 125.866906 -394.8049)
		(width 0.1651)
		(layer "In15.Cu")
		(net "P5E_PEX1_STN6_RX_DN<107>")
	)
	(segment
		(start 160.61182 -324.17893)
		(end 143.86941 -332.099158)
		(width 0.1651)
		(layer "In15.Cu")
		(net "P5E_PEX1_STN6_RX_DN<107>")
	)
	(segment
		(start 112.966754 -366.796828)
		(end 111.879888 -368.960146)
		(width 0.1651)
		(layer "In15.Cu")
		(net "P5E_PEX1_STN6_RX_DN<107>")
	)
	(segment
		(start 125.866906 -394.8049)
		(end 125.866906 -400.489674)
		(width 0.1651)
		(layer "In15.Cu")
		(net "P5E_PEX1_STN6_RX_DN<107>")
	)
	(segment
		(start 163.065968 -319.865248)
		(end 163.065968 -320.560446)
		(width 0.1651)
		(layer "In15.Cu")
		(net "P5E_PEX1_STN6_RX_DN<107>")
	)
	(segment
		(start 120.207278 -357.956612)
		(end 119.924322 -358.69372)
		(width 0.1651)
		(layer "In15.Cu")
		(net "P5E_PEX1_STN6_RX_DN<107>")
	)
	(segment
		(start 124.71019 -401.308062)
		(end 124.71019 -401.690078)
		(width 0.1651)
		(layer "In15.Cu")
		(net "P5E_PEX1_STN6_RX_DN<107>")
	)
	(segment
		(start 111.879888 -368.960146)
		(end 111.774478 -384.674618)
		(width 0.1651)
		(layer "In15.Cu")
		(net "P5E_PEX1_STN6_RX_DN<107>")
	)
	(segment
		(start 119.924322 -358.69372)
		(end 114.001296 -365.280956)
		(width 0.1651)
		(layer "In15.Cu")
		(net "P5E_PEX1_STN6_RX_DN<107>")
	)
	(segment
		(start 163.020248 -319.79108)
		(end 163.065968 -319.8368)
		(width 0.1143)
		(layer "In15.Cu")
		(net "P5E_PEX1_STN6_RX_DN<107>")
	)
	(segment
		(start 111.774478 -384.674618)
		(end 112.065562 -385.72313)
		(width 0.1651)
		(layer "In15.Cu")
		(net "P5E_PEX1_STN6_RX_DN<107>")
	)
	(segment
		(start 163.065968 -319.8368)
		(end 163.065968 -319.865248)
		(width 0.1143)
		(layer "In15.Cu")
		(net "P5E_PEX1_STN6_RX_DN<107>")
	)
	(segment
		(start 163.399978 -316.508892)
		(end 163.311078 -316.419992)
		(width 0.1143)
		(layer "In15.Cu")
		(net "P5E_PEX1_STN6_RX_DN<107>")
	)
	(segment
		(start 163.147248 -316.419992)
		(end 163.020248 -316.546992)
		(width 0.1143)
		(layer "In15.Cu")
		(net "P5E_PEX1_STN6_RX_DN<107>")
	)
	(segment
		(start 163.020248 -316.546992)
		(end 163.020248 -319.79108)
		(width 0.1143)
		(layer "In15.Cu")
		(net "P5E_PEX1_STN6_RX_DN<107>")
	)
	(segment
		(start 163.311078 -316.419992)
		(end 163.147248 -316.419992)
		(width 0.1143)
		(layer "In15.Cu")
		(net "P5E_PEX1_STN6_RX_DN<107>")
	)
	(segment
		(start 162.242754 -322.547996)
		(end 160.61182 -324.17893)
		(width 0.1651)
		(layer "In15.Cu")
		(net "P5E_PEX1_STN6_RX_DN<107>")
	)
	(segment
		(start 120.651524 -341.418164)
		(end 120.207278 -342.095582)
		(width 0.1651)
		(layer "In15.Cu")
		(net "P5E_PEX1_STN6_RX_DN<107>")
	)
	(segment
		(start 163.065968 -320.560446)
		(end 162.242754 -322.547996)
		(width 0.1651)
		(layer "In15.Cu")
		(net "P5E_PEX1_STN6_RX_DN<107>")
	)
	(segment
		(start 143.86941 -332.099158)
		(end 123.84024 -340.395052)
		(width 0.1651)
		(layer "In15.Cu")
		(net "P5E_PEX1_STN6_RX_DN<107>")
	)
	(segment
		(start 123.84024 -340.395052)
		(end 120.651524 -341.418164)
		(width 0.1651)
		(layer "In15.Cu")
		(net "P5E_PEX1_STN6_RX_DN<107>")
	)
	(segment
		(start 125.866906 -400.489674)
		(end 125.175518 -401.181062)
		(width 0.1651)
		(layer "In15.Cu")
		(net "P5E_PEX1_STN6_RX_DN<107>")
	)
	(segment
		(start 115.268248 -389.072882)
		(end 121.584212 -391.689336)
		(width 0.1651)
		(layer "In15.Cu")
		(net "P5E_PEX1_STN6_RX_DN<107>")
	)
	(segment
		(start 125.175518 -401.181062)
		(end 124.83719 -401.181062)
		(width 0.1651)
		(layer "In15.Cu")
		(net "P5E_PEX1_STN6_RX_DN<107>")
	)
	(segment
		(start 112.065562 -385.72313)
		(end 113.162334 -387.355588)
		(width 0.1651)
		(layer "In15.Cu")
		(net "P5E_PEX1_STN6_RX_DN<107>")
	)
	(segment
		(start 113.162334 -387.355588)
		(end 115.268248 -389.072882)
		(width 0.1651)
		(layer "In15.Cu")
		(net "P5E_PEX1_STN6_RX_DN<107>")
	)
	(segment
		(start 124.83719 -401.181062)
		(end 124.71019 -401.308062)
		(width 0.1651)
		(layer "In15.Cu")
		(net "P5E_PEX1_STN6_RX_DN<107>")
	)
	(segment
		(start 114.001296 -365.280956)
		(end 112.966754 -366.796828)
		(width 0.1651)
		(layer "In15.Cu")
		(net "P5E_PEX1_STN6_RX_DN<107>")
	)
	(segment
		(start 47.29988 -316.115192)
		(end 47.29988 -315.849762)
		(width 0.1143)
		(layer "In5.Cu")
		(net "P5E_PEX0_STN6_RX_DP<107>")
	)
	(segment
		(start 80.710024 -400.390106)
		(end 80.710024 -400.772122)
		(width 0.1651)
		(layer "In5.Cu")
		(net "P5E_PEX0_STN6_RX_DP<107>")
	)
	(segment
		(start 78.434946 -392.692128)
		(end 77.476096 -392.016742)
		(width 0.1651)
		(layer "In5.Cu")
		(net "P5E_PEX0_STN6_RX_DP<107>")
	)
	(segment
		(start 80.379062 -394.061188)
		(end 79.9846 -393.783312)
		(width 0.1651)
		(layer "In5.Cu")
		(net "P5E_PEX0_STN6_RX_DP<107>")
	)
	(segment
		(start 59.30773 -345.165426)
		(end 58.408824 -342.994996)
		(width 0.1651)
		(layer "In5.Cu")
		(net "P5E_PEX0_STN6_RX_DP<107>")
	)
	(segment
		(start 66.138298 -368.422936)
		(end 60.889642 -354.816664)
		(width 0.1651)
		(layer "In5.Cu")
		(net "P5E_PEX0_STN6_RX_DP<107>")
	)
	(segment
		(start 46.955456 -316.229492)
		(end 47.18558 -316.229492)
		(width 0.1143)
		(layer "In5.Cu")
		(net "P5E_PEX0_STN6_RX_DP<107>")
	)
	(segment
		(start 68.51142 -386.906516)
		(end 67.786758 -385.157218)
		(width 0.1651)
		(layer "In5.Cu")
		(net "P5E_PEX0_STN6_RX_DP<107>")
	)
	(segment
		(start 79.434182 -393.53236)
		(end 79.407004 -393.376658)
		(width 0.1651)
		(layer "In5.Cu")
		(net "P5E_PEX0_STN6_RX_DP<107>")
	)
	(segment
		(start 81.364328 -400.899122)
		(end 81.602326 -400.661124)
		(width 0.1651)
		(layer "In5.Cu")
		(net "P5E_PEX0_STN6_RX_DP<107>")
	)
	(segment
		(start 80.710024 -400.772122)
		(end 80.837024 -400.899122)
		(width 0.1651)
		(layer "In5.Cu")
		(net "P5E_PEX0_STN6_RX_DP<107>")
	)
	(segment
		(start 77.476096 -392.016742)
		(end 74.50836 -390.237726)
		(width 0.1651)
		(layer "In5.Cu")
		(net "P5E_PEX0_STN6_RX_DP<107>")
	)
	(segment
		(start 46.72965 -316.455298)
		(end 46.955456 -316.229492)
		(width 0.1143)
		(layer "In5.Cu")
		(net "P5E_PEX0_STN6_RX_DP<107>")
	)
	(segment
		(start 79.407004 -393.376658)
		(end 79.012542 -393.098782)
		(width 0.1651)
		(layer "In5.Cu")
		(net "P5E_PEX0_STN6_RX_DP<107>")
	)
	(segment
		(start 79.012542 -393.098782)
		(end 78.85684 -393.12596)
		(width 0.1651)
		(layer "In5.Cu")
		(net "P5E_PEX0_STN6_RX_DP<107>")
	)
	(segment
		(start 67.786758 -385.157218)
		(end 66.138298 -368.422936)
		(width 0.1651)
		(layer "In5.Cu")
		(net "P5E_PEX0_STN6_RX_DP<107>")
	)
	(segment
		(start 74.50836 -390.237726)
		(end 69.95795 -388.353046)
		(width 0.1651)
		(layer "In5.Cu")
		(net "P5E_PEX0_STN6_RX_DP<107>")
	)
	(segment
		(start 60.118498 -351.737676)
		(end 59.30773 -345.165426)
		(width 0.1651)
		(layer "In5.Cu")
		(net "P5E_PEX0_STN6_RX_DP<107>")
	)
	(segment
		(start 79.828898 -393.81049)
		(end 79.434182 -393.53236)
		(width 0.1651)
		(layer "In5.Cu")
		(net "P5E_PEX0_STN6_RX_DP<107>")
	)
	(segment
		(start 80.837024 -400.899122)
		(end 81.364328 -400.899122)
		(width 0.1651)
		(layer "In5.Cu")
		(net "P5E_PEX0_STN6_RX_DP<107>")
	)
	(segment
		(start 69.95795 -388.353046)
		(end 68.51142 -386.906516)
		(width 0.1651)
		(layer "In5.Cu")
		(net "P5E_PEX0_STN6_RX_DP<107>")
	)
	(segment
		(start 81.31556 -394.903452)
		(end 81.206594 -394.740384)
		(width 0.1651)
		(layer "In5.Cu")
		(net "P5E_PEX0_STN6_RX_DP<107>")
	)
	(segment
		(start 78.85684 -393.12596)
		(end 78.462124 -392.84783)
		(width 0.1651)
		(layer "In5.Cu")
		(net "P5E_PEX0_STN6_RX_DP<107>")
	)
	(segment
		(start 58.408824 -342.994996)
		(end 58.408824 -342.994488)
		(width 0.1651)
		(layer "In5.Cu")
		(net "P5E_PEX0_STN6_RX_DP<107>")
	)
	(segment
		(start 81.206594 -394.740384)
		(end 80.379062 -394.061188)
		(width 0.1651)
		(layer "In5.Cu")
		(net "P5E_PEX0_STN6_RX_DP<107>")
	)
	(segment
		(start 47.18558 -316.229492)
		(end 47.29988 -316.115192)
		(width 0.1143)
		(layer "In5.Cu")
		(net "P5E_PEX0_STN6_RX_DP<107>")
	)
	(segment
		(start 58.408824 -342.994488)
		(end 55.711852 -336.48269)
		(width 0.1651)
		(layer "In5.Cu")
		(net "P5E_PEX0_STN6_RX_DP<107>")
	)
	(segment
		(start 79.9846 -393.783312)
		(end 79.828898 -393.81049)
		(width 0.1651)
		(layer "In5.Cu")
		(net "P5E_PEX0_STN6_RX_DP<107>")
	)
	(segment
		(start 81.602326 -400.661124)
		(end 81.602326 -395.848332)
		(width 0.1651)
		(layer "In5.Cu")
		(net "P5E_PEX0_STN6_RX_DP<107>")
	)
	(segment
		(start 46.68393 -319.995296)
		(end 46.68393 -319.966848)
		(width 0.1143)
		(layer "In5.Cu")
		(net "P5E_PEX0_STN6_RX_DP<107>")
	)
	(segment
		(start 81.602326 -395.848332)
		(end 81.31556 -394.903452)
		(width 0.1651)
		(layer "In5.Cu")
		(net "P5E_PEX0_STN6_RX_DP<107>")
	)
	(segment
		(start 46.72965 -319.921128)
		(end 46.72965 -316.455298)
		(width 0.1143)
		(layer "In5.Cu")
		(net "P5E_PEX0_STN6_RX_DP<107>")
	)
	(segment
		(start 46.68393 -322.339208)
		(end 46.68393 -319.995296)
		(width 0.1651)
		(layer "In5.Cu")
		(net "P5E_PEX0_STN6_RX_DP<107>")
	)
	(segment
		(start 60.889642 -354.816664)
		(end 60.118498 -351.737676)
		(width 0.1651)
		(layer "In5.Cu")
		(net "P5E_PEX0_STN6_RX_DP<107>")
	)
	(segment
		(start 78.462124 -392.84783)
		(end 78.434946 -392.692128)
		(width 0.1651)
		(layer "In5.Cu")
		(net "P5E_PEX0_STN6_RX_DP<107>")
	)
	(segment
		(start 47.373794 -324.004178)
		(end 46.68393 -322.339208)
		(width 0.1651)
		(layer "In5.Cu")
		(net "P5E_PEX0_STN6_RX_DP<107>")
	)
	(segment
		(start 46.68393 -319.966848)
		(end 46.72965 -319.921128)
		(width 0.1143)
		(layer "In5.Cu")
		(net "P5E_PEX0_STN6_RX_DP<107>")
	)
	(segment
		(start 55.711852 -336.48269)
		(end 47.373794 -324.004178)
		(width 0.1651)
		(layer "In5.Cu")
		(net "P5E_PEX0_STN6_RX_DP<107>")
	)
	(segment
		(start 59.587892 -345.131136)
		(end 59.583066 -345.092782)
		(width 0.1651)
		(layer "In5.Cu")
		(net "P5E_PEX0_STN6_RX_DN<107>")
	)
	(segment
		(start 68.750434 -386.74675)
		(end 68.063364 -385.087876)
		(width 0.1651)
		(layer "In5.Cu")
		(net "P5E_PEX0_STN6_RX_DN<107>")
	)
	(segment
		(start 80.837024 -401.181062)
		(end 81.481168 -401.181062)
		(width 0.1651)
		(layer "In5.Cu")
		(net "P5E_PEX0_STN6_RX_DN<107>")
	)
	(segment
		(start 81.481168 -401.181062)
		(end 81.884266 -400.777964)
		(width 0.1651)
		(layer "In5.Cu")
		(net "P5E_PEX0_STN6_RX_DN<107>")
	)
	(segment
		(start 74.635614 -389.984996)
		(end 70.117716 -388.114032)
		(width 0.1651)
		(layer "In5.Cu")
		(net "P5E_PEX0_STN6_RX_DN<107>")
	)
	(segment
		(start 47.62373 -323.870574)
		(end 46.96587 -322.283074)
		(width 0.1651)
		(layer "In5.Cu")
		(net "P5E_PEX0_STN6_RX_DN<107>")
	)
	(segment
		(start 59.587638 -345.131136)
		(end 59.587892 -345.131136)
		(width 0.1651)
		(layer "In5.Cu")
		(net "P5E_PEX0_STN6_RX_DN<107>")
	)
	(segment
		(start 68.063364 -385.087876)
		(end 66.415158 -368.35715)
		(width 0.1651)
		(layer "In5.Cu")
		(net "P5E_PEX0_STN6_RX_DN<107>")
	)
	(segment
		(start 70.117716 -388.114032)
		(end 68.750434 -386.74675)
		(width 0.1651)
		(layer "In5.Cu")
		(net "P5E_PEX0_STN6_RX_DN<107>")
	)
	(segment
		(start 46.96587 -319.995296)
		(end 46.96587 -319.966848)
		(width 0.1143)
		(layer "In5.Cu")
		(net "P5E_PEX0_STN6_RX_DN<107>")
	)
	(segment
		(start 47.29988 -316.534292)
		(end 47.29988 -316.799722)
		(width 0.1143)
		(layer "In5.Cu")
		(net "P5E_PEX0_STN6_RX_DN<107>")
	)
	(segment
		(start 46.96587 -322.283074)
		(end 46.96587 -319.995296)
		(width 0.1651)
		(layer "In5.Cu")
		(net "P5E_PEX0_STN6_RX_DN<107>")
	)
	(segment
		(start 60.396374 -351.68586)
		(end 59.587638 -345.131136)
		(width 0.1651)
		(layer "In5.Cu")
		(net "P5E_PEX0_STN6_RX_DN<107>")
	)
	(segment
		(start 80.710024 -401.690078)
		(end 80.710024 -401.308062)
		(width 0.1651)
		(layer "In5.Cu")
		(net "P5E_PEX0_STN6_RX_DN<107>")
	)
	(segment
		(start 81.884266 -395.806422)
		(end 81.57337 -394.781532)
		(width 0.1651)
		(layer "In5.Cu")
		(net "P5E_PEX0_STN6_RX_DN<107>")
	)
	(segment
		(start 81.57337 -394.781532)
		(end 81.417922 -394.548868)
		(width 0.1651)
		(layer "In5.Cu")
		(net "P5E_PEX0_STN6_RX_DN<107>")
	)
	(segment
		(start 55.961788 -336.349086)
		(end 47.62373 -323.870574)
		(width 0.1651)
		(layer "In5.Cu")
		(net "P5E_PEX0_STN6_RX_DN<107>")
	)
	(segment
		(start 81.417922 -394.548868)
		(end 80.550004 -393.836652)
		(width 0.1651)
		(layer "In5.Cu")
		(net "P5E_PEX0_STN6_RX_DN<107>")
	)
	(segment
		(start 81.884266 -400.777964)
		(end 81.884266 -395.806422)
		(width 0.1651)
		(layer "In5.Cu")
		(net "P5E_PEX0_STN6_RX_DN<107>")
	)
	(segment
		(start 46.92015 -319.921128)
		(end 46.92015 -316.534292)
		(width 0.1143)
		(layer "In5.Cu")
		(net "P5E_PEX0_STN6_RX_DN<107>")
	)
	(segment
		(start 46.92015 -316.534292)
		(end 47.03445 -316.419992)
		(width 0.1143)
		(layer "In5.Cu")
		(net "P5E_PEX0_STN6_RX_DN<107>")
	)
	(segment
		(start 47.03445 -316.419992)
		(end 47.18558 -316.419992)
		(width 0.1143)
		(layer "In5.Cu")
		(net "P5E_PEX0_STN6_RX_DN<107>")
	)
	(segment
		(start 77.63002 -391.780268)
		(end 74.635614 -389.984996)
		(width 0.1651)
		(layer "In5.Cu")
		(net "P5E_PEX0_STN6_RX_DN<107>")
	)
	(segment
		(start 80.710024 -401.308062)
		(end 80.837024 -401.181062)
		(width 0.1651)
		(layer "In5.Cu")
		(net "P5E_PEX0_STN6_RX_DN<107>")
	)
	(segment
		(start 46.96587 -319.966848)
		(end 46.92015 -319.921128)
		(width 0.1143)
		(layer "In5.Cu")
		(net "P5E_PEX0_STN6_RX_DN<107>")
	)
	(segment
		(start 66.415158 -368.35715)
		(end 61.159136 -354.73132)
		(width 0.1651)
		(layer "In5.Cu")
		(net "P5E_PEX0_STN6_RX_DN<107>")
	)
	(segment
		(start 59.583066 -345.092782)
		(end 55.961788 -336.349086)
		(width 0.1651)
		(layer "In5.Cu")
		(net "P5E_PEX0_STN6_RX_DN<107>")
	)
	(segment
		(start 47.18558 -316.419992)
		(end 47.29988 -316.534292)
		(width 0.1143)
		(layer "In5.Cu")
		(net "P5E_PEX0_STN6_RX_DN<107>")
	)
	(segment
		(start 80.550004 -393.836652)
		(end 77.63002 -391.780268)
		(width 0.1651)
		(layer "In5.Cu")
		(net "P5E_PEX0_STN6_RX_DN<107>")
	)
	(segment
		(start 61.159136 -354.73132)
		(end 60.396374 -351.68586)
		(width 0.1651)
		(layer "In5.Cu")
		(net "P5E_PEX0_STN6_RX_DN<107>")
	)
	(segment
		(start 121.188988 -351.611438)
		(end 121.483628 -351.316798)
		(width 0.13462)
		(layer "F.Cu")
		(net "P5E_PEX1_STN6_TX_C_DP<107>")
	)
	(segment
		(start 121.483628 -350.685354)
		(end 121.163588 -350.365314)
		(width 0.13462)
		(layer "F.Cu")
		(net "P5E_PEX1_STN6_TX_C_DP<107>")
	)
	(segment
		(start 121.483628 -351.316798)
		(end 121.483628 -350.685354)
		(width 0.13462)
		(layer "F.Cu")
		(net "P5E_PEX1_STN6_TX_C_DP<107>")
	)
	(segment
		(start 119.925338 -358.177846)
		(end 119.925338 -353.993196)
		(width 0.1651)
		(layer "In13.Cu")
		(net "P5E_PEX1_STN6_TX_C_DP<107>")
	)
	(segment
		(start 111.805974 -385.84251)
		(end 111.151924 -383.487676)
		(width 0.1651)
		(layer "In13.Cu")
		(net "P5E_PEX1_STN6_TX_C_DP<107>")
	)
	(segment
		(start 123.657614 -393.413996)
		(end 123.24588 -393.138914)
		(width 0.1651)
		(layer "In13.Cu")
		(net "P5E_PEX1_STN6_TX_C_DP<107>")
	)
	(segment
		(start 121.479818 -352.438716)
		(end 121.479818 -351.902268)
		(width 0.1651)
		(layer "In13.Cu")
		(net "P5E_PEX1_STN6_TX_C_DP<107>")
	)
	(segment
		(start 114.036602 -388.432802)
		(end 114.036856 -388.432802)
		(width 0.1651)
		(layer "In13.Cu")
		(net "P5E_PEX1_STN6_TX_C_DP<107>")
	)
	(segment
		(start 115.121944 -389.317738)
		(end 114.036602 -388.432802)
		(width 0.1651)
		(layer "In13.Cu")
		(net "P5E_PEX1_STN6_TX_C_DP<107>")
	)
	(segment
		(start 121.450608 -391.939272)
		(end 115.121944 -389.317738)
		(width 0.1651)
		(layer "In13.Cu")
		(net "P5E_PEX1_STN6_TX_C_DP<107>")
	)
	(segment
		(start 124.101098 -393.847828)
		(end 123.68911 -393.572492)
		(width 0.1651)
		(layer "In13.Cu")
		(net "P5E_PEX1_STN6_TX_C_DP<107>")
	)
	(segment
		(start 125.058678 -408.699208)
		(end 125.584966 -408.17292)
		(width 0.1651)
		(layer "In13.Cu")
		(net "P5E_PEX1_STN6_TX_C_DP<107>")
	)
	(segment
		(start 122.643646 -392.736324)
		(end 121.450608 -391.939272)
		(width 0.1651)
		(layer "In13.Cu")
		(net "P5E_PEX1_STN6_TX_C_DP<107>")
	)
	(segment
		(start 124.259848 -393.816332)
		(end 124.101098 -393.847828)
		(width 0.1651)
		(layer "In13.Cu")
		(net "P5E_PEX1_STN6_TX_C_DP<107>")
	)
	(segment
		(start 123.087384 -393.17041)
		(end 122.675142 -392.895074)
		(width 0.1651)
		(layer "In13.Cu")
		(net "P5E_PEX1_STN6_TX_C_DP<107>")
	)
	(segment
		(start 111.151924 -383.487676)
		(end 111.25962 -367.493296)
		(width 0.1651)
		(layer "In13.Cu")
		(net "P5E_PEX1_STN6_TX_C_DP<107>")
	)
	(segment
		(start 122.675142 -392.895074)
		(end 122.643646 -392.736324)
		(width 0.1651)
		(layer "In13.Cu")
		(net "P5E_PEX1_STN6_TX_C_DP<107>")
	)
	(segment
		(start 121.479818 -351.902268)
		(end 121.188988 -351.611438)
		(width 0.1651)
		(layer "In13.Cu")
		(net "P5E_PEX1_STN6_TX_C_DP<107>")
	)
	(segment
		(start 125.584966 -408.17292)
		(end 125.584966 -394.92174)
		(width 0.1651)
		(layer "In13.Cu")
		(net "P5E_PEX1_STN6_TX_C_DP<107>")
	)
	(segment
		(start 119.925338 -353.993196)
		(end 121.479818 -352.438716)
		(width 0.1651)
		(layer "In13.Cu")
		(net "P5E_PEX1_STN6_TX_C_DP<107>")
	)
	(segment
		(start 111.696246 -366.624108)
		(end 119.397272 -359.397046)
		(width 0.1651)
		(layer "In13.Cu")
		(net "P5E_PEX1_STN6_TX_C_DP<107>")
	)
	(segment
		(start 112.951514 -387.547866)
		(end 111.805974 -385.84251)
		(width 0.1651)
		(layer "In13.Cu")
		(net "P5E_PEX1_STN6_TX_C_DP<107>")
	)
	(segment
		(start 124.71019 -408.190192)
		(end 124.71019 -408.572208)
		(width 0.1651)
		(layer "In13.Cu")
		(net "P5E_PEX1_STN6_TX_C_DP<107>")
	)
	(segment
		(start 125.584966 -394.92174)
		(end 124.92228 -394.259054)
		(width 0.1651)
		(layer "In13.Cu")
		(net "P5E_PEX1_STN6_TX_C_DP<107>")
	)
	(segment
		(start 124.92228 -394.259054)
		(end 124.259848 -393.816332)
		(width 0.1651)
		(layer "In13.Cu")
		(net "P5E_PEX1_STN6_TX_C_DP<107>")
	)
	(segment
		(start 124.83719 -408.699208)
		(end 125.058678 -408.699208)
		(width 0.1651)
		(layer "In13.Cu")
		(net "P5E_PEX1_STN6_TX_C_DP<107>")
	)
	(segment
		(start 111.25962 -367.493296)
		(end 111.696246 -366.624108)
		(width 0.1651)
		(layer "In13.Cu")
		(net "P5E_PEX1_STN6_TX_C_DP<107>")
	)
	(segment
		(start 119.397272 -359.397046)
		(end 119.925338 -358.177846)
		(width 0.1651)
		(layer "In13.Cu")
		(net "P5E_PEX1_STN6_TX_C_DP<107>")
	)
	(segment
		(start 124.71019 -408.572208)
		(end 124.83719 -408.699208)
		(width 0.1651)
		(layer "In13.Cu")
		(net "P5E_PEX1_STN6_TX_C_DP<107>")
	)
	(segment
		(start 123.24588 -393.138914)
		(end 123.087384 -393.17041)
		(width 0.1651)
		(layer "In13.Cu")
		(net "P5E_PEX1_STN6_TX_C_DP<107>")
	)
	(segment
		(start 114.036856 -388.432802)
		(end 112.951514 -387.547866)
		(width 0.1651)
		(layer "In13.Cu")
		(net "P5E_PEX1_STN6_TX_C_DP<107>")
	)
	(segment
		(start 123.68911 -393.572492)
		(end 123.657614 -393.413996)
		(width 0.1651)
		(layer "In13.Cu")
		(net "P5E_PEX1_STN6_TX_C_DP<107>")
	)
	(segment
		(start 121.757948 -350.685354)
		(end 122.077988 -350.365314)
		(width 0.13462)
		(layer "F.Cu")
		(net "P5E_PEX1_STN6_TX_C_DN<107>")
	)
	(segment
		(start 121.757948 -351.316798)
		(end 121.757948 -350.685354)
		(width 0.13462)
		(layer "F.Cu")
		(net "P5E_PEX1_STN6_TX_C_DN<107>")
	)
	(segment
		(start 122.052588 -351.611438)
		(end 121.757948 -351.316798)
		(width 0.13462)
		(layer "F.Cu")
		(net "P5E_PEX1_STN6_TX_C_DN<107>")
	)
	(segment
		(start 125.175518 -408.981148)
		(end 125.866906 -408.28976)
		(width 0.1651)
		(layer "In13.Cu")
		(net "P5E_PEX1_STN6_TX_C_DN<107>")
	)
	(segment
		(start 125.102112 -394.040106)
		(end 121.584212 -391.689336)
		(width 0.1651)
		(layer "In13.Cu")
		(net "P5E_PEX1_STN6_TX_C_DN<107>")
	)
	(segment
		(start 121.761758 -351.902268)
		(end 122.052588 -351.611438)
		(width 0.1651)
		(layer "In13.Cu")
		(net "P5E_PEX1_STN6_TX_C_DN<107>")
	)
	(segment
		(start 125.866906 -394.8049)
		(end 125.102112 -394.040106)
		(width 0.1651)
		(layer "In13.Cu")
		(net "P5E_PEX1_STN6_TX_C_DN<107>")
	)
	(segment
		(start 124.71019 -409.108148)
		(end 124.83719 -408.981148)
		(width 0.1651)
		(layer "In13.Cu")
		(net "P5E_PEX1_STN6_TX_C_DN<107>")
	)
	(segment
		(start 124.83719 -408.981148)
		(end 125.175518 -408.981148)
		(width 0.1651)
		(layer "In13.Cu")
		(net "P5E_PEX1_STN6_TX_C_DN<107>")
	)
	(segment
		(start 113.162334 -387.355588)
		(end 112.065562 -385.72313)
		(width 0.1651)
		(layer "In13.Cu")
		(net "P5E_PEX1_STN6_TX_C_DN<107>")
	)
	(segment
		(start 124.71019 -409.490164)
		(end 124.71019 -409.108148)
		(width 0.1651)
		(layer "In13.Cu")
		(net "P5E_PEX1_STN6_TX_C_DN<107>")
	)
	(segment
		(start 120.207278 -358.236266)
		(end 120.207278 -354.110036)
		(width 0.1651)
		(layer "In13.Cu")
		(net "P5E_PEX1_STN6_TX_C_DN<107>")
	)
	(segment
		(start 121.584212 -391.689336)
		(end 115.268248 -389.072882)
		(width 0.1651)
		(layer "In13.Cu")
		(net "P5E_PEX1_STN6_TX_C_DN<107>")
	)
	(segment
		(start 125.866906 -408.28976)
		(end 125.866906 -394.8049)
		(width 0.1651)
		(layer "In13.Cu")
		(net "P5E_PEX1_STN6_TX_C_DN<107>")
	)
	(segment
		(start 120.207278 -354.110036)
		(end 121.761758 -352.555556)
		(width 0.1651)
		(layer "In13.Cu")
		(net "P5E_PEX1_STN6_TX_C_DN<107>")
	)
	(segment
		(start 111.925862 -366.795558)
		(end 119.632984 -359.562908)
		(width 0.1651)
		(layer "In13.Cu")
		(net "P5E_PEX1_STN6_TX_C_DN<107>")
	)
	(segment
		(start 121.761758 -352.555556)
		(end 121.761758 -351.902268)
		(width 0.1651)
		(layer "In13.Cu")
		(net "P5E_PEX1_STN6_TX_C_DN<107>")
	)
	(segment
		(start 112.065562 -385.72313)
		(end 111.434372 -383.450084)
		(width 0.1651)
		(layer "In13.Cu")
		(net "P5E_PEX1_STN6_TX_C_DN<107>")
	)
	(segment
		(start 111.541306 -367.561114)
		(end 111.925862 -366.795558)
		(width 0.1651)
		(layer "In13.Cu")
		(net "P5E_PEX1_STN6_TX_C_DN<107>")
	)
	(segment
		(start 119.632984 -359.562908)
		(end 120.207278 -358.236266)
		(width 0.1651)
		(layer "In13.Cu")
		(net "P5E_PEX1_STN6_TX_C_DN<107>")
	)
	(segment
		(start 115.268248 -389.072882)
		(end 113.162334 -387.355588)
		(width 0.1651)
		(layer "In13.Cu")
		(net "P5E_PEX1_STN6_TX_C_DN<107>")
	)
	(segment
		(start 111.434372 -383.450084)
		(end 111.541306 -367.561114)
		(width 0.1651)
		(layer "In13.Cu")
		(net "P5E_PEX1_STN6_TX_C_DN<107>")
	)
	(segment
		(start 70.699122 -351.611438)
		(end 70.993762 -351.316798)
		(width 0.13462)
		(layer "F.Cu")
		(net "P5E_PEX0_STN6_TX_C_DP<107>")
	)
	(segment
		(start 70.993762 -351.316798)
		(end 70.993762 -350.685354)
		(width 0.13462)
		(layer "F.Cu")
		(net "P5E_PEX0_STN6_TX_C_DP<107>")
	)
	(segment
		(start 70.993762 -350.685354)
		(end 70.673722 -350.365314)
		(width 0.13462)
		(layer "F.Cu")
		(net "P5E_PEX0_STN6_TX_C_DP<107>")
	)
	(segment
		(start 69.223382 -361.384596)
		(end 69.435472 -359.233978)
		(width 0.1651)
		(layer "In13.Cu")
		(net "P5E_PEX0_STN6_TX_C_DP<107>")
	)
	(segment
		(start 81.602326 -394.802106)
		(end 80.990948 -394.190982)
		(width 0.1651)
		(layer "In13.Cu")
		(net "P5E_PEX0_STN6_TX_C_DP<107>")
	)
	(segment
		(start 80.990948 -394.190982)
		(end 80.463136 -393.908788)
		(width 0.1651)
		(layer "In13.Cu")
		(net "P5E_PEX0_STN6_TX_C_DP<107>")
	)
	(segment
		(start 80.463136 -393.908788)
		(end 80.30845 -393.955778)
		(width 0.1651)
		(layer "In13.Cu")
		(net "P5E_PEX0_STN6_TX_C_DP<107>")
	)
	(segment
		(start 80.837024 -408.699208)
		(end 81.286096 -408.699208)
		(width 0.1651)
		(layer "In13.Cu")
		(net "P5E_PEX0_STN6_TX_C_DP<107>")
	)
	(segment
		(start 80.710024 -408.572208)
		(end 80.837024 -408.699208)
		(width 0.1651)
		(layer "In13.Cu")
		(net "P5E_PEX0_STN6_TX_C_DP<107>")
	)
	(segment
		(start 80.30845 -393.955778)
		(end 79.871316 -393.722098)
		(width 0.1651)
		(layer "In13.Cu")
		(net "P5E_PEX0_STN6_TX_C_DP<107>")
	)
	(segment
		(start 70.989952 -352.417888)
		(end 70.989952 -351.902268)
		(width 0.1651)
		(layer "In13.Cu")
		(net "P5E_PEX0_STN6_TX_C_DP<107>")
	)
	(segment
		(start 80.710024 -408.190192)
		(end 80.710024 -408.572208)
		(width 0.1651)
		(layer "In13.Cu")
		(net "P5E_PEX0_STN6_TX_C_DP<107>")
	)
	(segment
		(start 79.871316 -393.722098)
		(end 79.824326 -393.567412)
		(width 0.1651)
		(layer "In13.Cu")
		(net "P5E_PEX0_STN6_TX_C_DP<107>")
	)
	(segment
		(start 79.824326 -393.567412)
		(end 79.3877 -393.333986)
		(width 0.1651)
		(layer "In13.Cu")
		(net "P5E_PEX0_STN6_TX_C_DP<107>")
	)
	(segment
		(start 69.435472 -353.972368)
		(end 70.989952 -352.417888)
		(width 0.1651)
		(layer "In13.Cu")
		(net "P5E_PEX0_STN6_TX_C_DP<107>")
	)
	(segment
		(start 81.286096 -408.699208)
		(end 81.602326 -408.382978)
		(width 0.1651)
		(layer "In13.Cu")
		(net "P5E_PEX0_STN6_TX_C_DP<107>")
	)
	(segment
		(start 70.989952 -351.902268)
		(end 70.699122 -351.611438)
		(width 0.1651)
		(layer "In13.Cu")
		(net "P5E_PEX0_STN6_TX_C_DP<107>")
	)
	(segment
		(start 67.38874 -383.995168)
		(end 67.38874 -382.17983)
		(width 0.1651)
		(layer "In13.Cu")
		(net "P5E_PEX0_STN6_TX_C_DP<107>")
	)
	(segment
		(start 79.3877 -393.333986)
		(end 79.233014 -393.380976)
		(width 0.1651)
		(layer "In13.Cu")
		(net "P5E_PEX0_STN6_TX_C_DP<107>")
	)
	(segment
		(start 81.602326 -408.382978)
		(end 81.602326 -394.802106)
		(width 0.1651)
		(layer "In13.Cu")
		(net "P5E_PEX0_STN6_TX_C_DP<107>")
	)
	(segment
		(start 67.38874 -382.17983)
		(end 67.705732 -369.015264)
		(width 0.1651)
		(layer "In13.Cu")
		(net "P5E_PEX0_STN6_TX_C_DP<107>")
	)
	(segment
		(start 79.233014 -393.380976)
		(end 78.79588 -393.147296)
		(width 0.1651)
		(layer "In13.Cu")
		(net "P5E_PEX0_STN6_TX_C_DP<107>")
	)
	(segment
		(start 68.589906 -386.895086)
		(end 67.38874 -383.995168)
		(width 0.1651)
		(layer "In13.Cu")
		(net "P5E_PEX0_STN6_TX_C_DP<107>")
	)
	(segment
		(start 78.79588 -393.147296)
		(end 78.74889 -392.99261)
		(width 0.1651)
		(layer "In13.Cu")
		(net "P5E_PEX0_STN6_TX_C_DP<107>")
	)
	(segment
		(start 78.74889 -392.99261)
		(end 70.023228 -388.328662)
		(width 0.1651)
		(layer "In13.Cu")
		(net "P5E_PEX0_STN6_TX_C_DP<107>")
	)
	(segment
		(start 69.435472 -359.233978)
		(end 69.435472 -353.972368)
		(width 0.1651)
		(layer "In13.Cu")
		(net "P5E_PEX0_STN6_TX_C_DP<107>")
	)
	(segment
		(start 67.705732 -369.015264)
		(end 69.223382 -361.384596)
		(width 0.1651)
		(layer "In13.Cu")
		(net "P5E_PEX0_STN6_TX_C_DP<107>")
	)
	(segment
		(start 70.023228 -388.328662)
		(end 68.589906 -386.895086)
		(width 0.1651)
		(layer "In13.Cu")
		(net "P5E_PEX0_STN6_TX_C_DP<107>")
	)
	(segment
		(start 71.268082 -351.316798)
		(end 71.268082 -350.685354)
		(width 0.13462)
		(layer "F.Cu")
		(net "P5E_PEX0_STN6_TX_C_DN<107>")
	)
	(segment
		(start 71.562722 -351.611438)
		(end 71.268082 -351.316798)
		(width 0.13462)
		(layer "F.Cu")
		(net "P5E_PEX0_STN6_TX_C_DN<107>")
	)
	(segment
		(start 71.268082 -350.685354)
		(end 71.588122 -350.365314)
		(width 0.13462)
		(layer "F.Cu")
		(net "P5E_PEX0_STN6_TX_C_DN<107>")
	)
	(segment
		(start 71.271892 -352.534728)
		(end 71.271892 -351.902268)
		(width 0.1651)
		(layer "In13.Cu")
		(net "P5E_PEX0_STN6_TX_C_DN<107>")
	)
	(segment
		(start 81.884266 -408.499818)
		(end 81.884266 -394.685266)
		(width 0.1651)
		(layer "In13.Cu")
		(net "P5E_PEX0_STN6_TX_C_DN<107>")
	)
	(segment
		(start 67.987164 -369.046506)
		(end 69.502782 -361.425998)
		(width 0.1651)
		(layer "In13.Cu")
		(net "P5E_PEX0_STN6_TX_C_DN<107>")
	)
	(segment
		(start 67.67068 -383.939034)
		(end 67.67068 -382.183386)
		(width 0.1651)
		(layer "In13.Cu")
		(net "P5E_PEX0_STN6_TX_C_DN<107>")
	)
	(segment
		(start 80.710024 -409.108148)
		(end 80.837024 -408.981148)
		(width 0.1651)
		(layer "In13.Cu")
		(net "P5E_PEX0_STN6_TX_C_DN<107>")
	)
	(segment
		(start 68.82892 -386.73532)
		(end 67.67068 -383.939034)
		(width 0.1651)
		(layer "In13.Cu")
		(net "P5E_PEX0_STN6_TX_C_DN<107>")
	)
	(segment
		(start 81.402936 -408.981148)
		(end 81.884266 -408.499818)
		(width 0.1651)
		(layer "In13.Cu")
		(net "P5E_PEX0_STN6_TX_C_DN<107>")
	)
	(segment
		(start 69.502782 -361.425998)
		(end 69.717412 -359.247948)
		(width 0.1651)
		(layer "In13.Cu")
		(net "P5E_PEX0_STN6_TX_C_DN<107>")
	)
	(segment
		(start 70.193154 -388.099554)
		(end 68.82892 -386.73532)
		(width 0.1651)
		(layer "In13.Cu")
		(net "P5E_PEX0_STN6_TX_C_DN<107>")
	)
	(segment
		(start 69.717412 -359.247948)
		(end 69.717412 -354.089208)
		(width 0.1651)
		(layer "In13.Cu")
		(net "P5E_PEX0_STN6_TX_C_DN<107>")
	)
	(segment
		(start 80.837024 -408.981148)
		(end 81.402936 -408.981148)
		(width 0.1651)
		(layer "In13.Cu")
		(net "P5E_PEX0_STN6_TX_C_DN<107>")
	)
	(segment
		(start 71.271892 -351.902268)
		(end 71.562722 -351.611438)
		(width 0.1651)
		(layer "In13.Cu")
		(net "P5E_PEX0_STN6_TX_C_DN<107>")
	)
	(segment
		(start 81.160874 -393.961874)
		(end 70.193154 -388.099554)
		(width 0.1651)
		(layer "In13.Cu")
		(net "P5E_PEX0_STN6_TX_C_DN<107>")
	)
	(segment
		(start 81.884266 -394.685266)
		(end 81.160874 -393.961874)
		(width 0.1651)
		(layer "In13.Cu")
		(net "P5E_PEX0_STN6_TX_C_DN<107>")
	)
	(segment
		(start 67.67068 -382.183386)
		(end 67.987164 -369.046506)
		(width 0.1651)
		(layer "In13.Cu")
		(net "P5E_PEX0_STN6_TX_C_DN<107>")
	)
	(segment
		(start 80.710024 -409.490164)
		(end 80.710024 -409.108148)
		(width 0.1651)
		(layer "In13.Cu")
		(net "P5E_PEX0_STN6_TX_C_DN<107>")
	)
	(segment
		(start 69.717412 -354.089208)
		(end 71.271892 -352.534728)
		(width 0.1651)
		(layer "In13.Cu")
		(net "P5E_PEX0_STN6_TX_C_DN<107>")
	)
	(segment
		(start 124.592588 -345.170506)
		(end 124.592588 -344.539062)
		(width 0.13462)
		(layer "F.Cu")
		(net "P5E_PEX1_STN6_TX_C_DP<106>")
	)
	(segment
		(start 124.592588 -344.539062)
		(end 124.272548 -344.219022)
		(width 0.13462)
		(layer "F.Cu")
		(net "P5E_PEX1_STN6_TX_C_DP<106>")
	)
	(segment
		(start 124.297948 -345.465146)
		(end 124.592588 -345.170506)
		(width 0.13462)
		(layer "F.Cu")
		(net "P5E_PEX1_STN6_TX_C_DP<106>")
	)
	(segment
		(start 113.75644 -386.952998)
		(end 112.731042 -385.426712)
		(width 0.1651)
		(layer "In13.Cu")
		(net "P5E_PEX1_STN6_TX_C_DP<106>")
	)
	(segment
		(start 127.78486 -395.565376)
		(end 126.233428 -393.853162)
		(width 0.1651)
		(layer "In13.Cu")
		(net "P5E_PEX1_STN6_TX_C_DP<106>")
	)
	(segment
		(start 127.78486 -409.27274)
		(end 127.78486 -395.565376)
		(width 0.1651)
		(layer "In13.Cu")
		(net "P5E_PEX1_STN6_TX_C_DP<106>")
	)
	(segment
		(start 122.644916 -358.910382)
		(end 123.034298 -358.091232)
		(width 0.1651)
		(layer "In13.Cu")
		(net "P5E_PEX1_STN6_TX_C_DP<106>")
	)
	(segment
		(start 126.910084 -409.672028)
		(end 127.037084 -409.799028)
		(width 0.1651)
		(layer "In13.Cu")
		(net "P5E_PEX1_STN6_TX_C_DP<106>")
	)
	(segment
		(start 124.588778 -345.755976)
		(end 124.297948 -345.465146)
		(width 0.1651)
		(layer "In13.Cu")
		(net "P5E_PEX1_STN6_TX_C_DP<106>")
	)
	(segment
		(start 123.034298 -347.792802)
		(end 124.588778 -346.238322)
		(width 0.1651)
		(layer "In13.Cu")
		(net "P5E_PEX1_STN6_TX_C_DP<106>")
	)
	(segment
		(start 115.590574 -388.448804)
		(end 113.75644 -386.952998)
		(width 0.1651)
		(layer "In13.Cu")
		(net "P5E_PEX1_STN6_TX_C_DP<106>")
	)
	(segment
		(start 122.314208 -391.234422)
		(end 115.590574 -388.448804)
		(width 0.1651)
		(layer "In13.Cu")
		(net "P5E_PEX1_STN6_TX_C_DP<106>")
	)
	(segment
		(start 112.137444 -383.289556)
		(end 112.240568 -367.906046)
		(width 0.1651)
		(layer "In13.Cu")
		(net "P5E_PEX1_STN6_TX_C_DP<106>")
	)
	(segment
		(start 123.034298 -358.091232)
		(end 123.034298 -347.792802)
		(width 0.1651)
		(layer "In13.Cu")
		(net "P5E_PEX1_STN6_TX_C_DP<106>")
	)
	(segment
		(start 112.687862 -367.015522)
		(end 122.644916 -358.910382)
		(width 0.1651)
		(layer "In13.Cu")
		(net "P5E_PEX1_STN6_TX_C_DP<106>")
	)
	(segment
		(start 112.240568 -367.906046)
		(end 112.687862 -367.015522)
		(width 0.1651)
		(layer "In13.Cu")
		(net "P5E_PEX1_STN6_TX_C_DP<106>")
	)
	(segment
		(start 124.588778 -346.238322)
		(end 124.588778 -345.755976)
		(width 0.1651)
		(layer "In13.Cu")
		(net "P5E_PEX1_STN6_TX_C_DP<106>")
	)
	(segment
		(start 126.233428 -393.853162)
		(end 122.314208 -391.234422)
		(width 0.1651)
		(layer "In13.Cu")
		(net "P5E_PEX1_STN6_TX_C_DP<106>")
	)
	(segment
		(start 112.731042 -385.426712)
		(end 112.137444 -383.289556)
		(width 0.1651)
		(layer "In13.Cu")
		(net "P5E_PEX1_STN6_TX_C_DP<106>")
	)
	(segment
		(start 127.037084 -409.799028)
		(end 127.258572 -409.799028)
		(width 0.1651)
		(layer "In13.Cu")
		(net "P5E_PEX1_STN6_TX_C_DP<106>")
	)
	(segment
		(start 126.910084 -409.290012)
		(end 126.910084 -409.672028)
		(width 0.1651)
		(layer "In13.Cu")
		(net "P5E_PEX1_STN6_TX_C_DP<106>")
	)
	(segment
		(start 127.258572 -409.799028)
		(end 127.78486 -409.27274)
		(width 0.1651)
		(layer "In13.Cu")
		(net "P5E_PEX1_STN6_TX_C_DP<106>")
	)
	(segment
		(start 125.229112 -393.182348)
		(end 125.088396 -393.210288)
		(width 0.1651)
		(layer "In15.Cu")
		(net "P5E_PEX1_STN6_RX_DP<106>")
	)
	(segment
		(start 122.693176 -358.611932)
		(end 123.034298 -357.850694)
		(width 0.1651)
		(layer "In15.Cu")
		(net "P5E_PEX1_STN6_RX_DP<106>")
	)
	(segment
		(start 123.034298 -357.850694)
		(end 123.034298 -341.910416)
		(width 0.1651)
		(layer "In15.Cu")
		(net "P5E_PEX1_STN6_RX_DP<106>")
	)
	(segment
		(start 122.314208 -391.234422)
		(end 115.590574 -388.448804)
		(width 0.1651)
		(layer "In15.Cu")
		(net "P5E_PEX1_STN6_RX_DP<106>")
	)
	(segment
		(start 164.349938 -318.040766)
		(end 164.349938 -317.749936)
		(width 0.1143)
		(layer "In15.Cu")
		(net "P5E_PEX1_STN6_RX_DP<106>")
	)
	(segment
		(start 163.779708 -318.368172)
		(end 164.018214 -318.129666)
		(width 0.1143)
		(layer "In15.Cu")
		(net "P5E_PEX1_STN6_RX_DP<106>")
	)
	(segment
		(start 123.655328 -392.130534)
		(end 122.314208 -391.234422)
		(width 0.1651)
		(layer "In15.Cu")
		(net "P5E_PEX1_STN6_RX_DP<106>")
	)
	(segment
		(start 124.09551 -392.54684)
		(end 123.683522 -392.271504)
		(width 0.1651)
		(layer "In15.Cu")
		(net "P5E_PEX1_STN6_RX_DP<106>")
	)
	(segment
		(start 163.733988 -319.8368)
		(end 163.779708 -319.79108)
		(width 0.1143)
		(layer "In15.Cu")
		(net "P5E_PEX1_STN6_RX_DP<106>")
	)
	(segment
		(start 163.733988 -320.71564)
		(end 163.733988 -319.865248)
		(width 0.1651)
		(layer "In15.Cu")
		(net "P5E_PEX1_STN6_RX_DP<106>")
	)
	(segment
		(start 144.162526 -332.70825)
		(end 161.016188 -324.73519)
		(width 0.1651)
		(layer "In15.Cu")
		(net "P5E_PEX1_STN6_RX_DP<106>")
	)
	(segment
		(start 113.62182 -367.081562)
		(end 114.52987 -365.896398)
		(width 0.1651)
		(layer "In15.Cu")
		(net "P5E_PEX1_STN6_RX_DP<106>")
	)
	(segment
		(start 126.233428 -393.853162)
		(end 125.229112 -393.182348)
		(width 0.1651)
		(layer "In15.Cu")
		(net "P5E_PEX1_STN6_RX_DP<106>")
	)
	(segment
		(start 164.261038 -318.129666)
		(end 164.349938 -318.040766)
		(width 0.1143)
		(layer "In15.Cu")
		(net "P5E_PEX1_STN6_RX_DP<106>")
	)
	(segment
		(start 127.78486 -401.472908)
		(end 127.78486 -395.56563)
		(width 0.1651)
		(layer "In15.Cu")
		(net "P5E_PEX1_STN6_RX_DP<106>")
	)
	(segment
		(start 114.52987 -365.896398)
		(end 122.693176 -358.611932)
		(width 0.1651)
		(layer "In15.Cu")
		(net "P5E_PEX1_STN6_RX_DP<106>")
	)
	(segment
		(start 126.910084 -401.49018)
		(end 126.910084 -401.872196)
		(width 0.1651)
		(layer "In15.Cu")
		(net "P5E_PEX1_STN6_RX_DP<106>")
	)
	(segment
		(start 113.75644 -386.952998)
		(end 112.731042 -385.426712)
		(width 0.1651)
		(layer "In15.Cu")
		(net "P5E_PEX1_STN6_RX_DP<106>")
	)
	(segment
		(start 124.648214 -392.793982)
		(end 124.23648 -392.5189)
		(width 0.1651)
		(layer "In15.Cu")
		(net "P5E_PEX1_STN6_RX_DP<106>")
	)
	(segment
		(start 124.23648 -392.5189)
		(end 124.09551 -392.54684)
		(width 0.1651)
		(layer "In15.Cu")
		(net "P5E_PEX1_STN6_RX_DP<106>")
	)
	(segment
		(start 112.457738 -384.442716)
		(end 112.5601 -369.19535)
		(width 0.1651)
		(layer "In15.Cu")
		(net "P5E_PEX1_STN6_RX_DP<106>")
	)
	(segment
		(start 161.016188 -324.73519)
		(end 162.813746 -322.937632)
		(width 0.1651)
		(layer "In15.Cu")
		(net "P5E_PEX1_STN6_RX_DP<106>")
	)
	(segment
		(start 162.813746 -322.937632)
		(end 163.733988 -320.71564)
		(width 0.1651)
		(layer "In15.Cu")
		(net "P5E_PEX1_STN6_RX_DP<106>")
	)
	(segment
		(start 112.731042 -385.426712)
		(end 112.457738 -384.442716)
		(width 0.1651)
		(layer "In15.Cu")
		(net "P5E_PEX1_STN6_RX_DP<106>")
	)
	(segment
		(start 123.034298 -341.910416)
		(end 123.45035 -341.287354)
		(width 0.1651)
		(layer "In15.Cu")
		(net "P5E_PEX1_STN6_RX_DP<106>")
	)
	(segment
		(start 163.733988 -319.865248)
		(end 163.733988 -319.8368)
		(width 0.1143)
		(layer "In15.Cu")
		(net "P5E_PEX1_STN6_RX_DP<106>")
	)
	(segment
		(start 123.683522 -392.271504)
		(end 123.655328 -392.130534)
		(width 0.1651)
		(layer "In15.Cu")
		(net "P5E_PEX1_STN6_RX_DP<106>")
	)
	(segment
		(start 127.258572 -401.999196)
		(end 127.78486 -401.472908)
		(width 0.1651)
		(layer "In15.Cu")
		(net "P5E_PEX1_STN6_RX_DP<106>")
	)
	(segment
		(start 127.78486 -395.56563)
		(end 126.233428 -393.853162)
		(width 0.1651)
		(layer "In15.Cu")
		(net "P5E_PEX1_STN6_RX_DP<106>")
	)
	(segment
		(start 124.676154 -392.934952)
		(end 124.648214 -392.793982)
		(width 0.1651)
		(layer "In15.Cu")
		(net "P5E_PEX1_STN6_RX_DP<106>")
	)
	(segment
		(start 112.5601 -369.19535)
		(end 113.62182 -367.081562)
		(width 0.1651)
		(layer "In15.Cu")
		(net "P5E_PEX1_STN6_RX_DP<106>")
	)
	(segment
		(start 115.590574 -388.448804)
		(end 113.75644 -386.952998)
		(width 0.1651)
		(layer "In15.Cu")
		(net "P5E_PEX1_STN6_RX_DP<106>")
	)
	(segment
		(start 163.779708 -319.79108)
		(end 163.779708 -318.368172)
		(width 0.1143)
		(layer "In15.Cu")
		(net "P5E_PEX1_STN6_RX_DP<106>")
	)
	(segment
		(start 126.910084 -401.872196)
		(end 127.037084 -401.999196)
		(width 0.1651)
		(layer "In15.Cu")
		(net "P5E_PEX1_STN6_RX_DP<106>")
	)
	(segment
		(start 127.037084 -401.999196)
		(end 127.258572 -401.999196)
		(width 0.1651)
		(layer "In15.Cu")
		(net "P5E_PEX1_STN6_RX_DP<106>")
	)
	(segment
		(start 123.45035 -341.287354)
		(end 144.162526 -332.70825)
		(width 0.1651)
		(layer "In15.Cu")
		(net "P5E_PEX1_STN6_RX_DP<106>")
	)
	(segment
		(start 125.088396 -393.210288)
		(end 124.676154 -392.934952)
		(width 0.1651)
		(layer "In15.Cu")
		(net "P5E_PEX1_STN6_RX_DP<106>")
	)
	(segment
		(start 164.018214 -318.129666)
		(end 164.261038 -318.129666)
		(width 0.1143)
		(layer "In15.Cu")
		(net "P5E_PEX1_STN6_RX_DP<106>")
	)
	(segment
		(start 113.86185 -367.23193)
		(end 114.737642 -366.089184)
		(width 0.1651)
		(layer "In15.Cu")
		(net "P5E_PEX1_STN6_RX_DN<106>")
	)
	(segment
		(start 127.037084 -402.281136)
		(end 127.375412 -402.281136)
		(width 0.1651)
		(layer "In15.Cu")
		(net "P5E_PEX1_STN6_RX_DN<106>")
	)
	(segment
		(start 115.736878 -388.203948)
		(end 113.96726 -386.76072)
		(width 0.1651)
		(layer "In15.Cu")
		(net "P5E_PEX1_STN6_RX_DN<106>")
	)
	(segment
		(start 128.0668 -395.456664)
		(end 126.419102 -393.638024)
		(width 0.1651)
		(layer "In15.Cu")
		(net "P5E_PEX1_STN6_RX_DN<106>")
	)
	(segment
		(start 113.96726 -386.76072)
		(end 112.99063 -385.307332)
		(width 0.1651)
		(layer "In15.Cu")
		(net "P5E_PEX1_STN6_RX_DN<106>")
	)
	(segment
		(start 164.015928 -320.771774)
		(end 164.015928 -319.865248)
		(width 0.1651)
		(layer "In15.Cu")
		(net "P5E_PEX1_STN6_RX_DN<106>")
	)
	(segment
		(start 164.349938 -318.409066)
		(end 164.349938 -318.699896)
		(width 0.1143)
		(layer "In15.Cu")
		(net "P5E_PEX1_STN6_RX_DN<106>")
	)
	(segment
		(start 112.99063 -385.307332)
		(end 112.740186 -384.405124)
		(width 0.1651)
		(layer "In15.Cu")
		(net "P5E_PEX1_STN6_RX_DN<106>")
	)
	(segment
		(start 123.637294 -341.515192)
		(end 144.276826 -332.966314)
		(width 0.1651)
		(layer "In15.Cu")
		(net "P5E_PEX1_STN6_RX_DN<106>")
	)
	(segment
		(start 163.05276 -323.097398)
		(end 164.015928 -320.771774)
		(width 0.1651)
		(layer "In15.Cu")
		(net "P5E_PEX1_STN6_RX_DN<106>")
	)
	(segment
		(start 126.910084 -402.790152)
		(end 126.910084 -402.408136)
		(width 0.1651)
		(layer "In15.Cu")
		(net "P5E_PEX1_STN6_RX_DN<106>")
	)
	(segment
		(start 163.970208 -319.79108)
		(end 163.970208 -318.447166)
		(width 0.1143)
		(layer "In15.Cu")
		(net "P5E_PEX1_STN6_RX_DN<106>")
	)
	(segment
		(start 112.740186 -384.405124)
		(end 112.841786 -369.263168)
		(width 0.1651)
		(layer "In15.Cu")
		(net "P5E_PEX1_STN6_RX_DN<106>")
	)
	(segment
		(start 112.841786 -369.263168)
		(end 113.86185 -367.23193)
		(width 0.1651)
		(layer "In15.Cu")
		(net "P5E_PEX1_STN6_RX_DN<106>")
	)
	(segment
		(start 114.737642 -366.089184)
		(end 122.926094 -358.782366)
		(width 0.1651)
		(layer "In15.Cu")
		(net "P5E_PEX1_STN6_RX_DN<106>")
	)
	(segment
		(start 144.276826 -332.966314)
		(end 161.181034 -324.969124)
		(width 0.1651)
		(layer "In15.Cu")
		(net "P5E_PEX1_STN6_RX_DN<106>")
	)
	(segment
		(start 127.375412 -402.281136)
		(end 128.0668 -401.589748)
		(width 0.1651)
		(layer "In15.Cu")
		(net "P5E_PEX1_STN6_RX_DN<106>")
	)
	(segment
		(start 164.015928 -319.8368)
		(end 163.970208 -319.79108)
		(width 0.1143)
		(layer "In15.Cu")
		(net "P5E_PEX1_STN6_RX_DN<106>")
	)
	(segment
		(start 122.926094 -358.782366)
		(end 123.316238 -357.911146)
		(width 0.1651)
		(layer "In15.Cu")
		(net "P5E_PEX1_STN6_RX_DN<106>")
	)
	(segment
		(start 123.316238 -341.996014)
		(end 123.637294 -341.515192)
		(width 0.1651)
		(layer "In15.Cu")
		(net "P5E_PEX1_STN6_RX_DN<106>")
	)
	(segment
		(start 164.097208 -318.320166)
		(end 164.261038 -318.320166)
		(width 0.1143)
		(layer "In15.Cu")
		(net "P5E_PEX1_STN6_RX_DN<106>")
	)
	(segment
		(start 161.181034 -324.969124)
		(end 163.05276 -323.097398)
		(width 0.1651)
		(layer "In15.Cu")
		(net "P5E_PEX1_STN6_RX_DN<106>")
	)
	(segment
		(start 126.910084 -402.408136)
		(end 127.037084 -402.281136)
		(width 0.1651)
		(layer "In15.Cu")
		(net "P5E_PEX1_STN6_RX_DN<106>")
	)
	(segment
		(start 163.970208 -318.447166)
		(end 164.097208 -318.320166)
		(width 0.1143)
		(layer "In15.Cu")
		(net "P5E_PEX1_STN6_RX_DN<106>")
	)
	(segment
		(start 164.261038 -318.320166)
		(end 164.349938 -318.409066)
		(width 0.1143)
		(layer "In15.Cu")
		(net "P5E_PEX1_STN6_RX_DN<106>")
	)
	(segment
		(start 126.419102 -393.638024)
		(end 122.447812 -390.984486)
		(width 0.1651)
		(layer "In15.Cu")
		(net "P5E_PEX1_STN6_RX_DN<106>")
	)
	(segment
		(start 122.447812 -390.984486)
		(end 115.736878 -388.203948)
		(width 0.1651)
		(layer "In15.Cu")
		(net "P5E_PEX1_STN6_RX_DN<106>")
	)
	(segment
		(start 128.0668 -401.589748)
		(end 128.0668 -395.456664)
		(width 0.1651)
		(layer "In15.Cu")
		(net "P5E_PEX1_STN6_RX_DN<106>")
	)
	(segment
		(start 164.015928 -319.865248)
		(end 164.015928 -319.8368)
		(width 0.1143)
		(layer "In15.Cu")
		(net "P5E_PEX1_STN6_RX_DN<106>")
	)
	(segment
		(start 123.316238 -357.911146)
		(end 123.316238 -341.996014)
		(width 0.1651)
		(layer "In15.Cu")
		(net "P5E_PEX1_STN6_RX_DN<106>")
	)
	(segment
		(start 70.498716 -387.54304)
		(end 69.367908 -386.412232)
		(width 0.1651)
		(layer "In5.Cu")
		(net "P5E_PEX0_STN6_RX_DP<106>")
	)
	(segment
		(start 63.217552 -341.556086)
		(end 61.723524 -339.320124)
		(width 0.1651)
		(layer "In5.Cu")
		(net "P5E_PEX0_STN6_RX_DP<106>")
	)
	(segment
		(start 47.63389 -319.966848)
		(end 47.67961 -319.921128)
		(width 0.1143)
		(layer "In5.Cu")
		(net "P5E_PEX0_STN6_RX_DP<106>")
	)
	(segment
		(start 82.909918 -401.49018)
		(end 82.909918 -401.872196)
		(width 0.1651)
		(layer "In5.Cu")
		(net "P5E_PEX0_STN6_RX_DP<106>")
	)
	(segment
		(start 81.591912 -393.601702)
		(end 81.43621 -393.62888)
		(width 0.1651)
		(layer "In5.Cu")
		(net "P5E_PEX0_STN6_RX_DP<106>")
	)
	(segment
		(start 47.905416 -318.129666)
		(end 48.13554 -318.129666)
		(width 0.1143)
		(layer "In5.Cu")
		(net "P5E_PEX0_STN6_RX_DP<106>")
	)
	(segment
		(start 80.042258 -392.510518)
		(end 78.333346 -391.306812)
		(width 0.1651)
		(layer "In5.Cu")
		(net "P5E_PEX0_STN6_RX_DP<106>")
	)
	(segment
		(start 47.63389 -321.86626)
		(end 47.63389 -319.995296)
		(width 0.1651)
		(layer "In5.Cu")
		(net "P5E_PEX0_STN6_RX_DP<106>")
	)
	(segment
		(start 83.036918 -401.999196)
		(end 83.515708 -401.999196)
		(width 0.1651)
		(layer "In5.Cu")
		(net "P5E_PEX0_STN6_RX_DP<106>")
	)
	(segment
		(start 48.488854 -323.929248)
		(end 47.63389 -321.86626)
		(width 0.1651)
		(layer "In5.Cu")
		(net "P5E_PEX0_STN6_RX_DP<106>")
	)
	(segment
		(start 47.63389 -319.995296)
		(end 47.63389 -319.966848)
		(width 0.1143)
		(layer "In5.Cu")
		(net "P5E_PEX0_STN6_RX_DP<106>")
	)
	(segment
		(start 80.619854 -392.917172)
		(end 80.464152 -392.94435)
		(width 0.1651)
		(layer "In5.Cu")
		(net "P5E_PEX0_STN6_RX_DP<106>")
	)
	(segment
		(start 48.24984 -318.015366)
		(end 48.24984 -317.749936)
		(width 0.1143)
		(layer "In5.Cu")
		(net "P5E_PEX0_STN6_RX_DP<106>")
	)
	(segment
		(start 47.67961 -318.355472)
		(end 47.905416 -318.129666)
		(width 0.1143)
		(layer "In5.Cu")
		(net "P5E_PEX0_STN6_RX_DP<106>")
	)
	(segment
		(start 81.43621 -393.62888)
		(end 81.041494 -393.35075)
		(width 0.1651)
		(layer "In5.Cu")
		(net "P5E_PEX0_STN6_RX_DP<106>")
	)
	(segment
		(start 82.909918 -401.872196)
		(end 83.036918 -401.999196)
		(width 0.1651)
		(layer "In5.Cu")
		(net "P5E_PEX0_STN6_RX_DP<106>")
	)
	(segment
		(start 82.3468 -394.133324)
		(end 81.591912 -393.601702)
		(width 0.1651)
		(layer "In5.Cu")
		(net "P5E_PEX0_STN6_RX_DP<106>")
	)
	(segment
		(start 81.041494 -393.35075)
		(end 81.014316 -393.195048)
		(width 0.1651)
		(layer "In5.Cu")
		(net "P5E_PEX0_STN6_RX_DP<106>")
	)
	(segment
		(start 48.13554 -318.129666)
		(end 48.24984 -318.015366)
		(width 0.1143)
		(layer "In5.Cu")
		(net "P5E_PEX0_STN6_RX_DP<106>")
	)
	(segment
		(start 80.069436 -392.66622)
		(end 80.042258 -392.510518)
		(width 0.1651)
		(layer "In5.Cu")
		(net "P5E_PEX0_STN6_RX_DP<106>")
	)
	(segment
		(start 54.873906 -330.97343)
		(end 48.488854 -323.929248)
		(width 0.1651)
		(layer "In5.Cu")
		(net "P5E_PEX0_STN6_RX_DP<106>")
	)
	(segment
		(start 78.333346 -391.306812)
		(end 75.532742 -389.627872)
		(width 0.1651)
		(layer "In5.Cu")
		(net "P5E_PEX0_STN6_RX_DP<106>")
	)
	(segment
		(start 66.987674 -367.300002)
		(end 63.217552 -358.196642)
		(width 0.1651)
		(layer "In5.Cu")
		(net "P5E_PEX0_STN6_RX_DP<106>")
	)
	(segment
		(start 47.67961 -319.921128)
		(end 47.67961 -318.355472)
		(width 0.1143)
		(layer "In5.Cu")
		(net "P5E_PEX0_STN6_RX_DP<106>")
	)
	(segment
		(start 83.80222 -401.712684)
		(end 83.80222 -396.948406)
		(width 0.1651)
		(layer "In5.Cu")
		(net "P5E_PEX0_STN6_RX_DP<106>")
	)
	(segment
		(start 80.464152 -392.94435)
		(end 80.069436 -392.66622)
		(width 0.1651)
		(layer "In5.Cu")
		(net "P5E_PEX0_STN6_RX_DP<106>")
	)
	(segment
		(start 83.448144 -395.781276)
		(end 82.3468 -394.133324)
		(width 0.1651)
		(layer "In5.Cu")
		(net "P5E_PEX0_STN6_RX_DP<106>")
	)
	(segment
		(start 69.367908 -386.412232)
		(end 68.715382 -384.837178)
		(width 0.1651)
		(layer "In5.Cu")
		(net "P5E_PEX0_STN6_RX_DP<106>")
	)
	(segment
		(start 81.014316 -393.195048)
		(end 80.619854 -392.917172)
		(width 0.1651)
		(layer "In5.Cu")
		(net "P5E_PEX0_STN6_RX_DP<106>")
	)
	(segment
		(start 83.515708 -401.999196)
		(end 83.80222 -401.712684)
		(width 0.1651)
		(layer "In5.Cu")
		(net "P5E_PEX0_STN6_RX_DP<106>")
	)
	(segment
		(start 61.723524 -339.320124)
		(end 54.873906 -330.97343)
		(width 0.1651)
		(layer "In5.Cu")
		(net "P5E_PEX0_STN6_RX_DP<106>")
	)
	(segment
		(start 68.715382 -384.837178)
		(end 66.987674 -367.300002)
		(width 0.1651)
		(layer "In5.Cu")
		(net "P5E_PEX0_STN6_RX_DP<106>")
	)
	(segment
		(start 63.217552 -358.196642)
		(end 63.217552 -341.556086)
		(width 0.1651)
		(layer "In5.Cu")
		(net "P5E_PEX0_STN6_RX_DP<106>")
	)
	(segment
		(start 83.80222 -396.948406)
		(end 83.448144 -395.781276)
		(width 0.1651)
		(layer "In5.Cu")
		(net "P5E_PEX0_STN6_RX_DP<106>")
	)
	(segment
		(start 75.532742 -389.627872)
		(end 70.498716 -387.54304)
		(width 0.1651)
		(layer "In5.Cu")
		(net "P5E_PEX0_STN6_RX_DP<106>")
	)
	(segment
		(start 69.606922 -386.252466)
		(end 68.991988 -384.767836)
		(width 0.1651)
		(layer "In5.Cu")
		(net "P5E_PEX0_STN6_RX_DN<106>")
	)
	(segment
		(start 83.705954 -395.659356)
		(end 82.552032 -393.932918)
		(width 0.1651)
		(layer "In5.Cu")
		(net "P5E_PEX0_STN6_RX_DN<106>")
	)
	(segment
		(start 48.730662 -323.776086)
		(end 47.91583 -321.810126)
		(width 0.1651)
		(layer "In5.Cu")
		(net "P5E_PEX0_STN6_RX_DN<106>")
	)
	(segment
		(start 47.98441 -318.320166)
		(end 48.13554 -318.320166)
		(width 0.1143)
		(layer "In5.Cu")
		(net "P5E_PEX0_STN6_RX_DN<106>")
	)
	(segment
		(start 63.499492 -358.140508)
		(end 63.499492 -341.470488)
		(width 0.1651)
		(layer "In5.Cu")
		(net "P5E_PEX0_STN6_RX_DN<106>")
	)
	(segment
		(start 47.91583 -319.966848)
		(end 47.87011 -319.921128)
		(width 0.1143)
		(layer "In5.Cu")
		(net "P5E_PEX0_STN6_RX_DN<106>")
	)
	(segment
		(start 82.909918 -402.408136)
		(end 83.036918 -402.281136)
		(width 0.1651)
		(layer "In5.Cu")
		(net "P5E_PEX0_STN6_RX_DN<106>")
	)
	(segment
		(start 63.499492 -341.470488)
		(end 61.950346 -339.151976)
		(width 0.1651)
		(layer "In5.Cu")
		(net "P5E_PEX0_STN6_RX_DN<106>")
	)
	(segment
		(start 48.13554 -318.320166)
		(end 48.24984 -318.434466)
		(width 0.1143)
		(layer "In5.Cu")
		(net "P5E_PEX0_STN6_RX_DN<106>")
	)
	(segment
		(start 68.991988 -384.767836)
		(end 67.26428 -367.23066)
		(width 0.1651)
		(layer "In5.Cu")
		(net "P5E_PEX0_STN6_RX_DN<106>")
	)
	(segment
		(start 48.24984 -318.434466)
		(end 48.24984 -318.699896)
		(width 0.1143)
		(layer "In5.Cu")
		(net "P5E_PEX0_STN6_RX_DN<106>")
	)
	(segment
		(start 47.87011 -318.434466)
		(end 47.98441 -318.320166)
		(width 0.1143)
		(layer "In5.Cu")
		(net "P5E_PEX0_STN6_RX_DN<106>")
	)
	(segment
		(start 47.91583 -321.810126)
		(end 47.91583 -319.995296)
		(width 0.1651)
		(layer "In5.Cu")
		(net "P5E_PEX0_STN6_RX_DN<106>")
	)
	(segment
		(start 82.552032 -393.932918)
		(end 78.48727 -391.070338)
		(width 0.1651)
		(layer "In5.Cu")
		(net "P5E_PEX0_STN6_RX_DN<106>")
	)
	(segment
		(start 75.659996 -389.375142)
		(end 70.658482 -387.304026)
		(width 0.1651)
		(layer "In5.Cu")
		(net "P5E_PEX0_STN6_RX_DN<106>")
	)
	(segment
		(start 78.48727 -391.070338)
		(end 75.659996 -389.375142)
		(width 0.1651)
		(layer "In5.Cu")
		(net "P5E_PEX0_STN6_RX_DN<106>")
	)
	(segment
		(start 61.950346 -339.151976)
		(end 55.08752 -330.78928)
		(width 0.1651)
		(layer "In5.Cu")
		(net "P5E_PEX0_STN6_RX_DN<106>")
	)
	(segment
		(start 70.658482 -387.304026)
		(end 69.606922 -386.252466)
		(width 0.1651)
		(layer "In5.Cu")
		(net "P5E_PEX0_STN6_RX_DN<106>")
	)
	(segment
		(start 82.909918 -402.790152)
		(end 82.909918 -402.408136)
		(width 0.1651)
		(layer "In5.Cu")
		(net "P5E_PEX0_STN6_RX_DN<106>")
	)
	(segment
		(start 83.036918 -402.281136)
		(end 83.632548 -402.281136)
		(width 0.1651)
		(layer "In5.Cu")
		(net "P5E_PEX0_STN6_RX_DN<106>")
	)
	(segment
		(start 47.91583 -319.995296)
		(end 47.91583 -319.966848)
		(width 0.1143)
		(layer "In5.Cu")
		(net "P5E_PEX0_STN6_RX_DN<106>")
	)
	(segment
		(start 55.08752 -330.78928)
		(end 48.730662 -323.776086)
		(width 0.1651)
		(layer "In5.Cu")
		(net "P5E_PEX0_STN6_RX_DN<106>")
	)
	(segment
		(start 84.08416 -401.829524)
		(end 84.08416 -396.906496)
		(width 0.1651)
		(layer "In5.Cu")
		(net "P5E_PEX0_STN6_RX_DN<106>")
	)
	(segment
		(start 67.26428 -367.23066)
		(end 63.499492 -358.140508)
		(width 0.1651)
		(layer "In5.Cu")
		(net "P5E_PEX0_STN6_RX_DN<106>")
	)
	(segment
		(start 83.632548 -402.281136)
		(end 84.08416 -401.829524)
		(width 0.1651)
		(layer "In5.Cu")
		(net "P5E_PEX0_STN6_RX_DN<106>")
	)
	(segment
		(start 47.87011 -319.921128)
		(end 47.87011 -318.434466)
		(width 0.1143)
		(layer "In5.Cu")
		(net "P5E_PEX0_STN6_RX_DN<106>")
	)
	(segment
		(start 84.08416 -396.906496)
		(end 83.705954 -395.659356)
		(width 0.1651)
		(layer "In5.Cu")
		(net "P5E_PEX0_STN6_RX_DN<106>")
	)
	(segment
		(start 124.866908 -345.170506)
		(end 124.866908 -344.539062)
		(width 0.13462)
		(layer "F.Cu")
		(net "P5E_PEX1_STN6_TX_C_DN<106>")
	)
	(segment
		(start 125.161548 -345.465146)
		(end 124.866908 -345.170506)
		(width 0.13462)
		(layer "F.Cu")
		(net "P5E_PEX1_STN6_TX_C_DN<106>")
	)
	(segment
		(start 124.866908 -344.539062)
		(end 125.186948 -344.219022)
		(width 0.13462)
		(layer "F.Cu")
		(net "P5E_PEX1_STN6_TX_C_DN<106>")
	)
	(segment
		(start 126.910084 -410.207968)
		(end 126.910084 -410.589984)
		(width 0.1651)
		(layer "In13.Cu")
		(net "P5E_PEX1_STN6_TX_C_DN<106>")
	)
	(segment
		(start 124.870718 -345.755976)
		(end 124.870718 -346.355162)
		(width 0.1651)
		(layer "In13.Cu")
		(net "P5E_PEX1_STN6_TX_C_DN<106>")
	)
	(segment
		(start 124.870718 -346.355162)
		(end 123.316238 -347.909642)
		(width 0.1651)
		(layer "In13.Cu")
		(net "P5E_PEX1_STN6_TX_C_DN<106>")
	)
	(segment
		(start 127.037084 -410.080968)
		(end 126.910084 -410.207968)
		(width 0.1651)
		(layer "In13.Cu")
		(net "P5E_PEX1_STN6_TX_C_DN<106>")
	)
	(segment
		(start 122.447812 -390.984486)
		(end 126.419102 -393.638024)
		(width 0.1651)
		(layer "In13.Cu")
		(net "P5E_PEX1_STN6_TX_C_DN<106>")
	)
	(segment
		(start 122.872246 -359.088944)
		(end 112.912906 -367.196116)
		(width 0.1651)
		(layer "In13.Cu")
		(net "P5E_PEX1_STN6_TX_C_DN<106>")
	)
	(segment
		(start 127.375412 -410.080968)
		(end 127.037084 -410.080968)
		(width 0.1651)
		(layer "In13.Cu")
		(net "P5E_PEX1_STN6_TX_C_DN<106>")
	)
	(segment
		(start 126.419102 -393.638024)
		(end 127.156464 -394.45184)
		(width 0.1651)
		(layer "In13.Cu")
		(net "P5E_PEX1_STN6_TX_C_DN<106>")
	)
	(segment
		(start 128.0668 -409.38958)
		(end 127.375412 -410.080968)
		(width 0.1651)
		(layer "In13.Cu")
		(net "P5E_PEX1_STN6_TX_C_DN<106>")
	)
	(segment
		(start 123.316238 -358.154986)
		(end 122.872246 -359.088944)
		(width 0.1651)
		(layer "In13.Cu")
		(net "P5E_PEX1_STN6_TX_C_DN<106>")
	)
	(segment
		(start 127.156464 -394.45184)
		(end 127.26416 -394.457174)
		(width 0.1651)
		(layer "In13.Cu")
		(net "P5E_PEX1_STN6_TX_C_DN<106>")
	)
	(segment
		(start 112.419892 -383.251964)
		(end 112.99063 -385.307332)
		(width 0.1651)
		(layer "In13.Cu")
		(net "P5E_PEX1_STN6_TX_C_DN<106>")
	)
	(segment
		(start 112.912906 -367.196116)
		(end 112.522254 -367.973864)
		(width 0.1651)
		(layer "In13.Cu")
		(net "P5E_PEX1_STN6_TX_C_DN<106>")
	)
	(segment
		(start 125.161548 -345.465146)
		(end 124.870718 -345.755976)
		(width 0.1651)
		(layer "In13.Cu")
		(net "P5E_PEX1_STN6_TX_C_DN<106>")
	)
	(segment
		(start 115.736878 -388.203948)
		(end 122.447812 -390.984486)
		(width 0.1651)
		(layer "In13.Cu")
		(net "P5E_PEX1_STN6_TX_C_DN<106>")
	)
	(segment
		(start 123.316238 -347.909642)
		(end 123.316238 -358.154986)
		(width 0.1651)
		(layer "In13.Cu")
		(net "P5E_PEX1_STN6_TX_C_DN<106>")
	)
	(segment
		(start 127.59182 -394.932154)
		(end 128.0668 -395.45641)
		(width 0.1651)
		(layer "In13.Cu")
		(net "P5E_PEX1_STN6_TX_C_DN<106>")
	)
	(segment
		(start 113.96726 -386.76072)
		(end 115.736878 -388.203948)
		(width 0.1651)
		(layer "In13.Cu")
		(net "P5E_PEX1_STN6_TX_C_DN<106>")
	)
	(segment
		(start 127.597154 -394.824458)
		(end 127.59182 -394.932154)
		(width 0.1651)
		(layer "In13.Cu")
		(net "P5E_PEX1_STN6_TX_C_DN<106>")
	)
	(segment
		(start 128.0668 -395.45641)
		(end 128.0668 -409.38958)
		(width 0.1651)
		(layer "In13.Cu")
		(net "P5E_PEX1_STN6_TX_C_DN<106>")
	)
	(segment
		(start 112.522254 -367.973864)
		(end 112.419892 -383.251964)
		(width 0.1651)
		(layer "In13.Cu")
		(net "P5E_PEX1_STN6_TX_C_DN<106>")
	)
	(segment
		(start 112.99063 -385.307332)
		(end 113.96726 -386.76072)
		(width 0.1651)
		(layer "In13.Cu")
		(net "P5E_PEX1_STN6_TX_C_DN<106>")
	)
	(segment
		(start 127.26416 -394.457174)
		(end 127.597154 -394.824458)
		(width 0.1651)
		(layer "In13.Cu")
		(net "P5E_PEX1_STN6_TX_C_DN<106>")
	)
	(segment
		(start 73.808082 -345.465146)
		(end 74.102722 -345.170506)
		(width 0.13462)
		(layer "F.Cu")
		(net "P5E_PEX0_STN6_TX_C_DP<106>")
	)
	(segment
		(start 74.102722 -345.170506)
		(end 74.102722 -344.539062)
		(width 0.13462)
		(layer "F.Cu")
		(net "P5E_PEX0_STN6_TX_C_DP<106>")
	)
	(segment
		(start 74.102722 -344.539062)
		(end 73.782682 -344.219022)
		(width 0.13462)
		(layer "F.Cu")
		(net "P5E_PEX0_STN6_TX_C_DP<106>")
	)
	(segment
		(start 83.036918 -409.799028)
		(end 83.564222 -409.799028)
		(width 0.1651)
		(layer "In13.Cu")
		(net "P5E_PEX0_STN6_TX_C_DP<106>")
	)
	(segment
		(start 82.909918 -409.290012)
		(end 82.909918 -409.672028)
		(width 0.1651)
		(layer "In13.Cu")
		(net "P5E_PEX0_STN6_TX_C_DP<106>")
	)
	(segment
		(start 69.421248 -386.33908)
		(end 68.36918 -383.79908)
		(width 0.1651)
		(layer "In13.Cu")
		(net "P5E_PEX0_STN6_TX_C_DP<106>")
	)
	(segment
		(start 73.345294 -388.663942)
		(end 72.01281 -388.112)
		(width 0.1651)
		(layer "In13.Cu")
		(net "P5E_PEX0_STN6_TX_C_DP<106>")
	)
	(segment
		(start 82.909918 -409.672028)
		(end 83.036918 -409.799028)
		(width 0.1651)
		(layer "In13.Cu")
		(net "P5E_PEX0_STN6_TX_C_DP<106>")
	)
	(segment
		(start 72.544432 -359.503218)
		(end 72.544432 -347.866208)
		(width 0.1651)
		(layer "In13.Cu")
		(net "P5E_PEX0_STN6_TX_C_DP<106>")
	)
	(segment
		(start 68.36918 -383.79908)
		(end 68.36918 -382.192276)
		(width 0.1651)
		(layer "In13.Cu")
		(net "P5E_PEX0_STN6_TX_C_DP<106>")
	)
	(segment
		(start 72.544432 -347.866208)
		(end 74.098912 -346.311728)
		(width 0.1651)
		(layer "In13.Cu")
		(net "P5E_PEX0_STN6_TX_C_DP<106>")
	)
	(segment
		(start 74.098912 -346.311728)
		(end 74.098912 -345.755976)
		(width 0.1651)
		(layer "In13.Cu")
		(net "P5E_PEX0_STN6_TX_C_DP<106>")
	)
	(segment
		(start 83.80222 -409.56103)
		(end 83.80222 -395.3256)
		(width 0.1651)
		(layer "In13.Cu")
		(net "P5E_PEX0_STN6_TX_C_DP<106>")
	)
	(segment
		(start 69.313552 -366.33277)
		(end 72.544432 -359.503218)
		(width 0.1651)
		(layer "In13.Cu")
		(net "P5E_PEX0_STN6_TX_C_DP<106>")
	)
	(segment
		(start 72.01281 -388.112)
		(end 70.615302 -387.533134)
		(width 0.1651)
		(layer "In13.Cu")
		(net "P5E_PEX0_STN6_TX_C_DP<106>")
	)
	(segment
		(start 83.80222 -395.3256)
		(end 81.49844 -393.022074)
		(width 0.1651)
		(layer "In13.Cu")
		(net "P5E_PEX0_STN6_TX_C_DP<106>")
	)
	(segment
		(start 81.49844 -393.022074)
		(end 77.421994 -390.843008)
		(width 0.1651)
		(layer "In13.Cu")
		(net "P5E_PEX0_STN6_TX_C_DP<106>")
	)
	(segment
		(start 77.421994 -390.843008)
		(end 77.421994 -390.843262)
		(width 0.1651)
		(layer "In13.Cu")
		(net "P5E_PEX0_STN6_TX_C_DP<106>")
	)
	(segment
		(start 83.564222 -409.799028)
		(end 83.80222 -409.56103)
		(width 0.1651)
		(layer "In13.Cu")
		(net "P5E_PEX0_STN6_TX_C_DP<106>")
	)
	(segment
		(start 68.683632 -369.136676)
		(end 69.313552 -366.33277)
		(width 0.1651)
		(layer "In13.Cu")
		(net "P5E_PEX0_STN6_TX_C_DP<106>")
	)
	(segment
		(start 77.421994 -390.843262)
		(end 73.345294 -388.663942)
		(width 0.1651)
		(layer "In13.Cu")
		(net "P5E_PEX0_STN6_TX_C_DP<106>")
	)
	(segment
		(start 74.098912 -345.755976)
		(end 73.808082 -345.465146)
		(width 0.1651)
		(layer "In13.Cu")
		(net "P5E_PEX0_STN6_TX_C_DP<106>")
	)
	(segment
		(start 70.615302 -387.533134)
		(end 69.421248 -386.33908)
		(width 0.1651)
		(layer "In13.Cu")
		(net "P5E_PEX0_STN6_TX_C_DP<106>")
	)
	(segment
		(start 68.36918 -382.192276)
		(end 68.683632 -369.136676)
		(width 0.1651)
		(layer "In13.Cu")
		(net "P5E_PEX0_STN6_TX_C_DP<106>")
	)
	(segment
		(start 74.377042 -344.539062)
		(end 74.697082 -344.219022)
		(width 0.13462)
		(layer "F.Cu")
		(net "P5E_PEX0_STN6_TX_C_DN<106>")
	)
	(segment
		(start 74.671682 -345.465146)
		(end 74.377042 -345.170506)
		(width 0.13462)
		(layer "F.Cu")
		(net "P5E_PEX0_STN6_TX_C_DN<106>")
	)
	(segment
		(start 74.377042 -345.170506)
		(end 74.377042 -344.539062)
		(width 0.13462)
		(layer "F.Cu")
		(net "P5E_PEX0_STN6_TX_C_DN<106>")
	)
	(segment
		(start 72.826372 -359.566718)
		(end 69.58203 -366.425226)
		(width 0.1651)
		(layer "In13.Cu")
		(net "P5E_PEX0_STN6_TX_C_DN<106>")
	)
	(segment
		(start 73.465944 -388.408672)
		(end 81.668366 -392.792966)
		(width 0.1651)
		(layer "In13.Cu")
		(net "P5E_PEX0_STN6_TX_C_DN<106>")
	)
	(segment
		(start 83.363308 -394.380212)
		(end 83.363308 -394.487908)
		(width 0.1651)
		(layer "In13.Cu")
		(net "P5E_PEX0_STN6_TX_C_DN<106>")
	)
	(segment
		(start 82.905092 -394.029692)
		(end 83.012788 -394.029692)
		(width 0.1651)
		(layer "In13.Cu")
		(net "P5E_PEX0_STN6_TX_C_DN<106>")
	)
	(segment
		(start 68.965064 -369.17122)
		(end 68.65112 -382.195832)
		(width 0.1651)
		(layer "In13.Cu")
		(net "P5E_PEX0_STN6_TX_C_DN<106>")
	)
	(segment
		(start 83.681062 -410.080968)
		(end 83.036918 -410.080968)
		(width 0.1651)
		(layer "In13.Cu")
		(net "P5E_PEX0_STN6_TX_C_DN<106>")
	)
	(segment
		(start 72.826372 -347.983048)
		(end 72.826372 -359.566718)
		(width 0.1651)
		(layer "In13.Cu")
		(net "P5E_PEX0_STN6_TX_C_DN<106>")
	)
	(segment
		(start 83.363308 -394.487908)
		(end 84.08416 -395.20876)
		(width 0.1651)
		(layer "In13.Cu")
		(net "P5E_PEX0_STN6_TX_C_DN<106>")
	)
	(segment
		(start 74.380852 -345.755976)
		(end 74.380852 -346.428568)
		(width 0.1651)
		(layer "In13.Cu")
		(net "P5E_PEX0_STN6_TX_C_DN<106>")
	)
	(segment
		(start 84.08416 -395.20876)
		(end 84.08416 -409.67787)
		(width 0.1651)
		(layer "In13.Cu")
		(net "P5E_PEX0_STN6_TX_C_DN<106>")
	)
	(segment
		(start 82.909918 -410.207968)
		(end 82.909918 -410.589984)
		(width 0.1651)
		(layer "In13.Cu")
		(net "P5E_PEX0_STN6_TX_C_DN<106>")
	)
	(segment
		(start 70.775068 -387.29412)
		(end 73.465944 -388.408672)
		(width 0.1651)
		(layer "In13.Cu")
		(net "P5E_PEX0_STN6_TX_C_DN<106>")
	)
	(segment
		(start 74.671682 -345.465146)
		(end 74.380852 -345.755976)
		(width 0.1651)
		(layer "In13.Cu")
		(net "P5E_PEX0_STN6_TX_C_DN<106>")
	)
	(segment
		(start 84.08416 -409.67787)
		(end 83.681062 -410.080968)
		(width 0.1651)
		(layer "In13.Cu")
		(net "P5E_PEX0_STN6_TX_C_DN<106>")
	)
	(segment
		(start 81.668366 -392.792966)
		(end 82.905092 -394.029692)
		(width 0.1651)
		(layer "In13.Cu")
		(net "P5E_PEX0_STN6_TX_C_DN<106>")
	)
	(segment
		(start 74.380852 -346.428568)
		(end 72.826372 -347.983048)
		(width 0.1651)
		(layer "In13.Cu")
		(net "P5E_PEX0_STN6_TX_C_DN<106>")
	)
	(segment
		(start 83.012788 -394.029692)
		(end 83.363308 -394.380212)
		(width 0.1651)
		(layer "In13.Cu")
		(net "P5E_PEX0_STN6_TX_C_DN<106>")
	)
	(segment
		(start 83.036918 -410.080968)
		(end 82.909918 -410.207968)
		(width 0.1651)
		(layer "In13.Cu")
		(net "P5E_PEX0_STN6_TX_C_DN<106>")
	)
	(segment
		(start 69.660262 -386.179314)
		(end 70.775068 -387.29412)
		(width 0.1651)
		(layer "In13.Cu")
		(net "P5E_PEX0_STN6_TX_C_DN<106>")
	)
	(segment
		(start 68.65112 -382.195832)
		(end 68.65112 -383.742946)
		(width 0.1651)
		(layer "In13.Cu")
		(net "P5E_PEX0_STN6_TX_C_DN<106>")
	)
	(segment
		(start 69.58203 -366.425226)
		(end 68.965064 -369.17122)
		(width 0.1651)
		(layer "In13.Cu")
		(net "P5E_PEX0_STN6_TX_C_DN<106>")
	)
	(segment
		(start 68.65112 -383.742946)
		(end 69.660262 -386.179314)
		(width 0.1651)
		(layer "In13.Cu")
		(net "P5E_PEX0_STN6_TX_C_DN<106>")
	)
	(segment
		(start 124.592588 -356.831646)
		(end 124.272548 -356.511606)
		(width 0.13462)
		(layer "F.Cu")
		(net "P5E_PEX1_STN6_TX_C_DP<105>")
	)
	(segment
		(start 124.297948 -357.75773)
		(end 124.592588 -357.46309)
		(width 0.13462)
		(layer "F.Cu")
		(net "P5E_PEX1_STN6_TX_C_DP<105>")
	)
	(segment
		(start 124.592588 -357.46309)
		(end 124.592588 -356.831646)
		(width 0.13462)
		(layer "F.Cu")
		(net "P5E_PEX1_STN6_TX_C_DP<105>")
	)
	(segment
		(start 129.984754 -395.279372)
		(end 129.671318 -394.693394)
		(width 0.1651)
		(layer "In13.Cu")
		(net "P5E_PEX1_STN6_TX_C_DP<105>")
	)
	(segment
		(start 114.561366 -386.358638)
		(end 114.1095 -385.6863)
		(width 0.1651)
		(layer "In13.Cu")
		(net "P5E_PEX1_STN6_TX_C_DP<105>")
	)
	(segment
		(start 113.65611 -385.010914)
		(end 113.122964 -383.090928)
		(width 0.1651)
		(layer "In13.Cu")
		(net "P5E_PEX1_STN6_TX_C_DP<105>")
	)
	(segment
		(start 129.236978 -408.699208)
		(end 129.458466 -408.699208)
		(width 0.1651)
		(layer "In13.Cu")
		(net "P5E_PEX1_STN6_TX_C_DP<105>")
	)
	(segment
		(start 114.109754 -385.6863)
		(end 113.65611 -385.010914)
		(width 0.1651)
		(layer "In13.Cu")
		(net "P5E_PEX1_STN6_TX_C_DP<105>")
	)
	(segment
		(start 127.34925 -393.141708)
		(end 127.190754 -393.173204)
		(width 0.1651)
		(layer "In13.Cu")
		(net "P5E_PEX1_STN6_TX_C_DP<105>")
	)
	(segment
		(start 113.538254 -367.590832)
		(end 124.037344 -359.572306)
		(width 0.1651)
		(layer "In13.Cu")
		(net "P5E_PEX1_STN6_TX_C_DP<105>")
	)
	(segment
		(start 113.222024 -368.220244)
		(end 113.538254 -367.590832)
		(width 0.1651)
		(layer "In13.Cu")
		(net "P5E_PEX1_STN6_TX_C_DP<105>")
	)
	(segment
		(start 115.337082 -386.991098)
		(end 114.561366 -386.358638)
		(width 0.1651)
		(layer "In13.Cu")
		(net "P5E_PEX1_STN6_TX_C_DP<105>")
	)
	(segment
		(start 113.122964 -383.090928)
		(end 113.222024 -368.220244)
		(width 0.1651)
		(layer "In13.Cu")
		(net "P5E_PEX1_STN6_TX_C_DP<105>")
	)
	(segment
		(start 128.204722 -393.850876)
		(end 127.792734 -393.57554)
		(width 0.1651)
		(layer "In13.Cu")
		(net "P5E_PEX1_STN6_TX_C_DP<105>")
	)
	(segment
		(start 127.760984 -393.41679)
		(end 127.34925 -393.141708)
		(width 0.1651)
		(layer "In13.Cu")
		(net "P5E_PEX1_STN6_TX_C_DP<105>")
	)
	(segment
		(start 129.671318 -394.693394)
		(end 128.363218 -393.81938)
		(width 0.1651)
		(layer "In13.Cu")
		(net "P5E_PEX1_STN6_TX_C_DP<105>")
	)
	(segment
		(start 116.112798 -387.623812)
		(end 115.337082 -386.991352)
		(width 0.1651)
		(layer "In13.Cu")
		(net "P5E_PEX1_STN6_TX_C_DP<105>")
	)
	(segment
		(start 115.337082 -386.991352)
		(end 115.337082 -386.991098)
		(width 0.1651)
		(layer "In13.Cu")
		(net "P5E_PEX1_STN6_TX_C_DP<105>")
	)
	(segment
		(start 127.792734 -393.57554)
		(end 127.760984 -393.41679)
		(width 0.1651)
		(layer "In13.Cu")
		(net "P5E_PEX1_STN6_TX_C_DP<105>")
	)
	(segment
		(start 126.747016 -392.739372)
		(end 123.952508 -390.871964)
		(width 0.1651)
		(layer "In13.Cu")
		(net "P5E_PEX1_STN6_TX_C_DP<105>")
	)
	(segment
		(start 128.363218 -393.81938)
		(end 128.204722 -393.850876)
		(width 0.1651)
		(layer "In13.Cu")
		(net "P5E_PEX1_STN6_TX_C_DP<105>")
	)
	(segment
		(start 124.588778 -358.457246)
		(end 124.588778 -358.04856)
		(width 0.1651)
		(layer "In13.Cu")
		(net "P5E_PEX1_STN6_TX_C_DP<105>")
	)
	(segment
		(start 123.952508 -390.871964)
		(end 116.112798 -387.623812)
		(width 0.1651)
		(layer "In13.Cu")
		(net "P5E_PEX1_STN6_TX_C_DP<105>")
	)
	(segment
		(start 129.458466 -408.699208)
		(end 129.984754 -408.17292)
		(width 0.1651)
		(layer "In13.Cu")
		(net "P5E_PEX1_STN6_TX_C_DP<105>")
	)
	(segment
		(start 129.109978 -408.572208)
		(end 129.236978 -408.699208)
		(width 0.1651)
		(layer "In13.Cu")
		(net "P5E_PEX1_STN6_TX_C_DP<105>")
	)
	(segment
		(start 124.037344 -359.572306)
		(end 124.588778 -358.457246)
		(width 0.1651)
		(layer "In13.Cu")
		(net "P5E_PEX1_STN6_TX_C_DP<105>")
	)
	(segment
		(start 129.984754 -408.17292)
		(end 129.984754 -395.279372)
		(width 0.1651)
		(layer "In13.Cu")
		(net "P5E_PEX1_STN6_TX_C_DP<105>")
	)
	(segment
		(start 129.109978 -408.190192)
		(end 129.109978 -408.572208)
		(width 0.1651)
		(layer "In13.Cu")
		(net "P5E_PEX1_STN6_TX_C_DP<105>")
	)
	(segment
		(start 124.588778 -358.04856)
		(end 124.297948 -357.75773)
		(width 0.1651)
		(layer "In13.Cu")
		(net "P5E_PEX1_STN6_TX_C_DP<105>")
	)
	(segment
		(start 127.190754 -393.173204)
		(end 126.778766 -392.897868)
		(width 0.1651)
		(layer "In13.Cu")
		(net "P5E_PEX1_STN6_TX_C_DP<105>")
	)
	(segment
		(start 114.1095 -385.6863)
		(end 114.109754 -385.6863)
		(width 0.1651)
		(layer "In13.Cu")
		(net "P5E_PEX1_STN6_TX_C_DP<105>")
	)
	(segment
		(start 126.778766 -392.897868)
		(end 126.747016 -392.739372)
		(width 0.1651)
		(layer "In13.Cu")
		(net "P5E_PEX1_STN6_TX_C_DP<105>")
	)
	(segment
		(start 165.210998 -316.229492)
		(end 165.299898 -316.140592)
		(width 0.1143)
		(layer "In15.Cu")
		(net "P5E_PEX1_STN6_RX_DP<105>")
	)
	(segment
		(start 126.361698 -392.60399)
		(end 126.333758 -392.46302)
		(width 0.1651)
		(layer "In15.Cu")
		(net "P5E_PEX1_STN6_RX_DP<105>")
	)
	(segment
		(start 114.1095 -385.6863)
		(end 114.109754 -385.6863)
		(width 0.1651)
		(layer "In15.Cu")
		(net "P5E_PEX1_STN6_RX_DP<105>")
	)
	(segment
		(start 115.337082 -386.991352)
		(end 115.337082 -386.991098)
		(width 0.1651)
		(layer "In15.Cu")
		(net "P5E_PEX1_STN6_RX_DP<105>")
	)
	(segment
		(start 113.65611 -385.010914)
		(end 113.438686 -384.22834)
		(width 0.1651)
		(layer "In15.Cu")
		(net "P5E_PEX1_STN6_RX_DP<105>")
	)
	(segment
		(start 164.683948 -319.8368)
		(end 164.729668 -319.79108)
		(width 0.1143)
		(layer "In15.Cu")
		(net "P5E_PEX1_STN6_RX_DP<105>")
	)
	(segment
		(start 126.143258 -357.881682)
		(end 126.143258 -341.664544)
		(width 0.1651)
		(layer "In15.Cu")
		(net "P5E_PEX1_STN6_RX_DP<105>")
	)
	(segment
		(start 129.985516 -400.372072)
		(end 129.985516 -395.280896)
		(width 0.1651)
		(layer "In15.Cu")
		(net "P5E_PEX1_STN6_RX_DP<105>")
	)
	(segment
		(start 116.112798 -387.623812)
		(end 115.337082 -386.991352)
		(width 0.1651)
		(layer "In15.Cu")
		(net "P5E_PEX1_STN6_RX_DP<105>")
	)
	(segment
		(start 114.109754 -385.6863)
		(end 113.65611 -385.010914)
		(width 0.1651)
		(layer "In15.Cu")
		(net "P5E_PEX1_STN6_RX_DP<105>")
	)
	(segment
		(start 164.683948 -320.92646)
		(end 164.683948 -319.865248)
		(width 0.1651)
		(layer "In15.Cu")
		(net "P5E_PEX1_STN6_RX_DP<105>")
	)
	(segment
		(start 165.299898 -316.140592)
		(end 165.299898 -315.849762)
		(width 0.1143)
		(layer "In15.Cu")
		(net "P5E_PEX1_STN6_RX_DP<105>")
	)
	(segment
		(start 164.683948 -319.865248)
		(end 164.683948 -319.8368)
		(width 0.1143)
		(layer "In15.Cu")
		(net "P5E_PEX1_STN6_RX_DP<105>")
	)
	(segment
		(start 126.914656 -392.851386)
		(end 126.773686 -392.879326)
		(width 0.1651)
		(layer "In15.Cu")
		(net "P5E_PEX1_STN6_RX_DP<105>")
	)
	(segment
		(start 126.773686 -392.879326)
		(end 126.361698 -392.60399)
		(width 0.1651)
		(layer "In15.Cu")
		(net "P5E_PEX1_STN6_RX_DP<105>")
	)
	(segment
		(start 129.671318 -394.693394)
		(end 126.914656 -392.851386)
		(width 0.1651)
		(layer "In15.Cu")
		(net "P5E_PEX1_STN6_RX_DP<105>")
	)
	(segment
		(start 126.922784 -340.885018)
		(end 144.569942 -333.575406)
		(width 0.1651)
		(layer "In15.Cu")
		(net "P5E_PEX1_STN6_RX_DP<105>")
	)
	(segment
		(start 125.77318 -358.632252)
		(end 126.143258 -357.881682)
		(width 0.1651)
		(layer "In15.Cu")
		(net "P5E_PEX1_STN6_RX_DP<105>")
	)
	(segment
		(start 115.31981 -366.646968)
		(end 125.77318 -358.632252)
		(width 0.1651)
		(layer "In15.Cu")
		(net "P5E_PEX1_STN6_RX_DP<105>")
	)
	(segment
		(start 164.729668 -319.79108)
		(end 164.729668 -316.467998)
		(width 0.1143)
		(layer "In15.Cu")
		(net "P5E_PEX1_STN6_RX_DP<105>")
	)
	(segment
		(start 129.985516 -395.280896)
		(end 129.671318 -394.693394)
		(width 0.1651)
		(layer "In15.Cu")
		(net "P5E_PEX1_STN6_RX_DP<105>")
	)
	(segment
		(start 115.337082 -386.991098)
		(end 114.561366 -386.358638)
		(width 0.1651)
		(layer "In15.Cu")
		(net "P5E_PEX1_STN6_RX_DP<105>")
	)
	(segment
		(start 114.376962 -367.787428)
		(end 115.31981 -366.646968)
		(width 0.1651)
		(layer "In15.Cu")
		(net "P5E_PEX1_STN6_RX_DP<105>")
	)
	(segment
		(start 129.458466 -400.899122)
		(end 129.985516 -400.372072)
		(width 0.1651)
		(layer "In15.Cu")
		(net "P5E_PEX1_STN6_RX_DP<105>")
	)
	(segment
		(start 164.968174 -316.229492)
		(end 165.210998 -316.229492)
		(width 0.1143)
		(layer "In15.Cu")
		(net "P5E_PEX1_STN6_RX_DP<105>")
	)
	(segment
		(start 129.109978 -400.390106)
		(end 129.109978 -400.772122)
		(width 0.1651)
		(layer "In15.Cu")
		(net "P5E_PEX1_STN6_RX_DP<105>")
	)
	(segment
		(start 113.491518 -376.350784)
		(end 113.491518 -376.332242)
		(width 0.1651)
		(layer "In15.Cu")
		(net "P5E_PEX1_STN6_RX_DP<105>")
	)
	(segment
		(start 144.569942 -333.575406)
		(end 161.583878 -325.526908)
		(width 0.1651)
		(layer "In15.Cu")
		(net "P5E_PEX1_STN6_RX_DP<105>")
	)
	(segment
		(start 129.236978 -400.899122)
		(end 129.458466 -400.899122)
		(width 0.1651)
		(layer "In15.Cu")
		(net "P5E_PEX1_STN6_RX_DP<105>")
	)
	(segment
		(start 129.109978 -400.772122)
		(end 129.236978 -400.899122)
		(width 0.1651)
		(layer "In15.Cu")
		(net "P5E_PEX1_STN6_RX_DP<105>")
	)
	(segment
		(start 161.583878 -325.526908)
		(end 163.623752 -323.487034)
		(width 0.1651)
		(layer "In15.Cu")
		(net "P5E_PEX1_STN6_RX_DP<105>")
	)
	(segment
		(start 125.340872 -391.799572)
		(end 123.952508 -390.871964)
		(width 0.1651)
		(layer "In15.Cu")
		(net "P5E_PEX1_STN6_RX_DP<105>")
	)
	(segment
		(start 125.781054 -392.216132)
		(end 125.369066 -391.940542)
		(width 0.1651)
		(layer "In15.Cu")
		(net "P5E_PEX1_STN6_RX_DP<105>")
	)
	(segment
		(start 113.491518 -376.332242)
		(end 113.536984 -369.460272)
		(width 0.1651)
		(layer "In15.Cu")
		(net "P5E_PEX1_STN6_RX_DP<105>")
	)
	(segment
		(start 123.952508 -390.871964)
		(end 116.112798 -387.623812)
		(width 0.1651)
		(layer "In15.Cu")
		(net "P5E_PEX1_STN6_RX_DP<105>")
	)
	(segment
		(start 126.333758 -392.46302)
		(end 125.922024 -392.187938)
		(width 0.1651)
		(layer "In15.Cu")
		(net "P5E_PEX1_STN6_RX_DP<105>")
	)
	(segment
		(start 126.143258 -341.664544)
		(end 126.922784 -340.885018)
		(width 0.1651)
		(layer "In15.Cu")
		(net "P5E_PEX1_STN6_RX_DP<105>")
	)
	(segment
		(start 113.536984 -369.460272)
		(end 114.376962 -367.787428)
		(width 0.1651)
		(layer "In15.Cu")
		(net "P5E_PEX1_STN6_RX_DP<105>")
	)
	(segment
		(start 114.561366 -386.358638)
		(end 114.1095 -385.6863)
		(width 0.1651)
		(layer "In15.Cu")
		(net "P5E_PEX1_STN6_RX_DP<105>")
	)
	(segment
		(start 164.729668 -316.467998)
		(end 164.968174 -316.229492)
		(width 0.1143)
		(layer "In15.Cu")
		(net "P5E_PEX1_STN6_RX_DP<105>")
	)
	(segment
		(start 125.369066 -391.940542)
		(end 125.340872 -391.799572)
		(width 0.1651)
		(layer "In15.Cu")
		(net "P5E_PEX1_STN6_RX_DP<105>")
	)
	(segment
		(start 113.438686 -384.22834)
		(end 113.491518 -376.350784)
		(width 0.1651)
		(layer "In15.Cu")
		(net "P5E_PEX1_STN6_RX_DP<105>")
	)
	(segment
		(start 125.922024 -392.187938)
		(end 125.781054 -392.216132)
		(width 0.1651)
		(layer "In15.Cu")
		(net "P5E_PEX1_STN6_RX_DP<105>")
	)
	(segment
		(start 163.623752 -323.487034)
		(end 164.683948 -320.92646)
		(width 0.1651)
		(layer "In15.Cu")
		(net "P5E_PEX1_STN6_RX_DP<105>")
	)
	(segment
		(start 129.109978 -401.308062)
		(end 129.236978 -401.181062)
		(width 0.1651)
		(layer "In15.Cu")
		(net "P5E_PEX1_STN6_RX_DN<105>")
	)
	(segment
		(start 115.516914 -366.851438)
		(end 125.997208 -358.816148)
		(width 0.1651)
		(layer "In15.Cu")
		(net "P5E_PEX1_STN6_RX_DN<105>")
	)
	(segment
		(start 114.614706 -367.942368)
		(end 115.516914 -366.851438)
		(width 0.1651)
		(layer "In15.Cu")
		(net "P5E_PEX1_STN6_RX_DN<105>")
	)
	(segment
		(start 129.236978 -401.181062)
		(end 129.575306 -401.181062)
		(width 0.1651)
		(layer "In15.Cu")
		(net "P5E_PEX1_STN6_RX_DN<105>")
	)
	(segment
		(start 164.965888 -319.865248)
		(end 164.965888 -319.8368)
		(width 0.1143)
		(layer "In15.Cu")
		(net "P5E_PEX1_STN6_RX_DN<105>")
	)
	(segment
		(start 130.267456 -395.21003)
		(end 129.886964 -394.498068)
		(width 0.1651)
		(layer "In15.Cu")
		(net "P5E_PEX1_STN6_RX_DN<105>")
	)
	(segment
		(start 161.748724 -325.760842)
		(end 163.862766 -323.6468)
		(width 0.1651)
		(layer "In15.Cu")
		(net "P5E_PEX1_STN6_RX_DN<105>")
	)
	(segment
		(start 164.920168 -319.79108)
		(end 164.920168 -316.546992)
		(width 0.1143)
		(layer "In15.Cu")
		(net "P5E_PEX1_STN6_RX_DN<105>")
	)
	(segment
		(start 113.773458 -376.3518)
		(end 113.773458 -376.333258)
		(width 0.1651)
		(layer "In15.Cu")
		(net "P5E_PEX1_STN6_RX_DN<105>")
	)
	(segment
		(start 114.772186 -386.16636)
		(end 113.915698 -384.891534)
		(width 0.1651)
		(layer "In15.Cu")
		(net "P5E_PEX1_STN6_RX_DN<105>")
	)
	(segment
		(start 113.721134 -384.190748)
		(end 113.773458 -376.3518)
		(width 0.1651)
		(layer "In15.Cu")
		(net "P5E_PEX1_STN6_RX_DN<105>")
	)
	(segment
		(start 129.109978 -401.690078)
		(end 129.109978 -401.308062)
		(width 0.1651)
		(layer "In15.Cu")
		(net "P5E_PEX1_STN6_RX_DN<105>")
	)
	(segment
		(start 113.915698 -384.891534)
		(end 113.721134 -384.190748)
		(width 0.1651)
		(layer "In15.Cu")
		(net "P5E_PEX1_STN6_RX_DN<105>")
	)
	(segment
		(start 129.886964 -394.498068)
		(end 124.086112 -390.622028)
		(width 0.1651)
		(layer "In15.Cu")
		(net "P5E_PEX1_STN6_RX_DN<105>")
	)
	(segment
		(start 125.997208 -358.816148)
		(end 126.425198 -357.947468)
		(width 0.1651)
		(layer "In15.Cu")
		(net "P5E_PEX1_STN6_RX_DN<105>")
	)
	(segment
		(start 165.210998 -316.419992)
		(end 165.299898 -316.508892)
		(width 0.1143)
		(layer "In15.Cu")
		(net "P5E_PEX1_STN6_RX_DN<105>")
	)
	(segment
		(start 129.575306 -401.181062)
		(end 130.267456 -400.488912)
		(width 0.1651)
		(layer "In15.Cu")
		(net "P5E_PEX1_STN6_RX_DN<105>")
	)
	(segment
		(start 164.965888 -320.982594)
		(end 164.965888 -319.865248)
		(width 0.1651)
		(layer "In15.Cu")
		(net "P5E_PEX1_STN6_RX_DN<105>")
	)
	(segment
		(start 130.267456 -400.488912)
		(end 130.267456 -395.21003)
		(width 0.1651)
		(layer "In15.Cu")
		(net "P5E_PEX1_STN6_RX_DN<105>")
	)
	(segment
		(start 163.862766 -323.6468)
		(end 164.965888 -320.982594)
		(width 0.1651)
		(layer "In15.Cu")
		(net "P5E_PEX1_STN6_RX_DN<105>")
	)
	(segment
		(start 116.259102 -387.378956)
		(end 114.772186 -386.16636)
		(width 0.1651)
		(layer "In15.Cu")
		(net "P5E_PEX1_STN6_RX_DN<105>")
	)
	(segment
		(start 126.425198 -341.781384)
		(end 127.08255 -341.124032)
		(width 0.1651)
		(layer "In15.Cu")
		(net "P5E_PEX1_STN6_RX_DN<105>")
	)
	(segment
		(start 164.965888 -319.8368)
		(end 164.920168 -319.79108)
		(width 0.1143)
		(layer "In15.Cu")
		(net "P5E_PEX1_STN6_RX_DN<105>")
	)
	(segment
		(start 126.425198 -357.947468)
		(end 126.425198 -341.781384)
		(width 0.1651)
		(layer "In15.Cu")
		(net "P5E_PEX1_STN6_RX_DN<105>")
	)
	(segment
		(start 144.684242 -333.83347)
		(end 161.748724 -325.760842)
		(width 0.1651)
		(layer "In15.Cu")
		(net "P5E_PEX1_STN6_RX_DN<105>")
	)
	(segment
		(start 135.882888 -337.479132)
		(end 135.882888 -337.478878)
		(width 0.1651)
		(layer "In15.Cu")
		(net "P5E_PEX1_STN6_RX_DN<105>")
	)
	(segment
		(start 135.882888 -337.478878)
		(end 144.684242 -333.83347)
		(width 0.1651)
		(layer "In15.Cu")
		(net "P5E_PEX1_STN6_RX_DN<105>")
	)
	(segment
		(start 113.81867 -369.52809)
		(end 114.614706 -367.942368)
		(width 0.1651)
		(layer "In15.Cu")
		(net "P5E_PEX1_STN6_RX_DN<105>")
	)
	(segment
		(start 164.920168 -316.546992)
		(end 165.047168 -316.419992)
		(width 0.1143)
		(layer "In15.Cu")
		(net "P5E_PEX1_STN6_RX_DN<105>")
	)
	(segment
		(start 165.047168 -316.419992)
		(end 165.210998 -316.419992)
		(width 0.1143)
		(layer "In15.Cu")
		(net "P5E_PEX1_STN6_RX_DN<105>")
	)
	(segment
		(start 165.299898 -316.508892)
		(end 165.299898 -316.799722)
		(width 0.1143)
		(layer "In15.Cu")
		(net "P5E_PEX1_STN6_RX_DN<105>")
	)
	(segment
		(start 113.773458 -376.333258)
		(end 113.81867 -369.52809)
		(width 0.1651)
		(layer "In15.Cu")
		(net "P5E_PEX1_STN6_RX_DN<105>")
	)
	(segment
		(start 127.08255 -341.124032)
		(end 135.882888 -337.479132)
		(width 0.1651)
		(layer "In15.Cu")
		(net "P5E_PEX1_STN6_RX_DN<105>")
	)
	(segment
		(start 124.086112 -390.622028)
		(end 116.259102 -387.378956)
		(width 0.1651)
		(layer "In15.Cu")
		(net "P5E_PEX1_STN6_RX_DN<105>")
	)
	(segment
		(start 83.027774 -392.996674)
		(end 77.688694 -389.42899)
		(width 0.1651)
		(layer "In5.Cu")
		(net "P5E_PEX0_STN6_RX_DP<105>")
	)
	(segment
		(start 83.61553 -393.389358)
		(end 83.460336 -393.420092)
		(width 0.1651)
		(layer "In5.Cu")
		(net "P5E_PEX0_STN6_RX_DP<105>")
	)
	(segment
		(start 66.326512 -358.63784)
		(end 66.326512 -342.123014)
		(width 0.1651)
		(layer "In5.Cu")
		(net "P5E_PEX0_STN6_RX_DP<105>")
	)
	(segment
		(start 86.002114 -400.661124)
		(end 86.002114 -395.61262)
		(width 0.1651)
		(layer "In5.Cu")
		(net "P5E_PEX0_STN6_RX_DP<105>")
	)
	(segment
		(start 49.358296 -323.244464)
		(end 48.58385 -321.375532)
		(width 0.1651)
		(layer "In5.Cu")
		(net "P5E_PEX0_STN6_RX_DP<105>")
	)
	(segment
		(start 84.448904 -394.080746)
		(end 84.047584 -393.812268)
		(width 0.1651)
		(layer "In5.Cu")
		(net "P5E_PEX0_STN6_RX_DP<105>")
	)
	(segment
		(start 83.460336 -393.420092)
		(end 83.059016 -393.151868)
		(width 0.1651)
		(layer "In5.Cu")
		(net "P5E_PEX0_STN6_RX_DP<105>")
	)
	(segment
		(start 86.002114 -395.61262)
		(end 85.67166 -394.814806)
		(width 0.1651)
		(layer "In5.Cu")
		(net "P5E_PEX0_STN6_RX_DP<105>")
	)
	(segment
		(start 49.1998 -316.115192)
		(end 49.1998 -315.849762)
		(width 0.1143)
		(layer "In5.Cu")
		(net "P5E_PEX0_STN6_RX_DP<105>")
	)
	(segment
		(start 70.940168 -386.63372)
		(end 70.25259 -385.946142)
		(width 0.1651)
		(layer "In5.Cu")
		(net "P5E_PEX0_STN6_RX_DP<105>")
	)
	(segment
		(start 85.764116 -400.899122)
		(end 86.002114 -400.661124)
		(width 0.1651)
		(layer "In5.Cu")
		(net "P5E_PEX0_STN6_RX_DP<105>")
	)
	(segment
		(start 67.84975 -366.29594)
		(end 66.326512 -358.63784)
		(width 0.1651)
		(layer "In5.Cu")
		(net "P5E_PEX0_STN6_RX_DP<105>")
	)
	(segment
		(start 65.5447 -340.952836)
		(end 58.57748 -332.463648)
		(width 0.1651)
		(layer "In5.Cu")
		(net "P5E_PEX0_STN6_RX_DP<105>")
	)
	(segment
		(start 48.58385 -319.966848)
		(end 48.62957 -319.921128)
		(width 0.1143)
		(layer "In5.Cu")
		(net "P5E_PEX0_STN6_RX_DP<105>")
	)
	(segment
		(start 48.58385 -319.995296)
		(end 48.58385 -319.966848)
		(width 0.1143)
		(layer "In5.Cu")
		(net "P5E_PEX0_STN6_RX_DP<105>")
	)
	(segment
		(start 85.109812 -400.772122)
		(end 85.236812 -400.899122)
		(width 0.1651)
		(layer "In5.Cu")
		(net "P5E_PEX0_STN6_RX_DP<105>")
	)
	(segment
		(start 85.109812 -400.390106)
		(end 85.109812 -400.772122)
		(width 0.1651)
		(layer "In5.Cu")
		(net "P5E_PEX0_STN6_RX_DP<105>")
	)
	(segment
		(start 83.028028 -392.996674)
		(end 83.027774 -392.996674)
		(width 0.1651)
		(layer "In5.Cu")
		(net "P5E_PEX0_STN6_RX_DP<105>")
	)
	(segment
		(start 48.58385 -321.375532)
		(end 48.58385 -319.995296)
		(width 0.1651)
		(layer "In5.Cu")
		(net "P5E_PEX0_STN6_RX_DP<105>")
	)
	(segment
		(start 49.0855 -316.229492)
		(end 49.1998 -316.115192)
		(width 0.1143)
		(layer "In5.Cu")
		(net "P5E_PEX0_STN6_RX_DP<105>")
	)
	(segment
		(start 48.62957 -319.921128)
		(end 48.62957 -316.455298)
		(width 0.1143)
		(layer "In5.Cu")
		(net "P5E_PEX0_STN6_RX_DP<105>")
	)
	(segment
		(start 58.57748 -332.463648)
		(end 49.358296 -323.244464)
		(width 0.1651)
		(layer "In5.Cu")
		(net "P5E_PEX0_STN6_RX_DP<105>")
	)
	(segment
		(start 69.638926 -384.465068)
		(end 67.84975 -366.29594)
		(width 0.1651)
		(layer "In5.Cu")
		(net "P5E_PEX0_STN6_RX_DP<105>")
	)
	(segment
		(start 48.855376 -316.229492)
		(end 49.0855 -316.229492)
		(width 0.1143)
		(layer "In5.Cu")
		(net "P5E_PEX0_STN6_RX_DP<105>")
	)
	(segment
		(start 66.326512 -342.123014)
		(end 65.5447 -340.952836)
		(width 0.1651)
		(layer "In5.Cu")
		(net "P5E_PEX0_STN6_RX_DP<105>")
	)
	(segment
		(start 77.688694 -389.42899)
		(end 70.940168 -386.63372)
		(width 0.1651)
		(layer "In5.Cu")
		(net "P5E_PEX0_STN6_RX_DP<105>")
	)
	(segment
		(start 48.62957 -316.455298)
		(end 48.855376 -316.229492)
		(width 0.1143)
		(layer "In5.Cu")
		(net "P5E_PEX0_STN6_RX_DP<105>")
	)
	(segment
		(start 85.236812 -400.899122)
		(end 85.764116 -400.899122)
		(width 0.1651)
		(layer "In5.Cu")
		(net "P5E_PEX0_STN6_RX_DP<105>")
	)
	(segment
		(start 85.67166 -394.814806)
		(end 85.516212 -394.659358)
		(width 0.1651)
		(layer "In5.Cu")
		(net "P5E_PEX0_STN6_RX_DP<105>")
	)
	(segment
		(start 84.603844 -394.049758)
		(end 84.448904 -394.080746)
		(width 0.1651)
		(layer "In5.Cu")
		(net "P5E_PEX0_STN6_RX_DP<105>")
	)
	(segment
		(start 84.047584 -393.812268)
		(end 84.016596 -393.657328)
		(width 0.1651)
		(layer "In5.Cu")
		(net "P5E_PEX0_STN6_RX_DP<105>")
	)
	(segment
		(start 85.516212 -394.659358)
		(end 84.603844 -394.049758)
		(width 0.1651)
		(layer "In5.Cu")
		(net "P5E_PEX0_STN6_RX_DP<105>")
	)
	(segment
		(start 84.016596 -393.657328)
		(end 83.61553 -393.389358)
		(width 0.1651)
		(layer "In5.Cu")
		(net "P5E_PEX0_STN6_RX_DP<105>")
	)
	(segment
		(start 83.059016 -393.151868)
		(end 83.028028 -392.996674)
		(width 0.1651)
		(layer "In5.Cu")
		(net "P5E_PEX0_STN6_RX_DP<105>")
	)
	(segment
		(start 70.25259 -385.946142)
		(end 69.638926 -384.465068)
		(width 0.1651)
		(layer "In5.Cu")
		(net "P5E_PEX0_STN6_RX_DP<105>")
	)
	(segment
		(start 65.771522 -340.784688)
		(end 58.786776 -332.27391)
		(width 0.1651)
		(layer "In5.Cu")
		(net "P5E_PEX0_STN6_RX_DN<105>")
	)
	(segment
		(start 48.86579 -319.966848)
		(end 48.82007 -319.921128)
		(width 0.1143)
		(layer "In5.Cu")
		(net "P5E_PEX0_STN6_RX_DN<105>")
	)
	(segment
		(start 48.86579 -321.319398)
		(end 48.86579 -319.995296)
		(width 0.1651)
		(layer "In5.Cu")
		(net "P5E_PEX0_STN6_RX_DN<105>")
	)
	(segment
		(start 85.236812 -401.181062)
		(end 85.880956 -401.181062)
		(width 0.1651)
		(layer "In5.Cu")
		(net "P5E_PEX0_STN6_RX_DN<105>")
	)
	(segment
		(start 86.284054 -400.777964)
		(end 86.284054 -395.556486)
		(width 0.1651)
		(layer "In5.Cu")
		(net "P5E_PEX0_STN6_RX_DN<105>")
	)
	(segment
		(start 48.82007 -319.921128)
		(end 48.82007 -316.534292)
		(width 0.1143)
		(layer "In5.Cu")
		(net "P5E_PEX0_STN6_RX_DN<105>")
	)
	(segment
		(start 66.608452 -358.6099)
		(end 66.608452 -342.037416)
		(width 0.1651)
		(layer "In5.Cu")
		(net "P5E_PEX0_STN6_RX_DN<105>")
	)
	(segment
		(start 58.786776 -332.27391)
		(end 49.59731 -323.084698)
		(width 0.1651)
		(layer "In5.Cu")
		(net "P5E_PEX0_STN6_RX_DN<105>")
	)
	(segment
		(start 85.910674 -394.65504)
		(end 85.696044 -394.44041)
		(width 0.1651)
		(layer "In5.Cu")
		(net "P5E_PEX0_STN6_RX_DN<105>")
	)
	(segment
		(start 85.696044 -394.44041)
		(end 77.822298 -389.179054)
		(width 0.1651)
		(layer "In5.Cu")
		(net "P5E_PEX0_STN6_RX_DN<105>")
	)
	(segment
		(start 85.109812 -401.690078)
		(end 85.109812 -401.308062)
		(width 0.1651)
		(layer "In5.Cu")
		(net "P5E_PEX0_STN6_RX_DN<105>")
	)
	(segment
		(start 77.822298 -389.179054)
		(end 71.099934 -386.394706)
		(width 0.1651)
		(layer "In5.Cu")
		(net "P5E_PEX0_STN6_RX_DN<105>")
	)
	(segment
		(start 71.099934 -386.394706)
		(end 70.491604 -385.786376)
		(width 0.1651)
		(layer "In5.Cu")
		(net "P5E_PEX0_STN6_RX_DN<105>")
	)
	(segment
		(start 48.93437 -316.419992)
		(end 49.0855 -316.419992)
		(width 0.1143)
		(layer "In5.Cu")
		(net "P5E_PEX0_STN6_RX_DN<105>")
	)
	(segment
		(start 85.109812 -401.308062)
		(end 85.236812 -401.181062)
		(width 0.1651)
		(layer "In5.Cu")
		(net "P5E_PEX0_STN6_RX_DN<105>")
	)
	(segment
		(start 66.608452 -342.037416)
		(end 65.771522 -340.784688)
		(width 0.1651)
		(layer "In5.Cu")
		(net "P5E_PEX0_STN6_RX_DN<105>")
	)
	(segment
		(start 68.12915 -366.254538)
		(end 66.608452 -358.6099)
		(width 0.1651)
		(layer "In5.Cu")
		(net "P5E_PEX0_STN6_RX_DN<105>")
	)
	(segment
		(start 85.880956 -401.181062)
		(end 86.284054 -400.777964)
		(width 0.1651)
		(layer "In5.Cu")
		(net "P5E_PEX0_STN6_RX_DN<105>")
	)
	(segment
		(start 48.82007 -316.534292)
		(end 48.93437 -316.419992)
		(width 0.1143)
		(layer "In5.Cu")
		(net "P5E_PEX0_STN6_RX_DN<105>")
	)
	(segment
		(start 48.86579 -319.995296)
		(end 48.86579 -319.966848)
		(width 0.1143)
		(layer "In5.Cu")
		(net "P5E_PEX0_STN6_RX_DN<105>")
	)
	(segment
		(start 49.1998 -316.534292)
		(end 49.1998 -316.799722)
		(width 0.1143)
		(layer "In5.Cu")
		(net "P5E_PEX0_STN6_RX_DN<105>")
	)
	(segment
		(start 49.0855 -316.419992)
		(end 49.1998 -316.534292)
		(width 0.1143)
		(layer "In5.Cu")
		(net "P5E_PEX0_STN6_RX_DN<105>")
	)
	(segment
		(start 49.59731 -323.084698)
		(end 48.86579 -321.319398)
		(width 0.1651)
		(layer "In5.Cu")
		(net "P5E_PEX0_STN6_RX_DN<105>")
	)
	(segment
		(start 86.284054 -395.556486)
		(end 85.910674 -394.65504)
		(width 0.1651)
		(layer "In5.Cu")
		(net "P5E_PEX0_STN6_RX_DN<105>")
	)
	(segment
		(start 70.491604 -385.786376)
		(end 69.915532 -384.395726)
		(width 0.1651)
		(layer "In5.Cu")
		(net "P5E_PEX0_STN6_RX_DN<105>")
	)
	(segment
		(start 69.915532 -384.395726)
		(end 68.12915 -366.254538)
		(width 0.1651)
		(layer "In5.Cu")
		(net "P5E_PEX0_STN6_RX_DN<105>")
	)
	(segment
		(start 124.866908 -357.46309)
		(end 124.866908 -356.831646)
		(width 0.13462)
		(layer "F.Cu")
		(net "P5E_PEX1_STN6_TX_C_DN<105>")
	)
	(segment
		(start 124.866908 -356.831646)
		(end 125.186948 -356.511606)
		(width 0.13462)
		(layer "F.Cu")
		(net "P5E_PEX1_STN6_TX_C_DN<105>")
	)
	(segment
		(start 125.161548 -357.75773)
		(end 124.866908 -357.46309)
		(width 0.13462)
		(layer "F.Cu")
		(net "P5E_PEX1_STN6_TX_C_DN<105>")
	)
	(segment
		(start 129.575306 -408.981148)
		(end 130.266694 -408.28976)
		(width 0.1651)
		(layer "In13.Cu")
		(net "P5E_PEX1_STN6_TX_C_DN<105>")
	)
	(segment
		(start 129.886964 -394.498068)
		(end 124.086112 -390.622028)
		(width 0.1651)
		(layer "In13.Cu")
		(net "P5E_PEX1_STN6_TX_C_DN<105>")
	)
	(segment
		(start 130.266694 -408.28976)
		(end 130.266694 -395.208506)
		(width 0.1651)
		(layer "In13.Cu")
		(net "P5E_PEX1_STN6_TX_C_DN<105>")
	)
	(segment
		(start 124.870718 -358.523286)
		(end 124.870718 -358.04856)
		(width 0.1651)
		(layer "In13.Cu")
		(net "P5E_PEX1_STN6_TX_C_DN<105>")
	)
	(segment
		(start 129.109978 -409.490164)
		(end 129.109978 -409.108148)
		(width 0.1651)
		(layer "In13.Cu")
		(net "P5E_PEX1_STN6_TX_C_DN<105>")
	)
	(segment
		(start 113.405412 -383.053336)
		(end 113.450116 -376.349768)
		(width 0.1651)
		(layer "In13.Cu")
		(net "P5E_PEX1_STN6_TX_C_DN<105>")
	)
	(segment
		(start 113.761012 -367.77549)
		(end 124.260864 -359.756456)
		(width 0.1651)
		(layer "In13.Cu")
		(net "P5E_PEX1_STN6_TX_C_DN<105>")
	)
	(segment
		(start 113.50371 -368.288062)
		(end 113.761012 -367.77549)
		(width 0.1651)
		(layer "In13.Cu")
		(net "P5E_PEX1_STN6_TX_C_DN<105>")
	)
	(segment
		(start 124.086112 -390.622028)
		(end 116.259102 -387.378956)
		(width 0.1651)
		(layer "In13.Cu")
		(net "P5E_PEX1_STN6_TX_C_DN<105>")
	)
	(segment
		(start 129.236978 -408.981148)
		(end 129.575306 -408.981148)
		(width 0.1651)
		(layer "In13.Cu")
		(net "P5E_PEX1_STN6_TX_C_DN<105>")
	)
	(segment
		(start 116.259102 -387.378956)
		(end 114.772186 -386.16636)
		(width 0.1651)
		(layer "In13.Cu")
		(net "P5E_PEX1_STN6_TX_C_DN<105>")
	)
	(segment
		(start 129.109978 -409.108148)
		(end 129.236978 -408.981148)
		(width 0.1651)
		(layer "In13.Cu")
		(net "P5E_PEX1_STN6_TX_C_DN<105>")
	)
	(segment
		(start 130.266694 -395.208506)
		(end 129.886964 -394.498068)
		(width 0.1651)
		(layer "In13.Cu")
		(net "P5E_PEX1_STN6_TX_C_DN<105>")
	)
	(segment
		(start 124.260864 -359.756456)
		(end 124.870718 -358.523286)
		(width 0.1651)
		(layer "In13.Cu")
		(net "P5E_PEX1_STN6_TX_C_DN<105>")
	)
	(segment
		(start 114.772186 -386.16636)
		(end 113.915698 -384.891534)
		(width 0.1651)
		(layer "In13.Cu")
		(net "P5E_PEX1_STN6_TX_C_DN<105>")
	)
	(segment
		(start 113.450116 -376.330464)
		(end 113.50371 -368.288062)
		(width 0.1651)
		(layer "In13.Cu")
		(net "P5E_PEX1_STN6_TX_C_DN<105>")
	)
	(segment
		(start 113.915698 -384.891534)
		(end 113.405412 -383.053336)
		(width 0.1651)
		(layer "In13.Cu")
		(net "P5E_PEX1_STN6_TX_C_DN<105>")
	)
	(segment
		(start 124.870718 -358.04856)
		(end 125.161548 -357.75773)
		(width 0.1651)
		(layer "In13.Cu")
		(net "P5E_PEX1_STN6_TX_C_DN<105>")
	)
	(segment
		(start 113.450116 -376.349768)
		(end 113.450116 -376.330464)
		(width 0.1651)
		(layer "In13.Cu")
		(net "P5E_PEX1_STN6_TX_C_DN<105>")
	)
	(segment
		(start 73.808082 -357.75773)
		(end 74.102722 -357.46309)
		(width 0.13462)
		(layer "F.Cu")
		(net "P5E_PEX0_STN6_TX_C_DP<105>")
	)
	(segment
		(start 74.102722 -357.46309)
		(end 74.102722 -356.831646)
		(width 0.13462)
		(layer "F.Cu")
		(net "P5E_PEX0_STN6_TX_C_DP<105>")
	)
	(segment
		(start 74.102722 -356.831646)
		(end 73.782682 -356.511606)
		(width 0.13462)
		(layer "F.Cu")
		(net "P5E_PEX0_STN6_TX_C_DP<105>")
	)
	(segment
		(start 81.414366 -391.860786)
		(end 81.367376 -391.7061)
		(width 0.1651)
		(layer "In13.Cu")
		(net "P5E_PEX0_STN6_TX_C_DP<105>")
	)
	(segment
		(start 79.242158 -390.570466)
		(end 75.107292 -388.359904)
		(width 0.1651)
		(layer "In13.Cu")
		(net "P5E_PEX0_STN6_TX_C_DP<105>")
	)
	(segment
		(start 69.32422 -383.600706)
		(end 69.32422 -382.20396)
		(width 0.1651)
		(layer "In13.Cu")
		(net "P5E_PEX0_STN6_TX_C_DP<105>")
	)
	(segment
		(start 80.33893 -391.285984)
		(end 80.29194 -391.131298)
		(width 0.1651)
		(layer "In13.Cu")
		(net "P5E_PEX0_STN6_TX_C_DP<105>")
	)
	(segment
		(start 83.37677 -392.780266)
		(end 82.006186 -392.04773)
		(width 0.1651)
		(layer "In13.Cu")
		(net "P5E_PEX0_STN6_TX_C_DP<105>")
	)
	(segment
		(start 86.002114 -394.993114)
		(end 84.619084 -393.610084)
		(width 0.1651)
		(layer "In13.Cu")
		(net "P5E_PEX0_STN6_TX_C_DP<105>")
	)
	(segment
		(start 71.156322 -386.723382)
		(end 70.236588 -385.803648)
		(width 0.1651)
		(layer "In13.Cu")
		(net "P5E_PEX0_STN6_TX_C_DP<105>")
	)
	(segment
		(start 80.776064 -391.519664)
		(end 80.33893 -391.285984)
		(width 0.1651)
		(layer "In13.Cu")
		(net "P5E_PEX0_STN6_TX_C_DP<105>")
	)
	(segment
		(start 79.242158 -390.570212)
		(end 79.242158 -390.570466)
		(width 0.1651)
		(layer "In13.Cu")
		(net "P5E_PEX0_STN6_TX_C_DP<105>")
	)
	(segment
		(start 86.002114 -408.382978)
		(end 86.002114 -394.993114)
		(width 0.1651)
		(layer "In13.Cu")
		(net "P5E_PEX0_STN6_TX_C_DP<105>")
	)
	(segment
		(start 75.107292 -388.359904)
		(end 71.156322 -386.723382)
		(width 0.1651)
		(layer "In13.Cu")
		(net "P5E_PEX0_STN6_TX_C_DP<105>")
	)
	(segment
		(start 81.8515 -392.09472)
		(end 81.414366 -391.860786)
		(width 0.1651)
		(layer "In13.Cu")
		(net "P5E_PEX0_STN6_TX_C_DP<105>")
	)
	(segment
		(start 74.098912 -358.555544)
		(end 74.098912 -358.04856)
		(width 0.1651)
		(layer "In13.Cu")
		(net "P5E_PEX0_STN6_TX_C_DP<105>")
	)
	(segment
		(start 84.619084 -393.610084)
		(end 83.37677 -392.780266)
		(width 0.1651)
		(layer "In13.Cu")
		(net "P5E_PEX0_STN6_TX_C_DP<105>")
	)
	(segment
		(start 80.29194 -391.131298)
		(end 79.242158 -390.570212)
		(width 0.1651)
		(layer "In13.Cu")
		(net "P5E_PEX0_STN6_TX_C_DP<105>")
	)
	(segment
		(start 70.259448 -366.672876)
		(end 74.098912 -358.555544)
		(width 0.1651)
		(layer "In13.Cu")
		(net "P5E_PEX0_STN6_TX_C_DP<105>")
	)
	(segment
		(start 82.006186 -392.04773)
		(end 81.8515 -392.09472)
		(width 0.1651)
		(layer "In13.Cu")
		(net "P5E_PEX0_STN6_TX_C_DP<105>")
	)
	(segment
		(start 74.098912 -358.04856)
		(end 73.808082 -357.75773)
		(width 0.1651)
		(layer "In13.Cu")
		(net "P5E_PEX0_STN6_TX_C_DP<105>")
	)
	(segment
		(start 80.93075 -391.472674)
		(end 80.776064 -391.519664)
		(width 0.1651)
		(layer "In13.Cu")
		(net "P5E_PEX0_STN6_TX_C_DP<105>")
	)
	(segment
		(start 85.109812 -408.190192)
		(end 85.109812 -408.572208)
		(width 0.1651)
		(layer "In13.Cu")
		(net "P5E_PEX0_STN6_TX_C_DP<105>")
	)
	(segment
		(start 85.685884 -408.699208)
		(end 86.002114 -408.382978)
		(width 0.1651)
		(layer "In13.Cu")
		(net "P5E_PEX0_STN6_TX_C_DP<105>")
	)
	(segment
		(start 69.63537 -369.30457)
		(end 70.259448 -366.672876)
		(width 0.1651)
		(layer "In13.Cu")
		(net "P5E_PEX0_STN6_TX_C_DP<105>")
	)
	(segment
		(start 70.236588 -385.803648)
		(end 69.32422 -383.600706)
		(width 0.1651)
		(layer "In13.Cu")
		(net "P5E_PEX0_STN6_TX_C_DP<105>")
	)
	(segment
		(start 85.236812 -408.699208)
		(end 85.685884 -408.699208)
		(width 0.1651)
		(layer "In13.Cu")
		(net "P5E_PEX0_STN6_TX_C_DP<105>")
	)
	(segment
		(start 81.367376 -391.7061)
		(end 80.93075 -391.472674)
		(width 0.1651)
		(layer "In13.Cu")
		(net "P5E_PEX0_STN6_TX_C_DP<105>")
	)
	(segment
		(start 85.109812 -408.572208)
		(end 85.236812 -408.699208)
		(width 0.1651)
		(layer "In13.Cu")
		(net "P5E_PEX0_STN6_TX_C_DP<105>")
	)
	(segment
		(start 69.32422 -382.20396)
		(end 69.63537 -369.30457)
		(width 0.1651)
		(layer "In13.Cu")
		(net "P5E_PEX0_STN6_TX_C_DP<105>")
	)
	(segment
		(start 74.377042 -357.46309)
		(end 74.377042 -356.831646)
		(width 0.13462)
		(layer "F.Cu")
		(net "P5E_PEX0_STN6_TX_C_DN<105>")
	)
	(segment
		(start 74.377042 -356.831646)
		(end 74.697082 -356.511606)
		(width 0.13462)
		(layer "F.Cu")
		(net "P5E_PEX0_STN6_TX_C_DN<105>")
	)
	(segment
		(start 74.671682 -357.75773)
		(end 74.377042 -357.46309)
		(width 0.13462)
		(layer "F.Cu")
		(net "P5E_PEX0_STN6_TX_C_DN<105>")
	)
	(segment
		(start 74.380852 -358.04856)
		(end 74.671682 -357.75773)
		(width 0.1651)
		(layer "In13.Cu")
		(net "P5E_PEX0_STN6_TX_C_DN<105>")
	)
	(segment
		(start 85.802724 -408.981148)
		(end 86.284054 -408.499818)
		(width 0.1651)
		(layer "In13.Cu")
		(net "P5E_PEX0_STN6_TX_C_DN<105>")
	)
	(segment
		(start 84.798916 -393.391136)
		(end 83.522058 -392.53795)
		(width 0.1651)
		(layer "In13.Cu")
		(net "P5E_PEX0_STN6_TX_C_DN<105>")
	)
	(segment
		(start 70.475602 -385.643882)
		(end 69.60616 -383.544572)
		(width 0.1651)
		(layer "In13.Cu")
		(net "P5E_PEX0_STN6_TX_C_DN<105>")
	)
	(segment
		(start 86.284054 -394.876274)
		(end 84.798916 -393.391136)
		(width 0.1651)
		(layer "In13.Cu")
		(net "P5E_PEX0_STN6_TX_C_DN<105>")
	)
	(segment
		(start 71.316088 -386.484368)
		(end 70.475602 -385.643882)
		(width 0.1651)
		(layer "In13.Cu")
		(net "P5E_PEX0_STN6_TX_C_DN<105>")
	)
	(segment
		(start 86.284054 -408.499818)
		(end 86.284054 -394.876274)
		(width 0.1651)
		(layer "In13.Cu")
		(net "P5E_PEX0_STN6_TX_C_DN<105>")
	)
	(segment
		(start 69.916548 -369.340892)
		(end 70.527164 -366.766856)
		(width 0.1651)
		(layer "In13.Cu")
		(net "P5E_PEX0_STN6_TX_C_DN<105>")
	)
	(segment
		(start 85.109812 -409.490164)
		(end 85.109812 -409.108148)
		(width 0.1651)
		(layer "In13.Cu")
		(net "P5E_PEX0_STN6_TX_C_DN<105>")
	)
	(segment
		(start 70.527164 -366.766856)
		(end 74.380852 -358.619044)
		(width 0.1651)
		(layer "In13.Cu")
		(net "P5E_PEX0_STN6_TX_C_DN<105>")
	)
	(segment
		(start 83.522058 -392.53795)
		(end 75.227942 -388.104634)
		(width 0.1651)
		(layer "In13.Cu")
		(net "P5E_PEX0_STN6_TX_C_DN<105>")
	)
	(segment
		(start 69.60616 -383.544572)
		(end 69.60616 -382.207516)
		(width 0.1651)
		(layer "In13.Cu")
		(net "P5E_PEX0_STN6_TX_C_DN<105>")
	)
	(segment
		(start 74.380852 -358.619044)
		(end 74.380852 -358.04856)
		(width 0.1651)
		(layer "In13.Cu")
		(net "P5E_PEX0_STN6_TX_C_DN<105>")
	)
	(segment
		(start 85.236812 -408.981148)
		(end 85.802724 -408.981148)
		(width 0.1651)
		(layer "In13.Cu")
		(net "P5E_PEX0_STN6_TX_C_DN<105>")
	)
	(segment
		(start 85.109812 -409.108148)
		(end 85.236812 -408.981148)
		(width 0.1651)
		(layer "In13.Cu")
		(net "P5E_PEX0_STN6_TX_C_DN<105>")
	)
	(segment
		(start 69.60616 -382.207516)
		(end 69.916548 -369.340892)
		(width 0.1651)
		(layer "In13.Cu")
		(net "P5E_PEX0_STN6_TX_C_DN<105>")
	)
	(segment
		(start 75.227942 -388.104634)
		(end 71.316088 -386.484368)
		(width 0.1651)
		(layer "In13.Cu")
		(net "P5E_PEX0_STN6_TX_C_DN<105>")
	)
	(segment
		(start 127.701548 -351.316798)
		(end 127.701548 -350.685354)
		(width 0.13462)
		(layer "F.Cu")
		(net "P5E_PEX1_STN6_TX_C_DP<104>")
	)
	(segment
		(start 127.701548 -350.685354)
		(end 127.381508 -350.365314)
		(width 0.13462)
		(layer "F.Cu")
		(net "P5E_PEX1_STN6_TX_C_DP<104>")
	)
	(segment
		(start 127.406908 -351.611438)
		(end 127.701548 -351.316798)
		(width 0.13462)
		(layer "F.Cu")
		(net "P5E_PEX1_STN6_TX_C_DP<104>")
	)
	(segment
		(start 131.310126 -409.672028)
		(end 131.437126 -409.799028)
		(width 0.1651)
		(layer "In13.Cu")
		(net "P5E_PEX1_STN6_TX_C_DP<104>")
	)
	(segment
		(start 131.658614 -409.799028)
		(end 132.184902 -409.27274)
		(width 0.1651)
		(layer "In13.Cu")
		(net "P5E_PEX1_STN6_TX_C_DP<104>")
	)
	(segment
		(start 114.10823 -382.891284)
		(end 114.202972 -368.6429)
		(width 0.1651)
		(layer "In13.Cu")
		(net "P5E_PEX1_STN6_TX_C_DP<104>")
	)
	(segment
		(start 131.437126 -409.799028)
		(end 131.658614 -409.799028)
		(width 0.1651)
		(layer "In13.Cu")
		(net "P5E_PEX1_STN6_TX_C_DP<104>")
	)
	(segment
		(start 115.365784 -385.763008)
		(end 114.581178 -384.595116)
		(width 0.1651)
		(layer "In13.Cu")
		(net "P5E_PEX1_STN6_TX_C_DP<104>")
	)
	(segment
		(start 132.184902 -395.968474)
		(end 131.927092 -395.34592)
		(width 0.1651)
		(layer "In13.Cu")
		(net "P5E_PEX1_STN6_TX_C_DP<104>")
	)
	(segment
		(start 114.581178 -384.595116)
		(end 114.10823 -382.891284)
		(width 0.1651)
		(layer "In13.Cu")
		(net "P5E_PEX1_STN6_TX_C_DP<104>")
	)
	(segment
		(start 132.184902 -409.27274)
		(end 132.184902 -395.968474)
		(width 0.1651)
		(layer "In13.Cu")
		(net "P5E_PEX1_STN6_TX_C_DP<104>")
	)
	(segment
		(start 131.310126 -409.290012)
		(end 131.310126 -409.672028)
		(width 0.1651)
		(layer "In13.Cu")
		(net "P5E_PEX1_STN6_TX_C_DP<104>")
	)
	(segment
		(start 126.143258 -358.262428)
		(end 126.143258 -354.084382)
		(width 0.1651)
		(layer "In13.Cu")
		(net "P5E_PEX1_STN6_TX_C_DP<104>")
	)
	(segment
		(start 125.248416 -360.059732)
		(end 126.143258 -358.262428)
		(width 0.1651)
		(layer "In13.Cu")
		(net "P5E_PEX1_STN6_TX_C_DP<104>")
	)
	(segment
		(start 126.143258 -354.084382)
		(end 127.697738 -352.529902)
		(width 0.1651)
		(layer "In13.Cu")
		(net "P5E_PEX1_STN6_TX_C_DP<104>")
	)
	(segment
		(start 114.399822 -368.250978)
		(end 125.248416 -360.059732)
		(width 0.1651)
		(layer "In13.Cu")
		(net "P5E_PEX1_STN6_TX_C_DP<104>")
	)
	(segment
		(start 116.577872 -386.75183)
		(end 115.365784 -385.763008)
		(width 0.1651)
		(layer "In13.Cu")
		(net "P5E_PEX1_STN6_TX_C_DP<104>")
	)
	(segment
		(start 127.697738 -351.902268)
		(end 127.406908 -351.611438)
		(width 0.1651)
		(layer "In13.Cu")
		(net "P5E_PEX1_STN6_TX_C_DP<104>")
	)
	(segment
		(start 131.927092 -395.34592)
		(end 130.421126 -393.839954)
		(width 0.1651)
		(layer "In13.Cu")
		(net "P5E_PEX1_STN6_TX_C_DP<104>")
	)
	(segment
		(start 127.697738 -352.529902)
		(end 127.697738 -351.902268)
		(width 0.1651)
		(layer "In13.Cu")
		(net "P5E_PEX1_STN6_TX_C_DP<104>")
	)
	(segment
		(start 114.202972 -368.6429)
		(end 114.399822 -368.250978)
		(width 0.1651)
		(layer "In13.Cu")
		(net "P5E_PEX1_STN6_TX_C_DP<104>")
	)
	(segment
		(start 125.094492 -390.280398)
		(end 116.577872 -386.75183)
		(width 0.1651)
		(layer "In13.Cu")
		(net "P5E_PEX1_STN6_TX_C_DP<104>")
	)
	(segment
		(start 130.421126 -393.839954)
		(end 125.094492 -390.280398)
		(width 0.1651)
		(layer "In13.Cu")
		(net "P5E_PEX1_STN6_TX_C_DP<104>")
	)
	(segment
		(start 131.310126 -401.872196)
		(end 131.437126 -401.999196)
		(width 0.1651)
		(layer "In15.Cu")
		(net "P5E_PEX1_STN6_RX_DP<104>")
	)
	(segment
		(start 165.633908 -319.865248)
		(end 165.633908 -319.8368)
		(width 0.1143)
		(layer "In15.Cu")
		(net "P5E_PEX1_STN6_RX_DP<104>")
	)
	(segment
		(start 116.137436 -367.360708)
		(end 128.853692 -358.770936)
		(width 0.1651)
		(layer "In15.Cu")
		(net "P5E_PEX1_STN6_RX_DP<104>")
	)
	(segment
		(start 129.252218 -358.021128)
		(end 129.252218 -341.385652)
		(width 0.1651)
		(layer "In15.Cu")
		(net "P5E_PEX1_STN6_RX_DP<104>")
	)
	(segment
		(start 128.142492 -392.317478)
		(end 128.001776 -392.345418)
		(width 0.1651)
		(layer "In15.Cu")
		(net "P5E_PEX1_STN6_RX_DP<104>")
	)
	(segment
		(start 131.927092 -395.34592)
		(end 130.421126 -393.839954)
		(width 0.1651)
		(layer "In15.Cu")
		(net "P5E_PEX1_STN6_RX_DP<104>")
	)
	(segment
		(start 129.252218 -341.385652)
		(end 129.985008 -340.652862)
		(width 0.1651)
		(layer "In15.Cu")
		(net "P5E_PEX1_STN6_RX_DP<104>")
	)
	(segment
		(start 129.985008 -340.652862)
		(end 144.973802 -334.444086)
		(width 0.1651)
		(layer "In15.Cu")
		(net "P5E_PEX1_STN6_RX_DP<104>")
	)
	(segment
		(start 128.853692 -358.770936)
		(end 128.853946 -358.770936)
		(width 0.1651)
		(layer "In15.Cu")
		(net "P5E_PEX1_STN6_RX_DP<104>")
	)
	(segment
		(start 126.596902 -391.406634)
		(end 126.568962 -391.265664)
		(width 0.1651)
		(layer "In15.Cu")
		(net "P5E_PEX1_STN6_RX_DP<104>")
	)
	(segment
		(start 131.310126 -401.49018)
		(end 131.310126 -401.872196)
		(width 0.1651)
		(layer "In15.Cu")
		(net "P5E_PEX1_STN6_RX_DP<104>")
	)
	(segment
		(start 115.054126 -368.59337)
		(end 116.137436 -367.360708)
		(width 0.1651)
		(layer "In15.Cu")
		(net "P5E_PEX1_STN6_RX_DP<104>")
	)
	(segment
		(start 116.577872 -386.75183)
		(end 115.365784 -385.763008)
		(width 0.1651)
		(layer "In15.Cu")
		(net "P5E_PEX1_STN6_RX_DP<104>")
	)
	(segment
		(start 114.581178 -384.59537)
		(end 114.433858 -384.065272)
		(width 0.1651)
		(layer "In15.Cu")
		(net "P5E_PEX1_STN6_RX_DP<104>")
	)
	(segment
		(start 125.094492 -390.280398)
		(end 116.577872 -386.75183)
		(width 0.1651)
		(layer "In15.Cu")
		(net "P5E_PEX1_STN6_RX_DP<104>")
	)
	(segment
		(start 165.918134 -318.129666)
		(end 166.160958 -318.129666)
		(width 0.1143)
		(layer "In15.Cu")
		(net "P5E_PEX1_STN6_RX_DP<104>")
	)
	(segment
		(start 126.568962 -391.265664)
		(end 125.094492 -390.280398)
		(width 0.1651)
		(layer "In15.Cu")
		(net "P5E_PEX1_STN6_RX_DP<104>")
	)
	(segment
		(start 165.679628 -319.79108)
		(end 165.679628 -318.368172)
		(width 0.1143)
		(layer "In15.Cu")
		(net "P5E_PEX1_STN6_RX_DP<104>")
	)
	(segment
		(start 131.658614 -401.999196)
		(end 132.184902 -401.472908)
		(width 0.1651)
		(layer "In15.Cu")
		(net "P5E_PEX1_STN6_RX_DP<104>")
	)
	(segment
		(start 128.001776 -392.345418)
		(end 127.589534 -392.070082)
		(width 0.1651)
		(layer "In15.Cu")
		(net "P5E_PEX1_STN6_RX_DP<104>")
	)
	(segment
		(start 115.365784 -385.763008)
		(end 114.581178 -384.59537)
		(width 0.1651)
		(layer "In15.Cu")
		(net "P5E_PEX1_STN6_RX_DP<104>")
	)
	(segment
		(start 127.589534 -392.070082)
		(end 127.561594 -391.929112)
		(width 0.1651)
		(layer "In15.Cu")
		(net "P5E_PEX1_STN6_RX_DP<104>")
	)
	(segment
		(start 114.529616 -369.637056)
		(end 115.054126 -368.59337)
		(width 0.1651)
		(layer "In15.Cu")
		(net "P5E_PEX1_STN6_RX_DP<104>")
	)
	(segment
		(start 132.184902 -395.968474)
		(end 131.927092 -395.34592)
		(width 0.1651)
		(layer "In15.Cu")
		(net "P5E_PEX1_STN6_RX_DP<104>")
	)
	(segment
		(start 132.184902 -401.472908)
		(end 132.184902 -395.968474)
		(width 0.1651)
		(layer "In15.Cu")
		(net "P5E_PEX1_STN6_RX_DP<104>")
	)
	(segment
		(start 153.56205 -330.381356)
		(end 153.56205 -330.38161)
		(width 0.1651)
		(layer "In15.Cu")
		(net "P5E_PEX1_STN6_RX_DP<104>")
	)
	(segment
		(start 162.15233 -326.318118)
		(end 164.433758 -324.036436)
		(width 0.1651)
		(layer "In15.Cu")
		(net "P5E_PEX1_STN6_RX_DP<104>")
	)
	(segment
		(start 166.160958 -318.129666)
		(end 166.249858 -318.040766)
		(width 0.1143)
		(layer "In15.Cu")
		(net "P5E_PEX1_STN6_RX_DP<104>")
	)
	(segment
		(start 144.973802 -334.444086)
		(end 153.56205 -330.381356)
		(width 0.1651)
		(layer "In15.Cu")
		(net "P5E_PEX1_STN6_RX_DP<104>")
	)
	(segment
		(start 166.249858 -318.040766)
		(end 166.249858 -317.749936)
		(width 0.1143)
		(layer "In15.Cu")
		(net "P5E_PEX1_STN6_RX_DP<104>")
	)
	(segment
		(start 165.633908 -319.8368)
		(end 165.679628 -319.79108)
		(width 0.1143)
		(layer "In15.Cu")
		(net "P5E_PEX1_STN6_RX_DP<104>")
	)
	(segment
		(start 127.14986 -391.65403)
		(end 127.00889 -391.68197)
		(width 0.1651)
		(layer "In15.Cu")
		(net "P5E_PEX1_STN6_RX_DP<104>")
	)
	(segment
		(start 127.00889 -391.68197)
		(end 126.596902 -391.406634)
		(width 0.1651)
		(layer "In15.Cu")
		(net "P5E_PEX1_STN6_RX_DP<104>")
	)
	(segment
		(start 164.433758 -324.036436)
		(end 165.633908 -321.138042)
		(width 0.1651)
		(layer "In15.Cu")
		(net "P5E_PEX1_STN6_RX_DP<104>")
	)
	(segment
		(start 131.437126 -401.999196)
		(end 131.658614 -401.999196)
		(width 0.1651)
		(layer "In15.Cu")
		(net "P5E_PEX1_STN6_RX_DP<104>")
	)
	(segment
		(start 165.679628 -318.368172)
		(end 165.918134 -318.129666)
		(width 0.1143)
		(layer "In15.Cu")
		(net "P5E_PEX1_STN6_RX_DP<104>")
	)
	(segment
		(start 130.421126 -393.839954)
		(end 128.142492 -392.317478)
		(width 0.1651)
		(layer "In15.Cu")
		(net "P5E_PEX1_STN6_RX_DP<104>")
	)
	(segment
		(start 114.433858 -384.065272)
		(end 114.529616 -369.637056)
		(width 0.1651)
		(layer "In15.Cu")
		(net "P5E_PEX1_STN6_RX_DP<104>")
	)
	(segment
		(start 165.633908 -321.138042)
		(end 165.633908 -319.865248)
		(width 0.1651)
		(layer "In15.Cu")
		(net "P5E_PEX1_STN6_RX_DP<104>")
	)
	(segment
		(start 153.56205 -330.38161)
		(end 162.15233 -326.318118)
		(width 0.1651)
		(layer "In15.Cu")
		(net "P5E_PEX1_STN6_RX_DP<104>")
	)
	(segment
		(start 127.561594 -391.929112)
		(end 127.14986 -391.65403)
		(width 0.1651)
		(layer "In15.Cu")
		(net "P5E_PEX1_STN6_RX_DP<104>")
	)
	(segment
		(start 128.853946 -358.770936)
		(end 129.252218 -358.021128)
		(width 0.1651)
		(layer "In15.Cu")
		(net "P5E_PEX1_STN6_RX_DP<104>")
	)
	(segment
		(start 165.915848 -319.8368)
		(end 165.870128 -319.79108)
		(width 0.1143)
		(layer "In15.Cu")
		(net "P5E_PEX1_STN6_RX_DN<104>")
	)
	(segment
		(start 132.166106 -395.186154)
		(end 130.600958 -393.621006)
		(width 0.1651)
		(layer "In15.Cu")
		(net "P5E_PEX1_STN6_RX_DN<104>")
	)
	(segment
		(start 131.310126 -402.408136)
		(end 131.437126 -402.281136)
		(width 0.1651)
		(layer "In15.Cu")
		(net "P5E_PEX1_STN6_RX_DN<104>")
	)
	(segment
		(start 116.724176 -386.506974)
		(end 115.576604 -385.57073)
		(width 0.1651)
		(layer "In15.Cu")
		(net "P5E_PEX1_STN6_RX_DN<104>")
	)
	(segment
		(start 114.811302 -369.704874)
		(end 115.289838 -368.752374)
		(width 0.1651)
		(layer "In15.Cu")
		(net "P5E_PEX1_STN6_RX_DN<104>")
	)
	(segment
		(start 165.997128 -318.320166)
		(end 166.160958 -318.320166)
		(width 0.1143)
		(layer "In15.Cu")
		(net "P5E_PEX1_STN6_RX_DN<104>")
	)
	(segment
		(start 165.915848 -321.194176)
		(end 165.915848 -319.865248)
		(width 0.1651)
		(layer "In15.Cu")
		(net "P5E_PEX1_STN6_RX_DN<104>")
	)
	(segment
		(start 114.716306 -384.02768)
		(end 114.811302 -369.704874)
		(width 0.1651)
		(layer "In15.Cu")
		(net "P5E_PEX1_STN6_RX_DN<104>")
	)
	(segment
		(start 165.870128 -318.447166)
		(end 165.997128 -318.320166)
		(width 0.1143)
		(layer "In15.Cu")
		(net "P5E_PEX1_STN6_RX_DN<104>")
	)
	(segment
		(start 115.289838 -368.752374)
		(end 116.325396 -367.574068)
		(width 0.1651)
		(layer "In15.Cu")
		(net "P5E_PEX1_STN6_RX_DN<104>")
	)
	(segment
		(start 166.249858 -318.409066)
		(end 166.249858 -318.699896)
		(width 0.1143)
		(layer "In15.Cu")
		(net "P5E_PEX1_STN6_RX_DN<104>")
	)
	(segment
		(start 162.317176 -326.552052)
		(end 164.672772 -324.196202)
		(width 0.1651)
		(layer "In15.Cu")
		(net "P5E_PEX1_STN6_RX_DN<104>")
	)
	(segment
		(start 131.775454 -402.281136)
		(end 132.466842 -401.589748)
		(width 0.1651)
		(layer "In15.Cu")
		(net "P5E_PEX1_STN6_RX_DN<104>")
	)
	(segment
		(start 125.228096 -390.030462)
		(end 116.724176 -386.506974)
		(width 0.1651)
		(layer "In15.Cu")
		(net "P5E_PEX1_STN6_RX_DN<104>")
	)
	(segment
		(start 132.466842 -395.91234)
		(end 132.166106 -395.186154)
		(width 0.1651)
		(layer "In15.Cu")
		(net "P5E_PEX1_STN6_RX_DN<104>")
	)
	(segment
		(start 129.0701 -358.965246)
		(end 129.534158 -358.091486)
		(width 0.1651)
		(layer "In15.Cu")
		(net "P5E_PEX1_STN6_RX_DN<104>")
	)
	(segment
		(start 129.534158 -358.091486)
		(end 129.534158 -341.502492)
		(width 0.1651)
		(layer "In15.Cu")
		(net "P5E_PEX1_STN6_RX_DN<104>")
	)
	(segment
		(start 115.576604 -385.57073)
		(end 114.840766 -384.475736)
		(width 0.1651)
		(layer "In15.Cu")
		(net "P5E_PEX1_STN6_RX_DN<104>")
	)
	(segment
		(start 116.325396 -367.574068)
		(end 129.0701 -358.965246)
		(width 0.1651)
		(layer "In15.Cu")
		(net "P5E_PEX1_STN6_RX_DN<104>")
	)
	(segment
		(start 130.600958 -393.621006)
		(end 125.228096 -390.030462)
		(width 0.1651)
		(layer "In15.Cu")
		(net "P5E_PEX1_STN6_RX_DN<104>")
	)
	(segment
		(start 165.915848 -319.865248)
		(end 165.915848 -319.8368)
		(width 0.1143)
		(layer "In15.Cu")
		(net "P5E_PEX1_STN6_RX_DN<104>")
	)
	(segment
		(start 131.437126 -402.281136)
		(end 131.775454 -402.281136)
		(width 0.1651)
		(layer "In15.Cu")
		(net "P5E_PEX1_STN6_RX_DN<104>")
	)
	(segment
		(start 166.160958 -318.320166)
		(end 166.249858 -318.409066)
		(width 0.1143)
		(layer "In15.Cu")
		(net "P5E_PEX1_STN6_RX_DN<104>")
	)
	(segment
		(start 131.310126 -402.790152)
		(end 131.310126 -402.408136)
		(width 0.1651)
		(layer "In15.Cu")
		(net "P5E_PEX1_STN6_RX_DN<104>")
	)
	(segment
		(start 114.840766 -384.475736)
		(end 114.716306 -384.02768)
		(width 0.1651)
		(layer "In15.Cu")
		(net "P5E_PEX1_STN6_RX_DN<104>")
	)
	(segment
		(start 130.144774 -340.891876)
		(end 145.088102 -334.70215)
		(width 0.1651)
		(layer "In15.Cu")
		(net "P5E_PEX1_STN6_RX_DN<104>")
	)
	(segment
		(start 165.870128 -319.79108)
		(end 165.870128 -318.447166)
		(width 0.1143)
		(layer "In15.Cu")
		(net "P5E_PEX1_STN6_RX_DN<104>")
	)
	(segment
		(start 164.672772 -324.196202)
		(end 165.915848 -321.194176)
		(width 0.1651)
		(layer "In15.Cu")
		(net "P5E_PEX1_STN6_RX_DN<104>")
	)
	(segment
		(start 145.088102 -334.70215)
		(end 162.317176 -326.552052)
		(width 0.1651)
		(layer "In15.Cu")
		(net "P5E_PEX1_STN6_RX_DN<104>")
	)
	(segment
		(start 132.466842 -401.589748)
		(end 132.466842 -395.91234)
		(width 0.1651)
		(layer "In15.Cu")
		(net "P5E_PEX1_STN6_RX_DN<104>")
	)
	(segment
		(start 129.534158 -341.502492)
		(end 130.144774 -340.891876)
		(width 0.1651)
		(layer "In15.Cu")
		(net "P5E_PEX1_STN6_RX_DN<104>")
	)
	(segment
		(start 49.53381 -319.995296)
		(end 49.53381 -319.966848)
		(width 0.1143)
		(layer "In5.Cu")
		(net "P5E_PEX0_STN6_RX_DP<104>")
	)
	(segment
		(start 87.30996 -401.49018)
		(end 87.30996 -401.872196)
		(width 0.1651)
		(layer "In5.Cu")
		(net "P5E_PEX0_STN6_RX_DP<104>")
	)
	(segment
		(start 69.00037 -341.30615)
		(end 50.107596 -322.413122)
		(width 0.1651)
		(layer "In5.Cu")
		(net "P5E_PEX0_STN6_RX_DP<104>")
	)
	(segment
		(start 85.791294 -393.692888)
		(end 85.38972 -393.42441)
		(width 0.1651)
		(layer "In5.Cu")
		(net "P5E_PEX0_STN6_RX_DP<104>")
	)
	(segment
		(start 87.91575 -401.999196)
		(end 88.202262 -401.712684)
		(width 0.1651)
		(layer "In5.Cu")
		(net "P5E_PEX0_STN6_RX_DP<104>")
	)
	(segment
		(start 87.30996 -401.872196)
		(end 87.43696 -401.999196)
		(width 0.1651)
		(layer "In5.Cu")
		(net "P5E_PEX0_STN6_RX_DP<104>")
	)
	(segment
		(start 69.435472 -342.356694)
		(end 69.00037 -341.30615)
		(width 0.1651)
		(layer "In5.Cu")
		(net "P5E_PEX0_STN6_RX_DP<104>")
	)
	(segment
		(start 49.57953 -319.921128)
		(end 49.57953 -318.355472)
		(width 0.1143)
		(layer "In5.Cu")
		(net "P5E_PEX0_STN6_RX_DP<104>")
	)
	(segment
		(start 71.48068 -385.82346)
		(end 71.103998 -385.446778)
		(width 0.1651)
		(layer "In5.Cu")
		(net "P5E_PEX0_STN6_RX_DP<104>")
	)
	(segment
		(start 78.676246 -388.80415)
		(end 71.48068 -385.82346)
		(width 0.1651)
		(layer "In5.Cu")
		(net "P5E_PEX0_STN6_RX_DP<104>")
	)
	(segment
		(start 85.358986 -393.26947)
		(end 84.95792 -393.0015)
		(width 0.1651)
		(layer "In5.Cu")
		(net "P5E_PEX0_STN6_RX_DP<104>")
	)
	(segment
		(start 49.53381 -321.027806)
		(end 49.53381 -319.995296)
		(width 0.1651)
		(layer "In5.Cu")
		(net "P5E_PEX0_STN6_RX_DP<104>")
	)
	(segment
		(start 50.03546 -318.129666)
		(end 50.14976 -318.015366)
		(width 0.1143)
		(layer "In5.Cu")
		(net "P5E_PEX0_STN6_RX_DP<104>")
	)
	(segment
		(start 84.95792 -393.0015)
		(end 84.802726 -393.032234)
		(width 0.1651)
		(layer "In5.Cu")
		(net "P5E_PEX0_STN6_RX_DP<104>")
	)
	(segment
		(start 49.53381 -319.966848)
		(end 49.57953 -319.921128)
		(width 0.1143)
		(layer "In5.Cu")
		(net "P5E_PEX0_STN6_RX_DP<104>")
	)
	(segment
		(start 84.401406 -392.76401)
		(end 84.370418 -392.608816)
		(width 0.1651)
		(layer "In5.Cu")
		(net "P5E_PEX0_STN6_RX_DP<104>")
	)
	(segment
		(start 88.202262 -401.712684)
		(end 88.202262 -396.553436)
		(width 0.1651)
		(layer "In5.Cu")
		(net "P5E_PEX0_STN6_RX_DP<104>")
	)
	(segment
		(start 84.802726 -393.032234)
		(end 84.401406 -392.76401)
		(width 0.1651)
		(layer "In5.Cu")
		(net "P5E_PEX0_STN6_RX_DP<104>")
	)
	(segment
		(start 50.14976 -318.015366)
		(end 50.14976 -317.749936)
		(width 0.1143)
		(layer "In5.Cu")
		(net "P5E_PEX0_STN6_RX_DP<104>")
	)
	(segment
		(start 49.805336 -318.129666)
		(end 50.03546 -318.129666)
		(width 0.1143)
		(layer "In5.Cu")
		(net "P5E_PEX0_STN6_RX_DP<104>")
	)
	(segment
		(start 50.107596 -322.413122)
		(end 49.53381 -321.027806)
		(width 0.1651)
		(layer "In5.Cu")
		(net "P5E_PEX0_STN6_RX_DP<104>")
	)
	(segment
		(start 87.43696 -401.999196)
		(end 87.91575 -401.999196)
		(width 0.1651)
		(layer "In5.Cu")
		(net "P5E_PEX0_STN6_RX_DP<104>")
	)
	(segment
		(start 88.202262 -396.553436)
		(end 87.05088 -394.400024)
		(width 0.1651)
		(layer "In5.Cu")
		(net "P5E_PEX0_STN6_RX_DP<104>")
	)
	(segment
		(start 69.435472 -361.100116)
		(end 69.435472 -342.356694)
		(width 0.1651)
		(layer "In5.Cu")
		(net "P5E_PEX0_STN6_RX_DP<104>")
	)
	(segment
		(start 84.370418 -392.608816)
		(end 78.676246 -388.80415)
		(width 0.1651)
		(layer "In5.Cu")
		(net "P5E_PEX0_STN6_RX_DP<104>")
	)
	(segment
		(start 49.57953 -318.355472)
		(end 49.805336 -318.129666)
		(width 0.1143)
		(layer "In5.Cu")
		(net "P5E_PEX0_STN6_RX_DP<104>")
	)
	(segment
		(start 71.103998 -385.446778)
		(end 70.568058 -384.152902)
		(width 0.1651)
		(layer "In5.Cu")
		(net "P5E_PEX0_STN6_RX_DP<104>")
	)
	(segment
		(start 85.946234 -393.6619)
		(end 85.791294 -393.692888)
		(width 0.1651)
		(layer "In5.Cu")
		(net "P5E_PEX0_STN6_RX_DP<104>")
	)
	(segment
		(start 70.568058 -384.152902)
		(end 69.435472 -361.100116)
		(width 0.1651)
		(layer "In5.Cu")
		(net "P5E_PEX0_STN6_RX_DP<104>")
	)
	(segment
		(start 87.05088 -394.400024)
		(end 85.946234 -393.6619)
		(width 0.1651)
		(layer "In5.Cu")
		(net "P5E_PEX0_STN6_RX_DP<104>")
	)
	(segment
		(start 85.38972 -393.42441)
		(end 85.358986 -393.26947)
		(width 0.1651)
		(layer "In5.Cu")
		(net "P5E_PEX0_STN6_RX_DP<104>")
	)
	(segment
		(start 87.30996 -402.790152)
		(end 87.30996 -402.408136)
		(width 0.1651)
		(layer "In5.Cu")
		(net "P5E_PEX0_STN6_RX_DN<104>")
	)
	(segment
		(start 71.343012 -385.287012)
		(end 70.847458 -384.090164)
		(width 0.1651)
		(layer "In5.Cu")
		(net "P5E_PEX0_STN6_RX_DN<104>")
	)
	(segment
		(start 87.266526 -394.204698)
		(end 78.80985 -388.554214)
		(width 0.1651)
		(layer "In5.Cu")
		(net "P5E_PEX0_STN6_RX_DN<104>")
	)
	(segment
		(start 69.717412 -361.093004)
		(end 69.717412 -342.30056)
		(width 0.1651)
		(layer "In5.Cu")
		(net "P5E_PEX0_STN6_RX_DN<104>")
	)
	(segment
		(start 87.30996 -402.408136)
		(end 87.43696 -402.281136)
		(width 0.1651)
		(layer "In5.Cu")
		(net "P5E_PEX0_STN6_RX_DN<104>")
	)
	(segment
		(start 71.640446 -385.584446)
		(end 71.343012 -385.287012)
		(width 0.1651)
		(layer "In5.Cu")
		(net "P5E_PEX0_STN6_RX_DN<104>")
	)
	(segment
		(start 49.81575 -319.966848)
		(end 49.77003 -319.921128)
		(width 0.1143)
		(layer "In5.Cu")
		(net "P5E_PEX0_STN6_RX_DN<104>")
	)
	(segment
		(start 78.80985 -388.554214)
		(end 71.640446 -385.584446)
		(width 0.1651)
		(layer "In5.Cu")
		(net "P5E_PEX0_STN6_RX_DN<104>")
	)
	(segment
		(start 49.81575 -320.971672)
		(end 49.81575 -319.995296)
		(width 0.1651)
		(layer "In5.Cu")
		(net "P5E_PEX0_STN6_RX_DN<104>")
	)
	(segment
		(start 69.717412 -342.30056)
		(end 69.239384 -341.146384)
		(width 0.1651)
		(layer "In5.Cu")
		(net "P5E_PEX0_STN6_RX_DN<104>")
	)
	(segment
		(start 49.77003 -318.434466)
		(end 49.88433 -318.320166)
		(width 0.1143)
		(layer "In5.Cu")
		(net "P5E_PEX0_STN6_RX_DN<104>")
	)
	(segment
		(start 49.88433 -318.320166)
		(end 50.03546 -318.320166)
		(width 0.1143)
		(layer "In5.Cu")
		(net "P5E_PEX0_STN6_RX_DN<104>")
	)
	(segment
		(start 50.03546 -318.320166)
		(end 50.14976 -318.434466)
		(width 0.1143)
		(layer "In5.Cu")
		(net "P5E_PEX0_STN6_RX_DN<104>")
	)
	(segment
		(start 87.43696 -402.281136)
		(end 88.03259 -402.281136)
		(width 0.1651)
		(layer "In5.Cu")
		(net "P5E_PEX0_STN6_RX_DN<104>")
	)
	(segment
		(start 88.03259 -402.281136)
		(end 88.484202 -401.829524)
		(width 0.1651)
		(layer "In5.Cu")
		(net "P5E_PEX0_STN6_RX_DN<104>")
	)
	(segment
		(start 88.484202 -396.48257)
		(end 87.266526 -394.204698)
		(width 0.1651)
		(layer "In5.Cu")
		(net "P5E_PEX0_STN6_RX_DN<104>")
	)
	(segment
		(start 49.77003 -319.921128)
		(end 49.77003 -318.434466)
		(width 0.1143)
		(layer "In5.Cu")
		(net "P5E_PEX0_STN6_RX_DN<104>")
	)
	(segment
		(start 49.81575 -319.995296)
		(end 49.81575 -319.966848)
		(width 0.1143)
		(layer "In5.Cu")
		(net "P5E_PEX0_STN6_RX_DN<104>")
	)
	(segment
		(start 50.34661 -322.253356)
		(end 49.81575 -320.971672)
		(width 0.1651)
		(layer "In5.Cu")
		(net "P5E_PEX0_STN6_RX_DN<104>")
	)
	(segment
		(start 88.484202 -401.829524)
		(end 88.484202 -396.48257)
		(width 0.1651)
		(layer "In5.Cu")
		(net "P5E_PEX0_STN6_RX_DN<104>")
	)
	(segment
		(start 50.14976 -318.434466)
		(end 50.14976 -318.699896)
		(width 0.1143)
		(layer "In5.Cu")
		(net "P5E_PEX0_STN6_RX_DN<104>")
	)
	(segment
		(start 69.239384 -341.146384)
		(end 50.34661 -322.253356)
		(width 0.1651)
		(layer "In5.Cu")
		(net "P5E_PEX0_STN6_RX_DN<104>")
	)
	(segment
		(start 70.847458 -384.090164)
		(end 69.717412 -361.093004)
		(width 0.1651)
		(layer "In5.Cu")
		(net "P5E_PEX0_STN6_RX_DN<104>")
	)
	(segment
		(start 128.270508 -351.611438)
		(end 127.975868 -351.316798)
		(width 0.13462)
		(layer "F.Cu")
		(net "P5E_PEX1_STN6_TX_C_DN<104>")
	)
	(segment
		(start 127.975868 -351.316798)
		(end 127.975868 -350.685354)
		(width 0.13462)
		(layer "F.Cu")
		(net "P5E_PEX1_STN6_TX_C_DN<104>")
	)
	(segment
		(start 127.975868 -350.685354)
		(end 128.295908 -350.365314)
		(width 0.13462)
		(layer "F.Cu")
		(net "P5E_PEX1_STN6_TX_C_DN<104>")
	)
	(segment
		(start 114.484658 -368.710718)
		(end 114.390678 -382.853692)
		(width 0.1651)
		(layer "In13.Cu")
		(net "P5E_PEX1_STN6_TX_C_DN<104>")
	)
	(segment
		(start 128.901698 -392.485372)
		(end 129.007616 -392.464544)
		(width 0.1651)
		(layer "In13.Cu")
		(net "P5E_PEX1_STN6_TX_C_DN<104>")
	)
	(segment
		(start 126.425198 -358.328976)
		(end 125.471174 -360.244898)
		(width 0.1651)
		(layer "In13.Cu")
		(net "P5E_PEX1_STN6_TX_C_DN<104>")
	)
	(segment
		(start 132.466842 -395.91234)
		(end 132.466842 -409.38958)
		(width 0.1651)
		(layer "In13.Cu")
		(net "P5E_PEX1_STN6_TX_C_DN<104>")
	)
	(segment
		(start 129.419604 -392.73988)
		(end 129.440686 -392.845544)
		(width 0.1651)
		(layer "In13.Cu")
		(net "P5E_PEX1_STN6_TX_C_DN<104>")
	)
	(segment
		(start 115.576604 -385.57073)
		(end 116.150136 -386.038852)
		(width 0.1651)
		(layer "In13.Cu")
		(net "P5E_PEX1_STN6_TX_C_DN<104>")
	)
	(segment
		(start 114.390678 -382.853692)
		(end 114.840766 -384.475736)
		(width 0.1651)
		(layer "In13.Cu")
		(net "P5E_PEX1_STN6_TX_C_DN<104>")
	)
	(segment
		(start 132.466842 -409.38958)
		(end 131.775454 -410.080968)
		(width 0.1651)
		(layer "In13.Cu")
		(net "P5E_PEX1_STN6_TX_C_DN<104>")
	)
	(segment
		(start 131.775454 -410.080968)
		(end 131.437126 -410.080968)
		(width 0.1651)
		(layer "In13.Cu")
		(net "P5E_PEX1_STN6_TX_C_DN<104>")
	)
	(segment
		(start 129.007616 -392.464544)
		(end 129.419604 -392.73988)
		(width 0.1651)
		(layer "In13.Cu")
		(net "P5E_PEX1_STN6_TX_C_DN<104>")
	)
	(segment
		(start 116.724176 -386.506974)
		(end 125.228096 -390.030462)
		(width 0.1651)
		(layer "In13.Cu")
		(net "P5E_PEX1_STN6_TX_C_DN<104>")
	)
	(segment
		(start 131.437126 -410.080968)
		(end 131.310126 -410.207968)
		(width 0.1651)
		(layer "In13.Cu")
		(net "P5E_PEX1_STN6_TX_C_DN<104>")
	)
	(segment
		(start 114.840766 -384.475736)
		(end 115.576604 -385.57073)
		(width 0.1651)
		(layer "In13.Cu")
		(net "P5E_PEX1_STN6_TX_C_DN<104>")
	)
	(segment
		(start 127.979678 -352.646742)
		(end 126.425198 -354.201222)
		(width 0.1651)
		(layer "In13.Cu")
		(net "P5E_PEX1_STN6_TX_C_DN<104>")
	)
	(segment
		(start 125.471174 -360.244898)
		(end 114.622326 -368.436398)
		(width 0.1651)
		(layer "In13.Cu")
		(net "P5E_PEX1_STN6_TX_C_DN<104>")
	)
	(segment
		(start 125.228096 -390.030462)
		(end 128.901698 -392.485372)
		(width 0.1651)
		(layer "In13.Cu")
		(net "P5E_PEX1_STN6_TX_C_DN<104>")
	)
	(segment
		(start 128.270508 -351.611438)
		(end 127.979678 -351.902268)
		(width 0.1651)
		(layer "In13.Cu")
		(net "P5E_PEX1_STN6_TX_C_DN<104>")
	)
	(segment
		(start 132.166106 -395.186154)
		(end 132.466842 -395.91234)
		(width 0.1651)
		(layer "In13.Cu")
		(net "P5E_PEX1_STN6_TX_C_DN<104>")
	)
	(segment
		(start 131.310126 -410.207968)
		(end 131.310126 -410.589984)
		(width 0.1651)
		(layer "In13.Cu")
		(net "P5E_PEX1_STN6_TX_C_DN<104>")
	)
	(segment
		(start 126.425198 -354.201222)
		(end 126.425198 -358.328976)
		(width 0.1651)
		(layer "In13.Cu")
		(net "P5E_PEX1_STN6_TX_C_DN<104>")
	)
	(segment
		(start 129.440686 -392.845544)
		(end 130.600958 -393.621006)
		(width 0.1651)
		(layer "In13.Cu")
		(net "P5E_PEX1_STN6_TX_C_DN<104>")
	)
	(segment
		(start 116.150136 -386.038852)
		(end 116.15039 -386.038852)
		(width 0.1651)
		(layer "In13.Cu")
		(net "P5E_PEX1_STN6_TX_C_DN<104>")
	)
	(segment
		(start 127.979678 -351.902268)
		(end 127.979678 -352.646742)
		(width 0.1651)
		(layer "In13.Cu")
		(net "P5E_PEX1_STN6_TX_C_DN<104>")
	)
	(segment
		(start 114.622326 -368.436398)
		(end 114.484658 -368.710718)
		(width 0.1651)
		(layer "In13.Cu")
		(net "P5E_PEX1_STN6_TX_C_DN<104>")
	)
	(segment
		(start 116.15039 -386.038852)
		(end 116.724176 -386.506974)
		(width 0.1651)
		(layer "In13.Cu")
		(net "P5E_PEX1_STN6_TX_C_DN<104>")
	)
	(segment
		(start 130.600958 -393.621006)
		(end 132.166106 -395.186154)
		(width 0.1651)
		(layer "In13.Cu")
		(net "P5E_PEX1_STN6_TX_C_DN<104>")
	)
	(segment
		(start 76.917042 -351.611438)
		(end 77.211682 -351.316798)
		(width 0.13462)
		(layer "F.Cu")
		(net "P5E_PEX0_STN6_TX_C_DP<104>")
	)
	(segment
		(start 77.211682 -350.685354)
		(end 76.891642 -350.365314)
		(width 0.13462)
		(layer "F.Cu")
		(net "P5E_PEX0_STN6_TX_C_DP<104>")
	)
	(segment
		(start 77.211682 -351.316798)
		(end 77.211682 -350.685354)
		(width 0.13462)
		(layer "F.Cu")
		(net "P5E_PEX0_STN6_TX_C_DP<104>")
	)
	(segment
		(start 77.207872 -352.417888)
		(end 77.207872 -351.902268)
		(width 0.1651)
		(layer "In13.Cu")
		(net "P5E_PEX0_STN6_TX_C_DP<104>")
	)
	(segment
		(start 77.207872 -351.902268)
		(end 76.917042 -351.611438)
		(width 0.1651)
		(layer "In13.Cu")
		(net "P5E_PEX0_STN6_TX_C_DP<104>")
	)
	(segment
		(start 80.855566 -390.307322)
		(end 75.867514 -387.64083)
		(width 0.1651)
		(layer "In13.Cu")
		(net "P5E_PEX0_STN6_TX_C_DP<104>")
	)
	(segment
		(start 80.855566 -390.307068)
		(end 80.855566 -390.307322)
		(width 0.1651)
		(layer "In13.Cu")
		(net "P5E_PEX0_STN6_TX_C_DP<104>")
	)
	(segment
		(start 70.27926 -383.410206)
		(end 70.27926 -382.215644)
		(width 0.1651)
		(layer "In13.Cu")
		(net "P5E_PEX0_STN6_TX_C_DP<104>")
	)
	(segment
		(start 87.30996 -409.672028)
		(end 87.43696 -409.799028)
		(width 0.1651)
		(layer "In13.Cu")
		(net "P5E_PEX0_STN6_TX_C_DP<104>")
	)
	(segment
		(start 70.27926 -382.215644)
		(end 70.58025 -369.741704)
		(width 0.1651)
		(layer "In13.Cu")
		(net "P5E_PEX0_STN6_TX_C_DP<104>")
	)
	(segment
		(start 75.653392 -353.972368)
		(end 77.207872 -352.417888)
		(width 0.1651)
		(layer "In13.Cu")
		(net "P5E_PEX0_STN6_TX_C_DP<104>")
	)
	(segment
		(start 71.079106 -367.6396)
		(end 75.653392 -357.969312)
		(width 0.1651)
		(layer "In13.Cu")
		(net "P5E_PEX0_STN6_TX_C_DP<104>")
	)
	(segment
		(start 88.202262 -395.331442)
		(end 85.843618 -392.973052)
		(width 0.1651)
		(layer "In13.Cu")
		(net "P5E_PEX0_STN6_TX_C_DP<104>")
	)
	(segment
		(start 87.43696 -409.799028)
		(end 87.964264 -409.799028)
		(width 0.1651)
		(layer "In13.Cu")
		(net "P5E_PEX0_STN6_TX_C_DP<104>")
	)
	(segment
		(start 87.964264 -409.799028)
		(end 88.202262 -409.56103)
		(width 0.1651)
		(layer "In13.Cu")
		(net "P5E_PEX0_STN6_TX_C_DP<104>")
	)
	(segment
		(start 85.843618 -392.973052)
		(end 80.855566 -390.307068)
		(width 0.1651)
		(layer "In13.Cu")
		(net "P5E_PEX0_STN6_TX_C_DP<104>")
	)
	(segment
		(start 71.04634 -385.262628)
		(end 70.27926 -383.410206)
		(width 0.1651)
		(layer "In13.Cu")
		(net "P5E_PEX0_STN6_TX_C_DP<104>")
	)
	(segment
		(start 70.58025 -369.741704)
		(end 71.079106 -367.6396)
		(width 0.1651)
		(layer "In13.Cu")
		(net "P5E_PEX0_STN6_TX_C_DP<104>")
	)
	(segment
		(start 75.867514 -387.64083)
		(end 71.697088 -385.913376)
		(width 0.1651)
		(layer "In13.Cu")
		(net "P5E_PEX0_STN6_TX_C_DP<104>")
	)
	(segment
		(start 75.653392 -357.969312)
		(end 75.653392 -353.972368)
		(width 0.1651)
		(layer "In13.Cu")
		(net "P5E_PEX0_STN6_TX_C_DP<104>")
	)
	(segment
		(start 87.30996 -409.290012)
		(end 87.30996 -409.672028)
		(width 0.1651)
		(layer "In13.Cu")
		(net "P5E_PEX0_STN6_TX_C_DP<104>")
	)
	(segment
		(start 88.202262 -409.56103)
		(end 88.202262 -395.331442)
		(width 0.1651)
		(layer "In13.Cu")
		(net "P5E_PEX0_STN6_TX_C_DP<104>")
	)
	(segment
		(start 71.697088 -385.913376)
		(end 71.04634 -385.262628)
		(width 0.1651)
		(layer "In13.Cu")
		(net "P5E_PEX0_STN6_TX_C_DP<104>")
	)
	(segment
		(start 77.486002 -351.316798)
		(end 77.486002 -350.685354)
		(width 0.13462)
		(layer "F.Cu")
		(net "P5E_PEX0_STN6_TX_C_DN<104>")
	)
	(segment
		(start 77.486002 -350.685354)
		(end 77.806042 -350.365314)
		(width 0.13462)
		(layer "F.Cu")
		(net "P5E_PEX0_STN6_TX_C_DN<104>")
	)
	(segment
		(start 77.780642 -351.611438)
		(end 77.486002 -351.316798)
		(width 0.13462)
		(layer "F.Cu")
		(net "P5E_PEX0_STN6_TX_C_DN<104>")
	)
	(segment
		(start 87.248492 -393.978892)
		(end 87.356188 -393.978892)
		(width 0.1651)
		(layer "In13.Cu")
		(net "P5E_PEX0_STN6_TX_C_DN<104>")
	)
	(segment
		(start 71.346822 -367.73358)
		(end 70.861428 -369.778026)
		(width 0.1651)
		(layer "In13.Cu")
		(net "P5E_PEX0_STN6_TX_C_DN<104>")
	)
	(segment
		(start 71.856854 -385.674362)
		(end 75.988164 -387.38556)
		(width 0.1651)
		(layer "In13.Cu")
		(net "P5E_PEX0_STN6_TX_C_DN<104>")
	)
	(segment
		(start 87.356188 -393.978892)
		(end 87.706708 -394.329412)
		(width 0.1651)
		(layer "In13.Cu")
		(net "P5E_PEX0_STN6_TX_C_DN<104>")
	)
	(segment
		(start 75.935332 -358.032812)
		(end 71.346822 -367.73358)
		(width 0.1651)
		(layer "In13.Cu")
		(net "P5E_PEX0_STN6_TX_C_DN<104>")
	)
	(segment
		(start 70.5612 -383.354072)
		(end 71.285354 -385.102608)
		(width 0.1651)
		(layer "In13.Cu")
		(net "P5E_PEX0_STN6_TX_C_DN<104>")
	)
	(segment
		(start 77.489812 -352.534728)
		(end 75.935332 -354.089208)
		(width 0.1651)
		(layer "In13.Cu")
		(net "P5E_PEX0_STN6_TX_C_DN<104>")
	)
	(segment
		(start 87.706708 -394.437108)
		(end 88.484202 -395.214602)
		(width 0.1651)
		(layer "In13.Cu")
		(net "P5E_PEX0_STN6_TX_C_DN<104>")
	)
	(segment
		(start 88.484202 -395.214602)
		(end 88.484202 -409.67787)
		(width 0.1651)
		(layer "In13.Cu")
		(net "P5E_PEX0_STN6_TX_C_DN<104>")
	)
	(segment
		(start 77.780642 -351.611438)
		(end 77.489812 -351.902268)
		(width 0.1651)
		(layer "In13.Cu")
		(net "P5E_PEX0_STN6_TX_C_DN<104>")
	)
	(segment
		(start 86.013544 -392.743944)
		(end 87.248492 -393.978892)
		(width 0.1651)
		(layer "In13.Cu")
		(net "P5E_PEX0_STN6_TX_C_DN<104>")
	)
	(segment
		(start 71.285354 -385.102862)
		(end 71.856854 -385.674362)
		(width 0.1651)
		(layer "In13.Cu")
		(net "P5E_PEX0_STN6_TX_C_DN<104>")
	)
	(segment
		(start 75.988164 -387.38556)
		(end 86.013544 -392.743944)
		(width 0.1651)
		(layer "In13.Cu")
		(net "P5E_PEX0_STN6_TX_C_DN<104>")
	)
	(segment
		(start 70.861428 -369.778026)
		(end 70.5612 -382.2192)
		(width 0.1651)
		(layer "In13.Cu")
		(net "P5E_PEX0_STN6_TX_C_DN<104>")
	)
	(segment
		(start 87.30996 -410.207968)
		(end 87.30996 -410.589984)
		(width 0.1651)
		(layer "In13.Cu")
		(net "P5E_PEX0_STN6_TX_C_DN<104>")
	)
	(segment
		(start 87.706708 -394.329412)
		(end 87.706708 -394.437108)
		(width 0.1651)
		(layer "In13.Cu")
		(net "P5E_PEX0_STN6_TX_C_DN<104>")
	)
	(segment
		(start 71.285354 -385.102608)
		(end 71.285354 -385.102862)
		(width 0.1651)
		(layer "In13.Cu")
		(net "P5E_PEX0_STN6_TX_C_DN<104>")
	)
	(segment
		(start 88.484202 -409.67787)
		(end 88.081104 -410.080968)
		(width 0.1651)
		(layer "In13.Cu")
		(net "P5E_PEX0_STN6_TX_C_DN<104>")
	)
	(segment
		(start 75.935332 -354.089208)
		(end 75.935332 -358.032812)
		(width 0.1651)
		(layer "In13.Cu")
		(net "P5E_PEX0_STN6_TX_C_DN<104>")
	)
	(segment
		(start 88.081104 -410.080968)
		(end 87.43696 -410.080968)
		(width 0.1651)
		(layer "In13.Cu")
		(net "P5E_PEX0_STN6_TX_C_DN<104>")
	)
	(segment
		(start 70.5612 -382.2192)
		(end 70.5612 -383.354072)
		(width 0.1651)
		(layer "In13.Cu")
		(net "P5E_PEX0_STN6_TX_C_DN<104>")
	)
	(segment
		(start 87.43696 -410.080968)
		(end 87.30996 -410.207968)
		(width 0.1651)
		(layer "In13.Cu")
		(net "P5E_PEX0_STN6_TX_C_DN<104>")
	)
	(segment
		(start 77.489812 -351.902268)
		(end 77.489812 -352.534728)
		(width 0.1651)
		(layer "In13.Cu")
		(net "P5E_PEX0_STN6_TX_C_DN<104>")
	)
	(segment
		(start 243.577872 -357.400098)
		(end 241.85372 -357.400098)
		(width 0.4572)
		(layer "F.Cu")
		(net "P12V_STBY")
	)
	(via
		(at 258.432046 -384.15341)
		(size 0.508)
		(drill 0.254)
		(layers "F.Cu" "B.Cu")
		(net "P12V_STBY")
	)
	(via
		(at 208.558384 -375.053098)
		(size 0.508)
		(drill 0.254)
		(layers "F.Cu" "B.Cu")
		(net "P12V_STBY")
	)
	(via
		(at 257.771646 -384.15341)
		(size 0.508)
		(drill 0.254)
		(layers "F.Cu" "B.Cu")
		(net "P12V_STBY")
	)
	(via
		(at 231.691434 -367.654586)
		(size 0.508)
		(drill 0.254)
		(layers "F.Cu" "B.Cu")
		(net "P12V_STBY")
	)
	(via
		(at 236.751876 -392.519662)
		(size 0.508)
		(drill 0.254)
		(layers "F.Cu" "B.Cu")
		(net "P12V_STBY")
	)
	(via
		(at 249.31116 -384.732022)
		(size 0.508)
		(drill 0.254)
		(layers "F.Cu" "B.Cu")
		(net "P12V_STBY")
	)
	(via
		(at 207.034384 -371.954298)
		(size 0.508)
		(drill 0.254)
		(layers "F.Cu" "B.Cu")
		(net "P12V_STBY")
	)
	(via
		(at 220.381576 -375.096786)
		(size 0.508)
		(drill 0.254)
		(layers "F.Cu" "B.Cu")
		(net "P12V_STBY")
	)
	(via
		(at 259.473446 -383.49301)
		(size 0.508)
		(drill 0.254)
		(layers "F.Cu" "B.Cu")
		(net "P12V_STBY")
	)
	(via
		(at 219.619576 -374.334786)
		(size 0.508)
		(drill 0.254)
		(layers "F.Cu" "B.Cu")
		(net "P12V_STBY")
	)
	(via
		(at 231.48798 -372.766082)
		(size 0.508)
		(drill 0.254)
		(layers "F.Cu" "B.Cu")
		(net "P12V_STBY")
	)
	(via
		(at 243.59489 -392.514582)
		(size 0.508)
		(drill 0.254)
		(layers "F.Cu" "B.Cu")
		(net "P12V_STBY")
	)
	(via
		(at 239.799876 -392.519662)
		(size 0.508)
		(drill 0.254)
		(layers "F.Cu" "B.Cu")
		(net "P12V_STBY")
	)
	(via
		(at 207.765396 -368.957098)
		(size 0.508)
		(drill 0.254)
		(layers "F.Cu" "B.Cu")
		(net "P12V_STBY")
	)
	(via
		(at 260.133846 -383.49301)
		(size 0.508)
		(drill 0.254)
		(layers "F.Cu" "B.Cu")
		(net "P12V_STBY")
	)
	(via
		(at 240.561876 -391.757662)
		(size 0.508)
		(drill 0.254)
		(layers "F.Cu" "B.Cu")
		(net "P12V_STBY")
	)
	(via
		(at 238.42218 -382.353312)
		(size 0.508)
		(drill 0.254)
		(layers "F.Cu" "B.Cu")
		(net "P12V_STBY")
	)
	(via
		(at 217.333576 -375.096786)
		(size 0.508)
		(drill 0.254)
		(layers "F.Cu" "B.Cu")
		(net "P12V_STBY")
	)
	(via
		(at 256.450846 -384.15341)
		(size 0.508)
		(drill 0.254)
		(layers "F.Cu" "B.Cu")
		(net "P12V_STBY")
	)
	(via
		(at 247.692418 -382.75641)
		(size 0.508)
		(drill 0.254)
		(layers "F.Cu" "B.Cu")
		(net "P12V_STBY")
	)
	(via
		(at 246.66956 -384.732022)
		(size 0.508)
		(drill 0.254)
		(layers "F.Cu" "B.Cu")
		(net "P12V_STBY")
	)
	(via
		(at 241.30889 -392.514582)
		(size 0.508)
		(drill 0.254)
		(layers "F.Cu" "B.Cu")
		(net "P12V_STBY")
	)
	(via
		(at 235.214414 -394.843762)
		(size 0.508)
		(drill 0.254)
		(layers "F.Cu" "B.Cu")
		(net "P12V_STBY")
	)
	(via
		(at 235.215176 -391.76198)
		(size 0.508)
		(drill 0.254)
		(layers "F.Cu" "B.Cu")
		(net "P12V_STBY")
	)
	(via
		(at 246.752618 -383.41681)
		(size 0.508)
		(drill 0.254)
		(layers "F.Cu" "B.Cu")
		(net "P12V_STBY")
	)
	(via
		(at 261.454646 -383.49301)
		(size 0.508)
		(drill 0.254)
		(layers "F.Cu" "B.Cu")
		(net "P12V_STBY")
	)
	(via
		(at 218.095576 -373.572786)
		(size 0.508)
		(drill 0.254)
		(layers "F.Cu" "B.Cu")
		(net "P12V_STBY")
	)
	(via
		(at 219.619576 -373.572786)
		(size 0.508)
		(drill 0.254)
		(layers "F.Cu" "B.Cu")
		(net "P12V_STBY")
	)
	(via
		(at 206.272384 -375.815098)
		(size 0.508)
		(drill 0.254)
		(layers "F.Cu" "B.Cu")
		(net "P12V_STBY")
	)
	(via
		(at 207.796384 -372.716298)
		(size 0.508)
		(drill 0.254)
		(layers "F.Cu" "B.Cu")
		(net "P12V_STBY")
	)
	(via
		(at 260.413246 -382.83261)
		(size 0.508)
		(drill 0.254)
		(layers "F.Cu" "B.Cu")
		(net "P12V_STBY")
	)
	(via
		(at 243.59489 -391.752582)
		(size 0.508)
		(drill 0.254)
		(layers "F.Cu" "B.Cu")
		(net "P12V_STBY")
	)
	(via
		(at 247.413018 -383.41681)
		(size 0.508)
		(drill 0.254)
		(layers "F.Cu" "B.Cu")
		(net "P12V_STBY")
	)
	(via
		(at 237.513876 -392.519662)
		(size 0.508)
		(drill 0.254)
		(layers "F.Cu" "B.Cu")
		(net "P12V_STBY")
	)
	(via
		(at 255.427988 -384.808222)
		(size 0.508)
		(drill 0.254)
		(layers "F.Cu" "B.Cu")
		(net "P12V_STBY")
	)
	(via
		(at 241.30889 -391.752582)
		(size 0.508)
		(drill 0.254)
		(layers "F.Cu" "B.Cu")
		(net "P12V_STBY")
	)
	(via
		(at 208.558384 -373.478298)
		(size 0.508)
		(drill 0.254)
		(layers "F.Cu" "B.Cu")
		(net "P12V_STBY")
	)
	(via
		(at 250.994418 -382.75641)
		(size 0.508)
		(drill 0.254)
		(layers "F.Cu" "B.Cu")
		(net "P12V_STBY")
	)
	(via
		(at 248.352818 -382.75641)
		(size 0.508)
		(drill 0.254)
		(layers "F.Cu" "B.Cu")
		(net "P12V_STBY")
	)
	(via
		(at 235.214414 -395.605762)
		(size 0.508)
		(drill 0.254)
		(layers "F.Cu" "B.Cu")
		(net "P12V_STBY")
	)
	(via
		(at 242.07089 -391.752582)
		(size 0.508)
		(drill 0.254)
		(layers "F.Cu" "B.Cu")
		(net "P12V_STBY")
	)
	(via
		(at 235.989876 -392.519662)
		(size 0.508)
		(drill 0.254)
		(layers "F.Cu" "B.Cu")
		(net "P12V_STBY")
	)
	(via
		(at 258.152646 -383.49301)
		(size 0.508)
		(drill 0.254)
		(layers "F.Cu" "B.Cu")
		(net "P12V_STBY")
	)
	(via
		(at 207.034384 -374.240298)
		(size 0.508)
		(drill 0.254)
		(layers "F.Cu" "B.Cu")
		(net "P12V_STBY")
	)
	(via
		(at 247.99036 -384.732022)
		(size 0.508)
		(drill 0.254)
		(layers "F.Cu" "B.Cu")
		(net "P12V_STBY")
	)
	(via
		(at 207.796384 -375.053098)
		(size 0.508)
		(drill 0.254)
		(layers "F.Cu" "B.Cu")
		(net "P12V_STBY")
	)
	(via
		(at 206.368396 -370.260118)
		(size 0.508)
		(drill 0.254)
		(layers "F.Cu" "B.Cu")
		(net "P12V_STBY")
	)
	(via
		(at 247.032018 -384.07721)
		(size 0.508)
		(drill 0.254)
		(layers "F.Cu" "B.Cu")
		(net "P12V_STBY")
	)
	(via
		(at 251.654818 -384.07721)
		(size 0.508)
		(drill 0.254)
		(layers "F.Cu" "B.Cu")
		(net "P12V_STBY")
	)
	(via
		(at 249.673618 -384.07721)
		(size 0.508)
		(drill 0.254)
		(layers "F.Cu" "B.Cu")
		(net "P12V_STBY")
	)
	(via
		(at 257.771646 -382.83261)
		(size 0.508)
		(drill 0.254)
		(layers "F.Cu" "B.Cu")
		(net "P12V_STBY")
	)
	(via
		(at 217.333576 -373.572786)
		(size 0.508)
		(drill 0.254)
		(layers "F.Cu" "B.Cu")
		(net "P12V_STBY")
	)
	(via
		(at 204.945996 -370.260118)
		(size 0.508)
		(drill 0.254)
		(layers "F.Cu" "B.Cu")
		(net "P12V_STBY")
	)
	(via
		(at 221.023434 -367.654586)
		(size 0.508)
		(drill 0.254)
		(layers "F.Cu" "B.Cu")
		(net "P12V_STBY")
	)
	(via
		(at 256.088388 -384.808222)
		(size 0.508)
		(drill 0.254)
		(layers "F.Cu" "B.Cu")
		(net "P12V_STBY")
	)
	(via
		(at 240.40338 -382.353312)
		(size 0.508)
		(drill 0.254)
		(layers "F.Cu" "B.Cu")
		(net "P12V_STBY")
	)
	(via
		(at 229.20198 -375.052082)
		(size 0.508)
		(drill 0.254)
		(layers "F.Cu" "B.Cu")
		(net "P12V_STBY")
	)
	(via
		(at 246.371618 -382.75641)
		(size 0.508)
		(drill 0.254)
		(layers "F.Cu" "B.Cu")
		(net "P12V_STBY")
	)
	(via
		(at 239.74298 -382.353312)
		(size 0.508)
		(drill 0.254)
		(layers "F.Cu" "B.Cu")
		(net "P12V_STBY")
	)
	(via
		(at 231.48798 -372.004082)
		(size 0.508)
		(drill 0.254)
		(layers "F.Cu" "B.Cu")
		(net "P12V_STBY")
	)
	(via
		(at 242.07089 -392.514582)
		(size 0.508)
		(drill 0.254)
		(layers "F.Cu" "B.Cu")
		(net "P12V_STBY")
	)
	(via
		(at 219.619576 -372.048786)
		(size 0.508)
		(drill 0.254)
		(layers "F.Cu" "B.Cu")
		(net "P12V_STBY")
	)
	(via
		(at 249.013218 -382.75641)
		(size 0.508)
		(drill 0.254)
		(layers "F.Cu" "B.Cu")
		(net "P12V_STBY")
	)
	(via
		(at 257.111246 -382.83261)
		(size 0.508)
		(drill 0.254)
		(layers "F.Cu" "B.Cu")
		(net "P12V_STBY")
	)
	(via
		(at 218.857576 -374.334786)
		(size 0.508)
		(drill 0.254)
		(layers "F.Cu" "B.Cu")
		(net "P12V_STBY")
	)
	(via
		(at 249.013218 -384.07721)
		(size 0.508)
		(drill 0.254)
		(layers "F.Cu" "B.Cu")
		(net "P12V_STBY")
	)
	(via
		(at 250.334018 -384.07721)
		(size 0.508)
		(drill 0.254)
		(layers "F.Cu" "B.Cu")
		(net "P12V_STBY")
	)
	(via
		(at 239.037876 -391.757662)
		(size 0.508)
		(drill 0.254)
		(layers "F.Cu" "B.Cu")
		(net "P12V_STBY")
	)
	(via
		(at 235.214414 -394.081762)
		(size 0.508)
		(drill 0.254)
		(layers "F.Cu" "B.Cu")
		(net "P12V_STBY")
	)
	(via
		(at 207.034384 -375.815098)
		(size 0.508)
		(drill 0.254)
		(layers "F.Cu" "B.Cu")
		(net "P12V_STBY")
	)
	(via
		(at 238.275876 -391.757662)
		(size 0.508)
		(drill 0.254)
		(layers "F.Cu" "B.Cu")
		(net "P12V_STBY")
	)
	(via
		(at 236.751876 -391.757662)
		(size 0.508)
		(drill 0.254)
		(layers "F.Cu" "B.Cu")
		(net "P12V_STBY")
	)
	(via
		(at 232.24998 -374.290082)
		(size 0.508)
		(drill 0.254)
		(layers "F.Cu" "B.Cu")
		(net "P12V_STBY")
	)
	(via
		(at 248.65076 -384.732022)
		(size 0.508)
		(drill 0.254)
		(layers "F.Cu" "B.Cu")
		(net "P12V_STBY")
	)
	(via
		(at 239.037876 -392.519662)
		(size 0.508)
		(drill 0.254)
		(layers "F.Cu" "B.Cu")
		(net "P12V_STBY")
	)
	(via
		(at 231.691434 -370.260626)
		(size 0.508)
		(drill 0.254)
		(layers "F.Cu" "B.Cu")
		(net "P12V_STBY")
	)
	(via
		(at 240.40338 -383.674112)
		(size 0.508)
		(drill 0.254)
		(layers "F.Cu" "B.Cu")
		(net "P12V_STBY")
	)
	(via
		(at 257.409188 -384.808222)
		(size 0.508)
		(drill 0.254)
		(layers "F.Cu" "B.Cu")
		(net "P12V_STBY")
	)
	(via
		(at 208.558384 -372.716298)
		(size 0.508)
		(drill 0.254)
		(layers "F.Cu" "B.Cu")
		(net "P12V_STBY")
	)
	(via
		(at 249.673618 -382.75641)
		(size 0.508)
		(drill 0.254)
		(layers "F.Cu" "B.Cu")
		(net "P12V_STBY")
	)
	(via
		(at 229.96398 -372.766082)
		(size 0.508)
		(drill 0.254)
		(layers "F.Cu" "B.Cu")
		(net "P12V_STBY")
	)
	(via
		(at 218.857576 -372.048786)
		(size 0.508)
		(drill 0.254)
		(layers "F.Cu" "B.Cu")
		(net "P12V_STBY")
	)
	(via
		(at 259.092446 -382.83261)
		(size 0.508)
		(drill 0.254)
		(layers "F.Cu" "B.Cu")
		(net "P12V_STBY")
	)
	(via
		(at 248.352818 -384.07721)
		(size 0.508)
		(drill 0.254)
		(layers "F.Cu" "B.Cu")
		(net "P12V_STBY")
	)
	(via
		(at 207.034384 -372.716298)
		(size 0.508)
		(drill 0.254)
		(layers "F.Cu" "B.Cu")
		(net "P12V_STBY")
	)
	(via
		(at 221.143576 -373.572786)
		(size 0.508)
		(drill 0.254)
		(layers "F.Cu" "B.Cu")
		(net "P12V_STBY")
	)
	(via
		(at 238.275876 -392.519662)
		(size 0.508)
		(drill 0.254)
		(layers "F.Cu" "B.Cu")
		(net "P12V_STBY")
	)
	(via
		(at 207.034384 -375.053098)
		(size 0.508)
		(drill 0.254)
		(layers "F.Cu" "B.Cu")
		(net "P12V_STBY")
	)
	(via
		(at 231.48798 -373.528082)
		(size 0.508)
		(drill 0.254)
		(layers "F.Cu" "B.Cu")
		(net "P12V_STBY")
	)
	(via
		(at 257.111246 -384.15341)
		(size 0.508)
		(drill 0.254)
		(layers "F.Cu" "B.Cu")
		(net "P12V_STBY")
	)
	(via
		(at 259.752846 -384.15341)
		(size 0.508)
		(drill 0.254)
		(layers "F.Cu" "B.Cu")
		(net "P12V_STBY")
	)
	(via
		(at 247.032018 -382.75641)
		(size 0.508)
		(drill 0.254)
		(layers "F.Cu" "B.Cu")
		(net "P12V_STBY")
	)
	(via
		(at 229.96398 -373.528082)
		(size 0.508)
		(drill 0.254)
		(layers "F.Cu" "B.Cu")
		(net "P12V_STBY")
	)
	(via
		(at 207.796384 -371.954298)
		(size 0.508)
		(drill 0.254)
		(layers "F.Cu" "B.Cu")
		(net "P12V_STBY")
	)
	(via
		(at 228.872034 -367.654586)
		(size 0.508)
		(drill 0.254)
		(layers "F.Cu" "B.Cu")
		(net "P12V_STBY")
	)
	(via
		(at 247.692418 -384.07721)
		(size 0.508)
		(drill 0.254)
		(layers "F.Cu" "B.Cu")
		(net "P12V_STBY")
	)
	(via
		(at 221.143576 -372.048786)
		(size 0.508)
		(drill 0.254)
		(layers "F.Cu" "B.Cu")
		(net "P12V_STBY")
	)
	(via
		(at 218.095576 -372.048786)
		(size 0.508)
		(drill 0.254)
		(layers "F.Cu" "B.Cu")
		(net "P12V_STBY")
	)
	(via
		(at 229.96398 -375.052082)
		(size 0.508)
		(drill 0.254)
		(layers "F.Cu" "B.Cu")
		(net "P12V_STBY")
	)
	(via
		(at 221.023434 -370.260626)
		(size 0.508)
		(drill 0.254)
		(layers "F.Cu" "B.Cu")
		(net "P12V_STBY")
	)
	(via
		(at 218.204034 -367.654586)
		(size 0.508)
		(drill 0.254)
		(layers "F.Cu" "B.Cu")
		(net "P12V_STBY")
	)
	(via
		(at 207.034384 -373.478298)
		(size 0.508)
		(drill 0.254)
		(layers "F.Cu" "B.Cu")
		(net "P12V_STBY")
	)
	(via
		(at 218.095576 -372.810786)
		(size 0.508)
		(drill 0.254)
		(layers "F.Cu" "B.Cu")
		(net "P12V_STBY")
	)
	(via
		(at 204.945996 -368.957098)
		(size 0.508)
		(drill 0.254)
		(layers "F.Cu" "B.Cu")
		(net "P12V_STBY")
	)
	(via
		(at 239.799876 -391.757662)
		(size 0.508)
		(drill 0.254)
		(layers "F.Cu" "B.Cu")
		(net "P12V_STBY")
	)
	(via
		(at 229.96398 -372.004082)
		(size 0.508)
		(drill 0.254)
		(layers "F.Cu" "B.Cu")
		(net "P12V_STBY")
	)
	(via
		(at 209.320384 -373.478298)
		(size 0.508)
		(drill 0.254)
		(layers "F.Cu" "B.Cu")
		(net "P12V_STBY")
	)
	(via
		(at 230.72598 -375.052082)
		(size 0.508)
		(drill 0.254)
		(layers "F.Cu" "B.Cu")
		(net "P12V_STBY")
	)
	(via
		(at 209.320384 -375.815098)
		(size 0.508)
		(drill 0.254)
		(layers "F.Cu" "B.Cu")
		(net "P12V_STBY")
	)
	(via
		(at 219.619576 -372.810786)
		(size 0.508)
		(drill 0.254)
		(layers "F.Cu" "B.Cu")
		(net "P12V_STBY")
	)
	(via
		(at 222.4532 -375.5644)
		(size 0.762)
		(drill 0.381)
		(layers "F.Cu" "B.Cu")
		(net "P12V_STBY")
	)
	(via
		(at 256.450846 -382.83261)
		(size 0.508)
		(drill 0.254)
		(layers "F.Cu" "B.Cu")
		(net "P12V_STBY")
	)
	(via
		(at 258.813046 -383.49301)
		(size 0.508)
		(drill 0.254)
		(layers "F.Cu" "B.Cu")
		(net "P12V_STBY")
	)
	(via
		(at 258.729988 -384.808222)
		(size 0.508)
		(drill 0.254)
		(layers "F.Cu" "B.Cu")
		(net "P12V_STBY")
	)
	(via
		(at 220.381576 -372.048786)
		(size 0.508)
		(drill 0.254)
		(layers "F.Cu" "B.Cu")
		(net "P12V_STBY")
	)
	(via
		(at 206.272384 -375.053098)
		(size 0.508)
		(drill 0.254)
		(layers "F.Cu" "B.Cu")
		(net "P12V_STBY")
	)
	(via
		(at 207.796384 -373.478298)
		(size 0.508)
		(drill 0.254)
		(layers "F.Cu" "B.Cu")
		(net "P12V_STBY")
	)
	(via
		(at 220.381576 -372.810786)
		(size 0.508)
		(drill 0.254)
		(layers "F.Cu" "B.Cu")
		(net "P12V_STBY")
	)
	(via
		(at 230.72598 -372.004082)
		(size 0.508)
		(drill 0.254)
		(layers "F.Cu" "B.Cu")
		(net "P12V_STBY")
	)
	(via
		(at 221.143576 -375.096786)
		(size 0.508)
		(drill 0.254)
		(layers "F.Cu" "B.Cu")
		(net "P12V_STBY")
	)
	(via
		(at 218.857576 -373.572786)
		(size 0.508)
		(drill 0.254)
		(layers "F.Cu" "B.Cu")
		(net "P12V_STBY")
	)
	(via
		(at 206.250286 -374.251728)
		(size 0.508)
		(drill 0.254)
		(layers "F.Cu" "B.Cu")
		(net "P12V_STBY")
	)
	(via
		(at 239.46358 -383.013712)
		(size 0.508)
		(drill 0.254)
		(layers "F.Cu" "B.Cu")
		(net "P12V_STBY")
	)
	(via
		(at 235.214414 -393.319762)
		(size 0.508)
		(drill 0.254)
		(layers "F.Cu" "B.Cu")
		(net "P12V_STBY")
	)
	(via
		(at 217.333576 -374.334786)
		(size 0.508)
		(drill 0.254)
		(layers "F.Cu" "B.Cu")
		(net "P12V_STBY")
	)
	(via
		(at 259.390388 -384.808222)
		(size 0.508)
		(drill 0.254)
		(layers "F.Cu" "B.Cu")
		(net "P12V_STBY")
	)
	(via
		(at 256.171446 -383.49301)
		(size 0.508)
		(drill 0.254)
		(layers "F.Cu" "B.Cu")
		(net "P12V_STBY")
	)
	(via
		(at 219.626434 -367.654586)
		(size 0.508)
		(drill 0.254)
		(layers "F.Cu" "B.Cu")
		(net "P12V_STBY")
	)
	(via
		(at 251.29236 -384.732022)
		(size 0.508)
		(drill 0.254)
		(layers "F.Cu" "B.Cu")
		(net "P12V_STBY")
	)
	(via
		(at 242.83289 -391.752582)
		(size 0.508)
		(drill 0.254)
		(layers "F.Cu" "B.Cu")
		(net "P12V_STBY")
	)
	(via
		(at 228.872034 -370.260626)
		(size 0.508)
		(drill 0.254)
		(layers "F.Cu" "B.Cu")
		(net "P12V_STBY")
	)
	(via
		(at 239.74298 -383.674112)
		(size 0.508)
		(drill 0.254)
		(layers "F.Cu" "B.Cu")
		(net "P12V_STBY")
	)
	(via
		(at 256.831846 -383.49301)
		(size 0.508)
		(drill 0.254)
		(layers "F.Cu" "B.Cu")
		(net "P12V_STBY")
	)
	(via
		(at 235.989876 -391.757662)
		(size 0.508)
		(drill 0.254)
		(layers "F.Cu" "B.Cu")
		(net "P12V_STBY")
	)
	(via
		(at 210.9216 -374.3706)
		(size 0.762)
		(drill 0.381)
		(layers "F.Cu" "B.Cu")
		(net "P12V_STBY")
	)
	(via
		(at 218.204034 -368.957606)
		(size 0.508)
		(drill 0.254)
		(layers "F.Cu" "B.Cu")
		(net "P12V_STBY")
	)
	(via
		(at 246.371618 -384.07721)
		(size 0.508)
		(drill 0.254)
		(layers "F.Cu" "B.Cu")
		(net "P12V_STBY")
	)
	(via
		(at 259.092446 -384.15341)
		(size 0.508)
		(drill 0.254)
		(layers "F.Cu" "B.Cu")
		(net "P12V_STBY")
	)
	(via
		(at 241.85372 -357.400098)
		(size 0.508)
		(drill 0.254)
		(layers "F.Cu" "B.Cu")
		(net "P12V_STBY")
	)
	(via
		(at 230.72598 -372.766082)
		(size 0.508)
		(drill 0.254)
		(layers "F.Cu" "B.Cu")
		(net "P12V_STBY")
	)
	(via
		(at 260.050788 -384.808222)
		(size 0.508)
		(drill 0.254)
		(layers "F.Cu" "B.Cu")
		(net "P12V_STBY")
	)
	(via
		(at 230.294434 -367.654586)
		(size 0.508)
		(drill 0.254)
		(layers "F.Cu" "B.Cu")
		(net "P12V_STBY")
	)
	(via
		(at 217.333576 -372.810786)
		(size 0.508)
		(drill 0.254)
		(layers "F.Cu" "B.Cu")
		(net "P12V_STBY")
	)
	(via
		(at 259.752846 -382.83261)
		(size 0.508)
		(drill 0.254)
		(layers "F.Cu" "B.Cu")
		(net "P12V_STBY")
	)
	(via
		(at 228.43998 -372.004082)
		(size 0.508)
		(drill 0.254)
		(layers "F.Cu" "B.Cu")
		(net "P12V_STBY")
	)
	(via
		(at 242.83289 -392.514582)
		(size 0.508)
		(drill 0.254)
		(layers "F.Cu" "B.Cu")
		(net "P12V_STBY")
	)
	(via
		(at 237.513876 -391.757662)
		(size 0.508)
		(drill 0.254)
		(layers "F.Cu" "B.Cu")
		(net "P12V_STBY")
	)
	(via
		(at 204.945996 -367.654078)
		(size 0.508)
		(drill 0.254)
		(layers "F.Cu" "B.Cu")
		(net "P12V_STBY")
	)
	(via
		(at 239.08258 -382.353312)
		(size 0.508)
		(drill 0.254)
		(layers "F.Cu" "B.Cu")
		(net "P12V_STBY")
	)
	(via
		(at 218.857576 -372.810786)
		(size 0.508)
		(drill 0.254)
		(layers "F.Cu" "B.Cu")
		(net "P12V_STBY")
	)
	(via
		(at 208.558384 -374.240298)
		(size 0.508)
		(drill 0.254)
		(layers "F.Cu" "B.Cu")
		(net "P12V_STBY")
	)
	(via
		(at 217.333576 -372.048786)
		(size 0.508)
		(drill 0.254)
		(layers "F.Cu" "B.Cu")
		(net "P12V_STBY")
	)
	(via
		(at 209.320384 -375.053098)
		(size 0.508)
		(drill 0.254)
		(layers "F.Cu" "B.Cu")
		(net "P12V_STBY")
	)
	(via
		(at 258.069588 -384.808222)
		(size 0.508)
		(drill 0.254)
		(layers "F.Cu" "B.Cu")
		(net "P12V_STBY")
	)
	(via
		(at 232.24998 -375.052082)
		(size 0.508)
		(drill 0.254)
		(layers "F.Cu" "B.Cu")
		(net "P12V_STBY")
	)
	(via
		(at 231.48798 -374.290082)
		(size 0.508)
		(drill 0.254)
		(layers "F.Cu" "B.Cu")
		(net "P12V_STBY")
	)
	(via
		(at 260.794246 -383.49301)
		(size 0.508)
		(drill 0.254)
		(layers "F.Cu" "B.Cu")
		(net "P12V_STBY")
	)
	(via
		(at 249.97156 -384.732022)
		(size 0.508)
		(drill 0.254)
		(layers "F.Cu" "B.Cu")
		(net "P12V_STBY")
	)
	(via
		(at 218.095576 -375.096786)
		(size 0.508)
		(drill 0.254)
		(layers "F.Cu" "B.Cu")
		(net "P12V_STBY")
	)
	(via
		(at 261.073646 -384.15341)
		(size 0.508)
		(drill 0.254)
		(layers "F.Cu" "B.Cu")
		(net "P12V_STBY")
	)
	(via
		(at 229.20198 -372.766082)
		(size 0.508)
		(drill 0.254)
		(layers "F.Cu" "B.Cu")
		(net "P12V_STBY")
	)
	(via
		(at 255.790446 -384.15341)
		(size 0.508)
		(drill 0.254)
		(layers "F.Cu" "B.Cu")
		(net "P12V_STBY")
	)
	(via
		(at 239.08258 -383.674112)
		(size 0.508)
		(drill 0.254)
		(layers "F.Cu" "B.Cu")
		(net "P12V_STBY")
	)
	(via
		(at 261.073646 -382.83261)
		(size 0.508)
		(drill 0.254)
		(layers "F.Cu" "B.Cu")
		(net "P12V_STBY")
	)
	(via
		(at 235.180886 -358.91978)
		(size 0.6604)
		(drill 0.3302)
		(layers "F.Cu" "B.Cu")
		(net "P12V_STBY")
	)
	(via
		(at 228.43998 -374.290082)
		(size 0.508)
		(drill 0.254)
		(layers "F.Cu" "B.Cu")
		(net "P12V_STBY")
	)
	(via
		(at 241.360706 -358.02697)
		(size 0.508)
		(drill 0.254)
		(layers "F.Cu" "B.Cu")
		(net "P12V_STBY")
	)
	(via
		(at 257.492246 -383.49301)
		(size 0.508)
		(drill 0.254)
		(layers "F.Cu" "B.Cu")
		(net "P12V_STBY")
	)
	(via
		(at 218.204034 -370.260626)
		(size 0.508)
		(drill 0.254)
		(layers "F.Cu" "B.Cu")
		(net "P12V_STBY")
	)
	(via
		(at 235.215176 -392.52398)
		(size 0.508)
		(drill 0.254)
		(layers "F.Cu" "B.Cu")
		(net "P12V_STBY")
	)
	(via
		(at 250.715018 -383.41681)
		(size 0.508)
		(drill 0.254)
		(layers "F.Cu" "B.Cu")
		(net "P12V_STBY")
	)
	(via
		(at 228.43998 -372.766082)
		(size 0.508)
		(drill 0.254)
		(layers "F.Cu" "B.Cu")
		(net "P12V_STBY")
	)
	(via
		(at 249.394218 -383.41681)
		(size 0.508)
		(drill 0.254)
		(layers "F.Cu" "B.Cu")
		(net "P12V_STBY")
	)
	(via
		(at 207.765396 -367.654078)
		(size 0.508)
		(drill 0.254)
		(layers "F.Cu" "B.Cu")
		(net "P12V_STBY")
	)
	(via
		(at 246.00916 -384.732022)
		(size 0.508)
		(drill 0.254)
		(layers "F.Cu" "B.Cu")
		(net "P12V_STBY")
	)
	(via
		(at 229.20198 -373.528082)
		(size 0.508)
		(drill 0.254)
		(layers "F.Cu" "B.Cu")
		(net "P12V_STBY")
	)
	(via
		(at 209.320384 -374.240298)
		(size 0.508)
		(drill 0.254)
		(layers "F.Cu" "B.Cu")
		(net "P12V_STBY")
	)
	(via
		(at 240.12398 -383.013712)
		(size 0.508)
		(drill 0.254)
		(layers "F.Cu" "B.Cu")
		(net "P12V_STBY")
	)
	(via
		(at 221.143576 -374.334786)
		(size 0.508)
		(drill 0.254)
		(layers "F.Cu" "B.Cu")
		(net "P12V_STBY")
	)
	(via
		(at 207.796384 -375.815098)
		(size 0.508)
		(drill 0.254)
		(layers "F.Cu" "B.Cu")
		(net "P12V_STBY")
	)
	(via
		(at 255.790446 -382.83261)
		(size 0.508)
		(drill 0.254)
		(layers "F.Cu" "B.Cu")
		(net "P12V_STBY")
	)
	(via
		(at 220.381576 -374.334786)
		(size 0.508)
		(drill 0.254)
		(layers "F.Cu" "B.Cu")
		(net "P12V_STBY")
	)
	(via
		(at 230.72598 -374.290082)
		(size 0.508)
		(drill 0.254)
		(layers "F.Cu" "B.Cu")
		(net "P12V_STBY")
	)
	(via
		(at 229.96398 -374.290082)
		(size 0.508)
		(drill 0.254)
		(layers "F.Cu" "B.Cu")
		(net "P12V_STBY")
	)
	(via
		(at 215.2904 -374.4214)
		(size 0.762)
		(drill 0.381)
		(layers "F.Cu" "B.Cu")
		(net "P12V_STBY")
	)
	(via
		(at 229.20198 -372.004082)
		(size 0.508)
		(drill 0.254)
		(layers "F.Cu" "B.Cu")
		(net "P12V_STBY")
	)
	(via
		(at 251.654818 -382.75641)
		(size 0.508)
		(drill 0.254)
		(layers "F.Cu" "B.Cu")
		(net "P12V_STBY")
	)
	(via
		(at 208.558384 -371.954298)
		(size 0.508)
		(drill 0.254)
		(layers "F.Cu" "B.Cu")
		(net "P12V_STBY")
	)
	(via
		(at 232.24998 -373.528082)
		(size 0.508)
		(drill 0.254)
		(layers "F.Cu" "B.Cu")
		(net "P12V_STBY")
	)
	(via
		(at 247.32996 -384.732022)
		(size 0.508)
		(drill 0.254)
		(layers "F.Cu" "B.Cu")
		(net "P12V_STBY")
	)
	(via
		(at 220.381576 -373.572786)
		(size 0.508)
		(drill 0.254)
		(layers "F.Cu" "B.Cu")
		(net "P12V_STBY")
	)
	(via
		(at 208.558384 -375.815098)
		(size 0.508)
		(drill 0.254)
		(layers "F.Cu" "B.Cu")
		(net "P12V_STBY")
	)
	(via
		(at 250.63196 -384.732022)
		(size 0.508)
		(drill 0.254)
		(layers "F.Cu" "B.Cu")
		(net "P12V_STBY")
	)
	(via
		(at 250.054618 -383.41681)
		(size 0.508)
		(drill 0.254)
		(layers "F.Cu" "B.Cu")
		(net "P12V_STBY")
	)
	(via
		(at 218.857576 -375.096786)
		(size 0.508)
		(drill 0.254)
		(layers "F.Cu" "B.Cu")
		(net "P12V_STBY")
	)
	(via
		(at 207.796384 -374.240298)
		(size 0.508)
		(drill 0.254)
		(layers "F.Cu" "B.Cu")
		(net "P12V_STBY")
	)
	(via
		(at 206.250286 -373.489728)
		(size 0.508)
		(drill 0.254)
		(layers "F.Cu" "B.Cu")
		(net "P12V_STBY")
	)
	(via
		(at 260.413246 -384.15341)
		(size 0.508)
		(drill 0.254)
		(layers "F.Cu" "B.Cu")
		(net "P12V_STBY")
	)
	(via
		(at 229.20198 -374.290082)
		(size 0.508)
		(drill 0.254)
		(layers "F.Cu" "B.Cu")
		(net "P12V_STBY")
	)
	(via
		(at 206.368396 -367.654078)
		(size 0.508)
		(drill 0.254)
		(layers "F.Cu" "B.Cu")
		(net "P12V_STBY")
	)
	(via
		(at 228.872034 -368.957606)
		(size 0.508)
		(drill 0.254)
		(layers "F.Cu" "B.Cu")
		(net "P12V_STBY")
	)
	(via
		(at 250.994418 -384.07721)
		(size 0.508)
		(drill 0.254)
		(layers "F.Cu" "B.Cu")
		(net "P12V_STBY")
	)
	(via
		(at 228.43998 -373.528082)
		(size 0.508)
		(drill 0.254)
		(layers "F.Cu" "B.Cu")
		(net "P12V_STBY")
	)
	(via
		(at 218.095576 -374.334786)
		(size 0.508)
		(drill 0.254)
		(layers "F.Cu" "B.Cu")
		(net "P12V_STBY")
	)
	(via
		(at 250.334018 -382.75641)
		(size 0.508)
		(drill 0.254)
		(layers "F.Cu" "B.Cu")
		(net "P12V_STBY")
	)
	(via
		(at 230.294434 -370.260626)
		(size 0.508)
		(drill 0.254)
		(layers "F.Cu" "B.Cu")
		(net "P12V_STBY")
	)
	(via
		(at 235.214414 -396.367762)
		(size 0.508)
		(drill 0.254)
		(layers "F.Cu" "B.Cu")
		(net "P12V_STBY")
	)
	(via
		(at 228.43998 -375.052082)
		(size 0.508)
		(drill 0.254)
		(layers "F.Cu" "B.Cu")
		(net "P12V_STBY")
	)
	(via
		(at 232.24998 -372.766082)
		(size 0.508)
		(drill 0.254)
		(layers "F.Cu" "B.Cu")
		(net "P12V_STBY")
	)
	(via
		(at 221.023434 -368.957606)
		(size 0.508)
		(drill 0.254)
		(layers "F.Cu" "B.Cu")
		(net "P12V_STBY")
	)
	(via
		(at 258.432046 -382.83261)
		(size 0.508)
		(drill 0.254)
		(layers "F.Cu" "B.Cu")
		(net "P12V_STBY")
	)
	(via
		(at 256.748788 -384.808222)
		(size 0.508)
		(drill 0.254)
		(layers "F.Cu" "B.Cu")
		(net "P12V_STBY")
	)
	(via
		(at 248.733818 -383.41681)
		(size 0.508)
		(drill 0.254)
		(layers "F.Cu" "B.Cu")
		(net "P12V_STBY")
	)
	(via
		(at 207.765396 -370.260118)
		(size 0.508)
		(drill 0.254)
		(layers "F.Cu" "B.Cu")
		(net "P12V_STBY")
	)
	(via
		(at 240.561876 -392.519662)
		(size 0.508)
		(drill 0.254)
		(layers "F.Cu" "B.Cu")
		(net "P12V_STBY")
	)
	(via
		(at 219.619576 -375.096786)
		(size 0.508)
		(drill 0.254)
		(layers "F.Cu" "B.Cu")
		(net "P12V_STBY")
	)
	(via
		(at 251.375418 -383.41681)
		(size 0.508)
		(drill 0.254)
		(layers "F.Cu" "B.Cu")
		(net "P12V_STBY")
	)
	(via
		(at 248.073418 -383.41681)
		(size 0.508)
		(drill 0.254)
		(layers "F.Cu" "B.Cu")
		(net "P12V_STBY")
	)
	(via
		(at 209.320384 -372.716298)
		(size 0.508)
		(drill 0.254)
		(layers "F.Cu" "B.Cu")
		(net "P12V_STBY")
	)
	(via
		(at 260.711188 -384.808222)
		(size 0.508)
		(drill 0.254)
		(layers "F.Cu" "B.Cu")
		(net "P12V_STBY")
	)
	(via
		(at 226.8728 -375.5644)
		(size 0.762)
		(drill 0.381)
		(layers "F.Cu" "B.Cu")
		(net "P12V_STBY")
	)
	(via
		(at 252.035818 -383.41681)
		(size 0.508)
		(drill 0.254)
		(layers "F.Cu" "B.Cu")
		(net "P12V_STBY")
	)
	(via
		(at 231.691434 -368.957606)
		(size 0.508)
		(drill 0.254)
		(layers "F.Cu" "B.Cu")
		(net "P12V_STBY")
	)
	(via
		(at 231.48798 -375.052082)
		(size 0.508)
		(drill 0.254)
		(layers "F.Cu" "B.Cu")
		(net "P12V_STBY")
	)
	(via
		(at 238.80318 -383.013712)
		(size 0.508)
		(drill 0.254)
		(layers "F.Cu" "B.Cu")
		(net "P12V_STBY")
	)
	(via
		(at 238.42218 -383.674112)
		(size 0.508)
		(drill 0.254)
		(layers "F.Cu" "B.Cu")
		(net "P12V_STBY")
	)
	(via
		(at 230.72598 -373.528082)
		(size 0.508)
		(drill 0.254)
		(layers "F.Cu" "B.Cu")
		(net "P12V_STBY")
	)
	(via
		(at 221.143576 -372.810786)
		(size 0.508)
		(drill 0.254)
		(layers "F.Cu" "B.Cu")
		(net "P12V_STBY")
	)
	(via
		(at 219.626434 -370.260626)
		(size 0.508)
		(drill 0.254)
		(layers "F.Cu" "B.Cu")
		(net "P12V_STBY")
	)
	(via
		(at 232.24998 -372.004082)
		(size 0.508)
		(drill 0.254)
		(layers "F.Cu" "B.Cu")
		(net "P12V_STBY")
	)
	(segment
		(start 235.573062 -358.527604)
		(end 235.180886 -358.91978)
		(width 0.4572)
		(layer "B.Cu")
		(net "P12V_STBY")
	)
	(segment
		(start 234.583986 -366.89538)
		(end 234.583986 -359.51668)
		(width 0.4572)
		(layer "B.Cu")
		(net "P12V_STBY")
	)
	(segment
		(start 235.084366 -367.39576)
		(end 234.583986 -366.89538)
		(width 0.4572)
		(layer "B.Cu")
		(net "P12V_STBY")
	)
	(segment
		(start 241.360706 -358.02697)
		(end 241.85372 -357.533956)
		(width 0.4572)
		(layer "B.Cu")
		(net "P12V_STBY")
	)
	(segment
		(start 240.860326 -358.527604)
		(end 235.573062 -358.527604)
		(width 0.4572)
		(layer "B.Cu")
		(net "P12V_STBY")
	)
	(segment
		(start 235.084366 -369.61191)
		(end 235.084366 -367.39576)
		(width 0.4572)
		(layer "B.Cu")
		(net "P12V_STBY")
	)
	(segment
		(start 241.360706 -358.02697)
		(end 240.860326 -358.52735)
		(width 0.4572)
		(layer "B.Cu")
		(net "P12V_STBY")
	)
	(segment
		(start 233.117136 -371.136926)
		(end 233.55935 -371.136926)
		(width 0.4572)
		(layer "B.Cu")
		(net "P12V_STBY")
	)
	(segment
		(start 241.85372 -357.533956)
		(end 241.85372 -357.400098)
		(width 0.4572)
		(layer "B.Cu")
		(net "P12V_STBY")
	)
	(segment
		(start 240.860326 -358.52735)
		(end 240.860326 -358.527604)
		(width 0.4572)
		(layer "B.Cu")
		(net "P12V_STBY")
	)
	(segment
		(start 232.24998 -372.004082)
		(end 233.117136 -371.136926)
		(width 0.4572)
		(layer "B.Cu")
		(net "P12V_STBY")
	)
	(segment
		(start 234.583986 -359.51668)
		(end 235.180886 -358.91978)
		(width 0.4572)
		(layer "B.Cu")
		(net "P12V_STBY")
	)
	(segment
		(start 233.55935 -371.136926)
		(end 235.084366 -369.61191)
		(width 0.4572)
		(layer "B.Cu")
		(net "P12V_STBY")
	)
	(segment
		(start 162.64509 -193.220594)
		(end 163.044886 -192.820798)
		(width 0.13208)
		(layer "F.Cu")
		(net "SPI_BIC1_MISO_LS01_R1")
	)
	(segment
		(start 145.159222 -193.82486)
		(end 145.763488 -193.220594)
		(width 0.13208)
		(layer "F.Cu")
		(net "SPI_BIC1_MISO_LS01_R1")
	)
	(segment
		(start 163.044886 -192.820798)
		(end 165.930834 -192.820798)
		(width 0.13208)
		(layer "F.Cu")
		(net "SPI_BIC1_MISO_LS01_R1")
	)
	(segment
		(start 145.763488 -193.220594)
		(end 162.64509 -193.220594)
		(width 0.13208)
		(layer "F.Cu")
		(net "SPI_BIC1_MISO_LS01_R1")
	)
	(via
		(at 145.159222 -193.82486)
		(size 0.508)
		(drill 0.254)
		(layers "F.Cu" "B.Cu")
		(net "SPI_BIC1_MISO_LS01_R1")
	)
	(via
		(at 19.438112 -223.147382)
		(size 0.508)
		(drill 0.254)
		(layers "F.Cu" "B.Cu")
		(net "SPI_BIC1_MISO_LS01_R1")
	)
	(segment
		(start 19.438112 -224.341182)
		(end 19.438112 -223.147382)
		(width 0.13208)
		(layer "B.Cu")
		(net "SPI_BIC1_MISO_LS01_R1")
	)
	(segment
		(start 91.854274 -202.9714)
		(end 60.062872 -202.9714)
		(width 0.15494)
		(layer "In13.Cu")
		(net "SPI_BIC1_MISO_LS01_R1")
	)
	(segment
		(start 102.412292 -197.93966)
		(end 102.305358 -197.895464)
		(width 0.15494)
		(layer "In13.Cu")
		(net "SPI_BIC1_MISO_LS01_R1")
	)
	(segment
		(start 145.159222 -193.82486)
		(end 140.371576 -197.02399)
		(width 0.15494)
		(layer "In13.Cu")
		(net "SPI_BIC1_MISO_LS01_R1")
	)
	(segment
		(start 110.584742 -197.9422)
		(end 110.54969 -197.9422)
		(width 0.15494)
		(layer "In13.Cu")
		(net "SPI_BIC1_MISO_LS01_R1")
	)
	(segment
		(start 137.284206 -197.02399)
		(end 136.9822 -197.325996)
		(width 0.15494)
		(layer "In13.Cu")
		(net "SPI_BIC1_MISO_LS01_R1")
	)
	(segment
		(start 19.438112 -220.062552)
		(end 19.438112 -223.147382)
		(width 0.15494)
		(layer "In13.Cu")
		(net "SPI_BIC1_MISO_LS01_R1")
	)
	(segment
		(start 20.848066 -218.134692)
		(end 20.848066 -218.508072)
		(width 0.15494)
		(layer "In13.Cu")
		(net "SPI_BIC1_MISO_LS01_R1")
	)
	(segment
		(start 98.064828 -199.597772)
		(end 97.972626 -199.689974)
		(width 0.15494)
		(layer "In13.Cu")
		(net "SPI_BIC1_MISO_LS01_R1")
	)
	(segment
		(start 26.905712 -216.7636)
		(end 19.822414 -216.7636)
		(width 0.15494)
		(layer "In13.Cu")
		(net "SPI_BIC1_MISO_LS01_R1")
	)
	(segment
		(start 102.192328 -197.9422)
		(end 102.061772 -197.9422)
		(width 0.15494)
		(layer "In13.Cu")
		(net "SPI_BIC1_MISO_LS01_R1")
	)
	(segment
		(start 20.848066 -218.508072)
		(end 20.713446 -218.642692)
		(width 0.15494)
		(layer "In13.Cu")
		(net "SPI_BIC1_MISO_LS01_R1")
	)
	(segment
		(start 115.61318 -200.025)
		(end 110.584742 -197.9422)
		(width 0.15494)
		(layer "In13.Cu")
		(net "SPI_BIC1_MISO_LS01_R1")
	)
	(segment
		(start 140.371576 -197.02399)
		(end 137.284206 -197.02399)
		(width 0.15494)
		(layer "In13.Cu")
		(net "SPI_BIC1_MISO_LS01_R1")
	)
	(segment
		(start 110.54969 -197.9422)
		(end 110.54334 -197.93966)
		(width 0.15494)
		(layer "In13.Cu")
		(net "SPI_BIC1_MISO_LS01_R1")
	)
	(segment
		(start 20.713446 -219.927932)
		(end 19.572732 -219.927932)
		(width 0.15494)
		(layer "In13.Cu")
		(net "SPI_BIC1_MISO_LS01_R1")
	)
	(segment
		(start 19.438112 -218.777312)
		(end 19.438112 -219.150692)
		(width 0.15494)
		(layer "In13.Cu")
		(net "SPI_BIC1_MISO_LS01_R1")
	)
	(segment
		(start 19.822414 -216.7636)
		(end 19.438112 -217.147902)
		(width 0.15494)
		(layer "In13.Cu")
		(net "SPI_BIC1_MISO_LS01_R1")
	)
	(segment
		(start 97.972626 -199.689974)
		(end 97.93605 -199.705214)
		(width 0.15494)
		(layer "In13.Cu")
		(net "SPI_BIC1_MISO_LS01_R1")
	)
	(segment
		(start 128.113536 -197.325996)
		(end 121.597166 -200.025)
		(width 0.15494)
		(layer "In13.Cu")
		(net "SPI_BIC1_MISO_LS01_R1")
	)
	(segment
		(start 19.438112 -217.865452)
		(end 19.572732 -218.000072)
		(width 0.15494)
		(layer "In13.Cu")
		(net "SPI_BIC1_MISO_LS01_R1")
	)
	(segment
		(start 19.572732 -218.642692)
		(end 19.438112 -218.777312)
		(width 0.15494)
		(layer "In13.Cu")
		(net "SPI_BIC1_MISO_LS01_R1")
	)
	(segment
		(start 20.713446 -218.642692)
		(end 19.572732 -218.642692)
		(width 0.15494)
		(layer "In13.Cu")
		(net "SPI_BIC1_MISO_LS01_R1")
	)
	(segment
		(start 19.438112 -217.147902)
		(end 19.438112 -217.865452)
		(width 0.15494)
		(layer "In13.Cu")
		(net "SPI_BIC1_MISO_LS01_R1")
	)
	(segment
		(start 40.069262 -211.31149)
		(end 26.905712 -216.7636)
		(width 0.15494)
		(layer "In13.Cu")
		(net "SPI_BIC1_MISO_LS01_R1")
	)
	(segment
		(start 60.062872 -202.9714)
		(end 40.297608 -211.158328)
		(width 0.15494)
		(layer "In13.Cu")
		(net "SPI_BIC1_MISO_LS01_R1")
	)
	(segment
		(start 20.713446 -218.000072)
		(end 20.848066 -218.134692)
		(width 0.15494)
		(layer "In13.Cu")
		(net "SPI_BIC1_MISO_LS01_R1")
	)
	(segment
		(start 96.66097 -200.980294)
		(end 91.854274 -202.9714)
		(width 0.15494)
		(layer "In13.Cu")
		(net "SPI_BIC1_MISO_LS01_R1")
	)
	(segment
		(start 19.438112 -219.150692)
		(end 19.572732 -219.285312)
		(width 0.15494)
		(layer "In13.Cu")
		(net "SPI_BIC1_MISO_LS01_R1")
	)
	(segment
		(start 19.572732 -218.000072)
		(end 20.713446 -218.000072)
		(width 0.15494)
		(layer "In13.Cu")
		(net "SPI_BIC1_MISO_LS01_R1")
	)
	(segment
		(start 136.9822 -197.325996)
		(end 128.113536 -197.325996)
		(width 0.15494)
		(layer "In13.Cu")
		(net "SPI_BIC1_MISO_LS01_R1")
	)
	(segment
		(start 102.061772 -197.9422)
		(end 98.064828 -199.597772)
		(width 0.15494)
		(layer "In13.Cu")
		(net "SPI_BIC1_MISO_LS01_R1")
	)
	(segment
		(start 20.713446 -219.285312)
		(end 20.848066 -219.419932)
		(width 0.15494)
		(layer "In13.Cu")
		(net "SPI_BIC1_MISO_LS01_R1")
	)
	(segment
		(start 19.572732 -219.927932)
		(end 19.438112 -220.062552)
		(width 0.15494)
		(layer "In13.Cu")
		(net "SPI_BIC1_MISO_LS01_R1")
	)
	(segment
		(start 20.848066 -219.793312)
		(end 20.713446 -219.927932)
		(width 0.15494)
		(layer "In13.Cu")
		(net "SPI_BIC1_MISO_LS01_R1")
	)
	(segment
		(start 97.93605 -199.705214)
		(end 96.66097 -200.980294)
		(width 0.15494)
		(layer "In13.Cu")
		(net "SPI_BIC1_MISO_LS01_R1")
	)
	(segment
		(start 110.54334 -197.93966)
		(end 102.412292 -197.93966)
		(width 0.15494)
		(layer "In13.Cu")
		(net "SPI_BIC1_MISO_LS01_R1")
	)
	(segment
		(start 19.572732 -219.285312)
		(end 20.713446 -219.285312)
		(width 0.15494)
		(layer "In13.Cu")
		(net "SPI_BIC1_MISO_LS01_R1")
	)
	(segment
		(start 20.848066 -219.419932)
		(end 20.848066 -219.793312)
		(width 0.15494)
		(layer "In13.Cu")
		(net "SPI_BIC1_MISO_LS01_R1")
	)
	(segment
		(start 121.597166 -200.025)
		(end 115.61318 -200.025)
		(width 0.15494)
		(layer "In13.Cu")
		(net "SPI_BIC1_MISO_LS01_R1")
	)
	(segment
		(start 40.297608 -211.158328)
		(end 40.069262 -211.31149)
		(width 0.15494)
		(layer "In13.Cu")
		(net "SPI_BIC1_MISO_LS01_R1")
	)
	(segment
		(start 102.305358 -197.895464)
		(end 102.192328 -197.9422)
		(width 0.15494)
		(layer "In13.Cu")
		(net "SPI_BIC1_MISO_LS01_R1")
	)
	(segment
		(start 165.930834 -196.884798)
		(end 146.863816 -196.884798)
		(width 0.13208)
		(layer "F.Cu")
		(net "SPI_BIC1_CLK_LS01_R1")
	)
	(via
		(at 20.406106 -228.077522)
		(size 0.508)
		(drill 0.254)
		(layers "F.Cu" "B.Cu")
		(net "SPI_BIC1_CLK_LS01_R1")
	)
	(via
		(at 146.863816 -196.884798)
		(size 0.508)
		(drill 0.254)
		(layers "F.Cu" "B.Cu")
		(net "SPI_BIC1_CLK_LS01_R1")
	)
	(segment
		(start 20.708112 -228.892608)
		(end 20.406106 -228.590602)
		(width 0.13208)
		(layer "B.Cu")
		(net "SPI_BIC1_CLK_LS01_R1")
	)
	(segment
		(start 20.406106 -228.590602)
		(end 20.406106 -228.077522)
		(width 0.13208)
		(layer "B.Cu")
		(net "SPI_BIC1_CLK_LS01_R1")
	)
	(segment
		(start 20.708112 -229.827582)
		(end 20.708112 -228.892608)
		(width 0.13208)
		(layer "B.Cu")
		(net "SPI_BIC1_CLK_LS01_R1")
	)
	(segment
		(start 129.541524 -202.322176)
		(end 130.480816 -201.933048)
		(width 0.15494)
		(layer "In13.Cu")
		(net "SPI_BIC1_CLK_LS01_R1")
	)
	(segment
		(start 131.21386 -201.200004)
		(end 133.090412 -200.422764)
		(width 0.15494)
		(layer "In13.Cu")
		(net "SPI_BIC1_CLK_LS01_R1")
	)
	(segment
		(start 28.461716 -217.41765)
		(end 60.087764 -204.3176)
		(width 0.15494)
		(layer "In13.Cu")
		(net "SPI_BIC1_CLK_LS01_R1")
	)
	(segment
		(start 99.297744 -203.0984)
		(end 99.583494 -203.38415)
		(width 0.15494)
		(layer "In13.Cu")
		(net "SPI_BIC1_CLK_LS01_R1")
	)
	(segment
		(start 115.615212 -201.572622)
		(end 124.223526 -201.572622)
		(width 0.15494)
		(layer "In13.Cu")
		(net "SPI_BIC1_CLK_LS01_R1")
	)
	(segment
		(start 99.583494 -203.38415)
		(end 102.39375 -203.38415)
		(width 0.15494)
		(layer "In13.Cu")
		(net "SPI_BIC1_CLK_LS01_R1")
	)
	(segment
		(start 124.223526 -201.572622)
		(end 126.033276 -202.322176)
		(width 0.15494)
		(layer "In13.Cu")
		(net "SPI_BIC1_CLK_LS01_R1")
	)
	(segment
		(start 113.28908 -200.6092)
		(end 115.615212 -201.572622)
		(width 0.15494)
		(layer "In13.Cu")
		(net "SPI_BIC1_CLK_LS01_R1")
	)
	(segment
		(start 97.238566 -203.0984)
		(end 99.297744 -203.0984)
		(width 0.15494)
		(layer "In13.Cu")
		(net "SPI_BIC1_CLK_LS01_R1")
	)
	(segment
		(start 20.406106 -228.077522)
		(end 23.23592 -225.247708)
		(width 0.15494)
		(layer "In13.Cu")
		(net "SPI_BIC1_CLK_LS01_R1")
	)
	(segment
		(start 60.087764 -204.3176)
		(end 94.29496 -204.3176)
		(width 0.15494)
		(layer "In13.Cu")
		(net "SPI_BIC1_CLK_LS01_R1")
	)
	(segment
		(start 103.499412 -202.926188)
		(end 105.8164 -200.6092)
		(width 0.15494)
		(layer "In13.Cu")
		(net "SPI_BIC1_CLK_LS01_R1")
	)
	(segment
		(start 102.39375 -203.38415)
		(end 103.499412 -202.926188)
		(width 0.15494)
		(layer "In13.Cu")
		(net "SPI_BIC1_CLK_LS01_R1")
	)
	(segment
		(start 142.5067 -200.422764)
		(end 142.846298 -200.282048)
		(width 0.15494)
		(layer "In13.Cu")
		(net "SPI_BIC1_CLK_LS01_R1")
	)
	(segment
		(start 25.157938 -220.607636)
		(end 26.94305 -218.43238)
		(width 0.15494)
		(layer "In13.Cu")
		(net "SPI_BIC1_CLK_LS01_R1")
	)
	(segment
		(start 126.033276 -202.322176)
		(end 129.541524 -202.322176)
		(width 0.15494)
		(layer "In13.Cu")
		(net "SPI_BIC1_CLK_LS01_R1")
	)
	(segment
		(start 26.94305 -218.43238)
		(end 28.461716 -217.41765)
		(width 0.15494)
		(layer "In13.Cu")
		(net "SPI_BIC1_CLK_LS01_R1")
	)
	(segment
		(start 142.846298 -200.282048)
		(end 145.015458 -198.112888)
		(width 0.15494)
		(layer "In13.Cu")
		(net "SPI_BIC1_CLK_LS01_R1")
	)
	(segment
		(start 130.480816 -201.933048)
		(end 131.21386 -201.200004)
		(width 0.15494)
		(layer "In13.Cu")
		(net "SPI_BIC1_CLK_LS01_R1")
	)
	(segment
		(start 145.015458 -198.112888)
		(end 146.489166 -196.884798)
		(width 0.15494)
		(layer "In13.Cu")
		(net "SPI_BIC1_CLK_LS01_R1")
	)
	(segment
		(start 105.8164 -200.6092)
		(end 113.28908 -200.6092)
		(width 0.15494)
		(layer "In13.Cu")
		(net "SPI_BIC1_CLK_LS01_R1")
	)
	(segment
		(start 23.23592 -225.247708)
		(end 25.157938 -220.607636)
		(width 0.15494)
		(layer "In13.Cu")
		(net "SPI_BIC1_CLK_LS01_R1")
	)
	(segment
		(start 133.090412 -200.422764)
		(end 142.5067 -200.422764)
		(width 0.15494)
		(layer "In13.Cu")
		(net "SPI_BIC1_CLK_LS01_R1")
	)
	(segment
		(start 94.29496 -204.3176)
		(end 97.238566 -203.0984)
		(width 0.15494)
		(layer "In13.Cu")
		(net "SPI_BIC1_CLK_LS01_R1")
	)
	(segment
		(start 146.489166 -196.884798)
		(end 146.863816 -196.884798)
		(width 0.15494)
		(layer "In13.Cu")
		(net "SPI_BIC1_CLK_LS01_R1")
	)
	(via
		(at 24.48433 -229.97287)
		(size 0.6604)
		(drill 0.3302)
		(layers "F.Cu" "B.Cu")
		(net "SPI_PEX0_CS_MUX_N")
	)
	(segment
		(start 19.438112 -229.827582)
		(end 19.438112 -230.8225)
		(width 0.13208)
		(layer "B.Cu")
		(net "SPI_PEX0_CS_MUX_N")
	)
	(segment
		(start 23.5077 -230.9495)
		(end 24.48433 -229.97287)
		(width 0.13208)
		(layer "B.Cu")
		(net "SPI_PEX0_CS_MUX_N")
	)
	(segment
		(start 24.48433 -229.97287)
		(end 24.219408 -229.707948)
		(width 0.13208)
		(layer "B.Cu")
		(net "SPI_PEX0_CS_MUX_N")
	)
	(segment
		(start 19.438112 -230.8225)
		(end 19.565112 -230.9495)
		(width 0.13208)
		(layer "B.Cu")
		(net "SPI_PEX0_CS_MUX_N")
	)
	(segment
		(start 24.219408 -229.707948)
		(end 24.219408 -228.74605)
		(width 0.13208)
		(layer "B.Cu")
		(net "SPI_PEX0_CS_MUX_N")
	)
	(segment
		(start 19.565112 -230.9495)
		(end 23.5077 -230.9495)
		(width 0.13208)
		(layer "B.Cu")
		(net "SPI_PEX0_CS_MUX_N")
	)
	(segment
		(start 208.895696 -177.074322)
		(end 215.214454 -177.074322)
		(width 0.13208)
		(layer "F.Cu")
		(net "SEL_FLASH_PEX0_BUF_R")
	)
	(segment
		(start 188.050678 -186.995816)
		(end 188.059822 -187.00496)
		(width 0.13208)
		(layer "F.Cu")
		(net "SEL_FLASH_PEX0_BUF_R")
	)
	(segment
		(start 217.072464 -180.248306)
		(end 216.480136 -180.248306)
		(width 0.13208)
		(layer "F.Cu")
		(net "SEL_FLASH_PEX0_BUF_R")
	)
	(segment
		(start 205.35011 -180.619908)
		(end 208.895696 -177.074322)
		(width 0.13208)
		(layer "F.Cu")
		(net "SEL_FLASH_PEX0_BUF_R")
	)
	(segment
		(start 215.825324 -180.248306)
		(end 216.480136 -180.248306)
		(width 0.13208)
		(layer "F.Cu")
		(net "SEL_FLASH_PEX0_BUF_R")
	)
	(segment
		(start 189.935866 -187.00496)
		(end 205.35011 -180.619908)
		(width 0.13208)
		(layer "F.Cu")
		(net "SEL_FLASH_PEX0_BUF_R")
	)
	(segment
		(start 215.487504 -180.586126)
		(end 215.825324 -180.248306)
		(width 0.13208)
		(layer "F.Cu")
		(net "SEL_FLASH_PEX0_BUF_R")
	)
	(segment
		(start 214.8459 -180.586126)
		(end 215.487504 -180.586126)
		(width 0.13208)
		(layer "F.Cu")
		(net "SEL_FLASH_PEX0_BUF_R")
	)
	(segment
		(start 188.059822 -187.00496)
		(end 189.935866 -187.00496)
		(width 0.13208)
		(layer "F.Cu")
		(net "SEL_FLASH_PEX0_BUF_R")
	)
	(segment
		(start 215.214454 -177.074322)
		(end 217.199718 -179.059586)
		(width 0.13208)
		(layer "F.Cu")
		(net "SEL_FLASH_PEX0_BUF_R")
	)
	(segment
		(start 216.480136 -181.213506)
		(end 216.480136 -180.248306)
		(width 0.13208)
		(layer "F.Cu")
		(net "SEL_FLASH_PEX0_BUF_R")
	)
	(segment
		(start 217.199718 -180.121052)
		(end 217.072464 -180.248306)
		(width 0.13208)
		(layer "F.Cu")
		(net "SEL_FLASH_PEX0_BUF_R")
	)
	(segment
		(start 217.199718 -179.059586)
		(end 217.199718 -180.121052)
		(width 0.13208)
		(layer "F.Cu")
		(net "SEL_FLASH_PEX0_BUF_R")
	)
	(via
		(at 17.2974 -231.170988)
		(size 0.508)
		(drill 0.254)
		(layers "F.Cu" "B.Cu")
		(net "SEL_FLASH_PEX0_BUF_R")
	)
	(via
		(at 125.55601 -239.067848)
		(size 0.508)
		(drill 0.254)
		(layers "F.Cu" "B.Cu")
		(net "SEL_FLASH_PEX0_BUF_R")
	)
	(via
		(at 214.8459 -180.586126)
		(size 0.508)
		(drill 0.254)
		(layers "F.Cu" "B.Cu")
		(net "SEL_FLASH_PEX0_BUF_R")
	)
	(via
		(at 124.351288 -208.99247)
		(size 0.508)
		(drill 0.254)
		(layers "F.Cu" "B.Cu")
		(net "SEL_FLASH_PEX0_BUF_R")
	)
	(via
		(at 216.733628 -200.631298)
		(size 0.508)
		(drill 0.254)
		(layers "F.Cu" "B.Cu")
		(net "SEL_FLASH_PEX0_BUF_R")
	)
	(segment
		(start 17.533112 -230.935276)
		(end 17.2974 -231.170988)
		(width 0.13208)
		(layer "B.Cu")
		(net "SEL_FLASH_PEX0_BUF_R")
	)
	(segment
		(start 17.533112 -229.827582)
		(end 17.533112 -230.935276)
		(width 0.13208)
		(layer "B.Cu")
		(net "SEL_FLASH_PEX0_BUF_R")
	)
	(segment
		(start 210.100926 -187.29325)
		(end 210.100926 -187.992004)
		(width 0.15494)
		(layer "In5.Cu")
		(net "SEL_FLASH_PEX0_BUF_R")
	)
	(segment
		(start 210.100926 -187.992004)
		(end 210.465162 -188.35624)
		(width 0.15494)
		(layer "In5.Cu")
		(net "SEL_FLASH_PEX0_BUF_R")
	)
	(segment
		(start 212.4202 -190.145924)
		(end 213.944962 -190.145924)
		(width 0.15494)
		(layer "In5.Cu")
		(net "SEL_FLASH_PEX0_BUF_R")
	)
	(segment
		(start 212.2932 -190.018924)
		(end 212.4202 -190.145924)
		(width 0.15494)
		(layer "In5.Cu")
		(net "SEL_FLASH_PEX0_BUF_R")
	)
	(segment
		(start 211.181442 -186.212734)
		(end 210.100926 -187.29325)
		(width 0.15494)
		(layer "In5.Cu")
		(net "SEL_FLASH_PEX0_BUF_R")
	)
	(segment
		(start 210.80222 -188.49594)
		(end 211.15147 -188.49594)
		(width 0.15494)
		(layer "In5.Cu")
		(net "SEL_FLASH_PEX0_BUF_R")
	)
	(segment
		(start 213.944962 -190.145924)
		(end 216.713308 -192.91427)
		(width 0.15494)
		(layer "In5.Cu")
		(net "SEL_FLASH_PEX0_BUF_R")
	)
	(segment
		(start 214.345266 -182.628286)
		(end 211.884006 -185.089546)
		(width 0.15494)
		(layer "In5.Cu")
		(net "SEL_FLASH_PEX0_BUF_R")
	)
	(segment
		(start 216.713308 -199.8853)
		(end 216.733628 -199.90562)
		(width 0.15494)
		(layer "In5.Cu")
		(net "SEL_FLASH_PEX0_BUF_R")
	)
	(segment
		(start 214.8459 -180.586126)
		(end 214.345266 -181.08676)
		(width 0.15494)
		(layer "In5.Cu")
		(net "SEL_FLASH_PEX0_BUF_R")
	)
	(segment
		(start 211.884006 -185.089546)
		(end 211.884006 -185.929524)
		(width 0.15494)
		(layer "In5.Cu")
		(net "SEL_FLASH_PEX0_BUF_R")
	)
	(segment
		(start 125.55601 -217.73261)
		(end 123.6726 -215.8492)
		(width 0.15494)
		(layer "In5.Cu")
		(net "SEL_FLASH_PEX0_BUF_R")
	)
	(segment
		(start 123.6726 -215.8492)
		(end 123.6726 -209.671158)
		(width 0.15494)
		(layer "In5.Cu")
		(net "SEL_FLASH_PEX0_BUF_R")
	)
	(segment
		(start 211.15147 -188.49594)
		(end 212.2932 -189.63767)
		(width 0.15494)
		(layer "In5.Cu")
		(net "SEL_FLASH_PEX0_BUF_R")
	)
	(segment
		(start 212.2932 -189.63767)
		(end 212.2932 -190.018924)
		(width 0.15494)
		(layer "In5.Cu")
		(net "SEL_FLASH_PEX0_BUF_R")
	)
	(segment
		(start 216.713308 -192.91427)
		(end 216.713308 -199.8853)
		(width 0.15494)
		(layer "In5.Cu")
		(net "SEL_FLASH_PEX0_BUF_R")
	)
	(segment
		(start 125.55601 -239.067848)
		(end 125.55601 -217.73261)
		(width 0.15494)
		(layer "In5.Cu")
		(net "SEL_FLASH_PEX0_BUF_R")
	)
	(segment
		(start 123.6726 -209.671158)
		(end 124.351288 -208.99247)
		(width 0.15494)
		(layer "In5.Cu")
		(net "SEL_FLASH_PEX0_BUF_R")
	)
	(segment
		(start 211.600796 -186.212734)
		(end 211.181442 -186.212734)
		(width 0.15494)
		(layer "In5.Cu")
		(net "SEL_FLASH_PEX0_BUF_R")
	)
	(segment
		(start 214.345266 -181.08676)
		(end 214.345266 -182.628286)
		(width 0.15494)
		(layer "In5.Cu")
		(net "SEL_FLASH_PEX0_BUF_R")
	)
	(segment
		(start 211.884006 -185.929524)
		(end 211.600796 -186.212734)
		(width 0.15494)
		(layer "In5.Cu")
		(net "SEL_FLASH_PEX0_BUF_R")
	)
	(segment
		(start 216.733628 -199.90562)
		(end 216.733628 -200.631298)
		(width 0.15494)
		(layer "In5.Cu")
		(net "SEL_FLASH_PEX0_BUF_R")
	)
	(segment
		(start 210.465162 -188.35624)
		(end 210.80222 -188.49594)
		(width 0.15494)
		(layer "In5.Cu")
		(net "SEL_FLASH_PEX0_BUF_R")
	)
	(segment
		(start 143.570706 -211.896706)
		(end 143.9418 -212.2678)
		(width 0.15494)
		(layer "In15.Cu")
		(net "SEL_FLASH_PEX0_BUF_R")
	)
	(segment
		(start 16.669004 -222.852996)
		(end 18.202148 -222.852996)
		(width 0.15494)
		(layer "In15.Cu")
		(net "SEL_FLASH_PEX0_BUF_R")
	)
	(segment
		(start 69.784722 -213.648036)
		(end 74.579226 -208.853532)
		(width 0.15494)
		(layer "In15.Cu")
		(net "SEL_FLASH_PEX0_BUF_R")
	)
	(segment
		(start 74.579226 -208.853532)
		(end 109.373924 -208.853532)
		(width 0.15494)
		(layer "In15.Cu")
		(net "SEL_FLASH_PEX0_BUF_R")
	)
	(segment
		(start 182.298594 -212.2678)
		(end 183.811926 -213.781132)
		(width 0.15494)
		(layer "In15.Cu")
		(net "SEL_FLASH_PEX0_BUF_R")
	)
	(segment
		(start 109.373924 -208.853532)
		(end 113.38052 -212.860128)
		(width 0.15494)
		(layer "In15.Cu")
		(net "SEL_FLASH_PEX0_BUF_R")
	)
	(segment
		(start 125.315218 -208.02854)
		(end 133.312154 -208.02854)
		(width 0.15494)
		(layer "In15.Cu")
		(net "SEL_FLASH_PEX0_BUF_R")
	)
	(segment
		(start 124.351288 -208.99247)
		(end 125.315218 -208.02854)
		(width 0.15494)
		(layer "In15.Cu")
		(net "SEL_FLASH_PEX0_BUF_R")
	)
	(segment
		(start 143.9418 -212.2678)
		(end 182.298594 -212.2678)
		(width 0.15494)
		(layer "In15.Cu")
		(net "SEL_FLASH_PEX0_BUF_R")
	)
	(segment
		(start 194.17538 -213.781132)
		(end 203.972414 -203.984098)
		(width 0.15494)
		(layer "In15.Cu")
		(net "SEL_FLASH_PEX0_BUF_R")
	)
	(segment
		(start 134.469632 -209.186018)
		(end 134.469632 -210.16468)
		(width 0.15494)
		(layer "In15.Cu")
		(net "SEL_FLASH_PEX0_BUF_R")
	)
	(segment
		(start 16.3576 -223.1644)
		(end 16.669004 -222.852996)
		(width 0.15494)
		(layer "In15.Cu")
		(net "SEL_FLASH_PEX0_BUF_R")
	)
	(segment
		(start 134.469632 -210.16468)
		(end 134.752842 -210.44789)
		(width 0.15494)
		(layer "In15.Cu")
		(net "SEL_FLASH_PEX0_BUF_R")
	)
	(segment
		(start 134.752842 -210.44789)
		(end 134.766812 -210.44789)
		(width 0.15494)
		(layer "In15.Cu")
		(net "SEL_FLASH_PEX0_BUF_R")
	)
	(segment
		(start 119.675148 -239.067848)
		(end 125.55601 -239.067848)
		(width 0.15494)
		(layer "In15.Cu")
		(net "SEL_FLASH_PEX0_BUF_R")
	)
	(segment
		(start 18.202148 -222.852996)
		(end 27.407108 -213.648036)
		(width 0.15494)
		(layer "In15.Cu")
		(net "SEL_FLASH_PEX0_BUF_R")
	)
	(segment
		(start 210.575144 -203.984098)
		(end 213.927944 -200.631298)
		(width 0.15494)
		(layer "In15.Cu")
		(net "SEL_FLASH_PEX0_BUF_R")
	)
	(segment
		(start 213.927944 -200.631298)
		(end 216.733628 -200.631298)
		(width 0.15494)
		(layer "In15.Cu")
		(net "SEL_FLASH_PEX0_BUF_R")
	)
	(segment
		(start 113.38052 -212.860128)
		(end 113.38052 -232.77322)
		(width 0.15494)
		(layer "In15.Cu")
		(net "SEL_FLASH_PEX0_BUF_R")
	)
	(segment
		(start 17.184116 -225.1202)
		(end 16.3576 -224.293684)
		(width 0.15494)
		(layer "In15.Cu")
		(net "SEL_FLASH_PEX0_BUF_R")
	)
	(segment
		(start 183.811926 -213.781132)
		(end 194.17538 -213.781132)
		(width 0.15494)
		(layer "In15.Cu")
		(net "SEL_FLASH_PEX0_BUF_R")
	)
	(segment
		(start 113.38052 -232.77322)
		(end 119.675148 -239.067848)
		(width 0.15494)
		(layer "In15.Cu")
		(net "SEL_FLASH_PEX0_BUF_R")
	)
	(segment
		(start 16.3576 -224.293684)
		(end 16.3576 -223.1644)
		(width 0.15494)
		(layer "In15.Cu")
		(net "SEL_FLASH_PEX0_BUF_R")
	)
	(segment
		(start 17.2974 -230.709724)
		(end 17.184116 -230.59644)
		(width 0.15494)
		(layer "In15.Cu")
		(net "SEL_FLASH_PEX0_BUF_R")
	)
	(segment
		(start 136.216644 -211.896706)
		(end 143.570706 -211.896706)
		(width 0.15494)
		(layer "In15.Cu")
		(net "SEL_FLASH_PEX0_BUF_R")
	)
	(segment
		(start 27.407108 -213.648036)
		(end 69.784722 -213.648036)
		(width 0.15494)
		(layer "In15.Cu")
		(net "SEL_FLASH_PEX0_BUF_R")
	)
	(segment
		(start 17.184116 -230.59644)
		(end 17.184116 -225.1202)
		(width 0.15494)
		(layer "In15.Cu")
		(net "SEL_FLASH_PEX0_BUF_R")
	)
	(segment
		(start 17.2974 -231.170988)
		(end 17.2974 -230.709724)
		(width 0.15494)
		(layer "In15.Cu")
		(net "SEL_FLASH_PEX0_BUF_R")
	)
	(segment
		(start 134.766812 -210.44789)
		(end 136.216644 -211.896706)
		(width 0.15494)
		(layer "In15.Cu")
		(net "SEL_FLASH_PEX0_BUF_R")
	)
	(segment
		(start 133.312154 -208.02854)
		(end 134.469632 -209.186018)
		(width 0.15494)
		(layer "In15.Cu")
		(net "SEL_FLASH_PEX0_BUF_R")
	)
	(segment
		(start 203.972414 -203.984098)
		(end 210.575144 -203.984098)
		(width 0.15494)
		(layer "In15.Cu")
		(net "SEL_FLASH_PEX0_BUF_R")
	)
	(segment
		(start 149.144482 -199.392032)
		(end 149.619716 -198.916798)
		(width 0.13208)
		(layer "F.Cu")
		(net "SPI_BIC1_CS0_LS01_R1_N")
	)
	(segment
		(start 149.619716 -198.916798)
		(end 165.930834 -198.916798)
		(width 0.13208)
		(layer "F.Cu")
		(net "SPI_BIC1_CS0_LS01_R1_N")
	)
	(via
		(at 18.29689 -228.179884)
		(size 0.508)
		(drill 0.254)
		(layers "F.Cu" "B.Cu")
		(net "SPI_BIC1_CS0_LS01_R1_N")
	)
	(via
		(at 149.144482 -199.392032)
		(size 0.508)
		(drill 0.254)
		(layers "F.Cu" "B.Cu")
		(net "SPI_BIC1_CS0_LS01_R1_N")
	)
	(segment
		(start 18.29689 -228.179884)
		(end 18.29689 -228.704648)
		(width 0.13208)
		(layer "B.Cu")
		(net "SPI_BIC1_CS0_LS01_R1_N")
	)
	(segment
		(start 18.29689 -228.704648)
		(end 18.803112 -229.21087)
		(width 0.13208)
		(layer "B.Cu")
		(net "SPI_BIC1_CS0_LS01_R1_N")
	)
	(segment
		(start 18.803112 -229.21087)
		(end 18.803112 -229.827582)
		(width 0.13208)
		(layer "B.Cu")
		(net "SPI_BIC1_CS0_LS01_R1_N")
	)
	(segment
		(start 113.14811 -201.3204)
		(end 115.600988 -202.3364)
		(width 0.15494)
		(layer "In13.Cu")
		(net "SPI_BIC1_CS0_LS01_R1_N")
	)
	(segment
		(start 18.31086 -228.422708)
		(end 18.306542 -228.440742)
		(width 0.15494)
		(layer "In13.Cu")
		(net "SPI_BIC1_CS0_LS01_R1_N")
	)
	(segment
		(start 106.0958 -201.3204)
		(end 113.14811 -201.3204)
		(width 0.15494)
		(layer "In13.Cu")
		(net "SPI_BIC1_CS0_LS01_R1_N")
	)
	(segment
		(start 103.611172 -203.805028)
		(end 106.0958 -201.3204)
		(width 0.15494)
		(layer "In13.Cu")
		(net "SPI_BIC1_CS0_LS01_R1_N")
	)
	(segment
		(start 93.156786 -204.996034)
		(end 93.166438 -204.986382)
		(width 0.15494)
		(layer "In13.Cu")
		(net "SPI_BIC1_CS0_LS01_R1_N")
	)
	(segment
		(start 18.769838 -228.98989)
		(end 20.844764 -228.98989)
		(width 0.15494)
		(layer "In13.Cu")
		(net "SPI_BIC1_CS0_LS01_R1_N")
	)
	(segment
		(start 60.18276 -204.996034)
		(end 93.156786 -204.996034)
		(width 0.15494)
		(layer "In13.Cu")
		(net "SPI_BIC1_CS0_LS01_R1_N")
	)
	(segment
		(start 123.717558 -203.454)
		(end 141.055598 -203.454)
		(width 0.15494)
		(layer "In13.Cu")
		(net "SPI_BIC1_CS0_LS01_R1_N")
	)
	(segment
		(start 18.307812 -228.543358)
		(end 18.315432 -228.552248)
		(width 0.15494)
		(layer "In13.Cu")
		(net "SPI_BIC1_CS0_LS01_R1_N")
	)
	(segment
		(start 18.304256 -228.358192)
		(end 18.31086 -228.422708)
		(width 0.15494)
		(layer "In13.Cu")
		(net "SPI_BIC1_CS0_LS01_R1_N")
	)
	(segment
		(start 24.78151 -225.053144)
		(end 26.079196 -224.185988)
		(width 0.15494)
		(layer "In13.Cu")
		(net "SPI_BIC1_CS0_LS01_R1_N")
	)
	(segment
		(start 30.62478 -217.239596)
		(end 60.18276 -204.996034)
		(width 0.15494)
		(layer "In13.Cu")
		(net "SPI_BIC1_CS0_LS01_R1_N")
	)
	(segment
		(start 115.600988 -202.3364)
		(end 122.599958 -202.3364)
		(width 0.15494)
		(layer "In13.Cu")
		(net "SPI_BIC1_CS0_LS01_R1_N")
	)
	(segment
		(start 26.079196 -224.185988)
		(end 27.234896 -223.030288)
		(width 0.15494)
		(layer "In13.Cu")
		(net "SPI_BIC1_CS0_LS01_R1_N")
	)
	(segment
		(start 18.306542 -228.531166)
		(end 18.307812 -228.543358)
		(width 0.15494)
		(layer "In13.Cu")
		(net "SPI_BIC1_CS0_LS01_R1_N")
	)
	(segment
		(start 20.844764 -228.98989)
		(end 24.78151 -225.053144)
		(width 0.15494)
		(layer "In13.Cu")
		(net "SPI_BIC1_CS0_LS01_R1_N")
	)
	(segment
		(start 18.73504 -228.971856)
		(end 18.744692 -228.979984)
		(width 0.15494)
		(layer "In13.Cu")
		(net "SPI_BIC1_CS0_LS01_R1_N")
	)
	(segment
		(start 18.306542 -228.440742)
		(end 18.306542 -228.531166)
		(width 0.15494)
		(layer "In13.Cu")
		(net "SPI_BIC1_CS0_LS01_R1_N")
	)
	(segment
		(start 148.93925 -199.1868)
		(end 149.144482 -199.392032)
		(width 0.15494)
		(layer "In13.Cu")
		(net "SPI_BIC1_CS0_LS01_R1_N")
	)
	(segment
		(start 93.166438 -204.986382)
		(end 100.759006 -204.986382)
		(width 0.15494)
		(layer "In13.Cu")
		(net "SPI_BIC1_CS0_LS01_R1_N")
	)
	(segment
		(start 18.744692 -228.979984)
		(end 18.751804 -228.983794)
		(width 0.15494)
		(layer "In13.Cu")
		(net "SPI_BIC1_CS0_LS01_R1_N")
	)
	(segment
		(start 144.030954 -202.221592)
		(end 147.065746 -199.1868)
		(width 0.15494)
		(layer "In13.Cu")
		(net "SPI_BIC1_CS0_LS01_R1_N")
	)
	(segment
		(start 147.065746 -199.1868)
		(end 148.93925 -199.1868)
		(width 0.15494)
		(layer "In13.Cu")
		(net "SPI_BIC1_CS0_LS01_R1_N")
	)
	(segment
		(start 18.751804 -228.983794)
		(end 18.769838 -228.98989)
		(width 0.15494)
		(layer "In13.Cu")
		(net "SPI_BIC1_CS0_LS01_R1_N")
	)
	(segment
		(start 122.599958 -202.3364)
		(end 123.717558 -203.454)
		(width 0.15494)
		(layer "In13.Cu")
		(net "SPI_BIC1_CS0_LS01_R1_N")
	)
	(segment
		(start 18.29689 -228.303836)
		(end 18.304256 -228.358192)
		(width 0.15494)
		(layer "In13.Cu")
		(net "SPI_BIC1_CS0_LS01_R1_N")
	)
	(segment
		(start 100.759006 -204.986382)
		(end 103.611172 -203.805028)
		(width 0.15494)
		(layer "In13.Cu")
		(net "SPI_BIC1_CS0_LS01_R1_N")
	)
	(segment
		(start 27.234896 -223.030288)
		(end 28.932378 -218.931998)
		(width 0.15494)
		(layer "In13.Cu")
		(net "SPI_BIC1_CS0_LS01_R1_N")
	)
	(segment
		(start 18.315432 -228.552248)
		(end 18.73504 -228.971856)
		(width 0.15494)
		(layer "In13.Cu")
		(net "SPI_BIC1_CS0_LS01_R1_N")
	)
	(segment
		(start 18.29689 -228.179884)
		(end 18.29689 -228.303836)
		(width 0.15494)
		(layer "In13.Cu")
		(net "SPI_BIC1_CS0_LS01_R1_N")
	)
	(segment
		(start 28.932378 -218.931998)
		(end 30.62478 -217.239596)
		(width 0.15494)
		(layer "In13.Cu")
		(net "SPI_BIC1_CS0_LS01_R1_N")
	)
	(segment
		(start 141.055598 -203.454)
		(end 144.030954 -202.221592)
		(width 0.15494)
		(layer "In13.Cu")
		(net "SPI_BIC1_CS0_LS01_R1_N")
	)
	(segment
		(start 147.066762 -195.868798)
		(end 165.930834 -195.868798)
		(width 0.13208)
		(layer "F.Cu")
		(net "SPI_BIC1_MOSI_LS01_R1")
	)
	(segment
		(start 146.720052 -195.522088)
		(end 147.066762 -195.868798)
		(width 0.13208)
		(layer "F.Cu")
		(net "SPI_BIC1_MOSI_LS01_R1")
	)
	(via
		(at 146.720052 -195.522088)
		(size 0.508)
		(drill 0.254)
		(layers "F.Cu" "B.Cu")
		(net "SPI_BIC1_MOSI_LS01_R1")
	)
	(via
		(at 21.429218 -223.084644)
		(size 0.508)
		(drill 0.254)
		(layers "F.Cu" "B.Cu")
		(net "SPI_BIC1_MOSI_LS01_R1")
	)
	(segment
		(start 21.343112 -223.484694)
		(end 21.343112 -224.341182)
		(width 0.13208)
		(layer "B.Cu")
		(net "SPI_BIC1_MOSI_LS01_R1")
	)
	(segment
		(start 21.429218 -223.084644)
		(end 21.429218 -223.398588)
		(width 0.13208)
		(layer "B.Cu")
		(net "SPI_BIC1_MOSI_LS01_R1")
	)
	(segment
		(start 21.429218 -223.398588)
		(end 21.343112 -223.484694)
		(width 0.13208)
		(layer "B.Cu")
		(net "SPI_BIC1_MOSI_LS01_R1")
	)
	(segment
		(start 21.429218 -217.678254)
		(end 21.556218 -217.551254)
		(width 0.15494)
		(layer "In13.Cu")
		(net "SPI_BIC1_MOSI_LS01_R1")
	)
	(segment
		(start 23.76805 -217.551254)
		(end 23.90267 -217.685874)
		(width 0.15494)
		(layer "In13.Cu")
		(net "SPI_BIC1_MOSI_LS01_R1")
	)
	(segment
		(start 23.90267 -217.685874)
		(end 23.90267 -219.633038)
		(width 0.15494)
		(layer "In13.Cu")
		(net "SPI_BIC1_MOSI_LS01_R1")
	)
	(segment
		(start 23.26005 -219.633038)
		(end 23.26005 -217.685874)
		(width 0.15494)
		(layer "In13.Cu")
		(net "SPI_BIC1_MOSI_LS01_R1")
	)
	(segment
		(start 23.39467 -217.551254)
		(end 23.76805 -217.551254)
		(width 0.15494)
		(layer "In13.Cu")
		(net "SPI_BIC1_MOSI_LS01_R1")
	)
	(segment
		(start 24.03729 -219.767658)
		(end 24.41067 -219.767658)
		(width 0.15494)
		(layer "In13.Cu")
		(net "SPI_BIC1_MOSI_LS01_R1")
	)
	(segment
		(start 24.41067 -219.767658)
		(end 24.54529 -219.633038)
		(width 0.15494)
		(layer "In13.Cu")
		(net "SPI_BIC1_MOSI_LS01_R1")
	)
	(segment
		(start 137.637266 -197.861936)
		(end 137.939272 -197.55993)
		(width 0.15494)
		(layer "In13.Cu")
		(net "SPI_BIC1_MOSI_LS01_R1")
	)
	(segment
		(start 23.26005 -217.685874)
		(end 23.39467 -217.551254)
		(width 0.15494)
		(layer "In13.Cu")
		(net "SPI_BIC1_MOSI_LS01_R1")
	)
	(segment
		(start 22.48281 -217.551254)
		(end 22.61743 -217.685874)
		(width 0.15494)
		(layer "In13.Cu")
		(net "SPI_BIC1_MOSI_LS01_R1")
	)
	(segment
		(start 22.75205 -219.767658)
		(end 23.12543 -219.767658)
		(width 0.15494)
		(layer "In13.Cu")
		(net "SPI_BIC1_MOSI_LS01_R1")
	)
	(segment
		(start 21.429218 -223.084644)
		(end 21.429218 -217.678254)
		(width 0.15494)
		(layer "In13.Cu")
		(net "SPI_BIC1_MOSI_LS01_R1")
	)
	(segment
		(start 128.74371 -197.861936)
		(end 137.637266 -197.861936)
		(width 0.15494)
		(layer "In13.Cu")
		(net "SPI_BIC1_MOSI_LS01_R1")
	)
	(segment
		(start 24.54529 -217.685874)
		(end 24.67991 -217.551254)
		(width 0.15494)
		(layer "In13.Cu")
		(net "SPI_BIC1_MOSI_LS01_R1")
	)
	(segment
		(start 115.710716 -200.66)
		(end 121.98858 -200.66)
		(width 0.15494)
		(layer "In13.Cu")
		(net "SPI_BIC1_MOSI_LS01_R1")
	)
	(segment
		(start 140.50645 -197.55993)
		(end 145.426176 -195.522088)
		(width 0.15494)
		(layer "In13.Cu")
		(net "SPI_BIC1_MOSI_LS01_R1")
	)
	(segment
		(start 121.98858 -200.66)
		(end 128.74371 -197.861936)
		(width 0.15494)
		(layer "In13.Cu")
		(net "SPI_BIC1_MOSI_LS01_R1")
	)
	(segment
		(start 26.406094 -217.551254)
		(end 60.132468 -203.581)
		(width 0.15494)
		(layer "In13.Cu")
		(net "SPI_BIC1_MOSI_LS01_R1")
	)
	(segment
		(start 22.61743 -219.633038)
		(end 22.75205 -219.767658)
		(width 0.15494)
		(layer "In13.Cu")
		(net "SPI_BIC1_MOSI_LS01_R1")
	)
	(segment
		(start 21.556218 -217.551254)
		(end 22.48281 -217.551254)
		(width 0.15494)
		(layer "In13.Cu")
		(net "SPI_BIC1_MOSI_LS01_R1")
	)
	(segment
		(start 145.426176 -195.522088)
		(end 146.720052 -195.522088)
		(width 0.15494)
		(layer "In13.Cu")
		(net "SPI_BIC1_MOSI_LS01_R1")
	)
	(segment
		(start 24.54529 -219.633038)
		(end 24.54529 -217.685874)
		(width 0.15494)
		(layer "In13.Cu")
		(net "SPI_BIC1_MOSI_LS01_R1")
	)
	(segment
		(start 22.61743 -217.685874)
		(end 22.61743 -219.633038)
		(width 0.15494)
		(layer "In13.Cu")
		(net "SPI_BIC1_MOSI_LS01_R1")
	)
	(segment
		(start 60.132468 -203.581)
		(end 91.82608 -203.581)
		(width 0.15494)
		(layer "In13.Cu")
		(net "SPI_BIC1_MOSI_LS01_R1")
	)
	(segment
		(start 91.82608 -203.581)
		(end 96.933512 -201.465688)
		(width 0.15494)
		(layer "In13.Cu")
		(net "SPI_BIC1_MOSI_LS01_R1")
	)
	(segment
		(start 102.305358 -198.4756)
		(end 110.43666 -198.4756)
		(width 0.15494)
		(layer "In13.Cu")
		(net "SPI_BIC1_MOSI_LS01_R1")
	)
	(segment
		(start 24.67991 -217.551254)
		(end 26.406094 -217.551254)
		(width 0.15494)
		(layer "In13.Cu")
		(net "SPI_BIC1_MOSI_LS01_R1")
	)
	(segment
		(start 96.933512 -201.465688)
		(end 98.23958 -200.15962)
		(width 0.15494)
		(layer "In13.Cu")
		(net "SPI_BIC1_MOSI_LS01_R1")
	)
	(segment
		(start 137.939272 -197.55993)
		(end 140.50645 -197.55993)
		(width 0.15494)
		(layer "In13.Cu")
		(net "SPI_BIC1_MOSI_LS01_R1")
	)
	(segment
		(start 110.43666 -198.4756)
		(end 115.710716 -200.66)
		(width 0.15494)
		(layer "In13.Cu")
		(net "SPI_BIC1_MOSI_LS01_R1")
	)
	(segment
		(start 23.90267 -219.633038)
		(end 24.03729 -219.767658)
		(width 0.15494)
		(layer "In13.Cu")
		(net "SPI_BIC1_MOSI_LS01_R1")
	)
	(segment
		(start 98.23958 -200.15962)
		(end 102.305358 -198.4756)
		(width 0.15494)
		(layer "In13.Cu")
		(net "SPI_BIC1_MOSI_LS01_R1")
	)
	(segment
		(start 23.12543 -219.767658)
		(end 23.26005 -219.633038)
		(width 0.15494)
		(layer "In13.Cu")
		(net "SPI_BIC1_MOSI_LS01_R1")
	)
	(segment
		(start 390.849866 -292.099746)
		(end 390.374886 -291.624766)
		(width 0.13208)
		(layer "F.Cu")
		(net "SPI_PEX3_CS_N")
	)
	(via
		(at 390.846818 -291.152834)
		(size 0.6604)
		(drill 0.3302)
		(layers "F.Cu" "B.Cu")
		(net "SPI_PEX3_CS_N")
	)
	(via
		(at 390.374886 -291.624766)
		(size 0.4064)
		(drill 0.2032)
		(layers "F.Cu" "B.Cu")
		(net "SPI_PEX3_CS_N")
	)
	(segment
		(start 390.846818 -291.152834)
		(end 390.846818 -289.514026)
		(width 0.13208)
		(layer "B.Cu")
		(net "SPI_PEX3_CS_N")
	)
	(segment
		(start 390.374886 -291.624766)
		(end 390.846818 -291.152834)
		(width 0.13208)
		(layer "B.Cu")
		(net "SPI_PEX3_CS_N")
	)
	(segment
		(start 390.846818 -289.514026)
		(end 390.507728 -289.174936)
		(width 0.13208)
		(layer "B.Cu")
		(net "SPI_PEX3_CS_N")
	)
	(segment
		(start 389.899906 -289.174936)
		(end 388.949946 -289.174936)
		(width 0.13208)
		(layer "B.Cu")
		(net "SPI_PEX3_CS_N")
	)
	(segment
		(start 390.507728 -289.174936)
		(end 389.899906 -289.174936)
		(width 0.13208)
		(layer "B.Cu")
		(net "SPI_PEX3_CS_N")
	)
	(segment
		(start 390.849866 -293.04996)
		(end 390.374886 -292.57498)
		(width 0.13208)
		(layer "F.Cu")
		(net "SPI_PEX3_CLK")
	)
	(via
		(at 390.374886 -292.57498)
		(size 0.508)
		(drill 0.254)
		(layers "F.Cu" "B.Cu")
		(net "SPI_PEX3_CLK")
	)
	(segment
		(start 390.374886 -292.57498)
		(end 389.89635 -292.096444)
		(width 0.13208)
		(layer "B.Cu")
		(net "SPI_PEX3_CLK")
	)
	(segment
		(start 389.89635 -292.096444)
		(end 389.126984 -292.096444)
		(width 0.13208)
		(layer "B.Cu")
		(net "SPI_PEX3_CLK")
	)
	(segment
		(start 389.126984 -292.096444)
		(end 388.75716 -291.72662)
		(width 0.13208)
		(layer "B.Cu")
		(net "SPI_PEX3_CLK")
	)
	(segment
		(start 119.775732 -254.319532)
		(end 119.775732 -255.994916)
		(width 0.13208)
		(layer "F.Cu")
		(net "NC_P0V8_PEX0_PWM2")
	)
	(segment
		(start 119.746522 -254.290576)
		(end 119.775732 -254.319532)
		(width 0.13208)
		(layer "F.Cu")
		(net "NC_P0V8_PEX0_PWM2")
	)
	(via
		(at 119.746522 -254.290576)
		(size 0.762)
		(drill 0.381)
		(layers "F.Cu" "B.Cu")
		(net "NC_P0V8_PEX0_PWM2")
	)
	(segment
		(start 358.116886 -263.05002)
		(end 358.116886 -263.57072)
		(width 0.254)
		(layer "F.Cu")
		(net "SH_P0V8_PEX2_VSEN2_R")
	)
	(segment
		(start 357.767636 -262.70077)
		(end 358.116886 -263.05002)
		(width 0.254)
		(layer "F.Cu")
		(net "SH_P0V8_PEX2_VSEN2_R")
	)
	(segment
		(start 358.116886 -263.57072)
		(end 359.561384 -263.57072)
		(width 0.254)
		(layer "F.Cu")
		(net "SH_P0V8_PEX2_VSEN2_R")
	)
	(segment
		(start 357.767636 -262.17372)
		(end 357.767636 -262.70077)
		(width 0.254)
		(layer "F.Cu")
		(net "SH_P0V8_PEX2_VSEN2_R")
	)
	(via
		(at 359.561384 -263.57072)
		(size 0.762)
		(drill 0.381)
		(layers "F.Cu" "B.Cu")
		(net "SH_P0V8_PEX2_VSEN2_R")
	)
	(segment
		(start 361.36326 -257.620262)
		(end 361.49026 -257.747262)
		(width 0.13208)
		(layer "F.Cu")
		(net "P0V8_PEX3_BVRRDY")
	)
	(segment
		(start 355.375972 -258.59486)
		(end 358.37749 -258.59486)
		(width 0.13208)
		(layer "F.Cu")
		(net "P0V8_PEX3_BVRRDY")
	)
	(segment
		(start 361.49026 -258.131564)
		(end 361.49026 -259.147564)
		(width 0.13208)
		(layer "F.Cu")
		(net "P0V8_PEX3_BVRRDY")
	)
	(segment
		(start 358.840786 -258.131564)
		(end 359.45826 -258.131564)
		(width 0.13208)
		(layer "F.Cu")
		(net "P0V8_PEX3_BVRRDY")
	)
	(segment
		(start 358.37749 -258.59486)
		(end 358.840786 -258.131564)
		(width 0.13208)
		(layer "F.Cu")
		(net "P0V8_PEX3_BVRRDY")
	)
	(segment
		(start 359.45826 -257.747262)
		(end 359.58526 -257.620262)
		(width 0.13208)
		(layer "F.Cu")
		(net "P0V8_PEX3_BVRRDY")
	)
	(segment
		(start 359.45826 -258.131564)
		(end 359.45826 -257.747262)
		(width 0.13208)
		(layer "F.Cu")
		(net "P0V8_PEX3_BVRRDY")
	)
	(segment
		(start 361.49026 -257.747262)
		(end 361.49026 -258.131564)
		(width 0.13208)
		(layer "F.Cu")
		(net "P0V8_PEX3_BVRRDY")
	)
	(segment
		(start 359.58526 -257.620262)
		(end 361.36326 -257.620262)
		(width 0.13208)
		(layer "F.Cu")
		(net "P0V8_PEX3_BVRRDY")
	)
	(via
		(at 358.840786 -258.131564)
		(size 0.508)
		(drill 0.254)
		(layers "F.Cu" "B.Cu")
		(net "P0V8_PEX3_BVRRDY")
	)
	(segment
		(start 358.098598 -257.91668)
		(end 358.899714 -257.115564)
		(width 0.13208)
		(layer "F.Cu")
		(net "P0V8_PEX2_PINALRT")
	)
	(segment
		(start 357.426514 -258.195064)
		(end 358.098598 -257.91668)
		(width 0.13208)
		(layer "F.Cu")
		(net "P0V8_PEX2_PINALRT")
	)
	(segment
		(start 358.899714 -257.115564)
		(end 359.45826 -257.115564)
		(width 0.13208)
		(layer "F.Cu")
		(net "P0V8_PEX2_PINALRT")
	)
	(segment
		(start 355.375972 -258.195064)
		(end 357.426514 -258.195064)
		(width 0.13208)
		(layer "F.Cu")
		(net "P0V8_PEX2_PINALRT")
	)
	(via
		(at 358.098598 -257.91668)
		(size 0.762)
		(drill 0.381)
		(layers "F.Cu" "B.Cu")
		(net "P0V8_PEX2_PINALRT")
	)
	(segment
		(start 356.967536 -262.17372)
		(end 356.967536 -260.972808)
		(width 0.254)
		(layer "F.Cu")
		(net "P0V8_PEX2_VSEN2")
	)
	(segment
		(start 355.608636 -262.17372)
		(end 356.967536 -262.17372)
		(width 0.254)
		(layer "F.Cu")
		(net "P0V8_PEX2_VSEN2")
	)
	(segment
		(start 355.481636 -262.04672)
		(end 355.608636 -262.17372)
		(width 0.254)
		(layer "F.Cu")
		(net "P0V8_PEX2_VSEN2")
	)
	(segment
		(start 355.481636 -261.68477)
		(end 355.481636 -262.04672)
		(width 0.2032)
		(layer "F.Cu")
		(net "P0V8_PEX2_VSEN2")
	)
	(segment
		(start 354.776024 -260.979158)
		(end 355.481636 -261.68477)
		(width 0.2032)
		(layer "F.Cu")
		(net "P0V8_PEX2_VSEN2")
	)
	(segment
		(start 354.776024 -260.795008)
		(end 354.776024 -260.979158)
		(width 0.2032)
		(layer "F.Cu")
		(net "P0V8_PEX2_VSEN2")
	)
	(via
		(at 356.967536 -260.972808)
		(size 0.762)
		(drill 0.381)
		(layers "F.Cu" "B.Cu")
		(net "P0V8_PEX2_VSEN2")
	)
	(segment
		(start 350.083628 -258.195064)
		(end 350.57588 -258.195064)
		(width 0.1524)
		(layer "F.Cu")
		(net "P0V8_PEX3_TSEN_R")
	)
	(segment
		(start 349.595186 -258.27355)
		(end 350.005142 -258.27355)
		(width 0.1524)
		(layer "F.Cu")
		(net "P0V8_PEX3_TSEN_R")
	)
	(segment
		(start 350.005142 -258.27355)
		(end 350.083628 -258.195064)
		(width 0.1524)
		(layer "F.Cu")
		(net "P0V8_PEX3_TSEN_R")
	)
	(via
		(at 349.595186 -258.27355)
		(size 0.508)
		(drill 0.254)
		(layers "F.Cu" "B.Cu")
		(net "P0V8_PEX3_TSEN_R")
	)
	(via
		(at 350.28251 -258.843526)
		(size 0.6604)
		(drill 0.3302)
		(layers "F.Cu" "B.Cu")
		(net "P0V8_PEX3_TSEN_R")
	)
	(segment
		(start 349.74911 -257.699764)
		(end 349.595186 -257.853688)
		(width 0.254)
		(layer "B.Cu")
		(net "P0V8_PEX3_TSEN_R")
	)
	(segment
		(start 350.18726 -257.699764)
		(end 349.74911 -257.699764)
		(width 0.254)
		(layer "B.Cu")
		(net "P0V8_PEX3_TSEN_R")
	)
	(segment
		(start 349.595186 -257.853688)
		(end 349.595186 -258.27355)
		(width 0.254)
		(layer "B.Cu")
		(net "P0V8_PEX3_TSEN_R")
	)
	(segment
		(start 350.28251 -257.795014)
		(end 350.28251 -258.843526)
		(width 0.254)
		(layer "B.Cu")
		(net "P0V8_PEX3_TSEN_R")
	)
	(segment
		(start 350.18726 -257.699764)
		(end 350.28251 -257.795014)
		(width 0.254)
		(layer "B.Cu")
		(net "P0V8_PEX3_TSEN_R")
	)
	(segment
		(start 350.28251 -259.867146)
		(end 350.28251 -258.843526)
		(width 0.254)
		(layer "B.Cu")
		(net "P0V8_PEX3_TSEN_R")
	)
	(segment
		(start 350.153986 -259.99567)
		(end 350.28251 -259.867146)
		(width 0.254)
		(layer "B.Cu")
		(net "P0V8_PEX3_TSEN_R")
	)
	(segment
		(start 357.577644 -279.915366)
		(end 357.577644 -280.655014)
		(width 0.2286)
		(layer "F.Cu")
		(net "P0V8_PEX2_VREF")
	)
	(segment
		(start 348.738444 -281.477466)
		(end 348.322392 -281.893518)
		(width 0.2286)
		(layer "F.Cu")
		(net "P0V8_PEX2_VREF")
	)
	(segment
		(start 349.05061 -279.886918)
		(end 349.079058 -279.915366)
		(width 0.2286)
		(layer "F.Cu")
		(net "P0V8_PEX2_VREF")
	)
	(segment
		(start 348.325948 -279.886918)
		(end 349.05061 -279.886918)
		(width 0.254)
		(layer "F.Cu")
		(net "P0V8_PEX2_VREF")
	)
	(segment
		(start 364.985046 -279.886918)
		(end 365.119666 -279.886918)
		(width 0.254)
		(layer "F.Cu")
		(net "P0V8_PEX2_VREF")
	)
	(segment
		(start 356.820978 -281.893518)
		(end 356.820978 -281.999182)
		(width 0.2286)
		(layer "F.Cu")
		(net "P0V8_PEX2_VREF")
	)
	(segment
		(start 365.397542 -281.477466)
		(end 364.98149 -281.893518)
		(width 0.2286)
		(layer "F.Cu")
		(net "P0V8_PEX2_VREF")
	)
	(segment
		(start 365.576866 -280.344118)
		(end 365.576866 -281.04465)
		(width 0.2286)
		(layer "F.Cu")
		(net "P0V8_PEX2_VREF")
	)
	(segment
		(start 340.918546 -279.915366)
		(end 340.890098 -279.886918)
		(width 0.2286)
		(layer "F.Cu")
		(net "P0V8_PEX2_VREF")
	)
	(segment
		(start 357.23703 -281.477466)
		(end 356.820978 -281.893518)
		(width 0.2286)
		(layer "F.Cu")
		(net "P0V8_PEX2_VREF")
	)
	(segment
		(start 365.576866 -281.04465)
		(end 365.397542 -281.477466)
		(width 0.2286)
		(layer "F.Cu")
		(net "P0V8_PEX2_VREF")
	)
	(segment
		(start 340.890098 -279.886918)
		(end 340.165436 -279.886918)
		(width 0.254)
		(layer "F.Cu")
		(net "P0V8_PEX2_VREF")
	)
	(segment
		(start 340.16188 -281.999182)
		(end 340.16188 -281.893518)
		(width 0.2286)
		(layer "F.Cu")
		(net "P0V8_PEX2_VREF")
	)
	(segment
		(start 345.36126 -260.671564)
		(end 344.74531 -260.671564)
		(width 0.381)
		(layer "F.Cu")
		(net "P0V8_PEX2_VREF")
	)
	(segment
		(start 349.079058 -279.915366)
		(end 349.079058 -280.655014)
		(width 0.2286)
		(layer "F.Cu")
		(net "P0V8_PEX2_VREF")
	)
	(segment
		(start 357.577644 -280.655014)
		(end 357.23703 -281.477466)
		(width 0.2286)
		(layer "F.Cu")
		(net "P0V8_PEX2_VREF")
	)
	(segment
		(start 349.079058 -280.655014)
		(end 348.738444 -281.477466)
		(width 0.2286)
		(layer "F.Cu")
		(net "P0V8_PEX2_VREF")
	)
	(segment
		(start 365.119666 -279.886918)
		(end 365.576866 -280.344118)
		(width 0.254)
		(layer "F.Cu")
		(net "P0V8_PEX2_VREF")
	)
	(segment
		(start 364.98149 -281.893518)
		(end 364.98149 -281.999182)
		(width 0.2286)
		(layer "F.Cu")
		(net "P0V8_PEX2_VREF")
	)
	(segment
		(start 340.16188 -281.893518)
		(end 340.577932 -281.477466)
		(width 0.2286)
		(layer "F.Cu")
		(net "P0V8_PEX2_VREF")
	)
	(segment
		(start 340.577932 -281.477466)
		(end 340.918546 -280.655014)
		(width 0.2286)
		(layer "F.Cu")
		(net "P0V8_PEX2_VREF")
	)
	(segment
		(start 356.824534 -279.886918)
		(end 357.549196 -279.886918)
		(width 0.254)
		(layer "F.Cu")
		(net "P0V8_PEX2_VREF")
	)
	(segment
		(start 357.549196 -279.886918)
		(end 357.577644 -279.915366)
		(width 0.2286)
		(layer "F.Cu")
		(net "P0V8_PEX2_VREF")
	)
	(segment
		(start 340.918546 -280.655014)
		(end 340.918546 -279.915366)
		(width 0.2286)
		(layer "F.Cu")
		(net "P0V8_PEX2_VREF")
	)
	(segment
		(start 348.322392 -281.893518)
		(end 348.322392 -281.999182)
		(width 0.2286)
		(layer "F.Cu")
		(net "P0V8_PEX2_VREF")
	)
	(via
		(at 356.824534 -279.886918)
		(size 0.508)
		(drill 0.254)
		(layers "F.Cu" "B.Cu")
		(net "P0V8_PEX2_VREF")
	)
	(via
		(at 364.985046 -279.886918)
		(size 0.508)
		(drill 0.254)
		(layers "F.Cu" "B.Cu")
		(net "P0V8_PEX2_VREF")
	)
	(via
		(at 348.325948 -279.886918)
		(size 0.508)
		(drill 0.254)
		(layers "F.Cu" "B.Cu")
		(net "P0V8_PEX2_VREF")
	)
	(via
		(at 344.74531 -260.671564)
		(size 0.508)
		(drill 0.254)
		(layers "F.Cu" "B.Cu")
		(net "P0V8_PEX2_VREF")
	)
	(via
		(at 350.250252 -254.148844)
		(size 0.508)
		(drill 0.254)
		(layers "F.Cu" "B.Cu")
		(net "P0V8_PEX2_VREF")
	)
	(via
		(at 340.165436 -279.886918)
		(size 0.508)
		(drill 0.254)
		(layers "F.Cu" "B.Cu")
		(net "P0V8_PEX2_VREF")
	)
	(segment
		(start 353.875594 -253.152148)
		(end 354.461318 -253.152148)
		(width 0.381)
		(layer "B.Cu")
		(net "P0V8_PEX2_VREF")
	)
	(segment
		(start 358.287574 -258.991608)
		(end 358.287574 -260.160516)
		(width 0.381)
		(layer "B.Cu")
		(net "P0V8_PEX2_VREF")
	)
	(segment
		(start 355.95687 -254.6477)
		(end 355.95687 -256.660904)
		(width 0.381)
		(layer "B.Cu")
		(net "P0V8_PEX2_VREF")
	)
	(segment
		(start 352.878898 -254.148844)
		(end 353.875594 -253.152148)
		(width 0.381)
		(layer "B.Cu")
		(net "P0V8_PEX2_VREF")
	)
	(segment
		(start 350.250252 -254.148844)
		(end 352.878898 -254.148844)
		(width 0.381)
		(layer "B.Cu")
		(net "P0V8_PEX2_VREF")
	)
	(segment
		(start 354.461318 -253.152148)
		(end 355.95687 -254.6477)
		(width 0.381)
		(layer "B.Cu")
		(net "P0V8_PEX2_VREF")
	)
	(segment
		(start 355.95687 -256.660904)
		(end 358.287574 -258.991608)
		(width 0.381)
		(layer "B.Cu")
		(net "P0V8_PEX2_VREF")
	)
	(segment
		(start 348.721934 -280.282904)
		(end 348.325948 -279.886918)
		(width 0.254)
		(layer "In11.Cu")
		(net "P0V8_PEX2_VREF")
	)
	(segment
		(start 352.74758 -264.346944)
		(end 352.346768 -264.747756)
		(width 0.254)
		(layer "In11.Cu")
		(net "P0V8_PEX2_VREF")
	)
	(segment
		(start 349.159068 -280.282904)
		(end 348.721934 -280.282904)
		(width 0.254)
		(layer "In11.Cu")
		(net "P0V8_PEX2_VREF")
	)
	(segment
		(start 352.600006 -265.549126)
		(end 352.600006 -267.118084)
		(width 0.254)
		(layer "In11.Cu")
		(net "P0V8_PEX2_VREF")
	)
	(segment
		(start 353.47402 -264.346944)
		(end 352.74758 -264.346944)
		(width 0.254)
		(layer "In11.Cu")
		(net "P0V8_PEX2_VREF")
	)
	(segment
		(start 357.657654 -280.282904)
		(end 357.22052 -280.282904)
		(width 0.254)
		(layer "In11.Cu")
		(net "P0V8_PEX2_VREF")
	)
	(segment
		(start 355.25583 -276.650196)
		(end 358.003856 -279.398222)
		(width 0.254)
		(layer "In11.Cu")
		(net "P0V8_PEX2_VREF")
	)
	(segment
		(start 355.562662 -262.111744)
		(end 354.92182 -262.111744)
		(width 0.254)
		(layer "In11.Cu")
		(net "P0V8_PEX2_VREF")
	)
	(segment
		(start 363.492288 -268.074394)
		(end 358.920796 -263.502902)
		(width 0.254)
		(layer "In11.Cu")
		(net "P0V8_PEX2_VREF")
	)
	(segment
		(start 340.165436 -279.886918)
		(end 340.561422 -280.282904)
		(width 0.254)
		(layer "In11.Cu")
		(net "P0V8_PEX2_VREF")
	)
	(segment
		(start 358.003856 -279.936702)
		(end 357.657654 -280.282904)
		(width 0.254)
		(layer "In11.Cu")
		(net "P0V8_PEX2_VREF")
	)
	(segment
		(start 351.621598 -265.267186)
		(end 351.621598 -265.269472)
		(width 0.254)
		(layer "In11.Cu")
		(net "P0V8_PEX2_VREF")
	)
	(segment
		(start 355.25583 -266.922504)
		(end 355.25583 -276.650196)
		(width 0.254)
		(layer "In11.Cu")
		(net "P0V8_PEX2_VREF")
	)
	(segment
		(start 353.748086 -263.285478)
		(end 351.840546 -263.285478)
		(width 0.254)
		(layer "In11.Cu")
		(net "P0V8_PEX2_VREF")
	)
	(segment
		(start 364.20552 -277.559262)
		(end 363.492288 -275.837142)
		(width 0.254)
		(layer "In11.Cu")
		(net "P0V8_PEX2_VREF")
	)
	(segment
		(start 351.840546 -263.285478)
		(end 351.357184 -263.76884)
		(width 0.254)
		(layer "In11.Cu")
		(net "P0V8_PEX2_VREF")
	)
	(segment
		(start 353.731322 -265.397996)
		(end 353.731322 -264.604246)
		(width 0.254)
		(layer "In11.Cu")
		(net "P0V8_PEX2_VREF")
	)
	(segment
		(start 350.271588 -269.446502)
		(end 350.271588 -279.170384)
		(width 0.254)
		(layer "In11.Cu")
		(net "P0V8_PEX2_VREF")
	)
	(segment
		(start 357.22052 -280.282904)
		(end 356.824534 -279.886918)
		(width 0.254)
		(layer "In11.Cu")
		(net "P0V8_PEX2_VREF")
	)
	(segment
		(start 344.775282 -270.948404)
		(end 349.155766 -266.56792)
		(width 0.254)
		(layer "In11.Cu")
		(net "P0V8_PEX2_VREF")
	)
	(segment
		(start 352.320352 -265.269472)
		(end 352.600006 -265.549126)
		(width 0.254)
		(layer "In11.Cu")
		(net "P0V8_PEX2_VREF")
	)
	(segment
		(start 364.985046 -279.886918)
		(end 365.381032 -280.282904)
		(width 0.254)
		(layer "In11.Cu")
		(net "P0V8_PEX2_VREF")
	)
	(segment
		(start 365.64697 -280.282904)
		(end 365.939324 -279.99055)
		(width 0.254)
		(layer "In11.Cu")
		(net "P0V8_PEX2_VREF")
	)
	(segment
		(start 352.320352 -265.269472)
		(end 351.621598 -265.269472)
		(width 0.254)
		(layer "In11.Cu")
		(net "P0V8_PEX2_VREF")
	)
	(segment
		(start 365.381032 -280.282904)
		(end 365.64697 -280.282904)
		(width 0.254)
		(layer "In11.Cu")
		(net "P0V8_PEX2_VREF")
	)
	(segment
		(start 344.775282 -278.341074)
		(end 344.775282 -270.948404)
		(width 0.254)
		(layer "In11.Cu")
		(net "P0V8_PEX2_VREF")
	)
	(segment
		(start 350.32315 -266.56792)
		(end 351.621598 -265.269472)
		(width 0.254)
		(layer "In11.Cu")
		(net "P0V8_PEX2_VREF")
	)
	(segment
		(start 343.740486 -279.37587)
		(end 344.775282 -278.341074)
		(width 0.254)
		(layer "In11.Cu")
		(net "P0V8_PEX2_VREF")
	)
	(segment
		(start 354.92182 -262.111744)
		(end 353.748086 -263.285478)
		(width 0.254)
		(layer "In11.Cu")
		(net "P0V8_PEX2_VREF")
	)
	(segment
		(start 352.346768 -265.243056)
		(end 352.320352 -265.269472)
		(width 0.254)
		(layer "In11.Cu")
		(net "P0V8_PEX2_VREF")
	)
	(segment
		(start 351.357184 -265.002772)
		(end 351.621598 -265.267186)
		(width 0.254)
		(layer "In11.Cu")
		(net "P0V8_PEX2_VREF")
	)
	(segment
		(start 340.561422 -280.282904)
		(end 340.817708 -280.282904)
		(width 0.254)
		(layer "In11.Cu")
		(net "P0V8_PEX2_VREF")
	)
	(segment
		(start 349.155766 -266.56792)
		(end 350.32315 -266.56792)
		(width 0.254)
		(layer "In11.Cu")
		(net "P0V8_PEX2_VREF")
	)
	(segment
		(start 358.003856 -279.398222)
		(end 358.003856 -279.936702)
		(width 0.254)
		(layer "In11.Cu")
		(net "P0V8_PEX2_VREF")
	)
	(segment
		(start 353.731322 -264.604246)
		(end 353.47402 -264.346944)
		(width 0.254)
		(layer "In11.Cu")
		(net "P0V8_PEX2_VREF")
	)
	(segment
		(start 341.724742 -279.37587)
		(end 343.740486 -279.37587)
		(width 0.254)
		(layer "In11.Cu")
		(net "P0V8_PEX2_VREF")
	)
	(segment
		(start 358.920796 -263.502902)
		(end 355.562662 -262.111744)
		(width 0.254)
		(layer "In11.Cu")
		(net "P0V8_PEX2_VREF")
	)
	(segment
		(start 363.492288 -275.837142)
		(end 363.492288 -268.074394)
		(width 0.254)
		(layer "In11.Cu")
		(net "P0V8_PEX2_VREF")
	)
	(segment
		(start 365.939324 -279.293066)
		(end 364.20552 -277.559262)
		(width 0.254)
		(layer "In11.Cu")
		(net "P0V8_PEX2_VREF")
	)
	(segment
		(start 352.600006 -267.118084)
		(end 350.271588 -269.446502)
		(width 0.254)
		(layer "In11.Cu")
		(net "P0V8_PEX2_VREF")
	)
	(segment
		(start 340.817708 -280.282904)
		(end 341.724742 -279.37587)
		(width 0.254)
		(layer "In11.Cu")
		(net "P0V8_PEX2_VREF")
	)
	(segment
		(start 352.346768 -264.747756)
		(end 352.346768 -265.243056)
		(width 0.254)
		(layer "In11.Cu")
		(net "P0V8_PEX2_VREF")
	)
	(segment
		(start 350.271588 -279.170384)
		(end 349.159068 -280.282904)
		(width 0.254)
		(layer "In11.Cu")
		(net "P0V8_PEX2_VREF")
	)
	(segment
		(start 353.731322 -265.397996)
		(end 355.25583 -266.922504)
		(width 0.254)
		(layer "In11.Cu")
		(net "P0V8_PEX2_VREF")
	)
	(segment
		(start 365.939324 -279.99055)
		(end 365.939324 -279.293066)
		(width 0.254)
		(layer "In11.Cu")
		(net "P0V8_PEX2_VREF")
	)
	(segment
		(start 351.357184 -263.76884)
		(end 351.357184 -265.002772)
		(width 0.254)
		(layer "In11.Cu")
		(net "P0V8_PEX2_VREF")
	)
	(segment
		(start 359.669588 -253.683516)
		(end 359.45826 -253.894844)
		(width 0.13208)
		(layer "F.Cu")
		(net "P0V8_PEX2_AVRRDY")
	)
	(segment
		(start 358.942132 -254.194564)
		(end 359.45826 -254.194564)
		(width 0.13208)
		(layer "F.Cu")
		(net "P0V8_PEX2_AVRRDY")
	)
	(segment
		(start 361.49026 -254.194564)
		(end 361.49026 -253.842774)
		(width 0.13208)
		(layer "F.Cu")
		(net "P0V8_PEX2_AVRRDY")
	)
	(segment
		(start 361.331002 -253.683516)
		(end 359.669588 -253.683516)
		(width 0.13208)
		(layer "F.Cu")
		(net "P0V8_PEX2_AVRRDY")
	)
	(segment
		(start 356.141782 -256.994914)
		(end 358.075992 -255.060704)
		(width 0.13208)
		(layer "F.Cu")
		(net "P0V8_PEX2_AVRRDY")
	)
	(segment
		(start 358.075992 -255.060704)
		(end 358.942132 -254.194564)
		(width 0.13208)
		(layer "F.Cu")
		(net "P0V8_PEX2_AVRRDY")
	)
	(segment
		(start 361.49026 -253.524258)
		(end 361.49026 -253.178564)
		(width 0.13208)
		(layer "F.Cu")
		(net "P0V8_PEX2_AVRRDY")
	)
	(segment
		(start 361.49026 -253.842774)
		(end 361.331002 -253.683516)
		(width 0.13208)
		(layer "F.Cu")
		(net "P0V8_PEX2_AVRRDY")
	)
	(segment
		(start 359.45826 -253.894844)
		(end 359.45826 -254.194564)
		(width 0.13208)
		(layer "F.Cu")
		(net "P0V8_PEX2_AVRRDY")
	)
	(segment
		(start 361.331002 -253.683516)
		(end 361.49026 -253.524258)
		(width 0.13208)
		(layer "F.Cu")
		(net "P0V8_PEX2_AVRRDY")
	)
	(segment
		(start 355.375972 -256.994914)
		(end 356.141782 -256.994914)
		(width 0.13208)
		(layer "F.Cu")
		(net "P0V8_PEX2_AVRRDY")
	)
	(via
		(at 358.075992 -255.060704)
		(size 0.762)
		(drill 0.381)
		(layers "F.Cu" "B.Cu")
		(net "P0V8_PEX2_AVRRDY")
	)
	(segment
		(start 355.470968 -281.567128)
		(end 355.668834 -281.369262)
		(width 0.2286)
		(layer "F.Cu")
		(net "P0V8_PEX3_TSEN")
	)
	(segment
		(start 355.737922 -281.12212)
		(end 355.737922 -280.810208)
		(width 0.2286)
		(layer "F.Cu")
		(net "P0V8_PEX3_TSEN")
	)
	(segment
		(start 355.668834 -281.369262)
		(end 355.737922 -281.12212)
		(width 0.2286)
		(layer "F.Cu")
		(net "P0V8_PEX3_TSEN")
	)
	(segment
		(start 363.63148 -281.567128)
		(end 363.829346 -281.369262)
		(width 0.2286)
		(layer "F.Cu")
		(net "P0V8_PEX3_TSEN")
	)
	(segment
		(start 355.470968 -281.999182)
		(end 355.470968 -281.567128)
		(width 0.2286)
		(layer "F.Cu")
		(net "P0V8_PEX3_TSEN")
	)
	(segment
		(start 363.898434 -281.12212)
		(end 363.898434 -280.810208)
		(width 0.2286)
		(layer "F.Cu")
		(net "P0V8_PEX3_TSEN")
	)
	(segment
		(start 363.829346 -281.369262)
		(end 363.898434 -281.12212)
		(width 0.2286)
		(layer "F.Cu")
		(net "P0V8_PEX3_TSEN")
	)
	(segment
		(start 363.63148 -281.999182)
		(end 363.63148 -281.567128)
		(width 0.2286)
		(layer "F.Cu")
		(net "P0V8_PEX3_TSEN")
	)
	(via
		(at 350.153986 -263.787636)
		(size 0.508)
		(drill 0.254)
		(layers "F.Cu" "B.Cu")
		(net "P0V8_PEX3_TSEN")
	)
	(via
		(at 363.898434 -280.810208)
		(size 0.508)
		(drill 0.254)
		(layers "F.Cu" "B.Cu")
		(net "P0V8_PEX3_TSEN")
	)
	(via
		(at 355.737922 -280.810208)
		(size 0.508)
		(drill 0.254)
		(layers "F.Cu" "B.Cu")
		(net "P0V8_PEX3_TSEN")
	)
	(segment
		(start 350.153986 -260.79577)
		(end 350.619822 -261.261606)
		(width 0.254)
		(layer "B.Cu")
		(net "P0V8_PEX3_TSEN")
	)
	(segment
		(start 350.619822 -261.261606)
		(end 350.619822 -263.3218)
		(width 0.254)
		(layer "B.Cu")
		(net "P0V8_PEX3_TSEN")
	)
	(segment
		(start 350.619822 -263.3218)
		(end 350.153986 -263.787636)
		(width 0.254)
		(layer "B.Cu")
		(net "P0V8_PEX3_TSEN")
	)
	(segment
		(start 356.546658 -278.34336)
		(end 357.344472 -278.34336)
		(width 0.254)
		(layer "In7.Cu")
		(net "P0V8_PEX3_TSEN")
	)
	(segment
		(start 363.158786 -279.38984)
		(end 363.898434 -280.129488)
		(width 0.254)
		(layer "In7.Cu")
		(net "P0V8_PEX3_TSEN")
	)
	(segment
		(start 355.209856 -279.66289)
		(end 351.291906 -279.66289)
		(width 0.254)
		(layer "In7.Cu")
		(net "P0V8_PEX3_TSEN")
	)
	(segment
		(start 363.158786 -278.84501)
		(end 363.158786 -279.38984)
		(width 0.254)
		(layer "In7.Cu")
		(net "P0V8_PEX3_TSEN")
	)
	(segment
		(start 350.153986 -278.52497)
		(end 350.153986 -263.787636)
		(width 0.254)
		(layer "In7.Cu")
		(net "P0V8_PEX3_TSEN")
	)
	(segment
		(start 361.982512 -278.34336)
		(end 362.657136 -278.34336)
		(width 0.254)
		(layer "In7.Cu")
		(net "P0V8_PEX3_TSEN")
	)
	(segment
		(start 356.239064 -278.650954)
		(end 356.546658 -278.34336)
		(width 0.254)
		(layer "In7.Cu")
		(net "P0V8_PEX3_TSEN")
	)
	(segment
		(start 362.657136 -278.34336)
		(end 363.158786 -278.84501)
		(width 0.254)
		(layer "In7.Cu")
		(net "P0V8_PEX3_TSEN")
	)
	(segment
		(start 360.788458 -279.537414)
		(end 361.982512 -278.34336)
		(width 0.254)
		(layer "In7.Cu")
		(net "P0V8_PEX3_TSEN")
	)
	(segment
		(start 355.737922 -280.810208)
		(end 355.737922 -280.190956)
		(width 0.254)
		(layer "In7.Cu")
		(net "P0V8_PEX3_TSEN")
	)
	(segment
		(start 355.737922 -280.190956)
		(end 355.209856 -279.66289)
		(width 0.254)
		(layer "In7.Cu")
		(net "P0V8_PEX3_TSEN")
	)
	(segment
		(start 355.737922 -280.190956)
		(end 356.239064 -279.689814)
		(width 0.254)
		(layer "In7.Cu")
		(net "P0V8_PEX3_TSEN")
	)
	(segment
		(start 356.239064 -279.689814)
		(end 356.239064 -278.650954)
		(width 0.254)
		(layer "In7.Cu")
		(net "P0V8_PEX3_TSEN")
	)
	(segment
		(start 351.291906 -279.66289)
		(end 350.153986 -278.52497)
		(width 0.254)
		(layer "In7.Cu")
		(net "P0V8_PEX3_TSEN")
	)
	(segment
		(start 363.898434 -280.129488)
		(end 363.898434 -280.810208)
		(width 0.254)
		(layer "In7.Cu")
		(net "P0V8_PEX3_TSEN")
	)
	(segment
		(start 357.344472 -278.34336)
		(end 358.538526 -279.537414)
		(width 0.254)
		(layer "In7.Cu")
		(net "P0V8_PEX3_TSEN")
	)
	(segment
		(start 358.538526 -279.537414)
		(end 360.788458 -279.537414)
		(width 0.254)
		(layer "In7.Cu")
		(net "P0V8_PEX3_TSEN")
	)
	(segment
		(start 346.789756 -259.535422)
		(end 347.050614 -259.274564)
		(width 0.254)
		(layer "F.Cu")
		(net "P0V8_PEX2_ADDR")
	)
	(segment
		(start 346.16136 -260.671564)
		(end 346.16136 -259.782564)
		(width 0.254)
		(layer "F.Cu")
		(net "P0V8_PEX2_ADDR")
	)
	(segment
		(start 346.542614 -259.782564)
		(end 346.789756 -259.535422)
		(width 0.254)
		(layer "F.Cu")
		(net "P0V8_PEX2_ADDR")
	)
	(segment
		(start 347.050614 -259.274564)
		(end 347.15831 -259.274564)
		(width 0.254)
		(layer "F.Cu")
		(net "P0V8_PEX2_ADDR")
	)
	(segment
		(start 347.15831 -259.274564)
		(end 349.74403 -259.274564)
		(width 0.1524)
		(layer "F.Cu")
		(net "P0V8_PEX2_ADDR")
	)
	(segment
		(start 346.16136 -259.782564)
		(end 346.542614 -259.782564)
		(width 0.254)
		(layer "F.Cu")
		(net "P0V8_PEX2_ADDR")
	)
	(segment
		(start 349.74403 -259.274564)
		(end 350.023684 -258.99491)
		(width 0.1524)
		(layer "F.Cu")
		(net "P0V8_PEX2_ADDR")
	)
	(segment
		(start 350.023684 -258.99491)
		(end 350.57588 -258.99491)
		(width 0.1524)
		(layer "F.Cu")
		(net "P0V8_PEX2_ADDR")
	)
	(via
		(at 346.789756 -259.535422)
		(size 0.508)
		(drill 0.254)
		(layers "F.Cu" "B.Cu")
		(net "P0V8_PEX2_ADDR")
	)
	(via
		(at 375.769886 18.657824)
		(size 0.508)
		(drill 0.254)
		(layers "F.Cu" "B.Cu")
		(net "COUPON_GND2")
	)
	(via
		(at 337.435952 16.947388)
		(size 0.508)
		(drill 0.254)
		(layers "F.Cu" "B.Cu")
		(net "COUPON_GND2")
	)
	(via
		(at 402.082 20.323556)
		(size 0.508)
		(drill 0.254)
		(layers "F.Cu" "B.Cu")
		(net "COUPON_GND2")
	)
	(via
		(at 182.499 8.46328)
		(size 0.508)
		(drill 0.254)
		(layers "F.Cu" "B.Cu")
		(net "COUPON_GND2")
	)
	(via
		(at 338.262214 19.025616)
		(size 0.508)
		(drill 0.254)
		(layers "F.Cu" "B.Cu")
		(net "COUPON_GND2")
	)
	(via
		(at 313.351418 6.73989)
		(size 0.508)
		(drill 0.254)
		(layers "F.Cu" "B.Cu")
		(net "COUPON_GND2")
	)
	(via
		(at 310.618886 17.399)
		(size 0.508)
		(drill 0.254)
		(layers "F.Cu" "B.Cu")
		(net "COUPON_GND2")
	)
	(via
		(at 212.979762 19.73707)
		(size 0.508)
		(drill 0.254)
		(layers "F.Cu" "B.Cu")
		(net "COUPON_GND2")
	)
	(via
		(at 340.406482 17.406112)
		(size 0.508)
		(drill 0.254)
		(layers "F.Cu" "B.Cu")
		(net "COUPON_GND2")
	)
	(via
		(at 212.975952 16.972788)
		(size 0.508)
		(drill 0.254)
		(layers "F.Cu" "B.Cu")
		(net "COUPON_GND2")
	)
	(via
		(at 257.475482 7.454392)
		(size 0.508)
		(drill 0.254)
		(layers "F.Cu" "B.Cu")
		(net "COUPON_GND2")
	)
	(via
		(at 254.508 11.006836)
		(size 0.508)
		(drill 0.254)
		(layers "F.Cu" "B.Cu")
		(net "COUPON_GND2")
	)
	(via
		(at 255.331214 9.073896)
		(size 0.508)
		(drill 0.254)
		(layers "F.Cu" "B.Cu")
		(net "COUPON_GND2")
	)
	(via
		(at 311.97931 8.739124)
		(size 0.508)
		(drill 0.254)
		(layers "F.Cu" "B.Cu")
		(net "COUPON_GND2")
	)
	(via
		(at 402.509482 11.319256)
		(size 0.508)
		(drill 0.254)
		(layers "F.Cu" "B.Cu")
		(net "COUPON_GND2")
	)
	(via
		(at 402.082762 22.280626)
		(size 0.508)
		(drill 0.254)
		(layers "F.Cu" "B.Cu")
		(net "COUPON_GND2")
	)
	(via
		(at 377.910344 18.93951)
		(size 0.508)
		(drill 0.254)
		(layers "F.Cu" "B.Cu")
		(net "COUPON_GND2")
	)
	(via
		(at 328.102214 7.025132)
		(size 0.508)
		(drill 0.254)
		(layers "F.Cu" "B.Cu")
		(net "COUPON_GND2")
	)
	(via
		(at 440.412886 18.657824)
		(size 0.508)
		(drill 0.254)
		(layers "F.Cu" "B.Cu")
		(net "COUPON_GND2")
	)
	(via
		(at 440.412886 17.399)
		(size 0.508)
		(drill 0.254)
		(layers "F.Cu" "B.Cu")
		(net "COUPON_GND2")
	)
	(via
		(at 399.538952 11.756136)
		(size 0.508)
		(drill 0.254)
		(layers "F.Cu" "B.Cu")
		(net "COUPON_GND2")
	)
	(via
		(at 273.883374 19.329146)
		(size 0.508)
		(drill 0.254)
		(layers "F.Cu" "B.Cu")
		(net "COUPON_GND2")
	)
	(via
		(at 242.937792 8.433816)
		(size 0.508)
		(drill 0.254)
		(layers "F.Cu" "B.Cu")
		(net "COUPON_GND2")
	)
	(via
		(at 339.034374 16.640302)
		(size 0.508)
		(drill 0.254)
		(layers "F.Cu" "B.Cu")
		(net "COUPON_GND2")
	)
	(via
		(at 327.279 11.039856)
		(size 0.508)
		(drill 0.254)
		(layers "F.Cu" "B.Cu")
		(net "COUPON_GND2")
	)
	(via
		(at 337.439762 16.308578)
		(size 0.508)
		(drill 0.254)
		(layers "F.Cu" "B.Cu")
		(net "COUPON_GND2")
	)
	(via
		(at 338.262214 21.66366)
		(size 0.508)
		(drill 0.254)
		(layers "F.Cu" "B.Cu")
		(net "COUPON_GND2")
	)
	(via
		(at 375.769886 21.197824)
		(size 0.508)
		(drill 0.254)
		(layers "F.Cu" "B.Cu")
		(net "COUPON_GND2")
	)
	(via
		(at 248.421144 19.733514)
		(size 0.508)
		(drill 0.254)
		(layers "F.Cu" "B.Cu")
		(net "COUPON_GND2")
	)
	(via
		(at 338.262214 16.943832)
		(size 0.508)
		(drill 0.254)
		(layers "F.Cu" "B.Cu")
		(net "COUPON_GND2")
	)
	(via
		(at 213.806024 16.330422)
		(size 0.508)
		(drill 0.254)
		(layers "F.Cu" "B.Cu")
		(net "COUPON_GND2")
	)
	(via
		(at 328.106024 12.361926)
		(size 0.508)
		(drill 0.254)
		(layers "F.Cu" "B.Cu")
		(net "COUPON_GND2")
	)
	(via
		(at 242.114578 7.0104)
		(size 0.508)
		(drill 0.254)
		(layers "F.Cu" "B.Cu")
		(net "COUPON_GND2")
	)
	(via
		(at 273.115024 16.330422)
		(size 0.508)
		(drill 0.254)
		(layers "F.Cu" "B.Cu")
		(net "COUPON_GND2")
	)
	(via
		(at 249.248168 17.648936)
		(size 0.508)
		(drill 0.254)
		(layers "F.Cu" "B.Cu")
		(net "COUPON_GND2")
	)
	(via
		(at 241.342418 9.446514)
		(size 0.508)
		(drill 0.254)
		(layers "F.Cu" "B.Cu")
		(net "COUPON_GND2")
	)
	(via
		(at 442.557154 19.57832)
		(size 0.508)
		(drill 0.254)
		(layers "F.Cu" "B.Cu")
		(net "COUPON_GND2")
	)
	(via
		(at 403.677374 21.945346)
		(size 0.508)
		(drill 0.254)
		(layers "F.Cu" "B.Cu")
		(net "COUPON_GND2")
	)
	(via
		(at 313.589416 21.656548)
		(size 0.508)
		(drill 0.254)
		(layers "F.Cu" "B.Cu")
		(net "COUPON_GND2")
	)
	(via
		(at 275.255482 21.204936)
		(size 0.508)
		(drill 0.254)
		(layers "F.Cu" "B.Cu")
		(net "COUPON_GND2")
	)
	(via
		(at 314.94984 9.663176)
		(size 0.508)
		(drill 0.254)
		(layers "F.Cu" "B.Cu")
		(net "COUPON_GND2")
	)
	(via
		(at 330.246482 7.487412)
		(size 0.508)
		(drill 0.254)
		(layers "F.Cu" "B.Cu")
		(net "COUPON_GND2")
	)
	(via
		(at 273.883374 16.665702)
		(size 0.508)
		(drill 0.254)
		(layers "F.Cu" "B.Cu")
		(net "COUPON_GND2")
	)
	(via
		(at 405.049482 17.406112)
		(size 0.508)
		(drill 0.254)
		(layers "F.Cu" "B.Cu")
		(net "COUPON_GND2")
	)
	(via
		(at 242.110768 6.37159)
		(size 0.508)
		(drill 0.254)
		(layers "F.Cu" "B.Cu")
		(net "COUPON_GND2")
	)
	(via
		(at 254.508 10.371836)
		(size 0.508)
		(drill 0.254)
		(layers "F.Cu" "B.Cu")
		(net "COUPON_GND2")
	)
	(via
		(at 441.784994 19.27479)
		(size 0.508)
		(drill 0.254)
		(layers "F.Cu" "B.Cu")
		(net "COUPON_GND2")
	)
	(via
		(at 378.740416 19.581876)
		(size 0.508)
		(drill 0.254)
		(layers "F.Cu" "B.Cu")
		(net "COUPON_GND2")
	)
	(via
		(at 443.379606 16.32331)
		(size 0.508)
		(drill 0.254)
		(layers "F.Cu" "B.Cu")
		(net "COUPON_GND2")
	)
	(via
		(at 272.288 20.9804)
		(size 0.508)
		(drill 0.254)
		(layers "F.Cu" "B.Cu")
		(net "COUPON_GND2")
	)
	(via
		(at 387.72084 11.770868)
		(size 0.508)
		(drill 0.254)
		(layers "F.Cu" "B.Cu")
		(net "COUPON_GND2")
	)
	(via
		(at 378.736606 18.943066)
		(size 0.508)
		(drill 0.254)
		(layers "F.Cu" "B.Cu")
		(net "COUPON_GND2")
	)
	(via
		(at 311.990994 19.27479)
		(size 0.508)
		(drill 0.254)
		(layers "F.Cu" "B.Cu")
		(net "COUPON_GND2")
	)
	(via
		(at 212.979 18.415)
		(size 0.508)
		(drill 0.254)
		(layers "F.Cu" "B.Cu")
		(net "COUPON_GND2")
	)
	(via
		(at 386.122418 6.77291)
		(size 0.508)
		(drill 0.254)
		(layers "F.Cu" "B.Cu")
		(net "COUPON_GND2")
	)
	(via
		(at 386.890768 6.43763)
		(size 0.508)
		(drill 0.254)
		(layers "F.Cu" "B.Cu")
		(net "COUPON_GND2")
	)
	(via
		(at 337.435952 19.02206)
		(size 0.508)
		(drill 0.254)
		(layers "F.Cu" "B.Cu")
		(net "COUPON_GND2")
	)
	(via
		(at 401.137374 9.443466)
		(size 0.508)
		(drill 0.254)
		(layers "F.Cu" "B.Cu")
		(net "COUPON_GND2")
	)
	(via
		(at 377.914154 19.57832)
		(size 0.508)
		(drill 0.254)
		(layers "F.Cu" "B.Cu")
		(net "COUPON_GND2")
	)
	(via
		(at 183.326024 9.788906)
		(size 0.508)
		(drill 0.254)
		(layers "F.Cu" "B.Cu")
		(net "COUPON_GND2")
	)
	(via
		(at 328.874374 12.026646)
		(size 0.508)
		(drill 0.254)
		(layers "F.Cu" "B.Cu")
		(net "COUPON_GND2")
	)
	(via
		(at 405.049482 19.946112)
		(size 0.508)
		(drill 0.254)
		(layers "F.Cu" "B.Cu")
		(net "COUPON_GND2")
	)
	(via
		(at 378.740416 16.96212)
		(size 0.508)
		(drill 0.254)
		(layers "F.Cu" "B.Cu")
		(net "COUPON_GND2")
	)
	(via
		(at 386.890768 12.409678)
		(size 0.508)
		(drill 0.254)
		(layers "F.Cu" "B.Cu")
		(net "COUPON_GND2")
	)
	(via
		(at 312.759344 16.32331)
		(size 0.508)
		(drill 0.254)
		(layers "F.Cu" "B.Cu")
		(net "COUPON_GND2")
	)
	(via
		(at 272.284952 19.02206)
		(size 0.508)
		(drill 0.254)
		(layers "F.Cu" "B.Cu")
		(net "COUPON_GND2")
	)
	(via
		(at 255.331214 11.690096)
		(size 0.508)
		(drill 0.254)
		(layers "F.Cu" "B.Cu")
		(net "COUPON_GND2")
	)
	(via
		(at 272.288 18.288)
		(size 0.508)
		(drill 0.254)
		(layers "F.Cu" "B.Cu")
		(net "COUPON_GND2")
	)
	(via
		(at 272.288 20.3454)
		(size 0.508)
		(drill 0.254)
		(layers "F.Cu" "B.Cu")
		(net "COUPON_GND2")
	)
	(via
		(at 443.380368 20.976336)
		(size 0.508)
		(drill 0.254)
		(layers "F.Cu" "B.Cu")
		(net "COUPON_GND2")
	)
	(via
		(at 400.369024 9.778746)
		(size 0.508)
		(drill 0.254)
		(layers "F.Cu" "B.Cu")
		(net "COUPON_GND2")
	)
	(via
		(at 328.874374 9.410446)
		(size 0.508)
		(drill 0.254)
		(layers "F.Cu" "B.Cu")
		(net "COUPON_GND2")
	)
	(via
		(at 242.937792 7.697216)
		(size 0.508)
		(drill 0.254)
		(layers "F.Cu" "B.Cu")
		(net "COUPON_GND2")
	)
	(via
		(at 399.542 10.437876)
		(size 0.508)
		(drill 0.254)
		(layers "F.Cu" "B.Cu")
		(net "COUPON_GND2")
	)
	(via
		(at 313.351418 12.044934)
		(size 0.508)
		(drill 0.254)
		(layers "F.Cu" "B.Cu")
		(net "COUPON_GND2")
	)
	(via
		(at 212.975952 19.09826)
		(size 0.508)
		(drill 0.254)
		(layers "F.Cu" "B.Cu")
		(net "COUPON_GND2")
	)
	(via
		(at 248.424954 16.96212)
		(size 0.508)
		(drill 0.254)
		(layers "F.Cu" "B.Cu")
		(net "COUPON_GND2")
	)
	(via
		(at 275.255482 19.946112)
		(size 0.508)
		(drill 0.254)
		(layers "F.Cu" "B.Cu")
		(net "COUPON_GND2")
	)
	(via
		(at 311.990994 16.65859)
		(size 0.508)
		(drill 0.254)
		(layers "F.Cu" "B.Cu")
		(net "COUPON_GND2")
	)
	(via
		(at 242.93703 9.778238)
		(size 0.508)
		(drill 0.254)
		(layers "F.Cu" "B.Cu")
		(net "COUPON_GND2")
	)
	(via
		(at 387.717792 8.3947)
		(size 0.508)
		(drill 0.254)
		(layers "F.Cu" "B.Cu")
		(net "COUPON_GND2")
	)
	(via
		(at 402.078952 21.641816)
		(size 0.508)
		(drill 0.254)
		(layers "F.Cu" "B.Cu")
		(net "COUPON_GND2")
	)
	(via
		(at 402.909024 22.280626)
		(size 0.508)
		(drill 0.254)
		(layers "F.Cu" "B.Cu")
		(net "COUPON_GND2")
	)
	(via
		(at 402.909024 16.308578)
		(size 0.508)
		(drill 0.254)
		(layers "F.Cu" "B.Cu")
		(net "COUPON_GND2")
	)
	(via
		(at 330.246482 8.746236)
		(size 0.508)
		(drill 0.254)
		(layers "F.Cu" "B.Cu")
		(net "COUPON_GND2")
	)
	(via
		(at 182.499762 9.78535)
		(size 0.508)
		(drill 0.254)
		(layers "F.Cu" "B.Cu")
		(net "COUPON_GND2")
	)
	(via
		(at 337.439 20.3454)
		(size 0.508)
		(drill 0.254)
		(layers "F.Cu" "B.Cu")
		(net "COUPON_GND2")
	)
	(via
		(at 459.153768 6.47065)
		(size 0.508)
		(drill 0.254)
		(layers "F.Cu" "B.Cu")
		(net "COUPON_GND2")
	)
	(via
		(at 313.586368 18.28038)
		(size 0.508)
		(drill 0.254)
		(layers "F.Cu" "B.Cu")
		(net "COUPON_GND2")
	)
	(via
		(at 184.094374 9.453626)
		(size 0.508)
		(drill 0.254)
		(layers "F.Cu" "B.Cu")
		(net "COUPON_GND2")
	)
	(via
		(at 402.509482 7.520432)
		(size 0.508)
		(drill 0.254)
		(layers "F.Cu" "B.Cu")
		(net "COUPON_GND2")
	)
	(via
		(at 378.737368 18.28038)
		(size 0.508)
		(drill 0.254)
		(layers "F.Cu" "B.Cu")
		(net "COUPON_GND2")
	)
	(via
		(at 402.905214 16.947388)
		(size 0.508)
		(drill 0.254)
		(layers "F.Cu" "B.Cu")
		(net "COUPON_GND2")
	)
	(via
		(at 387.71703 6.43763)
		(size 0.508)
		(drill 0.254)
		(layers "F.Cu" "B.Cu")
		(net "COUPON_GND2")
	)
	(via
		(at 459.980792 11.123676)
		(size 0.508)
		(drill 0.254)
		(layers "F.Cu" "B.Cu")
		(net "COUPON_GND2")
	)
	(via
		(at 254.508762 6.356858)
		(size 0.508)
		(drill 0.254)
		(layers "F.Cu" "B.Cu")
		(net "COUPON_GND2")
	)
	(via
		(at 386.894578 7.07644)
		(size 0.508)
		(drill 0.254)
		(layers "F.Cu" "B.Cu")
		(net "COUPON_GND2")
	)
	(via
		(at 242.94084 7.013956)
		(size 0.508)
		(drill 0.254)
		(layers "F.Cu" "B.Cu")
		(net "COUPON_GND2")
	)
	(via
		(at 242.114578 9.142984)
		(size 0.508)
		(drill 0.254)
		(layers "F.Cu" "B.Cu")
		(net "COUPON_GND2")
	)
	(via
		(at 255.335024 6.378702)
		(size 0.508)
		(drill 0.254)
		(layers "F.Cu" "B.Cu")
		(net "COUPON_GND2")
	)
	(via
		(at 338.266024 19.664426)
		(size 0.508)
		(drill 0.254)
		(layers "F.Cu" "B.Cu")
		(net "COUPON_GND2")
	)
	(via
		(at 249.248168 18.385536)
		(size 0.508)
		(drill 0.254)
		(layers "F.Cu" "B.Cu")
		(net "COUPON_GND2")
	)
	(via
		(at 310.618886 18.657824)
		(size 0.508)
		(drill 0.254)
		(layers "F.Cu" "B.Cu")
		(net "COUPON_GND2")
	)
	(via
		(at 273.115024 19.664426)
		(size 0.508)
		(drill 0.254)
		(layers "F.Cu" "B.Cu")
		(net "COUPON_GND2")
	)
	(via
		(at 377.910344 16.32331)
		(size 0.508)
		(drill 0.254)
		(layers "F.Cu" "B.Cu")
		(net "COUPON_GND2")
	)
	(via
		(at 312.759344 18.93951)
		(size 0.508)
		(drill 0.254)
		(layers "F.Cu" "B.Cu")
		(net "COUPON_GND2")
	)
	(via
		(at 405.049482 21.204936)
		(size 0.508)
		(drill 0.254)
		(layers "F.Cu" "B.Cu")
		(net "COUPON_GND2")
	)
	(via
		(at 254.508 7.65048)
		(size 0.508)
		(drill 0.254)
		(layers "F.Cu" "B.Cu")
		(net "COUPON_GND2")
	)
	(via
		(at 330.246482 10.027412)
		(size 0.508)
		(drill 0.254)
		(layers "F.Cu" "B.Cu")
		(net "COUPON_GND2")
	)
	(via
		(at 400.369024 6.419342)
		(size 0.508)
		(drill 0.254)
		(layers "F.Cu" "B.Cu")
		(net "COUPON_GND2")
	)
	(via
		(at 313.586368 20.315936)
		(size 0.508)
		(drill 0.254)
		(layers "F.Cu" "B.Cu")
		(net "COUPON_GND2")
	)
	(via
		(at 249.251216 19.091148)
		(size 0.508)
		(drill 0.254)
		(layers "F.Cu" "B.Cu")
		(net "COUPON_GND2")
	)
	(via
		(at 457.01331 7.54634)
		(size 0.508)
		(drill 0.254)
		(layers "F.Cu" "B.Cu")
		(net "COUPON_GND2")
	)
	(via
		(at 459.98003 9.090406)
		(size 0.508)
		(drill 0.254)
		(layers "F.Cu" "B.Cu")
		(net "COUPON_GND2")
	)
	(via
		(at 272.288 17.6276)
		(size 0.508)
		(drill 0.254)
		(layers "F.Cu" "B.Cu")
		(net "COUPON_GND2")
	)
	(via
		(at 313.585606 16.32331)
		(size 0.508)
		(drill 0.254)
		(layers "F.Cu" "B.Cu")
		(net "COUPON_GND2")
	)
	(via
		(at 328.102214 9.106916)
		(size 0.508)
		(drill 0.254)
		(layers "F.Cu" "B.Cu")
		(net "COUPON_GND2")
	)
	(via
		(at 399.542 7.74192)
		(size 0.508)
		(drill 0.254)
		(layers "F.Cu" "B.Cu")
		(net "COUPON_GND2")
	)
	(via
		(at 330.246482 11.286236)
		(size 0.508)
		(drill 0.254)
		(layers "F.Cu" "B.Cu")
		(net "COUPON_GND2")
	)
	(via
		(at 384.75031 11.312144)
		(size 0.508)
		(drill 0.254)
		(layers "F.Cu" "B.Cu")
		(net "COUPON_GND2")
	)
	(via
		(at 402.509482 8.779256)
		(size 0.508)
		(drill 0.254)
		(layers "F.Cu" "B.Cu")
		(net "COUPON_GND2")
	)
	(via
		(at 247.652794 19.398234)
		(size 0.508)
		(drill 0.254)
		(layers "F.Cu" "B.Cu")
		(net "COUPON_GND2")
	)
	(via
		(at 402.082762 16.308578)
		(size 0.508)
		(drill 0.254)
		(layers "F.Cu" "B.Cu")
		(net "COUPON_GND2")
	)
	(via
		(at 377.910344 22.295358)
		(size 0.508)
		(drill 0.254)
		(layers "F.Cu" "B.Cu")
		(net "COUPON_GND2")
	)
	(via
		(at 182.499 7.72668)
		(size 0.508)
		(drill 0.254)
		(layers "F.Cu" "B.Cu")
		(net "COUPON_GND2")
	)
	(via
		(at 254.508762 12.328906)
		(size 0.508)
		(drill 0.254)
		(layers "F.Cu" "B.Cu")
		(net "COUPON_GND2")
	)
	(via
		(at 310.618886 19.939)
		(size 0.508)
		(drill 0.254)
		(layers "F.Cu" "B.Cu")
		(net "COUPON_GND2")
	)
	(via
		(at 443.380368 17.64538)
		(size 0.508)
		(drill 0.254)
		(layers "F.Cu" "B.Cu")
		(net "COUPON_GND2")
	)
	(via
		(at 213.806024 19.740626)
		(size 0.508)
		(drill 0.254)
		(layers "F.Cu" "B.Cu")
		(net "COUPON_GND2")
	)
	(via
		(at 399.542762 12.394946)
		(size 0.508)
		(drill 0.254)
		(layers "F.Cu" "B.Cu")
		(net "COUPON_GND2")
	)
	(via
		(at 386.122418 9.38911)
		(size 0.508)
		(drill 0.254)
		(layers "F.Cu" "B.Cu")
		(net "COUPON_GND2")
	)
	(via
		(at 182.495952 9.14654)
		(size 0.508)
		(drill 0.254)
		(layers "F.Cu" "B.Cu")
		(net "COUPON_GND2")
	)
	(via
		(at 338.266024 16.305022)
		(size 0.508)
		(drill 0.254)
		(layers "F.Cu" "B.Cu")
		(net "COUPON_GND2")
	)
	(via
		(at 327.279762 6.389878)
		(size 0.508)
		(drill 0.254)
		(layers "F.Cu" "B.Cu")
		(net "COUPON_GND2")
	)
	(via
		(at 459.980792 10.463276)
		(size 0.508)
		(drill 0.254)
		(layers "F.Cu" "B.Cu")
		(net "COUPON_GND2")
	)
	(via
		(at 440.412886 21.197824)
		(size 0.508)
		(drill 0.254)
		(layers "F.Cu" "B.Cu")
		(net "COUPON_GND2")
	)
	(via
		(at 272.284952 16.947388)
		(size 0.508)
		(drill 0.254)
		(layers "F.Cu" "B.Cu")
		(net "COUPON_GND2")
	)
	(via
		(at 328.102214 11.723116)
		(size 0.508)
		(drill 0.254)
		(layers "F.Cu" "B.Cu")
		(net "COUPON_GND2")
	)
	(via
		(at 337.439762 22.30247)
		(size 0.508)
		(drill 0.254)
		(layers "F.Cu" "B.Cu")
		(net "COUPON_GND2")
	)
	(via
		(at 340.406482 21.204936)
		(size 0.508)
		(drill 0.254)
		(layers "F.Cu" "B.Cu")
		(net "COUPON_GND2")
	)
	(via
		(at 313.589416 19.581876)
		(size 0.508)
		(drill 0.254)
		(layers "F.Cu" "B.Cu")
		(net "COUPON_GND2")
	)
	(via
		(at 213.802214 16.969232)
		(size 0.508)
		(drill 0.254)
		(layers "F.Cu" "B.Cu")
		(net "COUPON_GND2")
	)
	(via
		(at 441.784994 21.938234)
		(size 0.508)
		(drill 0.254)
		(layers "F.Cu" "B.Cu")
		(net "COUPON_GND2")
	)
	(via
		(at 312.763154 16.96212)
		(size 0.508)
		(drill 0.254)
		(layers "F.Cu" "B.Cu")
		(net "COUPON_GND2")
	)
	(via
		(at 327.279 8.3693)
		(size 0.508)
		(drill 0.254)
		(layers "F.Cu" "B.Cu")
		(net "COUPON_GND2")
	)
	(via
		(at 248.424954 19.094704)
		(size 0.508)
		(drill 0.254)
		(layers "F.Cu" "B.Cu")
		(net "COUPON_GND2")
	)
	(via
		(at 337.439 18.288)
		(size 0.508)
		(drill 0.254)
		(layers "F.Cu" "B.Cu")
		(net "COUPON_GND2")
	)
	(via
		(at 378.737368 20.976336)
		(size 0.508)
		(drill 0.254)
		(layers "F.Cu" "B.Cu")
		(net "COUPON_GND2")
	)
	(via
		(at 337.439 17.6276)
		(size 0.508)
		(drill 0.254)
		(layers "F.Cu" "B.Cu")
		(net "COUPON_GND2")
	)
	(via
		(at 457.01331 8.805164)
		(size 0.508)
		(drill 0.254)
		(layers "F.Cu" "B.Cu")
		(net "COUPON_GND2")
	)
	(via
		(at 313.585606 22.295358)
		(size 0.508)
		(drill 0.254)
		(layers "F.Cu" "B.Cu")
		(net "COUPON_GND2")
	)
	(via
		(at 458.385418 9.42213)
		(size 0.508)
		(drill 0.254)
		(layers "F.Cu" "B.Cu")
		(net "COUPON_GND2")
	)
	(via
		(at 378.737368 20.315936)
		(size 0.508)
		(drill 0.254)
		(layers "F.Cu" "B.Cu")
		(net "COUPON_GND2")
	)
	(via
		(at 249.247406 16.326866)
		(size 0.508)
		(drill 0.254)
		(layers "F.Cu" "B.Cu")
		(net "COUPON_GND2")
	)
	(via
		(at 443.379606 22.295358)
		(size 0.508)
		(drill 0.254)
		(layers "F.Cu" "B.Cu")
		(net "COUPON_GND2")
	)
	(via
		(at 311.97931 10.0203)
		(size 0.508)
		(drill 0.254)
		(layers "F.Cu" "B.Cu")
		(net "COUPON_GND2")
	)
	(via
		(at 387.71703 9.057386)
		(size 0.508)
		(drill 0.254)
		(layers "F.Cu" "B.Cu")
		(net "COUPON_GND2")
	)
	(via
		(at 312.763154 21.634704)
		(size 0.508)
		(drill 0.254)
		(layers "F.Cu" "B.Cu")
		(net "COUPON_GND2")
	)
	(via
		(at 387.717792 10.430256)
		(size 0.508)
		(drill 0.254)
		(layers "F.Cu" "B.Cu")
		(net "COUPON_GND2")
	)
	(via
		(at 400.369024 12.394946)
		(size 0.508)
		(drill 0.254)
		(layers "F.Cu" "B.Cu")
		(net "COUPON_GND2")
	)
	(via
		(at 442.553344 18.93951)
		(size 0.508)
		(drill 0.254)
		(layers "F.Cu" "B.Cu")
		(net "COUPON_GND2")
	)
	(via
		(at 314.123578 11.737848)
		(size 0.508)
		(drill 0.254)
		(layers "F.Cu" "B.Cu")
		(net "COUPON_GND2")
	)
	(via
		(at 375.769886 19.939)
		(size 0.508)
		(drill 0.254)
		(layers "F.Cu" "B.Cu")
		(net "COUPON_GND2")
	)
	(via
		(at 311.97931 7.4803)
		(size 0.508)
		(drill 0.254)
		(layers "F.Cu" "B.Cu")
		(net "COUPON_GND2")
	)
	(via
		(at 402.082762 19.66087)
		(size 0.508)
		(drill 0.254)
		(layers "F.Cu" "B.Cu")
		(net "COUPON_GND2")
	)
	(via
		(at 459.157578 7.10946)
		(size 0.508)
		(drill 0.254)
		(layers "F.Cu" "B.Cu")
		(net "COUPON_GND2")
	)
	(via
		(at 183.322214 7.017512)
		(size 0.508)
		(drill 0.254)
		(layers "F.Cu" "B.Cu")
		(net "COUPON_GND2")
	)
	(via
		(at 272.288762 22.30247)
		(size 0.508)
		(drill 0.254)
		(layers "F.Cu" "B.Cu")
		(net "COUPON_GND2")
	)
	(via
		(at 327.275952 7.028688)
		(size 0.508)
		(drill 0.254)
		(layers "F.Cu" "B.Cu")
		(net "COUPON_GND2")
	)
	(via
		(at 327.275952 11.723116)
		(size 0.508)
		(drill 0.254)
		(layers "F.Cu" "B.Cu")
		(net "COUPON_GND2")
	)
	(via
		(at 405.049482 18.664936)
		(size 0.508)
		(drill 0.254)
		(layers "F.Cu" "B.Cu")
		(net "COUPON_GND2")
	)
	(via
		(at 399.542762 9.77519)
		(size 0.508)
		(drill 0.254)
		(layers "F.Cu" "B.Cu")
		(net "COUPON_GND2")
	)
	(via
		(at 402.082 17.6276)
		(size 0.508)
		(drill 0.254)
		(layers "F.Cu" "B.Cu")
		(net "COUPON_GND2")
	)
	(via
		(at 313.351418 9.35609)
		(size 0.508)
		(drill 0.254)
		(layers "F.Cu" "B.Cu")
		(net "COUPON_GND2")
	)
	(via
		(at 377.141994 16.65859)
		(size 0.508)
		(drill 0.254)
		(layers "F.Cu" "B.Cu")
		(net "COUPON_GND2")
	)
	(via
		(at 340.406482 19.946112)
		(size 0.508)
		(drill 0.254)
		(layers "F.Cu" "B.Cu")
		(net "COUPON_GND2")
	)
	(via
		(at 313.585606 18.943066)
		(size 0.508)
		(drill 0.254)
		(layers "F.Cu" "B.Cu")
		(net "COUPON_GND2")
	)
	(via
		(at 338.266024 22.30247)
		(size 0.508)
		(drill 0.254)
		(layers "F.Cu" "B.Cu")
		(net "COUPON_GND2")
	)
	(via
		(at 247.652794 16.65859)
		(size 0.508)
		(drill 0.254)
		(layers "F.Cu" "B.Cu")
		(net "COUPON_GND2")
	)
	(via
		(at 402.909024 19.664426)
		(size 0.508)
		(drill 0.254)
		(layers "F.Cu" "B.Cu")
		(net "COUPON_GND2")
	)
	(via
		(at 254.508 8.31088)
		(size 0.508)
		(drill 0.254)
		(layers "F.Cu" "B.Cu")
		(net "COUPON_GND2")
	)
	(via
		(at 183.326024 6.378702)
		(size 0.508)
		(drill 0.254)
		(layers "F.Cu" "B.Cu")
		(net "COUPON_GND2")
	)
	(via
		(at 402.905214 19.025616)
		(size 0.508)
		(drill 0.254)
		(layers "F.Cu" "B.Cu")
		(net "COUPON_GND2")
	)
	(via
		(at 400.365214 11.756136)
		(size 0.508)
		(drill 0.254)
		(layers "F.Cu" "B.Cu")
		(net "COUPON_GND2")
	)
	(via
		(at 257.475482 11.253216)
		(size 0.508)
		(drill 0.254)
		(layers "F.Cu" "B.Cu")
		(net "COUPON_GND2")
	)
	(via
		(at 314.94984 11.737848)
		(size 0.508)
		(drill 0.254)
		(layers "F.Cu" "B.Cu")
		(net "COUPON_GND2")
	)
	(via
		(at 212.979 17.6784)
		(size 0.508)
		(drill 0.254)
		(layers "F.Cu" "B.Cu")
		(net "COUPON_GND2")
	)
	(via
		(at 457.01331 10.08634)
		(size 0.508)
		(drill 0.254)
		(layers "F.Cu" "B.Cu")
		(net "COUPON_GND2")
	)
	(via
		(at 442.557154 16.96212)
		(size 0.508)
		(drill 0.254)
		(layers "F.Cu" "B.Cu")
		(net "COUPON_GND2")
	)
	(via
		(at 457.01331 11.345164)
		(size 0.508)
		(drill 0.254)
		(layers "F.Cu" "B.Cu")
		(net "COUPON_GND2")
	)
	(via
		(at 386.894578 11.770868)
		(size 0.508)
		(drill 0.254)
		(layers "F.Cu" "B.Cu")
		(net "COUPON_GND2")
	)
	(via
		(at 378.740416 21.656548)
		(size 0.508)
		(drill 0.254)
		(layers "F.Cu" "B.Cu")
		(net "COUPON_GND2")
	)
	(via
		(at 314.946792 10.397236)
		(size 0.508)
		(drill 0.254)
		(layers "F.Cu" "B.Cu")
		(net "COUPON_GND2")
	)
	(via
		(at 377.914154 21.656548)
		(size 0.508)
		(drill 0.254)
		(layers "F.Cu" "B.Cu")
		(net "COUPON_GND2")
	)
	(via
		(at 441.784994 16.65859)
		(size 0.508)
		(drill 0.254)
		(layers "F.Cu" "B.Cu")
		(net "COUPON_GND2")
	)
	(via
		(at 377.141994 21.938234)
		(size 0.508)
		(drill 0.254)
		(layers "F.Cu" "B.Cu")
		(net "COUPON_GND2")
	)
	(via
		(at 328.106024 6.386322)
		(size 0.508)
		(drill 0.254)
		(layers "F.Cu" "B.Cu")
		(net "COUPON_GND2")
	)
	(via
		(at 443.383416 21.656548)
		(size 0.508)
		(drill 0.254)
		(layers "F.Cu" "B.Cu")
		(net "COUPON_GND2")
	)
	(via
		(at 401.137374 6.780022)
		(size 0.508)
		(drill 0.254)
		(layers "F.Cu" "B.Cu")
		(net "COUPON_GND2")
	)
	(via
		(at 402.082 20.958556)
		(size 0.508)
		(drill 0.254)
		(layers "F.Cu" "B.Cu")
		(net "COUPON_GND2")
	)
	(via
		(at 182.499762 6.382258)
		(size 0.508)
		(drill 0.254)
		(layers "F.Cu" "B.Cu")
		(net "COUPON_GND2")
	)
	(via
		(at 402.509482 10.060432)
		(size 0.508)
		(drill 0.254)
		(layers "F.Cu" "B.Cu")
		(net "COUPON_GND2")
	)
	(via
		(at 400.365214 9.139936)
		(size 0.508)
		(drill 0.254)
		(layers "F.Cu" "B.Cu")
		(net "COUPON_GND2")
	)
	(via
		(at 314.119768 12.376658)
		(size 0.508)
		(drill 0.254)
		(layers "F.Cu" "B.Cu")
		(net "COUPON_GND2")
	)
	(via
		(at 459.98384 9.729216)
		(size 0.508)
		(drill 0.254)
		(layers "F.Cu" "B.Cu")
		(net "COUPON_GND2")
	)
	(via
		(at 378.737368 17.64538)
		(size 0.508)
		(drill 0.254)
		(layers "F.Cu" "B.Cu")
		(net "COUPON_GND2")
	)
	(via
		(at 272.288762 16.308578)
		(size 0.508)
		(drill 0.254)
		(layers "F.Cu" "B.Cu")
		(net "COUPON_GND2")
	)
	(via
		(at 399.538952 7.061708)
		(size 0.508)
		(drill 0.254)
		(layers "F.Cu" "B.Cu")
		(net "COUPON_GND2")
	)
	(via
		(at 399.538952 9.13638)
		(size 0.508)
		(drill 0.254)
		(layers "F.Cu" "B.Cu")
		(net "COUPON_GND2")
	)
	(via
		(at 327.275952 9.10336)
		(size 0.508)
		(drill 0.254)
		(layers "F.Cu" "B.Cu")
		(net "COUPON_GND2")
	)
	(via
		(at 402.078952 16.947388)
		(size 0.508)
		(drill 0.254)
		(layers "F.Cu" "B.Cu")
		(net "COUPON_GND2")
	)
	(via
		(at 399.542 8.40232)
		(size 0.508)
		(drill 0.254)
		(layers "F.Cu" "B.Cu")
		(net "COUPON_GND2")
	)
	(via
		(at 314.94603 9.024366)
		(size 0.508)
		(drill 0.254)
		(layers "F.Cu" "B.Cu")
		(net "COUPON_GND2")
	)
	(via
		(at 311.97931 11.279124)
		(size 0.508)
		(drill 0.254)
		(layers "F.Cu" "B.Cu")
		(net "COUPON_GND2")
	)
	(via
		(at 257.475482 8.713216)
		(size 0.508)
		(drill 0.254)
		(layers "F.Cu" "B.Cu")
		(net "COUPON_GND2")
	)
	(via
		(at 387.72084 9.696196)
		(size 0.508)
		(drill 0.254)
		(layers "F.Cu" "B.Cu")
		(net "COUPON_GND2")
	)
	(via
		(at 403.677374 19.329146)
		(size 0.508)
		(drill 0.254)
		(layers "F.Cu" "B.Cu")
		(net "COUPON_GND2")
	)
	(via
		(at 459.157578 11.807444)
		(size 0.508)
		(drill 0.254)
		(layers "F.Cu" "B.Cu")
		(net "COUPON_GND2")
	)
	(via
		(at 459.98384 7.10946)
		(size 0.508)
		(drill 0.254)
		(layers "F.Cu" "B.Cu")
		(net "COUPON_GND2")
	)
	(via
		(at 314.946792 8.36168)
		(size 0.508)
		(drill 0.254)
		(layers "F.Cu" "B.Cu")
		(net "COUPON_GND2")
	)
	(via
		(at 337.439 20.9804)
		(size 0.508)
		(drill 0.254)
		(layers "F.Cu" "B.Cu")
		(net "COUPON_GND2")
	)
	(via
		(at 272.288762 19.66087)
		(size 0.508)
		(drill 0.254)
		(layers "F.Cu" "B.Cu")
		(net "COUPON_GND2")
	)
	(via
		(at 327.279762 12.361926)
		(size 0.508)
		(drill 0.254)
		(layers "F.Cu" "B.Cu")
		(net "COUPON_GND2")
	)
	(via
		(at 387.717792 11.090656)
		(size 0.508)
		(drill 0.254)
		(layers "F.Cu" "B.Cu")
		(net "COUPON_GND2")
	)
	(via
		(at 314.946792 11.057636)
		(size 0.508)
		(drill 0.254)
		(layers "F.Cu" "B.Cu")
		(net "COUPON_GND2")
	)
	(via
		(at 401.137374 12.059666)
		(size 0.508)
		(drill 0.254)
		(layers "F.Cu" "B.Cu")
		(net "COUPON_GND2")
	)
	(via
		(at 337.435952 21.66366)
		(size 0.508)
		(drill 0.254)
		(layers "F.Cu" "B.Cu")
		(net "COUPON_GND2")
	)
	(via
		(at 384.75031 10.05332)
		(size 0.508)
		(drill 0.254)
		(layers "F.Cu" "B.Cu")
		(net "COUPON_GND2")
	)
	(via
		(at 275.255482 18.664936)
		(size 0.508)
		(drill 0.254)
		(layers "F.Cu" "B.Cu")
		(net "COUPON_GND2")
	)
	(via
		(at 378.736606 16.32331)
		(size 0.508)
		(drill 0.254)
		(layers "F.Cu" "B.Cu")
		(net "COUPON_GND2")
	)
	(via
		(at 313.586368 17.64538)
		(size 0.508)
		(drill 0.254)
		(layers "F.Cu" "B.Cu")
		(net "COUPON_GND2")
	)
	(via
		(at 254.504952 9.07034)
		(size 0.508)
		(drill 0.254)
		(layers "F.Cu" "B.Cu")
		(net "COUPON_GND2")
	)
	(via
		(at 249.247406 19.729958)
		(size 0.508)
		(drill 0.254)
		(layers "F.Cu" "B.Cu")
		(net "COUPON_GND2")
	)
	(via
		(at 399.542762 6.422898)
		(size 0.508)
		(drill 0.254)
		(layers "F.Cu" "B.Cu")
		(net "COUPON_GND2")
	)
	(via
		(at 442.553344 16.32331)
		(size 0.508)
		(drill 0.254)
		(layers "F.Cu" "B.Cu")
		(net "COUPON_GND2")
	)
	(via
		(at 328.106024 9.745726)
		(size 0.508)
		(drill 0.254)
		(layers "F.Cu" "B.Cu")
		(net "COUPON_GND2")
	)
	(via
		(at 440.412886 19.939)
		(size 0.508)
		(drill 0.254)
		(layers "F.Cu" "B.Cu")
		(net "COUPON_GND2")
	)
	(via
		(at 314.94984 7.04342)
		(size 0.508)
		(drill 0.254)
		(layers "F.Cu" "B.Cu")
		(net "COUPON_GND2")
	)
	(via
		(at 459.980792 8.42772)
		(size 0.508)
		(drill 0.254)
		(layers "F.Cu" "B.Cu")
		(net "COUPON_GND2")
	)
	(via
		(at 387.71703 12.409678)
		(size 0.508)
		(drill 0.254)
		(layers "F.Cu" "B.Cu")
		(net "COUPON_GND2")
	)
	(via
		(at 313.589416 16.96212)
		(size 0.508)
		(drill 0.254)
		(layers "F.Cu" "B.Cu")
		(net "COUPON_GND2")
	)
	(via
		(at 443.379606 18.943066)
		(size 0.508)
		(drill 0.254)
		(layers "F.Cu" "B.Cu")
		(net "COUPON_GND2")
	)
	(via
		(at 242.110768 9.781794)
		(size 0.508)
		(drill 0.254)
		(layers "F.Cu" "B.Cu")
		(net "COUPON_GND2")
	)
	(via
		(at 314.119768 9.02081)
		(size 0.508)
		(drill 0.254)
		(layers "F.Cu" "B.Cu")
		(net "COUPON_GND2")
	)
	(via
		(at 248.421144 16.32331)
		(size 0.508)
		(drill 0.254)
		(layers "F.Cu" "B.Cu")
		(net "COUPON_GND2")
	)
	(via
		(at 254.504952 6.995668)
		(size 0.508)
		(drill 0.254)
		(layers "F.Cu" "B.Cu")
		(net "COUPON_GND2")
	)
	(via
		(at 459.98003 6.47065)
		(size 0.508)
		(drill 0.254)
		(layers "F.Cu" "B.Cu")
		(net "COUPON_GND2")
	)
	(via
		(at 402.905214 21.641816)
		(size 0.508)
		(drill 0.254)
		(layers "F.Cu" "B.Cu")
		(net "COUPON_GND2")
	)
	(via
		(at 339.034374 19.329146)
		(size 0.508)
		(drill 0.254)
		(layers "F.Cu" "B.Cu")
		(net "COUPON_GND2")
	)
	(via
		(at 242.93703 6.375146)
		(size 0.508)
		(drill 0.254)
		(layers "F.Cu" "B.Cu")
		(net "COUPON_GND2")
	)
	(via
		(at 399.542 11.072876)
		(size 0.508)
		(drill 0.254)
		(layers "F.Cu" "B.Cu")
		(net "COUPON_GND2")
	)
	(via
		(at 314.946792 7.72668)
		(size 0.508)
		(drill 0.254)
		(layers "F.Cu" "B.Cu")
		(net "COUPON_GND2")
	)
	(via
		(at 311.990994 21.938234)
		(size 0.508)
		(drill 0.254)
		(layers "F.Cu" "B.Cu")
		(net "COUPON_GND2")
	)
	(via
		(at 214.574374 19.405346)
		(size 0.508)
		(drill 0.254)
		(layers "F.Cu" "B.Cu")
		(net "COUPON_GND2")
	)
	(via
		(at 255.335024 12.328906)
		(size 0.508)
		(drill 0.254)
		(layers "F.Cu" "B.Cu")
		(net "COUPON_GND2")
	)
	(via
		(at 442.553344 22.295358)
		(size 0.508)
		(drill 0.254)
		(layers "F.Cu" "B.Cu")
		(net "COUPON_GND2")
	)
	(via
		(at 459.153768 9.08685)
		(size 0.508)
		(drill 0.254)
		(layers "F.Cu" "B.Cu")
		(net "COUPON_GND2")
	)
	(via
		(at 375.769886 17.399)
		(size 0.508)
		(drill 0.254)
		(layers "F.Cu" "B.Cu")
		(net "COUPON_GND2")
	)
	(via
		(at 384.75031 7.51332)
		(size 0.508)
		(drill 0.254)
		(layers "F.Cu" "B.Cu")
		(net "COUPON_GND2")
	)
	(via
		(at 328.874374 6.721602)
		(size 0.508)
		(drill 0.254)
		(layers "F.Cu" "B.Cu")
		(net "COUPON_GND2")
	)
	(via
		(at 312.763154 19.57832)
		(size 0.508)
		(drill 0.254)
		(layers "F.Cu" "B.Cu")
		(net "COUPON_GND2")
	)
	(via
		(at 327.279762 9.74217)
		(size 0.508)
		(drill 0.254)
		(layers "F.Cu" "B.Cu")
		(net "COUPON_GND2")
	)
	(via
		(at 337.439762 19.66087)
		(size 0.508)
		(drill 0.254)
		(layers "F.Cu" "B.Cu")
		(net "COUPON_GND2")
	)
	(via
		(at 443.383416 19.581876)
		(size 0.508)
		(drill 0.254)
		(layers "F.Cu" "B.Cu")
		(net "COUPON_GND2")
	)
	(via
		(at 184.094374 6.713982)
		(size 0.508)
		(drill 0.254)
		(layers "F.Cu" "B.Cu")
		(net "COUPON_GND2")
	)
	(via
		(at 213.802214 19.101816)
		(size 0.508)
		(drill 0.254)
		(layers "F.Cu" "B.Cu")
		(net "COUPON_GND2")
	)
	(via
		(at 214.574374 16.665702)
		(size 0.508)
		(drill 0.254)
		(layers "F.Cu" "B.Cu")
		(net "COUPON_GND2")
	)
	(via
		(at 310.618886 21.197824)
		(size 0.508)
		(drill 0.254)
		(layers "F.Cu" "B.Cu")
		(net "COUPON_GND2")
	)
	(via
		(at 183.322214 9.150096)
		(size 0.508)
		(drill 0.254)
		(layers "F.Cu" "B.Cu")
		(net "COUPON_GND2")
	)
	(via
		(at 459.157578 9.72566)
		(size 0.508)
		(drill 0.254)
		(layers "F.Cu" "B.Cu")
		(net "COUPON_GND2")
	)
	(via
		(at 327.279 7.7089)
		(size 0.508)
		(drill 0.254)
		(layers "F.Cu" "B.Cu")
		(net "COUPON_GND2")
	)
	(via
		(at 378.736606 22.295358)
		(size 0.508)
		(drill 0.254)
		(layers "F.Cu" "B.Cu")
		(net "COUPON_GND2")
	)
	(via
		(at 256.103374 9.377426)
		(size 0.508)
		(drill 0.254)
		(layers "F.Cu" "B.Cu")
		(net "COUPON_GND2")
	)
	(via
		(at 273.115024 22.30247)
		(size 0.508)
		(drill 0.254)
		(layers "F.Cu" "B.Cu")
		(net "COUPON_GND2")
	)
	(via
		(at 327.279 10.404856)
		(size 0.508)
		(drill 0.254)
		(layers "F.Cu" "B.Cu")
		(net "COUPON_GND2")
	)
	(via
		(at 377.141994 19.27479)
		(size 0.508)
		(drill 0.254)
		(layers "F.Cu" "B.Cu")
		(net "COUPON_GND2")
	)
	(via
		(at 377.914154 16.96212)
		(size 0.508)
		(drill 0.254)
		(layers "F.Cu" "B.Cu")
		(net "COUPON_GND2")
	)
	(via
		(at 273.883374 21.945346)
		(size 0.508)
		(drill 0.254)
		(layers "F.Cu" "B.Cu")
		(net "COUPON_GND2")
	)
	(via
		(at 182.495952 7.021068)
		(size 0.508)
		(drill 0.254)
		(layers "F.Cu" "B.Cu")
		(net "COUPON_GND2")
	)
	(via
		(at 255.331214 7.017512)
		(size 0.508)
		(drill 0.254)
		(layers "F.Cu" "B.Cu")
		(net "COUPON_GND2")
	)
	(via
		(at 314.123578 9.65962)
		(size 0.508)
		(drill 0.254)
		(layers "F.Cu" "B.Cu")
		(net "COUPON_GND2")
	)
	(via
		(at 458.385418 6.80593)
		(size 0.508)
		(drill 0.254)
		(layers "F.Cu" "B.Cu")
		(net "COUPON_GND2")
	)
	(via
		(at 275.255482 17.406112)
		(size 0.508)
		(drill 0.254)
		(layers "F.Cu" "B.Cu")
		(net "COUPON_GND2")
	)
	(via
		(at 458.385418 12.085574)
		(size 0.508)
		(drill 0.254)
		(layers "F.Cu" "B.Cu")
		(net "COUPON_GND2")
	)
	(via
		(at 443.380368 20.315936)
		(size 0.508)
		(drill 0.254)
		(layers "F.Cu" "B.Cu")
		(net "COUPON_GND2")
	)
	(via
		(at 314.94603 12.376658)
		(size 0.508)
		(drill 0.254)
		(layers "F.Cu" "B.Cu")
		(net "COUPON_GND2")
	)
	(via
		(at 241.342418 6.70687)
		(size 0.508)
		(drill 0.254)
		(layers "F.Cu" "B.Cu")
		(net "COUPON_GND2")
	)
	(via
		(at 242.94084 9.139428)
		(size 0.508)
		(drill 0.254)
		(layers "F.Cu" "B.Cu")
		(net "COUPON_GND2")
	)
	(via
		(at 443.383416 16.96212)
		(size 0.508)
		(drill 0.254)
		(layers "F.Cu" "B.Cu")
		(net "COUPON_GND2")
	)
	(via
		(at 255.335024 9.712706)
		(size 0.508)
		(drill 0.254)
		(layers "F.Cu" "B.Cu")
		(net "COUPON_GND2")
	)
	(via
		(at 387.72084 7.07644)
		(size 0.508)
		(drill 0.254)
		(layers "F.Cu" "B.Cu")
		(net "COUPON_GND2")
	)
	(via
		(at 254.504952 11.690096)
		(size 0.508)
		(drill 0.254)
		(layers "F.Cu" "B.Cu")
		(net "COUPON_GND2")
	)
	(via
		(at 384.75031 8.772144)
		(size 0.508)
		(drill 0.254)
		(layers "F.Cu" "B.Cu")
		(net "COUPON_GND2")
	)
	(via
		(at 256.103374 6.713982)
		(size 0.508)
		(drill 0.254)
		(layers "F.Cu" "B.Cu")
		(net "COUPON_GND2")
	)
	(via
		(at 249.251216 16.965676)
		(size 0.508)
		(drill 0.254)
		(layers "F.Cu" "B.Cu")
		(net "COUPON_GND2")
	)
	(via
		(at 402.078952 19.02206)
		(size 0.508)
		(drill 0.254)
		(layers "F.Cu" "B.Cu")
		(net "COUPON_GND2")
	)
	(via
		(at 386.122418 12.052554)
		(size 0.508)
		(drill 0.254)
		(layers "F.Cu" "B.Cu")
		(net "COUPON_GND2")
	)
	(via
		(at 340.406482 18.664936)
		(size 0.508)
		(drill 0.254)
		(layers "F.Cu" "B.Cu")
		(net "COUPON_GND2")
	)
	(via
		(at 212.979762 16.333978)
		(size 0.508)
		(drill 0.254)
		(layers "F.Cu" "B.Cu")
		(net "COUPON_GND2")
	)
	(via
		(at 459.980792 7.79272)
		(size 0.508)
		(drill 0.254)
		(layers "F.Cu" "B.Cu")
		(net "COUPON_GND2")
	)
	(via
		(at 256.103374 11.993626)
		(size 0.508)
		(drill 0.254)
		(layers "F.Cu" "B.Cu")
		(net "COUPON_GND2")
	)
	(via
		(at 459.153768 12.446254)
		(size 0.508)
		(drill 0.254)
		(layers "F.Cu" "B.Cu")
		(net "COUPON_GND2")
	)
	(via
		(at 442.557154 21.656548)
		(size 0.508)
		(drill 0.254)
		(layers "F.Cu" "B.Cu")
		(net "COUPON_GND2")
	)
	(via
		(at 273.111214 16.969232)
		(size 0.508)
		(drill 0.254)
		(layers "F.Cu" "B.Cu")
		(net "COUPON_GND2")
	)
	(via
		(at 402.082 18.288)
		(size 0.508)
		(drill 0.254)
		(layers "F.Cu" "B.Cu")
		(net "COUPON_GND2")
	)
	(via
		(at 339.034374 21.970746)
		(size 0.508)
		(drill 0.254)
		(layers "F.Cu" "B.Cu")
		(net "COUPON_GND2")
	)
	(via
		(at 314.119768 6.40461)
		(size 0.508)
		(drill 0.254)
		(layers "F.Cu" "B.Cu")
		(net "COUPON_GND2")
	)
	(via
		(at 272.284952 21.66366)
		(size 0.508)
		(drill 0.254)
		(layers "F.Cu" "B.Cu")
		(net "COUPON_GND2")
	)
	(via
		(at 254.508762 9.70915)
		(size 0.508)
		(drill 0.254)
		(layers "F.Cu" "B.Cu")
		(net "COUPON_GND2")
	)
	(via
		(at 403.677374 16.665702)
		(size 0.508)
		(drill 0.254)
		(layers "F.Cu" "B.Cu")
		(net "COUPON_GND2")
	)
	(via
		(at 273.111214 21.66366)
		(size 0.508)
		(drill 0.254)
		(layers "F.Cu" "B.Cu")
		(net "COUPON_GND2")
	)
	(via
		(at 257.475482 9.994392)
		(size 0.508)
		(drill 0.254)
		(layers "F.Cu" "B.Cu")
		(net "COUPON_GND2")
	)
	(via
		(at 313.586368 20.976336)
		(size 0.508)
		(drill 0.254)
		(layers "F.Cu" "B.Cu")
		(net "COUPON_GND2")
	)
	(via
		(at 443.380368 18.28038)
		(size 0.508)
		(drill 0.254)
		(layers "F.Cu" "B.Cu")
		(net "COUPON_GND2")
	)
	(via
		(at 459.98384 11.803888)
		(size 0.508)
		(drill 0.254)
		(layers "F.Cu" "B.Cu")
		(net "COUPON_GND2")
	)
	(via
		(at 314.94603 6.40461)
		(size 0.508)
		(drill 0.254)
		(layers "F.Cu" "B.Cu")
		(net "COUPON_GND2")
	)
	(via
		(at 387.717792 7.7597)
		(size 0.508)
		(drill 0.254)
		(layers "F.Cu" "B.Cu")
		(net "COUPON_GND2")
	)
	(via
		(at 273.111214 19.025616)
		(size 0.508)
		(drill 0.254)
		(layers "F.Cu" "B.Cu")
		(net "COUPON_GND2")
	)
	(via
		(at 312.759344 22.273514)
		(size 0.508)
		(drill 0.254)
		(layers "F.Cu" "B.Cu")
		(net "COUPON_GND2")
	)
	(via
		(at 386.890768 9.05383)
		(size 0.508)
		(drill 0.254)
		(layers "F.Cu" "B.Cu")
		(net "COUPON_GND2")
	)
	(via
		(at 314.123578 7.04342)
		(size 0.508)
		(drill 0.254)
		(layers "F.Cu" "B.Cu")
		(net "COUPON_GND2")
	)
	(via
		(at 386.894578 9.69264)
		(size 0.508)
		(drill 0.254)
		(layers "F.Cu" "B.Cu")
		(net "COUPON_GND2")
	)
	(via
		(at 459.98003 12.442698)
		(size 0.508)
		(drill 0.254)
		(layers "F.Cu" "B.Cu")
		(net "COUPON_GND2")
	)
	(via
		(at 400.365214 7.058152)
		(size 0.508)
		(drill 0.254)
		(layers "F.Cu" "B.Cu")
		(net "COUPON_GND2")
	)
	(segment
		(start 400.349974 -293.99992)
		(end 400.824954 -294.4749)
		(width 0.249936)
		(layer "F.Cu")
		(net "P0V8_PEX3")
	)
	(segment
		(start 403.674834 -296.37482)
		(end 403.199854 -296.8498)
		(width 0.249936)
		(layer "F.Cu")
		(net "P0V8_PEX3")
	)
	(segment
		(start 405.100028 -296.8498)
		(end 405.575008 -296.37482)
		(width 0.249936)
		(layer "F.Cu")
		(net "P0V8_PEX3")
	)
	(segment
		(start 404.624794 -294.4749)
		(end 405.100028 -294.94988)
		(width 0.249936)
		(layer "F.Cu")
		(net "P0V8_PEX3")
	)
	(segment
		(start 403.674834 -293.52494)
		(end 404.149814 -293.99992)
		(width 0.249936)
		(layer "F.Cu")
		(net "P0V8_PEX3")
	)
	(segment
		(start 399.400014 -296.8498)
		(end 399.874994 -296.37482)
		(width 0.249936)
		(layer "F.Cu")
		(net "P0V8_PEX3")
	)
	(segment
		(start 401.299934 -296.8498)
		(end 401.774914 -296.37482)
		(width 0.249936)
		(layer "F.Cu")
		(net "P0V8_PEX3")
	)
	(segment
		(start 397.02486 -290.674806)
		(end 397.49984 -291.149786)
		(width 0.249936)
		(layer "F.Cu")
		(net "P0V8_PEX3")
	)
	(segment
		(start 402.249894 -293.99992)
		(end 402.724874 -294.4749)
		(width 0.249936)
		(layer "F.Cu")
		(net "P0V8_PEX3")
	)
	(segment
		(start 398.4498 -293.99992)
		(end 398.925034 -294.4749)
		(width 0.249936)
		(layer "F.Cu")
		(net "P0V8_PEX3")
	)
	(segment
		(start 400.824954 -294.4749)
		(end 401.299934 -294.94988)
		(width 0.249936)
		(layer "F.Cu")
		(net "P0V8_PEX3")
	)
	(segment
		(start 402.249894 -297.79976)
		(end 402.724874 -297.32478)
		(width 0.249936)
		(layer "F.Cu")
		(net "P0V8_PEX3")
	)
	(segment
		(start 404.149814 -293.99992)
		(end 404.624794 -294.4749)
		(width 0.249936)
		(layer "F.Cu")
		(net "P0V8_PEX3")
	)
	(segment
		(start 397.49984 -296.8498)
		(end 397.02486 -297.32478)
		(width 0.249936)
		(layer "F.Cu")
		(net "P0V8_PEX3")
	)
	(segment
		(start 402.724874 -297.32478)
		(end 403.199854 -296.8498)
		(width 0.249936)
		(layer "F.Cu")
		(net "P0V8_PEX3")
	)
	(segment
		(start 413.649922 -297.79976)
		(end 414.124902 -298.27474)
		(width 0.249936)
		(layer "F.Cu")
		(net "P0V8_PEX3")
	)
	(segment
		(start 415.549842 -293.99992)
		(end 416.024822 -293.52494)
		(width 0.249936)
		(layer "F.Cu")
		(net "P0V8_PEX3")
	)
	(segment
		(start 411.750002 -295.89984)
		(end 412.224982 -296.37482)
		(width 0.249936)
		(layer "F.Cu")
		(net "P0V8_PEX3")
	)
	(segment
		(start 397.49984 -291.149786)
		(end 397.97482 -291.624766)
		(width 0.249936)
		(layer "F.Cu")
		(net "P0V8_PEX3")
	)
	(segment
		(start 398.4498 -295.89984)
		(end 397.97482 -296.37482)
		(width 0.249936)
		(layer "F.Cu")
		(net "P0V8_PEX3")
	)
	(segment
		(start 404.624794 -297.32478)
		(end 404.149814 -297.79976)
		(width 0.249936)
		(layer "F.Cu")
		(net "P0V8_PEX3")
	)
	(segment
		(start 397.97482 -298.27474)
		(end 397.49984 -298.74972)
		(width 0.249936)
		(layer "F.Cu")
		(net "P0V8_PEX3")
	)
	(segment
		(start 406.524968 -294.4749)
		(end 406.999948 -294.94988)
		(width 0.249936)
		(layer "F.Cu")
		(net "P0V8_PEX3")
	)
	(segment
		(start 413.174942 -297.32478)
		(end 413.649922 -297.79976)
		(width 0.249936)
		(layer "F.Cu")
		(net "P0V8_PEX3")
	)
	(segment
		(start 409.849828 -295.89984)
		(end 410.324808 -296.37482)
		(width 0.249936)
		(layer "F.Cu")
		(net "P0V8_PEX3")
	)
	(segment
		(start 397.02486 -301.124874)
		(end 397.49984 -300.649894)
		(width 0.249936)
		(layer "F.Cu")
		(net "P0V8_PEX3")
	)
	(segment
		(start 412.224982 -298.27474)
		(end 411.750002 -297.79976)
		(width 0.249936)
		(layer "F.Cu")
		(net "P0V8_PEX3")
	)
	(segment
		(start 406.524968 -297.32478)
		(end 406.049988 -297.79976)
		(width 0.249936)
		(layer "F.Cu")
		(net "P0V8_PEX3")
	)
	(segment
		(start 411.275022 -297.32478)
		(end 411.750002 -297.79976)
		(width 0.249936)
		(layer "F.Cu")
		(net "P0V8_PEX3")
	)
	(segment
		(start 397.49984 -293.04996)
		(end 397.97482 -293.52494)
		(width 0.249936)
		(layer "F.Cu")
		(net "P0V8_PEX3")
	)
	(segment
		(start 410.324808 -293.52494)
		(end 409.849828 -293.99992)
		(width 0.249936)
		(layer "F.Cu")
		(net "P0V8_PEX3")
	)
	(segment
		(start 413.649922 -295.89984)
		(end 414.124902 -296.37482)
		(width 0.249936)
		(layer "F.Cu")
		(net "P0V8_PEX3")
	)
	(segment
		(start 397.97482 -296.37482)
		(end 397.49984 -296.8498)
		(width 0.249936)
		(layer "F.Cu")
		(net "P0V8_PEX3")
	)
	(segment
		(start 405.575008 -298.27474)
		(end 406.049988 -297.79976)
		(width 0.249936)
		(layer "F.Cu")
		(net "P0V8_PEX3")
	)
	(segment
		(start 408.899868 -296.8498)
		(end 409.374848 -297.32478)
		(width 0.249936)
		(layer "F.Cu")
		(net "P0V8_PEX3")
	)
	(segment
		(start 408.899868 -294.94988)
		(end 409.374848 -294.4749)
		(width 0.249936)
		(layer "F.Cu")
		(net "P0V8_PEX3")
	)
	(segment
		(start 400.824954 -297.32478)
		(end 401.299934 -296.8498)
		(width 0.249936)
		(layer "F.Cu")
		(net "P0V8_PEX3")
	)
	(segment
		(start 405.100028 -296.8498)
		(end 404.624794 -297.32478)
		(width 0.249936)
		(layer "F.Cu")
		(net "P0V8_PEX3")
	)
	(segment
		(start 398.4498 -297.79976)
		(end 398.925034 -297.32478)
		(width 0.249936)
		(layer "F.Cu")
		(net "P0V8_PEX3")
	)
	(segment
		(start 415.549842 -297.79976)
		(end 416.024822 -298.27474)
		(width 0.249936)
		(layer "F.Cu")
		(net "P0V8_PEX3")
	)
	(segment
		(start 406.999948 -296.8498)
		(end 406.524968 -297.32478)
		(width 0.249936)
		(layer "F.Cu")
		(net "P0V8_PEX3")
	)
	(segment
		(start 397.49984 -300.649894)
		(end 397.97482 -300.174914)
		(width 0.249936)
		(layer "F.Cu")
		(net "P0V8_PEX3")
	)
	(segment
		(start 399.874994 -293.52494)
		(end 400.349974 -293.99992)
		(width 0.249936)
		(layer "F.Cu")
		(net "P0V8_PEX3")
	)
	(segment
		(start 412.699962 -294.94988)
		(end 413.174942 -294.4749)
		(width 0.249936)
		(layer "F.Cu")
		(net "P0V8_PEX3")
	)
	(segment
		(start 397.97482 -300.174914)
		(end 398.4498 -299.699934)
		(width 0.249936)
		(layer "F.Cu")
		(net "P0V8_PEX3")
	)
	(segment
		(start 397.02486 -299.224954)
		(end 397.49984 -298.74972)
		(width 0.249936)
		(layer "F.Cu")
		(net "P0V8_PEX3")
	)
	(segment
		(start 407.949908 -295.89984)
		(end 408.424888 -296.37482)
		(width 0.249936)
		(layer "F.Cu")
		(net "P0V8_PEX3")
	)
	(segment
		(start 400.349974 -297.79976)
		(end 399.874994 -298.27474)
		(width 0.249936)
		(layer "F.Cu")
		(net "P0V8_PEX3")
	)
	(segment
		(start 401.774914 -298.27474)
		(end 402.249894 -297.79976)
		(width 0.249936)
		(layer "F.Cu")
		(net "P0V8_PEX3")
	)
	(segment
		(start 398.925034 -297.32478)
		(end 399.400014 -296.8498)
		(width 0.249936)
		(layer "F.Cu")
		(net "P0V8_PEX3")
	)
	(segment
		(start 412.699962 -296.8498)
		(end 413.174942 -297.32478)
		(width 0.249936)
		(layer "F.Cu")
		(net "P0V8_PEX3")
	)
	(segment
		(start 409.374848 -297.32478)
		(end 409.849828 -297.79976)
		(width 0.249936)
		(layer "F.Cu")
		(net "P0V8_PEX3")
	)
	(segment
		(start 397.97482 -293.52494)
		(end 398.4498 -293.99992)
		(width 0.249936)
		(layer "F.Cu")
		(net "P0V8_PEX3")
	)
	(segment
		(start 410.324808 -298.27474)
		(end 409.849828 -297.79976)
		(width 0.249936)
		(layer "F.Cu")
		(net "P0V8_PEX3")
	)
	(segment
		(start 398.925034 -294.4749)
		(end 399.400014 -294.94988)
		(width 0.249936)
		(layer "F.Cu")
		(net "P0V8_PEX3")
	)
	(segment
		(start 412.224982 -296.37482)
		(end 412.699962 -296.8498)
		(width 0.249936)
		(layer "F.Cu")
		(net "P0V8_PEX3")
	)
	(segment
		(start 397.49984 -294.94988)
		(end 397.02486 -294.4749)
		(width 0.249936)
		(layer "F.Cu")
		(net "P0V8_PEX3")
	)
	(segment
		(start 411.750002 -293.99992)
		(end 411.275022 -294.4749)
		(width 0.249936)
		(layer "F.Cu")
		(net "P0V8_PEX3")
	)
	(segment
		(start 397.02486 -292.574726)
		(end 397.49984 -293.04996)
		(width 0.249936)
		(layer "F.Cu")
		(net "P0V8_PEX3")
	)
	(segment
		(start 402.724874 -294.4749)
		(end 403.199854 -294.94988)
		(width 0.249936)
		(layer "F.Cu")
		(net "P0V8_PEX3")
	)
	(segment
		(start 413.174942 -294.4749)
		(end 413.649922 -293.99992)
		(width 0.249936)
		(layer "F.Cu")
		(net "P0V8_PEX3")
	)
	(segment
		(start 397.97482 -291.624766)
		(end 398.4498 -292.099746)
		(width 0.249936)
		(layer "F.Cu")
		(net "P0V8_PEX3")
	)
	(segment
		(start 402.249894 -293.99992)
		(end 401.774914 -293.52494)
		(width 0.249936)
		(layer "F.Cu")
		(net "P0V8_PEX3")
	)
	(segment
		(start 411.275022 -294.4749)
		(end 410.799788 -294.94988)
		(width 0.249936)
		(layer "F.Cu")
		(net "P0V8_PEX3")
	)
	(segment
		(start 403.674834 -298.27474)
		(end 404.149814 -297.79976)
		(width 0.249936)
		(layer "F.Cu")
		(net "P0V8_PEX3")
	)
	(segment
		(start 412.224982 -293.52494)
		(end 411.750002 -293.99992)
		(width 0.249936)
		(layer "F.Cu")
		(net "P0V8_PEX3")
	)
	(segment
		(start 407.949908 -293.99992)
		(end 408.424888 -293.52494)
		(width 0.249936)
		(layer "F.Cu")
		(net "P0V8_PEX3")
	)
	(segment
		(start 405.575008 -296.37482)
		(end 406.049988 -295.89984)
		(width 0.249936)
		(layer "F.Cu")
		(net "P0V8_PEX3")
	)
	(segment
		(start 405.575008 -293.52494)
		(end 406.049988 -293.99992)
		(width 0.249936)
		(layer "F.Cu")
		(net "P0V8_PEX3")
	)
	(segment
		(start 398.4498 -297.79976)
		(end 397.97482 -298.27474)
		(width 0.249936)
		(layer "F.Cu")
		(net "P0V8_PEX3")
	)
	(segment
		(start 407.949908 -297.79976)
		(end 408.424888 -298.27474)
		(width 0.249936)
		(layer "F.Cu")
		(net "P0V8_PEX3")
	)
	(segment
		(start 401.774914 -296.37482)
		(end 402.249894 -295.89984)
		(width 0.249936)
		(layer "F.Cu")
		(net "P0V8_PEX3")
	)
	(segment
		(start 406.049988 -293.99992)
		(end 406.524968 -294.4749)
		(width 0.249936)
		(layer "F.Cu")
		(net "P0V8_PEX3")
	)
	(segment
		(start 399.874994 -296.37482)
		(end 400.349974 -295.89984)
		(width 0.249936)
		(layer "F.Cu")
		(net "P0V8_PEX3")
	)
	(segment
		(start 410.799788 -296.8498)
		(end 411.275022 -297.32478)
		(width 0.249936)
		(layer "F.Cu")
		(net "P0V8_PEX3")
	)
	(segment
		(start 404.149814 -295.89984)
		(end 403.674834 -296.37482)
		(width 0.249936)
		(layer "F.Cu")
		(net "P0V8_PEX3")
	)
	(segment
		(start 413.649922 -293.99992)
		(end 414.124902 -293.52494)
		(width 0.249936)
		(layer "F.Cu")
		(net "P0V8_PEX3")
	)
	(segment
		(start 409.374848 -294.4749)
		(end 409.849828 -293.99992)
		(width 0.249936)
		(layer "F.Cu")
		(net "P0V8_PEX3")
	)
	(segment
		(start 410.324808 -296.37482)
		(end 410.799788 -296.8498)
		(width 0.249936)
		(layer "F.Cu")
		(net "P0V8_PEX3")
	)
	(via
		(at 397.97482 -296.37482)
		(size 0.4064)
		(drill 0.2032)
		(layers "F.Cu" "B.Cu")
		(net "P0V8_PEX3")
	)
	(via
		(at 358.010968 -296.515536)
		(size 0.508)
		(drill 0.254)
		(layers "F.Cu" "B.Cu")
		(net "P0V8_PEX3")
	)
	(via
		(at 359.850944 -316.533276)
		(size 0.508)
		(drill 0.254)
		(layers "F.Cu" "B.Cu")
		(net "P0V8_PEX3")
	)
	(via
		(at 357.375968 -296.515536)
		(size 0.508)
		(drill 0.254)
		(layers "F.Cu" "B.Cu")
		(net "P0V8_PEX3")
	)
	(via
		(at 357.63073 -300.842934)
		(size 0.508)
		(drill 0.254)
		(layers "F.Cu" "B.Cu")
		(net "P0V8_PEX3")
	)
	(via
		(at 364.44428 -295.245536)
		(size 0.508)
		(drill 0.254)
		(layers "F.Cu" "B.Cu")
		(net "P0V8_PEX3")
	)
	(via
		(at 364.47095 -300.207934)
		(size 0.508)
		(drill 0.254)
		(layers "F.Cu" "B.Cu")
		(net "P0V8_PEX3")
	)
	(via
		(at 358.010968 -298.420536)
		(size 0.508)
		(drill 0.254)
		(layers "F.Cu" "B.Cu")
		(net "P0V8_PEX3")
	)
	(via
		(at 356.83063 -302.290734)
		(size 0.508)
		(drill 0.254)
		(layers "F.Cu" "B.Cu")
		(net "P0V8_PEX3")
	)
	(via
		(at 357.375968 -297.150536)
		(size 0.508)
		(drill 0.254)
		(layers "F.Cu" "B.Cu")
		(net "P0V8_PEX3")
	)
	(via
		(at 414.124902 -293.52494)
		(size 0.4064)
		(drill 0.2032)
		(layers "F.Cu" "B.Cu")
		(net "P0V8_PEX3")
	)
	(via
		(at 403.674834 -298.27474)
		(size 0.4064)
		(drill 0.2032)
		(layers "F.Cu" "B.Cu")
		(net "P0V8_PEX3")
	)
	(via
		(at 357.63073 -300.207934)
		(size 0.508)
		(drill 0.254)
		(layers "F.Cu" "B.Cu")
		(net "P0V8_PEX3")
	)
	(via
		(at 360.866944 -312.469276)
		(size 0.508)
		(drill 0.254)
		(layers "F.Cu" "B.Cu")
		(net "P0V8_PEX3")
	)
	(via
		(at 413.174942 -294.4749)
		(size 0.4064)
		(drill 0.2032)
		(layers "F.Cu" "B.Cu")
		(net "P0V8_PEX3")
	)
	(via
		(at 360.866944 -310.437276)
		(size 0.508)
		(drill 0.254)
		(layers "F.Cu" "B.Cu")
		(net "P0V8_PEX3")
	)
	(via
		(at 397.97482 -291.624766)
		(size 0.4064)
		(drill 0.2032)
		(layers "F.Cu" "B.Cu")
		(net "P0V8_PEX3")
	)
	(via
		(at 358.21874 -302.925734)
		(size 0.508)
		(drill 0.254)
		(layers "F.Cu" "B.Cu")
		(net "P0V8_PEX3")
	)
	(via
		(at 365.05896 -302.290734)
		(size 0.508)
		(drill 0.254)
		(layers "F.Cu" "B.Cu")
		(net "P0V8_PEX3")
	)
	(via
		(at 353.370388 -297.150536)
		(size 0.508)
		(drill 0.254)
		(layers "F.Cu" "B.Cu")
		(net "P0V8_PEX3")
	)
	(via
		(at 360.4387 -297.785536)
		(size 0.508)
		(drill 0.254)
		(layers "F.Cu" "B.Cu")
		(net "P0V8_PEX3")
	)
	(via
		(at 411.275022 -294.4749)
		(size 0.4064)
		(drill 0.2032)
		(layers "F.Cu" "B.Cu")
		(net "P0V8_PEX3")
	)
	(via
		(at 358.010968 -295.245536)
		(size 0.508)
		(drill 0.254)
		(layers "F.Cu" "B.Cu")
		(net "P0V8_PEX3")
	)
	(via
		(at 399.874994 -293.52494)
		(size 0.4064)
		(drill 0.2032)
		(layers "F.Cu" "B.Cu")
		(net "P0V8_PEX3")
	)
	(via
		(at 360.4387 -296.515536)
		(size 0.508)
		(drill 0.254)
		(layers "F.Cu" "B.Cu")
		(net "P0V8_PEX3")
	)
	(via
		(at 398.925034 -294.4749)
		(size 0.4064)
		(drill 0.2032)
		(layers "F.Cu" "B.Cu")
		(net "P0V8_PEX3")
	)
	(via
		(at 400.824954 -294.4749)
		(size 0.4064)
		(drill 0.2032)
		(layers "F.Cu" "B.Cu")
		(net "P0V8_PEX3")
	)
	(via
		(at 361.882944 -312.469276)
		(size 0.508)
		(drill 0.254)
		(layers "F.Cu" "B.Cu")
		(net "P0V8_PEX3")
	)
	(via
		(at 408.424888 -296.37482)
		(size 0.4064)
		(drill 0.2032)
		(layers "F.Cu" "B.Cu")
		(net "P0V8_PEX3")
	)
	(via
		(at 364.47095 -299.572934)
		(size 0.508)
		(drill 0.254)
		(layers "F.Cu" "B.Cu")
		(net "P0V8_PEX3")
	)
	(via
		(at 399.874994 -296.37482)
		(size 0.4064)
		(drill 0.2032)
		(layers "F.Cu" "B.Cu")
		(net "P0V8_PEX3")
	)
	(via
		(at 401.774914 -296.37482)
		(size 0.4064)
		(drill 0.2032)
		(layers "F.Cu" "B.Cu")
		(net "P0V8_PEX3")
	)
	(via
		(at 361.882944 -310.437276)
		(size 0.508)
		(drill 0.254)
		(layers "F.Cu" "B.Cu")
		(net "P0V8_PEX3")
	)
	(via
		(at 358.834944 -314.501276)
		(size 0.508)
		(drill 0.254)
		(layers "F.Cu" "B.Cu")
		(net "P0V8_PEX3")
	)
	(via
		(at 410.324808 -298.27474)
		(size 0.4064)
		(drill 0.2032)
		(layers "F.Cu" "B.Cu")
		(net "P0V8_PEX3")
	)
	(via
		(at 353.99853 -301.424086)
		(size 0.508)
		(drill 0.254)
		(layers "F.Cu" "B.Cu")
		(net "P0V8_PEX3")
	)
	(via
		(at 358.010968 -297.785536)
		(size 0.508)
		(drill 0.254)
		(layers "F.Cu" "B.Cu")
		(net "P0V8_PEX3")
	)
	(via
		(at 364.44428 -296.515536)
		(size 0.508)
		(drill 0.254)
		(layers "F.Cu" "B.Cu")
		(net "P0V8_PEX3")
	)
	(via
		(at 358.834944 -313.485276)
		(size 0.508)
		(drill 0.254)
		(layers "F.Cu" "B.Cu")
		(net "P0V8_PEX3")
	)
	(via
		(at 402.724874 -297.32478)
		(size 0.4064)
		(drill 0.2032)
		(layers "F.Cu" "B.Cu")
		(net "P0V8_PEX3")
	)
	(via
		(at 353.370388 -296.515536)
		(size 0.508)
		(drill 0.254)
		(layers "F.Cu" "B.Cu")
		(net "P0V8_PEX3")
	)
	(via
		(at 401.774914 -293.52494)
		(size 0.4064)
		(drill 0.2032)
		(layers "F.Cu" "B.Cu")
		(net "P0V8_PEX3")
	)
	(via
		(at 358.010968 -295.880536)
		(size 0.508)
		(drill 0.254)
		(layers "F.Cu" "B.Cu")
		(net "P0V8_PEX3")
	)
	(via
		(at 357.818944 -315.517276)
		(size 0.508)
		(drill 0.254)
		(layers "F.Cu" "B.Cu")
		(net "P0V8_PEX3")
	)
	(via
		(at 360.4387 -295.880536)
		(size 0.508)
		(drill 0.254)
		(layers "F.Cu" "B.Cu")
		(net "P0V8_PEX3")
	)
	(via
		(at 357.818944 -311.453276)
		(size 0.508)
		(drill 0.254)
		(layers "F.Cu" "B.Cu")
		(net "P0V8_PEX3")
	)
	(via
		(at 364.930944 -310.437276)
		(size 0.508)
		(drill 0.254)
		(layers "F.Cu" "B.Cu")
		(net "P0V8_PEX3")
	)
	(via
		(at 360.866944 -314.501276)
		(size 0.508)
		(drill 0.254)
		(layers "F.Cu" "B.Cu")
		(net "P0V8_PEX3")
	)
	(via
		(at 352.735388 -296.515536)
		(size 0.508)
		(drill 0.254)
		(layers "F.Cu" "B.Cu")
		(net "P0V8_PEX3")
	)
	(via
		(at 362.898944 -314.501276)
		(size 0.508)
		(drill 0.254)
		(layers "F.Cu" "B.Cu")
		(net "P0V8_PEX3")
	)
	(via
		(at 406.524968 -297.32478)
		(size 0.4064)
		(drill 0.2032)
		(layers "F.Cu" "B.Cu")
		(net "P0V8_PEX3")
	)
	(via
		(at 359.850944 -294.1828)
		(size 0.508)
		(drill 0.254)
		(layers "F.Cu" "B.Cu")
		(net "P0V8_PEX3")
	)
	(via
		(at 357.375968 -295.245536)
		(size 0.508)
		(drill 0.254)
		(layers "F.Cu" "B.Cu")
		(net "P0V8_PEX3")
	)
	(via
		(at 357.818944 -310.437276)
		(size 0.508)
		(drill 0.254)
		(layers "F.Cu" "B.Cu")
		(net "P0V8_PEX3")
	)
	(via
		(at 397.97482 -293.52494)
		(size 0.4064)
		(drill 0.2032)
		(layers "F.Cu" "B.Cu")
		(net "P0V8_PEX3")
	)
	(via
		(at 359.850944 -313.485276)
		(size 0.508)
		(drill 0.254)
		(layers "F.Cu" "B.Cu")
		(net "P0V8_PEX3")
	)
	(via
		(at 360.4387 -297.150536)
		(size 0.508)
		(drill 0.254)
		(layers "F.Cu" "B.Cu")
		(net "P0V8_PEX3")
	)
	(via
		(at 357.375968 -297.785536)
		(size 0.508)
		(drill 0.254)
		(layers "F.Cu" "B.Cu")
		(net "P0V8_PEX3")
	)
	(via
		(at 352.735388 -295.880536)
		(size 0.508)
		(drill 0.254)
		(layers "F.Cu" "B.Cu")
		(net "P0V8_PEX3")
	)
	(via
		(at 352.735388 -298.420536)
		(size 0.508)
		(drill 0.254)
		(layers "F.Cu" "B.Cu")
		(net "P0V8_PEX3")
	)
	(via
		(at 359.8037 -297.785536)
		(size 0.508)
		(drill 0.254)
		(layers "F.Cu" "B.Cu")
		(net "P0V8_PEX3")
	)
	(via
		(at 414.124902 -296.37482)
		(size 0.4064)
		(drill 0.2032)
		(layers "F.Cu" "B.Cu")
		(net "P0V8_PEX3")
	)
	(via
		(at 359.850944 -312.469276)
		(size 0.508)
		(drill 0.254)
		(layers "F.Cu" "B.Cu")
		(net "P0V8_PEX3")
	)
	(via
		(at 353.370388 -298.420536)
		(size 0.508)
		(drill 0.254)
		(layers "F.Cu" "B.Cu")
		(net "P0V8_PEX3")
	)
	(via
		(at 358.010968 -297.150536)
		(size 0.508)
		(drill 0.254)
		(layers "F.Cu" "B.Cu")
		(net "P0V8_PEX3")
	)
	(via
		(at 365.07928 -297.150536)
		(size 0.508)
		(drill 0.254)
		(layers "F.Cu" "B.Cu")
		(net "P0V8_PEX3")
	)
	(via
		(at 365.05896 -302.925734)
		(size 0.508)
		(drill 0.254)
		(layers "F.Cu" "B.Cu")
		(net "P0V8_PEX3")
	)
	(via
		(at 397.97482 -298.27474)
		(size 0.4064)
		(drill 0.2032)
		(layers "F.Cu" "B.Cu")
		(net "P0V8_PEX3")
	)
	(via
		(at 365.07928 -296.515536)
		(size 0.508)
		(drill 0.254)
		(layers "F.Cu" "B.Cu")
		(net "P0V8_PEX3")
	)
	(via
		(at 412.224982 -298.27474)
		(size 0.4064)
		(drill 0.2032)
		(layers "F.Cu" "B.Cu")
		(net "P0V8_PEX3")
	)
	(via
		(at 352.735388 -297.785536)
		(size 0.508)
		(drill 0.254)
		(layers "F.Cu" "B.Cu")
		(net "P0V8_PEX3")
	)
	(via
		(at 398.925034 -297.32478)
		(size 0.4064)
		(drill 0.2032)
		(layers "F.Cu" "B.Cu")
		(net "P0V8_PEX3")
	)
	(via
		(at 365.07928 -295.880536)
		(size 0.508)
		(drill 0.254)
		(layers "F.Cu" "B.Cu")
		(net "P0V8_PEX3")
	)
	(via
		(at 353.370388 -297.785536)
		(size 0.508)
		(drill 0.254)
		(layers "F.Cu" "B.Cu")
		(net "P0V8_PEX3")
	)
	(via
		(at 364.44428 -297.150536)
		(size 0.508)
		(drill 0.254)
		(layers "F.Cu" "B.Cu")
		(net "P0V8_PEX3")
	)
	(via
		(at 397.02486 -290.674806)
		(size 0.4064)
		(drill 0.2032)
		(layers "F.Cu" "B.Cu")
		(net "P0V8_PEX3")
	)
	(via
		(at 357.818944 -314.501276)
		(size 0.508)
		(drill 0.254)
		(layers "F.Cu" "B.Cu")
		(net "P0V8_PEX3")
	)
	(via
		(at 360.83875 -300.789086)
		(size 0.508)
		(drill 0.254)
		(layers "F.Cu" "B.Cu")
		(net "P0V8_PEX3")
	)
	(via
		(at 360.866944 -311.453276)
		(size 0.508)
		(drill 0.254)
		(layers "F.Cu" "B.Cu")
		(net "P0V8_PEX3")
	)
	(via
		(at 361.882944 -315.517276)
		(size 0.508)
		(drill 0.254)
		(layers "F.Cu" "B.Cu")
		(net "P0V8_PEX3")
	)
	(via
		(at 360.25074 -302.925734)
		(size 0.508)
		(drill 0.254)
		(layers "F.Cu" "B.Cu")
		(net "P0V8_PEX3")
	)
	(via
		(at 356.83063 -302.925734)
		(size 0.508)
		(drill 0.254)
		(layers "F.Cu" "B.Cu")
		(net "P0V8_PEX3")
	)
	(via
		(at 359.8037 -295.245536)
		(size 0.508)
		(drill 0.254)
		(layers "F.Cu" "B.Cu")
		(net "P0V8_PEX3")
	)
	(via
		(at 405.575008 -296.37482)
		(size 0.4064)
		(drill 0.2032)
		(layers "F.Cu" "B.Cu")
		(net "P0V8_PEX3")
	)
	(via
		(at 358.21874 -302.290734)
		(size 0.508)
		(drill 0.254)
		(layers "F.Cu" "B.Cu")
		(net "P0V8_PEX3")
	)
	(via
		(at 360.83875 -300.154086)
		(size 0.508)
		(drill 0.254)
		(layers "F.Cu" "B.Cu")
		(net "P0V8_PEX3")
	)
	(via
		(at 403.674834 -296.37482)
		(size 0.4064)
		(drill 0.2032)
		(layers "F.Cu" "B.Cu")
		(net "P0V8_PEX3")
	)
	(via
		(at 359.8037 -295.880536)
		(size 0.508)
		(drill 0.254)
		(layers "F.Cu" "B.Cu")
		(net "P0V8_PEX3")
	)
	(via
		(at 412.224982 -296.37482)
		(size 0.4064)
		(drill 0.2032)
		(layers "F.Cu" "B.Cu")
		(net "P0V8_PEX3")
	)
	(via
		(at 359.850944 -314.501276)
		(size 0.508)
		(drill 0.254)
		(layers "F.Cu" "B.Cu")
		(net "P0V8_PEX3")
	)
	(via
		(at 352.735388 -295.245536)
		(size 0.508)
		(drill 0.254)
		(layers "F.Cu" "B.Cu")
		(net "P0V8_PEX3")
	)
	(via
		(at 357.818944 -312.469276)
		(size 0.508)
		(drill 0.254)
		(layers "F.Cu" "B.Cu")
		(net "P0V8_PEX3")
	)
	(via
		(at 357.63073 -299.572934)
		(size 0.508)
		(drill 0.254)
		(layers "F.Cu" "B.Cu")
		(net "P0V8_PEX3")
	)
	(via
		(at 408.424888 -293.52494)
		(size 0.4064)
		(drill 0.2032)
		(layers "F.Cu" "B.Cu")
		(net "P0V8_PEX3")
	)
	(via
		(at 361.882944 -314.501276)
		(size 0.508)
		(drill 0.254)
		(layers "F.Cu" "B.Cu")
		(net "P0V8_PEX3")
	)
	(via
		(at 360.83875 -301.424086)
		(size 0.508)
		(drill 0.254)
		(layers "F.Cu" "B.Cu")
		(net "P0V8_PEX3")
	)
	(via
		(at 404.624794 -294.4749)
		(size 0.4064)
		(drill 0.2032)
		(layers "F.Cu" "B.Cu")
		(net "P0V8_PEX3")
	)
	(via
		(at 358.834944 -311.453276)
		(size 0.508)
		(drill 0.254)
		(layers "F.Cu" "B.Cu")
		(net "P0V8_PEX3")
	)
	(via
		(at 358.834944 -315.517276)
		(size 0.508)
		(drill 0.254)
		(layers "F.Cu" "B.Cu")
		(net "P0V8_PEX3")
	)
	(via
		(at 409.374848 -294.4749)
		(size 0.4064)
		(drill 0.2032)
		(layers "F.Cu" "B.Cu")
		(net "P0V8_PEX3")
	)
	(via
		(at 353.370388 -295.880536)
		(size 0.508)
		(drill 0.254)
		(layers "F.Cu" "B.Cu")
		(net "P0V8_PEX3")
	)
	(via
		(at 409.374848 -297.32478)
		(size 0.4064)
		(drill 0.2032)
		(layers "F.Cu" "B.Cu")
		(net "P0V8_PEX3")
	)
	(via
		(at 362.898944 -312.469276)
		(size 0.508)
		(drill 0.254)
		(layers "F.Cu" "B.Cu")
		(net "P0V8_PEX3")
	)
	(via
		(at 357.375968 -298.420536)
		(size 0.508)
		(drill 0.254)
		(layers "F.Cu" "B.Cu")
		(net "P0V8_PEX3")
	)
	(via
		(at 359.8037 -296.515536)
		(size 0.508)
		(drill 0.254)
		(layers "F.Cu" "B.Cu")
		(net "P0V8_PEX3")
	)
	(via
		(at 366.439196 -281.01671)
		(size 0.508)
		(drill 0.254)
		(layers "F.Cu" "B.Cu")
		(net "P0V8_PEX3")
	)
	(via
		(at 400.824954 -297.32478)
		(size 0.4064)
		(drill 0.2032)
		(layers "F.Cu" "B.Cu")
		(net "P0V8_PEX3")
	)
	(via
		(at 397.97482 -300.174914)
		(size 0.4064)
		(drill 0.2032)
		(layers "F.Cu" "B.Cu")
		(net "P0V8_PEX3")
	)
	(via
		(at 359.850944 -311.453276)
		(size 0.508)
		(drill 0.254)
		(layers "F.Cu" "B.Cu")
		(net "P0V8_PEX3")
	)
	(via
		(at 362.898944 -316.533276)
		(size 0.508)
		(drill 0.254)
		(layers "F.Cu" "B.Cu")
		(net "P0V8_PEX3")
	)
	(via
		(at 363.914944 -310.437276)
		(size 0.508)
		(drill 0.254)
		(layers "F.Cu" "B.Cu")
		(net "P0V8_PEX3")
	)
	(via
		(at 366.381792 -294.851836)
		(size 0.508)
		(drill 0.254)
		(layers "F.Cu" "B.Cu")
		(net "P0V8_PEX3")
	)
	(via
		(at 362.898944 -315.517276)
		(size 0.508)
		(drill 0.254)
		(layers "F.Cu" "B.Cu")
		(net "P0V8_PEX3")
	)
	(via
		(at 353.99853 -300.789086)
		(size 0.508)
		(drill 0.254)
		(layers "F.Cu" "B.Cu")
		(net "P0V8_PEX3")
	)
	(via
		(at 397.02486 -294.4749)
		(size 0.4064)
		(drill 0.2032)
		(layers "F.Cu" "B.Cu")
		(net "P0V8_PEX3")
	)
	(via
		(at 358.834944 -312.469276)
		(size 0.508)
		(drill 0.254)
		(layers "F.Cu" "B.Cu")
		(net "P0V8_PEX3")
	)
	(via
		(at 362.898944 -313.485276)
		(size 0.508)
		(drill 0.254)
		(layers "F.Cu" "B.Cu")
		(net "P0V8_PEX3")
	)
	(via
		(at 402.724874 -294.4749)
		(size 0.4064)
		(drill 0.2032)
		(layers "F.Cu" "B.Cu")
		(net "P0V8_PEX3")
	)
	(via
		(at 414.124902 -298.27474)
		(size 0.4064)
		(drill 0.2032)
		(layers "F.Cu" "B.Cu")
		(net "P0V8_PEX3")
	)
	(via
		(at 362.898944 -310.437276)
		(size 0.508)
		(drill 0.254)
		(layers "F.Cu" "B.Cu")
		(net "P0V8_PEX3")
	)
	(via
		(at 357.63073 -301.477934)
		(size 0.508)
		(drill 0.254)
		(layers "F.Cu" "B.Cu")
		(net "P0V8_PEX3")
	)
	(via
		(at 364.44428 -295.880536)
		(size 0.508)
		(drill 0.254)
		(layers "F.Cu" "B.Cu")
		(net "P0V8_PEX3")
	)
	(via
		(at 410.324808 -296.37482)
		(size 0.4064)
		(drill 0.2032)
		(layers "F.Cu" "B.Cu")
		(net "P0V8_PEX3")
	)
	(via
		(at 401.774914 -298.27474)
		(size 0.4064)
		(drill 0.2032)
		(layers "F.Cu" "B.Cu")
		(net "P0V8_PEX3")
	)
	(via
		(at 404.624794 -297.32478)
		(size 0.4064)
		(drill 0.2032)
		(layers "F.Cu" "B.Cu")
		(net "P0V8_PEX3")
	)
	(via
		(at 353.99853 -299.519086)
		(size 0.508)
		(drill 0.254)
		(layers "F.Cu" "B.Cu")
		(net "P0V8_PEX3")
	)
	(via
		(at 361.882944 -311.453276)
		(size 0.508)
		(drill 0.254)
		(layers "F.Cu" "B.Cu")
		(net "P0V8_PEX3")
	)
	(via
		(at 397.02486 -299.224954)
		(size 0.4064)
		(drill 0.2032)
		(layers "F.Cu" "B.Cu")
		(net "P0V8_PEX3")
	)
	(via
		(at 357.818944 -313.485276)
		(size 0.508)
		(drill 0.254)
		(layers "F.Cu" "B.Cu")
		(net "P0V8_PEX3")
	)
	(via
		(at 359.8037 -297.150536)
		(size 0.508)
		(drill 0.254)
		(layers "F.Cu" "B.Cu")
		(net "P0V8_PEX3")
	)
	(via
		(at 362.898944 -311.453276)
		(size 0.508)
		(drill 0.254)
		(layers "F.Cu" "B.Cu")
		(net "P0V8_PEX3")
	)
	(via
		(at 360.25074 -302.290734)
		(size 0.508)
		(drill 0.254)
		(layers "F.Cu" "B.Cu")
		(net "P0V8_PEX3")
	)
	(via
		(at 363.914944 -311.453276)
		(size 0.508)
		(drill 0.254)
		(layers "F.Cu" "B.Cu")
		(net "P0V8_PEX3")
	)
	(via
		(at 416.024822 -298.27474)
		(size 0.4064)
		(drill 0.2032)
		(layers "F.Cu" "B.Cu")
		(net "P0V8_PEX3")
	)
	(via
		(at 399.874994 -298.27474)
		(size 0.4064)
		(drill 0.2032)
		(layers "F.Cu" "B.Cu")
		(net "P0V8_PEX3")
	)
	(via
		(at 353.41052 -302.925734)
		(size 0.508)
		(drill 0.254)
		(layers "F.Cu" "B.Cu")
		(net "P0V8_PEX3")
	)
	(via
		(at 360.83875 -299.519086)
		(size 0.508)
		(drill 0.254)
		(layers "F.Cu" "B.Cu")
		(net "P0V8_PEX3")
	)
	(via
		(at 360.866944 -313.485276)
		(size 0.508)
		(drill 0.254)
		(layers "F.Cu" "B.Cu")
		(net "P0V8_PEX3")
	)
	(via
		(at 357.375968 -295.880536)
		(size 0.508)
		(drill 0.254)
		(layers "F.Cu" "B.Cu")
		(net "P0V8_PEX3")
	)
	(via
		(at 364.930944 -311.453276)
		(size 0.508)
		(drill 0.254)
		(layers "F.Cu" "B.Cu")
		(net "P0V8_PEX3")
	)
	(via
		(at 360.866944 -315.517276)
		(size 0.508)
		(drill 0.254)
		(layers "F.Cu" "B.Cu")
		(net "P0V8_PEX3")
	)
	(via
		(at 365.07928 -297.785536)
		(size 0.508)
		(drill 0.254)
		(layers "F.Cu" "B.Cu")
		(net "P0V8_PEX3")
	)
	(via
		(at 405.575008 -298.27474)
		(size 0.4064)
		(drill 0.2032)
		(layers "F.Cu" "B.Cu")
		(net "P0V8_PEX3")
	)
	(via
		(at 351.288096 -294.851836)
		(size 0.508)
		(drill 0.254)
		(layers "F.Cu" "B.Cu")
		(net "P0V8_PEX3")
	)
	(via
		(at 359.850944 -315.517276)
		(size 0.508)
		(drill 0.254)
		(layers "F.Cu" "B.Cu")
		(net "P0V8_PEX3")
	)
	(via
		(at 352.735388 -297.150536)
		(size 0.508)
		(drill 0.254)
		(layers "F.Cu" "B.Cu")
		(net "P0V8_PEX3")
	)
	(via
		(at 358.834944 -310.437276)
		(size 0.508)
		(drill 0.254)
		(layers "F.Cu" "B.Cu")
		(net "P0V8_PEX3")
	)
	(via
		(at 411.275022 -297.32478)
		(size 0.4064)
		(drill 0.2032)
		(layers "F.Cu" "B.Cu")
		(net "P0V8_PEX3")
	)
	(via
		(at 361.882944 -316.533276)
		(size 0.508)
		(drill 0.254)
		(layers "F.Cu" "B.Cu")
		(net "P0V8_PEX3")
	)
	(via
		(at 357.818944 -316.533276)
		(size 0.508)
		(drill 0.254)
		(layers "F.Cu" "B.Cu")
		(net "P0V8_PEX3")
	)
	(via
		(at 365.07928 -298.420536)
		(size 0.508)
		(drill 0.254)
		(layers "F.Cu" "B.Cu")
		(net "P0V8_PEX3")
	)
	(via
		(at 405.575008 -293.52494)
		(size 0.4064)
		(drill 0.2032)
		(layers "F.Cu" "B.Cu")
		(net "P0V8_PEX3")
	)
	(via
		(at 360.4387 -295.245536)
		(size 0.508)
		(drill 0.254)
		(layers "F.Cu" "B.Cu")
		(net "P0V8_PEX3")
	)
	(via
		(at 353.41052 -302.290734)
		(size 0.508)
		(drill 0.254)
		(layers "F.Cu" "B.Cu")
		(net "P0V8_PEX3")
	)
	(via
		(at 412.224982 -293.52494)
		(size 0.4064)
		(drill 0.2032)
		(layers "F.Cu" "B.Cu")
		(net "P0V8_PEX3")
	)
	(via
		(at 363.914944 -312.469276)
		(size 0.508)
		(drill 0.254)
		(layers "F.Cu" "B.Cu")
		(net "P0V8_PEX3")
	)
	(via
		(at 408.424888 -298.27474)
		(size 0.4064)
		(drill 0.2032)
		(layers "F.Cu" "B.Cu")
		(net "P0V8_PEX3")
	)
	(via
		(at 365.07928 -295.245536)
		(size 0.508)
		(drill 0.254)
		(layers "F.Cu" "B.Cu")
		(net "P0V8_PEX3")
	)
	(via
		(at 360.866944 -316.533276)
		(size 0.508)
		(drill 0.254)
		(layers "F.Cu" "B.Cu")
		(net "P0V8_PEX3")
	)
	(via
		(at 364.47095 -301.477934)
		(size 0.508)
		(drill 0.254)
		(layers "F.Cu" "B.Cu")
		(net "P0V8_PEX3")
	)
	(via
		(at 416.024822 -293.52494)
		(size 0.4064)
		(drill 0.2032)
		(layers "F.Cu" "B.Cu")
		(net "P0V8_PEX3")
	)
	(via
		(at 360.4387 -298.420536)
		(size 0.508)
		(drill 0.254)
		(layers "F.Cu" "B.Cu")
		(net "P0V8_PEX3")
	)
	(via
		(at 364.44428 -297.785536)
		(size 0.508)
		(drill 0.254)
		(layers "F.Cu" "B.Cu")
		(net "P0V8_PEX3")
	)
	(via
		(at 397.02486 -292.574726)
		(size 0.4064)
		(drill 0.2032)
		(layers "F.Cu" "B.Cu")
		(net "P0V8_PEX3")
	)
	(via
		(at 413.174942 -297.32478)
		(size 0.4064)
		(drill 0.2032)
		(layers "F.Cu" "B.Cu")
		(net "P0V8_PEX3")
	)
	(via
		(at 358.278684 -280.999692)
		(size 0.508)
		(drill 0.254)
		(layers "F.Cu" "B.Cu")
		(net "P0V8_PEX3")
	)
	(via
		(at 364.44428 -298.420536)
		(size 0.508)
		(drill 0.254)
		(layers "F.Cu" "B.Cu")
		(net "P0V8_PEX3")
	)
	(via
		(at 410.324808 -293.52494)
		(size 0.4064)
		(drill 0.2032)
		(layers "F.Cu" "B.Cu")
		(net "P0V8_PEX3")
	)
	(via
		(at 397.02486 -297.32478)
		(size 0.4064)
		(drill 0.2032)
		(layers "F.Cu" "B.Cu")
		(net "P0V8_PEX3")
	)
	(via
		(at 363.914944 -313.485276)
		(size 0.508)
		(drill 0.254)
		(layers "F.Cu" "B.Cu")
		(net "P0V8_PEX3")
	)
	(via
		(at 359.8037 -298.420536)
		(size 0.508)
		(drill 0.254)
		(layers "F.Cu" "B.Cu")
		(net "P0V8_PEX3")
	)
	(via
		(at 353.370388 -295.245536)
		(size 0.508)
		(drill 0.254)
		(layers "F.Cu" "B.Cu")
		(net "P0V8_PEX3")
	)
	(via
		(at 403.674834 -293.52494)
		(size 0.4064)
		(drill 0.2032)
		(layers "F.Cu" "B.Cu")
		(net "P0V8_PEX3")
	)
	(via
		(at 361.882944 -313.485276)
		(size 0.508)
		(drill 0.254)
		(layers "F.Cu" "B.Cu")
		(net "P0V8_PEX3")
	)
	(via
		(at 406.524968 -294.4749)
		(size 0.4064)
		(drill 0.2032)
		(layers "F.Cu" "B.Cu")
		(net "P0V8_PEX3")
	)
	(via
		(at 359.850944 -310.437276)
		(size 0.508)
		(drill 0.254)
		(layers "F.Cu" "B.Cu")
		(net "P0V8_PEX3")
	)
	(via
		(at 358.834944 -316.533276)
		(size 0.508)
		(drill 0.254)
		(layers "F.Cu" "B.Cu")
		(net "P0V8_PEX3")
	)
	(via
		(at 353.99853 -300.154086)
		(size 0.508)
		(drill 0.254)
		(layers "F.Cu" "B.Cu")
		(net "P0V8_PEX3")
	)
	(via
		(at 397.02486 -301.124874)
		(size 0.4064)
		(drill 0.2032)
		(layers "F.Cu" "B.Cu")
		(net "P0V8_PEX3")
	)
	(via
		(at 364.47095 -300.842934)
		(size 0.508)
		(drill 0.254)
		(layers "F.Cu" "B.Cu")
		(net "P0V8_PEX3")
	)
	(segment
		(start 366.439196 -281.640534)
		(end 366.439196 -281.01671)
		(width 0.254)
		(layer "B.Cu")
		(net "P0V8_PEX3")
	)
	(segment
		(start 416.233102 -293.52494)
		(end 416.024822 -293.52494)
		(width 0.3048)
		(layer "B.Cu")
		(net "P0V8_PEX3")
	)
	(segment
		(start 416.233102 -298.27474)
		(end 416.024822 -298.27474)
		(width 0.3048)
		(layer "B.Cu")
		(net "P0V8_PEX3")
	)
	(segment
		(start 358.278684 -281.640534)
		(end 358.278684 -280.999692)
		(width 0.254)
		(layer "B.Cu")
		(net "P0V8_PEX3")
	)
	(segment
		(start 365.53648 -286.487362)
		(end 365.53648 -294.788336)
		(width 0.254)
		(layer "In5.Cu")
		(net "P0V8_PEX3")
	)
	(segment
		(start 366.439196 -281.01671)
		(end 366.439196 -282.431236)
		(width 0.254)
		(layer "In5.Cu")
		(net "P0V8_PEX3")
	)
	(segment
		(start 366.439196 -282.431236)
		(end 367.1951 -283.18714)
		(width 0.254)
		(layer "In5.Cu")
		(net "P0V8_PEX3")
	)
	(segment
		(start 357.375968 -283.316934)
		(end 358.278684 -282.414218)
		(width 0.254)
		(layer "In5.Cu")
		(net "P0V8_PEX3")
	)
	(segment
		(start 365.53648 -294.788336)
		(end 365.07928 -295.245536)
		(width 0.254)
		(layer "In5.Cu")
		(net "P0V8_PEX3")
	)
	(segment
		(start 358.278684 -282.414218)
		(end 358.278684 -280.999692)
		(width 0.254)
		(layer "In5.Cu")
		(net "P0V8_PEX3")
	)
	(segment
		(start 357.375968 -295.245536)
		(end 357.375968 -283.316934)
		(width 0.254)
		(layer "In5.Cu")
		(net "P0V8_PEX3")
	)
	(segment
		(start 367.1951 -283.18714)
		(end 367.1951 -284.828742)
		(width 0.254)
		(layer "In5.Cu")
		(net "P0V8_PEX3")
	)
	(segment
		(start 367.1951 -284.828742)
		(end 365.53648 -286.487362)
		(width 0.254)
		(layer "In5.Cu")
		(net "P0V8_PEX3")
	)
	(segment
		(start 118.70563 -255.269746)
		(end 118.975632 -255.539748)
		(width 0.1524)
		(layer "F.Cu")
		(net "P0V8_PEX1_PWM1")
	)
	(segment
		(start 122.448828 -280.897838)
		(end 122.57405 -280.617168)
		(width 0.2032)
		(layer "F.Cu")
		(net "P0V8_PEX1_PWM1")
	)
	(segment
		(start 122.370596 -281.438858)
		(end 122.448828 -281.249882)
		(width 0.2032)
		(layer "F.Cu")
		(net "P0V8_PEX1_PWM1")
	)
	(segment
		(start 118.70563 -253.10592)
		(end 118.70563 -255.269746)
		(width 0.1524)
		(layer "F.Cu")
		(net "P0V8_PEX1_PWM1")
	)
	(segment
		(start 122.370596 -281.999182)
		(end 122.370596 -281.438858)
		(width 0.2032)
		(layer "F.Cu")
		(net "P0V8_PEX1_PWM1")
	)
	(segment
		(start 122.448828 -281.249882)
		(end 122.448828 -280.897838)
		(width 0.2032)
		(layer "F.Cu")
		(net "P0V8_PEX1_PWM1")
	)
	(segment
		(start 118.975632 -255.539748)
		(end 118.975632 -255.994916)
		(width 0.1524)
		(layer "F.Cu")
		(net "P0V8_PEX1_PWM1")
	)
	(via
		(at 122.57405 -280.617168)
		(size 0.508)
		(drill 0.254)
		(layers "F.Cu" "B.Cu")
		(net "P0V8_PEX1_PWM1")
	)
	(via
		(at 118.70563 -253.10592)
		(size 0.508)
		(drill 0.254)
		(layers "F.Cu" "B.Cu")
		(net "P0V8_PEX1_PWM1")
	)
	(segment
		(start 118.24208 -278.387048)
		(end 119.715788 -279.860756)
		(width 0.2032)
		(layer "In5.Cu")
		(net "P0V8_PEX1_PWM1")
	)
	(segment
		(start 119.715788 -279.860756)
		(end 121.817638 -279.860756)
		(width 0.2032)
		(layer "In5.Cu")
		(net "P0V8_PEX1_PWM1")
	)
	(segment
		(start 118.70563 -253.10592)
		(end 118.75643 -253.05512)
		(width 0.2032)
		(layer "In5.Cu")
		(net "P0V8_PEX1_PWM1")
	)
	(segment
		(start 122.628406 -253.05512)
		(end 123.403106 -253.82982)
		(width 0.2032)
		(layer "In5.Cu")
		(net "P0V8_PEX1_PWM1")
	)
	(segment
		(start 118.75643 -253.05512)
		(end 122.628406 -253.05512)
		(width 0.2032)
		(layer "In5.Cu")
		(net "P0V8_PEX1_PWM1")
	)
	(segment
		(start 123.403106 -260.86689)
		(end 124.46635 -261.930134)
		(width 0.2032)
		(layer "In5.Cu")
		(net "P0V8_PEX1_PWM1")
	)
	(segment
		(start 124.46635 -261.930134)
		(end 124.46635 -264.254488)
		(width 0.2032)
		(layer "In5.Cu")
		(net "P0V8_PEX1_PWM1")
	)
	(segment
		(start 120.647968 -267.149326)
		(end 118.24208 -269.555214)
		(width 0.2032)
		(layer "In5.Cu")
		(net "P0V8_PEX1_PWM1")
	)
	(segment
		(start 121.571512 -267.149326)
		(end 120.647968 -267.149326)
		(width 0.2032)
		(layer "In5.Cu")
		(net "P0V8_PEX1_PWM1")
	)
	(segment
		(start 123.403106 -253.82982)
		(end 123.403106 -260.86689)
		(width 0.2032)
		(layer "In5.Cu")
		(net "P0V8_PEX1_PWM1")
	)
	(segment
		(start 124.46635 -264.254488)
		(end 121.571512 -267.149326)
		(width 0.2032)
		(layer "In5.Cu")
		(net "P0V8_PEX1_PWM1")
	)
	(segment
		(start 118.24208 -269.555214)
		(end 118.24208 -278.387048)
		(width 0.2032)
		(layer "In5.Cu")
		(net "P0V8_PEX1_PWM1")
	)
	(segment
		(start 121.817638 -279.860756)
		(end 122.57405 -280.617168)
		(width 0.2032)
		(layer "In5.Cu")
		(net "P0V8_PEX1_PWM1")
	)
	(segment
		(start 113.87201 -281.999182)
		(end 113.87201 -281.438858)
		(width 0.2032)
		(layer "F.Cu")
		(net "P0V8_PEX0_PWM2")
	)
	(segment
		(start 113.950242 -281.249882)
		(end 113.950242 -280.897838)
		(width 0.2032)
		(layer "F.Cu")
		(net "P0V8_PEX0_PWM2")
	)
	(segment
		(start 113.950242 -280.897838)
		(end 114.075464 -280.617168)
		(width 0.2032)
		(layer "F.Cu")
		(net "P0V8_PEX0_PWM2")
	)
	(segment
		(start 113.87201 -281.438858)
		(end 113.950242 -281.249882)
		(width 0.2032)
		(layer "F.Cu")
		(net "P0V8_PEX0_PWM2")
	)
	(segment
		(start 121.375678 -255.11125)
		(end 121.375678 -255.994916)
		(width 0.1524)
		(layer "F.Cu")
		(net "P0V8_PEX0_PWM2")
	)
	(via
		(at 121.375678 -255.11125)
		(size 0.508)
		(drill 0.254)
		(layers "F.Cu" "B.Cu")
		(net "P0V8_PEX0_PWM2")
	)
	(via
		(at 114.075464 -280.617168)
		(size 0.508)
		(drill 0.254)
		(layers "F.Cu" "B.Cu")
		(net "P0V8_PEX0_PWM2")
	)
	(segment
		(start 119.952262 -256.534666)
		(end 119.952262 -259.994908)
		(width 0.2032)
		(layer "In5.Cu")
		(net "P0V8_PEX0_PWM2")
	)
	(segment
		(start 118.82374 -263.29767)
		(end 118.82374 -264.622534)
		(width 0.2032)
		(layer "In5.Cu")
		(net "P0V8_PEX0_PWM2")
	)
	(segment
		(start 118.82374 -264.622534)
		(end 112.990884 -270.45539)
		(width 0.2032)
		(layer "In5.Cu")
		(net "P0V8_PEX0_PWM2")
	)
	(segment
		(start 112.990884 -270.45539)
		(end 112.990884 -277.509986)
		(width 0.2032)
		(layer "In5.Cu")
		(net "P0V8_PEX0_PWM2")
	)
	(segment
		(start 119.952262 -259.994908)
		(end 118.364 -261.58317)
		(width 0.2032)
		(layer "In5.Cu")
		(net "P0V8_PEX0_PWM2")
	)
	(segment
		(start 114.075464 -278.594566)
		(end 114.075464 -280.617168)
		(width 0.2032)
		(layer "In5.Cu")
		(net "P0V8_PEX0_PWM2")
	)
	(segment
		(start 118.364 -262.83793)
		(end 118.82374 -263.29767)
		(width 0.2032)
		(layer "In5.Cu")
		(net "P0V8_PEX0_PWM2")
	)
	(segment
		(start 121.375678 -255.11125)
		(end 119.952262 -256.534666)
		(width 0.2032)
		(layer "In5.Cu")
		(net "P0V8_PEX0_PWM2")
	)
	(segment
		(start 112.990884 -277.509986)
		(end 114.075464 -278.594566)
		(width 0.2032)
		(layer "In5.Cu")
		(net "P0V8_PEX0_PWM2")
	)
	(segment
		(start 118.364 -261.58317)
		(end 118.364 -262.83793)
		(width 0.2032)
		(layer "In5.Cu")
		(net "P0V8_PEX0_PWM2")
	)
	(segment
		(start 358.802686 -256.226564)
		(end 359.45826 -256.226564)
		(width 0.13208)
		(layer "F.Cu")
		(net "P0V8_PEX2_VRHOT_R")
	)
	(segment
		(start 357.234236 -257.795014)
		(end 358.802686 -256.226564)
		(width 0.13208)
		(layer "F.Cu")
		(net "P0V8_PEX2_VRHOT_R")
	)
	(segment
		(start 355.375972 -257.795014)
		(end 357.234236 -257.795014)
		(width 0.13208)
		(layer "F.Cu")
		(net "P0V8_PEX2_VRHOT_R")
	)
	(via
		(at 358.802686 -256.226564)
		(size 0.508)
		(drill 0.254)
		(layers "F.Cu" "B.Cu")
		(net "P0V8_PEX2_VRHOT_R")
	)
	(segment
		(start 120.304306 -261.328916)
		(end 120.175782 -261.200392)
		(width 0.13208)
		(layer "F.Cu")
		(net "NC_P0V8_PEX0_ISEN3")
	)
	(segment
		(start 120.175782 -261.200392)
		(end 120.175782 -260.795008)
		(width 0.13208)
		(layer "F.Cu")
		(net "NC_P0V8_PEX0_ISEN3")
	)
	(segment
		(start 120.304306 -261.861808)
		(end 120.304306 -261.328916)
		(width 0.13208)
		(layer "F.Cu")
		(net "NC_P0V8_PEX0_ISEN3")
	)
	(via
		(at 120.304306 -261.861808)
		(size 0.508)
		(drill 0.254)
		(layers "F.Cu" "B.Cu")
		(net "NC_P0V8_PEX0_ISEN3")
	)
	(via
		(at 121.85269 -262.267954)
		(size 0.6604)
		(drill 0.3302)
		(layers "F.Cu" "B.Cu")
		(net "NC_P0V8_PEX0_ISEN3")
	)
	(segment
		(start 122.96521 -261.155434)
		(end 121.85269 -262.267954)
		(width 0.13208)
		(layer "B.Cu")
		(net "NC_P0V8_PEX0_ISEN3")
	)
	(segment
		(start 120.710452 -262.267954)
		(end 120.304306 -261.861808)
		(width 0.13208)
		(layer "B.Cu")
		(net "NC_P0V8_PEX0_ISEN3")
	)
	(segment
		(start 122.96521 -260.869176)
		(end 122.96521 -261.155434)
		(width 0.13208)
		(layer "B.Cu")
		(net "NC_P0V8_PEX0_ISEN3")
	)
	(segment
		(start 121.85269 -262.267954)
		(end 120.710452 -262.267954)
		(width 0.13208)
		(layer "B.Cu")
		(net "NC_P0V8_PEX0_ISEN3")
	)
	(segment
		(start 294.22471 -288.774886)
		(end 294.69969 -289.249866)
		(width 0.249936)
		(layer "F.Cu")
		(net "P1V25_PEX2")
	)
	(segment
		(start 295.649904 -302.549814)
		(end 296.124884 -303.024794)
		(width 0.249936)
		(layer "F.Cu")
		(net "P1V25_PEX2")
	)
	(segment
		(start 298.499784 -302.549814)
		(end 298.974764 -303.024794)
		(width 0.249936)
		(layer "F.Cu")
		(net "P1V25_PEX2")
	)
	(segment
		(start 289.94989 -289.249866)
		(end 290.42487 -288.774886)
		(width 0.249936)
		(layer "F.Cu")
		(net "P1V25_PEX2")
	)
	(segment
		(start 299.449744 -289.249866)
		(end 299.924724 -288.774886)
		(width 0.249936)
		(layer "F.Cu")
		(net "P1V25_PEX2")
	)
	(segment
		(start 302.774858 -294.4749)
		(end 302.299878 -294.94988)
		(width 0.249936)
		(layer "F.Cu")
		(net "P1V25_PEX2")
	)
	(segment
		(start 298.024804 -288.774886)
		(end 298.499784 -289.249866)
		(width 0.249936)
		(layer "F.Cu")
		(net "P1V25_PEX2")
	)
	(segment
		(start 289.47491 -288.774886)
		(end 289.94989 -289.249866)
		(width 0.249936)
		(layer "F.Cu")
		(net "P1V25_PEX2")
	)
	(segment
		(start 283.299916 -289.249866)
		(end 283.774896 -288.774886)
		(width 0.249936)
		(layer "F.Cu")
		(net "P1V25_PEX2")
	)
	(segment
		(start 288.99993 -289.249866)
		(end 289.47491 -288.774886)
		(width 0.249936)
		(layer "F.Cu")
		(net "P1V25_PEX2")
	)
	(segment
		(start 286.624776 -288.774886)
		(end 286.149796 -289.249866)
		(width 0.249936)
		(layer "F.Cu")
		(net "P1V25_PEX2")
	)
	(segment
		(start 287.574736 -303.024794)
		(end 288.049716 -302.549814)
		(width 0.249936)
		(layer "F.Cu")
		(net "P1V25_PEX2")
	)
	(segment
		(start 290.89985 -302.549814)
		(end 290.42487 -303.024794)
		(width 0.249936)
		(layer "F.Cu")
		(net "P1V25_PEX2")
	)
	(segment
		(start 297.549824 -302.549814)
		(end 298.024804 -303.024794)
		(width 0.249936)
		(layer "F.Cu")
		(net "P1V25_PEX2")
	)
	(segment
		(start 285.199836 -302.549814)
		(end 284.724856 -303.024794)
		(width 0.249936)
		(layer "F.Cu")
		(net "P1V25_PEX2")
	)
	(segment
		(start 284.249876 -289.249866)
		(end 284.724856 -288.774886)
		(width 0.249936)
		(layer "F.Cu")
		(net "P1V25_PEX2")
	)
	(segment
		(start 302.299878 -297.79976)
		(end 302.774858 -298.27474)
		(width 0.249936)
		(layer "F.Cu")
		(net "P1V25_PEX2")
	)
	(segment
		(start 302.774858 -296.37482)
		(end 302.299878 -296.8498)
		(width 0.249936)
		(layer "F.Cu")
		(net "P1V25_PEX2")
	)
	(segment
		(start 296.599864 -289.249866)
		(end 296.124884 -288.774886)
		(width 0.249936)
		(layer "F.Cu")
		(net "P1V25_PEX2")
	)
	(segment
		(start 285.199836 -302.549814)
		(end 285.674816 -303.024794)
		(width 0.249936)
		(layer "F.Cu")
		(net "P1V25_PEX2")
	)
	(segment
		(start 283.774896 -303.024794)
		(end 283.299916 -302.549814)
		(width 0.249936)
		(layer "F.Cu")
		(net "P1V25_PEX2")
	)
	(segment
		(start 292.32479 -303.024794)
		(end 291.84981 -302.549814)
		(width 0.249936)
		(layer "F.Cu")
		(net "P1V25_PEX2")
	)
	(segment
		(start 287.574736 -288.774886)
		(end 287.099756 -289.249866)
		(width 0.249936)
		(layer "F.Cu")
		(net "P1V25_PEX2")
	)
	(segment
		(start 293.74973 -302.549814)
		(end 294.22471 -303.024794)
		(width 0.249936)
		(layer "F.Cu")
		(net "P1V25_PEX2")
	)
	(segment
		(start 291.84981 -289.249866)
		(end 292.32479 -288.774886)
		(width 0.249936)
		(layer "F.Cu")
		(net "P1V25_PEX2")
	)
	(segment
		(start 285.674816 -288.774886)
		(end 286.149796 -289.249866)
		(width 0.249936)
		(layer "F.Cu")
		(net "P1V25_PEX2")
	)
	(segment
		(start 293.74973 -289.249866)
		(end 294.22471 -288.774886)
		(width 0.249936)
		(layer "F.Cu")
		(net "P1V25_PEX2")
	)
	(segment
		(start 288.524696 -288.774886)
		(end 288.99993 -289.249866)
		(width 0.249936)
		(layer "F.Cu")
		(net "P1V25_PEX2")
	)
	(segment
		(start 290.42487 -288.774886)
		(end 290.89985 -289.249866)
		(width 0.249936)
		(layer "F.Cu")
		(net "P1V25_PEX2")
	)
	(segment
		(start 288.049716 -302.549814)
		(end 288.524696 -303.024794)
		(width 0.249936)
		(layer "F.Cu")
		(net "P1V25_PEX2")
	)
	(segment
		(start 284.724856 -303.024794)
		(end 284.249876 -302.549814)
		(width 0.249936)
		(layer "F.Cu")
		(net "P1V25_PEX2")
	)
	(segment
		(start 285.674816 -303.024794)
		(end 286.149796 -302.549814)
		(width 0.249936)
		(layer "F.Cu")
		(net "P1V25_PEX2")
	)
	(segment
		(start 283.774896 -288.774886)
		(end 284.249876 -289.249866)
		(width 0.249936)
		(layer "F.Cu")
		(net "P1V25_PEX2")
	)
	(segment
		(start 297.549824 -289.249866)
		(end 297.074844 -288.774886)
		(width 0.249936)
		(layer "F.Cu")
		(net "P1V25_PEX2")
	)
	(segment
		(start 284.249876 -302.549814)
		(end 283.774896 -303.024794)
		(width 0.249936)
		(layer "F.Cu")
		(net "P1V25_PEX2")
	)
	(segment
		(start 292.79977 -302.549814)
		(end 292.32479 -303.024794)
		(width 0.249936)
		(layer "F.Cu")
		(net "P1V25_PEX2")
	)
	(segment
		(start 283.299916 -289.249866)
		(end 282.824936 -288.774886)
		(width 0.249936)
		(layer "F.Cu")
		(net "P1V25_PEX2")
	)
	(segment
		(start 287.099756 -289.249866)
		(end 286.624776 -288.774886)
		(width 0.249936)
		(layer "F.Cu")
		(net "P1V25_PEX2")
	)
	(segment
		(start 293.74973 -289.249866)
		(end 293.27475 -288.774886)
		(width 0.249936)
		(layer "F.Cu")
		(net "P1V25_PEX2")
	)
	(segment
		(start 302.299878 -297.79976)
		(end 302.774858 -297.32478)
		(width 0.249936)
		(layer "F.Cu")
		(net "P1V25_PEX2")
	)
	(segment
		(start 289.47491 -303.024794)
		(end 289.94989 -302.549814)
		(width 0.249936)
		(layer "F.Cu")
		(net "P1V25_PEX2")
	)
	(segment
		(start 285.199836 -289.249866)
		(end 285.674816 -288.774886)
		(width 0.249936)
		(layer "F.Cu")
		(net "P1V25_PEX2")
	)
	(segment
		(start 288.99993 -302.549814)
		(end 289.47491 -303.024794)
		(width 0.249936)
		(layer "F.Cu")
		(net "P1V25_PEX2")
	)
	(segment
		(start 295.174924 -288.774886)
		(end 295.649904 -289.249866)
		(width 0.249936)
		(layer "F.Cu")
		(net "P1V25_PEX2")
	)
	(segment
		(start 297.074844 -288.774886)
		(end 296.599864 -289.249866)
		(width 0.249936)
		(layer "F.Cu")
		(net "P1V25_PEX2")
	)
	(segment
		(start 288.049716 -289.249866)
		(end 288.524696 -288.774886)
		(width 0.249936)
		(layer "F.Cu")
		(net "P1V25_PEX2")
	)
	(segment
		(start 292.79977 -302.549814)
		(end 293.27475 -303.024794)
		(width 0.249936)
		(layer "F.Cu")
		(net "P1V25_PEX2")
	)
	(segment
		(start 302.774858 -293.52494)
		(end 302.299878 -293.99992)
		(width 0.249936)
		(layer "F.Cu")
		(net "P1V25_PEX2")
	)
	(segment
		(start 297.549824 -289.249866)
		(end 298.024804 -288.774886)
		(width 0.249936)
		(layer "F.Cu")
		(net "P1V25_PEX2")
	)
	(segment
		(start 287.099756 -302.549814)
		(end 286.624776 -303.024794)
		(width 0.249936)
		(layer "F.Cu")
		(net "P1V25_PEX2")
	)
	(segment
		(start 290.42487 -303.024794)
		(end 289.94989 -302.549814)
		(width 0.249936)
		(layer "F.Cu")
		(net "P1V25_PEX2")
	)
	(segment
		(start 287.099756 -302.549814)
		(end 287.574736 -303.024794)
		(width 0.249936)
		(layer "F.Cu")
		(net "P1V25_PEX2")
	)
	(segment
		(start 298.499784 -289.249866)
		(end 298.974764 -288.774886)
		(width 0.249936)
		(layer "F.Cu")
		(net "P1V25_PEX2")
	)
	(segment
		(start 302.299878 -295.89984)
		(end 302.774858 -296.37482)
		(width 0.249936)
		(layer "F.Cu")
		(net "P1V25_PEX2")
	)
	(segment
		(start 302.774858 -297.32478)
		(end 302.299878 -296.8498)
		(width 0.249936)
		(layer "F.Cu")
		(net "P1V25_PEX2")
	)
	(segment
		(start 299.449744 -302.549814)
		(end 299.924724 -303.024794)
		(width 0.249936)
		(layer "F.Cu")
		(net "P1V25_PEX2")
	)
	(segment
		(start 298.974764 -288.774886)
		(end 299.449744 -289.249866)
		(width 0.249936)
		(layer "F.Cu")
		(net "P1V25_PEX2")
	)
	(segment
		(start 288.049716 -289.249866)
		(end 287.574736 -288.774886)
		(width 0.249936)
		(layer "F.Cu")
		(net "P1V25_PEX2")
	)
	(segment
		(start 293.27475 -288.774886)
		(end 292.79977 -289.249866)
		(width 0.249936)
		(layer "F.Cu")
		(net "P1V25_PEX2")
	)
	(segment
		(start 296.124884 -288.774886)
		(end 295.649904 -289.249866)
		(width 0.249936)
		(layer "F.Cu")
		(net "P1V25_PEX2")
	)
	(segment
		(start 288.524696 -303.024794)
		(end 288.99993 -302.549814)
		(width 0.249936)
		(layer "F.Cu")
		(net "P1V25_PEX2")
	)
	(segment
		(start 286.624776 -303.024794)
		(end 286.149796 -302.549814)
		(width 0.249936)
		(layer "F.Cu")
		(net "P1V25_PEX2")
	)
	(segment
		(start 292.32479 -288.774886)
		(end 292.79977 -289.249866)
		(width 0.249936)
		(layer "F.Cu")
		(net "P1V25_PEX2")
	)
	(segment
		(start 284.724856 -288.774886)
		(end 285.199836 -289.249866)
		(width 0.249936)
		(layer "F.Cu")
		(net "P1V25_PEX2")
	)
	(segment
		(start 296.599864 -302.549814)
		(end 297.074844 -303.024794)
		(width 0.249936)
		(layer "F.Cu")
		(net "P1V25_PEX2")
	)
	(segment
		(start 283.299916 -302.549814)
		(end 282.824936 -303.024794)
		(width 0.249936)
		(layer "F.Cu")
		(net "P1V25_PEX2")
	)
	(segment
		(start 294.69969 -302.549814)
		(end 295.174924 -303.024794)
		(width 0.249936)
		(layer "F.Cu")
		(net "P1V25_PEX2")
	)
	(segment
		(start 294.69969 -289.249866)
		(end 295.174924 -288.774886)
		(width 0.249936)
		(layer "F.Cu")
		(net "P1V25_PEX2")
	)
	(segment
		(start 247.954038 -308.568852)
		(end 248.567956 -308.568852)
		(width 0.254)
		(layer "F.Cu")
		(net "P1V25_PEX2")
	)
	(via
		(at 236.801406 -272.842228)
		(size 0.508)
		(drill 0.254)
		(layers "F.Cu" "B.Cu")
		(net "P1V25_PEX2")
	)
	(via
		(at 284.724856 -303.024794)
		(size 0.4064)
		(drill 0.2032)
		(layers "F.Cu" "B.Cu")
		(net "P1V25_PEX2")
	)
	(via
		(at 295.174924 -303.024794)
		(size 0.4064)
		(drill 0.2032)
		(layers "F.Cu" "B.Cu")
		(net "P1V25_PEX2")
	)
	(via
		(at 287.574736 -288.774886)
		(size 0.4064)
		(drill 0.2032)
		(layers "F.Cu" "B.Cu")
		(net "P1V25_PEX2")
	)
	(via
		(at 288.524696 -303.024794)
		(size 0.4064)
		(drill 0.2032)
		(layers "F.Cu" "B.Cu")
		(net "P1V25_PEX2")
	)
	(via
		(at 294.22471 -288.774886)
		(size 0.4064)
		(drill 0.2032)
		(layers "F.Cu" "B.Cu")
		(net "P1V25_PEX2")
	)
	(via
		(at 237.461806 -272.842228)
		(size 0.508)
		(drill 0.254)
		(layers "F.Cu" "B.Cu")
		(net "P1V25_PEX2")
	)
	(via
		(at 241.136424 -272.822416)
		(size 0.508)
		(drill 0.254)
		(layers "F.Cu" "B.Cu")
		(net "P1V25_PEX2")
	)
	(via
		(at 282.824936 -288.774886)
		(size 0.4064)
		(drill 0.2032)
		(layers "F.Cu" "B.Cu")
		(net "P1V25_PEX2")
	)
	(via
		(at 242.457224 -272.822416)
		(size 0.508)
		(drill 0.254)
		(layers "F.Cu" "B.Cu")
		(net "P1V25_PEX2")
	)
	(via
		(at 294.22471 -303.024794)
		(size 0.4064)
		(drill 0.2032)
		(layers "F.Cu" "B.Cu")
		(net "P1V25_PEX2")
	)
	(via
		(at 298.974764 -288.774886)
		(size 0.4064)
		(drill 0.2032)
		(layers "F.Cu" "B.Cu")
		(net "P1V25_PEX2")
	)
	(via
		(at 282.824936 -303.024794)
		(size 0.4064)
		(drill 0.2032)
		(layers "F.Cu" "B.Cu")
		(net "P1V25_PEX2")
	)
	(via
		(at 241.796824 -272.187416)
		(size 0.508)
		(drill 0.254)
		(layers "F.Cu" "B.Cu")
		(net "P1V25_PEX2")
	)
	(via
		(at 238.122206 -272.207228)
		(size 0.508)
		(drill 0.254)
		(layers "F.Cu" "B.Cu")
		(net "P1V25_PEX2")
	)
	(via
		(at 237.293912 -276.582886)
		(size 0.508)
		(drill 0.254)
		(layers "F.Cu" "B.Cu")
		(net "P1V25_PEX2")
	)
	(via
		(at 237.293912 -277.217886)
		(size 0.508)
		(drill 0.254)
		(layers "F.Cu" "B.Cu")
		(net "P1V25_PEX2")
	)
	(via
		(at 284.724856 -288.774886)
		(size 0.4064)
		(drill 0.2032)
		(layers "F.Cu" "B.Cu")
		(net "P1V25_PEX2")
	)
	(via
		(at 295.174924 -288.774886)
		(size 0.4064)
		(drill 0.2032)
		(layers "F.Cu" "B.Cu")
		(net "P1V25_PEX2")
	)
	(via
		(at 236.633512 -276.582886)
		(size 0.508)
		(drill 0.254)
		(layers "F.Cu" "B.Cu")
		(net "P1V25_PEX2")
	)
	(via
		(at 283.774896 -303.024794)
		(size 0.4064)
		(drill 0.2032)
		(layers "F.Cu" "B.Cu")
		(net "P1V25_PEX2")
	)
	(via
		(at 302.774858 -293.52494)
		(size 0.4064)
		(drill 0.2032)
		(layers "F.Cu" "B.Cu")
		(net "P1V25_PEX2")
	)
	(via
		(at 238.122206 -272.842228)
		(size 0.508)
		(drill 0.254)
		(layers "F.Cu" "B.Cu")
		(net "P1V25_PEX2")
	)
	(via
		(at 240.476024 -272.187416)
		(size 0.508)
		(drill 0.254)
		(layers "F.Cu" "B.Cu")
		(net "P1V25_PEX2")
	)
	(via
		(at 286.624776 -303.024794)
		(size 0.4064)
		(drill 0.2032)
		(layers "F.Cu" "B.Cu")
		(net "P1V25_PEX2")
	)
	(via
		(at 293.27475 -288.774886)
		(size 0.4064)
		(drill 0.2032)
		(layers "F.Cu" "B.Cu")
		(net "P1V25_PEX2")
	)
	(via
		(at 285.674816 -288.774886)
		(size 0.4064)
		(drill 0.2032)
		(layers "F.Cu" "B.Cu")
		(net "P1V25_PEX2")
	)
	(via
		(at 240.952782 -274.042632)
		(size 0.6604)
		(drill 0.3302)
		(layers "F.Cu" "B.Cu")
		(net "P1V25_PEX2")
	)
	(via
		(at 302.774858 -297.32478)
		(size 0.4064)
		(drill 0.2032)
		(layers "F.Cu" "B.Cu")
		(net "P1V25_PEX2")
	)
	(via
		(at 238.614712 -277.217886)
		(size 0.508)
		(drill 0.254)
		(layers "F.Cu" "B.Cu")
		(net "P1V25_PEX2")
	)
	(via
		(at 298.024804 -288.774886)
		(size 0.4064)
		(drill 0.2032)
		(layers "F.Cu" "B.Cu")
		(net "P1V25_PEX2")
	)
	(via
		(at 298.974764 -303.024794)
		(size 0.4064)
		(drill 0.2032)
		(layers "F.Cu" "B.Cu")
		(net "P1V25_PEX2")
	)
	(via
		(at 297.074844 -288.774886)
		(size 0.4064)
		(drill 0.2032)
		(layers "F.Cu" "B.Cu")
		(net "P1V25_PEX2")
	)
	(via
		(at 299.924724 -288.774886)
		(size 0.4064)
		(drill 0.2032)
		(layers "F.Cu" "B.Cu")
		(net "P1V25_PEX2")
	)
	(via
		(at 302.774858 -296.37482)
		(size 0.4064)
		(drill 0.2032)
		(layers "F.Cu" "B.Cu")
		(net "P1V25_PEX2")
	)
	(via
		(at 238.782606 -272.207228)
		(size 0.508)
		(drill 0.254)
		(layers "F.Cu" "B.Cu")
		(net "P1V25_PEX2")
	)
	(via
		(at 240.476024 -272.822416)
		(size 0.508)
		(drill 0.254)
		(layers "F.Cu" "B.Cu")
		(net "P1V25_PEX2")
	)
	(via
		(at 302.774858 -298.27474)
		(size 0.4064)
		(drill 0.2032)
		(layers "F.Cu" "B.Cu")
		(net "P1V25_PEX2")
	)
	(via
		(at 238.614712 -276.582886)
		(size 0.508)
		(drill 0.254)
		(layers "F.Cu" "B.Cu")
		(net "P1V25_PEX2")
	)
	(via
		(at 289.47491 -288.774886)
		(size 0.4064)
		(drill 0.2032)
		(layers "F.Cu" "B.Cu")
		(net "P1V25_PEX2")
	)
	(via
		(at 236.633512 -277.217886)
		(size 0.508)
		(drill 0.254)
		(layers "F.Cu" "B.Cu")
		(net "P1V25_PEX2")
	)
	(via
		(at 296.124884 -288.774886)
		(size 0.4064)
		(drill 0.2032)
		(layers "F.Cu" "B.Cu")
		(net "P1V25_PEX2")
	)
	(via
		(at 296.124884 -303.024794)
		(size 0.4064)
		(drill 0.2032)
		(layers "F.Cu" "B.Cu")
		(net "P1V25_PEX2")
	)
	(via
		(at 283.774896 -288.774886)
		(size 0.4064)
		(drill 0.2032)
		(layers "F.Cu" "B.Cu")
		(net "P1V25_PEX2")
	)
	(via
		(at 292.32479 -303.024794)
		(size 0.4064)
		(drill 0.2032)
		(layers "F.Cu" "B.Cu")
		(net "P1V25_PEX2")
	)
	(via
		(at 293.27475 -303.024794)
		(size 0.4064)
		(drill 0.2032)
		(layers "F.Cu" "B.Cu")
		(net "P1V25_PEX2")
	)
	(via
		(at 297.074844 -303.024794)
		(size 0.4064)
		(drill 0.2032)
		(layers "F.Cu" "B.Cu")
		(net "P1V25_PEX2")
	)
	(via
		(at 299.924724 -303.024794)
		(size 0.4064)
		(drill 0.2032)
		(layers "F.Cu" "B.Cu")
		(net "P1V25_PEX2")
	)
	(via
		(at 241.796824 -272.822416)
		(size 0.508)
		(drill 0.254)
		(layers "F.Cu" "B.Cu")
		(net "P1V25_PEX2")
	)
	(via
		(at 287.574736 -303.024794)
		(size 0.4064)
		(drill 0.2032)
		(layers "F.Cu" "B.Cu")
		(net "P1V25_PEX2")
	)
	(via
		(at 286.624776 -288.774886)
		(size 0.4064)
		(drill 0.2032)
		(layers "F.Cu" "B.Cu")
		(net "P1V25_PEX2")
	)
	(via
		(at 292.32479 -288.774886)
		(size 0.4064)
		(drill 0.2032)
		(layers "F.Cu" "B.Cu")
		(net "P1V25_PEX2")
	)
	(via
		(at 240.434368 -275.505164)
		(size 0.508)
		(drill 0.254)
		(layers "F.Cu" "B.Cu")
		(net "P1V25_PEX2")
	)
	(via
		(at 237.461806 -272.207228)
		(size 0.508)
		(drill 0.254)
		(layers "F.Cu" "B.Cu")
		(net "P1V25_PEX2")
	)
	(via
		(at 290.42487 -288.774886)
		(size 0.4064)
		(drill 0.2032)
		(layers "F.Cu" "B.Cu")
		(net "P1V25_PEX2")
	)
	(via
		(at 310.374792 -296.37482)
		(size 0.4064)
		(drill 0.2032)
		(layers "F.Cu" "B.Cu")
		(net "P1V25_PEX2")
	)
	(via
		(at 239.799368 -275.505164)
		(size 0.508)
		(drill 0.254)
		(layers "F.Cu" "B.Cu")
		(net "P1V25_PEX2")
	)
	(via
		(at 298.024804 -303.024794)
		(size 0.4064)
		(drill 0.2032)
		(layers "F.Cu" "B.Cu")
		(net "P1V25_PEX2")
	)
	(via
		(at 248.567956 -308.568852)
		(size 0.508)
		(drill 0.254)
		(layers "F.Cu" "B.Cu")
		(net "P1V25_PEX2")
	)
	(via
		(at 241.136424 -272.187416)
		(size 0.508)
		(drill 0.254)
		(layers "F.Cu" "B.Cu")
		(net "P1V25_PEX2")
	)
	(via
		(at 237.954312 -277.217886)
		(size 0.508)
		(drill 0.254)
		(layers "F.Cu" "B.Cu")
		(net "P1V25_PEX2")
	)
	(via
		(at 285.674816 -303.024794)
		(size 0.4064)
		(drill 0.2032)
		(layers "F.Cu" "B.Cu")
		(net "P1V25_PEX2")
	)
	(via
		(at 237.954312 -276.582886)
		(size 0.508)
		(drill 0.254)
		(layers "F.Cu" "B.Cu")
		(net "P1V25_PEX2")
	)
	(via
		(at 302.677322 -295.430956)
		(size 0.6604)
		(drill 0.3302)
		(layers "F.Cu" "B.Cu")
		(net "P1V25_PEX2")
	)
	(via
		(at 238.782606 -272.842228)
		(size 0.508)
		(drill 0.254)
		(layers "F.Cu" "B.Cu")
		(net "P1V25_PEX2")
	)
	(via
		(at 242.457224 -272.187416)
		(size 0.508)
		(drill 0.254)
		(layers "F.Cu" "B.Cu")
		(net "P1V25_PEX2")
	)
	(via
		(at 309.424832 -296.37482)
		(size 0.4064)
		(drill 0.2032)
		(layers "F.Cu" "B.Cu")
		(net "P1V25_PEX2")
	)
	(via
		(at 290.42487 -303.024794)
		(size 0.4064)
		(drill 0.2032)
		(layers "F.Cu" "B.Cu")
		(net "P1V25_PEX2")
	)
	(via
		(at 289.47491 -303.024794)
		(size 0.4064)
		(drill 0.2032)
		(layers "F.Cu" "B.Cu")
		(net "P1V25_PEX2")
	)
	(via
		(at 236.801406 -272.207228)
		(size 0.508)
		(drill 0.254)
		(layers "F.Cu" "B.Cu")
		(net "P1V25_PEX2")
	)
	(via
		(at 237.205266 -274.085558)
		(size 0.6604)
		(drill 0.3302)
		(layers "F.Cu" "B.Cu")
		(net "P1V25_PEX2")
	)
	(via
		(at 309.424832 -294.4749)
		(size 0.4064)
		(drill 0.2032)
		(layers "F.Cu" "B.Cu")
		(net "P1V25_PEX2")
	)
	(via
		(at 288.524696 -288.774886)
		(size 0.4064)
		(drill 0.2032)
		(layers "F.Cu" "B.Cu")
		(net "P1V25_PEX2")
	)
	(via
		(at 302.774858 -294.4749)
		(size 0.4064)
		(drill 0.2032)
		(layers "F.Cu" "B.Cu")
		(net "P1V25_PEX2")
	)
	(segment
		(start 248.869962 -308.266846)
		(end 254.704596 -308.266846)
		(width 0.254)
		(layer "In9.Cu")
		(net "P1V25_PEX2")
	)
	(segment
		(start 290.889182 -303.024794)
		(end 290.42487 -303.024794)
		(width 0.254)
		(layer "In9.Cu")
		(net "P1V25_PEX2")
	)
	(segment
		(start 267.021056 -295.27881)
		(end 267.582396 -295.84015)
		(width 0.254)
		(layer "In9.Cu")
		(net "P1V25_PEX2")
	)
	(segment
		(start 290.552632 -295.84015)
		(end 291.21227 -296.499788)
		(width 0.254)
		(layer "In9.Cu")
		(net "P1V25_PEX2")
	)
	(segment
		(start 262.634222 -295.88587)
		(end 263.241282 -295.27881)
		(width 0.254)
		(layer "In9.Cu")
		(net "P1V25_PEX2")
	)
	(segment
		(start 291.21227 -296.499788)
		(end 291.21227 -302.701706)
		(width 0.254)
		(layer "In9.Cu")
		(net "P1V25_PEX2")
	)
	(segment
		(start 262.634222 -300.33722)
		(end 262.634222 -295.88587)
		(width 0.254)
		(layer "In9.Cu")
		(net "P1V25_PEX2")
	)
	(segment
		(start 248.567956 -308.568852)
		(end 248.869962 -308.266846)
		(width 0.254)
		(layer "In9.Cu")
		(net "P1V25_PEX2")
	)
	(segment
		(start 291.21227 -302.701706)
		(end 290.889182 -303.024794)
		(width 0.254)
		(layer "In9.Cu")
		(net "P1V25_PEX2")
	)
	(segment
		(start 254.704596 -308.266846)
		(end 262.634222 -300.33722)
		(width 0.254)
		(layer "In9.Cu")
		(net "P1V25_PEX2")
	)
	(segment
		(start 267.582396 -295.84015)
		(end 290.552632 -295.84015)
		(width 0.254)
		(layer "In9.Cu")
		(net "P1V25_PEX2")
	)
	(segment
		(start 263.241282 -295.27881)
		(end 267.021056 -295.27881)
		(width 0.254)
		(layer "In9.Cu")
		(net "P1V25_PEX2")
	)
	(segment
		(start 121.375678 -261.100824)
		(end 121.412 -261.137146)
		(width 0.1778)
		(layer "F.Cu")
		(net "P0V8_PEX0_ISEN2")
	)
	(segment
		(start 121.375678 -260.795008)
		(end 121.375678 -261.100824)
		(width 0.1778)
		(layer "F.Cu")
		(net "P0V8_PEX0_ISEN2")
	)
	(segment
		(start 121.412 -261.137146)
		(end 121.412 -264.323322)
		(width 0.1778)
		(layer "F.Cu")
		(net "P0V8_PEX0_ISEN2")
	)
	(segment
		(start 116.109242 -281.217116)
		(end 116.109242 -281.151838)
		(width 0.2286)
		(layer "F.Cu")
		(net "P0V8_PEX0_ISEN2")
	)
	(segment
		(start 121.412 -264.323322)
		(end 120.799352 -264.93597)
		(width 0.1778)
		(layer "F.Cu")
		(net "P0V8_PEX0_ISEN2")
	)
	(segment
		(start 115.672108 -281.65425)
		(end 116.109242 -281.217116)
		(width 0.2286)
		(layer "F.Cu")
		(net "P0V8_PEX0_ISEN2")
	)
	(segment
		(start 115.672108 -281.999182)
		(end 115.672108 -281.65425)
		(width 0.2286)
		(layer "F.Cu")
		(net "P0V8_PEX0_ISEN2")
	)
	(via
		(at 116.109242 -281.151838)
		(size 0.508)
		(drill 0.254)
		(layers "F.Cu" "B.Cu")
		(net "P0V8_PEX0_ISEN2")
	)
	(via
		(at 120.799352 -264.93597)
		(size 0.508)
		(drill 0.254)
		(layers "F.Cu" "B.Cu")
		(net "P0V8_PEX0_ISEN2")
	)
	(segment
		(start 120.799352 -264.93597)
		(end 120.799352 -267.365226)
		(width 0.254)
		(layer "In11.Cu")
		(net "P0V8_PEX0_ISEN2")
	)
	(segment
		(start 116.597176 -280.663904)
		(end 116.109242 -281.151838)
		(width 0.254)
		(layer "In11.Cu")
		(net "P0V8_PEX0_ISEN2")
	)
	(segment
		(start 120.799352 -267.365226)
		(end 118.452392 -269.712186)
		(width 0.254)
		(layer "In11.Cu")
		(net "P0V8_PEX0_ISEN2")
	)
	(segment
		(start 118.452392 -279.328372)
		(end 117.11686 -280.663904)
		(width 0.254)
		(layer "In11.Cu")
		(net "P0V8_PEX0_ISEN2")
	)
	(segment
		(start 117.11686 -280.663904)
		(end 116.597176 -280.663904)
		(width 0.254)
		(layer "In11.Cu")
		(net "P0V8_PEX0_ISEN2")
	)
	(segment
		(start 118.452392 -269.712186)
		(end 118.452392 -279.328372)
		(width 0.254)
		(layer "In11.Cu")
		(net "P0V8_PEX0_ISEN2")
	)
	(segment
		(start 456.776836 -310.392064)
		(end 457.724002 -311.33923)
		(width 0.13208)
		(layer "F.Cu")
		(net "PWRGD_P1V25_PEX3")
	)
	(segment
		(start 457.724002 -311.33923)
		(end 458.502004 -311.33923)
		(width 0.13208)
		(layer "F.Cu")
		(net "PWRGD_P1V25_PEX3")
	)
	(segment
		(start 456.540108 -310.392064)
		(end 456.776836 -310.392064)
		(width 0.13208)
		(layer "F.Cu")
		(net "PWRGD_P1V25_PEX3")
	)
	(via
		(at 458.502004 -311.33923)
		(size 0.508)
		(drill 0.254)
		(layers "F.Cu" "B.Cu")
		(net "PWRGD_P1V25_PEX3")
	)
	(segment
		(start 461.729328 -307.189378)
		(end 461.729328 -306.207414)
		(width 0.13208)
		(layer "B.Cu")
		(net "PWRGD_P1V25_PEX3")
	)
	(segment
		(start 460.624936 -307.904388)
		(end 460.226918 -308.302406)
		(width 0.13208)
		(layer "B.Cu")
		(net "PWRGD_P1V25_PEX3")
	)
	(segment
		(start 459.135988 -311.33923)
		(end 458.502004 -311.33923)
		(width 0.13208)
		(layer "B.Cu")
		(net "PWRGD_P1V25_PEX3")
	)
	(segment
		(start 461.550766 -306.19065)
		(end 460.624936 -307.11648)
		(width 0.13208)
		(layer "B.Cu")
		(net "PWRGD_P1V25_PEX3")
	)
	(segment
		(start 460.624936 -307.11648)
		(end 460.624936 -307.904388)
		(width 0.13208)
		(layer "B.Cu")
		(net "PWRGD_P1V25_PEX3")
	)
	(segment
		(start 461.712564 -306.19065)
		(end 461.550766 -306.19065)
		(width 0.13208)
		(layer "B.Cu")
		(net "PWRGD_P1V25_PEX3")
	)
	(segment
		(start 460.226918 -310.2483)
		(end 459.135988 -311.33923)
		(width 0.13208)
		(layer "B.Cu")
		(net "PWRGD_P1V25_PEX3")
	)
	(segment
		(start 460.226918 -308.302406)
		(end 460.226918 -310.2483)
		(width 0.13208)
		(layer "B.Cu")
		(net "PWRGD_P1V25_PEX3")
	)
	(segment
		(start 461.729328 -306.207414)
		(end 461.712564 -306.19065)
		(width 0.13208)
		(layer "B.Cu")
		(net "PWRGD_P1V25_PEX3")
	)
	(segment
		(start 300.399704 -299.699934)
		(end 300.874684 -300.174914)
		(width 0.249936)
		(layer "F.Cu")
		(net "P1V8_VDDA_PEX2")
	)
	(segment
		(start 277.124922 -298.27474)
		(end 277.599902 -297.79976)
		(width 0.249936)
		(layer "F.Cu")
		(net "P1V8_VDDA_PEX2")
	)
	(segment
		(start 277.599902 -298.74972)
		(end 277.124922 -299.224954)
		(width 0.249936)
		(layer "F.Cu")
		(net "P1V8_VDDA_PEX2")
	)
	(segment
		(start 277.599902 -299.699934)
		(end 277.124922 -300.174914)
		(width 0.249936)
		(layer "F.Cu")
		(net "P1V8_VDDA_PEX2")
	)
	(segment
		(start 277.599902 -298.74972)
		(end 277.124922 -298.27474)
		(width 0.249936)
		(layer "F.Cu")
		(net "P1V8_VDDA_PEX2")
	)
	(segment
		(start 281.399742 -302.549814)
		(end 280.924762 -303.024794)
		(width 0.249936)
		(layer "F.Cu")
		(net "P1V8_VDDA_PEX2")
	)
	(segment
		(start 301.349918 -287.349946)
		(end 301.824898 -286.874966)
		(width 0.249936)
		(layer "F.Cu")
		(net "P1V8_VDDA_PEX2")
	)
	(segment
		(start 303.249838 -299.699934)
		(end 303.724818 -300.174914)
		(width 0.249936)
		(layer "F.Cu")
		(net "P1V8_VDDA_PEX2")
	)
	(segment
		(start 301.349918 -304.449734)
		(end 301.824898 -304.924714)
		(width 0.249936)
		(layer "F.Cu")
		(net "P1V8_VDDA_PEX2")
	)
	(segment
		(start 281.399742 -289.249866)
		(end 280.924762 -288.774886)
		(width 0.249936)
		(layer "F.Cu")
		(net "P1V8_VDDA_PEX2")
	)
	(segment
		(start 277.124922 -299.224954)
		(end 277.599902 -299.699934)
		(width 0.249936)
		(layer "F.Cu")
		(net "P1V8_VDDA_PEX2")
	)
	(via
		(at 300.874684 -300.174914)
		(size 0.4064)
		(drill 0.2032)
		(layers "F.Cu" "B.Cu")
		(net "P1V8_VDDA_PEX2")
	)
	(via
		(at 258.862322 -261.790688)
		(size 0.508)
		(drill 0.254)
		(layers "F.Cu" "B.Cu")
		(net "P1V8_VDDA_PEX2")
	)
	(via
		(at 277.124922 -300.174914)
		(size 0.4064)
		(drill 0.2032)
		(layers "F.Cu" "B.Cu")
		(net "P1V8_VDDA_PEX2")
	)
	(via
		(at 280.924762 -288.774886)
		(size 0.4064)
		(drill 0.2032)
		(layers "F.Cu" "B.Cu")
		(net "P1V8_VDDA_PEX2")
	)
	(via
		(at 278.549354 -303.508918)
		(size 0.6604)
		(drill 0.3302)
		(layers "F.Cu" "B.Cu")
		(net "P1V8_VDDA_PEX2")
	)
	(via
		(at 280.924762 -303.024794)
		(size 0.4064)
		(drill 0.2032)
		(layers "F.Cu" "B.Cu")
		(net "P1V8_VDDA_PEX2")
	)
	(via
		(at 272.9611 -271.781524)
		(size 0.508)
		(drill 0.254)
		(layers "F.Cu" "B.Cu")
		(net "P1V8_VDDA_PEX2")
	)
	(via
		(at 301.824898 -286.874966)
		(size 0.4064)
		(drill 0.2032)
		(layers "F.Cu" "B.Cu")
		(net "P1V8_VDDA_PEX2")
	)
	(via
		(at 259.624322 -261.790688)
		(size 0.508)
		(drill 0.254)
		(layers "F.Cu" "B.Cu")
		(net "P1V8_VDDA_PEX2")
	)
	(via
		(at 301.824898 -304.924714)
		(size 0.4064)
		(drill 0.2032)
		(layers "F.Cu" "B.Cu")
		(net "P1V8_VDDA_PEX2")
	)
	(via
		(at 304.879502 -286.5374)
		(size 0.6604)
		(drill 0.3302)
		(layers "F.Cu" "B.Cu")
		(net "P1V8_VDDA_PEX2")
	)
	(via
		(at 303.724818 -300.174914)
		(size 0.4064)
		(drill 0.2032)
		(layers "F.Cu" "B.Cu")
		(net "P1V8_VDDA_PEX2")
	)
	(via
		(at 277.124922 -298.27474)
		(size 0.4064)
		(drill 0.2032)
		(layers "F.Cu" "B.Cu")
		(net "P1V8_VDDA_PEX2")
	)
	(via
		(at 258.100322 -261.790688)
		(size 0.508)
		(drill 0.254)
		(layers "F.Cu" "B.Cu")
		(net "P1V8_VDDA_PEX2")
	)
	(via
		(at 275.122386 -297.203368)
		(size 0.6604)
		(drill 0.3302)
		(layers "F.Cu" "B.Cu")
		(net "P1V8_VDDA_PEX2")
	)
	(via
		(at 277.124922 -299.224954)
		(size 0.4064)
		(drill 0.2032)
		(layers "F.Cu" "B.Cu")
		(net "P1V8_VDDA_PEX2")
	)
	(segment
		(start 276.5552 -296.898822)
		(end 275.426932 -296.898822)
		(width 0.13208)
		(layer "B.Cu")
		(net "P1V8_VDDA_PEX2")
	)
	(segment
		(start 301.824898 -304.508154)
		(end 301.824898 -304.924714)
		(width 0.3048)
		(layer "B.Cu")
		(net "P1V8_VDDA_PEX2")
	)
	(segment
		(start 276.733 -297.5356)
		(end 276.733 -297.076622)
		(width 0.13208)
		(layer "B.Cu")
		(net "P1V8_VDDA_PEX2")
	)
	(segment
		(start 280.508202 -303.107598)
		(end 280.106882 -303.508918)
		(width 0.13208)
		(layer "B.Cu")
		(net "P1V8_VDDA_PEX2")
	)
	(segment
		(start 275.426932 -296.898822)
		(end 275.122386 -297.203368)
		(width 0.13208)
		(layer "B.Cu")
		(net "P1V8_VDDA_PEX2")
	)
	(segment
		(start 280.106882 -303.508918)
		(end 278.549354 -303.508918)
		(width 0.13208)
		(layer "B.Cu")
		(net "P1V8_VDDA_PEX2")
	)
	(segment
		(start 280.508202 -303.024794)
		(end 280.508202 -303.107598)
		(width 0.13208)
		(layer "B.Cu")
		(net "P1V8_VDDA_PEX2")
	)
	(segment
		(start 301.824898 -305.341528)
		(end 301.824898 -304.924714)
		(width 0.3048)
		(layer "B.Cu")
		(net "P1V8_VDDA_PEX2")
	)
	(segment
		(start 276.733 -297.076622)
		(end 276.5552 -296.898822)
		(width 0.13208)
		(layer "B.Cu")
		(net "P1V8_VDDA_PEX2")
	)
	(segment
		(start 281.133042 -288.774886)
		(end 280.924762 -288.774886)
		(width 0.3048)
		(layer "B.Cu")
		(net "P1V8_VDDA_PEX2")
	)
	(segment
		(start 301.083218 -300.174914)
		(end 300.874684 -300.174914)
		(width 0.3048)
		(layer "B.Cu")
		(net "P1V8_VDDA_PEX2")
	)
	(segment
		(start 276.9108 -297.7134)
		(end 276.733 -297.5356)
		(width 0.13208)
		(layer "B.Cu")
		(net "P1V8_VDDA_PEX2")
	)
	(segment
		(start 304.141378 -300.174914)
		(end 303.724818 -300.174914)
		(width 0.3048)
		(layer "B.Cu")
		(net "P1V8_VDDA_PEX2")
	)
	(segment
		(start 303.308258 -300.174914)
		(end 303.724818 -300.174914)
		(width 0.3048)
		(layer "B.Cu")
		(net "P1V8_VDDA_PEX2")
	)
	(segment
		(start 260.356096 -260.712712)
		(end 259.624322 -261.444486)
		(width 0.381)
		(layer "In11.Cu")
		(net "P1V8_VDDA_PEX2")
	)
	(segment
		(start 269.913862 -266.837668)
		(end 269.913862 -264.418064)
		(width 0.381)
		(layer "In11.Cu")
		(net "P1V8_VDDA_PEX2")
	)
	(segment
		(start 270.291814 -269.112238)
		(end 270.291814 -267.21562)
		(width 0.381)
		(layer "In11.Cu")
		(net "P1V8_VDDA_PEX2")
	)
	(segment
		(start 259.624322 -261.444486)
		(end 259.624322 -261.790688)
		(width 0.381)
		(layer "In11.Cu")
		(net "P1V8_VDDA_PEX2")
	)
	(segment
		(start 270.291814 -267.21562)
		(end 269.913862 -266.837668)
		(width 0.381)
		(layer "In11.Cu")
		(net "P1V8_VDDA_PEX2")
	)
	(segment
		(start 266.20851 -260.712712)
		(end 260.356096 -260.712712)
		(width 0.381)
		(layer "In11.Cu")
		(net "P1V8_VDDA_PEX2")
	)
	(segment
		(start 272.9611 -271.781524)
		(end 270.291814 -269.112238)
		(width 0.381)
		(layer "In11.Cu")
		(net "P1V8_VDDA_PEX2")
	)
	(segment
		(start 269.913862 -264.418064)
		(end 266.20851 -260.712712)
		(width 0.381)
		(layer "In11.Cu")
		(net "P1V8_VDDA_PEX2")
	)
	(via
		(at 345.029028 -282.866592)
		(size 0.508)
		(drill 0.254)
		(layers "F.Cu" "B.Cu")
		(net "SW_P12V_P0V8_PEX2_FLT")
	)
	(via
		(at 344.305382 -284.175454)
		(size 0.508)
		(drill 0.254)
		(layers "F.Cu" "B.Cu")
		(net "SW_P12V_P0V8_PEX2_FLT")
	)
	(via
		(at 343.178638 -281.786838)
		(size 0.508)
		(drill 0.254)
		(layers "F.Cu" "B.Cu")
		(net "SW_P12V_P0V8_PEX2_FLT")
	)
	(via
		(at 335.551526 -281.431238)
		(size 0.508)
		(drill 0.254)
		(layers "F.Cu" "B.Cu")
		(net "SW_P12V_P0V8_PEX2_FLT")
	)
	(via
		(at 343.936828 -282.866592)
		(size 0.508)
		(drill 0.254)
		(layers "F.Cu" "B.Cu")
		(net "SW_P12V_P0V8_PEX2_FLT")
	)
	(via
		(at 343.712038 -281.431238)
		(size 0.508)
		(drill 0.254)
		(layers "F.Cu" "B.Cu")
		(net "SW_P12V_P0V8_PEX2_FLT")
	)
	(via
		(at 344.305382 -283.489654)
		(size 0.508)
		(drill 0.254)
		(layers "F.Cu" "B.Cu")
		(net "SW_P12V_P0V8_PEX2_FLT")
	)
	(via
		(at 336.090006 -275.64207)
		(size 0.508)
		(drill 0.254)
		(layers "F.Cu" "B.Cu")
		(net "SW_P12V_P0V8_PEX2_FLT")
	)
	(via
		(at 335.776316 -282.866592)
		(size 0.508)
		(drill 0.254)
		(layers "F.Cu" "B.Cu")
		(net "SW_P12V_P0V8_PEX2_FLT")
	)
	(via
		(at 336.852006 -275.64207)
		(size 0.508)
		(drill 0.254)
		(layers "F.Cu" "B.Cu")
		(net "SW_P12V_P0V8_PEX2_FLT")
	)
	(via
		(at 335.043526 -282.548838)
		(size 0.508)
		(drill 0.254)
		(layers "F.Cu" "B.Cu")
		(net "SW_P12V_P0V8_PEX2_FLT")
	)
	(via
		(at 336.923634 -277.171658)
		(size 0.508)
		(drill 0.254)
		(layers "F.Cu" "B.Cu")
		(net "SW_P12V_P0V8_PEX2_FLT")
	)
	(via
		(at 336.083402 -274.955254)
		(size 0.508)
		(drill 0.254)
		(layers "F.Cu" "B.Cu")
		(net "SW_P12V_P0V8_PEX2_FLT")
	)
	(via
		(at 336.14487 -283.489654)
		(size 0.508)
		(drill 0.254)
		(layers "F.Cu" "B.Cu")
		(net "SW_P12V_P0V8_PEX2_FLT")
	)
	(via
		(at 342.278208 -277.321264)
		(size 0.508)
		(drill 0.254)
		(layers "F.Cu" "B.Cu")
		(net "SW_P12V_P0V8_PEX2_FLT")
	)
	(via
		(at 336.852006 -276.40407)
		(size 0.508)
		(drill 0.254)
		(layers "F.Cu" "B.Cu")
		(net "SW_P12V_P0V8_PEX2_FLT")
	)
	(via
		(at 336.047334 -277.102824)
		(size 0.508)
		(drill 0.254)
		(layers "F.Cu" "B.Cu")
		(net "SW_P12V_P0V8_PEX2_FLT")
	)
	(via
		(at 343.737438 -282.091638)
		(size 0.508)
		(drill 0.254)
		(layers "F.Cu" "B.Cu")
		(net "SW_P12V_P0V8_PEX2_FLT")
	)
	(via
		(at 343.006172 -276.933152)
		(size 0.508)
		(drill 0.254)
		(layers "F.Cu" "B.Cu")
		(net "SW_P12V_P0V8_PEX2_FLT")
	)
	(via
		(at 343.204038 -282.548838)
		(size 0.508)
		(drill 0.254)
		(layers "F.Cu" "B.Cu")
		(net "SW_P12V_P0V8_PEX2_FLT")
	)
	(via
		(at 341.643208 -274.781264)
		(size 0.508)
		(drill 0.254)
		(layers "F.Cu" "B.Cu")
		(net "SW_P12V_P0V8_PEX2_FLT")
	)
	(via
		(at 334.484726 -282.904438)
		(size 0.508)
		(drill 0.254)
		(layers "F.Cu" "B.Cu")
		(net "SW_P12V_P0V8_PEX2_FLT")
	)
	(via
		(at 334.484726 -282.167838)
		(size 0.508)
		(drill 0.254)
		(layers "F.Cu" "B.Cu")
		(net "SW_P12V_P0V8_PEX2_FLT")
	)
	(via
		(at 342.645238 -282.904438)
		(size 0.508)
		(drill 0.254)
		(layers "F.Cu" "B.Cu")
		(net "SW_P12V_P0V8_PEX2_FLT")
	)
	(via
		(at 337.607402 -274.955254)
		(size 0.508)
		(drill 0.254)
		(layers "F.Cu" "B.Cu")
		(net "SW_P12V_P0V8_PEX2_FLT")
	)
	(via
		(at 342.278208 -274.781264)
		(size 0.508)
		(drill 0.254)
		(layers "F.Cu" "B.Cu")
		(net "SW_P12V_P0V8_PEX2_FLT")
	)
	(via
		(at 341.643208 -275.416264)
		(size 0.508)
		(drill 0.254)
		(layers "F.Cu" "B.Cu")
		(net "SW_P12V_P0V8_PEX2_FLT")
	)
	(via
		(at 342.645238 -281.431238)
		(size 0.508)
		(drill 0.254)
		(layers "F.Cu" "B.Cu")
		(net "SW_P12V_P0V8_PEX2_FLT")
	)
	(via
		(at 342.645238 -282.167838)
		(size 0.508)
		(drill 0.254)
		(layers "F.Cu" "B.Cu")
		(net "SW_P12V_P0V8_PEX2_FLT")
	)
	(via
		(at 336.047334 -277.864824)
		(size 0.508)
		(drill 0.254)
		(layers "F.Cu" "B.Cu")
		(net "SW_P12V_P0V8_PEX2_FLT")
	)
	(via
		(at 342.278208 -276.051264)
		(size 0.508)
		(drill 0.254)
		(layers "F.Cu" "B.Cu")
		(net "SW_P12V_P0V8_PEX2_FLT")
	)
	(via
		(at 342.278208 -276.686264)
		(size 0.508)
		(drill 0.254)
		(layers "F.Cu" "B.Cu")
		(net "SW_P12V_P0V8_PEX2_FLT")
	)
	(via
		(at 336.14487 -284.175454)
		(size 0.508)
		(drill 0.254)
		(layers "F.Cu" "B.Cu")
		(net "SW_P12V_P0V8_PEX2_FLT")
	)
	(via
		(at 336.868516 -282.866592)
		(size 0.508)
		(drill 0.254)
		(layers "F.Cu" "B.Cu")
		(net "SW_P12V_P0V8_PEX2_FLT")
	)
	(via
		(at 345.664028 -282.866592)
		(size 0.508)
		(drill 0.254)
		(layers "F.Cu" "B.Cu")
		(net "SW_P12V_P0V8_PEX2_FLT")
	)
	(via
		(at 337.614006 -276.40407)
		(size 0.508)
		(drill 0.254)
		(layers "F.Cu" "B.Cu")
		(net "SW_P12V_P0V8_PEX2_FLT")
	)
	(via
		(at 341.643208 -276.051264)
		(size 0.508)
		(drill 0.254)
		(layers "F.Cu" "B.Cu")
		(net "SW_P12V_P0V8_PEX2_FLT")
	)
	(via
		(at 334.484726 -281.431238)
		(size 0.508)
		(drill 0.254)
		(layers "F.Cu" "B.Cu")
		(net "SW_P12V_P0V8_PEX2_FLT")
	)
	(via
		(at 336.090006 -276.27707)
		(size 0.508)
		(drill 0.254)
		(layers "F.Cu" "B.Cu")
		(net "SW_P12V_P0V8_PEX2_FLT")
	)
	(via
		(at 337.503516 -282.866592)
		(size 0.508)
		(drill 0.254)
		(layers "F.Cu" "B.Cu")
		(net "SW_P12V_P0V8_PEX2_FLT")
	)
	(via
		(at 343.006172 -277.644352)
		(size 0.508)
		(drill 0.254)
		(layers "F.Cu" "B.Cu")
		(net "SW_P12V_P0V8_PEX2_FLT")
	)
	(via
		(at 335.576926 -282.091638)
		(size 0.508)
		(drill 0.254)
		(layers "F.Cu" "B.Cu")
		(net "SW_P12V_P0V8_PEX2_FLT")
	)
	(via
		(at 342.278208 -275.416264)
		(size 0.508)
		(drill 0.254)
		(layers "F.Cu" "B.Cu")
		(net "SW_P12V_P0V8_PEX2_FLT")
	)
	(via
		(at 337.614006 -275.64207)
		(size 0.508)
		(drill 0.254)
		(layers "F.Cu" "B.Cu")
		(net "SW_P12V_P0V8_PEX2_FLT")
	)
	(via
		(at 335.018126 -281.786838)
		(size 0.508)
		(drill 0.254)
		(layers "F.Cu" "B.Cu")
		(net "SW_P12V_P0V8_PEX2_FLT")
	)
	(via
		(at 336.845402 -274.955254)
		(size 0.508)
		(drill 0.254)
		(layers "F.Cu" "B.Cu")
		(net "SW_P12V_P0V8_PEX2_FLT")
	)
	(via
		(at 342.789764 -280.109676)
		(size 0.762)
		(drill 0.381)
		(layers "F.Cu" "B.Cu")
		(net "SW_P12V_P0V8_PEX2_FLT")
	)
	(segment
		(start 293.27475 -286.874966)
		(end 292.79977 -287.349946)
		(width 0.249936)
		(layer "F.Cu")
		(net "P1V25_SERDES_VDDPLL_PEX2")
	)
	(segment
		(start 286.624776 -286.874966)
		(end 287.099756 -287.349946)
		(width 0.249936)
		(layer "F.Cu")
		(net "P1V25_SERDES_VDDPLL_PEX2")
	)
	(segment
		(start 298.974764 -286.874966)
		(end 298.499784 -287.349946)
		(width 0.249936)
		(layer "F.Cu")
		(net "P1V25_SERDES_VDDPLL_PEX2")
	)
	(segment
		(start 295.174924 -286.874966)
		(end 294.69969 -287.349946)
		(width 0.249936)
		(layer "F.Cu")
		(net "P1V25_SERDES_VDDPLL_PEX2")
	)
	(segment
		(start 298.974764 -304.924714)
		(end 298.499784 -304.449734)
		(width 0.249936)
		(layer "F.Cu")
		(net "P1V25_SERDES_VDDPLL_PEX2")
	)
	(segment
		(start 299.924724 -286.874966)
		(end 299.449744 -287.349946)
		(width 0.249936)
		(layer "F.Cu")
		(net "P1V25_SERDES_VDDPLL_PEX2")
	)
	(segment
		(start 297.074844 -286.874966)
		(end 296.599864 -287.349946)
		(width 0.249936)
		(layer "F.Cu")
		(net "P1V25_SERDES_VDDPLL_PEX2")
	)
	(segment
		(start 282.824936 -304.924714)
		(end 283.299916 -304.449734)
		(width 0.249936)
		(layer "F.Cu")
		(net "P1V25_SERDES_VDDPLL_PEX2")
	)
	(segment
		(start 287.574736 -304.924714)
		(end 288.049716 -304.449734)
		(width 0.249936)
		(layer "F.Cu")
		(net "P1V25_SERDES_VDDPLL_PEX2")
	)
	(segment
		(start 296.124884 -304.924714)
		(end 295.649904 -304.449734)
		(width 0.249936)
		(layer "F.Cu")
		(net "P1V25_SERDES_VDDPLL_PEX2")
	)
	(segment
		(start 289.47491 -304.924714)
		(end 289.94989 -304.449734)
		(width 0.249936)
		(layer "F.Cu")
		(net "P1V25_SERDES_VDDPLL_PEX2")
	)
	(segment
		(start 304.674778 -297.32478)
		(end 304.199798 -296.8498)
		(width 0.249936)
		(layer "F.Cu")
		(net "P1V25_SERDES_VDDPLL_PEX2")
	)
	(segment
		(start 290.42487 -304.924714)
		(end 290.89985 -304.449734)
		(width 0.249936)
		(layer "F.Cu")
		(net "P1V25_SERDES_VDDPLL_PEX2")
	)
	(segment
		(start 304.674778 -294.4749)
		(end 304.199798 -294.94988)
		(width 0.249936)
		(layer "F.Cu")
		(net "P1V25_SERDES_VDDPLL_PEX2")
	)
	(segment
		(start 304.674778 -298.27474)
		(end 304.199798 -297.79976)
		(width 0.249936)
		(layer "F.Cu")
		(net "P1V25_SERDES_VDDPLL_PEX2")
	)
	(segment
		(start 283.774896 -304.924714)
		(end 284.249876 -304.449734)
		(width 0.249936)
		(layer "F.Cu")
		(net "P1V25_SERDES_VDDPLL_PEX2")
	)
	(segment
		(start 294.22471 -304.924714)
		(end 293.74973 -304.449734)
		(width 0.249936)
		(layer "F.Cu")
		(net "P1V25_SERDES_VDDPLL_PEX2")
	)
	(segment
		(start 292.32479 -286.874966)
		(end 291.84981 -287.349946)
		(width 0.249936)
		(layer "F.Cu")
		(net "P1V25_SERDES_VDDPLL_PEX2")
	)
	(segment
		(start 284.724856 -286.874966)
		(end 285.199836 -287.349946)
		(width 0.249936)
		(layer "F.Cu")
		(net "P1V25_SERDES_VDDPLL_PEX2")
	)
	(segment
		(start 304.674778 -293.52494)
		(end 304.199798 -293.99992)
		(width 0.249936)
		(layer "F.Cu")
		(net "P1V25_SERDES_VDDPLL_PEX2")
	)
	(segment
		(start 288.524696 -286.874966)
		(end 288.99993 -287.349946)
		(width 0.249936)
		(layer "F.Cu")
		(net "P1V25_SERDES_VDDPLL_PEX2")
	)
	(segment
		(start 299.924724 -304.924714)
		(end 299.449744 -304.449734)
		(width 0.249936)
		(layer "F.Cu")
		(net "P1V25_SERDES_VDDPLL_PEX2")
	)
	(segment
		(start 292.32479 -304.924714)
		(end 291.84981 -304.449734)
		(width 0.249936)
		(layer "F.Cu")
		(net "P1V25_SERDES_VDDPLL_PEX2")
	)
	(segment
		(start 286.149796 -287.349946)
		(end 285.674816 -286.874966)
		(width 0.249936)
		(layer "F.Cu")
		(net "P1V25_SERDES_VDDPLL_PEX2")
	)
	(segment
		(start 290.42487 -286.874966)
		(end 290.89985 -287.349946)
		(width 0.249936)
		(layer "F.Cu")
		(net "P1V25_SERDES_VDDPLL_PEX2")
	)
	(segment
		(start 298.024804 -304.924714)
		(end 297.549824 -304.449734)
		(width 0.249936)
		(layer "F.Cu")
		(net "P1V25_SERDES_VDDPLL_PEX2")
	)
	(segment
		(start 286.149796 -304.449734)
		(end 285.674816 -304.924714)
		(width 0.249936)
		(layer "F.Cu")
		(net "P1V25_SERDES_VDDPLL_PEX2")
	)
	(segment
		(start 293.27475 -304.924714)
		(end 292.79977 -304.449734)
		(width 0.249936)
		(layer "F.Cu")
		(net "P1V25_SERDES_VDDPLL_PEX2")
	)
	(segment
		(start 287.574736 -286.874966)
		(end 288.049716 -287.349946)
		(width 0.249936)
		(layer "F.Cu")
		(net "P1V25_SERDES_VDDPLL_PEX2")
	)
	(segment
		(start 282.824936 -286.874966)
		(end 283.299916 -287.349946)
		(width 0.249936)
		(layer "F.Cu")
		(net "P1V25_SERDES_VDDPLL_PEX2")
	)
	(segment
		(start 294.22471 -286.874966)
		(end 293.74973 -287.349946)
		(width 0.249936)
		(layer "F.Cu")
		(net "P1V25_SERDES_VDDPLL_PEX2")
	)
	(segment
		(start 288.524696 -304.924714)
		(end 288.99993 -304.449734)
		(width 0.249936)
		(layer "F.Cu")
		(net "P1V25_SERDES_VDDPLL_PEX2")
	)
	(segment
		(start 283.774896 -286.874966)
		(end 284.249876 -287.349946)
		(width 0.249936)
		(layer "F.Cu")
		(net "P1V25_SERDES_VDDPLL_PEX2")
	)
	(segment
		(start 304.674778 -296.37482)
		(end 304.199798 -295.89984)
		(width 0.249936)
		(layer "F.Cu")
		(net "P1V25_SERDES_VDDPLL_PEX2")
	)
	(segment
		(start 296.124884 -286.874966)
		(end 295.649904 -287.349946)
		(width 0.249936)
		(layer "F.Cu")
		(net "P1V25_SERDES_VDDPLL_PEX2")
	)
	(segment
		(start 289.47491 -286.874966)
		(end 289.94989 -287.349946)
		(width 0.249936)
		(layer "F.Cu")
		(net "P1V25_SERDES_VDDPLL_PEX2")
	)
	(segment
		(start 286.624776 -304.924714)
		(end 287.099756 -304.449734)
		(width 0.249936)
		(layer "F.Cu")
		(net "P1V25_SERDES_VDDPLL_PEX2")
	)
	(segment
		(start 295.174924 -304.924714)
		(end 294.69969 -304.449734)
		(width 0.249936)
		(layer "F.Cu")
		(net "P1V25_SERDES_VDDPLL_PEX2")
	)
	(segment
		(start 284.724856 -304.924714)
		(end 285.199836 -304.449734)
		(width 0.249936)
		(layer "F.Cu")
		(net "P1V25_SERDES_VDDPLL_PEX2")
	)
	(segment
		(start 297.074844 -304.924714)
		(end 296.599864 -304.449734)
		(width 0.249936)
		(layer "F.Cu")
		(net "P1V25_SERDES_VDDPLL_PEX2")
	)
	(segment
		(start 298.024804 -286.874966)
		(end 297.549824 -287.349946)
		(width 0.249936)
		(layer "F.Cu")
		(net "P1V25_SERDES_VDDPLL_PEX2")
	)
	(via
		(at 299.924724 -286.874966)
		(size 0.4064)
		(drill 0.2032)
		(layers "F.Cu" "B.Cu")
		(net "P1V25_SERDES_VDDPLL_PEX2")
	)
	(via
		(at 284.724856 -286.874966)
		(size 0.4064)
		(drill 0.2032)
		(layers "F.Cu" "B.Cu")
		(net "P1V25_SERDES_VDDPLL_PEX2")
	)
	(via
		(at 252.732286 -287.330642)
		(size 0.508)
		(drill 0.254)
		(layers "F.Cu" "B.Cu")
		(net "P1V25_SERDES_VDDPLL_PEX2")
	)
	(via
		(at 298.024804 -304.924714)
		(size 0.4064)
		(drill 0.2032)
		(layers "F.Cu" "B.Cu")
		(net "P1V25_SERDES_VDDPLL_PEX2")
	)
	(via
		(at 293.27475 -304.924714)
		(size 0.4064)
		(drill 0.2032)
		(layers "F.Cu" "B.Cu")
		(net "P1V25_SERDES_VDDPLL_PEX2")
	)
	(via
		(at 296.124884 -304.924714)
		(size 0.4064)
		(drill 0.2032)
		(layers "F.Cu" "B.Cu")
		(net "P1V25_SERDES_VDDPLL_PEX2")
	)
	(via
		(at 243.297456 -259.894832)
		(size 0.508)
		(drill 0.254)
		(layers "F.Cu" "B.Cu")
		(net "P1V25_SERDES_VDDPLL_PEX2")
	)
	(via
		(at 289.47491 -304.924714)
		(size 0.4064)
		(drill 0.2032)
		(layers "F.Cu" "B.Cu")
		(net "P1V25_SERDES_VDDPLL_PEX2")
	)
	(via
		(at 287.574736 -304.924714)
		(size 0.4064)
		(drill 0.2032)
		(layers "F.Cu" "B.Cu")
		(net "P1V25_SERDES_VDDPLL_PEX2")
	)
	(via
		(at 304.674778 -297.32478)
		(size 0.4064)
		(drill 0.2032)
		(layers "F.Cu" "B.Cu")
		(net "P1V25_SERDES_VDDPLL_PEX2")
	)
	(via
		(at 284.724856 -304.924714)
		(size 0.4064)
		(drill 0.2032)
		(layers "F.Cu" "B.Cu")
		(net "P1V25_SERDES_VDDPLL_PEX2")
	)
	(via
		(at 298.974764 -304.924714)
		(size 0.4064)
		(drill 0.2032)
		(layers "F.Cu" "B.Cu")
		(net "P1V25_SERDES_VDDPLL_PEX2")
	)
	(via
		(at 239.46104 -258.762754)
		(size 0.508)
		(drill 0.254)
		(layers "F.Cu" "B.Cu")
		(net "P1V25_SERDES_VDDPLL_PEX2")
	)
	(via
		(at 290.42487 -286.874966)
		(size 0.4064)
		(drill 0.2032)
		(layers "F.Cu" "B.Cu")
		(net "P1V25_SERDES_VDDPLL_PEX2")
	)
	(via
		(at 288.524696 -286.874966)
		(size 0.4064)
		(drill 0.2032)
		(layers "F.Cu" "B.Cu")
		(net "P1V25_SERDES_VDDPLL_PEX2")
	)
	(via
		(at 244.001544 -259.566918)
		(size 0.508)
		(drill 0.254)
		(layers "F.Cu" "B.Cu")
		(net "P1V25_SERDES_VDDPLL_PEX2")
	)
	(via
		(at 237.963456 -260.797548)
		(size 0.508)
		(drill 0.254)
		(layers "F.Cu" "B.Cu")
		(net "P1V25_SERDES_VDDPLL_PEX2")
	)
	(via
		(at 304.674778 -298.27474)
		(size 0.4064)
		(drill 0.2032)
		(layers "F.Cu" "B.Cu")
		(net "P1V25_SERDES_VDDPLL_PEX2")
	)
	(via
		(at 250.902216 -287.431226)
		(size 0.508)
		(drill 0.254)
		(layers "F.Cu" "B.Cu")
		(net "P1V25_SERDES_VDDPLL_PEX2")
	)
	(via
		(at 250.077732 -288.232596)
		(size 0.508)
		(drill 0.254)
		(layers "F.Cu" "B.Cu")
		(net "P1V25_SERDES_VDDPLL_PEX2")
	)
	(via
		(at 290.42487 -304.924714)
		(size 0.4064)
		(drill 0.2032)
		(layers "F.Cu" "B.Cu")
		(net "P1V25_SERDES_VDDPLL_PEX2")
	)
	(via
		(at 295.174924 -304.924714)
		(size 0.4064)
		(drill 0.2032)
		(layers "F.Cu" "B.Cu")
		(net "P1V25_SERDES_VDDPLL_PEX2")
	)
	(via
		(at 239.545622 -259.529326)
		(size 0.508)
		(drill 0.254)
		(layers "F.Cu" "B.Cu")
		(net "P1V25_SERDES_VDDPLL_PEX2")
	)
	(via
		(at 304.674778 -293.52494)
		(size 0.4064)
		(drill 0.2032)
		(layers "F.Cu" "B.Cu")
		(net "P1V25_SERDES_VDDPLL_PEX2")
	)
	(via
		(at 244.821456 -259.894832)
		(size 0.508)
		(drill 0.254)
		(layers "F.Cu" "B.Cu")
		(net "P1V25_SERDES_VDDPLL_PEX2")
	)
	(via
		(at 288.524696 -304.924714)
		(size 0.4064)
		(drill 0.2032)
		(layers "F.Cu" "B.Cu")
		(net "P1V25_SERDES_VDDPLL_PEX2")
	)
	(via
		(at 283.774896 -304.924714)
		(size 0.4064)
		(drill 0.2032)
		(layers "F.Cu" "B.Cu")
		(net "P1V25_SERDES_VDDPLL_PEX2")
	)
	(via
		(at 241.03965 -259.41655)
		(size 0.508)
		(drill 0.254)
		(layers "F.Cu" "B.Cu")
		(net "P1V25_SERDES_VDDPLL_PEX2")
	)
	(via
		(at 287.574736 -286.874966)
		(size 0.4064)
		(drill 0.2032)
		(layers "F.Cu" "B.Cu")
		(net "P1V25_SERDES_VDDPLL_PEX2")
	)
	(via
		(at 282.824936 -286.874966)
		(size 0.4064)
		(drill 0.2032)
		(layers "F.Cu" "B.Cu")
		(net "P1V25_SERDES_VDDPLL_PEX2")
	)
	(via
		(at 285.674816 -304.924714)
		(size 0.4064)
		(drill 0.2032)
		(layers "F.Cu" "B.Cu")
		(net "P1V25_SERDES_VDDPLL_PEX2")
	)
	(via
		(at 293.27475 -286.874966)
		(size 0.4064)
		(drill 0.2032)
		(layers "F.Cu" "B.Cu")
		(net "P1V25_SERDES_VDDPLL_PEX2")
	)
	(via
		(at 244.146832 -258.722368)
		(size 0.508)
		(drill 0.254)
		(layers "F.Cu" "B.Cu")
		(net "P1V25_SERDES_VDDPLL_PEX2")
	)
	(via
		(at 294.22471 -304.924714)
		(size 0.4064)
		(drill 0.2032)
		(layers "F.Cu" "B.Cu")
		(net "P1V25_SERDES_VDDPLL_PEX2")
	)
	(via
		(at 242.553998 -259.587492)
		(size 0.508)
		(drill 0.254)
		(layers "F.Cu" "B.Cu")
		(net "P1V25_SERDES_VDDPLL_PEX2")
	)
	(via
		(at 298.974764 -286.874966)
		(size 0.4064)
		(drill 0.2032)
		(layers "F.Cu" "B.Cu")
		(net "P1V25_SERDES_VDDPLL_PEX2")
	)
	(via
		(at 292.32479 -304.924714)
		(size 0.4064)
		(drill 0.2032)
		(layers "F.Cu" "B.Cu")
		(net "P1V25_SERDES_VDDPLL_PEX2")
	)
	(via
		(at 297.074844 -286.874966)
		(size 0.4064)
		(drill 0.2032)
		(layers "F.Cu" "B.Cu")
		(net "P1V25_SERDES_VDDPLL_PEX2")
	)
	(via
		(at 285.674816 -286.874966)
		(size 0.4064)
		(drill 0.2032)
		(layers "F.Cu" "B.Cu")
		(net "P1V25_SERDES_VDDPLL_PEX2")
	)
	(via
		(at 289.47491 -286.874966)
		(size 0.4064)
		(drill 0.2032)
		(layers "F.Cu" "B.Cu")
		(net "P1V25_SERDES_VDDPLL_PEX2")
	)
	(via
		(at 236.444282 -258.762754)
		(size 0.508)
		(drill 0.254)
		(layers "F.Cu" "B.Cu")
		(net "P1V25_SERDES_VDDPLL_PEX2")
	)
	(via
		(at 234.956096 -258.802886)
		(size 0.508)
		(drill 0.254)
		(layers "F.Cu" "B.Cu")
		(net "P1V25_SERDES_VDDPLL_PEX2")
	)
	(via
		(at 292.32479 -286.874966)
		(size 0.4064)
		(drill 0.2032)
		(layers "F.Cu" "B.Cu")
		(net "P1V25_SERDES_VDDPLL_PEX2")
	)
	(via
		(at 240.249456 -259.894832)
		(size 0.508)
		(drill 0.254)
		(layers "F.Cu" "B.Cu")
		(net "P1V25_SERDES_VDDPLL_PEX2")
	)
	(via
		(at 237.467394 -259.989066)
		(size 0.508)
		(drill 0.254)
		(layers "F.Cu" "B.Cu")
		(net "P1V25_SERDES_VDDPLL_PEX2")
	)
	(via
		(at 252.810518 -288.894012)
		(size 0.508)
		(drill 0.254)
		(layers "F.Cu" "B.Cu")
		(net "P1V25_SERDES_VDDPLL_PEX2")
	)
	(via
		(at 239.487456 -260.797548)
		(size 0.508)
		(drill 0.254)
		(layers "F.Cu" "B.Cu")
		(net "P1V25_SERDES_VDDPLL_PEX2")
	)
	(via
		(at 286.624776 -304.924714)
		(size 0.4064)
		(drill 0.2032)
		(layers "F.Cu" "B.Cu")
		(net "P1V25_SERDES_VDDPLL_PEX2")
	)
	(via
		(at 243.250212 -258.71297)
		(size 0.508)
		(drill 0.254)
		(layers "F.Cu" "B.Cu")
		(net "P1V25_SERDES_VDDPLL_PEX2")
	)
	(via
		(at 244.821456 -260.797548)
		(size 0.508)
		(drill 0.254)
		(layers "F.Cu" "B.Cu")
		(net "P1V25_SERDES_VDDPLL_PEX2")
	)
	(via
		(at 283.774896 -286.874966)
		(size 0.4064)
		(drill 0.2032)
		(layers "F.Cu" "B.Cu")
		(net "P1V25_SERDES_VDDPLL_PEX2")
	)
	(via
		(at 250.077732 -286.708596)
		(size 0.508)
		(drill 0.254)
		(layers "F.Cu" "B.Cu")
		(net "P1V25_SERDES_VDDPLL_PEX2")
	)
	(via
		(at 250.980448 -288.994596)
		(size 0.508)
		(drill 0.254)
		(layers "F.Cu" "B.Cu")
		(net "P1V25_SERDES_VDDPLL_PEX2")
	)
	(via
		(at 294.22471 -286.874966)
		(size 0.4064)
		(drill 0.2032)
		(layers "F.Cu" "B.Cu")
		(net "P1V25_SERDES_VDDPLL_PEX2")
	)
	(via
		(at 243.680234 -260.85419)
		(size 0.508)
		(drill 0.254)
		(layers "F.Cu" "B.Cu")
		(net "P1V25_SERDES_VDDPLL_PEX2")
	)
	(via
		(at 234.915456 -260.797548)
		(size 0.508)
		(drill 0.254)
		(layers "F.Cu" "B.Cu")
		(net "P1V25_SERDES_VDDPLL_PEX2")
	)
	(via
		(at 298.024804 -286.874966)
		(size 0.4064)
		(drill 0.2032)
		(layers "F.Cu" "B.Cu")
		(net "P1V25_SERDES_VDDPLL_PEX2")
	)
	(via
		(at 250.077732 -289.756596)
		(size 0.508)
		(drill 0.254)
		(layers "F.Cu" "B.Cu")
		(net "P1V25_SERDES_VDDPLL_PEX2")
	)
	(via
		(at 286.624776 -286.874966)
		(size 0.4064)
		(drill 0.2032)
		(layers "F.Cu" "B.Cu")
		(net "P1V25_SERDES_VDDPLL_PEX2")
	)
	(via
		(at 238.725456 -259.894832)
		(size 0.508)
		(drill 0.254)
		(layers "F.Cu" "B.Cu")
		(net "P1V25_SERDES_VDDPLL_PEX2")
	)
	(via
		(at 295.174924 -286.874966)
		(size 0.4064)
		(drill 0.2032)
		(layers "F.Cu" "B.Cu")
		(net "P1V25_SERDES_VDDPLL_PEX2")
	)
	(via
		(at 251.907802 -288.132012)
		(size 0.508)
		(drill 0.254)
		(layers "F.Cu" "B.Cu")
		(net "P1V25_SERDES_VDDPLL_PEX2")
	)
	(via
		(at 297.074844 -304.924714)
		(size 0.4064)
		(drill 0.2032)
		(layers "F.Cu" "B.Cu")
		(net "P1V25_SERDES_VDDPLL_PEX2")
	)
	(via
		(at 236.439456 -260.797548)
		(size 0.508)
		(drill 0.254)
		(layers "F.Cu" "B.Cu")
		(net "P1V25_SERDES_VDDPLL_PEX2")
	)
	(via
		(at 299.924724 -304.924714)
		(size 0.4064)
		(drill 0.2032)
		(layers "F.Cu" "B.Cu")
		(net "P1V25_SERDES_VDDPLL_PEX2")
	)
	(via
		(at 304.674778 -294.4749)
		(size 0.4064)
		(drill 0.2032)
		(layers "F.Cu" "B.Cu")
		(net "P1V25_SERDES_VDDPLL_PEX2")
	)
	(via
		(at 251.907802 -286.608012)
		(size 0.508)
		(drill 0.254)
		(layers "F.Cu" "B.Cu")
		(net "P1V25_SERDES_VDDPLL_PEX2")
	)
	(via
		(at 296.124884 -286.874966)
		(size 0.4064)
		(drill 0.2032)
		(layers "F.Cu" "B.Cu")
		(net "P1V25_SERDES_VDDPLL_PEX2")
	)
	(via
		(at 237.952788 -258.822952)
		(size 0.508)
		(drill 0.254)
		(layers "F.Cu" "B.Cu")
		(net "P1V25_SERDES_VDDPLL_PEX2")
	)
	(via
		(at 236.439456 -259.894832)
		(size 0.508)
		(drill 0.254)
		(layers "F.Cu" "B.Cu")
		(net "P1V25_SERDES_VDDPLL_PEX2")
	)
	(via
		(at 242.535456 -260.797548)
		(size 0.508)
		(drill 0.254)
		(layers "F.Cu" "B.Cu")
		(net "P1V25_SERDES_VDDPLL_PEX2")
	)
	(via
		(at 238.76381 -259.124704)
		(size 0.508)
		(drill 0.254)
		(layers "F.Cu" "B.Cu")
		(net "P1V25_SERDES_VDDPLL_PEX2")
	)
	(via
		(at 282.824936 -304.924714)
		(size 0.4064)
		(drill 0.2032)
		(layers "F.Cu" "B.Cu")
		(net "P1V25_SERDES_VDDPLL_PEX2")
	)
	(via
		(at 304.674778 -296.37482)
		(size 0.4064)
		(drill 0.2032)
		(layers "F.Cu" "B.Cu")
		(net "P1V25_SERDES_VDDPLL_PEX2")
	)
	(via
		(at 234.915456 -259.894832)
		(size 0.508)
		(drill 0.254)
		(layers "F.Cu" "B.Cu")
		(net "P1V25_SERDES_VDDPLL_PEX2")
	)
	(via
		(at 235.676694 -260.291072)
		(size 0.508)
		(drill 0.254)
		(layers "F.Cu" "B.Cu")
		(net "P1V25_SERDES_VDDPLL_PEX2")
	)
	(via
		(at 241.773456 -259.894832)
		(size 0.508)
		(drill 0.254)
		(layers "F.Cu" "B.Cu")
		(net "P1V25_SERDES_VDDPLL_PEX2")
	)
	(via
		(at 251.907802 -289.656012)
		(size 0.508)
		(drill 0.254)
		(layers "F.Cu" "B.Cu")
		(net "P1V25_SERDES_VDDPLL_PEX2")
	)
	(via
		(at 241.011456 -260.797548)
		(size 0.508)
		(drill 0.254)
		(layers "F.Cu" "B.Cu")
		(net "P1V25_SERDES_VDDPLL_PEX2")
	)
	(segment
		(start 132.331206 -281.65425)
		(end 132.76834 -281.217116)
		(width 0.2286)
		(layer "F.Cu")
		(net "P0V8_PEX1_ISEN2")
	)
	(segment
		(start 119.375682 -261.1247)
		(end 119.375682 -260.795008)
		(width 0.2032)
		(layer "F.Cu")
		(net "P0V8_PEX1_ISEN2")
	)
	(segment
		(start 119.194326 -262.240268)
		(end 119.194326 -261.306056)
		(width 0.2032)
		(layer "F.Cu")
		(net "P0V8_PEX1_ISEN2")
	)
	(segment
		(start 132.331206 -281.999182)
		(end 132.331206 -281.65425)
		(width 0.2286)
		(layer "F.Cu")
		(net "P0V8_PEX1_ISEN2")
	)
	(segment
		(start 119.53494 -262.580882)
		(end 119.194326 -262.240268)
		(width 0.2032)
		(layer "F.Cu")
		(net "P0V8_PEX1_ISEN2")
	)
	(segment
		(start 119.194326 -261.306056)
		(end 119.375682 -261.1247)
		(width 0.2032)
		(layer "F.Cu")
		(net "P0V8_PEX1_ISEN2")
	)
	(segment
		(start 132.76834 -281.217116)
		(end 132.76834 -281.151838)
		(width 0.2286)
		(layer "F.Cu")
		(net "P0V8_PEX1_ISEN2")
	)
	(via
		(at 132.76834 -281.151838)
		(size 0.508)
		(drill 0.254)
		(layers "F.Cu" "B.Cu")
		(net "P0V8_PEX1_ISEN2")
	)
	(via
		(at 119.53494 -262.580882)
		(size 0.508)
		(drill 0.254)
		(layers "F.Cu" "B.Cu")
		(net "P0V8_PEX1_ISEN2")
	)
	(segment
		(start 123.438666 -261.730744)
		(end 126.936246 -263.17956)
		(width 0.254)
		(layer "In11.Cu")
		(net "P0V8_PEX1_ISEN2")
	)
	(segment
		(start 121.401586 -262.758682)
		(end 122.429524 -261.730744)
		(width 0.254)
		(layer "In11.Cu")
		(net "P0V8_PEX1_ISEN2")
	)
	(segment
		(start 133.604762 -280.663904)
		(end 133.256274 -280.663904)
		(width 0.254)
		(layer "In11.Cu")
		(net "P0V8_PEX1_ISEN2")
	)
	(segment
		(start 132.328412 -277.343362)
		(end 134.120128 -279.135078)
		(width 0.254)
		(layer "In11.Cu")
		(net "P0V8_PEX1_ISEN2")
	)
	(segment
		(start 131.673092 -267.916406)
		(end 131.673092 -275.761196)
		(width 0.254)
		(layer "In11.Cu")
		(net "P0V8_PEX1_ISEN2")
	)
	(segment
		(start 126.936246 -263.17956)
		(end 131.673092 -267.916406)
		(width 0.254)
		(layer "In11.Cu")
		(net "P0V8_PEX1_ISEN2")
	)
	(segment
		(start 134.120128 -280.148538)
		(end 133.604762 -280.663904)
		(width 0.254)
		(layer "In11.Cu")
		(net "P0V8_PEX1_ISEN2")
	)
	(segment
		(start 119.53494 -262.580882)
		(end 119.9642 -262.758682)
		(width 0.254)
		(layer "In11.Cu")
		(net "P0V8_PEX1_ISEN2")
	)
	(segment
		(start 134.120128 -279.135078)
		(end 134.120128 -280.148538)
		(width 0.254)
		(layer "In11.Cu")
		(net "P0V8_PEX1_ISEN2")
	)
	(segment
		(start 119.9642 -262.758682)
		(end 121.401586 -262.758682)
		(width 0.254)
		(layer "In11.Cu")
		(net "P0V8_PEX1_ISEN2")
	)
	(segment
		(start 131.673092 -275.761196)
		(end 132.328412 -277.343362)
		(width 0.254)
		(layer "In11.Cu")
		(net "P0V8_PEX1_ISEN2")
	)
	(segment
		(start 133.256274 -280.663904)
		(end 132.76834 -281.151838)
		(width 0.254)
		(layer "In11.Cu")
		(net "P0V8_PEX1_ISEN2")
	)
	(segment
		(start 122.429524 -261.730744)
		(end 123.438666 -261.730744)
		(width 0.254)
		(layer "In11.Cu")
		(net "P0V8_PEX1_ISEN2")
	)
	(segment
		(start 457.745084 -307.56987)
		(end 457.87818 -307.56987)
		(width 0.1778)
		(layer "F.Cu")
		(net "P1V25_PEX3_CS")
	)
	(segment
		(start 456.540108 -307.891942)
		(end 456.968098 -307.891942)
		(width 0.1778)
		(layer "F.Cu")
		(net "P1V25_PEX3_CS")
	)
	(segment
		(start 458.567536 -307.205126)
		(end 458.242924 -307.205126)
		(width 0.254)
		(layer "F.Cu")
		(net "P1V25_PEX3_CS")
	)
	(segment
		(start 458.242924 -307.205126)
		(end 457.87818 -307.56987)
		(width 0.254)
		(layer "F.Cu")
		(net "P1V25_PEX3_CS")
	)
	(segment
		(start 456.968098 -307.891942)
		(end 457.745084 -307.56987)
		(width 0.1778)
		(layer "F.Cu")
		(net "P1V25_PEX3_CS")
	)
	(via
		(at 457.87818 -307.56987)
		(size 0.508)
		(drill 0.254)
		(layers "F.Cu" "B.Cu")
		(net "P1V25_PEX3_CS")
	)
	(segment
		(start 347.239336 -281.12212)
		(end 347.239336 -280.810208)
		(width 0.2286)
		(layer "F.Cu")
		(net "P0V8_PEX2_TSEN")
	)
	(segment
		(start 338.81187 -281.999182)
		(end 338.81187 -281.567128)
		(width 0.2286)
		(layer "F.Cu")
		(net "P0V8_PEX2_TSEN")
	)
	(segment
		(start 339.078824 -281.12212)
		(end 339.078824 -280.810208)
		(width 0.2286)
		(layer "F.Cu")
		(net "P0V8_PEX2_TSEN")
	)
	(segment
		(start 338.81187 -281.567128)
		(end 339.009736 -281.369262)
		(width 0.2286)
		(layer "F.Cu")
		(net "P0V8_PEX2_TSEN")
	)
	(segment
		(start 339.009736 -281.369262)
		(end 339.078824 -281.12212)
		(width 0.2286)
		(layer "F.Cu")
		(net "P0V8_PEX2_TSEN")
	)
	(segment
		(start 347.170248 -281.369262)
		(end 347.239336 -281.12212)
		(width 0.2286)
		(layer "F.Cu")
		(net "P0V8_PEX2_TSEN")
	)
	(segment
		(start 346.972382 -281.999182)
		(end 346.972382 -281.567128)
		(width 0.2286)
		(layer "F.Cu")
		(net "P0V8_PEX2_TSEN")
	)
	(segment
		(start 346.972382 -281.567128)
		(end 347.170248 -281.369262)
		(width 0.2286)
		(layer "F.Cu")
		(net "P0V8_PEX2_TSEN")
	)
	(via
		(at 347.03131 -264.12952)
		(size 0.508)
		(drill 0.254)
		(layers "F.Cu" "B.Cu")
		(net "P0V8_PEX2_TSEN")
	)
	(via
		(at 339.078824 -280.810208)
		(size 0.508)
		(drill 0.254)
		(layers "F.Cu" "B.Cu")
		(net "P0V8_PEX2_TSEN")
	)
	(via
		(at 347.239336 -280.810208)
		(size 0.508)
		(drill 0.254)
		(layers "F.Cu" "B.Cu")
		(net "P0V8_PEX2_TSEN")
	)
	(segment
		(start 347.03131 -261.88924)
		(end 347.03131 -264.12952)
		(width 0.254)
		(layer "B.Cu")
		(net "P0V8_PEX2_TSEN")
	)
	(segment
		(start 348.119954 -260.800596)
		(end 347.03131 -261.88924)
		(width 0.254)
		(layer "B.Cu")
		(net "P0V8_PEX2_TSEN")
	)
	(segment
		(start 347.239336 -280.810208)
		(end 347.239336 -280.129488)
		(width 0.254)
		(layer "In7.Cu")
		(net "P0V8_PEX2_TSEN")
	)
	(segment
		(start 345.323414 -278.34336)
		(end 344.12936 -279.537414)
		(width 0.254)
		(layer "In7.Cu")
		(net "P0V8_PEX2_TSEN")
	)
	(segment
		(start 337.931506 -279.66289)
		(end 337.627976 -279.35936)
		(width 0.254)
		(layer "In7.Cu")
		(net "P0V8_PEX2_TSEN")
	)
	(segment
		(start 346.319094 -264.12952)
		(end 347.03131 -264.12952)
		(width 0.254)
		(layer "In7.Cu")
		(net "P0V8_PEX2_TSEN")
	)
	(segment
		(start 339.078824 -280.190956)
		(end 338.550758 -279.66289)
		(width 0.254)
		(layer "In7.Cu")
		(net "P0V8_PEX2_TSEN")
	)
	(segment
		(start 337.627976 -279.35936)
		(end 337.627976 -278.863552)
		(width 0.254)
		(layer "In7.Cu")
		(net "P0V8_PEX2_TSEN")
	)
	(segment
		(start 344.12936 -279.537414)
		(end 341.879428 -279.537414)
		(width 0.254)
		(layer "In7.Cu")
		(net "P0V8_PEX2_TSEN")
	)
	(segment
		(start 339.573108 -276.91842)
		(end 339.573108 -268.59738)
		(width 0.254)
		(layer "In7.Cu")
		(net "P0V8_PEX2_TSEN")
	)
	(segment
		(start 339.579966 -279.689814)
		(end 339.078824 -280.190956)
		(width 0.254)
		(layer "In7.Cu")
		(net "P0V8_PEX2_TSEN")
	)
	(segment
		(start 339.88756 -278.34336)
		(end 339.579966 -278.650954)
		(width 0.254)
		(layer "In7.Cu")
		(net "P0V8_PEX2_TSEN")
	)
	(segment
		(start 337.627976 -278.863552)
		(end 339.573108 -276.91842)
		(width 0.254)
		(layer "In7.Cu")
		(net "P0V8_PEX2_TSEN")
	)
	(segment
		(start 338.550758 -279.66289)
		(end 337.931506 -279.66289)
		(width 0.254)
		(layer "In7.Cu")
		(net "P0V8_PEX2_TSEN")
	)
	(segment
		(start 347.239336 -280.129488)
		(end 346.499688 -279.38984)
		(width 0.254)
		(layer "In7.Cu")
		(net "P0V8_PEX2_TSEN")
	)
	(segment
		(start 339.078824 -280.190956)
		(end 339.078824 -280.810208)
		(width 0.254)
		(layer "In7.Cu")
		(net "P0V8_PEX2_TSEN")
	)
	(segment
		(start 345.998038 -278.34336)
		(end 345.323414 -278.34336)
		(width 0.254)
		(layer "In7.Cu")
		(net "P0V8_PEX2_TSEN")
	)
	(segment
		(start 339.573108 -268.59738)
		(end 341.486744 -266.683744)
		(width 0.254)
		(layer "In7.Cu")
		(net "P0V8_PEX2_TSEN")
	)
	(segment
		(start 346.499688 -279.38984)
		(end 346.499688 -278.84501)
		(width 0.254)
		(layer "In7.Cu")
		(net "P0V8_PEX2_TSEN")
	)
	(segment
		(start 341.486744 -266.683744)
		(end 343.76487 -266.683744)
		(width 0.254)
		(layer "In7.Cu")
		(net "P0V8_PEX2_TSEN")
	)
	(segment
		(start 346.499688 -278.84501)
		(end 345.998038 -278.34336)
		(width 0.254)
		(layer "In7.Cu")
		(net "P0V8_PEX2_TSEN")
	)
	(segment
		(start 340.685374 -278.34336)
		(end 339.88756 -278.34336)
		(width 0.254)
		(layer "In7.Cu")
		(net "P0V8_PEX2_TSEN")
	)
	(segment
		(start 341.879428 -279.537414)
		(end 340.685374 -278.34336)
		(width 0.254)
		(layer "In7.Cu")
		(net "P0V8_PEX2_TSEN")
	)
	(segment
		(start 343.76487 -266.683744)
		(end 346.319094 -264.12952)
		(width 0.254)
		(layer "In7.Cu")
		(net "P0V8_PEX2_TSEN")
	)
	(segment
		(start 339.579966 -278.650954)
		(end 339.579966 -279.689814)
		(width 0.254)
		(layer "In7.Cu")
		(net "P0V8_PEX2_TSEN")
	)
	(via
		(at 452.952612 -306.86756)
		(size 0.508)
		(drill 0.254)
		(layers "F.Cu" "B.Cu")
		(net "P1V25_PEX3_VCC")
	)
	(segment
		(start 458.340206 -306.277772)
		(end 458.340206 -306.31257)
		(width 0.508)
		(layer "B.Cu")
		(net "P1V25_PEX3_VCC")
	)
	(segment
		(start 459.35138 -305.266598)
		(end 458.340206 -306.277772)
		(width 0.508)
		(layer "B.Cu")
		(net "P1V25_PEX3_VCC")
	)
	(segment
		(start 461.588612 -305.266598)
		(end 459.35138 -305.266598)
		(width 0.508)
		(layer "B.Cu")
		(net "P1V25_PEX3_VCC")
	)
	(segment
		(start 461.712564 -305.39055)
		(end 461.588612 -305.266598)
		(width 0.508)
		(layer "B.Cu")
		(net "P1V25_PEX3_VCC")
	)
	(segment
		(start 453.507602 -306.31257)
		(end 452.952612 -306.86756)
		(width 0.508)
		(layer "B.Cu")
		(net "P1V25_PEX3_VCC")
	)
	(segment
		(start 458.340206 -306.31257)
		(end 453.507602 -306.31257)
		(width 0.508)
		(layer "B.Cu")
		(net "P1V25_PEX3_VCC")
	)
	(segment
		(start 105.711498 -281.438858)
		(end 105.78973 -281.249882)
		(width 0.2032)
		(layer "F.Cu")
		(net "P0V8_PEX0_PWM1")
	)
	(segment
		(start 122.100594 -255.105154)
		(end 121.775728 -255.43002)
		(width 0.1524)
		(layer "F.Cu")
		(net "P0V8_PEX0_PWM1")
	)
	(segment
		(start 105.78973 -280.897838)
		(end 105.914952 -280.617168)
		(width 0.2032)
		(layer "F.Cu")
		(net "P0V8_PEX0_PWM1")
	)
	(segment
		(start 105.78973 -281.249882)
		(end 105.78973 -280.897838)
		(width 0.2032)
		(layer "F.Cu")
		(net "P0V8_PEX0_PWM1")
	)
	(segment
		(start 121.775728 -255.43002)
		(end 121.775728 -255.994916)
		(width 0.1524)
		(layer "F.Cu")
		(net "P0V8_PEX0_PWM1")
	)
	(segment
		(start 122.100594 -253.985014)
		(end 122.100594 -255.105154)
		(width 0.1524)
		(layer "F.Cu")
		(net "P0V8_PEX0_PWM1")
	)
	(segment
		(start 105.711498 -281.999182)
		(end 105.711498 -281.438858)
		(width 0.2032)
		(layer "F.Cu")
		(net "P0V8_PEX0_PWM1")
	)
	(via
		(at 122.100594 -253.985014)
		(size 0.508)
		(drill 0.254)
		(layers "F.Cu" "B.Cu")
		(net "P0V8_PEX0_PWM1")
	)
	(via
		(at 105.914952 -280.617168)
		(size 0.508)
		(drill 0.254)
		(layers "F.Cu" "B.Cu")
		(net "P0V8_PEX0_PWM1")
	)
	(segment
		(start 122.100594 -253.985014)
		(end 121.034048 -253.985014)
		(width 0.2032)
		(layer "In5.Cu")
		(net "P0V8_PEX0_PWM1")
	)
	(segment
		(start 105.3592 -280.061416)
		(end 105.914952 -280.617168)
		(width 0.2032)
		(layer "In5.Cu")
		(net "P0V8_PEX0_PWM1")
	)
	(segment
		(start 118.301516 -258.994148)
		(end 110.533942 -266.761722)
		(width 0.2032)
		(layer "In5.Cu")
		(net "P0V8_PEX0_PWM1")
	)
	(segment
		(start 105.3592 -278.931624)
		(end 105.3592 -280.061416)
		(width 0.2032)
		(layer "In5.Cu")
		(net "P0V8_PEX0_PWM1")
	)
	(segment
		(start 121.034048 -253.985014)
		(end 118.301516 -256.717546)
		(width 0.2032)
		(layer "In5.Cu")
		(net "P0V8_PEX0_PWM1")
	)
	(segment
		(start 107.011978 -268.78915)
		(end 107.011978 -277.278846)
		(width 0.2032)
		(layer "In5.Cu")
		(net "P0V8_PEX0_PWM1")
	)
	(segment
		(start 107.011978 -277.278846)
		(end 105.3592 -278.931624)
		(width 0.2032)
		(layer "In5.Cu")
		(net "P0V8_PEX0_PWM1")
	)
	(segment
		(start 110.533942 -266.761722)
		(end 109.039406 -266.761722)
		(width 0.2032)
		(layer "In5.Cu")
		(net "P0V8_PEX0_PWM1")
	)
	(segment
		(start 109.039406 -266.761722)
		(end 107.011978 -268.78915)
		(width 0.2032)
		(layer "In5.Cu")
		(net "P0V8_PEX0_PWM1")
	)
	(segment
		(start 118.301516 -256.717546)
		(end 118.301516 -258.994148)
		(width 0.2032)
		(layer "In5.Cu")
		(net "P0V8_PEX0_PWM1")
	)
	(segment
		(start 458.035914 -309.734712)
		(end 458.394562 -309.734712)
		(width 0.254)
		(layer "F.Cu")
		(net "P1V25_PEX3_FB")
	)
	(segment
		(start 456.540108 -309.492142)
		(end 457.158598 -309.492142)
		(width 0.1778)
		(layer "F.Cu")
		(net "P1V25_PEX3_FB")
	)
	(segment
		(start 459.375256 -309.679086)
		(end 459.703678 -309.679086)
		(width 0.254)
		(layer "F.Cu")
		(net "P1V25_PEX3_FB")
	)
	(segment
		(start 459.039722 -309.86857)
		(end 459.185772 -309.86857)
		(width 0.254)
		(layer "F.Cu")
		(net "P1V25_PEX3_FB")
	)
	(segment
		(start 458.394562 -309.734712)
		(end 458.73035 -309.734712)
		(width 0.254)
		(layer "F.Cu")
		(net "P1V25_PEX3_FB")
	)
	(segment
		(start 457.164948 -309.498492)
		(end 457.46543 -309.498492)
		(width 0.254)
		(layer "F.Cu")
		(net "P1V25_PEX3_FB")
	)
	(segment
		(start 457.158598 -309.492142)
		(end 457.164948 -309.498492)
		(width 0.254)
		(layer "F.Cu")
		(net "P1V25_PEX3_FB")
	)
	(segment
		(start 457.46543 -309.498492)
		(end 458.035914 -309.734712)
		(width 0.254)
		(layer "F.Cu")
		(net "P1V25_PEX3_FB")
	)
	(segment
		(start 458.73035 -309.734712)
		(end 458.864208 -309.86857)
		(width 0.254)
		(layer "F.Cu")
		(net "P1V25_PEX3_FB")
	)
	(segment
		(start 459.703678 -310.695086)
		(end 459.703678 -309.679086)
		(width 0.254)
		(layer "F.Cu")
		(net "P1V25_PEX3_FB")
	)
	(segment
		(start 459.185772 -309.86857)
		(end 459.375256 -309.679086)
		(width 0.254)
		(layer "F.Cu")
		(net "P1V25_PEX3_FB")
	)
	(segment
		(start 458.864208 -309.86857)
		(end 459.039722 -309.86857)
		(width 0.254)
		(layer "F.Cu")
		(net "P1V25_PEX3_FB")
	)
	(via
		(at 459.039722 -309.86857)
		(size 0.508)
		(drill 0.254)
		(layers "F.Cu" "B.Cu")
		(net "P1V25_PEX3_FB")
	)
	(segment
		(start 120.339612 -253.411228)
		(end 119.925592 -252.997208)
		(width 0.13208)
		(layer "F.Cu")
		(net "NC_P0V8_PEX0_PWM3")
	)
	(segment
		(start 120.339612 -254.716788)
		(end 120.339612 -253.411228)
		(width 0.13208)
		(layer "F.Cu")
		(net "NC_P0V8_PEX0_PWM3")
	)
	(segment
		(start 120.175782 -254.880618)
		(end 120.339612 -254.716788)
		(width 0.13208)
		(layer "F.Cu")
		(net "NC_P0V8_PEX0_PWM3")
	)
	(segment
		(start 120.175782 -255.994916)
		(end 120.175782 -254.880618)
		(width 0.13208)
		(layer "F.Cu")
		(net "NC_P0V8_PEX0_PWM3")
	)
	(via
		(at 119.925592 -252.997208)
		(size 0.762)
		(drill 0.381)
		(layers "F.Cu" "B.Cu")
		(net "NC_P0V8_PEX0_PWM3")
	)
	(segment
		(start 456.540108 -309.891938)
		(end 456.986132 -309.891938)
		(width 0.13208)
		(layer "F.Cu")
		(net "P1V25_PEX3_EN")
	)
	(segment
		(start 457.957682 -310.692292)
		(end 457.957682 -310.665368)
		(width 0.13208)
		(layer "F.Cu")
		(net "P1V25_PEX3_EN")
	)
	(segment
		(start 456.986132 -309.891938)
		(end 457.324206 -310.031892)
		(width 0.13208)
		(layer "F.Cu")
		(net "P1V25_PEX3_EN")
	)
	(segment
		(start 457.957682 -310.665368)
		(end 457.324206 -310.031892)
		(width 0.13208)
		(layer "F.Cu")
		(net "P1V25_PEX3_EN")
	)
	(via
		(at 457.324206 -310.031892)
		(size 0.508)
		(drill 0.254)
		(layers "F.Cu" "B.Cu")
		(net "P1V25_PEX3_EN")
	)
	(segment
		(start 349.657924 -260.271514)
		(end 349.31731 -260.271514)
		(width 0.1778)
		(layer "F.Cu")
		(net "P0V8_PEX3_VSEN3")
	)
	(segment
		(start 349.29826 -260.290564)
		(end 349.31731 -260.271514)
		(width 0.254)
		(layer "F.Cu")
		(net "P0V8_PEX3_VSEN3")
	)
	(segment
		(start 350.57588 -259.79501)
		(end 350.134428 -259.79501)
		(width 0.1778)
		(layer "F.Cu")
		(net "P0V8_PEX3_VSEN3")
	)
	(segment
		(start 350.134428 -259.79501)
		(end 349.657924 -260.271514)
		(width 0.1778)
		(layer "F.Cu")
		(net "P0V8_PEX3_VSEN3")
	)
	(segment
		(start 348.32036 -260.290564)
		(end 349.29826 -260.290564)
		(width 0.254)
		(layer "F.Cu")
		(net "P0V8_PEX3_VSEN3")
	)
	(segment
		(start 119.628412 -265.834114)
		(end 121.06402 -265.834114)
		(width 0.1778)
		(layer "F.Cu")
		(net "P0V8_PEX0_ISEN1")
	)
	(segment
		(start 121.06402 -265.834114)
		(end 121.775728 -265.122406)
		(width 0.1778)
		(layer "F.Cu")
		(net "P0V8_PEX0_ISEN1")
	)
	(segment
		(start 107.511596 -281.65425)
		(end 107.94873 -281.217116)
		(width 0.2286)
		(layer "F.Cu")
		(net "P0V8_PEX0_ISEN1")
	)
	(segment
		(start 121.775728 -265.122406)
		(end 121.775728 -260.795008)
		(width 0.1778)
		(layer "F.Cu")
		(net "P0V8_PEX0_ISEN1")
	)
	(segment
		(start 107.511596 -281.999182)
		(end 107.511596 -281.65425)
		(width 0.2286)
		(layer "F.Cu")
		(net "P0V8_PEX0_ISEN1")
	)
	(segment
		(start 107.94873 -281.217116)
		(end 107.94873 -281.151838)
		(width 0.2286)
		(layer "F.Cu")
		(net "P0V8_PEX0_ISEN1")
	)
	(via
		(at 107.94873 -281.151838)
		(size 0.508)
		(drill 0.254)
		(layers "F.Cu" "B.Cu")
		(net "P0V8_PEX0_ISEN1")
	)
	(via
		(at 119.628412 -265.834114)
		(size 0.508)
		(drill 0.254)
		(layers "F.Cu" "B.Cu")
		(net "P0V8_PEX0_ISEN1")
	)
	(segment
		(start 119.628412 -265.834114)
		(end 119.231156 -265.998706)
		(width 0.254)
		(layer "In11.Cu")
		(net "P0V8_PEX0_ISEN1")
	)
	(segment
		(start 108.436664 -280.663904)
		(end 107.94873 -281.151838)
		(width 0.254)
		(layer "In11.Cu")
		(net "P0V8_PEX0_ISEN1")
	)
	(segment
		(start 119.231156 -265.998706)
		(end 118.280942 -266.94892)
		(width 0.254)
		(layer "In11.Cu")
		(net "P0V8_PEX0_ISEN1")
	)
	(segment
		(start 109.863382 -279.75687)
		(end 108.956348 -280.663904)
		(width 0.254)
		(layer "In11.Cu")
		(net "P0V8_PEX0_ISEN1")
	)
	(segment
		(start 112.956086 -278.499062)
		(end 111.698278 -279.75687)
		(width 0.254)
		(layer "In11.Cu")
		(net "P0V8_PEX0_ISEN1")
	)
	(segment
		(start 111.698278 -279.75687)
		(end 109.863382 -279.75687)
		(width 0.254)
		(layer "In11.Cu")
		(net "P0V8_PEX0_ISEN1")
	)
	(segment
		(start 117.113558 -266.94892)
		(end 112.956086 -271.106392)
		(width 0.254)
		(layer "In11.Cu")
		(net "P0V8_PEX0_ISEN1")
	)
	(segment
		(start 118.280942 -266.94892)
		(end 117.113558 -266.94892)
		(width 0.254)
		(layer "In11.Cu")
		(net "P0V8_PEX0_ISEN1")
	)
	(segment
		(start 108.956348 -280.663904)
		(end 108.436664 -280.663904)
		(width 0.254)
		(layer "In11.Cu")
		(net "P0V8_PEX0_ISEN1")
	)
	(segment
		(start 112.956086 -271.106392)
		(end 112.956086 -278.499062)
		(width 0.254)
		(layer "In11.Cu")
		(net "P0V8_PEX0_ISEN1")
	)
	(segment
		(start 459.574646 -306.86502)
		(end 459.574646 -306.910486)
		(width 0.13208)
		(layer "F.Cu")
		(net "P1V25_PEX3_REF")
	)
	(segment
		(start 458.537818 -307.885846)
		(end 459.5368 -307.885846)
		(width 0.254)
		(layer "F.Cu")
		(net "P1V25_PEX3_REF")
	)
	(segment
		(start 457.62545 -308.692042)
		(end 457.806552 -308.617112)
		(width 0.1778)
		(layer "F.Cu")
		(net "P1V25_PEX3_REF")
	)
	(segment
		(start 459.5368 -307.885846)
		(end 459.574646 -307.848)
		(width 0.254)
		(layer "F.Cu")
		(net "P1V25_PEX3_REF")
	)
	(segment
		(start 458.029056 -308.394608)
		(end 458.537818 -307.885846)
		(width 0.254)
		(layer "F.Cu")
		(net "P1V25_PEX3_REF")
	)
	(segment
		(start 460.28102 -306.158646)
		(end 459.574646 -306.86502)
		(width 0.13208)
		(layer "F.Cu")
		(net "P1V25_PEX3_REF")
	)
	(segment
		(start 456.540108 -308.692042)
		(end 457.62545 -308.692042)
		(width 0.1778)
		(layer "F.Cu")
		(net "P1V25_PEX3_REF")
	)
	(segment
		(start 457.806552 -308.617112)
		(end 458.029056 -308.394608)
		(width 0.1778)
		(layer "F.Cu")
		(net "P1V25_PEX3_REF")
	)
	(segment
		(start 459.574646 -307.848)
		(end 459.574646 -306.910486)
		(width 0.254)
		(layer "F.Cu")
		(net "P1V25_PEX3_REF")
	)
	(via
		(at 460.28102 -306.158646)
		(size 0.508)
		(drill 0.254)
		(layers "F.Cu" "B.Cu")
		(net "P1V25_PEX3_REF")
	)
	(segment
		(start 421.249856 -302.549814)
		(end 421.724836 -302.074834)
		(width 0.127)
		(layer "F.Cu")
		(net "VSENSE_P0V8_PEX3_SKT_VSEN")
	)
	(via
		(at 421.724836 -302.074834)
		(size 0.4064)
		(drill 0.2032)
		(layers "F.Cu" "B.Cu")
		(net "VSENSE_P0V8_PEX3_SKT_VSEN")
	)
	(via
		(at 370.279676 -328.352404)
		(size 0.6604)
		(drill 0.3302)
		(layers "F.Cu" "B.Cu")
		(net "VSENSE_P0V8_PEX3_SKT_VSEN")
	)
	(segment
		(start 408.184604 -307.406548)
		(end 419.132004 -307.406548)
		(width 0.09906)
		(layer "B.Cu")
		(net "VSENSE_P0V8_PEX3_SKT_VSEN")
	)
	(segment
		(start 367.197132 -328.092054)
		(end 370.019326 -328.092054)
		(width 0.254)
		(layer "B.Cu")
		(net "VSENSE_P0V8_PEX3_SKT_VSEN")
	)
	(segment
		(start 370.540026 -328.092054)
		(end 390.761982 -328.092054)
		(width 0.254)
		(layer "B.Cu")
		(net "VSENSE_P0V8_PEX3_SKT_VSEN")
	)
	(segment
		(start 370.279676 -328.352404)
		(end 370.540026 -328.092054)
		(width 0.254)
		(layer "B.Cu")
		(net "VSENSE_P0V8_PEX3_SKT_VSEN")
	)
	(segment
		(start 419.59403 -302.656494)
		(end 421.102536 -302.656494)
		(width 0.09906)
		(layer "B.Cu")
		(net "VSENSE_P0V8_PEX3_SKT_VSEN")
	)
	(segment
		(start 407.581608 -320.171572)
		(end 407.581608 -308.009544)
		(width 0.09906)
		(layer "B.Cu")
		(net "VSENSE_P0V8_PEX3_SKT_VSEN")
	)
	(segment
		(start 421.455596 -302.074834)
		(end 421.724836 -302.074834)
		(width 0.09906)
		(layer "B.Cu")
		(net "VSENSE_P0V8_PEX3_SKT_VSEN")
	)
	(segment
		(start 407.665428 -320.81597)
		(end 407.665428 -320.294)
		(width 0.254)
		(layer "B.Cu")
		(net "VSENSE_P0V8_PEX3_SKT_VSEN")
	)
	(segment
		(start 407.665428 -320.294)
		(end 407.665428 -320.255392)
		(width 0.09906)
		(layer "B.Cu")
		(net "VSENSE_P0V8_PEX3_SKT_VSEN")
	)
	(segment
		(start 407.196798 -321.2846)
		(end 407.665428 -320.81597)
		(width 0.254)
		(layer "B.Cu")
		(net "VSENSE_P0V8_PEX3_SKT_VSEN")
	)
	(segment
		(start 407.665428 -320.255392)
		(end 407.581608 -320.171572)
		(width 0.09906)
		(layer "B.Cu")
		(net "VSENSE_P0V8_PEX3_SKT_VSEN")
	)
	(segment
		(start 421.102536 -302.656494)
		(end 421.356536 -302.402494)
		(width 0.09906)
		(layer "B.Cu")
		(net "VSENSE_P0V8_PEX3_SKT_VSEN")
	)
	(segment
		(start 390.761982 -328.092054)
		(end 407.196798 -321.2846)
		(width 0.254)
		(layer "B.Cu")
		(net "VSENSE_P0V8_PEX3_SKT_VSEN")
	)
	(segment
		(start 419.132004 -307.406548)
		(end 419.456616 -307.081936)
		(width 0.09906)
		(layer "B.Cu")
		(net "VSENSE_P0V8_PEX3_SKT_VSEN")
	)
	(segment
		(start 421.356536 -302.173894)
		(end 421.455596 -302.074834)
		(width 0.09906)
		(layer "B.Cu")
		(net "VSENSE_P0V8_PEX3_SKT_VSEN")
	)
	(segment
		(start 421.356536 -302.402494)
		(end 421.356536 -302.173894)
		(width 0.09906)
		(layer "B.Cu")
		(net "VSENSE_P0V8_PEX3_SKT_VSEN")
	)
	(segment
		(start 419.456616 -302.793908)
		(end 419.59403 -302.656494)
		(width 0.09906)
		(layer "B.Cu")
		(net "VSENSE_P0V8_PEX3_SKT_VSEN")
	)
	(segment
		(start 419.456616 -307.081936)
		(end 419.456616 -302.793908)
		(width 0.09906)
		(layer "B.Cu")
		(net "VSENSE_P0V8_PEX3_SKT_VSEN")
	)
	(segment
		(start 366.892586 -328.422)
		(end 367.197132 -328.092054)
		(width 0.254)
		(layer "B.Cu")
		(net "VSENSE_P0V8_PEX3_SKT_VSEN")
	)
	(segment
		(start 407.581608 -308.009544)
		(end 408.184604 -307.406548)
		(width 0.09906)
		(layer "B.Cu")
		(net "VSENSE_P0V8_PEX3_SKT_VSEN")
	)
	(segment
		(start 370.019326 -328.092054)
		(end 370.279676 -328.352404)
		(width 0.254)
		(layer "B.Cu")
		(net "VSENSE_P0V8_PEX3_SKT_VSEN")
	)
	(segment
		(start 461.517238 -307.683916)
		(end 461.524858 -307.607716)
		(width 0.254)
		(layer "F.Cu")
		(net "SH_P1V25_PEX3_FB_N")
	)
	(segment
		(start 458.068426 -308.934612)
		(end 458.394562 -308.934612)
		(width 0.254)
		(layer "F.Cu")
		(net "SH_P1V25_PEX3_FB_N")
	)
	(segment
		(start 460.508858 -307.81879)
		(end 460.821786 -307.81879)
		(width 0.254)
		(layer "F.Cu")
		(net "SH_P1V25_PEX3_FB_N")
	)
	(segment
		(start 460.508858 -307.81879)
		(end 460.211678 -307.81879)
		(width 0.254)
		(layer "F.Cu")
		(net "SH_P1V25_PEX3_FB_N")
	)
	(segment
		(start 457.513944 -309.092092)
		(end 457.688188 -309.092092)
		(width 0.254)
		(layer "F.Cu")
		(net "SH_P1V25_PEX3_FB_N")
	)
	(segment
		(start 459.599792 -308.685946)
		(end 459.5368 -308.685946)
		(width 0.254)
		(layer "F.Cu")
		(net "SH_P1V25_PEX3_FB_N")
	)
	(segment
		(start 456.540108 -309.092092)
		(end 457.513944 -309.092092)
		(width 0.1778)
		(layer "F.Cu")
		(net "SH_P1V25_PEX3_FB_N")
	)
	(segment
		(start 459.188566 -308.778148)
		(end 459.444598 -308.778148)
		(width 0.254)
		(layer "F.Cu")
		(net "SH_P1V25_PEX3_FB_N")
	)
	(segment
		(start 458.93609 -308.525672)
		(end 459.188566 -308.778148)
		(width 0.254)
		(layer "F.Cu")
		(net "SH_P1V25_PEX3_FB_N")
	)
	(segment
		(start 460.064866 -308.03215)
		(end 460.064866 -308.220872)
		(width 0.254)
		(layer "F.Cu")
		(net "SH_P1V25_PEX3_FB_N")
	)
	(segment
		(start 459.444598 -308.778148)
		(end 459.5368 -308.685946)
		(width 0.254)
		(layer "F.Cu")
		(net "SH_P1V25_PEX3_FB_N")
	)
	(segment
		(start 460.111856 -307.918612)
		(end 460.064866 -308.03215)
		(width 0.254)
		(layer "F.Cu")
		(net "SH_P1V25_PEX3_FB_N")
	)
	(segment
		(start 461.244188 -307.956966)
		(end 461.517238 -307.683916)
		(width 0.254)
		(layer "F.Cu")
		(net "SH_P1V25_PEX3_FB_N")
	)
	(segment
		(start 460.211678 -307.81879)
		(end 460.111856 -307.918612)
		(width 0.254)
		(layer "F.Cu")
		(net "SH_P1V25_PEX3_FB_N")
	)
	(segment
		(start 458.52715 -308.934612)
		(end 458.93609 -308.525672)
		(width 0.254)
		(layer "F.Cu")
		(net "SH_P1V25_PEX3_FB_N")
	)
	(segment
		(start 460.821786 -307.81879)
		(end 460.959962 -307.956966)
		(width 0.254)
		(layer "F.Cu")
		(net "SH_P1V25_PEX3_FB_N")
	)
	(segment
		(start 460.064866 -308.220872)
		(end 459.599792 -308.685946)
		(width 0.254)
		(layer "F.Cu")
		(net "SH_P1V25_PEX3_FB_N")
	)
	(segment
		(start 460.959962 -307.956966)
		(end 461.244188 -307.956966)
		(width 0.254)
		(layer "F.Cu")
		(net "SH_P1V25_PEX3_FB_N")
	)
	(segment
		(start 457.688188 -309.092092)
		(end 458.068426 -308.934612)
		(width 0.254)
		(layer "F.Cu")
		(net "SH_P1V25_PEX3_FB_N")
	)
	(segment
		(start 458.394562 -308.934612)
		(end 458.52715 -308.934612)
		(width 0.254)
		(layer "F.Cu")
		(net "SH_P1V25_PEX3_FB_N")
	)
	(via
		(at 458.93609 -308.525672)
		(size 0.508)
		(drill 0.254)
		(layers "F.Cu" "B.Cu")
		(net "SH_P1V25_PEX3_FB_N")
	)
	(segment
		(start 355.375972 -256.594864)
		(end 355.618288 -256.594864)
		(width 0.13208)
		(layer "F.Cu")
		(net "P0V8_PEX2_SMBALERT")
	)
	(segment
		(start 359.034588 -253.178564)
		(end 359.45826 -253.178564)
		(width 0.13208)
		(layer "F.Cu")
		(net "P0V8_PEX2_SMBALERT")
	)
	(segment
		(start 216.835736 -213.222586)
		(end 216.200736 -213.222586)
		(width 0.13208)
		(layer "F.Cu")
		(net "P0V8_PEX2_SMBALERT")
	)
	(segment
		(start 358.825292 -253.38786)
		(end 359.034588 -253.178564)
		(width 0.13208)
		(layer "F.Cu")
		(net "P0V8_PEX2_SMBALERT")
	)
	(segment
		(start 355.618288 -256.594864)
		(end 358.825292 -253.38786)
		(width 0.13208)
		(layer "F.Cu")
		(net "P0V8_PEX2_SMBALERT")
	)
	(via
		(at 219.957142 -248.459498)
		(size 0.508)
		(drill 0.254)
		(layers "F.Cu" "B.Cu")
		(net "P0V8_PEX2_SMBALERT")
	)
	(via
		(at 304.7238 -257.469894)
		(size 0.508)
		(drill 0.254)
		(layers "F.Cu" "B.Cu")
		(net "P0V8_PEX2_SMBALERT")
	)
	(via
		(at 358.825292 -253.38786)
		(size 0.508)
		(drill 0.254)
		(layers "F.Cu" "B.Cu")
		(net "P0V8_PEX2_SMBALERT")
	)
	(via
		(at 216.200736 -213.222586)
		(size 0.508)
		(drill 0.254)
		(layers "F.Cu" "B.Cu")
		(net "P0V8_PEX2_SMBALERT")
	)
	(segment
		(start 308.09565 -252.923294)
		(end 307.910484 -252.923294)
		(width 0.13208)
		(layer "B.Cu")
		(net "P0V8_PEX2_SMBALERT")
	)
	(segment
		(start 304.27041 -257.016504)
		(end 304.7238 -257.469894)
		(width 0.13208)
		(layer "B.Cu")
		(net "P0V8_PEX2_SMBALERT")
	)
	(segment
		(start 308.174644 -252.8443)
		(end 308.09565 -252.923294)
		(width 0.13208)
		(layer "B.Cu")
		(net "P0V8_PEX2_SMBALERT")
	)
	(segment
		(start 360.355388 -252.672596)
		(end 360.355388 -250.360942)
		(width 0.13208)
		(layer "B.Cu")
		(net "P0V8_PEX2_SMBALERT")
	)
	(segment
		(start 358.194864 -248.200418)
		(end 344.506042 -248.200418)
		(width 0.13208)
		(layer "B.Cu")
		(net "P0V8_PEX2_SMBALERT")
	)
	(segment
		(start 307.910484 -252.923294)
		(end 304.27041 -256.563368)
		(width 0.13208)
		(layer "B.Cu")
		(net "P0V8_PEX2_SMBALERT")
	)
	(segment
		(start 344.506042 -248.200418)
		(end 339.86216 -252.8443)
		(width 0.13208)
		(layer "B.Cu")
		(net "P0V8_PEX2_SMBALERT")
	)
	(segment
		(start 360.355388 -250.360942)
		(end 358.194864 -248.200418)
		(width 0.13208)
		(layer "B.Cu")
		(net "P0V8_PEX2_SMBALERT")
	)
	(segment
		(start 358.825292 -253.38786)
		(end 359.640124 -253.38786)
		(width 0.13208)
		(layer "B.Cu")
		(net "P0V8_PEX2_SMBALERT")
	)
	(segment
		(start 304.27041 -256.563368)
		(end 304.27041 -257.016504)
		(width 0.13208)
		(layer "B.Cu")
		(net "P0V8_PEX2_SMBALERT")
	)
	(segment
		(start 339.86216 -252.8443)
		(end 308.174644 -252.8443)
		(width 0.13208)
		(layer "B.Cu")
		(net "P0V8_PEX2_SMBALERT")
	)
	(segment
		(start 359.640124 -253.38786)
		(end 360.355388 -252.672596)
		(width 0.13208)
		(layer "B.Cu")
		(net "P0V8_PEX2_SMBALERT")
	)
	(segment
		(start 219.957142 -248.393458)
		(end 221.361 -246.9896)
		(width 0.15494)
		(layer "In5.Cu")
		(net "P0V8_PEX2_SMBALERT")
	)
	(segment
		(start 219.74556 -226.1362)
		(end 219.74556 -223.982534)
		(width 0.15494)
		(layer "In5.Cu")
		(net "P0V8_PEX2_SMBALERT")
	)
	(segment
		(start 220.380306 -217.726006)
		(end 219.17152 -216.51722)
		(width 0.15494)
		(layer "In5.Cu")
		(net "P0V8_PEX2_SMBALERT")
	)
	(segment
		(start 222.02394 -240.200942)
		(end 219.758514 -237.935516)
		(width 0.15494)
		(layer "In5.Cu")
		(net "P0V8_PEX2_SMBALERT")
	)
	(segment
		(start 222.02394 -245.8593)
		(end 222.02394 -240.200942)
		(width 0.15494)
		(layer "In5.Cu")
		(net "P0V8_PEX2_SMBALERT")
	)
	(segment
		(start 220.380306 -219.290646)
		(end 220.380306 -217.726006)
		(width 0.15494)
		(layer "In5.Cu")
		(net "P0V8_PEX2_SMBALERT")
	)
	(segment
		(start 221.361 -246.9896)
		(end 221.361 -246.52224)
		(width 0.15494)
		(layer "In5.Cu")
		(net "P0V8_PEX2_SMBALERT")
	)
	(segment
		(start 219.745306 -223.98228)
		(end 219.745306 -219.925646)
		(width 0.15494)
		(layer "In5.Cu")
		(net "P0V8_PEX2_SMBALERT")
	)
	(segment
		(start 219.17152 -214.397844)
		(end 217.996262 -213.222586)
		(width 0.15494)
		(layer "In5.Cu")
		(net "P0V8_PEX2_SMBALERT")
	)
	(segment
		(start 219.758514 -237.404148)
		(end 220.046042 -237.11662)
		(width 0.15494)
		(layer "In5.Cu")
		(net "P0V8_PEX2_SMBALERT")
	)
	(segment
		(start 219.17152 -216.51722)
		(end 219.17152 -214.397844)
		(width 0.15494)
		(layer "In5.Cu")
		(net "P0V8_PEX2_SMBALERT")
	)
	(segment
		(start 219.957142 -248.459498)
		(end 219.957142 -248.393458)
		(width 0.15494)
		(layer "In5.Cu")
		(net "P0V8_PEX2_SMBALERT")
	)
	(segment
		(start 217.996262 -213.222586)
		(end 216.200736 -213.222586)
		(width 0.15494)
		(layer "In5.Cu")
		(net "P0V8_PEX2_SMBALERT")
	)
	(segment
		(start 220.046042 -226.436682)
		(end 219.74556 -226.1362)
		(width 0.15494)
		(layer "In5.Cu")
		(net "P0V8_PEX2_SMBALERT")
	)
	(segment
		(start 220.046042 -237.11662)
		(end 220.046042 -226.436682)
		(width 0.15494)
		(layer "In5.Cu")
		(net "P0V8_PEX2_SMBALERT")
	)
	(segment
		(start 221.361 -246.52224)
		(end 222.02394 -245.8593)
		(width 0.15494)
		(layer "In5.Cu")
		(net "P0V8_PEX2_SMBALERT")
	)
	(segment
		(start 219.758514 -237.935516)
		(end 219.758514 -237.404148)
		(width 0.15494)
		(layer "In5.Cu")
		(net "P0V8_PEX2_SMBALERT")
	)
	(segment
		(start 219.745306 -219.925646)
		(end 220.380306 -219.290646)
		(width 0.15494)
		(layer "In5.Cu")
		(net "P0V8_PEX2_SMBALERT")
	)
	(segment
		(start 219.74556 -223.982534)
		(end 219.745306 -223.98228)
		(width 0.15494)
		(layer "In5.Cu")
		(net "P0V8_PEX2_SMBALERT")
	)
	(segment
		(start 301.02048 -257.469894)
		(end 304.7238 -257.469894)
		(width 0.15494)
		(layer "In13.Cu")
		(net "P0V8_PEX2_SMBALERT")
	)
	(segment
		(start 220.920056 -249.422412)
		(end 228.442774 -249.422412)
		(width 0.15494)
		(layer "In13.Cu")
		(net "P0V8_PEX2_SMBALERT")
	)
	(segment
		(start 271.298416 -253.72187)
		(end 271.726406 -254.14986)
		(width 0.15494)
		(layer "In13.Cu")
		(net "P0V8_PEX2_SMBALERT")
	)
	(segment
		(start 297.700446 -254.14986)
		(end 301.02048 -257.469894)
		(width 0.15494)
		(layer "In13.Cu")
		(net "P0V8_PEX2_SMBALERT")
	)
	(segment
		(start 235.329984 -251.613924)
		(end 236.15904 -252.44298)
		(width 0.15494)
		(layer "In13.Cu")
		(net "P0V8_PEX2_SMBALERT")
	)
	(segment
		(start 236.15904 -252.44298)
		(end 245.422166 -252.44298)
		(width 0.15494)
		(layer "In13.Cu")
		(net "P0V8_PEX2_SMBALERT")
	)
	(segment
		(start 228.442774 -249.422412)
		(end 229.611682 -250.59132)
		(width 0.15494)
		(layer "In13.Cu")
		(net "P0V8_PEX2_SMBALERT")
	)
	(segment
		(start 271.298416 -253.010416)
		(end 271.298416 -253.72187)
		(width 0.15494)
		(layer "In13.Cu")
		(net "P0V8_PEX2_SMBALERT")
	)
	(segment
		(start 219.957142 -248.459498)
		(end 220.920056 -249.422412)
		(width 0.15494)
		(layer "In13.Cu")
		(net "P0V8_PEX2_SMBALERT")
	)
	(segment
		(start 246.151146 -251.714)
		(end 253.014226 -251.714)
		(width 0.15494)
		(layer "In13.Cu")
		(net "P0V8_PEX2_SMBALERT")
	)
	(segment
		(start 229.611682 -250.59132)
		(end 233.171746 -250.59132)
		(width 0.15494)
		(layer "In13.Cu")
		(net "P0V8_PEX2_SMBALERT")
	)
	(segment
		(start 245.422166 -252.44298)
		(end 246.151146 -251.714)
		(width 0.15494)
		(layer "In13.Cu")
		(net "P0V8_PEX2_SMBALERT")
	)
	(segment
		(start 234.19435 -251.613924)
		(end 235.329984 -251.613924)
		(width 0.15494)
		(layer "In13.Cu")
		(net "P0V8_PEX2_SMBALERT")
	)
	(segment
		(start 253.014226 -251.714)
		(end 254.103886 -252.80366)
		(width 0.15494)
		(layer "In13.Cu")
		(net "P0V8_PEX2_SMBALERT")
	)
	(segment
		(start 271.726406 -254.14986)
		(end 297.700446 -254.14986)
		(width 0.15494)
		(layer "In13.Cu")
		(net "P0V8_PEX2_SMBALERT")
	)
	(segment
		(start 233.171746 -250.59132)
		(end 234.19435 -251.613924)
		(width 0.15494)
		(layer "In13.Cu")
		(net "P0V8_PEX2_SMBALERT")
	)
	(segment
		(start 254.103886 -252.80366)
		(end 271.09166 -252.80366)
		(width 0.15494)
		(layer "In13.Cu")
		(net "P0V8_PEX2_SMBALERT")
	)
	(segment
		(start 271.09166 -252.80366)
		(end 271.298416 -253.010416)
		(width 0.15494)
		(layer "In13.Cu")
		(net "P0V8_PEX2_SMBALERT")
	)
	(segment
		(start 347.52026 -260.290564)
		(end 347.52026 -261.046214)
		(width 0.254)
		(layer "F.Cu")
		(net "SH_P0V8_PEX3_VSEN3_R")
	)
	(segment
		(start 347.52026 -261.046214)
		(end 348.04731 -261.573264)
		(width 0.254)
		(layer "F.Cu")
		(net "SH_P0V8_PEX3_VSEN3_R")
	)
	(segment
		(start 460.508858 -308.706266)
		(end 460.944214 -309.141622)
		(width 0.254)
		(layer "F.Cu")
		(net "SH_P1V25_PEX3_FB_P")
	)
	(segment
		(start 460.508858 -308.61889)
		(end 460.508858 -308.706266)
		(width 0.254)
		(layer "F.Cu")
		(net "SH_P1V25_PEX3_FB_P")
	)
	(segment
		(start 461.188816 -308.363874)
		(end 460.762858 -308.363874)
		(width 0.254)
		(layer "F.Cu")
		(net "SH_P1V25_PEX3_FB_P")
	)
	(segment
		(start 460.944214 -309.141622)
		(end 460.503778 -309.582058)
		(width 0.254)
		(layer "F.Cu")
		(net "SH_P1V25_PEX3_FB_P")
	)
	(segment
		(start 460.762858 -308.363874)
		(end 460.508858 -308.617874)
		(width 0.254)
		(layer "F.Cu")
		(net "SH_P1V25_PEX3_FB_P")
	)
	(segment
		(start 460.503778 -309.679086)
		(end 460.503778 -310.695086)
		(width 0.254)
		(layer "F.Cu")
		(net "SH_P1V25_PEX3_FB_P")
	)
	(segment
		(start 460.508858 -308.617874)
		(end 460.508858 -308.61889)
		(width 0.254)
		(layer "F.Cu")
		(net "SH_P1V25_PEX3_FB_P")
	)
	(segment
		(start 460.503778 -309.582058)
		(end 460.503778 -309.679086)
		(width 0.254)
		(layer "F.Cu")
		(net "SH_P1V25_PEX3_FB_P")
	)
	(segment
		(start 461.524858 -308.692296)
		(end 461.188816 -308.363874)
		(width 0.254)
		(layer "F.Cu")
		(net "SH_P1V25_PEX3_FB_P")
	)
	(via
		(at 460.944214 -309.141622)
		(size 0.508)
		(drill 0.254)
		(layers "F.Cu" "B.Cu")
		(net "SH_P1V25_PEX3_FB_P")
	)
	(segment
		(start 356.722172 -257.394964)
		(end 357.078534 -257.038602)
		(width 0.13208)
		(layer "F.Cu")
		(net "FM_P0V8_PEX2_EN_R")
	)
	(segment
		(start 355.375972 -257.394964)
		(end 356.722172 -257.394964)
		(width 0.13208)
		(layer "F.Cu")
		(net "FM_P0V8_PEX2_EN_R")
	)
	(segment
		(start 361.285282 -254.678942)
		(end 360.008424 -254.678942)
		(width 0.13208)
		(layer "F.Cu")
		(net "FM_P0V8_PEX2_EN_R")
	)
	(segment
		(start 358.906572 -255.210564)
		(end 359.45826 -255.210564)
		(width 0.13208)
		(layer "F.Cu")
		(net "FM_P0V8_PEX2_EN_R")
	)
	(segment
		(start 359.476802 -255.210564)
		(end 359.45826 -255.210564)
		(width 0.13208)
		(layer "F.Cu")
		(net "FM_P0V8_PEX2_EN_R")
	)
	(segment
		(start 357.078534 -257.038602)
		(end 358.906572 -255.210564)
		(width 0.13208)
		(layer "F.Cu")
		(net "FM_P0V8_PEX2_EN_R")
	)
	(segment
		(start 361.49026 -255.210564)
		(end 361.49026 -254.88392)
		(width 0.13208)
		(layer "F.Cu")
		(net "FM_P0V8_PEX2_EN_R")
	)
	(segment
		(start 361.49026 -254.88392)
		(end 361.285282 -254.678942)
		(width 0.13208)
		(layer "F.Cu")
		(net "FM_P0V8_PEX2_EN_R")
	)
	(segment
		(start 360.008424 -254.678942)
		(end 359.476802 -255.210564)
		(width 0.13208)
		(layer "F.Cu")
		(net "FM_P0V8_PEX2_EN_R")
	)
	(via
		(at 357.078534 -257.038602)
		(size 0.762)
		(drill 0.381)
		(layers "F.Cu" "B.Cu")
		(net "FM_P0V8_PEX2_EN_R")
	)
	(segment
		(start 284.249876 -293.99992)
		(end 283.774896 -293.52494)
		(width 0.249936)
		(layer "F.Cu")
		(net "P0V8_PEX2")
	)
	(segment
		(start 286.149796 -297.79976)
		(end 285.674816 -298.27474)
		(width 0.249936)
		(layer "F.Cu")
		(net "P0V8_PEX2")
	)
	(segment
		(start 286.149796 -297.79976)
		(end 286.624776 -297.32478)
		(width 0.249936)
		(layer "F.Cu")
		(net "P0V8_PEX2")
	)
	(segment
		(start 288.049716 -295.89984)
		(end 287.574736 -296.37482)
		(width 0.249936)
		(layer "F.Cu")
		(net "P0V8_PEX2")
	)
	(segment
		(start 299.449744 -297.79976)
		(end 299.924724 -298.27474)
		(width 0.249936)
		(layer "F.Cu")
		(net "P0V8_PEX2")
	)
	(segment
		(start 281.399742 -291.149786)
		(end 280.924762 -290.674806)
		(width 0.249936)
		(layer "F.Cu")
		(net "P0V8_PEX2")
	)
	(segment
		(start 297.549824 -293.99992)
		(end 297.074844 -294.4749)
		(width 0.249936)
		(layer "F.Cu")
		(net "P0V8_PEX2")
	)
	(segment
		(start 281.874722 -298.27474)
		(end 282.349702 -297.79976)
		(width 0.249936)
		(layer "F.Cu")
		(net "P0V8_PEX2")
	)
	(segment
		(start 281.399742 -294.94988)
		(end 280.924762 -294.4749)
		(width 0.249936)
		(layer "F.Cu")
		(net "P0V8_PEX2")
	)
	(segment
		(start 285.199836 -296.8498)
		(end 285.674816 -296.37482)
		(width 0.249936)
		(layer "F.Cu")
		(net "P0V8_PEX2")
	)
	(segment
		(start 291.84981 -295.89984)
		(end 292.32479 -296.37482)
		(width 0.249936)
		(layer "F.Cu")
		(net "P0V8_PEX2")
	)
	(segment
		(start 285.199836 -296.8498)
		(end 284.724856 -297.32478)
		(width 0.249936)
		(layer "F.Cu")
		(net "P0V8_PEX2")
	)
	(segment
		(start 295.649904 -297.79976)
		(end 295.174924 -297.32478)
		(width 0.249936)
		(layer "F.Cu")
		(net "P0V8_PEX2")
	)
	(segment
		(start 282.824936 -294.4749)
		(end 283.299916 -294.94988)
		(width 0.249936)
		(layer "F.Cu")
		(net "P0V8_PEX2")
	)
	(segment
		(start 292.79977 -296.8498)
		(end 293.27475 -297.32478)
		(width 0.249936)
		(layer "F.Cu")
		(net "P0V8_PEX2")
	)
	(segment
		(start 286.624776 -297.32478)
		(end 287.099756 -296.8498)
		(width 0.249936)
		(layer "F.Cu")
		(net "P0V8_PEX2")
	)
	(segment
		(start 282.824936 -297.32478)
		(end 282.349702 -297.79976)
		(width 0.249936)
		(layer "F.Cu")
		(net "P0V8_PEX2")
	)
	(segment
		(start 281.399742 -300.649894)
		(end 281.874722 -300.174914)
		(width 0.249936)
		(layer "F.Cu")
		(net "P0V8_PEX2")
	)
	(segment
		(start 294.22471 -296.37482)
		(end 294.69969 -296.8498)
		(width 0.249936)
		(layer "F.Cu")
		(net "P0V8_PEX2")
	)
	(segment
		(start 291.84981 -293.99992)
		(end 292.32479 -293.52494)
		(width 0.249936)
		(layer "F.Cu")
		(net "P0V8_PEX2")
	)
	(segment
		(start 295.649904 -295.89984)
		(end 296.124884 -296.37482)
		(width 0.249936)
		(layer "F.Cu")
		(net "P0V8_PEX2")
	)
	(segment
		(start 281.874722 -293.52494)
		(end 282.349702 -293.99992)
		(width 0.249936)
		(layer "F.Cu")
		(net "P0V8_PEX2")
	)
	(segment
		(start 281.874722 -291.624766)
		(end 282.349702 -292.099746)
		(width 0.249936)
		(layer "F.Cu")
		(net "P0V8_PEX2")
	)
	(segment
		(start 283.299916 -296.8498)
		(end 282.824936 -297.32478)
		(width 0.249936)
		(layer "F.Cu")
		(net "P0V8_PEX2")
	)
	(segment
		(start 293.74973 -295.89984)
		(end 294.22471 -296.37482)
		(width 0.249936)
		(layer "F.Cu")
		(net "P0V8_PEX2")
	)
	(segment
		(start 297.549824 -297.79976)
		(end 297.074844 -297.32478)
		(width 0.249936)
		(layer "F.Cu")
		(net "P0V8_PEX2")
	)
	(segment
		(start 297.074844 -294.4749)
		(end 296.599864 -294.94988)
		(width 0.249936)
		(layer "F.Cu")
		(net "P0V8_PEX2")
	)
	(segment
		(start 296.124884 -296.37482)
		(end 296.599864 -296.8498)
		(width 0.249936)
		(layer "F.Cu")
		(net "P0V8_PEX2")
	)
	(segment
		(start 281.399742 -293.04996)
		(end 280.924762 -292.574726)
		(width 0.249936)
		(layer "F.Cu")
		(net "P0V8_PEX2")
	)
	(segment
		(start 281.874722 -296.37482)
		(end 282.349702 -295.89984)
		(width 0.249936)
		(layer "F.Cu")
		(net "P0V8_PEX2")
	)
	(segment
		(start 288.524696 -297.32478)
		(end 288.049716 -297.79976)
		(width 0.249936)
		(layer "F.Cu")
		(net "P0V8_PEX2")
	)
	(segment
		(start 289.94989 -297.79976)
		(end 289.47491 -298.27474)
		(width 0.249936)
		(layer "F.Cu")
		(net "P0V8_PEX2")
	)
	(segment
		(start 288.049716 -297.79976)
		(end 287.574736 -298.27474)
		(width 0.249936)
		(layer "F.Cu")
		(net "P0V8_PEX2")
	)
	(segment
		(start 281.399742 -293.04996)
		(end 281.874722 -293.52494)
		(width 0.249936)
		(layer "F.Cu")
		(net "P0V8_PEX2")
	)
	(segment
		(start 286.624776 -294.4749)
		(end 286.149796 -293.99992)
		(width 0.249936)
		(layer "F.Cu")
		(net "P0V8_PEX2")
	)
	(segment
		(start 281.874722 -300.174914)
		(end 282.349702 -299.699934)
		(width 0.249936)
		(layer "F.Cu")
		(net "P0V8_PEX2")
	)
	(segment
		(start 295.649904 -293.99992)
		(end 296.124884 -293.52494)
		(width 0.249936)
		(layer "F.Cu")
		(net "P0V8_PEX2")
	)
	(segment
		(start 290.42487 -294.4749)
		(end 289.94989 -293.99992)
		(width 0.249936)
		(layer "F.Cu")
		(net "P0V8_PEX2")
	)
	(segment
		(start 297.074844 -297.32478)
		(end 296.599864 -296.8498)
		(width 0.249936)
		(layer "F.Cu")
		(net "P0V8_PEX2")
	)
	(segment
		(start 298.024804 -293.52494)
		(end 297.549824 -293.99992)
		(width 0.249936)
		(layer "F.Cu")
		(net "P0V8_PEX2")
	)
	(segment
		(start 281.399742 -296.8498)
		(end 281.874722 -296.37482)
		(width 0.249936)
		(layer "F.Cu")
		(net "P0V8_PEX2")
	)
	(segment
		(start 283.299916 -296.8498)
		(end 283.774896 -296.37482)
		(width 0.249936)
		(layer "F.Cu")
		(net "P0V8_PEX2")
	)
	(segment
		(start 286.149796 -293.99992)
		(end 285.674816 -293.52494)
		(width 0.249936)
		(layer "F.Cu")
		(net "P0V8_PEX2")
	)
	(segment
		(start 288.524696 -294.4749)
		(end 288.049716 -293.99992)
		(width 0.249936)
		(layer "F.Cu")
		(net "P0V8_PEX2")
	)
	(segment
		(start 295.649904 -297.79976)
		(end 296.124884 -298.27474)
		(width 0.249936)
		(layer "F.Cu")
		(net "P0V8_PEX2")
	)
	(segment
		(start 292.79977 -294.94988)
		(end 293.27475 -294.4749)
		(width 0.249936)
		(layer "F.Cu")
		(net "P0V8_PEX2")
	)
	(segment
		(start 291.84981 -297.79976)
		(end 292.32479 -298.27474)
		(width 0.249936)
		(layer "F.Cu")
		(net "P0V8_PEX2")
	)
	(segment
		(start 287.574736 -296.37482)
		(end 287.099756 -296.8498)
		(width 0.249936)
		(layer "F.Cu")
		(net "P0V8_PEX2")
	)
	(segment
		(start 293.74973 -297.79976)
		(end 294.22471 -298.27474)
		(width 0.249936)
		(layer "F.Cu")
		(net "P0V8_PEX2")
	)
	(segment
		(start 299.449744 -293.99992)
		(end 299.924724 -293.52494)
		(width 0.249936)
		(layer "F.Cu")
		(net "P0V8_PEX2")
	)
	(segment
		(start 281.399742 -298.74972)
		(end 281.874722 -298.27474)
		(width 0.249936)
		(layer "F.Cu")
		(net "P0V8_PEX2")
	)
	(segment
		(start 288.99993 -294.94988)
		(end 288.524696 -294.4749)
		(width 0.249936)
		(layer "F.Cu")
		(net "P0V8_PEX2")
	)
	(segment
		(start 281.399742 -291.149786)
		(end 281.874722 -291.624766)
		(width 0.249936)
		(layer "F.Cu")
		(net "P0V8_PEX2")
	)
	(segment
		(start 281.399742 -296.8498)
		(end 280.924762 -297.32478)
		(width 0.249936)
		(layer "F.Cu")
		(net "P0V8_PEX2")
	)
	(segment
		(start 295.174924 -297.32478)
		(end 294.69969 -296.8498)
		(width 0.249936)
		(layer "F.Cu")
		(net "P0V8_PEX2")
	)
	(segment
		(start 290.42487 -297.32478)
		(end 289.94989 -297.79976)
		(width 0.249936)
		(layer "F.Cu")
		(net "P0V8_PEX2")
	)
	(segment
		(start 288.99993 -296.8498)
		(end 288.524696 -297.32478)
		(width 0.249936)
		(layer "F.Cu")
		(net "P0V8_PEX2")
	)
	(segment
		(start 288.049716 -293.99992)
		(end 287.574736 -293.52494)
		(width 0.249936)
		(layer "F.Cu")
		(net "P0V8_PEX2")
	)
	(segment
		(start 281.399742 -298.74972)
		(end 280.924762 -299.224954)
		(width 0.249936)
		(layer "F.Cu")
		(net "P0V8_PEX2")
	)
	(segment
		(start 282.349702 -293.99992)
		(end 282.824936 -294.4749)
		(width 0.249936)
		(layer "F.Cu")
		(net "P0V8_PEX2")
	)
	(segment
		(start 284.249876 -297.79976)
		(end 283.774896 -298.27474)
		(width 0.249936)
		(layer "F.Cu")
		(net "P0V8_PEX2")
	)
	(segment
		(start 283.774896 -296.37482)
		(end 284.249876 -295.89984)
		(width 0.249936)
		(layer "F.Cu")
		(net "P0V8_PEX2")
	)
	(segment
		(start 293.74973 -293.99992)
		(end 294.22471 -293.52494)
		(width 0.249936)
		(layer "F.Cu")
		(net "P0V8_PEX2")
	)
	(segment
		(start 288.99993 -296.8498)
		(end 289.47491 -296.37482)
		(width 0.249936)
		(layer "F.Cu")
		(net "P0V8_PEX2")
	)
	(segment
		(start 295.174924 -294.4749)
		(end 295.649904 -293.99992)
		(width 0.249936)
		(layer "F.Cu")
		(net "P0V8_PEX2")
	)
	(segment
		(start 293.27475 -297.32478)
		(end 293.74973 -297.79976)
		(width 0.249936)
		(layer "F.Cu")
		(net "P0V8_PEX2")
	)
	(segment
		(start 293.27475 -294.4749)
		(end 293.74973 -293.99992)
		(width 0.249936)
		(layer "F.Cu")
		(net "P0V8_PEX2")
	)
	(segment
		(start 294.69969 -294.94988)
		(end 295.174924 -294.4749)
		(width 0.249936)
		(layer "F.Cu")
		(net "P0V8_PEX2")
	)
	(segment
		(start 290.89985 -296.8498)
		(end 290.42487 -297.32478)
		(width 0.249936)
		(layer "F.Cu")
		(net "P0V8_PEX2")
	)
	(segment
		(start 298.024804 -298.27474)
		(end 297.549824 -297.79976)
		(width 0.249936)
		(layer "F.Cu")
		(net "P0V8_PEX2")
	)
	(segment
		(start 290.89985 -294.94988)
		(end 290.42487 -294.4749)
		(width 0.249936)
		(layer "F.Cu")
		(net "P0V8_PEX2")
	)
	(segment
		(start 289.47491 -296.37482)
		(end 289.94989 -295.89984)
		(width 0.249936)
		(layer "F.Cu")
		(net "P0V8_PEX2")
	)
	(segment
		(start 287.099756 -294.94988)
		(end 286.624776 -294.4749)
		(width 0.249936)
		(layer "F.Cu")
		(net "P0V8_PEX2")
	)
	(segment
		(start 285.674816 -296.37482)
		(end 286.149796 -295.89984)
		(width 0.249936)
		(layer "F.Cu")
		(net "P0V8_PEX2")
	)
	(segment
		(start 280.924762 -301.124874)
		(end 281.399742 -300.649894)
		(width 0.249936)
		(layer "F.Cu")
		(net "P0V8_PEX2")
	)
	(segment
		(start 284.724856 -294.4749)
		(end 284.249876 -293.99992)
		(width 0.249936)
		(layer "F.Cu")
		(net "P0V8_PEX2")
	)
	(segment
		(start 289.94989 -293.99992)
		(end 289.47491 -293.52494)
		(width 0.249936)
		(layer "F.Cu")
		(net "P0V8_PEX2")
	)
	(segment
		(start 285.199836 -294.94988)
		(end 284.724856 -294.4749)
		(width 0.249936)
		(layer "F.Cu")
		(net "P0V8_PEX2")
	)
	(segment
		(start 297.549824 -295.89984)
		(end 298.024804 -296.37482)
		(width 0.249936)
		(layer "F.Cu")
		(net "P0V8_PEX2")
	)
	(via
		(at 292.32479 -293.52494)
		(size 0.4064)
		(drill 0.2032)
		(layers "F.Cu" "B.Cu")
		(net "P0V8_PEX2")
	)
	(via
		(at 346.465652 -302.290734)
		(size 0.508)
		(drill 0.254)
		(layers "F.Cu" "B.Cu")
		(net "P0V8_PEX2")
	)
	(via
		(at 299.924724 -293.52494)
		(size 0.4064)
		(drill 0.2032)
		(layers "F.Cu" "B.Cu")
		(net "P0V8_PEX2")
	)
	(via
		(at 342.198198 -313.290712)
		(size 0.508)
		(drill 0.254)
		(layers "F.Cu" "B.Cu")
		(net "P0V8_PEX2")
	)
	(via
		(at 336.07629 -298.420536)
		(size 0.508)
		(drill 0.254)
		(layers "F.Cu" "B.Cu")
		(net "P0V8_PEX2")
	)
	(via
		(at 339.625432 -302.925734)
		(size 0.508)
		(drill 0.254)
		(layers "F.Cu" "B.Cu")
		(net "P0V8_PEX2")
	)
	(via
		(at 337.118198 -310.242712)
		(size 0.508)
		(drill 0.254)
		(layers "F.Cu" "B.Cu")
		(net "P0V8_PEX2")
	)
	(via
		(at 282.824936 -294.4749)
		(size 0.4064)
		(drill 0.2032)
		(layers "F.Cu" "B.Cu")
		(net "P0V8_PEX2")
	)
	(via
		(at 335.086198 -315.322712)
		(size 0.508)
		(drill 0.254)
		(layers "F.Cu" "B.Cu")
		(net "P0V8_PEX2")
	)
	(via
		(at 338.134198 -314.306712)
		(size 0.508)
		(drill 0.254)
		(layers "F.Cu" "B.Cu")
		(net "P0V8_PEX2")
	)
	(via
		(at 294.22471 -296.37482)
		(size 0.4064)
		(drill 0.2032)
		(layers "F.Cu" "B.Cu")
		(net "P0V8_PEX2")
	)
	(via
		(at 348.420182 -295.245536)
		(size 0.508)
		(drill 0.254)
		(layers "F.Cu" "B.Cu")
		(net "P0V8_PEX2")
	)
	(via
		(at 340.166198 -311.258712)
		(size 0.508)
		(drill 0.254)
		(layers "F.Cu" "B.Cu")
		(net "P0V8_PEX2")
	)
	(via
		(at 341.182198 -313.290712)
		(size 0.508)
		(drill 0.254)
		(layers "F.Cu" "B.Cu")
		(net "P0V8_PEX2")
	)
	(via
		(at 336.07629 -296.515536)
		(size 0.508)
		(drill 0.254)
		(layers "F.Cu" "B.Cu")
		(net "P0V8_PEX2")
	)
	(via
		(at 280.924762 -301.124874)
		(size 0.4064)
		(drill 0.2032)
		(layers "F.Cu" "B.Cu")
		(net "P0V8_PEX2")
	)
	(via
		(at 339.150198 -312.274712)
		(size 0.508)
		(drill 0.254)
		(layers "F.Cu" "B.Cu")
		(net "P0V8_PEX2")
	)
	(via
		(at 340.71687 -297.150536)
		(size 0.508)
		(drill 0.254)
		(layers "F.Cu" "B.Cu")
		(net "P0V8_PEX2")
	)
	(via
		(at 335.086198 -311.258712)
		(size 0.508)
		(drill 0.254)
		(layers "F.Cu" "B.Cu")
		(net "P0V8_PEX2")
	)
	(via
		(at 340.166198 -310.242712)
		(size 0.508)
		(drill 0.254)
		(layers "F.Cu" "B.Cu")
		(net "P0V8_PEX2")
	)
	(via
		(at 342.198198 -315.322712)
		(size 0.508)
		(drill 0.254)
		(layers "F.Cu" "B.Cu")
		(net "P0V8_PEX2")
	)
	(via
		(at 283.774896 -296.37482)
		(size 0.4064)
		(drill 0.2032)
		(layers "F.Cu" "B.Cu")
		(net "P0V8_PEX2")
	)
	(via
		(at 348.420182 -297.785536)
		(size 0.508)
		(drill 0.254)
		(layers "F.Cu" "B.Cu")
		(net "P0V8_PEX2")
	)
	(via
		(at 293.27475 -297.32478)
		(size 0.4064)
		(drill 0.2032)
		(layers "F.Cu" "B.Cu")
		(net "P0V8_PEX2")
	)
	(via
		(at 335.405222 -300.789086)
		(size 0.508)
		(drill 0.254)
		(layers "F.Cu" "B.Cu")
		(net "P0V8_PEX2")
	)
	(via
		(at 342.245442 -300.154086)
		(size 0.508)
		(drill 0.254)
		(layers "F.Cu" "B.Cu")
		(net "P0V8_PEX2")
	)
	(via
		(at 338.237322 -302.290734)
		(size 0.508)
		(drill 0.254)
		(layers "F.Cu" "B.Cu")
		(net "P0V8_PEX2")
	)
	(via
		(at 341.657432 -302.925734)
		(size 0.508)
		(drill 0.254)
		(layers "F.Cu" "B.Cu")
		(net "P0V8_PEX2")
	)
	(via
		(at 335.086198 -310.242712)
		(size 0.508)
		(drill 0.254)
		(layers "F.Cu" "B.Cu")
		(net "P0V8_PEX2")
	)
	(via
		(at 339.150198 -315.322712)
		(size 0.508)
		(drill 0.254)
		(layers "F.Cu" "B.Cu")
		(net "P0V8_PEX2")
	)
	(via
		(at 336.71129 -295.880536)
		(size 0.508)
		(drill 0.254)
		(layers "F.Cu" "B.Cu")
		(net "P0V8_PEX2")
	)
	(via
		(at 340.166198 -315.322712)
		(size 0.508)
		(drill 0.254)
		(layers "F.Cu" "B.Cu")
		(net "P0V8_PEX2")
	)
	(via
		(at 347.785182 -295.880536)
		(size 0.508)
		(drill 0.254)
		(layers "F.Cu" "B.Cu")
		(net "P0V8_PEX2")
	)
	(via
		(at 336.102198 -311.258712)
		(size 0.508)
		(drill 0.254)
		(layers "F.Cu" "B.Cu")
		(net "P0V8_PEX2")
	)
	(via
		(at 296.124884 -293.52494)
		(size 0.4064)
		(drill 0.2032)
		(layers "F.Cu" "B.Cu")
		(net "P0V8_PEX2")
	)
	(via
		(at 336.102198 -312.274712)
		(size 0.508)
		(drill 0.254)
		(layers "F.Cu" "B.Cu")
		(net "P0V8_PEX2")
	)
	(via
		(at 336.07629 -295.245536)
		(size 0.508)
		(drill 0.254)
		(layers "F.Cu" "B.Cu")
		(net "P0V8_PEX2")
	)
	(via
		(at 347.785182 -298.420536)
		(size 0.508)
		(drill 0.254)
		(layers "F.Cu" "B.Cu")
		(net "P0V8_PEX2")
	)
	(via
		(at 341.182198 -312.274712)
		(size 0.508)
		(drill 0.254)
		(layers "F.Cu" "B.Cu")
		(net "P0V8_PEX2")
	)
	(via
		(at 336.102198 -313.290712)
		(size 0.508)
		(drill 0.254)
		(layers "F.Cu" "B.Cu")
		(net "P0V8_PEX2")
	)
	(via
		(at 296.124884 -296.37482)
		(size 0.4064)
		(drill 0.2032)
		(layers "F.Cu" "B.Cu")
		(net "P0V8_PEX2")
	)
	(via
		(at 340.71687 -297.785536)
		(size 0.508)
		(drill 0.254)
		(layers "F.Cu" "B.Cu")
		(net "P0V8_PEX2")
	)
	(via
		(at 340.166198 -316.338712)
		(size 0.508)
		(drill 0.254)
		(layers "F.Cu" "B.Cu")
		(net "P0V8_PEX2")
	)
	(via
		(at 340.71687 -296.515536)
		(size 0.508)
		(drill 0.254)
		(layers "F.Cu" "B.Cu")
		(net "P0V8_PEX2")
	)
	(via
		(at 345.877642 -300.207934)
		(size 0.508)
		(drill 0.254)
		(layers "F.Cu" "B.Cu")
		(net "P0V8_PEX2")
	)
	(via
		(at 286.624776 -297.32478)
		(size 0.4064)
		(drill 0.2032)
		(layers "F.Cu" "B.Cu")
		(net "P0V8_PEX2")
	)
	(via
		(at 280.924762 -294.4749)
		(size 0.4064)
		(drill 0.2032)
		(layers "F.Cu" "B.Cu")
		(net "P0V8_PEX2")
	)
	(via
		(at 333.054198 -313.290712)
		(size 0.508)
		(drill 0.254)
		(layers "F.Cu" "B.Cu")
		(net "P0V8_PEX2")
	)
	(via
		(at 292.32479 -298.27474)
		(size 0.4064)
		(drill 0.2032)
		(layers "F.Cu" "B.Cu")
		(net "P0V8_PEX2")
	)
	(via
		(at 341.182198 -316.338712)
		(size 0.508)
		(drill 0.254)
		(layers "F.Cu" "B.Cu")
		(net "P0V8_PEX2")
	)
	(via
		(at 334.628998 -294.851836)
		(size 0.508)
		(drill 0.254)
		(layers "F.Cu" "B.Cu")
		(net "P0V8_PEX2")
	)
	(via
		(at 341.35187 -297.150536)
		(size 0.508)
		(drill 0.254)
		(layers "F.Cu" "B.Cu")
		(net "P0V8_PEX2")
	)
	(via
		(at 335.086198 -314.306712)
		(size 0.508)
		(drill 0.254)
		(layers "F.Cu" "B.Cu")
		(net "P0V8_PEX2")
	)
	(via
		(at 341.657432 -302.290734)
		(size 0.508)
		(drill 0.254)
		(layers "F.Cu" "B.Cu")
		(net "P0V8_PEX2")
	)
	(via
		(at 341.182198 -315.322712)
		(size 0.508)
		(drill 0.254)
		(layers "F.Cu" "B.Cu")
		(net "P0V8_PEX2")
	)
	(via
		(at 289.47491 -296.37482)
		(size 0.4064)
		(drill 0.2032)
		(layers "F.Cu" "B.Cu")
		(net "P0V8_PEX2")
	)
	(via
		(at 335.405222 -300.154086)
		(size 0.508)
		(drill 0.254)
		(layers "F.Cu" "B.Cu")
		(net "P0V8_PEX2")
	)
	(via
		(at 333.054198 -311.258712)
		(size 0.508)
		(drill 0.254)
		(layers "F.Cu" "B.Cu")
		(net "P0V8_PEX2")
	)
	(via
		(at 335.405222 -301.424086)
		(size 0.508)
		(drill 0.254)
		(layers "F.Cu" "B.Cu")
		(net "P0V8_PEX2")
	)
	(via
		(at 341.35187 -297.785536)
		(size 0.508)
		(drill 0.254)
		(layers "F.Cu" "B.Cu")
		(net "P0V8_PEX2")
	)
	(via
		(at 338.134198 -310.242712)
		(size 0.508)
		(drill 0.254)
		(layers "F.Cu" "B.Cu")
		(net "P0V8_PEX2")
	)
	(via
		(at 285.674816 -298.27474)
		(size 0.4064)
		(drill 0.2032)
		(layers "F.Cu" "B.Cu")
		(net "P0V8_PEX2")
	)
	(via
		(at 284.724856 -297.32478)
		(size 0.4064)
		(drill 0.2032)
		(layers "F.Cu" "B.Cu")
		(net "P0V8_PEX2")
	)
	(via
		(at 345.877642 -301.477934)
		(size 0.508)
		(drill 0.254)
		(layers "F.Cu" "B.Cu")
		(net "P0V8_PEX2")
	)
	(via
		(at 339.037422 -301.477934)
		(size 0.508)
		(drill 0.254)
		(layers "F.Cu" "B.Cu")
		(net "P0V8_PEX2")
	)
	(via
		(at 336.102198 -316.338712)
		(size 0.508)
		(drill 0.254)
		(layers "F.Cu" "B.Cu")
		(net "P0V8_PEX2")
	)
	(via
		(at 337.118198 -314.306712)
		(size 0.508)
		(drill 0.254)
		(layers "F.Cu" "B.Cu")
		(net "P0V8_PEX2")
	)
	(via
		(at 339.150198 -314.306712)
		(size 0.508)
		(drill 0.254)
		(layers "F.Cu" "B.Cu")
		(net "P0V8_PEX2")
	)
	(via
		(at 342.198198 -316.338712)
		(size 0.508)
		(drill 0.254)
		(layers "F.Cu" "B.Cu")
		(net "P0V8_PEX2")
	)
	(via
		(at 345.877642 -300.842934)
		(size 0.508)
		(drill 0.254)
		(layers "F.Cu" "B.Cu")
		(net "P0V8_PEX2")
	)
	(via
		(at 336.102198 -310.242712)
		(size 0.508)
		(drill 0.254)
		(layers "F.Cu" "B.Cu")
		(net "P0V8_PEX2")
	)
	(via
		(at 334.070198 -313.290712)
		(size 0.508)
		(drill 0.254)
		(layers "F.Cu" "B.Cu")
		(net "P0V8_PEX2")
	)
	(via
		(at 341.182198 -310.242712)
		(size 0.508)
		(drill 0.254)
		(layers "F.Cu" "B.Cu")
		(net "P0V8_PEX2")
	)
	(via
		(at 282.824936 -297.32478)
		(size 0.4064)
		(drill 0.2032)
		(layers "F.Cu" "B.Cu")
		(net "P0V8_PEX2")
	)
	(via
		(at 290.42487 -294.4749)
		(size 0.4064)
		(drill 0.2032)
		(layers "F.Cu" "B.Cu")
		(net "P0V8_PEX2")
	)
	(via
		(at 338.134198 -312.274712)
		(size 0.508)
		(drill 0.254)
		(layers "F.Cu" "B.Cu")
		(net "P0V8_PEX2")
	)
	(via
		(at 334.070198 -312.274712)
		(size 0.508)
		(drill 0.254)
		(layers "F.Cu" "B.Cu")
		(net "P0V8_PEX2")
	)
	(via
		(at 337.118198 -316.338712)
		(size 0.508)
		(drill 0.254)
		(layers "F.Cu" "B.Cu")
		(net "P0V8_PEX2")
	)
	(via
		(at 340.166198 -313.290712)
		(size 0.508)
		(drill 0.254)
		(layers "F.Cu" "B.Cu")
		(net "P0V8_PEX2")
	)
	(via
		(at 287.574736 -296.37482)
		(size 0.4064)
		(drill 0.2032)
		(layers "F.Cu" "B.Cu")
		(net "P0V8_PEX2")
	)
	(via
		(at 343.144602 -297.150536)
		(size 0.508)
		(drill 0.254)
		(layers "F.Cu" "B.Cu")
		(net "P0V8_PEX2")
	)
	(via
		(at 342.198198 -314.306712)
		(size 0.508)
		(drill 0.254)
		(layers "F.Cu" "B.Cu")
		(net "P0V8_PEX2")
	)
	(via
		(at 333.054198 -312.274712)
		(size 0.508)
		(drill 0.254)
		(layers "F.Cu" "B.Cu")
		(net "P0V8_PEX2")
	)
	(via
		(at 340.166198 -314.306712)
		(size 0.508)
		(drill 0.254)
		(layers "F.Cu" "B.Cu")
		(net "P0V8_PEX2")
	)
	(via
		(at 338.134198 -311.258712)
		(size 0.508)
		(drill 0.254)
		(layers "F.Cu" "B.Cu")
		(net "P0V8_PEX2")
	)
	(via
		(at 341.437214 -280.999692)
		(size 0.508)
		(drill 0.254)
		(layers "F.Cu" "B.Cu")
		(net "P0V8_PEX2")
	)
	(via
		(at 341.35187 -295.880536)
		(size 0.508)
		(drill 0.254)
		(layers "F.Cu" "B.Cu")
		(net "P0V8_PEX2")
	)
	(via
		(at 280.924762 -292.574726)
		(size 0.4064)
		(drill 0.2032)
		(layers "F.Cu" "B.Cu")
		(net "P0V8_PEX2")
	)
	(via
		(at 289.47491 -293.52494)
		(size 0.4064)
		(drill 0.2032)
		(layers "F.Cu" "B.Cu")
		(net "P0V8_PEX2")
	)
	(via
		(at 341.182198 -314.306712)
		(size 0.508)
		(drill 0.254)
		(layers "F.Cu" "B.Cu")
		(net "P0V8_PEX2")
	)
	(via
		(at 338.134198 -313.290712)
		(size 0.508)
		(drill 0.254)
		(layers "F.Cu" "B.Cu")
		(net "P0V8_PEX2")
	)
	(via
		(at 348.420182 -298.420536)
		(size 0.508)
		(drill 0.254)
		(layers "F.Cu" "B.Cu")
		(net "P0V8_PEX2")
	)
	(via
		(at 339.037422 -300.207934)
		(size 0.508)
		(drill 0.254)
		(layers "F.Cu" "B.Cu")
		(net "P0V8_PEX2")
	)
	(via
		(at 290.42487 -297.32478)
		(size 0.4064)
		(drill 0.2032)
		(layers "F.Cu" "B.Cu")
		(net "P0V8_PEX2")
	)
	(via
		(at 335.086198 -312.274712)
		(size 0.508)
		(drill 0.254)
		(layers "F.Cu" "B.Cu")
		(net "P0V8_PEX2")
	)
	(via
		(at 336.07629 -295.880536)
		(size 0.508)
		(drill 0.254)
		(layers "F.Cu" "B.Cu")
		(net "P0V8_PEX2")
	)
	(via
		(at 336.71129 -297.785536)
		(size 0.508)
		(drill 0.254)
		(layers "F.Cu" "B.Cu")
		(net "P0V8_PEX2")
	)
	(via
		(at 345.877642 -299.572934)
		(size 0.508)
		(drill 0.254)
		(layers "F.Cu" "B.Cu")
		(net "P0V8_PEX2")
	)
	(via
		(at 297.074844 -297.32478)
		(size 0.4064)
		(drill 0.2032)
		(layers "F.Cu" "B.Cu")
		(net "P0V8_PEX2")
	)
	(via
		(at 347.785182 -297.785536)
		(size 0.508)
		(drill 0.254)
		(layers "F.Cu" "B.Cu")
		(net "P0V8_PEX2")
	)
	(via
		(at 287.574736 -298.27474)
		(size 0.4064)
		(drill 0.2032)
		(layers "F.Cu" "B.Cu")
		(net "P0V8_PEX2")
	)
	(via
		(at 336.71129 -296.515536)
		(size 0.508)
		(drill 0.254)
		(layers "F.Cu" "B.Cu")
		(net "P0V8_PEX2")
	)
	(via
		(at 288.524696 -294.4749)
		(size 0.4064)
		(drill 0.2032)
		(layers "F.Cu" "B.Cu")
		(net "P0V8_PEX2")
	)
	(via
		(at 335.086198 -313.290712)
		(size 0.508)
		(drill 0.254)
		(layers "F.Cu" "B.Cu")
		(net "P0V8_PEX2")
	)
	(via
		(at 294.22471 -298.27474)
		(size 0.4064)
		(drill 0.2032)
		(layers "F.Cu" "B.Cu")
		(net "P0V8_PEX2")
	)
	(via
		(at 336.71129 -295.245536)
		(size 0.508)
		(drill 0.254)
		(layers "F.Cu" "B.Cu")
		(net "P0V8_PEX2")
	)
	(via
		(at 343.779602 -297.150536)
		(size 0.508)
		(drill 0.254)
		(layers "F.Cu" "B.Cu")
		(net "P0V8_PEX2")
	)
	(via
		(at 340.71687 -295.880536)
		(size 0.508)
		(drill 0.254)
		(layers "F.Cu" "B.Cu")
		(net "P0V8_PEX2")
	)
	(via
		(at 348.420182 -296.515536)
		(size 0.508)
		(drill 0.254)
		(layers "F.Cu" "B.Cu")
		(net "P0V8_PEX2")
	)
	(via
		(at 340.71687 -295.245536)
		(size 0.508)
		(drill 0.254)
		(layers "F.Cu" "B.Cu")
		(net "P0V8_PEX2")
	)
	(via
		(at 336.07629 -297.785536)
		(size 0.508)
		(drill 0.254)
		(layers "F.Cu" "B.Cu")
		(net "P0V8_PEX2")
	)
	(via
		(at 280.924762 -297.32478)
		(size 0.4064)
		(drill 0.2032)
		(layers "F.Cu" "B.Cu")
		(net "P0V8_PEX2")
	)
	(via
		(at 343.779602 -297.785536)
		(size 0.508)
		(drill 0.254)
		(layers "F.Cu" "B.Cu")
		(net "P0V8_PEX2")
	)
	(via
		(at 339.037422 -300.842934)
		(size 0.508)
		(drill 0.254)
		(layers "F.Cu" "B.Cu")
		(net "P0V8_PEX2")
	)
	(via
		(at 343.144602 -298.420536)
		(size 0.508)
		(drill 0.254)
		(layers "F.Cu" "B.Cu")
		(net "P0V8_PEX2")
	)
	(via
		(at 281.874722 -300.174914)
		(size 0.4064)
		(drill 0.2032)
		(layers "F.Cu" "B.Cu")
		(net "P0V8_PEX2")
	)
	(via
		(at 296.124884 -298.27474)
		(size 0.4064)
		(drill 0.2032)
		(layers "F.Cu" "B.Cu")
		(net "P0V8_PEX2")
	)
	(via
		(at 343.144602 -295.245536)
		(size 0.508)
		(drill 0.254)
		(layers "F.Cu" "B.Cu")
		(net "P0V8_PEX2")
	)
	(via
		(at 280.924762 -299.224954)
		(size 0.4064)
		(drill 0.2032)
		(layers "F.Cu" "B.Cu")
		(net "P0V8_PEX2")
	)
	(via
		(at 284.724856 -294.4749)
		(size 0.4064)
		(drill 0.2032)
		(layers "F.Cu" "B.Cu")
		(net "P0V8_PEX2")
	)
	(via
		(at 338.134198 -316.338712)
		(size 0.508)
		(drill 0.254)
		(layers "F.Cu" "B.Cu")
		(net "P0V8_PEX2")
	)
	(via
		(at 339.150198 -310.242712)
		(size 0.508)
		(drill 0.254)
		(layers "F.Cu" "B.Cu")
		(net "P0V8_PEX2")
	)
	(via
		(at 338.237322 -302.925734)
		(size 0.508)
		(drill 0.254)
		(layers "F.Cu" "B.Cu")
		(net "P0V8_PEX2")
	)
	(via
		(at 286.624776 -294.4749)
		(size 0.4064)
		(drill 0.2032)
		(layers "F.Cu" "B.Cu")
		(net "P0V8_PEX2")
	)
	(via
		(at 334.070198 -315.322712)
		(size 0.508)
		(drill 0.254)
		(layers "F.Cu" "B.Cu")
		(net "P0V8_PEX2")
	)
	(via
		(at 287.574736 -293.52494)
		(size 0.4064)
		(drill 0.2032)
		(layers "F.Cu" "B.Cu")
		(net "P0V8_PEX2")
	)
	(via
		(at 297.074844 -294.4749)
		(size 0.4064)
		(drill 0.2032)
		(layers "F.Cu" "B.Cu")
		(net "P0V8_PEX2")
	)
	(via
		(at 340.71687 -298.420536)
		(size 0.508)
		(drill 0.254)
		(layers "F.Cu" "B.Cu")
		(net "P0V8_PEX2")
	)
	(via
		(at 283.774896 -293.52494)
		(size 0.4064)
		(drill 0.2032)
		(layers "F.Cu" "B.Cu")
		(net "P0V8_PEX2")
	)
	(via
		(at 347.785182 -295.245536)
		(size 0.508)
		(drill 0.254)
		(layers "F.Cu" "B.Cu")
		(net "P0V8_PEX2")
	)
	(via
		(at 342.245442 -300.789086)
		(size 0.508)
		(drill 0.254)
		(layers "F.Cu" "B.Cu")
		(net "P0V8_PEX2")
	)
	(via
		(at 343.144602 -295.880536)
		(size 0.508)
		(drill 0.254)
		(layers "F.Cu" "B.Cu")
		(net "P0V8_PEX2")
	)
	(via
		(at 343.779602 -295.245536)
		(size 0.508)
		(drill 0.254)
		(layers "F.Cu" "B.Cu")
		(net "P0V8_PEX2")
	)
	(via
		(at 339.150198 -311.258712)
		(size 0.508)
		(drill 0.254)
		(layers "F.Cu" "B.Cu")
		(net "P0V8_PEX2")
	)
	(via
		(at 339.150198 -316.338712)
		(size 0.508)
		(drill 0.254)
		(layers "F.Cu" "B.Cu")
		(net "P0V8_PEX2")
	)
	(via
		(at 298.024804 -293.52494)
		(size 0.4064)
		(drill 0.2032)
		(layers "F.Cu" "B.Cu")
		(net "P0V8_PEX2")
	)
	(via
		(at 281.874722 -296.37482)
		(size 0.4064)
		(drill 0.2032)
		(layers "F.Cu" "B.Cu")
		(net "P0V8_PEX2")
	)
	(via
		(at 285.674816 -293.52494)
		(size 0.4064)
		(drill 0.2032)
		(layers "F.Cu" "B.Cu")
		(net "P0V8_PEX2")
	)
	(via
		(at 295.174924 -294.4749)
		(size 0.4064)
		(drill 0.2032)
		(layers "F.Cu" "B.Cu")
		(net "P0V8_PEX2")
	)
	(via
		(at 349.722694 -294.851836)
		(size 0.508)
		(drill 0.254)
		(layers "F.Cu" "B.Cu")
		(net "P0V8_PEX2")
	)
	(via
		(at 337.118198 -312.274712)
		(size 0.508)
		(drill 0.254)
		(layers "F.Cu" "B.Cu")
		(net "P0V8_PEX2")
	)
	(via
		(at 336.102198 -315.322712)
		(size 0.508)
		(drill 0.254)
		(layers "F.Cu" "B.Cu")
		(net "P0V8_PEX2")
	)
	(via
		(at 343.191846 -294.1828)
		(size 0.508)
		(drill 0.254)
		(layers "F.Cu" "B.Cu")
		(net "P0V8_PEX2")
	)
	(via
		(at 333.054198 -310.242712)
		(size 0.508)
		(drill 0.254)
		(layers "F.Cu" "B.Cu")
		(net "P0V8_PEX2")
	)
	(via
		(at 341.35187 -295.245536)
		(size 0.508)
		(drill 0.254)
		(layers "F.Cu" "B.Cu")
		(net "P0V8_PEX2")
	)
	(via
		(at 335.405222 -299.519086)
		(size 0.508)
		(drill 0.254)
		(layers "F.Cu" "B.Cu")
		(net "P0V8_PEX2")
	)
	(via
		(at 346.465652 -302.925734)
		(size 0.508)
		(drill 0.254)
		(layers "F.Cu" "B.Cu")
		(net "P0V8_PEX2")
	)
	(via
		(at 342.198198 -312.274712)
		(size 0.508)
		(drill 0.254)
		(layers "F.Cu" "B.Cu")
		(net "P0V8_PEX2")
	)
	(via
		(at 283.774896 -298.27474)
		(size 0.4064)
		(drill 0.2032)
		(layers "F.Cu" "B.Cu")
		(net "P0V8_PEX2")
	)
	(via
		(at 342.245442 -299.519086)
		(size 0.508)
		(drill 0.254)
		(layers "F.Cu" "B.Cu")
		(net "P0V8_PEX2")
	)
	(via
		(at 343.144602 -297.785536)
		(size 0.508)
		(drill 0.254)
		(layers "F.Cu" "B.Cu")
		(net "P0V8_PEX2")
	)
	(via
		(at 280.924762 -290.674806)
		(size 0.4064)
		(drill 0.2032)
		(layers "F.Cu" "B.Cu")
		(net "P0V8_PEX2")
	)
	(via
		(at 341.35187 -296.515536)
		(size 0.508)
		(drill 0.254)
		(layers "F.Cu" "B.Cu")
		(net "P0V8_PEX2")
	)
	(via
		(at 334.070198 -310.242712)
		(size 0.508)
		(drill 0.254)
		(layers "F.Cu" "B.Cu")
		(net "P0V8_PEX2")
	)
	(via
		(at 281.874722 -291.624766)
		(size 0.4064)
		(drill 0.2032)
		(layers "F.Cu" "B.Cu")
		(net "P0V8_PEX2")
	)
	(via
		(at 281.874722 -293.52494)
		(size 0.4064)
		(drill 0.2032)
		(layers "F.Cu" "B.Cu")
		(net "P0V8_PEX2")
	)
	(via
		(at 292.32479 -296.37482)
		(size 0.4064)
		(drill 0.2032)
		(layers "F.Cu" "B.Cu")
		(net "P0V8_PEX2")
	)
	(via
		(at 339.150198 -313.290712)
		(size 0.508)
		(drill 0.254)
		(layers "F.Cu" "B.Cu")
		(net "P0V8_PEX2")
	)
	(via
		(at 338.134198 -315.322712)
		(size 0.508)
		(drill 0.254)
		(layers "F.Cu" "B.Cu")
		(net "P0V8_PEX2")
	)
	(via
		(at 285.674816 -296.37482)
		(size 0.4064)
		(drill 0.2032)
		(layers "F.Cu" "B.Cu")
		(net "P0V8_PEX2")
	)
	(via
		(at 298.024804 -298.27474)
		(size 0.4064)
		(drill 0.2032)
		(layers "F.Cu" "B.Cu")
		(net "P0V8_PEX2")
	)
	(via
		(at 294.22471 -293.52494)
		(size 0.4064)
		(drill 0.2032)
		(layers "F.Cu" "B.Cu")
		(net "P0V8_PEX2")
	)
	(via
		(at 293.27475 -294.4749)
		(size 0.4064)
		(drill 0.2032)
		(layers "F.Cu" "B.Cu")
		(net "P0V8_PEX2")
	)
	(via
		(at 337.118198 -313.290712)
		(size 0.508)
		(drill 0.254)
		(layers "F.Cu" "B.Cu")
		(net "P0V8_PEX2")
	)
	(via
		(at 343.779602 -296.515536)
		(size 0.508)
		(drill 0.254)
		(layers "F.Cu" "B.Cu")
		(net "P0V8_PEX2")
	)
	(via
		(at 336.71129 -298.420536)
		(size 0.508)
		(drill 0.254)
		(layers "F.Cu" "B.Cu")
		(net "P0V8_PEX2")
	)
	(via
		(at 348.420182 -295.880536)
		(size 0.508)
		(drill 0.254)
		(layers "F.Cu" "B.Cu")
		(net "P0V8_PEX2")
	)
	(via
		(at 334.817212 -302.290734)
		(size 0.508)
		(drill 0.254)
		(layers "F.Cu" "B.Cu")
		(net "P0V8_PEX2")
	)
	(via
		(at 340.166198 -312.274712)
		(size 0.508)
		(drill 0.254)
		(layers "F.Cu" "B.Cu")
		(net "P0V8_PEX2")
	)
	(via
		(at 334.070198 -314.306712)
		(size 0.508)
		(drill 0.254)
		(layers "F.Cu" "B.Cu")
		(net "P0V8_PEX2")
	)
	(via
		(at 342.198198 -310.242712)
		(size 0.508)
		(drill 0.254)
		(layers "F.Cu" "B.Cu")
		(net "P0V8_PEX2")
	)
	(via
		(at 334.070198 -311.258712)
		(size 0.508)
		(drill 0.254)
		(layers "F.Cu" "B.Cu")
		(net "P0V8_PEX2")
	)
	(via
		(at 336.07629 -297.150536)
		(size 0.508)
		(drill 0.254)
		(layers "F.Cu" "B.Cu")
		(net "P0V8_PEX2")
	)
	(via
		(at 348.420182 -297.150536)
		(size 0.508)
		(drill 0.254)
		(layers "F.Cu" "B.Cu")
		(net "P0V8_PEX2")
	)
	(via
		(at 339.625432 -302.290734)
		(size 0.508)
		(drill 0.254)
		(layers "F.Cu" "B.Cu")
		(net "P0V8_PEX2")
	)
	(via
		(at 298.024804 -296.37482)
		(size 0.4064)
		(drill 0.2032)
		(layers "F.Cu" "B.Cu")
		(net "P0V8_PEX2")
	)
	(via
		(at 337.118198 -311.258712)
		(size 0.508)
		(drill 0.254)
		(layers "F.Cu" "B.Cu")
		(net "P0V8_PEX2")
	)
	(via
		(at 341.35187 -298.420536)
		(size 0.508)
		(drill 0.254)
		(layers "F.Cu" "B.Cu")
		(net "P0V8_PEX2")
	)
	(via
		(at 343.779602 -295.880536)
		(size 0.508)
		(drill 0.254)
		(layers "F.Cu" "B.Cu")
		(net "P0V8_PEX2")
	)
	(via
		(at 342.245442 -301.424086)
		(size 0.508)
		(drill 0.254)
		(layers "F.Cu" "B.Cu")
		(net "P0V8_PEX2")
	)
	(via
		(at 299.924724 -298.27474)
		(size 0.4064)
		(drill 0.2032)
		(layers "F.Cu" "B.Cu")
		(net "P0V8_PEX2")
	)
	(via
		(at 289.47491 -298.27474)
		(size 0.4064)
		(drill 0.2032)
		(layers "F.Cu" "B.Cu")
		(net "P0V8_PEX2")
	)
	(via
		(at 295.174924 -297.32478)
		(size 0.4064)
		(drill 0.2032)
		(layers "F.Cu" "B.Cu")
		(net "P0V8_PEX2")
	)
	(via
		(at 347.785182 -297.150536)
		(size 0.508)
		(drill 0.254)
		(layers "F.Cu" "B.Cu")
		(net "P0V8_PEX2")
	)
	(via
		(at 349.780098 -281.01671)
		(size 0.508)
		(drill 0.254)
		(layers "F.Cu" "B.Cu")
		(net "P0V8_PEX2")
	)
	(via
		(at 343.779602 -298.420536)
		(size 0.508)
		(drill 0.254)
		(layers "F.Cu" "B.Cu")
		(net "P0V8_PEX2")
	)
	(via
		(at 281.874722 -298.27474)
		(size 0.4064)
		(drill 0.2032)
		(layers "F.Cu" "B.Cu")
		(net "P0V8_PEX2")
	)
	(via
		(at 343.144602 -296.515536)
		(size 0.508)
		(drill 0.254)
		(layers "F.Cu" "B.Cu")
		(net "P0V8_PEX2")
	)
	(via
		(at 336.71129 -297.150536)
		(size 0.508)
		(drill 0.254)
		(layers "F.Cu" "B.Cu")
		(net "P0V8_PEX2")
	)
	(via
		(at 336.102198 -314.306712)
		(size 0.508)
		(drill 0.254)
		(layers "F.Cu" "B.Cu")
		(net "P0V8_PEX2")
	)
	(via
		(at 339.037422 -299.572934)
		(size 0.508)
		(drill 0.254)
		(layers "F.Cu" "B.Cu")
		(net "P0V8_PEX2")
	)
	(via
		(at 337.118198 -315.322712)
		(size 0.508)
		(drill 0.254)
		(layers "F.Cu" "B.Cu")
		(net "P0V8_PEX2")
	)
	(via
		(at 347.785182 -296.515536)
		(size 0.508)
		(drill 0.254)
		(layers "F.Cu" "B.Cu")
		(net "P0V8_PEX2")
	)
	(via
		(at 334.817212 -302.925734)
		(size 0.508)
		(drill 0.254)
		(layers "F.Cu" "B.Cu")
		(net "P0V8_PEX2")
	)
	(via
		(at 288.524696 -297.32478)
		(size 0.4064)
		(drill 0.2032)
		(layers "F.Cu" "B.Cu")
		(net "P0V8_PEX2")
	)
	(segment
		(start 300.133004 -298.27474)
		(end 299.924724 -298.27474)
		(width 0.3048)
		(layer "B.Cu")
		(net "P0V8_PEX2")
	)
	(segment
		(start 300.133004 -293.52494)
		(end 299.924724 -293.52494)
		(width 0.3048)
		(layer "B.Cu")
		(net "P0V8_PEX2")
	)
	(segment
		(start 341.619586 -281.182064)
		(end 341.437214 -280.999692)
		(width 0.254)
		(layer "B.Cu")
		(net "P0V8_PEX2")
	)
	(segment
		(start 341.619586 -281.640534)
		(end 341.619586 -281.182064)
		(width 0.254)
		(layer "B.Cu")
		(net "P0V8_PEX2")
	)
	(segment
		(start 349.780098 -281.01671)
		(end 349.780098 -281.640534)
		(width 0.254)
		(layer "B.Cu")
		(net "P0V8_PEX2")
	)
	(segment
		(start 341.619586 -282.414218)
		(end 341.22106 -282.812744)
		(width 0.254)
		(layer "In5.Cu")
		(net "P0V8_PEX2")
	)
	(segment
		(start 341.22106 -282.812744)
		(end 341.22106 -284.28442)
		(width 0.254)
		(layer "In5.Cu")
		(net "P0V8_PEX2")
	)
	(segment
		(start 340.71687 -292.836854)
		(end 340.71687 -295.245536)
		(width 0.254)
		(layer "In5.Cu")
		(net "P0V8_PEX2")
	)
	(segment
		(start 342.816942 -285.880302)
		(end 342.816942 -286.761174)
		(width 0.254)
		(layer "In5.Cu")
		(net "P0V8_PEX2")
	)
	(segment
		(start 349.780098 -282.431236)
		(end 349.780098 -281.01671)
		(width 0.254)
		(layer "In5.Cu")
		(net "P0V8_PEX2")
	)
	(segment
		(start 341.22106 -284.28442)
		(end 342.816942 -285.880302)
		(width 0.254)
		(layer "In5.Cu")
		(net "P0V8_PEX2")
	)
	(segment
		(start 342.112854 -291.44087)
		(end 340.71687 -292.836854)
		(width 0.254)
		(layer "In5.Cu")
		(net "P0V8_PEX2")
	)
	(segment
		(start 342.112854 -287.465262)
		(end 342.112854 -291.44087)
		(width 0.254)
		(layer "In5.Cu")
		(net "P0V8_PEX2")
	)
	(segment
		(start 348.877382 -294.788336)
		(end 348.877382 -286.182562)
		(width 0.254)
		(layer "In5.Cu")
		(net "P0V8_PEX2")
	)
	(segment
		(start 350.589342 -283.24048)
		(end 349.780098 -282.431236)
		(width 0.254)
		(layer "In5.Cu")
		(net "P0V8_PEX2")
	)
	(segment
		(start 341.437214 -280.999692)
		(end 341.619586 -281.182064)
		(width 0.254)
		(layer "In5.Cu")
		(net "P0V8_PEX2")
	)
	(segment
		(start 342.816942 -286.761174)
		(end 342.112854 -287.465262)
		(width 0.254)
		(layer "In5.Cu")
		(net "P0V8_PEX2")
	)
	(segment
		(start 348.877382 -286.182562)
		(end 350.589342 -284.470602)
		(width 0.254)
		(layer "In5.Cu")
		(net "P0V8_PEX2")
	)
	(segment
		(start 350.589342 -284.470602)
		(end 350.589342 -283.24048)
		(width 0.254)
		(layer "In5.Cu")
		(net "P0V8_PEX2")
	)
	(segment
		(start 341.619586 -281.182064)
		(end 341.619586 -282.414218)
		(width 0.254)
		(layer "In5.Cu")
		(net "P0V8_PEX2")
	)
	(segment
		(start 348.420182 -295.245536)
		(end 348.877382 -294.788336)
		(width 0.254)
		(layer "In5.Cu")
		(net "P0V8_PEX2")
	)
	(segment
		(start 305.149758 -301.599854)
		(end 304.674778 -302.074834)
		(width 0.127)
		(layer "F.Cu")
		(net "VSENSE_P0V8_PEX2_SKT_VRTN")
	)
	(via
		(at 330.649326 -328.969116)
		(size 0.6604)
		(drill 0.3302)
		(layers "F.Cu" "B.Cu")
		(net "VSENSE_P0V8_PEX2_SKT_VRTN")
	)
	(via
		(at 304.674778 -302.074834)
		(size 0.4064)
		(drill 0.2032)
		(layers "F.Cu" "B.Cu")
		(net "VSENSE_P0V8_PEX2_SKT_VRTN")
	)
	(segment
		(start 303.143158 -307.01869)
		(end 302.96866 -307.193188)
		(width 0.09906)
		(layer "B.Cu")
		(net "VSENSE_P0V8_PEX2_SKT_VRTN")
	)
	(segment
		(start 304.674778 -302.074834)
		(end 304.944018 -302.074834)
		(width 0.09906)
		(layer "B.Cu")
		(net "VSENSE_P0V8_PEX2_SKT_VRTN")
	)
	(segment
		(start 330.909168 -328.709274)
		(end 332.399386 -328.709274)
		(width 0.254)
		(layer "B.Cu")
		(net "VSENSE_P0V8_PEX2_SKT_VRTN")
	)
	(segment
		(start 291.18433 -320.294)
		(end 291.18433 -321.124072)
		(width 0.254)
		(layer "B.Cu")
		(net "VSENSE_P0V8_PEX2_SKT_VRTN")
	)
	(segment
		(start 291.26815 -307.66385)
		(end 291.26815 -320.171572)
		(width 0.09906)
		(layer "B.Cu")
		(net "VSENSE_P0V8_PEX2_SKT_VRTN")
	)
	(segment
		(start 291.26815 -320.171572)
		(end 291.18433 -320.255392)
		(width 0.09906)
		(layer "B.Cu")
		(net "VSENSE_P0V8_PEX2_SKT_VRTN")
	)
	(segment
		(start 305.043078 -302.173894)
		(end 305.043078 -302.314102)
		(width 0.09906)
		(layer "B.Cu")
		(net "VSENSE_P0V8_PEX2_SKT_VRTN")
	)
	(segment
		(start 302.96866 -307.193188)
		(end 291.738812 -307.193188)
		(width 0.09906)
		(layer "B.Cu")
		(net "VSENSE_P0V8_PEX2_SKT_VRTN")
	)
	(segment
		(start 303.426114 -302.443134)
		(end 303.143158 -302.72609)
		(width 0.09906)
		(layer "B.Cu")
		(net "VSENSE_P0V8_PEX2_SKT_VRTN")
	)
	(segment
		(start 291.18433 -320.255392)
		(end 291.18433 -320.294)
		(width 0.09906)
		(layer "B.Cu")
		(net "VSENSE_P0V8_PEX2_SKT_VRTN")
	)
	(segment
		(start 304.914046 -302.443134)
		(end 303.426114 -302.443134)
		(width 0.09906)
		(layer "B.Cu")
		(net "VSENSE_P0V8_PEX2_SKT_VRTN")
	)
	(segment
		(start 303.143158 -302.72609)
		(end 303.143158 -307.01869)
		(width 0.09906)
		(layer "B.Cu")
		(net "VSENSE_P0V8_PEX2_SKT_VRTN")
	)
	(segment
		(start 305.043078 -302.314102)
		(end 304.914046 -302.443134)
		(width 0.09906)
		(layer "B.Cu")
		(net "VSENSE_P0V8_PEX2_SKT_VRTN")
	)
	(segment
		(start 291.18433 -321.124072)
		(end 293.300404 -323.240146)
		(width 0.254)
		(layer "B.Cu")
		(net "VSENSE_P0V8_PEX2_SKT_VRTN")
	)
	(segment
		(start 306.50434 -328.709274)
		(end 330.389484 -328.709274)
		(width 0.254)
		(layer "B.Cu")
		(net "VSENSE_P0V8_PEX2_SKT_VRTN")
	)
	(segment
		(start 293.300404 -323.240146)
		(end 306.50434 -328.709274)
		(width 0.254)
		(layer "B.Cu")
		(net "VSENSE_P0V8_PEX2_SKT_VRTN")
	)
	(segment
		(start 330.389484 -328.709274)
		(end 330.649326 -328.969116)
		(width 0.254)
		(layer "B.Cu")
		(net "VSENSE_P0V8_PEX2_SKT_VRTN")
	)
	(segment
		(start 304.944018 -302.074834)
		(end 305.043078 -302.173894)
		(width 0.09906)
		(layer "B.Cu")
		(net "VSENSE_P0V8_PEX2_SKT_VRTN")
	)
	(segment
		(start 332.399386 -328.709274)
		(end 332.673706 -329.008994)
		(width 0.254)
		(layer "B.Cu")
		(net "VSENSE_P0V8_PEX2_SKT_VRTN")
	)
	(segment
		(start 330.649326 -328.969116)
		(end 330.909168 -328.709274)
		(width 0.254)
		(layer "B.Cu")
		(net "VSENSE_P0V8_PEX2_SKT_VRTN")
	)
	(segment
		(start 291.738812 -307.193188)
		(end 291.26815 -307.66385)
		(width 0.09906)
		(layer "B.Cu")
		(net "VSENSE_P0V8_PEX2_SKT_VRTN")
	)
	(segment
		(start 361.49026 -262.259572)
		(end 361.307634 -262.442198)
		(width 0.13208)
		(layer "F.Cu")
		(net "FM_P0V8_PEX3_EN_R")
	)
	(segment
		(start 358.240838 -260.882638)
		(end 359.172764 -261.814564)
		(width 0.13208)
		(layer "F.Cu")
		(net "FM_P0V8_PEX3_EN_R")
	)
	(segment
		(start 359.45826 -262.315198)
		(end 359.45826 -261.814564)
		(width 0.13208)
		(layer "F.Cu")
		(net "FM_P0V8_PEX3_EN_R")
	)
	(segment
		(start 359.58526 -262.442198)
		(end 359.45826 -262.315198)
		(width 0.13208)
		(layer "F.Cu")
		(net "FM_P0V8_PEX3_EN_R")
	)
	(segment
		(start 361.307634 -262.442198)
		(end 359.58526 -262.442198)
		(width 0.13208)
		(layer "F.Cu")
		(net "FM_P0V8_PEX3_EN_R")
	)
	(segment
		(start 355.375972 -260.19506)
		(end 357.55326 -260.19506)
		(width 0.13208)
		(layer "F.Cu")
		(net "FM_P0V8_PEX3_EN_R")
	)
	(segment
		(start 359.172764 -261.814564)
		(end 359.45826 -261.814564)
		(width 0.13208)
		(layer "F.Cu")
		(net "FM_P0V8_PEX3_EN_R")
	)
	(segment
		(start 357.55326 -260.19506)
		(end 358.240838 -260.882638)
		(width 0.13208)
		(layer "F.Cu")
		(net "FM_P0V8_PEX3_EN_R")
	)
	(segment
		(start 361.49026 -261.814564)
		(end 361.49026 -262.259572)
		(width 0.13208)
		(layer "F.Cu")
		(net "FM_P0V8_PEX3_EN_R")
	)
	(via
		(at 358.240838 -260.882638)
		(size 0.762)
		(drill 0.381)
		(layers "F.Cu" "B.Cu")
		(net "FM_P0V8_PEX3_EN_R")
	)
	(segment
		(start 68.199762 -299.699934)
		(end 68.674742 -300.174914)
		(width 0.249936)
		(layer "F.Cu")
		(net "P1V8_VDDA_PEX0")
	)
	(segment
		(start 45.39996 -298.74972)
		(end 44.92498 -298.27474)
		(width 0.249936)
		(layer "F.Cu")
		(net "P1V8_VDDA_PEX0")
	)
	(segment
		(start 49.1998 -302.549814)
		(end 48.72482 -303.024794)
		(width 0.249936)
		(layer "F.Cu")
		(net "P1V8_VDDA_PEX0")
	)
	(segment
		(start 71.049896 -299.699934)
		(end 71.524876 -300.174914)
		(width 0.249936)
		(layer "F.Cu")
		(net "P1V8_VDDA_PEX0")
	)
	(segment
		(start 69.149976 -287.349946)
		(end 69.624956 -286.874966)
		(width 0.249936)
		(layer "F.Cu")
		(net "P1V8_VDDA_PEX0")
	)
	(segment
		(start 69.149976 -304.449734)
		(end 69.624956 -304.924714)
		(width 0.249936)
		(layer "F.Cu")
		(net "P1V8_VDDA_PEX0")
	)
	(segment
		(start 44.92498 -299.224954)
		(end 45.39996 -298.74972)
		(width 0.249936)
		(layer "F.Cu")
		(net "P1V8_VDDA_PEX0")
	)
	(segment
		(start 49.1998 -289.249866)
		(end 48.72482 -288.774886)
		(width 0.249936)
		(layer "F.Cu")
		(net "P1V8_VDDA_PEX0")
	)
	(segment
		(start 45.39996 -299.699934)
		(end 44.92498 -300.174914)
		(width 0.249936)
		(layer "F.Cu")
		(net "P1V8_VDDA_PEX0")
	)
	(segment
		(start 44.92498 -298.27474)
		(end 45.39996 -297.79976)
		(width 0.249936)
		(layer "F.Cu")
		(net "P1V8_VDDA_PEX0")
	)
	(segment
		(start 45.39996 -299.699934)
		(end 44.92498 -299.224954)
		(width 0.249936)
		(layer "F.Cu")
		(net "P1V8_VDDA_PEX0")
	)
	(via
		(at 68.674742 -300.174914)
		(size 0.4064)
		(drill 0.2032)
		(layers "F.Cu" "B.Cu")
		(net "P1V8_VDDA_PEX0")
	)
	(via
		(at 42.922444 -297.203368)
		(size 0.6604)
		(drill 0.3302)
		(layers "F.Cu" "B.Cu")
		(net "P1V8_VDDA_PEX0")
	)
	(via
		(at 69.624956 -286.874966)
		(size 0.4064)
		(drill 0.2032)
		(layers "F.Cu" "B.Cu")
		(net "P1V8_VDDA_PEX0")
	)
	(via
		(at 71.524876 -300.174914)
		(size 0.4064)
		(drill 0.2032)
		(layers "F.Cu" "B.Cu")
		(net "P1V8_VDDA_PEX0")
	)
	(via
		(at 44.92498 -300.174914)
		(size 0.4064)
		(drill 0.2032)
		(layers "F.Cu" "B.Cu")
		(net "P1V8_VDDA_PEX0")
	)
	(via
		(at 46.349412 -303.508918)
		(size 0.6604)
		(drill 0.3302)
		(layers "F.Cu" "B.Cu")
		(net "P1V8_VDDA_PEX0")
	)
	(via
		(at 44.92498 -299.224954)
		(size 0.4064)
		(drill 0.2032)
		(layers "F.Cu" "B.Cu")
		(net "P1V8_VDDA_PEX0")
	)
	(via
		(at 26.916634 -260.53923)
		(size 0.508)
		(drill 0.254)
		(layers "F.Cu" "B.Cu")
		(net "P1V8_VDDA_PEX0")
	)
	(via
		(at 48.72482 -303.024794)
		(size 0.4064)
		(drill 0.2032)
		(layers "F.Cu" "B.Cu")
		(net "P1V8_VDDA_PEX0")
	)
	(via
		(at 69.624956 -304.924714)
		(size 0.4064)
		(drill 0.2032)
		(layers "F.Cu" "B.Cu")
		(net "P1V8_VDDA_PEX0")
	)
	(via
		(at 48.72482 -288.774886)
		(size 0.4064)
		(drill 0.2032)
		(layers "F.Cu" "B.Cu")
		(net "P1V8_VDDA_PEX0")
	)
	(via
		(at 44.92498 -298.27474)
		(size 0.4064)
		(drill 0.2032)
		(layers "F.Cu" "B.Cu")
		(net "P1V8_VDDA_PEX0")
	)
	(via
		(at 72.6694 -286.5374)
		(size 0.6604)
		(drill 0.3302)
		(layers "F.Cu" "B.Cu")
		(net "P1V8_VDDA_PEX0")
	)
	(segment
		(start 48.9331 -288.774886)
		(end 48.72482 -288.774886)
		(width 0.3048)
		(layer "B.Cu")
		(net "P1V8_VDDA_PEX0")
	)
	(segment
		(start 69.624956 -305.341528)
		(end 69.624956 -304.924714)
		(width 0.3048)
		(layer "B.Cu")
		(net "P1V8_VDDA_PEX0")
	)
	(segment
		(start 68.883276 -300.174914)
		(end 68.674742 -300.174914)
		(width 0.3048)
		(layer "B.Cu")
		(net "P1V8_VDDA_PEX0")
	)
	(segment
		(start 48.30826 -303.15154)
		(end 47.950882 -303.508918)
		(width 0.13208)
		(layer "B.Cu")
		(net "P1V8_VDDA_PEX0")
	)
	(segment
		(start 43.301412 -296.8244)
		(end 42.922444 -297.203368)
		(width 0.13208)
		(layer "B.Cu")
		(net "P1V8_VDDA_PEX0")
	)
	(segment
		(start 69.624956 -304.508154)
		(end 69.624956 -304.924714)
		(width 0.3048)
		(layer "B.Cu")
		(net "P1V8_VDDA_PEX0")
	)
	(segment
		(start 71.941436 -300.174914)
		(end 71.524876 -300.174914)
		(width 0.3048)
		(layer "B.Cu")
		(net "P1V8_VDDA_PEX0")
	)
	(segment
		(start 44.716446 -297.751246)
		(end 44.5262 -297.561)
		(width 0.13208)
		(layer "B.Cu")
		(net "P1V8_VDDA_PEX0")
	)
	(segment
		(start 47.950882 -303.508918)
		(end 46.349412 -303.508918)
		(width 0.13208)
		(layer "B.Cu")
		(net "P1V8_VDDA_PEX0")
	)
	(segment
		(start 44.2722 -296.8244)
		(end 43.301412 -296.8244)
		(width 0.13208)
		(layer "B.Cu")
		(net "P1V8_VDDA_PEX0")
	)
	(segment
		(start 71.108316 -300.174914)
		(end 71.524876 -300.174914)
		(width 0.3048)
		(layer "B.Cu")
		(net "P1V8_VDDA_PEX0")
	)
	(segment
		(start 44.5262 -297.561)
		(end 44.5262 -297.0784)
		(width 0.13208)
		(layer "B.Cu")
		(net "P1V8_VDDA_PEX0")
	)
	(segment
		(start 44.5262 -297.0784)
		(end 44.2722 -296.8244)
		(width 0.13208)
		(layer "B.Cu")
		(net "P1V8_VDDA_PEX0")
	)
	(segment
		(start 44.716446 -298.27474)
		(end 44.716446 -297.751246)
		(width 0.13208)
		(layer "B.Cu")
		(net "P1V8_VDDA_PEX0")
	)
	(segment
		(start 48.30826 -303.024794)
		(end 48.30826 -303.15154)
		(width 0.13208)
		(layer "B.Cu")
		(net "P1V8_VDDA_PEX0")
	)
	(segment
		(start 44.938696 -268.549882)
		(end 44.938696 -265.153648)
		(width 0.381)
		(layer "In5.Cu")
		(net "P1V8_VDDA_PEX0")
	)
	(segment
		(start 38.439852 -271.599406)
		(end 42.617644 -271.599406)
		(width 0.381)
		(layer "In5.Cu")
		(net "P1V8_VDDA_PEX0")
	)
	(segment
		(start 44.938696 -265.153648)
		(end 40.997886 -261.212838)
		(width 0.381)
		(layer "In5.Cu")
		(net "P1V8_VDDA_PEX0")
	)
	(segment
		(start 40.997886 -261.212838)
		(end 32.025844 -261.212838)
		(width 0.381)
		(layer "In5.Cu")
		(net "P1V8_VDDA_PEX0")
	)
	(segment
		(start 27.282902 -260.53923)
		(end 26.916634 -260.53923)
		(width 0.381)
		(layer "In5.Cu")
		(net "P1V8_VDDA_PEX0")
	)
	(segment
		(start 32.025844 -261.212838)
		(end 31.633922 -260.820916)
		(width 0.381)
		(layer "In5.Cu")
		(net "P1V8_VDDA_PEX0")
	)
	(segment
		(start 43.455082 -270.761968)
		(end 43.455082 -270.033496)
		(width 0.381)
		(layer "In5.Cu")
		(net "P1V8_VDDA_PEX0")
	)
	(segment
		(start 43.455082 -270.033496)
		(end 44.938696 -268.549882)
		(width 0.381)
		(layer "In5.Cu")
		(net "P1V8_VDDA_PEX0")
	)
	(segment
		(start 42.617644 -271.599406)
		(end 43.455082 -270.761968)
		(width 0.381)
		(layer "In5.Cu")
		(net "P1V8_VDDA_PEX0")
	)
	(segment
		(start 31.633922 -260.820916)
		(end 27.564588 -260.820916)
		(width 0.381)
		(layer "In5.Cu")
		(net "P1V8_VDDA_PEX0")
	)
	(segment
		(start 27.564588 -260.820916)
		(end 27.282902 -260.53923)
		(width 0.381)
		(layer "In5.Cu")
		(net "P1V8_VDDA_PEX0")
	)
	(segment
		(start 354.375974 -255.5113)
		(end 354.978208 -254.909066)
		(width 0.13208)
		(layer "F.Cu")
		(net "SMB_VR_P0V8_PEX2_SDA")
	)
	(segment
		(start 356.17531 -253.459488)
		(end 355.262434 -254.372364)
		(width 0.13208)
		(layer "F.Cu")
		(net "SMB_VR_P0V8_PEX2_SDA")
	)
	(segment
		(start 354.978208 -254.909066)
		(end 354.978208 -254.65659)
		(width 0.13208)
		(layer "F.Cu")
		(net "SMB_VR_P0V8_PEX2_SDA")
	)
	(segment
		(start 354.375974 -255.994916)
		(end 354.375974 -255.5113)
		(width 0.13208)
		(layer "F.Cu")
		(net "SMB_VR_P0V8_PEX2_SDA")
	)
	(segment
		(start 354.978208 -254.65659)
		(end 355.262434 -254.372364)
		(width 0.13208)
		(layer "F.Cu")
		(net "SMB_VR_P0V8_PEX2_SDA")
	)
	(segment
		(start 356.17531 -252.816614)
		(end 356.17531 -253.459488)
		(width 0.13208)
		(layer "F.Cu")
		(net "SMB_VR_P0V8_PEX2_SDA")
	)
	(via
		(at 355.262434 -254.372364)
		(size 0.762)
		(drill 0.381)
		(layers "F.Cu" "B.Cu")
		(net "SMB_VR_P0V8_PEX2_SDA")
	)
	(segment
		(start 118.783608 -261.205218)
		(end 118.975632 -261.013194)
		(width 0.2032)
		(layer "F.Cu")
		(net "P0V8_PEX1_ISEN1")
	)
	(segment
		(start 124.607828 -281.217116)
		(end 124.607828 -281.151838)
		(width 0.2286)
		(layer "F.Cu")
		(net "P0V8_PEX1_ISEN1")
	)
	(segment
		(start 118.783608 -262.778748)
		(end 118.783608 -261.205218)
		(width 0.2032)
		(layer "F.Cu")
		(net "P0V8_PEX1_ISEN1")
	)
	(segment
		(start 124.170694 -281.65425)
		(end 124.607828 -281.217116)
		(width 0.2286)
		(layer "F.Cu")
		(net "P0V8_PEX1_ISEN1")
	)
	(segment
		(start 124.170694 -281.999182)
		(end 124.170694 -281.65425)
		(width 0.2286)
		(layer "F.Cu")
		(net "P0V8_PEX1_ISEN1")
	)
	(segment
		(start 118.975632 -261.013194)
		(end 118.975632 -260.795008)
		(width 0.2032)
		(layer "F.Cu")
		(net "P0V8_PEX1_ISEN1")
	)
	(segment
		(start 119.82577 -263.82091)
		(end 118.783608 -262.778748)
		(width 0.2032)
		(layer "F.Cu")
		(net "P0V8_PEX1_ISEN1")
	)
	(via
		(at 124.607828 -281.151838)
		(size 0.508)
		(drill 0.254)
		(layers "F.Cu" "B.Cu")
		(net "P0V8_PEX1_ISEN1")
	)
	(via
		(at 119.82577 -263.82091)
		(size 0.508)
		(drill 0.254)
		(layers "F.Cu" "B.Cu")
		(net "P0V8_PEX1_ISEN1")
	)
	(segment
		(start 123.436634 -276.492208)
		(end 123.436634 -266.764516)
		(width 0.254)
		(layer "In11.Cu")
		(net "P0V8_PEX1_ISEN1")
	)
	(segment
		(start 121.94032 -264.471912)
		(end 121.289318 -263.82091)
		(width 0.254)
		(layer "In11.Cu")
		(net "P0V8_PEX1_ISEN1")
	)
	(segment
		(start 125.095762 -280.663904)
		(end 125.659642 -280.663904)
		(width 0.254)
		(layer "In11.Cu")
		(net "P0V8_PEX1_ISEN1")
	)
	(segment
		(start 125.659642 -280.663904)
		(end 126.18466 -280.138886)
		(width 0.254)
		(layer "In11.Cu")
		(net "P0V8_PEX1_ISEN1")
	)
	(segment
		(start 121.289318 -263.82091)
		(end 119.82577 -263.82091)
		(width 0.254)
		(layer "In11.Cu")
		(net "P0V8_PEX1_ISEN1")
	)
	(segment
		(start 123.436634 -266.764516)
		(end 121.94032 -265.268202)
		(width 0.254)
		(layer "In11.Cu")
		(net "P0V8_PEX1_ISEN1")
	)
	(segment
		(start 126.18466 -280.138886)
		(end 126.18466 -279.240234)
		(width 0.254)
		(layer "In11.Cu")
		(net "P0V8_PEX1_ISEN1")
	)
	(segment
		(start 121.94032 -265.268202)
		(end 121.94032 -264.471912)
		(width 0.254)
		(layer "In11.Cu")
		(net "P0V8_PEX1_ISEN1")
	)
	(segment
		(start 126.18466 -279.240234)
		(end 123.436634 -276.492208)
		(width 0.254)
		(layer "In11.Cu")
		(net "P0V8_PEX1_ISEN1")
	)
	(segment
		(start 124.607828 -281.151838)
		(end 125.095762 -280.663904)
		(width 0.254)
		(layer "In11.Cu")
		(net "P0V8_PEX1_ISEN1")
	)
	(segment
		(start 348.877636 -255.82372)
		(end 348.877636 -255.18872)
		(width 0.254)
		(layer "F.Cu")
		(net "P0V8_PEX2_VDD")
	)
	(segment
		(start 350.57588 -256.994914)
		(end 349.712534 -256.994914)
		(width 0.1778)
		(layer "F.Cu")
		(net "P0V8_PEX2_VDD")
	)
	(segment
		(start 349.712534 -256.994914)
		(end 348.877636 -256.160016)
		(width 0.1778)
		(layer "F.Cu")
		(net "P0V8_PEX2_VDD")
	)
	(segment
		(start 348.877636 -256.160016)
		(end 348.877636 -255.82372)
		(width 0.1778)
		(layer "F.Cu")
		(net "P0V8_PEX2_VDD")
	)
	(via
		(at 348.877636 -255.18872)
		(size 0.508)
		(drill 0.254)
		(layers "F.Cu" "B.Cu")
		(net "P0V8_PEX2_VDD")
	)
	(via
		(at 348.877636 -253.17577)
		(size 0.6604)
		(drill 0.3302)
		(layers "F.Cu" "B.Cu")
		(net "P0V8_PEX2_VDD")
	)
	(segment
		(start 348.864936 -255.20142)
		(end 348.864936 -255.86055)
		(width 0.381)
		(layer "B.Cu")
		(net "P0V8_PEX2_VDD")
	)
	(segment
		(start 348.877636 -253.17577)
		(end 348.877636 -254.55372)
		(width 0.4572)
		(layer "B.Cu")
		(net "P0V8_PEX2_VDD")
	)
	(segment
		(start 348.877636 -254.55372)
		(end 348.877636 -255.18872)
		(width 0.381)
		(layer "B.Cu")
		(net "P0V8_PEX2_VDD")
	)
	(segment
		(start 348.877636 -255.18872)
		(end 348.864936 -255.20142)
		(width 0.381)
		(layer "B.Cu")
		(net "P0V8_PEX2_VDD")
	)
	(segment
		(start 349.992442 -258.59486)
		(end 350.57588 -258.59486)
		(width 0.1524)
		(layer "F.Cu")
		(net "P0V8_PEX2_TSEN_R")
	)
	(segment
		(start 349.796862 -258.79044)
		(end 349.992442 -258.59486)
		(width 0.1524)
		(layer "F.Cu")
		(net "P0V8_PEX2_TSEN_R")
	)
	(segment
		(start 349.010986 -258.79044)
		(end 349.796862 -258.79044)
		(width 0.1524)
		(layer "F.Cu")
		(net "P0V8_PEX2_TSEN_R")
	)
	(via
		(at 349.010986 -258.79044)
		(size 0.508)
		(drill 0.254)
		(layers "F.Cu" "B.Cu")
		(net "P0V8_PEX2_TSEN_R")
	)
	(segment
		(start 349.135954 -260.000496)
		(end 349.135954 -258.915408)
		(width 0.254)
		(layer "B.Cu")
		(net "P0V8_PEX2_TSEN_R")
	)
	(segment
		(start 349.135954 -258.915408)
		(end 349.010986 -258.79044)
		(width 0.254)
		(layer "B.Cu")
		(net "P0V8_PEX2_TSEN_R")
	)
	(segment
		(start 348.119954 -260.000496)
		(end 349.135954 -260.000496)
		(width 0.254)
		(layer "B.Cu")
		(net "P0V8_PEX2_TSEN_R")
	)
	(segment
		(start 305.149758 -302.549814)
		(end 305.624738 -302.074834)
		(width 0.127)
		(layer "F.Cu")
		(net "VSENSE_P0V8_PEX2_SKT_VSEN")
	)
	(via
		(at 305.624738 -302.074834)
		(size 0.4064)
		(drill 0.2032)
		(layers "F.Cu" "B.Cu")
		(net "VSENSE_P0V8_PEX2_SKT_VSEN")
	)
	(via
		(at 329.383898 -327.96988)
		(size 0.6604)
		(drill 0.3302)
		(layers "F.Cu" "B.Cu")
		(net "VSENSE_P0V8_PEX2_SKT_VSEN")
	)
	(segment
		(start 291.48151 -320.171572)
		(end 291.56533 -320.255392)
		(width 0.09906)
		(layer "B.Cu")
		(net "VSENSE_P0V8_PEX2_SKT_VSEN")
	)
	(segment
		(start 291.56533 -320.966084)
		(end 293.516304 -322.917058)
		(width 0.254)
		(layer "B.Cu")
		(net "VSENSE_P0V8_PEX2_SKT_VSEN")
	)
	(segment
		(start 305.002438 -302.656494)
		(end 303.514506 -302.656494)
		(width 0.09906)
		(layer "B.Cu")
		(net "VSENSE_P0V8_PEX2_SKT_VSEN")
	)
	(segment
		(start 332.313026 -328.328274)
		(end 332.673706 -327.942194)
		(width 0.254)
		(layer "B.Cu")
		(net "VSENSE_P0V8_PEX2_SKT_VSEN")
	)
	(segment
		(start 291.56533 -320.255392)
		(end 291.56533 -320.294)
		(width 0.09906)
		(layer "B.Cu")
		(net "VSENSE_P0V8_PEX2_SKT_VSEN")
	)
	(segment
		(start 303.356518 -307.107082)
		(end 303.057052 -307.406548)
		(width 0.09906)
		(layer "B.Cu")
		(net "VSENSE_P0V8_PEX2_SKT_VSEN")
	)
	(segment
		(start 305.256438 -302.402494)
		(end 305.002438 -302.656494)
		(width 0.09906)
		(layer "B.Cu")
		(net "VSENSE_P0V8_PEX2_SKT_VSEN")
	)
	(segment
		(start 291.56533 -320.294)
		(end 291.56533 -320.966084)
		(width 0.254)
		(layer "B.Cu")
		(net "VSENSE_P0V8_PEX2_SKT_VSEN")
	)
	(segment
		(start 293.516304 -322.917058)
		(end 306.580286 -328.328274)
		(width 0.254)
		(layer "B.Cu")
		(net "VSENSE_P0V8_PEX2_SKT_VSEN")
	)
	(segment
		(start 303.057052 -307.406548)
		(end 291.827204 -307.406548)
		(width 0.09906)
		(layer "B.Cu")
		(net "VSENSE_P0V8_PEX2_SKT_VSEN")
	)
	(segment
		(start 305.624738 -302.074834)
		(end 305.355498 -302.074834)
		(width 0.09906)
		(layer "B.Cu")
		(net "VSENSE_P0V8_PEX2_SKT_VSEN")
	)
	(segment
		(start 303.356518 -302.814482)
		(end 303.356518 -307.107082)
		(width 0.09906)
		(layer "B.Cu")
		(net "VSENSE_P0V8_PEX2_SKT_VSEN")
	)
	(segment
		(start 306.580286 -328.328274)
		(end 329.025504 -328.328274)
		(width 0.254)
		(layer "B.Cu")
		(net "VSENSE_P0V8_PEX2_SKT_VSEN")
	)
	(segment
		(start 329.383898 -327.96988)
		(end 329.742292 -328.328274)
		(width 0.254)
		(layer "B.Cu")
		(net "VSENSE_P0V8_PEX2_SKT_VSEN")
	)
	(segment
		(start 291.48151 -307.752242)
		(end 291.48151 -320.171572)
		(width 0.09906)
		(layer "B.Cu")
		(net "VSENSE_P0V8_PEX2_SKT_VSEN")
	)
	(segment
		(start 303.514506 -302.656494)
		(end 303.356518 -302.814482)
		(width 0.09906)
		(layer "B.Cu")
		(net "VSENSE_P0V8_PEX2_SKT_VSEN")
	)
	(segment
		(start 329.742292 -328.328274)
		(end 332.313026 -328.328274)
		(width 0.254)
		(layer "B.Cu")
		(net "VSENSE_P0V8_PEX2_SKT_VSEN")
	)
	(segment
		(start 305.256438 -302.173894)
		(end 305.256438 -302.402494)
		(width 0.09906)
		(layer "B.Cu")
		(net "VSENSE_P0V8_PEX2_SKT_VSEN")
	)
	(segment
		(start 305.355498 -302.074834)
		(end 305.256438 -302.173894)
		(width 0.09906)
		(layer "B.Cu")
		(net "VSENSE_P0V8_PEX2_SKT_VSEN")
	)
	(segment
		(start 329.025504 -328.328274)
		(end 329.383898 -327.96988)
		(width 0.254)
		(layer "B.Cu")
		(net "VSENSE_P0V8_PEX2_SKT_VSEN")
	)
	(segment
		(start 291.827204 -307.406548)
		(end 291.48151 -307.752242)
		(width 0.09906)
		(layer "B.Cu")
		(net "VSENSE_P0V8_PEX2_SKT_VSEN")
	)
	(segment
		(start 356.588568 -259.79501)
		(end 355.375972 -259.79501)
		(width 0.13208)
		(layer "F.Cu")
		(net "NC_P0V8_PEX2_SVID_ALERT_N_R")
	)
	(segment
		(start 357.178864 -259.204714)
		(end 356.588568 -259.79501)
		(width 0.13208)
		(layer "F.Cu")
		(net "NC_P0V8_PEX2_SVID_ALERT_N_R")
	)
	(segment
		(start 357.240078 -259.1435)
		(end 359.459276 -259.1435)
		(width 0.13208)
		(layer "F.Cu")
		(net "NC_P0V8_PEX2_SVID_ALERT_N_R")
	)
	(segment
		(start 357.178864 -259.204714)
		(end 357.240078 -259.1435)
		(width 0.13208)
		(layer "F.Cu")
		(net "NC_P0V8_PEX2_SVID_ALERT_N_R")
	)
	(via
		(at 357.178864 -259.204714)
		(size 0.762)
		(drill 0.381)
		(layers "F.Cu" "B.Cu")
		(net "NC_P0V8_PEX2_SVID_ALERT_N_R")
	)
	(segment
		(start 350.00184 -257.76555)
		(end 350.031304 -257.795014)
		(width 0.2032)
		(layer "F.Cu")
		(net "P0V8_PEX2_IINSEN")
	)
	(segment
		(start 349.258636 -257.76555)
		(end 350.00184 -257.76555)
		(width 0.2032)
		(layer "F.Cu")
		(net "P0V8_PEX2_IINSEN")
	)
	(segment
		(start 349.004636 -258.01955)
		(end 349.258636 -257.76555)
		(width 0.2032)
		(layer "F.Cu")
		(net "P0V8_PEX2_IINSEN")
	)
	(segment
		(start 350.031304 -257.795014)
		(end 350.57588 -257.795014)
		(width 0.2032)
		(layer "F.Cu")
		(net "P0V8_PEX2_IINSEN")
	)
	(segment
		(start 348.242636 -258.14655)
		(end 348.369636 -258.01955)
		(width 0.254)
		(layer "F.Cu")
		(net "P0V8_PEX2_IINSEN")
	)
	(segment
		(start 348.369636 -258.01955)
		(end 349.004636 -258.01955)
		(width 0.254)
		(layer "F.Cu")
		(net "P0V8_PEX2_IINSEN")
	)
	(via
		(at 349.004636 -258.01955)
		(size 0.508)
		(drill 0.254)
		(layers "F.Cu" "B.Cu")
		(net "P0V8_PEX2_IINSEN")
	)
	(via
		(at 347.92031 -258.01955)
		(size 0.6604)
		(drill 0.3302)
		(layers "F.Cu" "B.Cu")
		(net "P0V8_PEX2_IINSEN")
	)
	(segment
		(start 346.65031 -257.604514)
		(end 347.505274 -257.604514)
		(width 0.254)
		(layer "B.Cu")
		(net "P0V8_PEX2_IINSEN")
	)
	(segment
		(start 344.87231 -257.604514)
		(end 345.76131 -257.604514)
		(width 0.254)
		(layer "B.Cu")
		(net "P0V8_PEX2_IINSEN")
	)
	(segment
		(start 347.505274 -257.604514)
		(end 347.92031 -258.01955)
		(width 0.254)
		(layer "B.Cu")
		(net "P0V8_PEX2_IINSEN")
	)
	(segment
		(start 345.76131 -257.604514)
		(end 346.65031 -257.604514)
		(width 0.254)
		(layer "B.Cu")
		(net "P0V8_PEX2_IINSEN")
	)
	(segment
		(start 347.92031 -258.01955)
		(end 349.004636 -258.01955)
		(width 0.254)
		(layer "B.Cu")
		(net "P0V8_PEX2_IINSEN")
	)
	(segment
		(start 349.955612 -282.870148)
		(end 349.955612 -283.437584)
		(width 0.254)
		(layer "F.Cu")
		(net "P0V8_PEX2_VCC2")
	)
	(segment
		(start 348.732348 -283.524198)
		(end 349.168212 -283.524198)
		(width 0.2286)
		(layer "F.Cu")
		(net "P0V8_PEX2_VCC2")
	)
	(segment
		(start 349.168212 -283.524198)
		(end 349.870776 -282.821634)
		(width 0.2286)
		(layer "F.Cu")
		(net "P0V8_PEX2_VCC2")
	)
	(segment
		(start 349.907098 -282.821634)
		(end 349.955612 -282.870148)
		(width 0.254)
		(layer "F.Cu")
		(net "P0V8_PEX2_VCC2")
	)
	(segment
		(start 349.870776 -282.821634)
		(end 349.907098 -282.821634)
		(width 0.2286)
		(layer "F.Cu")
		(net "P0V8_PEX2_VCC2")
	)
	(via
		(at 349.955612 -283.437584)
		(size 0.508)
		(drill 0.254)
		(layers "F.Cu" "B.Cu")
		(net "P0V8_PEX2_VCC2")
	)
	(segment
		(start 347.46819 -282.244292)
		(end 347.425264 -282.244292)
		(width 0.254)
		(layer "B.Cu")
		(net "P0V8_PEX2_VCC2")
	)
	(segment
		(start 348.435168 -282.56738)
		(end 348.155006 -282.287218)
		(width 0.254)
		(layer "B.Cu")
		(net "P0V8_PEX2_VCC2")
	)
	(segment
		(start 348.109032 -282.287218)
		(end 347.982032 -282.160218)
		(width 0.254)
		(layer "B.Cu")
		(net "P0V8_PEX2_VCC2")
	)
	(segment
		(start 348.155006 -282.287218)
		(end 348.109032 -282.287218)
		(width 0.254)
		(layer "B.Cu")
		(net "P0V8_PEX2_VCC2")
	)
	(segment
		(start 349.291148 -283.437584)
		(end 349.272098 -283.418534)
		(width 0.254)
		(layer "B.Cu")
		(net "P0V8_PEX2_VCC2")
	)
	(segment
		(start 347.552264 -282.160218)
		(end 347.46819 -282.244292)
		(width 0.254)
		(layer "B.Cu")
		(net "P0V8_PEX2_VCC2")
	)
	(segment
		(start 347.982032 -282.160218)
		(end 347.552264 -282.160218)
		(width 0.254)
		(layer "B.Cu")
		(net "P0V8_PEX2_VCC2")
	)
	(segment
		(start 349.955612 -283.437584)
		(end 349.291148 -283.437584)
		(width 0.254)
		(layer "B.Cu")
		(net "P0V8_PEX2_VCC2")
	)
	(segment
		(start 348.754954 -282.56738)
		(end 348.435168 -282.56738)
		(width 0.254)
		(layer "B.Cu")
		(net "P0V8_PEX2_VCC2")
	)
	(segment
		(start 349.272098 -283.418534)
		(end 349.272098 -283.084524)
		(width 0.254)
		(layer "B.Cu")
		(net "P0V8_PEX2_VCC2")
	)
	(segment
		(start 349.272098 -283.084524)
		(end 348.754954 -282.56738)
		(width 0.254)
		(layer "B.Cu")
		(net "P0V8_PEX2_VCC2")
	)
	(segment
		(start 345.172284 -281.350974)
		(end 345.172284 -281.999182)
		(width 0.2286)
		(layer "F.Cu")
		(net "SW_P0V8_PEX2_PHASE2")
	)
	(segment
		(start 344.67038 -280.84907)
		(end 345.172284 -281.350974)
		(width 0.2286)
		(layer "F.Cu")
		(net "SW_P0V8_PEX2_PHASE2")
	)
	(segment
		(start 340.571836 -283.524198)
		(end 341.0077 -283.524198)
		(width 0.2286)
		(layer "F.Cu")
		(net "P0V8_PEX2_VCC1")
	)
	(segment
		(start 341.0077 -283.524198)
		(end 341.710264 -282.821634)
		(width 0.2286)
		(layer "F.Cu")
		(net "P0V8_PEX2_VCC1")
	)
	(segment
		(start 341.7951 -282.870148)
		(end 341.7951 -283.437584)
		(width 0.254)
		(layer "F.Cu")
		(net "P0V8_PEX2_VCC1")
	)
	(segment
		(start 341.710264 -282.821634)
		(end 341.746586 -282.821634)
		(width 0.2286)
		(layer "F.Cu")
		(net "P0V8_PEX2_VCC1")
	)
	(segment
		(start 341.746586 -282.821634)
		(end 341.7951 -282.870148)
		(width 0.254)
		(layer "F.Cu")
		(net "P0V8_PEX2_VCC1")
	)
	(via
		(at 341.7951 -283.437584)
		(size 0.508)
		(drill 0.254)
		(layers "F.Cu" "B.Cu")
		(net "P0V8_PEX2_VCC1")
	)
	(segment
		(start 341.77605 -283.418534)
		(end 341.111586 -283.418534)
		(width 0.254)
		(layer "B.Cu")
		(net "P0V8_PEX2_VCC1")
	)
	(segment
		(start 340.007956 -282.295092)
		(end 339.889084 -282.295092)
		(width 0.254)
		(layer "B.Cu")
		(net "P0V8_PEX2_VCC1")
	)
	(segment
		(start 340.27999 -282.586938)
		(end 341.111586 -283.418534)
		(width 0.254)
		(layer "B.Cu")
		(net "P0V8_PEX2_VCC1")
	)
	(segment
		(start 339.734398 -282.140406)
		(end 339.347556 -282.140406)
		(width 0.254)
		(layer "B.Cu")
		(net "P0V8_PEX2_VCC1")
	)
	(segment
		(start 339.347556 -282.140406)
		(end 339.24367 -282.244292)
		(width 0.254)
		(layer "B.Cu")
		(net "P0V8_PEX2_VCC1")
	)
	(segment
		(start 340.27999 -282.567126)
		(end 340.27999 -282.586938)
		(width 0.254)
		(layer "B.Cu")
		(net "P0V8_PEX2_VCC1")
	)
	(segment
		(start 341.7951 -283.437584)
		(end 341.77605 -283.418534)
		(width 0.254)
		(layer "B.Cu")
		(net "P0V8_PEX2_VCC1")
	)
	(segment
		(start 339.889084 -282.295092)
		(end 339.734398 -282.140406)
		(width 0.254)
		(layer "B.Cu")
		(net "P0V8_PEX2_VCC1")
	)
	(segment
		(start 340.27999 -282.567126)
		(end 340.007956 -282.295092)
		(width 0.254)
		(layer "B.Cu")
		(net "P0V8_PEX2_VCC1")
	)
	(segment
		(start 337.471766 -280.04897)
		(end 336.509868 -280.04897)
		(width 0.254)
		(layer "F.Cu")
		(net "SW_P0V8_PEX2_BOOT1_R")
	)
	(segment
		(start 337.471766 -280.84907)
		(end 337.471766 -281.989276)
		(width 0.2286)
		(layer "F.Cu")
		(net "SW_P0V8_PEX2_BOOT1")
	)
	(segment
		(start 337.471766 -281.989276)
		(end 337.46186 -281.999182)
		(width 0.2286)
		(layer "F.Cu")
		(net "SW_P0V8_PEX2_BOOT1")
	)
	(segment
		(start 345.632278 -280.04897)
		(end 344.67038 -280.04897)
		(width 0.254)
		(layer "F.Cu")
		(net "SW_P0V8_PEX2_BOOT2_R")
	)
	(segment
		(start 348.947994 -282.477718)
		(end 348.80169 -282.624022)
		(width 0.2286)
		(layer "F.Cu")
		(net "SW_P0V8_PEX2_VOS2")
	)
	(segment
		(start 349.024448 -282.293314)
		(end 348.947994 -282.477718)
		(width 0.2286)
		(layer "F.Cu")
		(net "SW_P0V8_PEX2_VOS2")
	)
	(segment
		(start 348.80169 -282.624022)
		(end 348.732348 -282.624022)
		(width 0.2286)
		(layer "F.Cu")
		(net "SW_P0V8_PEX2_VOS2")
	)
	(segment
		(start 349.024448 -281.963368)
		(end 349.024448 -282.293314)
		(width 0.2286)
		(layer "F.Cu")
		(net "SW_P0V8_PEX2_VOS2")
	)
	(via
		(at 349.024448 -281.963368)
		(size 0.508)
		(drill 0.254)
		(layers "F.Cu" "B.Cu")
		(net "SW_P0V8_PEX2_VOS2")
	)
	(segment
		(start 349.67545 -282.335986)
		(end 349.397066 -282.335986)
		(width 0.254)
		(layer "B.Cu")
		(net "SW_P0V8_PEX2_VOS2")
	)
	(segment
		(start 349.397066 -282.335986)
		(end 349.024448 -281.963368)
		(width 0.254)
		(layer "B.Cu")
		(net "SW_P0V8_PEX2_VOS2")
	)
	(segment
		(start 349.780098 -282.440634)
		(end 349.67545 -282.335986)
		(width 0.254)
		(layer "B.Cu")
		(net "SW_P0V8_PEX2_VOS2")
	)
	(segment
		(start 49.375822 -456.720448)
		(end 49.375822 -458.54874)
		(width 0.1651)
		(layer "In5.Cu")
		(net "TDR_DIFF_85_IN1_DIN")
	)
	(segment
		(start 64.031622 -458.54874)
		(end 64.361822 -458.87894)
		(width 0.1651)
		(layer "In5.Cu")
		(net "TDR_DIFF_85_IN1_DIN")
	)
	(segment
		(start 38.834822 -458.54874)
		(end 38.834822 -456.720448)
		(width 0.1651)
		(layer "In5.Cu")
		(net "TDR_DIFF_85_IN1_DIN")
	)
	(segment
		(start 25.431242 -456.225148)
		(end 25.926542 -456.720448)
		(width 0.1651)
		(layer "In5.Cu")
		(net "TDR_DIFF_85_IN1_DIN")
	)
	(segment
		(start 37.981382 -458.87894)
		(end 38.504622 -458.87894)
		(width 0.1651)
		(layer "In5.Cu")
		(net "TDR_DIFF_85_IN1_DIN")
	)
	(segment
		(start 43.513502 -458.54874)
		(end 43.843702 -458.87894)
		(width 0.1651)
		(layer "In5.Cu")
		(net "TDR_DIFF_85_IN1_DIN")
	)
	(segment
		(start 64.031622 -456.720448)
		(end 64.031622 -458.54874)
		(width 0.1651)
		(layer "In5.Cu")
		(net "TDR_DIFF_85_IN1_DIN")
	)
	(segment
		(start 34.224722 -456.225148)
		(end 34.720022 -456.720448)
		(width 0.1651)
		(layer "In5.Cu")
		(net "TDR_DIFF_85_IN1_DIN")
	)
	(segment
		(start 50.229262 -458.87894)
		(end 50.559462 -458.54874)
		(width 0.1651)
		(layer "In5.Cu")
		(net "TDR_DIFF_85_IN1_DIN")
	)
	(segment
		(start 41.765982 -456.720448)
		(end 42.261282 -456.225148)
		(width 0.1651)
		(layer "In5.Cu")
		(net "TDR_DIFF_85_IN1_DIN")
	)
	(segment
		(start 49.375822 -458.54874)
		(end 49.706022 -458.87894)
		(width 0.1651)
		(layer "In5.Cu")
		(net "TDR_DIFF_85_IN1_DIN")
	)
	(segment
		(start 56.917082 -456.225148)
		(end 57.674002 -456.225148)
		(width 0.1651)
		(layer "In5.Cu")
		(net "TDR_DIFF_85_IN1_DIN")
	)
	(segment
		(start 46.774862 -458.87894)
		(end 47.298102 -458.87894)
		(width 0.1651)
		(layer "In5.Cu")
		(net "TDR_DIFF_85_IN1_DIN")
	)
	(segment
		(start 39.330122 -456.225148)
		(end 40.087042 -456.225148)
		(width 0.1651)
		(layer "In5.Cu")
		(net "TDR_DIFF_85_IN1_DIN")
	)
	(segment
		(start 31.788862 -456.720448)
		(end 31.788862 -458.54874)
		(width 0.1651)
		(layer "In5.Cu")
		(net "TDR_DIFF_85_IN1_DIN")
	)
	(segment
		(start 23.325582 -458.87894)
		(end 23.848822 -458.87894)
		(width 0.1651)
		(layer "In5.Cu")
		(net "TDR_DIFF_85_IN1_DIN")
	)
	(segment
		(start 29.187902 -458.87894)
		(end 29.711142 -458.87894)
		(width 0.1651)
		(layer "In5.Cu")
		(net "TDR_DIFF_85_IN1_DIN")
	)
	(segment
		(start 68.146422 -456.720448)
		(end 68.641722 -456.225148)
		(width 0.1651)
		(layer "In5.Cu")
		(net "TDR_DIFF_85_IN1_DIN")
	)
	(segment
		(start 35.050222 -458.87894)
		(end 35.573462 -458.87894)
		(width 0.1651)
		(layer "In5.Cu")
		(net "TDR_DIFF_85_IN1_DIN")
	)
	(segment
		(start 56.421782 -456.720448)
		(end 56.917082 -456.225148)
		(width 0.1651)
		(layer "In5.Cu")
		(net "TDR_DIFF_85_IN1_DIN")
	)
	(segment
		(start 28.362402 -456.225148)
		(end 28.857702 -456.720448)
		(width 0.1651)
		(layer "In5.Cu")
		(net "TDR_DIFF_85_IN1_DIN")
	)
	(segment
		(start 47.628302 -458.54874)
		(end 47.628302 -456.720448)
		(width 0.1651)
		(layer "In5.Cu")
		(net "TDR_DIFF_85_IN1_DIN")
	)
	(segment
		(start 35.903662 -458.54874)
		(end 35.903662 -456.720448)
		(width 0.1651)
		(layer "In5.Cu")
		(net "TDR_DIFF_85_IN1_DIN")
	)
	(segment
		(start 29.711142 -458.87894)
		(end 30.041342 -458.54874)
		(width 0.1651)
		(layer "In5.Cu")
		(net "TDR_DIFF_85_IN1_DIN")
	)
	(segment
		(start 72.329802 -456.225148)
		(end 72.825102 -456.720448)
		(width 0.1651)
		(layer "In5.Cu")
		(net "TDR_DIFF_85_IN1_DIN")
	)
	(segment
		(start 32.972502 -456.720448)
		(end 33.467802 -456.225148)
		(width 0.1651)
		(layer "In5.Cu")
		(net "TDR_DIFF_85_IN1_DIN")
	)
	(segment
		(start 32.119062 -458.87894)
		(end 32.642302 -458.87894)
		(width 0.1651)
		(layer "In5.Cu")
		(net "TDR_DIFF_85_IN1_DIN")
	)
	(segment
		(start 58.169302 -456.720448)
		(end 58.169302 -458.54874)
		(width 0.1651)
		(layer "In5.Cu")
		(net "TDR_DIFF_85_IN1_DIN")
	)
	(segment
		(start 46.444662 -458.54874)
		(end 46.774862 -458.87894)
		(width 0.1651)
		(layer "In5.Cu")
		(net "TDR_DIFF_85_IN1_DIN")
	)
	(segment
		(start 75.756262 -456.720448)
		(end 75.756262 -457.221844)
		(width 0.1651)
		(layer "In5.Cu")
		(net "TDR_DIFF_85_IN1_DIN")
	)
	(segment
		(start 35.573462 -458.87894)
		(end 35.903662 -458.54874)
		(width 0.1651)
		(layer "In5.Cu")
		(net "TDR_DIFF_85_IN1_DIN")
	)
	(segment
		(start 19.568922 -456.225148)
		(end 20.064222 -456.720448)
		(width 0.1651)
		(layer "In5.Cu")
		(net "TDR_DIFF_85_IN1_DIN")
	)
	(segment
		(start 27.110182 -458.54874)
		(end 27.110182 -456.720448)
		(width 0.1651)
		(layer "In5.Cu")
		(net "TDR_DIFF_85_IN1_DIN")
	)
	(segment
		(start 58.169302 -458.54874)
		(end 58.499502 -458.87894)
		(width 0.1651)
		(layer "In5.Cu")
		(net "TDR_DIFF_85_IN1_DIN")
	)
	(segment
		(start 20.917662 -458.87894)
		(end 21.247862 -458.54874)
		(width 0.1651)
		(layer "In5.Cu")
		(net "TDR_DIFF_85_IN1_DIN")
	)
	(segment
		(start 51.054762 -456.225148)
		(end 51.811682 -456.225148)
		(width 0.1651)
		(layer "In5.Cu")
		(net "TDR_DIFF_85_IN1_DIN")
	)
	(segment
		(start 30.536642 -456.225148)
		(end 31.293562 -456.225148)
		(width 0.1651)
		(layer "In5.Cu")
		(net "TDR_DIFF_85_IN1_DIN")
	)
	(segment
		(start 26.256742 -458.87894)
		(end 26.779982 -458.87894)
		(width 0.1651)
		(layer "In5.Cu")
		(net "TDR_DIFF_85_IN1_DIN")
	)
	(segment
		(start 78.155292 -457.552044)
		(end 78.320392 -457.386944)
		(width 0.1651)
		(layer "In5.Cu")
		(net "TDR_DIFF_85_IN1_DIN")
	)
	(segment
		(start 55.568342 -458.87894)
		(end 56.091582 -458.87894)
		(width 0.1651)
		(layer "In5.Cu")
		(net "TDR_DIFF_85_IN1_DIN")
	)
	(segment
		(start 44.697142 -458.54874)
		(end 44.697142 -456.720448)
		(width 0.1651)
		(layer "In5.Cu")
		(net "TDR_DIFF_85_IN1_DIN")
	)
	(segment
		(start 45.192442 -456.225148)
		(end 45.949362 -456.225148)
		(width 0.1651)
		(layer "In5.Cu")
		(net "TDR_DIFF_85_IN1_DIN")
	)
	(segment
		(start 50.559462 -458.54874)
		(end 50.559462 -456.720448)
		(width 0.1651)
		(layer "In5.Cu")
		(net "TDR_DIFF_85_IN1_DIN")
	)
	(segment
		(start 21.743162 -456.225148)
		(end 22.500082 -456.225148)
		(width 0.1651)
		(layer "In5.Cu")
		(net "TDR_DIFF_85_IN1_DIN")
	)
	(segment
		(start 66.962782 -456.720448)
		(end 66.962782 -458.54874)
		(width 0.1651)
		(layer "In5.Cu")
		(net "TDR_DIFF_85_IN1_DIN")
	)
	(segment
		(start 27.605482 -456.225148)
		(end 28.362402 -456.225148)
		(width 0.1651)
		(layer "In5.Cu")
		(net "TDR_DIFF_85_IN1_DIN")
	)
	(segment
		(start 37.651182 -458.54874)
		(end 37.981382 -458.87894)
		(width 0.1651)
		(layer "In5.Cu")
		(net "TDR_DIFF_85_IN1_DIN")
	)
	(segment
		(start 35.903662 -456.720448)
		(end 36.398962 -456.225148)
		(width 0.1651)
		(layer "In5.Cu")
		(net "TDR_DIFF_85_IN1_DIN")
	)
	(segment
		(start 49.706022 -458.87894)
		(end 50.229262 -458.87894)
		(width 0.1651)
		(layer "In5.Cu")
		(net "TDR_DIFF_85_IN1_DIN")
	)
	(segment
		(start 17.133062 -458.54874)
		(end 17.463262 -458.87894)
		(width 0.1651)
		(layer "In5.Cu")
		(net "TDR_DIFF_85_IN1_DIN")
	)
	(segment
		(start 74.008742 -456.720448)
		(end 74.504042 -456.225148)
		(width 0.1651)
		(layer "In5.Cu")
		(net "TDR_DIFF_85_IN1_DIN")
	)
	(segment
		(start 64.885062 -458.87894)
		(end 65.215262 -458.54874)
		(width 0.1651)
		(layer "In5.Cu")
		(net "TDR_DIFF_85_IN1_DIN")
	)
	(segment
		(start 40.582342 -456.720448)
		(end 40.582342 -458.54874)
		(width 0.1651)
		(layer "In5.Cu")
		(net "TDR_DIFF_85_IN1_DIN")
	)
	(segment
		(start 27.110182 -456.720448)
		(end 27.605482 -456.225148)
		(width 0.1651)
		(layer "In5.Cu")
		(net "TDR_DIFF_85_IN1_DIN")
	)
	(segment
		(start 40.087042 -456.225148)
		(end 40.582342 -456.720448)
		(width 0.1651)
		(layer "In5.Cu")
		(net "TDR_DIFF_85_IN1_DIN")
	)
	(segment
		(start 52.637182 -458.87894)
		(end 53.160422 -458.87894)
		(width 0.1651)
		(layer "In5.Cu")
		(net "TDR_DIFF_85_IN1_DIN")
	)
	(segment
		(start 61.100462 -458.54874)
		(end 61.430662 -458.87894)
		(width 0.1651)
		(layer "In5.Cu")
		(net "TDR_DIFF_85_IN1_DIN")
	)
	(segment
		(start 47.298102 -458.87894)
		(end 47.628302 -458.54874)
		(width 0.1651)
		(layer "In5.Cu")
		(net "TDR_DIFF_85_IN1_DIN")
	)
	(segment
		(start 62.284102 -456.720448)
		(end 62.779402 -456.225148)
		(width 0.1651)
		(layer "In5.Cu")
		(net "TDR_DIFF_85_IN1_DIN")
	)
	(segment
		(start 66.962782 -458.54874)
		(end 67.292982 -458.87894)
		(width 0.1651)
		(layer "In5.Cu")
		(net "TDR_DIFF_85_IN1_DIN")
	)
	(segment
		(start 25.926542 -458.54874)
		(end 26.256742 -458.87894)
		(width 0.1651)
		(layer "In5.Cu")
		(net "TDR_DIFF_85_IN1_DIN")
	)
	(segment
		(start 74.504042 -456.225148)
		(end 75.260962 -456.225148)
		(width 0.1651)
		(layer "In5.Cu")
		(net "TDR_DIFF_85_IN1_DIN")
	)
	(segment
		(start 24.179022 -458.54874)
		(end 24.179022 -456.720448)
		(width 0.1651)
		(layer "In5.Cu")
		(net "TDR_DIFF_85_IN1_DIN")
	)
	(segment
		(start 59.352942 -458.54874)
		(end 59.352942 -456.720448)
		(width 0.1651)
		(layer "In5.Cu")
		(net "TDR_DIFF_85_IN1_DIN")
	)
	(segment
		(start 40.912542 -458.87894)
		(end 41.435782 -458.87894)
		(width 0.1651)
		(layer "In5.Cu")
		(net "TDR_DIFF_85_IN1_DIN")
	)
	(segment
		(start 51.811682 -456.225148)
		(end 52.306982 -456.720448)
		(width 0.1651)
		(layer "In5.Cu")
		(net "TDR_DIFF_85_IN1_DIN")
	)
	(segment
		(start 44.366942 -458.87894)
		(end 44.697142 -458.54874)
		(width 0.1651)
		(layer "In5.Cu")
		(net "TDR_DIFF_85_IN1_DIN")
	)
	(segment
		(start 71.077582 -458.54874)
		(end 71.077582 -456.720448)
		(width 0.1651)
		(layer "In5.Cu")
		(net "TDR_DIFF_85_IN1_DIN")
	)
	(segment
		(start 21.247862 -456.720448)
		(end 21.743162 -456.225148)
		(width 0.1651)
		(layer "In5.Cu")
		(net "TDR_DIFF_85_IN1_DIN")
	)
	(segment
		(start 65.215262 -458.54874)
		(end 65.215262 -456.720448)
		(width 0.1651)
		(layer "In5.Cu")
		(net "TDR_DIFF_85_IN1_DIN")
	)
	(segment
		(start 17.463262 -458.87894)
		(end 17.986502 -458.87894)
		(width 0.1651)
		(layer "In5.Cu")
		(net "TDR_DIFF_85_IN1_DIN")
	)
	(segment
		(start 28.857702 -456.720448)
		(end 28.857702 -458.54874)
		(width 0.1651)
		(layer "In5.Cu")
		(net "TDR_DIFF_85_IN1_DIN")
	)
	(segment
		(start 69.893942 -458.54874)
		(end 70.224142 -458.87894)
		(width 0.1651)
		(layer "In5.Cu")
		(net "TDR_DIFF_85_IN1_DIN")
	)
	(segment
		(start 17.133062 -458.047344)
		(end 17.133062 -458.54874)
		(width 0.1651)
		(layer "In5.Cu")
		(net "TDR_DIFF_85_IN1_DIN")
	)
	(segment
		(start 22.995382 -456.720448)
		(end 22.995382 -458.54874)
		(width 0.1651)
		(layer "In5.Cu")
		(net "TDR_DIFF_85_IN1_DIN")
	)
	(segment
		(start 78.320392 -457.386944)
		(end 78.320392 -456.423014)
		(width 0.1651)
		(layer "In5.Cu")
		(net "TDR_DIFF_85_IN1_DIN")
	)
	(segment
		(start 53.985922 -456.225148)
		(end 54.742842 -456.225148)
		(width 0.1651)
		(layer "In5.Cu")
		(net "TDR_DIFF_85_IN1_DIN")
	)
	(segment
		(start 18.316702 -456.720448)
		(end 18.812002 -456.225148)
		(width 0.1651)
		(layer "In5.Cu")
		(net "TDR_DIFF_85_IN1_DIN")
	)
	(segment
		(start 26.779982 -458.87894)
		(end 27.110182 -458.54874)
		(width 0.1651)
		(layer "In5.Cu")
		(net "TDR_DIFF_85_IN1_DIN")
	)
	(segment
		(start 72.825102 -458.54874)
		(end 73.155302 -458.87894)
		(width 0.1651)
		(layer "In5.Cu")
		(net "TDR_DIFF_85_IN1_DIN")
	)
	(segment
		(start 24.674322 -456.225148)
		(end 25.431242 -456.225148)
		(width 0.1651)
		(layer "In5.Cu")
		(net "TDR_DIFF_85_IN1_DIN")
	)
	(segment
		(start 73.155302 -458.87894)
		(end 73.678542 -458.87894)
		(width 0.1651)
		(layer "In5.Cu")
		(net "TDR_DIFF_85_IN1_DIN")
	)
	(segment
		(start 37.651182 -456.720448)
		(end 37.651182 -458.54874)
		(width 0.1651)
		(layer "In5.Cu")
		(net "TDR_DIFF_85_IN1_DIN")
	)
	(segment
		(start 22.500082 -456.225148)
		(end 22.995382 -456.720448)
		(width 0.1651)
		(layer "In5.Cu")
		(net "TDR_DIFF_85_IN1_DIN")
	)
	(segment
		(start 31.788862 -458.54874)
		(end 32.119062 -458.87894)
		(width 0.1651)
		(layer "In5.Cu")
		(net "TDR_DIFF_85_IN1_DIN")
	)
	(segment
		(start 72.825102 -456.720448)
		(end 72.825102 -458.54874)
		(width 0.1651)
		(layer "In5.Cu")
		(net "TDR_DIFF_85_IN1_DIN")
	)
	(segment
		(start 76.086462 -457.552044)
		(end 78.155292 -457.552044)
		(width 0.1651)
		(layer "In5.Cu")
		(net "TDR_DIFF_85_IN1_DIN")
	)
	(segment
		(start 61.100462 -456.720448)
		(end 61.100462 -458.54874)
		(width 0.1651)
		(layer "In5.Cu")
		(net "TDR_DIFF_85_IN1_DIN")
	)
	(segment
		(start 20.064222 -458.54874)
		(end 20.394422 -458.87894)
		(width 0.1651)
		(layer "In5.Cu")
		(net "TDR_DIFF_85_IN1_DIN")
	)
	(segment
		(start 40.582342 -458.54874)
		(end 40.912542 -458.87894)
		(width 0.1651)
		(layer "In5.Cu")
		(net "TDR_DIFF_85_IN1_DIN")
	)
	(segment
		(start 37.155882 -456.225148)
		(end 37.651182 -456.720448)
		(width 0.1651)
		(layer "In5.Cu")
		(net "TDR_DIFF_85_IN1_DIN")
	)
	(segment
		(start 23.848822 -458.87894)
		(end 24.179022 -458.54874)
		(width 0.1651)
		(layer "In5.Cu")
		(net "TDR_DIFF_85_IN1_DIN")
	)
	(segment
		(start 53.160422 -458.87894)
		(end 53.490622 -458.54874)
		(width 0.1651)
		(layer "In5.Cu")
		(net "TDR_DIFF_85_IN1_DIN")
	)
	(segment
		(start 67.816222 -458.87894)
		(end 68.146422 -458.54874)
		(width 0.1651)
		(layer "In5.Cu")
		(net "TDR_DIFF_85_IN1_DIN")
	)
	(segment
		(start 18.316702 -458.54874)
		(end 18.316702 -456.720448)
		(width 0.1651)
		(layer "In5.Cu")
		(net "TDR_DIFF_85_IN1_DIN")
	)
	(segment
		(start 24.179022 -456.720448)
		(end 24.674322 -456.225148)
		(width 0.1651)
		(layer "In5.Cu")
		(net "TDR_DIFF_85_IN1_DIN")
	)
	(segment
		(start 44.697142 -456.720448)
		(end 45.192442 -456.225148)
		(width 0.1651)
		(layer "In5.Cu")
		(net "TDR_DIFF_85_IN1_DIN")
	)
	(segment
		(start 34.720022 -456.720448)
		(end 34.720022 -458.54874)
		(width 0.1651)
		(layer "In5.Cu")
		(net "TDR_DIFF_85_IN1_DIN")
	)
	(segment
		(start 25.926542 -456.720448)
		(end 25.926542 -458.54874)
		(width 0.1651)
		(layer "In5.Cu")
		(net "TDR_DIFF_85_IN1_DIN")
	)
	(segment
		(start 56.091582 -458.87894)
		(end 56.421782 -458.54874)
		(width 0.1651)
		(layer "In5.Cu")
		(net "TDR_DIFF_85_IN1_DIN")
	)
	(segment
		(start 74.008742 -458.54874)
		(end 74.008742 -456.720448)
		(width 0.1651)
		(layer "In5.Cu")
		(net "TDR_DIFF_85_IN1_DIN")
	)
	(segment
		(start 58.499502 -458.87894)
		(end 59.022742 -458.87894)
		(width 0.1651)
		(layer "In5.Cu")
		(net "TDR_DIFF_85_IN1_DIN")
	)
	(segment
		(start 66.467482 -456.225148)
		(end 66.962782 -456.720448)
		(width 0.1651)
		(layer "In5.Cu")
		(net "TDR_DIFF_85_IN1_DIN")
	)
	(segment
		(start 68.641722 -456.225148)
		(end 69.398642 -456.225148)
		(width 0.1651)
		(layer "In5.Cu")
		(net "TDR_DIFF_85_IN1_DIN")
	)
	(segment
		(start 55.238142 -458.54874)
		(end 55.568342 -458.87894)
		(width 0.1651)
		(layer "In5.Cu")
		(net "TDR_DIFF_85_IN1_DIN")
	)
	(segment
		(start 59.022742 -458.87894)
		(end 59.352942 -458.54874)
		(width 0.1651)
		(layer "In5.Cu")
		(net "TDR_DIFF_85_IN1_DIN")
	)
	(segment
		(start 65.215262 -456.720448)
		(end 65.710562 -456.225148)
		(width 0.1651)
		(layer "In5.Cu")
		(net "TDR_DIFF_85_IN1_DIN")
	)
	(segment
		(start 54.742842 -456.225148)
		(end 55.238142 -456.720448)
		(width 0.1651)
		(layer "In5.Cu")
		(net "TDR_DIFF_85_IN1_DIN")
	)
	(segment
		(start 57.674002 -456.225148)
		(end 58.169302 -456.720448)
		(width 0.1651)
		(layer "In5.Cu")
		(net "TDR_DIFF_85_IN1_DIN")
	)
	(segment
		(start 64.361822 -458.87894)
		(end 64.885062 -458.87894)
		(width 0.1651)
		(layer "In5.Cu")
		(net "TDR_DIFF_85_IN1_DIN")
	)
	(segment
		(start 20.064222 -456.720448)
		(end 20.064222 -458.54874)
		(width 0.1651)
		(layer "In5.Cu")
		(net "TDR_DIFF_85_IN1_DIN")
	)
	(segment
		(start 14.452092 -457.552044)
		(end 16.637762 -457.552044)
		(width 0.1651)
		(layer "In5.Cu")
		(net "TDR_DIFF_85_IN1_DIN")
	)
	(segment
		(start 65.710562 -456.225148)
		(end 66.467482 -456.225148)
		(width 0.1651)
		(layer "In5.Cu")
		(net "TDR_DIFF_85_IN1_DIN")
	)
	(segment
		(start 52.306982 -458.54874)
		(end 52.637182 -458.87894)
		(width 0.1651)
		(layer "In5.Cu")
		(net "TDR_DIFF_85_IN1_DIN")
	)
	(segment
		(start 61.953902 -458.87894)
		(end 62.284102 -458.54874)
		(width 0.1651)
		(layer "In5.Cu")
		(net "TDR_DIFF_85_IN1_DIN")
	)
	(segment
		(start 31.293562 -456.225148)
		(end 31.788862 -456.720448)
		(width 0.1651)
		(layer "In5.Cu")
		(net "TDR_DIFF_85_IN1_DIN")
	)
	(segment
		(start 59.848242 -456.225148)
		(end 60.605162 -456.225148)
		(width 0.1651)
		(layer "In5.Cu")
		(net "TDR_DIFF_85_IN1_DIN")
	)
	(segment
		(start 14.286992 -457.386944)
		(end 14.452092 -457.552044)
		(width 0.1651)
		(layer "In5.Cu")
		(net "TDR_DIFF_85_IN1_DIN")
	)
	(segment
		(start 38.504622 -458.87894)
		(end 38.834822 -458.54874)
		(width 0.1651)
		(layer "In5.Cu")
		(net "TDR_DIFF_85_IN1_DIN")
	)
	(segment
		(start 71.077582 -456.720448)
		(end 71.572882 -456.225148)
		(width 0.1651)
		(layer "In5.Cu")
		(net "TDR_DIFF_85_IN1_DIN")
	)
	(segment
		(start 69.893942 -456.720448)
		(end 69.893942 -458.54874)
		(width 0.1651)
		(layer "In5.Cu")
		(net "TDR_DIFF_85_IN1_DIN")
	)
	(segment
		(start 18.812002 -456.225148)
		(end 19.568922 -456.225148)
		(width 0.1651)
		(layer "In5.Cu")
		(net "TDR_DIFF_85_IN1_DIN")
	)
	(segment
		(start 53.490622 -456.720448)
		(end 53.985922 -456.225148)
		(width 0.1651)
		(layer "In5.Cu")
		(net "TDR_DIFF_85_IN1_DIN")
	)
	(segment
		(start 52.306982 -456.720448)
		(end 52.306982 -458.54874)
		(width 0.1651)
		(layer "In5.Cu")
		(net "TDR_DIFF_85_IN1_DIN")
	)
	(segment
		(start 46.444662 -456.720448)
		(end 46.444662 -458.54874)
		(width 0.1651)
		(layer "In5.Cu")
		(net "TDR_DIFF_85_IN1_DIN")
	)
	(segment
		(start 32.972502 -458.54874)
		(end 32.972502 -456.720448)
		(width 0.1651)
		(layer "In5.Cu")
		(net "TDR_DIFF_85_IN1_DIN")
	)
	(segment
		(start 48.880522 -456.225148)
		(end 49.375822 -456.720448)
		(width 0.1651)
		(layer "In5.Cu")
		(net "TDR_DIFF_85_IN1_DIN")
	)
	(segment
		(start 68.146422 -458.54874)
		(end 68.146422 -456.720448)
		(width 0.1651)
		(layer "In5.Cu")
		(net "TDR_DIFF_85_IN1_DIN")
	)
	(segment
		(start 61.430662 -458.87894)
		(end 61.953902 -458.87894)
		(width 0.1651)
		(layer "In5.Cu")
		(net "TDR_DIFF_85_IN1_DIN")
	)
	(segment
		(start 30.041342 -456.720448)
		(end 30.536642 -456.225148)
		(width 0.1651)
		(layer "In5.Cu")
		(net "TDR_DIFF_85_IN1_DIN")
	)
	(segment
		(start 56.421782 -458.54874)
		(end 56.421782 -456.720448)
		(width 0.1651)
		(layer "In5.Cu")
		(net "TDR_DIFF_85_IN1_DIN")
	)
	(segment
		(start 41.435782 -458.87894)
		(end 41.765982 -458.54874)
		(width 0.1651)
		(layer "In5.Cu")
		(net "TDR_DIFF_85_IN1_DIN")
	)
	(segment
		(start 36.398962 -456.225148)
		(end 37.155882 -456.225148)
		(width 0.1651)
		(layer "In5.Cu")
		(net "TDR_DIFF_85_IN1_DIN")
	)
	(segment
		(start 55.238142 -456.720448)
		(end 55.238142 -458.54874)
		(width 0.1651)
		(layer "In5.Cu")
		(net "TDR_DIFF_85_IN1_DIN")
	)
	(segment
		(start 70.747382 -458.87894)
		(end 71.077582 -458.54874)
		(width 0.1651)
		(layer "In5.Cu")
		(net "TDR_DIFF_85_IN1_DIN")
	)
	(segment
		(start 45.949362 -456.225148)
		(end 46.444662 -456.720448)
		(width 0.1651)
		(layer "In5.Cu")
		(net "TDR_DIFF_85_IN1_DIN")
	)
	(segment
		(start 48.123602 -456.225148)
		(end 48.880522 -456.225148)
		(width 0.1651)
		(layer "In5.Cu")
		(net "TDR_DIFF_85_IN1_DIN")
	)
	(segment
		(start 62.284102 -458.54874)
		(end 62.284102 -456.720448)
		(width 0.1651)
		(layer "In5.Cu")
		(net "TDR_DIFF_85_IN1_DIN")
	)
	(segment
		(start 50.559462 -456.720448)
		(end 51.054762 -456.225148)
		(width 0.1651)
		(layer "In5.Cu")
		(net "TDR_DIFF_85_IN1_DIN")
	)
	(segment
		(start 62.779402 -456.225148)
		(end 63.536322 -456.225148)
		(width 0.1651)
		(layer "In5.Cu")
		(net "TDR_DIFF_85_IN1_DIN")
	)
	(segment
		(start 75.260962 -456.225148)
		(end 75.756262 -456.720448)
		(width 0.1651)
		(layer "In5.Cu")
		(net "TDR_DIFF_85_IN1_DIN")
	)
	(segment
		(start 30.041342 -458.54874)
		(end 30.041342 -456.720448)
		(width 0.1651)
		(layer "In5.Cu")
		(net "TDR_DIFF_85_IN1_DIN")
	)
	(segment
		(start 34.720022 -458.54874)
		(end 35.050222 -458.87894)
		(width 0.1651)
		(layer "In5.Cu")
		(net "TDR_DIFF_85_IN1_DIN")
	)
	(segment
		(start 67.292982 -458.87894)
		(end 67.816222 -458.87894)
		(width 0.1651)
		(layer "In5.Cu")
		(net "TDR_DIFF_85_IN1_DIN")
	)
	(segment
		(start 20.394422 -458.87894)
		(end 20.917662 -458.87894)
		(width 0.1651)
		(layer "In5.Cu")
		(net "TDR_DIFF_85_IN1_DIN")
	)
	(segment
		(start 73.678542 -458.87894)
		(end 74.008742 -458.54874)
		(width 0.1651)
		(layer "In5.Cu")
		(net "TDR_DIFF_85_IN1_DIN")
	)
	(segment
		(start 33.467802 -456.225148)
		(end 34.224722 -456.225148)
		(width 0.1651)
		(layer "In5.Cu")
		(net "TDR_DIFF_85_IN1_DIN")
	)
	(segment
		(start 43.018202 -456.225148)
		(end 43.513502 -456.720448)
		(width 0.1651)
		(layer "In5.Cu")
		(net "TDR_DIFF_85_IN1_DIN")
	)
	(segment
		(start 41.765982 -458.54874)
		(end 41.765982 -456.720448)
		(width 0.1651)
		(layer "In5.Cu")
		(net "TDR_DIFF_85_IN1_DIN")
	)
	(segment
		(start 42.261282 -456.225148)
		(end 43.018202 -456.225148)
		(width 0.1651)
		(layer "In5.Cu")
		(net "TDR_DIFF_85_IN1_DIN")
	)
	(segment
		(start 21.247862 -458.54874)
		(end 21.247862 -456.720448)
		(width 0.1651)
		(layer "In5.Cu")
		(net "TDR_DIFF_85_IN1_DIN")
	)
	(segment
		(start 17.986502 -458.87894)
		(end 18.316702 -458.54874)
		(width 0.1651)
		(layer "In5.Cu")
		(net "TDR_DIFF_85_IN1_DIN")
	)
	(segment
		(start 22.995382 -458.54874)
		(end 23.325582 -458.87894)
		(width 0.1651)
		(layer "In5.Cu")
		(net "TDR_DIFF_85_IN1_DIN")
	)
	(segment
		(start 60.605162 -456.225148)
		(end 61.100462 -456.720448)
		(width 0.1651)
		(layer "In5.Cu")
		(net "TDR_DIFF_85_IN1_DIN")
	)
	(segment
		(start 47.628302 -456.720448)
		(end 48.123602 -456.225148)
		(width 0.1651)
		(layer "In5.Cu")
		(net "TDR_DIFF_85_IN1_DIN")
	)
	(segment
		(start 14.286992 -456.423014)
		(end 14.286992 -457.386944)
		(width 0.1651)
		(layer "In5.Cu")
		(net "TDR_DIFF_85_IN1_DIN")
	)
	(segment
		(start 63.536322 -456.225148)
		(end 64.031622 -456.720448)
		(width 0.1651)
		(layer "In5.Cu")
		(net "TDR_DIFF_85_IN1_DIN")
	)
	(segment
		(start 43.843702 -458.87894)
		(end 44.366942 -458.87894)
		(width 0.1651)
		(layer "In5.Cu")
		(net "TDR_DIFF_85_IN1_DIN")
	)
	(segment
		(start 28.857702 -458.54874)
		(end 29.187902 -458.87894)
		(width 0.1651)
		(layer "In5.Cu")
		(net "TDR_DIFF_85_IN1_DIN")
	)
	(segment
		(start 16.637762 -457.552044)
		(end 17.133062 -458.047344)
		(width 0.1651)
		(layer "In5.Cu")
		(net "TDR_DIFF_85_IN1_DIN")
	)
	(segment
		(start 32.642302 -458.87894)
		(end 32.972502 -458.54874)
		(width 0.1651)
		(layer "In5.Cu")
		(net "TDR_DIFF_85_IN1_DIN")
	)
	(segment
		(start 43.513502 -456.720448)
		(end 43.513502 -458.54874)
		(width 0.1651)
		(layer "In5.Cu")
		(net "TDR_DIFF_85_IN1_DIN")
	)
	(segment
		(start 75.756262 -457.221844)
		(end 76.086462 -457.552044)
		(width 0.1651)
		(layer "In5.Cu")
		(net "TDR_DIFF_85_IN1_DIN")
	)
	(segment
		(start 70.224142 -458.87894)
		(end 70.747382 -458.87894)
		(width 0.1651)
		(layer "In5.Cu")
		(net "TDR_DIFF_85_IN1_DIN")
	)
	(segment
		(start 38.834822 -456.720448)
		(end 39.330122 -456.225148)
		(width 0.1651)
		(layer "In5.Cu")
		(net "TDR_DIFF_85_IN1_DIN")
	)
	(segment
		(start 71.572882 -456.225148)
		(end 72.329802 -456.225148)
		(width 0.1651)
		(layer "In5.Cu")
		(net "TDR_DIFF_85_IN1_DIN")
	)
	(segment
		(start 59.352942 -456.720448)
		(end 59.848242 -456.225148)
		(width 0.1651)
		(layer "In5.Cu")
		(net "TDR_DIFF_85_IN1_DIN")
	)
	(segment
		(start 69.398642 -456.225148)
		(end 69.893942 -456.720448)
		(width 0.1651)
		(layer "In5.Cu")
		(net "TDR_DIFF_85_IN1_DIN")
	)
	(segment
		(start 53.490622 -458.54874)
		(end 53.490622 -456.720448)
		(width 0.1651)
		(layer "In5.Cu")
		(net "TDR_DIFF_85_IN1_DIN")
	)
	(segment
		(start 337.011772 -281.350974)
		(end 337.011772 -281.999182)
		(width 0.2286)
		(layer "F.Cu")
		(net "SW_P0V8_PEX2_PHASE1")
	)
	(segment
		(start 336.509868 -280.84907)
		(end 337.011772 -281.350974)
		(width 0.2286)
		(layer "F.Cu")
		(net "SW_P0V8_PEX2_PHASE1")
	)
	(segment
		(start 393.052554 -450.699378)
		(end 392.044174 -451.707758)
		(width 0.15494)
		(layer "In13.Cu")
		(net "TDR_SE_50_OHM_IN5")
	)
	(segment
		(start 392.044174 -451.707758)
		(end 317.512192 -451.707758)
		(width 0.15494)
		(layer "In13.Cu")
		(net "TDR_SE_50_OHM_IN5")
	)
	(segment
		(start 317.512192 -449.167758)
		(end 392.044174 -449.167758)
		(width 0.15494)
		(layer "In13.Cu")
		(net "TDR_SE_50_OHM_IN5")
	)
	(segment
		(start 393.052554 -450.176138)
		(end 393.052554 -450.699378)
		(width 0.15494)
		(layer "In13.Cu")
		(net "TDR_SE_50_OHM_IN5")
	)
	(segment
		(start 392.044174 -449.167758)
		(end 393.052554 -450.176138)
		(width 0.15494)
		(layer "In13.Cu")
		(net "TDR_SE_50_OHM_IN5")
	)
	(segment
		(start 339.728556 -280.530046)
		(end 339.728556 -280.50109)
		(width 0.1524)
		(layer "F.Cu")
		(net "P0V8_PEX2_LSET1")
	)
	(segment
		(start 339.261704 -281.657298)
		(end 339.728556 -280.530046)
		(width 0.1524)
		(layer "F.Cu")
		(net "P0V8_PEX2_LSET1")
	)
	(segment
		(start 339.523324 -280.295858)
		(end 339.728556 -280.50109)
		(width 0.1524)
		(layer "F.Cu")
		(net "P0V8_PEX2_LSET1")
	)
	(segment
		(start 339.523324 -279.886918)
		(end 339.523324 -280.295858)
		(width 0.1524)
		(layer "F.Cu")
		(net "P0V8_PEX2_LSET1")
	)
	(segment
		(start 339.261704 -281.999182)
		(end 339.261704 -281.657298)
		(width 0.1524)
		(layer "F.Cu")
		(net "P0V8_PEX2_LSET1")
	)
	(via
		(at 339.728556 -280.50109)
		(size 0.508)
		(drill 0.254)
		(layers "F.Cu" "B.Cu")
		(net "P0V8_PEX2_LSET1")
	)
	(segment
		(start 340.863936 -281.963368)
		(end 340.863936 -282.293314)
		(width 0.2286)
		(layer "F.Cu")
		(net "SW_P0V8_PEX2_VOS1")
	)
	(segment
		(start 340.863936 -282.293314)
		(end 340.787482 -282.477718)
		(width 0.2286)
		(layer "F.Cu")
		(net "SW_P0V8_PEX2_VOS1")
	)
	(segment
		(start 340.641178 -282.624022)
		(end 340.571836 -282.624022)
		(width 0.2286)
		(layer "F.Cu")
		(net "SW_P0V8_PEX2_VOS1")
	)
	(segment
		(start 340.787482 -282.477718)
		(end 340.641178 -282.624022)
		(width 0.2286)
		(layer "F.Cu")
		(net "SW_P0V8_PEX2_VOS1")
	)
	(via
		(at 340.863936 -281.963368)
		(size 0.508)
		(drill 0.254)
		(layers "F.Cu" "B.Cu")
		(net "SW_P0V8_PEX2_VOS1")
	)
	(segment
		(start 341.520526 -282.341574)
		(end 341.242142 -282.341574)
		(width 0.254)
		(layer "B.Cu")
		(net "SW_P0V8_PEX2_VOS1")
	)
	(segment
		(start 341.619586 -282.440634)
		(end 341.520526 -282.341574)
		(width 0.254)
		(layer "B.Cu")
		(net "SW_P0V8_PEX2_VOS1")
	)
	(segment
		(start 341.242142 -282.341574)
		(end 340.863936 -281.963368)
		(width 0.254)
		(layer "B.Cu")
		(net "SW_P0V8_PEX2_VOS1")
	)
	(segment
		(start 50.866802 -439.311288)
		(end 51.197002 -438.981088)
		(width 0.1651)
		(layer "In13.Cu")
		(net "TDR_DIFF_85_IN5_DIP")
	)
	(segment
		(start 14.312392 -440.473084)
		(end 14.477492 -440.307984)
		(width 0.1651)
		(layer "In13.Cu")
		(net "TDR_DIFF_85_IN5_DIP")
	)
	(segment
		(start 66.706242 -441.13958)
		(end 67.201542 -441.63488)
		(width 0.1651)
		(layer "In13.Cu")
		(net "TDR_DIFF_85_IN5_DIP")
	)
	(segment
		(start 69.637402 -439.311288)
		(end 69.637402 -441.13958)
		(width 0.1651)
		(layer "In13.Cu")
		(net "TDR_DIFF_85_IN5_DIP")
	)
	(segment
		(start 72.238362 -438.981088)
		(end 72.568562 -439.311288)
		(width 0.1651)
		(layer "In13.Cu")
		(net "TDR_DIFF_85_IN5_DIP")
	)
	(segment
		(start 51.720242 -438.981088)
		(end 52.050442 -439.311288)
		(width 0.1651)
		(layer "In13.Cu")
		(net "TDR_DIFF_85_IN5_DIP")
	)
	(segment
		(start 33.279842 -439.311288)
		(end 33.610042 -438.981088)
		(width 0.1651)
		(layer "In13.Cu")
		(net "TDR_DIFF_85_IN5_DIP")
	)
	(segment
		(start 52.545742 -441.63488)
		(end 53.302662 -441.63488)
		(width 0.1651)
		(layer "In13.Cu")
		(net "TDR_DIFF_85_IN5_DIP")
	)
	(segment
		(start 32.027622 -441.63488)
		(end 32.784542 -441.63488)
		(width 0.1651)
		(layer "In13.Cu")
		(net "TDR_DIFF_85_IN5_DIP")
	)
	(segment
		(start 56.233822 -441.63488)
		(end 56.729122 -441.13958)
		(width 0.1651)
		(layer "In13.Cu")
		(net "TDR_DIFF_85_IN5_DIP")
	)
	(segment
		(start 75.499722 -439.812684)
		(end 75.995022 -440.307984)
		(width 0.1651)
		(layer "In13.Cu")
		(net "TDR_DIFF_85_IN5_DIP")
	)
	(segment
		(start 71.715122 -438.981088)
		(end 72.238362 -438.981088)
		(width 0.1651)
		(layer "In13.Cu")
		(net "TDR_DIFF_85_IN5_DIP")
	)
	(segment
		(start 29.096462 -441.63488)
		(end 29.853382 -441.63488)
		(width 0.1651)
		(layer "In13.Cu")
		(net "TDR_DIFF_85_IN5_DIP")
	)
	(segment
		(start 28.270962 -438.981088)
		(end 28.601162 -439.311288)
		(width 0.1651)
		(layer "In13.Cu")
		(net "TDR_DIFF_85_IN5_DIP")
	)
	(segment
		(start 54.651402 -438.981088)
		(end 54.981602 -439.311288)
		(width 0.1651)
		(layer "In13.Cu")
		(net "TDR_DIFF_85_IN5_DIP")
	)
	(segment
		(start 26.165302 -441.63488)
		(end 26.922222 -441.63488)
		(width 0.1651)
		(layer "In13.Cu")
		(net "TDR_DIFF_85_IN5_DIP")
	)
	(segment
		(start 25.670002 -439.311288)
		(end 25.670002 -441.13958)
		(width 0.1651)
		(layer "In13.Cu")
		(net "TDR_DIFF_85_IN5_DIP")
	)
	(segment
		(start 36.211002 -441.13958)
		(end 36.211002 -439.311288)
		(width 0.1651)
		(layer "In13.Cu")
		(net "TDR_DIFF_85_IN5_DIP")
	)
	(segment
		(start 28.601162 -439.311288)
		(end 28.601162 -441.13958)
		(width 0.1651)
		(layer "In13.Cu")
		(net "TDR_DIFF_85_IN5_DIP")
	)
	(segment
		(start 74.316082 -439.311288)
		(end 74.646282 -438.981088)
		(width 0.1651)
		(layer "In13.Cu")
		(net "TDR_DIFF_85_IN5_DIP")
	)
	(segment
		(start 68.453762 -439.311288)
		(end 68.783962 -438.981088)
		(width 0.1651)
		(layer "In13.Cu")
		(net "TDR_DIFF_85_IN5_DIP")
	)
	(segment
		(start 49.119282 -441.13958)
		(end 49.614582 -441.63488)
		(width 0.1651)
		(layer "In13.Cu")
		(net "TDR_DIFF_85_IN5_DIP")
	)
	(segment
		(start 59.990482 -438.981088)
		(end 60.513722 -438.981088)
		(width 0.1651)
		(layer "In13.Cu")
		(net "TDR_DIFF_85_IN5_DIP")
	)
	(segment
		(start 18.954242 -438.981088)
		(end 19.477482 -438.981088)
		(width 0.1651)
		(layer "In13.Cu")
		(net "TDR_DIFF_85_IN5_DIP")
	)
	(segment
		(start 59.660282 -441.13958)
		(end 59.660282 -439.311288)
		(width 0.1651)
		(layer "In13.Cu")
		(net "TDR_DIFF_85_IN5_DIP")
	)
	(segment
		(start 64.270382 -441.63488)
		(end 65.027302 -441.63488)
		(width 0.1651)
		(layer "In13.Cu")
		(net "TDR_DIFF_85_IN5_DIP")
	)
	(segment
		(start 70.132702 -441.63488)
		(end 70.889622 -441.63488)
		(width 0.1651)
		(layer "In13.Cu")
		(net "TDR_DIFF_85_IN5_DIP")
	)
	(segment
		(start 21.555202 -439.311288)
		(end 21.885402 -438.981088)
		(width 0.1651)
		(layer "In13.Cu")
		(net "TDR_DIFF_85_IN5_DIP")
	)
	(segment
		(start 45.334682 -438.981088)
		(end 45.857922 -438.981088)
		(width 0.1651)
		(layer "In13.Cu")
		(net "TDR_DIFF_85_IN5_DIP")
	)
	(segment
		(start 65.522602 -441.13958)
		(end 65.522602 -439.311288)
		(width 0.1651)
		(layer "In13.Cu")
		(net "TDR_DIFF_85_IN5_DIP")
	)
	(segment
		(start 32.784542 -441.63488)
		(end 33.279842 -441.13958)
		(width 0.1651)
		(layer "In13.Cu")
		(net "TDR_DIFF_85_IN5_DIP")
	)
	(segment
		(start 35.715702 -441.63488)
		(end 36.211002 -441.13958)
		(width 0.1651)
		(layer "In13.Cu")
		(net "TDR_DIFF_85_IN5_DIP")
	)
	(segment
		(start 39.472362 -438.981088)
		(end 39.995602 -438.981088)
		(width 0.1651)
		(layer "In13.Cu")
		(net "TDR_DIFF_85_IN5_DIP")
	)
	(segment
		(start 60.843922 -441.13958)
		(end 61.339222 -441.63488)
		(width 0.1651)
		(layer "In13.Cu")
		(net "TDR_DIFF_85_IN5_DIP")
	)
	(segment
		(start 63.775082 -439.311288)
		(end 63.775082 -441.13958)
		(width 0.1651)
		(layer "In13.Cu")
		(net "TDR_DIFF_85_IN5_DIP")
	)
	(segment
		(start 42.073322 -439.311288)
		(end 42.403522 -438.981088)
		(width 0.1651)
		(layer "In13.Cu")
		(net "TDR_DIFF_85_IN5_DIP")
	)
	(segment
		(start 16.876522 -441.13958)
		(end 17.371822 -441.63488)
		(width 0.1651)
		(layer "In13.Cu")
		(net "TDR_DIFF_85_IN5_DIP")
	)
	(segment
		(start 43.752262 -441.63488)
		(end 44.509182 -441.63488)
		(width 0.1651)
		(layer "In13.Cu")
		(net "TDR_DIFF_85_IN5_DIP")
	)
	(segment
		(start 54.128162 -438.981088)
		(end 54.651402 -438.981088)
		(width 0.1651)
		(layer "In13.Cu")
		(net "TDR_DIFF_85_IN5_DIP")
	)
	(segment
		(start 62.591442 -441.13958)
		(end 62.591442 -439.311288)
		(width 0.1651)
		(layer "In13.Cu")
		(net "TDR_DIFF_85_IN5_DIP")
	)
	(segment
		(start 48.789082 -438.981088)
		(end 49.119282 -439.311288)
		(width 0.1651)
		(layer "In13.Cu")
		(net "TDR_DIFF_85_IN5_DIP")
	)
	(segment
		(start 25.670002 -441.13958)
		(end 26.165302 -441.63488)
		(width 0.1651)
		(layer "In13.Cu")
		(net "TDR_DIFF_85_IN5_DIP")
	)
	(segment
		(start 33.610042 -438.981088)
		(end 34.133282 -438.981088)
		(width 0.1651)
		(layer "In13.Cu")
		(net "TDR_DIFF_85_IN5_DIP")
	)
	(segment
		(start 42.073322 -441.13958)
		(end 42.073322 -439.311288)
		(width 0.1651)
		(layer "In13.Cu")
		(net "TDR_DIFF_85_IN5_DIP")
	)
	(segment
		(start 66.706242 -439.311288)
		(end 66.706242 -441.13958)
		(width 0.1651)
		(layer "In13.Cu")
		(net "TDR_DIFF_85_IN5_DIP")
	)
	(segment
		(start 19.807682 -441.13958)
		(end 20.302982 -441.63488)
		(width 0.1651)
		(layer "In13.Cu")
		(net "TDR_DIFF_85_IN5_DIP")
	)
	(segment
		(start 56.729122 -439.311288)
		(end 57.059322 -438.981088)
		(width 0.1651)
		(layer "In13.Cu")
		(net "TDR_DIFF_85_IN5_DIP")
	)
	(segment
		(start 18.624042 -441.13958)
		(end 18.624042 -439.311288)
		(width 0.1651)
		(layer "In13.Cu")
		(net "TDR_DIFF_85_IN5_DIP")
	)
	(segment
		(start 27.417522 -441.13958)
		(end 27.417522 -439.311288)
		(width 0.1651)
		(layer "In13.Cu")
		(net "TDR_DIFF_85_IN5_DIP")
	)
	(segment
		(start 45.004482 -441.13958)
		(end 45.004482 -439.311288)
		(width 0.1651)
		(layer "In13.Cu")
		(net "TDR_DIFF_85_IN5_DIP")
	)
	(segment
		(start 60.513722 -438.981088)
		(end 60.843922 -439.311288)
		(width 0.1651)
		(layer "In13.Cu")
		(net "TDR_DIFF_85_IN5_DIP")
	)
	(segment
		(start 72.568562 -441.13958)
		(end 73.063862 -441.63488)
		(width 0.1651)
		(layer "In13.Cu")
		(net "TDR_DIFF_85_IN5_DIP")
	)
	(segment
		(start 39.995602 -438.981088)
		(end 40.325802 -439.311288)
		(width 0.1651)
		(layer "In13.Cu")
		(net "TDR_DIFF_85_IN5_DIP")
	)
	(segment
		(start 69.637402 -441.13958)
		(end 70.132702 -441.63488)
		(width 0.1651)
		(layer "In13.Cu")
		(net "TDR_DIFF_85_IN5_DIP")
	)
	(segment
		(start 34.463482 -441.13958)
		(end 34.958782 -441.63488)
		(width 0.1651)
		(layer "In13.Cu")
		(net "TDR_DIFF_85_IN5_DIP")
	)
	(segment
		(start 70.889622 -441.63488)
		(end 71.384922 -441.13958)
		(width 0.1651)
		(layer "In13.Cu")
		(net "TDR_DIFF_85_IN5_DIP")
	)
	(segment
		(start 37.064442 -438.981088)
		(end 37.394642 -439.311288)
		(width 0.1651)
		(layer "In13.Cu")
		(net "TDR_DIFF_85_IN5_DIP")
	)
	(segment
		(start 37.394642 -439.311288)
		(end 37.394642 -441.13958)
		(width 0.1651)
		(layer "In13.Cu")
		(net "TDR_DIFF_85_IN5_DIP")
	)
	(segment
		(start 57.912762 -441.13958)
		(end 58.408062 -441.63488)
		(width 0.1651)
		(layer "In13.Cu")
		(net "TDR_DIFF_85_IN5_DIP")
	)
	(segment
		(start 40.325802 -439.311288)
		(end 40.325802 -441.13958)
		(width 0.1651)
		(layer "In13.Cu")
		(net "TDR_DIFF_85_IN5_DIP")
	)
	(segment
		(start 37.889942 -441.63488)
		(end 38.646862 -441.63488)
		(width 0.1651)
		(layer "In13.Cu")
		(net "TDR_DIFF_85_IN5_DIP")
	)
	(segment
		(start 68.783962 -438.981088)
		(end 69.307202 -438.981088)
		(width 0.1651)
		(layer "In13.Cu")
		(net "TDR_DIFF_85_IN5_DIP")
	)
	(segment
		(start 30.678882 -438.981088)
		(end 31.202122 -438.981088)
		(width 0.1651)
		(layer "In13.Cu")
		(net "TDR_DIFF_85_IN5_DIP")
	)
	(segment
		(start 71.384922 -439.311288)
		(end 71.715122 -438.981088)
		(width 0.1651)
		(layer "In13.Cu")
		(net "TDR_DIFF_85_IN5_DIP")
	)
	(segment
		(start 27.747722 -438.981088)
		(end 28.270962 -438.981088)
		(width 0.1651)
		(layer "In13.Cu")
		(net "TDR_DIFF_85_IN5_DIP")
	)
	(segment
		(start 21.555202 -441.13958)
		(end 21.555202 -439.311288)
		(width 0.1651)
		(layer "In13.Cu")
		(net "TDR_DIFF_85_IN5_DIP")
	)
	(segment
		(start 37.394642 -441.13958)
		(end 37.889942 -441.63488)
		(width 0.1651)
		(layer "In13.Cu")
		(net "TDR_DIFF_85_IN5_DIP")
	)
	(segment
		(start 22.738842 -439.311288)
		(end 22.738842 -441.13958)
		(width 0.1651)
		(layer "In13.Cu")
		(net "TDR_DIFF_85_IN5_DIP")
	)
	(segment
		(start 75.499722 -439.311288)
		(end 75.499722 -439.812684)
		(width 0.1651)
		(layer "In13.Cu")
		(net "TDR_DIFF_85_IN5_DIP")
	)
	(segment
		(start 62.591442 -439.311288)
		(end 62.921642 -438.981088)
		(width 0.1651)
		(layer "In13.Cu")
		(net "TDR_DIFF_85_IN5_DIP")
	)
	(segment
		(start 23.991062 -441.63488)
		(end 24.486362 -441.13958)
		(width 0.1651)
		(layer "In13.Cu")
		(net "TDR_DIFF_85_IN5_DIP")
	)
	(segment
		(start 21.885402 -438.981088)
		(end 22.408642 -438.981088)
		(width 0.1651)
		(layer "In13.Cu")
		(net "TDR_DIFF_85_IN5_DIP")
	)
	(segment
		(start 46.683422 -441.63488)
		(end 47.440342 -441.63488)
		(width 0.1651)
		(layer "In13.Cu")
		(net "TDR_DIFF_85_IN5_DIP")
	)
	(segment
		(start 18.128742 -441.63488)
		(end 18.624042 -441.13958)
		(width 0.1651)
		(layer "In13.Cu")
		(net "TDR_DIFF_85_IN5_DIP")
	)
	(segment
		(start 34.133282 -438.981088)
		(end 34.463482 -439.311288)
		(width 0.1651)
		(layer "In13.Cu")
		(net "TDR_DIFF_85_IN5_DIP")
	)
	(segment
		(start 68.453762 -441.13958)
		(end 68.453762 -439.311288)
		(width 0.1651)
		(layer "In13.Cu")
		(net "TDR_DIFF_85_IN5_DIP")
	)
	(segment
		(start 56.729122 -441.13958)
		(end 56.729122 -439.311288)
		(width 0.1651)
		(layer "In13.Cu")
		(net "TDR_DIFF_85_IN5_DIP")
	)
	(segment
		(start 48.265842 -438.981088)
		(end 48.789082 -438.981088)
		(width 0.1651)
		(layer "In13.Cu")
		(net "TDR_DIFF_85_IN5_DIP")
	)
	(segment
		(start 65.852802 -438.981088)
		(end 66.376042 -438.981088)
		(width 0.1651)
		(layer "In13.Cu")
		(net "TDR_DIFF_85_IN5_DIP")
	)
	(segment
		(start 59.660282 -439.311288)
		(end 59.990482 -438.981088)
		(width 0.1651)
		(layer "In13.Cu")
		(net "TDR_DIFF_85_IN5_DIP")
	)
	(segment
		(start 29.853382 -441.63488)
		(end 30.348682 -441.13958)
		(width 0.1651)
		(layer "In13.Cu")
		(net "TDR_DIFF_85_IN5_DIP")
	)
	(segment
		(start 59.164982 -441.63488)
		(end 59.660282 -441.13958)
		(width 0.1651)
		(layer "In13.Cu")
		(net "TDR_DIFF_85_IN5_DIP")
	)
	(segment
		(start 45.004482 -439.311288)
		(end 45.334682 -438.981088)
		(width 0.1651)
		(layer "In13.Cu")
		(net "TDR_DIFF_85_IN5_DIP")
	)
	(segment
		(start 39.142162 -441.13958)
		(end 39.142162 -439.311288)
		(width 0.1651)
		(layer "In13.Cu")
		(net "TDR_DIFF_85_IN5_DIP")
	)
	(segment
		(start 51.197002 -438.981088)
		(end 51.720242 -438.981088)
		(width 0.1651)
		(layer "In13.Cu")
		(net "TDR_DIFF_85_IN5_DIP")
	)
	(segment
		(start 20.302982 -441.63488)
		(end 21.059902 -441.63488)
		(width 0.1651)
		(layer "In13.Cu")
		(net "TDR_DIFF_85_IN5_DIP")
	)
	(segment
		(start 39.142162 -439.311288)
		(end 39.472362 -438.981088)
		(width 0.1651)
		(layer "In13.Cu")
		(net "TDR_DIFF_85_IN5_DIP")
	)
	(segment
		(start 50.866802 -441.13958)
		(end 50.866802 -439.311288)
		(width 0.1651)
		(layer "In13.Cu")
		(net "TDR_DIFF_85_IN5_DIP")
	)
	(segment
		(start 72.568562 -439.311288)
		(end 72.568562 -441.13958)
		(width 0.1651)
		(layer "In13.Cu")
		(net "TDR_DIFF_85_IN5_DIP")
	)
	(segment
		(start 22.738842 -441.13958)
		(end 23.234142 -441.63488)
		(width 0.1651)
		(layer "In13.Cu")
		(net "TDR_DIFF_85_IN5_DIP")
	)
	(segment
		(start 30.348682 -439.311288)
		(end 30.678882 -438.981088)
		(width 0.1651)
		(layer "In13.Cu")
		(net "TDR_DIFF_85_IN5_DIP")
	)
	(segment
		(start 65.522602 -439.311288)
		(end 65.852802 -438.981088)
		(width 0.1651)
		(layer "In13.Cu")
		(net "TDR_DIFF_85_IN5_DIP")
	)
	(segment
		(start 62.096142 -441.63488)
		(end 62.591442 -441.13958)
		(width 0.1651)
		(layer "In13.Cu")
		(net "TDR_DIFF_85_IN5_DIP")
	)
	(segment
		(start 40.821102 -441.63488)
		(end 41.578022 -441.63488)
		(width 0.1651)
		(layer "In13.Cu")
		(net "TDR_DIFF_85_IN5_DIP")
	)
	(segment
		(start 46.188122 -439.311288)
		(end 46.188122 -441.13958)
		(width 0.1651)
		(layer "In13.Cu")
		(net "TDR_DIFF_85_IN5_DIP")
	)
	(segment
		(start 63.444882 -438.981088)
		(end 63.775082 -439.311288)
		(width 0.1651)
		(layer "In13.Cu")
		(net "TDR_DIFF_85_IN5_DIP")
	)
	(segment
		(start 47.935642 -439.311288)
		(end 48.265842 -438.981088)
		(width 0.1651)
		(layer "In13.Cu")
		(net "TDR_DIFF_85_IN5_DIP")
	)
	(segment
		(start 42.403522 -438.981088)
		(end 42.926762 -438.981088)
		(width 0.1651)
		(layer "In13.Cu")
		(net "TDR_DIFF_85_IN5_DIP")
	)
	(segment
		(start 16.546322 -440.307984)
		(end 16.876522 -440.638184)
		(width 0.1651)
		(layer "In13.Cu")
		(net "TDR_DIFF_85_IN5_DIP")
	)
	(segment
		(start 26.922222 -441.63488)
		(end 27.417522 -441.13958)
		(width 0.1651)
		(layer "In13.Cu")
		(net "TDR_DIFF_85_IN5_DIP")
	)
	(segment
		(start 63.775082 -441.13958)
		(end 64.270382 -441.63488)
		(width 0.1651)
		(layer "In13.Cu")
		(net "TDR_DIFF_85_IN5_DIP")
	)
	(segment
		(start 78.345792 -440.473084)
		(end 78.345792 -441.437014)
		(width 0.1651)
		(layer "In13.Cu")
		(net "TDR_DIFF_85_IN5_DIP")
	)
	(segment
		(start 24.816562 -438.981088)
		(end 25.339802 -438.981088)
		(width 0.1651)
		(layer "In13.Cu")
		(net "TDR_DIFF_85_IN5_DIP")
	)
	(segment
		(start 66.376042 -438.981088)
		(end 66.706242 -439.311288)
		(width 0.1651)
		(layer "In13.Cu")
		(net "TDR_DIFF_85_IN5_DIP")
	)
	(segment
		(start 33.279842 -441.13958)
		(end 33.279842 -439.311288)
		(width 0.1651)
		(layer "In13.Cu")
		(net "TDR_DIFF_85_IN5_DIP")
	)
	(segment
		(start 50.371502 -441.63488)
		(end 50.866802 -441.13958)
		(width 0.1651)
		(layer "In13.Cu")
		(net "TDR_DIFF_85_IN5_DIP")
	)
	(segment
		(start 28.601162 -441.13958)
		(end 29.096462 -441.63488)
		(width 0.1651)
		(layer "In13.Cu")
		(net "TDR_DIFF_85_IN5_DIP")
	)
	(segment
		(start 34.463482 -439.311288)
		(end 34.463482 -441.13958)
		(width 0.1651)
		(layer "In13.Cu")
		(net "TDR_DIFF_85_IN5_DIP")
	)
	(segment
		(start 43.256962 -439.311288)
		(end 43.256962 -441.13958)
		(width 0.1651)
		(layer "In13.Cu")
		(net "TDR_DIFF_85_IN5_DIP")
	)
	(segment
		(start 31.202122 -438.981088)
		(end 31.532322 -439.311288)
		(width 0.1651)
		(layer "In13.Cu")
		(net "TDR_DIFF_85_IN5_DIP")
	)
	(segment
		(start 67.958462 -441.63488)
		(end 68.453762 -441.13958)
		(width 0.1651)
		(layer "In13.Cu")
		(net "TDR_DIFF_85_IN5_DIP")
	)
	(segment
		(start 71.384922 -441.13958)
		(end 71.384922 -439.311288)
		(width 0.1651)
		(layer "In13.Cu")
		(net "TDR_DIFF_85_IN5_DIP")
	)
	(segment
		(start 62.921642 -438.981088)
		(end 63.444882 -438.981088)
		(width 0.1651)
		(layer "In13.Cu")
		(net "TDR_DIFF_85_IN5_DIP")
	)
	(segment
		(start 46.188122 -441.13958)
		(end 46.683422 -441.63488)
		(width 0.1651)
		(layer "In13.Cu")
		(net "TDR_DIFF_85_IN5_DIP")
	)
	(segment
		(start 57.582562 -438.981088)
		(end 57.912762 -439.311288)
		(width 0.1651)
		(layer "In13.Cu")
		(net "TDR_DIFF_85_IN5_DIP")
	)
	(segment
		(start 55.476902 -441.63488)
		(end 56.233822 -441.63488)
		(width 0.1651)
		(layer "In13.Cu")
		(net "TDR_DIFF_85_IN5_DIP")
	)
	(segment
		(start 16.876522 -440.638184)
		(end 16.876522 -441.13958)
		(width 0.1651)
		(layer "In13.Cu")
		(net "TDR_DIFF_85_IN5_DIP")
	)
	(segment
		(start 23.234142 -441.63488)
		(end 23.991062 -441.63488)
		(width 0.1651)
		(layer "In13.Cu")
		(net "TDR_DIFF_85_IN5_DIP")
	)
	(segment
		(start 38.646862 -441.63488)
		(end 39.142162 -441.13958)
		(width 0.1651)
		(layer "In13.Cu")
		(net "TDR_DIFF_85_IN5_DIP")
	)
	(segment
		(start 24.486362 -439.311288)
		(end 24.816562 -438.981088)
		(width 0.1651)
		(layer "In13.Cu")
		(net "TDR_DIFF_85_IN5_DIP")
	)
	(segment
		(start 75.995022 -440.307984)
		(end 78.180692 -440.307984)
		(width 0.1651)
		(layer "In13.Cu")
		(net "TDR_DIFF_85_IN5_DIP")
	)
	(segment
		(start 44.509182 -441.63488)
		(end 45.004482 -441.13958)
		(width 0.1651)
		(layer "In13.Cu")
		(net "TDR_DIFF_85_IN5_DIP")
	)
	(segment
		(start 61.339222 -441.63488)
		(end 62.096142 -441.63488)
		(width 0.1651)
		(layer "In13.Cu")
		(net "TDR_DIFF_85_IN5_DIP")
	)
	(segment
		(start 53.797962 -441.13958)
		(end 53.797962 -439.311288)
		(width 0.1651)
		(layer "In13.Cu")
		(net "TDR_DIFF_85_IN5_DIP")
	)
	(segment
		(start 19.807682 -439.311288)
		(end 19.807682 -441.13958)
		(width 0.1651)
		(layer "In13.Cu")
		(net "TDR_DIFF_85_IN5_DIP")
	)
	(segment
		(start 36.211002 -439.311288)
		(end 36.541202 -438.981088)
		(width 0.1651)
		(layer "In13.Cu")
		(net "TDR_DIFF_85_IN5_DIP")
	)
	(segment
		(start 18.624042 -439.311288)
		(end 18.954242 -438.981088)
		(width 0.1651)
		(layer "In13.Cu")
		(net "TDR_DIFF_85_IN5_DIP")
	)
	(segment
		(start 41.578022 -441.63488)
		(end 42.073322 -441.13958)
		(width 0.1651)
		(layer "In13.Cu")
		(net "TDR_DIFF_85_IN5_DIP")
	)
	(segment
		(start 27.417522 -439.311288)
		(end 27.747722 -438.981088)
		(width 0.1651)
		(layer "In13.Cu")
		(net "TDR_DIFF_85_IN5_DIP")
	)
	(segment
		(start 54.981602 -439.311288)
		(end 54.981602 -441.13958)
		(width 0.1651)
		(layer "In13.Cu")
		(net "TDR_DIFF_85_IN5_DIP")
	)
	(segment
		(start 47.935642 -441.13958)
		(end 47.935642 -439.311288)
		(width 0.1651)
		(layer "In13.Cu")
		(net "TDR_DIFF_85_IN5_DIP")
	)
	(segment
		(start 67.201542 -441.63488)
		(end 67.958462 -441.63488)
		(width 0.1651)
		(layer "In13.Cu")
		(net "TDR_DIFF_85_IN5_DIP")
	)
	(segment
		(start 58.408062 -441.63488)
		(end 59.164982 -441.63488)
		(width 0.1651)
		(layer "In13.Cu")
		(net "TDR_DIFF_85_IN5_DIP")
	)
	(segment
		(start 49.119282 -439.311288)
		(end 49.119282 -441.13958)
		(width 0.1651)
		(layer "In13.Cu")
		(net "TDR_DIFF_85_IN5_DIP")
	)
	(segment
		(start 73.063862 -441.63488)
		(end 73.820782 -441.63488)
		(width 0.1651)
		(layer "In13.Cu")
		(net "TDR_DIFF_85_IN5_DIP")
	)
	(segment
		(start 31.532322 -439.311288)
		(end 31.532322 -441.13958)
		(width 0.1651)
		(layer "In13.Cu")
		(net "TDR_DIFF_85_IN5_DIP")
	)
	(segment
		(start 78.180692 -440.307984)
		(end 78.345792 -440.473084)
		(width 0.1651)
		(layer "In13.Cu")
		(net "TDR_DIFF_85_IN5_DIP")
	)
	(segment
		(start 14.477492 -440.307984)
		(end 16.546322 -440.307984)
		(width 0.1651)
		(layer "In13.Cu")
		(net "TDR_DIFF_85_IN5_DIP")
	)
	(segment
		(start 53.797962 -439.311288)
		(end 54.128162 -438.981088)
		(width 0.1651)
		(layer "In13.Cu")
		(net "TDR_DIFF_85_IN5_DIP")
	)
	(segment
		(start 17.371822 -441.63488)
		(end 18.128742 -441.63488)
		(width 0.1651)
		(layer "In13.Cu")
		(net "TDR_DIFF_85_IN5_DIP")
	)
	(segment
		(start 42.926762 -438.981088)
		(end 43.256962 -439.311288)
		(width 0.1651)
		(layer "In13.Cu")
		(net "TDR_DIFF_85_IN5_DIP")
	)
	(segment
		(start 75.169522 -438.981088)
		(end 75.499722 -439.311288)
		(width 0.1651)
		(layer "In13.Cu")
		(net "TDR_DIFF_85_IN5_DIP")
	)
	(segment
		(start 54.981602 -441.13958)
		(end 55.476902 -441.63488)
		(width 0.1651)
		(layer "In13.Cu")
		(net "TDR_DIFF_85_IN5_DIP")
	)
	(segment
		(start 45.857922 -438.981088)
		(end 46.188122 -439.311288)
		(width 0.1651)
		(layer "In13.Cu")
		(net "TDR_DIFF_85_IN5_DIP")
	)
	(segment
		(start 43.256962 -441.13958)
		(end 43.752262 -441.63488)
		(width 0.1651)
		(layer "In13.Cu")
		(net "TDR_DIFF_85_IN5_DIP")
	)
	(segment
		(start 36.541202 -438.981088)
		(end 37.064442 -438.981088)
		(width 0.1651)
		(layer "In13.Cu")
		(net "TDR_DIFF_85_IN5_DIP")
	)
	(segment
		(start 74.316082 -441.13958)
		(end 74.316082 -439.311288)
		(width 0.1651)
		(layer "In13.Cu")
		(net "TDR_DIFF_85_IN5_DIP")
	)
	(segment
		(start 52.050442 -441.13958)
		(end 52.545742 -441.63488)
		(width 0.1651)
		(layer "In13.Cu")
		(net "TDR_DIFF_85_IN5_DIP")
	)
	(segment
		(start 53.302662 -441.63488)
		(end 53.797962 -441.13958)
		(width 0.1651)
		(layer "In13.Cu")
		(net "TDR_DIFF_85_IN5_DIP")
	)
	(segment
		(start 25.339802 -438.981088)
		(end 25.670002 -439.311288)
		(width 0.1651)
		(layer "In13.Cu")
		(net "TDR_DIFF_85_IN5_DIP")
	)
	(segment
		(start 21.059902 -441.63488)
		(end 21.555202 -441.13958)
		(width 0.1651)
		(layer "In13.Cu")
		(net "TDR_DIFF_85_IN5_DIP")
	)
	(segment
		(start 65.027302 -441.63488)
		(end 65.522602 -441.13958)
		(width 0.1651)
		(layer "In13.Cu")
		(net "TDR_DIFF_85_IN5_DIP")
	)
	(segment
		(start 47.440342 -441.63488)
		(end 47.935642 -441.13958)
		(width 0.1651)
		(layer "In13.Cu")
		(net "TDR_DIFF_85_IN5_DIP")
	)
	(segment
		(start 22.408642 -438.981088)
		(end 22.738842 -439.311288)
		(width 0.1651)
		(layer "In13.Cu")
		(net "TDR_DIFF_85_IN5_DIP")
	)
	(segment
		(start 57.059322 -438.981088)
		(end 57.582562 -438.981088)
		(width 0.1651)
		(layer "In13.Cu")
		(net "TDR_DIFF_85_IN5_DIP")
	)
	(segment
		(start 57.912762 -439.311288)
		(end 57.912762 -441.13958)
		(width 0.1651)
		(layer "In13.Cu")
		(net "TDR_DIFF_85_IN5_DIP")
	)
	(segment
		(start 52.050442 -439.311288)
		(end 52.050442 -441.13958)
		(width 0.1651)
		(layer "In13.Cu")
		(net "TDR_DIFF_85_IN5_DIP")
	)
	(segment
		(start 40.325802 -441.13958)
		(end 40.821102 -441.63488)
		(width 0.1651)
		(layer "In13.Cu")
		(net "TDR_DIFF_85_IN5_DIP")
	)
	(segment
		(start 30.348682 -441.13958)
		(end 30.348682 -439.311288)
		(width 0.1651)
		(layer "In13.Cu")
		(net "TDR_DIFF_85_IN5_DIP")
	)
	(segment
		(start 34.958782 -441.63488)
		(end 35.715702 -441.63488)
		(width 0.1651)
		(layer "In13.Cu")
		(net "TDR_DIFF_85_IN5_DIP")
	)
	(segment
		(start 49.614582 -441.63488)
		(end 50.371502 -441.63488)
		(width 0.1651)
		(layer "In13.Cu")
		(net "TDR_DIFF_85_IN5_DIP")
	)
	(segment
		(start 73.820782 -441.63488)
		(end 74.316082 -441.13958)
		(width 0.1651)
		(layer "In13.Cu")
		(net "TDR_DIFF_85_IN5_DIP")
	)
	(segment
		(start 69.307202 -438.981088)
		(end 69.637402 -439.311288)
		(width 0.1651)
		(layer "In13.Cu")
		(net "TDR_DIFF_85_IN5_DIP")
	)
	(segment
		(start 24.486362 -441.13958)
		(end 24.486362 -439.311288)
		(width 0.1651)
		(layer "In13.Cu")
		(net "TDR_DIFF_85_IN5_DIP")
	)
	(segment
		(start 60.843922 -439.311288)
		(end 60.843922 -441.13958)
		(width 0.1651)
		(layer "In13.Cu")
		(net "TDR_DIFF_85_IN5_DIP")
	)
	(segment
		(start 19.477482 -438.981088)
		(end 19.807682 -439.311288)
		(width 0.1651)
		(layer "In13.Cu")
		(net "TDR_DIFF_85_IN5_DIP")
	)
	(segment
		(start 14.312392 -441.437014)
		(end 14.312392 -440.473084)
		(width 0.1651)
		(layer "In13.Cu")
		(net "TDR_DIFF_85_IN5_DIP")
	)
	(segment
		(start 31.532322 -441.13958)
		(end 32.027622 -441.63488)
		(width 0.1651)
		(layer "In13.Cu")
		(net "TDR_DIFF_85_IN5_DIP")
	)
	(segment
		(start 74.646282 -438.981088)
		(end 75.169522 -438.981088)
		(width 0.1651)
		(layer "In13.Cu")
		(net "TDR_DIFF_85_IN5_DIP")
	)
	(segment
		(start 345.632278 -280.84907)
		(end 345.632278 -281.989276)
		(width 0.2286)
		(layer "F.Cu")
		(net "SW_P0V8_PEX2_BOOT2")
	)
	(segment
		(start 345.632278 -281.989276)
		(end 345.622372 -281.999182)
		(width 0.2286)
		(layer "F.Cu")
		(net "SW_P0V8_PEX2_BOOT2")
	)
	(segment
		(start 347.889068 -280.530046)
		(end 347.889068 -280.50109)
		(width 0.1524)
		(layer "F.Cu")
		(net "P0V8_PEX2_LSET2")
	)
	(segment
		(start 347.422216 -281.657298)
		(end 347.889068 -280.530046)
		(width 0.1524)
		(layer "F.Cu")
		(net "P0V8_PEX2_LSET2")
	)
	(segment
		(start 347.422216 -281.999182)
		(end 347.422216 -281.657298)
		(width 0.1524)
		(layer "F.Cu")
		(net "P0V8_PEX2_LSET2")
	)
	(segment
		(start 347.683836 -280.295858)
		(end 347.889068 -280.50109)
		(width 0.1524)
		(layer "F.Cu")
		(net "P0V8_PEX2_LSET2")
	)
	(segment
		(start 347.683836 -279.886918)
		(end 347.683836 -280.295858)
		(width 0.1524)
		(layer "F.Cu")
		(net "P0V8_PEX2_LSET2")
	)
	(via
		(at 347.889068 -280.50109)
		(size 0.508)
		(drill 0.254)
		(layers "F.Cu" "B.Cu")
		(net "P0V8_PEX2_LSET2")
	)
	(segment
		(start 212.522054 -199.095106)
		(end 211.49564 -199.095106)
		(width 0.3556)
		(layer "F.Cu")
		(net "P1V2_AUX")
	)
	(segment
		(start 212.522054 -203.667106)
		(end 211.49564 -203.667106)
		(width 0.3556)
		(layer "F.Cu")
		(net "P1V2_AUX")
	)
	(segment
		(start 210.03895 -206.375)
		(end 210.03895 -207.391)
		(width 0.381)
		(layer "F.Cu")
		(net "P1V2_AUX")
	)
	(segment
		(start 209.423 -202.311)
		(end 209.53095 -202.311)
		(width 0.381)
		(layer "F.Cu")
		(net "P1V2_AUX")
	)
	(segment
		(start 210.03895 -198.247)
		(end 210.03895 -197.231)
		(width 0.381)
		(layer "F.Cu")
		(net "P1V2_AUX")
	)
	(segment
		(start 211.49564 -199.095106)
		(end 211.327746 -199.263)
		(width 0.3556)
		(layer "F.Cu")
		(net "P1V2_AUX")
	)
	(segment
		(start 210.03895 -192.659)
		(end 209.677 -192.659)
		(width 0.381)
		(layer "F.Cu")
		(net "P1V2_AUX")
	)
	(segment
		(start 213.535006 -215.26246)
		(end 212.900006 -215.26246)
		(width 0.4572)
		(layer "F.Cu")
		(net "P1V2_AUX")
	)
	(segment
		(start 209.677 -192.659)
		(end 209.423 -192.913)
		(width 0.381)
		(layer "F.Cu")
		(net "P1V2_AUX")
	)
	(segment
		(start 213.42604 -217.262964)
		(end 213.433406 -217.27033)
		(width 0.4572)
		(layer "F.Cu")
		(net "P1V2_AUX")
	)
	(segment
		(start 34.558224 -215.413844)
		(end 21.937218 -215.413844)
		(width 0.508)
		(layer "F.Cu")
		(net "P1V2_AUX")
	)
	(segment
		(start 213.535006 -214.32266)
		(end 213.535006 -215.26246)
		(width 0.4572)
		(layer "F.Cu")
		(net "P1V2_AUX")
	)
	(segment
		(start 210.03895 -201.803)
		(end 210.03895 -202.819)
		(width 0.381)
		(layer "F.Cu")
		(net "P1V2_AUX")
	)
	(segment
		(start 211.327746 -208.407)
		(end 210.83905 -208.407)
		(width 0.3556)
		(layer "F.Cu")
		(net "P1V2_AUX")
	)
	(segment
		(start 211.327746 -199.263)
		(end 210.83905 -199.263)
		(width 0.3556)
		(layer "F.Cu")
		(net "P1V2_AUX")
	)
	(segment
		(start 212.522054 -194.523106)
		(end 211.49564 -194.523106)
		(width 0.3556)
		(layer "F.Cu")
		(net "P1V2_AUX")
	)
	(segment
		(start 211.49564 -208.239106)
		(end 211.327746 -208.407)
		(width 0.3556)
		(layer "F.Cu")
		(net "P1V2_AUX")
	)
	(segment
		(start 213.322154 -219.385896)
		(end 213.401148 -219.306902)
		(width 0.3556)
		(layer "F.Cu")
		(net "P1V2_AUX")
	)
	(segment
		(start 228.267768 -216.704164)
		(end 227.867972 -216.304368)
		(width 0.381)
		(layer "F.Cu")
		(net "P1V2_AUX")
	)
	(segment
		(start 232.26776 -217.504264)
		(end 232.667556 -217.104468)
		(width 0.381)
		(layer "F.Cu")
		(net "P1V2_AUX")
	)
	(segment
		(start 212.644482 -217.263218)
		(end 212.644736 -217.262964)
		(width 0.4572)
		(layer "F.Cu")
		(net "P1V2_AUX")
	)
	(segment
		(start 226.667568 -219.10421)
		(end 226.267772 -219.504006)
		(width 0.381)
		(layer "F.Cu")
		(net "P1V2_AUX")
	)
	(segment
		(start 41.89857 -222.75419)
		(end 34.558224 -215.413844)
		(width 0.508)
		(layer "F.Cu")
		(net "P1V2_AUX")
	)
	(segment
		(start 212.486748 -219.385896)
		(end 213.322154 -219.385896)
		(width 0.3556)
		(layer "F.Cu")
		(net "P1V2_AUX")
	)
	(segment
		(start 210.83905 -203.835)
		(end 210.83905 -204.47)
		(width 0.4572)
		(layer "F.Cu")
		(net "P1V2_AUX")
	)
	(segment
		(start 213.433406 -216.284556)
		(end 213.419436 -216.270586)
		(width 0.4572)
		(layer "F.Cu")
		(net "P1V2_AUX")
	)
	(segment
		(start 209.423 -206.883)
		(end 209.423 -206.629)
		(width 0.381)
		(layer "F.Cu")
		(net "P1V2_AUX")
	)
	(segment
		(start 249.333512 -211.622386)
		(end 248.717562 -211.622386)
		(width 0.4572)
		(layer "F.Cu")
		(net "P1V2_AUX")
	)
	(segment
		(start 226.667568 -218.30411)
		(end 226.267772 -217.904314)
		(width 0.381)
		(layer "F.Cu")
		(net "P1V2_AUX")
	)
	(segment
		(start 211.49564 -194.523106)
		(end 211.327746 -194.691)
		(width 0.3556)
		(layer "F.Cu")
		(net "P1V2_AUX")
	)
	(segment
		(start 213.401148 -220.322902)
		(end 213.401148 -219.306902)
		(width 0.4572)
		(layer "F.Cu")
		(net "P1V2_AUX")
	)
	(segment
		(start 212.644736 -217.262964)
		(end 213.42604 -217.262964)
		(width 0.4572)
		(layer "F.Cu")
		(net "P1V2_AUX")
	)
	(segment
		(start 232.26776 -218.30411)
		(end 232.667556 -217.904314)
		(width 0.381)
		(layer "F.Cu")
		(net "P1V2_AUX")
	)
	(segment
		(start 42.851578 -263.697466)
		(end 41.89857 -262.744458)
		(width 0.508)
		(layer "F.Cu")
		(net "P1V2_AUX")
	)
	(segment
		(start 41.450514 -270.589502)
		(end 42.851578 -269.188438)
		(width 0.508)
		(layer "F.Cu")
		(net "P1V2_AUX")
	)
	(segment
		(start 209.677 -206.375)
		(end 210.03895 -206.375)
		(width 0.381)
		(layer "F.Cu")
		(net "P1V2_AUX")
	)
	(segment
		(start 209.423 -192.913)
		(end 209.423 -193.167)
		(width 0.381)
		(layer "F.Cu")
		(net "P1V2_AUX")
	)
	(segment
		(start 240.75263 -223.066864)
		(end 241.270536 -223.066864)
		(width 0.4572)
		(layer "F.Cu")
		(net "P1V2_AUX")
	)
	(segment
		(start 229.067614 -216.704164)
		(end 228.667818 -216.304368)
		(width 0.381)
		(layer "F.Cu")
		(net "P1V2_AUX")
	)
	(segment
		(start 231.46766 -221.504256)
		(end 231.867456 -221.904052)
		(width 0.381)
		(layer "F.Cu")
		(net "P1V2_AUX")
	)
	(segment
		(start 212.644482 -217.286586)
		(end 212.644482 -217.263218)
		(width 0.4572)
		(layer "F.Cu")
		(net "P1V2_AUX")
	)
	(segment
		(start 209.677 -197.231)
		(end 209.423 -197.485)
		(width 0.381)
		(layer "F.Cu")
		(net "P1V2_AUX")
	)
	(segment
		(start 212.44687 -219.346018)
		(end 212.486748 -219.385896)
		(width 0.3556)
		(layer "F.Cu")
		(net "P1V2_AUX")
	)
	(segment
		(start 210.03895 -193.675)
		(end 210.03895 -192.659)
		(width 0.381)
		(layer "F.Cu")
		(net "P1V2_AUX")
	)
	(segment
		(start 209.423 -197.485)
		(end 209.423 -197.739)
		(width 0.381)
		(layer "F.Cu")
		(net "P1V2_AUX")
	)
	(segment
		(start 229.867714 -222.304102)
		(end 230.26751 -222.703898)
		(width 0.381)
		(layer "F.Cu")
		(net "P1V2_AUX")
	)
	(segment
		(start 209.423 -206.629)
		(end 209.677 -206.375)
		(width 0.381)
		(layer "F.Cu")
		(net "P1V2_AUX")
	)
	(segment
		(start 211.327746 -194.691)
		(end 210.83905 -194.691)
		(width 0.3556)
		(layer "F.Cu")
		(net "P1V2_AUX")
	)
	(segment
		(start 229.867714 -216.704164)
		(end 230.26751 -216.304368)
		(width 0.381)
		(layer "F.Cu")
		(net "P1V2_AUX")
	)
	(segment
		(start 209.53095 -202.311)
		(end 210.03895 -201.803)
		(width 0.381)
		(layer "F.Cu")
		(net "P1V2_AUX")
	)
	(segment
		(start 229.067614 -222.304102)
		(end 228.667818 -222.703898)
		(width 0.381)
		(layer "F.Cu")
		(net "P1V2_AUX")
	)
	(segment
		(start 210.83905 -194.691)
		(end 210.83905 -195.326)
		(width 0.4572)
		(layer "F.Cu")
		(net "P1V2_AUX")
	)
	(segment
		(start 226.667568 -219.904056)
		(end 226.267772 -220.303852)
		(width 0.381)
		(layer "F.Cu")
		(net "P1V2_AUX")
	)
	(segment
		(start 210.83905 -208.407)
		(end 210.83905 -209.042)
		(width 0.4572)
		(layer "F.Cu")
		(net "P1V2_AUX")
	)
	(segment
		(start 214.054436 -216.270586)
		(end 213.419436 -216.270586)
		(width 0.4572)
		(layer "F.Cu")
		(net "P1V2_AUX")
	)
	(segment
		(start 212.522054 -208.239106)
		(end 211.49564 -208.239106)
		(width 0.3556)
		(layer "F.Cu")
		(net "P1V2_AUX")
	)
	(segment
		(start 211.327746 -203.835)
		(end 210.83905 -203.835)
		(width 0.3556)
		(layer "F.Cu")
		(net "P1V2_AUX")
	)
	(segment
		(start 241.270536 -223.066864)
		(end 241.3762 -222.9612)
		(width 0.4572)
		(layer "F.Cu")
		(net "P1V2_AUX")
	)
	(segment
		(start 210.03895 -197.231)
		(end 209.677 -197.231)
		(width 0.381)
		(layer "F.Cu")
		(net "P1V2_AUX")
	)
	(segment
		(start 211.49564 -203.667106)
		(end 211.327746 -203.835)
		(width 0.3556)
		(layer "F.Cu")
		(net "P1V2_AUX")
	)
	(segment
		(start 41.89857 -262.744458)
		(end 41.89857 -222.75419)
		(width 0.508)
		(layer "F.Cu")
		(net "P1V2_AUX")
	)
	(segment
		(start 210.83905 -199.263)
		(end 210.83905 -199.898)
		(width 0.4572)
		(layer "F.Cu")
		(net "P1V2_AUX")
	)
	(segment
		(start 42.851578 -269.188438)
		(end 42.851578 -263.697466)
		(width 0.508)
		(layer "F.Cu")
		(net "P1V2_AUX")
	)
	(segment
		(start 213.433406 -217.27033)
		(end 213.433406 -216.284556)
		(width 0.4572)
		(layer "F.Cu")
		(net "P1V2_AUX")
	)
	(segment
		(start 213.401148 -220.322902)
		(end 212.597746 -220.322902)
		(width 0.4572)
		(layer "F.Cu")
		(net "P1V2_AUX")
	)
	(via
		(at 226.267772 -217.904314)
		(size 0.4572)
		(drill 0.254)
		(layers "F.Cu" "B.Cu")
		(net "P1V2_AUX")
	)
	(via
		(at 239.851438 -213.35365)
		(size 0.508)
		(drill 0.254)
		(layers "F.Cu" "B.Cu")
		(net "P1V2_AUX")
	)
	(via
		(at 212.597746 -220.322902)
		(size 0.508)
		(drill 0.254)
		(layers "F.Cu" "B.Cu")
		(net "P1V2_AUX")
	)
	(via
		(at 212.900006 -215.26246)
		(size 0.508)
		(drill 0.254)
		(layers "F.Cu" "B.Cu")
		(net "P1V2_AUX")
	)
	(via
		(at 209.423 -202.311)
		(size 0.508)
		(drill 0.254)
		(layers "F.Cu" "B.Cu")
		(net "P1V2_AUX")
	)
	(via
		(at 213.419436 -216.270586)
		(size 0.508)
		(drill 0.254)
		(layers "F.Cu" "B.Cu")
		(net "P1V2_AUX")
	)
	(via
		(at 207.772 -202.438)
		(size 0.508)
		(drill 0.254)
		(layers "F.Cu" "B.Cu")
		(net "P1V2_AUX")
	)
	(via
		(at 241.671094 -206.304642)
		(size 0.508)
		(drill 0.254)
		(layers "F.Cu" "B.Cu")
		(net "P1V2_AUX")
	)
	(via
		(at 248.717562 -211.622386)
		(size 0.508)
		(drill 0.254)
		(layers "F.Cu" "B.Cu")
		(net "P1V2_AUX")
	)
	(via
		(at 230.26751 -222.703898)
		(size 0.4572)
		(drill 0.254)
		(layers "F.Cu" "B.Cu")
		(net "P1V2_AUX")
	)
	(via
		(at 241.3762 -222.9612)
		(size 0.508)
		(drill 0.254)
		(layers "F.Cu" "B.Cu")
		(net "P1V2_AUX")
	)
	(via
		(at 250.7488 -215.63076)
		(size 0.508)
		(drill 0.254)
		(layers "F.Cu" "B.Cu")
		(net "P1V2_AUX")
	)
	(via
		(at 250.749308 -214.98433)
		(size 0.508)
		(drill 0.254)
		(layers "F.Cu" "B.Cu")
		(net "P1V2_AUX")
	)
	(via
		(at 210.83905 -204.47)
		(size 0.508)
		(drill 0.254)
		(layers "F.Cu" "B.Cu")
		(net "P1V2_AUX")
	)
	(via
		(at 241.733832 -207.999076)
		(size 0.508)
		(drill 0.254)
		(layers "F.Cu" "B.Cu")
		(net "P1V2_AUX")
	)
	(via
		(at 230.26751 -216.304368)
		(size 0.4572)
		(drill 0.254)
		(layers "F.Cu" "B.Cu")
		(net "P1V2_AUX")
	)
	(via
		(at 237.521496 -211.171028)
		(size 0.508)
		(drill 0.254)
		(layers "F.Cu" "B.Cu")
		(net "P1V2_AUX")
	)
	(via
		(at 209.423 -206.883)
		(size 0.508)
		(drill 0.254)
		(layers "F.Cu" "B.Cu")
		(net "P1V2_AUX")
	)
	(via
		(at 41.450514 -270.589502)
		(size 0.508)
		(drill 0.254)
		(layers "F.Cu" "B.Cu")
		(net "P1V2_AUX")
	)
	(via
		(at 232.667556 -217.104468)
		(size 0.4572)
		(drill 0.254)
		(layers "F.Cu" "B.Cu")
		(net "P1V2_AUX")
	)
	(via
		(at 210.83905 -199.898)
		(size 0.508)
		(drill 0.254)
		(layers "F.Cu" "B.Cu")
		(net "P1V2_AUX")
	)
	(via
		(at 14.844522 -323.153278)
		(size 0.508)
		(drill 0.254)
		(layers "F.Cu" "B.Cu")
		(net "P1V2_AUX")
	)
	(via
		(at 226.267772 -220.303852)
		(size 0.4572)
		(drill 0.254)
		(layers "F.Cu" "B.Cu")
		(net "P1V2_AUX")
	)
	(via
		(at 251.4092 -214.3506)
		(size 0.508)
		(drill 0.254)
		(layers "F.Cu" "B.Cu")
		(net "P1V2_AUX")
	)
	(via
		(at 228.667818 -216.304368)
		(size 0.4572)
		(drill 0.254)
		(layers "F.Cu" "B.Cu")
		(net "P1V2_AUX")
	)
	(via
		(at 210.83905 -195.326)
		(size 0.508)
		(drill 0.254)
		(layers "F.Cu" "B.Cu")
		(net "P1V2_AUX")
	)
	(via
		(at 250.779026 -214.271606)
		(size 0.508)
		(drill 0.254)
		(layers "F.Cu" "B.Cu")
		(net "P1V2_AUX")
	)
	(via
		(at 228.667818 -222.703898)
		(size 0.4572)
		(drill 0.254)
		(layers "F.Cu" "B.Cu")
		(net "P1V2_AUX")
	)
	(via
		(at 231.867456 -221.904052)
		(size 0.4572)
		(drill 0.254)
		(layers "F.Cu" "B.Cu")
		(net "P1V2_AUX")
	)
	(via
		(at 209.423 -197.739)
		(size 0.508)
		(drill 0.254)
		(layers "F.Cu" "B.Cu")
		(net "P1V2_AUX")
	)
	(via
		(at 21.937218 -215.413844)
		(size 0.508)
		(drill 0.254)
		(layers "F.Cu" "B.Cu")
		(net "P1V2_AUX")
	)
	(via
		(at 226.267772 -219.504006)
		(size 0.4572)
		(drill 0.254)
		(layers "F.Cu" "B.Cu")
		(net "P1V2_AUX")
	)
	(via
		(at 251.3838 -215.011)
		(size 0.508)
		(drill 0.254)
		(layers "F.Cu" "B.Cu")
		(net "P1V2_AUX")
	)
	(via
		(at 209.423 -193.167)
		(size 0.508)
		(drill 0.254)
		(layers "F.Cu" "B.Cu")
		(net "P1V2_AUX")
	)
	(via
		(at 232.667556 -217.904314)
		(size 0.4572)
		(drill 0.254)
		(layers "F.Cu" "B.Cu")
		(net "P1V2_AUX")
	)
	(via
		(at 238.941864 -213.378796)
		(size 0.508)
		(drill 0.254)
		(layers "F.Cu" "B.Cu")
		(net "P1V2_AUX")
	)
	(via
		(at 212.644482 -217.286586)
		(size 0.508)
		(drill 0.254)
		(layers "F.Cu" "B.Cu")
		(net "P1V2_AUX")
	)
	(via
		(at 210.83905 -209.042)
		(size 0.508)
		(drill 0.254)
		(layers "F.Cu" "B.Cu")
		(net "P1V2_AUX")
	)
	(via
		(at 227.867972 -216.304368)
		(size 0.4572)
		(drill 0.254)
		(layers "F.Cu" "B.Cu")
		(net "P1V2_AUX")
	)
	(via
		(at 241.754914 -205.262734)
		(size 0.508)
		(drill 0.254)
		(layers "F.Cu" "B.Cu")
		(net "P1V2_AUX")
	)
	(via
		(at 19.744436 -278.301704)
		(size 0.508)
		(drill 0.254)
		(layers "F.Cu" "B.Cu")
		(net "P1V2_AUX")
	)
	(segment
		(start 17.304004 -394.038582)
		(end 13.548106 -394.038582)
		(width 0.508)
		(layer "B.Cu")
		(net "P1V2_AUX")
	)
	(segment
		(start 13.548106 -394.038582)
		(end 12.964922 -393.455398)
		(width 0.508)
		(layer "B.Cu")
		(net "P1V2_AUX")
	)
	(segment
		(start 229.867714 -222.304102)
		(end 230.26751 -222.703898)
		(width 0.3048)
		(layer "B.Cu")
		(net "P1V2_AUX")
	)
	(segment
		(start 12.964922 -393.455398)
		(end 12.964922 -392.135106)
		(width 0.508)
		(layer "B.Cu")
		(net "P1V2_AUX")
	)
	(segment
		(start 232.667556 -217.904314)
		(end 232.26776 -218.30411)
		(width 0.3048)
		(layer "B.Cu")
		(net "P1V2_AUX")
	)
	(segment
		(start 212.644482 -217.779092)
		(end 212.644482 -217.286586)
		(width 0.4572)
		(layer "B.Cu")
		(net "P1V2_AUX")
	)
	(segment
		(start 18.943574 -392.399012)
		(end 17.304004 -394.038582)
		(width 0.508)
		(layer "B.Cu")
		(net "P1V2_AUX")
	)
	(segment
		(start 18.943574 -357.241856)
		(end 18.943574 -392.399012)
		(width 0.508)
		(layer "B.Cu")
		(net "P1V2_AUX")
	)
	(segment
		(start 213.432644 -217.270838)
		(end 213.416896 -217.286586)
		(width 0.4572)
		(layer "B.Cu")
		(net "P1V2_AUX")
	)
	(segment
		(start 228.667818 -216.304368)
		(end 229.067614 -216.704164)
		(width 0.3048)
		(layer "B.Cu")
		(net "P1V2_AUX")
	)
	(segment
		(start 237.521496 -211.932774)
		(end 237.521496 -211.171028)
		(width 0.4572)
		(layer "B.Cu")
		(net "P1V2_AUX")
	)
	(segment
		(start 213.416896 -217.286586)
		(end 212.644482 -217.286586)
		(width 0.4572)
		(layer "B.Cu")
		(net "P1V2_AUX")
	)
	(segment
		(start 14.844522 -323.153278)
		(end 14.844522 -353.142804)
		(width 0.508)
		(layer "B.Cu")
		(net "P1V2_AUX")
	)
	(segment
		(start 226.667568 -218.30411)
		(end 226.267772 -217.904314)
		(width 0.3048)
		(layer "B.Cu")
		(net "P1V2_AUX")
	)
	(segment
		(start 229.067614 -222.304102)
		(end 228.667818 -222.703898)
		(width 0.3048)
		(layer "B.Cu")
		(net "P1V2_AUX")
	)
	(segment
		(start 212.507576 -217.915998)
		(end 212.644482 -217.779092)
		(width 0.4572)
		(layer "B.Cu")
		(net "P1V2_AUX")
	)
	(segment
		(start 226.667568 -219.10421)
		(end 226.267772 -219.504006)
		(width 0.3048)
		(layer "B.Cu")
		(net "P1V2_AUX")
	)
	(segment
		(start 14.844522 -353.142804)
		(end 18.943574 -357.241856)
		(width 0.508)
		(layer "B.Cu")
		(net "P1V2_AUX")
	)
	(segment
		(start 16.379444 -299.912024)
		(end 19.744436 -296.547032)
		(width 0.508)
		(layer "In5.Cu")
		(net "P1V2_AUX")
	)
	(segment
		(start 18.171414 -307.38572)
		(end 16.379444 -305.59375)
		(width 0.508)
		(layer "In5.Cu")
		(net "P1V2_AUX")
	)
	(segment
		(start 18.171414 -308.043834)
		(end 18.171414 -307.38572)
		(width 0.508)
		(layer "In5.Cu")
		(net "P1V2_AUX")
	)
	(segment
		(start 14.844522 -320.098674)
		(end 16.846296 -315.265816)
		(width 0.508)
		(layer "In5.Cu")
		(net "P1V2_AUX")
	)
	(segment
		(start 16.846296 -309.368698)
		(end 18.171414 -308.043834)
		(width 0.508)
		(layer "In5.Cu")
		(net "P1V2_AUX")
	)
	(segment
		(start 16.846296 -315.265816)
		(end 16.846296 -309.368698)
		(width 0.508)
		(layer "In5.Cu")
		(net "P1V2_AUX")
	)
	(segment
		(start 14.844522 -323.153278)
		(end 14.844522 -320.098674)
		(width 0.508)
		(layer "In5.Cu")
		(net "P1V2_AUX")
	)
	(segment
		(start 19.744436 -296.547032)
		(end 19.744436 -278.301704)
		(width 0.508)
		(layer "In5.Cu")
		(net "P1V2_AUX")
	)
	(segment
		(start 16.379444 -305.59375)
		(end 16.379444 -299.912024)
		(width 0.508)
		(layer "In5.Cu")
		(net "P1V2_AUX")
	)
	(segment
		(start 123.918218 -186.872626)
		(end 131.582668 -194.537076)
		(width 0.508)
		(layer "In13.Cu")
		(net "P1V2_AUX")
	)
	(segment
		(start 198.893684 -190.495174)
		(end 207.626712 -190.495174)
		(width 0.508)
		(layer "In13.Cu")
		(net "P1V2_AUX")
	)
	(segment
		(start 155.281122 -200.008744)
		(end 179.055776 -200.008744)
		(width 0.508)
		(layer "In13.Cu")
		(net "P1V2_AUX")
	)
	(segment
		(start 135.834374 -191.73444)
		(end 139.781026 -191.73444)
		(width 0.508)
		(layer "In13.Cu")
		(net "P1V2_AUX")
	)
	(segment
		(start 207.626712 -190.495174)
		(end 207.888332 -190.233554)
		(width 0.508)
		(layer "In13.Cu")
		(net "P1V2_AUX")
	)
	(segment
		(start 139.781026 -191.73444)
		(end 141.382496 -193.33591)
		(width 0.508)
		(layer "In13.Cu")
		(net "P1V2_AUX")
	)
	(segment
		(start 31.98495 -264.94613)
		(end 25.33015 -264.94613)
		(width 0.508)
		(layer "In13.Cu")
		(net "P1V2_AUX")
	)
	(segment
		(start 197.673468 -191.71539)
		(end 198.893684 -190.495174)
		(width 0.508)
		(layer "In13.Cu")
		(net "P1V2_AUX")
	)
	(segment
		(start 179.055776 -200.008744)
		(end 179.970938 -199.093582)
		(width 0.508)
		(layer "In13.Cu")
		(net "P1V2_AUX")
	)
	(segment
		(start 22.451568 -267.824712)
		(end 22.451568 -275.594572)
		(width 0.508)
		(layer "In13.Cu")
		(net "P1V2_AUX")
	)
	(segment
		(start 22.451568 -275.594572)
		(end 19.744436 -278.301704)
		(width 0.508)
		(layer "In13.Cu")
		(net "P1V2_AUX")
	)
	(segment
		(start 144.490186 -192.706752)
		(end 147.97913 -192.706752)
		(width 0.508)
		(layer "In13.Cu")
		(net "P1V2_AUX")
	)
	(segment
		(start 61.716666 -201.514964)
		(end 89.924636 -201.514964)
		(width 0.508)
		(layer "In13.Cu")
		(net "P1V2_AUX")
	)
	(segment
		(start 131.582668 -194.537076)
		(end 133.031738 -194.537076)
		(width 0.508)
		(layer "In13.Cu")
		(net "P1V2_AUX")
	)
	(segment
		(start 36.799012 -269.760192)
		(end 31.98495 -264.94613)
		(width 0.508)
		(layer "In13.Cu")
		(net "P1V2_AUX")
	)
	(segment
		(start 147.97913 -192.706752)
		(end 155.281122 -200.008744)
		(width 0.508)
		(layer "In13.Cu")
		(net "P1V2_AUX")
	)
	(segment
		(start 100.829872 -188.950854)
		(end 102.9081 -186.872626)
		(width 0.508)
		(layer "In13.Cu")
		(net "P1V2_AUX")
	)
	(segment
		(start 102.9081 -186.872626)
		(end 123.918218 -186.872626)
		(width 0.508)
		(layer "In13.Cu")
		(net "P1V2_AUX")
	)
	(segment
		(start 207.888332 -190.233554)
		(end 208.965546 -190.233554)
		(width 0.508)
		(layer "In13.Cu")
		(net "P1V2_AUX")
	)
	(segment
		(start 210.13801 -191.406018)
		(end 210.13801 -192.45199)
		(width 0.508)
		(layer "In13.Cu")
		(net "P1V2_AUX")
	)
	(segment
		(start 41.450514 -270.589502)
		(end 41.450514 -270.246094)
		(width 0.508)
		(layer "In13.Cu")
		(net "P1V2_AUX")
	)
	(segment
		(start 89.924636 -201.514964)
		(end 95.282004 -196.157596)
		(width 0.508)
		(layer "In13.Cu")
		(net "P1V2_AUX")
	)
	(segment
		(start 141.382496 -193.33591)
		(end 143.861028 -193.33591)
		(width 0.508)
		(layer "In13.Cu")
		(net "P1V2_AUX")
	)
	(segment
		(start 179.970938 -196.3293)
		(end 184.584848 -191.71539)
		(width 0.508)
		(layer "In13.Cu")
		(net "P1V2_AUX")
	)
	(segment
		(start 143.861028 -193.33591)
		(end 144.490186 -192.706752)
		(width 0.508)
		(layer "In13.Cu")
		(net "P1V2_AUX")
	)
	(segment
		(start 133.031738 -194.537076)
		(end 135.834374 -191.73444)
		(width 0.508)
		(layer "In13.Cu")
		(net "P1V2_AUX")
	)
	(segment
		(start 25.33015 -264.94613)
		(end 22.451568 -267.824712)
		(width 0.508)
		(layer "In13.Cu")
		(net "P1V2_AUX")
	)
	(segment
		(start 97.855786 -196.157596)
		(end 100.829872 -193.18351)
		(width 0.508)
		(layer "In13.Cu")
		(net "P1V2_AUX")
	)
	(segment
		(start 95.282004 -196.157596)
		(end 97.855786 -196.157596)
		(width 0.508)
		(layer "In13.Cu")
		(net "P1V2_AUX")
	)
	(segment
		(start 184.584848 -191.71539)
		(end 197.673468 -191.71539)
		(width 0.508)
		(layer "In13.Cu")
		(net "P1V2_AUX")
	)
	(segment
		(start 210.13801 -192.45199)
		(end 209.423 -193.167)
		(width 0.508)
		(layer "In13.Cu")
		(net "P1V2_AUX")
	)
	(segment
		(start 28.161742 -215.413844)
		(end 61.716666 -201.514964)
		(width 0.508)
		(layer "In13.Cu")
		(net "P1V2_AUX")
	)
	(segment
		(start 208.965546 -190.233554)
		(end 210.13801 -191.406018)
		(width 0.508)
		(layer "In13.Cu")
		(net "P1V2_AUX")
	)
	(segment
		(start 40.964612 -269.760192)
		(end 36.799012 -269.760192)
		(width 0.508)
		(layer "In13.Cu")
		(net "P1V2_AUX")
	)
	(segment
		(start 179.970938 -199.093582)
		(end 179.970938 -196.3293)
		(width 0.508)
		(layer "In13.Cu")
		(net "P1V2_AUX")
	)
	(segment
		(start 100.829872 -193.18351)
		(end 100.829872 -188.950854)
		(width 0.508)
		(layer "In13.Cu")
		(net "P1V2_AUX")
	)
	(segment
		(start 41.450514 -270.246094)
		(end 40.964612 -269.760192)
		(width 0.508)
		(layer "In13.Cu")
		(net "P1V2_AUX")
	)
	(segment
		(start 21.937218 -215.413844)
		(end 28.161742 -215.413844)
		(width 0.508)
		(layer "In13.Cu")
		(net "P1V2_AUX")
	)
	(segment
		(start 123.343416 -444.396368)
		(end 124.69368 -444.396368)
		(width 0.13462)
		(layer "B.Cu")
		(net "TDR_DIFF_85_BOT_DIP")
	)
	(segment
		(start 128.994408 -447.425064)
		(end 129.263648 -447.694304)
		(width 0.13462)
		(layer "B.Cu")
		(net "TDR_DIFF_85_BOT_DIP")
	)
	(segment
		(start 122.913648 -444.826136)
		(end 123.343416 -444.396368)
		(width 0.13462)
		(layer "B.Cu")
		(net "TDR_DIFF_85_BOT_DIP")
	)
	(segment
		(start 134.956296 -444.396368)
		(end 136.30656 -444.396368)
		(width 0.13462)
		(layer "B.Cu")
		(net "TDR_DIFF_85_BOT_DIP")
	)
	(segment
		(start 97.59696 -444.396368)
		(end 98.026728 -444.826136)
		(width 0.13462)
		(layer "B.Cu")
		(net "TDR_DIFF_85_BOT_DIP")
	)
	(segment
		(start 132.865368 -447.425064)
		(end 133.134608 -447.694304)
		(width 0.13462)
		(layer "B.Cu")
		(net "TDR_DIFF_85_BOT_DIP")
	)
	(segment
		(start 144.478248 -444.826136)
		(end 144.478248 -447.425064)
		(width 0.13462)
		(layer "B.Cu")
		(net "TDR_DIFF_85_BOT_DIP")
	)
	(segment
		(start 113.510568 -447.425064)
		(end 113.779808 -447.694304)
		(width 0.13462)
		(layer "B.Cu")
		(net "TDR_DIFF_85_BOT_DIP")
	)
	(segment
		(start 100.117656 -444.396368)
		(end 101.46792 -444.396368)
		(width 0.13462)
		(layer "B.Cu")
		(net "TDR_DIFF_85_BOT_DIP")
	)
	(segment
		(start 98.295968 -447.694304)
		(end 99.418648 -447.694304)
		(width 0.13462)
		(layer "B.Cu")
		(net "TDR_DIFF_85_BOT_DIP")
	)
	(segment
		(start 140.607288 -447.425064)
		(end 140.876528 -447.694304)
		(width 0.13462)
		(layer "B.Cu")
		(net "TDR_DIFF_85_BOT_DIP")
	)
	(segment
		(start 120.82272 -444.396368)
		(end 121.252488 -444.826136)
		(width 0.13462)
		(layer "B.Cu")
		(net "TDR_DIFF_85_BOT_DIP")
	)
	(segment
		(start 91.945968 -444.826136)
		(end 92.375736 -444.396368)
		(width 0.13462)
		(layer "B.Cu")
		(net "TDR_DIFF_85_BOT_DIP")
	)
	(segment
		(start 130.386328 -447.694304)
		(end 130.655568 -447.425064)
		(width 0.13462)
		(layer "B.Cu")
		(net "TDR_DIFF_85_BOT_DIP")
	)
	(segment
		(start 138.397488 -444.826136)
		(end 138.827256 -444.396368)
		(width 0.13462)
		(layer "B.Cu")
		(net "TDR_DIFF_85_BOT_DIP")
	)
	(segment
		(start 107.429808 -447.425064)
		(end 107.429808 -444.826136)
		(width 0.13462)
		(layer "B.Cu")
		(net "TDR_DIFF_85_BOT_DIP")
	)
	(segment
		(start 103.988616 -444.396368)
		(end 105.33888 -444.396368)
		(width 0.13462)
		(layer "B.Cu")
		(net "TDR_DIFF_85_BOT_DIP")
	)
	(segment
		(start 140.607288 -444.826136)
		(end 140.607288 -447.425064)
		(width 0.13462)
		(layer "B.Cu")
		(net "TDR_DIFF_85_BOT_DIP")
	)
	(segment
		(start 105.768648 -444.826136)
		(end 105.768648 -447.425064)
		(width 0.13462)
		(layer "B.Cu")
		(net "TDR_DIFF_85_BOT_DIP")
	)
	(segment
		(start 132.865368 -444.826136)
		(end 132.865368 -447.425064)
		(width 0.13462)
		(layer "B.Cu")
		(net "TDR_DIFF_85_BOT_DIP")
	)
	(segment
		(start 128.56464 -444.396368)
		(end 128.994408 -444.826136)
		(width 0.13462)
		(layer "B.Cu")
		(net "TDR_DIFF_85_BOT_DIP")
	)
	(segment
		(start 129.263648 -447.694304)
		(end 130.386328 -447.694304)
		(width 0.13462)
		(layer "B.Cu")
		(net "TDR_DIFF_85_BOT_DIP")
	)
	(segment
		(start 134.526528 -447.425064)
		(end 134.526528 -444.826136)
		(width 0.13462)
		(layer "B.Cu")
		(net "TDR_DIFF_85_BOT_DIP")
	)
	(segment
		(start 148.349208 -445.776096)
		(end 148.618448 -446.045336)
		(width 0.13462)
		(layer "B.Cu")
		(net "TDR_DIFF_85_BOT_DIP")
	)
	(segment
		(start 122.913648 -447.425064)
		(end 122.913648 -444.826136)
		(width 0.13462)
		(layer "B.Cu")
		(net "TDR_DIFF_85_BOT_DIP")
	)
	(segment
		(start 102.166928 -447.694304)
		(end 103.289608 -447.694304)
		(width 0.13462)
		(layer "B.Cu")
		(net "TDR_DIFF_85_BOT_DIP")
	)
	(segment
		(start 96.246696 -444.396368)
		(end 97.59696 -444.396368)
		(width 0.13462)
		(layer "B.Cu")
		(net "TDR_DIFF_85_BOT_DIP")
	)
	(segment
		(start 107.160568 -447.694304)
		(end 107.429808 -447.425064)
		(width 0.13462)
		(layer "B.Cu")
		(net "TDR_DIFF_85_BOT_DIP")
	)
	(segment
		(start 87.285068 -446.045336)
		(end 89.85504 -446.045336)
		(width 0.13462)
		(layer "B.Cu")
		(net "TDR_DIFF_85_BOT_DIP")
	)
	(segment
		(start 148.349208 -444.826136)
		(end 148.349208 -445.776096)
		(width 0.13462)
		(layer "B.Cu")
		(net "TDR_DIFF_85_BOT_DIP")
	)
	(segment
		(start 142.268448 -447.425064)
		(end 142.268448 -444.826136)
		(width 0.13462)
		(layer "B.Cu")
		(net "TDR_DIFF_85_BOT_DIP")
	)
	(segment
		(start 133.134608 -447.694304)
		(end 134.257288 -447.694304)
		(width 0.13462)
		(layer "B.Cu")
		(net "TDR_DIFF_85_BOT_DIP")
	)
	(segment
		(start 95.547688 -447.694304)
		(end 95.816928 -447.425064)
		(width 0.13462)
		(layer "B.Cu")
		(net "TDR_DIFF_85_BOT_DIP")
	)
	(segment
		(start 130.655568 -444.826136)
		(end 131.085336 -444.396368)
		(width 0.13462)
		(layer "B.Cu")
		(net "TDR_DIFF_85_BOT_DIP")
	)
	(segment
		(start 119.042688 -447.425064)
		(end 119.042688 -444.826136)
		(width 0.13462)
		(layer "B.Cu")
		(net "TDR_DIFF_85_BOT_DIP")
	)
	(segment
		(start 141.999208 -447.694304)
		(end 142.268448 -447.425064)
		(width 0.13462)
		(layer "B.Cu")
		(net "TDR_DIFF_85_BOT_DIP")
	)
	(segment
		(start 90.284808 -446.475104)
		(end 90.284808 -447.425064)
		(width 0.13462)
		(layer "B.Cu")
		(net "TDR_DIFF_85_BOT_DIP")
	)
	(segment
		(start 95.816928 -444.826136)
		(end 96.246696 -444.396368)
		(width 0.13462)
		(layer "B.Cu")
		(net "TDR_DIFF_85_BOT_DIP")
	)
	(segment
		(start 95.816928 -447.425064)
		(end 95.816928 -444.826136)
		(width 0.13462)
		(layer "B.Cu")
		(net "TDR_DIFF_85_BOT_DIP")
	)
	(segment
		(start 113.0808 -444.396368)
		(end 113.510568 -444.826136)
		(width 0.13462)
		(layer "B.Cu")
		(net "TDR_DIFF_85_BOT_DIP")
	)
	(segment
		(start 117.381528 -447.425064)
		(end 117.650768 -447.694304)
		(width 0.13462)
		(layer "B.Cu")
		(net "TDR_DIFF_85_BOT_DIP")
	)
	(segment
		(start 136.736328 -444.826136)
		(end 136.736328 -447.425064)
		(width 0.13462)
		(layer "B.Cu")
		(net "TDR_DIFF_85_BOT_DIP")
	)
	(segment
		(start 148.618448 -446.045336)
		(end 151.074628 -446.045336)
		(width 0.13462)
		(layer "B.Cu")
		(net "TDR_DIFF_85_BOT_DIP")
	)
	(segment
		(start 99.418648 -447.694304)
		(end 99.687888 -447.425064)
		(width 0.13462)
		(layer "B.Cu")
		(net "TDR_DIFF_85_BOT_DIP")
	)
	(segment
		(start 115.171728 -447.425064)
		(end 115.171728 -444.826136)
		(width 0.13462)
		(layer "B.Cu")
		(net "TDR_DIFF_85_BOT_DIP")
	)
	(segment
		(start 140.876528 -447.694304)
		(end 141.999208 -447.694304)
		(width 0.13462)
		(layer "B.Cu")
		(net "TDR_DIFF_85_BOT_DIP")
	)
	(segment
		(start 126.784608 -447.425064)
		(end 126.784608 -444.826136)
		(width 0.13462)
		(layer "B.Cu")
		(net "TDR_DIFF_85_BOT_DIP")
	)
	(segment
		(start 145.870168 -447.694304)
		(end 146.139408 -447.425064)
		(width 0.13462)
		(layer "B.Cu")
		(net "TDR_DIFF_85_BOT_DIP")
	)
	(segment
		(start 115.171728 -444.826136)
		(end 115.601496 -444.396368)
		(width 0.13462)
		(layer "B.Cu")
		(net "TDR_DIFF_85_BOT_DIP")
	)
	(segment
		(start 111.031528 -447.694304)
		(end 111.300768 -447.425064)
		(width 0.13462)
		(layer "B.Cu")
		(net "TDR_DIFF_85_BOT_DIP")
	)
	(segment
		(start 94.155768 -447.425064)
		(end 94.425008 -447.694304)
		(width 0.13462)
		(layer "B.Cu")
		(net "TDR_DIFF_85_BOT_DIP")
	)
	(segment
		(start 98.026728 -447.425064)
		(end 98.295968 -447.694304)
		(width 0.13462)
		(layer "B.Cu")
		(net "TDR_DIFF_85_BOT_DIP")
	)
	(segment
		(start 94.425008 -447.694304)
		(end 95.547688 -447.694304)
		(width 0.13462)
		(layer "B.Cu")
		(net "TDR_DIFF_85_BOT_DIP")
	)
	(segment
		(start 122.644408 -447.694304)
		(end 122.913648 -447.425064)
		(width 0.13462)
		(layer "B.Cu")
		(net "TDR_DIFF_85_BOT_DIP")
	)
	(segment
		(start 107.859576 -444.396368)
		(end 109.20984 -444.396368)
		(width 0.13462)
		(layer "B.Cu")
		(net "TDR_DIFF_85_BOT_DIP")
	)
	(segment
		(start 128.994408 -444.826136)
		(end 128.994408 -447.425064)
		(width 0.13462)
		(layer "B.Cu")
		(net "TDR_DIFF_85_BOT_DIP")
	)
	(segment
		(start 151.209248 -445.910716)
		(end 151.209248 -444.912496)
		(width 0.13462)
		(layer "B.Cu")
		(net "TDR_DIFF_85_BOT_DIP")
	)
	(segment
		(start 136.30656 -444.396368)
		(end 136.736328 -444.826136)
		(width 0.13462)
		(layer "B.Cu")
		(net "TDR_DIFF_85_BOT_DIP")
	)
	(segment
		(start 90.554048 -447.694304)
		(end 91.676728 -447.694304)
		(width 0.13462)
		(layer "B.Cu")
		(net "TDR_DIFF_85_BOT_DIP")
	)
	(segment
		(start 124.69368 -444.396368)
		(end 125.123448 -444.826136)
		(width 0.13462)
		(layer "B.Cu")
		(net "TDR_DIFF_85_BOT_DIP")
	)
	(segment
		(start 125.123448 -444.826136)
		(end 125.123448 -447.425064)
		(width 0.13462)
		(layer "B.Cu")
		(net "TDR_DIFF_85_BOT_DIP")
	)
	(segment
		(start 101.897688 -447.425064)
		(end 102.166928 -447.694304)
		(width 0.13462)
		(layer "B.Cu")
		(net "TDR_DIFF_85_BOT_DIP")
	)
	(segment
		(start 125.392688 -447.694304)
		(end 126.515368 -447.694304)
		(width 0.13462)
		(layer "B.Cu")
		(net "TDR_DIFF_85_BOT_DIP")
	)
	(segment
		(start 94.155768 -444.826136)
		(end 94.155768 -447.425064)
		(width 0.13462)
		(layer "B.Cu")
		(net "TDR_DIFF_85_BOT_DIP")
	)
	(segment
		(start 103.289608 -447.694304)
		(end 103.558848 -447.425064)
		(width 0.13462)
		(layer "B.Cu")
		(net "TDR_DIFF_85_BOT_DIP")
	)
	(segment
		(start 134.257288 -447.694304)
		(end 134.526528 -447.425064)
		(width 0.13462)
		(layer "B.Cu")
		(net "TDR_DIFF_85_BOT_DIP")
	)
	(segment
		(start 147.91944 -444.396368)
		(end 148.349208 -444.826136)
		(width 0.13462)
		(layer "B.Cu")
		(net "TDR_DIFF_85_BOT_DIP")
	)
	(segment
		(start 131.085336 -444.396368)
		(end 132.4356 -444.396368)
		(width 0.13462)
		(layer "B.Cu")
		(net "TDR_DIFF_85_BOT_DIP")
	)
	(segment
		(start 89.85504 -446.045336)
		(end 90.284808 -446.475104)
		(width 0.13462)
		(layer "B.Cu")
		(net "TDR_DIFF_85_BOT_DIP")
	)
	(segment
		(start 103.558848 -444.826136)
		(end 103.988616 -444.396368)
		(width 0.13462)
		(layer "B.Cu")
		(net "TDR_DIFF_85_BOT_DIP")
	)
	(segment
		(start 105.33888 -444.396368)
		(end 105.768648 -444.826136)
		(width 0.13462)
		(layer "B.Cu")
		(net "TDR_DIFF_85_BOT_DIP")
	)
	(segment
		(start 146.569176 -444.396368)
		(end 147.91944 -444.396368)
		(width 0.13462)
		(layer "B.Cu")
		(net "TDR_DIFF_85_BOT_DIP")
	)
	(segment
		(start 109.908848 -447.694304)
		(end 111.031528 -447.694304)
		(width 0.13462)
		(layer "B.Cu")
		(net "TDR_DIFF_85_BOT_DIP")
	)
	(segment
		(start 87.150448 -445.910716)
		(end 87.285068 -446.045336)
		(width 0.13462)
		(layer "B.Cu")
		(net "TDR_DIFF_85_BOT_DIP")
	)
	(segment
		(start 107.429808 -444.826136)
		(end 107.859576 -444.396368)
		(width 0.13462)
		(layer "B.Cu")
		(net "TDR_DIFF_85_BOT_DIP")
	)
	(segment
		(start 109.639608 -444.826136)
		(end 109.639608 -447.425064)
		(width 0.13462)
		(layer "B.Cu")
		(net "TDR_DIFF_85_BOT_DIP")
	)
	(segment
		(start 146.139408 -447.425064)
		(end 146.139408 -444.826136)
		(width 0.13462)
		(layer "B.Cu")
		(net "TDR_DIFF_85_BOT_DIP")
	)
	(segment
		(start 92.375736 -444.396368)
		(end 93.726 -444.396368)
		(width 0.13462)
		(layer "B.Cu")
		(net "TDR_DIFF_85_BOT_DIP")
	)
	(segment
		(start 91.945968 -447.425064)
		(end 91.945968 -444.826136)
		(width 0.13462)
		(layer "B.Cu")
		(net "TDR_DIFF_85_BOT_DIP")
	)
	(segment
		(start 126.515368 -447.694304)
		(end 126.784608 -447.425064)
		(width 0.13462)
		(layer "B.Cu")
		(net "TDR_DIFF_85_BOT_DIP")
	)
	(segment
		(start 138.827256 -444.396368)
		(end 140.17752 -444.396368)
		(width 0.13462)
		(layer "B.Cu")
		(net "TDR_DIFF_85_BOT_DIP")
	)
	(segment
		(start 105.768648 -447.425064)
		(end 106.037888 -447.694304)
		(width 0.13462)
		(layer "B.Cu")
		(net "TDR_DIFF_85_BOT_DIP")
	)
	(segment
		(start 111.730536 -444.396368)
		(end 113.0808 -444.396368)
		(width 0.13462)
		(layer "B.Cu")
		(net "TDR_DIFF_85_BOT_DIP")
	)
	(segment
		(start 117.381528 -444.826136)
		(end 117.381528 -447.425064)
		(width 0.13462)
		(layer "B.Cu")
		(net "TDR_DIFF_85_BOT_DIP")
	)
	(segment
		(start 151.074628 -446.045336)
		(end 151.209248 -445.910716)
		(width 0.13462)
		(layer "B.Cu")
		(net "TDR_DIFF_85_BOT_DIP")
	)
	(segment
		(start 111.300768 -447.425064)
		(end 111.300768 -444.826136)
		(width 0.13462)
		(layer "B.Cu")
		(net "TDR_DIFF_85_BOT_DIP")
	)
	(segment
		(start 137.005568 -447.694304)
		(end 138.128248 -447.694304)
		(width 0.13462)
		(layer "B.Cu")
		(net "TDR_DIFF_85_BOT_DIP")
	)
	(segment
		(start 140.17752 -444.396368)
		(end 140.607288 -444.826136)
		(width 0.13462)
		(layer "B.Cu")
		(net "TDR_DIFF_85_BOT_DIP")
	)
	(segment
		(start 121.521728 -447.694304)
		(end 122.644408 -447.694304)
		(width 0.13462)
		(layer "B.Cu")
		(net "TDR_DIFF_85_BOT_DIP")
	)
	(segment
		(start 117.650768 -447.694304)
		(end 118.773448 -447.694304)
		(width 0.13462)
		(layer "B.Cu")
		(net "TDR_DIFF_85_BOT_DIP")
	)
	(segment
		(start 132.4356 -444.396368)
		(end 132.865368 -444.826136)
		(width 0.13462)
		(layer "B.Cu")
		(net "TDR_DIFF_85_BOT_DIP")
	)
	(segment
		(start 121.252488 -447.425064)
		(end 121.521728 -447.694304)
		(width 0.13462)
		(layer "B.Cu")
		(net "TDR_DIFF_85_BOT_DIP")
	)
	(segment
		(start 109.20984 -444.396368)
		(end 109.639608 -444.826136)
		(width 0.13462)
		(layer "B.Cu")
		(net "TDR_DIFF_85_BOT_DIP")
	)
	(segment
		(start 93.726 -444.396368)
		(end 94.155768 -444.826136)
		(width 0.13462)
		(layer "B.Cu")
		(net "TDR_DIFF_85_BOT_DIP")
	)
	(segment
		(start 114.902488 -447.694304)
		(end 115.171728 -447.425064)
		(width 0.13462)
		(layer "B.Cu")
		(net "TDR_DIFF_85_BOT_DIP")
	)
	(segment
		(start 119.042688 -444.826136)
		(end 119.472456 -444.396368)
		(width 0.13462)
		(layer "B.Cu")
		(net "TDR_DIFF_85_BOT_DIP")
	)
	(segment
		(start 103.558848 -447.425064)
		(end 103.558848 -444.826136)
		(width 0.13462)
		(layer "B.Cu")
		(net "TDR_DIFF_85_BOT_DIP")
	)
	(segment
		(start 101.46792 -444.396368)
		(end 101.897688 -444.826136)
		(width 0.13462)
		(layer "B.Cu")
		(net "TDR_DIFF_85_BOT_DIP")
	)
	(segment
		(start 99.687888 -447.425064)
		(end 99.687888 -444.826136)
		(width 0.13462)
		(layer "B.Cu")
		(net "TDR_DIFF_85_BOT_DIP")
	)
	(segment
		(start 113.510568 -444.826136)
		(end 113.510568 -447.425064)
		(width 0.13462)
		(layer "B.Cu")
		(net "TDR_DIFF_85_BOT_DIP")
	)
	(segment
		(start 136.736328 -447.425064)
		(end 137.005568 -447.694304)
		(width 0.13462)
		(layer "B.Cu")
		(net "TDR_DIFF_85_BOT_DIP")
	)
	(segment
		(start 106.037888 -447.694304)
		(end 107.160568 -447.694304)
		(width 0.13462)
		(layer "B.Cu")
		(net "TDR_DIFF_85_BOT_DIP")
	)
	(segment
		(start 144.478248 -447.425064)
		(end 144.747488 -447.694304)
		(width 0.13462)
		(layer "B.Cu")
		(net "TDR_DIFF_85_BOT_DIP")
	)
	(segment
		(start 99.687888 -444.826136)
		(end 100.117656 -444.396368)
		(width 0.13462)
		(layer "B.Cu")
		(net "TDR_DIFF_85_BOT_DIP")
	)
	(segment
		(start 113.779808 -447.694304)
		(end 114.902488 -447.694304)
		(width 0.13462)
		(layer "B.Cu")
		(net "TDR_DIFF_85_BOT_DIP")
	)
	(segment
		(start 118.773448 -447.694304)
		(end 119.042688 -447.425064)
		(width 0.13462)
		(layer "B.Cu")
		(net "TDR_DIFF_85_BOT_DIP")
	)
	(segment
		(start 87.150448 -444.912496)
		(end 87.150448 -445.910716)
		(width 0.13462)
		(layer "B.Cu")
		(net "TDR_DIFF_85_BOT_DIP")
	)
	(segment
		(start 109.639608 -447.425064)
		(end 109.908848 -447.694304)
		(width 0.13462)
		(layer "B.Cu")
		(net "TDR_DIFF_85_BOT_DIP")
	)
	(segment
		(start 121.252488 -444.826136)
		(end 121.252488 -447.425064)
		(width 0.13462)
		(layer "B.Cu")
		(net "TDR_DIFF_85_BOT_DIP")
	)
	(segment
		(start 126.784608 -444.826136)
		(end 127.214376 -444.396368)
		(width 0.13462)
		(layer "B.Cu")
		(net "TDR_DIFF_85_BOT_DIP")
	)
	(segment
		(start 98.026728 -444.826136)
		(end 98.026728 -447.425064)
		(width 0.13462)
		(layer "B.Cu")
		(net "TDR_DIFF_85_BOT_DIP")
	)
	(segment
		(start 115.601496 -444.396368)
		(end 116.95176 -444.396368)
		(width 0.13462)
		(layer "B.Cu")
		(net "TDR_DIFF_85_BOT_DIP")
	)
	(segment
		(start 142.698216 -444.396368)
		(end 144.04848 -444.396368)
		(width 0.13462)
		(layer "B.Cu")
		(net "TDR_DIFF_85_BOT_DIP")
	)
	(segment
		(start 130.655568 -447.425064)
		(end 130.655568 -444.826136)
		(width 0.13462)
		(layer "B.Cu")
		(net "TDR_DIFF_85_BOT_DIP")
	)
	(segment
		(start 90.284808 -447.425064)
		(end 90.554048 -447.694304)
		(width 0.13462)
		(layer "B.Cu")
		(net "TDR_DIFF_85_BOT_DIP")
	)
	(segment
		(start 134.526528 -444.826136)
		(end 134.956296 -444.396368)
		(width 0.13462)
		(layer "B.Cu")
		(net "TDR_DIFF_85_BOT_DIP")
	)
	(segment
		(start 138.397488 -447.425064)
		(end 138.397488 -444.826136)
		(width 0.13462)
		(layer "B.Cu")
		(net "TDR_DIFF_85_BOT_DIP")
	)
	(segment
		(start 116.95176 -444.396368)
		(end 117.381528 -444.826136)
		(width 0.13462)
		(layer "B.Cu")
		(net "TDR_DIFF_85_BOT_DIP")
	)
	(segment
		(start 91.676728 -447.694304)
		(end 91.945968 -447.425064)
		(width 0.13462)
		(layer "B.Cu")
		(net "TDR_DIFF_85_BOT_DIP")
	)
	(segment
		(start 101.897688 -444.826136)
		(end 101.897688 -447.425064)
		(width 0.13462)
		(layer "B.Cu")
		(net "TDR_DIFF_85_BOT_DIP")
	)
	(segment
		(start 125.123448 -447.425064)
		(end 125.392688 -447.694304)
		(width 0.13462)
		(layer "B.Cu")
		(net "TDR_DIFF_85_BOT_DIP")
	)
	(segment
		(start 142.268448 -444.826136)
		(end 142.698216 -444.396368)
		(width 0.13462)
		(layer "B.Cu")
		(net "TDR_DIFF_85_BOT_DIP")
	)
	(segment
		(start 119.472456 -444.396368)
		(end 120.82272 -444.396368)
		(width 0.13462)
		(layer "B.Cu")
		(net "TDR_DIFF_85_BOT_DIP")
	)
	(segment
		(start 146.139408 -444.826136)
		(end 146.569176 -444.396368)
		(width 0.13462)
		(layer "B.Cu")
		(net "TDR_DIFF_85_BOT_DIP")
	)
	(segment
		(start 144.04848 -444.396368)
		(end 144.478248 -444.826136)
		(width 0.13462)
		(layer "B.Cu")
		(net "TDR_DIFF_85_BOT_DIP")
	)
	(segment
		(start 111.300768 -444.826136)
		(end 111.730536 -444.396368)
		(width 0.13462)
		(layer "B.Cu")
		(net "TDR_DIFF_85_BOT_DIP")
	)
	(segment
		(start 127.214376 -444.396368)
		(end 128.56464 -444.396368)
		(width 0.13462)
		(layer "B.Cu")
		(net "TDR_DIFF_85_BOT_DIP")
	)
	(segment
		(start 138.128248 -447.694304)
		(end 138.397488 -447.425064)
		(width 0.13462)
		(layer "B.Cu")
		(net "TDR_DIFF_85_BOT_DIP")
	)
	(segment
		(start 144.747488 -447.694304)
		(end 145.870168 -447.694304)
		(width 0.13462)
		(layer "B.Cu")
		(net "TDR_DIFF_85_BOT_DIP")
	)
	(segment
		(start 364.913164 -458.200506)
		(end 364.913164 -457.677266)
		(width 0.15494)
		(layer "In9.Cu")
		(net "TDR_SE_50_OHM_IN3")
	)
	(segment
		(start 440.453526 -459.208886)
		(end 365.921544 -459.208886)
		(width 0.15494)
		(layer "In9.Cu")
		(net "TDR_SE_50_OHM_IN3")
	)
	(segment
		(start 365.921544 -456.668886)
		(end 440.453526 -456.668886)
		(width 0.15494)
		(layer "In9.Cu")
		(net "TDR_SE_50_OHM_IN3")
	)
	(segment
		(start 364.913164 -457.677266)
		(end 365.921544 -456.668886)
		(width 0.15494)
		(layer "In9.Cu")
		(net "TDR_SE_50_OHM_IN3")
	)
	(segment
		(start 365.921544 -459.208886)
		(end 364.913164 -458.200506)
		(width 0.15494)
		(layer "In9.Cu")
		(net "TDR_SE_50_OHM_IN3")
	)
	(segment
		(start 392.019536 -436.928006)
		(end 317.51397 -436.928006)
		(width 0.13208)
		(layer "B.Cu")
		(net "TDR_SE_50_OHM_BOT")
	)
	(segment
		(start 392.019536 -434.388006)
		(end 393.159996 -435.528466)
		(width 0.13208)
		(layer "B.Cu")
		(net "TDR_SE_50_OHM_BOT")
	)
	(segment
		(start 393.159996 -435.787546)
		(end 392.019536 -436.928006)
		(width 0.13208)
		(layer "B.Cu")
		(net "TDR_SE_50_OHM_BOT")
	)
	(segment
		(start 317.51397 -434.388006)
		(end 392.019536 -434.388006)
		(width 0.13208)
		(layer "B.Cu")
		(net "TDR_SE_50_OHM_BOT")
	)
	(segment
		(start 393.159996 -435.528466)
		(end 393.159996 -435.787546)
		(width 0.13208)
		(layer "B.Cu")
		(net "TDR_SE_50_OHM_BOT")
	)
	(segment
		(start 55.856632 -444.766446)
		(end 55.856632 -447.365374)
		(width 0.13462)
		(layer "F.Cu")
		(net "TDR_DIFF_85_TOP_DIN")
	)
	(segment
		(start 48.114712 -447.365374)
		(end 48.54448 -447.795142)
		(width 0.13462)
		(layer "F.Cu")
		(net "TDR_DIFF_85_TOP_DIN")
	)
	(segment
		(start 58.066432 -444.766446)
		(end 58.335672 -444.497206)
		(width 0.13462)
		(layer "F.Cu")
		(net "TDR_DIFF_85_TOP_DIN")
	)
	(segment
		(start 34.840672 -447.365374)
		(end 34.840672 -444.766446)
		(width 0.13462)
		(layer "F.Cu")
		(net "TDR_DIFF_85_TOP_DIN")
	)
	(segment
		(start 71.340472 -447.365374)
		(end 71.77024 -447.795142)
		(width 0.13462)
		(layer "F.Cu")
		(net "TDR_DIFF_85_TOP_DIN")
	)
	(segment
		(start 24.619712 -444.497206)
		(end 24.888952 -444.766446)
		(width 0.13462)
		(layer "F.Cu")
		(net "TDR_DIFF_85_TOP_DIN")
	)
	(segment
		(start 54.464712 -444.497206)
		(end 55.587392 -444.497206)
		(width 0.13462)
		(layer "F.Cu")
		(net "TDR_DIFF_85_TOP_DIN")
	)
	(segment
		(start 30.539944 -447.795142)
		(end 30.969712 -447.365374)
		(width 0.13462)
		(layer "F.Cu")
		(net "TDR_DIFF_85_TOP_DIN")
	)
	(segment
		(start 59.458352 -444.497206)
		(end 59.727592 -444.766446)
		(width 0.13462)
		(layer "F.Cu")
		(net "TDR_DIFF_85_TOP_DIN")
	)
	(segment
		(start 73.819512 -444.497206)
		(end 74.942192 -444.497206)
		(width 0.13462)
		(layer "F.Cu")
		(net "TDR_DIFF_85_TOP_DIN")
	)
	(segment
		(start 49.894744 -447.795142)
		(end 50.324512 -447.365374)
		(width 0.13462)
		(layer "F.Cu")
		(net "TDR_DIFF_85_TOP_DIN")
	)
	(segment
		(start 32.630872 -447.365374)
		(end 33.06064 -447.795142)
		(width 0.13462)
		(layer "F.Cu")
		(net "TDR_DIFF_85_TOP_DIN")
	)
	(segment
		(start 28.759912 -447.365374)
		(end 29.18968 -447.795142)
		(width 0.13462)
		(layer "F.Cu")
		(net "TDR_DIFF_85_TOP_DIN")
	)
	(segment
		(start 48.54448 -447.795142)
		(end 49.894744 -447.795142)
		(width 0.13462)
		(layer "F.Cu")
		(net "TDR_DIFF_85_TOP_DIN")
	)
	(segment
		(start 59.727592 -444.766446)
		(end 59.727592 -447.365374)
		(width 0.13462)
		(layer "F.Cu")
		(net "TDR_DIFF_85_TOP_DIN")
	)
	(segment
		(start 78.345792 -446.280794)
		(end 78.345792 -447.279014)
		(width 0.13462)
		(layer "F.Cu")
		(net "TDR_DIFF_85_TOP_DIN")
	)
	(segment
		(start 52.41544 -447.795142)
		(end 53.765704 -447.795142)
		(width 0.13462)
		(layer "F.Cu")
		(net "TDR_DIFF_85_TOP_DIN")
	)
	(segment
		(start 19.356832 -447.365374)
		(end 19.356832 -444.766446)
		(width 0.13462)
		(layer "F.Cu")
		(net "TDR_DIFF_85_TOP_DIN")
	)
	(segment
		(start 44.243752 -447.365374)
		(end 44.67352 -447.795142)
		(width 0.13462)
		(layer "F.Cu")
		(net "TDR_DIFF_85_TOP_DIN")
	)
	(segment
		(start 34.410904 -447.795142)
		(end 34.840672 -447.365374)
		(width 0.13462)
		(layer "F.Cu")
		(net "TDR_DIFF_85_TOP_DIN")
	)
	(segment
		(start 31.238952 -444.497206)
		(end 32.361632 -444.497206)
		(width 0.13462)
		(layer "F.Cu")
		(net "TDR_DIFF_85_TOP_DIN")
	)
	(segment
		(start 27.098752 -447.365374)
		(end 27.098752 -444.766446)
		(width 0.13462)
		(layer "F.Cu")
		(net "TDR_DIFF_85_TOP_DIN")
	)
	(segment
		(start 21.44776 -447.795142)
		(end 22.798024 -447.795142)
		(width 0.13462)
		(layer "F.Cu")
		(net "TDR_DIFF_85_TOP_DIN")
	)
	(segment
		(start 34.840672 -444.766446)
		(end 35.109912 -444.497206)
		(width 0.13462)
		(layer "F.Cu")
		(net "TDR_DIFF_85_TOP_DIN")
	)
	(segment
		(start 19.356832 -444.766446)
		(end 19.626072 -444.497206)
		(width 0.13462)
		(layer "F.Cu")
		(net "TDR_DIFF_85_TOP_DIN")
	)
	(segment
		(start 58.066432 -447.365374)
		(end 58.066432 -444.766446)
		(width 0.13462)
		(layer "F.Cu")
		(net "TDR_DIFF_85_TOP_DIN")
	)
	(segment
		(start 63.598552 -444.766446)
		(end 63.598552 -447.365374)
		(width 0.13462)
		(layer "F.Cu")
		(net "TDR_DIFF_85_TOP_DIN")
	)
	(segment
		(start 62.206632 -444.497206)
		(end 63.329312 -444.497206)
		(width 0.13462)
		(layer "F.Cu")
		(net "TDR_DIFF_85_TOP_DIN")
	)
	(segment
		(start 67.469512 -444.766446)
		(end 67.469512 -447.365374)
		(width 0.13462)
		(layer "F.Cu")
		(net "TDR_DIFF_85_TOP_DIN")
	)
	(segment
		(start 14.421612 -446.146174)
		(end 16.877792 -446.146174)
		(width 0.13462)
		(layer "F.Cu")
		(net "TDR_DIFF_85_TOP_DIN")
	)
	(segment
		(start 48.114712 -444.766446)
		(end 48.114712 -447.365374)
		(width 0.13462)
		(layer "F.Cu")
		(net "TDR_DIFF_85_TOP_DIN")
	)
	(segment
		(start 69.679312 -447.365374)
		(end 69.679312 -444.766446)
		(width 0.13462)
		(layer "F.Cu")
		(net "TDR_DIFF_85_TOP_DIN")
	)
	(segment
		(start 17.5768 -447.795142)
		(end 18.927064 -447.795142)
		(width 0.13462)
		(layer "F.Cu")
		(net "TDR_DIFF_85_TOP_DIN")
	)
	(segment
		(start 44.243752 -444.766446)
		(end 44.243752 -447.365374)
		(width 0.13462)
		(layer "F.Cu")
		(net "TDR_DIFF_85_TOP_DIN")
	)
	(segment
		(start 40.372792 -444.766446)
		(end 40.372792 -447.365374)
		(width 0.13462)
		(layer "F.Cu")
		(net "TDR_DIFF_85_TOP_DIN")
	)
	(segment
		(start 66.077592 -444.497206)
		(end 67.200272 -444.497206)
		(width 0.13462)
		(layer "F.Cu")
		(net "TDR_DIFF_85_TOP_DIN")
	)
	(segment
		(start 17.147032 -447.365374)
		(end 17.5768 -447.795142)
		(width 0.13462)
		(layer "F.Cu")
		(net "TDR_DIFF_85_TOP_DIN")
	)
	(segment
		(start 42.582592 -447.365374)
		(end 42.582592 -444.766446)
		(width 0.13462)
		(layer "F.Cu")
		(net "TDR_DIFF_85_TOP_DIN")
	)
	(segment
		(start 61.937392 -444.766446)
		(end 62.206632 -444.497206)
		(width 0.13462)
		(layer "F.Cu")
		(net "TDR_DIFF_85_TOP_DIN")
	)
	(segment
		(start 17.147032 -446.415414)
		(end 17.147032 -447.365374)
		(width 0.13462)
		(layer "F.Cu")
		(net "TDR_DIFF_85_TOP_DIN")
	)
	(segment
		(start 30.969712 -444.766446)
		(end 31.238952 -444.497206)
		(width 0.13462)
		(layer "F.Cu")
		(net "TDR_DIFF_85_TOP_DIN")
	)
	(segment
		(start 67.200272 -444.497206)
		(end 67.469512 -444.766446)
		(width 0.13462)
		(layer "F.Cu")
		(net "TDR_DIFF_85_TOP_DIN")
	)
	(segment
		(start 27.098752 -444.766446)
		(end 27.367992 -444.497206)
		(width 0.13462)
		(layer "F.Cu")
		(net "TDR_DIFF_85_TOP_DIN")
	)
	(segment
		(start 46.722792 -444.497206)
		(end 47.845472 -444.497206)
		(width 0.13462)
		(layer "F.Cu")
		(net "TDR_DIFF_85_TOP_DIN")
	)
	(segment
		(start 38.711632 -447.365374)
		(end 38.711632 -444.766446)
		(width 0.13462)
		(layer "F.Cu")
		(net "TDR_DIFF_85_TOP_DIN")
	)
	(segment
		(start 38.980872 -444.497206)
		(end 40.103552 -444.497206)
		(width 0.13462)
		(layer "F.Cu")
		(net "TDR_DIFF_85_TOP_DIN")
	)
	(segment
		(start 24.888952 -447.365374)
		(end 25.31872 -447.795142)
		(width 0.13462)
		(layer "F.Cu")
		(net "TDR_DIFF_85_TOP_DIN")
	)
	(segment
		(start 14.286992 -446.280794)
		(end 14.421612 -446.146174)
		(width 0.13462)
		(layer "F.Cu")
		(net "TDR_DIFF_85_TOP_DIN")
	)
	(segment
		(start 51.716432 -444.497206)
		(end 51.985672 -444.766446)
		(width 0.13462)
		(layer "F.Cu")
		(net "TDR_DIFF_85_TOP_DIN")
	)
	(segment
		(start 69.679312 -444.766446)
		(end 69.948552 -444.497206)
		(width 0.13462)
		(layer "F.Cu")
		(net "TDR_DIFF_85_TOP_DIN")
	)
	(segment
		(start 42.851832 -444.497206)
		(end 43.974512 -444.497206)
		(width 0.13462)
		(layer "F.Cu")
		(net "TDR_DIFF_85_TOP_DIN")
	)
	(segment
		(start 51.985672 -444.766446)
		(end 51.985672 -447.365374)
		(width 0.13462)
		(layer "F.Cu")
		(net "TDR_DIFF_85_TOP_DIN")
	)
	(segment
		(start 57.636664 -447.795142)
		(end 58.066432 -447.365374)
		(width 0.13462)
		(layer "F.Cu")
		(net "TDR_DIFF_85_TOP_DIN")
	)
	(segment
		(start 36.232592 -444.497206)
		(end 36.501832 -444.766446)
		(width 0.13462)
		(layer "F.Cu")
		(net "TDR_DIFF_85_TOP_DIN")
	)
	(segment
		(start 69.249544 -447.795142)
		(end 69.679312 -447.365374)
		(width 0.13462)
		(layer "F.Cu")
		(net "TDR_DIFF_85_TOP_DIN")
	)
	(segment
		(start 65.808352 -444.766446)
		(end 66.077592 -444.497206)
		(width 0.13462)
		(layer "F.Cu")
		(net "TDR_DIFF_85_TOP_DIN")
	)
	(segment
		(start 65.378584 -447.795142)
		(end 65.808352 -447.365374)
		(width 0.13462)
		(layer "F.Cu")
		(net "TDR_DIFF_85_TOP_DIN")
	)
	(segment
		(start 23.497032 -444.497206)
		(end 24.619712 -444.497206)
		(width 0.13462)
		(layer "F.Cu")
		(net "TDR_DIFF_85_TOP_DIN")
	)
	(segment
		(start 58.335672 -444.497206)
		(end 59.458352 -444.497206)
		(width 0.13462)
		(layer "F.Cu")
		(net "TDR_DIFF_85_TOP_DIN")
	)
	(segment
		(start 75.211432 -445.716406)
		(end 75.6412 -446.146174)
		(width 0.13462)
		(layer "F.Cu")
		(net "TDR_DIFF_85_TOP_DIN")
	)
	(segment
		(start 75.6412 -446.146174)
		(end 78.211172 -446.146174)
		(width 0.13462)
		(layer "F.Cu")
		(net "TDR_DIFF_85_TOP_DIN")
	)
	(segment
		(start 44.67352 -447.795142)
		(end 46.023784 -447.795142)
		(width 0.13462)
		(layer "F.Cu")
		(net "TDR_DIFF_85_TOP_DIN")
	)
	(segment
		(start 23.227792 -444.766446)
		(end 23.497032 -444.497206)
		(width 0.13462)
		(layer "F.Cu")
		(net "TDR_DIFF_85_TOP_DIN")
	)
	(segment
		(start 47.845472 -444.497206)
		(end 48.114712 -444.766446)
		(width 0.13462)
		(layer "F.Cu")
		(net "TDR_DIFF_85_TOP_DIN")
	)
	(segment
		(start 35.109912 -444.497206)
		(end 36.232592 -444.497206)
		(width 0.13462)
		(layer "F.Cu")
		(net "TDR_DIFF_85_TOP_DIN")
	)
	(segment
		(start 42.152824 -447.795142)
		(end 42.582592 -447.365374)
		(width 0.13462)
		(layer "F.Cu")
		(net "TDR_DIFF_85_TOP_DIN")
	)
	(segment
		(start 64.02832 -447.795142)
		(end 65.378584 -447.795142)
		(width 0.13462)
		(layer "F.Cu")
		(net "TDR_DIFF_85_TOP_DIN")
	)
	(segment
		(start 30.969712 -447.365374)
		(end 30.969712 -444.766446)
		(width 0.13462)
		(layer "F.Cu")
		(net "TDR_DIFF_85_TOP_DIN")
	)
	(segment
		(start 40.372792 -447.365374)
		(end 40.80256 -447.795142)
		(width 0.13462)
		(layer "F.Cu")
		(net "TDR_DIFF_85_TOP_DIN")
	)
	(segment
		(start 69.948552 -444.497206)
		(end 71.071232 -444.497206)
		(width 0.13462)
		(layer "F.Cu")
		(net "TDR_DIFF_85_TOP_DIN")
	)
	(segment
		(start 71.340472 -444.766446)
		(end 71.340472 -447.365374)
		(width 0.13462)
		(layer "F.Cu")
		(net "TDR_DIFF_85_TOP_DIN")
	)
	(segment
		(start 40.103552 -444.497206)
		(end 40.372792 -444.766446)
		(width 0.13462)
		(layer "F.Cu")
		(net "TDR_DIFF_85_TOP_DIN")
	)
	(segment
		(start 50.324512 -444.766446)
		(end 50.593752 -444.497206)
		(width 0.13462)
		(layer "F.Cu")
		(net "TDR_DIFF_85_TOP_DIN")
	)
	(segment
		(start 32.630872 -444.766446)
		(end 32.630872 -447.365374)
		(width 0.13462)
		(layer "F.Cu")
		(net "TDR_DIFF_85_TOP_DIN")
	)
	(segment
		(start 25.31872 -447.795142)
		(end 26.668984 -447.795142)
		(width 0.13462)
		(layer "F.Cu")
		(net "TDR_DIFF_85_TOP_DIN")
	)
	(segment
		(start 78.211172 -446.146174)
		(end 78.345792 -446.280794)
		(width 0.13462)
		(layer "F.Cu")
		(net "TDR_DIFF_85_TOP_DIN")
	)
	(segment
		(start 73.550272 -447.365374)
		(end 73.550272 -444.766446)
		(width 0.13462)
		(layer "F.Cu")
		(net "TDR_DIFF_85_TOP_DIN")
	)
	(segment
		(start 67.89928 -447.795142)
		(end 69.249544 -447.795142)
		(width 0.13462)
		(layer "F.Cu")
		(net "TDR_DIFF_85_TOP_DIN")
	)
	(segment
		(start 32.361632 -444.497206)
		(end 32.630872 -444.766446)
		(width 0.13462)
		(layer "F.Cu")
		(net "TDR_DIFF_85_TOP_DIN")
	)
	(segment
		(start 60.15736 -447.795142)
		(end 61.507624 -447.795142)
		(width 0.13462)
		(layer "F.Cu")
		(net "TDR_DIFF_85_TOP_DIN")
	)
	(segment
		(start 23.227792 -447.365374)
		(end 23.227792 -444.766446)
		(width 0.13462)
		(layer "F.Cu")
		(net "TDR_DIFF_85_TOP_DIN")
	)
	(segment
		(start 73.550272 -444.766446)
		(end 73.819512 -444.497206)
		(width 0.13462)
		(layer "F.Cu")
		(net "TDR_DIFF_85_TOP_DIN")
	)
	(segment
		(start 18.927064 -447.795142)
		(end 19.356832 -447.365374)
		(width 0.13462)
		(layer "F.Cu")
		(net "TDR_DIFF_85_TOP_DIN")
	)
	(segment
		(start 28.759912 -444.766446)
		(end 28.759912 -447.365374)
		(width 0.13462)
		(layer "F.Cu")
		(net "TDR_DIFF_85_TOP_DIN")
	)
	(segment
		(start 42.582592 -444.766446)
		(end 42.851832 -444.497206)
		(width 0.13462)
		(layer "F.Cu")
		(net "TDR_DIFF_85_TOP_DIN")
	)
	(segment
		(start 54.195472 -444.766446)
		(end 54.464712 -444.497206)
		(width 0.13462)
		(layer "F.Cu")
		(net "TDR_DIFF_85_TOP_DIN")
	)
	(segment
		(start 55.856632 -447.365374)
		(end 56.2864 -447.795142)
		(width 0.13462)
		(layer "F.Cu")
		(net "TDR_DIFF_85_TOP_DIN")
	)
	(segment
		(start 14.286992 -447.279014)
		(end 14.286992 -446.280794)
		(width 0.13462)
		(layer "F.Cu")
		(net "TDR_DIFF_85_TOP_DIN")
	)
	(segment
		(start 75.211432 -444.766446)
		(end 75.211432 -445.716406)
		(width 0.13462)
		(layer "F.Cu")
		(net "TDR_DIFF_85_TOP_DIN")
	)
	(segment
		(start 21.017992 -447.365374)
		(end 21.44776 -447.795142)
		(width 0.13462)
		(layer "F.Cu")
		(net "TDR_DIFF_85_TOP_DIN")
	)
	(segment
		(start 55.587392 -444.497206)
		(end 55.856632 -444.766446)
		(width 0.13462)
		(layer "F.Cu")
		(net "TDR_DIFF_85_TOP_DIN")
	)
	(segment
		(start 65.808352 -447.365374)
		(end 65.808352 -444.766446)
		(width 0.13462)
		(layer "F.Cu")
		(net "TDR_DIFF_85_TOP_DIN")
	)
	(segment
		(start 26.668984 -447.795142)
		(end 27.098752 -447.365374)
		(width 0.13462)
		(layer "F.Cu")
		(net "TDR_DIFF_85_TOP_DIN")
	)
	(segment
		(start 61.507624 -447.795142)
		(end 61.937392 -447.365374)
		(width 0.13462)
		(layer "F.Cu")
		(net "TDR_DIFF_85_TOP_DIN")
	)
	(segment
		(start 63.329312 -444.497206)
		(end 63.598552 -444.766446)
		(width 0.13462)
		(layer "F.Cu")
		(net "TDR_DIFF_85_TOP_DIN")
	)
	(segment
		(start 46.453552 -444.766446)
		(end 46.722792 -444.497206)
		(width 0.13462)
		(layer "F.Cu")
		(net "TDR_DIFF_85_TOP_DIN")
	)
	(segment
		(start 19.626072 -444.497206)
		(end 20.748752 -444.497206)
		(width 0.13462)
		(layer "F.Cu")
		(net "TDR_DIFF_85_TOP_DIN")
	)
	(segment
		(start 29.18968 -447.795142)
		(end 30.539944 -447.795142)
		(width 0.13462)
		(layer "F.Cu")
		(net "TDR_DIFF_85_TOP_DIN")
	)
	(segment
		(start 71.77024 -447.795142)
		(end 73.120504 -447.795142)
		(width 0.13462)
		(layer "F.Cu")
		(net "TDR_DIFF_85_TOP_DIN")
	)
	(segment
		(start 28.490672 -444.497206)
		(end 28.759912 -444.766446)
		(width 0.13462)
		(layer "F.Cu")
		(net "TDR_DIFF_85_TOP_DIN")
	)
	(segment
		(start 54.195472 -447.365374)
		(end 54.195472 -444.766446)
		(width 0.13462)
		(layer "F.Cu")
		(net "TDR_DIFF_85_TOP_DIN")
	)
	(segment
		(start 33.06064 -447.795142)
		(end 34.410904 -447.795142)
		(width 0.13462)
		(layer "F.Cu")
		(net "TDR_DIFF_85_TOP_DIN")
	)
	(segment
		(start 50.593752 -444.497206)
		(end 51.716432 -444.497206)
		(width 0.13462)
		(layer "F.Cu")
		(net "TDR_DIFF_85_TOP_DIN")
	)
	(segment
		(start 67.469512 -447.365374)
		(end 67.89928 -447.795142)
		(width 0.13462)
		(layer "F.Cu")
		(net "TDR_DIFF_85_TOP_DIN")
	)
	(segment
		(start 46.453552 -447.365374)
		(end 46.453552 -444.766446)
		(width 0.13462)
		(layer "F.Cu")
		(net "TDR_DIFF_85_TOP_DIN")
	)
	(segment
		(start 36.501832 -447.365374)
		(end 36.9316 -447.795142)
		(width 0.13462)
		(layer "F.Cu")
		(net "TDR_DIFF_85_TOP_DIN")
	)
	(segment
		(start 53.765704 -447.795142)
		(end 54.195472 -447.365374)
		(width 0.13462)
		(layer "F.Cu")
		(net "TDR_DIFF_85_TOP_DIN")
	)
	(segment
		(start 43.974512 -444.497206)
		(end 44.243752 -444.766446)
		(width 0.13462)
		(layer "F.Cu")
		(net "TDR_DIFF_85_TOP_DIN")
	)
	(segment
		(start 16.877792 -446.146174)
		(end 17.147032 -446.415414)
		(width 0.13462)
		(layer "F.Cu")
		(net "TDR_DIFF_85_TOP_DIN")
	)
	(segment
		(start 56.2864 -447.795142)
		(end 57.636664 -447.795142)
		(width 0.13462)
		(layer "F.Cu")
		(net "TDR_DIFF_85_TOP_DIN")
	)
	(segment
		(start 61.937392 -447.365374)
		(end 61.937392 -444.766446)
		(width 0.13462)
		(layer "F.Cu")
		(net "TDR_DIFF_85_TOP_DIN")
	)
	(segment
		(start 38.711632 -444.766446)
		(end 38.980872 -444.497206)
		(width 0.13462)
		(layer "F.Cu")
		(net "TDR_DIFF_85_TOP_DIN")
	)
	(segment
		(start 73.120504 -447.795142)
		(end 73.550272 -447.365374)
		(width 0.13462)
		(layer "F.Cu")
		(net "TDR_DIFF_85_TOP_DIN")
	)
	(segment
		(start 63.598552 -447.365374)
		(end 64.02832 -447.795142)
		(width 0.13462)
		(layer "F.Cu")
		(net "TDR_DIFF_85_TOP_DIN")
	)
	(segment
		(start 22.798024 -447.795142)
		(end 23.227792 -447.365374)
		(width 0.13462)
		(layer "F.Cu")
		(net "TDR_DIFF_85_TOP_DIN")
	)
	(segment
		(start 59.727592 -447.365374)
		(end 60.15736 -447.795142)
		(width 0.13462)
		(layer "F.Cu")
		(net "TDR_DIFF_85_TOP_DIN")
	)
	(segment
		(start 51.985672 -447.365374)
		(end 52.41544 -447.795142)
		(width 0.13462)
		(layer "F.Cu")
		(net "TDR_DIFF_85_TOP_DIN")
	)
	(segment
		(start 24.888952 -444.766446)
		(end 24.888952 -447.365374)
		(width 0.13462)
		(layer "F.Cu")
		(net "TDR_DIFF_85_TOP_DIN")
	)
	(segment
		(start 46.023784 -447.795142)
		(end 46.453552 -447.365374)
		(width 0.13462)
		(layer "F.Cu")
		(net "TDR_DIFF_85_TOP_DIN")
	)
	(segment
		(start 27.367992 -444.497206)
		(end 28.490672 -444.497206)
		(width 0.13462)
		(layer "F.Cu")
		(net "TDR_DIFF_85_TOP_DIN")
	)
	(segment
		(start 38.281864 -447.795142)
		(end 38.711632 -447.365374)
		(width 0.13462)
		(layer "F.Cu")
		(net "TDR_DIFF_85_TOP_DIN")
	)
	(segment
		(start 40.80256 -447.795142)
		(end 42.152824 -447.795142)
		(width 0.13462)
		(layer "F.Cu")
		(net "TDR_DIFF_85_TOP_DIN")
	)
	(segment
		(start 21.017992 -444.766446)
		(end 21.017992 -447.365374)
		(width 0.13462)
		(layer "F.Cu")
		(net "TDR_DIFF_85_TOP_DIN")
	)
	(segment
		(start 71.071232 -444.497206)
		(end 71.340472 -444.766446)
		(width 0.13462)
		(layer "F.Cu")
		(net "TDR_DIFF_85_TOP_DIN")
	)
	(segment
		(start 20.748752 -444.497206)
		(end 21.017992 -444.766446)
		(width 0.13462)
		(layer "F.Cu")
		(net "TDR_DIFF_85_TOP_DIN")
	)
	(segment
		(start 36.501832 -444.766446)
		(end 36.501832 -447.365374)
		(width 0.13462)
		(layer "F.Cu")
		(net "TDR_DIFF_85_TOP_DIN")
	)
	(segment
		(start 74.942192 -444.497206)
		(end 75.211432 -444.766446)
		(width 0.13462)
		(layer "F.Cu")
		(net "TDR_DIFF_85_TOP_DIN")
	)
	(segment
		(start 50.324512 -447.365374)
		(end 50.324512 -444.766446)
		(width 0.13462)
		(layer "F.Cu")
		(net "TDR_DIFF_85_TOP_DIN")
	)
	(segment
		(start 36.9316 -447.795142)
		(end 38.281864 -447.795142)
		(width 0.13462)
		(layer "F.Cu")
		(net "TDR_DIFF_85_TOP_DIN")
	)
	(segment
		(start 364.913164 -442.767212)
		(end 365.921544 -441.758832)
		(width 0.15494)
		(layer "In7.Cu")
		(net "TDR_SE_50_OHM_IN2")
	)
	(segment
		(start 364.913164 -443.290452)
		(end 364.913164 -442.767212)
		(width 0.15494)
		(layer "In7.Cu")
		(net "TDR_SE_50_OHM_IN2")
	)
	(segment
		(start 440.453526 -444.298832)
		(end 365.921544 -444.298832)
		(width 0.15494)
		(layer "In7.Cu")
		(net "TDR_SE_50_OHM_IN2")
	)
	(segment
		(start 365.921544 -444.298832)
		(end 364.913164 -443.290452)
		(width 0.15494)
		(layer "In7.Cu")
		(net "TDR_SE_50_OHM_IN2")
	)
	(segment
		(start 365.921544 -441.758832)
		(end 440.453526 -441.758832)
		(width 0.15494)
		(layer "In7.Cu")
		(net "TDR_SE_50_OHM_IN2")
	)
	(segment
		(start 136.920478 -456.89393)
		(end 136.920478 -458.722222)
		(width 0.1651)
		(layer "In11.Cu")
		(net "TDR_DIFF_85_IN4_DIN")
	)
	(segment
		(start 131.911598 -459.052422)
		(end 132.241798 -458.722222)
		(width 0.1651)
		(layer "In11.Cu")
		(net "TDR_DIFF_85_IN4_DIN")
	)
	(segment
		(start 133.989318 -456.89393)
		(end 133.989318 -458.722222)
		(width 0.1651)
		(layer "In11.Cu")
		(net "TDR_DIFF_85_IN4_DIN")
	)
	(segment
		(start 117.585998 -456.89393)
		(end 118.081298 -456.39863)
		(width 0.1651)
		(layer "In11.Cu")
		(net "TDR_DIFF_85_IN4_DIN")
	)
	(segment
		(start 120.517158 -458.722222)
		(end 120.517158 -456.89393)
		(width 0.1651)
		(layer "In11.Cu")
		(net "TDR_DIFF_85_IN4_DIN")
	)
	(segment
		(start 96.737678 -459.052422)
		(end 97.067878 -458.722222)
		(width 0.1651)
		(layer "In11.Cu")
		(net "TDR_DIFF_85_IN4_DIN")
	)
	(segment
		(start 99.999038 -456.89393)
		(end 100.494338 -456.39863)
		(width 0.1651)
		(layer "In11.Cu")
		(net "TDR_DIFF_85_IN4_DIN")
	)
	(segment
		(start 109.287818 -456.39863)
		(end 110.044738 -456.39863)
		(width 0.1651)
		(layer "In11.Cu")
		(net "TDR_DIFF_85_IN4_DIN")
	)
	(segment
		(start 107.608878 -456.89393)
		(end 107.608878 -458.722222)
		(width 0.1651)
		(layer "In11.Cu")
		(net "TDR_DIFF_85_IN4_DIN")
	)
	(segment
		(start 107.113578 -456.39863)
		(end 107.608878 -456.89393)
		(width 0.1651)
		(layer "In11.Cu")
		(net "TDR_DIFF_85_IN4_DIN")
	)
	(segment
		(start 146.897598 -458.722222)
		(end 146.897598 -456.89393)
		(width 0.1651)
		(layer "In11.Cu")
		(net "TDR_DIFF_85_IN4_DIN")
	)
	(segment
		(start 104.182418 -456.39863)
		(end 104.677718 -456.89393)
		(width 0.1651)
		(layer "In11.Cu")
		(net "TDR_DIFF_85_IN4_DIN")
	)
	(segment
		(start 111.393478 -459.052422)
		(end 111.723678 -458.722222)
		(width 0.1651)
		(layer "In11.Cu")
		(net "TDR_DIFF_85_IN4_DIN")
	)
	(segment
		(start 114.654838 -458.722222)
		(end 114.654838 -456.89393)
		(width 0.1651)
		(layer "In11.Cu")
		(net "TDR_DIFF_85_IN4_DIN")
	)
	(segment
		(start 101.746558 -458.722222)
		(end 102.076758 -459.052422)
		(width 0.1651)
		(layer "In11.Cu")
		(net "TDR_DIFF_85_IN4_DIN")
	)
	(segment
		(start 125.526038 -459.052422)
		(end 126.049278 -459.052422)
		(width 0.1651)
		(layer "In11.Cu")
		(net "TDR_DIFF_85_IN4_DIN")
	)
	(segment
		(start 113.801398 -459.052422)
		(end 114.324638 -459.052422)
		(width 0.1651)
		(layer "In11.Cu")
		(net "TDR_DIFF_85_IN4_DIN")
	)
	(segment
		(start 128.126998 -458.722222)
		(end 128.457198 -459.052422)
		(width 0.1651)
		(layer "In11.Cu")
		(net "TDR_DIFF_85_IN4_DIN")
	)
	(segment
		(start 122.594878 -459.052422)
		(end 123.118118 -459.052422)
		(width 0.1651)
		(layer "In11.Cu")
		(net "TDR_DIFF_85_IN4_DIN")
	)
	(segment
		(start 131.388358 -459.052422)
		(end 131.911598 -459.052422)
		(width 0.1651)
		(layer "In11.Cu")
		(net "TDR_DIFF_85_IN4_DIN")
	)
	(segment
		(start 106.356658 -456.39863)
		(end 107.113578 -456.39863)
		(width 0.1651)
		(layer "In11.Cu")
		(net "TDR_DIFF_85_IN4_DIN")
	)
	(segment
		(start 118.081298 -456.39863)
		(end 118.838218 -456.39863)
		(width 0.1651)
		(layer "In11.Cu")
		(net "TDR_DIFF_85_IN4_DIN")
	)
	(segment
		(start 130.562858 -456.39863)
		(end 131.058158 -456.89393)
		(width 0.1651)
		(layer "In11.Cu")
		(net "TDR_DIFF_85_IN4_DIN")
	)
	(segment
		(start 143.966438 -458.722222)
		(end 143.966438 -456.89393)
		(width 0.1651)
		(layer "In11.Cu")
		(net "TDR_DIFF_85_IN4_DIN")
	)
	(segment
		(start 119.663718 -459.052422)
		(end 120.186958 -459.052422)
		(width 0.1651)
		(layer "In11.Cu")
		(net "TDR_DIFF_85_IN4_DIN")
	)
	(segment
		(start 133.989318 -458.722222)
		(end 134.319518 -459.052422)
		(width 0.1651)
		(layer "In11.Cu")
		(net "TDR_DIFF_85_IN4_DIN")
	)
	(segment
		(start 101.746558 -456.89393)
		(end 101.746558 -458.722222)
		(width 0.1651)
		(layer "In11.Cu")
		(net "TDR_DIFF_85_IN4_DIN")
	)
	(segment
		(start 96.214438 -459.052422)
		(end 96.737678 -459.052422)
		(width 0.1651)
		(layer "In11.Cu")
		(net "TDR_DIFF_85_IN4_DIN")
	)
	(segment
		(start 148.645118 -456.89393)
		(end 148.645118 -457.395326)
		(width 0.1651)
		(layer "In11.Cu")
		(net "TDR_DIFF_85_IN4_DIN")
	)
	(segment
		(start 125.195838 -458.722222)
		(end 125.526038 -459.052422)
		(width 0.1651)
		(layer "In11.Cu")
		(net "TDR_DIFF_85_IN4_DIN")
	)
	(segment
		(start 148.975318 -457.725526)
		(end 151.044148 -457.725526)
		(width 0.1651)
		(layer "In11.Cu")
		(net "TDR_DIFF_85_IN4_DIN")
	)
	(segment
		(start 108.792518 -456.89393)
		(end 109.287818 -456.39863)
		(width 0.1651)
		(layer "In11.Cu")
		(net "TDR_DIFF_85_IN4_DIN")
	)
	(segment
		(start 90.875358 -459.052422)
		(end 91.205558 -458.722222)
		(width 0.1651)
		(layer "In11.Cu")
		(net "TDR_DIFF_85_IN4_DIN")
	)
	(segment
		(start 123.118118 -459.052422)
		(end 123.448318 -458.722222)
		(width 0.1651)
		(layer "In11.Cu")
		(net "TDR_DIFF_85_IN4_DIN")
	)
	(segment
		(start 128.126998 -456.89393)
		(end 128.126998 -458.722222)
		(width 0.1651)
		(layer "In11.Cu")
		(net "TDR_DIFF_85_IN4_DIN")
	)
	(segment
		(start 141.035278 -456.89393)
		(end 141.530578 -456.39863)
		(width 0.1651)
		(layer "In11.Cu")
		(net "TDR_DIFF_85_IN4_DIN")
	)
	(segment
		(start 102.930198 -456.89393)
		(end 103.425498 -456.39863)
		(width 0.1651)
		(layer "In11.Cu")
		(net "TDR_DIFF_85_IN4_DIN")
	)
	(segment
		(start 87.175848 -457.560426)
		(end 87.340948 -457.725526)
		(width 0.1651)
		(layer "In11.Cu")
		(net "TDR_DIFF_85_IN4_DIN")
	)
	(segment
		(start 122.264678 -458.722222)
		(end 122.594878 -459.052422)
		(width 0.1651)
		(layer "In11.Cu")
		(net "TDR_DIFF_85_IN4_DIN")
	)
	(segment
		(start 126.379478 -458.722222)
		(end 126.379478 -456.89393)
		(width 0.1651)
		(layer "In11.Cu")
		(net "TDR_DIFF_85_IN4_DIN")
	)
	(segment
		(start 110.870238 -459.052422)
		(end 111.393478 -459.052422)
		(width 0.1651)
		(layer "In11.Cu")
		(net "TDR_DIFF_85_IN4_DIN")
	)
	(segment
		(start 105.531158 -459.052422)
		(end 105.861358 -458.722222)
		(width 0.1651)
		(layer "In11.Cu")
		(net "TDR_DIFF_85_IN4_DIN")
	)
	(segment
		(start 141.035278 -458.722222)
		(end 141.035278 -456.89393)
		(width 0.1651)
		(layer "In11.Cu")
		(net "TDR_DIFF_85_IN4_DIN")
	)
	(segment
		(start 108.462318 -459.052422)
		(end 108.792518 -458.722222)
		(width 0.1651)
		(layer "In11.Cu")
		(net "TDR_DIFF_85_IN4_DIN")
	)
	(segment
		(start 123.448318 -458.722222)
		(end 123.448318 -456.89393)
		(width 0.1651)
		(layer "In11.Cu")
		(net "TDR_DIFF_85_IN4_DIN")
	)
	(segment
		(start 95.388938 -456.39863)
		(end 95.884238 -456.89393)
		(width 0.1651)
		(layer "In11.Cu")
		(net "TDR_DIFF_85_IN4_DIN")
	)
	(segment
		(start 141.530578 -456.39863)
		(end 142.287498 -456.39863)
		(width 0.1651)
		(layer "In11.Cu")
		(net "TDR_DIFF_85_IN4_DIN")
	)
	(segment
		(start 129.310638 -458.722222)
		(end 129.310638 -456.89393)
		(width 0.1651)
		(layer "In11.Cu")
		(net "TDR_DIFF_85_IN4_DIN")
	)
	(segment
		(start 91.700858 -456.39863)
		(end 92.457778 -456.39863)
		(width 0.1651)
		(layer "In11.Cu")
		(net "TDR_DIFF_85_IN4_DIN")
	)
	(segment
		(start 103.425498 -456.39863)
		(end 104.182418 -456.39863)
		(width 0.1651)
		(layer "In11.Cu")
		(net "TDR_DIFF_85_IN4_DIN")
	)
	(segment
		(start 129.805938 -456.39863)
		(end 130.562858 -456.39863)
		(width 0.1651)
		(layer "In11.Cu")
		(net "TDR_DIFF_85_IN4_DIN")
	)
	(segment
		(start 135.668258 -456.39863)
		(end 136.425178 -456.39863)
		(width 0.1651)
		(layer "In11.Cu")
		(net "TDR_DIFF_85_IN4_DIN")
	)
	(segment
		(start 135.172958 -456.89393)
		(end 135.668258 -456.39863)
		(width 0.1651)
		(layer "In11.Cu")
		(net "TDR_DIFF_85_IN4_DIN")
	)
	(segment
		(start 142.782798 -456.89393)
		(end 142.782798 -458.722222)
		(width 0.1651)
		(layer "In11.Cu")
		(net "TDR_DIFF_85_IN4_DIN")
	)
	(segment
		(start 87.175848 -456.596496)
		(end 87.175848 -457.560426)
		(width 0.1651)
		(layer "In11.Cu")
		(net "TDR_DIFF_85_IN4_DIN")
	)
	(segment
		(start 92.457778 -456.39863)
		(end 92.953078 -456.89393)
		(width 0.1651)
		(layer "In11.Cu")
		(net "TDR_DIFF_85_IN4_DIN")
	)
	(segment
		(start 121.769378 -456.39863)
		(end 122.264678 -456.89393)
		(width 0.1651)
		(layer "In11.Cu")
		(net "TDR_DIFF_85_IN4_DIN")
	)
	(segment
		(start 128.457198 -459.052422)
		(end 128.980438 -459.052422)
		(width 0.1651)
		(layer "In11.Cu")
		(net "TDR_DIFF_85_IN4_DIN")
	)
	(segment
		(start 146.897598 -456.89393)
		(end 147.392898 -456.39863)
		(width 0.1651)
		(layer "In11.Cu")
		(net "TDR_DIFF_85_IN4_DIN")
	)
	(segment
		(start 116.732558 -459.052422)
		(end 117.255798 -459.052422)
		(width 0.1651)
		(layer "In11.Cu")
		(net "TDR_DIFF_85_IN4_DIN")
	)
	(segment
		(start 111.723678 -456.89393)
		(end 112.218978 -456.39863)
		(width 0.1651)
		(layer "In11.Cu")
		(net "TDR_DIFF_85_IN4_DIN")
	)
	(segment
		(start 112.975898 -456.39863)
		(end 113.471198 -456.89393)
		(width 0.1651)
		(layer "In11.Cu")
		(net "TDR_DIFF_85_IN4_DIN")
	)
	(segment
		(start 94.136718 -458.722222)
		(end 94.136718 -456.89393)
		(width 0.1651)
		(layer "In11.Cu")
		(net "TDR_DIFF_85_IN4_DIN")
	)
	(segment
		(start 99.668838 -459.052422)
		(end 99.999038 -458.722222)
		(width 0.1651)
		(layer "In11.Cu")
		(net "TDR_DIFF_85_IN4_DIN")
	)
	(segment
		(start 94.136718 -456.89393)
		(end 94.632018 -456.39863)
		(width 0.1651)
		(layer "In11.Cu")
		(net "TDR_DIFF_85_IN4_DIN")
	)
	(segment
		(start 123.943618 -456.39863)
		(end 124.700538 -456.39863)
		(width 0.1651)
		(layer "In11.Cu")
		(net "TDR_DIFF_85_IN4_DIN")
	)
	(segment
		(start 128.980438 -459.052422)
		(end 129.310638 -458.722222)
		(width 0.1651)
		(layer "In11.Cu")
		(net "TDR_DIFF_85_IN4_DIN")
	)
	(segment
		(start 129.310638 -456.89393)
		(end 129.805938 -456.39863)
		(width 0.1651)
		(layer "In11.Cu")
		(net "TDR_DIFF_85_IN4_DIN")
	)
	(segment
		(start 107.608878 -458.722222)
		(end 107.939078 -459.052422)
		(width 0.1651)
		(layer "In11.Cu")
		(net "TDR_DIFF_85_IN4_DIN")
	)
	(segment
		(start 98.815398 -456.89393)
		(end 98.815398 -458.722222)
		(width 0.1651)
		(layer "In11.Cu")
		(net "TDR_DIFF_85_IN4_DIN")
	)
	(segment
		(start 110.044738 -456.39863)
		(end 110.540038 -456.89393)
		(width 0.1651)
		(layer "In11.Cu")
		(net "TDR_DIFF_85_IN4_DIN")
	)
	(segment
		(start 122.264678 -456.89393)
		(end 122.264678 -458.722222)
		(width 0.1651)
		(layer "In11.Cu")
		(net "TDR_DIFF_85_IN4_DIN")
	)
	(segment
		(start 145.713958 -458.722222)
		(end 146.044158 -459.052422)
		(width 0.1651)
		(layer "In11.Cu")
		(net "TDR_DIFF_85_IN4_DIN")
	)
	(segment
		(start 125.195838 -456.89393)
		(end 125.195838 -458.722222)
		(width 0.1651)
		(layer "In11.Cu")
		(net "TDR_DIFF_85_IN4_DIN")
	)
	(segment
		(start 92.953078 -456.89393)
		(end 92.953078 -458.722222)
		(width 0.1651)
		(layer "In11.Cu")
		(net "TDR_DIFF_85_IN4_DIN")
	)
	(segment
		(start 89.526618 -457.725526)
		(end 90.021918 -458.220826)
		(width 0.1651)
		(layer "In11.Cu")
		(net "TDR_DIFF_85_IN4_DIN")
	)
	(segment
		(start 116.402358 -456.89393)
		(end 116.402358 -458.722222)
		(width 0.1651)
		(layer "In11.Cu")
		(net "TDR_DIFF_85_IN4_DIN")
	)
	(segment
		(start 137.250678 -459.052422)
		(end 137.773918 -459.052422)
		(width 0.1651)
		(layer "In11.Cu")
		(net "TDR_DIFF_85_IN4_DIN")
	)
	(segment
		(start 98.815398 -458.722222)
		(end 99.145598 -459.052422)
		(width 0.1651)
		(layer "In11.Cu")
		(net "TDR_DIFF_85_IN4_DIN")
	)
	(segment
		(start 143.112998 -459.052422)
		(end 143.636238 -459.052422)
		(width 0.1651)
		(layer "In11.Cu")
		(net "TDR_DIFF_85_IN4_DIN")
	)
	(segment
		(start 90.021918 -458.220826)
		(end 90.021918 -458.722222)
		(width 0.1651)
		(layer "In11.Cu")
		(net "TDR_DIFF_85_IN4_DIN")
	)
	(segment
		(start 97.067878 -458.722222)
		(end 97.067878 -456.89393)
		(width 0.1651)
		(layer "In11.Cu")
		(net "TDR_DIFF_85_IN4_DIN")
	)
	(segment
		(start 140.181838 -459.052422)
		(end 140.705078 -459.052422)
		(width 0.1651)
		(layer "In11.Cu")
		(net "TDR_DIFF_85_IN4_DIN")
	)
	(segment
		(start 95.884238 -458.722222)
		(end 96.214438 -459.052422)
		(width 0.1651)
		(layer "In11.Cu")
		(net "TDR_DIFF_85_IN4_DIN")
	)
	(segment
		(start 116.402358 -458.722222)
		(end 116.732558 -459.052422)
		(width 0.1651)
		(layer "In11.Cu")
		(net "TDR_DIFF_85_IN4_DIN")
	)
	(segment
		(start 115.907058 -456.39863)
		(end 116.402358 -456.89393)
		(width 0.1651)
		(layer "In11.Cu")
		(net "TDR_DIFF_85_IN4_DIN")
	)
	(segment
		(start 139.356338 -456.39863)
		(end 139.851638 -456.89393)
		(width 0.1651)
		(layer "In11.Cu")
		(net "TDR_DIFF_85_IN4_DIN")
	)
	(segment
		(start 117.255798 -459.052422)
		(end 117.585998 -458.722222)
		(width 0.1651)
		(layer "In11.Cu")
		(net "TDR_DIFF_85_IN4_DIN")
	)
	(segment
		(start 145.218658 -456.39863)
		(end 145.713958 -456.89393)
		(width 0.1651)
		(layer "In11.Cu")
		(net "TDR_DIFF_85_IN4_DIN")
	)
	(segment
		(start 135.172958 -458.722222)
		(end 135.172958 -456.89393)
		(width 0.1651)
		(layer "In11.Cu")
		(net "TDR_DIFF_85_IN4_DIN")
	)
	(segment
		(start 117.585998 -458.722222)
		(end 117.585998 -456.89393)
		(width 0.1651)
		(layer "In11.Cu")
		(net "TDR_DIFF_85_IN4_DIN")
	)
	(segment
		(start 108.792518 -458.722222)
		(end 108.792518 -456.89393)
		(width 0.1651)
		(layer "In11.Cu")
		(net "TDR_DIFF_85_IN4_DIN")
	)
	(segment
		(start 99.145598 -459.052422)
		(end 99.668838 -459.052422)
		(width 0.1651)
		(layer "In11.Cu")
		(net "TDR_DIFF_85_IN4_DIN")
	)
	(segment
		(start 143.966438 -456.89393)
		(end 144.461738 -456.39863)
		(width 0.1651)
		(layer "In11.Cu")
		(net "TDR_DIFF_85_IN4_DIN")
	)
	(segment
		(start 102.599998 -459.052422)
		(end 102.930198 -458.722222)
		(width 0.1651)
		(layer "In11.Cu")
		(net "TDR_DIFF_85_IN4_DIN")
	)
	(segment
		(start 143.636238 -459.052422)
		(end 143.966438 -458.722222)
		(width 0.1651)
		(layer "In11.Cu")
		(net "TDR_DIFF_85_IN4_DIN")
	)
	(segment
		(start 114.654838 -456.89393)
		(end 115.150138 -456.39863)
		(width 0.1651)
		(layer "In11.Cu")
		(net "TDR_DIFF_85_IN4_DIN")
	)
	(segment
		(start 127.631698 -456.39863)
		(end 128.126998 -456.89393)
		(width 0.1651)
		(layer "In11.Cu")
		(net "TDR_DIFF_85_IN4_DIN")
	)
	(segment
		(start 118.838218 -456.39863)
		(end 119.333518 -456.89393)
		(width 0.1651)
		(layer "In11.Cu")
		(net "TDR_DIFF_85_IN4_DIN")
	)
	(segment
		(start 94.632018 -456.39863)
		(end 95.388938 -456.39863)
		(width 0.1651)
		(layer "In11.Cu")
		(net "TDR_DIFF_85_IN4_DIN")
	)
	(segment
		(start 93.283278 -459.052422)
		(end 93.806518 -459.052422)
		(width 0.1651)
		(layer "In11.Cu")
		(net "TDR_DIFF_85_IN4_DIN")
	)
	(segment
		(start 90.352118 -459.052422)
		(end 90.875358 -459.052422)
		(width 0.1651)
		(layer "In11.Cu")
		(net "TDR_DIFF_85_IN4_DIN")
	)
	(segment
		(start 104.677718 -458.722222)
		(end 105.007918 -459.052422)
		(width 0.1651)
		(layer "In11.Cu")
		(net "TDR_DIFF_85_IN4_DIN")
	)
	(segment
		(start 101.251258 -456.39863)
		(end 101.746558 -456.89393)
		(width 0.1651)
		(layer "In11.Cu")
		(net "TDR_DIFF_85_IN4_DIN")
	)
	(segment
		(start 90.021918 -458.722222)
		(end 90.352118 -459.052422)
		(width 0.1651)
		(layer "In11.Cu")
		(net "TDR_DIFF_85_IN4_DIN")
	)
	(segment
		(start 136.920478 -458.722222)
		(end 137.250678 -459.052422)
		(width 0.1651)
		(layer "In11.Cu")
		(net "TDR_DIFF_85_IN4_DIN")
	)
	(segment
		(start 102.930198 -458.722222)
		(end 102.930198 -456.89393)
		(width 0.1651)
		(layer "In11.Cu")
		(net "TDR_DIFF_85_IN4_DIN")
	)
	(segment
		(start 137.773918 -459.052422)
		(end 138.104118 -458.722222)
		(width 0.1651)
		(layer "In11.Cu")
		(net "TDR_DIFF_85_IN4_DIN")
	)
	(segment
		(start 131.058158 -458.722222)
		(end 131.388358 -459.052422)
		(width 0.1651)
		(layer "In11.Cu")
		(net "TDR_DIFF_85_IN4_DIN")
	)
	(segment
		(start 146.044158 -459.052422)
		(end 146.567398 -459.052422)
		(width 0.1651)
		(layer "In11.Cu")
		(net "TDR_DIFF_85_IN4_DIN")
	)
	(segment
		(start 114.324638 -459.052422)
		(end 114.654838 -458.722222)
		(width 0.1651)
		(layer "In11.Cu")
		(net "TDR_DIFF_85_IN4_DIN")
	)
	(segment
		(start 97.563178 -456.39863)
		(end 98.320098 -456.39863)
		(width 0.1651)
		(layer "In11.Cu")
		(net "TDR_DIFF_85_IN4_DIN")
	)
	(segment
		(start 91.205558 -458.722222)
		(end 91.205558 -456.89393)
		(width 0.1651)
		(layer "In11.Cu")
		(net "TDR_DIFF_85_IN4_DIN")
	)
	(segment
		(start 110.540038 -456.89393)
		(end 110.540038 -458.722222)
		(width 0.1651)
		(layer "In11.Cu")
		(net "TDR_DIFF_85_IN4_DIN")
	)
	(segment
		(start 102.076758 -459.052422)
		(end 102.599998 -459.052422)
		(width 0.1651)
		(layer "In11.Cu")
		(net "TDR_DIFF_85_IN4_DIN")
	)
	(segment
		(start 148.645118 -457.395326)
		(end 148.975318 -457.725526)
		(width 0.1651)
		(layer "In11.Cu")
		(net "TDR_DIFF_85_IN4_DIN")
	)
	(segment
		(start 138.104118 -456.89393)
		(end 138.599418 -456.39863)
		(width 0.1651)
		(layer "In11.Cu")
		(net "TDR_DIFF_85_IN4_DIN")
	)
	(segment
		(start 126.874778 -456.39863)
		(end 127.631698 -456.39863)
		(width 0.1651)
		(layer "In11.Cu")
		(net "TDR_DIFF_85_IN4_DIN")
	)
	(segment
		(start 131.058158 -456.89393)
		(end 131.058158 -458.722222)
		(width 0.1651)
		(layer "In11.Cu")
		(net "TDR_DIFF_85_IN4_DIN")
	)
	(segment
		(start 115.150138 -456.39863)
		(end 115.907058 -456.39863)
		(width 0.1651)
		(layer "In11.Cu")
		(net "TDR_DIFF_85_IN4_DIN")
	)
	(segment
		(start 123.448318 -456.89393)
		(end 123.943618 -456.39863)
		(width 0.1651)
		(layer "In11.Cu")
		(net "TDR_DIFF_85_IN4_DIN")
	)
	(segment
		(start 134.319518 -459.052422)
		(end 134.842758 -459.052422)
		(width 0.1651)
		(layer "In11.Cu")
		(net "TDR_DIFF_85_IN4_DIN")
	)
	(segment
		(start 113.471198 -456.89393)
		(end 113.471198 -458.722222)
		(width 0.1651)
		(layer "In11.Cu")
		(net "TDR_DIFF_85_IN4_DIN")
	)
	(segment
		(start 139.851638 -458.722222)
		(end 140.181838 -459.052422)
		(width 0.1651)
		(layer "In11.Cu")
		(net "TDR_DIFF_85_IN4_DIN")
	)
	(segment
		(start 133.494018 -456.39863)
		(end 133.989318 -456.89393)
		(width 0.1651)
		(layer "In11.Cu")
		(net "TDR_DIFF_85_IN4_DIN")
	)
	(segment
		(start 119.333518 -456.89393)
		(end 119.333518 -458.722222)
		(width 0.1651)
		(layer "In11.Cu")
		(net "TDR_DIFF_85_IN4_DIN")
	)
	(segment
		(start 126.379478 -456.89393)
		(end 126.874778 -456.39863)
		(width 0.1651)
		(layer "In11.Cu")
		(net "TDR_DIFF_85_IN4_DIN")
	)
	(segment
		(start 138.599418 -456.39863)
		(end 139.356338 -456.39863)
		(width 0.1651)
		(layer "In11.Cu")
		(net "TDR_DIFF_85_IN4_DIN")
	)
	(segment
		(start 119.333518 -458.722222)
		(end 119.663718 -459.052422)
		(width 0.1651)
		(layer "In11.Cu")
		(net "TDR_DIFF_85_IN4_DIN")
	)
	(segment
		(start 145.713958 -456.89393)
		(end 145.713958 -458.722222)
		(width 0.1651)
		(layer "In11.Cu")
		(net "TDR_DIFF_85_IN4_DIN")
	)
	(segment
		(start 132.241798 -456.89393)
		(end 132.737098 -456.39863)
		(width 0.1651)
		(layer "In11.Cu")
		(net "TDR_DIFF_85_IN4_DIN")
	)
	(segment
		(start 151.209248 -457.560426)
		(end 151.209248 -456.596496)
		(width 0.1651)
		(layer "In11.Cu")
		(net "TDR_DIFF_85_IN4_DIN")
	)
	(segment
		(start 87.340948 -457.725526)
		(end 89.526618 -457.725526)
		(width 0.1651)
		(layer "In11.Cu")
		(net "TDR_DIFF_85_IN4_DIN")
	)
	(segment
		(start 105.861358 -456.89393)
		(end 106.356658 -456.39863)
		(width 0.1651)
		(layer "In11.Cu")
		(net "TDR_DIFF_85_IN4_DIN")
	)
	(segment
		(start 104.677718 -456.89393)
		(end 104.677718 -458.722222)
		(width 0.1651)
		(layer "In11.Cu")
		(net "TDR_DIFF_85_IN4_DIN")
	)
	(segment
		(start 139.851638 -456.89393)
		(end 139.851638 -458.722222)
		(width 0.1651)
		(layer "In11.Cu")
		(net "TDR_DIFF_85_IN4_DIN")
	)
	(segment
		(start 140.705078 -459.052422)
		(end 141.035278 -458.722222)
		(width 0.1651)
		(layer "In11.Cu")
		(net "TDR_DIFF_85_IN4_DIN")
	)
	(segment
		(start 142.287498 -456.39863)
		(end 142.782798 -456.89393)
		(width 0.1651)
		(layer "In11.Cu")
		(net "TDR_DIFF_85_IN4_DIN")
	)
	(segment
		(start 111.723678 -458.722222)
		(end 111.723678 -456.89393)
		(width 0.1651)
		(layer "In11.Cu")
		(net "TDR_DIFF_85_IN4_DIN")
	)
	(segment
		(start 97.067878 -456.89393)
		(end 97.563178 -456.39863)
		(width 0.1651)
		(layer "In11.Cu")
		(net "TDR_DIFF_85_IN4_DIN")
	)
	(segment
		(start 144.461738 -456.39863)
		(end 145.218658 -456.39863)
		(width 0.1651)
		(layer "In11.Cu")
		(net "TDR_DIFF_85_IN4_DIN")
	)
	(segment
		(start 138.104118 -458.722222)
		(end 138.104118 -456.89393)
		(width 0.1651)
		(layer "In11.Cu")
		(net "TDR_DIFF_85_IN4_DIN")
	)
	(segment
		(start 107.939078 -459.052422)
		(end 108.462318 -459.052422)
		(width 0.1651)
		(layer "In11.Cu")
		(net "TDR_DIFF_85_IN4_DIN")
	)
	(segment
		(start 120.517158 -456.89393)
		(end 121.012458 -456.39863)
		(width 0.1651)
		(layer "In11.Cu")
		(net "TDR_DIFF_85_IN4_DIN")
	)
	(segment
		(start 112.218978 -456.39863)
		(end 112.975898 -456.39863)
		(width 0.1651)
		(layer "In11.Cu")
		(net "TDR_DIFF_85_IN4_DIN")
	)
	(segment
		(start 121.012458 -456.39863)
		(end 121.769378 -456.39863)
		(width 0.1651)
		(layer "In11.Cu")
		(net "TDR_DIFF_85_IN4_DIN")
	)
	(segment
		(start 93.806518 -459.052422)
		(end 94.136718 -458.722222)
		(width 0.1651)
		(layer "In11.Cu")
		(net "TDR_DIFF_85_IN4_DIN")
	)
	(segment
		(start 132.241798 -458.722222)
		(end 132.241798 -456.89393)
		(width 0.1651)
		(layer "In11.Cu")
		(net "TDR_DIFF_85_IN4_DIN")
	)
	(segment
		(start 120.186958 -459.052422)
		(end 120.517158 -458.722222)
		(width 0.1651)
		(layer "In11.Cu")
		(net "TDR_DIFF_85_IN4_DIN")
	)
	(segment
		(start 126.049278 -459.052422)
		(end 126.379478 -458.722222)
		(width 0.1651)
		(layer "In11.Cu")
		(net "TDR_DIFF_85_IN4_DIN")
	)
	(segment
		(start 142.782798 -458.722222)
		(end 143.112998 -459.052422)
		(width 0.1651)
		(layer "In11.Cu")
		(net "TDR_DIFF_85_IN4_DIN")
	)
	(segment
		(start 105.861358 -458.722222)
		(end 105.861358 -456.89393)
		(width 0.1651)
		(layer "In11.Cu")
		(net "TDR_DIFF_85_IN4_DIN")
	)
	(segment
		(start 113.471198 -458.722222)
		(end 113.801398 -459.052422)
		(width 0.1651)
		(layer "In11.Cu")
		(net "TDR_DIFF_85_IN4_DIN")
	)
	(segment
		(start 99.999038 -458.722222)
		(end 99.999038 -456.89393)
		(width 0.1651)
		(layer "In11.Cu")
		(net "TDR_DIFF_85_IN4_DIN")
	)
	(segment
		(start 151.044148 -457.725526)
		(end 151.209248 -457.560426)
		(width 0.1651)
		(layer "In11.Cu")
		(net "TDR_DIFF_85_IN4_DIN")
	)
	(segment
		(start 136.425178 -456.39863)
		(end 136.920478 -456.89393)
		(width 0.1651)
		(layer "In11.Cu")
		(net "TDR_DIFF_85_IN4_DIN")
	)
	(segment
		(start 134.842758 -459.052422)
		(end 135.172958 -458.722222)
		(width 0.1651)
		(layer "In11.Cu")
		(net "TDR_DIFF_85_IN4_DIN")
	)
	(segment
		(start 147.392898 -456.39863)
		(end 148.149818 -456.39863)
		(width 0.1651)
		(layer "In11.Cu")
		(net "TDR_DIFF_85_IN4_DIN")
	)
	(segment
		(start 132.737098 -456.39863)
		(end 133.494018 -456.39863)
		(width 0.1651)
		(layer "In11.Cu")
		(net "TDR_DIFF_85_IN4_DIN")
	)
	(segment
		(start 92.953078 -458.722222)
		(end 93.283278 -459.052422)
		(width 0.1651)
		(layer "In11.Cu")
		(net "TDR_DIFF_85_IN4_DIN")
	)
	(segment
		(start 124.700538 -456.39863)
		(end 125.195838 -456.89393)
		(width 0.1651)
		(layer "In11.Cu")
		(net "TDR_DIFF_85_IN4_DIN")
	)
	(segment
		(start 100.494338 -456.39863)
		(end 101.251258 -456.39863)
		(width 0.1651)
		(layer "In11.Cu")
		(net "TDR_DIFF_85_IN4_DIN")
	)
	(segment
		(start 105.007918 -459.052422)
		(end 105.531158 -459.052422)
		(width 0.1651)
		(layer "In11.Cu")
		(net "TDR_DIFF_85_IN4_DIN")
	)
	(segment
		(start 95.884238 -456.89393)
		(end 95.884238 -458.722222)
		(width 0.1651)
		(layer "In11.Cu")
		(net "TDR_DIFF_85_IN4_DIN")
	)
	(segment
		(start 91.205558 -456.89393)
		(end 91.700858 -456.39863)
		(width 0.1651)
		(layer "In11.Cu")
		(net "TDR_DIFF_85_IN4_DIN")
	)
	(segment
		(start 98.320098 -456.39863)
		(end 98.815398 -456.89393)
		(width 0.1651)
		(layer "In11.Cu")
		(net "TDR_DIFF_85_IN4_DIN")
	)
	(segment
		(start 148.149818 -456.39863)
		(end 148.645118 -456.89393)
		(width 0.1651)
		(layer "In11.Cu")
		(net "TDR_DIFF_85_IN4_DIN")
	)
	(segment
		(start 146.567398 -459.052422)
		(end 146.897598 -458.722222)
		(width 0.1651)
		(layer "In11.Cu")
		(net "TDR_DIFF_85_IN4_DIN")
	)
	(segment
		(start 110.540038 -458.722222)
		(end 110.870238 -459.052422)
		(width 0.1651)
		(layer "In11.Cu")
		(net "TDR_DIFF_85_IN4_DIN")
	)
	(segment
		(start 48.905922 -450.383148)
		(end 49.401222 -450.878448)
		(width 0.1651)
		(layer "In15.Cu")
		(net "TDR_DIFF_85_IN6_DIN")
	)
	(segment
		(start 32.144462 -453.03694)
		(end 32.667702 -453.03694)
		(width 0.1651)
		(layer "In15.Cu")
		(net "TDR_DIFF_85_IN6_DIN")
	)
	(segment
		(start 64.910462 -453.03694)
		(end 65.240662 -452.70674)
		(width 0.1651)
		(layer "In15.Cu")
		(net "TDR_DIFF_85_IN6_DIN")
	)
	(segment
		(start 75.286362 -450.383148)
		(end 75.781662 -450.878448)
		(width 0.1651)
		(layer "In15.Cu")
		(net "TDR_DIFF_85_IN6_DIN")
	)
	(segment
		(start 32.997902 -452.70674)
		(end 32.997902 -450.878448)
		(width 0.1651)
		(layer "In15.Cu")
		(net "TDR_DIFF_85_IN6_DIN")
	)
	(segment
		(start 39.355522 -450.383148)
		(end 40.112442 -450.383148)
		(width 0.1651)
		(layer "In15.Cu")
		(net "TDR_DIFF_85_IN6_DIN")
	)
	(segment
		(start 38.860222 -450.878448)
		(end 39.355522 -450.383148)
		(width 0.1651)
		(layer "In15.Cu")
		(net "TDR_DIFF_85_IN6_DIN")
	)
	(segment
		(start 35.929062 -450.878448)
		(end 36.424362 -450.383148)
		(width 0.1651)
		(layer "In15.Cu")
		(net "TDR_DIFF_85_IN6_DIN")
	)
	(segment
		(start 18.011902 -453.03694)
		(end 18.342102 -452.70674)
		(width 0.1651)
		(layer "In15.Cu")
		(net "TDR_DIFF_85_IN6_DIN")
	)
	(segment
		(start 65.735962 -450.383148)
		(end 66.492882 -450.383148)
		(width 0.1651)
		(layer "In15.Cu")
		(net "TDR_DIFF_85_IN6_DIN")
	)
	(segment
		(start 14.312392 -451.544944)
		(end 14.477492 -451.710044)
		(width 0.1651)
		(layer "In15.Cu")
		(net "TDR_DIFF_85_IN6_DIN")
	)
	(segment
		(start 21.273262 -450.878448)
		(end 21.768562 -450.383148)
		(width 0.1651)
		(layer "In15.Cu")
		(net "TDR_DIFF_85_IN6_DIN")
	)
	(segment
		(start 61.979302 -453.03694)
		(end 62.309502 -452.70674)
		(width 0.1651)
		(layer "In15.Cu")
		(net "TDR_DIFF_85_IN6_DIN")
	)
	(segment
		(start 47.653702 -452.70674)
		(end 47.653702 -450.878448)
		(width 0.1651)
		(layer "In15.Cu")
		(net "TDR_DIFF_85_IN6_DIN")
	)
	(segment
		(start 18.837402 -450.383148)
		(end 19.594322 -450.383148)
		(width 0.1651)
		(layer "In15.Cu")
		(net "TDR_DIFF_85_IN6_DIN")
	)
	(segment
		(start 41.791382 -450.878448)
		(end 42.286682 -450.383148)
		(width 0.1651)
		(layer "In15.Cu")
		(net "TDR_DIFF_85_IN6_DIN")
	)
	(segment
		(start 30.066742 -450.878448)
		(end 30.562042 -450.383148)
		(width 0.1651)
		(layer "In15.Cu")
		(net "TDR_DIFF_85_IN6_DIN")
	)
	(segment
		(start 54.768242 -450.383148)
		(end 55.263542 -450.878448)
		(width 0.1651)
		(layer "In15.Cu")
		(net "TDR_DIFF_85_IN6_DIN")
	)
	(segment
		(start 43.869102 -453.03694)
		(end 44.392342 -453.03694)
		(width 0.1651)
		(layer "In15.Cu")
		(net "TDR_DIFF_85_IN6_DIN")
	)
	(segment
		(start 65.240662 -452.70674)
		(end 65.240662 -450.878448)
		(width 0.1651)
		(layer "In15.Cu")
		(net "TDR_DIFF_85_IN6_DIN")
	)
	(segment
		(start 50.584862 -450.878448)
		(end 51.080162 -450.383148)
		(width 0.1651)
		(layer "In15.Cu")
		(net "TDR_DIFF_85_IN6_DIN")
	)
	(segment
		(start 48.149002 -450.383148)
		(end 48.905922 -450.383148)
		(width 0.1651)
		(layer "In15.Cu")
		(net "TDR_DIFF_85_IN6_DIN")
	)
	(segment
		(start 20.089622 -452.70674)
		(end 20.419822 -453.03694)
		(width 0.1651)
		(layer "In15.Cu")
		(net "TDR_DIFF_85_IN6_DIN")
	)
	(segment
		(start 68.171822 -450.878448)
		(end 68.667122 -450.383148)
		(width 0.1651)
		(layer "In15.Cu")
		(net "TDR_DIFF_85_IN6_DIN")
	)
	(segment
		(start 44.392342 -453.03694)
		(end 44.722542 -452.70674)
		(width 0.1651)
		(layer "In15.Cu")
		(net "TDR_DIFF_85_IN6_DIN")
	)
	(segment
		(start 61.125862 -450.878448)
		(end 61.125862 -452.70674)
		(width 0.1651)
		(layer "In15.Cu")
		(net "TDR_DIFF_85_IN6_DIN")
	)
	(segment
		(start 38.006782 -453.03694)
		(end 38.530022 -453.03694)
		(width 0.1651)
		(layer "In15.Cu")
		(net "TDR_DIFF_85_IN6_DIN")
	)
	(segment
		(start 40.607742 -452.70674)
		(end 40.937942 -453.03694)
		(width 0.1651)
		(layer "In15.Cu")
		(net "TDR_DIFF_85_IN6_DIN")
	)
	(segment
		(start 59.378342 -450.878448)
		(end 59.873642 -450.383148)
		(width 0.1651)
		(layer "In15.Cu")
		(net "TDR_DIFF_85_IN6_DIN")
	)
	(segment
		(start 73.703942 -453.03694)
		(end 74.034142 -452.70674)
		(width 0.1651)
		(layer "In15.Cu")
		(net "TDR_DIFF_85_IN6_DIN")
	)
	(segment
		(start 29.213302 -453.03694)
		(end 29.736542 -453.03694)
		(width 0.1651)
		(layer "In15.Cu")
		(net "TDR_DIFF_85_IN6_DIN")
	)
	(segment
		(start 71.102982 -452.70674)
		(end 71.102982 -450.878448)
		(width 0.1651)
		(layer "In15.Cu")
		(net "TDR_DIFF_85_IN6_DIN")
	)
	(segment
		(start 44.722542 -450.878448)
		(end 45.217842 -450.383148)
		(width 0.1651)
		(layer "In15.Cu")
		(net "TDR_DIFF_85_IN6_DIN")
	)
	(segment
		(start 21.768562 -450.383148)
		(end 22.525482 -450.383148)
		(width 0.1651)
		(layer "In15.Cu")
		(net "TDR_DIFF_85_IN6_DIN")
	)
	(segment
		(start 64.387222 -453.03694)
		(end 64.910462 -453.03694)
		(width 0.1651)
		(layer "In15.Cu")
		(net "TDR_DIFF_85_IN6_DIN")
	)
	(segment
		(start 24.204422 -450.878448)
		(end 24.699722 -450.383148)
		(width 0.1651)
		(layer "In15.Cu")
		(net "TDR_DIFF_85_IN6_DIN")
	)
	(segment
		(start 26.805382 -453.03694)
		(end 27.135582 -452.70674)
		(width 0.1651)
		(layer "In15.Cu")
		(net "TDR_DIFF_85_IN6_DIN")
	)
	(segment
		(start 74.034142 -450.878448)
		(end 74.529442 -450.383148)
		(width 0.1651)
		(layer "In15.Cu")
		(net "TDR_DIFF_85_IN6_DIN")
	)
	(segment
		(start 71.102982 -450.878448)
		(end 71.598282 -450.383148)
		(width 0.1651)
		(layer "In15.Cu")
		(net "TDR_DIFF_85_IN6_DIN")
	)
	(segment
		(start 28.387802 -450.383148)
		(end 28.883102 -450.878448)
		(width 0.1651)
		(layer "In15.Cu")
		(net "TDR_DIFF_85_IN6_DIN")
	)
	(segment
		(start 20.419822 -453.03694)
		(end 20.943062 -453.03694)
		(width 0.1651)
		(layer "In15.Cu")
		(net "TDR_DIFF_85_IN6_DIN")
	)
	(segment
		(start 25.456642 -450.383148)
		(end 25.951942 -450.878448)
		(width 0.1651)
		(layer "In15.Cu")
		(net "TDR_DIFF_85_IN6_DIN")
	)
	(segment
		(start 78.345792 -451.544944)
		(end 78.345792 -450.581014)
		(width 0.1651)
		(layer "In15.Cu")
		(net "TDR_DIFF_85_IN6_DIN")
	)
	(segment
		(start 76.111862 -451.710044)
		(end 78.180692 -451.710044)
		(width 0.1651)
		(layer "In15.Cu")
		(net "TDR_DIFF_85_IN6_DIN")
	)
	(segment
		(start 55.593742 -453.03694)
		(end 56.116982 -453.03694)
		(width 0.1651)
		(layer "In15.Cu")
		(net "TDR_DIFF_85_IN6_DIN")
	)
	(segment
		(start 56.116982 -453.03694)
		(end 56.447182 -452.70674)
		(width 0.1651)
		(layer "In15.Cu")
		(net "TDR_DIFF_85_IN6_DIN")
	)
	(segment
		(start 58.194702 -450.878448)
		(end 58.194702 -452.70674)
		(width 0.1651)
		(layer "In15.Cu")
		(net "TDR_DIFF_85_IN6_DIN")
	)
	(segment
		(start 25.951942 -452.70674)
		(end 26.282142 -453.03694)
		(width 0.1651)
		(layer "In15.Cu")
		(net "TDR_DIFF_85_IN6_DIN")
	)
	(segment
		(start 20.943062 -453.03694)
		(end 21.273262 -452.70674)
		(width 0.1651)
		(layer "In15.Cu")
		(net "TDR_DIFF_85_IN6_DIN")
	)
	(segment
		(start 21.273262 -452.70674)
		(end 21.273262 -450.878448)
		(width 0.1651)
		(layer "In15.Cu")
		(net "TDR_DIFF_85_IN6_DIN")
	)
	(segment
		(start 67.841622 -453.03694)
		(end 68.171822 -452.70674)
		(width 0.1651)
		(layer "In15.Cu")
		(net "TDR_DIFF_85_IN6_DIN")
	)
	(segment
		(start 31.318962 -450.383148)
		(end 31.814262 -450.878448)
		(width 0.1651)
		(layer "In15.Cu")
		(net "TDR_DIFF_85_IN6_DIN")
	)
	(segment
		(start 14.477492 -451.710044)
		(end 16.663162 -451.710044)
		(width 0.1651)
		(layer "In15.Cu")
		(net "TDR_DIFF_85_IN6_DIN")
	)
	(segment
		(start 64.057022 -450.878448)
		(end 64.057022 -452.70674)
		(width 0.1651)
		(layer "In15.Cu")
		(net "TDR_DIFF_85_IN6_DIN")
	)
	(segment
		(start 14.312392 -450.581014)
		(end 14.312392 -451.544944)
		(width 0.1651)
		(layer "In15.Cu")
		(net "TDR_DIFF_85_IN6_DIN")
	)
	(segment
		(start 64.057022 -452.70674)
		(end 64.387222 -453.03694)
		(width 0.1651)
		(layer "In15.Cu")
		(net "TDR_DIFF_85_IN6_DIN")
	)
	(segment
		(start 74.034142 -452.70674)
		(end 74.034142 -450.878448)
		(width 0.1651)
		(layer "In15.Cu")
		(net "TDR_DIFF_85_IN6_DIN")
	)
	(segment
		(start 30.562042 -450.383148)
		(end 31.318962 -450.383148)
		(width 0.1651)
		(layer "In15.Cu")
		(net "TDR_DIFF_85_IN6_DIN")
	)
	(segment
		(start 32.997902 -450.878448)
		(end 33.493202 -450.383148)
		(width 0.1651)
		(layer "In15.Cu")
		(net "TDR_DIFF_85_IN6_DIN")
	)
	(segment
		(start 57.699402 -450.383148)
		(end 58.194702 -450.878448)
		(width 0.1651)
		(layer "In15.Cu")
		(net "TDR_DIFF_85_IN6_DIN")
	)
	(segment
		(start 66.988182 -450.878448)
		(end 66.988182 -452.70674)
		(width 0.1651)
		(layer "In15.Cu")
		(net "TDR_DIFF_85_IN6_DIN")
	)
	(segment
		(start 37.181282 -450.383148)
		(end 37.676582 -450.878448)
		(width 0.1651)
		(layer "In15.Cu")
		(net "TDR_DIFF_85_IN6_DIN")
	)
	(segment
		(start 46.470062 -450.878448)
		(end 46.470062 -452.70674)
		(width 0.1651)
		(layer "In15.Cu")
		(net "TDR_DIFF_85_IN6_DIN")
	)
	(segment
		(start 75.781662 -450.878448)
		(end 75.781662 -451.379844)
		(width 0.1651)
		(layer "In15.Cu")
		(net "TDR_DIFF_85_IN6_DIN")
	)
	(segment
		(start 19.594322 -450.383148)
		(end 20.089622 -450.878448)
		(width 0.1651)
		(layer "In15.Cu")
		(net "TDR_DIFF_85_IN6_DIN")
	)
	(segment
		(start 22.525482 -450.383148)
		(end 23.020782 -450.878448)
		(width 0.1651)
		(layer "In15.Cu")
		(net "TDR_DIFF_85_IN6_DIN")
	)
	(segment
		(start 44.722542 -452.70674)
		(end 44.722542 -450.878448)
		(width 0.1651)
		(layer "In15.Cu")
		(net "TDR_DIFF_85_IN6_DIN")
	)
	(segment
		(start 52.332382 -452.70674)
		(end 52.662582 -453.03694)
		(width 0.1651)
		(layer "In15.Cu")
		(net "TDR_DIFF_85_IN6_DIN")
	)
	(segment
		(start 59.048142 -453.03694)
		(end 59.378342 -452.70674)
		(width 0.1651)
		(layer "In15.Cu")
		(net "TDR_DIFF_85_IN6_DIN")
	)
	(segment
		(start 53.185822 -453.03694)
		(end 53.516022 -452.70674)
		(width 0.1651)
		(layer "In15.Cu")
		(net "TDR_DIFF_85_IN6_DIN")
	)
	(segment
		(start 49.731422 -453.03694)
		(end 50.254662 -453.03694)
		(width 0.1651)
		(layer "In15.Cu")
		(net "TDR_DIFF_85_IN6_DIN")
	)
	(segment
		(start 71.598282 -450.383148)
		(end 72.355202 -450.383148)
		(width 0.1651)
		(layer "In15.Cu")
		(net "TDR_DIFF_85_IN6_DIN")
	)
	(segment
		(start 72.850502 -450.878448)
		(end 72.850502 -452.70674)
		(width 0.1651)
		(layer "In15.Cu")
		(net "TDR_DIFF_85_IN6_DIN")
	)
	(segment
		(start 75.781662 -451.379844)
		(end 76.111862 -451.710044)
		(width 0.1651)
		(layer "In15.Cu")
		(net "TDR_DIFF_85_IN6_DIN")
	)
	(segment
		(start 34.250122 -450.383148)
		(end 34.745422 -450.878448)
		(width 0.1651)
		(layer "In15.Cu")
		(net "TDR_DIFF_85_IN6_DIN")
	)
	(segment
		(start 59.873642 -450.383148)
		(end 60.630562 -450.383148)
		(width 0.1651)
		(layer "In15.Cu")
		(net "TDR_DIFF_85_IN6_DIN")
	)
	(segment
		(start 35.075622 -453.03694)
		(end 35.598862 -453.03694)
		(width 0.1651)
		(layer "In15.Cu")
		(net "TDR_DIFF_85_IN6_DIN")
	)
	(segment
		(start 34.745422 -452.70674)
		(end 35.075622 -453.03694)
		(width 0.1651)
		(layer "In15.Cu")
		(net "TDR_DIFF_85_IN6_DIN")
	)
	(segment
		(start 49.401222 -450.878448)
		(end 49.401222 -452.70674)
		(width 0.1651)
		(layer "In15.Cu")
		(net "TDR_DIFF_85_IN6_DIN")
	)
	(segment
		(start 62.309502 -452.70674)
		(end 62.309502 -450.878448)
		(width 0.1651)
		(layer "In15.Cu")
		(net "TDR_DIFF_85_IN6_DIN")
	)
	(segment
		(start 55.263542 -452.70674)
		(end 55.593742 -453.03694)
		(width 0.1651)
		(layer "In15.Cu")
		(net "TDR_DIFF_85_IN6_DIN")
	)
	(segment
		(start 23.350982 -453.03694)
		(end 23.874222 -453.03694)
		(width 0.1651)
		(layer "In15.Cu")
		(net "TDR_DIFF_85_IN6_DIN")
	)
	(segment
		(start 47.653702 -450.878448)
		(end 48.149002 -450.383148)
		(width 0.1651)
		(layer "In15.Cu")
		(net "TDR_DIFF_85_IN6_DIN")
	)
	(segment
		(start 30.066742 -452.70674)
		(end 30.066742 -450.878448)
		(width 0.1651)
		(layer "In15.Cu")
		(net "TDR_DIFF_85_IN6_DIN")
	)
	(segment
		(start 41.461182 -453.03694)
		(end 41.791382 -452.70674)
		(width 0.1651)
		(layer "In15.Cu")
		(net "TDR_DIFF_85_IN6_DIN")
	)
	(segment
		(start 27.630882 -450.383148)
		(end 28.387802 -450.383148)
		(width 0.1651)
		(layer "In15.Cu")
		(net "TDR_DIFF_85_IN6_DIN")
	)
	(segment
		(start 33.493202 -450.383148)
		(end 34.250122 -450.383148)
		(width 0.1651)
		(layer "In15.Cu")
		(net "TDR_DIFF_85_IN6_DIN")
	)
	(segment
		(start 20.089622 -450.878448)
		(end 20.089622 -452.70674)
		(width 0.1651)
		(layer "In15.Cu")
		(net "TDR_DIFF_85_IN6_DIN")
	)
	(segment
		(start 73.180702 -453.03694)
		(end 73.703942 -453.03694)
		(width 0.1651)
		(layer "In15.Cu")
		(net "TDR_DIFF_85_IN6_DIN")
	)
	(segment
		(start 35.929062 -452.70674)
		(end 35.929062 -450.878448)
		(width 0.1651)
		(layer "In15.Cu")
		(net "TDR_DIFF_85_IN6_DIN")
	)
	(segment
		(start 46.800262 -453.03694)
		(end 47.323502 -453.03694)
		(width 0.1651)
		(layer "In15.Cu")
		(net "TDR_DIFF_85_IN6_DIN")
	)
	(segment
		(start 46.470062 -452.70674)
		(end 46.800262 -453.03694)
		(width 0.1651)
		(layer "In15.Cu")
		(net "TDR_DIFF_85_IN6_DIN")
	)
	(segment
		(start 50.584862 -452.70674)
		(end 50.584862 -450.878448)
		(width 0.1651)
		(layer "In15.Cu")
		(net "TDR_DIFF_85_IN6_DIN")
	)
	(segment
		(start 69.424042 -450.383148)
		(end 69.919342 -450.878448)
		(width 0.1651)
		(layer "In15.Cu")
		(net "TDR_DIFF_85_IN6_DIN")
	)
	(segment
		(start 58.524902 -453.03694)
		(end 59.048142 -453.03694)
		(width 0.1651)
		(layer "In15.Cu")
		(net "TDR_DIFF_85_IN6_DIN")
	)
	(segment
		(start 40.112442 -450.383148)
		(end 40.607742 -450.878448)
		(width 0.1651)
		(layer "In15.Cu")
		(net "TDR_DIFF_85_IN6_DIN")
	)
	(segment
		(start 66.988182 -452.70674)
		(end 67.318382 -453.03694)
		(width 0.1651)
		(layer "In15.Cu")
		(net "TDR_DIFF_85_IN6_DIN")
	)
	(segment
		(start 41.791382 -452.70674)
		(end 41.791382 -450.878448)
		(width 0.1651)
		(layer "In15.Cu")
		(net "TDR_DIFF_85_IN6_DIN")
	)
	(segment
		(start 27.135582 -450.878448)
		(end 27.630882 -450.383148)
		(width 0.1651)
		(layer "In15.Cu")
		(net "TDR_DIFF_85_IN6_DIN")
	)
	(segment
		(start 31.814262 -452.70674)
		(end 32.144462 -453.03694)
		(width 0.1651)
		(layer "In15.Cu")
		(net "TDR_DIFF_85_IN6_DIN")
	)
	(segment
		(start 53.516022 -452.70674)
		(end 53.516022 -450.878448)
		(width 0.1651)
		(layer "In15.Cu")
		(net "TDR_DIFF_85_IN6_DIN")
	)
	(segment
		(start 67.318382 -453.03694)
		(end 67.841622 -453.03694)
		(width 0.1651)
		(layer "In15.Cu")
		(net "TDR_DIFF_85_IN6_DIN")
	)
	(segment
		(start 43.043602 -450.383148)
		(end 43.538902 -450.878448)
		(width 0.1651)
		(layer "In15.Cu")
		(net "TDR_DIFF_85_IN6_DIN")
	)
	(segment
		(start 29.736542 -453.03694)
		(end 30.066742 -452.70674)
		(width 0.1651)
		(layer "In15.Cu")
		(net "TDR_DIFF_85_IN6_DIN")
	)
	(segment
		(start 24.204422 -452.70674)
		(end 24.204422 -450.878448)
		(width 0.1651)
		(layer "In15.Cu")
		(net "TDR_DIFF_85_IN6_DIN")
	)
	(segment
		(start 43.538902 -452.70674)
		(end 43.869102 -453.03694)
		(width 0.1651)
		(layer "In15.Cu")
		(net "TDR_DIFF_85_IN6_DIN")
	)
	(segment
		(start 62.804802 -450.383148)
		(end 63.561722 -450.383148)
		(width 0.1651)
		(layer "In15.Cu")
		(net "TDR_DIFF_85_IN6_DIN")
	)
	(segment
		(start 43.538902 -450.878448)
		(end 43.538902 -452.70674)
		(width 0.1651)
		(layer "In15.Cu")
		(net "TDR_DIFF_85_IN6_DIN")
	)
	(segment
		(start 40.607742 -450.878448)
		(end 40.607742 -452.70674)
		(width 0.1651)
		(layer "In15.Cu")
		(net "TDR_DIFF_85_IN6_DIN")
	)
	(segment
		(start 36.424362 -450.383148)
		(end 37.181282 -450.383148)
		(width 0.1651)
		(layer "In15.Cu")
		(net "TDR_DIFF_85_IN6_DIN")
	)
	(segment
		(start 28.883102 -452.70674)
		(end 29.213302 -453.03694)
		(width 0.1651)
		(layer "In15.Cu")
		(net "TDR_DIFF_85_IN6_DIN")
	)
	(segment
		(start 34.745422 -450.878448)
		(end 34.745422 -452.70674)
		(width 0.1651)
		(layer "In15.Cu")
		(net "TDR_DIFF_85_IN6_DIN")
	)
	(segment
		(start 37.676582 -450.878448)
		(end 37.676582 -452.70674)
		(width 0.1651)
		(layer "In15.Cu")
		(net "TDR_DIFF_85_IN6_DIN")
	)
	(segment
		(start 27.135582 -452.70674)
		(end 27.135582 -450.878448)
		(width 0.1651)
		(layer "In15.Cu")
		(net "TDR_DIFF_85_IN6_DIN")
	)
	(segment
		(start 23.874222 -453.03694)
		(end 24.204422 -452.70674)
		(width 0.1651)
		(layer "In15.Cu")
		(net "TDR_DIFF_85_IN6_DIN")
	)
	(segment
		(start 72.355202 -450.383148)
		(end 72.850502 -450.878448)
		(width 0.1651)
		(layer "In15.Cu")
		(net "TDR_DIFF_85_IN6_DIN")
	)
	(segment
		(start 78.180692 -451.710044)
		(end 78.345792 -451.544944)
		(width 0.1651)
		(layer "In15.Cu")
		(net "TDR_DIFF_85_IN6_DIN")
	)
	(segment
		(start 69.919342 -452.70674)
		(end 70.249542 -453.03694)
		(width 0.1651)
		(layer "In15.Cu")
		(net "TDR_DIFF_85_IN6_DIN")
	)
	(segment
		(start 56.447182 -450.878448)
		(end 56.942482 -450.383148)
		(width 0.1651)
		(layer "In15.Cu")
		(net "TDR_DIFF_85_IN6_DIN")
	)
	(segment
		(start 72.850502 -452.70674)
		(end 73.180702 -453.03694)
		(width 0.1651)
		(layer "In15.Cu")
		(net "TDR_DIFF_85_IN6_DIN")
	)
	(segment
		(start 65.240662 -450.878448)
		(end 65.735962 -450.383148)
		(width 0.1651)
		(layer "In15.Cu")
		(net "TDR_DIFF_85_IN6_DIN")
	)
	(segment
		(start 59.378342 -452.70674)
		(end 59.378342 -450.878448)
		(width 0.1651)
		(layer "In15.Cu")
		(net "TDR_DIFF_85_IN6_DIN")
	)
	(segment
		(start 70.772782 -453.03694)
		(end 71.102982 -452.70674)
		(width 0.1651)
		(layer "In15.Cu")
		(net "TDR_DIFF_85_IN6_DIN")
	)
	(segment
		(start 24.699722 -450.383148)
		(end 25.456642 -450.383148)
		(width 0.1651)
		(layer "In15.Cu")
		(net "TDR_DIFF_85_IN6_DIN")
	)
	(segment
		(start 35.598862 -453.03694)
		(end 35.929062 -452.70674)
		(width 0.1651)
		(layer "In15.Cu")
		(net "TDR_DIFF_85_IN6_DIN")
	)
	(segment
		(start 37.676582 -452.70674)
		(end 38.006782 -453.03694)
		(width 0.1651)
		(layer "In15.Cu")
		(net "TDR_DIFF_85_IN6_DIN")
	)
	(segment
		(start 42.286682 -450.383148)
		(end 43.043602 -450.383148)
		(width 0.1651)
		(layer "In15.Cu")
		(net "TDR_DIFF_85_IN6_DIN")
	)
	(segment
		(start 18.342102 -452.70674)
		(end 18.342102 -450.878448)
		(width 0.1651)
		(layer "In15.Cu")
		(net "TDR_DIFF_85_IN6_DIN")
	)
	(segment
		(start 62.309502 -450.878448)
		(end 62.804802 -450.383148)
		(width 0.1651)
		(layer "In15.Cu")
		(net "TDR_DIFF_85_IN6_DIN")
	)
	(segment
		(start 58.194702 -452.70674)
		(end 58.524902 -453.03694)
		(width 0.1651)
		(layer "In15.Cu")
		(net "TDR_DIFF_85_IN6_DIN")
	)
	(segment
		(start 60.630562 -450.383148)
		(end 61.125862 -450.878448)
		(width 0.1651)
		(layer "In15.Cu")
		(net "TDR_DIFF_85_IN6_DIN")
	)
	(segment
		(start 38.860222 -452.70674)
		(end 38.860222 -450.878448)
		(width 0.1651)
		(layer "In15.Cu")
		(net "TDR_DIFF_85_IN6_DIN")
	)
	(segment
		(start 45.974762 -450.383148)
		(end 46.470062 -450.878448)
		(width 0.1651)
		(layer "In15.Cu")
		(net "TDR_DIFF_85_IN6_DIN")
	)
	(segment
		(start 63.561722 -450.383148)
		(end 64.057022 -450.878448)
		(width 0.1651)
		(layer "In15.Cu")
		(net "TDR_DIFF_85_IN6_DIN")
	)
	(segment
		(start 53.516022 -450.878448)
		(end 54.011322 -450.383148)
		(width 0.1651)
		(layer "In15.Cu")
		(net "TDR_DIFF_85_IN6_DIN")
	)
	(segment
		(start 74.529442 -450.383148)
		(end 75.286362 -450.383148)
		(width 0.1651)
		(layer "In15.Cu")
		(net "TDR_DIFF_85_IN6_DIN")
	)
	(segment
		(start 52.332382 -450.878448)
		(end 52.332382 -452.70674)
		(width 0.1651)
		(layer "In15.Cu")
		(net "TDR_DIFF_85_IN6_DIN")
	)
	(segment
		(start 49.401222 -452.70674)
		(end 49.731422 -453.03694)
		(width 0.1651)
		(layer "In15.Cu")
		(net "TDR_DIFF_85_IN6_DIN")
	)
	(segment
		(start 70.249542 -453.03694)
		(end 70.772782 -453.03694)
		(width 0.1651)
		(layer "In15.Cu")
		(net "TDR_DIFF_85_IN6_DIN")
	)
	(segment
		(start 51.837082 -450.383148)
		(end 52.332382 -450.878448)
		(width 0.1651)
		(layer "In15.Cu")
		(net "TDR_DIFF_85_IN6_DIN")
	)
	(segment
		(start 18.342102 -450.878448)
		(end 18.837402 -450.383148)
		(width 0.1651)
		(layer "In15.Cu")
		(net "TDR_DIFF_85_IN6_DIN")
	)
	(segment
		(start 25.951942 -450.878448)
		(end 25.951942 -452.70674)
		(width 0.1651)
		(layer "In15.Cu")
		(net "TDR_DIFF_85_IN6_DIN")
	)
	(segment
		(start 16.663162 -451.710044)
		(end 17.158462 -452.205344)
		(width 0.1651)
		(layer "In15.Cu")
		(net "TDR_DIFF_85_IN6_DIN")
	)
	(segment
		(start 69.919342 -450.878448)
		(end 69.919342 -452.70674)
		(width 0.1651)
		(layer "In15.Cu")
		(net "TDR_DIFF_85_IN6_DIN")
	)
	(segment
		(start 45.217842 -450.383148)
		(end 45.974762 -450.383148)
		(width 0.1651)
		(layer "In15.Cu")
		(net "TDR_DIFF_85_IN6_DIN")
	)
	(segment
		(start 61.456062 -453.03694)
		(end 61.979302 -453.03694)
		(width 0.1651)
		(layer "In15.Cu")
		(net "TDR_DIFF_85_IN6_DIN")
	)
	(segment
		(start 17.488662 -453.03694)
		(end 18.011902 -453.03694)
		(width 0.1651)
		(layer "In15.Cu")
		(net "TDR_DIFF_85_IN6_DIN")
	)
	(segment
		(start 52.662582 -453.03694)
		(end 53.185822 -453.03694)
		(width 0.1651)
		(layer "In15.Cu")
		(net "TDR_DIFF_85_IN6_DIN")
	)
	(segment
		(start 50.254662 -453.03694)
		(end 50.584862 -452.70674)
		(width 0.1651)
		(layer "In15.Cu")
		(net "TDR_DIFF_85_IN6_DIN")
	)
	(segment
		(start 56.447182 -452.70674)
		(end 56.447182 -450.878448)
		(width 0.1651)
		(layer "In15.Cu")
		(net "TDR_DIFF_85_IN6_DIN")
	)
	(segment
		(start 68.171822 -452.70674)
		(end 68.171822 -450.878448)
		(width 0.1651)
		(layer "In15.Cu")
		(net "TDR_DIFF_85_IN6_DIN")
	)
	(segment
		(start 26.282142 -453.03694)
		(end 26.805382 -453.03694)
		(width 0.1651)
		(layer "In15.Cu")
		(net "TDR_DIFF_85_IN6_DIN")
	)
	(segment
		(start 38.530022 -453.03694)
		(end 38.860222 -452.70674)
		(width 0.1651)
		(layer "In15.Cu")
		(net "TDR_DIFF_85_IN6_DIN")
	)
	(segment
		(start 68.667122 -450.383148)
		(end 69.424042 -450.383148)
		(width 0.1651)
		(layer "In15.Cu")
		(net "TDR_DIFF_85_IN6_DIN")
	)
	(segment
		(start 66.492882 -450.383148)
		(end 66.988182 -450.878448)
		(width 0.1651)
		(layer "In15.Cu")
		(net "TDR_DIFF_85_IN6_DIN")
	)
	(segment
		(start 61.125862 -452.70674)
		(end 61.456062 -453.03694)
		(width 0.1651)
		(layer "In15.Cu")
		(net "TDR_DIFF_85_IN6_DIN")
	)
	(segment
		(start 17.158462 -452.70674)
		(end 17.488662 -453.03694)
		(width 0.1651)
		(layer "In15.Cu")
		(net "TDR_DIFF_85_IN6_DIN")
	)
	(segment
		(start 56.942482 -450.383148)
		(end 57.699402 -450.383148)
		(width 0.1651)
		(layer "In15.Cu")
		(net "TDR_DIFF_85_IN6_DIN")
	)
	(segment
		(start 54.011322 -450.383148)
		(end 54.768242 -450.383148)
		(width 0.1651)
		(layer "In15.Cu")
		(net "TDR_DIFF_85_IN6_DIN")
	)
	(segment
		(start 23.020782 -452.70674)
		(end 23.350982 -453.03694)
		(width 0.1651)
		(layer "In15.Cu")
		(net "TDR_DIFF_85_IN6_DIN")
	)
	(segment
		(start 32.667702 -453.03694)
		(end 32.997902 -452.70674)
		(width 0.1651)
		(layer "In15.Cu")
		(net "TDR_DIFF_85_IN6_DIN")
	)
	(segment
		(start 55.263542 -450.878448)
		(end 55.263542 -452.70674)
		(width 0.1651)
		(layer "In15.Cu")
		(net "TDR_DIFF_85_IN6_DIN")
	)
	(segment
		(start 17.158462 -452.205344)
		(end 17.158462 -452.70674)
		(width 0.1651)
		(layer "In15.Cu")
		(net "TDR_DIFF_85_IN6_DIN")
	)
	(segment
		(start 40.937942 -453.03694)
		(end 41.461182 -453.03694)
		(width 0.1651)
		(layer "In15.Cu")
		(net "TDR_DIFF_85_IN6_DIN")
	)
	(segment
		(start 31.814262 -450.878448)
		(end 31.814262 -452.70674)
		(width 0.1651)
		(layer "In15.Cu")
		(net "TDR_DIFF_85_IN6_DIN")
	)
	(segment
		(start 23.020782 -450.878448)
		(end 23.020782 -452.70674)
		(width 0.1651)
		(layer "In15.Cu")
		(net "TDR_DIFF_85_IN6_DIN")
	)
	(segment
		(start 51.080162 -450.383148)
		(end 51.837082 -450.383148)
		(width 0.1651)
		(layer "In15.Cu")
		(net "TDR_DIFF_85_IN6_DIN")
	)
	(segment
		(start 28.883102 -450.878448)
		(end 28.883102 -452.70674)
		(width 0.1651)
		(layer "In15.Cu")
		(net "TDR_DIFF_85_IN6_DIN")
	)
	(segment
		(start 47.323502 -453.03694)
		(end 47.653702 -452.70674)
		(width 0.1651)
		(layer "In15.Cu")
		(net "TDR_DIFF_85_IN6_DIN")
	)
	(segment
		(start 110.258098 -457.01077)
		(end 110.258098 -458.839062)
		(width 0.1651)
		(layer "In11.Cu")
		(net "TDR_DIFF_85_IN4_DIP")
	)
	(segment
		(start 129.097278 -459.334362)
		(end 129.592578 -458.839062)
		(width 0.1651)
		(layer "In11.Cu")
		(net "TDR_DIFF_85_IN4_DIP")
	)
	(segment
		(start 131.271518 -459.334362)
		(end 132.028438 -459.334362)
		(width 0.1651)
		(layer "In11.Cu")
		(net "TDR_DIFF_85_IN4_DIP")
	)
	(segment
		(start 104.065578 -456.68057)
		(end 104.395778 -457.01077)
		(width 0.1651)
		(layer "In11.Cu")
		(net "TDR_DIFF_85_IN4_DIP")
	)
	(segment
		(start 121.129298 -456.68057)
		(end 121.652538 -456.68057)
		(width 0.1651)
		(layer "In11.Cu")
		(net "TDR_DIFF_85_IN4_DIP")
	)
	(segment
		(start 119.051578 -458.839062)
		(end 119.546878 -459.334362)
		(width 0.1651)
		(layer "In11.Cu")
		(net "TDR_DIFF_85_IN4_DIP")
	)
	(segment
		(start 147.179538 -458.839062)
		(end 147.179538 -457.01077)
		(width 0.1651)
		(layer "In11.Cu")
		(net "TDR_DIFF_85_IN4_DIP")
	)
	(segment
		(start 104.891078 -459.334362)
		(end 105.647998 -459.334362)
		(width 0.1651)
		(layer "In11.Cu")
		(net "TDR_DIFF_85_IN4_DIP")
	)
	(segment
		(start 115.790218 -456.68057)
		(end 116.120418 -457.01077)
		(width 0.1651)
		(layer "In11.Cu")
		(net "TDR_DIFF_85_IN4_DIP")
	)
	(segment
		(start 99.785678 -459.334362)
		(end 100.280978 -458.839062)
		(width 0.1651)
		(layer "In11.Cu")
		(net "TDR_DIFF_85_IN4_DIP")
	)
	(segment
		(start 102.716838 -459.334362)
		(end 103.212138 -458.839062)
		(width 0.1651)
		(layer "In11.Cu")
		(net "TDR_DIFF_85_IN4_DIP")
	)
	(segment
		(start 120.799098 -458.839062)
		(end 120.799098 -457.01077)
		(width 0.1651)
		(layer "In11.Cu")
		(net "TDR_DIFF_85_IN4_DIP")
	)
	(segment
		(start 94.748858 -456.68057)
		(end 95.272098 -456.68057)
		(width 0.1651)
		(layer "In11.Cu")
		(net "TDR_DIFF_85_IN4_DIP")
	)
	(segment
		(start 91.817698 -456.68057)
		(end 92.340938 -456.68057)
		(width 0.1651)
		(layer "In11.Cu")
		(net "TDR_DIFF_85_IN4_DIP")
	)
	(segment
		(start 138.386058 -458.839062)
		(end 138.386058 -457.01077)
		(width 0.1651)
		(layer "In11.Cu")
		(net "TDR_DIFF_85_IN4_DIP")
	)
	(segment
		(start 126.661418 -458.839062)
		(end 126.661418 -457.01077)
		(width 0.1651)
		(layer "In11.Cu")
		(net "TDR_DIFF_85_IN4_DIP")
	)
	(segment
		(start 146.684238 -459.334362)
		(end 147.179538 -458.839062)
		(width 0.1651)
		(layer "In11.Cu")
		(net "TDR_DIFF_85_IN4_DIP")
	)
	(segment
		(start 91.487498 -457.01077)
		(end 91.817698 -456.68057)
		(width 0.1651)
		(layer "In11.Cu")
		(net "TDR_DIFF_85_IN4_DIP")
	)
	(segment
		(start 112.859058 -456.68057)
		(end 113.189258 -457.01077)
		(width 0.1651)
		(layer "In11.Cu")
		(net "TDR_DIFF_85_IN4_DIP")
	)
	(segment
		(start 107.326938 -458.839062)
		(end 107.822238 -459.334362)
		(width 0.1651)
		(layer "In11.Cu")
		(net "TDR_DIFF_85_IN4_DIP")
	)
	(segment
		(start 133.377178 -456.68057)
		(end 133.707378 -457.01077)
		(width 0.1651)
		(layer "In11.Cu")
		(net "TDR_DIFF_85_IN4_DIP")
	)
	(segment
		(start 148.363178 -457.01077)
		(end 148.363178 -457.512166)
		(width 0.1651)
		(layer "In11.Cu")
		(net "TDR_DIFF_85_IN4_DIP")
	)
	(segment
		(start 112.005618 -457.01077)
		(end 112.335818 -456.68057)
		(width 0.1651)
		(layer "In11.Cu")
		(net "TDR_DIFF_85_IN4_DIP")
	)
	(segment
		(start 132.853938 -456.68057)
		(end 133.377178 -456.68057)
		(width 0.1651)
		(layer "In11.Cu")
		(net "TDR_DIFF_85_IN4_DIP")
	)
	(segment
		(start 112.335818 -456.68057)
		(end 112.859058 -456.68057)
		(width 0.1651)
		(layer "In11.Cu")
		(net "TDR_DIFF_85_IN4_DIP")
	)
	(segment
		(start 148.858478 -458.007466)
		(end 151.044148 -458.007466)
		(width 0.1651)
		(layer "In11.Cu")
		(net "TDR_DIFF_85_IN4_DIP")
	)
	(segment
		(start 124.060458 -456.68057)
		(end 124.583698 -456.68057)
		(width 0.1651)
		(layer "In11.Cu")
		(net "TDR_DIFF_85_IN4_DIP")
	)
	(segment
		(start 145.101818 -456.68057)
		(end 145.432018 -457.01077)
		(width 0.1651)
		(layer "In11.Cu")
		(net "TDR_DIFF_85_IN4_DIP")
	)
	(segment
		(start 119.546878 -459.334362)
		(end 120.303798 -459.334362)
		(width 0.1651)
		(layer "In11.Cu")
		(net "TDR_DIFF_85_IN4_DIP")
	)
	(segment
		(start 123.234958 -459.334362)
		(end 123.730258 -458.839062)
		(width 0.1651)
		(layer "In11.Cu")
		(net "TDR_DIFF_85_IN4_DIP")
	)
	(segment
		(start 93.166438 -459.334362)
		(end 93.923358 -459.334362)
		(width 0.1651)
		(layer "In11.Cu")
		(net "TDR_DIFF_85_IN4_DIP")
	)
	(segment
		(start 130.776218 -457.01077)
		(end 130.776218 -458.839062)
		(width 0.1651)
		(layer "In11.Cu")
		(net "TDR_DIFF_85_IN4_DIP")
	)
	(segment
		(start 129.922778 -456.68057)
		(end 130.446018 -456.68057)
		(width 0.1651)
		(layer "In11.Cu")
		(net "TDR_DIFF_85_IN4_DIP")
	)
	(segment
		(start 142.996158 -459.334362)
		(end 143.753078 -459.334362)
		(width 0.1651)
		(layer "In11.Cu")
		(net "TDR_DIFF_85_IN4_DIP")
	)
	(segment
		(start 112.005618 -458.839062)
		(end 112.005618 -457.01077)
		(width 0.1651)
		(layer "In11.Cu")
		(net "TDR_DIFF_85_IN4_DIP")
	)
	(segment
		(start 97.349818 -458.839062)
		(end 97.349818 -457.01077)
		(width 0.1651)
		(layer "In11.Cu")
		(net "TDR_DIFF_85_IN4_DIP")
	)
	(segment
		(start 128.340358 -459.334362)
		(end 129.097278 -459.334362)
		(width 0.1651)
		(layer "In11.Cu")
		(net "TDR_DIFF_85_IN4_DIP")
	)
	(segment
		(start 99.028758 -459.334362)
		(end 99.785678 -459.334362)
		(width 0.1651)
		(layer "In11.Cu")
		(net "TDR_DIFF_85_IN4_DIP")
	)
	(segment
		(start 144.248378 -457.01077)
		(end 144.578578 -456.68057)
		(width 0.1651)
		(layer "In11.Cu")
		(net "TDR_DIFF_85_IN4_DIP")
	)
	(segment
		(start 103.542338 -456.68057)
		(end 104.065578 -456.68057)
		(width 0.1651)
		(layer "In11.Cu")
		(net "TDR_DIFF_85_IN4_DIP")
	)
	(segment
		(start 124.583698 -456.68057)
		(end 124.913898 -457.01077)
		(width 0.1651)
		(layer "In11.Cu")
		(net "TDR_DIFF_85_IN4_DIP")
	)
	(segment
		(start 130.446018 -456.68057)
		(end 130.776218 -457.01077)
		(width 0.1651)
		(layer "In11.Cu")
		(net "TDR_DIFF_85_IN4_DIP")
	)
	(segment
		(start 108.579158 -459.334362)
		(end 109.074458 -458.839062)
		(width 0.1651)
		(layer "In11.Cu")
		(net "TDR_DIFF_85_IN4_DIP")
	)
	(segment
		(start 130.776218 -458.839062)
		(end 131.271518 -459.334362)
		(width 0.1651)
		(layer "In11.Cu")
		(net "TDR_DIFF_85_IN4_DIP")
	)
	(segment
		(start 139.569698 -457.01077)
		(end 139.569698 -458.839062)
		(width 0.1651)
		(layer "In11.Cu")
		(net "TDR_DIFF_85_IN4_DIP")
	)
	(segment
		(start 129.592578 -458.839062)
		(end 129.592578 -457.01077)
		(width 0.1651)
		(layer "In11.Cu")
		(net "TDR_DIFF_85_IN4_DIP")
	)
	(segment
		(start 114.936778 -457.01077)
		(end 115.266978 -456.68057)
		(width 0.1651)
		(layer "In11.Cu")
		(net "TDR_DIFF_85_IN4_DIP")
	)
	(segment
		(start 141.317218 -457.01077)
		(end 141.647418 -456.68057)
		(width 0.1651)
		(layer "In11.Cu")
		(net "TDR_DIFF_85_IN4_DIP")
	)
	(segment
		(start 100.611178 -456.68057)
		(end 101.134418 -456.68057)
		(width 0.1651)
		(layer "In11.Cu")
		(net "TDR_DIFF_85_IN4_DIP")
	)
	(segment
		(start 116.615718 -459.334362)
		(end 117.372638 -459.334362)
		(width 0.1651)
		(layer "In11.Cu")
		(net "TDR_DIFF_85_IN4_DIP")
	)
	(segment
		(start 127.845058 -458.839062)
		(end 128.340358 -459.334362)
		(width 0.1651)
		(layer "In11.Cu")
		(net "TDR_DIFF_85_IN4_DIP")
	)
	(segment
		(start 121.652538 -456.68057)
		(end 121.982738 -457.01077)
		(width 0.1651)
		(layer "In11.Cu")
		(net "TDR_DIFF_85_IN4_DIP")
	)
	(segment
		(start 105.647998 -459.334362)
		(end 106.143298 -458.839062)
		(width 0.1651)
		(layer "In11.Cu")
		(net "TDR_DIFF_85_IN4_DIP")
	)
	(segment
		(start 141.317218 -458.839062)
		(end 141.317218 -457.01077)
		(width 0.1651)
		(layer "In11.Cu")
		(net "TDR_DIFF_85_IN4_DIP")
	)
	(segment
		(start 151.044148 -458.007466)
		(end 151.209248 -458.172566)
		(width 0.1651)
		(layer "In11.Cu")
		(net "TDR_DIFF_85_IN4_DIP")
	)
	(segment
		(start 92.671138 -458.839062)
		(end 93.166438 -459.334362)
		(width 0.1651)
		(layer "In11.Cu")
		(net "TDR_DIFF_85_IN4_DIP")
	)
	(segment
		(start 109.404658 -456.68057)
		(end 109.927898 -456.68057)
		(width 0.1651)
		(layer "In11.Cu")
		(net "TDR_DIFF_85_IN4_DIP")
	)
	(segment
		(start 95.272098 -456.68057)
		(end 95.602298 -457.01077)
		(width 0.1651)
		(layer "In11.Cu")
		(net "TDR_DIFF_85_IN4_DIP")
	)
	(segment
		(start 122.478038 -459.334362)
		(end 123.234958 -459.334362)
		(width 0.1651)
		(layer "In11.Cu")
		(net "TDR_DIFF_85_IN4_DIP")
	)
	(segment
		(start 127.845058 -457.01077)
		(end 127.845058 -458.839062)
		(width 0.1651)
		(layer "In11.Cu")
		(net "TDR_DIFF_85_IN4_DIP")
	)
	(segment
		(start 111.510318 -459.334362)
		(end 112.005618 -458.839062)
		(width 0.1651)
		(layer "In11.Cu")
		(net "TDR_DIFF_85_IN4_DIP")
	)
	(segment
		(start 106.143298 -458.839062)
		(end 106.143298 -457.01077)
		(width 0.1651)
		(layer "In11.Cu")
		(net "TDR_DIFF_85_IN4_DIP")
	)
	(segment
		(start 97.680018 -456.68057)
		(end 98.203258 -456.68057)
		(width 0.1651)
		(layer "In11.Cu")
		(net "TDR_DIFF_85_IN4_DIP")
	)
	(segment
		(start 87.175848 -458.172566)
		(end 87.340948 -458.007466)
		(width 0.1651)
		(layer "In11.Cu")
		(net "TDR_DIFF_85_IN4_DIP")
	)
	(segment
		(start 87.340948 -458.007466)
		(end 89.409778 -458.007466)
		(width 0.1651)
		(layer "In11.Cu")
		(net "TDR_DIFF_85_IN4_DIP")
	)
	(segment
		(start 91.487498 -458.839062)
		(end 91.487498 -457.01077)
		(width 0.1651)
		(layer "In11.Cu")
		(net "TDR_DIFF_85_IN4_DIP")
	)
	(segment
		(start 145.432018 -457.01077)
		(end 145.432018 -458.839062)
		(width 0.1651)
		(layer "In11.Cu")
		(net "TDR_DIFF_85_IN4_DIP")
	)
	(segment
		(start 142.500858 -458.839062)
		(end 142.996158 -459.334362)
		(width 0.1651)
		(layer "In11.Cu")
		(net "TDR_DIFF_85_IN4_DIP")
	)
	(segment
		(start 148.032978 -456.68057)
		(end 148.363178 -457.01077)
		(width 0.1651)
		(layer "In11.Cu")
		(net "TDR_DIFF_85_IN4_DIP")
	)
	(segment
		(start 107.822238 -459.334362)
		(end 108.579158 -459.334362)
		(width 0.1651)
		(layer "In11.Cu")
		(net "TDR_DIFF_85_IN4_DIP")
	)
	(segment
		(start 129.592578 -457.01077)
		(end 129.922778 -456.68057)
		(width 0.1651)
		(layer "In11.Cu")
		(net "TDR_DIFF_85_IN4_DIP")
	)
	(segment
		(start 104.395778 -457.01077)
		(end 104.395778 -458.839062)
		(width 0.1651)
		(layer "In11.Cu")
		(net "TDR_DIFF_85_IN4_DIP")
	)
	(segment
		(start 96.854518 -459.334362)
		(end 97.349818 -458.839062)
		(width 0.1651)
		(layer "In11.Cu")
		(net "TDR_DIFF_85_IN4_DIP")
	)
	(segment
		(start 145.432018 -458.839062)
		(end 145.927318 -459.334362)
		(width 0.1651)
		(layer "In11.Cu")
		(net "TDR_DIFF_85_IN4_DIP")
	)
	(segment
		(start 139.569698 -458.839062)
		(end 140.064998 -459.334362)
		(width 0.1651)
		(layer "In11.Cu")
		(net "TDR_DIFF_85_IN4_DIP")
	)
	(segment
		(start 134.202678 -459.334362)
		(end 134.959598 -459.334362)
		(width 0.1651)
		(layer "In11.Cu")
		(net "TDR_DIFF_85_IN4_DIP")
	)
	(segment
		(start 147.509738 -456.68057)
		(end 148.032978 -456.68057)
		(width 0.1651)
		(layer "In11.Cu")
		(net "TDR_DIFF_85_IN4_DIP")
	)
	(segment
		(start 109.927898 -456.68057)
		(end 110.258098 -457.01077)
		(width 0.1651)
		(layer "In11.Cu")
		(net "TDR_DIFF_85_IN4_DIP")
	)
	(segment
		(start 144.578578 -456.68057)
		(end 145.101818 -456.68057)
		(width 0.1651)
		(layer "In11.Cu")
		(net "TDR_DIFF_85_IN4_DIP")
	)
	(segment
		(start 98.203258 -456.68057)
		(end 98.533458 -457.01077)
		(width 0.1651)
		(layer "In11.Cu")
		(net "TDR_DIFF_85_IN4_DIP")
	)
	(segment
		(start 117.867938 -457.01077)
		(end 118.198138 -456.68057)
		(width 0.1651)
		(layer "In11.Cu")
		(net "TDR_DIFF_85_IN4_DIP")
	)
	(segment
		(start 126.166118 -459.334362)
		(end 126.661418 -458.839062)
		(width 0.1651)
		(layer "In11.Cu")
		(net "TDR_DIFF_85_IN4_DIP")
	)
	(segment
		(start 113.189258 -457.01077)
		(end 113.189258 -458.839062)
		(width 0.1651)
		(layer "In11.Cu")
		(net "TDR_DIFF_85_IN4_DIP")
	)
	(segment
		(start 90.235278 -459.334362)
		(end 90.992198 -459.334362)
		(width 0.1651)
		(layer "In11.Cu")
		(net "TDR_DIFF_85_IN4_DIP")
	)
	(segment
		(start 113.684558 -459.334362)
		(end 114.441478 -459.334362)
		(width 0.1651)
		(layer "In11.Cu")
		(net "TDR_DIFF_85_IN4_DIP")
	)
	(segment
		(start 138.386058 -457.01077)
		(end 138.716258 -456.68057)
		(width 0.1651)
		(layer "In11.Cu")
		(net "TDR_DIFF_85_IN4_DIP")
	)
	(segment
		(start 104.395778 -458.839062)
		(end 104.891078 -459.334362)
		(width 0.1651)
		(layer "In11.Cu")
		(net "TDR_DIFF_85_IN4_DIP")
	)
	(segment
		(start 107.326938 -457.01077)
		(end 107.326938 -458.839062)
		(width 0.1651)
		(layer "In11.Cu")
		(net "TDR_DIFF_85_IN4_DIP")
	)
	(segment
		(start 135.785098 -456.68057)
		(end 136.308338 -456.68057)
		(width 0.1651)
		(layer "In11.Cu")
		(net "TDR_DIFF_85_IN4_DIP")
	)
	(segment
		(start 135.454898 -458.839062)
		(end 135.454898 -457.01077)
		(width 0.1651)
		(layer "In11.Cu")
		(net "TDR_DIFF_85_IN4_DIP")
	)
	(segment
		(start 136.308338 -456.68057)
		(end 136.638538 -457.01077)
		(width 0.1651)
		(layer "In11.Cu")
		(net "TDR_DIFF_85_IN4_DIP")
	)
	(segment
		(start 127.514858 -456.68057)
		(end 127.845058 -457.01077)
		(width 0.1651)
		(layer "In11.Cu")
		(net "TDR_DIFF_85_IN4_DIP")
	)
	(segment
		(start 116.120418 -457.01077)
		(end 116.120418 -458.839062)
		(width 0.1651)
		(layer "In11.Cu")
		(net "TDR_DIFF_85_IN4_DIP")
	)
	(segment
		(start 101.134418 -456.68057)
		(end 101.464618 -457.01077)
		(width 0.1651)
		(layer "In11.Cu")
		(net "TDR_DIFF_85_IN4_DIP")
	)
	(segment
		(start 114.936778 -458.839062)
		(end 114.936778 -457.01077)
		(width 0.1651)
		(layer "In11.Cu")
		(net "TDR_DIFF_85_IN4_DIP")
	)
	(segment
		(start 114.441478 -459.334362)
		(end 114.936778 -458.839062)
		(width 0.1651)
		(layer "In11.Cu")
		(net "TDR_DIFF_85_IN4_DIP")
	)
	(segment
		(start 106.143298 -457.01077)
		(end 106.473498 -456.68057)
		(width 0.1651)
		(layer "In11.Cu")
		(net "TDR_DIFF_85_IN4_DIP")
	)
	(segment
		(start 125.409198 -459.334362)
		(end 126.166118 -459.334362)
		(width 0.1651)
		(layer "In11.Cu")
		(net "TDR_DIFF_85_IN4_DIP")
	)
	(segment
		(start 138.716258 -456.68057)
		(end 139.239498 -456.68057)
		(width 0.1651)
		(layer "In11.Cu")
		(net "TDR_DIFF_85_IN4_DIP")
	)
	(segment
		(start 140.821918 -459.334362)
		(end 141.317218 -458.839062)
		(width 0.1651)
		(layer "In11.Cu")
		(net "TDR_DIFF_85_IN4_DIP")
	)
	(segment
		(start 93.923358 -459.334362)
		(end 94.418658 -458.839062)
		(width 0.1651)
		(layer "In11.Cu")
		(net "TDR_DIFF_85_IN4_DIP")
	)
	(segment
		(start 147.179538 -457.01077)
		(end 147.509738 -456.68057)
		(width 0.1651)
		(layer "In11.Cu")
		(net "TDR_DIFF_85_IN4_DIP")
	)
	(segment
		(start 142.170658 -456.68057)
		(end 142.500858 -457.01077)
		(width 0.1651)
		(layer "In11.Cu")
		(net "TDR_DIFF_85_IN4_DIP")
	)
	(segment
		(start 94.418658 -457.01077)
		(end 94.748858 -456.68057)
		(width 0.1651)
		(layer "In11.Cu")
		(net "TDR_DIFF_85_IN4_DIP")
	)
	(segment
		(start 144.248378 -458.839062)
		(end 144.248378 -457.01077)
		(width 0.1651)
		(layer "In11.Cu")
		(net "TDR_DIFF_85_IN4_DIP")
	)
	(segment
		(start 119.051578 -457.01077)
		(end 119.051578 -458.839062)
		(width 0.1651)
		(layer "In11.Cu")
		(net "TDR_DIFF_85_IN4_DIP")
	)
	(segment
		(start 100.280978 -457.01077)
		(end 100.611178 -456.68057)
		(width 0.1651)
		(layer "In11.Cu")
		(net "TDR_DIFF_85_IN4_DIP")
	)
	(segment
		(start 120.799098 -457.01077)
		(end 121.129298 -456.68057)
		(width 0.1651)
		(layer "In11.Cu")
		(net "TDR_DIFF_85_IN4_DIP")
	)
	(segment
		(start 141.647418 -456.68057)
		(end 142.170658 -456.68057)
		(width 0.1651)
		(layer "In11.Cu")
		(net "TDR_DIFF_85_IN4_DIP")
	)
	(segment
		(start 137.133838 -459.334362)
		(end 137.890758 -459.334362)
		(width 0.1651)
		(layer "In11.Cu")
		(net "TDR_DIFF_85_IN4_DIP")
	)
	(segment
		(start 134.959598 -459.334362)
		(end 135.454898 -458.839062)
		(width 0.1651)
		(layer "In11.Cu")
		(net "TDR_DIFF_85_IN4_DIP")
	)
	(segment
		(start 143.753078 -459.334362)
		(end 144.248378 -458.839062)
		(width 0.1651)
		(layer "In11.Cu")
		(net "TDR_DIFF_85_IN4_DIP")
	)
	(segment
		(start 140.064998 -459.334362)
		(end 140.821918 -459.334362)
		(width 0.1651)
		(layer "In11.Cu")
		(net "TDR_DIFF_85_IN4_DIP")
	)
	(segment
		(start 94.418658 -458.839062)
		(end 94.418658 -457.01077)
		(width 0.1651)
		(layer "In11.Cu")
		(net "TDR_DIFF_85_IN4_DIP")
	)
	(segment
		(start 110.753398 -459.334362)
		(end 111.510318 -459.334362)
		(width 0.1651)
		(layer "In11.Cu")
		(net "TDR_DIFF_85_IN4_DIP")
	)
	(segment
		(start 121.982738 -458.839062)
		(end 122.478038 -459.334362)
		(width 0.1651)
		(layer "In11.Cu")
		(net "TDR_DIFF_85_IN4_DIP")
	)
	(segment
		(start 124.913898 -457.01077)
		(end 124.913898 -458.839062)
		(width 0.1651)
		(layer "In11.Cu")
		(net "TDR_DIFF_85_IN4_DIP")
	)
	(segment
		(start 95.602298 -457.01077)
		(end 95.602298 -458.839062)
		(width 0.1651)
		(layer "In11.Cu")
		(net "TDR_DIFF_85_IN4_DIP")
	)
	(segment
		(start 103.212138 -458.839062)
		(end 103.212138 -457.01077)
		(width 0.1651)
		(layer "In11.Cu")
		(net "TDR_DIFF_85_IN4_DIP")
	)
	(segment
		(start 118.721378 -456.68057)
		(end 119.051578 -457.01077)
		(width 0.1651)
		(layer "In11.Cu")
		(net "TDR_DIFF_85_IN4_DIP")
	)
	(segment
		(start 97.349818 -457.01077)
		(end 97.680018 -456.68057)
		(width 0.1651)
		(layer "In11.Cu")
		(net "TDR_DIFF_85_IN4_DIP")
	)
	(segment
		(start 139.239498 -456.68057)
		(end 139.569698 -457.01077)
		(width 0.1651)
		(layer "In11.Cu")
		(net "TDR_DIFF_85_IN4_DIP")
	)
	(segment
		(start 151.209248 -458.172566)
		(end 151.209248 -459.136496)
		(width 0.1651)
		(layer "In11.Cu")
		(net "TDR_DIFF_85_IN4_DIP")
	)
	(segment
		(start 123.730258 -458.839062)
		(end 123.730258 -457.01077)
		(width 0.1651)
		(layer "In11.Cu")
		(net "TDR_DIFF_85_IN4_DIP")
	)
	(segment
		(start 113.189258 -458.839062)
		(end 113.684558 -459.334362)
		(width 0.1651)
		(layer "In11.Cu")
		(net "TDR_DIFF_85_IN4_DIP")
	)
	(segment
		(start 96.097598 -459.334362)
		(end 96.854518 -459.334362)
		(width 0.1651)
		(layer "In11.Cu")
		(net "TDR_DIFF_85_IN4_DIP")
	)
	(segment
		(start 106.473498 -456.68057)
		(end 106.996738 -456.68057)
		(width 0.1651)
		(layer "In11.Cu")
		(net "TDR_DIFF_85_IN4_DIP")
	)
	(segment
		(start 124.913898 -458.839062)
		(end 125.409198 -459.334362)
		(width 0.1651)
		(layer "In11.Cu")
		(net "TDR_DIFF_85_IN4_DIP")
	)
	(segment
		(start 137.890758 -459.334362)
		(end 138.386058 -458.839062)
		(width 0.1651)
		(layer "In11.Cu")
		(net "TDR_DIFF_85_IN4_DIP")
	)
	(segment
		(start 132.523738 -457.01077)
		(end 132.853938 -456.68057)
		(width 0.1651)
		(layer "In11.Cu")
		(net "TDR_DIFF_85_IN4_DIP")
	)
	(segment
		(start 106.996738 -456.68057)
		(end 107.326938 -457.01077)
		(width 0.1651)
		(layer "In11.Cu")
		(net "TDR_DIFF_85_IN4_DIP")
	)
	(segment
		(start 89.739978 -458.337666)
		(end 89.739978 -458.839062)
		(width 0.1651)
		(layer "In11.Cu")
		(net "TDR_DIFF_85_IN4_DIP")
	)
	(segment
		(start 148.363178 -457.512166)
		(end 148.858478 -458.007466)
		(width 0.1651)
		(layer "In11.Cu")
		(net "TDR_DIFF_85_IN4_DIP")
	)
	(segment
		(start 110.258098 -458.839062)
		(end 110.753398 -459.334362)
		(width 0.1651)
		(layer "In11.Cu")
		(net "TDR_DIFF_85_IN4_DIP")
	)
	(segment
		(start 136.638538 -457.01077)
		(end 136.638538 -458.839062)
		(width 0.1651)
		(layer "In11.Cu")
		(net "TDR_DIFF_85_IN4_DIP")
	)
	(segment
		(start 109.074458 -457.01077)
		(end 109.404658 -456.68057)
		(width 0.1651)
		(layer "In11.Cu")
		(net "TDR_DIFF_85_IN4_DIP")
	)
	(segment
		(start 118.198138 -456.68057)
		(end 118.721378 -456.68057)
		(width 0.1651)
		(layer "In11.Cu")
		(net "TDR_DIFF_85_IN4_DIP")
	)
	(segment
		(start 120.303798 -459.334362)
		(end 120.799098 -458.839062)
		(width 0.1651)
		(layer "In11.Cu")
		(net "TDR_DIFF_85_IN4_DIP")
	)
	(segment
		(start 115.266978 -456.68057)
		(end 115.790218 -456.68057)
		(width 0.1651)
		(layer "In11.Cu")
		(net "TDR_DIFF_85_IN4_DIP")
	)
	(segment
		(start 101.464618 -457.01077)
		(end 101.464618 -458.839062)
		(width 0.1651)
		(layer "In11.Cu")
		(net "TDR_DIFF_85_IN4_DIP")
	)
	(segment
		(start 133.707378 -458.839062)
		(end 134.202678 -459.334362)
		(width 0.1651)
		(layer "In11.Cu")
		(net "TDR_DIFF_85_IN4_DIP")
	)
	(segment
		(start 135.454898 -457.01077)
		(end 135.785098 -456.68057)
		(width 0.1651)
		(layer "In11.Cu")
		(net "TDR_DIFF_85_IN4_DIP")
	)
	(segment
		(start 117.867938 -458.839062)
		(end 117.867938 -457.01077)
		(width 0.1651)
		(layer "In11.Cu")
		(net "TDR_DIFF_85_IN4_DIP")
	)
	(segment
		(start 145.927318 -459.334362)
		(end 146.684238 -459.334362)
		(width 0.1651)
		(layer "In11.Cu")
		(net "TDR_DIFF_85_IN4_DIP")
	)
	(segment
		(start 101.464618 -458.839062)
		(end 101.959918 -459.334362)
		(width 0.1651)
		(layer "In11.Cu")
		(net "TDR_DIFF_85_IN4_DIP")
	)
	(segment
		(start 142.500858 -457.01077)
		(end 142.500858 -458.839062)
		(width 0.1651)
		(layer "In11.Cu")
		(net "TDR_DIFF_85_IN4_DIP")
	)
	(segment
		(start 116.120418 -458.839062)
		(end 116.615718 -459.334362)
		(width 0.1651)
		(layer "In11.Cu")
		(net "TDR_DIFF_85_IN4_DIP")
	)
	(segment
		(start 132.028438 -459.334362)
		(end 132.523738 -458.839062)
		(width 0.1651)
		(layer "In11.Cu")
		(net "TDR_DIFF_85_IN4_DIP")
	)
	(segment
		(start 132.523738 -458.839062)
		(end 132.523738 -457.01077)
		(width 0.1651)
		(layer "In11.Cu")
		(net "TDR_DIFF_85_IN4_DIP")
	)
	(segment
		(start 98.533458 -458.839062)
		(end 99.028758 -459.334362)
		(width 0.1651)
		(layer "In11.Cu")
		(net "TDR_DIFF_85_IN4_DIP")
	)
	(segment
		(start 98.533458 -457.01077)
		(end 98.533458 -458.839062)
		(width 0.1651)
		(layer "In11.Cu")
		(net "TDR_DIFF_85_IN4_DIP")
	)
	(segment
		(start 90.992198 -459.334362)
		(end 91.487498 -458.839062)
		(width 0.1651)
		(layer "In11.Cu")
		(net "TDR_DIFF_85_IN4_DIP")
	)
	(segment
		(start 126.661418 -457.01077)
		(end 126.991618 -456.68057)
		(width 0.1651)
		(layer "In11.Cu")
		(net "TDR_DIFF_85_IN4_DIP")
	)
	(segment
		(start 123.730258 -457.01077)
		(end 124.060458 -456.68057)
		(width 0.1651)
		(layer "In11.Cu")
		(net "TDR_DIFF_85_IN4_DIP")
	)
	(segment
		(start 109.074458 -458.839062)
		(end 109.074458 -457.01077)
		(width 0.1651)
		(layer "In11.Cu")
		(net "TDR_DIFF_85_IN4_DIP")
	)
	(segment
		(start 101.959918 -459.334362)
		(end 102.716838 -459.334362)
		(width 0.1651)
		(layer "In11.Cu")
		(net "TDR_DIFF_85_IN4_DIP")
	)
	(segment
		(start 92.671138 -457.01077)
		(end 92.671138 -458.839062)
		(width 0.1651)
		(layer "In11.Cu")
		(net "TDR_DIFF_85_IN4_DIP")
	)
	(segment
		(start 95.602298 -458.839062)
		(end 96.097598 -459.334362)
		(width 0.1651)
		(layer "In11.Cu")
		(net "TDR_DIFF_85_IN4_DIP")
	)
	(segment
		(start 133.707378 -457.01077)
		(end 133.707378 -458.839062)
		(width 0.1651)
		(layer "In11.Cu")
		(net "TDR_DIFF_85_IN4_DIP")
	)
	(segment
		(start 121.982738 -457.01077)
		(end 121.982738 -458.839062)
		(width 0.1651)
		(layer "In11.Cu")
		(net "TDR_DIFF_85_IN4_DIP")
	)
	(segment
		(start 87.175848 -459.136496)
		(end 87.175848 -458.172566)
		(width 0.1651)
		(layer "In11.Cu")
		(net "TDR_DIFF_85_IN4_DIP")
	)
	(segment
		(start 136.638538 -458.839062)
		(end 137.133838 -459.334362)
		(width 0.1651)
		(layer "In11.Cu")
		(net "TDR_DIFF_85_IN4_DIP")
	)
	(segment
		(start 92.340938 -456.68057)
		(end 92.671138 -457.01077)
		(width 0.1651)
		(layer "In11.Cu")
		(net "TDR_DIFF_85_IN4_DIP")
	)
	(segment
		(start 126.991618 -456.68057)
		(end 127.514858 -456.68057)
		(width 0.1651)
		(layer "In11.Cu")
		(net "TDR_DIFF_85_IN4_DIP")
	)
	(segment
		(start 89.409778 -458.007466)
		(end 89.739978 -458.337666)
		(width 0.1651)
		(layer "In11.Cu")
		(net "TDR_DIFF_85_IN4_DIP")
	)
	(segment
		(start 103.212138 -457.01077)
		(end 103.542338 -456.68057)
		(width 0.1651)
		(layer "In11.Cu")
		(net "TDR_DIFF_85_IN4_DIP")
	)
	(segment
		(start 117.372638 -459.334362)
		(end 117.867938 -458.839062)
		(width 0.1651)
		(layer "In11.Cu")
		(net "TDR_DIFF_85_IN4_DIP")
	)
	(segment
		(start 89.739978 -458.839062)
		(end 90.235278 -459.334362)
		(width 0.1651)
		(layer "In11.Cu")
		(net "TDR_DIFF_85_IN4_DIP")
	)
	(segment
		(start 100.280978 -458.839062)
		(end 100.280978 -457.01077)
		(width 0.1651)
		(layer "In11.Cu")
		(net "TDR_DIFF_85_IN4_DIP")
	)
	(segment
		(start 392.045952 -444.298832)
		(end 393.054332 -443.290452)
		(width 0.15494)
		(layer "In5.Cu")
		(net "TDR_SE_50_OHM_IN1")
	)
	(segment
		(start 393.054332 -443.290452)
		(end 393.054332 -442.767212)
		(width 0.15494)
		(layer "In5.Cu")
		(net "TDR_SE_50_OHM_IN1")
	)
	(segment
		(start 392.045952 -441.758832)
		(end 317.51397 -441.758832)
		(width 0.15494)
		(layer "In5.Cu")
		(net "TDR_SE_50_OHM_IN1")
	)
	(segment
		(start 317.51397 -444.298832)
		(end 392.045952 -444.298832)
		(width 0.15494)
		(layer "In5.Cu")
		(net "TDR_SE_50_OHM_IN1")
	)
	(segment
		(start 393.054332 -442.767212)
		(end 392.045952 -441.758832)
		(width 0.15494)
		(layer "In5.Cu")
		(net "TDR_SE_50_OHM_IN1")
	)
	(segment
		(start 112.024414 -439.474356)
		(end 112.354614 -439.144156)
		(width 0.1651)
		(layer "In7.Cu")
		(net "TDR_DIFF_85_IN2_DIN")
	)
	(segment
		(start 123.253754 -441.797948)
		(end 123.749054 -441.302648)
		(width 0.1651)
		(layer "In7.Cu")
		(net "TDR_DIFF_85_IN2_DIN")
	)
	(segment
		(start 130.464814 -439.144156)
		(end 130.795014 -439.474356)
		(width 0.1651)
		(layer "In7.Cu")
		(net "TDR_DIFF_85_IN2_DIN")
	)
	(segment
		(start 135.803894 -439.144156)
		(end 136.327134 -439.144156)
		(width 0.1651)
		(layer "In7.Cu")
		(net "TDR_DIFF_85_IN2_DIN")
	)
	(segment
		(start 132.872734 -439.144156)
		(end 133.395974 -439.144156)
		(width 0.1651)
		(layer "In7.Cu")
		(net "TDR_DIFF_85_IN2_DIN")
	)
	(segment
		(start 94.437454 -439.474356)
		(end 94.767654 -439.144156)
		(width 0.1651)
		(layer "In7.Cu")
		(net "TDR_DIFF_85_IN2_DIN")
	)
	(segment
		(start 137.909554 -441.797948)
		(end 138.404854 -441.302648)
		(width 0.1651)
		(layer "In7.Cu")
		(net "TDR_DIFF_85_IN2_DIN")
	)
	(segment
		(start 109.093254 -439.474356)
		(end 109.423454 -439.144156)
		(width 0.1651)
		(layer "In7.Cu")
		(net "TDR_DIFF_85_IN2_DIN")
	)
	(segment
		(start 110.276894 -441.302648)
		(end 110.772194 -441.797948)
		(width 0.1651)
		(layer "In7.Cu")
		(net "TDR_DIFF_85_IN2_DIN")
	)
	(segment
		(start 92.689934 -441.302648)
		(end 93.185234 -441.797948)
		(width 0.1651)
		(layer "In7.Cu")
		(net "TDR_DIFF_85_IN2_DIN")
	)
	(segment
		(start 121.671334 -439.144156)
		(end 122.001534 -439.474356)
		(width 0.1651)
		(layer "In7.Cu")
		(net "TDR_DIFF_85_IN2_DIN")
	)
	(segment
		(start 128.359154 -441.797948)
		(end 129.116074 -441.797948)
		(width 0.1651)
		(layer "In7.Cu")
		(net "TDR_DIFF_85_IN2_DIN")
	)
	(segment
		(start 135.473694 -441.302648)
		(end 135.473694 -439.474356)
		(width 0.1651)
		(layer "In7.Cu")
		(net "TDR_DIFF_85_IN2_DIN")
	)
	(segment
		(start 131.290314 -441.797948)
		(end 132.047234 -441.797948)
		(width 0.1651)
		(layer "In7.Cu")
		(net "TDR_DIFF_85_IN2_DIN")
	)
	(segment
		(start 151.228044 -440.636152)
		(end 151.228044 -441.600082)
		(width 0.1651)
		(layer "In7.Cu")
		(net "TDR_DIFF_85_IN2_DIN")
	)
	(segment
		(start 127.863854 -441.302648)
		(end 128.359154 -441.797948)
		(width 0.1651)
		(layer "In7.Cu")
		(net "TDR_DIFF_85_IN2_DIN")
	)
	(segment
		(start 135.473694 -439.474356)
		(end 135.803894 -439.144156)
		(width 0.1651)
		(layer "In7.Cu")
		(net "TDR_DIFF_85_IN2_DIN")
	)
	(segment
		(start 122.001534 -441.302648)
		(end 122.496834 -441.797948)
		(width 0.1651)
		(layer "In7.Cu")
		(net "TDR_DIFF_85_IN2_DIN")
	)
	(segment
		(start 107.345734 -439.474356)
		(end 107.345734 -441.302648)
		(width 0.1651)
		(layer "In7.Cu")
		(net "TDR_DIFF_85_IN2_DIN")
	)
	(segment
		(start 113.208054 -441.302648)
		(end 113.703354 -441.797948)
		(width 0.1651)
		(layer "In7.Cu")
		(net "TDR_DIFF_85_IN2_DIN")
	)
	(segment
		(start 129.611374 -441.302648)
		(end 129.611374 -439.474356)
		(width 0.1651)
		(layer "In7.Cu")
		(net "TDR_DIFF_85_IN2_DIN")
	)
	(segment
		(start 145.946114 -441.797948)
		(end 146.703034 -441.797948)
		(width 0.1651)
		(layer "In7.Cu")
		(net "TDR_DIFF_85_IN2_DIN")
	)
	(segment
		(start 122.496834 -441.797948)
		(end 123.253754 -441.797948)
		(width 0.1651)
		(layer "In7.Cu")
		(net "TDR_DIFF_85_IN2_DIN")
	)
	(segment
		(start 147.198334 -439.474356)
		(end 147.528534 -439.144156)
		(width 0.1651)
		(layer "In7.Cu")
		(net "TDR_DIFF_85_IN2_DIN")
	)
	(segment
		(start 141.336014 -439.474356)
		(end 141.666214 -439.144156)
		(width 0.1651)
		(layer "In7.Cu")
		(net "TDR_DIFF_85_IN2_DIN")
	)
	(segment
		(start 147.198334 -441.302648)
		(end 147.198334 -439.474356)
		(width 0.1651)
		(layer "In7.Cu")
		(net "TDR_DIFF_85_IN2_DIN")
	)
	(segment
		(start 107.345734 -441.302648)
		(end 107.841034 -441.797948)
		(width 0.1651)
		(layer "In7.Cu")
		(net "TDR_DIFF_85_IN2_DIN")
	)
	(segment
		(start 112.024414 -441.302648)
		(end 112.024414 -439.474356)
		(width 0.1651)
		(layer "In7.Cu")
		(net "TDR_DIFF_85_IN2_DIN")
	)
	(segment
		(start 145.120614 -439.144156)
		(end 145.450814 -439.474356)
		(width 0.1651)
		(layer "In7.Cu")
		(net "TDR_DIFF_85_IN2_DIN")
	)
	(segment
		(start 144.267174 -439.474356)
		(end 144.597374 -439.144156)
		(width 0.1651)
		(layer "In7.Cu")
		(net "TDR_DIFF_85_IN2_DIN")
	)
	(segment
		(start 132.542534 -441.302648)
		(end 132.542534 -439.474356)
		(width 0.1651)
		(layer "In7.Cu")
		(net "TDR_DIFF_85_IN2_DIN")
	)
	(segment
		(start 132.542534 -439.474356)
		(end 132.872734 -439.144156)
		(width 0.1651)
		(layer "In7.Cu")
		(net "TDR_DIFF_85_IN2_DIN")
	)
	(segment
		(start 148.051774 -439.144156)
		(end 148.381974 -439.474356)
		(width 0.1651)
		(layer "In7.Cu")
		(net "TDR_DIFF_85_IN2_DIN")
	)
	(segment
		(start 129.941574 -439.144156)
		(end 130.464814 -439.144156)
		(width 0.1651)
		(layer "In7.Cu")
		(net "TDR_DIFF_85_IN2_DIN")
	)
	(segment
		(start 106.492294 -439.144156)
		(end 107.015534 -439.144156)
		(width 0.1651)
		(layer "In7.Cu")
		(net "TDR_DIFF_85_IN2_DIN")
	)
	(segment
		(start 136.657334 -439.474356)
		(end 136.657334 -441.302648)
		(width 0.1651)
		(layer "In7.Cu")
		(net "TDR_DIFF_85_IN2_DIN")
	)
	(segment
		(start 146.703034 -441.797948)
		(end 147.198334 -441.302648)
		(width 0.1651)
		(layer "In7.Cu")
		(net "TDR_DIFF_85_IN2_DIN")
	)
	(segment
		(start 102.735634 -441.797948)
		(end 103.230934 -441.302648)
		(width 0.1651)
		(layer "In7.Cu")
		(net "TDR_DIFF_85_IN2_DIN")
	)
	(segment
		(start 106.162094 -441.302648)
		(end 106.162094 -439.474356)
		(width 0.1651)
		(layer "In7.Cu")
		(net "TDR_DIFF_85_IN2_DIN")
	)
	(segment
		(start 111.529114 -441.797948)
		(end 112.024414 -441.302648)
		(width 0.1651)
		(layer "In7.Cu")
		(net "TDR_DIFF_85_IN2_DIN")
	)
	(segment
		(start 103.230934 -441.302648)
		(end 103.230934 -439.474356)
		(width 0.1651)
		(layer "In7.Cu")
		(net "TDR_DIFF_85_IN2_DIN")
	)
	(segment
		(start 138.735054 -439.144156)
		(end 139.258294 -439.144156)
		(width 0.1651)
		(layer "In7.Cu")
		(net "TDR_DIFF_85_IN2_DIN")
	)
	(segment
		(start 115.809014 -439.144156)
		(end 116.139214 -439.474356)
		(width 0.1651)
		(layer "In7.Cu")
		(net "TDR_DIFF_85_IN2_DIN")
	)
	(segment
		(start 105.666794 -441.797948)
		(end 106.162094 -441.302648)
		(width 0.1651)
		(layer "In7.Cu")
		(net "TDR_DIFF_85_IN2_DIN")
	)
	(segment
		(start 99.047554 -441.797948)
		(end 99.804474 -441.797948)
		(width 0.1651)
		(layer "In7.Cu")
		(net "TDR_DIFF_85_IN2_DIN")
	)
	(segment
		(start 97.368614 -441.302648)
		(end 97.368614 -439.474356)
		(width 0.1651)
		(layer "In7.Cu")
		(net "TDR_DIFF_85_IN2_DIN")
	)
	(segment
		(start 104.909874 -441.797948)
		(end 105.666794 -441.797948)
		(width 0.1651)
		(layer "In7.Cu")
		(net "TDR_DIFF_85_IN2_DIN")
	)
	(segment
		(start 124.932694 -441.302648)
		(end 125.427994 -441.797948)
		(width 0.1651)
		(layer "In7.Cu")
		(net "TDR_DIFF_85_IN2_DIN")
	)
	(segment
		(start 97.368614 -439.474356)
		(end 97.698814 -439.144156)
		(width 0.1651)
		(layer "In7.Cu")
		(net "TDR_DIFF_85_IN2_DIN")
	)
	(segment
		(start 91.010994 -441.797948)
		(end 91.506294 -441.302648)
		(width 0.1651)
		(layer "In7.Cu")
		(net "TDR_DIFF_85_IN2_DIN")
	)
	(segment
		(start 121.148094 -439.144156)
		(end 121.671334 -439.144156)
		(width 0.1651)
		(layer "In7.Cu")
		(net "TDR_DIFF_85_IN2_DIN")
	)
	(segment
		(start 126.680214 -439.474356)
		(end 127.010414 -439.144156)
		(width 0.1651)
		(layer "In7.Cu")
		(net "TDR_DIFF_85_IN2_DIN")
	)
	(segment
		(start 114.460274 -441.797948)
		(end 114.955574 -441.302648)
		(width 0.1651)
		(layer "In7.Cu")
		(net "TDR_DIFF_85_IN2_DIN")
	)
	(segment
		(start 103.561134 -439.144156)
		(end 104.084374 -439.144156)
		(width 0.1651)
		(layer "In7.Cu")
		(net "TDR_DIFF_85_IN2_DIN")
	)
	(segment
		(start 130.795014 -441.302648)
		(end 131.290314 -441.797948)
		(width 0.1651)
		(layer "In7.Cu")
		(net "TDR_DIFF_85_IN2_DIN")
	)
	(segment
		(start 136.327134 -439.144156)
		(end 136.657334 -439.474356)
		(width 0.1651)
		(layer "In7.Cu")
		(net "TDR_DIFF_85_IN2_DIN")
	)
	(segment
		(start 113.208054 -439.474356)
		(end 113.208054 -441.302648)
		(width 0.1651)
		(layer "In7.Cu")
		(net "TDR_DIFF_85_IN2_DIN")
	)
	(segment
		(start 142.519654 -441.302648)
		(end 143.014954 -441.797948)
		(width 0.1651)
		(layer "In7.Cu")
		(net "TDR_DIFF_85_IN2_DIN")
	)
	(segment
		(start 112.354614 -439.144156)
		(end 112.877854 -439.144156)
		(width 0.1651)
		(layer "In7.Cu")
		(net "TDR_DIFF_85_IN2_DIN")
	)
	(segment
		(start 87.194644 -441.600082)
		(end 87.194644 -440.636152)
		(width 0.1651)
		(layer "In7.Cu")
		(net "TDR_DIFF_85_IN2_DIN")
	)
	(segment
		(start 108.597954 -441.797948)
		(end 109.093254 -441.302648)
		(width 0.1651)
		(layer "In7.Cu")
		(net "TDR_DIFF_85_IN2_DIN")
	)
	(segment
		(start 95.621094 -441.302648)
		(end 96.116394 -441.797948)
		(width 0.1651)
		(layer "In7.Cu")
		(net "TDR_DIFF_85_IN2_DIN")
	)
	(segment
		(start 124.079254 -439.144156)
		(end 124.602494 -439.144156)
		(width 0.1651)
		(layer "In7.Cu")
		(net "TDR_DIFF_85_IN2_DIN")
	)
	(segment
		(start 99.804474 -441.797948)
		(end 100.299774 -441.302648)
		(width 0.1651)
		(layer "In7.Cu")
		(net "TDR_DIFF_85_IN2_DIN")
	)
	(segment
		(start 100.299774 -441.302648)
		(end 100.299774 -439.474356)
		(width 0.1651)
		(layer "In7.Cu")
		(net "TDR_DIFF_85_IN2_DIN")
	)
	(segment
		(start 92.359734 -439.144156)
		(end 92.689934 -439.474356)
		(width 0.1651)
		(layer "In7.Cu")
		(net "TDR_DIFF_85_IN2_DIN")
	)
	(segment
		(start 89.758774 -440.801252)
		(end 89.758774 -441.302648)
		(width 0.1651)
		(layer "In7.Cu")
		(net "TDR_DIFF_85_IN2_DIN")
	)
	(segment
		(start 94.437454 -441.302648)
		(end 94.437454 -439.474356)
		(width 0.1651)
		(layer "In7.Cu")
		(net "TDR_DIFF_85_IN2_DIN")
	)
	(segment
		(start 139.588494 -439.474356)
		(end 139.588494 -441.302648)
		(width 0.1651)
		(layer "In7.Cu")
		(net "TDR_DIFF_85_IN2_DIN")
	)
	(segment
		(start 110.276894 -439.474356)
		(end 110.276894 -441.302648)
		(width 0.1651)
		(layer "In7.Cu")
		(net "TDR_DIFF_85_IN2_DIN")
	)
	(segment
		(start 141.666214 -439.144156)
		(end 142.189454 -439.144156)
		(width 0.1651)
		(layer "In7.Cu")
		(net "TDR_DIFF_85_IN2_DIN")
	)
	(segment
		(start 109.093254 -441.302648)
		(end 109.093254 -439.474356)
		(width 0.1651)
		(layer "In7.Cu")
		(net "TDR_DIFF_85_IN2_DIN")
	)
	(segment
		(start 100.299774 -439.474356)
		(end 100.629974 -439.144156)
		(width 0.1651)
		(layer "In7.Cu")
		(net "TDR_DIFF_85_IN2_DIN")
	)
	(segment
		(start 115.285774 -439.144156)
		(end 115.809014 -439.144156)
		(width 0.1651)
		(layer "In7.Cu")
		(net "TDR_DIFF_85_IN2_DIN")
	)
	(segment
		(start 133.726174 -439.474356)
		(end 133.726174 -441.302648)
		(width 0.1651)
		(layer "In7.Cu")
		(net "TDR_DIFF_85_IN2_DIN")
	)
	(segment
		(start 117.886734 -439.474356)
		(end 118.216934 -439.144156)
		(width 0.1651)
		(layer "In7.Cu")
		(net "TDR_DIFF_85_IN2_DIN")
	)
	(segment
		(start 91.836494 -439.144156)
		(end 92.359734 -439.144156)
		(width 0.1651)
		(layer "In7.Cu")
		(net "TDR_DIFF_85_IN2_DIN")
	)
	(segment
		(start 141.336014 -441.302648)
		(end 141.336014 -439.474356)
		(width 0.1651)
		(layer "In7.Cu")
		(net "TDR_DIFF_85_IN2_DIN")
	)
	(segment
		(start 138.404854 -441.302648)
		(end 138.404854 -439.474356)
		(width 0.1651)
		(layer "In7.Cu")
		(net "TDR_DIFF_85_IN2_DIN")
	)
	(segment
		(start 142.519654 -439.474356)
		(end 142.519654 -441.302648)
		(width 0.1651)
		(layer "In7.Cu")
		(net "TDR_DIFF_85_IN2_DIN")
	)
	(segment
		(start 118.740174 -439.144156)
		(end 119.070374 -439.474356)
		(width 0.1651)
		(layer "In7.Cu")
		(net "TDR_DIFF_85_IN2_DIN")
	)
	(segment
		(start 87.194644 -440.636152)
		(end 87.359744 -440.471052)
		(width 0.1651)
		(layer "In7.Cu")
		(net "TDR_DIFF_85_IN2_DIN")
	)
	(segment
		(start 93.942154 -441.797948)
		(end 94.437454 -441.302648)
		(width 0.1651)
		(layer "In7.Cu")
		(net "TDR_DIFF_85_IN2_DIN")
	)
	(segment
		(start 119.565674 -441.797948)
		(end 120.322594 -441.797948)
		(width 0.1651)
		(layer "In7.Cu")
		(net "TDR_DIFF_85_IN2_DIN")
	)
	(segment
		(start 106.162094 -439.474356)
		(end 106.492294 -439.144156)
		(width 0.1651)
		(layer "In7.Cu")
		(net "TDR_DIFF_85_IN2_DIN")
	)
	(segment
		(start 144.267174 -441.302648)
		(end 144.267174 -439.474356)
		(width 0.1651)
		(layer "In7.Cu")
		(net "TDR_DIFF_85_IN2_DIN")
	)
	(segment
		(start 98.552254 -439.474356)
		(end 98.552254 -441.302648)
		(width 0.1651)
		(layer "In7.Cu")
		(net "TDR_DIFF_85_IN2_DIN")
	)
	(segment
		(start 122.001534 -439.474356)
		(end 122.001534 -441.302648)
		(width 0.1651)
		(layer "In7.Cu")
		(net "TDR_DIFF_85_IN2_DIN")
	)
	(segment
		(start 96.116394 -441.797948)
		(end 96.873314 -441.797948)
		(width 0.1651)
		(layer "In7.Cu")
		(net "TDR_DIFF_85_IN2_DIN")
	)
	(segment
		(start 100.629974 -439.144156)
		(end 101.153214 -439.144156)
		(width 0.1651)
		(layer "In7.Cu")
		(net "TDR_DIFF_85_IN2_DIN")
	)
	(segment
		(start 91.506294 -441.302648)
		(end 91.506294 -439.474356)
		(width 0.1651)
		(layer "In7.Cu")
		(net "TDR_DIFF_85_IN2_DIN")
	)
	(segment
		(start 136.657334 -441.302648)
		(end 137.152634 -441.797948)
		(width 0.1651)
		(layer "In7.Cu")
		(net "TDR_DIFF_85_IN2_DIN")
	)
	(segment
		(start 97.698814 -439.144156)
		(end 98.222054 -439.144156)
		(width 0.1651)
		(layer "In7.Cu")
		(net "TDR_DIFF_85_IN2_DIN")
	)
	(segment
		(start 116.139214 -441.302648)
		(end 116.634514 -441.797948)
		(width 0.1651)
		(layer "In7.Cu")
		(net "TDR_DIFF_85_IN2_DIN")
	)
	(segment
		(start 124.932694 -439.474356)
		(end 124.932694 -441.302648)
		(width 0.1651)
		(layer "In7.Cu")
		(net "TDR_DIFF_85_IN2_DIN")
	)
	(segment
		(start 87.359744 -440.471052)
		(end 89.428574 -440.471052)
		(width 0.1651)
		(layer "In7.Cu")
		(net "TDR_DIFF_85_IN2_DIN")
	)
	(segment
		(start 130.795014 -439.474356)
		(end 130.795014 -441.302648)
		(width 0.1651)
		(layer "In7.Cu")
		(net "TDR_DIFF_85_IN2_DIN")
	)
	(segment
		(start 114.955574 -441.302648)
		(end 114.955574 -439.474356)
		(width 0.1651)
		(layer "In7.Cu")
		(net "TDR_DIFF_85_IN2_DIN")
	)
	(segment
		(start 127.533654 -439.144156)
		(end 127.863854 -439.474356)
		(width 0.1651)
		(layer "In7.Cu")
		(net "TDR_DIFF_85_IN2_DIN")
	)
	(segment
		(start 116.139214 -439.474356)
		(end 116.139214 -441.302648)
		(width 0.1651)
		(layer "In7.Cu")
		(net "TDR_DIFF_85_IN2_DIN")
	)
	(segment
		(start 120.817894 -439.474356)
		(end 121.148094 -439.144156)
		(width 0.1651)
		(layer "In7.Cu")
		(net "TDR_DIFF_85_IN2_DIN")
	)
	(segment
		(start 138.404854 -439.474356)
		(end 138.735054 -439.144156)
		(width 0.1651)
		(layer "In7.Cu")
		(net "TDR_DIFF_85_IN2_DIN")
	)
	(segment
		(start 123.749054 -441.302648)
		(end 123.749054 -439.474356)
		(width 0.1651)
		(layer "In7.Cu")
		(net "TDR_DIFF_85_IN2_DIN")
	)
	(segment
		(start 101.978714 -441.797948)
		(end 102.735634 -441.797948)
		(width 0.1651)
		(layer "In7.Cu")
		(net "TDR_DIFF_85_IN2_DIN")
	)
	(segment
		(start 143.771874 -441.797948)
		(end 144.267174 -441.302648)
		(width 0.1651)
		(layer "In7.Cu")
		(net "TDR_DIFF_85_IN2_DIN")
	)
	(segment
		(start 107.841034 -441.797948)
		(end 108.597954 -441.797948)
		(width 0.1651)
		(layer "In7.Cu")
		(net "TDR_DIFF_85_IN2_DIN")
	)
	(segment
		(start 143.014954 -441.797948)
		(end 143.771874 -441.797948)
		(width 0.1651)
		(layer "In7.Cu")
		(net "TDR_DIFF_85_IN2_DIN")
	)
	(segment
		(start 104.414574 -441.302648)
		(end 104.909874 -441.797948)
		(width 0.1651)
		(layer "In7.Cu")
		(net "TDR_DIFF_85_IN2_DIN")
	)
	(segment
		(start 92.689934 -439.474356)
		(end 92.689934 -441.302648)
		(width 0.1651)
		(layer "In7.Cu")
		(net "TDR_DIFF_85_IN2_DIN")
	)
	(segment
		(start 126.680214 -441.302648)
		(end 126.680214 -439.474356)
		(width 0.1651)
		(layer "In7.Cu")
		(net "TDR_DIFF_85_IN2_DIN")
	)
	(segment
		(start 101.153214 -439.144156)
		(end 101.483414 -439.474356)
		(width 0.1651)
		(layer "In7.Cu")
		(net "TDR_DIFF_85_IN2_DIN")
	)
	(segment
		(start 109.946694 -439.144156)
		(end 110.276894 -439.474356)
		(width 0.1651)
		(layer "In7.Cu")
		(net "TDR_DIFF_85_IN2_DIN")
	)
	(segment
		(start 139.588494 -441.302648)
		(end 140.083794 -441.797948)
		(width 0.1651)
		(layer "In7.Cu")
		(net "TDR_DIFF_85_IN2_DIN")
	)
	(segment
		(start 113.703354 -441.797948)
		(end 114.460274 -441.797948)
		(width 0.1651)
		(layer "In7.Cu")
		(net "TDR_DIFF_85_IN2_DIN")
	)
	(segment
		(start 144.597374 -439.144156)
		(end 145.120614 -439.144156)
		(width 0.1651)
		(layer "In7.Cu")
		(net "TDR_DIFF_85_IN2_DIN")
	)
	(segment
		(start 90.254074 -441.797948)
		(end 91.010994 -441.797948)
		(width 0.1651)
		(layer "In7.Cu")
		(net "TDR_DIFF_85_IN2_DIN")
	)
	(segment
		(start 145.450814 -441.302648)
		(end 145.946114 -441.797948)
		(width 0.1651)
		(layer "In7.Cu")
		(net "TDR_DIFF_85_IN2_DIN")
	)
	(segment
		(start 124.602494 -439.144156)
		(end 124.932694 -439.474356)
		(width 0.1651)
		(layer "In7.Cu")
		(net "TDR_DIFF_85_IN2_DIN")
	)
	(segment
		(start 110.772194 -441.797948)
		(end 111.529114 -441.797948)
		(width 0.1651)
		(layer "In7.Cu")
		(net "TDR_DIFF_85_IN2_DIN")
	)
	(segment
		(start 98.552254 -441.302648)
		(end 99.047554 -441.797948)
		(width 0.1651)
		(layer "In7.Cu")
		(net "TDR_DIFF_85_IN2_DIN")
	)
	(segment
		(start 95.621094 -439.474356)
		(end 95.621094 -441.302648)
		(width 0.1651)
		(layer "In7.Cu")
		(net "TDR_DIFF_85_IN2_DIN")
	)
	(segment
		(start 104.084374 -439.144156)
		(end 104.414574 -439.474356)
		(width 0.1651)
		(layer "In7.Cu")
		(net "TDR_DIFF_85_IN2_DIN")
	)
	(segment
		(start 132.047234 -441.797948)
		(end 132.542534 -441.302648)
		(width 0.1651)
		(layer "In7.Cu")
		(net "TDR_DIFF_85_IN2_DIN")
	)
	(segment
		(start 147.528534 -439.144156)
		(end 148.051774 -439.144156)
		(width 0.1651)
		(layer "In7.Cu")
		(net "TDR_DIFF_85_IN2_DIN")
	)
	(segment
		(start 120.817894 -441.302648)
		(end 120.817894 -439.474356)
		(width 0.1651)
		(layer "In7.Cu")
		(net "TDR_DIFF_85_IN2_DIN")
	)
	(segment
		(start 142.189454 -439.144156)
		(end 142.519654 -439.474356)
		(width 0.1651)
		(layer "In7.Cu")
		(net "TDR_DIFF_85_IN2_DIN")
	)
	(segment
		(start 148.381974 -439.975752)
		(end 148.877274 -440.471052)
		(width 0.1651)
		(layer "In7.Cu")
		(net "TDR_DIFF_85_IN2_DIN")
	)
	(segment
		(start 140.840714 -441.797948)
		(end 141.336014 -441.302648)
		(width 0.1651)
		(layer "In7.Cu")
		(net "TDR_DIFF_85_IN2_DIN")
	)
	(segment
		(start 93.185234 -441.797948)
		(end 93.942154 -441.797948)
		(width 0.1651)
		(layer "In7.Cu")
		(net "TDR_DIFF_85_IN2_DIN")
	)
	(segment
		(start 104.414574 -439.474356)
		(end 104.414574 -441.302648)
		(width 0.1651)
		(layer "In7.Cu")
		(net "TDR_DIFF_85_IN2_DIN")
	)
	(segment
		(start 123.749054 -439.474356)
		(end 124.079254 -439.144156)
		(width 0.1651)
		(layer "In7.Cu")
		(net "TDR_DIFF_85_IN2_DIN")
	)
	(segment
		(start 112.877854 -439.144156)
		(end 113.208054 -439.474356)
		(width 0.1651)
		(layer "In7.Cu")
		(net "TDR_DIFF_85_IN2_DIN")
	)
	(segment
		(start 117.391434 -441.797948)
		(end 117.886734 -441.302648)
		(width 0.1651)
		(layer "In7.Cu")
		(net "TDR_DIFF_85_IN2_DIN")
	)
	(segment
		(start 139.258294 -439.144156)
		(end 139.588494 -439.474356)
		(width 0.1651)
		(layer "In7.Cu")
		(net "TDR_DIFF_85_IN2_DIN")
	)
	(segment
		(start 118.216934 -439.144156)
		(end 118.740174 -439.144156)
		(width 0.1651)
		(layer "In7.Cu")
		(net "TDR_DIFF_85_IN2_DIN")
	)
	(segment
		(start 103.230934 -439.474356)
		(end 103.561134 -439.144156)
		(width 0.1651)
		(layer "In7.Cu")
		(net "TDR_DIFF_85_IN2_DIN")
	)
	(segment
		(start 116.634514 -441.797948)
		(end 117.391434 -441.797948)
		(width 0.1651)
		(layer "In7.Cu")
		(net "TDR_DIFF_85_IN2_DIN")
	)
	(segment
		(start 114.955574 -439.474356)
		(end 115.285774 -439.144156)
		(width 0.1651)
		(layer "In7.Cu")
		(net "TDR_DIFF_85_IN2_DIN")
	)
	(segment
		(start 134.978394 -441.797948)
		(end 135.473694 -441.302648)
		(width 0.1651)
		(layer "In7.Cu")
		(net "TDR_DIFF_85_IN2_DIN")
	)
	(segment
		(start 91.506294 -439.474356)
		(end 91.836494 -439.144156)
		(width 0.1651)
		(layer "In7.Cu")
		(net "TDR_DIFF_85_IN2_DIN")
	)
	(segment
		(start 95.290894 -439.144156)
		(end 95.621094 -439.474356)
		(width 0.1651)
		(layer "In7.Cu")
		(net "TDR_DIFF_85_IN2_DIN")
	)
	(segment
		(start 140.083794 -441.797948)
		(end 140.840714 -441.797948)
		(width 0.1651)
		(layer "In7.Cu")
		(net "TDR_DIFF_85_IN2_DIN")
	)
	(segment
		(start 94.767654 -439.144156)
		(end 95.290894 -439.144156)
		(width 0.1651)
		(layer "In7.Cu")
		(net "TDR_DIFF_85_IN2_DIN")
	)
	(segment
		(start 96.873314 -441.797948)
		(end 97.368614 -441.302648)
		(width 0.1651)
		(layer "In7.Cu")
		(net "TDR_DIFF_85_IN2_DIN")
	)
	(segment
		(start 133.395974 -439.144156)
		(end 133.726174 -439.474356)
		(width 0.1651)
		(layer "In7.Cu")
		(net "TDR_DIFF_85_IN2_DIN")
	)
	(segment
		(start 151.062944 -440.471052)
		(end 151.228044 -440.636152)
		(width 0.1651)
		(layer "In7.Cu")
		(net "TDR_DIFF_85_IN2_DIN")
	)
	(segment
		(start 117.886734 -441.302648)
		(end 117.886734 -439.474356)
		(width 0.1651)
		(layer "In7.Cu")
		(net "TDR_DIFF_85_IN2_DIN")
	)
	(segment
		(start 107.015534 -439.144156)
		(end 107.345734 -439.474356)
		(width 0.1651)
		(layer "In7.Cu")
		(net "TDR_DIFF_85_IN2_DIN")
	)
	(segment
		(start 129.611374 -439.474356)
		(end 129.941574 -439.144156)
		(width 0.1651)
		(layer "In7.Cu")
		(net "TDR_DIFF_85_IN2_DIN")
	)
	(segment
		(start 89.758774 -441.302648)
		(end 90.254074 -441.797948)
		(width 0.1651)
		(layer "In7.Cu")
		(net "TDR_DIFF_85_IN2_DIN")
	)
	(segment
		(start 145.450814 -439.474356)
		(end 145.450814 -441.302648)
		(width 0.1651)
		(layer "In7.Cu")
		(net "TDR_DIFF_85_IN2_DIN")
	)
	(segment
		(start 119.070374 -439.474356)
		(end 119.070374 -441.302648)
		(width 0.1651)
		(layer "In7.Cu")
		(net "TDR_DIFF_85_IN2_DIN")
	)
	(segment
		(start 125.427994 -441.797948)
		(end 126.184914 -441.797948)
		(width 0.1651)
		(layer "In7.Cu")
		(net "TDR_DIFF_85_IN2_DIN")
	)
	(segment
		(start 134.221474 -441.797948)
		(end 134.978394 -441.797948)
		(width 0.1651)
		(layer "In7.Cu")
		(net "TDR_DIFF_85_IN2_DIN")
	)
	(segment
		(start 148.877274 -440.471052)
		(end 151.062944 -440.471052)
		(width 0.1651)
		(layer "In7.Cu")
		(net "TDR_DIFF_85_IN2_DIN")
	)
	(segment
		(start 101.483414 -439.474356)
		(end 101.483414 -441.302648)
		(width 0.1651)
		(layer "In7.Cu")
		(net "TDR_DIFF_85_IN2_DIN")
	)
	(segment
		(start 120.322594 -441.797948)
		(end 120.817894 -441.302648)
		(width 0.1651)
		(layer "In7.Cu")
		(net "TDR_DIFF_85_IN2_DIN")
	)
	(segment
		(start 101.483414 -441.302648)
		(end 101.978714 -441.797948)
		(width 0.1651)
		(layer "In7.Cu")
		(net "TDR_DIFF_85_IN2_DIN")
	)
	(segment
		(start 148.381974 -439.474356)
		(end 148.381974 -439.975752)
		(width 0.1651)
		(layer "In7.Cu")
		(net "TDR_DIFF_85_IN2_DIN")
	)
	(segment
		(start 119.070374 -441.302648)
		(end 119.565674 -441.797948)
		(width 0.1651)
		(layer "In7.Cu")
		(net "TDR_DIFF_85_IN2_DIN")
	)
	(segment
		(start 133.726174 -441.302648)
		(end 134.221474 -441.797948)
		(width 0.1651)
		(layer "In7.Cu")
		(net "TDR_DIFF_85_IN2_DIN")
	)
	(segment
		(start 129.116074 -441.797948)
		(end 129.611374 -441.302648)
		(width 0.1651)
		(layer "In7.Cu")
		(net "TDR_DIFF_85_IN2_DIN")
	)
	(segment
		(start 137.152634 -441.797948)
		(end 137.909554 -441.797948)
		(width 0.1651)
		(layer "In7.Cu")
		(net "TDR_DIFF_85_IN2_DIN")
	)
	(segment
		(start 127.010414 -439.144156)
		(end 127.533654 -439.144156)
		(width 0.1651)
		(layer "In7.Cu")
		(net "TDR_DIFF_85_IN2_DIN")
	)
	(segment
		(start 109.423454 -439.144156)
		(end 109.946694 -439.144156)
		(width 0.1651)
		(layer "In7.Cu")
		(net "TDR_DIFF_85_IN2_DIN")
	)
	(segment
		(start 89.428574 -440.471052)
		(end 89.758774 -440.801252)
		(width 0.1651)
		(layer "In7.Cu")
		(net "TDR_DIFF_85_IN2_DIN")
	)
	(segment
		(start 98.222054 -439.144156)
		(end 98.552254 -439.474356)
		(width 0.1651)
		(layer "In7.Cu")
		(net "TDR_DIFF_85_IN2_DIN")
	)
	(segment
		(start 126.184914 -441.797948)
		(end 126.680214 -441.302648)
		(width 0.1651)
		(layer "In7.Cu")
		(net "TDR_DIFF_85_IN2_DIN")
	)
	(segment
		(start 127.863854 -439.474356)
		(end 127.863854 -441.302648)
		(width 0.1651)
		(layer "In7.Cu")
		(net "TDR_DIFF_85_IN2_DIN")
	)
	(segment
		(start 42.308272 -444.652654)
		(end 42.73804 -444.222886)
		(width 0.13462)
		(layer "F.Cu")
		(net "TDR_DIFF_85_TOP_DIP")
	)
	(segment
		(start 32.475424 -444.222886)
		(end 32.905192 -444.652654)
		(width 0.13462)
		(layer "F.Cu")
		(net "TDR_DIFF_85_TOP_DIP")
	)
	(segment
		(start 67.314064 -444.222886)
		(end 67.743832 -444.652654)
		(width 0.13462)
		(layer "F.Cu")
		(net "TDR_DIFF_85_TOP_DIP")
	)
	(segment
		(start 56.130952 -444.652654)
		(end 56.130952 -447.251582)
		(width 0.13462)
		(layer "F.Cu")
		(net "TDR_DIFF_85_TOP_DIP")
	)
	(segment
		(start 63.872872 -444.652654)
		(end 63.872872 -447.251582)
		(width 0.13462)
		(layer "F.Cu")
		(net "TDR_DIFF_85_TOP_DIP")
	)
	(segment
		(start 53.921152 -447.251582)
		(end 53.921152 -444.652654)
		(width 0.13462)
		(layer "F.Cu")
		(net "TDR_DIFF_85_TOP_DIP")
	)
	(segment
		(start 71.185024 -444.222886)
		(end 71.614792 -444.652654)
		(width 0.13462)
		(layer "F.Cu")
		(net "TDR_DIFF_85_TOP_DIP")
	)
	(segment
		(start 62.09284 -444.222886)
		(end 63.443104 -444.222886)
		(width 0.13462)
		(layer "F.Cu")
		(net "TDR_DIFF_85_TOP_DIP")
	)
	(segment
		(start 60.271152 -447.520822)
		(end 61.393832 -447.520822)
		(width 0.13462)
		(layer "F.Cu")
		(net "TDR_DIFF_85_TOP_DIP")
	)
	(segment
		(start 28.604464 -444.222886)
		(end 29.034232 -444.652654)
		(width 0.13462)
		(layer "F.Cu")
		(net "TDR_DIFF_85_TOP_DIP")
	)
	(segment
		(start 54.35092 -444.222886)
		(end 55.701184 -444.222886)
		(width 0.13462)
		(layer "F.Cu")
		(net "TDR_DIFF_85_TOP_DIP")
	)
	(segment
		(start 59.572144 -444.222886)
		(end 60.001912 -444.652654)
		(width 0.13462)
		(layer "F.Cu")
		(net "TDR_DIFF_85_TOP_DIP")
	)
	(segment
		(start 69.135752 -447.520822)
		(end 69.404992 -447.251582)
		(width 0.13462)
		(layer "F.Cu")
		(net "TDR_DIFF_85_TOP_DIP")
	)
	(segment
		(start 20.862544 -444.222886)
		(end 21.292312 -444.652654)
		(width 0.13462)
		(layer "F.Cu")
		(net "TDR_DIFF_85_TOP_DIP")
	)
	(segment
		(start 73.70572 -444.222886)
		(end 75.055984 -444.222886)
		(width 0.13462)
		(layer "F.Cu")
		(net "TDR_DIFF_85_TOP_DIP")
	)
	(segment
		(start 26.555192 -447.520822)
		(end 26.824432 -447.251582)
		(width 0.13462)
		(layer "F.Cu")
		(net "TDR_DIFF_85_TOP_DIP")
	)
	(segment
		(start 65.9638 -444.222886)
		(end 67.314064 -444.222886)
		(width 0.13462)
		(layer "F.Cu")
		(net "TDR_DIFF_85_TOP_DIP")
	)
	(segment
		(start 67.743832 -444.652654)
		(end 67.743832 -447.251582)
		(width 0.13462)
		(layer "F.Cu")
		(net "TDR_DIFF_85_TOP_DIP")
	)
	(segment
		(start 38.86708 -444.222886)
		(end 40.217344 -444.222886)
		(width 0.13462)
		(layer "F.Cu")
		(net "TDR_DIFF_85_TOP_DIP")
	)
	(segment
		(start 63.443104 -444.222886)
		(end 63.872872 -444.652654)
		(width 0.13462)
		(layer "F.Cu")
		(net "TDR_DIFF_85_TOP_DIP")
	)
	(segment
		(start 38.437312 -444.652654)
		(end 38.86708 -444.222886)
		(width 0.13462)
		(layer "F.Cu")
		(net "TDR_DIFF_85_TOP_DIP")
	)
	(segment
		(start 65.534032 -444.652654)
		(end 65.9638 -444.222886)
		(width 0.13462)
		(layer "F.Cu")
		(net "TDR_DIFF_85_TOP_DIP")
	)
	(segment
		(start 31.12516 -444.222886)
		(end 32.475424 -444.222886)
		(width 0.13462)
		(layer "F.Cu")
		(net "TDR_DIFF_85_TOP_DIP")
	)
	(segment
		(start 58.22188 -444.222886)
		(end 59.572144 -444.222886)
		(width 0.13462)
		(layer "F.Cu")
		(net "TDR_DIFF_85_TOP_DIP")
	)
	(segment
		(start 53.651912 -447.520822)
		(end 53.921152 -447.251582)
		(width 0.13462)
		(layer "F.Cu")
		(net "TDR_DIFF_85_TOP_DIP")
	)
	(segment
		(start 46.179232 -444.652654)
		(end 46.609 -444.222886)
		(width 0.13462)
		(layer "F.Cu")
		(net "TDR_DIFF_85_TOP_DIP")
	)
	(segment
		(start 25.432512 -447.520822)
		(end 26.555192 -447.520822)
		(width 0.13462)
		(layer "F.Cu")
		(net "TDR_DIFF_85_TOP_DIP")
	)
	(segment
		(start 44.518072 -447.251582)
		(end 44.787312 -447.520822)
		(width 0.13462)
		(layer "F.Cu")
		(net "TDR_DIFF_85_TOP_DIP")
	)
	(segment
		(start 50.050192 -444.652654)
		(end 50.47996 -444.222886)
		(width 0.13462)
		(layer "F.Cu")
		(net "TDR_DIFF_85_TOP_DIP")
	)
	(segment
		(start 71.884032 -447.520822)
		(end 73.006712 -447.520822)
		(width 0.13462)
		(layer "F.Cu")
		(net "TDR_DIFF_85_TOP_DIP")
	)
	(segment
		(start 29.303472 -447.520822)
		(end 30.426152 -447.520822)
		(width 0.13462)
		(layer "F.Cu")
		(net "TDR_DIFF_85_TOP_DIP")
	)
	(segment
		(start 17.421352 -446.301622)
		(end 17.421352 -447.251582)
		(width 0.13462)
		(layer "F.Cu")
		(net "TDR_DIFF_85_TOP_DIP")
	)
	(segment
		(start 32.905192 -444.652654)
		(end 32.905192 -447.251582)
		(width 0.13462)
		(layer "F.Cu")
		(net "TDR_DIFF_85_TOP_DIP")
	)
	(segment
		(start 73.275952 -447.251582)
		(end 73.275952 -444.652654)
		(width 0.13462)
		(layer "F.Cu")
		(net "TDR_DIFF_85_TOP_DIP")
	)
	(segment
		(start 67.743832 -447.251582)
		(end 68.013072 -447.520822)
		(width 0.13462)
		(layer "F.Cu")
		(net "TDR_DIFF_85_TOP_DIP")
	)
	(segment
		(start 73.275952 -444.652654)
		(end 73.70572 -444.222886)
		(width 0.13462)
		(layer "F.Cu")
		(net "TDR_DIFF_85_TOP_DIP")
	)
	(segment
		(start 36.346384 -444.222886)
		(end 36.776152 -444.652654)
		(width 0.13462)
		(layer "F.Cu")
		(net "TDR_DIFF_85_TOP_DIP")
	)
	(segment
		(start 29.034232 -444.652654)
		(end 29.034232 -447.251582)
		(width 0.13462)
		(layer "F.Cu")
		(net "TDR_DIFF_85_TOP_DIP")
	)
	(segment
		(start 17.421352 -447.251582)
		(end 17.690592 -447.520822)
		(width 0.13462)
		(layer "F.Cu")
		(net "TDR_DIFF_85_TOP_DIP")
	)
	(segment
		(start 14.286992 -445.737234)
		(end 14.421612 -445.871854)
		(width 0.13462)
		(layer "F.Cu")
		(net "TDR_DIFF_85_TOP_DIP")
	)
	(segment
		(start 34.297112 -447.520822)
		(end 34.566352 -447.251582)
		(width 0.13462)
		(layer "F.Cu")
		(net "TDR_DIFF_85_TOP_DIP")
	)
	(segment
		(start 25.163272 -447.251582)
		(end 25.432512 -447.520822)
		(width 0.13462)
		(layer "F.Cu")
		(net "TDR_DIFF_85_TOP_DIP")
	)
	(segment
		(start 48.389032 -444.652654)
		(end 48.389032 -447.251582)
		(width 0.13462)
		(layer "F.Cu")
		(net "TDR_DIFF_85_TOP_DIP")
	)
	(segment
		(start 21.292312 -444.652654)
		(end 21.292312 -447.251582)
		(width 0.13462)
		(layer "F.Cu")
		(net "TDR_DIFF_85_TOP_DIP")
	)
	(segment
		(start 78.345792 -445.737234)
		(end 78.345792 -444.739014)
		(width 0.13462)
		(layer "F.Cu")
		(net "TDR_DIFF_85_TOP_DIP")
	)
	(segment
		(start 21.292312 -447.251582)
		(end 21.561552 -447.520822)
		(width 0.13462)
		(layer "F.Cu")
		(net "TDR_DIFF_85_TOP_DIP")
	)
	(segment
		(start 40.916352 -447.520822)
		(end 42.039032 -447.520822)
		(width 0.13462)
		(layer "F.Cu")
		(net "TDR_DIFF_85_TOP_DIP")
	)
	(segment
		(start 18.813272 -447.520822)
		(end 19.082512 -447.251582)
		(width 0.13462)
		(layer "F.Cu")
		(net "TDR_DIFF_85_TOP_DIP")
	)
	(segment
		(start 34.566352 -447.251582)
		(end 34.566352 -444.652654)
		(width 0.13462)
		(layer "F.Cu")
		(net "TDR_DIFF_85_TOP_DIP")
	)
	(segment
		(start 34.566352 -444.652654)
		(end 34.99612 -444.222886)
		(width 0.13462)
		(layer "F.Cu")
		(net "TDR_DIFF_85_TOP_DIP")
	)
	(segment
		(start 46.179232 -447.251582)
		(end 46.179232 -444.652654)
		(width 0.13462)
		(layer "F.Cu")
		(net "TDR_DIFF_85_TOP_DIP")
	)
	(segment
		(start 38.437312 -447.251582)
		(end 38.437312 -444.652654)
		(width 0.13462)
		(layer "F.Cu")
		(net "TDR_DIFF_85_TOP_DIP")
	)
	(segment
		(start 40.647112 -447.251582)
		(end 40.916352 -447.520822)
		(width 0.13462)
		(layer "F.Cu")
		(net "TDR_DIFF_85_TOP_DIP")
	)
	(segment
		(start 73.006712 -447.520822)
		(end 73.275952 -447.251582)
		(width 0.13462)
		(layer "F.Cu")
		(net "TDR_DIFF_85_TOP_DIP")
	)
	(segment
		(start 64.142112 -447.520822)
		(end 65.264792 -447.520822)
		(width 0.13462)
		(layer "F.Cu")
		(net "TDR_DIFF_85_TOP_DIP")
	)
	(segment
		(start 63.872872 -447.251582)
		(end 64.142112 -447.520822)
		(width 0.13462)
		(layer "F.Cu")
		(net "TDR_DIFF_85_TOP_DIP")
	)
	(segment
		(start 49.780952 -447.520822)
		(end 50.050192 -447.251582)
		(width 0.13462)
		(layer "F.Cu")
		(net "TDR_DIFF_85_TOP_DIP")
	)
	(segment
		(start 42.308272 -447.251582)
		(end 42.308272 -444.652654)
		(width 0.13462)
		(layer "F.Cu")
		(net "TDR_DIFF_85_TOP_DIP")
	)
	(segment
		(start 69.404992 -444.652654)
		(end 69.83476 -444.222886)
		(width 0.13462)
		(layer "F.Cu")
		(net "TDR_DIFF_85_TOP_DIP")
	)
	(segment
		(start 48.389032 -447.251582)
		(end 48.658272 -447.520822)
		(width 0.13462)
		(layer "F.Cu")
		(net "TDR_DIFF_85_TOP_DIP")
	)
	(segment
		(start 50.47996 -444.222886)
		(end 51.830224 -444.222886)
		(width 0.13462)
		(layer "F.Cu")
		(net "TDR_DIFF_85_TOP_DIP")
	)
	(segment
		(start 56.400192 -447.520822)
		(end 57.522872 -447.520822)
		(width 0.13462)
		(layer "F.Cu")
		(net "TDR_DIFF_85_TOP_DIP")
	)
	(segment
		(start 44.518072 -444.652654)
		(end 44.518072 -447.251582)
		(width 0.13462)
		(layer "F.Cu")
		(net "TDR_DIFF_85_TOP_DIP")
	)
	(segment
		(start 44.787312 -447.520822)
		(end 45.909992 -447.520822)
		(width 0.13462)
		(layer "F.Cu")
		(net "TDR_DIFF_85_TOP_DIP")
	)
	(segment
		(start 52.259992 -447.251582)
		(end 52.529232 -447.520822)
		(width 0.13462)
		(layer "F.Cu")
		(net "TDR_DIFF_85_TOP_DIP")
	)
	(segment
		(start 57.792112 -447.251582)
		(end 57.792112 -444.652654)
		(width 0.13462)
		(layer "F.Cu")
		(net "TDR_DIFF_85_TOP_DIP")
	)
	(segment
		(start 46.609 -444.222886)
		(end 47.959264 -444.222886)
		(width 0.13462)
		(layer "F.Cu")
		(net "TDR_DIFF_85_TOP_DIP")
	)
	(segment
		(start 75.055984 -444.222886)
		(end 75.485752 -444.652654)
		(width 0.13462)
		(layer "F.Cu")
		(net "TDR_DIFF_85_TOP_DIP")
	)
	(segment
		(start 69.404992 -447.251582)
		(end 69.404992 -444.652654)
		(width 0.13462)
		(layer "F.Cu")
		(net "TDR_DIFF_85_TOP_DIP")
	)
	(segment
		(start 69.83476 -444.222886)
		(end 71.185024 -444.222886)
		(width 0.13462)
		(layer "F.Cu")
		(net "TDR_DIFF_85_TOP_DIP")
	)
	(segment
		(start 60.001912 -444.652654)
		(end 60.001912 -447.251582)
		(width 0.13462)
		(layer "F.Cu")
		(net "TDR_DIFF_85_TOP_DIP")
	)
	(segment
		(start 51.830224 -444.222886)
		(end 52.259992 -444.652654)
		(width 0.13462)
		(layer "F.Cu")
		(net "TDR_DIFF_85_TOP_DIP")
	)
	(segment
		(start 61.663072 -444.652654)
		(end 62.09284 -444.222886)
		(width 0.13462)
		(layer "F.Cu")
		(net "TDR_DIFF_85_TOP_DIP")
	)
	(segment
		(start 26.824432 -447.251582)
		(end 26.824432 -444.652654)
		(width 0.13462)
		(layer "F.Cu")
		(net "TDR_DIFF_85_TOP_DIP")
	)
	(segment
		(start 44.088304 -444.222886)
		(end 44.518072 -444.652654)
		(width 0.13462)
		(layer "F.Cu")
		(net "TDR_DIFF_85_TOP_DIP")
	)
	(segment
		(start 61.663072 -447.251582)
		(end 61.663072 -444.652654)
		(width 0.13462)
		(layer "F.Cu")
		(net "TDR_DIFF_85_TOP_DIP")
	)
	(segment
		(start 40.217344 -444.222886)
		(end 40.647112 -444.652654)
		(width 0.13462)
		(layer "F.Cu")
		(net "TDR_DIFF_85_TOP_DIP")
	)
	(segment
		(start 56.130952 -447.251582)
		(end 56.400192 -447.520822)
		(width 0.13462)
		(layer "F.Cu")
		(net "TDR_DIFF_85_TOP_DIP")
	)
	(segment
		(start 30.426152 -447.520822)
		(end 30.695392 -447.251582)
		(width 0.13462)
		(layer "F.Cu")
		(net "TDR_DIFF_85_TOP_DIP")
	)
	(segment
		(start 17.690592 -447.520822)
		(end 18.813272 -447.520822)
		(width 0.13462)
		(layer "F.Cu")
		(net "TDR_DIFF_85_TOP_DIP")
	)
	(segment
		(start 34.99612 -444.222886)
		(end 36.346384 -444.222886)
		(width 0.13462)
		(layer "F.Cu")
		(net "TDR_DIFF_85_TOP_DIP")
	)
	(segment
		(start 19.082512 -447.251582)
		(end 19.082512 -444.652654)
		(width 0.13462)
		(layer "F.Cu")
		(net "TDR_DIFF_85_TOP_DIP")
	)
	(segment
		(start 75.754992 -445.871854)
		(end 78.211172 -445.871854)
		(width 0.13462)
		(layer "F.Cu")
		(net "TDR_DIFF_85_TOP_DIP")
	)
	(segment
		(start 21.561552 -447.520822)
		(end 22.684232 -447.520822)
		(width 0.13462)
		(layer "F.Cu")
		(net "TDR_DIFF_85_TOP_DIP")
	)
	(segment
		(start 27.2542 -444.222886)
		(end 28.604464 -444.222886)
		(width 0.13462)
		(layer "F.Cu")
		(net "TDR_DIFF_85_TOP_DIP")
	)
	(segment
		(start 45.909992 -447.520822)
		(end 46.179232 -447.251582)
		(width 0.13462)
		(layer "F.Cu")
		(net "TDR_DIFF_85_TOP_DIP")
	)
	(segment
		(start 42.039032 -447.520822)
		(end 42.308272 -447.251582)
		(width 0.13462)
		(layer "F.Cu")
		(net "TDR_DIFF_85_TOP_DIP")
	)
	(segment
		(start 24.733504 -444.222886)
		(end 25.163272 -444.652654)
		(width 0.13462)
		(layer "F.Cu")
		(net "TDR_DIFF_85_TOP_DIP")
	)
	(segment
		(start 38.168072 -447.520822)
		(end 38.437312 -447.251582)
		(width 0.13462)
		(layer "F.Cu")
		(net "TDR_DIFF_85_TOP_DIP")
	)
	(segment
		(start 53.921152 -444.652654)
		(end 54.35092 -444.222886)
		(width 0.13462)
		(layer "F.Cu")
		(net "TDR_DIFF_85_TOP_DIP")
	)
	(segment
		(start 78.211172 -445.871854)
		(end 78.345792 -445.737234)
		(width 0.13462)
		(layer "F.Cu")
		(net "TDR_DIFF_85_TOP_DIP")
	)
	(segment
		(start 19.082512 -444.652654)
		(end 19.51228 -444.222886)
		(width 0.13462)
		(layer "F.Cu")
		(net "TDR_DIFF_85_TOP_DIP")
	)
	(segment
		(start 57.792112 -444.652654)
		(end 58.22188 -444.222886)
		(width 0.13462)
		(layer "F.Cu")
		(net "TDR_DIFF_85_TOP_DIP")
	)
	(segment
		(start 61.393832 -447.520822)
		(end 61.663072 -447.251582)
		(width 0.13462)
		(layer "F.Cu")
		(net "TDR_DIFF_85_TOP_DIP")
	)
	(segment
		(start 47.959264 -444.222886)
		(end 48.389032 -444.652654)
		(width 0.13462)
		(layer "F.Cu")
		(net "TDR_DIFF_85_TOP_DIP")
	)
	(segment
		(start 60.001912 -447.251582)
		(end 60.271152 -447.520822)
		(width 0.13462)
		(layer "F.Cu")
		(net "TDR_DIFF_85_TOP_DIP")
	)
	(segment
		(start 33.174432 -447.520822)
		(end 34.297112 -447.520822)
		(width 0.13462)
		(layer "F.Cu")
		(net "TDR_DIFF_85_TOP_DIP")
	)
	(segment
		(start 14.421612 -445.871854)
		(end 16.991584 -445.871854)
		(width 0.13462)
		(layer "F.Cu")
		(net "TDR_DIFF_85_TOP_DIP")
	)
	(segment
		(start 65.264792 -447.520822)
		(end 65.534032 -447.251582)
		(width 0.13462)
		(layer "F.Cu")
		(net "TDR_DIFF_85_TOP_DIP")
	)
	(segment
		(start 68.013072 -447.520822)
		(end 69.135752 -447.520822)
		(width 0.13462)
		(layer "F.Cu")
		(net "TDR_DIFF_85_TOP_DIP")
	)
	(segment
		(start 22.684232 -447.520822)
		(end 22.953472 -447.251582)
		(width 0.13462)
		(layer "F.Cu")
		(net "TDR_DIFF_85_TOP_DIP")
	)
	(segment
		(start 26.824432 -444.652654)
		(end 27.2542 -444.222886)
		(width 0.13462)
		(layer "F.Cu")
		(net "TDR_DIFF_85_TOP_DIP")
	)
	(segment
		(start 65.534032 -447.251582)
		(end 65.534032 -444.652654)
		(width 0.13462)
		(layer "F.Cu")
		(net "TDR_DIFF_85_TOP_DIP")
	)
	(segment
		(start 30.695392 -444.652654)
		(end 31.12516 -444.222886)
		(width 0.13462)
		(layer "F.Cu")
		(net "TDR_DIFF_85_TOP_DIP")
	)
	(segment
		(start 36.776152 -447.251582)
		(end 37.045392 -447.520822)
		(width 0.13462)
		(layer "F.Cu")
		(net "TDR_DIFF_85_TOP_DIP")
	)
	(segment
		(start 40.647112 -444.652654)
		(end 40.647112 -447.251582)
		(width 0.13462)
		(layer "F.Cu")
		(net "TDR_DIFF_85_TOP_DIP")
	)
	(segment
		(start 48.658272 -447.520822)
		(end 49.780952 -447.520822)
		(width 0.13462)
		(layer "F.Cu")
		(net "TDR_DIFF_85_TOP_DIP")
	)
	(segment
		(start 75.485752 -445.602614)
		(end 75.754992 -445.871854)
		(width 0.13462)
		(layer "F.Cu")
		(net "TDR_DIFF_85_TOP_DIP")
	)
	(segment
		(start 50.050192 -447.251582)
		(end 50.050192 -444.652654)
		(width 0.13462)
		(layer "F.Cu")
		(net "TDR_DIFF_85_TOP_DIP")
	)
	(segment
		(start 32.905192 -447.251582)
		(end 33.174432 -447.520822)
		(width 0.13462)
		(layer "F.Cu")
		(net "TDR_DIFF_85_TOP_DIP")
	)
	(segment
		(start 30.695392 -447.251582)
		(end 30.695392 -444.652654)
		(width 0.13462)
		(layer "F.Cu")
		(net "TDR_DIFF_85_TOP_DIP")
	)
	(segment
		(start 52.259992 -444.652654)
		(end 52.259992 -447.251582)
		(width 0.13462)
		(layer "F.Cu")
		(net "TDR_DIFF_85_TOP_DIP")
	)
	(segment
		(start 29.034232 -447.251582)
		(end 29.303472 -447.520822)
		(width 0.13462)
		(layer "F.Cu")
		(net "TDR_DIFF_85_TOP_DIP")
	)
	(segment
		(start 22.953472 -447.251582)
		(end 22.953472 -444.652654)
		(width 0.13462)
		(layer "F.Cu")
		(net "TDR_DIFF_85_TOP_DIP")
	)
	(segment
		(start 19.51228 -444.222886)
		(end 20.862544 -444.222886)
		(width 0.13462)
		(layer "F.Cu")
		(net "TDR_DIFF_85_TOP_DIP")
	)
	(segment
		(start 57.522872 -447.520822)
		(end 57.792112 -447.251582)
		(width 0.13462)
		(layer "F.Cu")
		(net "TDR_DIFF_85_TOP_DIP")
	)
	(segment
		(start 52.529232 -447.520822)
		(end 53.651912 -447.520822)
		(width 0.13462)
		(layer "F.Cu")
		(net "TDR_DIFF_85_TOP_DIP")
	)
	(segment
		(start 71.614792 -444.652654)
		(end 71.614792 -447.251582)
		(width 0.13462)
		(layer "F.Cu")
		(net "TDR_DIFF_85_TOP_DIP")
	)
	(segment
		(start 36.776152 -444.652654)
		(end 36.776152 -447.251582)
		(width 0.13462)
		(layer "F.Cu")
		(net "TDR_DIFF_85_TOP_DIP")
	)
	(segment
		(start 23.38324 -444.222886)
		(end 24.733504 -444.222886)
		(width 0.13462)
		(layer "F.Cu")
		(net "TDR_DIFF_85_TOP_DIP")
	)
	(segment
		(start 14.286992 -444.739014)
		(end 14.286992 -445.737234)
		(width 0.13462)
		(layer "F.Cu")
		(net "TDR_DIFF_85_TOP_DIP")
	)
	(segment
		(start 16.991584 -445.871854)
		(end 17.421352 -446.301622)
		(width 0.13462)
		(layer "F.Cu")
		(net "TDR_DIFF_85_TOP_DIP")
	)
	(segment
		(start 37.045392 -447.520822)
		(end 38.168072 -447.520822)
		(width 0.13462)
		(layer "F.Cu")
		(net "TDR_DIFF_85_TOP_DIP")
	)
	(segment
		(start 55.701184 -444.222886)
		(end 56.130952 -444.652654)
		(width 0.13462)
		(layer "F.Cu")
		(net "TDR_DIFF_85_TOP_DIP")
	)
	(segment
		(start 42.73804 -444.222886)
		(end 44.088304 -444.222886)
		(width 0.13462)
		(layer "F.Cu")
		(net "TDR_DIFF_85_TOP_DIP")
	)
	(segment
		(start 71.614792 -447.251582)
		(end 71.884032 -447.520822)
		(width 0.13462)
		(layer "F.Cu")
		(net "TDR_DIFF_85_TOP_DIP")
	)
	(segment
		(start 25.163272 -444.652654)
		(end 25.163272 -447.251582)
		(width 0.13462)
		(layer "F.Cu")
		(net "TDR_DIFF_85_TOP_DIP")
	)
	(segment
		(start 75.485752 -444.652654)
		(end 75.485752 -445.602614)
		(width 0.13462)
		(layer "F.Cu")
		(net "TDR_DIFF_85_TOP_DIP")
	)
	(segment
		(start 22.953472 -444.652654)
		(end 23.38324 -444.222886)
		(width 0.13462)
		(layer "F.Cu")
		(net "TDR_DIFF_85_TOP_DIP")
	)
	(segment
		(start 131.388358 -453.210422)
		(end 131.911598 -453.210422)
		(width 0.1651)
		(layer "In9.Cu")
		(net "TDR_DIFF_85_IN3_DIP")
	)
	(segment
		(start 90.021918 -452.880222)
		(end 90.352118 -453.210422)
		(width 0.1651)
		(layer "In9.Cu")
		(net "TDR_DIFF_85_IN3_DIP")
	)
	(segment
		(start 142.782798 -452.880222)
		(end 143.112998 -453.210422)
		(width 0.1651)
		(layer "In9.Cu")
		(net "TDR_DIFF_85_IN3_DIP")
	)
	(segment
		(start 118.838218 -450.55663)
		(end 119.333518 -451.05193)
		(width 0.1651)
		(layer "In9.Cu")
		(net "TDR_DIFF_85_IN3_DIP")
	)
	(segment
		(start 91.700858 -450.55663)
		(end 92.457778 -450.55663)
		(width 0.1651)
		(layer "In9.Cu")
		(net "TDR_DIFF_85_IN3_DIP")
	)
	(segment
		(start 148.645118 -451.05193)
		(end 148.645118 -451.553326)
		(width 0.1651)
		(layer "In9.Cu")
		(net "TDR_DIFF_85_IN3_DIP")
	)
	(segment
		(start 148.645118 -451.553326)
		(end 148.975318 -451.883526)
		(width 0.1651)
		(layer "In9.Cu")
		(net "TDR_DIFF_85_IN3_DIP")
	)
	(segment
		(start 145.713958 -452.880222)
		(end 146.044158 -453.210422)
		(width 0.1651)
		(layer "In9.Cu")
		(net "TDR_DIFF_85_IN3_DIP")
	)
	(segment
		(start 94.136718 -451.05193)
		(end 94.632018 -450.55663)
		(width 0.1651)
		(layer "In9.Cu")
		(net "TDR_DIFF_85_IN3_DIP")
	)
	(segment
		(start 141.035278 -451.05193)
		(end 141.530578 -450.55663)
		(width 0.1651)
		(layer "In9.Cu")
		(net "TDR_DIFF_85_IN3_DIP")
	)
	(segment
		(start 135.172958 -452.880222)
		(end 135.172958 -451.05193)
		(width 0.1651)
		(layer "In9.Cu")
		(net "TDR_DIFF_85_IN3_DIP")
	)
	(segment
		(start 100.494338 -450.55663)
		(end 101.251258 -450.55663)
		(width 0.1651)
		(layer "In9.Cu")
		(net "TDR_DIFF_85_IN3_DIP")
	)
	(segment
		(start 133.494018 -450.55663)
		(end 133.989318 -451.05193)
		(width 0.1651)
		(layer "In9.Cu")
		(net "TDR_DIFF_85_IN3_DIP")
	)
	(segment
		(start 129.310638 -452.880222)
		(end 129.310638 -451.05193)
		(width 0.1651)
		(layer "In9.Cu")
		(net "TDR_DIFF_85_IN3_DIP")
	)
	(segment
		(start 95.884238 -452.880222)
		(end 96.214438 -453.210422)
		(width 0.1651)
		(layer "In9.Cu")
		(net "TDR_DIFF_85_IN3_DIP")
	)
	(segment
		(start 91.205558 -451.05193)
		(end 91.700858 -450.55663)
		(width 0.1651)
		(layer "In9.Cu")
		(net "TDR_DIFF_85_IN3_DIP")
	)
	(segment
		(start 136.425178 -450.55663)
		(end 136.920478 -451.05193)
		(width 0.1651)
		(layer "In9.Cu")
		(net "TDR_DIFF_85_IN3_DIP")
	)
	(segment
		(start 139.851638 -451.05193)
		(end 139.851638 -452.880222)
		(width 0.1651)
		(layer "In9.Cu")
		(net "TDR_DIFF_85_IN3_DIP")
	)
	(segment
		(start 115.907058 -450.55663)
		(end 116.402358 -451.05193)
		(width 0.1651)
		(layer "In9.Cu")
		(net "TDR_DIFF_85_IN3_DIP")
	)
	(segment
		(start 116.402358 -452.880222)
		(end 116.732558 -453.210422)
		(width 0.1651)
		(layer "In9.Cu")
		(net "TDR_DIFF_85_IN3_DIP")
	)
	(segment
		(start 143.966438 -451.05193)
		(end 144.461738 -450.55663)
		(width 0.1651)
		(layer "In9.Cu")
		(net "TDR_DIFF_85_IN3_DIP")
	)
	(segment
		(start 117.585998 -451.05193)
		(end 118.081298 -450.55663)
		(width 0.1651)
		(layer "In9.Cu")
		(net "TDR_DIFF_85_IN3_DIP")
	)
	(segment
		(start 97.067878 -452.880222)
		(end 97.067878 -451.05193)
		(width 0.1651)
		(layer "In9.Cu")
		(net "TDR_DIFF_85_IN3_DIP")
	)
	(segment
		(start 121.012458 -450.55663)
		(end 121.769378 -450.55663)
		(width 0.1651)
		(layer "In9.Cu")
		(net "TDR_DIFF_85_IN3_DIP")
	)
	(segment
		(start 146.897598 -452.880222)
		(end 146.897598 -451.05193)
		(width 0.1651)
		(layer "In9.Cu")
		(net "TDR_DIFF_85_IN3_DIP")
	)
	(segment
		(start 131.911598 -453.210422)
		(end 132.241798 -452.880222)
		(width 0.1651)
		(layer "In9.Cu")
		(net "TDR_DIFF_85_IN3_DIP")
	)
	(segment
		(start 137.773918 -453.210422)
		(end 138.104118 -452.880222)
		(width 0.1651)
		(layer "In9.Cu")
		(net "TDR_DIFF_85_IN3_DIP")
	)
	(segment
		(start 138.599418 -450.55663)
		(end 139.356338 -450.55663)
		(width 0.1651)
		(layer "In9.Cu")
		(net "TDR_DIFF_85_IN3_DIP")
	)
	(segment
		(start 108.462318 -453.210422)
		(end 108.792518 -452.880222)
		(width 0.1651)
		(layer "In9.Cu")
		(net "TDR_DIFF_85_IN3_DIP")
	)
	(segment
		(start 111.393478 -453.210422)
		(end 111.723678 -452.880222)
		(width 0.1651)
		(layer "In9.Cu")
		(net "TDR_DIFF_85_IN3_DIP")
	)
	(segment
		(start 97.563178 -450.55663)
		(end 98.320098 -450.55663)
		(width 0.1651)
		(layer "In9.Cu")
		(net "TDR_DIFF_85_IN3_DIP")
	)
	(segment
		(start 91.205558 -452.880222)
		(end 91.205558 -451.05193)
		(width 0.1651)
		(layer "In9.Cu")
		(net "TDR_DIFF_85_IN3_DIP")
	)
	(segment
		(start 105.007918 -453.210422)
		(end 105.531158 -453.210422)
		(width 0.1651)
		(layer "In9.Cu")
		(net "TDR_DIFF_85_IN3_DIP")
	)
	(segment
		(start 126.049278 -453.210422)
		(end 126.379478 -452.880222)
		(width 0.1651)
		(layer "In9.Cu")
		(net "TDR_DIFF_85_IN3_DIP")
	)
	(segment
		(start 87.175848 -450.754496)
		(end 87.175848 -451.718426)
		(width 0.1651)
		(layer "In9.Cu")
		(net "TDR_DIFF_85_IN3_DIP")
	)
	(segment
		(start 120.517158 -452.880222)
		(end 120.517158 -451.05193)
		(width 0.1651)
		(layer "In9.Cu")
		(net "TDR_DIFF_85_IN3_DIP")
	)
	(segment
		(start 113.471198 -451.05193)
		(end 113.471198 -452.880222)
		(width 0.1651)
		(layer "In9.Cu")
		(net "TDR_DIFF_85_IN3_DIP")
	)
	(segment
		(start 110.044738 -450.55663)
		(end 110.540038 -451.05193)
		(width 0.1651)
		(layer "In9.Cu")
		(net "TDR_DIFF_85_IN3_DIP")
	)
	(segment
		(start 123.448318 -452.880222)
		(end 123.448318 -451.05193)
		(width 0.1651)
		(layer "In9.Cu")
		(net "TDR_DIFF_85_IN3_DIP")
	)
	(segment
		(start 144.461738 -450.55663)
		(end 145.218658 -450.55663)
		(width 0.1651)
		(layer "In9.Cu")
		(net "TDR_DIFF_85_IN3_DIP")
	)
	(segment
		(start 126.379478 -451.05193)
		(end 126.874778 -450.55663)
		(width 0.1651)
		(layer "In9.Cu")
		(net "TDR_DIFF_85_IN3_DIP")
	)
	(segment
		(start 120.186958 -453.210422)
		(end 120.517158 -452.880222)
		(width 0.1651)
		(layer "In9.Cu")
		(net "TDR_DIFF_85_IN3_DIP")
	)
	(segment
		(start 118.081298 -450.55663)
		(end 118.838218 -450.55663)
		(width 0.1651)
		(layer "In9.Cu")
		(net "TDR_DIFF_85_IN3_DIP")
	)
	(segment
		(start 111.723678 -452.880222)
		(end 111.723678 -451.05193)
		(width 0.1651)
		(layer "In9.Cu")
		(net "TDR_DIFF_85_IN3_DIP")
	)
	(segment
		(start 136.920478 -451.05193)
		(end 136.920478 -452.880222)
		(width 0.1651)
		(layer "In9.Cu")
		(net "TDR_DIFF_85_IN3_DIP")
	)
	(segment
		(start 97.067878 -451.05193)
		(end 97.563178 -450.55663)
		(width 0.1651)
		(layer "In9.Cu")
		(net "TDR_DIFF_85_IN3_DIP")
	)
	(segment
		(start 103.425498 -450.55663)
		(end 104.182418 -450.55663)
		(width 0.1651)
		(layer "In9.Cu")
		(net "TDR_DIFF_85_IN3_DIP")
	)
	(segment
		(start 133.989318 -452.880222)
		(end 134.319518 -453.210422)
		(width 0.1651)
		(layer "In9.Cu")
		(net "TDR_DIFF_85_IN3_DIP")
	)
	(segment
		(start 136.920478 -452.880222)
		(end 137.250678 -453.210422)
		(width 0.1651)
		(layer "In9.Cu")
		(net "TDR_DIFF_85_IN3_DIP")
	)
	(segment
		(start 101.251258 -450.55663)
		(end 101.746558 -451.05193)
		(width 0.1651)
		(layer "In9.Cu")
		(net "TDR_DIFF_85_IN3_DIP")
	)
	(segment
		(start 95.388938 -450.55663)
		(end 95.884238 -451.05193)
		(width 0.1651)
		(layer "In9.Cu")
		(net "TDR_DIFF_85_IN3_DIP")
	)
	(segment
		(start 121.769378 -450.55663)
		(end 122.264678 -451.05193)
		(width 0.1651)
		(layer "In9.Cu")
		(net "TDR_DIFF_85_IN3_DIP")
	)
	(segment
		(start 112.975898 -450.55663)
		(end 113.471198 -451.05193)
		(width 0.1651)
		(layer "In9.Cu")
		(net "TDR_DIFF_85_IN3_DIP")
	)
	(segment
		(start 128.980438 -453.210422)
		(end 129.310638 -452.880222)
		(width 0.1651)
		(layer "In9.Cu")
		(net "TDR_DIFF_85_IN3_DIP")
	)
	(segment
		(start 146.897598 -451.05193)
		(end 147.392898 -450.55663)
		(width 0.1651)
		(layer "In9.Cu")
		(net "TDR_DIFF_85_IN3_DIP")
	)
	(segment
		(start 148.149818 -450.55663)
		(end 148.645118 -451.05193)
		(width 0.1651)
		(layer "In9.Cu")
		(net "TDR_DIFF_85_IN3_DIP")
	)
	(segment
		(start 110.870238 -453.210422)
		(end 111.393478 -453.210422)
		(width 0.1651)
		(layer "In9.Cu")
		(net "TDR_DIFF_85_IN3_DIP")
	)
	(segment
		(start 116.732558 -453.210422)
		(end 117.255798 -453.210422)
		(width 0.1651)
		(layer "In9.Cu")
		(net "TDR_DIFF_85_IN3_DIP")
	)
	(segment
		(start 95.884238 -451.05193)
		(end 95.884238 -452.880222)
		(width 0.1651)
		(layer "In9.Cu")
		(net "TDR_DIFF_85_IN3_DIP")
	)
	(segment
		(start 147.392898 -450.55663)
		(end 148.149818 -450.55663)
		(width 0.1651)
		(layer "In9.Cu")
		(net "TDR_DIFF_85_IN3_DIP")
	)
	(segment
		(start 123.943618 -450.55663)
		(end 124.700538 -450.55663)
		(width 0.1651)
		(layer "In9.Cu")
		(net "TDR_DIFF_85_IN3_DIP")
	)
	(segment
		(start 120.517158 -451.05193)
		(end 121.012458 -450.55663)
		(width 0.1651)
		(layer "In9.Cu")
		(net "TDR_DIFF_85_IN3_DIP")
	)
	(segment
		(start 92.457778 -450.55663)
		(end 92.953078 -451.05193)
		(width 0.1651)
		(layer "In9.Cu")
		(net "TDR_DIFF_85_IN3_DIP")
	)
	(segment
		(start 107.608878 -452.880222)
		(end 107.939078 -453.210422)
		(width 0.1651)
		(layer "In9.Cu")
		(net "TDR_DIFF_85_IN3_DIP")
	)
	(segment
		(start 145.218658 -450.55663)
		(end 145.713958 -451.05193)
		(width 0.1651)
		(layer "In9.Cu")
		(net "TDR_DIFF_85_IN3_DIP")
	)
	(segment
		(start 151.209248 -451.718426)
		(end 151.209248 -450.754496)
		(width 0.1651)
		(layer "In9.Cu")
		(net "TDR_DIFF_85_IN3_DIP")
	)
	(segment
		(start 90.352118 -453.210422)
		(end 90.875358 -453.210422)
		(width 0.1651)
		(layer "In9.Cu")
		(net "TDR_DIFF_85_IN3_DIP")
	)
	(segment
		(start 143.966438 -452.880222)
		(end 143.966438 -451.05193)
		(width 0.1651)
		(layer "In9.Cu")
		(net "TDR_DIFF_85_IN3_DIP")
	)
	(segment
		(start 107.608878 -451.05193)
		(end 107.608878 -452.880222)
		(width 0.1651)
		(layer "In9.Cu")
		(net "TDR_DIFF_85_IN3_DIP")
	)
	(segment
		(start 107.113578 -450.55663)
		(end 107.608878 -451.05193)
		(width 0.1651)
		(layer "In9.Cu")
		(net "TDR_DIFF_85_IN3_DIP")
	)
	(segment
		(start 123.118118 -453.210422)
		(end 123.448318 -452.880222)
		(width 0.1651)
		(layer "In9.Cu")
		(net "TDR_DIFF_85_IN3_DIP")
	)
	(segment
		(start 111.723678 -451.05193)
		(end 112.218978 -450.55663)
		(width 0.1651)
		(layer "In9.Cu")
		(net "TDR_DIFF_85_IN3_DIP")
	)
	(segment
		(start 143.112998 -453.210422)
		(end 143.636238 -453.210422)
		(width 0.1651)
		(layer "In9.Cu")
		(net "TDR_DIFF_85_IN3_DIP")
	)
	(segment
		(start 102.930198 -452.880222)
		(end 102.930198 -451.05193)
		(width 0.1651)
		(layer "In9.Cu")
		(net "TDR_DIFF_85_IN3_DIP")
	)
	(segment
		(start 99.999038 -452.880222)
		(end 99.999038 -451.05193)
		(width 0.1651)
		(layer "In9.Cu")
		(net "TDR_DIFF_85_IN3_DIP")
	)
	(segment
		(start 117.255798 -453.210422)
		(end 117.585998 -452.880222)
		(width 0.1651)
		(layer "In9.Cu")
		(net "TDR_DIFF_85_IN3_DIP")
	)
	(segment
		(start 131.058158 -451.05193)
		(end 131.058158 -452.880222)
		(width 0.1651)
		(layer "In9.Cu")
		(net "TDR_DIFF_85_IN3_DIP")
	)
	(segment
		(start 140.705078 -453.210422)
		(end 141.035278 -452.880222)
		(width 0.1651)
		(layer "In9.Cu")
		(net "TDR_DIFF_85_IN3_DIP")
	)
	(segment
		(start 101.746558 -451.05193)
		(end 101.746558 -452.880222)
		(width 0.1651)
		(layer "In9.Cu")
		(net "TDR_DIFF_85_IN3_DIP")
	)
	(segment
		(start 135.668258 -450.55663)
		(end 136.425178 -450.55663)
		(width 0.1651)
		(layer "In9.Cu")
		(net "TDR_DIFF_85_IN3_DIP")
	)
	(segment
		(start 122.264678 -451.05193)
		(end 122.264678 -452.880222)
		(width 0.1651)
		(layer "In9.Cu")
		(net "TDR_DIFF_85_IN3_DIP")
	)
	(segment
		(start 133.989318 -451.05193)
		(end 133.989318 -452.880222)
		(width 0.1651)
		(layer "In9.Cu")
		(net "TDR_DIFF_85_IN3_DIP")
	)
	(segment
		(start 119.333518 -452.880222)
		(end 119.663718 -453.210422)
		(width 0.1651)
		(layer "In9.Cu")
		(net "TDR_DIFF_85_IN3_DIP")
	)
	(segment
		(start 130.562858 -450.55663)
		(end 131.058158 -451.05193)
		(width 0.1651)
		(layer "In9.Cu")
		(net "TDR_DIFF_85_IN3_DIP")
	)
	(segment
		(start 117.585998 -452.880222)
		(end 117.585998 -451.05193)
		(width 0.1651)
		(layer "In9.Cu")
		(net "TDR_DIFF_85_IN3_DIP")
	)
	(segment
		(start 126.874778 -450.55663)
		(end 127.631698 -450.55663)
		(width 0.1651)
		(layer "In9.Cu")
		(net "TDR_DIFF_85_IN3_DIP")
	)
	(segment
		(start 94.632018 -450.55663)
		(end 95.388938 -450.55663)
		(width 0.1651)
		(layer "In9.Cu")
		(net "TDR_DIFF_85_IN3_DIP")
	)
	(segment
		(start 110.540038 -452.880222)
		(end 110.870238 -453.210422)
		(width 0.1651)
		(layer "In9.Cu")
		(net "TDR_DIFF_85_IN3_DIP")
	)
	(segment
		(start 99.999038 -451.05193)
		(end 100.494338 -450.55663)
		(width 0.1651)
		(layer "In9.Cu")
		(net "TDR_DIFF_85_IN3_DIP")
	)
	(segment
		(start 138.104118 -451.05193)
		(end 138.599418 -450.55663)
		(width 0.1651)
		(layer "In9.Cu")
		(net "TDR_DIFF_85_IN3_DIP")
	)
	(segment
		(start 127.631698 -450.55663)
		(end 128.126998 -451.05193)
		(width 0.1651)
		(layer "In9.Cu")
		(net "TDR_DIFF_85_IN3_DIP")
	)
	(segment
		(start 98.815398 -451.05193)
		(end 98.815398 -452.880222)
		(width 0.1651)
		(layer "In9.Cu")
		(net "TDR_DIFF_85_IN3_DIP")
	)
	(segment
		(start 128.126998 -451.05193)
		(end 128.126998 -452.880222)
		(width 0.1651)
		(layer "In9.Cu")
		(net "TDR_DIFF_85_IN3_DIP")
	)
	(segment
		(start 132.241798 -451.05193)
		(end 132.737098 -450.55663)
		(width 0.1651)
		(layer "In9.Cu")
		(net "TDR_DIFF_85_IN3_DIP")
	)
	(segment
		(start 114.654838 -452.880222)
		(end 114.654838 -451.05193)
		(width 0.1651)
		(layer "In9.Cu")
		(net "TDR_DIFF_85_IN3_DIP")
	)
	(segment
		(start 99.668838 -453.210422)
		(end 99.999038 -452.880222)
		(width 0.1651)
		(layer "In9.Cu")
		(net "TDR_DIFF_85_IN3_DIP")
	)
	(segment
		(start 108.792518 -452.880222)
		(end 108.792518 -451.05193)
		(width 0.1651)
		(layer "In9.Cu")
		(net "TDR_DIFF_85_IN3_DIP")
	)
	(segment
		(start 106.356658 -450.55663)
		(end 107.113578 -450.55663)
		(width 0.1651)
		(layer "In9.Cu")
		(net "TDR_DIFF_85_IN3_DIP")
	)
	(segment
		(start 125.195838 -451.05193)
		(end 125.195838 -452.880222)
		(width 0.1651)
		(layer "In9.Cu")
		(net "TDR_DIFF_85_IN3_DIP")
	)
	(segment
		(start 99.145598 -453.210422)
		(end 99.668838 -453.210422)
		(width 0.1651)
		(layer "In9.Cu")
		(net "TDR_DIFF_85_IN3_DIP")
	)
	(segment
		(start 105.861358 -452.880222)
		(end 105.861358 -451.05193)
		(width 0.1651)
		(layer "In9.Cu")
		(net "TDR_DIFF_85_IN3_DIP")
	)
	(segment
		(start 140.181838 -453.210422)
		(end 140.705078 -453.210422)
		(width 0.1651)
		(layer "In9.Cu")
		(net "TDR_DIFF_85_IN3_DIP")
	)
	(segment
		(start 90.021918 -452.378826)
		(end 90.021918 -452.880222)
		(width 0.1651)
		(layer "In9.Cu")
		(net "TDR_DIFF_85_IN3_DIP")
	)
	(segment
		(start 87.175848 -451.718426)
		(end 87.340948 -451.883526)
		(width 0.1651)
		(layer "In9.Cu")
		(net "TDR_DIFF_85_IN3_DIP")
	)
	(segment
		(start 96.737678 -453.210422)
		(end 97.067878 -452.880222)
		(width 0.1651)
		(layer "In9.Cu")
		(net "TDR_DIFF_85_IN3_DIP")
	)
	(segment
		(start 119.333518 -451.05193)
		(end 119.333518 -452.880222)
		(width 0.1651)
		(layer "In9.Cu")
		(net "TDR_DIFF_85_IN3_DIP")
	)
	(segment
		(start 138.104118 -452.880222)
		(end 138.104118 -451.05193)
		(width 0.1651)
		(layer "In9.Cu")
		(net "TDR_DIFF_85_IN3_DIP")
	)
	(segment
		(start 132.241798 -452.880222)
		(end 132.241798 -451.05193)
		(width 0.1651)
		(layer "In9.Cu")
		(net "TDR_DIFF_85_IN3_DIP")
	)
	(segment
		(start 98.320098 -450.55663)
		(end 98.815398 -451.05193)
		(width 0.1651)
		(layer "In9.Cu")
		(net "TDR_DIFF_85_IN3_DIP")
	)
	(segment
		(start 110.540038 -451.05193)
		(end 110.540038 -452.880222)
		(width 0.1651)
		(layer "In9.Cu")
		(net "TDR_DIFF_85_IN3_DIP")
	)
	(segment
		(start 92.953078 -451.05193)
		(end 92.953078 -452.880222)
		(width 0.1651)
		(layer "In9.Cu")
		(net "TDR_DIFF_85_IN3_DIP")
	)
	(segment
		(start 143.636238 -453.210422)
		(end 143.966438 -452.880222)
		(width 0.1651)
		(layer "In9.Cu")
		(net "TDR_DIFF_85_IN3_DIP")
	)
	(segment
		(start 137.250678 -453.210422)
		(end 137.773918 -453.210422)
		(width 0.1651)
		(layer "In9.Cu")
		(net "TDR_DIFF_85_IN3_DIP")
	)
	(segment
		(start 146.044158 -453.210422)
		(end 146.567398 -453.210422)
		(width 0.1651)
		(layer "In9.Cu")
		(net "TDR_DIFF_85_IN3_DIP")
	)
	(segment
		(start 89.526618 -451.883526)
		(end 90.021918 -452.378826)
		(width 0.1651)
		(layer "In9.Cu")
		(net "TDR_DIFF_85_IN3_DIP")
	)
	(segment
		(start 142.287498 -450.55663)
		(end 142.782798 -451.05193)
		(width 0.1651)
		(layer "In9.Cu")
		(net "TDR_DIFF_85_IN3_DIP")
	)
	(segment
		(start 134.319518 -453.210422)
		(end 134.842758 -453.210422)
		(width 0.1651)
		(layer "In9.Cu")
		(net "TDR_DIFF_85_IN3_DIP")
	)
	(segment
		(start 108.792518 -451.05193)
		(end 109.287818 -450.55663)
		(width 0.1651)
		(layer "In9.Cu")
		(net "TDR_DIFF_85_IN3_DIP")
	)
	(segment
		(start 139.851638 -452.880222)
		(end 140.181838 -453.210422)
		(width 0.1651)
		(layer "In9.Cu")
		(net "TDR_DIFF_85_IN3_DIP")
	)
	(segment
		(start 122.264678 -452.880222)
		(end 122.594878 -453.210422)
		(width 0.1651)
		(layer "In9.Cu")
		(net "TDR_DIFF_85_IN3_DIP")
	)
	(segment
		(start 145.713958 -451.05193)
		(end 145.713958 -452.880222)
		(width 0.1651)
		(layer "In9.Cu")
		(net "TDR_DIFF_85_IN3_DIP")
	)
	(segment
		(start 114.654838 -451.05193)
		(end 115.150138 -450.55663)
		(width 0.1651)
		(layer "In9.Cu")
		(net "TDR_DIFF_85_IN3_DIP")
	)
	(segment
		(start 132.737098 -450.55663)
		(end 133.494018 -450.55663)
		(width 0.1651)
		(layer "In9.Cu")
		(net "TDR_DIFF_85_IN3_DIP")
	)
	(segment
		(start 107.939078 -453.210422)
		(end 108.462318 -453.210422)
		(width 0.1651)
		(layer "In9.Cu")
		(net "TDR_DIFF_85_IN3_DIP")
	)
	(segment
		(start 114.324638 -453.210422)
		(end 114.654838 -452.880222)
		(width 0.1651)
		(layer "In9.Cu")
		(net "TDR_DIFF_85_IN3_DIP")
	)
	(segment
		(start 115.150138 -450.55663)
		(end 115.907058 -450.55663)
		(width 0.1651)
		(layer "In9.Cu")
		(net "TDR_DIFF_85_IN3_DIP")
	)
	(segment
		(start 104.677718 -452.880222)
		(end 105.007918 -453.210422)
		(width 0.1651)
		(layer "In9.Cu")
		(net "TDR_DIFF_85_IN3_DIP")
	)
	(segment
		(start 104.182418 -450.55663)
		(end 104.677718 -451.05193)
		(width 0.1651)
		(layer "In9.Cu")
		(net "TDR_DIFF_85_IN3_DIP")
	)
	(segment
		(start 93.806518 -453.210422)
		(end 94.136718 -452.880222)
		(width 0.1651)
		(layer "In9.Cu")
		(net "TDR_DIFF_85_IN3_DIP")
	)
	(segment
		(start 148.975318 -451.883526)
		(end 151.044148 -451.883526)
		(width 0.1651)
		(layer "In9.Cu")
		(net "TDR_DIFF_85_IN3_DIP")
	)
	(segment
		(start 90.875358 -453.210422)
		(end 91.205558 -452.880222)
		(width 0.1651)
		(layer "In9.Cu")
		(net "TDR_DIFF_85_IN3_DIP")
	)
	(segment
		(start 125.195838 -452.880222)
		(end 125.526038 -453.210422)
		(width 0.1651)
		(layer "In9.Cu")
		(net "TDR_DIFF_85_IN3_DIP")
	)
	(segment
		(start 119.663718 -453.210422)
		(end 120.186958 -453.210422)
		(width 0.1651)
		(layer "In9.Cu")
		(net "TDR_DIFF_85_IN3_DIP")
	)
	(segment
		(start 105.861358 -451.05193)
		(end 106.356658 -450.55663)
		(width 0.1651)
		(layer "In9.Cu")
		(net "TDR_DIFF_85_IN3_DIP")
	)
	(segment
		(start 128.457198 -453.210422)
		(end 128.980438 -453.210422)
		(width 0.1651)
		(layer "In9.Cu")
		(net "TDR_DIFF_85_IN3_DIP")
	)
	(segment
		(start 131.058158 -452.880222)
		(end 131.388358 -453.210422)
		(width 0.1651)
		(layer "In9.Cu")
		(net "TDR_DIFF_85_IN3_DIP")
	)
	(segment
		(start 151.044148 -451.883526)
		(end 151.209248 -451.718426)
		(width 0.1651)
		(layer "In9.Cu")
		(net "TDR_DIFF_85_IN3_DIP")
	)
	(segment
		(start 93.283278 -453.210422)
		(end 93.806518 -453.210422)
		(width 0.1651)
		(layer "In9.Cu")
		(net "TDR_DIFF_85_IN3_DIP")
	)
	(segment
		(start 104.677718 -451.05193)
		(end 104.677718 -452.880222)
		(width 0.1651)
		(layer "In9.Cu")
		(net "TDR_DIFF_85_IN3_DIP")
	)
	(segment
		(start 146.567398 -453.210422)
		(end 146.897598 -452.880222)
		(width 0.1651)
		(layer "In9.Cu")
		(net "TDR_DIFF_85_IN3_DIP")
	)
	(segment
		(start 96.214438 -453.210422)
		(end 96.737678 -453.210422)
		(width 0.1651)
		(layer "In9.Cu")
		(net "TDR_DIFF_85_IN3_DIP")
	)
	(segment
		(start 101.746558 -452.880222)
		(end 102.076758 -453.210422)
		(width 0.1651)
		(layer "In9.Cu")
		(net "TDR_DIFF_85_IN3_DIP")
	)
	(segment
		(start 141.530578 -450.55663)
		(end 142.287498 -450.55663)
		(width 0.1651)
		(layer "In9.Cu")
		(net "TDR_DIFF_85_IN3_DIP")
	)
	(segment
		(start 102.599998 -453.210422)
		(end 102.930198 -452.880222)
		(width 0.1651)
		(layer "In9.Cu")
		(net "TDR_DIFF_85_IN3_DIP")
	)
	(segment
		(start 128.126998 -452.880222)
		(end 128.457198 -453.210422)
		(width 0.1651)
		(layer "In9.Cu")
		(net "TDR_DIFF_85_IN3_DIP")
	)
	(segment
		(start 92.953078 -452.880222)
		(end 93.283278 -453.210422)
		(width 0.1651)
		(layer "In9.Cu")
		(net "TDR_DIFF_85_IN3_DIP")
	)
	(segment
		(start 141.035278 -452.880222)
		(end 141.035278 -451.05193)
		(width 0.1651)
		(layer "In9.Cu")
		(net "TDR_DIFF_85_IN3_DIP")
	)
	(segment
		(start 125.526038 -453.210422)
		(end 126.049278 -453.210422)
		(width 0.1651)
		(layer "In9.Cu")
		(net "TDR_DIFF_85_IN3_DIP")
	)
	(segment
		(start 126.379478 -452.880222)
		(end 126.379478 -451.05193)
		(width 0.1651)
		(layer "In9.Cu")
		(net "TDR_DIFF_85_IN3_DIP")
	)
	(segment
		(start 87.340948 -451.883526)
		(end 89.526618 -451.883526)
		(width 0.1651)
		(layer "In9.Cu")
		(net "TDR_DIFF_85_IN3_DIP")
	)
	(segment
		(start 134.842758 -453.210422)
		(end 135.172958 -452.880222)
		(width 0.1651)
		(layer "In9.Cu")
		(net "TDR_DIFF_85_IN3_DIP")
	)
	(segment
		(start 109.287818 -450.55663)
		(end 110.044738 -450.55663)
		(width 0.1651)
		(layer "In9.Cu")
		(net "TDR_DIFF_85_IN3_DIP")
	)
	(segment
		(start 129.805938 -450.55663)
		(end 130.562858 -450.55663)
		(width 0.1651)
		(layer "In9.Cu")
		(net "TDR_DIFF_85_IN3_DIP")
	)
	(segment
		(start 98.815398 -452.880222)
		(end 99.145598 -453.210422)
		(width 0.1651)
		(layer "In9.Cu")
		(net "TDR_DIFF_85_IN3_DIP")
	)
	(segment
		(start 124.700538 -450.55663)
		(end 125.195838 -451.05193)
		(width 0.1651)
		(layer "In9.Cu")
		(net "TDR_DIFF_85_IN3_DIP")
	)
	(segment
		(start 113.801398 -453.210422)
		(end 114.324638 -453.210422)
		(width 0.1651)
		(layer "In9.Cu")
		(net "TDR_DIFF_85_IN3_DIP")
	)
	(segment
		(start 102.076758 -453.210422)
		(end 102.599998 -453.210422)
		(width 0.1651)
		(layer "In9.Cu")
		(net "TDR_DIFF_85_IN3_DIP")
	)
	(segment
		(start 102.930198 -451.05193)
		(end 103.425498 -450.55663)
		(width 0.1651)
		(layer "In9.Cu")
		(net "TDR_DIFF_85_IN3_DIP")
	)
	(segment
		(start 135.172958 -451.05193)
		(end 135.668258 -450.55663)
		(width 0.1651)
		(layer "In9.Cu")
		(net "TDR_DIFF_85_IN3_DIP")
	)
	(segment
		(start 129.310638 -451.05193)
		(end 129.805938 -450.55663)
		(width 0.1651)
		(layer "In9.Cu")
		(net "TDR_DIFF_85_IN3_DIP")
	)
	(segment
		(start 94.136718 -452.880222)
		(end 94.136718 -451.05193)
		(width 0.1651)
		(layer "In9.Cu")
		(net "TDR_DIFF_85_IN3_DIP")
	)
	(segment
		(start 142.782798 -451.05193)
		(end 142.782798 -452.880222)
		(width 0.1651)
		(layer "In9.Cu")
		(net "TDR_DIFF_85_IN3_DIP")
	)
	(segment
		(start 123.448318 -451.05193)
		(end 123.943618 -450.55663)
		(width 0.1651)
		(layer "In9.Cu")
		(net "TDR_DIFF_85_IN3_DIP")
	)
	(segment
		(start 139.356338 -450.55663)
		(end 139.851638 -451.05193)
		(width 0.1651)
		(layer "In9.Cu")
		(net "TDR_DIFF_85_IN3_DIP")
	)
	(segment
		(start 112.218978 -450.55663)
		(end 112.975898 -450.55663)
		(width 0.1651)
		(layer "In9.Cu")
		(net "TDR_DIFF_85_IN3_DIP")
	)
	(segment
		(start 116.402358 -451.05193)
		(end 116.402358 -452.880222)
		(width 0.1651)
		(layer "In9.Cu")
		(net "TDR_DIFF_85_IN3_DIP")
	)
	(segment
		(start 122.594878 -453.210422)
		(end 123.118118 -453.210422)
		(width 0.1651)
		(layer "In9.Cu")
		(net "TDR_DIFF_85_IN3_DIP")
	)
	(segment
		(start 105.531158 -453.210422)
		(end 105.861358 -452.880222)
		(width 0.1651)
		(layer "In9.Cu")
		(net "TDR_DIFF_85_IN3_DIP")
	)
	(segment
		(start 113.471198 -452.880222)
		(end 113.801398 -453.210422)
		(width 0.1651)
		(layer "In9.Cu")
		(net "TDR_DIFF_85_IN3_DIP")
	)
	(segment
		(start 391.664952 -456.668886)
		(end 392.673332 -457.677266)
		(width 0.15494)
		(layer "In11.Cu")
		(net "TDR_SE_50_OHM_IN4")
	)
	(segment
		(start 317.13297 -456.668886)
		(end 391.664952 -456.668886)
		(width 0.15494)
		(layer "In11.Cu")
		(net "TDR_SE_50_OHM_IN4")
	)
	(segment
		(start 392.673332 -457.677266)
		(end 392.673332 -458.200506)
		(width 0.15494)
		(layer "In11.Cu")
		(net "TDR_SE_50_OHM_IN4")
	)
	(segment
		(start 391.664952 -459.208886)
		(end 317.13297 -459.208886)
		(width 0.15494)
		(layer "In11.Cu")
		(net "TDR_SE_50_OHM_IN4")
	)
	(segment
		(start 392.673332 -458.200506)
		(end 391.664952 -459.208886)
		(width 0.15494)
		(layer "In11.Cu")
		(net "TDR_SE_50_OHM_IN4")
	)
	(segment
		(start 63.749682 -458.66558)
		(end 64.244982 -459.16088)
		(width 0.1651)
		(layer "In5.Cu")
		(net "TDR_DIFF_85_IN1_DIP")
	)
	(segment
		(start 17.346422 -459.16088)
		(end 18.103342 -459.16088)
		(width 0.1651)
		(layer "In5.Cu")
		(net "TDR_DIFF_85_IN1_DIP")
	)
	(segment
		(start 18.598642 -458.66558)
		(end 18.598642 -456.837288)
		(width 0.1651)
		(layer "In5.Cu")
		(net "TDR_DIFF_85_IN1_DIP")
	)
	(segment
		(start 27.392122 -456.837288)
		(end 27.722322 -456.507088)
		(width 0.1651)
		(layer "In5.Cu")
		(net "TDR_DIFF_85_IN1_DIP")
	)
	(segment
		(start 18.928842 -456.507088)
		(end 19.452082 -456.507088)
		(width 0.1651)
		(layer "In5.Cu")
		(net "TDR_DIFF_85_IN1_DIP")
	)
	(segment
		(start 39.970202 -456.507088)
		(end 40.300402 -456.837288)
		(width 0.1651)
		(layer "In5.Cu")
		(net "TDR_DIFF_85_IN1_DIP")
	)
	(segment
		(start 74.290682 -456.837288)
		(end 74.620882 -456.507088)
		(width 0.1651)
		(layer "In5.Cu")
		(net "TDR_DIFF_85_IN1_DIP")
	)
	(segment
		(start 60.818522 -458.66558)
		(end 61.313822 -459.16088)
		(width 0.1651)
		(layer "In5.Cu")
		(net "TDR_DIFF_85_IN1_DIP")
	)
	(segment
		(start 43.231562 -456.837288)
		(end 43.231562 -458.66558)
		(width 0.1651)
		(layer "In5.Cu")
		(net "TDR_DIFF_85_IN1_DIP")
	)
	(segment
		(start 49.093882 -456.837288)
		(end 49.093882 -458.66558)
		(width 0.1651)
		(layer "In5.Cu")
		(net "TDR_DIFF_85_IN1_DIP")
	)
	(segment
		(start 32.759142 -459.16088)
		(end 33.254442 -458.66558)
		(width 0.1651)
		(layer "In5.Cu")
		(net "TDR_DIFF_85_IN1_DIP")
	)
	(segment
		(start 40.300402 -458.66558)
		(end 40.795702 -459.16088)
		(width 0.1651)
		(layer "In5.Cu")
		(net "TDR_DIFF_85_IN1_DIP")
	)
	(segment
		(start 14.286992 -457.999084)
		(end 14.452092 -457.833984)
		(width 0.1651)
		(layer "In5.Cu")
		(net "TDR_DIFF_85_IN1_DIP")
	)
	(segment
		(start 34.107882 -456.507088)
		(end 34.438082 -456.837288)
		(width 0.1651)
		(layer "In5.Cu")
		(net "TDR_DIFF_85_IN1_DIP")
	)
	(segment
		(start 29.827982 -459.16088)
		(end 30.323282 -458.66558)
		(width 0.1651)
		(layer "In5.Cu")
		(net "TDR_DIFF_85_IN1_DIP")
	)
	(segment
		(start 62.566042 -456.837288)
		(end 62.896242 -456.507088)
		(width 0.1651)
		(layer "In5.Cu")
		(net "TDR_DIFF_85_IN1_DIP")
	)
	(segment
		(start 33.254442 -458.66558)
		(end 33.254442 -456.837288)
		(width 0.1651)
		(layer "In5.Cu")
		(net "TDR_DIFF_85_IN1_DIP")
	)
	(segment
		(start 36.515802 -456.507088)
		(end 37.039042 -456.507088)
		(width 0.1651)
		(layer "In5.Cu")
		(net "TDR_DIFF_85_IN1_DIP")
	)
	(segment
		(start 34.933382 -459.16088)
		(end 35.690302 -459.16088)
		(width 0.1651)
		(layer "In5.Cu")
		(net "TDR_DIFF_85_IN1_DIP")
	)
	(segment
		(start 49.093882 -458.66558)
		(end 49.589182 -459.16088)
		(width 0.1651)
		(layer "In5.Cu")
		(net "TDR_DIFF_85_IN1_DIP")
	)
	(segment
		(start 31.506922 -458.66558)
		(end 32.002222 -459.16088)
		(width 0.1651)
		(layer "In5.Cu")
		(net "TDR_DIFF_85_IN1_DIP")
	)
	(segment
		(start 62.896242 -456.507088)
		(end 63.419482 -456.507088)
		(width 0.1651)
		(layer "In5.Cu")
		(net "TDR_DIFF_85_IN1_DIP")
	)
	(segment
		(start 40.300402 -456.837288)
		(end 40.300402 -458.66558)
		(width 0.1651)
		(layer "In5.Cu")
		(net "TDR_DIFF_85_IN1_DIP")
	)
	(segment
		(start 20.277582 -459.16088)
		(end 21.034502 -459.16088)
		(width 0.1651)
		(layer "In5.Cu")
		(net "TDR_DIFF_85_IN1_DIP")
	)
	(segment
		(start 40.795702 -459.16088)
		(end 41.552622 -459.16088)
		(width 0.1651)
		(layer "In5.Cu")
		(net "TDR_DIFF_85_IN1_DIP")
	)
	(segment
		(start 48.763682 -456.507088)
		(end 49.093882 -456.837288)
		(width 0.1651)
		(layer "In5.Cu")
		(net "TDR_DIFF_85_IN1_DIP")
	)
	(segment
		(start 41.552622 -459.16088)
		(end 42.047922 -458.66558)
		(width 0.1651)
		(layer "In5.Cu")
		(net "TDR_DIFF_85_IN1_DIP")
	)
	(segment
		(start 66.680842 -458.66558)
		(end 67.176142 -459.16088)
		(width 0.1651)
		(layer "In5.Cu")
		(net "TDR_DIFF_85_IN1_DIP")
	)
	(segment
		(start 68.428362 -458.66558)
		(end 68.428362 -456.837288)
		(width 0.1651)
		(layer "In5.Cu")
		(net "TDR_DIFF_85_IN1_DIP")
	)
	(segment
		(start 62.070742 -459.16088)
		(end 62.566042 -458.66558)
		(width 0.1651)
		(layer "In5.Cu")
		(net "TDR_DIFF_85_IN1_DIP")
	)
	(segment
		(start 42.901362 -456.507088)
		(end 43.231562 -456.837288)
		(width 0.1651)
		(layer "In5.Cu")
		(net "TDR_DIFF_85_IN1_DIP")
	)
	(segment
		(start 75.474322 -457.338684)
		(end 75.969622 -457.833984)
		(width 0.1651)
		(layer "In5.Cu")
		(net "TDR_DIFF_85_IN1_DIP")
	)
	(segment
		(start 23.208742 -459.16088)
		(end 23.965662 -459.16088)
		(width 0.1651)
		(layer "In5.Cu")
		(net "TDR_DIFF_85_IN1_DIP")
	)
	(segment
		(start 50.841402 -458.66558)
		(end 50.841402 -456.837288)
		(width 0.1651)
		(layer "In5.Cu")
		(net "TDR_DIFF_85_IN1_DIP")
	)
	(segment
		(start 52.520342 -459.16088)
		(end 53.277262 -459.16088)
		(width 0.1651)
		(layer "In5.Cu")
		(net "TDR_DIFF_85_IN1_DIP")
	)
	(segment
		(start 59.965082 -456.507088)
		(end 60.488322 -456.507088)
		(width 0.1651)
		(layer "In5.Cu")
		(net "TDR_DIFF_85_IN1_DIP")
	)
	(segment
		(start 24.460962 -456.837288)
		(end 24.791162 -456.507088)
		(width 0.1651)
		(layer "In5.Cu")
		(net "TDR_DIFF_85_IN1_DIP")
	)
	(segment
		(start 53.772562 -458.66558)
		(end 53.772562 -456.837288)
		(width 0.1651)
		(layer "In5.Cu")
		(net "TDR_DIFF_85_IN1_DIP")
	)
	(segment
		(start 32.002222 -459.16088)
		(end 32.759142 -459.16088)
		(width 0.1651)
		(layer "In5.Cu")
		(net "TDR_DIFF_85_IN1_DIP")
	)
	(segment
		(start 30.323282 -456.837288)
		(end 30.653482 -456.507088)
		(width 0.1651)
		(layer "In5.Cu")
		(net "TDR_DIFF_85_IN1_DIP")
	)
	(segment
		(start 25.644602 -458.66558)
		(end 26.139902 -459.16088)
		(width 0.1651)
		(layer "In5.Cu")
		(net "TDR_DIFF_85_IN1_DIP")
	)
	(segment
		(start 16.520922 -457.833984)
		(end 16.851122 -458.164184)
		(width 0.1651)
		(layer "In5.Cu")
		(net "TDR_DIFF_85_IN1_DIP")
	)
	(segment
		(start 59.139582 -459.16088)
		(end 59.634882 -458.66558)
		(width 0.1651)
		(layer "In5.Cu")
		(net "TDR_DIFF_85_IN1_DIP")
	)
	(segment
		(start 39.116762 -456.837288)
		(end 39.446962 -456.507088)
		(width 0.1651)
		(layer "In5.Cu")
		(net "TDR_DIFF_85_IN1_DIP")
	)
	(segment
		(start 71.359522 -456.837288)
		(end 71.689722 -456.507088)
		(width 0.1651)
		(layer "In5.Cu")
		(net "TDR_DIFF_85_IN1_DIP")
	)
	(segment
		(start 60.818522 -456.837288)
		(end 60.818522 -458.66558)
		(width 0.1651)
		(layer "In5.Cu")
		(net "TDR_DIFF_85_IN1_DIP")
	)
	(segment
		(start 72.543162 -458.66558)
		(end 73.038462 -459.16088)
		(width 0.1651)
		(layer "In5.Cu")
		(net "TDR_DIFF_85_IN1_DIP")
	)
	(segment
		(start 37.369242 -456.837288)
		(end 37.369242 -458.66558)
		(width 0.1651)
		(layer "In5.Cu")
		(net "TDR_DIFF_85_IN1_DIP")
	)
	(segment
		(start 63.419482 -456.507088)
		(end 63.749682 -456.837288)
		(width 0.1651)
		(layer "In5.Cu")
		(net "TDR_DIFF_85_IN1_DIP")
	)
	(segment
		(start 18.103342 -459.16088)
		(end 18.598642 -458.66558)
		(width 0.1651)
		(layer "In5.Cu")
		(net "TDR_DIFF_85_IN1_DIP")
	)
	(segment
		(start 37.369242 -458.66558)
		(end 37.864542 -459.16088)
		(width 0.1651)
		(layer "In5.Cu")
		(net "TDR_DIFF_85_IN1_DIP")
	)
	(segment
		(start 45.832522 -456.507088)
		(end 46.162722 -456.837288)
		(width 0.1651)
		(layer "In5.Cu")
		(net "TDR_DIFF_85_IN1_DIP")
	)
	(segment
		(start 21.529802 -456.837288)
		(end 21.860002 -456.507088)
		(width 0.1651)
		(layer "In5.Cu")
		(net "TDR_DIFF_85_IN1_DIP")
	)
	(segment
		(start 56.208422 -459.16088)
		(end 56.703722 -458.66558)
		(width 0.1651)
		(layer "In5.Cu")
		(net "TDR_DIFF_85_IN1_DIP")
	)
	(segment
		(start 54.956202 -458.66558)
		(end 55.451502 -459.16088)
		(width 0.1651)
		(layer "In5.Cu")
		(net "TDR_DIFF_85_IN1_DIP")
	)
	(segment
		(start 53.772562 -456.837288)
		(end 54.102762 -456.507088)
		(width 0.1651)
		(layer "In5.Cu")
		(net "TDR_DIFF_85_IN1_DIP")
	)
	(segment
		(start 49.589182 -459.16088)
		(end 50.346102 -459.16088)
		(width 0.1651)
		(layer "In5.Cu")
		(net "TDR_DIFF_85_IN1_DIP")
	)
	(segment
		(start 23.965662 -459.16088)
		(end 24.460962 -458.66558)
		(width 0.1651)
		(layer "In5.Cu")
		(net "TDR_DIFF_85_IN1_DIP")
	)
	(segment
		(start 42.047922 -458.66558)
		(end 42.047922 -456.837288)
		(width 0.1651)
		(layer "In5.Cu")
		(net "TDR_DIFF_85_IN1_DIP")
	)
	(segment
		(start 33.584642 -456.507088)
		(end 34.107882 -456.507088)
		(width 0.1651)
		(layer "In5.Cu")
		(net "TDR_DIFF_85_IN1_DIP")
	)
	(segment
		(start 27.722322 -456.507088)
		(end 28.245562 -456.507088)
		(width 0.1651)
		(layer "In5.Cu")
		(net "TDR_DIFF_85_IN1_DIP")
	)
	(segment
		(start 57.887362 -458.66558)
		(end 58.382662 -459.16088)
		(width 0.1651)
		(layer "In5.Cu")
		(net "TDR_DIFF_85_IN1_DIP")
	)
	(segment
		(start 44.979082 -458.66558)
		(end 44.979082 -456.837288)
		(width 0.1651)
		(layer "In5.Cu")
		(net "TDR_DIFF_85_IN1_DIP")
	)
	(segment
		(start 57.887362 -456.837288)
		(end 57.887362 -458.66558)
		(width 0.1651)
		(layer "In5.Cu")
		(net "TDR_DIFF_85_IN1_DIP")
	)
	(segment
		(start 59.634882 -458.66558)
		(end 59.634882 -456.837288)
		(width 0.1651)
		(layer "In5.Cu")
		(net "TDR_DIFF_85_IN1_DIP")
	)
	(segment
		(start 71.689722 -456.507088)
		(end 72.212962 -456.507088)
		(width 0.1651)
		(layer "In5.Cu")
		(net "TDR_DIFF_85_IN1_DIP")
	)
	(segment
		(start 65.827402 -456.507088)
		(end 66.350642 -456.507088)
		(width 0.1651)
		(layer "In5.Cu")
		(net "TDR_DIFF_85_IN1_DIP")
	)
	(segment
		(start 60.488322 -456.507088)
		(end 60.818522 -456.837288)
		(width 0.1651)
		(layer "In5.Cu")
		(net "TDR_DIFF_85_IN1_DIP")
	)
	(segment
		(start 37.864542 -459.16088)
		(end 38.621462 -459.16088)
		(width 0.1651)
		(layer "In5.Cu")
		(net "TDR_DIFF_85_IN1_DIP")
	)
	(segment
		(start 37.039042 -456.507088)
		(end 37.369242 -456.837288)
		(width 0.1651)
		(layer "In5.Cu")
		(net "TDR_DIFF_85_IN1_DIP")
	)
	(segment
		(start 53.277262 -459.16088)
		(end 53.772562 -458.66558)
		(width 0.1651)
		(layer "In5.Cu")
		(net "TDR_DIFF_85_IN1_DIP")
	)
	(segment
		(start 68.428362 -456.837288)
		(end 68.758562 -456.507088)
		(width 0.1651)
		(layer "In5.Cu")
		(net "TDR_DIFF_85_IN1_DIP")
	)
	(segment
		(start 47.414942 -459.16088)
		(end 47.910242 -458.66558)
		(width 0.1651)
		(layer "In5.Cu")
		(net "TDR_DIFF_85_IN1_DIP")
	)
	(segment
		(start 25.644602 -456.837288)
		(end 25.644602 -458.66558)
		(width 0.1651)
		(layer "In5.Cu")
		(net "TDR_DIFF_85_IN1_DIP")
	)
	(segment
		(start 46.162722 -458.66558)
		(end 46.658022 -459.16088)
		(width 0.1651)
		(layer "In5.Cu")
		(net "TDR_DIFF_85_IN1_DIP")
	)
	(segment
		(start 68.758562 -456.507088)
		(end 69.281802 -456.507088)
		(width 0.1651)
		(layer "In5.Cu")
		(net "TDR_DIFF_85_IN1_DIP")
	)
	(segment
		(start 14.286992 -458.963014)
		(end 14.286992 -457.999084)
		(width 0.1651)
		(layer "In5.Cu")
		(net "TDR_DIFF_85_IN1_DIP")
	)
	(segment
		(start 66.350642 -456.507088)
		(end 66.680842 -456.837288)
		(width 0.1651)
		(layer "In5.Cu")
		(net "TDR_DIFF_85_IN1_DIP")
	)
	(segment
		(start 65.497202 -458.66558)
		(end 65.497202 -456.837288)
		(width 0.1651)
		(layer "In5.Cu")
		(net "TDR_DIFF_85_IN1_DIP")
	)
	(segment
		(start 18.598642 -456.837288)
		(end 18.928842 -456.507088)
		(width 0.1651)
		(layer "In5.Cu")
		(net "TDR_DIFF_85_IN1_DIP")
	)
	(segment
		(start 43.231562 -458.66558)
		(end 43.726862 -459.16088)
		(width 0.1651)
		(layer "In5.Cu")
		(net "TDR_DIFF_85_IN1_DIP")
	)
	(segment
		(start 16.851122 -458.66558)
		(end 17.346422 -459.16088)
		(width 0.1651)
		(layer "In5.Cu")
		(net "TDR_DIFF_85_IN1_DIP")
	)
	(segment
		(start 19.452082 -456.507088)
		(end 19.782282 -456.837288)
		(width 0.1651)
		(layer "In5.Cu")
		(net "TDR_DIFF_85_IN1_DIP")
	)
	(segment
		(start 26.139902 -459.16088)
		(end 26.896822 -459.16088)
		(width 0.1651)
		(layer "In5.Cu")
		(net "TDR_DIFF_85_IN1_DIP")
	)
	(segment
		(start 31.176722 -456.507088)
		(end 31.506922 -456.837288)
		(width 0.1651)
		(layer "In5.Cu")
		(net "TDR_DIFF_85_IN1_DIP")
	)
	(segment
		(start 74.620882 -456.507088)
		(end 75.144122 -456.507088)
		(width 0.1651)
		(layer "In5.Cu")
		(net "TDR_DIFF_85_IN1_DIP")
	)
	(segment
		(start 47.910242 -456.837288)
		(end 48.240442 -456.507088)
		(width 0.1651)
		(layer "In5.Cu")
		(net "TDR_DIFF_85_IN1_DIP")
	)
	(segment
		(start 56.703722 -458.66558)
		(end 56.703722 -456.837288)
		(width 0.1651)
		(layer "In5.Cu")
		(net "TDR_DIFF_85_IN1_DIP")
	)
	(segment
		(start 24.460962 -458.66558)
		(end 24.460962 -456.837288)
		(width 0.1651)
		(layer "In5.Cu")
		(net "TDR_DIFF_85_IN1_DIP")
	)
	(segment
		(start 64.244982 -459.16088)
		(end 65.001902 -459.16088)
		(width 0.1651)
		(layer "In5.Cu")
		(net "TDR_DIFF_85_IN1_DIP")
	)
	(segment
		(start 29.071062 -459.16088)
		(end 29.827982 -459.16088)
		(width 0.1651)
		(layer "In5.Cu")
		(net "TDR_DIFF_85_IN1_DIP")
	)
	(segment
		(start 54.102762 -456.507088)
		(end 54.626002 -456.507088)
		(width 0.1651)
		(layer "In5.Cu")
		(net "TDR_DIFF_85_IN1_DIP")
	)
	(segment
		(start 55.451502 -459.16088)
		(end 56.208422 -459.16088)
		(width 0.1651)
		(layer "In5.Cu")
		(net "TDR_DIFF_85_IN1_DIP")
	)
	(segment
		(start 28.575762 -458.66558)
		(end 29.071062 -459.16088)
		(width 0.1651)
		(layer "In5.Cu")
		(net "TDR_DIFF_85_IN1_DIP")
	)
	(segment
		(start 48.240442 -456.507088)
		(end 48.763682 -456.507088)
		(width 0.1651)
		(layer "In5.Cu")
		(net "TDR_DIFF_85_IN1_DIP")
	)
	(segment
		(start 75.144122 -456.507088)
		(end 75.474322 -456.837288)
		(width 0.1651)
		(layer "In5.Cu")
		(net "TDR_DIFF_85_IN1_DIP")
	)
	(segment
		(start 75.969622 -457.833984)
		(end 78.155292 -457.833984)
		(width 0.1651)
		(layer "In5.Cu")
		(net "TDR_DIFF_85_IN1_DIP")
	)
	(segment
		(start 50.841402 -456.837288)
		(end 51.171602 -456.507088)
		(width 0.1651)
		(layer "In5.Cu")
		(net "TDR_DIFF_85_IN1_DIP")
	)
	(segment
		(start 70.107302 -459.16088)
		(end 70.864222 -459.16088)
		(width 0.1651)
		(layer "In5.Cu")
		(net "TDR_DIFF_85_IN1_DIP")
	)
	(segment
		(start 42.378122 -456.507088)
		(end 42.901362 -456.507088)
		(width 0.1651)
		(layer "In5.Cu")
		(net "TDR_DIFF_85_IN1_DIP")
	)
	(segment
		(start 73.795382 -459.16088)
		(end 74.290682 -458.66558)
		(width 0.1651)
		(layer "In5.Cu")
		(net "TDR_DIFF_85_IN1_DIP")
	)
	(segment
		(start 42.047922 -456.837288)
		(end 42.378122 -456.507088)
		(width 0.1651)
		(layer "In5.Cu")
		(net "TDR_DIFF_85_IN1_DIP")
	)
	(segment
		(start 21.529802 -458.66558)
		(end 21.529802 -456.837288)
		(width 0.1651)
		(layer "In5.Cu")
		(net "TDR_DIFF_85_IN1_DIP")
	)
	(segment
		(start 56.703722 -456.837288)
		(end 57.033922 -456.507088)
		(width 0.1651)
		(layer "In5.Cu")
		(net "TDR_DIFF_85_IN1_DIP")
	)
	(segment
		(start 63.749682 -456.837288)
		(end 63.749682 -458.66558)
		(width 0.1651)
		(layer "In5.Cu")
		(net "TDR_DIFF_85_IN1_DIP")
	)
	(segment
		(start 28.245562 -456.507088)
		(end 28.575762 -456.837288)
		(width 0.1651)
		(layer "In5.Cu")
		(net "TDR_DIFF_85_IN1_DIP")
	)
	(segment
		(start 65.497202 -456.837288)
		(end 65.827402 -456.507088)
		(width 0.1651)
		(layer "In5.Cu")
		(net "TDR_DIFF_85_IN1_DIP")
	)
	(segment
		(start 65.001902 -459.16088)
		(end 65.497202 -458.66558)
		(width 0.1651)
		(layer "In5.Cu")
		(net "TDR_DIFF_85_IN1_DIP")
	)
	(segment
		(start 26.896822 -459.16088)
		(end 27.392122 -458.66558)
		(width 0.1651)
		(layer "In5.Cu")
		(net "TDR_DIFF_85_IN1_DIP")
	)
	(segment
		(start 78.155292 -457.833984)
		(end 78.320392 -457.999084)
		(width 0.1651)
		(layer "In5.Cu")
		(net "TDR_DIFF_85_IN1_DIP")
	)
	(segment
		(start 52.025042 -458.66558)
		(end 52.520342 -459.16088)
		(width 0.1651)
		(layer "In5.Cu")
		(net "TDR_DIFF_85_IN1_DIP")
	)
	(segment
		(start 45.309282 -456.507088)
		(end 45.832522 -456.507088)
		(width 0.1651)
		(layer "In5.Cu")
		(net "TDR_DIFF_85_IN1_DIP")
	)
	(segment
		(start 44.483782 -459.16088)
		(end 44.979082 -458.66558)
		(width 0.1651)
		(layer "In5.Cu")
		(net "TDR_DIFF_85_IN1_DIP")
	)
	(segment
		(start 51.171602 -456.507088)
		(end 51.694842 -456.507088)
		(width 0.1651)
		(layer "In5.Cu")
		(net "TDR_DIFF_85_IN1_DIP")
	)
	(segment
		(start 21.034502 -459.16088)
		(end 21.529802 -458.66558)
		(width 0.1651)
		(layer "In5.Cu")
		(net "TDR_DIFF_85_IN1_DIP")
	)
	(segment
		(start 70.864222 -459.16088)
		(end 71.359522 -458.66558)
		(width 0.1651)
		(layer "In5.Cu")
		(net "TDR_DIFF_85_IN1_DIP")
	)
	(segment
		(start 21.860002 -456.507088)
		(end 22.383242 -456.507088)
		(width 0.1651)
		(layer "In5.Cu")
		(net "TDR_DIFF_85_IN1_DIP")
	)
	(segment
		(start 39.446962 -456.507088)
		(end 39.970202 -456.507088)
		(width 0.1651)
		(layer "In5.Cu")
		(net "TDR_DIFF_85_IN1_DIP")
	)
	(segment
		(start 34.438082 -458.66558)
		(end 34.933382 -459.16088)
		(width 0.1651)
		(layer "In5.Cu")
		(net "TDR_DIFF_85_IN1_DIP")
	)
	(segment
		(start 34.438082 -456.837288)
		(end 34.438082 -458.66558)
		(width 0.1651)
		(layer "In5.Cu")
		(net "TDR_DIFF_85_IN1_DIP")
	)
	(segment
		(start 19.782282 -456.837288)
		(end 19.782282 -458.66558)
		(width 0.1651)
		(layer "In5.Cu")
		(net "TDR_DIFF_85_IN1_DIP")
	)
	(segment
		(start 27.392122 -458.66558)
		(end 27.392122 -456.837288)
		(width 0.1651)
		(layer "In5.Cu")
		(net "TDR_DIFF_85_IN1_DIP")
	)
	(segment
		(start 72.543162 -456.837288)
		(end 72.543162 -458.66558)
		(width 0.1651)
		(layer "In5.Cu")
		(net "TDR_DIFF_85_IN1_DIP")
	)
	(segment
		(start 58.382662 -459.16088)
		(end 59.139582 -459.16088)
		(width 0.1651)
		(layer "In5.Cu")
		(net "TDR_DIFF_85_IN1_DIP")
	)
	(segment
		(start 28.575762 -456.837288)
		(end 28.575762 -458.66558)
		(width 0.1651)
		(layer "In5.Cu")
		(net "TDR_DIFF_85_IN1_DIP")
	)
	(segment
		(start 22.383242 -456.507088)
		(end 22.713442 -456.837288)
		(width 0.1651)
		(layer "In5.Cu")
		(net "TDR_DIFF_85_IN1_DIP")
	)
	(segment
		(start 54.626002 -456.507088)
		(end 54.956202 -456.837288)
		(width 0.1651)
		(layer "In5.Cu")
		(net "TDR_DIFF_85_IN1_DIP")
	)
	(segment
		(start 14.452092 -457.833984)
		(end 16.520922 -457.833984)
		(width 0.1651)
		(layer "In5.Cu")
		(net "TDR_DIFF_85_IN1_DIP")
	)
	(segment
		(start 30.653482 -456.507088)
		(end 31.176722 -456.507088)
		(width 0.1651)
		(layer "In5.Cu")
		(net "TDR_DIFF_85_IN1_DIP")
	)
	(segment
		(start 47.910242 -458.66558)
		(end 47.910242 -456.837288)
		(width 0.1651)
		(layer "In5.Cu")
		(net "TDR_DIFF_85_IN1_DIP")
	)
	(segment
		(start 22.713442 -456.837288)
		(end 22.713442 -458.66558)
		(width 0.1651)
		(layer "In5.Cu")
		(net "TDR_DIFF_85_IN1_DIP")
	)
	(segment
		(start 39.116762 -458.66558)
		(end 39.116762 -456.837288)
		(width 0.1651)
		(layer "In5.Cu")
		(net "TDR_DIFF_85_IN1_DIP")
	)
	(segment
		(start 54.956202 -456.837288)
		(end 54.956202 -458.66558)
		(width 0.1651)
		(layer "In5.Cu")
		(net "TDR_DIFF_85_IN1_DIP")
	)
	(segment
		(start 35.690302 -459.16088)
		(end 36.185602 -458.66558)
		(width 0.1651)
		(layer "In5.Cu")
		(net "TDR_DIFF_85_IN1_DIP")
	)
	(segment
		(start 69.612002 -458.66558)
		(end 70.107302 -459.16088)
		(width 0.1651)
		(layer "In5.Cu")
		(net "TDR_DIFF_85_IN1_DIP")
	)
	(segment
		(start 19.782282 -458.66558)
		(end 20.277582 -459.16088)
		(width 0.1651)
		(layer "In5.Cu")
		(net "TDR_DIFF_85_IN1_DIP")
	)
	(segment
		(start 62.566042 -458.66558)
		(end 62.566042 -456.837288)
		(width 0.1651)
		(layer "In5.Cu")
		(net "TDR_DIFF_85_IN1_DIP")
	)
	(segment
		(start 52.025042 -456.837288)
		(end 52.025042 -458.66558)
		(width 0.1651)
		(layer "In5.Cu")
		(net "TDR_DIFF_85_IN1_DIP")
	)
	(segment
		(start 46.658022 -459.16088)
		(end 47.414942 -459.16088)
		(width 0.1651)
		(layer "In5.Cu")
		(net "TDR_DIFF_85_IN1_DIP")
	)
	(segment
		(start 22.713442 -458.66558)
		(end 23.208742 -459.16088)
		(width 0.1651)
		(layer "In5.Cu")
		(net "TDR_DIFF_85_IN1_DIP")
	)
	(segment
		(start 67.933062 -459.16088)
		(end 68.428362 -458.66558)
		(width 0.1651)
		(layer "In5.Cu")
		(net "TDR_DIFF_85_IN1_DIP")
	)
	(segment
		(start 67.176142 -459.16088)
		(end 67.933062 -459.16088)
		(width 0.1651)
		(layer "In5.Cu")
		(net "TDR_DIFF_85_IN1_DIP")
	)
	(segment
		(start 24.791162 -456.507088)
		(end 25.314402 -456.507088)
		(width 0.1651)
		(layer "In5.Cu")
		(net "TDR_DIFF_85_IN1_DIP")
	)
	(segment
		(start 74.290682 -458.66558)
		(end 74.290682 -456.837288)
		(width 0.1651)
		(layer "In5.Cu")
		(net "TDR_DIFF_85_IN1_DIP")
	)
	(segment
		(start 25.314402 -456.507088)
		(end 25.644602 -456.837288)
		(width 0.1651)
		(layer "In5.Cu")
		(net "TDR_DIFF_85_IN1_DIP")
	)
	(segment
		(start 71.359522 -458.66558)
		(end 71.359522 -456.837288)
		(width 0.1651)
		(layer "In5.Cu")
		(net "TDR_DIFF_85_IN1_DIP")
	)
	(segment
		(start 72.212962 -456.507088)
		(end 72.543162 -456.837288)
		(width 0.1651)
		(layer "In5.Cu")
		(net "TDR_DIFF_85_IN1_DIP")
	)
	(segment
		(start 38.621462 -459.16088)
		(end 39.116762 -458.66558)
		(width 0.1651)
		(layer "In5.Cu")
		(net "TDR_DIFF_85_IN1_DIP")
	)
	(segment
		(start 36.185602 -458.66558)
		(end 36.185602 -456.837288)
		(width 0.1651)
		(layer "In5.Cu")
		(net "TDR_DIFF_85_IN1_DIP")
	)
	(segment
		(start 16.851122 -458.164184)
		(end 16.851122 -458.66558)
		(width 0.1651)
		(layer "In5.Cu")
		(net "TDR_DIFF_85_IN1_DIP")
	)
	(segment
		(start 57.033922 -456.507088)
		(end 57.557162 -456.507088)
		(width 0.1651)
		(layer "In5.Cu")
		(net "TDR_DIFF_85_IN1_DIP")
	)
	(segment
		(start 73.038462 -459.16088)
		(end 73.795382 -459.16088)
		(width 0.1651)
		(layer "In5.Cu")
		(net "TDR_DIFF_85_IN1_DIP")
	)
	(segment
		(start 31.506922 -456.837288)
		(end 31.506922 -458.66558)
		(width 0.1651)
		(layer "In5.Cu")
		(net "TDR_DIFF_85_IN1_DIP")
	)
	(segment
		(start 50.346102 -459.16088)
		(end 50.841402 -458.66558)
		(width 0.1651)
		(layer "In5.Cu")
		(net "TDR_DIFF_85_IN1_DIP")
	)
	(segment
		(start 75.474322 -456.837288)
		(end 75.474322 -457.338684)
		(width 0.1651)
		(layer "In5.Cu")
		(net "TDR_DIFF_85_IN1_DIP")
	)
	(segment
		(start 66.680842 -456.837288)
		(end 66.680842 -458.66558)
		(width 0.1651)
		(layer "In5.Cu")
		(net "TDR_DIFF_85_IN1_DIP")
	)
	(segment
		(start 69.281802 -456.507088)
		(end 69.612002 -456.837288)
		(width 0.1651)
		(layer "In5.Cu")
		(net "TDR_DIFF_85_IN1_DIP")
	)
	(segment
		(start 33.254442 -456.837288)
		(end 33.584642 -456.507088)
		(width 0.1651)
		(layer "In5.Cu")
		(net "TDR_DIFF_85_IN1_DIP")
	)
	(segment
		(start 61.313822 -459.16088)
		(end 62.070742 -459.16088)
		(width 0.1651)
		(layer "In5.Cu")
		(net "TDR_DIFF_85_IN1_DIP")
	)
	(segment
		(start 44.979082 -456.837288)
		(end 45.309282 -456.507088)
		(width 0.1651)
		(layer "In5.Cu")
		(net "TDR_DIFF_85_IN1_DIP")
	)
	(segment
		(start 57.557162 -456.507088)
		(end 57.887362 -456.837288)
		(width 0.1651)
		(layer "In5.Cu")
		(net "TDR_DIFF_85_IN1_DIP")
	)
	(segment
		(start 30.323282 -458.66558)
		(end 30.323282 -456.837288)
		(width 0.1651)
		(layer "In5.Cu")
		(net "TDR_DIFF_85_IN1_DIP")
	)
	(segment
		(start 43.726862 -459.16088)
		(end 44.483782 -459.16088)
		(width 0.1651)
		(layer "In5.Cu")
		(net "TDR_DIFF_85_IN1_DIP")
	)
	(segment
		(start 36.185602 -456.837288)
		(end 36.515802 -456.507088)
		(width 0.1651)
		(layer "In5.Cu")
		(net "TDR_DIFF_85_IN1_DIP")
	)
	(segment
		(start 69.612002 -456.837288)
		(end 69.612002 -458.66558)
		(width 0.1651)
		(layer "In5.Cu")
		(net "TDR_DIFF_85_IN1_DIP")
	)
	(segment
		(start 46.162722 -456.837288)
		(end 46.162722 -458.66558)
		(width 0.1651)
		(layer "In5.Cu")
		(net "TDR_DIFF_85_IN1_DIP")
	)
	(segment
		(start 59.634882 -456.837288)
		(end 59.965082 -456.507088)
		(width 0.1651)
		(layer "In5.Cu")
		(net "TDR_DIFF_85_IN1_DIP")
	)
	(segment
		(start 78.320392 -457.999084)
		(end 78.320392 -458.963014)
		(width 0.1651)
		(layer "In5.Cu")
		(net "TDR_DIFF_85_IN1_DIP")
	)
	(segment
		(start 51.694842 -456.507088)
		(end 52.025042 -456.837288)
		(width 0.1651)
		(layer "In5.Cu")
		(net "TDR_DIFF_85_IN1_DIP")
	)
	(segment
		(start 13.324586 -304.79492)
		(end 12.959842 -305.159664)
		(width 0.254)
		(layer "F.Cu")
		(net "P1V25_PEX0_CS")
	)
	(segment
		(start 11.62177 -305.481736)
		(end 12.04976 -305.481736)
		(width 0.1778)
		(layer "F.Cu")
		(net "P1V25_PEX0_CS")
	)
	(segment
		(start 12.04976 -305.481736)
		(end 12.826746 -305.159664)
		(width 0.1778)
		(layer "F.Cu")
		(net "P1V25_PEX0_CS")
	)
	(segment
		(start 13.649198 -304.79492)
		(end 13.324586 -304.79492)
		(width 0.254)
		(layer "F.Cu")
		(net "P1V25_PEX0_CS")
	)
	(segment
		(start 12.826746 -305.159664)
		(end 12.959842 -305.159664)
		(width 0.1778)
		(layer "F.Cu")
		(net "P1V25_PEX0_CS")
	)
	(via
		(at 12.959842 -305.159664)
		(size 0.508)
		(drill 0.254)
		(layers "F.Cu" "B.Cu")
		(net "P1V25_PEX0_CS")
	)
	(via
		(at 8.034274 -304.457354)
		(size 0.508)
		(drill 0.254)
		(layers "F.Cu" "B.Cu")
		(net "P1V25_PEX0_VCC")
	)
	(segment
		(start 14.978888 -305.419506)
		(end 14.978888 -307.573426)
		(width 0.508)
		(layer "B.Cu")
		(net "P1V25_PEX0_VCC")
	)
	(segment
		(start 15.267178 -307.861716)
		(end 16.251174 -307.861716)
		(width 0.508)
		(layer "B.Cu")
		(net "P1V25_PEX0_VCC")
	)
	(segment
		(start 8.034274 -304.457354)
		(end 8.589264 -303.902364)
		(width 0.508)
		(layer "B.Cu")
		(net "P1V25_PEX0_VCC")
	)
	(segment
		(start 8.589264 -303.902364)
		(end 13.461746 -303.902364)
		(width 0.508)
		(layer "B.Cu")
		(net "P1V25_PEX0_VCC")
	)
	(segment
		(start 14.978888 -307.573426)
		(end 15.267178 -307.861716)
		(width 0.508)
		(layer "B.Cu")
		(net "P1V25_PEX0_VCC")
	)
	(segment
		(start 13.461746 -303.902364)
		(end 14.978888 -305.419506)
		(width 0.508)
		(layer "B.Cu")
		(net "P1V25_PEX0_VCC")
	)
	(segment
		(start 15.29334 -305.408584)
		(end 15.193518 -305.508406)
		(width 0.254)
		(layer "F.Cu")
		(net "SH_P1V25_PEX0_FB_N")
	)
	(segment
		(start 12.595606 -306.681886)
		(end 12.76985 -306.681886)
		(width 0.254)
		(layer "F.Cu")
		(net "SH_P1V25_PEX0_FB_N")
	)
	(segment
		(start 14.618462 -306.27574)
		(end 14.52626 -306.367942)
		(width 0.254)
		(layer "F.Cu")
		(net "SH_P1V25_PEX0_FB_N")
	)
	(segment
		(start 12.76985 -306.681886)
		(end 13.150088 -306.524406)
		(width 0.254)
		(layer "F.Cu")
		(net "SH_P1V25_PEX0_FB_N")
	)
	(segment
		(start 15.193518 -305.508406)
		(end 15.146528 -305.621944)
		(width 0.254)
		(layer "F.Cu")
		(net "SH_P1V25_PEX0_FB_N")
	)
	(segment
		(start 15.146528 -305.621944)
		(end 15.146528 -305.810666)
		(width 0.254)
		(layer "F.Cu")
		(net "SH_P1V25_PEX0_FB_N")
	)
	(segment
		(start 16.32585 -305.54676)
		(end 16.5989 -305.27371)
		(width 0.254)
		(layer "F.Cu")
		(net "SH_P1V25_PEX0_FB_N")
	)
	(segment
		(start 14.017752 -306.115466)
		(end 13.608812 -306.524406)
		(width 0.254)
		(layer "F.Cu")
		(net "SH_P1V25_PEX0_FB_N")
	)
	(segment
		(start 15.59052 -305.408584)
		(end 15.29334 -305.408584)
		(width 0.254)
		(layer "F.Cu")
		(net "SH_P1V25_PEX0_FB_N")
	)
	(segment
		(start 16.041624 -305.54676)
		(end 16.32585 -305.54676)
		(width 0.254)
		(layer "F.Cu")
		(net "SH_P1V25_PEX0_FB_N")
	)
	(segment
		(start 13.608812 -306.524406)
		(end 13.476224 -306.524406)
		(width 0.254)
		(layer "F.Cu")
		(net "SH_P1V25_PEX0_FB_N")
	)
	(segment
		(start 16.5989 -305.27371)
		(end 16.606266 -305.19751)
		(width 0.254)
		(layer "F.Cu")
		(net "SH_P1V25_PEX0_FB_N")
	)
	(segment
		(start 15.59052 -305.408584)
		(end 15.903448 -305.408584)
		(width 0.254)
		(layer "F.Cu")
		(net "SH_P1V25_PEX0_FB_N")
	)
	(segment
		(start 14.681454 -306.27574)
		(end 14.618462 -306.27574)
		(width 0.254)
		(layer "F.Cu")
		(net "SH_P1V25_PEX0_FB_N")
	)
	(segment
		(start 15.903448 -305.408584)
		(end 16.041624 -305.54676)
		(width 0.254)
		(layer "F.Cu")
		(net "SH_P1V25_PEX0_FB_N")
	)
	(segment
		(start 15.146528 -305.810666)
		(end 14.681454 -306.27574)
		(width 0.254)
		(layer "F.Cu")
		(net "SH_P1V25_PEX0_FB_N")
	)
	(segment
		(start 14.270228 -306.367942)
		(end 14.017752 -306.115466)
		(width 0.254)
		(layer "F.Cu")
		(net "SH_P1V25_PEX0_FB_N")
	)
	(segment
		(start 11.62177 -306.681886)
		(end 12.595606 -306.681886)
		(width 0.1778)
		(layer "F.Cu")
		(net "SH_P1V25_PEX0_FB_N")
	)
	(segment
		(start 13.150088 -306.524406)
		(end 13.476224 -306.524406)
		(width 0.254)
		(layer "F.Cu")
		(net "SH_P1V25_PEX0_FB_N")
	)
	(segment
		(start 14.52626 -306.367942)
		(end 14.270228 -306.367942)
		(width 0.254)
		(layer "F.Cu")
		(net "SH_P1V25_PEX0_FB_N")
	)
	(via
		(at 14.017752 -306.115466)
		(size 0.508)
		(drill 0.254)
		(layers "F.Cu" "B.Cu")
		(net "SH_P1V25_PEX0_FB_N")
	)
	(segment
		(start 71.598282 -438.699148)
		(end 72.355202 -438.699148)
		(width 0.1651)
		(layer "In13.Cu")
		(net "TDR_DIFF_85_IN5_DIN")
	)
	(segment
		(start 43.538902 -441.02274)
		(end 43.869102 -441.35294)
		(width 0.1651)
		(layer "In13.Cu")
		(net "TDR_DIFF_85_IN5_DIN")
	)
	(segment
		(start 75.781662 -439.695844)
		(end 76.111862 -440.026044)
		(width 0.1651)
		(layer "In13.Cu")
		(net "TDR_DIFF_85_IN5_DIN")
	)
	(segment
		(start 65.735962 -438.699148)
		(end 66.492882 -438.699148)
		(width 0.1651)
		(layer "In13.Cu")
		(net "TDR_DIFF_85_IN5_DIN")
	)
	(segment
		(start 64.057022 -439.194448)
		(end 64.057022 -441.02274)
		(width 0.1651)
		(layer "In13.Cu")
		(net "TDR_DIFF_85_IN5_DIN")
	)
	(segment
		(start 47.653702 -439.194448)
		(end 48.149002 -438.699148)
		(width 0.1651)
		(layer "In13.Cu")
		(net "TDR_DIFF_85_IN5_DIN")
	)
	(segment
		(start 38.860222 -441.02274)
		(end 38.860222 -439.194448)
		(width 0.1651)
		(layer "In13.Cu")
		(net "TDR_DIFF_85_IN5_DIN")
	)
	(segment
		(start 44.722542 -441.02274)
		(end 44.722542 -439.194448)
		(width 0.1651)
		(layer "In13.Cu")
		(net "TDR_DIFF_85_IN5_DIN")
	)
	(segment
		(start 26.282142 -441.35294)
		(end 26.805382 -441.35294)
		(width 0.1651)
		(layer "In13.Cu")
		(net "TDR_DIFF_85_IN5_DIN")
	)
	(segment
		(start 69.919342 -441.02274)
		(end 70.249542 -441.35294)
		(width 0.1651)
		(layer "In13.Cu")
		(net "TDR_DIFF_85_IN5_DIN")
	)
	(segment
		(start 74.034142 -441.02274)
		(end 74.034142 -439.194448)
		(width 0.1651)
		(layer "In13.Cu")
		(net "TDR_DIFF_85_IN5_DIN")
	)
	(segment
		(start 71.102982 -441.02274)
		(end 71.102982 -439.194448)
		(width 0.1651)
		(layer "In13.Cu")
		(net "TDR_DIFF_85_IN5_DIN")
	)
	(segment
		(start 59.378342 -439.194448)
		(end 59.873642 -438.699148)
		(width 0.1651)
		(layer "In13.Cu")
		(net "TDR_DIFF_85_IN5_DIN")
	)
	(segment
		(start 36.424362 -438.699148)
		(end 37.181282 -438.699148)
		(width 0.1651)
		(layer "In13.Cu")
		(net "TDR_DIFF_85_IN5_DIN")
	)
	(segment
		(start 38.530022 -441.35294)
		(end 38.860222 -441.02274)
		(width 0.1651)
		(layer "In13.Cu")
		(net "TDR_DIFF_85_IN5_DIN")
	)
	(segment
		(start 72.850502 -441.02274)
		(end 73.180702 -441.35294)
		(width 0.1651)
		(layer "In13.Cu")
		(net "TDR_DIFF_85_IN5_DIN")
	)
	(segment
		(start 69.919342 -439.194448)
		(end 69.919342 -441.02274)
		(width 0.1651)
		(layer "In13.Cu")
		(net "TDR_DIFF_85_IN5_DIN")
	)
	(segment
		(start 76.111862 -440.026044)
		(end 78.180692 -440.026044)
		(width 0.1651)
		(layer "In13.Cu")
		(net "TDR_DIFF_85_IN5_DIN")
	)
	(segment
		(start 73.703942 -441.35294)
		(end 74.034142 -441.02274)
		(width 0.1651)
		(layer "In13.Cu")
		(net "TDR_DIFF_85_IN5_DIN")
	)
	(segment
		(start 39.355522 -438.699148)
		(end 40.112442 -438.699148)
		(width 0.1651)
		(layer "In13.Cu")
		(net "TDR_DIFF_85_IN5_DIN")
	)
	(segment
		(start 67.318382 -441.35294)
		(end 67.841622 -441.35294)
		(width 0.1651)
		(layer "In13.Cu")
		(net "TDR_DIFF_85_IN5_DIN")
	)
	(segment
		(start 37.676582 -439.194448)
		(end 37.676582 -441.02274)
		(width 0.1651)
		(layer "In13.Cu")
		(net "TDR_DIFF_85_IN5_DIN")
	)
	(segment
		(start 60.630562 -438.699148)
		(end 61.125862 -439.194448)
		(width 0.1651)
		(layer "In13.Cu")
		(net "TDR_DIFF_85_IN5_DIN")
	)
	(segment
		(start 34.745422 -439.194448)
		(end 34.745422 -441.02274)
		(width 0.1651)
		(layer "In13.Cu")
		(net "TDR_DIFF_85_IN5_DIN")
	)
	(segment
		(start 43.043602 -438.699148)
		(end 43.538902 -439.194448)
		(width 0.1651)
		(layer "In13.Cu")
		(net "TDR_DIFF_85_IN5_DIN")
	)
	(segment
		(start 35.598862 -441.35294)
		(end 35.929062 -441.02274)
		(width 0.1651)
		(layer "In13.Cu")
		(net "TDR_DIFF_85_IN5_DIN")
	)
	(segment
		(start 35.929062 -439.194448)
		(end 36.424362 -438.699148)
		(width 0.1651)
		(layer "In13.Cu")
		(net "TDR_DIFF_85_IN5_DIN")
	)
	(segment
		(start 21.273262 -439.194448)
		(end 21.768562 -438.699148)
		(width 0.1651)
		(layer "In13.Cu")
		(net "TDR_DIFF_85_IN5_DIN")
	)
	(segment
		(start 28.883102 -441.02274)
		(end 29.213302 -441.35294)
		(width 0.1651)
		(layer "In13.Cu")
		(net "TDR_DIFF_85_IN5_DIN")
	)
	(segment
		(start 14.477492 -440.026044)
		(end 16.663162 -440.026044)
		(width 0.1651)
		(layer "In13.Cu")
		(net "TDR_DIFF_85_IN5_DIN")
	)
	(segment
		(start 46.800262 -441.35294)
		(end 47.323502 -441.35294)
		(width 0.1651)
		(layer "In13.Cu")
		(net "TDR_DIFF_85_IN5_DIN")
	)
	(segment
		(start 27.135582 -441.02274)
		(end 27.135582 -439.194448)
		(width 0.1651)
		(layer "In13.Cu")
		(net "TDR_DIFF_85_IN5_DIN")
	)
	(segment
		(start 66.492882 -438.699148)
		(end 66.988182 -439.194448)
		(width 0.1651)
		(layer "In13.Cu")
		(net "TDR_DIFF_85_IN5_DIN")
	)
	(segment
		(start 55.593742 -441.35294)
		(end 56.116982 -441.35294)
		(width 0.1651)
		(layer "In13.Cu")
		(net "TDR_DIFF_85_IN5_DIN")
	)
	(segment
		(start 20.089622 -441.02274)
		(end 20.419822 -441.35294)
		(width 0.1651)
		(layer "In13.Cu")
		(net "TDR_DIFF_85_IN5_DIN")
	)
	(segment
		(start 54.768242 -438.699148)
		(end 55.263542 -439.194448)
		(width 0.1651)
		(layer "In13.Cu")
		(net "TDR_DIFF_85_IN5_DIN")
	)
	(segment
		(start 64.057022 -441.02274)
		(end 64.387222 -441.35294)
		(width 0.1651)
		(layer "In13.Cu")
		(net "TDR_DIFF_85_IN5_DIN")
	)
	(segment
		(start 20.419822 -441.35294)
		(end 20.943062 -441.35294)
		(width 0.1651)
		(layer "In13.Cu")
		(net "TDR_DIFF_85_IN5_DIN")
	)
	(segment
		(start 46.470062 -441.02274)
		(end 46.800262 -441.35294)
		(width 0.1651)
		(layer "In13.Cu")
		(net "TDR_DIFF_85_IN5_DIN")
	)
	(segment
		(start 14.312392 -439.860944)
		(end 14.477492 -440.026044)
		(width 0.1651)
		(layer "In13.Cu")
		(net "TDR_DIFF_85_IN5_DIN")
	)
	(segment
		(start 75.286362 -438.699148)
		(end 75.781662 -439.194448)
		(width 0.1651)
		(layer "In13.Cu")
		(net "TDR_DIFF_85_IN5_DIN")
	)
	(segment
		(start 75.781662 -439.194448)
		(end 75.781662 -439.695844)
		(width 0.1651)
		(layer "In13.Cu")
		(net "TDR_DIFF_85_IN5_DIN")
	)
	(segment
		(start 38.006782 -441.35294)
		(end 38.530022 -441.35294)
		(width 0.1651)
		(layer "In13.Cu")
		(net "TDR_DIFF_85_IN5_DIN")
	)
	(segment
		(start 61.125862 -441.02274)
		(end 61.456062 -441.35294)
		(width 0.1651)
		(layer "In13.Cu")
		(net "TDR_DIFF_85_IN5_DIN")
	)
	(segment
		(start 18.011902 -441.35294)
		(end 18.342102 -441.02274)
		(width 0.1651)
		(layer "In13.Cu")
		(net "TDR_DIFF_85_IN5_DIN")
	)
	(segment
		(start 41.461182 -441.35294)
		(end 41.791382 -441.02274)
		(width 0.1651)
		(layer "In13.Cu")
		(net "TDR_DIFF_85_IN5_DIN")
	)
	(segment
		(start 45.217842 -438.699148)
		(end 45.974762 -438.699148)
		(width 0.1651)
		(layer "In13.Cu")
		(net "TDR_DIFF_85_IN5_DIN")
	)
	(segment
		(start 68.171822 -439.194448)
		(end 68.667122 -438.699148)
		(width 0.1651)
		(layer "In13.Cu")
		(net "TDR_DIFF_85_IN5_DIN")
	)
	(segment
		(start 51.080162 -438.699148)
		(end 51.837082 -438.699148)
		(width 0.1651)
		(layer "In13.Cu")
		(net "TDR_DIFF_85_IN5_DIN")
	)
	(segment
		(start 61.456062 -441.35294)
		(end 61.979302 -441.35294)
		(width 0.1651)
		(layer "In13.Cu")
		(net "TDR_DIFF_85_IN5_DIN")
	)
	(segment
		(start 30.562042 -438.699148)
		(end 31.318962 -438.699148)
		(width 0.1651)
		(layer "In13.Cu")
		(net "TDR_DIFF_85_IN5_DIN")
	)
	(segment
		(start 57.699402 -438.699148)
		(end 58.194702 -439.194448)
		(width 0.1651)
		(layer "In13.Cu")
		(net "TDR_DIFF_85_IN5_DIN")
	)
	(segment
		(start 49.731422 -441.35294)
		(end 50.254662 -441.35294)
		(width 0.1651)
		(layer "In13.Cu")
		(net "TDR_DIFF_85_IN5_DIN")
	)
	(segment
		(start 32.144462 -441.35294)
		(end 32.667702 -441.35294)
		(width 0.1651)
		(layer "In13.Cu")
		(net "TDR_DIFF_85_IN5_DIN")
	)
	(segment
		(start 40.607742 -439.194448)
		(end 40.607742 -441.02274)
		(width 0.1651)
		(layer "In13.Cu")
		(net "TDR_DIFF_85_IN5_DIN")
	)
	(segment
		(start 23.020782 -439.194448)
		(end 23.020782 -441.02274)
		(width 0.1651)
		(layer "In13.Cu")
		(net "TDR_DIFF_85_IN5_DIN")
	)
	(segment
		(start 52.332382 -439.194448)
		(end 52.332382 -441.02274)
		(width 0.1651)
		(layer "In13.Cu")
		(net "TDR_DIFF_85_IN5_DIN")
	)
	(segment
		(start 35.075622 -441.35294)
		(end 35.598862 -441.35294)
		(width 0.1651)
		(layer "In13.Cu")
		(net "TDR_DIFF_85_IN5_DIN")
	)
	(segment
		(start 70.249542 -441.35294)
		(end 70.772782 -441.35294)
		(width 0.1651)
		(layer "In13.Cu")
		(net "TDR_DIFF_85_IN5_DIN")
	)
	(segment
		(start 59.378342 -441.02274)
		(end 59.378342 -439.194448)
		(width 0.1651)
		(layer "In13.Cu")
		(net "TDR_DIFF_85_IN5_DIN")
	)
	(segment
		(start 65.240662 -441.02274)
		(end 65.240662 -439.194448)
		(width 0.1651)
		(layer "In13.Cu")
		(net "TDR_DIFF_85_IN5_DIN")
	)
	(segment
		(start 59.873642 -438.699148)
		(end 60.630562 -438.699148)
		(width 0.1651)
		(layer "In13.Cu")
		(net "TDR_DIFF_85_IN5_DIN")
	)
	(segment
		(start 27.630882 -438.699148)
		(end 28.387802 -438.699148)
		(width 0.1651)
		(layer "In13.Cu")
		(net "TDR_DIFF_85_IN5_DIN")
	)
	(segment
		(start 51.837082 -438.699148)
		(end 52.332382 -439.194448)
		(width 0.1651)
		(layer "In13.Cu")
		(net "TDR_DIFF_85_IN5_DIN")
	)
	(segment
		(start 49.401222 -439.194448)
		(end 49.401222 -441.02274)
		(width 0.1651)
		(layer "In13.Cu")
		(net "TDR_DIFF_85_IN5_DIN")
	)
	(segment
		(start 53.516022 -439.194448)
		(end 54.011322 -438.699148)
		(width 0.1651)
		(layer "In13.Cu")
		(net "TDR_DIFF_85_IN5_DIN")
	)
	(segment
		(start 20.089622 -439.194448)
		(end 20.089622 -441.02274)
		(width 0.1651)
		(layer "In13.Cu")
		(net "TDR_DIFF_85_IN5_DIN")
	)
	(segment
		(start 68.171822 -441.02274)
		(end 68.171822 -439.194448)
		(width 0.1651)
		(layer "In13.Cu")
		(net "TDR_DIFF_85_IN5_DIN")
	)
	(segment
		(start 55.263542 -441.02274)
		(end 55.593742 -441.35294)
		(width 0.1651)
		(layer "In13.Cu")
		(net "TDR_DIFF_85_IN5_DIN")
	)
	(segment
		(start 26.805382 -441.35294)
		(end 27.135582 -441.02274)
		(width 0.1651)
		(layer "In13.Cu")
		(net "TDR_DIFF_85_IN5_DIN")
	)
	(segment
		(start 20.943062 -441.35294)
		(end 21.273262 -441.02274)
		(width 0.1651)
		(layer "In13.Cu")
		(net "TDR_DIFF_85_IN5_DIN")
	)
	(segment
		(start 41.791382 -439.194448)
		(end 42.286682 -438.699148)
		(width 0.1651)
		(layer "In13.Cu")
		(net "TDR_DIFF_85_IN5_DIN")
	)
	(segment
		(start 32.997902 -441.02274)
		(end 32.997902 -439.194448)
		(width 0.1651)
		(layer "In13.Cu")
		(net "TDR_DIFF_85_IN5_DIN")
	)
	(segment
		(start 49.401222 -441.02274)
		(end 49.731422 -441.35294)
		(width 0.1651)
		(layer "In13.Cu")
		(net "TDR_DIFF_85_IN5_DIN")
	)
	(segment
		(start 72.355202 -438.699148)
		(end 72.850502 -439.194448)
		(width 0.1651)
		(layer "In13.Cu")
		(net "TDR_DIFF_85_IN5_DIN")
	)
	(segment
		(start 41.791382 -441.02274)
		(end 41.791382 -439.194448)
		(width 0.1651)
		(layer "In13.Cu")
		(net "TDR_DIFF_85_IN5_DIN")
	)
	(segment
		(start 66.988182 -439.194448)
		(end 66.988182 -441.02274)
		(width 0.1651)
		(layer "In13.Cu")
		(net "TDR_DIFF_85_IN5_DIN")
	)
	(segment
		(start 56.447182 -441.02274)
		(end 56.447182 -439.194448)
		(width 0.1651)
		(layer "In13.Cu")
		(net "TDR_DIFF_85_IN5_DIN")
	)
	(segment
		(start 18.342102 -441.02274)
		(end 18.342102 -439.194448)
		(width 0.1651)
		(layer "In13.Cu")
		(net "TDR_DIFF_85_IN5_DIN")
	)
	(segment
		(start 73.180702 -441.35294)
		(end 73.703942 -441.35294)
		(width 0.1651)
		(layer "In13.Cu")
		(net "TDR_DIFF_85_IN5_DIN")
	)
	(segment
		(start 30.066742 -441.02274)
		(end 30.066742 -439.194448)
		(width 0.1651)
		(layer "In13.Cu")
		(net "TDR_DIFF_85_IN5_DIN")
	)
	(segment
		(start 29.213302 -441.35294)
		(end 29.736542 -441.35294)
		(width 0.1651)
		(layer "In13.Cu")
		(net "TDR_DIFF_85_IN5_DIN")
	)
	(segment
		(start 45.974762 -438.699148)
		(end 46.470062 -439.194448)
		(width 0.1651)
		(layer "In13.Cu")
		(net "TDR_DIFF_85_IN5_DIN")
	)
	(segment
		(start 59.048142 -441.35294)
		(end 59.378342 -441.02274)
		(width 0.1651)
		(layer "In13.Cu")
		(net "TDR_DIFF_85_IN5_DIN")
	)
	(segment
		(start 46.470062 -439.194448)
		(end 46.470062 -441.02274)
		(width 0.1651)
		(layer "In13.Cu")
		(net "TDR_DIFF_85_IN5_DIN")
	)
	(segment
		(start 62.309502 -441.02274)
		(end 62.309502 -439.194448)
		(width 0.1651)
		(layer "In13.Cu")
		(net "TDR_DIFF_85_IN5_DIN")
	)
	(segment
		(start 33.493202 -438.699148)
		(end 34.250122 -438.699148)
		(width 0.1651)
		(layer "In13.Cu")
		(net "TDR_DIFF_85_IN5_DIN")
	)
	(segment
		(start 68.667122 -438.699148)
		(end 69.424042 -438.699148)
		(width 0.1651)
		(layer "In13.Cu")
		(net "TDR_DIFF_85_IN5_DIN")
	)
	(segment
		(start 58.194702 -439.194448)
		(end 58.194702 -441.02274)
		(width 0.1651)
		(layer "In13.Cu")
		(net "TDR_DIFF_85_IN5_DIN")
	)
	(segment
		(start 21.273262 -441.02274)
		(end 21.273262 -439.194448)
		(width 0.1651)
		(layer "In13.Cu")
		(net "TDR_DIFF_85_IN5_DIN")
	)
	(segment
		(start 35.929062 -441.02274)
		(end 35.929062 -439.194448)
		(width 0.1651)
		(layer "In13.Cu")
		(net "TDR_DIFF_85_IN5_DIN")
	)
	(segment
		(start 71.102982 -439.194448)
		(end 71.598282 -438.699148)
		(width 0.1651)
		(layer "In13.Cu")
		(net "TDR_DIFF_85_IN5_DIN")
	)
	(segment
		(start 18.342102 -439.194448)
		(end 18.837402 -438.699148)
		(width 0.1651)
		(layer "In13.Cu")
		(net "TDR_DIFF_85_IN5_DIN")
	)
	(segment
		(start 25.456642 -438.699148)
		(end 25.951942 -439.194448)
		(width 0.1651)
		(layer "In13.Cu")
		(net "TDR_DIFF_85_IN5_DIN")
	)
	(segment
		(start 74.529442 -438.699148)
		(end 75.286362 -438.699148)
		(width 0.1651)
		(layer "In13.Cu")
		(net "TDR_DIFF_85_IN5_DIN")
	)
	(segment
		(start 47.323502 -441.35294)
		(end 47.653702 -441.02274)
		(width 0.1651)
		(layer "In13.Cu")
		(net "TDR_DIFF_85_IN5_DIN")
	)
	(segment
		(start 52.662582 -441.35294)
		(end 53.185822 -441.35294)
		(width 0.1651)
		(layer "In13.Cu")
		(net "TDR_DIFF_85_IN5_DIN")
	)
	(segment
		(start 25.951942 -441.02274)
		(end 26.282142 -441.35294)
		(width 0.1651)
		(layer "In13.Cu")
		(net "TDR_DIFF_85_IN5_DIN")
	)
	(segment
		(start 37.181282 -438.699148)
		(end 37.676582 -439.194448)
		(width 0.1651)
		(layer "In13.Cu")
		(net "TDR_DIFF_85_IN5_DIN")
	)
	(segment
		(start 53.516022 -441.02274)
		(end 53.516022 -439.194448)
		(width 0.1651)
		(layer "In13.Cu")
		(net "TDR_DIFF_85_IN5_DIN")
	)
	(segment
		(start 22.525482 -438.699148)
		(end 23.020782 -439.194448)
		(width 0.1651)
		(layer "In13.Cu")
		(net "TDR_DIFF_85_IN5_DIN")
	)
	(segment
		(start 17.158462 -441.02274)
		(end 17.488662 -441.35294)
		(width 0.1651)
		(layer "In13.Cu")
		(net "TDR_DIFF_85_IN5_DIN")
	)
	(segment
		(start 54.011322 -438.699148)
		(end 54.768242 -438.699148)
		(width 0.1651)
		(layer "In13.Cu")
		(net "TDR_DIFF_85_IN5_DIN")
	)
	(segment
		(start 69.424042 -438.699148)
		(end 69.919342 -439.194448)
		(width 0.1651)
		(layer "In13.Cu")
		(net "TDR_DIFF_85_IN5_DIN")
	)
	(segment
		(start 44.392342 -441.35294)
		(end 44.722542 -441.02274)
		(width 0.1651)
		(layer "In13.Cu")
		(net "TDR_DIFF_85_IN5_DIN")
	)
	(segment
		(start 31.814262 -441.02274)
		(end 32.144462 -441.35294)
		(width 0.1651)
		(layer "In13.Cu")
		(net "TDR_DIFF_85_IN5_DIN")
	)
	(segment
		(start 29.736542 -441.35294)
		(end 30.066742 -441.02274)
		(width 0.1651)
		(layer "In13.Cu")
		(net "TDR_DIFF_85_IN5_DIN")
	)
	(segment
		(start 58.524902 -441.35294)
		(end 59.048142 -441.35294)
		(width 0.1651)
		(layer "In13.Cu")
		(net "TDR_DIFF_85_IN5_DIN")
	)
	(segment
		(start 53.185822 -441.35294)
		(end 53.516022 -441.02274)
		(width 0.1651)
		(layer "In13.Cu")
		(net "TDR_DIFF_85_IN5_DIN")
	)
	(segment
		(start 55.263542 -439.194448)
		(end 55.263542 -441.02274)
		(width 0.1651)
		(layer "In13.Cu")
		(net "TDR_DIFF_85_IN5_DIN")
	)
	(segment
		(start 56.447182 -439.194448)
		(end 56.942482 -438.699148)
		(width 0.1651)
		(layer "In13.Cu")
		(net "TDR_DIFF_85_IN5_DIN")
	)
	(segment
		(start 56.942482 -438.699148)
		(end 57.699402 -438.699148)
		(width 0.1651)
		(layer "In13.Cu")
		(net "TDR_DIFF_85_IN5_DIN")
	)
	(segment
		(start 28.883102 -439.194448)
		(end 28.883102 -441.02274)
		(width 0.1651)
		(layer "In13.Cu")
		(net "TDR_DIFF_85_IN5_DIN")
	)
	(segment
		(start 48.149002 -438.699148)
		(end 48.905922 -438.699148)
		(width 0.1651)
		(layer "In13.Cu")
		(net "TDR_DIFF_85_IN5_DIN")
	)
	(segment
		(start 18.837402 -438.699148)
		(end 19.594322 -438.699148)
		(width 0.1651)
		(layer "In13.Cu")
		(net "TDR_DIFF_85_IN5_DIN")
	)
	(segment
		(start 43.538902 -439.194448)
		(end 43.538902 -441.02274)
		(width 0.1651)
		(layer "In13.Cu")
		(net "TDR_DIFF_85_IN5_DIN")
	)
	(segment
		(start 40.112442 -438.699148)
		(end 40.607742 -439.194448)
		(width 0.1651)
		(layer "In13.Cu")
		(net "TDR_DIFF_85_IN5_DIN")
	)
	(segment
		(start 58.194702 -441.02274)
		(end 58.524902 -441.35294)
		(width 0.1651)
		(layer "In13.Cu")
		(net "TDR_DIFF_85_IN5_DIN")
	)
	(segment
		(start 50.584862 -439.194448)
		(end 51.080162 -438.699148)
		(width 0.1651)
		(layer "In13.Cu")
		(net "TDR_DIFF_85_IN5_DIN")
	)
	(segment
		(start 40.937942 -441.35294)
		(end 41.461182 -441.35294)
		(width 0.1651)
		(layer "In13.Cu")
		(net "TDR_DIFF_85_IN5_DIN")
	)
	(segment
		(start 42.286682 -438.699148)
		(end 43.043602 -438.699148)
		(width 0.1651)
		(layer "In13.Cu")
		(net "TDR_DIFF_85_IN5_DIN")
	)
	(segment
		(start 32.997902 -439.194448)
		(end 33.493202 -438.699148)
		(width 0.1651)
		(layer "In13.Cu")
		(net "TDR_DIFF_85_IN5_DIN")
	)
	(segment
		(start 14.312392 -438.897014)
		(end 14.312392 -439.860944)
		(width 0.1651)
		(layer "In13.Cu")
		(net "TDR_DIFF_85_IN5_DIN")
	)
	(segment
		(start 62.309502 -439.194448)
		(end 62.804802 -438.699148)
		(width 0.1651)
		(layer "In13.Cu")
		(net "TDR_DIFF_85_IN5_DIN")
	)
	(segment
		(start 74.034142 -439.194448)
		(end 74.529442 -438.699148)
		(width 0.1651)
		(layer "In13.Cu")
		(net "TDR_DIFF_85_IN5_DIN")
	)
	(segment
		(start 66.988182 -441.02274)
		(end 67.318382 -441.35294)
		(width 0.1651)
		(layer "In13.Cu")
		(net "TDR_DIFF_85_IN5_DIN")
	)
	(segment
		(start 72.850502 -439.194448)
		(end 72.850502 -441.02274)
		(width 0.1651)
		(layer "In13.Cu")
		(net "TDR_DIFF_85_IN5_DIN")
	)
	(segment
		(start 64.387222 -441.35294)
		(end 64.910462 -441.35294)
		(width 0.1651)
		(layer "In13.Cu")
		(net "TDR_DIFF_85_IN5_DIN")
	)
	(segment
		(start 43.869102 -441.35294)
		(end 44.392342 -441.35294)
		(width 0.1651)
		(layer "In13.Cu")
		(net "TDR_DIFF_85_IN5_DIN")
	)
	(segment
		(start 19.594322 -438.699148)
		(end 20.089622 -439.194448)
		(width 0.1651)
		(layer "In13.Cu")
		(net "TDR_DIFF_85_IN5_DIN")
	)
	(segment
		(start 30.066742 -439.194448)
		(end 30.562042 -438.699148)
		(width 0.1651)
		(layer "In13.Cu")
		(net "TDR_DIFF_85_IN5_DIN")
	)
	(segment
		(start 32.667702 -441.35294)
		(end 32.997902 -441.02274)
		(width 0.1651)
		(layer "In13.Cu")
		(net "TDR_DIFF_85_IN5_DIN")
	)
	(segment
		(start 50.254662 -441.35294)
		(end 50.584862 -441.02274)
		(width 0.1651)
		(layer "In13.Cu")
		(net "TDR_DIFF_85_IN5_DIN")
	)
	(segment
		(start 61.979302 -441.35294)
		(end 62.309502 -441.02274)
		(width 0.1651)
		(layer "In13.Cu")
		(net "TDR_DIFF_85_IN5_DIN")
	)
	(segment
		(start 27.135582 -439.194448)
		(end 27.630882 -438.699148)
		(width 0.1651)
		(layer "In13.Cu")
		(net "TDR_DIFF_85_IN5_DIN")
	)
	(segment
		(start 16.663162 -440.026044)
		(end 17.158462 -440.521344)
		(width 0.1651)
		(layer "In13.Cu")
		(net "TDR_DIFF_85_IN5_DIN")
	)
	(segment
		(start 24.699722 -438.699148)
		(end 25.456642 -438.699148)
		(width 0.1651)
		(layer "In13.Cu")
		(net "TDR_DIFF_85_IN5_DIN")
	)
	(segment
		(start 65.240662 -439.194448)
		(end 65.735962 -438.699148)
		(width 0.1651)
		(layer "In13.Cu")
		(net "TDR_DIFF_85_IN5_DIN")
	)
	(segment
		(start 24.204422 -441.02274)
		(end 24.204422 -439.194448)
		(width 0.1651)
		(layer "In13.Cu")
		(net "TDR_DIFF_85_IN5_DIN")
	)
	(segment
		(start 34.250122 -438.699148)
		(end 34.745422 -439.194448)
		(width 0.1651)
		(layer "In13.Cu")
		(net "TDR_DIFF_85_IN5_DIN")
	)
	(segment
		(start 64.910462 -441.35294)
		(end 65.240662 -441.02274)
		(width 0.1651)
		(layer "In13.Cu")
		(net "TDR_DIFF_85_IN5_DIN")
	)
	(segment
		(start 23.874222 -441.35294)
		(end 24.204422 -441.02274)
		(width 0.1651)
		(layer "In13.Cu")
		(net "TDR_DIFF_85_IN5_DIN")
	)
	(segment
		(start 17.158462 -440.521344)
		(end 17.158462 -441.02274)
		(width 0.1651)
		(layer "In13.Cu")
		(net "TDR_DIFF_85_IN5_DIN")
	)
	(segment
		(start 23.350982 -441.35294)
		(end 23.874222 -441.35294)
		(width 0.1651)
		(layer "In13.Cu")
		(net "TDR_DIFF_85_IN5_DIN")
	)
	(segment
		(start 67.841622 -441.35294)
		(end 68.171822 -441.02274)
		(width 0.1651)
		(layer "In13.Cu")
		(net "TDR_DIFF_85_IN5_DIN")
	)
	(segment
		(start 62.804802 -438.699148)
		(end 63.561722 -438.699148)
		(width 0.1651)
		(layer "In13.Cu")
		(net "TDR_DIFF_85_IN5_DIN")
	)
	(segment
		(start 23.020782 -441.02274)
		(end 23.350982 -441.35294)
		(width 0.1651)
		(layer "In13.Cu")
		(net "TDR_DIFF_85_IN5_DIN")
	)
	(segment
		(start 78.180692 -440.026044)
		(end 78.345792 -439.860944)
		(width 0.1651)
		(layer "In13.Cu")
		(net "TDR_DIFF_85_IN5_DIN")
	)
	(segment
		(start 17.488662 -441.35294)
		(end 18.011902 -441.35294)
		(width 0.1651)
		(layer "In13.Cu")
		(net "TDR_DIFF_85_IN5_DIN")
	)
	(segment
		(start 47.653702 -441.02274)
		(end 47.653702 -439.194448)
		(width 0.1651)
		(layer "In13.Cu")
		(net "TDR_DIFF_85_IN5_DIN")
	)
	(segment
		(start 38.860222 -439.194448)
		(end 39.355522 -438.699148)
		(width 0.1651)
		(layer "In13.Cu")
		(net "TDR_DIFF_85_IN5_DIN")
	)
	(segment
		(start 40.607742 -441.02274)
		(end 40.937942 -441.35294)
		(width 0.1651)
		(layer "In13.Cu")
		(net "TDR_DIFF_85_IN5_DIN")
	)
	(segment
		(start 56.116982 -441.35294)
		(end 56.447182 -441.02274)
		(width 0.1651)
		(layer "In13.Cu")
		(net "TDR_DIFF_85_IN5_DIN")
	)
	(segment
		(start 21.768562 -438.699148)
		(end 22.525482 -438.699148)
		(width 0.1651)
		(layer "In13.Cu")
		(net "TDR_DIFF_85_IN5_DIN")
	)
	(segment
		(start 48.905922 -438.699148)
		(end 49.401222 -439.194448)
		(width 0.1651)
		(layer "In13.Cu")
		(net "TDR_DIFF_85_IN5_DIN")
	)
	(segment
		(start 78.345792 -439.860944)
		(end 78.345792 -438.897014)
		(width 0.1651)
		(layer "In13.Cu")
		(net "TDR_DIFF_85_IN5_DIN")
	)
	(segment
		(start 61.125862 -439.194448)
		(end 61.125862 -441.02274)
		(width 0.1651)
		(layer "In13.Cu")
		(net "TDR_DIFF_85_IN5_DIN")
	)
	(segment
		(start 44.722542 -439.194448)
		(end 45.217842 -438.699148)
		(width 0.1651)
		(layer "In13.Cu")
		(net "TDR_DIFF_85_IN5_DIN")
	)
	(segment
		(start 31.318962 -438.699148)
		(end 31.814262 -439.194448)
		(width 0.1651)
		(layer "In13.Cu")
		(net "TDR_DIFF_85_IN5_DIN")
	)
	(segment
		(start 37.676582 -441.02274)
		(end 38.006782 -441.35294)
		(width 0.1651)
		(layer "In13.Cu")
		(net "TDR_DIFF_85_IN5_DIN")
	)
	(segment
		(start 52.332382 -441.02274)
		(end 52.662582 -441.35294)
		(width 0.1651)
		(layer "In13.Cu")
		(net "TDR_DIFF_85_IN5_DIN")
	)
	(segment
		(start 28.387802 -438.699148)
		(end 28.883102 -439.194448)
		(width 0.1651)
		(layer "In13.Cu")
		(net "TDR_DIFF_85_IN5_DIN")
	)
	(segment
		(start 24.204422 -439.194448)
		(end 24.699722 -438.699148)
		(width 0.1651)
		(layer "In13.Cu")
		(net "TDR_DIFF_85_IN5_DIN")
	)
	(segment
		(start 70.772782 -441.35294)
		(end 71.102982 -441.02274)
		(width 0.1651)
		(layer "In13.Cu")
		(net "TDR_DIFF_85_IN5_DIN")
	)
	(segment
		(start 25.951942 -439.194448)
		(end 25.951942 -441.02274)
		(width 0.1651)
		(layer "In13.Cu")
		(net "TDR_DIFF_85_IN5_DIN")
	)
	(segment
		(start 50.584862 -441.02274)
		(end 50.584862 -439.194448)
		(width 0.1651)
		(layer "In13.Cu")
		(net "TDR_DIFF_85_IN5_DIN")
	)
	(segment
		(start 34.745422 -441.02274)
		(end 35.075622 -441.35294)
		(width 0.1651)
		(layer "In13.Cu")
		(net "TDR_DIFF_85_IN5_DIN")
	)
	(segment
		(start 31.814262 -439.194448)
		(end 31.814262 -441.02274)
		(width 0.1651)
		(layer "In13.Cu")
		(net "TDR_DIFF_85_IN5_DIN")
	)
	(segment
		(start 63.561722 -438.699148)
		(end 64.057022 -439.194448)
		(width 0.1651)
		(layer "In13.Cu")
		(net "TDR_DIFF_85_IN5_DIN")
	)
	(segment
		(start 365.919766 -449.167758)
		(end 440.451748 -449.167758)
		(width 0.15494)
		(layer "In15.Cu")
		(net "TDR_SE_50_OHM_IN6")
	)
	(segment
		(start 364.911386 -450.176138)
		(end 365.919766 -449.167758)
		(width 0.15494)
		(layer "In15.Cu")
		(net "TDR_SE_50_OHM_IN6")
	)
	(segment
		(start 364.911386 -450.699378)
		(end 364.911386 -450.176138)
		(width 0.15494)
		(layer "In15.Cu")
		(net "TDR_SE_50_OHM_IN6")
	)
	(segment
		(start 365.919766 -451.707758)
		(end 364.911386 -450.699378)
		(width 0.15494)
		(layer "In15.Cu")
		(net "TDR_SE_50_OHM_IN6")
	)
	(segment
		(start 440.451748 -451.707758)
		(end 365.919766 -451.707758)
		(width 0.15494)
		(layer "In15.Cu")
		(net "TDR_SE_50_OHM_IN6")
	)
	(segment
		(start 11.890502 -307.981858)
		(end 12.837668 -308.929024)
		(width 0.13208)
		(layer "F.Cu")
		(net "PWRGD_P1V25_PEX0")
	)
	(segment
		(start 12.837668 -308.929024)
		(end 13.583666 -308.929024)
		(width 0.13208)
		(layer "F.Cu")
		(net "PWRGD_P1V25_PEX0")
	)
	(segment
		(start 11.62177 -307.981858)
		(end 11.890502 -307.981858)
		(width 0.13208)
		(layer "F.Cu")
		(net "PWRGD_P1V25_PEX0")
	)
	(via
		(at 13.583666 -308.929024)
		(size 0.508)
		(drill 0.254)
		(layers "F.Cu" "B.Cu")
		(net "PWRGD_P1V25_PEX0")
	)
	(segment
		(start 13.583666 -308.929024)
		(end 13.850874 -308.661816)
		(width 0.13208)
		(layer "B.Cu")
		(net "PWRGD_P1V25_PEX0")
	)
	(segment
		(start 16.257778 -308.66842)
		(end 16.251174 -308.661816)
		(width 0.13208)
		(layer "B.Cu")
		(net "PWRGD_P1V25_PEX0")
	)
	(segment
		(start 16.257778 -309.754016)
		(end 16.257778 -308.66842)
		(width 0.13208)
		(layer "B.Cu")
		(net "PWRGD_P1V25_PEX0")
	)
	(segment
		(start 13.850874 -308.661816)
		(end 16.251174 -308.661816)
		(width 0.13208)
		(layer "B.Cu")
		(net "PWRGD_P1V25_PEX0")
	)
	(segment
		(start 151.044148 -452.165466)
		(end 151.209248 -452.330566)
		(width 0.1651)
		(layer "In9.Cu")
		(net "TDR_DIFF_85_IN3_DIN")
	)
	(segment
		(start 110.258098 -451.16877)
		(end 110.258098 -452.997062)
		(width 0.1651)
		(layer "In9.Cu")
		(net "TDR_DIFF_85_IN3_DIN")
	)
	(segment
		(start 131.271518 -453.492362)
		(end 132.028438 -453.492362)
		(width 0.1651)
		(layer "In9.Cu")
		(net "TDR_DIFF_85_IN3_DIN")
	)
	(segment
		(start 104.065578 -450.83857)
		(end 104.395778 -451.16877)
		(width 0.1651)
		(layer "In9.Cu")
		(net "TDR_DIFF_85_IN3_DIN")
	)
	(segment
		(start 141.317218 -451.16877)
		(end 141.647418 -450.83857)
		(width 0.1651)
		(layer "In9.Cu")
		(net "TDR_DIFF_85_IN3_DIN")
	)
	(segment
		(start 145.927318 -453.492362)
		(end 146.684238 -453.492362)
		(width 0.1651)
		(layer "In9.Cu")
		(net "TDR_DIFF_85_IN3_DIN")
	)
	(segment
		(start 96.854518 -453.492362)
		(end 97.349818 -452.997062)
		(width 0.1651)
		(layer "In9.Cu")
		(net "TDR_DIFF_85_IN3_DIN")
	)
	(segment
		(start 129.922778 -450.83857)
		(end 130.446018 -450.83857)
		(width 0.1651)
		(layer "In9.Cu")
		(net "TDR_DIFF_85_IN3_DIN")
	)
	(segment
		(start 115.790218 -450.83857)
		(end 116.120418 -451.16877)
		(width 0.1651)
		(layer "In9.Cu")
		(net "TDR_DIFF_85_IN3_DIN")
	)
	(segment
		(start 110.258098 -452.997062)
		(end 110.753398 -453.492362)
		(width 0.1651)
		(layer "In9.Cu")
		(net "TDR_DIFF_85_IN3_DIN")
	)
	(segment
		(start 121.982738 -452.997062)
		(end 122.478038 -453.492362)
		(width 0.1651)
		(layer "In9.Cu")
		(net "TDR_DIFF_85_IN3_DIN")
	)
	(segment
		(start 132.523738 -452.997062)
		(end 132.523738 -451.16877)
		(width 0.1651)
		(layer "In9.Cu")
		(net "TDR_DIFF_85_IN3_DIN")
	)
	(segment
		(start 132.523738 -451.16877)
		(end 132.853938 -450.83857)
		(width 0.1651)
		(layer "In9.Cu")
		(net "TDR_DIFF_85_IN3_DIN")
	)
	(segment
		(start 103.212138 -451.16877)
		(end 103.542338 -450.83857)
		(width 0.1651)
		(layer "In9.Cu")
		(net "TDR_DIFF_85_IN3_DIN")
	)
	(segment
		(start 126.661418 -452.997062)
		(end 126.661418 -451.16877)
		(width 0.1651)
		(layer "In9.Cu")
		(net "TDR_DIFF_85_IN3_DIN")
	)
	(segment
		(start 139.569698 -452.997062)
		(end 140.064998 -453.492362)
		(width 0.1651)
		(layer "In9.Cu")
		(net "TDR_DIFF_85_IN3_DIN")
	)
	(segment
		(start 139.239498 -450.83857)
		(end 139.569698 -451.16877)
		(width 0.1651)
		(layer "In9.Cu")
		(net "TDR_DIFF_85_IN3_DIN")
	)
	(segment
		(start 130.776218 -452.997062)
		(end 131.271518 -453.492362)
		(width 0.1651)
		(layer "In9.Cu")
		(net "TDR_DIFF_85_IN3_DIN")
	)
	(segment
		(start 142.500858 -452.997062)
		(end 142.996158 -453.492362)
		(width 0.1651)
		(layer "In9.Cu")
		(net "TDR_DIFF_85_IN3_DIN")
	)
	(segment
		(start 124.583698 -450.83857)
		(end 124.913898 -451.16877)
		(width 0.1651)
		(layer "In9.Cu")
		(net "TDR_DIFF_85_IN3_DIN")
	)
	(segment
		(start 87.175848 -453.294496)
		(end 87.175848 -452.330566)
		(width 0.1651)
		(layer "In9.Cu")
		(net "TDR_DIFF_85_IN3_DIN")
	)
	(segment
		(start 93.923358 -453.492362)
		(end 94.418658 -452.997062)
		(width 0.1651)
		(layer "In9.Cu")
		(net "TDR_DIFF_85_IN3_DIN")
	)
	(segment
		(start 103.212138 -452.997062)
		(end 103.212138 -451.16877)
		(width 0.1651)
		(layer "In9.Cu")
		(net "TDR_DIFF_85_IN3_DIN")
	)
	(segment
		(start 104.891078 -453.492362)
		(end 105.647998 -453.492362)
		(width 0.1651)
		(layer "In9.Cu")
		(net "TDR_DIFF_85_IN3_DIN")
	)
	(segment
		(start 132.853938 -450.83857)
		(end 133.377178 -450.83857)
		(width 0.1651)
		(layer "In9.Cu")
		(net "TDR_DIFF_85_IN3_DIN")
	)
	(segment
		(start 100.611178 -450.83857)
		(end 101.134418 -450.83857)
		(width 0.1651)
		(layer "In9.Cu")
		(net "TDR_DIFF_85_IN3_DIN")
	)
	(segment
		(start 123.730258 -451.16877)
		(end 124.060458 -450.83857)
		(width 0.1651)
		(layer "In9.Cu")
		(net "TDR_DIFF_85_IN3_DIN")
	)
	(segment
		(start 134.959598 -453.492362)
		(end 135.454898 -452.997062)
		(width 0.1651)
		(layer "In9.Cu")
		(net "TDR_DIFF_85_IN3_DIN")
	)
	(segment
		(start 93.166438 -453.492362)
		(end 93.923358 -453.492362)
		(width 0.1651)
		(layer "In9.Cu")
		(net "TDR_DIFF_85_IN3_DIN")
	)
	(segment
		(start 120.303798 -453.492362)
		(end 120.799098 -452.997062)
		(width 0.1651)
		(layer "In9.Cu")
		(net "TDR_DIFF_85_IN3_DIN")
	)
	(segment
		(start 121.652538 -450.83857)
		(end 121.982738 -451.16877)
		(width 0.1651)
		(layer "In9.Cu")
		(net "TDR_DIFF_85_IN3_DIN")
	)
	(segment
		(start 144.248378 -451.16877)
		(end 144.578578 -450.83857)
		(width 0.1651)
		(layer "In9.Cu")
		(net "TDR_DIFF_85_IN3_DIN")
	)
	(segment
		(start 107.822238 -453.492362)
		(end 108.579158 -453.492362)
		(width 0.1651)
		(layer "In9.Cu")
		(net "TDR_DIFF_85_IN3_DIN")
	)
	(segment
		(start 136.638538 -451.16877)
		(end 136.638538 -452.997062)
		(width 0.1651)
		(layer "In9.Cu")
		(net "TDR_DIFF_85_IN3_DIN")
	)
	(segment
		(start 96.097598 -453.492362)
		(end 96.854518 -453.492362)
		(width 0.1651)
		(layer "In9.Cu")
		(net "TDR_DIFF_85_IN3_DIN")
	)
	(segment
		(start 106.473498 -450.83857)
		(end 106.996738 -450.83857)
		(width 0.1651)
		(layer "In9.Cu")
		(net "TDR_DIFF_85_IN3_DIN")
	)
	(segment
		(start 124.060458 -450.83857)
		(end 124.583698 -450.83857)
		(width 0.1651)
		(layer "In9.Cu")
		(net "TDR_DIFF_85_IN3_DIN")
	)
	(segment
		(start 137.133838 -453.492362)
		(end 137.890758 -453.492362)
		(width 0.1651)
		(layer "In9.Cu")
		(net "TDR_DIFF_85_IN3_DIN")
	)
	(segment
		(start 129.592578 -452.997062)
		(end 129.592578 -451.16877)
		(width 0.1651)
		(layer "In9.Cu")
		(net "TDR_DIFF_85_IN3_DIN")
	)
	(segment
		(start 107.326938 -451.16877)
		(end 107.326938 -452.997062)
		(width 0.1651)
		(layer "In9.Cu")
		(net "TDR_DIFF_85_IN3_DIN")
	)
	(segment
		(start 132.028438 -453.492362)
		(end 132.523738 -452.997062)
		(width 0.1651)
		(layer "In9.Cu")
		(net "TDR_DIFF_85_IN3_DIN")
	)
	(segment
		(start 109.074458 -452.997062)
		(end 109.074458 -451.16877)
		(width 0.1651)
		(layer "In9.Cu")
		(net "TDR_DIFF_85_IN3_DIN")
	)
	(segment
		(start 151.209248 -452.330566)
		(end 151.209248 -453.294496)
		(width 0.1651)
		(layer "In9.Cu")
		(net "TDR_DIFF_85_IN3_DIN")
	)
	(segment
		(start 97.680018 -450.83857)
		(end 98.203258 -450.83857)
		(width 0.1651)
		(layer "In9.Cu")
		(net "TDR_DIFF_85_IN3_DIN")
	)
	(segment
		(start 101.464618 -452.997062)
		(end 101.959918 -453.492362)
		(width 0.1651)
		(layer "In9.Cu")
		(net "TDR_DIFF_85_IN3_DIN")
	)
	(segment
		(start 145.432018 -451.16877)
		(end 145.432018 -452.997062)
		(width 0.1651)
		(layer "In9.Cu")
		(net "TDR_DIFF_85_IN3_DIN")
	)
	(segment
		(start 90.235278 -453.492362)
		(end 90.992198 -453.492362)
		(width 0.1651)
		(layer "In9.Cu")
		(net "TDR_DIFF_85_IN3_DIN")
	)
	(segment
		(start 126.166118 -453.492362)
		(end 126.661418 -452.997062)
		(width 0.1651)
		(layer "In9.Cu")
		(net "TDR_DIFF_85_IN3_DIN")
	)
	(segment
		(start 98.533458 -451.16877)
		(end 98.533458 -452.997062)
		(width 0.1651)
		(layer "In9.Cu")
		(net "TDR_DIFF_85_IN3_DIN")
	)
	(segment
		(start 148.363178 -451.670166)
		(end 148.858478 -452.165466)
		(width 0.1651)
		(layer "In9.Cu")
		(net "TDR_DIFF_85_IN3_DIN")
	)
	(segment
		(start 94.418658 -452.997062)
		(end 94.418658 -451.16877)
		(width 0.1651)
		(layer "In9.Cu")
		(net "TDR_DIFF_85_IN3_DIN")
	)
	(segment
		(start 128.340358 -453.492362)
		(end 129.097278 -453.492362)
		(width 0.1651)
		(layer "In9.Cu")
		(net "TDR_DIFF_85_IN3_DIN")
	)
	(segment
		(start 110.753398 -453.492362)
		(end 111.510318 -453.492362)
		(width 0.1651)
		(layer "In9.Cu")
		(net "TDR_DIFF_85_IN3_DIN")
	)
	(segment
		(start 133.377178 -450.83857)
		(end 133.707378 -451.16877)
		(width 0.1651)
		(layer "In9.Cu")
		(net "TDR_DIFF_85_IN3_DIN")
	)
	(segment
		(start 91.817698 -450.83857)
		(end 92.340938 -450.83857)
		(width 0.1651)
		(layer "In9.Cu")
		(net "TDR_DIFF_85_IN3_DIN")
	)
	(segment
		(start 123.730258 -452.997062)
		(end 123.730258 -451.16877)
		(width 0.1651)
		(layer "In9.Cu")
		(net "TDR_DIFF_85_IN3_DIN")
	)
	(segment
		(start 121.982738 -451.16877)
		(end 121.982738 -452.997062)
		(width 0.1651)
		(layer "In9.Cu")
		(net "TDR_DIFF_85_IN3_DIN")
	)
	(segment
		(start 97.349818 -451.16877)
		(end 97.680018 -450.83857)
		(width 0.1651)
		(layer "In9.Cu")
		(net "TDR_DIFF_85_IN3_DIN")
	)
	(segment
		(start 148.032978 -450.83857)
		(end 148.363178 -451.16877)
		(width 0.1651)
		(layer "In9.Cu")
		(net "TDR_DIFF_85_IN3_DIN")
	)
	(segment
		(start 141.647418 -450.83857)
		(end 142.170658 -450.83857)
		(width 0.1651)
		(layer "In9.Cu")
		(net "TDR_DIFF_85_IN3_DIN")
	)
	(segment
		(start 127.845058 -451.16877)
		(end 127.845058 -452.997062)
		(width 0.1651)
		(layer "In9.Cu")
		(net "TDR_DIFF_85_IN3_DIN")
	)
	(segment
		(start 117.372638 -453.492362)
		(end 117.867938 -452.997062)
		(width 0.1651)
		(layer "In9.Cu")
		(net "TDR_DIFF_85_IN3_DIN")
	)
	(segment
		(start 147.179538 -451.16877)
		(end 147.509738 -450.83857)
		(width 0.1651)
		(layer "In9.Cu")
		(net "TDR_DIFF_85_IN3_DIN")
	)
	(segment
		(start 142.170658 -450.83857)
		(end 142.500858 -451.16877)
		(width 0.1651)
		(layer "In9.Cu")
		(net "TDR_DIFF_85_IN3_DIN")
	)
	(segment
		(start 135.454898 -451.16877)
		(end 135.785098 -450.83857)
		(width 0.1651)
		(layer "In9.Cu")
		(net "TDR_DIFF_85_IN3_DIN")
	)
	(segment
		(start 118.721378 -450.83857)
		(end 119.051578 -451.16877)
		(width 0.1651)
		(layer "In9.Cu")
		(net "TDR_DIFF_85_IN3_DIN")
	)
	(segment
		(start 123.234958 -453.492362)
		(end 123.730258 -452.997062)
		(width 0.1651)
		(layer "In9.Cu")
		(net "TDR_DIFF_85_IN3_DIN")
	)
	(segment
		(start 136.308338 -450.83857)
		(end 136.638538 -451.16877)
		(width 0.1651)
		(layer "In9.Cu")
		(net "TDR_DIFF_85_IN3_DIN")
	)
	(segment
		(start 91.487498 -451.16877)
		(end 91.817698 -450.83857)
		(width 0.1651)
		(layer "In9.Cu")
		(net "TDR_DIFF_85_IN3_DIN")
	)
	(segment
		(start 139.569698 -451.16877)
		(end 139.569698 -452.997062)
		(width 0.1651)
		(layer "In9.Cu")
		(net "TDR_DIFF_85_IN3_DIN")
	)
	(segment
		(start 116.120418 -451.16877)
		(end 116.120418 -452.997062)
		(width 0.1651)
		(layer "In9.Cu")
		(net "TDR_DIFF_85_IN3_DIN")
	)
	(segment
		(start 104.395778 -452.997062)
		(end 104.891078 -453.492362)
		(width 0.1651)
		(layer "In9.Cu")
		(net "TDR_DIFF_85_IN3_DIN")
	)
	(segment
		(start 113.684558 -453.492362)
		(end 114.441478 -453.492362)
		(width 0.1651)
		(layer "In9.Cu")
		(net "TDR_DIFF_85_IN3_DIN")
	)
	(segment
		(start 95.272098 -450.83857)
		(end 95.602298 -451.16877)
		(width 0.1651)
		(layer "In9.Cu")
		(net "TDR_DIFF_85_IN3_DIN")
	)
	(segment
		(start 135.454898 -452.997062)
		(end 135.454898 -451.16877)
		(width 0.1651)
		(layer "In9.Cu")
		(net "TDR_DIFF_85_IN3_DIN")
	)
	(segment
		(start 104.395778 -451.16877)
		(end 104.395778 -452.997062)
		(width 0.1651)
		(layer "In9.Cu")
		(net "TDR_DIFF_85_IN3_DIN")
	)
	(segment
		(start 122.478038 -453.492362)
		(end 123.234958 -453.492362)
		(width 0.1651)
		(layer "In9.Cu")
		(net "TDR_DIFF_85_IN3_DIN")
	)
	(segment
		(start 91.487498 -452.997062)
		(end 91.487498 -451.16877)
		(width 0.1651)
		(layer "In9.Cu")
		(net "TDR_DIFF_85_IN3_DIN")
	)
	(segment
		(start 119.051578 -451.16877)
		(end 119.051578 -452.997062)
		(width 0.1651)
		(layer "In9.Cu")
		(net "TDR_DIFF_85_IN3_DIN")
	)
	(segment
		(start 120.799098 -451.16877)
		(end 121.129298 -450.83857)
		(width 0.1651)
		(layer "In9.Cu")
		(net "TDR_DIFF_85_IN3_DIN")
	)
	(segment
		(start 133.707378 -452.997062)
		(end 134.202678 -453.492362)
		(width 0.1651)
		(layer "In9.Cu")
		(net "TDR_DIFF_85_IN3_DIN")
	)
	(segment
		(start 94.418658 -451.16877)
		(end 94.748858 -450.83857)
		(width 0.1651)
		(layer "In9.Cu")
		(net "TDR_DIFF_85_IN3_DIN")
	)
	(segment
		(start 147.179538 -452.997062)
		(end 147.179538 -451.16877)
		(width 0.1651)
		(layer "In9.Cu")
		(net "TDR_DIFF_85_IN3_DIN")
	)
	(segment
		(start 142.996158 -453.492362)
		(end 143.753078 -453.492362)
		(width 0.1651)
		(layer "In9.Cu")
		(net "TDR_DIFF_85_IN3_DIN")
	)
	(segment
		(start 124.913898 -452.997062)
		(end 125.409198 -453.492362)
		(width 0.1651)
		(layer "In9.Cu")
		(net "TDR_DIFF_85_IN3_DIN")
	)
	(segment
		(start 127.845058 -452.997062)
		(end 128.340358 -453.492362)
		(width 0.1651)
		(layer "In9.Cu")
		(net "TDR_DIFF_85_IN3_DIN")
	)
	(segment
		(start 119.546878 -453.492362)
		(end 120.303798 -453.492362)
		(width 0.1651)
		(layer "In9.Cu")
		(net "TDR_DIFF_85_IN3_DIN")
	)
	(segment
		(start 107.326938 -452.997062)
		(end 107.822238 -453.492362)
		(width 0.1651)
		(layer "In9.Cu")
		(net "TDR_DIFF_85_IN3_DIN")
	)
	(segment
		(start 95.602298 -451.16877)
		(end 95.602298 -452.997062)
		(width 0.1651)
		(layer "In9.Cu")
		(net "TDR_DIFF_85_IN3_DIN")
	)
	(segment
		(start 109.927898 -450.83857)
		(end 110.258098 -451.16877)
		(width 0.1651)
		(layer "In9.Cu")
		(net "TDR_DIFF_85_IN3_DIN")
	)
	(segment
		(start 147.509738 -450.83857)
		(end 148.032978 -450.83857)
		(width 0.1651)
		(layer "In9.Cu")
		(net "TDR_DIFF_85_IN3_DIN")
	)
	(segment
		(start 106.143298 -452.997062)
		(end 106.143298 -451.16877)
		(width 0.1651)
		(layer "In9.Cu")
		(net "TDR_DIFF_85_IN3_DIN")
	)
	(segment
		(start 108.579158 -453.492362)
		(end 109.074458 -452.997062)
		(width 0.1651)
		(layer "In9.Cu")
		(net "TDR_DIFF_85_IN3_DIN")
	)
	(segment
		(start 100.280978 -451.16877)
		(end 100.611178 -450.83857)
		(width 0.1651)
		(layer "In9.Cu")
		(net "TDR_DIFF_85_IN3_DIN")
	)
	(segment
		(start 112.335818 -450.83857)
		(end 112.859058 -450.83857)
		(width 0.1651)
		(layer "In9.Cu")
		(net "TDR_DIFF_85_IN3_DIN")
	)
	(segment
		(start 95.602298 -452.997062)
		(end 96.097598 -453.492362)
		(width 0.1651)
		(layer "In9.Cu")
		(net "TDR_DIFF_85_IN3_DIN")
	)
	(segment
		(start 99.785678 -453.492362)
		(end 100.280978 -452.997062)
		(width 0.1651)
		(layer "In9.Cu")
		(net "TDR_DIFF_85_IN3_DIN")
	)
	(segment
		(start 101.134418 -450.83857)
		(end 101.464618 -451.16877)
		(width 0.1651)
		(layer "In9.Cu")
		(net "TDR_DIFF_85_IN3_DIN")
	)
	(segment
		(start 109.074458 -451.16877)
		(end 109.404658 -450.83857)
		(width 0.1651)
		(layer "In9.Cu")
		(net "TDR_DIFF_85_IN3_DIN")
	)
	(segment
		(start 97.349818 -452.997062)
		(end 97.349818 -451.16877)
		(width 0.1651)
		(layer "In9.Cu")
		(net "TDR_DIFF_85_IN3_DIN")
	)
	(segment
		(start 117.867938 -452.997062)
		(end 117.867938 -451.16877)
		(width 0.1651)
		(layer "In9.Cu")
		(net "TDR_DIFF_85_IN3_DIN")
	)
	(segment
		(start 129.592578 -451.16877)
		(end 129.922778 -450.83857)
		(width 0.1651)
		(layer "In9.Cu")
		(net "TDR_DIFF_85_IN3_DIN")
	)
	(segment
		(start 124.913898 -451.16877)
		(end 124.913898 -452.997062)
		(width 0.1651)
		(layer "In9.Cu")
		(net "TDR_DIFF_85_IN3_DIN")
	)
	(segment
		(start 92.671138 -452.997062)
		(end 93.166438 -453.492362)
		(width 0.1651)
		(layer "In9.Cu")
		(net "TDR_DIFF_85_IN3_DIN")
	)
	(segment
		(start 89.739978 -452.997062)
		(end 90.235278 -453.492362)
		(width 0.1651)
		(layer "In9.Cu")
		(net "TDR_DIFF_85_IN3_DIN")
	)
	(segment
		(start 137.890758 -453.492362)
		(end 138.386058 -452.997062)
		(width 0.1651)
		(layer "In9.Cu")
		(net "TDR_DIFF_85_IN3_DIN")
	)
	(segment
		(start 89.409778 -452.165466)
		(end 89.739978 -452.495666)
		(width 0.1651)
		(layer "In9.Cu")
		(net "TDR_DIFF_85_IN3_DIN")
	)
	(segment
		(start 87.340948 -452.165466)
		(end 89.409778 -452.165466)
		(width 0.1651)
		(layer "In9.Cu")
		(net "TDR_DIFF_85_IN3_DIN")
	)
	(segment
		(start 98.533458 -452.997062)
		(end 99.028758 -453.492362)
		(width 0.1651)
		(layer "In9.Cu")
		(net "TDR_DIFF_85_IN3_DIN")
	)
	(segment
		(start 129.097278 -453.492362)
		(end 129.592578 -452.997062)
		(width 0.1651)
		(layer "In9.Cu")
		(net "TDR_DIFF_85_IN3_DIN")
	)
	(segment
		(start 114.936778 -451.16877)
		(end 115.266978 -450.83857)
		(width 0.1651)
		(layer "In9.Cu")
		(net "TDR_DIFF_85_IN3_DIN")
	)
	(segment
		(start 103.542338 -450.83857)
		(end 104.065578 -450.83857)
		(width 0.1651)
		(layer "In9.Cu")
		(net "TDR_DIFF_85_IN3_DIN")
	)
	(segment
		(start 148.858478 -452.165466)
		(end 151.044148 -452.165466)
		(width 0.1651)
		(layer "In9.Cu")
		(net "TDR_DIFF_85_IN3_DIN")
	)
	(segment
		(start 141.317218 -452.997062)
		(end 141.317218 -451.16877)
		(width 0.1651)
		(layer "In9.Cu")
		(net "TDR_DIFF_85_IN3_DIN")
	)
	(segment
		(start 101.464618 -451.16877)
		(end 101.464618 -452.997062)
		(width 0.1651)
		(layer "In9.Cu")
		(net "TDR_DIFF_85_IN3_DIN")
	)
	(segment
		(start 92.340938 -450.83857)
		(end 92.671138 -451.16877)
		(width 0.1651)
		(layer "In9.Cu")
		(net "TDR_DIFF_85_IN3_DIN")
	)
	(segment
		(start 112.005618 -452.997062)
		(end 112.005618 -451.16877)
		(width 0.1651)
		(layer "In9.Cu")
		(net "TDR_DIFF_85_IN3_DIN")
	)
	(segment
		(start 140.064998 -453.492362)
		(end 140.821918 -453.492362)
		(width 0.1651)
		(layer "In9.Cu")
		(net "TDR_DIFF_85_IN3_DIN")
	)
	(segment
		(start 99.028758 -453.492362)
		(end 99.785678 -453.492362)
		(width 0.1651)
		(layer "In9.Cu")
		(net "TDR_DIFF_85_IN3_DIN")
	)
	(segment
		(start 90.992198 -453.492362)
		(end 91.487498 -452.997062)
		(width 0.1651)
		(layer "In9.Cu")
		(net "TDR_DIFF_85_IN3_DIN")
	)
	(segment
		(start 146.684238 -453.492362)
		(end 147.179538 -452.997062)
		(width 0.1651)
		(layer "In9.Cu")
		(net "TDR_DIFF_85_IN3_DIN")
	)
	(segment
		(start 121.129298 -450.83857)
		(end 121.652538 -450.83857)
		(width 0.1651)
		(layer "In9.Cu")
		(net "TDR_DIFF_85_IN3_DIN")
	)
	(segment
		(start 145.432018 -452.997062)
		(end 145.927318 -453.492362)
		(width 0.1651)
		(layer "In9.Cu")
		(net "TDR_DIFF_85_IN3_DIN")
	)
	(segment
		(start 113.189258 -452.997062)
		(end 113.684558 -453.492362)
		(width 0.1651)
		(layer "In9.Cu")
		(net "TDR_DIFF_85_IN3_DIN")
	)
	(segment
		(start 133.707378 -451.16877)
		(end 133.707378 -452.997062)
		(width 0.1651)
		(layer "In9.Cu")
		(net "TDR_DIFF_85_IN3_DIN")
	)
	(segment
		(start 138.386058 -452.997062)
		(end 138.386058 -451.16877)
		(width 0.1651)
		(layer "In9.Cu")
		(net "TDR_DIFF_85_IN3_DIN")
	)
	(segment
		(start 135.785098 -450.83857)
		(end 136.308338 -450.83857)
		(width 0.1651)
		(layer "In9.Cu")
		(net "TDR_DIFF_85_IN3_DIN")
	)
	(segment
		(start 92.671138 -451.16877)
		(end 92.671138 -452.997062)
		(width 0.1651)
		(layer "In9.Cu")
		(net "TDR_DIFF_85_IN3_DIN")
	)
	(segment
		(start 115.266978 -450.83857)
		(end 115.790218 -450.83857)
		(width 0.1651)
		(layer "In9.Cu")
		(net "TDR_DIFF_85_IN3_DIN")
	)
	(segment
		(start 116.120418 -452.997062)
		(end 116.615718 -453.492362)
		(width 0.1651)
		(layer "In9.Cu")
		(net "TDR_DIFF_85_IN3_DIN")
	)
	(segment
		(start 118.198138 -450.83857)
		(end 118.721378 -450.83857)
		(width 0.1651)
		(layer "In9.Cu")
		(net "TDR_DIFF_85_IN3_DIN")
	)
	(segment
		(start 111.510318 -453.492362)
		(end 112.005618 -452.997062)
		(width 0.1651)
		(layer "In9.Cu")
		(net "TDR_DIFF_85_IN3_DIN")
	)
	(segment
		(start 106.143298 -451.16877)
		(end 106.473498 -450.83857)
		(width 0.1651)
		(layer "In9.Cu")
		(net "TDR_DIFF_85_IN3_DIN")
	)
	(segment
		(start 87.175848 -452.330566)
		(end 87.340948 -452.165466)
		(width 0.1651)
		(layer "In9.Cu")
		(net "TDR_DIFF_85_IN3_DIN")
	)
	(segment
		(start 105.647998 -453.492362)
		(end 106.143298 -452.997062)
		(width 0.1651)
		(layer "In9.Cu")
		(net "TDR_DIFF_85_IN3_DIN")
	)
	(segment
		(start 126.991618 -450.83857)
		(end 127.514858 -450.83857)
		(width 0.1651)
		(layer "In9.Cu")
		(net "TDR_DIFF_85_IN3_DIN")
	)
	(segment
		(start 114.441478 -453.492362)
		(end 114.936778 -452.997062)
		(width 0.1651)
		(layer "In9.Cu")
		(net "TDR_DIFF_85_IN3_DIN")
	)
	(segment
		(start 89.739978 -452.495666)
		(end 89.739978 -452.997062)
		(width 0.1651)
		(layer "In9.Cu")
		(net "TDR_DIFF_85_IN3_DIN")
	)
	(segment
		(start 101.959918 -453.492362)
		(end 102.716838 -453.492362)
		(width 0.1651)
		(layer "In9.Cu")
		(net "TDR_DIFF_85_IN3_DIN")
	)
	(segment
		(start 114.936778 -452.997062)
		(end 114.936778 -451.16877)
		(width 0.1651)
		(layer "In9.Cu")
		(net "TDR_DIFF_85_IN3_DIN")
	)
	(segment
		(start 136.638538 -452.997062)
		(end 137.133838 -453.492362)
		(width 0.1651)
		(layer "In9.Cu")
		(net "TDR_DIFF_85_IN3_DIN")
	)
	(segment
		(start 130.776218 -451.16877)
		(end 130.776218 -452.997062)
		(width 0.1651)
		(layer "In9.Cu")
		(net "TDR_DIFF_85_IN3_DIN")
	)
	(segment
		(start 112.005618 -451.16877)
		(end 112.335818 -450.83857)
		(width 0.1651)
		(layer "In9.Cu")
		(net "TDR_DIFF_85_IN3_DIN")
	)
	(segment
		(start 134.202678 -453.492362)
		(end 134.959598 -453.492362)
		(width 0.1651)
		(layer "In9.Cu")
		(net "TDR_DIFF_85_IN3_DIN")
	)
	(segment
		(start 117.867938 -451.16877)
		(end 118.198138 -450.83857)
		(width 0.1651)
		(layer "In9.Cu")
		(net "TDR_DIFF_85_IN3_DIN")
	)
	(segment
		(start 127.514858 -450.83857)
		(end 127.845058 -451.16877)
		(width 0.1651)
		(layer "In9.Cu")
		(net "TDR_DIFF_85_IN3_DIN")
	)
	(segment
		(start 145.101818 -450.83857)
		(end 145.432018 -451.16877)
		(width 0.1651)
		(layer "In9.Cu")
		(net "TDR_DIFF_85_IN3_DIN")
	)
	(segment
		(start 109.404658 -450.83857)
		(end 109.927898 -450.83857)
		(width 0.1651)
		(layer "In9.Cu")
		(net "TDR_DIFF_85_IN3_DIN")
	)
	(segment
		(start 144.578578 -450.83857)
		(end 145.101818 -450.83857)
		(width 0.1651)
		(layer "In9.Cu")
		(net "TDR_DIFF_85_IN3_DIN")
	)
	(segment
		(start 143.753078 -453.492362)
		(end 144.248378 -452.997062)
		(width 0.1651)
		(layer "In9.Cu")
		(net "TDR_DIFF_85_IN3_DIN")
	)
	(segment
		(start 116.615718 -453.492362)
		(end 117.372638 -453.492362)
		(width 0.1651)
		(layer "In9.Cu")
		(net "TDR_DIFF_85_IN3_DIN")
	)
	(segment
		(start 126.661418 -451.16877)
		(end 126.991618 -450.83857)
		(width 0.1651)
		(layer "In9.Cu")
		(net "TDR_DIFF_85_IN3_DIN")
	)
	(segment
		(start 119.051578 -452.997062)
		(end 119.546878 -453.492362)
		(width 0.1651)
		(layer "In9.Cu")
		(net "TDR_DIFF_85_IN3_DIN")
	)
	(segment
		(start 142.500858 -451.16877)
		(end 142.500858 -452.997062)
		(width 0.1651)
		(layer "In9.Cu")
		(net "TDR_DIFF_85_IN3_DIN")
	)
	(segment
		(start 140.821918 -453.492362)
		(end 141.317218 -452.997062)
		(width 0.1651)
		(layer "In9.Cu")
		(net "TDR_DIFF_85_IN3_DIN")
	)
	(segment
		(start 138.386058 -451.16877)
		(end 138.716258 -450.83857)
		(width 0.1651)
		(layer "In9.Cu")
		(net "TDR_DIFF_85_IN3_DIN")
	)
	(segment
		(start 144.248378 -452.997062)
		(end 144.248378 -451.16877)
		(width 0.1651)
		(layer "In9.Cu")
		(net "TDR_DIFF_85_IN3_DIN")
	)
	(segment
		(start 113.189258 -451.16877)
		(end 113.189258 -452.997062)
		(width 0.1651)
		(layer "In9.Cu")
		(net "TDR_DIFF_85_IN3_DIN")
	)
	(segment
		(start 130.446018 -450.83857)
		(end 130.776218 -451.16877)
		(width 0.1651)
		(layer "In9.Cu")
		(net "TDR_DIFF_85_IN3_DIN")
	)
	(segment
		(start 125.409198 -453.492362)
		(end 126.166118 -453.492362)
		(width 0.1651)
		(layer "In9.Cu")
		(net "TDR_DIFF_85_IN3_DIN")
	)
	(segment
		(start 112.859058 -450.83857)
		(end 113.189258 -451.16877)
		(width 0.1651)
		(layer "In9.Cu")
		(net "TDR_DIFF_85_IN3_DIN")
	)
	(segment
		(start 100.280978 -452.997062)
		(end 100.280978 -451.16877)
		(width 0.1651)
		(layer "In9.Cu")
		(net "TDR_DIFF_85_IN3_DIN")
	)
	(segment
		(start 102.716838 -453.492362)
		(end 103.212138 -452.997062)
		(width 0.1651)
		(layer "In9.Cu")
		(net "TDR_DIFF_85_IN3_DIN")
	)
	(segment
		(start 120.799098 -452.997062)
		(end 120.799098 -451.16877)
		(width 0.1651)
		(layer "In9.Cu")
		(net "TDR_DIFF_85_IN3_DIN")
	)
	(segment
		(start 94.748858 -450.83857)
		(end 95.272098 -450.83857)
		(width 0.1651)
		(layer "In9.Cu")
		(net "TDR_DIFF_85_IN3_DIN")
	)
	(segment
		(start 98.203258 -450.83857)
		(end 98.533458 -451.16877)
		(width 0.1651)
		(layer "In9.Cu")
		(net "TDR_DIFF_85_IN3_DIN")
	)
	(segment
		(start 106.996738 -450.83857)
		(end 107.326938 -451.16877)
		(width 0.1651)
		(layer "In9.Cu")
		(net "TDR_DIFF_85_IN3_DIN")
	)
	(segment
		(start 138.716258 -450.83857)
		(end 139.239498 -450.83857)
		(width 0.1651)
		(layer "In9.Cu")
		(net "TDR_DIFF_85_IN3_DIN")
	)
	(segment
		(start 148.363178 -451.16877)
		(end 148.363178 -451.670166)
		(width 0.1651)
		(layer "In9.Cu")
		(net "TDR_DIFF_85_IN3_DIN")
	)
	(segment
		(start 364.8075 -435.528466)
		(end 364.8075 -435.787546)
		(width 0.13208)
		(layer "F.Cu")
		(net "TDR_SE_50_OHM_TOP")
	)
	(segment
		(start 364.8075 -435.787546)
		(end 365.94796 -436.928006)
		(width 0.13208)
		(layer "F.Cu")
		(net "TDR_SE_50_OHM_TOP")
	)
	(segment
		(start 365.94796 -434.388006)
		(end 364.8075 -435.528466)
		(width 0.13208)
		(layer "F.Cu")
		(net "TDR_SE_50_OHM_TOP")
	)
	(segment
		(start 365.94796 -436.928006)
		(end 440.453526 -436.928006)
		(width 0.13208)
		(layer "F.Cu")
		(net "TDR_SE_50_OHM_TOP")
	)
	(segment
		(start 440.453526 -434.388006)
		(end 365.94796 -434.388006)
		(width 0.13208)
		(layer "F.Cu")
		(net "TDR_SE_50_OHM_TOP")
	)
	(segment
		(start 12.24661 -307.088286)
		(end 12.547092 -307.088286)
		(width 0.254)
		(layer "F.Cu")
		(net "P1V25_PEX0_FB")
	)
	(segment
		(start 14.456918 -307.26888)
		(end 14.78534 -307.26888)
		(width 0.254)
		(layer "F.Cu")
		(net "P1V25_PEX0_FB")
	)
	(segment
		(start 14.121384 -307.458364)
		(end 14.267434 -307.458364)
		(width 0.254)
		(layer "F.Cu")
		(net "P1V25_PEX0_FB")
	)
	(segment
		(start 12.24026 -307.081936)
		(end 12.24661 -307.088286)
		(width 0.254)
		(layer "F.Cu")
		(net "P1V25_PEX0_FB")
	)
	(segment
		(start 13.812012 -307.324506)
		(end 13.94587 -307.458364)
		(width 0.254)
		(layer "F.Cu")
		(net "P1V25_PEX0_FB")
	)
	(segment
		(start 13.94587 -307.458364)
		(end 14.121384 -307.458364)
		(width 0.254)
		(layer "F.Cu")
		(net "P1V25_PEX0_FB")
	)
	(segment
		(start 13.117576 -307.324506)
		(end 13.476224 -307.324506)
		(width 0.254)
		(layer "F.Cu")
		(net "P1V25_PEX0_FB")
	)
	(segment
		(start 11.62177 -307.081936)
		(end 12.24026 -307.081936)
		(width 0.1778)
		(layer "F.Cu")
		(net "P1V25_PEX0_FB")
	)
	(segment
		(start 12.547092 -307.088286)
		(end 13.117576 -307.324506)
		(width 0.254)
		(layer "F.Cu")
		(net "P1V25_PEX0_FB")
	)
	(segment
		(start 14.78534 -308.28488)
		(end 14.78534 -307.26888)
		(width 0.254)
		(layer "F.Cu")
		(net "P1V25_PEX0_FB")
	)
	(segment
		(start 14.267434 -307.458364)
		(end 14.456918 -307.26888)
		(width 0.254)
		(layer "F.Cu")
		(net "P1V25_PEX0_FB")
	)
	(segment
		(start 13.476224 -307.324506)
		(end 13.812012 -307.324506)
		(width 0.254)
		(layer "F.Cu")
		(net "P1V25_PEX0_FB")
	)
	(via
		(at 14.121384 -307.458364)
		(size 0.508)
		(drill 0.254)
		(layers "F.Cu" "B.Cu")
		(net "P1V25_PEX0_FB")
	)
	(segment
		(start 90.440256 -447.968624)
		(end 91.79052 -447.968624)
		(width 0.13462)
		(layer "B.Cu")
		(net "TDR_DIFF_85_BOT_DIN")
	)
	(segment
		(start 123.187968 -444.939928)
		(end 123.457208 -444.670688)
		(width 0.13462)
		(layer "B.Cu")
		(net "TDR_DIFF_85_BOT_DIN")
	)
	(segment
		(start 134.800848 -444.939928)
		(end 135.070088 -444.670688)
		(width 0.13462)
		(layer "B.Cu")
		(net "TDR_DIFF_85_BOT_DIN")
	)
	(segment
		(start 101.623368 -444.939928)
		(end 101.623368 -447.538856)
		(width 0.13462)
		(layer "B.Cu")
		(net "TDR_DIFF_85_BOT_DIN")
	)
	(segment
		(start 136.462008 -447.538856)
		(end 136.891776 -447.968624)
		(width 0.13462)
		(layer "B.Cu")
		(net "TDR_DIFF_85_BOT_DIN")
	)
	(segment
		(start 117.107208 -444.939928)
		(end 117.107208 -447.538856)
		(width 0.13462)
		(layer "B.Cu")
		(net "TDR_DIFF_85_BOT_DIN")
	)
	(segment
		(start 97.483168 -444.670688)
		(end 97.752408 -444.939928)
		(width 0.13462)
		(layer "B.Cu")
		(net "TDR_DIFF_85_BOT_DIN")
	)
	(segment
		(start 117.107208 -447.538856)
		(end 117.536976 -447.968624)
		(width 0.13462)
		(layer "B.Cu")
		(net "TDR_DIFF_85_BOT_DIN")
	)
	(segment
		(start 115.715288 -444.670688)
		(end 116.837968 -444.670688)
		(width 0.13462)
		(layer "B.Cu")
		(net "TDR_DIFF_85_BOT_DIN")
	)
	(segment
		(start 107.704128 -447.538856)
		(end 107.704128 -444.939928)
		(width 0.13462)
		(layer "B.Cu")
		(net "TDR_DIFF_85_BOT_DIN")
	)
	(segment
		(start 128.450848 -444.670688)
		(end 128.720088 -444.939928)
		(width 0.13462)
		(layer "B.Cu")
		(net "TDR_DIFF_85_BOT_DIN")
	)
	(segment
		(start 131.199128 -444.670688)
		(end 132.321808 -444.670688)
		(width 0.13462)
		(layer "B.Cu")
		(net "TDR_DIFF_85_BOT_DIN")
	)
	(segment
		(start 148.074888 -444.939928)
		(end 148.074888 -445.889888)
		(width 0.13462)
		(layer "B.Cu")
		(net "TDR_DIFF_85_BOT_DIN")
	)
	(segment
		(start 102.053136 -447.968624)
		(end 103.4034 -447.968624)
		(width 0.13462)
		(layer "B.Cu")
		(net "TDR_DIFF_85_BOT_DIN")
	)
	(segment
		(start 113.236248 -447.538856)
		(end 113.666016 -447.968624)
		(width 0.13462)
		(layer "B.Cu")
		(net "TDR_DIFF_85_BOT_DIN")
	)
	(segment
		(start 125.278896 -447.968624)
		(end 126.62916 -447.968624)
		(width 0.13462)
		(layer "B.Cu")
		(net "TDR_DIFF_85_BOT_DIN")
	)
	(segment
		(start 132.591048 -444.939928)
		(end 132.591048 -447.538856)
		(width 0.13462)
		(layer "B.Cu")
		(net "TDR_DIFF_85_BOT_DIN")
	)
	(segment
		(start 98.182176 -447.968624)
		(end 99.53244 -447.968624)
		(width 0.13462)
		(layer "B.Cu")
		(net "TDR_DIFF_85_BOT_DIN")
	)
	(segment
		(start 128.720088 -447.538856)
		(end 129.149856 -447.968624)
		(width 0.13462)
		(layer "B.Cu")
		(net "TDR_DIFF_85_BOT_DIN")
	)
	(segment
		(start 107.704128 -444.939928)
		(end 107.973368 -444.670688)
		(width 0.13462)
		(layer "B.Cu")
		(net "TDR_DIFF_85_BOT_DIN")
	)
	(segment
		(start 97.752408 -444.939928)
		(end 97.752408 -447.538856)
		(width 0.13462)
		(layer "B.Cu")
		(net "TDR_DIFF_85_BOT_DIN")
	)
	(segment
		(start 112.967008 -444.670688)
		(end 113.236248 -444.939928)
		(width 0.13462)
		(layer "B.Cu")
		(net "TDR_DIFF_85_BOT_DIN")
	)
	(segment
		(start 146.413728 -447.538856)
		(end 146.413728 -444.939928)
		(width 0.13462)
		(layer "B.Cu")
		(net "TDR_DIFF_85_BOT_DIN")
	)
	(segment
		(start 105.494328 -447.538856)
		(end 105.924096 -447.968624)
		(width 0.13462)
		(layer "B.Cu")
		(net "TDR_DIFF_85_BOT_DIN")
	)
	(segment
		(start 123.187968 -447.538856)
		(end 123.187968 -444.939928)
		(width 0.13462)
		(layer "B.Cu")
		(net "TDR_DIFF_85_BOT_DIN")
	)
	(segment
		(start 121.407936 -447.968624)
		(end 122.7582 -447.968624)
		(width 0.13462)
		(layer "B.Cu")
		(net "TDR_DIFF_85_BOT_DIN")
	)
	(segment
		(start 95.66148 -447.968624)
		(end 96.091248 -447.538856)
		(width 0.13462)
		(layer "B.Cu")
		(net "TDR_DIFF_85_BOT_DIN")
	)
	(segment
		(start 140.332968 -444.939928)
		(end 140.332968 -447.538856)
		(width 0.13462)
		(layer "B.Cu")
		(net "TDR_DIFF_85_BOT_DIN")
	)
	(segment
		(start 130.50012 -447.968624)
		(end 130.929888 -447.538856)
		(width 0.13462)
		(layer "B.Cu")
		(net "TDR_DIFF_85_BOT_DIN")
	)
	(segment
		(start 136.462008 -444.939928)
		(end 136.462008 -447.538856)
		(width 0.13462)
		(layer "B.Cu")
		(net "TDR_DIFF_85_BOT_DIN")
	)
	(segment
		(start 92.489528 -444.670688)
		(end 93.612208 -444.670688)
		(width 0.13462)
		(layer "B.Cu")
		(net "TDR_DIFF_85_BOT_DIN")
	)
	(segment
		(start 87.150448 -447.452496)
		(end 87.150448 -446.454276)
		(width 0.13462)
		(layer "B.Cu")
		(net "TDR_DIFF_85_BOT_DIN")
	)
	(segment
		(start 111.844328 -444.670688)
		(end 112.967008 -444.670688)
		(width 0.13462)
		(layer "B.Cu")
		(net "TDR_DIFF_85_BOT_DIN")
	)
	(segment
		(start 127.058928 -444.939928)
		(end 127.328168 -444.670688)
		(width 0.13462)
		(layer "B.Cu")
		(net "TDR_DIFF_85_BOT_DIN")
	)
	(segment
		(start 140.762736 -447.968624)
		(end 142.113 -447.968624)
		(width 0.13462)
		(layer "B.Cu")
		(net "TDR_DIFF_85_BOT_DIN")
	)
	(segment
		(start 115.446048 -447.538856)
		(end 115.446048 -444.939928)
		(width 0.13462)
		(layer "B.Cu")
		(net "TDR_DIFF_85_BOT_DIN")
	)
	(segment
		(start 142.542768 -447.538856)
		(end 142.542768 -444.939928)
		(width 0.13462)
		(layer "B.Cu")
		(net "TDR_DIFF_85_BOT_DIN")
	)
	(segment
		(start 120.708928 -444.670688)
		(end 120.978168 -444.939928)
		(width 0.13462)
		(layer "B.Cu")
		(net "TDR_DIFF_85_BOT_DIN")
	)
	(segment
		(start 96.360488 -444.670688)
		(end 97.483168 -444.670688)
		(width 0.13462)
		(layer "B.Cu")
		(net "TDR_DIFF_85_BOT_DIN")
	)
	(segment
		(start 111.14532 -447.968624)
		(end 111.575088 -447.538856)
		(width 0.13462)
		(layer "B.Cu")
		(net "TDR_DIFF_85_BOT_DIN")
	)
	(segment
		(start 142.812008 -444.670688)
		(end 143.934688 -444.670688)
		(width 0.13462)
		(layer "B.Cu")
		(net "TDR_DIFF_85_BOT_DIN")
	)
	(segment
		(start 94.311216 -447.968624)
		(end 95.66148 -447.968624)
		(width 0.13462)
		(layer "B.Cu")
		(net "TDR_DIFF_85_BOT_DIN")
	)
	(segment
		(start 138.24204 -447.968624)
		(end 138.671808 -447.538856)
		(width 0.13462)
		(layer "B.Cu")
		(net "TDR_DIFF_85_BOT_DIN")
	)
	(segment
		(start 138.941048 -444.670688)
		(end 140.063728 -444.670688)
		(width 0.13462)
		(layer "B.Cu")
		(net "TDR_DIFF_85_BOT_DIN")
	)
	(segment
		(start 123.457208 -444.670688)
		(end 124.579888 -444.670688)
		(width 0.13462)
		(layer "B.Cu")
		(net "TDR_DIFF_85_BOT_DIN")
	)
	(segment
		(start 129.149856 -447.968624)
		(end 130.50012 -447.968624)
		(width 0.13462)
		(layer "B.Cu")
		(net "TDR_DIFF_85_BOT_DIN")
	)
	(segment
		(start 119.586248 -444.670688)
		(end 120.708928 -444.670688)
		(width 0.13462)
		(layer "B.Cu")
		(net "TDR_DIFF_85_BOT_DIN")
	)
	(segment
		(start 93.612208 -444.670688)
		(end 93.881448 -444.939928)
		(width 0.13462)
		(layer "B.Cu")
		(net "TDR_DIFF_85_BOT_DIN")
	)
	(segment
		(start 99.962208 -447.538856)
		(end 99.962208 -444.939928)
		(width 0.13462)
		(layer "B.Cu")
		(net "TDR_DIFF_85_BOT_DIN")
	)
	(segment
		(start 136.192768 -444.670688)
		(end 136.462008 -444.939928)
		(width 0.13462)
		(layer "B.Cu")
		(net "TDR_DIFF_85_BOT_DIN")
	)
	(segment
		(start 132.591048 -447.538856)
		(end 133.020816 -447.968624)
		(width 0.13462)
		(layer "B.Cu")
		(net "TDR_DIFF_85_BOT_DIN")
	)
	(segment
		(start 127.058928 -447.538856)
		(end 127.058928 -444.939928)
		(width 0.13462)
		(layer "B.Cu")
		(net "TDR_DIFF_85_BOT_DIN")
	)
	(segment
		(start 126.62916 -447.968624)
		(end 127.058928 -447.538856)
		(width 0.13462)
		(layer "B.Cu")
		(net "TDR_DIFF_85_BOT_DIN")
	)
	(segment
		(start 148.504656 -446.319656)
		(end 151.074628 -446.319656)
		(width 0.13462)
		(layer "B.Cu")
		(net "TDR_DIFF_85_BOT_DIN")
	)
	(segment
		(start 101.354128 -444.670688)
		(end 101.623368 -444.939928)
		(width 0.13462)
		(layer "B.Cu")
		(net "TDR_DIFF_85_BOT_DIN")
	)
	(segment
		(start 119.317008 -447.538856)
		(end 119.317008 -444.939928)
		(width 0.13462)
		(layer "B.Cu")
		(net "TDR_DIFF_85_BOT_DIN")
	)
	(segment
		(start 124.579888 -444.670688)
		(end 124.849128 -444.939928)
		(width 0.13462)
		(layer "B.Cu")
		(net "TDR_DIFF_85_BOT_DIN")
	)
	(segment
		(start 115.446048 -444.939928)
		(end 115.715288 -444.670688)
		(width 0.13462)
		(layer "B.Cu")
		(net "TDR_DIFF_85_BOT_DIN")
	)
	(segment
		(start 90.010488 -446.588896)
		(end 90.010488 -447.538856)
		(width 0.13462)
		(layer "B.Cu")
		(net "TDR_DIFF_85_BOT_DIN")
	)
	(segment
		(start 120.978168 -447.538856)
		(end 121.407936 -447.968624)
		(width 0.13462)
		(layer "B.Cu")
		(net "TDR_DIFF_85_BOT_DIN")
	)
	(segment
		(start 127.328168 -444.670688)
		(end 128.450848 -444.670688)
		(width 0.13462)
		(layer "B.Cu")
		(net "TDR_DIFF_85_BOT_DIN")
	)
	(segment
		(start 92.220288 -444.939928)
		(end 92.489528 -444.670688)
		(width 0.13462)
		(layer "B.Cu")
		(net "TDR_DIFF_85_BOT_DIN")
	)
	(segment
		(start 97.752408 -447.538856)
		(end 98.182176 -447.968624)
		(width 0.13462)
		(layer "B.Cu")
		(net "TDR_DIFF_85_BOT_DIN")
	)
	(segment
		(start 92.220288 -447.538856)
		(end 92.220288 -444.939928)
		(width 0.13462)
		(layer "B.Cu")
		(net "TDR_DIFF_85_BOT_DIN")
	)
	(segment
		(start 140.332968 -447.538856)
		(end 140.762736 -447.968624)
		(width 0.13462)
		(layer "B.Cu")
		(net "TDR_DIFF_85_BOT_DIN")
	)
	(segment
		(start 145.98396 -447.968624)
		(end 146.413728 -447.538856)
		(width 0.13462)
		(layer "B.Cu")
		(net "TDR_DIFF_85_BOT_DIN")
	)
	(segment
		(start 124.849128 -444.939928)
		(end 124.849128 -447.538856)
		(width 0.13462)
		(layer "B.Cu")
		(net "TDR_DIFF_85_BOT_DIN")
	)
	(segment
		(start 105.924096 -447.968624)
		(end 107.27436 -447.968624)
		(width 0.13462)
		(layer "B.Cu")
		(net "TDR_DIFF_85_BOT_DIN")
	)
	(segment
		(start 128.720088 -444.939928)
		(end 128.720088 -447.538856)
		(width 0.13462)
		(layer "B.Cu")
		(net "TDR_DIFF_85_BOT_DIN")
	)
	(segment
		(start 90.010488 -447.538856)
		(end 90.440256 -447.968624)
		(width 0.13462)
		(layer "B.Cu")
		(net "TDR_DIFF_85_BOT_DIN")
	)
	(segment
		(start 109.365288 -447.538856)
		(end 109.795056 -447.968624)
		(width 0.13462)
		(layer "B.Cu")
		(net "TDR_DIFF_85_BOT_DIN")
	)
	(segment
		(start 99.53244 -447.968624)
		(end 99.962208 -447.538856)
		(width 0.13462)
		(layer "B.Cu")
		(net "TDR_DIFF_85_BOT_DIN")
	)
	(segment
		(start 107.973368 -444.670688)
		(end 109.096048 -444.670688)
		(width 0.13462)
		(layer "B.Cu")
		(net "TDR_DIFF_85_BOT_DIN")
	)
	(segment
		(start 144.203928 -444.939928)
		(end 144.203928 -447.538856)
		(width 0.13462)
		(layer "B.Cu")
		(net "TDR_DIFF_85_BOT_DIN")
	)
	(segment
		(start 144.203928 -447.538856)
		(end 144.633696 -447.968624)
		(width 0.13462)
		(layer "B.Cu")
		(net "TDR_DIFF_85_BOT_DIN")
	)
	(segment
		(start 120.978168 -444.939928)
		(end 120.978168 -447.538856)
		(width 0.13462)
		(layer "B.Cu")
		(net "TDR_DIFF_85_BOT_DIN")
	)
	(segment
		(start 146.682968 -444.670688)
		(end 147.805648 -444.670688)
		(width 0.13462)
		(layer "B.Cu")
		(net "TDR_DIFF_85_BOT_DIN")
	)
	(segment
		(start 107.27436 -447.968624)
		(end 107.704128 -447.538856)
		(width 0.13462)
		(layer "B.Cu")
		(net "TDR_DIFF_85_BOT_DIN")
	)
	(segment
		(start 115.01628 -447.968624)
		(end 115.446048 -447.538856)
		(width 0.13462)
		(layer "B.Cu")
		(net "TDR_DIFF_85_BOT_DIN")
	)
	(segment
		(start 103.833168 -444.939928)
		(end 104.102408 -444.670688)
		(width 0.13462)
		(layer "B.Cu")
		(net "TDR_DIFF_85_BOT_DIN")
	)
	(segment
		(start 105.225088 -444.670688)
		(end 105.494328 -444.939928)
		(width 0.13462)
		(layer "B.Cu")
		(net "TDR_DIFF_85_BOT_DIN")
	)
	(segment
		(start 96.091248 -447.538856)
		(end 96.091248 -444.939928)
		(width 0.13462)
		(layer "B.Cu")
		(net "TDR_DIFF_85_BOT_DIN")
	)
	(segment
		(start 146.413728 -444.939928)
		(end 146.682968 -444.670688)
		(width 0.13462)
		(layer "B.Cu")
		(net "TDR_DIFF_85_BOT_DIN")
	)
	(segment
		(start 104.102408 -444.670688)
		(end 105.225088 -444.670688)
		(width 0.13462)
		(layer "B.Cu")
		(net "TDR_DIFF_85_BOT_DIN")
	)
	(segment
		(start 134.800848 -447.538856)
		(end 134.800848 -444.939928)
		(width 0.13462)
		(layer "B.Cu")
		(net "TDR_DIFF_85_BOT_DIN")
	)
	(segment
		(start 100.231448 -444.670688)
		(end 101.354128 -444.670688)
		(width 0.13462)
		(layer "B.Cu")
		(net "TDR_DIFF_85_BOT_DIN")
	)
	(segment
		(start 109.365288 -444.939928)
		(end 109.365288 -447.538856)
		(width 0.13462)
		(layer "B.Cu")
		(net "TDR_DIFF_85_BOT_DIN")
	)
	(segment
		(start 119.317008 -444.939928)
		(end 119.586248 -444.670688)
		(width 0.13462)
		(layer "B.Cu")
		(net "TDR_DIFF_85_BOT_DIN")
	)
	(segment
		(start 96.091248 -444.939928)
		(end 96.360488 -444.670688)
		(width 0.13462)
		(layer "B.Cu")
		(net "TDR_DIFF_85_BOT_DIN")
	)
	(segment
		(start 151.074628 -446.319656)
		(end 151.209248 -446.454276)
		(width 0.13462)
		(layer "B.Cu")
		(net "TDR_DIFF_85_BOT_DIN")
	)
	(segment
		(start 116.837968 -444.670688)
		(end 117.107208 -444.939928)
		(width 0.13462)
		(layer "B.Cu")
		(net "TDR_DIFF_85_BOT_DIN")
	)
	(segment
		(start 132.321808 -444.670688)
		(end 132.591048 -444.939928)
		(width 0.13462)
		(layer "B.Cu")
		(net "TDR_DIFF_85_BOT_DIN")
	)
	(segment
		(start 103.833168 -447.538856)
		(end 103.833168 -444.939928)
		(width 0.13462)
		(layer "B.Cu")
		(net "TDR_DIFF_85_BOT_DIN")
	)
	(segment
		(start 148.074888 -445.889888)
		(end 148.504656 -446.319656)
		(width 0.13462)
		(layer "B.Cu")
		(net "TDR_DIFF_85_BOT_DIN")
	)
	(segment
		(start 134.37108 -447.968624)
		(end 134.800848 -447.538856)
		(width 0.13462)
		(layer "B.Cu")
		(net "TDR_DIFF_85_BOT_DIN")
	)
	(segment
		(start 105.494328 -444.939928)
		(end 105.494328 -447.538856)
		(width 0.13462)
		(layer "B.Cu")
		(net "TDR_DIFF_85_BOT_DIN")
	)
	(segment
		(start 118.88724 -447.968624)
		(end 119.317008 -447.538856)
		(width 0.13462)
		(layer "B.Cu")
		(net "TDR_DIFF_85_BOT_DIN")
	)
	(segment
		(start 142.542768 -444.939928)
		(end 142.812008 -444.670688)
		(width 0.13462)
		(layer "B.Cu")
		(net "TDR_DIFF_85_BOT_DIN")
	)
	(segment
		(start 133.020816 -447.968624)
		(end 134.37108 -447.968624)
		(width 0.13462)
		(layer "B.Cu")
		(net "TDR_DIFF_85_BOT_DIN")
	)
	(segment
		(start 147.805648 -444.670688)
		(end 148.074888 -444.939928)
		(width 0.13462)
		(layer "B.Cu")
		(net "TDR_DIFF_85_BOT_DIN")
	)
	(segment
		(start 91.79052 -447.968624)
		(end 92.220288 -447.538856)
		(width 0.13462)
		(layer "B.Cu")
		(net "TDR_DIFF_85_BOT_DIN")
	)
	(segment
		(start 93.881448 -444.939928)
		(end 93.881448 -447.538856)
		(width 0.13462)
		(layer "B.Cu")
		(net "TDR_DIFF_85_BOT_DIN")
	)
	(segment
		(start 99.962208 -444.939928)
		(end 100.231448 -444.670688)
		(width 0.13462)
		(layer "B.Cu")
		(net "TDR_DIFF_85_BOT_DIN")
	)
	(segment
		(start 113.666016 -447.968624)
		(end 115.01628 -447.968624)
		(width 0.13462)
		(layer "B.Cu")
		(net "TDR_DIFF_85_BOT_DIN")
	)
	(segment
		(start 93.881448 -447.538856)
		(end 94.311216 -447.968624)
		(width 0.13462)
		(layer "B.Cu")
		(net "TDR_DIFF_85_BOT_DIN")
	)
	(segment
		(start 138.671808 -444.939928)
		(end 138.941048 -444.670688)
		(width 0.13462)
		(layer "B.Cu")
		(net "TDR_DIFF_85_BOT_DIN")
	)
	(segment
		(start 109.795056 -447.968624)
		(end 111.14532 -447.968624)
		(width 0.13462)
		(layer "B.Cu")
		(net "TDR_DIFF_85_BOT_DIN")
	)
	(segment
		(start 111.575088 -444.939928)
		(end 111.844328 -444.670688)
		(width 0.13462)
		(layer "B.Cu")
		(net "TDR_DIFF_85_BOT_DIN")
	)
	(segment
		(start 140.063728 -444.670688)
		(end 140.332968 -444.939928)
		(width 0.13462)
		(layer "B.Cu")
		(net "TDR_DIFF_85_BOT_DIN")
	)
	(segment
		(start 130.929888 -444.939928)
		(end 131.199128 -444.670688)
		(width 0.13462)
		(layer "B.Cu")
		(net "TDR_DIFF_85_BOT_DIN")
	)
	(segment
		(start 109.096048 -444.670688)
		(end 109.365288 -444.939928)
		(width 0.13462)
		(layer "B.Cu")
		(net "TDR_DIFF_85_BOT_DIN")
	)
	(segment
		(start 103.4034 -447.968624)
		(end 103.833168 -447.538856)
		(width 0.13462)
		(layer "B.Cu")
		(net "TDR_DIFF_85_BOT_DIN")
	)
	(segment
		(start 87.285068 -446.319656)
		(end 89.741248 -446.319656)
		(width 0.13462)
		(layer "B.Cu")
		(net "TDR_DIFF_85_BOT_DIN")
	)
	(segment
		(start 101.623368 -447.538856)
		(end 102.053136 -447.968624)
		(width 0.13462)
		(layer "B.Cu")
		(net "TDR_DIFF_85_BOT_DIN")
	)
	(segment
		(start 130.929888 -447.538856)
		(end 130.929888 -444.939928)
		(width 0.13462)
		(layer "B.Cu")
		(net "TDR_DIFF_85_BOT_DIN")
	)
	(segment
		(start 151.209248 -446.454276)
		(end 151.209248 -447.452496)
		(width 0.13462)
		(layer "B.Cu")
		(net "TDR_DIFF_85_BOT_DIN")
	)
	(segment
		(start 144.633696 -447.968624)
		(end 145.98396 -447.968624)
		(width 0.13462)
		(layer "B.Cu")
		(net "TDR_DIFF_85_BOT_DIN")
	)
	(segment
		(start 143.934688 -444.670688)
		(end 144.203928 -444.939928)
		(width 0.13462)
		(layer "B.Cu")
		(net "TDR_DIFF_85_BOT_DIN")
	)
	(segment
		(start 142.113 -447.968624)
		(end 142.542768 -447.538856)
		(width 0.13462)
		(layer "B.Cu")
		(net "TDR_DIFF_85_BOT_DIN")
	)
	(segment
		(start 122.7582 -447.968624)
		(end 123.187968 -447.538856)
		(width 0.13462)
		(layer "B.Cu")
		(net "TDR_DIFF_85_BOT_DIN")
	)
	(segment
		(start 136.891776 -447.968624)
		(end 138.24204 -447.968624)
		(width 0.13462)
		(layer "B.Cu")
		(net "TDR_DIFF_85_BOT_DIN")
	)
	(segment
		(start 89.741248 -446.319656)
		(end 90.010488 -446.588896)
		(width 0.13462)
		(layer "B.Cu")
		(net "TDR_DIFF_85_BOT_DIN")
	)
	(segment
		(start 117.536976 -447.968624)
		(end 118.88724 -447.968624)
		(width 0.13462)
		(layer "B.Cu")
		(net "TDR_DIFF_85_BOT_DIN")
	)
	(segment
		(start 124.849128 -447.538856)
		(end 125.278896 -447.968624)
		(width 0.13462)
		(layer "B.Cu")
		(net "TDR_DIFF_85_BOT_DIN")
	)
	(segment
		(start 87.150448 -446.454276)
		(end 87.285068 -446.319656)
		(width 0.13462)
		(layer "B.Cu")
		(net "TDR_DIFF_85_BOT_DIN")
	)
	(segment
		(start 135.070088 -444.670688)
		(end 136.192768 -444.670688)
		(width 0.13462)
		(layer "B.Cu")
		(net "TDR_DIFF_85_BOT_DIN")
	)
	(segment
		(start 111.575088 -447.538856)
		(end 111.575088 -444.939928)
		(width 0.13462)
		(layer "B.Cu")
		(net "TDR_DIFF_85_BOT_DIN")
	)
	(segment
		(start 138.671808 -447.538856)
		(end 138.671808 -444.939928)
		(width 0.13462)
		(layer "B.Cu")
		(net "TDR_DIFF_85_BOT_DIN")
	)
	(segment
		(start 113.236248 -444.939928)
		(end 113.236248 -447.538856)
		(width 0.13462)
		(layer "B.Cu")
		(net "TDR_DIFF_85_BOT_DIN")
	)
	(segment
		(start 145.237454 -438.862216)
		(end 145.732754 -439.357516)
		(width 0.1651)
		(layer "In7.Cu")
		(net "TDR_DIFF_85_IN2_DIP")
	)
	(segment
		(start 107.957874 -441.516008)
		(end 108.481114 -441.516008)
		(width 0.1651)
		(layer "In7.Cu")
		(net "TDR_DIFF_85_IN2_DIP")
	)
	(segment
		(start 142.801594 -441.185808)
		(end 143.131794 -441.516008)
		(width 0.1651)
		(layer "In7.Cu")
		(net "TDR_DIFF_85_IN2_DIP")
	)
	(segment
		(start 131.930394 -441.516008)
		(end 132.260594 -441.185808)
		(width 0.1651)
		(layer "In7.Cu")
		(net "TDR_DIFF_85_IN2_DIP")
	)
	(segment
		(start 119.352314 -439.357516)
		(end 119.352314 -441.185808)
		(width 0.1651)
		(layer "In7.Cu")
		(net "TDR_DIFF_85_IN2_DIP")
	)
	(segment
		(start 94.155514 -441.185808)
		(end 94.155514 -439.357516)
		(width 0.1651)
		(layer "In7.Cu")
		(net "TDR_DIFF_85_IN2_DIP")
	)
	(segment
		(start 104.696514 -441.185808)
		(end 105.026714 -441.516008)
		(width 0.1651)
		(layer "In7.Cu")
		(net "TDR_DIFF_85_IN2_DIP")
	)
	(segment
		(start 120.535954 -441.185808)
		(end 120.535954 -439.357516)
		(width 0.1651)
		(layer "In7.Cu")
		(net "TDR_DIFF_85_IN2_DIP")
	)
	(segment
		(start 87.194644 -439.060082)
		(end 87.194644 -440.024012)
		(width 0.1651)
		(layer "In7.Cu")
		(net "TDR_DIFF_85_IN2_DIP")
	)
	(segment
		(start 136.939274 -441.185808)
		(end 137.269474 -441.516008)
		(width 0.1651)
		(layer "In7.Cu")
		(net "TDR_DIFF_85_IN2_DIP")
	)
	(segment
		(start 148.994114 -440.189112)
		(end 151.062944 -440.189112)
		(width 0.1651)
		(layer "In7.Cu")
		(net "TDR_DIFF_85_IN2_DIP")
	)
	(segment
		(start 143.131794 -441.516008)
		(end 143.655034 -441.516008)
		(width 0.1651)
		(layer "In7.Cu")
		(net "TDR_DIFF_85_IN2_DIP")
	)
	(segment
		(start 111.742474 -441.185808)
		(end 111.742474 -439.357516)
		(width 0.1651)
		(layer "In7.Cu")
		(net "TDR_DIFF_85_IN2_DIP")
	)
	(segment
		(start 91.224354 -441.185808)
		(end 91.224354 -439.357516)
		(width 0.1651)
		(layer "In7.Cu")
		(net "TDR_DIFF_85_IN2_DIP")
	)
	(segment
		(start 90.040714 -441.185808)
		(end 90.370914 -441.516008)
		(width 0.1651)
		(layer "In7.Cu")
		(net "TDR_DIFF_85_IN2_DIP")
	)
	(segment
		(start 143.655034 -441.516008)
		(end 143.985234 -441.185808)
		(width 0.1651)
		(layer "In7.Cu")
		(net "TDR_DIFF_85_IN2_DIP")
	)
	(segment
		(start 108.811314 -441.185808)
		(end 108.811314 -439.357516)
		(width 0.1651)
		(layer "In7.Cu")
		(net "TDR_DIFF_85_IN2_DIP")
	)
	(segment
		(start 128.475994 -441.516008)
		(end 128.999234 -441.516008)
		(width 0.1651)
		(layer "In7.Cu")
		(net "TDR_DIFF_85_IN2_DIP")
	)
	(segment
		(start 108.481114 -441.516008)
		(end 108.811314 -441.185808)
		(width 0.1651)
		(layer "In7.Cu")
		(net "TDR_DIFF_85_IN2_DIP")
	)
	(segment
		(start 129.824734 -438.862216)
		(end 130.581654 -438.862216)
		(width 0.1651)
		(layer "In7.Cu")
		(net "TDR_DIFF_85_IN2_DIP")
	)
	(segment
		(start 146.916394 -441.185808)
		(end 146.916394 -439.357516)
		(width 0.1651)
		(layer "In7.Cu")
		(net "TDR_DIFF_85_IN2_DIP")
	)
	(segment
		(start 113.820194 -441.516008)
		(end 114.343434 -441.516008)
		(width 0.1651)
		(layer "In7.Cu")
		(net "TDR_DIFF_85_IN2_DIP")
	)
	(segment
		(start 115.925854 -438.862216)
		(end 116.421154 -439.357516)
		(width 0.1651)
		(layer "In7.Cu")
		(net "TDR_DIFF_85_IN2_DIP")
	)
	(segment
		(start 103.444294 -438.862216)
		(end 104.201214 -438.862216)
		(width 0.1651)
		(layer "In7.Cu")
		(net "TDR_DIFF_85_IN2_DIP")
	)
	(segment
		(start 135.687054 -438.862216)
		(end 136.443974 -438.862216)
		(width 0.1651)
		(layer "In7.Cu")
		(net "TDR_DIFF_85_IN2_DIP")
	)
	(segment
		(start 95.407734 -438.862216)
		(end 95.903034 -439.357516)
		(width 0.1651)
		(layer "In7.Cu")
		(net "TDR_DIFF_85_IN2_DIP")
	)
	(segment
		(start 135.191754 -441.185808)
		(end 135.191754 -439.357516)
		(width 0.1651)
		(layer "In7.Cu")
		(net "TDR_DIFF_85_IN2_DIP")
	)
	(segment
		(start 127.650494 -438.862216)
		(end 128.145794 -439.357516)
		(width 0.1651)
		(layer "In7.Cu")
		(net "TDR_DIFF_85_IN2_DIP")
	)
	(segment
		(start 119.682514 -441.516008)
		(end 120.205754 -441.516008)
		(width 0.1651)
		(layer "In7.Cu")
		(net "TDR_DIFF_85_IN2_DIP")
	)
	(segment
		(start 97.086674 -441.185808)
		(end 97.086674 -439.357516)
		(width 0.1651)
		(layer "In7.Cu")
		(net "TDR_DIFF_85_IN2_DIP")
	)
	(segment
		(start 90.894154 -441.516008)
		(end 91.224354 -441.185808)
		(width 0.1651)
		(layer "In7.Cu")
		(net "TDR_DIFF_85_IN2_DIP")
	)
	(segment
		(start 110.889034 -441.516008)
		(end 111.412274 -441.516008)
		(width 0.1651)
		(layer "In7.Cu")
		(net "TDR_DIFF_85_IN2_DIP")
	)
	(segment
		(start 139.870434 -439.357516)
		(end 139.870434 -441.185808)
		(width 0.1651)
		(layer "In7.Cu")
		(net "TDR_DIFF_85_IN2_DIP")
	)
	(segment
		(start 131.407154 -441.516008)
		(end 131.930394 -441.516008)
		(width 0.1651)
		(layer "In7.Cu")
		(net "TDR_DIFF_85_IN2_DIP")
	)
	(segment
		(start 141.549374 -438.862216)
		(end 142.306294 -438.862216)
		(width 0.1651)
		(layer "In7.Cu")
		(net "TDR_DIFF_85_IN2_DIP")
	)
	(segment
		(start 134.008114 -439.357516)
		(end 134.008114 -441.185808)
		(width 0.1651)
		(layer "In7.Cu")
		(net "TDR_DIFF_85_IN2_DIP")
	)
	(segment
		(start 101.765354 -441.185808)
		(end 102.095554 -441.516008)
		(width 0.1651)
		(layer "In7.Cu")
		(net "TDR_DIFF_85_IN2_DIP")
	)
	(segment
		(start 123.467114 -439.357516)
		(end 123.962414 -438.862216)
		(width 0.1651)
		(layer "In7.Cu")
		(net "TDR_DIFF_85_IN2_DIP")
	)
	(segment
		(start 92.971874 -441.185808)
		(end 93.302074 -441.516008)
		(width 0.1651)
		(layer "In7.Cu")
		(net "TDR_DIFF_85_IN2_DIP")
	)
	(segment
		(start 114.673634 -439.357516)
		(end 115.168934 -438.862216)
		(width 0.1651)
		(layer "In7.Cu")
		(net "TDR_DIFF_85_IN2_DIP")
	)
	(segment
		(start 138.122914 -439.357516)
		(end 138.618214 -438.862216)
		(width 0.1651)
		(layer "In7.Cu")
		(net "TDR_DIFF_85_IN2_DIP")
	)
	(segment
		(start 116.421154 -441.185808)
		(end 116.751354 -441.516008)
		(width 0.1651)
		(layer "In7.Cu")
		(net "TDR_DIFF_85_IN2_DIP")
	)
	(segment
		(start 134.338314 -441.516008)
		(end 134.861554 -441.516008)
		(width 0.1651)
		(layer "In7.Cu")
		(net "TDR_DIFF_85_IN2_DIP")
	)
	(segment
		(start 93.302074 -441.516008)
		(end 93.825314 -441.516008)
		(width 0.1651)
		(layer "In7.Cu")
		(net "TDR_DIFF_85_IN2_DIP")
	)
	(segment
		(start 118.100094 -438.862216)
		(end 118.857014 -438.862216)
		(width 0.1651)
		(layer "In7.Cu")
		(net "TDR_DIFF_85_IN2_DIP")
	)
	(segment
		(start 122.283474 -441.185808)
		(end 122.613674 -441.516008)
		(width 0.1651)
		(layer "In7.Cu")
		(net "TDR_DIFF_85_IN2_DIP")
	)
	(segment
		(start 137.792714 -441.516008)
		(end 138.122914 -441.185808)
		(width 0.1651)
		(layer "In7.Cu")
		(net "TDR_DIFF_85_IN2_DIP")
	)
	(segment
		(start 120.535954 -439.357516)
		(end 121.031254 -438.862216)
		(width 0.1651)
		(layer "In7.Cu")
		(net "TDR_DIFF_85_IN2_DIP")
	)
	(segment
		(start 133.512814 -438.862216)
		(end 134.008114 -439.357516)
		(width 0.1651)
		(layer "In7.Cu")
		(net "TDR_DIFF_85_IN2_DIP")
	)
	(segment
		(start 119.352314 -441.185808)
		(end 119.682514 -441.516008)
		(width 0.1651)
		(layer "In7.Cu")
		(net "TDR_DIFF_85_IN2_DIP")
	)
	(segment
		(start 139.375134 -438.862216)
		(end 139.870434 -439.357516)
		(width 0.1651)
		(layer "In7.Cu")
		(net "TDR_DIFF_85_IN2_DIP")
	)
	(segment
		(start 120.205754 -441.516008)
		(end 120.535954 -441.185808)
		(width 0.1651)
		(layer "In7.Cu")
		(net "TDR_DIFF_85_IN2_DIP")
	)
	(segment
		(start 116.421154 -439.357516)
		(end 116.421154 -441.185808)
		(width 0.1651)
		(layer "In7.Cu")
		(net "TDR_DIFF_85_IN2_DIP")
	)
	(segment
		(start 105.549954 -441.516008)
		(end 105.880154 -441.185808)
		(width 0.1651)
		(layer "In7.Cu")
		(net "TDR_DIFF_85_IN2_DIP")
	)
	(segment
		(start 115.168934 -438.862216)
		(end 115.925854 -438.862216)
		(width 0.1651)
		(layer "In7.Cu")
		(net "TDR_DIFF_85_IN2_DIP")
	)
	(segment
		(start 90.370914 -441.516008)
		(end 90.894154 -441.516008)
		(width 0.1651)
		(layer "In7.Cu")
		(net "TDR_DIFF_85_IN2_DIP")
	)
	(segment
		(start 94.650814 -438.862216)
		(end 95.407734 -438.862216)
		(width 0.1651)
		(layer "In7.Cu")
		(net "TDR_DIFF_85_IN2_DIP")
	)
	(segment
		(start 117.274594 -441.516008)
		(end 117.604794 -441.185808)
		(width 0.1651)
		(layer "In7.Cu")
		(net "TDR_DIFF_85_IN2_DIP")
	)
	(segment
		(start 113.489994 -441.185808)
		(end 113.820194 -441.516008)
		(width 0.1651)
		(layer "In7.Cu")
		(net "TDR_DIFF_85_IN2_DIP")
	)
	(segment
		(start 125.214634 -439.357516)
		(end 125.214634 -441.185808)
		(width 0.1651)
		(layer "In7.Cu")
		(net "TDR_DIFF_85_IN2_DIP")
	)
	(segment
		(start 126.398274 -441.185808)
		(end 126.398274 -439.357516)
		(width 0.1651)
		(layer "In7.Cu")
		(net "TDR_DIFF_85_IN2_DIP")
	)
	(segment
		(start 95.903034 -441.185808)
		(end 96.233234 -441.516008)
		(width 0.1651)
		(layer "In7.Cu")
		(net "TDR_DIFF_85_IN2_DIP")
	)
	(segment
		(start 121.788174 -438.862216)
		(end 122.283474 -439.357516)
		(width 0.1651)
		(layer "In7.Cu")
		(net "TDR_DIFF_85_IN2_DIP")
	)
	(segment
		(start 143.985234 -441.185808)
		(end 143.985234 -439.357516)
		(width 0.1651)
		(layer "In7.Cu")
		(net "TDR_DIFF_85_IN2_DIP")
	)
	(segment
		(start 92.476574 -438.862216)
		(end 92.971874 -439.357516)
		(width 0.1651)
		(layer "In7.Cu")
		(net "TDR_DIFF_85_IN2_DIP")
	)
	(segment
		(start 132.755894 -438.862216)
		(end 133.512814 -438.862216)
		(width 0.1651)
		(layer "In7.Cu")
		(net "TDR_DIFF_85_IN2_DIP")
	)
	(segment
		(start 102.948994 -439.357516)
		(end 103.444294 -438.862216)
		(width 0.1651)
		(layer "In7.Cu")
		(net "TDR_DIFF_85_IN2_DIP")
	)
	(segment
		(start 114.673634 -441.185808)
		(end 114.673634 -439.357516)
		(width 0.1651)
		(layer "In7.Cu")
		(net "TDR_DIFF_85_IN2_DIP")
	)
	(segment
		(start 93.825314 -441.516008)
		(end 94.155514 -441.185808)
		(width 0.1651)
		(layer "In7.Cu")
		(net "TDR_DIFF_85_IN2_DIP")
	)
	(segment
		(start 107.627674 -439.357516)
		(end 107.627674 -441.185808)
		(width 0.1651)
		(layer "In7.Cu")
		(net "TDR_DIFF_85_IN2_DIP")
	)
	(segment
		(start 122.613674 -441.516008)
		(end 123.136914 -441.516008)
		(width 0.1651)
		(layer "In7.Cu")
		(net "TDR_DIFF_85_IN2_DIP")
	)
	(segment
		(start 91.719654 -438.862216)
		(end 92.476574 -438.862216)
		(width 0.1651)
		(layer "In7.Cu")
		(net "TDR_DIFF_85_IN2_DIP")
	)
	(segment
		(start 101.765354 -439.357516)
		(end 101.765354 -441.185808)
		(width 0.1651)
		(layer "In7.Cu")
		(net "TDR_DIFF_85_IN2_DIP")
	)
	(segment
		(start 106.375454 -438.862216)
		(end 107.132374 -438.862216)
		(width 0.1651)
		(layer "In7.Cu")
		(net "TDR_DIFF_85_IN2_DIP")
	)
	(segment
		(start 144.480534 -438.862216)
		(end 145.237454 -438.862216)
		(width 0.1651)
		(layer "In7.Cu")
		(net "TDR_DIFF_85_IN2_DIP")
	)
	(segment
		(start 146.916394 -439.357516)
		(end 147.411694 -438.862216)
		(width 0.1651)
		(layer "In7.Cu")
		(net "TDR_DIFF_85_IN2_DIP")
	)
	(segment
		(start 97.581974 -438.862216)
		(end 98.338894 -438.862216)
		(width 0.1651)
		(layer "In7.Cu")
		(net "TDR_DIFF_85_IN2_DIP")
	)
	(segment
		(start 89.545414 -440.189112)
		(end 90.040714 -440.684412)
		(width 0.1651)
		(layer "In7.Cu")
		(net "TDR_DIFF_85_IN2_DIP")
	)
	(segment
		(start 111.412274 -441.516008)
		(end 111.742474 -441.185808)
		(width 0.1651)
		(layer "In7.Cu")
		(net "TDR_DIFF_85_IN2_DIP")
	)
	(segment
		(start 126.398274 -439.357516)
		(end 126.893574 -438.862216)
		(width 0.1651)
		(layer "In7.Cu")
		(net "TDR_DIFF_85_IN2_DIP")
	)
	(segment
		(start 99.164394 -441.516008)
		(end 99.687634 -441.516008)
		(width 0.1651)
		(layer "In7.Cu")
		(net "TDR_DIFF_85_IN2_DIP")
	)
	(segment
		(start 128.999234 -441.516008)
		(end 129.329434 -441.185808)
		(width 0.1651)
		(layer "In7.Cu")
		(net "TDR_DIFF_85_IN2_DIP")
	)
	(segment
		(start 145.732754 -439.357516)
		(end 145.732754 -441.185808)
		(width 0.1651)
		(layer "In7.Cu")
		(net "TDR_DIFF_85_IN2_DIP")
	)
	(segment
		(start 125.544834 -441.516008)
		(end 126.068074 -441.516008)
		(width 0.1651)
		(layer "In7.Cu")
		(net "TDR_DIFF_85_IN2_DIP")
	)
	(segment
		(start 107.132374 -438.862216)
		(end 107.627674 -439.357516)
		(width 0.1651)
		(layer "In7.Cu")
		(net "TDR_DIFF_85_IN2_DIP")
	)
	(segment
		(start 97.086674 -439.357516)
		(end 97.581974 -438.862216)
		(width 0.1651)
		(layer "In7.Cu")
		(net "TDR_DIFF_85_IN2_DIP")
	)
	(segment
		(start 105.880154 -441.185808)
		(end 105.880154 -439.357516)
		(width 0.1651)
		(layer "In7.Cu")
		(net "TDR_DIFF_85_IN2_DIP")
	)
	(segment
		(start 92.971874 -439.357516)
		(end 92.971874 -441.185808)
		(width 0.1651)
		(layer "In7.Cu")
		(net "TDR_DIFF_85_IN2_DIP")
	)
	(segment
		(start 147.411694 -438.862216)
		(end 148.168614 -438.862216)
		(width 0.1651)
		(layer "In7.Cu")
		(net "TDR_DIFF_85_IN2_DIP")
	)
	(segment
		(start 131.076954 -439.357516)
		(end 131.076954 -441.185808)
		(width 0.1651)
		(layer "In7.Cu")
		(net "TDR_DIFF_85_IN2_DIP")
	)
	(segment
		(start 110.558834 -441.185808)
		(end 110.889034 -441.516008)
		(width 0.1651)
		(layer "In7.Cu")
		(net "TDR_DIFF_85_IN2_DIP")
	)
	(segment
		(start 87.194644 -440.024012)
		(end 87.359744 -440.189112)
		(width 0.1651)
		(layer "In7.Cu")
		(net "TDR_DIFF_85_IN2_DIP")
	)
	(segment
		(start 94.155514 -439.357516)
		(end 94.650814 -438.862216)
		(width 0.1651)
		(layer "In7.Cu")
		(net "TDR_DIFF_85_IN2_DIP")
	)
	(segment
		(start 131.076954 -441.185808)
		(end 131.407154 -441.516008)
		(width 0.1651)
		(layer "In7.Cu")
		(net "TDR_DIFF_85_IN2_DIP")
	)
	(segment
		(start 101.270054 -438.862216)
		(end 101.765354 -439.357516)
		(width 0.1651)
		(layer "In7.Cu")
		(net "TDR_DIFF_85_IN2_DIP")
	)
	(segment
		(start 99.687634 -441.516008)
		(end 100.017834 -441.185808)
		(width 0.1651)
		(layer "In7.Cu")
		(net "TDR_DIFF_85_IN2_DIP")
	)
	(segment
		(start 134.861554 -441.516008)
		(end 135.191754 -441.185808)
		(width 0.1651)
		(layer "In7.Cu")
		(net "TDR_DIFF_85_IN2_DIP")
	)
	(segment
		(start 107.627674 -441.185808)
		(end 107.957874 -441.516008)
		(width 0.1651)
		(layer "In7.Cu")
		(net "TDR_DIFF_85_IN2_DIP")
	)
	(segment
		(start 124.719334 -438.862216)
		(end 125.214634 -439.357516)
		(width 0.1651)
		(layer "In7.Cu")
		(net "TDR_DIFF_85_IN2_DIP")
	)
	(segment
		(start 95.903034 -439.357516)
		(end 95.903034 -441.185808)
		(width 0.1651)
		(layer "In7.Cu")
		(net "TDR_DIFF_85_IN2_DIP")
	)
	(segment
		(start 87.359744 -440.189112)
		(end 89.545414 -440.189112)
		(width 0.1651)
		(layer "In7.Cu")
		(net "TDR_DIFF_85_IN2_DIP")
	)
	(segment
		(start 140.200634 -441.516008)
		(end 140.723874 -441.516008)
		(width 0.1651)
		(layer "In7.Cu")
		(net "TDR_DIFF_85_IN2_DIP")
	)
	(segment
		(start 123.962414 -438.862216)
		(end 124.719334 -438.862216)
		(width 0.1651)
		(layer "In7.Cu")
		(net "TDR_DIFF_85_IN2_DIP")
	)
	(segment
		(start 102.618794 -441.516008)
		(end 102.948994 -441.185808)
		(width 0.1651)
		(layer "In7.Cu")
		(net "TDR_DIFF_85_IN2_DIP")
	)
	(segment
		(start 138.618214 -438.862216)
		(end 139.375134 -438.862216)
		(width 0.1651)
		(layer "In7.Cu")
		(net "TDR_DIFF_85_IN2_DIP")
	)
	(segment
		(start 123.136914 -441.516008)
		(end 123.467114 -441.185808)
		(width 0.1651)
		(layer "In7.Cu")
		(net "TDR_DIFF_85_IN2_DIP")
	)
	(segment
		(start 129.329434 -441.185808)
		(end 129.329434 -439.357516)
		(width 0.1651)
		(layer "In7.Cu")
		(net "TDR_DIFF_85_IN2_DIP")
	)
	(segment
		(start 118.857014 -438.862216)
		(end 119.352314 -439.357516)
		(width 0.1651)
		(layer "In7.Cu")
		(net "TDR_DIFF_85_IN2_DIP")
	)
	(segment
		(start 151.062944 -440.189112)
		(end 151.228044 -440.024012)
		(width 0.1651)
		(layer "In7.Cu")
		(net "TDR_DIFF_85_IN2_DIP")
	)
	(segment
		(start 98.834194 -441.185808)
		(end 99.164394 -441.516008)
		(width 0.1651)
		(layer "In7.Cu")
		(net "TDR_DIFF_85_IN2_DIP")
	)
	(segment
		(start 126.893574 -438.862216)
		(end 127.650494 -438.862216)
		(width 0.1651)
		(layer "In7.Cu")
		(net "TDR_DIFF_85_IN2_DIP")
	)
	(segment
		(start 136.939274 -439.357516)
		(end 136.939274 -441.185808)
		(width 0.1651)
		(layer "In7.Cu")
		(net "TDR_DIFF_85_IN2_DIP")
	)
	(segment
		(start 100.017834 -439.357516)
		(end 100.513134 -438.862216)
		(width 0.1651)
		(layer "In7.Cu")
		(net "TDR_DIFF_85_IN2_DIP")
	)
	(segment
		(start 122.283474 -439.357516)
		(end 122.283474 -441.185808)
		(width 0.1651)
		(layer "In7.Cu")
		(net "TDR_DIFF_85_IN2_DIP")
	)
	(segment
		(start 100.017834 -441.185808)
		(end 100.017834 -439.357516)
		(width 0.1651)
		(layer "In7.Cu")
		(net "TDR_DIFF_85_IN2_DIP")
	)
	(segment
		(start 141.054074 -439.357516)
		(end 141.549374 -438.862216)
		(width 0.1651)
		(layer "In7.Cu")
		(net "TDR_DIFF_85_IN2_DIP")
	)
	(segment
		(start 136.443974 -438.862216)
		(end 136.939274 -439.357516)
		(width 0.1651)
		(layer "In7.Cu")
		(net "TDR_DIFF_85_IN2_DIP")
	)
	(segment
		(start 110.558834 -439.357516)
		(end 110.558834 -441.185808)
		(width 0.1651)
		(layer "In7.Cu")
		(net "TDR_DIFF_85_IN2_DIP")
	)
	(segment
		(start 151.228044 -440.024012)
		(end 151.228044 -439.060082)
		(width 0.1651)
		(layer "In7.Cu")
		(net "TDR_DIFF_85_IN2_DIP")
	)
	(segment
		(start 108.811314 -439.357516)
		(end 109.306614 -438.862216)
		(width 0.1651)
		(layer "In7.Cu")
		(net "TDR_DIFF_85_IN2_DIP")
	)
	(segment
		(start 140.723874 -441.516008)
		(end 141.054074 -441.185808)
		(width 0.1651)
		(layer "In7.Cu")
		(net "TDR_DIFF_85_IN2_DIP")
	)
	(segment
		(start 145.732754 -441.185808)
		(end 146.062954 -441.516008)
		(width 0.1651)
		(layer "In7.Cu")
		(net "TDR_DIFF_85_IN2_DIP")
	)
	(segment
		(start 96.756474 -441.516008)
		(end 97.086674 -441.185808)
		(width 0.1651)
		(layer "In7.Cu")
		(net "TDR_DIFF_85_IN2_DIP")
	)
	(segment
		(start 116.751354 -441.516008)
		(end 117.274594 -441.516008)
		(width 0.1651)
		(layer "In7.Cu")
		(net "TDR_DIFF_85_IN2_DIP")
	)
	(segment
		(start 148.663914 -439.858912)
		(end 148.994114 -440.189112)
		(width 0.1651)
		(layer "In7.Cu")
		(net "TDR_DIFF_85_IN2_DIP")
	)
	(segment
		(start 105.880154 -439.357516)
		(end 106.375454 -438.862216)
		(width 0.1651)
		(layer "In7.Cu")
		(net "TDR_DIFF_85_IN2_DIP")
	)
	(segment
		(start 98.338894 -438.862216)
		(end 98.834194 -439.357516)
		(width 0.1651)
		(layer "In7.Cu")
		(net "TDR_DIFF_85_IN2_DIP")
	)
	(segment
		(start 125.214634 -441.185808)
		(end 125.544834 -441.516008)
		(width 0.1651)
		(layer "In7.Cu")
		(net "TDR_DIFF_85_IN2_DIP")
	)
	(segment
		(start 146.586194 -441.516008)
		(end 146.916394 -441.185808)
		(width 0.1651)
		(layer "In7.Cu")
		(net "TDR_DIFF_85_IN2_DIP")
	)
	(segment
		(start 129.329434 -439.357516)
		(end 129.824734 -438.862216)
		(width 0.1651)
		(layer "In7.Cu")
		(net "TDR_DIFF_85_IN2_DIP")
	)
	(segment
		(start 123.467114 -441.185808)
		(end 123.467114 -439.357516)
		(width 0.1651)
		(layer "In7.Cu")
		(net "TDR_DIFF_85_IN2_DIP")
	)
	(segment
		(start 111.742474 -439.357516)
		(end 112.237774 -438.862216)
		(width 0.1651)
		(layer "In7.Cu")
		(net "TDR_DIFF_85_IN2_DIP")
	)
	(segment
		(start 98.834194 -439.357516)
		(end 98.834194 -441.185808)
		(width 0.1651)
		(layer "In7.Cu")
		(net "TDR_DIFF_85_IN2_DIP")
	)
	(segment
		(start 91.224354 -439.357516)
		(end 91.719654 -438.862216)
		(width 0.1651)
		(layer "In7.Cu")
		(net "TDR_DIFF_85_IN2_DIP")
	)
	(segment
		(start 139.870434 -441.185808)
		(end 140.200634 -441.516008)
		(width 0.1651)
		(layer "In7.Cu")
		(net "TDR_DIFF_85_IN2_DIP")
	)
	(segment
		(start 114.343434 -441.516008)
		(end 114.673634 -441.185808)
		(width 0.1651)
		(layer "In7.Cu")
		(net "TDR_DIFF_85_IN2_DIP")
	)
	(segment
		(start 134.008114 -441.185808)
		(end 134.338314 -441.516008)
		(width 0.1651)
		(layer "In7.Cu")
		(net "TDR_DIFF_85_IN2_DIP")
	)
	(segment
		(start 141.054074 -441.185808)
		(end 141.054074 -439.357516)
		(width 0.1651)
		(layer "In7.Cu")
		(net "TDR_DIFF_85_IN2_DIP")
	)
	(segment
		(start 142.306294 -438.862216)
		(end 142.801594 -439.357516)
		(width 0.1651)
		(layer "In7.Cu")
		(net "TDR_DIFF_85_IN2_DIP")
	)
	(segment
		(start 138.122914 -441.185808)
		(end 138.122914 -439.357516)
		(width 0.1651)
		(layer "In7.Cu")
		(net "TDR_DIFF_85_IN2_DIP")
	)
	(segment
		(start 104.201214 -438.862216)
		(end 104.696514 -439.357516)
		(width 0.1651)
		(layer "In7.Cu")
		(net "TDR_DIFF_85_IN2_DIP")
	)
	(segment
		(start 96.233234 -441.516008)
		(end 96.756474 -441.516008)
		(width 0.1651)
		(layer "In7.Cu")
		(net "TDR_DIFF_85_IN2_DIP")
	)
	(segment
		(start 148.168614 -438.862216)
		(end 148.663914 -439.357516)
		(width 0.1651)
		(layer "In7.Cu")
		(net "TDR_DIFF_85_IN2_DIP")
	)
	(segment
		(start 126.068074 -441.516008)
		(end 126.398274 -441.185808)
		(width 0.1651)
		(layer "In7.Cu")
		(net "TDR_DIFF_85_IN2_DIP")
	)
	(segment
		(start 135.191754 -439.357516)
		(end 135.687054 -438.862216)
		(width 0.1651)
		(layer "In7.Cu")
		(net "TDR_DIFF_85_IN2_DIP")
	)
	(segment
		(start 137.269474 -441.516008)
		(end 137.792714 -441.516008)
		(width 0.1651)
		(layer "In7.Cu")
		(net "TDR_DIFF_85_IN2_DIP")
	)
	(segment
		(start 143.985234 -439.357516)
		(end 144.480534 -438.862216)
		(width 0.1651)
		(layer "In7.Cu")
		(net "TDR_DIFF_85_IN2_DIP")
	)
	(segment
		(start 112.994694 -438.862216)
		(end 113.489994 -439.357516)
		(width 0.1651)
		(layer "In7.Cu")
		(net "TDR_DIFF_85_IN2_DIP")
	)
	(segment
		(start 102.095554 -441.516008)
		(end 102.618794 -441.516008)
		(width 0.1651)
		(layer "In7.Cu")
		(net "TDR_DIFF_85_IN2_DIP")
	)
	(segment
		(start 104.696514 -439.357516)
		(end 104.696514 -441.185808)
		(width 0.1651)
		(layer "In7.Cu")
		(net "TDR_DIFF_85_IN2_DIP")
	)
	(segment
		(start 117.604794 -441.185808)
		(end 117.604794 -439.357516)
		(width 0.1651)
		(layer "In7.Cu")
		(net "TDR_DIFF_85_IN2_DIP")
	)
	(segment
		(start 132.260594 -441.185808)
		(end 132.260594 -439.357516)
		(width 0.1651)
		(layer "In7.Cu")
		(net "TDR_DIFF_85_IN2_DIP")
	)
	(segment
		(start 130.581654 -438.862216)
		(end 131.076954 -439.357516)
		(width 0.1651)
		(layer "In7.Cu")
		(net "TDR_DIFF_85_IN2_DIP")
	)
	(segment
		(start 142.801594 -439.357516)
		(end 142.801594 -441.185808)
		(width 0.1651)
		(layer "In7.Cu")
		(net "TDR_DIFF_85_IN2_DIP")
	)
	(segment
		(start 146.062954 -441.516008)
		(end 146.586194 -441.516008)
		(width 0.1651)
		(layer "In7.Cu")
		(net "TDR_DIFF_85_IN2_DIP")
	)
	(segment
		(start 112.237774 -438.862216)
		(end 112.994694 -438.862216)
		(width 0.1651)
		(layer "In7.Cu")
		(net "TDR_DIFF_85_IN2_DIP")
	)
	(segment
		(start 128.145794 -439.357516)
		(end 128.145794 -441.185808)
		(width 0.1651)
		(layer "In7.Cu")
		(net "TDR_DIFF_85_IN2_DIP")
	)
	(segment
		(start 102.948994 -441.185808)
		(end 102.948994 -439.357516)
		(width 0.1651)
		(layer "In7.Cu")
		(net "TDR_DIFF_85_IN2_DIP")
	)
	(segment
		(start 117.604794 -439.357516)
		(end 118.100094 -438.862216)
		(width 0.1651)
		(layer "In7.Cu")
		(net "TDR_DIFF_85_IN2_DIP")
	)
	(segment
		(start 110.063534 -438.862216)
		(end 110.558834 -439.357516)
		(width 0.1651)
		(layer "In7.Cu")
		(net "TDR_DIFF_85_IN2_DIP")
	)
	(segment
		(start 128.145794 -441.185808)
		(end 128.475994 -441.516008)
		(width 0.1651)
		(layer "In7.Cu")
		(net "TDR_DIFF_85_IN2_DIP")
	)
	(segment
		(start 90.040714 -440.684412)
		(end 90.040714 -441.185808)
		(width 0.1651)
		(layer "In7.Cu")
		(net "TDR_DIFF_85_IN2_DIP")
	)
	(segment
		(start 132.260594 -439.357516)
		(end 132.755894 -438.862216)
		(width 0.1651)
		(layer "In7.Cu")
		(net "TDR_DIFF_85_IN2_DIP")
	)
	(segment
		(start 113.489994 -439.357516)
		(end 113.489994 -441.185808)
		(width 0.1651)
		(layer "In7.Cu")
		(net "TDR_DIFF_85_IN2_DIP")
	)
	(segment
		(start 105.026714 -441.516008)
		(end 105.549954 -441.516008)
		(width 0.1651)
		(layer "In7.Cu")
		(net "TDR_DIFF_85_IN2_DIP")
	)
	(segment
		(start 121.031254 -438.862216)
		(end 121.788174 -438.862216)
		(width 0.1651)
		(layer "In7.Cu")
		(net "TDR_DIFF_85_IN2_DIP")
	)
	(segment
		(start 148.663914 -439.357516)
		(end 148.663914 -439.858912)
		(width 0.1651)
		(layer "In7.Cu")
		(net "TDR_DIFF_85_IN2_DIP")
	)
	(segment
		(start 109.306614 -438.862216)
		(end 110.063534 -438.862216)
		(width 0.1651)
		(layer "In7.Cu")
		(net "TDR_DIFF_85_IN2_DIP")
	)
	(segment
		(start 100.513134 -438.862216)
		(end 101.270054 -438.862216)
		(width 0.1651)
		(layer "In7.Cu")
		(net "TDR_DIFF_85_IN2_DIP")
	)
	(segment
		(start 12.067794 -307.481732)
		(end 12.405868 -307.621686)
		(width 0.13208)
		(layer "F.Cu")
		(net "P1V25_PEX0_EN")
	)
	(segment
		(start 11.62177 -307.481732)
		(end 12.067794 -307.481732)
		(width 0.13208)
		(layer "F.Cu")
		(net "P1V25_PEX0_EN")
	)
	(segment
		(start 12.405868 -307.621686)
		(end 13.039344 -308.255162)
		(width 0.13208)
		(layer "F.Cu")
		(net "P1V25_PEX0_EN")
	)
	(segment
		(start 13.039344 -308.255162)
		(end 13.039344 -308.282086)
		(width 0.13208)
		(layer "F.Cu")
		(net "P1V25_PEX0_EN")
	)
	(via
		(at 12.405868 -307.621686)
		(size 0.508)
		(drill 0.254)
		(layers "F.Cu" "B.Cu")
		(net "P1V25_PEX0_EN")
	)
	(segment
		(start 16.025876 -306.731416)
		(end 15.58544 -307.171852)
		(width 0.254)
		(layer "F.Cu")
		(net "SH_P1V25_PEX0_FB_P")
	)
	(segment
		(start 15.58544 -307.171852)
		(end 15.58544 -307.26888)
		(width 0.254)
		(layer "F.Cu")
		(net "SH_P1V25_PEX0_FB_P")
	)
	(segment
		(start 15.84452 -305.953668)
		(end 15.59052 -306.207668)
		(width 0.254)
		(layer "F.Cu")
		(net "SH_P1V25_PEX0_FB_P")
	)
	(segment
		(start 15.59052 -306.29606)
		(end 16.025876 -306.731416)
		(width 0.254)
		(layer "F.Cu")
		(net "SH_P1V25_PEX0_FB_P")
	)
	(segment
		(start 15.58544 -307.26888)
		(end 15.58544 -308.28488)
		(width 0.254)
		(layer "F.Cu")
		(net "SH_P1V25_PEX0_FB_P")
	)
	(segment
		(start 15.59052 -306.207668)
		(end 15.59052 -306.208684)
		(width 0.254)
		(layer "F.Cu")
		(net "SH_P1V25_PEX0_FB_P")
	)
	(segment
		(start 15.59052 -306.208684)
		(end 15.59052 -306.29606)
		(width 0.254)
		(layer "F.Cu")
		(net "SH_P1V25_PEX0_FB_P")
	)
	(segment
		(start 16.270478 -305.953668)
		(end 15.84452 -305.953668)
		(width 0.254)
		(layer "F.Cu")
		(net "SH_P1V25_PEX0_FB_P")
	)
	(segment
		(start 16.606266 -306.28209)
		(end 16.270478 -305.953668)
		(width 0.254)
		(layer "F.Cu")
		(net "SH_P1V25_PEX0_FB_P")
	)
	(via
		(at 16.025876 -306.731416)
		(size 0.508)
		(drill 0.254)
		(layers "F.Cu" "B.Cu")
		(net "SH_P1V25_PEX0_FB_P")
	)
	(segment
		(start 28.601162 -452.82358)
		(end 29.096462 -453.31888)
		(width 0.1651)
		(layer "In15.Cu")
		(net "TDR_DIFF_85_IN6_DIP")
	)
	(segment
		(start 33.610042 -450.665088)
		(end 34.133282 -450.665088)
		(width 0.1651)
		(layer "In15.Cu")
		(net "TDR_DIFF_85_IN6_DIP")
	)
	(segment
		(start 49.119282 -450.995288)
		(end 49.119282 -452.82358)
		(width 0.1651)
		(layer "In15.Cu")
		(net "TDR_DIFF_85_IN6_DIP")
	)
	(segment
		(start 45.004482 -450.995288)
		(end 45.334682 -450.665088)
		(width 0.1651)
		(layer "In15.Cu")
		(net "TDR_DIFF_85_IN6_DIP")
	)
	(segment
		(start 60.843922 -452.82358)
		(end 61.339222 -453.31888)
		(width 0.1651)
		(layer "In15.Cu")
		(net "TDR_DIFF_85_IN6_DIP")
	)
	(segment
		(start 45.004482 -452.82358)
		(end 45.004482 -450.995288)
		(width 0.1651)
		(layer "In15.Cu")
		(net "TDR_DIFF_85_IN6_DIP")
	)
	(segment
		(start 35.715702 -453.31888)
		(end 36.211002 -452.82358)
		(width 0.1651)
		(layer "In15.Cu")
		(net "TDR_DIFF_85_IN6_DIP")
	)
	(segment
		(start 36.211002 -450.995288)
		(end 36.541202 -450.665088)
		(width 0.1651)
		(layer "In15.Cu")
		(net "TDR_DIFF_85_IN6_DIP")
	)
	(segment
		(start 24.486362 -450.995288)
		(end 24.816562 -450.665088)
		(width 0.1651)
		(layer "In15.Cu")
		(net "TDR_DIFF_85_IN6_DIP")
	)
	(segment
		(start 46.683422 -453.31888)
		(end 47.440342 -453.31888)
		(width 0.1651)
		(layer "In15.Cu")
		(net "TDR_DIFF_85_IN6_DIP")
	)
	(segment
		(start 57.582562 -450.665088)
		(end 57.912762 -450.995288)
		(width 0.1651)
		(layer "In15.Cu")
		(net "TDR_DIFF_85_IN6_DIP")
	)
	(segment
		(start 19.807682 -452.82358)
		(end 20.302982 -453.31888)
		(width 0.1651)
		(layer "In15.Cu")
		(net "TDR_DIFF_85_IN6_DIP")
	)
	(segment
		(start 29.096462 -453.31888)
		(end 29.853382 -453.31888)
		(width 0.1651)
		(layer "In15.Cu")
		(net "TDR_DIFF_85_IN6_DIP")
	)
	(segment
		(start 61.339222 -453.31888)
		(end 62.096142 -453.31888)
		(width 0.1651)
		(layer "In15.Cu")
		(net "TDR_DIFF_85_IN6_DIP")
	)
	(segment
		(start 25.339802 -450.665088)
		(end 25.670002 -450.995288)
		(width 0.1651)
		(layer "In15.Cu")
		(net "TDR_DIFF_85_IN6_DIP")
	)
	(segment
		(start 31.532322 -452.82358)
		(end 32.027622 -453.31888)
		(width 0.1651)
		(layer "In15.Cu")
		(net "TDR_DIFF_85_IN6_DIP")
	)
	(segment
		(start 71.384922 -452.82358)
		(end 71.384922 -450.995288)
		(width 0.1651)
		(layer "In15.Cu")
		(net "TDR_DIFF_85_IN6_DIP")
	)
	(segment
		(start 33.279842 -452.82358)
		(end 33.279842 -450.995288)
		(width 0.1651)
		(layer "In15.Cu")
		(net "TDR_DIFF_85_IN6_DIP")
	)
	(segment
		(start 39.472362 -450.665088)
		(end 39.995602 -450.665088)
		(width 0.1651)
		(layer "In15.Cu")
		(net "TDR_DIFF_85_IN6_DIP")
	)
	(segment
		(start 55.476902 -453.31888)
		(end 56.233822 -453.31888)
		(width 0.1651)
		(layer "In15.Cu")
		(net "TDR_DIFF_85_IN6_DIP")
	)
	(segment
		(start 69.307202 -450.665088)
		(end 69.637402 -450.995288)
		(width 0.1651)
		(layer "In15.Cu")
		(net "TDR_DIFF_85_IN6_DIP")
	)
	(segment
		(start 47.935642 -452.82358)
		(end 47.935642 -450.995288)
		(width 0.1651)
		(layer "In15.Cu")
		(net "TDR_DIFF_85_IN6_DIP")
	)
	(segment
		(start 54.128162 -450.665088)
		(end 54.651402 -450.665088)
		(width 0.1651)
		(layer "In15.Cu")
		(net "TDR_DIFF_85_IN6_DIP")
	)
	(segment
		(start 59.660282 -452.82358)
		(end 59.660282 -450.995288)
		(width 0.1651)
		(layer "In15.Cu")
		(net "TDR_DIFF_85_IN6_DIP")
	)
	(segment
		(start 44.509182 -453.31888)
		(end 45.004482 -452.82358)
		(width 0.1651)
		(layer "In15.Cu")
		(net "TDR_DIFF_85_IN6_DIP")
	)
	(segment
		(start 56.729122 -450.995288)
		(end 57.059322 -450.665088)
		(width 0.1651)
		(layer "In15.Cu")
		(net "TDR_DIFF_85_IN6_DIP")
	)
	(segment
		(start 63.775082 -452.82358)
		(end 64.270382 -453.31888)
		(width 0.1651)
		(layer "In15.Cu")
		(net "TDR_DIFF_85_IN6_DIP")
	)
	(segment
		(start 21.885402 -450.665088)
		(end 22.408642 -450.665088)
		(width 0.1651)
		(layer "In15.Cu")
		(net "TDR_DIFF_85_IN6_DIP")
	)
	(segment
		(start 51.197002 -450.665088)
		(end 51.720242 -450.665088)
		(width 0.1651)
		(layer "In15.Cu")
		(net "TDR_DIFF_85_IN6_DIP")
	)
	(segment
		(start 19.807682 -450.995288)
		(end 19.807682 -452.82358)
		(width 0.1651)
		(layer "In15.Cu")
		(net "TDR_DIFF_85_IN6_DIP")
	)
	(segment
		(start 54.981602 -450.995288)
		(end 54.981602 -452.82358)
		(width 0.1651)
		(layer "In15.Cu")
		(net "TDR_DIFF_85_IN6_DIP")
	)
	(segment
		(start 43.752262 -453.31888)
		(end 44.509182 -453.31888)
		(width 0.1651)
		(layer "In15.Cu")
		(net "TDR_DIFF_85_IN6_DIP")
	)
	(segment
		(start 49.614582 -453.31888)
		(end 50.371502 -453.31888)
		(width 0.1651)
		(layer "In15.Cu")
		(net "TDR_DIFF_85_IN6_DIP")
	)
	(segment
		(start 65.027302 -453.31888)
		(end 65.522602 -452.82358)
		(width 0.1651)
		(layer "In15.Cu")
		(net "TDR_DIFF_85_IN6_DIP")
	)
	(segment
		(start 22.408642 -450.665088)
		(end 22.738842 -450.995288)
		(width 0.1651)
		(layer "In15.Cu")
		(net "TDR_DIFF_85_IN6_DIP")
	)
	(segment
		(start 23.234142 -453.31888)
		(end 23.991062 -453.31888)
		(width 0.1651)
		(layer "In15.Cu")
		(net "TDR_DIFF_85_IN6_DIP")
	)
	(segment
		(start 40.325802 -452.82358)
		(end 40.821102 -453.31888)
		(width 0.1651)
		(layer "In15.Cu")
		(net "TDR_DIFF_85_IN6_DIP")
	)
	(segment
		(start 21.555202 -450.995288)
		(end 21.885402 -450.665088)
		(width 0.1651)
		(layer "In15.Cu")
		(net "TDR_DIFF_85_IN6_DIP")
	)
	(segment
		(start 30.348682 -450.995288)
		(end 30.678882 -450.665088)
		(width 0.1651)
		(layer "In15.Cu")
		(net "TDR_DIFF_85_IN6_DIP")
	)
	(segment
		(start 72.568562 -450.995288)
		(end 72.568562 -452.82358)
		(width 0.1651)
		(layer "In15.Cu")
		(net "TDR_DIFF_85_IN6_DIP")
	)
	(segment
		(start 16.546322 -451.991984)
		(end 16.876522 -452.322184)
		(width 0.1651)
		(layer "In15.Cu")
		(net "TDR_DIFF_85_IN6_DIP")
	)
	(segment
		(start 37.064442 -450.665088)
		(end 37.394642 -450.995288)
		(width 0.1651)
		(layer "In15.Cu")
		(net "TDR_DIFF_85_IN6_DIP")
	)
	(segment
		(start 63.444882 -450.665088)
		(end 63.775082 -450.995288)
		(width 0.1651)
		(layer "In15.Cu")
		(net "TDR_DIFF_85_IN6_DIP")
	)
	(segment
		(start 54.651402 -450.665088)
		(end 54.981602 -450.995288)
		(width 0.1651)
		(layer "In15.Cu")
		(net "TDR_DIFF_85_IN6_DIP")
	)
	(segment
		(start 59.990482 -450.665088)
		(end 60.513722 -450.665088)
		(width 0.1651)
		(layer "In15.Cu")
		(net "TDR_DIFF_85_IN6_DIP")
	)
	(segment
		(start 32.784542 -453.31888)
		(end 33.279842 -452.82358)
		(width 0.1651)
		(layer "In15.Cu")
		(net "TDR_DIFF_85_IN6_DIP")
	)
	(segment
		(start 18.954242 -450.665088)
		(end 19.477482 -450.665088)
		(width 0.1651)
		(layer "In15.Cu")
		(net "TDR_DIFF_85_IN6_DIP")
	)
	(segment
		(start 53.302662 -453.31888)
		(end 53.797962 -452.82358)
		(width 0.1651)
		(layer "In15.Cu")
		(net "TDR_DIFF_85_IN6_DIP")
	)
	(segment
		(start 42.073322 -452.82358)
		(end 42.073322 -450.995288)
		(width 0.1651)
		(layer "In15.Cu")
		(net "TDR_DIFF_85_IN6_DIP")
	)
	(segment
		(start 65.852802 -450.665088)
		(end 66.376042 -450.665088)
		(width 0.1651)
		(layer "In15.Cu")
		(net "TDR_DIFF_85_IN6_DIP")
	)
	(segment
		(start 37.394642 -452.82358)
		(end 37.889942 -453.31888)
		(width 0.1651)
		(layer "In15.Cu")
		(net "TDR_DIFF_85_IN6_DIP")
	)
	(segment
		(start 69.637402 -452.82358)
		(end 70.132702 -453.31888)
		(width 0.1651)
		(layer "In15.Cu")
		(net "TDR_DIFF_85_IN6_DIP")
	)
	(segment
		(start 33.279842 -450.995288)
		(end 33.610042 -450.665088)
		(width 0.1651)
		(layer "In15.Cu")
		(net "TDR_DIFF_85_IN6_DIP")
	)
	(segment
		(start 75.169522 -450.665088)
		(end 75.499722 -450.995288)
		(width 0.1651)
		(layer "In15.Cu")
		(net "TDR_DIFF_85_IN6_DIP")
	)
	(segment
		(start 31.532322 -450.995288)
		(end 31.532322 -452.82358)
		(width 0.1651)
		(layer "In15.Cu")
		(net "TDR_DIFF_85_IN6_DIP")
	)
	(segment
		(start 69.637402 -450.995288)
		(end 69.637402 -452.82358)
		(width 0.1651)
		(layer "In15.Cu")
		(net "TDR_DIFF_85_IN6_DIP")
	)
	(segment
		(start 65.522602 -450.995288)
		(end 65.852802 -450.665088)
		(width 0.1651)
		(layer "In15.Cu")
		(net "TDR_DIFF_85_IN6_DIP")
	)
	(segment
		(start 23.991062 -453.31888)
		(end 24.486362 -452.82358)
		(width 0.1651)
		(layer "In15.Cu")
		(net "TDR_DIFF_85_IN6_DIP")
	)
	(segment
		(start 64.270382 -453.31888)
		(end 65.027302 -453.31888)
		(width 0.1651)
		(layer "In15.Cu")
		(net "TDR_DIFF_85_IN6_DIP")
	)
	(segment
		(start 28.270962 -450.665088)
		(end 28.601162 -450.995288)
		(width 0.1651)
		(layer "In15.Cu")
		(net "TDR_DIFF_85_IN6_DIP")
	)
	(segment
		(start 29.853382 -453.31888)
		(end 30.348682 -452.82358)
		(width 0.1651)
		(layer "In15.Cu")
		(net "TDR_DIFF_85_IN6_DIP")
	)
	(segment
		(start 71.384922 -450.995288)
		(end 71.715122 -450.665088)
		(width 0.1651)
		(layer "In15.Cu")
		(net "TDR_DIFF_85_IN6_DIP")
	)
	(segment
		(start 16.876522 -452.82358)
		(end 17.371822 -453.31888)
		(width 0.1651)
		(layer "In15.Cu")
		(net "TDR_DIFF_85_IN6_DIP")
	)
	(segment
		(start 21.555202 -452.82358)
		(end 21.555202 -450.995288)
		(width 0.1651)
		(layer "In15.Cu")
		(net "TDR_DIFF_85_IN6_DIP")
	)
	(segment
		(start 75.499722 -451.496684)
		(end 75.995022 -451.991984)
		(width 0.1651)
		(layer "In15.Cu")
		(net "TDR_DIFF_85_IN6_DIP")
	)
	(segment
		(start 43.256962 -450.995288)
		(end 43.256962 -452.82358)
		(width 0.1651)
		(layer "In15.Cu")
		(net "TDR_DIFF_85_IN6_DIP")
	)
	(segment
		(start 68.453762 -452.82358)
		(end 68.453762 -450.995288)
		(width 0.1651)
		(layer "In15.Cu")
		(net "TDR_DIFF_85_IN6_DIP")
	)
	(segment
		(start 27.417522 -452.82358)
		(end 27.417522 -450.995288)
		(width 0.1651)
		(layer "In15.Cu")
		(net "TDR_DIFF_85_IN6_DIP")
	)
	(segment
		(start 48.265842 -450.665088)
		(end 48.789082 -450.665088)
		(width 0.1651)
		(layer "In15.Cu")
		(net "TDR_DIFF_85_IN6_DIP")
	)
	(segment
		(start 14.312392 -452.157084)
		(end 14.477492 -451.991984)
		(width 0.1651)
		(layer "In15.Cu")
		(net "TDR_DIFF_85_IN6_DIP")
	)
	(segment
		(start 67.201542 -453.31888)
		(end 67.958462 -453.31888)
		(width 0.1651)
		(layer "In15.Cu")
		(net "TDR_DIFF_85_IN6_DIP")
	)
	(segment
		(start 62.591442 -450.995288)
		(end 62.921642 -450.665088)
		(width 0.1651)
		(layer "In15.Cu")
		(net "TDR_DIFF_85_IN6_DIP")
	)
	(segment
		(start 57.059322 -450.665088)
		(end 57.582562 -450.665088)
		(width 0.1651)
		(layer "In15.Cu")
		(net "TDR_DIFF_85_IN6_DIP")
	)
	(segment
		(start 62.591442 -452.82358)
		(end 62.591442 -450.995288)
		(width 0.1651)
		(layer "In15.Cu")
		(net "TDR_DIFF_85_IN6_DIP")
	)
	(segment
		(start 16.876522 -452.322184)
		(end 16.876522 -452.82358)
		(width 0.1651)
		(layer "In15.Cu")
		(net "TDR_DIFF_85_IN6_DIP")
	)
	(segment
		(start 74.316082 -450.995288)
		(end 74.646282 -450.665088)
		(width 0.1651)
		(layer "In15.Cu")
		(net "TDR_DIFF_85_IN6_DIP")
	)
	(segment
		(start 50.866802 -450.995288)
		(end 51.197002 -450.665088)
		(width 0.1651)
		(layer "In15.Cu")
		(net "TDR_DIFF_85_IN6_DIP")
	)
	(segment
		(start 62.921642 -450.665088)
		(end 63.444882 -450.665088)
		(width 0.1651)
		(layer "In15.Cu")
		(net "TDR_DIFF_85_IN6_DIP")
	)
	(segment
		(start 50.866802 -452.82358)
		(end 50.866802 -450.995288)
		(width 0.1651)
		(layer "In15.Cu")
		(net "TDR_DIFF_85_IN6_DIP")
	)
	(segment
		(start 41.578022 -453.31888)
		(end 42.073322 -452.82358)
		(width 0.1651)
		(layer "In15.Cu")
		(net "TDR_DIFF_85_IN6_DIP")
	)
	(segment
		(start 22.738842 -452.82358)
		(end 23.234142 -453.31888)
		(width 0.1651)
		(layer "In15.Cu")
		(net "TDR_DIFF_85_IN6_DIP")
	)
	(segment
		(start 58.408062 -453.31888)
		(end 59.164982 -453.31888)
		(width 0.1651)
		(layer "In15.Cu")
		(net "TDR_DIFF_85_IN6_DIP")
	)
	(segment
		(start 26.165302 -453.31888)
		(end 26.922222 -453.31888)
		(width 0.1651)
		(layer "In15.Cu")
		(net "TDR_DIFF_85_IN6_DIP")
	)
	(segment
		(start 72.238362 -450.665088)
		(end 72.568562 -450.995288)
		(width 0.1651)
		(layer "In15.Cu")
		(net "TDR_DIFF_85_IN6_DIP")
	)
	(segment
		(start 78.180692 -451.991984)
		(end 78.345792 -452.157084)
		(width 0.1651)
		(layer "In15.Cu")
		(net "TDR_DIFF_85_IN6_DIP")
	)
	(segment
		(start 46.188122 -450.995288)
		(end 46.188122 -452.82358)
		(width 0.1651)
		(layer "In15.Cu")
		(net "TDR_DIFF_85_IN6_DIP")
	)
	(segment
		(start 62.096142 -453.31888)
		(end 62.591442 -452.82358)
		(width 0.1651)
		(layer "In15.Cu")
		(net "TDR_DIFF_85_IN6_DIP")
	)
	(segment
		(start 66.706242 -450.995288)
		(end 66.706242 -452.82358)
		(width 0.1651)
		(layer "In15.Cu")
		(net "TDR_DIFF_85_IN6_DIP")
	)
	(segment
		(start 14.477492 -451.991984)
		(end 16.546322 -451.991984)
		(width 0.1651)
		(layer "In15.Cu")
		(net "TDR_DIFF_85_IN6_DIP")
	)
	(segment
		(start 75.995022 -451.991984)
		(end 78.180692 -451.991984)
		(width 0.1651)
		(layer "In15.Cu")
		(net "TDR_DIFF_85_IN6_DIP")
	)
	(segment
		(start 49.119282 -452.82358)
		(end 49.614582 -453.31888)
		(width 0.1651)
		(layer "In15.Cu")
		(net "TDR_DIFF_85_IN6_DIP")
	)
	(segment
		(start 28.601162 -450.995288)
		(end 28.601162 -452.82358)
		(width 0.1651)
		(layer "In15.Cu")
		(net "TDR_DIFF_85_IN6_DIP")
	)
	(segment
		(start 52.545742 -453.31888)
		(end 53.302662 -453.31888)
		(width 0.1651)
		(layer "In15.Cu")
		(net "TDR_DIFF_85_IN6_DIP")
	)
	(segment
		(start 68.783962 -450.665088)
		(end 69.307202 -450.665088)
		(width 0.1651)
		(layer "In15.Cu")
		(net "TDR_DIFF_85_IN6_DIP")
	)
	(segment
		(start 36.211002 -452.82358)
		(end 36.211002 -450.995288)
		(width 0.1651)
		(layer "In15.Cu")
		(net "TDR_DIFF_85_IN6_DIP")
	)
	(segment
		(start 60.513722 -450.665088)
		(end 60.843922 -450.995288)
		(width 0.1651)
		(layer "In15.Cu")
		(net "TDR_DIFF_85_IN6_DIP")
	)
	(segment
		(start 74.316082 -452.82358)
		(end 74.316082 -450.995288)
		(width 0.1651)
		(layer "In15.Cu")
		(net "TDR_DIFF_85_IN6_DIP")
	)
	(segment
		(start 34.133282 -450.665088)
		(end 34.463482 -450.995288)
		(width 0.1651)
		(layer "In15.Cu")
		(net "TDR_DIFF_85_IN6_DIP")
	)
	(segment
		(start 39.142162 -452.82358)
		(end 39.142162 -450.995288)
		(width 0.1651)
		(layer "In15.Cu")
		(net "TDR_DIFF_85_IN6_DIP")
	)
	(segment
		(start 47.935642 -450.995288)
		(end 48.265842 -450.665088)
		(width 0.1651)
		(layer "In15.Cu")
		(net "TDR_DIFF_85_IN6_DIP")
	)
	(segment
		(start 26.922222 -453.31888)
		(end 27.417522 -452.82358)
		(width 0.1651)
		(layer "In15.Cu")
		(net "TDR_DIFF_85_IN6_DIP")
	)
	(segment
		(start 36.541202 -450.665088)
		(end 37.064442 -450.665088)
		(width 0.1651)
		(layer "In15.Cu")
		(net "TDR_DIFF_85_IN6_DIP")
	)
	(segment
		(start 51.720242 -450.665088)
		(end 52.050442 -450.995288)
		(width 0.1651)
		(layer "In15.Cu")
		(net "TDR_DIFF_85_IN6_DIP")
	)
	(segment
		(start 24.486362 -452.82358)
		(end 24.486362 -450.995288)
		(width 0.1651)
		(layer "In15.Cu")
		(net "TDR_DIFF_85_IN6_DIP")
	)
	(segment
		(start 71.715122 -450.665088)
		(end 72.238362 -450.665088)
		(width 0.1651)
		(layer "In15.Cu")
		(net "TDR_DIFF_85_IN6_DIP")
	)
	(segment
		(start 38.646862 -453.31888)
		(end 39.142162 -452.82358)
		(width 0.1651)
		(layer "In15.Cu")
		(net "TDR_DIFF_85_IN6_DIP")
	)
	(segment
		(start 25.670002 -450.995288)
		(end 25.670002 -452.82358)
		(width 0.1651)
		(layer "In15.Cu")
		(net "TDR_DIFF_85_IN6_DIP")
	)
	(segment
		(start 42.073322 -450.995288)
		(end 42.403522 -450.665088)
		(width 0.1651)
		(layer "In15.Cu")
		(net "TDR_DIFF_85_IN6_DIP")
	)
	(segment
		(start 52.050442 -452.82358)
		(end 52.545742 -453.31888)
		(width 0.1651)
		(layer "In15.Cu")
		(net "TDR_DIFF_85_IN6_DIP")
	)
	(segment
		(start 18.624042 -450.995288)
		(end 18.954242 -450.665088)
		(width 0.1651)
		(layer "In15.Cu")
		(net "TDR_DIFF_85_IN6_DIP")
	)
	(segment
		(start 19.477482 -450.665088)
		(end 19.807682 -450.995288)
		(width 0.1651)
		(layer "In15.Cu")
		(net "TDR_DIFF_85_IN6_DIP")
	)
	(segment
		(start 66.706242 -452.82358)
		(end 67.201542 -453.31888)
		(width 0.1651)
		(layer "In15.Cu")
		(net "TDR_DIFF_85_IN6_DIP")
	)
	(segment
		(start 32.027622 -453.31888)
		(end 32.784542 -453.31888)
		(width 0.1651)
		(layer "In15.Cu")
		(net "TDR_DIFF_85_IN6_DIP")
	)
	(segment
		(start 57.912762 -452.82358)
		(end 58.408062 -453.31888)
		(width 0.1651)
		(layer "In15.Cu")
		(net "TDR_DIFF_85_IN6_DIP")
	)
	(segment
		(start 53.797962 -452.82358)
		(end 53.797962 -450.995288)
		(width 0.1651)
		(layer "In15.Cu")
		(net "TDR_DIFF_85_IN6_DIP")
	)
	(segment
		(start 46.188122 -452.82358)
		(end 46.683422 -453.31888)
		(width 0.1651)
		(layer "In15.Cu")
		(net "TDR_DIFF_85_IN6_DIP")
	)
	(segment
		(start 39.142162 -450.995288)
		(end 39.472362 -450.665088)
		(width 0.1651)
		(layer "In15.Cu")
		(net "TDR_DIFF_85_IN6_DIP")
	)
	(segment
		(start 37.394642 -450.995288)
		(end 37.394642 -452.82358)
		(width 0.1651)
		(layer "In15.Cu")
		(net "TDR_DIFF_85_IN6_DIP")
	)
	(segment
		(start 40.325802 -450.995288)
		(end 40.325802 -452.82358)
		(width 0.1651)
		(layer "In15.Cu")
		(net "TDR_DIFF_85_IN6_DIP")
	)
	(segment
		(start 27.417522 -450.995288)
		(end 27.747722 -450.665088)
		(width 0.1651)
		(layer "In15.Cu")
		(net "TDR_DIFF_85_IN6_DIP")
	)
	(segment
		(start 45.857922 -450.665088)
		(end 46.188122 -450.995288)
		(width 0.1651)
		(layer "In15.Cu")
		(net "TDR_DIFF_85_IN6_DIP")
	)
	(segment
		(start 53.797962 -450.995288)
		(end 54.128162 -450.665088)
		(width 0.1651)
		(layer "In15.Cu")
		(net "TDR_DIFF_85_IN6_DIP")
	)
	(segment
		(start 21.059902 -453.31888)
		(end 21.555202 -452.82358)
		(width 0.1651)
		(layer "In15.Cu")
		(net "TDR_DIFF_85_IN6_DIP")
	)
	(segment
		(start 56.233822 -453.31888)
		(end 56.729122 -452.82358)
		(width 0.1651)
		(layer "In15.Cu")
		(net "TDR_DIFF_85_IN6_DIP")
	)
	(segment
		(start 42.403522 -450.665088)
		(end 42.926762 -450.665088)
		(width 0.1651)
		(layer "In15.Cu")
		(net "TDR_DIFF_85_IN6_DIP")
	)
	(segment
		(start 70.889622 -453.31888)
		(end 71.384922 -452.82358)
		(width 0.1651)
		(layer "In15.Cu")
		(net "TDR_DIFF_85_IN6_DIP")
	)
	(segment
		(start 20.302982 -453.31888)
		(end 21.059902 -453.31888)
		(width 0.1651)
		(layer "In15.Cu")
		(net "TDR_DIFF_85_IN6_DIP")
	)
	(segment
		(start 17.371822 -453.31888)
		(end 18.128742 -453.31888)
		(width 0.1651)
		(layer "In15.Cu")
		(net "TDR_DIFF_85_IN6_DIP")
	)
	(segment
		(start 42.926762 -450.665088)
		(end 43.256962 -450.995288)
		(width 0.1651)
		(layer "In15.Cu")
		(net "TDR_DIFF_85_IN6_DIP")
	)
	(segment
		(start 75.499722 -450.995288)
		(end 75.499722 -451.496684)
		(width 0.1651)
		(layer "In15.Cu")
		(net "TDR_DIFF_85_IN6_DIP")
	)
	(segment
		(start 40.821102 -453.31888)
		(end 41.578022 -453.31888)
		(width 0.1651)
		(layer "In15.Cu")
		(net "TDR_DIFF_85_IN6_DIP")
	)
	(segment
		(start 34.463482 -452.82358)
		(end 34.958782 -453.31888)
		(width 0.1651)
		(layer "In15.Cu")
		(net "TDR_DIFF_85_IN6_DIP")
	)
	(segment
		(start 67.958462 -453.31888)
		(end 68.453762 -452.82358)
		(width 0.1651)
		(layer "In15.Cu")
		(net "TDR_DIFF_85_IN6_DIP")
	)
	(segment
		(start 60.843922 -450.995288)
		(end 60.843922 -452.82358)
		(width 0.1651)
		(layer "In15.Cu")
		(net "TDR_DIFF_85_IN6_DIP")
	)
	(segment
		(start 54.981602 -452.82358)
		(end 55.476902 -453.31888)
		(width 0.1651)
		(layer "In15.Cu")
		(net "TDR_DIFF_85_IN6_DIP")
	)
	(segment
		(start 57.912762 -450.995288)
		(end 57.912762 -452.82358)
		(width 0.1651)
		(layer "In15.Cu")
		(net "TDR_DIFF_85_IN6_DIP")
	)
	(segment
		(start 45.334682 -450.665088)
		(end 45.857922 -450.665088)
		(width 0.1651)
		(layer "In15.Cu")
		(net "TDR_DIFF_85_IN6_DIP")
	)
	(segment
		(start 70.132702 -453.31888)
		(end 70.889622 -453.31888)
		(width 0.1651)
		(layer "In15.Cu")
		(net "TDR_DIFF_85_IN6_DIP")
	)
	(segment
		(start 65.522602 -452.82358)
		(end 65.522602 -450.995288)
		(width 0.1651)
		(layer "In15.Cu")
		(net "TDR_DIFF_85_IN6_DIP")
	)
	(segment
		(start 59.164982 -453.31888)
		(end 59.660282 -452.82358)
		(width 0.1651)
		(layer "In15.Cu")
		(net "TDR_DIFF_85_IN6_DIP")
	)
	(segment
		(start 18.624042 -452.82358)
		(end 18.624042 -450.995288)
		(width 0.1651)
		(layer "In15.Cu")
		(net "TDR_DIFF_85_IN6_DIP")
	)
	(segment
		(start 30.348682 -452.82358)
		(end 30.348682 -450.995288)
		(width 0.1651)
		(layer "In15.Cu")
		(net "TDR_DIFF_85_IN6_DIP")
	)
	(segment
		(start 39.995602 -450.665088)
		(end 40.325802 -450.995288)
		(width 0.1651)
		(layer "In15.Cu")
		(net "TDR_DIFF_85_IN6_DIP")
	)
	(segment
		(start 30.678882 -450.665088)
		(end 31.202122 -450.665088)
		(width 0.1651)
		(layer "In15.Cu")
		(net "TDR_DIFF_85_IN6_DIP")
	)
	(segment
		(start 27.747722 -450.665088)
		(end 28.270962 -450.665088)
		(width 0.1651)
		(layer "In15.Cu")
		(net "TDR_DIFF_85_IN6_DIP")
	)
	(segment
		(start 73.820782 -453.31888)
		(end 74.316082 -452.82358)
		(width 0.1651)
		(layer "In15.Cu")
		(net "TDR_DIFF_85_IN6_DIP")
	)
	(segment
		(start 73.063862 -453.31888)
		(end 73.820782 -453.31888)
		(width 0.1651)
		(layer "In15.Cu")
		(net "TDR_DIFF_85_IN6_DIP")
	)
	(segment
		(start 25.670002 -452.82358)
		(end 26.165302 -453.31888)
		(width 0.1651)
		(layer "In15.Cu")
		(net "TDR_DIFF_85_IN6_DIP")
	)
	(segment
		(start 66.376042 -450.665088)
		(end 66.706242 -450.995288)
		(width 0.1651)
		(layer "In15.Cu")
		(net "TDR_DIFF_85_IN6_DIP")
	)
	(segment
		(start 43.256962 -452.82358)
		(end 43.752262 -453.31888)
		(width 0.1651)
		(layer "In15.Cu")
		(net "TDR_DIFF_85_IN6_DIP")
	)
	(segment
		(start 31.202122 -450.665088)
		(end 31.532322 -450.995288)
		(width 0.1651)
		(layer "In15.Cu")
		(net "TDR_DIFF_85_IN6_DIP")
	)
	(segment
		(start 34.463482 -450.995288)
		(end 34.463482 -452.82358)
		(width 0.1651)
		(layer "In15.Cu")
		(net "TDR_DIFF_85_IN6_DIP")
	)
	(segment
		(start 37.889942 -453.31888)
		(end 38.646862 -453.31888)
		(width 0.1651)
		(layer "In15.Cu")
		(net "TDR_DIFF_85_IN6_DIP")
	)
	(segment
		(start 48.789082 -450.665088)
		(end 49.119282 -450.995288)
		(width 0.1651)
		(layer "In15.Cu")
		(net "TDR_DIFF_85_IN6_DIP")
	)
	(segment
		(start 47.440342 -453.31888)
		(end 47.935642 -452.82358)
		(width 0.1651)
		(layer "In15.Cu")
		(net "TDR_DIFF_85_IN6_DIP")
	)
	(segment
		(start 34.958782 -453.31888)
		(end 35.715702 -453.31888)
		(width 0.1651)
		(layer "In15.Cu")
		(net "TDR_DIFF_85_IN6_DIP")
	)
	(segment
		(start 24.816562 -450.665088)
		(end 25.339802 -450.665088)
		(width 0.1651)
		(layer "In15.Cu")
		(net "TDR_DIFF_85_IN6_DIP")
	)
	(segment
		(start 68.453762 -450.995288)
		(end 68.783962 -450.665088)
		(width 0.1651)
		(layer "In15.Cu")
		(net "TDR_DIFF_85_IN6_DIP")
	)
	(segment
		(start 14.312392 -453.121014)
		(end 14.312392 -452.157084)
		(width 0.1651)
		(layer "In15.Cu")
		(net "TDR_DIFF_85_IN6_DIP")
	)
	(segment
		(start 18.128742 -453.31888)
		(end 18.624042 -452.82358)
		(width 0.1651)
		(layer "In15.Cu")
		(net "TDR_DIFF_85_IN6_DIP")
	)
	(segment
		(start 56.729122 -452.82358)
		(end 56.729122 -450.995288)
		(width 0.1651)
		(layer "In15.Cu")
		(net "TDR_DIFF_85_IN6_DIP")
	)
	(segment
		(start 52.050442 -450.995288)
		(end 52.050442 -452.82358)
		(width 0.1651)
		(layer "In15.Cu")
		(net "TDR_DIFF_85_IN6_DIP")
	)
	(segment
		(start 78.345792 -452.157084)
		(end 78.345792 -453.121014)
		(width 0.1651)
		(layer "In15.Cu")
		(net "TDR_DIFF_85_IN6_DIP")
	)
	(segment
		(start 59.660282 -450.995288)
		(end 59.990482 -450.665088)
		(width 0.1651)
		(layer "In15.Cu")
		(net "TDR_DIFF_85_IN6_DIP")
	)
	(segment
		(start 74.646282 -450.665088)
		(end 75.169522 -450.665088)
		(width 0.1651)
		(layer "In15.Cu")
		(net "TDR_DIFF_85_IN6_DIP")
	)
	(segment
		(start 63.775082 -450.995288)
		(end 63.775082 -452.82358)
		(width 0.1651)
		(layer "In15.Cu")
		(net "TDR_DIFF_85_IN6_DIP")
	)
	(segment
		(start 72.568562 -452.82358)
		(end 73.063862 -453.31888)
		(width 0.1651)
		(layer "In15.Cu")
		(net "TDR_DIFF_85_IN6_DIP")
	)
	(segment
		(start 22.738842 -450.995288)
		(end 22.738842 -452.82358)
		(width 0.1651)
		(layer "In15.Cu")
		(net "TDR_DIFF_85_IN6_DIP")
	)
	(segment
		(start 50.371502 -453.31888)
		(end 50.866802 -452.82358)
		(width 0.1651)
		(layer "In15.Cu")
		(net "TDR_DIFF_85_IN6_DIP")
	)
	(segment
		(start 14.618462 -305.47564)
		(end 14.656308 -305.437794)
		(width 0.254)
		(layer "F.Cu")
		(net "P1V25_PEX0_REF")
	)
	(segment
		(start 14.656308 -304.50028)
		(end 15.308326 -304.50028)
		(width 0.13208)
		(layer "F.Cu")
		(net "P1V25_PEX0_REF")
	)
	(segment
		(start 12.707112 -306.281836)
		(end 12.888214 -306.206906)
		(width 0.1778)
		(layer "F.Cu")
		(net "P1V25_PEX0_REF")
	)
	(segment
		(start 13.110718 -305.984402)
		(end 13.61948 -305.47564)
		(width 0.254)
		(layer "F.Cu")
		(net "P1V25_PEX0_REF")
	)
	(segment
		(start 13.61948 -305.47564)
		(end 14.618462 -305.47564)
		(width 0.254)
		(layer "F.Cu")
		(net "P1V25_PEX0_REF")
	)
	(segment
		(start 12.888214 -306.206906)
		(end 13.110718 -305.984402)
		(width 0.1778)
		(layer "F.Cu")
		(net "P1V25_PEX0_REF")
	)
	(segment
		(start 14.656308 -305.437794)
		(end 14.656308 -304.50028)
		(width 0.254)
		(layer "F.Cu")
		(net "P1V25_PEX0_REF")
	)
	(segment
		(start 11.62177 -306.281836)
		(end 12.707112 -306.281836)
		(width 0.1778)
		(layer "F.Cu")
		(net "P1V25_PEX0_REF")
	)
	(via
		(at 15.308326 -304.50028)
		(size 0.508)
		(drill 0.254)
		(layers "F.Cu" "B.Cu")
		(net "P1V25_PEX0_REF")
	)
	(segment
		(start 356.387654 -280.530046)
		(end 355.920802 -281.657298)
		(width 0.1524)
		(layer "F.Cu")
		(net "P0V8_PEX3_LSET1")
	)
	(segment
		(start 356.182422 -279.886918)
		(end 356.182422 -280.295858)
		(width 0.1524)
		(layer "F.Cu")
		(net "P0V8_PEX3_LSET1")
	)
	(segment
		(start 356.182422 -280.295858)
		(end 356.387654 -280.50109)
		(width 0.1524)
		(layer "F.Cu")
		(net "P0V8_PEX3_LSET1")
	)
	(segment
		(start 356.387654 -280.50109)
		(end 356.387654 -280.530046)
		(width 0.1524)
		(layer "F.Cu")
		(net "P0V8_PEX3_LSET1")
	)
	(segment
		(start 355.920802 -281.657298)
		(end 355.920802 -281.999182)
		(width 0.1524)
		(layer "F.Cu")
		(net "P0V8_PEX3_LSET1")
	)
	(via
		(at 356.387654 -280.50109)
		(size 0.508)
		(drill 0.254)
		(layers "F.Cu" "B.Cu")
		(net "P0V8_PEX3_LSET1")
	)
	(segment
		(start 357.523034 -282.293314)
		(end 357.44658 -282.477718)
		(width 0.2286)
		(layer "F.Cu")
		(net "SW_P0V8_PEX3_VOS1")
	)
	(segment
		(start 357.44658 -282.477718)
		(end 357.300276 -282.624022)
		(width 0.2286)
		(layer "F.Cu")
		(net "SW_P0V8_PEX3_VOS1")
	)
	(segment
		(start 357.523034 -281.963368)
		(end 357.523034 -282.293314)
		(width 0.2286)
		(layer "F.Cu")
		(net "SW_P0V8_PEX3_VOS1")
	)
	(segment
		(start 357.300276 -282.624022)
		(end 357.230934 -282.624022)
		(width 0.2286)
		(layer "F.Cu")
		(net "SW_P0V8_PEX3_VOS1")
	)
	(via
		(at 357.523034 -281.963368)
		(size 0.508)
		(drill 0.254)
		(layers "F.Cu" "B.Cu")
		(net "SW_P0V8_PEX3_VOS1")
	)
	(segment
		(start 358.278684 -282.440634)
		(end 358.179116 -282.341066)
		(width 0.254)
		(layer "B.Cu")
		(net "SW_P0V8_PEX3_VOS1")
	)
	(segment
		(start 357.900732 -282.341066)
		(end 357.523034 -281.963368)
		(width 0.254)
		(layer "B.Cu")
		(net "SW_P0V8_PEX3_VOS1")
	)
	(segment
		(start 358.179116 -282.341066)
		(end 357.900732 -282.341066)
		(width 0.254)
		(layer "B.Cu")
		(net "SW_P0V8_PEX3_VOS1")
	)
	(segment
		(start 353.168966 -280.84907)
		(end 353.67087 -281.350974)
		(width 0.2286)
		(layer "F.Cu")
		(net "SW_P0V8_PEX3_PHASE1")
	)
	(segment
		(start 353.67087 -281.350974)
		(end 353.67087 -281.999182)
		(width 0.2286)
		(layer "F.Cu")
		(net "SW_P0V8_PEX3_PHASE1")
	)
	(segment
		(start 364.081314 -281.999182)
		(end 364.081314 -281.657298)
		(width 0.1524)
		(layer "F.Cu")
		(net "P0V8_PEX3_LSET2")
	)
	(segment
		(start 364.342934 -280.295858)
		(end 364.548166 -280.50109)
		(width 0.1524)
		(layer "F.Cu")
		(net "P0V8_PEX3_LSET2")
	)
	(segment
		(start 364.081314 -281.657298)
		(end 364.548166 -280.530046)
		(width 0.1524)
		(layer "F.Cu")
		(net "P0V8_PEX3_LSET2")
	)
	(segment
		(start 364.548166 -280.530046)
		(end 364.548166 -280.50109)
		(width 0.1524)
		(layer "F.Cu")
		(net "P0V8_PEX3_LSET2")
	)
	(segment
		(start 364.342934 -279.886918)
		(end 364.342934 -280.295858)
		(width 0.1524)
		(layer "F.Cu")
		(net "P0V8_PEX3_LSET2")
	)
	(via
		(at 364.548166 -280.50109)
		(size 0.508)
		(drill 0.254)
		(layers "F.Cu" "B.Cu")
		(net "P0V8_PEX3_LSET2")
	)
	(segment
		(start 362.291376 -281.989276)
		(end 362.28147 -281.999182)
		(width 0.2286)
		(layer "F.Cu")
		(net "SW_P0V8_PEX3_BOOT2")
	)
	(segment
		(start 362.291376 -280.84907)
		(end 362.291376 -281.989276)
		(width 0.2286)
		(layer "F.Cu")
		(net "SW_P0V8_PEX3_BOOT2")
	)
	(segment
		(start 357.230934 -283.524198)
		(end 357.666798 -283.524198)
		(width 0.2286)
		(layer "F.Cu")
		(net "P0V8_PEX3_VCC1")
	)
	(segment
		(start 357.666798 -283.524198)
		(end 358.369362 -282.821634)
		(width 0.2286)
		(layer "F.Cu")
		(net "P0V8_PEX3_VCC1")
	)
	(segment
		(start 358.369362 -282.821634)
		(end 358.405684 -282.821634)
		(width 0.2286)
		(layer "F.Cu")
		(net "P0V8_PEX3_VCC1")
	)
	(segment
		(start 358.454198 -282.870148)
		(end 358.454198 -283.437584)
		(width 0.254)
		(layer "F.Cu")
		(net "P0V8_PEX3_VCC1")
	)
	(segment
		(start 358.405684 -282.821634)
		(end 358.454198 -282.870148)
		(width 0.254)
		(layer "F.Cu")
		(net "P0V8_PEX3_VCC1")
	)
	(via
		(at 358.454198 -283.437584)
		(size 0.508)
		(drill 0.254)
		(layers "F.Cu" "B.Cu")
		(net "P0V8_PEX3_VCC1")
	)
	(segment
		(start 356.918006 -282.566872)
		(end 356.634542 -282.283408)
		(width 0.254)
		(layer "B.Cu")
		(net "P0V8_PEX3_VCC1")
	)
	(segment
		(start 356.456742 -282.155646)
		(end 356.024688 -282.155646)
		(width 0.254)
		(layer "B.Cu")
		(net "P0V8_PEX3_VCC1")
	)
	(segment
		(start 356.918006 -282.566872)
		(end 356.919022 -282.566872)
		(width 0.254)
		(layer "B.Cu")
		(net "P0V8_PEX3_VCC1")
	)
	(segment
		(start 356.584504 -282.283408)
		(end 356.456742 -282.155646)
		(width 0.254)
		(layer "B.Cu")
		(net "P0V8_PEX3_VCC1")
	)
	(segment
		(start 358.454198 -283.437584)
		(end 357.789734 -283.437584)
		(width 0.254)
		(layer "B.Cu")
		(net "P0V8_PEX3_VCC1")
	)
	(segment
		(start 356.919022 -282.566872)
		(end 357.770684 -283.418534)
		(width 0.254)
		(layer "B.Cu")
		(net "P0V8_PEX3_VCC1")
	)
	(segment
		(start 356.024688 -282.155646)
		(end 355.920802 -282.259532)
		(width 0.254)
		(layer "B.Cu")
		(net "P0V8_PEX3_VCC1")
	)
	(segment
		(start 356.634542 -282.283408)
		(end 356.584504 -282.283408)
		(width 0.254)
		(layer "B.Cu")
		(net "P0V8_PEX3_VCC1")
	)
	(segment
		(start 357.789734 -283.437584)
		(end 357.770684 -283.418534)
		(width 0.254)
		(layer "B.Cu")
		(net "P0V8_PEX3_VCC1")
	)
	(segment
		(start 365.82731 -283.524198)
		(end 366.529874 -282.821634)
		(width 0.2286)
		(layer "F.Cu")
		(net "P0V8_PEX3_VCC2")
	)
	(segment
		(start 365.391446 -283.524198)
		(end 365.82731 -283.524198)
		(width 0.2286)
		(layer "F.Cu")
		(net "P0V8_PEX3_VCC2")
	)
	(segment
		(start 366.529874 -282.821634)
		(end 366.566196 -282.821634)
		(width 0.2286)
		(layer "F.Cu")
		(net "P0V8_PEX3_VCC2")
	)
	(segment
		(start 366.566196 -282.821634)
		(end 366.61471 -282.870148)
		(width 0.254)
		(layer "F.Cu")
		(net "P0V8_PEX3_VCC2")
	)
	(segment
		(start 366.61471 -282.870148)
		(end 366.61471 -283.437584)
		(width 0.254)
		(layer "F.Cu")
		(net "P0V8_PEX3_VCC2")
	)
	(via
		(at 366.61471 -283.437584)
		(size 0.508)
		(drill 0.254)
		(layers "F.Cu" "B.Cu")
		(net "P0V8_PEX3_VCC2")
	)
	(segment
		(start 365.931196 -283.417264)
		(end 365.087408 -282.573476)
		(width 0.254)
		(layer "B.Cu")
		(net "P0V8_PEX3_VCC2")
	)
	(segment
		(start 364.84941 -282.379674)
		(end 364.609888 -282.140152)
		(width 0.254)
		(layer "B.Cu")
		(net "P0V8_PEX3_VCC2")
	)
	(segment
		(start 364.893606 -282.379674)
		(end 364.84941 -282.379674)
		(width 0.254)
		(layer "B.Cu")
		(net "P0V8_PEX3_VCC2")
	)
	(segment
		(start 365.087408 -282.573476)
		(end 364.893606 -282.379674)
		(width 0.254)
		(layer "B.Cu")
		(net "P0V8_PEX3_VCC2")
	)
	(segment
		(start 365.931196 -283.418534)
		(end 365.950246 -283.437584)
		(width 0.254)
		(layer "B.Cu")
		(net "P0V8_PEX3_VCC2")
	)
	(segment
		(start 365.950246 -283.437584)
		(end 366.61471 -283.437584)
		(width 0.254)
		(layer "B.Cu")
		(net "P0V8_PEX3_VCC2")
	)
	(segment
		(start 365.931196 -283.418534)
		(end 365.931196 -283.417264)
		(width 0.254)
		(layer "B.Cu")
		(net "P0V8_PEX3_VCC2")
	)
	(segment
		(start 364.609888 -282.140152)
		(end 364.21441 -282.140152)
		(width 0.254)
		(layer "B.Cu")
		(net "P0V8_PEX3_VCC2")
	)
	(segment
		(start 364.21441 -282.140152)
		(end 364.110524 -282.244038)
		(width 0.254)
		(layer "B.Cu")
		(net "P0V8_PEX3_VCC2")
	)
	(segment
		(start 354.130864 -280.04897)
		(end 353.168966 -280.04897)
		(width 0.254)
		(layer "F.Cu")
		(net "SW_P0V8_PEX3_BOOT1_R")
	)
	(segment
		(start 362.291376 -280.04897)
		(end 361.329478 -280.04897)
		(width 0.254)
		(layer "F.Cu")
		(net "SW_P0V8_PEX3_BOOT2_R")
	)
	(segment
		(start 365.607092 -282.477718)
		(end 365.460788 -282.624022)
		(width 0.2286)
		(layer "F.Cu")
		(net "SW_P0V8_PEX3_VOS2")
	)
	(segment
		(start 365.460788 -282.624022)
		(end 365.391446 -282.624022)
		(width 0.2286)
		(layer "F.Cu")
		(net "SW_P0V8_PEX3_VOS2")
	)
	(segment
		(start 365.683546 -282.293314)
		(end 365.607092 -282.477718)
		(width 0.2286)
		(layer "F.Cu")
		(net "SW_P0V8_PEX3_VOS2")
	)
	(segment
		(start 365.683546 -281.963368)
		(end 365.683546 -282.293314)
		(width 0.2286)
		(layer "F.Cu")
		(net "SW_P0V8_PEX3_VOS2")
	)
	(via
		(at 365.683546 -281.963368)
		(size 0.508)
		(drill 0.254)
		(layers "F.Cu" "B.Cu")
		(net "SW_P0V8_PEX3_VOS2")
	)
	(segment
		(start 366.341914 -282.343352)
		(end 366.06353 -282.343352)
		(width 0.254)
		(layer "B.Cu")
		(net "SW_P0V8_PEX3_VOS2")
	)
	(segment
		(start 366.06353 -282.343352)
		(end 365.683546 -281.963368)
		(width 0.254)
		(layer "B.Cu")
		(net "SW_P0V8_PEX3_VOS2")
	)
	(segment
		(start 366.439196 -282.440634)
		(end 366.341914 -282.343352)
		(width 0.254)
		(layer "B.Cu")
		(net "SW_P0V8_PEX3_VOS2")
	)
	(segment
		(start 413.649922 -291.149786)
		(end 414.124902 -290.674806)
		(width 0.249936)
		(layer "F.Cu")
		(net "P0V8_SERDES_VDDA_PEX3")
	)
	(segment
		(start 409.849828 -298.74972)
		(end 410.324808 -299.224954)
		(width 0.249936)
		(layer "F.Cu")
		(net "P0V8_SERDES_VDDA_PEX3")
	)
	(segment
		(start 404.625048 -292.57498)
		(end 405.100028 -293.04996)
		(width 0.249936)
		(layer "F.Cu")
		(net "P0V8_SERDES_VDDA_PEX3")
	)
	(segment
		(start 406.524968 -290.674806)
		(end 406.999948 -291.149786)
		(width 0.249936)
		(layer "F.Cu")
		(net "P0V8_SERDES_VDDA_PEX3")
	)
	(segment
		(start 399.400014 -291.149786)
		(end 399.874994 -290.674806)
		(width 0.249936)
		(layer "F.Cu")
		(net "P0V8_SERDES_VDDA_PEX3")
	)
	(segment
		(start 399.874994 -290.674806)
		(end 400.349974 -291.149786)
		(width 0.249936)
		(layer "F.Cu")
		(net "P0V8_SERDES_VDDA_PEX3")
	)
	(segment
		(start 406.524968 -299.224954)
		(end 406.049988 -298.74972)
		(width 0.249936)
		(layer "F.Cu")
		(net "P0V8_SERDES_VDDA_PEX3")
	)
	(segment
		(start 411.275022 -299.224954)
		(end 411.750002 -298.74972)
		(width 0.249936)
		(layer "F.Cu")
		(net "P0V8_SERDES_VDDA_PEX3")
	)
	(segment
		(start 405.100028 -300.649894)
		(end 405.575008 -301.124874)
		(width 0.249936)
		(layer "F.Cu")
		(net "P0V8_SERDES_VDDA_PEX3")
	)
	(segment
		(start 412.699962 -298.74972)
		(end 413.174942 -299.224954)
		(width 0.249936)
		(layer "F.Cu")
		(net "P0V8_SERDES_VDDA_PEX3")
	)
	(segment
		(start 400.824954 -301.124874)
		(end 401.299934 -300.649894)
		(width 0.249936)
		(layer "F.Cu")
		(net "P0V8_SERDES_VDDA_PEX3")
	)
	(segment
		(start 412.699962 -293.04996)
		(end 413.174942 -292.574726)
		(width 0.249936)
		(layer "F.Cu")
		(net "P0V8_SERDES_VDDA_PEX3")
	)
	(segment
		(start 403.674834 -290.674806)
		(end 404.149814 -291.149786)
		(width 0.249936)
		(layer "F.Cu")
		(net "P0V8_SERDES_VDDA_PEX3")
	)
	(segment
		(start 399.874994 -301.124874)
		(end 400.349974 -300.649894)
		(width 0.249936)
		(layer "F.Cu")
		(net "P0V8_SERDES_VDDA_PEX3")
	)
	(segment
		(start 405.575008 -290.674806)
		(end 406.049988 -291.149786)
		(width 0.249936)
		(layer "F.Cu")
		(net "P0V8_SERDES_VDDA_PEX3")
	)
	(segment
		(start 407.949908 -298.74972)
		(end 408.424888 -299.224954)
		(width 0.249936)
		(layer "F.Cu")
		(net "P0V8_SERDES_VDDA_PEX3")
	)
	(segment
		(start 408.899868 -298.74972)
		(end 409.374848 -299.224954)
		(width 0.249936)
		(layer "F.Cu")
		(net "P0V8_SERDES_VDDA_PEX3")
	)
	(segment
		(start 404.624794 -290.674806)
		(end 405.100028 -291.149786)
		(width 0.249936)
		(layer "F.Cu")
		(net "P0V8_SERDES_VDDA_PEX3")
	)
	(segment
		(start 415.549842 -300.649894)
		(end 416.024822 -301.124874)
		(width 0.249936)
		(layer "F.Cu")
		(net "P0V8_SERDES_VDDA_PEX3")
	)
	(segment
		(start 409.374848 -292.574726)
		(end 409.849828 -293.04996)
		(width 0.249936)
		(layer "F.Cu")
		(net "P0V8_SERDES_VDDA_PEX3")
	)
	(segment
		(start 409.374848 -301.124874)
		(end 409.849828 -300.649894)
		(width 0.249936)
		(layer "F.Cu")
		(net "P0V8_SERDES_VDDA_PEX3")
	)
	(segment
		(start 412.699962 -291.149786)
		(end 413.174942 -290.674806)
		(width 0.249936)
		(layer "F.Cu")
		(net "P0V8_SERDES_VDDA_PEX3")
	)
	(segment
		(start 405.575008 -292.57498)
		(end 406.049988 -293.04996)
		(width 0.249936)
		(layer "F.Cu")
		(net "P0V8_SERDES_VDDA_PEX3")
	)
	(segment
		(start 409.374848 -290.674806)
		(end 409.849828 -291.149786)
		(width 0.249936)
		(layer "F.Cu")
		(net "P0V8_SERDES_VDDA_PEX3")
	)
	(segment
		(start 401.299934 -298.74972)
		(end 401.774914 -299.224954)
		(width 0.249936)
		(layer "F.Cu")
		(net "P0V8_SERDES_VDDA_PEX3")
	)
	(segment
		(start 413.174942 -292.574726)
		(end 413.649922 -293.04996)
		(width 0.249936)
		(layer "F.Cu")
		(net "P0V8_SERDES_VDDA_PEX3")
	)
	(segment
		(start 399.400014 -300.649894)
		(end 399.874994 -301.124874)
		(width 0.249936)
		(layer "F.Cu")
		(net "P0V8_SERDES_VDDA_PEX3")
	)
	(segment
		(start 405.575008 -299.224954)
		(end 406.049988 -298.74972)
		(width 0.249936)
		(layer "F.Cu")
		(net "P0V8_SERDES_VDDA_PEX3")
	)
	(segment
		(start 416.024822 -296.37482)
		(end 415.549842 -295.89984)
		(width 0.249936)
		(layer "F.Cu")
		(net "P0V8_SERDES_VDDA_PEX3")
	)
	(segment
		(start 413.174942 -290.674806)
		(end 413.649922 -291.149786)
		(width 0.249936)
		(layer "F.Cu")
		(net "P0V8_SERDES_VDDA_PEX3")
	)
	(segment
		(start 416.974782 -296.37482)
		(end 416.499802 -295.89984)
		(width 0.249936)
		(layer "F.Cu")
		(net "P0V8_SERDES_VDDA_PEX3")
	)
	(segment
		(start 412.699962 -291.149786)
		(end 412.224982 -290.674806)
		(width 0.249936)
		(layer "F.Cu")
		(net "P0V8_SERDES_VDDA_PEX3")
	)
	(segment
		(start 406.049988 -291.149786)
		(end 406.524968 -290.674806)
		(width 0.249936)
		(layer "F.Cu")
		(net "P0V8_SERDES_VDDA_PEX3")
	)
	(segment
		(start 408.899868 -300.649894)
		(end 409.374848 -301.124874)
		(width 0.249936)
		(layer "F.Cu")
		(net "P0V8_SERDES_VDDA_PEX3")
	)
	(segment
		(start 412.699962 -293.04996)
		(end 412.224982 -292.574726)
		(width 0.249936)
		(layer "F.Cu")
		(net "P0V8_SERDES_VDDA_PEX3")
	)
	(segment
		(start 398.925034 -290.674806)
		(end 399.400014 -291.149786)
		(width 0.249936)
		(layer "F.Cu")
		(net "P0V8_SERDES_VDDA_PEX3")
	)
	(segment
		(start 412.224982 -299.224954)
		(end 412.699962 -298.74972)
		(width 0.249936)
		(layer "F.Cu")
		(net "P0V8_SERDES_VDDA_PEX3")
	)
	(segment
		(start 414.124902 -292.574726)
		(end 414.599882 -293.04996)
		(width 0.249936)
		(layer "F.Cu")
		(net "P0V8_SERDES_VDDA_PEX3")
	)
	(segment
		(start 410.799788 -293.04996)
		(end 411.275022 -292.574726)
		(width 0.249936)
		(layer "F.Cu")
		(net "P0V8_SERDES_VDDA_PEX3")
	)
	(segment
		(start 413.649922 -300.649894)
		(end 413.174942 -301.124874)
		(width 0.249936)
		(layer "F.Cu")
		(net "P0V8_SERDES_VDDA_PEX3")
	)
	(segment
		(start 401.774914 -299.224954)
		(end 402.249894 -298.74972)
		(width 0.249936)
		(layer "F.Cu")
		(net "P0V8_SERDES_VDDA_PEX3")
	)
	(segment
		(start 408.899868 -293.04996)
		(end 409.374848 -292.574726)
		(width 0.249936)
		(layer "F.Cu")
		(net "P0V8_SERDES_VDDA_PEX3")
	)
	(segment
		(start 401.774914 -292.57498)
		(end 402.249894 -293.04996)
		(width 0.249936)
		(layer "F.Cu")
		(net "P0V8_SERDES_VDDA_PEX3")
	)
	(segment
		(start 416.024822 -292.574726)
		(end 415.549842 -293.04996)
		(width 0.249936)
		(layer "F.Cu")
		(net "P0V8_SERDES_VDDA_PEX3")
	)
	(segment
		(start 411.750002 -298.74972)
		(end 412.224982 -299.224954)
		(width 0.249936)
		(layer "F.Cu")
		(net "P0V8_SERDES_VDDA_PEX3")
	)
	(segment
		(start 399.874994 -292.57498)
		(end 400.349974 -293.04996)
		(width 0.249936)
		(layer "F.Cu")
		(net "P0V8_SERDES_VDDA_PEX3")
	)
	(segment
		(start 416.499802 -296.8498)
		(end 416.974782 -297.32478)
		(width 0.249936)
		(layer "F.Cu")
		(net "P0V8_SERDES_VDDA_PEX3")
	)
	(segment
		(start 408.899868 -291.149786)
		(end 409.374848 -290.674806)
		(width 0.249936)
		(layer "F.Cu")
		(net "P0V8_SERDES_VDDA_PEX3")
	)
	(segment
		(start 411.275022 -292.574726)
		(end 411.750002 -293.04996)
		(width 0.249936)
		(layer "F.Cu")
		(net "P0V8_SERDES_VDDA_PEX3")
	)
	(segment
		(start 408.424888 -299.224954)
		(end 408.899868 -298.74972)
		(width 0.249936)
		(layer "F.Cu")
		(net "P0V8_SERDES_VDDA_PEX3")
	)
	(segment
		(start 398.925034 -301.124874)
		(end 399.400014 -300.649894)
		(width 0.249936)
		(layer "F.Cu")
		(net "P0V8_SERDES_VDDA_PEX3")
	)
	(segment
		(start 404.149814 -298.74972)
		(end 403.674834 -299.224954)
		(width 0.249936)
		(layer "F.Cu")
		(net "P0V8_SERDES_VDDA_PEX3")
	)
	(segment
		(start 414.124902 -299.224954)
		(end 414.599882 -298.74972)
		(width 0.249936)
		(layer "F.Cu")
		(net "P0V8_SERDES_VDDA_PEX3")
	)
	(segment
		(start 404.624794 -299.224954)
		(end 404.149814 -298.74972)
		(width 0.249936)
		(layer "F.Cu")
		(net "P0V8_SERDES_VDDA_PEX3")
	)
	(segment
		(start 400.349974 -298.74972)
		(end 400.824954 -299.224954)
		(width 0.249936)
		(layer "F.Cu")
		(net "P0V8_SERDES_VDDA_PEX3")
	)
	(segment
		(start 405.575008 -301.124874)
		(end 406.049988 -300.649894)
		(width 0.249936)
		(layer "F.Cu")
		(net "P0V8_SERDES_VDDA_PEX3")
	)
	(segment
		(start 409.849828 -291.149786)
		(end 410.324808 -290.674806)
		(width 0.249936)
		(layer "F.Cu")
		(net "P0V8_SERDES_VDDA_PEX3")
	)
	(segment
		(start 413.174942 -299.224954)
		(end 413.649922 -298.74972)
		(width 0.249936)
		(layer "F.Cu")
		(net "P0V8_SERDES_VDDA_PEX3")
	)
	(segment
		(start 407.949908 -291.149786)
		(end 408.424888 -290.674806)
		(width 0.249936)
		(layer "F.Cu")
		(net "P0V8_SERDES_VDDA_PEX3")
	)
	(segment
		(start 403.674834 -301.124874)
		(end 403.199854 -300.649894)
		(width 0.249936)
		(layer "F.Cu")
		(net "P0V8_SERDES_VDDA_PEX3")
	)
	(segment
		(start 410.324808 -301.124874)
		(end 410.799788 -300.649894)
		(width 0.249936)
		(layer "F.Cu")
		(net "P0V8_SERDES_VDDA_PEX3")
	)
	(segment
		(start 407.949908 -300.649894)
		(end 408.424888 -301.124874)
		(width 0.249936)
		(layer "F.Cu")
		(net "P0V8_SERDES_VDDA_PEX3")
	)
	(segment
		(start 412.224982 -301.124874)
		(end 412.699962 -300.649894)
		(width 0.249936)
		(layer "F.Cu")
		(net "P0V8_SERDES_VDDA_PEX3")
	)
	(segment
		(start 406.524968 -301.124874)
		(end 406.999948 -300.649894)
		(width 0.249936)
		(layer "F.Cu")
		(net "P0V8_SERDES_VDDA_PEX3")
	)
	(segment
		(start 406.999948 -298.74972)
		(end 406.524968 -299.224954)
		(width 0.249936)
		(layer "F.Cu")
		(net "P0V8_SERDES_VDDA_PEX3")
	)
	(segment
		(start 403.674834 -299.224954)
		(end 403.199854 -298.74972)
		(width 0.249936)
		(layer "F.Cu")
		(net "P0V8_SERDES_VDDA_PEX3")
	)
	(segment
		(start 416.499802 -295.89984)
		(end 416.024822 -296.37482)
		(width 0.249936)
		(layer "F.Cu")
		(net "P0V8_SERDES_VDDA_PEX3")
	)
	(segment
		(start 416.024822 -294.4749)
		(end 415.549842 -294.94988)
		(width 0.249936)
		(layer "F.Cu")
		(net "P0V8_SERDES_VDDA_PEX3")
	)
	(segment
		(start 404.149814 -300.649894)
		(end 403.674834 -301.124874)
		(width 0.249936)
		(layer "F.Cu")
		(net "P0V8_SERDES_VDDA_PEX3")
	)
	(segment
		(start 413.174942 -301.124874)
		(end 412.699962 -300.649894)
		(width 0.249936)
		(layer "F.Cu")
		(net "P0V8_SERDES_VDDA_PEX3")
	)
	(segment
		(start 416.974782 -294.4749)
		(end 416.499802 -294.94988)
		(width 0.249936)
		(layer "F.Cu")
		(net "P0V8_SERDES_VDDA_PEX3")
	)
	(segment
		(start 413.649922 -293.04996)
		(end 414.124902 -292.574726)
		(width 0.249936)
		(layer "F.Cu")
		(net "P0V8_SERDES_VDDA_PEX3")
	)
	(segment
		(start 415.549842 -291.149786)
		(end 415.074862 -290.674806)
		(width 0.249936)
		(layer "F.Cu")
		(net "P0V8_SERDES_VDDA_PEX3")
	)
	(segment
		(start 398.925034 -292.57498)
		(end 399.400014 -293.04996)
		(width 0.249936)
		(layer "F.Cu")
		(net "P0V8_SERDES_VDDA_PEX3")
	)
	(segment
		(start 403.199854 -300.649894)
		(end 402.724874 -301.124874)
		(width 0.249936)
		(layer "F.Cu")
		(net "P0V8_SERDES_VDDA_PEX3")
	)
	(segment
		(start 406.049988 -300.649894)
		(end 406.524968 -301.124874)
		(width 0.249936)
		(layer "F.Cu")
		(net "P0V8_SERDES_VDDA_PEX3")
	)
	(segment
		(start 409.849828 -300.649894)
		(end 410.324808 -301.124874)
		(width 0.249936)
		(layer "F.Cu")
		(net "P0V8_SERDES_VDDA_PEX3")
	)
	(segment
		(start 399.874994 -299.224954)
		(end 400.349974 -298.74972)
		(width 0.249936)
		(layer "F.Cu")
		(net "P0V8_SERDES_VDDA_PEX3")
	)
	(segment
		(start 405.100028 -300.649894)
		(end 404.624794 -301.124874)
		(width 0.249936)
		(layer "F.Cu")
		(net "P0V8_SERDES_VDDA_PEX3")
	)
	(segment
		(start 413.649922 -300.649894)
		(end 414.124902 -301.124874)
		(width 0.249936)
		(layer "F.Cu")
		(net "P0V8_SERDES_VDDA_PEX3")
	)
	(segment
		(start 412.224982 -290.674806)
		(end 411.750002 -291.149786)
		(width 0.249936)
		(layer "F.Cu")
		(net "P0V8_SERDES_VDDA_PEX3")
	)
	(segment
		(start 404.624794 -301.124874)
		(end 404.149814 -300.649894)
		(width 0.249936)
		(layer "F.Cu")
		(net "P0V8_SERDES_VDDA_PEX3")
	)
	(segment
		(start 415.074862 -292.574726)
		(end 415.549842 -293.04996)
		(width 0.249936)
		(layer "F.Cu")
		(net "P0V8_SERDES_VDDA_PEX3")
	)
	(segment
		(start 406.524968 -292.57498)
		(end 406.999948 -293.04996)
		(width 0.249936)
		(layer "F.Cu")
		(net "P0V8_SERDES_VDDA_PEX3")
	)
	(segment
		(start 400.349974 -300.649894)
		(end 400.824954 -301.124874)
		(width 0.249936)
		(layer "F.Cu")
		(net "P0V8_SERDES_VDDA_PEX3")
	)
	(segment
		(start 411.750002 -300.649894)
		(end 412.224982 -301.124874)
		(width 0.249936)
		(layer "F.Cu")
		(net "P0V8_SERDES_VDDA_PEX3")
	)
	(segment
		(start 399.400014 -298.74972)
		(end 399.874994 -299.224954)
		(width 0.249936)
		(layer "F.Cu")
		(net "P0V8_SERDES_VDDA_PEX3")
	)
	(segment
		(start 414.124902 -290.674806)
		(end 414.599882 -291.149786)
		(width 0.249936)
		(layer "F.Cu")
		(net "P0V8_SERDES_VDDA_PEX3")
	)
	(segment
		(start 405.100028 -298.74972)
		(end 405.575008 -299.224954)
		(width 0.249936)
		(layer "F.Cu")
		(net "P0V8_SERDES_VDDA_PEX3")
	)
	(segment
		(start 415.074862 -297.32478)
		(end 415.549842 -296.8498)
		(width 0.249936)
		(layer "F.Cu")
		(net "P0V8_SERDES_VDDA_PEX3")
	)
	(segment
		(start 402.724874 -292.57498)
		(end 403.199854 -293.04996)
		(width 0.249936)
		(layer "F.Cu")
		(net "P0V8_SERDES_VDDA_PEX3")
	)
	(segment
		(start 405.100028 -298.74972)
		(end 404.624794 -299.224954)
		(width 0.249936)
		(layer "F.Cu")
		(net "P0V8_SERDES_VDDA_PEX3")
	)
	(segment
		(start 400.824954 -299.224954)
		(end 401.299934 -298.74972)
		(width 0.249936)
		(layer "F.Cu")
		(net "P0V8_SERDES_VDDA_PEX3")
	)
	(segment
		(start 415.549842 -298.74972)
		(end 416.024822 -299.224954)
		(width 0.249936)
		(layer "F.Cu")
		(net "P0V8_SERDES_VDDA_PEX3")
	)
	(segment
		(start 400.824954 -290.674806)
		(end 401.299934 -291.149786)
		(width 0.249936)
		(layer "F.Cu")
		(net "P0V8_SERDES_VDDA_PEX3")
	)
	(segment
		(start 410.799788 -293.04996)
		(end 410.324808 -292.574726)
		(width 0.249936)
		(layer "F.Cu")
		(net "P0V8_SERDES_VDDA_PEX3")
	)
	(segment
		(start 400.349974 -291.149786)
		(end 400.824954 -290.674806)
		(width 0.249936)
		(layer "F.Cu")
		(net "P0V8_SERDES_VDDA_PEX3")
	)
	(segment
		(start 402.724874 -290.674806)
		(end 402.249894 -291.149786)
		(width 0.249936)
		(layer "F.Cu")
		(net "P0V8_SERDES_VDDA_PEX3")
	)
	(segment
		(start 407.949908 -293.04996)
		(end 408.424888 -292.574726)
		(width 0.249936)
		(layer "F.Cu")
		(net "P0V8_SERDES_VDDA_PEX3")
	)
	(segment
		(start 411.275022 -301.124874)
		(end 410.799788 -300.649894)
		(width 0.249936)
		(layer "F.Cu")
		(net "P0V8_SERDES_VDDA_PEX3")
	)
	(segment
		(start 403.199854 -291.149786)
		(end 402.724874 -290.674806)
		(width 0.249936)
		(layer "F.Cu")
		(net "P0V8_SERDES_VDDA_PEX3")
	)
	(segment
		(start 410.324808 -299.224954)
		(end 410.799788 -298.74972)
		(width 0.249936)
		(layer "F.Cu")
		(net "P0V8_SERDES_VDDA_PEX3")
	)
	(segment
		(start 411.750002 -300.649894)
		(end 411.275022 -301.124874)
		(width 0.249936)
		(layer "F.Cu")
		(net "P0V8_SERDES_VDDA_PEX3")
	)
	(segment
		(start 415.549842 -296.8498)
		(end 416.024822 -297.32478)
		(width 0.249936)
		(layer "F.Cu")
		(net "P0V8_SERDES_VDDA_PEX3")
	)
	(segment
		(start 401.774914 -301.124874)
		(end 401.299934 -300.649894)
		(width 0.249936)
		(layer "F.Cu")
		(net "P0V8_SERDES_VDDA_PEX3")
	)
	(segment
		(start 401.774914 -290.674806)
		(end 401.299934 -291.149786)
		(width 0.249936)
		(layer "F.Cu")
		(net "P0V8_SERDES_VDDA_PEX3")
	)
	(segment
		(start 402.249894 -298.74972)
		(end 402.724874 -299.224954)
		(width 0.249936)
		(layer "F.Cu")
		(net "P0V8_SERDES_VDDA_PEX3")
	)
	(segment
		(start 414.599882 -296.8498)
		(end 415.074862 -297.32478)
		(width 0.249936)
		(layer "F.Cu")
		(net "P0V8_SERDES_VDDA_PEX3")
	)
	(segment
		(start 416.499802 -294.94988)
		(end 416.024822 -294.4749)
		(width 0.249936)
		(layer "F.Cu")
		(net "P0V8_SERDES_VDDA_PEX3")
	)
	(segment
		(start 413.649922 -298.74972)
		(end 414.124902 -299.224954)
		(width 0.249936)
		(layer "F.Cu")
		(net "P0V8_SERDES_VDDA_PEX3")
	)
	(segment
		(start 398.925034 -299.224954)
		(end 399.400014 -298.74972)
		(width 0.249936)
		(layer "F.Cu")
		(net "P0V8_SERDES_VDDA_PEX3")
	)
	(segment
		(start 415.074862 -299.224954)
		(end 414.599882 -298.74972)
		(width 0.249936)
		(layer "F.Cu")
		(net "P0V8_SERDES_VDDA_PEX3")
	)
	(segment
		(start 409.374848 -299.224954)
		(end 409.849828 -298.74972)
		(width 0.249936)
		(layer "F.Cu")
		(net "P0V8_SERDES_VDDA_PEX3")
	)
	(segment
		(start 400.824954 -292.57498)
		(end 401.299934 -293.04996)
		(width 0.249936)
		(layer "F.Cu")
		(net "P0V8_SERDES_VDDA_PEX3")
	)
	(segment
		(start 414.124902 -301.124874)
		(end 414.599882 -300.649894)
		(width 0.249936)
		(layer "F.Cu")
		(net "P0V8_SERDES_VDDA_PEX3")
	)
	(segment
		(start 410.799788 -291.149786)
		(end 411.275022 -290.674806)
		(width 0.249936)
		(layer "F.Cu")
		(net "P0V8_SERDES_VDDA_PEX3")
	)
	(segment
		(start 415.074862 -301.124874)
		(end 414.599882 -300.649894)
		(width 0.249936)
		(layer "F.Cu")
		(net "P0V8_SERDES_VDDA_PEX3")
	)
	(segment
		(start 408.424888 -292.574726)
		(end 408.899868 -293.04996)
		(width 0.249936)
		(layer "F.Cu")
		(net "P0V8_SERDES_VDDA_PEX3")
	)
	(segment
		(start 403.674834 -292.57498)
		(end 404.149814 -293.04996)
		(width 0.249936)
		(layer "F.Cu")
		(net "P0V8_SERDES_VDDA_PEX3")
	)
	(segment
		(start 415.074862 -294.4749)
		(end 415.549842 -294.94988)
		(width 0.249936)
		(layer "F.Cu")
		(net "P0V8_SERDES_VDDA_PEX3")
	)
	(segment
		(start 416.024822 -297.32478)
		(end 416.499802 -296.8498)
		(width 0.249936)
		(layer "F.Cu")
		(net "P0V8_SERDES_VDDA_PEX3")
	)
	(segment
		(start 412.224982 -292.574726)
		(end 411.750002 -293.04996)
		(width 0.249936)
		(layer "F.Cu")
		(net "P0V8_SERDES_VDDA_PEX3")
	)
	(segment
		(start 404.149814 -291.149786)
		(end 404.624794 -290.674806)
		(width 0.249936)
		(layer "F.Cu")
		(net "P0V8_SERDES_VDDA_PEX3")
	)
	(segment
		(start 410.324808 -290.674806)
		(end 410.799788 -291.149786)
		(width 0.249936)
		(layer "F.Cu")
		(net "P0V8_SERDES_VDDA_PEX3")
	)
	(segment
		(start 414.599882 -293.04996)
		(end 415.074862 -292.574726)
		(width 0.249936)
		(layer "F.Cu")
		(net "P0V8_SERDES_VDDA_PEX3")
	)
	(segment
		(start 402.724874 -299.224954)
		(end 403.199854 -298.74972)
		(width 0.249936)
		(layer "F.Cu")
		(net "P0V8_SERDES_VDDA_PEX3")
	)
	(segment
		(start 403.199854 -291.149786)
		(end 403.674834 -290.674806)
		(width 0.249936)
		(layer "F.Cu")
		(net "P0V8_SERDES_VDDA_PEX3")
	)
	(segment
		(start 411.275022 -290.674806)
		(end 411.750002 -291.149786)
		(width 0.249936)
		(layer "F.Cu")
		(net "P0V8_SERDES_VDDA_PEX3")
	)
	(segment
		(start 410.324808 -292.574726)
		(end 409.849828 -293.04996)
		(width 0.249936)
		(layer "F.Cu")
		(net "P0V8_SERDES_VDDA_PEX3")
	)
	(segment
		(start 410.799788 -298.74972)
		(end 411.275022 -299.224954)
		(width 0.249936)
		(layer "F.Cu")
		(net "P0V8_SERDES_VDDA_PEX3")
	)
	(segment
		(start 405.100028 -291.149786)
		(end 405.575008 -290.674806)
		(width 0.249936)
		(layer "F.Cu")
		(net "P0V8_SERDES_VDDA_PEX3")
	)
	(segment
		(start 402.724874 -301.124874)
		(end 402.249894 -300.649894)
		(width 0.249936)
		(layer "F.Cu")
		(net "P0V8_SERDES_VDDA_PEX3")
	)
	(segment
		(start 408.424888 -301.124874)
		(end 408.899868 -300.649894)
		(width 0.249936)
		(layer "F.Cu")
		(net "P0V8_SERDES_VDDA_PEX3")
	)
	(segment
		(start 414.599882 -294.94988)
		(end 415.074862 -294.4749)
		(width 0.249936)
		(layer "F.Cu")
		(net "P0V8_SERDES_VDDA_PEX3")
	)
	(segment
		(start 402.249894 -300.649894)
		(end 401.774914 -301.124874)
		(width 0.249936)
		(layer "F.Cu")
		(net "P0V8_SERDES_VDDA_PEX3")
	)
	(segment
		(start 416.024822 -290.674806)
		(end 415.549842 -291.149786)
		(width 0.249936)
		(layer "F.Cu")
		(net "P0V8_SERDES_VDDA_PEX3")
	)
	(segment
		(start 402.249894 -291.149786)
		(end 401.774914 -290.674806)
		(width 0.249936)
		(layer "F.Cu")
		(net "P0V8_SERDES_VDDA_PEX3")
	)
	(segment
		(start 408.424888 -290.674806)
		(end 408.899868 -291.149786)
		(width 0.249936)
		(layer "F.Cu")
		(net "P0V8_SERDES_VDDA_PEX3")
	)
	(segment
		(start 415.074862 -290.674806)
		(end 414.599882 -291.149786)
		(width 0.249936)
		(layer "F.Cu")
		(net "P0V8_SERDES_VDDA_PEX3")
	)
	(via
		(at 400.824954 -290.674806)
		(size 0.4064)
		(drill 0.2032)
		(layers "F.Cu" "B.Cu")
		(net "P0V8_SERDES_VDDA_PEX3")
	)
	(via
		(at 416.024822 -299.224954)
		(size 0.4064)
		(drill 0.2032)
		(layers "F.Cu" "B.Cu")
		(net "P0V8_SERDES_VDDA_PEX3")
	)
	(via
		(at 398.925034 -290.674806)
		(size 0.4064)
		(drill 0.2032)
		(layers "F.Cu" "B.Cu")
		(net "P0V8_SERDES_VDDA_PEX3")
	)
	(via
		(at 361.142534 -320.08064)
		(size 0.508)
		(drill 0.254)
		(layers "F.Cu" "B.Cu")
		(net "P0V8_SERDES_VDDA_PEX3")
	)
	(via
		(at 402.724874 -299.224954)
		(size 0.4064)
		(drill 0.2032)
		(layers "F.Cu" "B.Cu")
		(net "P0V8_SERDES_VDDA_PEX3")
	)
	(via
		(at 356.570534 -320.08064)
		(size 0.508)
		(drill 0.254)
		(layers "F.Cu" "B.Cu")
		(net "P0V8_SERDES_VDDA_PEX3")
	)
	(via
		(at 355.046534 -320.08064)
		(size 0.508)
		(drill 0.254)
		(layers "F.Cu" "B.Cu")
		(net "P0V8_SERDES_VDDA_PEX3")
	)
	(via
		(at 351.705418 -310.840882)
		(size 0.6604)
		(drill 0.3302)
		(layers "F.Cu" "B.Cu")
		(net "P0V8_SERDES_VDDA_PEX3")
	)
	(via
		(at 406.524968 -299.224954)
		(size 0.4064)
		(drill 0.2032)
		(layers "F.Cu" "B.Cu")
		(net "P0V8_SERDES_VDDA_PEX3")
	)
	(via
		(at 358.856534 -319.31864)
		(size 0.508)
		(drill 0.254)
		(layers "F.Cu" "B.Cu")
		(net "P0V8_SERDES_VDDA_PEX3")
	)
	(via
		(at 360.380534 -320.08064)
		(size 0.508)
		(drill 0.254)
		(layers "F.Cu" "B.Cu")
		(net "P0V8_SERDES_VDDA_PEX3")
	)
	(via
		(at 416.974782 -297.32478)
		(size 0.4064)
		(drill 0.2032)
		(layers "F.Cu" "B.Cu")
		(net "P0V8_SERDES_VDDA_PEX3")
	)
	(via
		(at 415.074862 -294.4749)
		(size 0.4064)
		(drill 0.2032)
		(layers "F.Cu" "B.Cu")
		(net "P0V8_SERDES_VDDA_PEX3")
	)
	(via
		(at 406.524968 -301.124874)
		(size 0.4064)
		(drill 0.2032)
		(layers "F.Cu" "B.Cu")
		(net "P0V8_SERDES_VDDA_PEX3")
	)
	(via
		(at 357.332534 -320.08064)
		(size 0.508)
		(drill 0.254)
		(layers "F.Cu" "B.Cu")
		(net "P0V8_SERDES_VDDA_PEX3")
	)
	(via
		(at 399.874994 -299.224954)
		(size 0.4064)
		(drill 0.2032)
		(layers "F.Cu" "B.Cu")
		(net "P0V8_SERDES_VDDA_PEX3")
	)
	(via
		(at 400.824954 -292.57498)
		(size 0.4064)
		(drill 0.2032)
		(layers "F.Cu" "B.Cu")
		(net "P0V8_SERDES_VDDA_PEX3")
	)
	(via
		(at 399.874994 -292.57498)
		(size 0.4064)
		(drill 0.2032)
		(layers "F.Cu" "B.Cu")
		(net "P0V8_SERDES_VDDA_PEX3")
	)
	(via
		(at 416.024822 -292.574726)
		(size 0.4064)
		(drill 0.2032)
		(layers "F.Cu" "B.Cu")
		(net "P0V8_SERDES_VDDA_PEX3")
	)
	(via
		(at 354.284534 -319.31864)
		(size 0.508)
		(drill 0.254)
		(layers "F.Cu" "B.Cu")
		(net "P0V8_SERDES_VDDA_PEX3")
	)
	(via
		(at 360.380534 -319.31864)
		(size 0.508)
		(drill 0.254)
		(layers "F.Cu" "B.Cu")
		(net "P0V8_SERDES_VDDA_PEX3")
	)
	(via
		(at 358.094534 -320.08064)
		(size 0.508)
		(drill 0.254)
		(layers "F.Cu" "B.Cu")
		(net "P0V8_SERDES_VDDA_PEX3")
	)
	(via
		(at 416.974782 -294.4749)
		(size 0.4064)
		(drill 0.2032)
		(layers "F.Cu" "B.Cu")
		(net "P0V8_SERDES_VDDA_PEX3")
	)
	(via
		(at 406.524968 -290.674806)
		(size 0.4064)
		(drill 0.2032)
		(layers "F.Cu" "B.Cu")
		(net "P0V8_SERDES_VDDA_PEX3")
	)
	(via
		(at 400.824954 -299.224954)
		(size 0.4064)
		(drill 0.2032)
		(layers "F.Cu" "B.Cu")
		(net "P0V8_SERDES_VDDA_PEX3")
	)
	(via
		(at 398.925034 -301.124874)
		(size 0.4064)
		(drill 0.2032)
		(layers "F.Cu" "B.Cu")
		(net "P0V8_SERDES_VDDA_PEX3")
	)
	(via
		(at 412.224982 -299.224954)
		(size 0.4064)
		(drill 0.2032)
		(layers "F.Cu" "B.Cu")
		(net "P0V8_SERDES_VDDA_PEX3")
	)
	(via
		(at 409.374848 -292.574726)
		(size 0.4064)
		(drill 0.2032)
		(layers "F.Cu" "B.Cu")
		(net "P0V8_SERDES_VDDA_PEX3")
	)
	(via
		(at 402.724874 -301.124874)
		(size 0.4064)
		(drill 0.2032)
		(layers "F.Cu" "B.Cu")
		(net "P0V8_SERDES_VDDA_PEX3")
	)
	(via
		(at 351.998534 -320.08064)
		(size 0.508)
		(drill 0.254)
		(layers "F.Cu" "B.Cu")
		(net "P0V8_SERDES_VDDA_PEX3")
	)
	(via
		(at 352.760534 -320.08064)
		(size 0.508)
		(drill 0.254)
		(layers "F.Cu" "B.Cu")
		(net "P0V8_SERDES_VDDA_PEX3")
	)
	(via
		(at 414.124902 -290.674806)
		(size 0.4064)
		(drill 0.2032)
		(layers "F.Cu" "B.Cu")
		(net "P0V8_SERDES_VDDA_PEX3")
	)
	(via
		(at 408.424888 -292.574726)
		(size 0.4064)
		(drill 0.2032)
		(layers "F.Cu" "B.Cu")
		(net "P0V8_SERDES_VDDA_PEX3")
	)
	(via
		(at 411.275022 -292.574726)
		(size 0.4064)
		(drill 0.2032)
		(layers "F.Cu" "B.Cu")
		(net "P0V8_SERDES_VDDA_PEX3")
	)
	(via
		(at 398.925034 -292.57498)
		(size 0.4064)
		(drill 0.2032)
		(layers "F.Cu" "B.Cu")
		(net "P0V8_SERDES_VDDA_PEX3")
	)
	(via
		(at 358.094534 -319.31864)
		(size 0.508)
		(drill 0.254)
		(layers "F.Cu" "B.Cu")
		(net "P0V8_SERDES_VDDA_PEX3")
	)
	(via
		(at 356.570534 -319.31864)
		(size 0.508)
		(drill 0.254)
		(layers "F.Cu" "B.Cu")
		(net "P0V8_SERDES_VDDA_PEX3")
	)
	(via
		(at 413.174942 -299.224954)
		(size 0.4064)
		(drill 0.2032)
		(layers "F.Cu" "B.Cu")
		(net "P0V8_SERDES_VDDA_PEX3")
	)
	(via
		(at 409.374848 -290.674806)
		(size 0.4064)
		(drill 0.2032)
		(layers "F.Cu" "B.Cu")
		(net "P0V8_SERDES_VDDA_PEX3")
	)
	(via
		(at 404.624794 -299.224954)
		(size 0.4064)
		(drill 0.2032)
		(layers "F.Cu" "B.Cu")
		(net "P0V8_SERDES_VDDA_PEX3")
	)
	(via
		(at 404.624794 -290.674806)
		(size 0.4064)
		(drill 0.2032)
		(layers "F.Cu" "B.Cu")
		(net "P0V8_SERDES_VDDA_PEX3")
	)
	(via
		(at 412.224982 -301.124874)
		(size 0.4064)
		(drill 0.2032)
		(layers "F.Cu" "B.Cu")
		(net "P0V8_SERDES_VDDA_PEX3")
	)
	(via
		(at 405.575008 -299.224954)
		(size 0.4064)
		(drill 0.2032)
		(layers "F.Cu" "B.Cu")
		(net "P0V8_SERDES_VDDA_PEX3")
	)
	(via
		(at 403.674834 -290.674806)
		(size 0.4064)
		(drill 0.2032)
		(layers "F.Cu" "B.Cu")
		(net "P0V8_SERDES_VDDA_PEX3")
	)
	(via
		(at 415.074862 -299.224954)
		(size 0.4064)
		(drill 0.2032)
		(layers "F.Cu" "B.Cu")
		(net "P0V8_SERDES_VDDA_PEX3")
	)
	(via
		(at 403.674834 -292.57498)
		(size 0.4064)
		(drill 0.2032)
		(layers "F.Cu" "B.Cu")
		(net "P0V8_SERDES_VDDA_PEX3")
	)
	(via
		(at 412.224982 -290.674806)
		(size 0.4064)
		(drill 0.2032)
		(layers "F.Cu" "B.Cu")
		(net "P0V8_SERDES_VDDA_PEX3")
	)
	(via
		(at 351.998534 -319.31864)
		(size 0.508)
		(drill 0.254)
		(layers "F.Cu" "B.Cu")
		(net "P0V8_SERDES_VDDA_PEX3")
	)
	(via
		(at 351.047812 -314.649612)
		(size 0.6604)
		(drill 0.3302)
		(layers "F.Cu" "B.Cu")
		(net "P0V8_SERDES_VDDA_PEX3")
	)
	(via
		(at 401.774914 -292.57498)
		(size 0.4064)
		(drill 0.2032)
		(layers "F.Cu" "B.Cu")
		(net "P0V8_SERDES_VDDA_PEX3")
	)
	(via
		(at 403.674834 -301.124874)
		(size 0.4064)
		(drill 0.2032)
		(layers "F.Cu" "B.Cu")
		(net "P0V8_SERDES_VDDA_PEX3")
	)
	(via
		(at 353.522534 -319.31864)
		(size 0.508)
		(drill 0.254)
		(layers "F.Cu" "B.Cu")
		(net "P0V8_SERDES_VDDA_PEX3")
	)
	(via
		(at 358.856534 -320.08064)
		(size 0.508)
		(drill 0.254)
		(layers "F.Cu" "B.Cu")
		(net "P0V8_SERDES_VDDA_PEX3")
	)
	(via
		(at 415.074862 -292.574726)
		(size 0.4064)
		(drill 0.2032)
		(layers "F.Cu" "B.Cu")
		(net "P0V8_SERDES_VDDA_PEX3")
	)
	(via
		(at 402.724874 -290.674806)
		(size 0.4064)
		(drill 0.2032)
		(layers "F.Cu" "B.Cu")
		(net "P0V8_SERDES_VDDA_PEX3")
	)
	(via
		(at 410.324808 -301.124874)
		(size 0.4064)
		(drill 0.2032)
		(layers "F.Cu" "B.Cu")
		(net "P0V8_SERDES_VDDA_PEX3")
	)
	(via
		(at 415.074862 -301.124874)
		(size 0.4064)
		(drill 0.2032)
		(layers "F.Cu" "B.Cu")
		(net "P0V8_SERDES_VDDA_PEX3")
	)
	(via
		(at 409.374848 -301.124874)
		(size 0.4064)
		(drill 0.2032)
		(layers "F.Cu" "B.Cu")
		(net "P0V8_SERDES_VDDA_PEX3")
	)
	(via
		(at 416.024822 -294.4749)
		(size 0.4064)
		(drill 0.2032)
		(layers "F.Cu" "B.Cu")
		(net "P0V8_SERDES_VDDA_PEX3")
	)
	(via
		(at 361.142534 -319.31864)
		(size 0.508)
		(drill 0.254)
		(layers "F.Cu" "B.Cu")
		(net "P0V8_SERDES_VDDA_PEX3")
	)
	(via
		(at 403.674834 -299.224954)
		(size 0.4064)
		(drill 0.2032)
		(layers "F.Cu" "B.Cu")
		(net "P0V8_SERDES_VDDA_PEX3")
	)
	(via
		(at 354.284534 -320.08064)
		(size 0.508)
		(drill 0.254)
		(layers "F.Cu" "B.Cu")
		(net "P0V8_SERDES_VDDA_PEX3")
	)
	(via
		(at 405.575008 -292.57498)
		(size 0.4064)
		(drill 0.2032)
		(layers "F.Cu" "B.Cu")
		(net "P0V8_SERDES_VDDA_PEX3")
	)
	(via
		(at 408.424888 -290.674806)
		(size 0.4064)
		(drill 0.2032)
		(layers "F.Cu" "B.Cu")
		(net "P0V8_SERDES_VDDA_PEX3")
	)
	(via
		(at 404.625048 -292.57498)
		(size 0.4064)
		(drill 0.2032)
		(layers "F.Cu" "B.Cu")
		(net "P0V8_SERDES_VDDA_PEX3")
	)
	(via
		(at 399.874994 -301.124874)
		(size 0.4064)
		(drill 0.2032)
		(layers "F.Cu" "B.Cu")
		(net "P0V8_SERDES_VDDA_PEX3")
	)
	(via
		(at 411.275022 -301.124874)
		(size 0.4064)
		(drill 0.2032)
		(layers "F.Cu" "B.Cu")
		(net "P0V8_SERDES_VDDA_PEX3")
	)
	(via
		(at 413.174942 -301.124874)
		(size 0.4064)
		(drill 0.2032)
		(layers "F.Cu" "B.Cu")
		(net "P0V8_SERDES_VDDA_PEX3")
	)
	(via
		(at 350.73717 -312.457592)
		(size 0.6604)
		(drill 0.3302)
		(layers "F.Cu" "B.Cu")
		(net "P0V8_SERDES_VDDA_PEX3")
	)
	(via
		(at 413.174942 -290.674806)
		(size 0.4064)
		(drill 0.2032)
		(layers "F.Cu" "B.Cu")
		(net "P0V8_SERDES_VDDA_PEX3")
	)
	(via
		(at 416.024822 -297.32478)
		(size 0.4064)
		(drill 0.2032)
		(layers "F.Cu" "B.Cu")
		(net "P0V8_SERDES_VDDA_PEX3")
	)
	(via
		(at 415.074862 -297.32478)
		(size 0.4064)
		(drill 0.2032)
		(layers "F.Cu" "B.Cu")
		(net "P0V8_SERDES_VDDA_PEX3")
	)
	(via
		(at 398.925034 -299.224954)
		(size 0.4064)
		(drill 0.2032)
		(layers "F.Cu" "B.Cu")
		(net "P0V8_SERDES_VDDA_PEX3")
	)
	(via
		(at 414.124902 -292.574726)
		(size 0.4064)
		(drill 0.2032)
		(layers "F.Cu" "B.Cu")
		(net "P0V8_SERDES_VDDA_PEX3")
	)
	(via
		(at 415.074862 -290.674806)
		(size 0.4064)
		(drill 0.2032)
		(layers "F.Cu" "B.Cu")
		(net "P0V8_SERDES_VDDA_PEX3")
	)
	(via
		(at 404.624794 -301.124874)
		(size 0.4064)
		(drill 0.2032)
		(layers "F.Cu" "B.Cu")
		(net "P0V8_SERDES_VDDA_PEX3")
	)
	(via
		(at 410.324808 -292.574726)
		(size 0.4064)
		(drill 0.2032)
		(layers "F.Cu" "B.Cu")
		(net "P0V8_SERDES_VDDA_PEX3")
	)
	(via
		(at 405.575008 -290.674806)
		(size 0.4064)
		(drill 0.2032)
		(layers "F.Cu" "B.Cu")
		(net "P0V8_SERDES_VDDA_PEX3")
	)
	(via
		(at 355.046534 -319.31864)
		(size 0.508)
		(drill 0.254)
		(layers "F.Cu" "B.Cu")
		(net "P0V8_SERDES_VDDA_PEX3")
	)
	(via
		(at 414.124902 -299.224954)
		(size 0.4064)
		(drill 0.2032)
		(layers "F.Cu" "B.Cu")
		(net "P0V8_SERDES_VDDA_PEX3")
	)
	(via
		(at 399.874994 -290.674806)
		(size 0.4064)
		(drill 0.2032)
		(layers "F.Cu" "B.Cu")
		(net "P0V8_SERDES_VDDA_PEX3")
	)
	(via
		(at 405.575008 -301.124874)
		(size 0.4064)
		(drill 0.2032)
		(layers "F.Cu" "B.Cu")
		(net "P0V8_SERDES_VDDA_PEX3")
	)
	(via
		(at 401.774914 -301.124874)
		(size 0.4064)
		(drill 0.2032)
		(layers "F.Cu" "B.Cu")
		(net "P0V8_SERDES_VDDA_PEX3")
	)
	(via
		(at 353.522534 -320.08064)
		(size 0.508)
		(drill 0.254)
		(layers "F.Cu" "B.Cu")
		(net "P0V8_SERDES_VDDA_PEX3")
	)
	(via
		(at 410.324808 -299.224954)
		(size 0.4064)
		(drill 0.2032)
		(layers "F.Cu" "B.Cu")
		(net "P0V8_SERDES_VDDA_PEX3")
	)
	(via
		(at 401.774914 -290.674806)
		(size 0.4064)
		(drill 0.2032)
		(layers "F.Cu" "B.Cu")
		(net "P0V8_SERDES_VDDA_PEX3")
	)
	(via
		(at 416.024822 -290.674806)
		(size 0.4064)
		(drill 0.2032)
		(layers "F.Cu" "B.Cu")
		(net "P0V8_SERDES_VDDA_PEX3")
	)
	(via
		(at 416.024822 -296.37482)
		(size 0.4064)
		(drill 0.2032)
		(layers "F.Cu" "B.Cu")
		(net "P0V8_SERDES_VDDA_PEX3")
	)
	(via
		(at 411.275022 -290.674806)
		(size 0.4064)
		(drill 0.2032)
		(layers "F.Cu" "B.Cu")
		(net "P0V8_SERDES_VDDA_PEX3")
	)
	(via
		(at 410.324808 -290.674806)
		(size 0.4064)
		(drill 0.2032)
		(layers "F.Cu" "B.Cu")
		(net "P0V8_SERDES_VDDA_PEX3")
	)
	(via
		(at 408.424888 -301.124874)
		(size 0.4064)
		(drill 0.2032)
		(layers "F.Cu" "B.Cu")
		(net "P0V8_SERDES_VDDA_PEX3")
	)
	(via
		(at 352.760534 -319.31864)
		(size 0.508)
		(drill 0.254)
		(layers "F.Cu" "B.Cu")
		(net "P0V8_SERDES_VDDA_PEX3")
	)
	(via
		(at 416.024822 -301.124874)
		(size 0.4064)
		(drill 0.2032)
		(layers "F.Cu" "B.Cu")
		(net "P0V8_SERDES_VDDA_PEX3")
	)
	(via
		(at 411.275022 -299.224954)
		(size 0.4064)
		(drill 0.2032)
		(layers "F.Cu" "B.Cu")
		(net "P0V8_SERDES_VDDA_PEX3")
	)
	(via
		(at 409.374848 -299.224954)
		(size 0.4064)
		(drill 0.2032)
		(layers "F.Cu" "B.Cu")
		(net "P0V8_SERDES_VDDA_PEX3")
	)
	(via
		(at 357.332534 -319.31864)
		(size 0.508)
		(drill 0.254)
		(layers "F.Cu" "B.Cu")
		(net "P0V8_SERDES_VDDA_PEX3")
	)
	(via
		(at 359.618534 -320.08064)
		(size 0.508)
		(drill 0.254)
		(layers "F.Cu" "B.Cu")
		(net "P0V8_SERDES_VDDA_PEX3")
	)
	(via
		(at 359.618534 -319.31864)
		(size 0.508)
		(drill 0.254)
		(layers "F.Cu" "B.Cu")
		(net "P0V8_SERDES_VDDA_PEX3")
	)
	(via
		(at 401.774914 -299.224954)
		(size 0.4064)
		(drill 0.2032)
		(layers "F.Cu" "B.Cu")
		(net "P0V8_SERDES_VDDA_PEX3")
	)
	(via
		(at 412.224982 -292.574726)
		(size 0.4064)
		(drill 0.2032)
		(layers "F.Cu" "B.Cu")
		(net "P0V8_SERDES_VDDA_PEX3")
	)
	(via
		(at 416.974782 -296.37482)
		(size 0.4064)
		(drill 0.2032)
		(layers "F.Cu" "B.Cu")
		(net "P0V8_SERDES_VDDA_PEX3")
	)
	(via
		(at 400.824954 -301.124874)
		(size 0.4064)
		(drill 0.2032)
		(layers "F.Cu" "B.Cu")
		(net "P0V8_SERDES_VDDA_PEX3")
	)
	(via
		(at 355.808534 -319.31864)
		(size 0.508)
		(drill 0.254)
		(layers "F.Cu" "B.Cu")
		(net "P0V8_SERDES_VDDA_PEX3")
	)
	(via
		(at 413.174942 -292.574726)
		(size 0.4064)
		(drill 0.2032)
		(layers "F.Cu" "B.Cu")
		(net "P0V8_SERDES_VDDA_PEX3")
	)
	(via
		(at 402.724874 -292.57498)
		(size 0.4064)
		(drill 0.2032)
		(layers "F.Cu" "B.Cu")
		(net "P0V8_SERDES_VDDA_PEX3")
	)
	(via
		(at 408.424888 -299.224954)
		(size 0.4064)
		(drill 0.2032)
		(layers "F.Cu" "B.Cu")
		(net "P0V8_SERDES_VDDA_PEX3")
	)
	(via
		(at 414.124902 -301.124874)
		(size 0.4064)
		(drill 0.2032)
		(layers "F.Cu" "B.Cu")
		(net "P0V8_SERDES_VDDA_PEX3")
	)
	(via
		(at 355.808534 -320.08064)
		(size 0.508)
		(drill 0.254)
		(layers "F.Cu" "B.Cu")
		(net "P0V8_SERDES_VDDA_PEX3")
	)
	(via
		(at 406.524968 -292.57498)
		(size 0.4064)
		(drill 0.2032)
		(layers "F.Cu" "B.Cu")
		(net "P0V8_SERDES_VDDA_PEX3")
	)
	(segment
		(start 354.130864 -281.989276)
		(end 354.120958 -281.999182)
		(width 0.2286)
		(layer "F.Cu")
		(net "SW_P0V8_PEX3_BOOT1")
	)
	(segment
		(start 354.130864 -280.84907)
		(end 354.130864 -281.989276)
		(width 0.2286)
		(layer "F.Cu")
		(net "SW_P0V8_PEX3_BOOT1")
	)
	(segment
		(start 288.524696 -290.674806)
		(end 288.99993 -291.149786)
		(width 0.249936)
		(layer "F.Cu")
		(net "P0V8_SERDES_VDDA_PEX2")
	)
	(segment
		(start 283.299916 -291.149786)
		(end 282.824936 -290.674806)
		(width 0.249936)
		(layer "F.Cu")
		(net "P0V8_SERDES_VDDA_PEX2")
	)
	(segment
		(start 287.574736 -299.224954)
		(end 287.099756 -298.74972)
		(width 0.249936)
		(layer "F.Cu")
		(net "P0V8_SERDES_VDDA_PEX2")
	)
	(segment
		(start 289.47491 -299.224954)
		(end 288.99993 -298.74972)
		(width 0.249936)
		(layer "F.Cu")
		(net "P0V8_SERDES_VDDA_PEX2")
	)
	(segment
		(start 284.249876 -300.649894)
		(end 284.724856 -301.124874)
		(width 0.249936)
		(layer "F.Cu")
		(net "P0V8_SERDES_VDDA_PEX2")
	)
	(segment
		(start 297.074844 -299.224954)
		(end 297.549824 -298.74972)
		(width 0.249936)
		(layer "F.Cu")
		(net "P0V8_SERDES_VDDA_PEX2")
	)
	(segment
		(start 295.649904 -298.74972)
		(end 296.124884 -299.224954)
		(width 0.249936)
		(layer "F.Cu")
		(net "P0V8_SERDES_VDDA_PEX2")
	)
	(segment
		(start 285.199836 -300.649894)
		(end 285.674816 -301.124874)
		(width 0.249936)
		(layer "F.Cu")
		(net "P0V8_SERDES_VDDA_PEX2")
	)
	(segment
		(start 291.84981 -293.04996)
		(end 292.32479 -292.574726)
		(width 0.249936)
		(layer "F.Cu")
		(net "P0V8_SERDES_VDDA_PEX2")
	)
	(segment
		(start 299.924724 -296.37482)
		(end 299.449744 -295.89984)
		(width 0.249936)
		(layer "F.Cu")
		(net "P0V8_SERDES_VDDA_PEX2")
	)
	(segment
		(start 293.74973 -300.649894)
		(end 294.22471 -301.124874)
		(width 0.249936)
		(layer "F.Cu")
		(net "P0V8_SERDES_VDDA_PEX2")
	)
	(segment
		(start 297.074844 -301.124874)
		(end 297.549824 -300.649894)
		(width 0.249936)
		(layer "F.Cu")
		(net "P0V8_SERDES_VDDA_PEX2")
	)
	(segment
		(start 294.22471 -301.124874)
		(end 294.69969 -300.649894)
		(width 0.249936)
		(layer "F.Cu")
		(net "P0V8_SERDES_VDDA_PEX2")
	)
	(segment
		(start 297.549824 -300.649894)
		(end 298.024804 -301.124874)
		(width 0.249936)
		(layer "F.Cu")
		(net "P0V8_SERDES_VDDA_PEX2")
	)
	(segment
		(start 298.024804 -292.574726)
		(end 298.499784 -293.04996)
		(width 0.249936)
		(layer "F.Cu")
		(net "P0V8_SERDES_VDDA_PEX2")
	)
	(segment
		(start 296.599864 -300.649894)
		(end 296.124884 -301.124874)
		(width 0.249936)
		(layer "F.Cu")
		(net "P0V8_SERDES_VDDA_PEX2")
	)
	(segment
		(start 300.399704 -296.8498)
		(end 300.874684 -297.32478)
		(width 0.249936)
		(layer "F.Cu")
		(net "P0V8_SERDES_VDDA_PEX2")
	)
	(segment
		(start 298.499784 -291.149786)
		(end 298.974764 -290.674806)
		(width 0.249936)
		(layer "F.Cu")
		(net "P0V8_SERDES_VDDA_PEX2")
	)
	(segment
		(start 299.449744 -296.8498)
		(end 299.924724 -297.32478)
		(width 0.249936)
		(layer "F.Cu")
		(net "P0V8_SERDES_VDDA_PEX2")
	)
	(segment
		(start 294.69969 -300.649894)
		(end 295.174924 -301.124874)
		(width 0.249936)
		(layer "F.Cu")
		(net "P0V8_SERDES_VDDA_PEX2")
	)
	(segment
		(start 284.249876 -291.149786)
		(end 284.724856 -290.674806)
		(width 0.249936)
		(layer "F.Cu")
		(net "P0V8_SERDES_VDDA_PEX2")
	)
	(segment
		(start 297.549824 -291.149786)
		(end 298.024804 -290.674806)
		(width 0.249936)
		(layer "F.Cu")
		(net "P0V8_SERDES_VDDA_PEX2")
	)
	(segment
		(start 288.049716 -298.74972)
		(end 287.574736 -299.224954)
		(width 0.249936)
		(layer "F.Cu")
		(net "P0V8_SERDES_VDDA_PEX2")
	)
	(segment
		(start 288.524696 -299.224954)
		(end 288.99993 -298.74972)
		(width 0.249936)
		(layer "F.Cu")
		(net "P0V8_SERDES_VDDA_PEX2")
	)
	(segment
		(start 289.47491 -292.57498)
		(end 289.94989 -293.04996)
		(width 0.249936)
		(layer "F.Cu")
		(net "P0V8_SERDES_VDDA_PEX2")
	)
	(segment
		(start 295.174924 -299.224954)
		(end 294.69969 -298.74972)
		(width 0.249936)
		(layer "F.Cu")
		(net "P0V8_SERDES_VDDA_PEX2")
	)
	(segment
		(start 293.27475 -292.574726)
		(end 292.79977 -293.04996)
		(width 0.249936)
		(layer "F.Cu")
		(net "P0V8_SERDES_VDDA_PEX2")
	)
	(segment
		(start 283.299916 -291.149786)
		(end 283.774896 -290.674806)
		(width 0.249936)
		(layer "F.Cu")
		(net "P0V8_SERDES_VDDA_PEX2")
	)
	(segment
		(start 290.42487 -299.224954)
		(end 290.89985 -298.74972)
		(width 0.249936)
		(layer "F.Cu")
		(net "P0V8_SERDES_VDDA_PEX2")
	)
	(segment
		(start 295.174924 -290.674806)
		(end 295.649904 -291.149786)
		(width 0.249936)
		(layer "F.Cu")
		(net "P0V8_SERDES_VDDA_PEX2")
	)
	(segment
		(start 297.549824 -293.04996)
		(end 297.074844 -292.574726)
		(width 0.249936)
		(layer "F.Cu")
		(net "P0V8_SERDES_VDDA_PEX2")
	)
	(segment
		(start 296.599864 -291.149786)
		(end 296.124884 -290.674806)
		(width 0.249936)
		(layer "F.Cu")
		(net "P0V8_SERDES_VDDA_PEX2")
	)
	(segment
		(start 285.674816 -299.224954)
		(end 286.149796 -298.74972)
		(width 0.249936)
		(layer "F.Cu")
		(net "P0V8_SERDES_VDDA_PEX2")
	)
	(segment
		(start 284.724856 -290.674806)
		(end 285.199836 -291.149786)
		(width 0.249936)
		(layer "F.Cu")
		(net "P0V8_SERDES_VDDA_PEX2")
	)
	(segment
		(start 290.42487 -292.57498)
		(end 290.89985 -293.04996)
		(width 0.249936)
		(layer "F.Cu")
		(net "P0V8_SERDES_VDDA_PEX2")
	)
	(segment
		(start 295.174924 -292.574726)
		(end 295.649904 -293.04996)
		(width 0.249936)
		(layer "F.Cu")
		(net "P0V8_SERDES_VDDA_PEX2")
	)
	(segment
		(start 289.94989 -298.74972)
		(end 289.47491 -299.224954)
		(width 0.249936)
		(layer "F.Cu")
		(net "P0V8_SERDES_VDDA_PEX2")
	)
	(segment
		(start 296.124884 -290.674806)
		(end 295.649904 -291.149786)
		(width 0.249936)
		(layer "F.Cu")
		(net "P0V8_SERDES_VDDA_PEX2")
	)
	(segment
		(start 299.449744 -291.149786)
		(end 299.924724 -290.674806)
		(width 0.249936)
		(layer "F.Cu")
		(net "P0V8_SERDES_VDDA_PEX2")
	)
	(segment
		(start 289.47491 -290.674806)
		(end 288.99993 -291.149786)
		(width 0.249936)
		(layer "F.Cu")
		(net "P0V8_SERDES_VDDA_PEX2")
	)
	(segment
		(start 292.32479 -290.674806)
		(end 292.79977 -291.149786)
		(width 0.249936)
		(layer "F.Cu")
		(net "P0V8_SERDES_VDDA_PEX2")
	)
	(segment
		(start 289.94989 -300.649894)
		(end 290.42487 -301.124874)
		(width 0.249936)
		(layer "F.Cu")
		(net "P0V8_SERDES_VDDA_PEX2")
	)
	(segment
		(start 283.774896 -301.124874)
		(end 283.299916 -300.649894)
		(width 0.249936)
		(layer "F.Cu")
		(net "P0V8_SERDES_VDDA_PEX2")
	)
	(segment
		(start 299.924724 -297.32478)
		(end 300.399704 -296.8498)
		(width 0.249936)
		(layer "F.Cu")
		(net "P0V8_SERDES_VDDA_PEX2")
	)
	(segment
		(start 293.27475 -301.124874)
		(end 292.79977 -300.649894)
		(width 0.249936)
		(layer "F.Cu")
		(net "P0V8_SERDES_VDDA_PEX2")
	)
	(segment
		(start 296.599864 -293.04996)
		(end 296.124884 -292.574726)
		(width 0.249936)
		(layer "F.Cu")
		(net "P0V8_SERDES_VDDA_PEX2")
	)
	(segment
		(start 296.124884 -292.574726)
		(end 295.649904 -293.04996)
		(width 0.249936)
		(layer "F.Cu")
		(net "P0V8_SERDES_VDDA_PEX2")
	)
	(segment
		(start 286.624776 -299.224954)
		(end 286.149796 -298.74972)
		(width 0.249936)
		(layer "F.Cu")
		(net "P0V8_SERDES_VDDA_PEX2")
	)
	(segment
		(start 297.549824 -293.04996)
		(end 298.024804 -292.574726)
		(width 0.249936)
		(layer "F.Cu")
		(net "P0V8_SERDES_VDDA_PEX2")
	)
	(segment
		(start 290.42487 -290.674806)
		(end 290.89985 -291.149786)
		(width 0.249936)
		(layer "F.Cu")
		(net "P0V8_SERDES_VDDA_PEX2")
	)
	(segment
		(start 298.974764 -290.674806)
		(end 299.449744 -291.149786)
		(width 0.249936)
		(layer "F.Cu")
		(net "P0V8_SERDES_VDDA_PEX2")
	)
	(segment
		(start 283.299916 -298.74972)
		(end 282.824936 -299.224954)
		(width 0.249936)
		(layer "F.Cu")
		(net "P0V8_SERDES_VDDA_PEX2")
	)
	(segment
		(start 284.724856 -301.124874)
		(end 285.199836 -300.649894)
		(width 0.249936)
		(layer "F.Cu")
		(net "P0V8_SERDES_VDDA_PEX2")
	)
	(segment
		(start 298.499784 -300.649894)
		(end 298.974764 -301.124874)
		(width 0.249936)
		(layer "F.Cu")
		(net "P0V8_SERDES_VDDA_PEX2")
	)
	(segment
		(start 294.69969 -291.149786)
		(end 295.174924 -290.674806)
		(width 0.249936)
		(layer "F.Cu")
		(net "P0V8_SERDES_VDDA_PEX2")
	)
	(segment
		(start 298.024804 -301.124874)
		(end 298.499784 -300.649894)
		(width 0.249936)
		(layer "F.Cu")
		(net "P0V8_SERDES_VDDA_PEX2")
	)
	(segment
		(start 296.124884 -301.124874)
		(end 295.649904 -300.649894)
		(width 0.249936)
		(layer "F.Cu")
		(net "P0V8_SERDES_VDDA_PEX2")
	)
	(segment
		(start 288.049716 -298.74972)
		(end 288.524696 -299.224954)
		(width 0.249936)
		(layer "F.Cu")
		(net "P0V8_SERDES_VDDA_PEX2")
	)
	(segment
		(start 285.674816 -290.674806)
		(end 286.149796 -291.149786)
		(width 0.249936)
		(layer "F.Cu")
		(net "P0V8_SERDES_VDDA_PEX2")
	)
	(segment
		(start 283.774896 -299.224954)
		(end 284.249876 -298.74972)
		(width 0.249936)
		(layer "F.Cu")
		(net "P0V8_SERDES_VDDA_PEX2")
	)
	(segment
		(start 300.399704 -295.89984)
		(end 300.874684 -296.37482)
		(width 0.249936)
		(layer "F.Cu")
		(net "P0V8_SERDES_VDDA_PEX2")
	)
	(segment
		(start 293.74973 -293.04996)
		(end 294.22471 -292.574726)
		(width 0.249936)
		(layer "F.Cu")
		(net "P0V8_SERDES_VDDA_PEX2")
	)
	(segment
		(start 284.249876 -298.74972)
		(end 284.724856 -299.224954)
		(width 0.249936)
		(layer "F.Cu")
		(net "P0V8_SERDES_VDDA_PEX2")
	)
	(segment
		(start 297.549824 -298.74972)
		(end 298.024804 -299.224954)
		(width 0.249936)
		(layer "F.Cu")
		(net "P0V8_SERDES_VDDA_PEX2")
	)
	(segment
		(start 293.74973 -298.74972)
		(end 293.27475 -299.224954)
		(width 0.249936)
		(layer "F.Cu")
		(net "P0V8_SERDES_VDDA_PEX2")
	)
	(segment
		(start 295.174924 -301.124874)
		(end 295.649904 -300.649894)
		(width 0.249936)
		(layer "F.Cu")
		(net "P0V8_SERDES_VDDA_PEX2")
	)
	(segment
		(start 297.549824 -291.149786)
		(end 297.074844 -290.674806)
		(width 0.249936)
		(layer "F.Cu")
		(net "P0V8_SERDES_VDDA_PEX2")
	)
	(segment
		(start 292.32479 -292.574726)
		(end 292.79977 -293.04996)
		(width 0.249936)
		(layer "F.Cu")
		(net "P0V8_SERDES_VDDA_PEX2")
	)
	(segment
		(start 289.94989 -291.149786)
		(end 290.42487 -290.674806)
		(width 0.249936)
		(layer "F.Cu")
		(net "P0V8_SERDES_VDDA_PEX2")
	)
	(segment
		(start 298.974764 -292.574726)
		(end 299.449744 -293.04996)
		(width 0.249936)
		(layer "F.Cu")
		(net "P0V8_SERDES_VDDA_PEX2")
	)
	(segment
		(start 284.249876 -300.649894)
		(end 283.774896 -301.124874)
		(width 0.249936)
		(layer "F.Cu")
		(net "P0V8_SERDES_VDDA_PEX2")
	)
	(segment
		(start 284.724856 -292.57498)
		(end 285.199836 -293.04996)
		(width 0.249936)
		(layer "F.Cu")
		(net "P0V8_SERDES_VDDA_PEX2")
	)
	(segment
		(start 287.574736 -292.57498)
		(end 288.049716 -293.04996)
		(width 0.249936)
		(layer "F.Cu")
		(net "P0V8_SERDES_VDDA_PEX2")
	)
	(segment
		(start 293.27475 -299.224954)
		(end 292.79977 -298.74972)
		(width 0.249936)
		(layer "F.Cu")
		(net "P0V8_SERDES_VDDA_PEX2")
	)
	(segment
		(start 293.74973 -293.04996)
		(end 293.27475 -292.574726)
		(width 0.249936)
		(layer "F.Cu")
		(net "P0V8_SERDES_VDDA_PEX2")
	)
	(segment
		(start 285.674816 -301.124874)
		(end 286.149796 -300.649894)
		(width 0.249936)
		(layer "F.Cu")
		(net "P0V8_SERDES_VDDA_PEX2")
	)
	(segment
		(start 285.199836 -291.149786)
		(end 285.674816 -290.674806)
		(width 0.249936)
		(layer "F.Cu")
		(net "P0V8_SERDES_VDDA_PEX2")
	)
	(segment
		(start 299.449744 -298.74972)
		(end 299.924724 -299.224954)
		(width 0.249936)
		(layer "F.Cu")
		(net "P0V8_SERDES_VDDA_PEX2")
	)
	(segment
		(start 293.27475 -290.674806)
		(end 292.79977 -291.149786)
		(width 0.249936)
		(layer "F.Cu")
		(net "P0V8_SERDES_VDDA_PEX2")
	)
	(segment
		(start 300.399704 -294.94988)
		(end 300.874684 -294.4749)
		(width 0.249936)
		(layer "F.Cu")
		(net "P0V8_SERDES_VDDA_PEX2")
	)
	(segment
		(start 294.22471 -299.224954)
		(end 294.69969 -298.74972)
		(width 0.249936)
		(layer "F.Cu")
		(net "P0V8_SERDES_VDDA_PEX2")
	)
	(segment
		(start 297.074844 -290.674806)
		(end 296.599864 -291.149786)
		(width 0.249936)
		(layer "F.Cu")
		(net "P0V8_SERDES_VDDA_PEX2")
	)
	(segment
		(start 293.74973 -300.649894)
		(end 293.27475 -301.124874)
		(width 0.249936)
		(layer "F.Cu")
		(net "P0V8_SERDES_VDDA_PEX2")
	)
	(segment
		(start 291.84981 -300.649894)
		(end 292.32479 -301.124874)
		(width 0.249936)
		(layer "F.Cu")
		(net "P0V8_SERDES_VDDA_PEX2")
	)
	(segment
		(start 288.52495 -292.57498)
		(end 288.99993 -293.04996)
		(width 0.249936)
		(layer "F.Cu")
		(net "P0V8_SERDES_VDDA_PEX2")
	)
	(segment
		(start 292.32479 -299.224954)
		(end 292.79977 -298.74972)
		(width 0.249936)
		(layer "F.Cu")
		(net "P0V8_SERDES_VDDA_PEX2")
	)
	(segment
		(start 299.449744 -293.04996)
		(end 299.924724 -292.574726)
		(width 0.249936)
		(layer "F.Cu")
		(net "P0V8_SERDES_VDDA_PEX2")
	)
	(segment
		(start 298.974764 -297.32478)
		(end 298.499784 -296.8498)
		(width 0.249936)
		(layer "F.Cu")
		(net "P0V8_SERDES_VDDA_PEX2")
	)
	(segment
		(start 289.94989 -298.74972)
		(end 290.42487 -299.224954)
		(width 0.249936)
		(layer "F.Cu")
		(net "P0V8_SERDES_VDDA_PEX2")
	)
	(segment
		(start 287.574736 -290.674806)
		(end 287.099756 -291.149786)
		(width 0.249936)
		(layer "F.Cu")
		(net "P0V8_SERDES_VDDA_PEX2")
	)
	(segment
		(start 291.84981 -291.149786)
		(end 292.32479 -290.674806)
		(width 0.249936)
		(layer "F.Cu")
		(net "P0V8_SERDES_VDDA_PEX2")
	)
	(segment
		(start 300.399704 -295.89984)
		(end 299.924724 -296.37482)
		(width 0.249936)
		(layer "F.Cu")
		(net "P0V8_SERDES_VDDA_PEX2")
	)
	(segment
		(start 288.049716 -300.649894)
		(end 288.524696 -301.124874)
		(width 0.249936)
		(layer "F.Cu")
		(net "P0V8_SERDES_VDDA_PEX2")
	)
	(segment
		(start 289.94989 -291.149786)
		(end 289.47491 -290.674806)
		(width 0.249936)
		(layer "F.Cu")
		(net "P0V8_SERDES_VDDA_PEX2")
	)
	(segment
		(start 283.299916 -300.649894)
		(end 282.824936 -301.124874)
		(width 0.249936)
		(layer "F.Cu")
		(net "P0V8_SERDES_VDDA_PEX2")
	)
	(segment
		(start 288.049716 -291.149786)
		(end 288.524696 -290.674806)
		(width 0.249936)
		(layer "F.Cu")
		(net "P0V8_SERDES_VDDA_PEX2")
	)
	(segment
		(start 287.574736 -301.124874)
		(end 287.099756 -300.649894)
		(width 0.249936)
		(layer "F.Cu")
		(net "P0V8_SERDES_VDDA_PEX2")
	)
	(segment
		(start 297.074844 -292.574726)
		(end 296.599864 -293.04996)
		(width 0.249936)
		(layer "F.Cu")
		(net "P0V8_SERDES_VDDA_PEX2")
	)
	(segment
		(start 288.049716 -291.149786)
		(end 287.574736 -290.674806)
		(width 0.249936)
		(layer "F.Cu")
		(net "P0V8_SERDES_VDDA_PEX2")
	)
	(segment
		(start 283.299916 -298.74972)
		(end 283.774896 -299.224954)
		(width 0.249936)
		(layer "F.Cu")
		(net "P0V8_SERDES_VDDA_PEX2")
	)
	(segment
		(start 288.049716 -300.649894)
		(end 287.574736 -301.124874)
		(width 0.249936)
		(layer "F.Cu")
		(net "P0V8_SERDES_VDDA_PEX2")
	)
	(segment
		(start 283.774896 -290.674806)
		(end 284.249876 -291.149786)
		(width 0.249936)
		(layer "F.Cu")
		(net "P0V8_SERDES_VDDA_PEX2")
	)
	(segment
		(start 296.599864 -300.649894)
		(end 297.074844 -301.124874)
		(width 0.249936)
		(layer "F.Cu")
		(net "P0V8_SERDES_VDDA_PEX2")
	)
	(segment
		(start 289.94989 -300.649894)
		(end 289.47491 -301.124874)
		(width 0.249936)
		(layer "F.Cu")
		(net "P0V8_SERDES_VDDA_PEX2")
	)
	(segment
		(start 283.774896 -292.57498)
		(end 284.249876 -293.04996)
		(width 0.249936)
		(layer "F.Cu")
		(net "P0V8_SERDES_VDDA_PEX2")
	)
	(segment
		(start 299.924724 -294.4749)
		(end 300.399704 -294.94988)
		(width 0.249936)
		(layer "F.Cu")
		(net "P0V8_SERDES_VDDA_PEX2")
	)
	(segment
		(start 286.149796 -291.149786)
		(end 286.624776 -290.674806)
		(width 0.249936)
		(layer "F.Cu")
		(net "P0V8_SERDES_VDDA_PEX2")
	)
	(segment
		(start 286.149796 -293.04996)
		(end 285.674816 -292.57498)
		(width 0.249936)
		(layer "F.Cu")
		(net "P0V8_SERDES_VDDA_PEX2")
	)
	(segment
		(start 282.824936 -292.57498)
		(end 283.299916 -293.04996)
		(width 0.249936)
		(layer "F.Cu")
		(net "P0V8_SERDES_VDDA_PEX2")
	)
	(segment
		(start 299.449744 -294.94988)
		(end 298.974764 -294.4749)
		(width 0.249936)
		(layer "F.Cu")
		(net "P0V8_SERDES_VDDA_PEX2")
	)
	(segment
		(start 298.499784 -298.74972)
		(end 298.974764 -299.224954)
		(width 0.249936)
		(layer "F.Cu")
		(net "P0V8_SERDES_VDDA_PEX2")
	)
	(segment
		(start 296.124884 -299.224954)
		(end 296.599864 -298.74972)
		(width 0.249936)
		(layer "F.Cu")
		(net "P0V8_SERDES_VDDA_PEX2")
	)
	(segment
		(start 289.47491 -301.124874)
		(end 288.99993 -300.649894)
		(width 0.249936)
		(layer "F.Cu")
		(net "P0V8_SERDES_VDDA_PEX2")
	)
	(segment
		(start 299.449744 -300.649894)
		(end 299.924724 -301.124874)
		(width 0.249936)
		(layer "F.Cu")
		(net "P0V8_SERDES_VDDA_PEX2")
	)
	(segment
		(start 286.624776 -290.674806)
		(end 287.099756 -291.149786)
		(width 0.249936)
		(layer "F.Cu")
		(net "P0V8_SERDES_VDDA_PEX2")
	)
	(segment
		(start 291.84981 -298.74972)
		(end 292.32479 -299.224954)
		(width 0.249936)
		(layer "F.Cu")
		(net "P0V8_SERDES_VDDA_PEX2")
	)
	(segment
		(start 285.199836 -298.74972)
		(end 285.674816 -299.224954)
		(width 0.249936)
		(layer "F.Cu")
		(net "P0V8_SERDES_VDDA_PEX2")
	)
	(segment
		(start 298.974764 -294.4749)
		(end 298.499784 -294.94988)
		(width 0.249936)
		(layer "F.Cu")
		(net "P0V8_SERDES_VDDA_PEX2")
	)
	(segment
		(start 294.22471 -292.574726)
		(end 294.69969 -293.04996)
		(width 0.249936)
		(layer "F.Cu")
		(net "P0V8_SERDES_VDDA_PEX2")
	)
	(segment
		(start 288.524696 -301.124874)
		(end 288.99993 -300.649894)
		(width 0.249936)
		(layer "F.Cu")
		(net "P0V8_SERDES_VDDA_PEX2")
	)
	(segment
		(start 294.22471 -290.674806)
		(end 294.69969 -291.149786)
		(width 0.249936)
		(layer "F.Cu")
		(net "P0V8_SERDES_VDDA_PEX2")
	)
	(segment
		(start 294.69969 -293.04996)
		(end 295.174924 -292.574726)
		(width 0.249936)
		(layer "F.Cu")
		(net "P0V8_SERDES_VDDA_PEX2")
	)
	(segment
		(start 292.32479 -301.124874)
		(end 292.79977 -300.649894)
		(width 0.249936)
		(layer "F.Cu")
		(net "P0V8_SERDES_VDDA_PEX2")
	)
	(segment
		(start 298.499784 -293.04996)
		(end 298.974764 -292.574726)
		(width 0.249936)
		(layer "F.Cu")
		(net "P0V8_SERDES_VDDA_PEX2")
	)
	(segment
		(start 287.099756 -300.649894)
		(end 286.624776 -301.124874)
		(width 0.249936)
		(layer "F.Cu")
		(net "P0V8_SERDES_VDDA_PEX2")
	)
	(segment
		(start 293.74973 -291.149786)
		(end 293.27475 -290.674806)
		(width 0.249936)
		(layer "F.Cu")
		(net "P0V8_SERDES_VDDA_PEX2")
	)
	(segment
		(start 298.024804 -290.674806)
		(end 298.499784 -291.149786)
		(width 0.249936)
		(layer "F.Cu")
		(net "P0V8_SERDES_VDDA_PEX2")
	)
	(segment
		(start 293.74973 -298.74972)
		(end 294.22471 -299.224954)
		(width 0.249936)
		(layer "F.Cu")
		(net "P0V8_SERDES_VDDA_PEX2")
	)
	(segment
		(start 286.624776 -292.57498)
		(end 287.099756 -293.04996)
		(width 0.249936)
		(layer "F.Cu")
		(net "P0V8_SERDES_VDDA_PEX2")
	)
	(segment
		(start 287.099756 -298.74972)
		(end 286.624776 -299.224954)
		(width 0.249936)
		(layer "F.Cu")
		(net "P0V8_SERDES_VDDA_PEX2")
	)
	(segment
		(start 290.42487 -301.124874)
		(end 290.89985 -300.649894)
		(width 0.249936)
		(layer "F.Cu")
		(net "P0V8_SERDES_VDDA_PEX2")
	)
	(segment
		(start 286.624776 -301.124874)
		(end 286.149796 -300.649894)
		(width 0.249936)
		(layer "F.Cu")
		(net "P0V8_SERDES_VDDA_PEX2")
	)
	(segment
		(start 299.449744 -294.94988)
		(end 299.924724 -294.4749)
		(width 0.249936)
		(layer "F.Cu")
		(net "P0V8_SERDES_VDDA_PEX2")
	)
	(segment
		(start 296.599864 -298.74972)
		(end 297.074844 -299.224954)
		(width 0.249936)
		(layer "F.Cu")
		(net "P0V8_SERDES_VDDA_PEX2")
	)
	(segment
		(start 284.724856 -299.224954)
		(end 285.199836 -298.74972)
		(width 0.249936)
		(layer "F.Cu")
		(net "P0V8_SERDES_VDDA_PEX2")
	)
	(segment
		(start 293.74973 -291.149786)
		(end 294.22471 -290.674806)
		(width 0.249936)
		(layer "F.Cu")
		(net "P0V8_SERDES_VDDA_PEX2")
	)
	(segment
		(start 299.449744 -296.8498)
		(end 298.974764 -297.32478)
		(width 0.249936)
		(layer "F.Cu")
		(net "P0V8_SERDES_VDDA_PEX2")
	)
	(segment
		(start 298.024804 -299.224954)
		(end 298.499784 -298.74972)
		(width 0.249936)
		(layer "F.Cu")
		(net "P0V8_SERDES_VDDA_PEX2")
	)
	(segment
		(start 295.649904 -298.74972)
		(end 295.174924 -299.224954)
		(width 0.249936)
		(layer "F.Cu")
		(net "P0V8_SERDES_VDDA_PEX2")
	)
	(via
		(at 293.27475 -292.574726)
		(size 0.4064)
		(drill 0.2032)
		(layers "F.Cu" "B.Cu")
		(net "P0V8_SERDES_VDDA_PEX2")
	)
	(via
		(at 296.124884 -290.674806)
		(size 0.4064)
		(drill 0.2032)
		(layers "F.Cu" "B.Cu")
		(net "P0V8_SERDES_VDDA_PEX2")
	)
	(via
		(at 292.32479 -292.574726)
		(size 0.4064)
		(drill 0.2032)
		(layers "F.Cu" "B.Cu")
		(net "P0V8_SERDES_VDDA_PEX2")
	)
	(via
		(at 285.674816 -292.57498)
		(size 0.4064)
		(drill 0.2032)
		(layers "F.Cu" "B.Cu")
		(net "P0V8_SERDES_VDDA_PEX2")
	)
	(via
		(at 341.852504 -319.31864)
		(size 0.508)
		(drill 0.254)
		(layers "F.Cu" "B.Cu")
		(net "P0V8_SERDES_VDDA_PEX2")
	)
	(via
		(at 340.328504 -320.08064)
		(size 0.508)
		(drill 0.254)
		(layers "F.Cu" "B.Cu")
		(net "P0V8_SERDES_VDDA_PEX2")
	)
	(via
		(at 286.624776 -299.224954)
		(size 0.4064)
		(drill 0.2032)
		(layers "F.Cu" "B.Cu")
		(net "P0V8_SERDES_VDDA_PEX2")
	)
	(via
		(at 298.974764 -294.4749)
		(size 0.4064)
		(drill 0.2032)
		(layers "F.Cu" "B.Cu")
		(net "P0V8_SERDES_VDDA_PEX2")
	)
	(via
		(at 298.974764 -301.124874)
		(size 0.4064)
		(drill 0.2032)
		(layers "F.Cu" "B.Cu")
		(net "P0V8_SERDES_VDDA_PEX2")
	)
	(via
		(at 287.574736 -301.124874)
		(size 0.4064)
		(drill 0.2032)
		(layers "F.Cu" "B.Cu")
		(net "P0V8_SERDES_VDDA_PEX2")
	)
	(via
		(at 345.662504 -320.08064)
		(size 0.508)
		(drill 0.254)
		(layers "F.Cu" "B.Cu")
		(net "P0V8_SERDES_VDDA_PEX2")
	)
	(via
		(at 282.824936 -292.57498)
		(size 0.4064)
		(drill 0.2032)
		(layers "F.Cu" "B.Cu")
		(net "P0V8_SERDES_VDDA_PEX2")
	)
	(via
		(at 292.32479 -301.124874)
		(size 0.4064)
		(drill 0.2032)
		(layers "F.Cu" "B.Cu")
		(net "P0V8_SERDES_VDDA_PEX2")
	)
	(via
		(at 286.624776 -301.124874)
		(size 0.4064)
		(drill 0.2032)
		(layers "F.Cu" "B.Cu")
		(net "P0V8_SERDES_VDDA_PEX2")
	)
	(via
		(at 346.424504 -319.31864)
		(size 0.508)
		(drill 0.254)
		(layers "F.Cu" "B.Cu")
		(net "P0V8_SERDES_VDDA_PEX2")
	)
	(via
		(at 299.924724 -296.37482)
		(size 0.4064)
		(drill 0.2032)
		(layers "F.Cu" "B.Cu")
		(net "P0V8_SERDES_VDDA_PEX2")
	)
	(via
		(at 295.174924 -290.674806)
		(size 0.4064)
		(drill 0.2032)
		(layers "F.Cu" "B.Cu")
		(net "P0V8_SERDES_VDDA_PEX2")
	)
	(via
		(at 287.574736 -292.57498)
		(size 0.4064)
		(drill 0.2032)
		(layers "F.Cu" "B.Cu")
		(net "P0V8_SERDES_VDDA_PEX2")
	)
	(via
		(at 290.42487 -290.674806)
		(size 0.4064)
		(drill 0.2032)
		(layers "F.Cu" "B.Cu")
		(net "P0V8_SERDES_VDDA_PEX2")
	)
	(via
		(at 292.32479 -299.224954)
		(size 0.4064)
		(drill 0.2032)
		(layers "F.Cu" "B.Cu")
		(net "P0V8_SERDES_VDDA_PEX2")
	)
	(via
		(at 297.074844 -301.124874)
		(size 0.4064)
		(drill 0.2032)
		(layers "F.Cu" "B.Cu")
		(net "P0V8_SERDES_VDDA_PEX2")
	)
	(via
		(at 299.924724 -297.32478)
		(size 0.4064)
		(drill 0.2032)
		(layers "F.Cu" "B.Cu")
		(net "P0V8_SERDES_VDDA_PEX2")
	)
	(via
		(at 341.852504 -320.08064)
		(size 0.508)
		(drill 0.254)
		(layers "F.Cu" "B.Cu")
		(net "P0V8_SERDES_VDDA_PEX2")
	)
	(via
		(at 299.924724 -299.224954)
		(size 0.4064)
		(drill 0.2032)
		(layers "F.Cu" "B.Cu")
		(net "P0V8_SERDES_VDDA_PEX2")
	)
	(via
		(at 283.774896 -292.57498)
		(size 0.4064)
		(drill 0.2032)
		(layers "F.Cu" "B.Cu")
		(net "P0V8_SERDES_VDDA_PEX2")
	)
	(via
		(at 286.624776 -292.57498)
		(size 0.4064)
		(drill 0.2032)
		(layers "F.Cu" "B.Cu")
		(net "P0V8_SERDES_VDDA_PEX2")
	)
	(via
		(at 298.024804 -301.124874)
		(size 0.4064)
		(drill 0.2032)
		(layers "F.Cu" "B.Cu")
		(net "P0V8_SERDES_VDDA_PEX2")
	)
	(via
		(at 296.124884 -292.574726)
		(size 0.4064)
		(drill 0.2032)
		(layers "F.Cu" "B.Cu")
		(net "P0V8_SERDES_VDDA_PEX2")
	)
	(via
		(at 344.900504 -320.08064)
		(size 0.508)
		(drill 0.254)
		(layers "F.Cu" "B.Cu")
		(net "P0V8_SERDES_VDDA_PEX2")
	)
	(via
		(at 293.27475 -299.224954)
		(size 0.4064)
		(drill 0.2032)
		(layers "F.Cu" "B.Cu")
		(net "P0V8_SERDES_VDDA_PEX2")
	)
	(via
		(at 299.924724 -294.4749)
		(size 0.4064)
		(drill 0.2032)
		(layers "F.Cu" "B.Cu")
		(net "P0V8_SERDES_VDDA_PEX2")
	)
	(via
		(at 293.27475 -290.674806)
		(size 0.4064)
		(drill 0.2032)
		(layers "F.Cu" "B.Cu")
		(net "P0V8_SERDES_VDDA_PEX2")
	)
	(via
		(at 287.574736 -299.224954)
		(size 0.4064)
		(drill 0.2032)
		(layers "F.Cu" "B.Cu")
		(net "P0V8_SERDES_VDDA_PEX2")
	)
	(via
		(at 296.124884 -299.224954)
		(size 0.4064)
		(drill 0.2032)
		(layers "F.Cu" "B.Cu")
		(net "P0V8_SERDES_VDDA_PEX2")
	)
	(via
		(at 288.52495 -292.57498)
		(size 0.4064)
		(drill 0.2032)
		(layers "F.Cu" "B.Cu")
		(net "P0V8_SERDES_VDDA_PEX2")
	)
	(via
		(at 283.774896 -290.674806)
		(size 0.4064)
		(drill 0.2032)
		(layers "F.Cu" "B.Cu")
		(net "P0V8_SERDES_VDDA_PEX2")
	)
	(via
		(at 289.47491 -292.57498)
		(size 0.4064)
		(drill 0.2032)
		(layers "F.Cu" "B.Cu")
		(net "P0V8_SERDES_VDDA_PEX2")
	)
	(via
		(at 289.47491 -301.124874)
		(size 0.4064)
		(drill 0.2032)
		(layers "F.Cu" "B.Cu")
		(net "P0V8_SERDES_VDDA_PEX2")
	)
	(via
		(at 346.424504 -320.08064)
		(size 0.508)
		(drill 0.254)
		(layers "F.Cu" "B.Cu")
		(net "P0V8_SERDES_VDDA_PEX2")
	)
	(via
		(at 297.074844 -299.224954)
		(size 0.4064)
		(drill 0.2032)
		(layers "F.Cu" "B.Cu")
		(net "P0V8_SERDES_VDDA_PEX2")
	)
	(via
		(at 298.974764 -299.224954)
		(size 0.4064)
		(drill 0.2032)
		(layers "F.Cu" "B.Cu")
		(net "P0V8_SERDES_VDDA_PEX2")
	)
	(via
		(at 285.674816 -290.674806)
		(size 0.4064)
		(drill 0.2032)
		(layers "F.Cu" "B.Cu")
		(net "P0V8_SERDES_VDDA_PEX2")
	)
	(via
		(at 298.974764 -297.32478)
		(size 0.4064)
		(drill 0.2032)
		(layers "F.Cu" "B.Cu")
		(net "P0V8_SERDES_VDDA_PEX2")
	)
	(via
		(at 340.328504 -319.31864)
		(size 0.508)
		(drill 0.254)
		(layers "F.Cu" "B.Cu")
		(net "P0V8_SERDES_VDDA_PEX2")
	)
	(via
		(at 288.524696 -290.674806)
		(size 0.4064)
		(drill 0.2032)
		(layers "F.Cu" "B.Cu")
		(net "P0V8_SERDES_VDDA_PEX2")
	)
	(via
		(at 298.024804 -290.674806)
		(size 0.4064)
		(drill 0.2032)
		(layers "F.Cu" "B.Cu")
		(net "P0V8_SERDES_VDDA_PEX2")
	)
	(via
		(at 338.804504 -319.31864)
		(size 0.508)
		(drill 0.254)
		(layers "F.Cu" "B.Cu")
		(net "P0V8_SERDES_VDDA_PEX2")
	)
	(via
		(at 297.074844 -290.674806)
		(size 0.4064)
		(drill 0.2032)
		(layers "F.Cu" "B.Cu")
		(net "P0V8_SERDES_VDDA_PEX2")
	)
	(via
		(at 344.138504 -319.31864)
		(size 0.508)
		(drill 0.254)
		(layers "F.Cu" "B.Cu")
		(net "P0V8_SERDES_VDDA_PEX2")
	)
	(via
		(at 287.574736 -290.674806)
		(size 0.4064)
		(drill 0.2032)
		(layers "F.Cu" "B.Cu")
		(net "P0V8_SERDES_VDDA_PEX2")
	)
	(via
		(at 285.674816 -299.224954)
		(size 0.4064)
		(drill 0.2032)
		(layers "F.Cu" "B.Cu")
		(net "P0V8_SERDES_VDDA_PEX2")
	)
	(via
		(at 288.524696 -299.224954)
		(size 0.4064)
		(drill 0.2032)
		(layers "F.Cu" "B.Cu")
		(net "P0V8_SERDES_VDDA_PEX2")
	)
	(via
		(at 300.874684 -297.32478)
		(size 0.4064)
		(drill 0.2032)
		(layers "F.Cu" "B.Cu")
		(net "P0V8_SERDES_VDDA_PEX2")
	)
	(via
		(at 338.804504 -320.08064)
		(size 0.508)
		(drill 0.254)
		(layers "F.Cu" "B.Cu")
		(net "P0V8_SERDES_VDDA_PEX2")
	)
	(via
		(at 343.376504 -320.08064)
		(size 0.508)
		(drill 0.254)
		(layers "F.Cu" "B.Cu")
		(net "P0V8_SERDES_VDDA_PEX2")
	)
	(via
		(at 284.724856 -299.224954)
		(size 0.4064)
		(drill 0.2032)
		(layers "F.Cu" "B.Cu")
		(net "P0V8_SERDES_VDDA_PEX2")
	)
	(via
		(at 284.724856 -292.57498)
		(size 0.4064)
		(drill 0.2032)
		(layers "F.Cu" "B.Cu")
		(net "P0V8_SERDES_VDDA_PEX2")
	)
	(via
		(at 295.174924 -299.224954)
		(size 0.4064)
		(drill 0.2032)
		(layers "F.Cu" "B.Cu")
		(net "P0V8_SERDES_VDDA_PEX2")
	)
	(via
		(at 292.32479 -290.674806)
		(size 0.4064)
		(drill 0.2032)
		(layers "F.Cu" "B.Cu")
		(net "P0V8_SERDES_VDDA_PEX2")
	)
	(via
		(at 347.186504 -320.08064)
		(size 0.508)
		(drill 0.254)
		(layers "F.Cu" "B.Cu")
		(net "P0V8_SERDES_VDDA_PEX2")
	)
	(via
		(at 298.024804 -299.224954)
		(size 0.4064)
		(drill 0.2032)
		(layers "F.Cu" "B.Cu")
		(net "P0V8_SERDES_VDDA_PEX2")
	)
	(via
		(at 285.674816 -301.124874)
		(size 0.4064)
		(drill 0.2032)
		(layers "F.Cu" "B.Cu")
		(net "P0V8_SERDES_VDDA_PEX2")
	)
	(via
		(at 342.614504 -320.08064)
		(size 0.508)
		(drill 0.254)
		(layers "F.Cu" "B.Cu")
		(net "P0V8_SERDES_VDDA_PEX2")
	)
	(via
		(at 290.42487 -292.57498)
		(size 0.4064)
		(drill 0.2032)
		(layers "F.Cu" "B.Cu")
		(net "P0V8_SERDES_VDDA_PEX2")
	)
	(via
		(at 299.924724 -290.674806)
		(size 0.4064)
		(drill 0.2032)
		(layers "F.Cu" "B.Cu")
		(net "P0V8_SERDES_VDDA_PEX2")
	)
	(via
		(at 300.874684 -294.4749)
		(size 0.4064)
		(drill 0.2032)
		(layers "F.Cu" "B.Cu")
		(net "P0V8_SERDES_VDDA_PEX2")
	)
	(via
		(at 295.174924 -292.574726)
		(size 0.4064)
		(drill 0.2032)
		(layers "F.Cu" "B.Cu")
		(net "P0V8_SERDES_VDDA_PEX2")
	)
	(via
		(at 284.724856 -290.674806)
		(size 0.4064)
		(drill 0.2032)
		(layers "F.Cu" "B.Cu")
		(net "P0V8_SERDES_VDDA_PEX2")
	)
	(via
		(at 339.566504 -320.08064)
		(size 0.508)
		(drill 0.254)
		(layers "F.Cu" "B.Cu")
		(net "P0V8_SERDES_VDDA_PEX2")
	)
	(via
		(at 298.024804 -292.574726)
		(size 0.4064)
		(drill 0.2032)
		(layers "F.Cu" "B.Cu")
		(net "P0V8_SERDES_VDDA_PEX2")
	)
	(via
		(at 295.174924 -301.124874)
		(size 0.4064)
		(drill 0.2032)
		(layers "F.Cu" "B.Cu")
		(net "P0V8_SERDES_VDDA_PEX2")
	)
	(via
		(at 339.566504 -319.31864)
		(size 0.508)
		(drill 0.254)
		(layers "F.Cu" "B.Cu")
		(net "P0V8_SERDES_VDDA_PEX2")
	)
	(via
		(at 344.900504 -319.31864)
		(size 0.508)
		(drill 0.254)
		(layers "F.Cu" "B.Cu")
		(net "P0V8_SERDES_VDDA_PEX2")
	)
	(via
		(at 284.724856 -301.124874)
		(size 0.4064)
		(drill 0.2032)
		(layers "F.Cu" "B.Cu")
		(net "P0V8_SERDES_VDDA_PEX2")
	)
	(via
		(at 299.924724 -301.124874)
		(size 0.4064)
		(drill 0.2032)
		(layers "F.Cu" "B.Cu")
		(net "P0V8_SERDES_VDDA_PEX2")
	)
	(via
		(at 300.874684 -296.37482)
		(size 0.4064)
		(drill 0.2032)
		(layers "F.Cu" "B.Cu")
		(net "P0V8_SERDES_VDDA_PEX2")
	)
	(via
		(at 298.974764 -290.674806)
		(size 0.4064)
		(drill 0.2032)
		(layers "F.Cu" "B.Cu")
		(net "P0V8_SERDES_VDDA_PEX2")
	)
	(via
		(at 344.138504 -320.08064)
		(size 0.508)
		(drill 0.254)
		(layers "F.Cu" "B.Cu")
		(net "P0V8_SERDES_VDDA_PEX2")
	)
	(via
		(at 294.22471 -299.224954)
		(size 0.4064)
		(drill 0.2032)
		(layers "F.Cu" "B.Cu")
		(net "P0V8_SERDES_VDDA_PEX2")
	)
	(via
		(at 282.824936 -299.224954)
		(size 0.4064)
		(drill 0.2032)
		(layers "F.Cu" "B.Cu")
		(net "P0V8_SERDES_VDDA_PEX2")
	)
	(via
		(at 342.614504 -319.31864)
		(size 0.508)
		(drill 0.254)
		(layers "F.Cu" "B.Cu")
		(net "P0V8_SERDES_VDDA_PEX2")
	)
	(via
		(at 294.22471 -290.674806)
		(size 0.4064)
		(drill 0.2032)
		(layers "F.Cu" "B.Cu")
		(net "P0V8_SERDES_VDDA_PEX2")
	)
	(via
		(at 343.376504 -319.31864)
		(size 0.508)
		(drill 0.254)
		(layers "F.Cu" "B.Cu")
		(net "P0V8_SERDES_VDDA_PEX2")
	)
	(via
		(at 294.22471 -292.574726)
		(size 0.4064)
		(drill 0.2032)
		(layers "F.Cu" "B.Cu")
		(net "P0V8_SERDES_VDDA_PEX2")
	)
	(via
		(at 289.47491 -299.224954)
		(size 0.4064)
		(drill 0.2032)
		(layers "F.Cu" "B.Cu")
		(net "P0V8_SERDES_VDDA_PEX2")
	)
	(via
		(at 341.090504 -320.08064)
		(size 0.508)
		(drill 0.254)
		(layers "F.Cu" "B.Cu")
		(net "P0V8_SERDES_VDDA_PEX2")
	)
	(via
		(at 345.662504 -319.31864)
		(size 0.508)
		(drill 0.254)
		(layers "F.Cu" "B.Cu")
		(net "P0V8_SERDES_VDDA_PEX2")
	)
	(via
		(at 296.124884 -301.124874)
		(size 0.4064)
		(drill 0.2032)
		(layers "F.Cu" "B.Cu")
		(net "P0V8_SERDES_VDDA_PEX2")
	)
	(via
		(at 297.074844 -292.574726)
		(size 0.4064)
		(drill 0.2032)
		(layers "F.Cu" "B.Cu")
		(net "P0V8_SERDES_VDDA_PEX2")
	)
	(via
		(at 283.774896 -299.224954)
		(size 0.4064)
		(drill 0.2032)
		(layers "F.Cu" "B.Cu")
		(net "P0V8_SERDES_VDDA_PEX2")
	)
	(via
		(at 289.47491 -290.674806)
		(size 0.4064)
		(drill 0.2032)
		(layers "F.Cu" "B.Cu")
		(net "P0V8_SERDES_VDDA_PEX2")
	)
	(via
		(at 298.974764 -292.574726)
		(size 0.4064)
		(drill 0.2032)
		(layers "F.Cu" "B.Cu")
		(net "P0V8_SERDES_VDDA_PEX2")
	)
	(via
		(at 288.524696 -301.124874)
		(size 0.4064)
		(drill 0.2032)
		(layers "F.Cu" "B.Cu")
		(net "P0V8_SERDES_VDDA_PEX2")
	)
	(via
		(at 299.924724 -292.574726)
		(size 0.4064)
		(drill 0.2032)
		(layers "F.Cu" "B.Cu")
		(net "P0V8_SERDES_VDDA_PEX2")
	)
	(via
		(at 290.42487 -301.124874)
		(size 0.4064)
		(drill 0.2032)
		(layers "F.Cu" "B.Cu")
		(net "P0V8_SERDES_VDDA_PEX2")
	)
	(via
		(at 294.22471 -301.124874)
		(size 0.4064)
		(drill 0.2032)
		(layers "F.Cu" "B.Cu")
		(net "P0V8_SERDES_VDDA_PEX2")
	)
	(via
		(at 347.186504 -319.31864)
		(size 0.508)
		(drill 0.254)
		(layers "F.Cu" "B.Cu")
		(net "P0V8_SERDES_VDDA_PEX2")
	)
	(via
		(at 293.27475 -301.124874)
		(size 0.4064)
		(drill 0.2032)
		(layers "F.Cu" "B.Cu")
		(net "P0V8_SERDES_VDDA_PEX2")
	)
	(via
		(at 290.42487 -299.224954)
		(size 0.4064)
		(drill 0.2032)
		(layers "F.Cu" "B.Cu")
		(net "P0V8_SERDES_VDDA_PEX2")
	)
	(via
		(at 286.624776 -290.674806)
		(size 0.4064)
		(drill 0.2032)
		(layers "F.Cu" "B.Cu")
		(net "P0V8_SERDES_VDDA_PEX2")
	)
	(via
		(at 283.774896 -301.124874)
		(size 0.4064)
		(drill 0.2032)
		(layers "F.Cu" "B.Cu")
		(net "P0V8_SERDES_VDDA_PEX2")
	)
	(via
		(at 282.824936 -301.124874)
		(size 0.4064)
		(drill 0.2032)
		(layers "F.Cu" "B.Cu")
		(net "P0V8_SERDES_VDDA_PEX2")
	)
	(via
		(at 282.824936 -290.674806)
		(size 0.4064)
		(drill 0.2032)
		(layers "F.Cu" "B.Cu")
		(net "P0V8_SERDES_VDDA_PEX2")
	)
	(via
		(at 341.090504 -319.31864)
		(size 0.508)
		(drill 0.254)
		(layers "F.Cu" "B.Cu")
		(net "P0V8_SERDES_VDDA_PEX2")
	)
	(segment
		(start 361.831382 -281.350974)
		(end 361.831382 -281.999182)
		(width 0.2286)
		(layer "F.Cu")
		(net "SW_P0V8_PEX3_PHASE2")
	)
	(segment
		(start 361.329478 -280.84907)
		(end 361.831382 -281.350974)
		(width 0.2286)
		(layer "F.Cu")
		(net "SW_P0V8_PEX3_PHASE2")
	)
	(segment
		(start 242.169188 -309.768494)
		(end 242.615212 -309.768494)
		(width 0.13208)
		(layer "F.Cu")
		(net "P1V25_PEX2_EN")
	)
	(segment
		(start 242.615212 -309.768494)
		(end 242.953286 -309.908448)
		(width 0.13208)
		(layer "F.Cu")
		(net "P1V25_PEX2_EN")
	)
	(segment
		(start 243.586762 -310.541924)
		(end 242.953286 -309.908448)
		(width 0.13208)
		(layer "F.Cu")
		(net "P1V25_PEX2_EN")
	)
	(segment
		(start 243.586762 -310.568848)
		(end 243.586762 -310.541924)
		(width 0.13208)
		(layer "F.Cu")
		(net "P1V25_PEX2_EN")
	)
	(via
		(at 242.953286 -309.908448)
		(size 0.508)
		(drill 0.254)
		(layers "F.Cu" "B.Cu")
		(net "P1V25_PEX2_EN")
	)
	(segment
		(start 246.817896 -308.24043)
		(end 246.391938 -308.24043)
		(width 0.254)
		(layer "F.Cu")
		(net "SH_P1V25_PEX2_FB_P")
	)
	(segment
		(start 246.137938 -308.49443)
		(end 246.137938 -308.495446)
		(width 0.254)
		(layer "F.Cu")
		(net "SH_P1V25_PEX2_FB_P")
	)
	(segment
		(start 246.391938 -308.24043)
		(end 246.137938 -308.49443)
		(width 0.254)
		(layer "F.Cu")
		(net "SH_P1V25_PEX2_FB_P")
	)
	(segment
		(start 246.132858 -309.458614)
		(end 246.132858 -309.555642)
		(width 0.254)
		(layer "F.Cu")
		(net "SH_P1V25_PEX2_FB_P")
	)
	(segment
		(start 246.137938 -308.582822)
		(end 246.573294 -309.018178)
		(width 0.254)
		(layer "F.Cu")
		(net "SH_P1V25_PEX2_FB_P")
	)
	(segment
		(start 246.137938 -308.495446)
		(end 246.137938 -308.582822)
		(width 0.254)
		(layer "F.Cu")
		(net "SH_P1V25_PEX2_FB_P")
	)
	(segment
		(start 246.573294 -309.018178)
		(end 246.132858 -309.458614)
		(width 0.254)
		(layer "F.Cu")
		(net "SH_P1V25_PEX2_FB_P")
	)
	(segment
		(start 247.153938 -308.568852)
		(end 246.817896 -308.24043)
		(width 0.254)
		(layer "F.Cu")
		(net "SH_P1V25_PEX2_FB_P")
	)
	(segment
		(start 246.132858 -309.555642)
		(end 246.132858 -310.571642)
		(width 0.254)
		(layer "F.Cu")
		(net "SH_P1V25_PEX2_FB_P")
	)
	(via
		(at 246.573294 -309.018178)
		(size 0.508)
		(drill 0.254)
		(layers "F.Cu" "B.Cu")
		(net "SH_P1V25_PEX2_FB_P")
	)
	(segment
		(start 244.56517 -308.402228)
		(end 244.817646 -308.654704)
		(width 0.254)
		(layer "F.Cu")
		(net "SH_P1V25_PEX2_FB_N")
	)
	(segment
		(start 246.450866 -307.695346)
		(end 246.589042 -307.833522)
		(width 0.254)
		(layer "F.Cu")
		(net "SH_P1V25_PEX2_FB_N")
	)
	(segment
		(start 246.137938 -307.695346)
		(end 246.450866 -307.695346)
		(width 0.254)
		(layer "F.Cu")
		(net "SH_P1V25_PEX2_FB_N")
	)
	(segment
		(start 247.146318 -307.560472)
		(end 247.153938 -307.484272)
		(width 0.254)
		(layer "F.Cu")
		(net "SH_P1V25_PEX2_FB_N")
	)
	(segment
		(start 246.589042 -307.833522)
		(end 246.873268 -307.833522)
		(width 0.254)
		(layer "F.Cu")
		(net "SH_P1V25_PEX2_FB_N")
	)
	(segment
		(start 242.169188 -308.968648)
		(end 243.143024 -308.968648)
		(width 0.1778)
		(layer "F.Cu")
		(net "SH_P1V25_PEX2_FB_N")
	)
	(segment
		(start 245.228872 -308.562502)
		(end 245.16588 -308.562502)
		(width 0.254)
		(layer "F.Cu")
		(net "SH_P1V25_PEX2_FB_N")
	)
	(segment
		(start 245.073678 -308.654704)
		(end 245.16588 -308.562502)
		(width 0.254)
		(layer "F.Cu")
		(net "SH_P1V25_PEX2_FB_N")
	)
	(segment
		(start 243.697506 -308.811168)
		(end 244.023642 -308.811168)
		(width 0.254)
		(layer "F.Cu")
		(net "SH_P1V25_PEX2_FB_N")
	)
	(segment
		(start 245.740936 -307.795168)
		(end 245.693946 -307.908706)
		(width 0.254)
		(layer "F.Cu")
		(net "SH_P1V25_PEX2_FB_N")
	)
	(segment
		(start 245.840758 -307.695346)
		(end 245.740936 -307.795168)
		(width 0.254)
		(layer "F.Cu")
		(net "SH_P1V25_PEX2_FB_N")
	)
	(segment
		(start 246.137938 -307.695346)
		(end 245.840758 -307.695346)
		(width 0.254)
		(layer "F.Cu")
		(net "SH_P1V25_PEX2_FB_N")
	)
	(segment
		(start 244.15623 -308.811168)
		(end 244.56517 -308.402228)
		(width 0.254)
		(layer "F.Cu")
		(net "SH_P1V25_PEX2_FB_N")
	)
	(segment
		(start 246.873268 -307.833522)
		(end 247.146318 -307.560472)
		(width 0.254)
		(layer "F.Cu")
		(net "SH_P1V25_PEX2_FB_N")
	)
	(segment
		(start 244.023642 -308.811168)
		(end 244.15623 -308.811168)
		(width 0.254)
		(layer "F.Cu")
		(net "SH_P1V25_PEX2_FB_N")
	)
	(segment
		(start 243.143024 -308.968648)
		(end 243.317268 -308.968648)
		(width 0.254)
		(layer "F.Cu")
		(net "SH_P1V25_PEX2_FB_N")
	)
	(segment
		(start 245.693946 -307.908706)
		(end 245.693946 -308.097428)
		(width 0.254)
		(layer "F.Cu")
		(net "SH_P1V25_PEX2_FB_N")
	)
	(segment
		(start 243.317268 -308.968648)
		(end 243.697506 -308.811168)
		(width 0.254)
		(layer "F.Cu")
		(net "SH_P1V25_PEX2_FB_N")
	)
	(segment
		(start 245.693946 -308.097428)
		(end 245.228872 -308.562502)
		(width 0.254)
		(layer "F.Cu")
		(net "SH_P1V25_PEX2_FB_N")
	)
	(segment
		(start 244.817646 -308.654704)
		(end 245.073678 -308.654704)
		(width 0.254)
		(layer "F.Cu")
		(net "SH_P1V25_PEX2_FB_N")
	)
	(via
		(at 244.56517 -308.402228)
		(size 0.508)
		(drill 0.254)
		(layers "F.Cu" "B.Cu")
		(net "SH_P1V25_PEX2_FB_N")
	)
	(segment
		(start 243.25453 -308.568598)
		(end 243.435632 -308.493668)
		(width 0.1778)
		(layer "F.Cu")
		(net "P1V25_PEX2_REF")
	)
	(segment
		(start 245.16588 -307.762402)
		(end 245.203726 -307.724556)
		(width 0.254)
		(layer "F.Cu")
		(net "P1V25_PEX2_REF")
	)
	(segment
		(start 245.203726 -307.724556)
		(end 245.203726 -306.787042)
		(width 0.254)
		(layer "F.Cu")
		(net "P1V25_PEX2_REF")
	)
	(segment
		(start 242.169188 -308.568598)
		(end 243.25453 -308.568598)
		(width 0.1778)
		(layer "F.Cu")
		(net "P1V25_PEX2_REF")
	)
	(segment
		(start 243.435632 -308.493668)
		(end 243.658136 -308.271164)
		(width 0.1778)
		(layer "F.Cu")
		(net "P1V25_PEX2_REF")
	)
	(segment
		(start 245.855744 -306.787042)
		(end 245.203726 -306.787042)
		(width 0.13208)
		(layer "F.Cu")
		(net "P1V25_PEX2_REF")
	)
	(segment
		(start 244.166898 -307.762402)
		(end 245.16588 -307.762402)
		(width 0.254)
		(layer "F.Cu")
		(net "P1V25_PEX2_REF")
	)
	(segment
		(start 243.658136 -308.271164)
		(end 244.166898 -307.762402)
		(width 0.254)
		(layer "F.Cu")
		(net "P1V25_PEX2_REF")
	)
	(via
		(at 245.855744 -306.787042)
		(size 0.508)
		(drill 0.254)
		(layers "F.Cu" "B.Cu")
		(net "P1V25_PEX2_REF")
	)
	(segment
		(start 244.023642 -309.611268)
		(end 244.35943 -309.611268)
		(width 0.254)
		(layer "F.Cu")
		(net "P1V25_PEX2_FB")
	)
	(segment
		(start 245.004336 -309.555642)
		(end 245.332758 -309.555642)
		(width 0.254)
		(layer "F.Cu")
		(net "P1V25_PEX2_FB")
	)
	(segment
		(start 244.814852 -309.745126)
		(end 245.004336 -309.555642)
		(width 0.254)
		(layer "F.Cu")
		(net "P1V25_PEX2_FB")
	)
	(segment
		(start 243.09451 -309.375048)
		(end 243.664994 -309.611268)
		(width 0.254)
		(layer "F.Cu")
		(net "P1V25_PEX2_FB")
	)
	(segment
		(start 242.787678 -309.368698)
		(end 242.794028 -309.375048)
		(width 0.254)
		(layer "F.Cu")
		(net "P1V25_PEX2_FB")
	)
	(segment
		(start 244.668802 -309.745126)
		(end 244.814852 -309.745126)
		(width 0.254)
		(layer "F.Cu")
		(net "P1V25_PEX2_FB")
	)
	(segment
		(start 242.169188 -309.368698)
		(end 242.787678 -309.368698)
		(width 0.1778)
		(layer "F.Cu")
		(net "P1V25_PEX2_FB")
	)
	(segment
		(start 244.493288 -309.745126)
		(end 244.668802 -309.745126)
		(width 0.254)
		(layer "F.Cu")
		(net "P1V25_PEX2_FB")
	)
	(segment
		(start 244.35943 -309.611268)
		(end 244.493288 -309.745126)
		(width 0.254)
		(layer "F.Cu")
		(net "P1V25_PEX2_FB")
	)
	(segment
		(start 242.794028 -309.375048)
		(end 243.09451 -309.375048)
		(width 0.254)
		(layer "F.Cu")
		(net "P1V25_PEX2_FB")
	)
	(segment
		(start 243.664994 -309.611268)
		(end 244.023642 -309.611268)
		(width 0.254)
		(layer "F.Cu")
		(net "P1V25_PEX2_FB")
	)
	(segment
		(start 245.332758 -310.571642)
		(end 245.332758 -309.555642)
		(width 0.254)
		(layer "F.Cu")
		(net "P1V25_PEX2_FB")
	)
	(via
		(at 244.668802 -309.745126)
		(size 0.508)
		(drill 0.254)
		(layers "F.Cu" "B.Cu")
		(net "P1V25_PEX2_FB")
	)
	(segment
		(start 243.50726 -307.446426)
		(end 243.872004 -307.081682)
		(width 0.254)
		(layer "F.Cu")
		(net "P1V25_PEX2_CS")
	)
	(segment
		(start 243.374164 -307.446426)
		(end 243.50726 -307.446426)
		(width 0.1778)
		(layer "F.Cu")
		(net "P1V25_PEX2_CS")
	)
	(segment
		(start 242.169188 -307.768498)
		(end 242.597178 -307.768498)
		(width 0.1778)
		(layer "F.Cu")
		(net "P1V25_PEX2_CS")
	)
	(segment
		(start 243.872004 -307.081682)
		(end 244.196616 -307.081682)
		(width 0.254)
		(layer "F.Cu")
		(net "P1V25_PEX2_CS")
	)
	(segment
		(start 242.597178 -307.768498)
		(end 243.374164 -307.446426)
		(width 0.1778)
		(layer "F.Cu")
		(net "P1V25_PEX2_CS")
	)
	(via
		(at 243.50726 -307.446426)
		(size 0.508)
		(drill 0.254)
		(layers "F.Cu" "B.Cu")
		(net "P1V25_PEX2_CS")
	)
	(segment
		(start 243.353082 -311.215786)
		(end 244.131084 -311.215786)
		(width 0.13208)
		(layer "F.Cu")
		(net "PWRGD_P1V25_PEX2")
	)
	(segment
		(start 242.405916 -310.26862)
		(end 243.353082 -311.215786)
		(width 0.13208)
		(layer "F.Cu")
		(net "PWRGD_P1V25_PEX2")
	)
	(segment
		(start 242.169188 -310.26862)
		(end 242.405916 -310.26862)
		(width 0.13208)
		(layer "F.Cu")
		(net "PWRGD_P1V25_PEX2")
	)
	(via
		(at 244.131084 -311.215786)
		(size 0.508)
		(drill 0.254)
		(layers "F.Cu" "B.Cu")
		(net "PWRGD_P1V25_PEX2")
	)
	(segment
		(start 246.798592 -310.948578)
		(end 244.398292 -310.948578)
		(width 0.13208)
		(layer "B.Cu")
		(net "PWRGD_P1V25_PEX2")
	)
	(segment
		(start 246.804688 -312.034428)
		(end 246.804688 -310.954674)
		(width 0.13208)
		(layer "B.Cu")
		(net "PWRGD_P1V25_PEX2")
	)
	(segment
		(start 244.398292 -310.948578)
		(end 244.131084 -311.215786)
		(width 0.13208)
		(layer "B.Cu")
		(net "PWRGD_P1V25_PEX2")
	)
	(segment
		(start 246.804688 -310.954674)
		(end 246.798592 -310.948578)
		(width 0.13208)
		(layer "B.Cu")
		(net "PWRGD_P1V25_PEX2")
	)
	(via
		(at 238.581692 -306.744116)
		(size 0.508)
		(drill 0.254)
		(layers "F.Cu" "B.Cu")
		(net "P1V25_PEX2_VCC")
	)
	(segment
		(start 239.136682 -306.189126)
		(end 238.581692 -306.744116)
		(width 0.508)
		(layer "B.Cu")
		(net "P1V25_PEX2_VCC")
	)
	(segment
		(start 244.009164 -306.189126)
		(end 239.136682 -306.189126)
		(width 0.508)
		(layer "B.Cu")
		(net "P1V25_PEX2_VCC")
	)
	(segment
		(start 246.798592 -310.148478)
		(end 245.814596 -310.148478)
		(width 0.508)
		(layer "B.Cu")
		(net "P1V25_PEX2_VCC")
	)
	(segment
		(start 245.526306 -309.860188)
		(end 245.526306 -307.706268)
		(width 0.508)
		(layer "B.Cu")
		(net "P1V25_PEX2_VCC")
	)
	(segment
		(start 245.526306 -307.706268)
		(end 244.009164 -306.189126)
		(width 0.508)
		(layer "B.Cu")
		(net "P1V25_PEX2_VCC")
	)
	(segment
		(start 245.814596 -310.148478)
		(end 245.526306 -309.860188)
		(width 0.508)
		(layer "B.Cu")
		(net "P1V25_PEX2_VCC")
	)
	(segment
		(start 397.49984 -289.249866)
		(end 397.02486 -288.774886)
		(width 0.249936)
		(layer "F.Cu")
		(net "P1V8_VDDA_PEX3")
	)
	(segment
		(start 393.7 -299.699934)
		(end 393.22502 -299.224954)
		(width 0.249936)
		(layer "F.Cu")
		(net "P1V8_VDDA_PEX3")
	)
	(segment
		(start 393.22502 -299.224954)
		(end 393.7 -298.74972)
		(width 0.249936)
		(layer "F.Cu")
		(net "P1V8_VDDA_PEX3")
	)
	(segment
		(start 393.22502 -300.174914)
		(end 393.7 -299.699934)
		(width 0.249936)
		(layer "F.Cu")
		(net "P1V8_VDDA_PEX3")
	)
	(segment
		(start 419.349936 -299.699934)
		(end 419.824916 -300.174914)
		(width 0.249936)
		(layer "F.Cu")
		(net "P1V8_VDDA_PEX3")
	)
	(segment
		(start 417.450016 -287.349946)
		(end 417.924996 -286.874966)
		(width 0.249936)
		(layer "F.Cu")
		(net "P1V8_VDDA_PEX3")
	)
	(segment
		(start 393.7 -298.74972)
		(end 393.22502 -298.27474)
		(width 0.249936)
		(layer "F.Cu")
		(net "P1V8_VDDA_PEX3")
	)
	(segment
		(start 416.499802 -299.699934)
		(end 416.974782 -300.174914)
		(width 0.249936)
		(layer "F.Cu")
		(net "P1V8_VDDA_PEX3")
	)
	(segment
		(start 393.22502 -298.27474)
		(end 393.7 -297.79976)
		(width 0.249936)
		(layer "F.Cu")
		(net "P1V8_VDDA_PEX3")
	)
	(segment
		(start 397.49984 -302.549814)
		(end 397.02486 -303.024794)
		(width 0.249936)
		(layer "F.Cu")
		(net "P1V8_VDDA_PEX3")
	)
	(segment
		(start 417.450016 -304.449734)
		(end 417.924996 -304.924714)
		(width 0.249936)
		(layer "F.Cu")
		(net "P1V8_VDDA_PEX3")
	)
	(via
		(at 397.02486 -288.774886)
		(size 0.4064)
		(drill 0.2032)
		(layers "F.Cu" "B.Cu")
		(net "P1V8_VDDA_PEX3")
	)
	(via
		(at 393.22502 -300.174914)
		(size 0.4064)
		(drill 0.2032)
		(layers "F.Cu" "B.Cu")
		(net "P1V8_VDDA_PEX3")
	)
	(via
		(at 374.20042 -261.790688)
		(size 0.508)
		(drill 0.254)
		(layers "F.Cu" "B.Cu")
		(net "P1V8_VDDA_PEX3")
	)
	(via
		(at 417.924996 -304.924714)
		(size 0.4064)
		(drill 0.2032)
		(layers "F.Cu" "B.Cu")
		(net "P1V8_VDDA_PEX3")
	)
	(via
		(at 393.22502 -298.27474)
		(size 0.4064)
		(drill 0.2032)
		(layers "F.Cu" "B.Cu")
		(net "P1V8_VDDA_PEX3")
	)
	(via
		(at 419.824916 -300.174914)
		(size 0.4064)
		(drill 0.2032)
		(layers "F.Cu" "B.Cu")
		(net "P1V8_VDDA_PEX3")
	)
	(via
		(at 416.974782 -300.174914)
		(size 0.4064)
		(drill 0.2032)
		(layers "F.Cu" "B.Cu")
		(net "P1V8_VDDA_PEX3")
	)
	(via
		(at 397.02486 -303.024794)
		(size 0.4064)
		(drill 0.2032)
		(layers "F.Cu" "B.Cu")
		(net "P1V8_VDDA_PEX3")
	)
	(via
		(at 390.86663 -296.834052)
		(size 0.6604)
		(drill 0.3302)
		(layers "F.Cu" "B.Cu")
		(net "P1V8_VDDA_PEX3")
	)
	(via
		(at 374.96242 -261.790688)
		(size 0.508)
		(drill 0.254)
		(layers "F.Cu" "B.Cu")
		(net "P1V8_VDDA_PEX3")
	)
	(via
		(at 420.9796 -286.5374)
		(size 0.6604)
		(drill 0.3302)
		(layers "F.Cu" "B.Cu")
		(net "P1V8_VDDA_PEX3")
	)
	(via
		(at 394.649452 -303.508918)
		(size 0.6604)
		(drill 0.3302)
		(layers "F.Cu" "B.Cu")
		(net "P1V8_VDDA_PEX3")
	)
	(via
		(at 393.22502 -299.224954)
		(size 0.4064)
		(drill 0.2032)
		(layers "F.Cu" "B.Cu")
		(net "P1V8_VDDA_PEX3")
	)
	(via
		(at 417.924996 -286.874966)
		(size 0.4064)
		(drill 0.2032)
		(layers "F.Cu" "B.Cu")
		(net "P1V8_VDDA_PEX3")
	)
	(segment
		(start 392.811 -297.362118)
		(end 392.811 -297.050206)
		(width 0.13208)
		(layer "B.Cu")
		(net "P1V8_VDDA_PEX3")
	)
	(segment
		(start 393.016486 -297.664632)
		(end 393.016486 -297.815)
		(width 0.13208)
		(layer "B.Cu")
		(net "P1V8_VDDA_PEX3")
	)
	(segment
		(start 419.408356 -300.174914)
		(end 419.824916 -300.174914)
		(width 0.3048)
		(layer "B.Cu")
		(net "P1V8_VDDA_PEX3")
	)
	(segment
		(start 396.6083 -303.136046)
		(end 396.235428 -303.508918)
		(width 0.13208)
		(layer "B.Cu")
		(net "P1V8_VDDA_PEX3")
	)
	(segment
		(start 397.23314 -288.774886)
		(end 397.02486 -288.774886)
		(width 0.3048)
		(layer "B.Cu")
		(net "P1V8_VDDA_PEX3")
	)
	(segment
		(start 417.924996 -305.341528)
		(end 417.924996 -304.924714)
		(width 0.3048)
		(layer "B.Cu")
		(net "P1V8_VDDA_PEX3")
	)
	(segment
		(start 417.924996 -304.508154)
		(end 417.924996 -304.924714)
		(width 0.3048)
		(layer "B.Cu")
		(net "P1V8_VDDA_PEX3")
	)
	(segment
		(start 392.87958 -297.527726)
		(end 392.811 -297.362118)
		(width 0.13208)
		(layer "B.Cu")
		(net "P1V8_VDDA_PEX3")
	)
	(segment
		(start 420.241476 -300.174914)
		(end 419.824916 -300.174914)
		(width 0.3048)
		(layer "B.Cu")
		(net "P1V8_VDDA_PEX3")
	)
	(segment
		(start 417.183316 -300.174914)
		(end 416.974782 -300.174914)
		(width 0.3048)
		(layer "B.Cu")
		(net "P1V8_VDDA_PEX3")
	)
	(segment
		(start 396.6083 -303.024794)
		(end 396.6083 -303.136046)
		(width 0.13208)
		(layer "B.Cu")
		(net "P1V8_VDDA_PEX3")
	)
	(segment
		(start 396.235428 -303.508918)
		(end 394.649452 -303.508918)
		(width 0.13208)
		(layer "B.Cu")
		(net "P1V8_VDDA_PEX3")
	)
	(segment
		(start 392.594846 -296.834052)
		(end 390.86663 -296.834052)
		(width 0.13208)
		(layer "B.Cu")
		(net "P1V8_VDDA_PEX3")
	)
	(segment
		(start 392.811 -297.050206)
		(end 392.594846 -296.834052)
		(width 0.13208)
		(layer "B.Cu")
		(net "P1V8_VDDA_PEX3")
	)
	(segment
		(start 393.016486 -297.664632)
		(end 392.87958 -297.527726)
		(width 0.13208)
		(layer "B.Cu")
		(net "P1V8_VDDA_PEX3")
	)
	(segment
		(start 410.324808 -286.874966)
		(end 409.849828 -287.349946)
		(width 0.249936)
		(layer "F.Cu")
		(net "P1V25_SERDES_VDDPLL_PEX3")
	)
	(segment
		(start 413.174942 -286.874966)
		(end 412.699962 -287.349946)
		(width 0.249936)
		(layer "F.Cu")
		(net "P1V25_SERDES_VDDPLL_PEX3")
	)
	(segment
		(start 401.774914 -304.924714)
		(end 402.249894 -304.449734)
		(width 0.249936)
		(layer "F.Cu")
		(net "P1V25_SERDES_VDDPLL_PEX3")
	)
	(segment
		(start 400.824954 -286.874966)
		(end 401.299934 -287.349946)
		(width 0.249936)
		(layer "F.Cu")
		(net "P1V25_SERDES_VDDPLL_PEX3")
	)
	(segment
		(start 406.524968 -286.874966)
		(end 406.999948 -287.349946)
		(width 0.249936)
		(layer "F.Cu")
		(net "P1V25_SERDES_VDDPLL_PEX3")
	)
	(segment
		(start 411.275022 -286.874966)
		(end 410.799788 -287.349946)
		(width 0.249936)
		(layer "F.Cu")
		(net "P1V25_SERDES_VDDPLL_PEX3")
	)
	(segment
		(start 413.174942 -304.924714)
		(end 412.699962 -304.449734)
		(width 0.249936)
		(layer "F.Cu")
		(net "P1V25_SERDES_VDDPLL_PEX3")
	)
	(segment
		(start 402.724874 -286.874966)
		(end 403.199854 -287.349946)
		(width 0.249936)
		(layer "F.Cu")
		(net "P1V25_SERDES_VDDPLL_PEX3")
	)
	(segment
		(start 399.874994 -286.874966)
		(end 400.349974 -287.349946)
		(width 0.249936)
		(layer "F.Cu")
		(net "P1V25_SERDES_VDDPLL_PEX3")
	)
	(segment
		(start 420.774876 -297.32478)
		(end 420.299896 -296.8498)
		(width 0.249936)
		(layer "F.Cu")
		(net "P1V25_SERDES_VDDPLL_PEX3")
	)
	(segment
		(start 420.774876 -296.37482)
		(end 420.299896 -295.89984)
		(width 0.249936)
		(layer "F.Cu")
		(net "P1V25_SERDES_VDDPLL_PEX3")
	)
	(segment
		(start 415.074862 -304.924714)
		(end 414.599882 -304.449734)
		(width 0.249936)
		(layer "F.Cu")
		(net "P1V25_SERDES_VDDPLL_PEX3")
	)
	(segment
		(start 412.224982 -304.924714)
		(end 411.750002 -304.449734)
		(width 0.249936)
		(layer "F.Cu")
		(net "P1V25_SERDES_VDDPLL_PEX3")
	)
	(segment
		(start 420.774876 -298.27474)
		(end 420.299896 -297.79976)
		(width 0.249936)
		(layer "F.Cu")
		(net "P1V25_SERDES_VDDPLL_PEX3")
	)
	(segment
		(start 405.575008 -286.874966)
		(end 406.049988 -287.349946)
		(width 0.249936)
		(layer "F.Cu")
		(net "P1V25_SERDES_VDDPLL_PEX3")
	)
	(segment
		(start 398.925034 -304.924714)
		(end 399.400014 -304.449734)
		(width 0.249936)
		(layer "F.Cu")
		(net "P1V25_SERDES_VDDPLL_PEX3")
	)
	(segment
		(start 410.324808 -304.924714)
		(end 409.849828 -304.449734)
		(width 0.249936)
		(layer "F.Cu")
		(net "P1V25_SERDES_VDDPLL_PEX3")
	)
	(segment
		(start 401.774914 -286.874966)
		(end 402.249894 -287.349946)
		(width 0.249936)
		(layer "F.Cu")
		(net "P1V25_SERDES_VDDPLL_PEX3")
	)
	(segment
		(start 416.024822 -286.874966)
		(end 415.549842 -287.349946)
		(width 0.249936)
		(layer "F.Cu")
		(net "P1V25_SERDES_VDDPLL_PEX3")
	)
	(segment
		(start 403.674834 -304.924714)
		(end 404.149814 -304.449734)
		(width 0.249936)
		(layer "F.Cu")
		(net "P1V25_SERDES_VDDPLL_PEX3")
	)
	(segment
		(start 416.024822 -304.924714)
		(end 415.549842 -304.449734)
		(width 0.249936)
		(layer "F.Cu")
		(net "P1V25_SERDES_VDDPLL_PEX3")
	)
	(segment
		(start 420.774876 -293.52494)
		(end 420.299896 -293.99992)
		(width 0.249936)
		(layer "F.Cu")
		(net "P1V25_SERDES_VDDPLL_PEX3")
	)
	(segment
		(start 409.374848 -304.924714)
		(end 408.899868 -304.449734)
		(width 0.249936)
		(layer "F.Cu")
		(net "P1V25_SERDES_VDDPLL_PEX3")
	)
	(segment
		(start 415.074862 -286.874966)
		(end 414.599882 -287.349946)
		(width 0.249936)
		(layer "F.Cu")
		(net "P1V25_SERDES_VDDPLL_PEX3")
	)
	(segment
		(start 409.374848 -286.874966)
		(end 408.899868 -287.349946)
		(width 0.249936)
		(layer "F.Cu")
		(net "P1V25_SERDES_VDDPLL_PEX3")
	)
	(segment
		(start 414.124902 -304.924714)
		(end 413.649922 -304.449734)
		(width 0.249936)
		(layer "F.Cu")
		(net "P1V25_SERDES_VDDPLL_PEX3")
	)
	(segment
		(start 420.774876 -294.4749)
		(end 420.299896 -294.94988)
		(width 0.249936)
		(layer "F.Cu")
		(net "P1V25_SERDES_VDDPLL_PEX3")
	)
	(segment
		(start 405.575008 -304.924714)
		(end 406.049988 -304.449734)
		(width 0.249936)
		(layer "F.Cu")
		(net "P1V25_SERDES_VDDPLL_PEX3")
	)
	(segment
		(start 404.624794 -304.924714)
		(end 405.100028 -304.449734)
		(width 0.249936)
		(layer "F.Cu")
		(net "P1V25_SERDES_VDDPLL_PEX3")
	)
	(segment
		(start 408.424888 -304.924714)
		(end 407.949908 -304.449734)
		(width 0.249936)
		(layer "F.Cu")
		(net "P1V25_SERDES_VDDPLL_PEX3")
	)
	(segment
		(start 414.124902 -286.874966)
		(end 413.649922 -287.349946)
		(width 0.249936)
		(layer "F.Cu")
		(net "P1V25_SERDES_VDDPLL_PEX3")
	)
	(segment
		(start 399.874994 -304.924714)
		(end 400.349974 -304.449734)
		(width 0.249936)
		(layer "F.Cu")
		(net "P1V25_SERDES_VDDPLL_PEX3")
	)
	(segment
		(start 406.524968 -304.924714)
		(end 406.999948 -304.449734)
		(width 0.249936)
		(layer "F.Cu")
		(net "P1V25_SERDES_VDDPLL_PEX3")
	)
	(segment
		(start 403.674834 -286.874966)
		(end 404.149814 -287.349946)
		(width 0.249936)
		(layer "F.Cu")
		(net "P1V25_SERDES_VDDPLL_PEX3")
	)
	(segment
		(start 402.724874 -304.924714)
		(end 403.199854 -304.449734)
		(width 0.249936)
		(layer "F.Cu")
		(net "P1V25_SERDES_VDDPLL_PEX3")
	)
	(segment
		(start 404.624794 -286.874966)
		(end 405.100028 -287.349946)
		(width 0.249936)
		(layer "F.Cu")
		(net "P1V25_SERDES_VDDPLL_PEX3")
	)
	(segment
		(start 412.224982 -286.874966)
		(end 411.750002 -287.349946)
		(width 0.249936)
		(layer "F.Cu")
		(net "P1V25_SERDES_VDDPLL_PEX3")
	)
	(segment
		(start 408.424888 -286.874966)
		(end 407.949908 -287.349946)
		(width 0.249936)
		(layer "F.Cu")
		(net "P1V25_SERDES_VDDPLL_PEX3")
	)
	(segment
		(start 398.925034 -286.874966)
		(end 399.400014 -287.349946)
		(width 0.249936)
		(layer "F.Cu")
		(net "P1V25_SERDES_VDDPLL_PEX3")
	)
	(segment
		(start 400.824954 -304.924714)
		(end 401.299934 -304.449734)
		(width 0.249936)
		(layer "F.Cu")
		(net "P1V25_SERDES_VDDPLL_PEX3")
	)
	(segment
		(start 411.275022 -304.924714)
		(end 410.799788 -304.449734)
		(width 0.249936)
		(layer "F.Cu")
		(net "P1V25_SERDES_VDDPLL_PEX3")
	)
	(via
		(at 456.906376 -260.920992)
		(size 0.508)
		(drill 0.254)
		(layers "F.Cu" "B.Cu")
		(net "P1V25_SERDES_VDDPLL_PEX3")
	)
	(via
		(at 403.674834 -286.874966)
		(size 0.4064)
		(drill 0.2032)
		(layers "F.Cu" "B.Cu")
		(net "P1V25_SERDES_VDDPLL_PEX3")
	)
	(via
		(at 400.824954 -286.874966)
		(size 0.4064)
		(drill 0.2032)
		(layers "F.Cu" "B.Cu")
		(net "P1V25_SERDES_VDDPLL_PEX3")
	)
	(via
		(at 401.774914 -286.874966)
		(size 0.4064)
		(drill 0.2032)
		(layers "F.Cu" "B.Cu")
		(net "P1V25_SERDES_VDDPLL_PEX3")
	)
	(via
		(at 420.774876 -296.37482)
		(size 0.4064)
		(drill 0.2032)
		(layers "F.Cu" "B.Cu")
		(net "P1V25_SERDES_VDDPLL_PEX3")
	)
	(via
		(at 412.224982 -304.924714)
		(size 0.4064)
		(drill 0.2032)
		(layers "F.Cu" "B.Cu")
		(net "P1V25_SERDES_VDDPLL_PEX3")
	)
	(via
		(at 404.624794 -286.874966)
		(size 0.4064)
		(drill 0.2032)
		(layers "F.Cu" "B.Cu")
		(net "P1V25_SERDES_VDDPLL_PEX3")
	)
	(via
		(at 450.810376 -260.018276)
		(size 0.508)
		(drill 0.254)
		(layers "F.Cu" "B.Cu")
		(net "P1V25_SERDES_VDDPLL_PEX3")
	)
	(via
		(at 455.54138 -258.765548)
		(size 0.508)
		(drill 0.254)
		(layers "F.Cu" "B.Cu")
		(net "P1V25_SERDES_VDDPLL_PEX3")
	)
	(via
		(at 460.112872 -259.355336)
		(size 0.508)
		(drill 0.254)
		(layers "F.Cu" "B.Cu")
		(net "P1V25_SERDES_VDDPLL_PEX3")
	)
	(via
		(at 449.286376 -260.018276)
		(size 0.508)
		(drill 0.254)
		(layers "F.Cu" "B.Cu")
		(net "P1V25_SERDES_VDDPLL_PEX3")
	)
	(via
		(at 406.524968 -286.874966)
		(size 0.4064)
		(drill 0.2032)
		(layers "F.Cu" "B.Cu")
		(net "P1V25_SERDES_VDDPLL_PEX3")
	)
	(via
		(at 403.674834 -304.924714)
		(size 0.4064)
		(drill 0.2032)
		(layers "F.Cu" "B.Cu")
		(net "P1V25_SERDES_VDDPLL_PEX3")
	)
	(via
		(at 446.930526 -259.573776)
		(size 0.508)
		(drill 0.254)
		(layers "F.Cu" "B.Cu")
		(net "P1V25_SERDES_VDDPLL_PEX3")
	)
	(via
		(at 406.524968 -304.924714)
		(size 0.4064)
		(drill 0.2032)
		(layers "F.Cu" "B.Cu")
		(net "P1V25_SERDES_VDDPLL_PEX3")
	)
	(via
		(at 413.174942 -304.924714)
		(size 0.4064)
		(drill 0.2032)
		(layers "F.Cu" "B.Cu")
		(net "P1V25_SERDES_VDDPLL_PEX3")
	)
	(via
		(at 398.925034 -286.874966)
		(size 0.4064)
		(drill 0.2032)
		(layers "F.Cu" "B.Cu")
		(net "P1V25_SERDES_VDDPLL_PEX3")
	)
	(via
		(at 409.374848 -304.924714)
		(size 0.4064)
		(drill 0.2032)
		(layers "F.Cu" "B.Cu")
		(net "P1V25_SERDES_VDDPLL_PEX3")
	)
	(via
		(at 420.774876 -297.32478)
		(size 0.4064)
		(drill 0.2032)
		(layers "F.Cu" "B.Cu")
		(net "P1V25_SERDES_VDDPLL_PEX3")
	)
	(via
		(at 457.668376 -260.018276)
		(size 0.508)
		(drill 0.254)
		(layers "F.Cu" "B.Cu")
		(net "P1V25_SERDES_VDDPLL_PEX3")
	)
	(via
		(at 398.925034 -304.924714)
		(size 0.4064)
		(drill 0.2032)
		(layers "F.Cu" "B.Cu")
		(net "P1V25_SERDES_VDDPLL_PEX3")
	)
	(via
		(at 408.424888 -286.874966)
		(size 0.4064)
		(drill 0.2032)
		(layers "F.Cu" "B.Cu")
		(net "P1V25_SERDES_VDDPLL_PEX3")
	)
	(via
		(at 450.815202 -258.886198)
		(size 0.508)
		(drill 0.254)
		(layers "F.Cu" "B.Cu")
		(net "P1V25_SERDES_VDDPLL_PEX3")
	)
	(via
		(at 455.382376 -260.920992)
		(size 0.508)
		(drill 0.254)
		(layers "F.Cu" "B.Cu")
		(net "P1V25_SERDES_VDDPLL_PEX3")
	)
	(via
		(at 453.096376 -260.018276)
		(size 0.508)
		(drill 0.254)
		(layers "F.Cu" "B.Cu")
		(net "P1V25_SERDES_VDDPLL_PEX3")
	)
	(via
		(at 460.384652 -260.822186)
		(size 0.508)
		(drill 0.254)
		(layers "F.Cu" "B.Cu")
		(net "P1V25_SERDES_VDDPLL_PEX3")
	)
	(via
		(at 420.774876 -293.52494)
		(size 0.4064)
		(drill 0.2032)
		(layers "F.Cu" "B.Cu")
		(net "P1V25_SERDES_VDDPLL_PEX3")
	)
	(via
		(at 458.517752 -258.845812)
		(size 0.508)
		(drill 0.254)
		(layers "F.Cu" "B.Cu")
		(net "P1V25_SERDES_VDDPLL_PEX3")
	)
	(via
		(at 459.192376 -260.920992)
		(size 0.508)
		(drill 0.254)
		(layers "F.Cu" "B.Cu")
		(net "P1V25_SERDES_VDDPLL_PEX3")
	)
	(via
		(at 405.575008 -304.924714)
		(size 0.4064)
		(drill 0.2032)
		(layers "F.Cu" "B.Cu")
		(net "P1V25_SERDES_VDDPLL_PEX3")
	)
	(via
		(at 449.327016 -258.92633)
		(size 0.508)
		(drill 0.254)
		(layers "F.Cu" "B.Cu")
		(net "P1V25_SERDES_VDDPLL_PEX3")
	)
	(via
		(at 404.624794 -304.924714)
		(size 0.4064)
		(drill 0.2032)
		(layers "F.Cu" "B.Cu")
		(net "P1V25_SERDES_VDDPLL_PEX3")
	)
	(via
		(at 400.824954 -304.924714)
		(size 0.4064)
		(drill 0.2032)
		(layers "F.Cu" "B.Cu")
		(net "P1V25_SERDES_VDDPLL_PEX3")
	)
	(via
		(at 402.724874 -286.874966)
		(size 0.4064)
		(drill 0.2032)
		(layers "F.Cu" "B.Cu")
		(net "P1V25_SERDES_VDDPLL_PEX3")
	)
	(via
		(at 414.124902 -286.874966)
		(size 0.4064)
		(drill 0.2032)
		(layers "F.Cu" "B.Cu")
		(net "P1V25_SERDES_VDDPLL_PEX3")
	)
	(via
		(at 411.275022 -286.874966)
		(size 0.4064)
		(drill 0.2032)
		(layers "F.Cu" "B.Cu")
		(net "P1V25_SERDES_VDDPLL_PEX3")
	)
	(via
		(at 454.620376 -260.018276)
		(size 0.508)
		(drill 0.254)
		(layers "F.Cu" "B.Cu")
		(net "P1V25_SERDES_VDDPLL_PEX3")
	)
	(via
		(at 456.144376 -260.018276)
		(size 0.508)
		(drill 0.254)
		(layers "F.Cu" "B.Cu")
		(net "P1V25_SERDES_VDDPLL_PEX3")
	)
	(via
		(at 399.874994 -304.924714)
		(size 0.4064)
		(drill 0.2032)
		(layers "F.Cu" "B.Cu")
		(net "P1V25_SERDES_VDDPLL_PEX3")
	)
	(via
		(at 414.124902 -304.924714)
		(size 0.4064)
		(drill 0.2032)
		(layers "F.Cu" "B.Cu")
		(net "P1V25_SERDES_VDDPLL_PEX3")
	)
	(via
		(at 413.174942 -286.874966)
		(size 0.4064)
		(drill 0.2032)
		(layers "F.Cu" "B.Cu")
		(net "P1V25_SERDES_VDDPLL_PEX3")
	)
	(via
		(at 401.774914 -304.924714)
		(size 0.4064)
		(drill 0.2032)
		(layers "F.Cu" "B.Cu")
		(net "P1V25_SERDES_VDDPLL_PEX3")
	)
	(via
		(at 411.275022 -304.924714)
		(size 0.4064)
		(drill 0.2032)
		(layers "F.Cu" "B.Cu")
		(net "P1V25_SERDES_VDDPLL_PEX3")
	)
	(via
		(at 409.374848 -286.874966)
		(size 0.4064)
		(drill 0.2032)
		(layers "F.Cu" "B.Cu")
		(net "P1V25_SERDES_VDDPLL_PEX3")
	)
	(via
		(at 453.83196 -258.886198)
		(size 0.508)
		(drill 0.254)
		(layers "F.Cu" "B.Cu")
		(net "P1V25_SERDES_VDDPLL_PEX3")
	)
	(via
		(at 453.858376 -260.920992)
		(size 0.508)
		(drill 0.254)
		(layers "F.Cu" "B.Cu")
		(net "P1V25_SERDES_VDDPLL_PEX3")
	)
	(via
		(at 412.224982 -286.874966)
		(size 0.4064)
		(drill 0.2032)
		(layers "F.Cu" "B.Cu")
		(net "P1V25_SERDES_VDDPLL_PEX3")
	)
	(via
		(at 410.324808 -286.874966)
		(size 0.4064)
		(drill 0.2032)
		(layers "F.Cu" "B.Cu")
		(net "P1V25_SERDES_VDDPLL_PEX3")
	)
	(via
		(at 415.074862 -286.874966)
		(size 0.4064)
		(drill 0.2032)
		(layers "F.Cu" "B.Cu")
		(net "P1V25_SERDES_VDDPLL_PEX3")
	)
	(via
		(at 420.774876 -298.27474)
		(size 0.4064)
		(drill 0.2032)
		(layers "F.Cu" "B.Cu")
		(net "P1V25_SERDES_VDDPLL_PEX3")
	)
	(via
		(at 459.192376 -260.018276)
		(size 0.508)
		(drill 0.254)
		(layers "F.Cu" "B.Cu")
		(net "P1V25_SERDES_VDDPLL_PEX3")
	)
	(via
		(at 416.024822 -304.924714)
		(size 0.4064)
		(drill 0.2032)
		(layers "F.Cu" "B.Cu")
		(net "P1V25_SERDES_VDDPLL_PEX3")
	)
	(via
		(at 408.424888 -304.924714)
		(size 0.4064)
		(drill 0.2032)
		(layers "F.Cu" "B.Cu")
		(net "P1V25_SERDES_VDDPLL_PEX3")
	)
	(via
		(at 399.874994 -286.874966)
		(size 0.4064)
		(drill 0.2032)
		(layers "F.Cu" "B.Cu")
		(net "P1V25_SERDES_VDDPLL_PEX3")
	)
	(via
		(at 450.030342 -261.322566)
		(size 0.508)
		(drill 0.254)
		(layers "F.Cu" "B.Cu")
		(net "P1V25_SERDES_VDDPLL_PEX3")
	)
	(via
		(at 402.724874 -304.924714)
		(size 0.4064)
		(drill 0.2032)
		(layers "F.Cu" "B.Cu")
		(net "P1V25_SERDES_VDDPLL_PEX3")
	)
	(via
		(at 457.110084 -258.825746)
		(size 0.508)
		(drill 0.254)
		(layers "F.Cu" "B.Cu")
		(net "P1V25_SERDES_VDDPLL_PEX3")
	)
	(via
		(at 452.334376 -260.920992)
		(size 0.508)
		(drill 0.254)
		(layers "F.Cu" "B.Cu")
		(net "P1V25_SERDES_VDDPLL_PEX3")
	)
	(via
		(at 451.874382 -259.951728)
		(size 0.508)
		(drill 0.254)
		(layers "F.Cu" "B.Cu")
		(net "P1V25_SERDES_VDDPLL_PEX3")
	)
	(via
		(at 416.024822 -286.874966)
		(size 0.4064)
		(drill 0.2032)
		(layers "F.Cu" "B.Cu")
		(net "P1V25_SERDES_VDDPLL_PEX3")
	)
	(via
		(at 415.074862 -304.924714)
		(size 0.4064)
		(drill 0.2032)
		(layers "F.Cu" "B.Cu")
		(net "P1V25_SERDES_VDDPLL_PEX3")
	)
	(via
		(at 452.323708 -258.946396)
		(size 0.508)
		(drill 0.254)
		(layers "F.Cu" "B.Cu")
		(net "P1V25_SERDES_VDDPLL_PEX3")
	)
	(via
		(at 450.810376 -260.920992)
		(size 0.508)
		(drill 0.254)
		(layers "F.Cu" "B.Cu")
		(net "P1V25_SERDES_VDDPLL_PEX3")
	)
	(via
		(at 459.828646 -261.941056)
		(size 0.508)
		(drill 0.254)
		(layers "F.Cu" "B.Cu")
		(net "P1V25_SERDES_VDDPLL_PEX3")
	)
	(via
		(at 410.324808 -304.924714)
		(size 0.4064)
		(drill 0.2032)
		(layers "F.Cu" "B.Cu")
		(net "P1V25_SERDES_VDDPLL_PEX3")
	)
	(via
		(at 449.286376 -260.920992)
		(size 0.508)
		(drill 0.254)
		(layers "F.Cu" "B.Cu")
		(net "P1V25_SERDES_VDDPLL_PEX3")
	)
	(via
		(at 405.575008 -286.874966)
		(size 0.4064)
		(drill 0.2032)
		(layers "F.Cu" "B.Cu")
		(net "P1V25_SERDES_VDDPLL_PEX3")
	)
	(via
		(at 458.051154 -260.977634)
		(size 0.508)
		(drill 0.254)
		(layers "F.Cu" "B.Cu")
		(net "P1V25_SERDES_VDDPLL_PEX3")
	)
	(via
		(at 420.774876 -294.4749)
		(size 0.4064)
		(drill 0.2032)
		(layers "F.Cu" "B.Cu")
		(net "P1V25_SERDES_VDDPLL_PEX3")
	)
	(segment
		(start 409.849828 -289.249866)
		(end 410.324808 -288.774886)
		(width 0.249936)
		(layer "F.Cu")
		(net "P1V25_PEX3")
	)
	(segment
		(start 410.799788 -289.249866)
		(end 411.275022 -288.774886)
		(width 0.249936)
		(layer "F.Cu")
		(net "P1V25_PEX3")
	)
	(segment
		(start 401.774914 -288.774886)
		(end 402.249894 -289.249866)
		(width 0.249936)
		(layer "F.Cu")
		(net "P1V25_PEX3")
	)
	(segment
		(start 418.874956 -298.27474)
		(end 418.399976 -297.79976)
		(width 0.249936)
		(layer "F.Cu")
		(net "P1V25_PEX3")
	)
	(segment
		(start 405.100028 -289.249866)
		(end 405.575008 -288.774886)
		(width 0.249936)
		(layer "F.Cu")
		(net "P1V25_PEX3")
	)
	(segment
		(start 413.649922 -289.249866)
		(end 414.124902 -288.774886)
		(width 0.249936)
		(layer "F.Cu")
		(net "P1V25_PEX3")
	)
	(segment
		(start 403.674834 -303.024794)
		(end 404.149814 -302.549814)
		(width 0.249936)
		(layer "F.Cu")
		(net "P1V25_PEX3")
	)
	(segment
		(start 411.750002 -302.549814)
		(end 412.224982 -303.024794)
		(width 0.249936)
		(layer "F.Cu")
		(net "P1V25_PEX3")
	)
	(segment
		(start 410.799788 -302.549814)
		(end 411.275022 -303.024794)
		(width 0.249936)
		(layer "F.Cu")
		(net "P1V25_PEX3")
	)
	(segment
		(start 405.575008 -303.024794)
		(end 406.049988 -302.549814)
		(width 0.249936)
		(layer "F.Cu")
		(net "P1V25_PEX3")
	)
	(segment
		(start 411.750002 -289.249866)
		(end 412.224982 -288.774886)
		(width 0.249936)
		(layer "F.Cu")
		(net "P1V25_PEX3")
	)
	(segment
		(start 418.399976 -295.89984)
		(end 418.874956 -296.37482)
		(width 0.249936)
		(layer "F.Cu")
		(net "P1V25_PEX3")
	)
	(segment
		(start 404.624794 -303.024794)
		(end 405.100028 -302.549814)
		(width 0.249936)
		(layer "F.Cu")
		(net "P1V25_PEX3")
	)
	(segment
		(start 409.849828 -302.549814)
		(end 410.324808 -303.024794)
		(width 0.249936)
		(layer "F.Cu")
		(net "P1V25_PEX3")
	)
	(segment
		(start 402.724874 -288.774886)
		(end 402.249894 -289.249866)
		(width 0.249936)
		(layer "F.Cu")
		(net "P1V25_PEX3")
	)
	(segment
		(start 414.599882 -289.249866)
		(end 415.074862 -288.774886)
		(width 0.249936)
		(layer "F.Cu")
		(net "P1V25_PEX3")
	)
	(segment
		(start 408.899868 -302.549814)
		(end 409.374848 -303.024794)
		(width 0.249936)
		(layer "F.Cu")
		(net "P1V25_PEX3")
	)
	(segment
		(start 462.324958 -308.692296)
		(end 462.938876 -308.692296)
		(width 0.254)
		(layer "F.Cu")
		(net "P1V25_PEX3")
	)
	(segment
		(start 400.824954 -288.774886)
		(end 401.299934 -289.249866)
		(width 0.249936)
		(layer "F.Cu")
		(net "P1V25_PEX3")
	)
	(segment
		(start 398.925034 -288.774886)
		(end 399.400014 -289.249866)
		(width 0.249936)
		(layer "F.Cu")
		(net "P1V25_PEX3")
	)
	(segment
		(start 408.899868 -289.249866)
		(end 409.374848 -288.774886)
		(width 0.249936)
		(layer "F.Cu")
		(net "P1V25_PEX3")
	)
	(segment
		(start 399.874994 -303.024794)
		(end 399.400014 -302.549814)
		(width 0.249936)
		(layer "F.Cu")
		(net "P1V25_PEX3")
	)
	(segment
		(start 407.949908 -289.249866)
		(end 408.424888 -288.774886)
		(width 0.249936)
		(layer "F.Cu")
		(net "P1V25_PEX3")
	)
	(segment
		(start 412.699962 -289.249866)
		(end 413.174942 -288.774886)
		(width 0.249936)
		(layer "F.Cu")
		(net "P1V25_PEX3")
	)
	(segment
		(start 402.724874 -303.024794)
		(end 402.249894 -302.549814)
		(width 0.249936)
		(layer "F.Cu")
		(net "P1V25_PEX3")
	)
	(segment
		(start 415.074862 -288.774886)
		(end 415.549842 -289.249866)
		(width 0.249936)
		(layer "F.Cu")
		(net "P1V25_PEX3")
	)
	(segment
		(start 414.124902 -288.774886)
		(end 414.599882 -289.249866)
		(width 0.249936)
		(layer "F.Cu")
		(net "P1V25_PEX3")
	)
	(segment
		(start 408.424888 -288.774886)
		(end 408.899868 -289.249866)
		(width 0.249936)
		(layer "F.Cu")
		(net "P1V25_PEX3")
	)
	(segment
		(start 401.299934 -302.549814)
		(end 400.824954 -303.024794)
		(width 0.249936)
		(layer "F.Cu")
		(net "P1V25_PEX3")
	)
	(segment
		(start 400.349974 -289.249866)
		(end 400.824954 -288.774886)
		(width 0.249936)
		(layer "F.Cu")
		(net "P1V25_PEX3")
	)
	(segment
		(start 404.149814 -302.549814)
		(end 404.624794 -303.024794)
		(width 0.249936)
		(layer "F.Cu")
		(net "P1V25_PEX3")
	)
	(segment
		(start 404.149814 -289.249866)
		(end 404.624794 -288.774886)
		(width 0.249936)
		(layer "F.Cu")
		(net "P1V25_PEX3")
	)
	(segment
		(start 398.925034 -303.024794)
		(end 399.400014 -302.549814)
		(width 0.249936)
		(layer "F.Cu")
		(net "P1V25_PEX3")
	)
	(segment
		(start 414.599882 -302.549814)
		(end 415.074862 -303.024794)
		(width 0.249936)
		(layer "F.Cu")
		(net "P1V25_PEX3")
	)
	(segment
		(start 402.249894 -302.549814)
		(end 401.774914 -303.024794)
		(width 0.249936)
		(layer "F.Cu")
		(net "P1V25_PEX3")
	)
	(segment
		(start 409.374848 -288.774886)
		(end 409.849828 -289.249866)
		(width 0.249936)
		(layer "F.Cu")
		(net "P1V25_PEX3")
	)
	(segment
		(start 418.874956 -297.32478)
		(end 418.399976 -296.8498)
		(width 0.249936)
		(layer "F.Cu")
		(net "P1V25_PEX3")
	)
	(segment
		(start 403.199854 -289.249866)
		(end 402.724874 -288.774886)
		(width 0.249936)
		(layer "F.Cu")
		(net "P1V25_PEX3")
	)
	(segment
		(start 408.899868 -302.549814)
		(end 408.424888 -303.024794)
		(width 0.249936)
		(layer "F.Cu")
		(net "P1V25_PEX3")
	)
	(segment
		(start 400.349974 -289.249866)
		(end 399.874994 -288.774886)
		(width 0.249936)
		(layer "F.Cu")
		(net "P1V25_PEX3")
	)
	(segment
		(start 410.324808 -288.774886)
		(end 410.799788 -289.249866)
		(width 0.249936)
		(layer "F.Cu")
		(net "P1V25_PEX3")
	)
	(segment
		(start 416.024822 -288.774886)
		(end 415.549842 -289.249866)
		(width 0.249936)
		(layer "F.Cu")
		(net "P1V25_PEX3")
	)
	(segment
		(start 418.874956 -294.4749)
		(end 418.399976 -294.94988)
		(width 0.249936)
		(layer "F.Cu")
		(net "P1V25_PEX3")
	)
	(segment
		(start 401.299934 -289.249866)
		(end 401.774914 -288.774886)
		(width 0.249936)
		(layer "F.Cu")
		(net "P1V25_PEX3")
	)
	(segment
		(start 413.174942 -288.774886)
		(end 413.649922 -289.249866)
		(width 0.249936)
		(layer "F.Cu")
		(net "P1V25_PEX3")
	)
	(segment
		(start 399.874994 -288.774886)
		(end 399.400014 -289.249866)
		(width 0.249936)
		(layer "F.Cu")
		(net "P1V25_PEX3")
	)
	(segment
		(start 406.049988 -289.249866)
		(end 406.524968 -288.774886)
		(width 0.249936)
		(layer "F.Cu")
		(net "P1V25_PEX3")
	)
	(segment
		(start 406.524968 -288.774886)
		(end 406.999948 -289.249866)
		(width 0.249936)
		(layer "F.Cu")
		(net "P1V25_PEX3")
	)
	(segment
		(start 404.624794 -288.774886)
		(end 405.100028 -289.249866)
		(width 0.249936)
		(layer "F.Cu")
		(net "P1V25_PEX3")
	)
	(segment
		(start 403.199854 -302.549814)
		(end 403.674834 -303.024794)
		(width 0.249936)
		(layer "F.Cu")
		(net "P1V25_PEX3")
	)
	(segment
		(start 400.349974 -302.549814)
		(end 399.874994 -303.024794)
		(width 0.249936)
		(layer "F.Cu")
		(net "P1V25_PEX3")
	)
	(segment
		(start 406.999948 -302.549814)
		(end 406.524968 -303.024794)
		(width 0.249936)
		(layer "F.Cu")
		(net "P1V25_PEX3")
	)
	(segment
		(start 403.199854 -302.549814)
		(end 402.724874 -303.024794)
		(width 0.249936)
		(layer "F.Cu")
		(net "P1V25_PEX3")
	)
	(segment
		(start 403.674834 -288.774886)
		(end 404.149814 -289.249866)
		(width 0.249936)
		(layer "F.Cu")
		(net "P1V25_PEX3")
	)
	(segment
		(start 412.224982 -288.774886)
		(end 412.699962 -289.249866)
		(width 0.249936)
		(layer "F.Cu")
		(net "P1V25_PEX3")
	)
	(segment
		(start 403.199854 -289.249866)
		(end 403.674834 -288.774886)
		(width 0.249936)
		(layer "F.Cu")
		(net "P1V25_PEX3")
	)
	(segment
		(start 405.100028 -302.549814)
		(end 405.575008 -303.024794)
		(width 0.249936)
		(layer "F.Cu")
		(net "P1V25_PEX3")
	)
	(segment
		(start 405.575008 -288.774886)
		(end 406.049988 -289.249866)
		(width 0.249936)
		(layer "F.Cu")
		(net "P1V25_PEX3")
	)
	(segment
		(start 412.699962 -302.549814)
		(end 413.174942 -303.024794)
		(width 0.249936)
		(layer "F.Cu")
		(net "P1V25_PEX3")
	)
	(segment
		(start 400.824954 -303.024794)
		(end 400.349974 -302.549814)
		(width 0.249936)
		(layer "F.Cu")
		(net "P1V25_PEX3")
	)
	(segment
		(start 418.874956 -293.52494)
		(end 418.399976 -293.99992)
		(width 0.249936)
		(layer "F.Cu")
		(net "P1V25_PEX3")
	)
	(segment
		(start 418.874956 -296.37482)
		(end 418.399976 -296.8498)
		(width 0.249936)
		(layer "F.Cu")
		(net "P1V25_PEX3")
	)
	(segment
		(start 401.774914 -303.024794)
		(end 401.299934 -302.549814)
		(width 0.249936)
		(layer "F.Cu")
		(net "P1V25_PEX3")
	)
	(segment
		(start 418.399976 -297.79976)
		(end 418.874956 -297.32478)
		(width 0.249936)
		(layer "F.Cu")
		(net "P1V25_PEX3")
	)
	(segment
		(start 406.524968 -303.024794)
		(end 406.049988 -302.549814)
		(width 0.249936)
		(layer "F.Cu")
		(net "P1V25_PEX3")
	)
	(segment
		(start 408.424888 -303.024794)
		(end 407.949908 -302.549814)
		(width 0.249936)
		(layer "F.Cu")
		(net "P1V25_PEX3")
	)
	(segment
		(start 411.275022 -288.774886)
		(end 411.750002 -289.249866)
		(width 0.249936)
		(layer "F.Cu")
		(net "P1V25_PEX3")
	)
	(segment
		(start 413.649922 -302.549814)
		(end 414.124902 -303.024794)
		(width 0.249936)
		(layer "F.Cu")
		(net "P1V25_PEX3")
	)
	(segment
		(start 415.549842 -302.549814)
		(end 416.024822 -303.024794)
		(width 0.249936)
		(layer "F.Cu")
		(net "P1V25_PEX3")
	)
	(via
		(at 402.724874 -303.024794)
		(size 0.4064)
		(drill 0.2032)
		(layers "F.Cu" "B.Cu")
		(net "P1V25_PEX3")
	)
	(via
		(at 452.863204 -277.457154)
		(size 0.508)
		(drill 0.254)
		(layers "F.Cu" "B.Cu")
		(net "P1V25_PEX3")
	)
	(via
		(at 406.524968 -303.024794)
		(size 0.4064)
		(drill 0.2032)
		(layers "F.Cu" "B.Cu")
		(net "P1V25_PEX3")
	)
	(via
		(at 408.424888 -303.024794)
		(size 0.4064)
		(drill 0.2032)
		(layers "F.Cu" "B.Cu")
		(net "P1V25_PEX3")
	)
	(via
		(at 452.424292 -272.975578)
		(size 0.508)
		(drill 0.254)
		(layers "F.Cu" "B.Cu")
		(net "P1V25_PEX3")
	)
	(via
		(at 415.074862 -288.774886)
		(size 0.4064)
		(drill 0.2032)
		(layers "F.Cu" "B.Cu")
		(net "P1V25_PEX3")
	)
	(via
		(at 410.324808 -288.774886)
		(size 0.4064)
		(drill 0.2032)
		(layers "F.Cu" "B.Cu")
		(net "P1V25_PEX3")
	)
	(via
		(at 418.874956 -298.27474)
		(size 0.4064)
		(drill 0.2032)
		(layers "F.Cu" "B.Cu")
		(net "P1V25_PEX3")
	)
	(via
		(at 453.084692 -272.975578)
		(size 0.508)
		(drill 0.254)
		(layers "F.Cu" "B.Cu")
		(net "P1V25_PEX3")
	)
	(via
		(at 455.507344 -272.31086)
		(size 0.508)
		(drill 0.254)
		(layers "F.Cu" "B.Cu")
		(net "P1V25_PEX3")
	)
	(via
		(at 418.874956 -296.37482)
		(size 0.4064)
		(drill 0.2032)
		(layers "F.Cu" "B.Cu")
		(net "P1V25_PEX3")
	)
	(via
		(at 410.324808 -303.024794)
		(size 0.4064)
		(drill 0.2032)
		(layers "F.Cu" "B.Cu")
		(net "P1V25_PEX3")
	)
	(via
		(at 451.763892 -272.340578)
		(size 0.508)
		(drill 0.254)
		(layers "F.Cu" "B.Cu")
		(net "P1V25_PEX3")
	)
	(via
		(at 408.424888 -288.774886)
		(size 0.4064)
		(drill 0.2032)
		(layers "F.Cu" "B.Cu")
		(net "P1V25_PEX3")
	)
	(via
		(at 414.124902 -303.024794)
		(size 0.4064)
		(drill 0.2032)
		(layers "F.Cu" "B.Cu")
		(net "P1V25_PEX3")
	)
	(via
		(at 451.542404 -276.822154)
		(size 0.508)
		(drill 0.254)
		(layers "F.Cu" "B.Cu")
		(net "P1V25_PEX3")
	)
	(via
		(at 399.874994 -303.024794)
		(size 0.4064)
		(drill 0.2032)
		(layers "F.Cu" "B.Cu")
		(net "P1V25_PEX3")
	)
	(via
		(at 403.674834 -288.774886)
		(size 0.4064)
		(drill 0.2032)
		(layers "F.Cu" "B.Cu")
		(net "P1V25_PEX3")
	)
	(via
		(at 452.202804 -277.457154)
		(size 0.508)
		(drill 0.254)
		(layers "F.Cu" "B.Cu")
		(net "P1V25_PEX3")
	)
	(via
		(at 451.103492 -272.340578)
		(size 0.508)
		(drill 0.254)
		(layers "F.Cu" "B.Cu")
		(net "P1V25_PEX3")
	)
	(via
		(at 409.374848 -303.024794)
		(size 0.4064)
		(drill 0.2032)
		(layers "F.Cu" "B.Cu")
		(net "P1V25_PEX3")
	)
	(via
		(at 406.524968 -288.774886)
		(size 0.4064)
		(drill 0.2032)
		(layers "F.Cu" "B.Cu")
		(net "P1V25_PEX3")
	)
	(via
		(at 451.542404 -277.457154)
		(size 0.508)
		(drill 0.254)
		(layers "F.Cu" "B.Cu")
		(net "P1V25_PEX3")
	)
	(via
		(at 425.52493 -294.4749)
		(size 0.4064)
		(drill 0.2032)
		(layers "F.Cu" "B.Cu")
		(net "P1V25_PEX3")
	)
	(via
		(at 452.863204 -276.822154)
		(size 0.508)
		(drill 0.254)
		(layers "F.Cu" "B.Cu")
		(net "P1V25_PEX3")
	)
	(via
		(at 398.925034 -303.024794)
		(size 0.4064)
		(drill 0.2032)
		(layers "F.Cu" "B.Cu")
		(net "P1V25_PEX3")
	)
	(via
		(at 400.824954 -303.024794)
		(size 0.4064)
		(drill 0.2032)
		(layers "F.Cu" "B.Cu")
		(net "P1V25_PEX3")
	)
	(via
		(at 413.174942 -303.024794)
		(size 0.4064)
		(drill 0.2032)
		(layers "F.Cu" "B.Cu")
		(net "P1V25_PEX3")
	)
	(via
		(at 405.575008 -303.024794)
		(size 0.4064)
		(drill 0.2032)
		(layers "F.Cu" "B.Cu")
		(net "P1V25_PEX3")
	)
	(via
		(at 404.624794 -303.024794)
		(size 0.4064)
		(drill 0.2032)
		(layers "F.Cu" "B.Cu")
		(net "P1V25_PEX3")
	)
	(via
		(at 416.024822 -288.774886)
		(size 0.4064)
		(drill 0.2032)
		(layers "F.Cu" "B.Cu")
		(net "P1V25_PEX3")
	)
	(via
		(at 418.77742 -295.430956)
		(size 0.6604)
		(drill 0.3302)
		(layers "F.Cu" "B.Cu")
		(net "P1V25_PEX3")
	)
	(via
		(at 403.674834 -303.024794)
		(size 0.4064)
		(drill 0.2032)
		(layers "F.Cu" "B.Cu")
		(net "P1V25_PEX3")
	)
	(via
		(at 455.507344 -272.94586)
		(size 0.508)
		(drill 0.254)
		(layers "F.Cu" "B.Cu")
		(net "P1V25_PEX3")
	)
	(via
		(at 425.52493 -296.37482)
		(size 0.4064)
		(drill 0.2032)
		(layers "F.Cu" "B.Cu")
		(net "P1V25_PEX3")
	)
	(via
		(at 456.167744 -272.31086)
		(size 0.508)
		(drill 0.254)
		(layers "F.Cu" "B.Cu")
		(net "P1V25_PEX3")
	)
	(via
		(at 401.774914 -303.024794)
		(size 0.4064)
		(drill 0.2032)
		(layers "F.Cu" "B.Cu")
		(net "P1V25_PEX3")
	)
	(via
		(at 456.828144 -272.94586)
		(size 0.508)
		(drill 0.254)
		(layers "F.Cu" "B.Cu")
		(net "P1V25_PEX3")
	)
	(via
		(at 418.874956 -297.32478)
		(size 0.4064)
		(drill 0.2032)
		(layers "F.Cu" "B.Cu")
		(net "P1V25_PEX3")
	)
	(via
		(at 411.275022 -303.024794)
		(size 0.4064)
		(drill 0.2032)
		(layers "F.Cu" "B.Cu")
		(net "P1V25_PEX3")
	)
	(via
		(at 405.575008 -288.774886)
		(size 0.4064)
		(drill 0.2032)
		(layers "F.Cu" "B.Cu")
		(net "P1V25_PEX3")
	)
	(via
		(at 401.774914 -288.774886)
		(size 0.4064)
		(drill 0.2032)
		(layers "F.Cu" "B.Cu")
		(net "P1V25_PEX3")
	)
	(via
		(at 412.224982 -303.024794)
		(size 0.4064)
		(drill 0.2032)
		(layers "F.Cu" "B.Cu")
		(net "P1V25_PEX3")
	)
	(via
		(at 451.103492 -272.975578)
		(size 0.508)
		(drill 0.254)
		(layers "F.Cu" "B.Cu")
		(net "P1V25_PEX3")
	)
	(via
		(at 416.024822 -303.024794)
		(size 0.4064)
		(drill 0.2032)
		(layers "F.Cu" "B.Cu")
		(net "P1V25_PEX3")
	)
	(via
		(at 426.47489 -296.37482)
		(size 0.4064)
		(drill 0.2032)
		(layers "F.Cu" "B.Cu")
		(net "P1V25_PEX3")
	)
	(via
		(at 462.938876 -308.692296)
		(size 0.508)
		(drill 0.254)
		(layers "F.Cu" "B.Cu")
		(net "P1V25_PEX3")
	)
	(via
		(at 400.824954 -288.774886)
		(size 0.4064)
		(drill 0.2032)
		(layers "F.Cu" "B.Cu")
		(net "P1V25_PEX3")
	)
	(via
		(at 456.167744 -272.94586)
		(size 0.508)
		(drill 0.254)
		(layers "F.Cu" "B.Cu")
		(net "P1V25_PEX3")
	)
	(via
		(at 411.275022 -288.774886)
		(size 0.4064)
		(drill 0.2032)
		(layers "F.Cu" "B.Cu")
		(net "P1V25_PEX3")
	)
	(via
		(at 455.323702 -274.166076)
		(size 0.6604)
		(drill 0.3302)
		(layers "F.Cu" "B.Cu")
		(net "P1V25_PEX3")
	)
	(via
		(at 418.874956 -294.4749)
		(size 0.4064)
		(drill 0.2032)
		(layers "F.Cu" "B.Cu")
		(net "P1V25_PEX3")
	)
	(via
		(at 418.874956 -293.52494)
		(size 0.4064)
		(drill 0.2032)
		(layers "F.Cu" "B.Cu")
		(net "P1V25_PEX3")
	)
	(via
		(at 456.828144 -272.31086)
		(size 0.508)
		(drill 0.254)
		(layers "F.Cu" "B.Cu")
		(net "P1V25_PEX3")
	)
	(via
		(at 454.805288 -275.628608)
		(size 0.508)
		(drill 0.254)
		(layers "F.Cu" "B.Cu")
		(net "P1V25_PEX3")
	)
	(via
		(at 452.202804 -276.822154)
		(size 0.508)
		(drill 0.254)
		(layers "F.Cu" "B.Cu")
		(net "P1V25_PEX3")
	)
	(via
		(at 453.084692 -272.340578)
		(size 0.508)
		(drill 0.254)
		(layers "F.Cu" "B.Cu")
		(net "P1V25_PEX3")
	)
	(via
		(at 450.882004 -276.822154)
		(size 0.508)
		(drill 0.254)
		(layers "F.Cu" "B.Cu")
		(net "P1V25_PEX3")
	)
	(via
		(at 454.822306 -274.97659)
		(size 0.508)
		(drill 0.254)
		(layers "F.Cu" "B.Cu")
		(net "P1V25_PEX3")
	)
	(via
		(at 413.174942 -288.774886)
		(size 0.4064)
		(drill 0.2032)
		(layers "F.Cu" "B.Cu")
		(net "P1V25_PEX3")
	)
	(via
		(at 452.515986 -274.84705)
		(size 0.6604)
		(drill 0.3302)
		(layers "F.Cu" "B.Cu")
		(net "P1V25_PEX3")
	)
	(via
		(at 450.882004 -277.457154)
		(size 0.508)
		(drill 0.254)
		(layers "F.Cu" "B.Cu")
		(net "P1V25_PEX3")
	)
	(via
		(at 402.724874 -288.774886)
		(size 0.4064)
		(drill 0.2032)
		(layers "F.Cu" "B.Cu")
		(net "P1V25_PEX3")
	)
	(via
		(at 451.763892 -272.975578)
		(size 0.508)
		(drill 0.254)
		(layers "F.Cu" "B.Cu")
		(net "P1V25_PEX3")
	)
	(via
		(at 409.374848 -288.774886)
		(size 0.4064)
		(drill 0.2032)
		(layers "F.Cu" "B.Cu")
		(net "P1V25_PEX3")
	)
	(via
		(at 415.074862 -303.024794)
		(size 0.4064)
		(drill 0.2032)
		(layers "F.Cu" "B.Cu")
		(net "P1V25_PEX3")
	)
	(via
		(at 414.124902 -288.774886)
		(size 0.4064)
		(drill 0.2032)
		(layers "F.Cu" "B.Cu")
		(net "P1V25_PEX3")
	)
	(via
		(at 404.624794 -288.774886)
		(size 0.4064)
		(drill 0.2032)
		(layers "F.Cu" "B.Cu")
		(net "P1V25_PEX3")
	)
	(via
		(at 398.925034 -288.774886)
		(size 0.4064)
		(drill 0.2032)
		(layers "F.Cu" "B.Cu")
		(net "P1V25_PEX3")
	)
	(via
		(at 427.42485 -310.624728)
		(size 0.4064)
		(drill 0.2032)
		(layers "F.Cu" "B.Cu")
		(net "P1V25_PEX3")
	)
	(via
		(at 399.874994 -288.774886)
		(size 0.4064)
		(drill 0.2032)
		(layers "F.Cu" "B.Cu")
		(net "P1V25_PEX3")
	)
	(via
		(at 454.846944 -272.31086)
		(size 0.508)
		(drill 0.254)
		(layers "F.Cu" "B.Cu")
		(net "P1V25_PEX3")
	)
	(via
		(at 412.224982 -288.774886)
		(size 0.4064)
		(drill 0.2032)
		(layers "F.Cu" "B.Cu")
		(net "P1V25_PEX3")
	)
	(via
		(at 452.424292 -272.340578)
		(size 0.508)
		(drill 0.254)
		(layers "F.Cu" "B.Cu")
		(net "P1V25_PEX3")
	)
	(via
		(at 454.846944 -272.94586)
		(size 0.508)
		(drill 0.254)
		(layers "F.Cu" "B.Cu")
		(net "P1V25_PEX3")
	)
	(segment
		(start 464.168236 -287.908492)
		(end 462.880964 -286.62122)
		(width 0.254)
		(layer "In15.Cu")
		(net "P1V25_PEX3")
	)
	(segment
		(start 432.050698 -295.273476)
		(end 419.519862 -295.273476)
		(width 0.254)
		(layer "In15.Cu")
		(net "P1V25_PEX3")
	)
	(segment
		(start 462.880964 -286.62122)
		(end 456.63358 -286.62122)
		(width 0.254)
		(layer "In15.Cu")
		(net "P1V25_PEX3")
	)
	(segment
		(start 434.215032 -293.109142)
		(end 432.050698 -295.273476)
		(width 0.254)
		(layer "In15.Cu")
		(net "P1V25_PEX3")
	)
	(segment
		(start 444.894462 -289.534346)
		(end 440.457844 -289.534346)
		(width 0.254)
		(layer "In15.Cu")
		(net "P1V25_PEX3")
	)
	(segment
		(start 456.63358 -286.62122)
		(end 456.145392 -286.133032)
		(width 0.254)
		(layer "In15.Cu")
		(net "P1V25_PEX3")
	)
	(segment
		(start 448.295776 -286.133032)
		(end 444.894462 -289.534346)
		(width 0.254)
		(layer "In15.Cu")
		(net "P1V25_PEX3")
	)
	(segment
		(start 419.104826 -296.14495)
		(end 418.874956 -296.37482)
		(width 0.254)
		(layer "In15.Cu")
		(net "P1V25_PEX3")
	)
	(segment
		(start 464.168236 -307.81752)
		(end 464.168236 -287.908492)
		(width 0.254)
		(layer "In15.Cu")
		(net "P1V25_PEX3")
	)
	(segment
		(start 463.302096 -308.329076)
		(end 463.65668 -308.329076)
		(width 0.254)
		(layer "In15.Cu")
		(net "P1V25_PEX3")
	)
	(segment
		(start 419.104826 -295.688512)
		(end 419.104826 -296.14495)
		(width 0.254)
		(layer "In15.Cu")
		(net "P1V25_PEX3")
	)
	(segment
		(start 440.457844 -289.534346)
		(end 436.883048 -293.109142)
		(width 0.254)
		(layer "In15.Cu")
		(net "P1V25_PEX3")
	)
	(segment
		(start 462.938876 -308.692296)
		(end 463.302096 -308.329076)
		(width 0.254)
		(layer "In15.Cu")
		(net "P1V25_PEX3")
	)
	(segment
		(start 456.145392 -286.133032)
		(end 448.295776 -286.133032)
		(width 0.254)
		(layer "In15.Cu")
		(net "P1V25_PEX3")
	)
	(segment
		(start 463.65668 -308.329076)
		(end 464.168236 -307.81752)
		(width 0.254)
		(layer "In15.Cu")
		(net "P1V25_PEX3")
	)
	(segment
		(start 436.883048 -293.109142)
		(end 434.215032 -293.109142)
		(width 0.254)
		(layer "In15.Cu")
		(net "P1V25_PEX3")
	)
	(segment
		(start 419.519862 -295.273476)
		(end 419.104826 -295.688512)
		(width 0.254)
		(layer "In15.Cu")
		(net "P1V25_PEX3")
	)
	(segment
		(start 229.867714 -213.504272)
		(end 230.26751 -213.104476)
		(width 0.381)
		(layer "F.Cu")
		(net "P3V3_BIC_SPI")
	)
	(via
		(at 232.43413 -213.030054)
		(size 0.6604)
		(drill 0.3302)
		(layers "F.Cu" "B.Cu")
		(net "P3V3_BIC_SPI")
	)
	(via
		(at 230.26751 -213.104476)
		(size 0.4572)
		(drill 0.254)
		(layers "F.Cu" "B.Cu")
		(net "P3V3_BIC_SPI")
	)
	(segment
		(start 230.644446 -212.136736)
		(end 231.540812 -212.136736)
		(width 0.13208)
		(layer "B.Cu")
		(net "P3V3_BIC_SPI")
	)
	(segment
		(start 231.540812 -212.136736)
		(end 232.43413 -213.030054)
		(width 0.13208)
		(layer "B.Cu")
		(net "P3V3_BIC_SPI")
	)
	(segment
		(start 233.867706 -217.504264)
		(end 234.267502 -217.104468)
		(width 0.381)
		(layer "F.Cu")
		(net "P1V2_BIC_PLL")
	)
	(via
		(at 236.444536 -215.639396)
		(size 0.6604)
		(drill 0.3302)
		(layers "F.Cu" "B.Cu")
		(net "P1V2_BIC_PLL")
	)
	(via
		(at 234.267502 -217.104468)
		(size 0.4572)
		(drill 0.254)
		(layers "F.Cu" "B.Cu")
		(net "P1V2_BIC_PLL")
	)
	(segment
		(start 227.407978 -308.271164)
		(end 227.91674 -307.762402)
		(width 0.254)
		(layer "F.Cu")
		(net "P1V25_PEX1_REF")
	)
	(segment
		(start 228.953568 -307.724556)
		(end 228.953568 -306.787042)
		(width 0.254)
		(layer "F.Cu")
		(net "P1V25_PEX1_REF")
	)
	(segment
		(start 225.91903 -308.568598)
		(end 227.004372 -308.568598)
		(width 0.1778)
		(layer "F.Cu")
		(net "P1V25_PEX1_REF")
	)
	(segment
		(start 227.004372 -308.568598)
		(end 227.185474 -308.493668)
		(width 0.1778)
		(layer "F.Cu")
		(net "P1V25_PEX1_REF")
	)
	(segment
		(start 227.91674 -307.762402)
		(end 228.915722 -307.762402)
		(width 0.254)
		(layer "F.Cu")
		(net "P1V25_PEX1_REF")
	)
	(segment
		(start 228.915722 -307.762402)
		(end 228.953568 -307.724556)
		(width 0.254)
		(layer "F.Cu")
		(net "P1V25_PEX1_REF")
	)
	(segment
		(start 228.953568 -306.787042)
		(end 229.605586 -306.787042)
		(width 0.13208)
		(layer "F.Cu")
		(net "P1V25_PEX1_REF")
	)
	(segment
		(start 227.185474 -308.493668)
		(end 227.407978 -308.271164)
		(width 0.1778)
		(layer "F.Cu")
		(net "P1V25_PEX1_REF")
	)
	(via
		(at 229.605586 -306.787042)
		(size 0.508)
		(drill 0.254)
		(layers "F.Cu" "B.Cu")
		(net "P1V25_PEX1_REF")
	)
	(segment
		(start 225.91903 -310.26862)
		(end 226.155758 -310.26862)
		(width 0.13208)
		(layer "F.Cu")
		(net "PWRGD_P1V25_PEX1")
	)
	(segment
		(start 230.848408 -311.933082)
		(end 231.832404 -311.933082)
		(width 0.13208)
		(layer "F.Cu")
		(net "PWRGD_P1V25_PEX1")
	)
	(segment
		(start 230.848408 -311.933082)
		(end 230.56723 -311.933082)
		(width 0.13208)
		(layer "F.Cu")
		(net "PWRGD_P1V25_PEX1")
	)
	(segment
		(start 230.56723 -311.933082)
		(end 230.202486 -311.568338)
		(width 0.13208)
		(layer "F.Cu")
		(net "PWRGD_P1V25_PEX1")
	)
	(segment
		(start 226.155758 -310.26862)
		(end 227.102924 -311.215786)
		(width 0.13208)
		(layer "F.Cu")
		(net "PWRGD_P1V25_PEX1")
	)
	(segment
		(start 227.102924 -311.215786)
		(end 227.880926 -311.215786)
		(width 0.13208)
		(layer "F.Cu")
		(net "PWRGD_P1V25_PEX1")
	)
	(via
		(at 230.202486 -311.568338)
		(size 0.508)
		(drill 0.254)
		(layers "F.Cu" "B.Cu")
		(net "PWRGD_P1V25_PEX1")
	)
	(via
		(at 227.880926 -311.215786)
		(size 0.508)
		(drill 0.254)
		(layers "F.Cu" "B.Cu")
		(net "PWRGD_P1V25_PEX1")
	)
	(segment
		(start 227.880926 -311.215786)
		(end 229.849934 -311.215786)
		(width 0.13208)
		(layer "B.Cu")
		(net "PWRGD_P1V25_PEX1")
	)
	(segment
		(start 229.849934 -311.215786)
		(end 230.202486 -311.568338)
		(width 0.13208)
		(layer "B.Cu")
		(net "PWRGD_P1V25_PEX1")
	)
	(segment
		(start 230.567738 -308.24043)
		(end 230.14178 -308.24043)
		(width 0.254)
		(layer "F.Cu")
		(net "SH_P1V25_PEX1_FB_P")
	)
	(segment
		(start 229.88778 -308.582822)
		(end 230.323136 -309.018178)
		(width 0.254)
		(layer "F.Cu")
		(net "SH_P1V25_PEX1_FB_P")
	)
	(segment
		(start 230.323136 -309.018178)
		(end 229.8827 -309.458614)
		(width 0.254)
		(layer "F.Cu")
		(net "SH_P1V25_PEX1_FB_P")
	)
	(segment
		(start 229.88778 -308.495446)
		(end 229.88778 -308.582822)
		(width 0.254)
		(layer "F.Cu")
		(net "SH_P1V25_PEX1_FB_P")
	)
	(segment
		(start 229.8827 -309.555642)
		(end 229.8827 -310.571642)
		(width 0.254)
		(layer "F.Cu")
		(net "SH_P1V25_PEX1_FB_P")
	)
	(segment
		(start 230.90378 -308.568852)
		(end 230.567738 -308.24043)
		(width 0.254)
		(layer "F.Cu")
		(net "SH_P1V25_PEX1_FB_P")
	)
	(segment
		(start 229.88778 -308.49443)
		(end 229.88778 -308.495446)
		(width 0.254)
		(layer "F.Cu")
		(net "SH_P1V25_PEX1_FB_P")
	)
	(segment
		(start 229.8827 -309.458614)
		(end 229.8827 -309.555642)
		(width 0.254)
		(layer "F.Cu")
		(net "SH_P1V25_PEX1_FB_P")
	)
	(segment
		(start 230.14178 -308.24043)
		(end 229.88778 -308.49443)
		(width 0.254)
		(layer "F.Cu")
		(net "SH_P1V25_PEX1_FB_P")
	)
	(via
		(at 230.323136 -309.018178)
		(size 0.508)
		(drill 0.254)
		(layers "F.Cu" "B.Cu")
		(net "SH_P1V25_PEX1_FB_P")
	)
	(segment
		(start 230.848408 -311.04332)
		(end 230.848408 -311.132982)
		(width 0.381)
		(layer "F.Cu")
		(net "P1V25_PEX1_VCC")
	)
	(segment
		(start 231.300782 -310.590946)
		(end 230.848408 -311.04332)
		(width 0.381)
		(layer "F.Cu")
		(net "P1V25_PEX1_VCC")
	)
	(via
		(at 222.331534 -306.744116)
		(size 0.508)
		(drill 0.254)
		(layers "F.Cu" "B.Cu")
		(net "P1V25_PEX1_VCC")
	)
	(via
		(at 231.300782 -310.590946)
		(size 0.508)
		(drill 0.254)
		(layers "F.Cu" "B.Cu")
		(net "P1V25_PEX1_VCC")
	)
	(segment
		(start 229.276148 -309.860188)
		(end 229.276148 -307.706268)
		(width 0.508)
		(layer "B.Cu")
		(net "P1V25_PEX1_VCC")
	)
	(segment
		(start 227.759006 -306.189126)
		(end 222.886524 -306.189126)
		(width 0.508)
		(layer "B.Cu")
		(net "P1V25_PEX1_VCC")
	)
	(segment
		(start 231.300782 -310.590946)
		(end 230.006906 -310.590946)
		(width 0.508)
		(layer "B.Cu")
		(net "P1V25_PEX1_VCC")
	)
	(segment
		(start 229.276148 -307.706268)
		(end 227.759006 -306.189126)
		(width 0.508)
		(layer "B.Cu")
		(net "P1V25_PEX1_VCC")
	)
	(segment
		(start 222.886524 -306.189126)
		(end 222.331534 -306.744116)
		(width 0.508)
		(layer "B.Cu")
		(net "P1V25_PEX1_VCC")
	)
	(segment
		(start 230.006906 -310.590946)
		(end 229.276148 -309.860188)
		(width 0.508)
		(layer "B.Cu")
		(net "P1V25_PEX1_VCC")
	)
	(segment
		(start 174.325026 -288.774886)
		(end 174.800006 -289.249866)
		(width 0.249936)
		(layer "F.Cu")
		(net "P1V25_PEX1")
	)
	(segment
		(start 172.900086 -302.549814)
		(end 172.424852 -303.024794)
		(width 0.249936)
		(layer "F.Cu")
		(net "P1V25_PEX1")
	)
	(segment
		(start 170.524932 -288.774886)
		(end 170.999912 -289.249866)
		(width 0.249936)
		(layer "F.Cu")
		(net "P1V25_PEX1")
	)
	(segment
		(start 172.900086 -289.249866)
		(end 172.424852 -288.774886)
		(width 0.249936)
		(layer "F.Cu")
		(net "P1V25_PEX1")
	)
	(segment
		(start 171.474892 -303.024794)
		(end 170.999912 -302.549814)
		(width 0.249936)
		(layer "F.Cu")
		(net "P1V25_PEX1")
	)
	(segment
		(start 179.55006 -289.249866)
		(end 180.02504 -288.774886)
		(width 0.249936)
		(layer "F.Cu")
		(net "P1V25_PEX1")
	)
	(segment
		(start 181.92496 -288.774886)
		(end 182.39994 -289.249866)
		(width 0.249936)
		(layer "F.Cu")
		(net "P1V25_PEX1")
	)
	(segment
		(start 173.850046 -289.249866)
		(end 174.325026 -288.774886)
		(width 0.249936)
		(layer "F.Cu")
		(net "P1V25_PEX1")
	)
	(segment
		(start 179.55006 -289.249866)
		(end 179.07508 -288.774886)
		(width 0.249936)
		(layer "F.Cu")
		(net "P1V25_PEX1")
	)
	(segment
		(start 173.850046 -302.549814)
		(end 174.325026 -303.024794)
		(width 0.249936)
		(layer "F.Cu")
		(net "P1V25_PEX1")
	)
	(segment
		(start 169.574972 -288.774886)
		(end 170.049952 -289.249866)
		(width 0.249936)
		(layer "F.Cu")
		(net "P1V25_PEX1")
	)
	(segment
		(start 169.099992 -302.549814)
		(end 168.625012 -303.024794)
		(width 0.249936)
		(layer "F.Cu")
		(net "P1V25_PEX1")
	)
	(segment
		(start 168.150032 -302.549814)
		(end 167.675052 -303.024794)
		(width 0.249936)
		(layer "F.Cu")
		(net "P1V25_PEX1")
	)
	(segment
		(start 176.699926 -302.549814)
		(end 177.174906 -303.024794)
		(width 0.249936)
		(layer "F.Cu")
		(net "P1V25_PEX1")
	)
	(segment
		(start 170.049952 -289.249866)
		(end 170.524932 -288.774886)
		(width 0.249936)
		(layer "F.Cu")
		(net "P1V25_PEX1")
	)
	(segment
		(start 179.07508 -288.774886)
		(end 178.599846 -289.249866)
		(width 0.249936)
		(layer "F.Cu")
		(net "P1V25_PEX1")
	)
	(segment
		(start 176.224946 -288.774886)
		(end 175.749966 -289.249866)
		(width 0.249936)
		(layer "F.Cu")
		(net "P1V25_PEX1")
	)
	(segment
		(start 170.049952 -302.549814)
		(end 169.574972 -303.024794)
		(width 0.249936)
		(layer "F.Cu")
		(net "P1V25_PEX1")
	)
	(segment
		(start 180.50002 -302.549814)
		(end 180.975 -303.024794)
		(width 0.249936)
		(layer "F.Cu")
		(net "P1V25_PEX1")
	)
	(segment
		(start 174.325026 -303.024794)
		(end 174.800006 -302.549814)
		(width 0.249936)
		(layer "F.Cu")
		(net "P1V25_PEX1")
	)
	(segment
		(start 169.099992 -289.249866)
		(end 168.625012 -288.774886)
		(width 0.249936)
		(layer "F.Cu")
		(net "P1V25_PEX1")
	)
	(segment
		(start 178.599846 -289.249866)
		(end 178.124866 -288.774886)
		(width 0.249936)
		(layer "F.Cu")
		(net "P1V25_PEX1")
	)
	(segment
		(start 176.224946 -303.024794)
		(end 176.699926 -302.549814)
		(width 0.249936)
		(layer "F.Cu")
		(net "P1V25_PEX1")
	)
	(segment
		(start 186.675014 -294.4749)
		(end 186.200034 -294.94988)
		(width 0.249936)
		(layer "F.Cu")
		(net "P1V25_PEX1")
	)
	(segment
		(start 186.200034 -297.79976)
		(end 186.675014 -297.32478)
		(width 0.249936)
		(layer "F.Cu")
		(net "P1V25_PEX1")
	)
	(segment
		(start 181.44998 -302.549814)
		(end 181.92496 -303.024794)
		(width 0.249936)
		(layer "F.Cu")
		(net "P1V25_PEX1")
	)
	(segment
		(start 171.949872 -289.249866)
		(end 171.474892 -288.774886)
		(width 0.249936)
		(layer "F.Cu")
		(net "P1V25_PEX1")
	)
	(segment
		(start 180.50002 -289.249866)
		(end 180.975 -288.774886)
		(width 0.249936)
		(layer "F.Cu")
		(net "P1V25_PEX1")
	)
	(segment
		(start 168.625012 -303.024794)
		(end 168.150032 -302.549814)
		(width 0.249936)
		(layer "F.Cu")
		(net "P1V25_PEX1")
	)
	(segment
		(start 182.39994 -302.549814)
		(end 182.87492 -303.024794)
		(width 0.249936)
		(layer "F.Cu")
		(net "P1V25_PEX1")
	)
	(segment
		(start 168.625012 -288.774886)
		(end 168.150032 -289.249866)
		(width 0.249936)
		(layer "F.Cu")
		(net "P1V25_PEX1")
	)
	(segment
		(start 176.699926 -289.249866)
		(end 176.224946 -288.774886)
		(width 0.249936)
		(layer "F.Cu")
		(net "P1V25_PEX1")
	)
	(segment
		(start 231.70388 -308.568852)
		(end 232.317798 -308.568852)
		(width 0.254)
		(layer "F.Cu")
		(net "P1V25_PEX1")
	)
	(segment
		(start 167.675052 -288.774886)
		(end 167.200072 -289.249866)
		(width 0.249936)
		(layer "F.Cu")
		(net "P1V25_PEX1")
	)
	(segment
		(start 175.749966 -302.549814)
		(end 176.224946 -303.024794)
		(width 0.249936)
		(layer "F.Cu")
		(net "P1V25_PEX1")
	)
	(segment
		(start 173.375066 -288.774886)
		(end 173.850046 -289.249866)
		(width 0.249936)
		(layer "F.Cu")
		(net "P1V25_PEX1")
	)
	(segment
		(start 182.39994 -289.249866)
		(end 182.87492 -288.774886)
		(width 0.249936)
		(layer "F.Cu")
		(net "P1V25_PEX1")
	)
	(segment
		(start 182.87492 -288.774886)
		(end 183.3499 -289.249866)
		(width 0.249936)
		(layer "F.Cu")
		(net "P1V25_PEX1")
	)
	(segment
		(start 172.900086 -302.549814)
		(end 173.375066 -303.024794)
		(width 0.249936)
		(layer "F.Cu")
		(net "P1V25_PEX1")
	)
	(segment
		(start 177.649886 -302.549814)
		(end 178.124866 -303.024794)
		(width 0.249936)
		(layer "F.Cu")
		(net "P1V25_PEX1")
	)
	(segment
		(start 180.975 -288.774886)
		(end 181.44998 -289.249866)
		(width 0.249936)
		(layer "F.Cu")
		(net "P1V25_PEX1")
	)
	(segment
		(start 186.675014 -296.37482)
		(end 186.200034 -296.8498)
		(width 0.249936)
		(layer "F.Cu")
		(net "P1V25_PEX1")
	)
	(segment
		(start 169.574972 -303.024794)
		(end 169.099992 -302.549814)
		(width 0.249936)
		(layer "F.Cu")
		(net "P1V25_PEX1")
	)
	(segment
		(start 178.124866 -288.774886)
		(end 177.649886 -289.249866)
		(width 0.249936)
		(layer "F.Cu")
		(net "P1V25_PEX1")
	)
	(segment
		(start 179.55006 -302.549814)
		(end 180.02504 -303.024794)
		(width 0.249936)
		(layer "F.Cu")
		(net "P1V25_PEX1")
	)
	(segment
		(start 186.675014 -293.52494)
		(end 186.200034 -293.99992)
		(width 0.249936)
		(layer "F.Cu")
		(net "P1V25_PEX1")
	)
	(segment
		(start 176.699926 -289.249866)
		(end 177.174906 -288.774886)
		(width 0.249936)
		(layer "F.Cu")
		(net "P1V25_PEX1")
	)
	(segment
		(start 181.44998 -289.249866)
		(end 181.92496 -288.774886)
		(width 0.249936)
		(layer "F.Cu")
		(net "P1V25_PEX1")
	)
	(segment
		(start 170.049952 -302.549814)
		(end 170.524932 -303.024794)
		(width 0.249936)
		(layer "F.Cu")
		(net "P1V25_PEX1")
	)
	(segment
		(start 180.02504 -288.774886)
		(end 180.50002 -289.249866)
		(width 0.249936)
		(layer "F.Cu")
		(net "P1V25_PEX1")
	)
	(segment
		(start 186.675014 -297.32478)
		(end 186.200034 -296.8498)
		(width 0.249936)
		(layer "F.Cu")
		(net "P1V25_PEX1")
	)
	(segment
		(start 170.524932 -303.024794)
		(end 170.999912 -302.549814)
		(width 0.249936)
		(layer "F.Cu")
		(net "P1V25_PEX1")
	)
	(segment
		(start 178.599846 -302.549814)
		(end 179.07508 -303.024794)
		(width 0.249936)
		(layer "F.Cu")
		(net "P1V25_PEX1")
	)
	(segment
		(start 167.675052 -303.024794)
		(end 167.200072 -302.549814)
		(width 0.249936)
		(layer "F.Cu")
		(net "P1V25_PEX1")
	)
	(segment
		(start 186.200034 -295.89984)
		(end 186.675014 -296.37482)
		(width 0.249936)
		(layer "F.Cu")
		(net "P1V25_PEX1")
	)
	(segment
		(start 167.200072 -289.249866)
		(end 166.725092 -288.774886)
		(width 0.249936)
		(layer "F.Cu")
		(net "P1V25_PEX1")
	)
	(segment
		(start 186.200034 -297.79976)
		(end 186.675014 -298.27474)
		(width 0.249936)
		(layer "F.Cu")
		(net "P1V25_PEX1")
	)
	(segment
		(start 173.375066 -303.024794)
		(end 173.850046 -302.549814)
		(width 0.249936)
		(layer "F.Cu")
		(net "P1V25_PEX1")
	)
	(segment
		(start 171.949872 -302.549814)
		(end 171.474892 -303.024794)
		(width 0.249936)
		(layer "F.Cu")
		(net "P1V25_PEX1")
	)
	(segment
		(start 167.200072 -302.549814)
		(end 166.725092 -303.024794)
		(width 0.249936)
		(layer "F.Cu")
		(net "P1V25_PEX1")
	)
	(segment
		(start 169.099992 -289.249866)
		(end 169.574972 -288.774886)
		(width 0.249936)
		(layer "F.Cu")
		(net "P1V25_PEX1")
	)
	(segment
		(start 171.474892 -288.774886)
		(end 170.999912 -289.249866)
		(width 0.249936)
		(layer "F.Cu")
		(net "P1V25_PEX1")
	)
	(segment
		(start 177.174906 -288.774886)
		(end 177.649886 -289.249866)
		(width 0.249936)
		(layer "F.Cu")
		(net "P1V25_PEX1")
	)
	(segment
		(start 168.150032 -289.249866)
		(end 167.675052 -288.774886)
		(width 0.249936)
		(layer "F.Cu")
		(net "P1V25_PEX1")
	)
	(segment
		(start 172.424852 -288.774886)
		(end 171.949872 -289.249866)
		(width 0.249936)
		(layer "F.Cu")
		(net "P1V25_PEX1")
	)
	(segment
		(start 183.3499 -302.549814)
		(end 183.82488 -303.024794)
		(width 0.249936)
		(layer "F.Cu")
		(net "P1V25_PEX1")
	)
	(segment
		(start 172.900086 -289.249866)
		(end 173.375066 -288.774886)
		(width 0.249936)
		(layer "F.Cu")
		(net "P1V25_PEX1")
	)
	(segment
		(start 172.424852 -303.024794)
		(end 171.949872 -302.549814)
		(width 0.249936)
		(layer "F.Cu")
		(net "P1V25_PEX1")
	)
	(segment
		(start 183.3499 -289.249866)
		(end 183.82488 -288.774886)
		(width 0.249936)
		(layer "F.Cu")
		(net "P1V25_PEX1")
	)
	(via
		(at 171.474892 -303.024794)
		(size 0.4064)
		(drill 0.2032)
		(layers "F.Cu" "B.Cu")
		(net "P1V25_PEX1")
	)
	(via
		(at 220.994478 -276.632416)
		(size 0.508)
		(drill 0.254)
		(layers "F.Cu" "B.Cu")
		(net "P1V25_PEX1")
	)
	(via
		(at 177.174906 -303.024794)
		(size 0.4064)
		(drill 0.2032)
		(layers "F.Cu" "B.Cu")
		(net "P1V25_PEX1")
	)
	(via
		(at 221.951296 -272.187416)
		(size 0.508)
		(drill 0.254)
		(layers "F.Cu" "B.Cu")
		(net "P1V25_PEX1")
	)
	(via
		(at 186.675014 -297.32478)
		(size 0.4064)
		(drill 0.2032)
		(layers "F.Cu" "B.Cu")
		(net "P1V25_PEX1")
	)
	(via
		(at 170.524932 -288.774886)
		(size 0.4064)
		(drill 0.2032)
		(layers "F.Cu" "B.Cu")
		(net "P1V25_PEX1")
	)
	(via
		(at 168.625012 -303.024794)
		(size 0.4064)
		(drill 0.2032)
		(layers "F.Cu" "B.Cu")
		(net "P1V25_PEX1")
	)
	(via
		(at 222.315278 -277.267416)
		(size 0.508)
		(drill 0.254)
		(layers "F.Cu" "B.Cu")
		(net "P1V25_PEX1")
	)
	(via
		(at 169.574972 -288.774886)
		(size 0.4064)
		(drill 0.2032)
		(layers "F.Cu" "B.Cu")
		(net "P1V25_PEX1")
	)
	(via
		(at 168.625012 -288.774886)
		(size 0.4064)
		(drill 0.2032)
		(layers "F.Cu" "B.Cu")
		(net "P1V25_PEX1")
	)
	(via
		(at 180.975 -303.024794)
		(size 0.4064)
		(drill 0.2032)
		(layers "F.Cu" "B.Cu")
		(net "P1V25_PEX1")
	)
	(via
		(at 179.07508 -288.774886)
		(size 0.4064)
		(drill 0.2032)
		(layers "F.Cu" "B.Cu")
		(net "P1V25_PEX1")
	)
	(via
		(at 167.675052 -303.024794)
		(size 0.4064)
		(drill 0.2032)
		(layers "F.Cu" "B.Cu")
		(net "P1V25_PEX1")
	)
	(via
		(at 220.994478 -277.267416)
		(size 0.508)
		(drill 0.254)
		(layers "F.Cu" "B.Cu")
		(net "P1V25_PEX1")
	)
	(via
		(at 222.611696 -272.187416)
		(size 0.508)
		(drill 0.254)
		(layers "F.Cu" "B.Cu")
		(net "P1V25_PEX1")
	)
	(via
		(at 171.474892 -288.774886)
		(size 0.4064)
		(drill 0.2032)
		(layers "F.Cu" "B.Cu")
		(net "P1V25_PEX1")
	)
	(via
		(at 172.424852 -303.024794)
		(size 0.4064)
		(drill 0.2032)
		(layers "F.Cu" "B.Cu")
		(net "P1V25_PEX1")
	)
	(via
		(at 186.675014 -294.4749)
		(size 0.4064)
		(drill 0.2032)
		(layers "F.Cu" "B.Cu")
		(net "P1V25_PEX1")
	)
	(via
		(at 224.886266 -272.187416)
		(size 0.508)
		(drill 0.254)
		(layers "F.Cu" "B.Cu")
		(net "P1V25_PEX1")
	)
	(via
		(at 178.124866 -288.774886)
		(size 0.4064)
		(drill 0.2032)
		(layers "F.Cu" "B.Cu")
		(net "P1V25_PEX1")
	)
	(via
		(at 193.324988 -294.4749)
		(size 0.4064)
		(drill 0.2032)
		(layers "F.Cu" "B.Cu")
		(net "P1V25_PEX1")
	)
	(via
		(at 220.334078 -277.267416)
		(size 0.508)
		(drill 0.254)
		(layers "F.Cu" "B.Cu")
		(net "P1V25_PEX1")
	)
	(via
		(at 225.546666 -272.187416)
		(size 0.508)
		(drill 0.254)
		(layers "F.Cu" "B.Cu")
		(net "P1V25_PEX1")
	)
	(via
		(at 224.886266 -272.822416)
		(size 0.508)
		(drill 0.254)
		(layers "F.Cu" "B.Cu")
		(net "P1V25_PEX1")
	)
	(via
		(at 220.955108 -274.085558)
		(size 0.6604)
		(drill 0.3302)
		(layers "F.Cu" "B.Cu")
		(net "P1V25_PEX1")
	)
	(via
		(at 166.725092 -288.774886)
		(size 0.4064)
		(drill 0.2032)
		(layers "F.Cu" "B.Cu")
		(net "P1V25_PEX1")
	)
	(via
		(at 176.224946 -303.024794)
		(size 0.4064)
		(drill 0.2032)
		(layers "F.Cu" "B.Cu")
		(net "P1V25_PEX1")
	)
	(via
		(at 183.82488 -288.774886)
		(size 0.4064)
		(drill 0.2032)
		(layers "F.Cu" "B.Cu")
		(net "P1V25_PEX1")
	)
	(via
		(at 181.92496 -303.024794)
		(size 0.4064)
		(drill 0.2032)
		(layers "F.Cu" "B.Cu")
		(net "P1V25_PEX1")
	)
	(via
		(at 225.546666 -272.822416)
		(size 0.508)
		(drill 0.254)
		(layers "F.Cu" "B.Cu")
		(net "P1V25_PEX1")
	)
	(via
		(at 174.325026 -303.024794)
		(size 0.4064)
		(drill 0.2032)
		(layers "F.Cu" "B.Cu")
		(net "P1V25_PEX1")
	)
	(via
		(at 170.524932 -303.024794)
		(size 0.4064)
		(drill 0.2032)
		(layers "F.Cu" "B.Cu")
		(net "P1V25_PEX1")
	)
	(via
		(at 220.334078 -276.632416)
		(size 0.508)
		(drill 0.254)
		(layers "F.Cu" "B.Cu")
		(net "P1V25_PEX1")
	)
	(via
		(at 183.82488 -303.024794)
		(size 0.4064)
		(drill 0.2032)
		(layers "F.Cu" "B.Cu")
		(net "P1V25_PEX1")
	)
	(via
		(at 224.225866 -272.822416)
		(size 0.508)
		(drill 0.254)
		(layers "F.Cu" "B.Cu")
		(net "P1V25_PEX1")
	)
	(via
		(at 220.630496 -272.822416)
		(size 0.508)
		(drill 0.254)
		(layers "F.Cu" "B.Cu")
		(net "P1V25_PEX1")
	)
	(via
		(at 220.630496 -272.187416)
		(size 0.508)
		(drill 0.254)
		(layers "F.Cu" "B.Cu")
		(net "P1V25_PEX1")
	)
	(via
		(at 176.224946 -288.774886)
		(size 0.4064)
		(drill 0.2032)
		(layers "F.Cu" "B.Cu")
		(net "P1V25_PEX1")
	)
	(via
		(at 181.92496 -288.774886)
		(size 0.4064)
		(drill 0.2032)
		(layers "F.Cu" "B.Cu")
		(net "P1V25_PEX1")
	)
	(via
		(at 222.4024 -278.4348)
		(size 0.6604)
		(drill 0.3302)
		(layers "F.Cu" "B.Cu")
		(net "P1V25_PEX1")
	)
	(via
		(at 178.124866 -303.024794)
		(size 0.4064)
		(drill 0.2032)
		(layers "F.Cu" "B.Cu")
		(net "P1V25_PEX1")
	)
	(via
		(at 182.87492 -288.774886)
		(size 0.4064)
		(drill 0.2032)
		(layers "F.Cu" "B.Cu")
		(net "P1V25_PEX1")
	)
	(via
		(at 186.675014 -296.37482)
		(size 0.4064)
		(drill 0.2032)
		(layers "F.Cu" "B.Cu")
		(net "P1V25_PEX1")
	)
	(via
		(at 221.654878 -276.632416)
		(size 0.508)
		(drill 0.254)
		(layers "F.Cu" "B.Cu")
		(net "P1V25_PEX1")
	)
	(via
		(at 166.725092 -303.024794)
		(size 0.4064)
		(drill 0.2032)
		(layers "F.Cu" "B.Cu")
		(net "P1V25_PEX1")
	)
	(via
		(at 180.02504 -288.774886)
		(size 0.4064)
		(drill 0.2032)
		(layers "F.Cu" "B.Cu")
		(net "P1V25_PEX1")
	)
	(via
		(at 221.951296 -272.822416)
		(size 0.508)
		(drill 0.254)
		(layers "F.Cu" "B.Cu")
		(net "P1V25_PEX1")
	)
	(via
		(at 177.174906 -288.774886)
		(size 0.4064)
		(drill 0.2032)
		(layers "F.Cu" "B.Cu")
		(net "P1V25_PEX1")
	)
	(via
		(at 179.07508 -303.024794)
		(size 0.4064)
		(drill 0.2032)
		(layers "F.Cu" "B.Cu")
		(net "P1V25_PEX1")
	)
	(via
		(at 186.675014 -298.27474)
		(size 0.4064)
		(drill 0.2032)
		(layers "F.Cu" "B.Cu")
		(net "P1V25_PEX1")
	)
	(via
		(at 226.207066 -272.187416)
		(size 0.508)
		(drill 0.254)
		(layers "F.Cu" "B.Cu")
		(net "P1V25_PEX1")
	)
	(via
		(at 226.207066 -272.822416)
		(size 0.508)
		(drill 0.254)
		(layers "F.Cu" "B.Cu")
		(net "P1V25_PEX1")
	)
	(via
		(at 173.375066 -288.774886)
		(size 0.4064)
		(drill 0.2032)
		(layers "F.Cu" "B.Cu")
		(net "P1V25_PEX1")
	)
	(via
		(at 182.87492 -303.024794)
		(size 0.4064)
		(drill 0.2032)
		(layers "F.Cu" "B.Cu")
		(net "P1V25_PEX1")
	)
	(via
		(at 221.290896 -272.187416)
		(size 0.508)
		(drill 0.254)
		(layers "F.Cu" "B.Cu")
		(net "P1V25_PEX1")
	)
	(via
		(at 221.290896 -272.822416)
		(size 0.508)
		(drill 0.254)
		(layers "F.Cu" "B.Cu")
		(net "P1V25_PEX1")
	)
	(via
		(at 169.574972 -303.024794)
		(size 0.4064)
		(drill 0.2032)
		(layers "F.Cu" "B.Cu")
		(net "P1V25_PEX1")
	)
	(via
		(at 180.02504 -303.024794)
		(size 0.4064)
		(drill 0.2032)
		(layers "F.Cu" "B.Cu")
		(net "P1V25_PEX1")
	)
	(via
		(at 194.274948 -296.37482)
		(size 0.4064)
		(drill 0.2032)
		(layers "F.Cu" "B.Cu")
		(net "P1V25_PEX1")
	)
	(via
		(at 223.54921 -275.505164)
		(size 0.508)
		(drill 0.254)
		(layers "F.Cu" "B.Cu")
		(net "P1V25_PEX1")
	)
	(via
		(at 172.424852 -288.774886)
		(size 0.4064)
		(drill 0.2032)
		(layers "F.Cu" "B.Cu")
		(net "P1V25_PEX1")
	)
	(via
		(at 222.611696 -272.822416)
		(size 0.508)
		(drill 0.254)
		(layers "F.Cu" "B.Cu")
		(net "P1V25_PEX1")
	)
	(via
		(at 186.675014 -293.52494)
		(size 0.4064)
		(drill 0.2032)
		(layers "F.Cu" "B.Cu")
		(net "P1V25_PEX1")
	)
	(via
		(at 224.18421 -275.505164)
		(size 0.508)
		(drill 0.254)
		(layers "F.Cu" "B.Cu")
		(net "P1V25_PEX1")
	)
	(via
		(at 232.317798 -308.568852)
		(size 0.508)
		(drill 0.254)
		(layers "F.Cu" "B.Cu")
		(net "P1V25_PEX1")
	)
	(via
		(at 193.324988 -296.37482)
		(size 0.4064)
		(drill 0.2032)
		(layers "F.Cu" "B.Cu")
		(net "P1V25_PEX1")
	)
	(via
		(at 174.325026 -288.774886)
		(size 0.4064)
		(drill 0.2032)
		(layers "F.Cu" "B.Cu")
		(net "P1V25_PEX1")
	)
	(via
		(at 224.225866 -272.187416)
		(size 0.508)
		(drill 0.254)
		(layers "F.Cu" "B.Cu")
		(net "P1V25_PEX1")
	)
	(via
		(at 222.315278 -276.632416)
		(size 0.508)
		(drill 0.254)
		(layers "F.Cu" "B.Cu")
		(net "P1V25_PEX1")
	)
	(via
		(at 167.675052 -288.774886)
		(size 0.4064)
		(drill 0.2032)
		(layers "F.Cu" "B.Cu")
		(net "P1V25_PEX1")
	)
	(via
		(at 180.975 -288.774886)
		(size 0.4064)
		(drill 0.2032)
		(layers "F.Cu" "B.Cu")
		(net "P1V25_PEX1")
	)
	(via
		(at 221.654878 -277.267416)
		(size 0.508)
		(drill 0.254)
		(layers "F.Cu" "B.Cu")
		(net "P1V25_PEX1")
	)
	(via
		(at 173.375066 -303.024794)
		(size 0.4064)
		(drill 0.2032)
		(layers "F.Cu" "B.Cu")
		(net "P1V25_PEX1")
	)
	(segment
		(start 214.196676 -285.938722)
		(end 210.391756 -289.743642)
		(width 0.254)
		(layer "In15.Cu")
		(net "P1V25_PEX1")
	)
	(segment
		(start 199.4281 -295.273476)
		(end 187.31992 -295.273476)
		(width 0.254)
		(layer "In15.Cu")
		(net "P1V25_PEX1")
	)
	(segment
		(start 224.348802 -285.938722)
		(end 214.196676 -285.938722)
		(width 0.254)
		(layer "In15.Cu")
		(net "P1V25_PEX1")
	)
	(segment
		(start 209.504026 -289.743642)
		(end 206.26197 -292.985698)
		(width 0.254)
		(layer "In15.Cu")
		(net "P1V25_PEX1")
	)
	(segment
		(start 210.391756 -289.743642)
		(end 209.504026 -289.743642)
		(width 0.254)
		(layer "In15.Cu")
		(net "P1V25_PEX1")
	)
	(segment
		(start 233.547158 -290.170108)
		(end 229.748842 -286.371792)
		(width 0.254)
		(layer "In15.Cu")
		(net "P1V25_PEX1")
	)
	(segment
		(start 224.781872 -286.371792)
		(end 224.348802 -285.938722)
		(width 0.254)
		(layer "In15.Cu")
		(net "P1V25_PEX1")
	)
	(segment
		(start 232.681018 -308.205632)
		(end 233.025442 -308.205632)
		(width 0.254)
		(layer "In15.Cu")
		(net "P1V25_PEX1")
	)
	(segment
		(start 186.904884 -295.688512)
		(end 186.904884 -296.14495)
		(width 0.254)
		(layer "In15.Cu")
		(net "P1V25_PEX1")
	)
	(segment
		(start 229.748842 -286.371792)
		(end 224.781872 -286.371792)
		(width 0.254)
		(layer "In15.Cu")
		(net "P1V25_PEX1")
	)
	(segment
		(start 204.96276 -292.985698)
		(end 204.525372 -293.423086)
		(width 0.254)
		(layer "In15.Cu")
		(net "P1V25_PEX1")
	)
	(segment
		(start 187.31992 -295.273476)
		(end 186.904884 -295.688512)
		(width 0.254)
		(layer "In15.Cu")
		(net "P1V25_PEX1")
	)
	(segment
		(start 204.525372 -293.423086)
		(end 201.27849 -293.423086)
		(width 0.254)
		(layer "In15.Cu")
		(net "P1V25_PEX1")
	)
	(segment
		(start 232.317798 -308.568852)
		(end 232.681018 -308.205632)
		(width 0.254)
		(layer "In15.Cu")
		(net "P1V25_PEX1")
	)
	(segment
		(start 186.904884 -296.14495)
		(end 186.675014 -296.37482)
		(width 0.254)
		(layer "In15.Cu")
		(net "P1V25_PEX1")
	)
	(segment
		(start 206.26197 -292.985698)
		(end 204.96276 -292.985698)
		(width 0.254)
		(layer "In15.Cu")
		(net "P1V25_PEX1")
	)
	(segment
		(start 201.27849 -293.423086)
		(end 199.4281 -295.273476)
		(width 0.254)
		(layer "In15.Cu")
		(net "P1V25_PEX1")
	)
	(segment
		(start 233.025442 -308.205632)
		(end 233.547158 -307.683916)
		(width 0.254)
		(layer "In15.Cu")
		(net "P1V25_PEX1")
	)
	(segment
		(start 233.547158 -307.683916)
		(end 233.547158 -290.170108)
		(width 0.254)
		(layer "In15.Cu")
		(net "P1V25_PEX1")
	)
	(segment
		(start 174.325026 -292.57498)
		(end 174.800006 -293.04996)
		(width 0.249936)
		(layer "F.Cu")
		(net "P0V8_SERDES_VDDA_PEX1")
	)
	(segment
		(start 177.174906 -290.674806)
		(end 176.699926 -291.149786)
		(width 0.249936)
		(layer "F.Cu")
		(net "P0V8_SERDES_VDDA_PEX1")
	)
	(segment
		(start 178.599846 -300.649894)
		(end 178.124866 -301.124874)
		(width 0.249936)
		(layer "F.Cu")
		(net "P0V8_SERDES_VDDA_PEX1")
	)
	(segment
		(start 169.574972 -299.224954)
		(end 170.049952 -298.74972)
		(width 0.249936)
		(layer "F.Cu")
		(net "P0V8_SERDES_VDDA_PEX1")
	)
	(segment
		(start 177.649886 -293.04996)
		(end 177.498756 -292.89883)
		(width 0.249936)
		(layer "F.Cu")
		(net "P0V8_SERDES_VDDA_PEX1")
	)
	(segment
		(start 170.524932 -299.224954)
		(end 170.999912 -298.74972)
		(width 0.249936)
		(layer "F.Cu")
		(net "P0V8_SERDES_VDDA_PEX1")
	)
	(segment
		(start 180.975 -290.674806)
		(end 180.50002 -291.149786)
		(width 0.249936)
		(layer "F.Cu")
		(net "P0V8_SERDES_VDDA_PEX1")
	)
	(segment
		(start 170.049952 -291.149786)
		(end 170.524932 -290.674806)
		(width 0.249936)
		(layer "F.Cu")
		(net "P0V8_SERDES_VDDA_PEX1")
	)
	(segment
		(start 170.049952 -298.74972)
		(end 170.524932 -299.224954)
		(width 0.249936)
		(layer "F.Cu")
		(net "P0V8_SERDES_VDDA_PEX1")
	)
	(segment
		(start 167.675052 -301.124874)
		(end 168.150032 -300.649894)
		(width 0.249936)
		(layer "F.Cu")
		(net "P0V8_SERDES_VDDA_PEX1")
	)
	(segment
		(start 176.224946 -290.674806)
		(end 176.699926 -291.149786)
		(width 0.249936)
		(layer "F.Cu")
		(net "P0V8_SERDES_VDDA_PEX1")
	)
	(segment
		(start 177.649886 -300.649894)
		(end 177.174906 -301.124874)
		(width 0.249936)
		(layer "F.Cu")
		(net "P0V8_SERDES_VDDA_PEX1")
	)
	(segment
		(start 173.375066 -290.674806)
		(end 172.900086 -291.149786)
		(width 0.249936)
		(layer "F.Cu")
		(net "P0V8_SERDES_VDDA_PEX1")
	)
	(segment
		(start 167.675052 -290.674806)
		(end 167.200072 -291.149786)
		(width 0.249936)
		(layer "F.Cu")
		(net "P0V8_SERDES_VDDA_PEX1")
	)
	(segment
		(start 167.200072 -298.74972)
		(end 166.725092 -299.224954)
		(width 0.249936)
		(layer "F.Cu")
		(net "P0V8_SERDES_VDDA_PEX1")
	)
	(segment
		(start 167.200072 -291.149786)
		(end 166.725092 -290.674806)
		(width 0.249936)
		(layer "F.Cu")
		(net "P0V8_SERDES_VDDA_PEX1")
	)
	(segment
		(start 184.29986 -296.8498)
		(end 184.77484 -297.32478)
		(width 0.249936)
		(layer "F.Cu")
		(net "P0V8_SERDES_VDDA_PEX1")
	)
	(segment
		(start 171.949872 -291.149786)
		(end 172.424852 -290.674806)
		(width 0.249936)
		(layer "F.Cu")
		(net "P0V8_SERDES_VDDA_PEX1")
	)
	(segment
		(start 184.29986 -294.94988)
		(end 184.77484 -294.4749)
		(width 0.249936)
		(layer "F.Cu")
		(net "P0V8_SERDES_VDDA_PEX1")
	)
	(segment
		(start 182.39994 -298.74972)
		(end 182.87492 -299.224954)
		(width 0.249936)
		(layer "F.Cu")
		(net "P0V8_SERDES_VDDA_PEX1")
	)
	(segment
		(start 178.599846 -298.74972)
		(end 178.124866 -299.224954)
		(width 0.249936)
		(layer "F.Cu")
		(net "P0V8_SERDES_VDDA_PEX1")
	)
	(segment
		(start 182.87492 -292.574726)
		(end 183.3499 -293.04996)
		(width 0.249936)
		(layer "F.Cu")
		(net "P0V8_SERDES_VDDA_PEX1")
	)
	(segment
		(start 168.625012 -299.224954)
		(end 168.150032 -298.74972)
		(width 0.249936)
		(layer "F.Cu")
		(net "P0V8_SERDES_VDDA_PEX1")
	)
	(segment
		(start 173.375066 -301.124874)
		(end 172.900086 -300.649894)
		(width 0.249936)
		(layer "F.Cu")
		(net "P0V8_SERDES_VDDA_PEX1")
	)
	(segment
		(start 173.850046 -300.649894)
		(end 174.325026 -301.124874)
		(width 0.249936)
		(layer "F.Cu")
		(net "P0V8_SERDES_VDDA_PEX1")
	)
	(segment
		(start 184.29986 -295.89984)
		(end 184.77484 -296.37482)
		(width 0.249936)
		(layer "F.Cu")
		(net "P0V8_SERDES_VDDA_PEX1")
	)
	(segment
		(start 179.55006 -300.649894)
		(end 180.02504 -301.124874)
		(width 0.249936)
		(layer "F.Cu")
		(net "P0V8_SERDES_VDDA_PEX1")
	)
	(segment
		(start 179.55006 -291.149786)
		(end 180.02504 -290.674806)
		(width 0.249936)
		(layer "F.Cu")
		(net "P0V8_SERDES_VDDA_PEX1")
	)
	(segment
		(start 173.850046 -298.74972)
		(end 173.375066 -299.224954)
		(width 0.249936)
		(layer "F.Cu")
		(net "P0V8_SERDES_VDDA_PEX1")
	)
	(segment
		(start 169.099992 -291.149786)
		(end 169.574972 -290.674806)
		(width 0.249936)
		(layer "F.Cu")
		(net "P0V8_SERDES_VDDA_PEX1")
	)
	(segment
		(start 170.524932 -292.57498)
		(end 170.999912 -293.04996)
		(width 0.249936)
		(layer "F.Cu")
		(net "P0V8_SERDES_VDDA_PEX1")
	)
	(segment
		(start 171.474892 -301.124874)
		(end 170.999912 -300.649894)
		(width 0.249936)
		(layer "F.Cu")
		(net "P0V8_SERDES_VDDA_PEX1")
	)
	(segment
		(start 173.850046 -298.74972)
		(end 174.325026 -299.224954)
		(width 0.249936)
		(layer "F.Cu")
		(net "P0V8_SERDES_VDDA_PEX1")
	)
	(segment
		(start 176.699926 -298.74972)
		(end 177.174906 -299.224954)
		(width 0.249936)
		(layer "F.Cu")
		(net "P0V8_SERDES_VDDA_PEX1")
	)
	(segment
		(start 178.124866 -292.574726)
		(end 177.649886 -293.04996)
		(width 0.249936)
		(layer "F.Cu")
		(net "P0V8_SERDES_VDDA_PEX1")
	)
	(segment
		(start 182.39994 -296.8498)
		(end 182.87492 -297.32478)
		(width 0.249936)
		(layer "F.Cu")
		(net "P0V8_SERDES_VDDA_PEX1")
	)
	(segment
		(start 181.44998 -291.149786)
		(end 180.975 -290.674806)
		(width 0.249936)
		(layer "F.Cu")
		(net "P0V8_SERDES_VDDA_PEX1")
	)
	(segment
		(start 181.92496 -290.674806)
		(end 182.39994 -291.149786)
		(width 0.249936)
		(layer "F.Cu")
		(net "P0V8_SERDES_VDDA_PEX1")
	)
	(segment
		(start 173.375066 -299.224954)
		(end 172.900086 -298.74972)
		(width 0.249936)
		(layer "F.Cu")
		(net "P0V8_SERDES_VDDA_PEX1")
	)
	(segment
		(start 182.87492 -294.4749)
		(end 183.3499 -294.94988)
		(width 0.249936)
		(layer "F.Cu")
		(net "P0V8_SERDES_VDDA_PEX1")
	)
	(segment
		(start 180.975 -299.224954)
		(end 181.44998 -298.74972)
		(width 0.249936)
		(layer "F.Cu")
		(net "P0V8_SERDES_VDDA_PEX1")
	)
	(segment
		(start 176.224946 -301.124874)
		(end 176.699926 -300.649894)
		(width 0.249936)
		(layer "F.Cu")
		(net "P0V8_SERDES_VDDA_PEX1")
	)
	(segment
		(start 177.498756 -298.90085)
		(end 177.649886 -298.74972)
		(width 0.249936)
		(layer "F.Cu")
		(net "P0V8_SERDES_VDDA_PEX1")
	)
	(segment
		(start 180.50002 -298.74972)
		(end 180.02504 -299.224954)
		(width 0.249936)
		(layer "F.Cu")
		(net "P0V8_SERDES_VDDA_PEX1")
	)
	(segment
		(start 167.675052 -299.224954)
		(end 167.200072 -298.74972)
		(width 0.249936)
		(layer "F.Cu")
		(net "P0V8_SERDES_VDDA_PEX1")
	)
	(segment
		(start 177.174906 -301.124874)
		(end 176.699926 -300.649894)
		(width 0.249936)
		(layer "F.Cu")
		(net "P0V8_SERDES_VDDA_PEX1")
	)
	(segment
		(start 171.474892 -290.674806)
		(end 171.949872 -291.149786)
		(width 0.249936)
		(layer "F.Cu")
		(net "P0V8_SERDES_VDDA_PEX1")
	)
	(segment
		(start 176.224946 -299.224954)
		(end 176.699926 -298.74972)
		(width 0.249936)
		(layer "F.Cu")
		(net "P0V8_SERDES_VDDA_PEX1")
	)
	(segment
		(start 182.39994 -300.649894)
		(end 181.92496 -301.124874)
		(width 0.249936)
		(layer "F.Cu")
		(net "P0V8_SERDES_VDDA_PEX1")
	)
	(segment
		(start 181.92496 -299.224954)
		(end 181.44998 -298.74972)
		(width 0.249936)
		(layer "F.Cu")
		(net "P0V8_SERDES_VDDA_PEX1")
	)
	(segment
		(start 171.949872 -298.74972)
		(end 171.474892 -299.224954)
		(width 0.249936)
		(layer "F.Cu")
		(net "P0V8_SERDES_VDDA_PEX1")
	)
	(segment
		(start 170.999912 -291.149786)
		(end 171.474892 -290.674806)
		(width 0.249936)
		(layer "F.Cu")
		(net "P0V8_SERDES_VDDA_PEX1")
	)
	(segment
		(start 179.07508 -299.224954)
		(end 179.55006 -298.74972)
		(width 0.249936)
		(layer "F.Cu")
		(net "P0V8_SERDES_VDDA_PEX1")
	)
	(segment
		(start 171.949872 -298.74972)
		(end 172.424852 -299.224954)
		(width 0.249936)
		(layer "F.Cu")
		(net "P0V8_SERDES_VDDA_PEX1")
	)
	(segment
		(start 179.07508 -301.124874)
		(end 178.599846 -300.649894)
		(width 0.249936)
		(layer "F.Cu")
		(net "P0V8_SERDES_VDDA_PEX1")
	)
	(segment
		(start 170.049952 -300.649894)
		(end 170.524932 -301.124874)
		(width 0.249936)
		(layer "F.Cu")
		(net "P0V8_SERDES_VDDA_PEX1")
	)
	(segment
		(start 182.39994 -294.94988)
		(end 182.87492 -294.4749)
		(width 0.249936)
		(layer "F.Cu")
		(net "P0V8_SERDES_VDDA_PEX1")
	)
	(segment
		(start 175.749966 -293.04996)
		(end 176.224946 -292.574726)
		(width 0.249936)
		(layer "F.Cu")
		(net "P0V8_SERDES_VDDA_PEX1")
	)
	(segment
		(start 183.3499 -298.74972)
		(end 183.82488 -299.224954)
		(width 0.249936)
		(layer "F.Cu")
		(net "P0V8_SERDES_VDDA_PEX1")
	)
	(segment
		(start 175.749966 -291.149786)
		(end 176.224946 -290.674806)
		(width 0.249936)
		(layer "F.Cu")
		(net "P0V8_SERDES_VDDA_PEX1")
	)
	(segment
		(start 183.82488 -297.32478)
		(end 183.3499 -296.8498)
		(width 0.249936)
		(layer "F.Cu")
		(net "P0V8_SERDES_VDDA_PEX1")
	)
	(segment
		(start 170.524932 -290.674806)
		(end 170.999912 -291.149786)
		(width 0.249936)
		(layer "F.Cu")
		(net "P0V8_SERDES_VDDA_PEX1")
	)
	(segment
		(start 171.949872 -300.649894)
		(end 172.424852 -301.124874)
		(width 0.249936)
		(layer "F.Cu")
		(net "P0V8_SERDES_VDDA_PEX1")
	)
	(segment
		(start 180.50002 -298.74972)
		(end 180.975 -299.224954)
		(width 0.249936)
		(layer "F.Cu")
		(net "P0V8_SERDES_VDDA_PEX1")
	)
	(segment
		(start 173.850046 -300.649894)
		(end 173.375066 -301.124874)
		(width 0.249936)
		(layer "F.Cu")
		(net "P0V8_SERDES_VDDA_PEX1")
	)
	(segment
		(start 169.099992 -298.74972)
		(end 169.574972 -299.224954)
		(width 0.249936)
		(layer "F.Cu")
		(net "P0V8_SERDES_VDDA_PEX1")
	)
	(segment
		(start 179.55006 -300.649894)
		(end 179.07508 -301.124874)
		(width 0.249936)
		(layer "F.Cu")
		(net "P0V8_SERDES_VDDA_PEX1")
	)
	(segment
		(start 169.099992 -298.74972)
		(end 168.625012 -299.224954)
		(width 0.249936)
		(layer "F.Cu")
		(net "P0V8_SERDES_VDDA_PEX1")
	)
	(segment
		(start 183.3499 -291.149786)
		(end 183.82488 -290.674806)
		(width 0.249936)
		(layer "F.Cu")
		(net "P0V8_SERDES_VDDA_PEX1")
	)
	(segment
		(start 182.39994 -300.649894)
		(end 182.87492 -301.124874)
		(width 0.249936)
		(layer "F.Cu")
		(net "P0V8_SERDES_VDDA_PEX1")
	)
	(segment
		(start 178.124866 -299.224954)
		(end 177.649886 -298.74972)
		(width 0.249936)
		(layer "F.Cu")
		(net "P0V8_SERDES_VDDA_PEX1")
	)
	(segment
		(start 181.44998 -293.04996)
		(end 180.975 -292.574726)
		(width 0.249936)
		(layer "F.Cu")
		(net "P0V8_SERDES_VDDA_PEX1")
	)
	(segment
		(start 178.599846 -298.74972)
		(end 179.07508 -299.224954)
		(width 0.249936)
		(layer "F.Cu")
		(net "P0V8_SERDES_VDDA_PEX1")
	)
	(segment
		(start 183.3499 -300.649894)
		(end 183.82488 -301.124874)
		(width 0.249936)
		(layer "F.Cu")
		(net "P0V8_SERDES_VDDA_PEX1")
	)
	(segment
		(start 179.55006 -293.04996)
		(end 180.02504 -292.574726)
		(width 0.249936)
		(layer "F.Cu")
		(net "P0V8_SERDES_VDDA_PEX1")
	)
	(segment
		(start 184.29986 -296.8498)
		(end 183.82488 -297.32478)
		(width 0.249936)
		(layer "F.Cu")
		(net "P0V8_SERDES_VDDA_PEX1")
	)
	(segment
		(start 180.975 -292.574726)
		(end 180.50002 -293.04996)
		(width 0.249936)
		(layer "F.Cu")
		(net "P0V8_SERDES_VDDA_PEX1")
	)
	(segment
		(start 182.39994 -298.74972)
		(end 181.92496 -299.224954)
		(width 0.249936)
		(layer "F.Cu")
		(net "P0V8_SERDES_VDDA_PEX1")
	)
	(segment
		(start 169.574972 -301.124874)
		(end 170.049952 -300.649894)
		(width 0.249936)
		(layer "F.Cu")
		(net "P0V8_SERDES_VDDA_PEX1")
	)
	(segment
		(start 183.3499 -295.89984)
		(end 183.82488 -296.37482)
		(width 0.249936)
		(layer "F.Cu")
		(net "P0V8_SERDES_VDDA_PEX1")
	)
	(segment
		(start 181.92496 -301.124874)
		(end 181.44998 -300.649894)
		(width 0.249936)
		(layer "F.Cu")
		(net "P0V8_SERDES_VDDA_PEX1")
	)
	(segment
		(start 174.325026 -299.224954)
		(end 174.800006 -298.74972)
		(width 0.249936)
		(layer "F.Cu")
		(net "P0V8_SERDES_VDDA_PEX1")
	)
	(segment
		(start 169.099992 -291.149786)
		(end 168.625012 -290.674806)
		(width 0.249936)
		(layer "F.Cu")
		(net "P0V8_SERDES_VDDA_PEX1")
	)
	(segment
		(start 178.124866 -301.124874)
		(end 177.649886 -300.649894)
		(width 0.249936)
		(layer "F.Cu")
		(net "P0V8_SERDES_VDDA_PEX1")
	)
	(segment
		(start 173.375066 -292.57498)
		(end 173.850046 -293.04996)
		(width 0.249936)
		(layer "F.Cu")
		(net "P0V8_SERDES_VDDA_PEX1")
	)
	(segment
		(start 175.749966 -298.74972)
		(end 176.224946 -299.224954)
		(width 0.249936)
		(layer "F.Cu")
		(net "P0V8_SERDES_VDDA_PEX1")
	)
	(segment
		(start 172.424852 -299.224954)
		(end 172.900086 -298.74972)
		(width 0.249936)
		(layer "F.Cu")
		(net "P0V8_SERDES_VDDA_PEX1")
	)
	(segment
		(start 182.39994 -293.04996)
		(end 182.87492 -292.574726)
		(width 0.249936)
		(layer "F.Cu")
		(net "P0V8_SERDES_VDDA_PEX1")
	)
	(segment
		(start 179.55006 -291.149786)
		(end 179.07508 -290.674806)
		(width 0.249936)
		(layer "F.Cu")
		(net "P0V8_SERDES_VDDA_PEX1")
	)
	(segment
		(start 179.55006 -293.04996)
		(end 179.07508 -292.574726)
		(width 0.249936)
		(layer "F.Cu")
		(net "P0V8_SERDES_VDDA_PEX1")
	)
	(segment
		(start 172.424852 -290.674806)
		(end 172.900086 -291.149786)
		(width 0.249936)
		(layer "F.Cu")
		(net "P0V8_SERDES_VDDA_PEX1")
	)
	(segment
		(start 177.174906 -299.224954)
		(end 177.498756 -298.90085)
		(width 0.249936)
		(layer "F.Cu")
		(net "P0V8_SERDES_VDDA_PEX1")
	)
	(segment
		(start 168.625012 -301.124874)
		(end 168.150032 -300.649894)
		(width 0.249936)
		(layer "F.Cu")
		(net "P0V8_SERDES_VDDA_PEX1")
	)
	(segment
		(start 174.325026 -301.124874)
		(end 174.800006 -300.649894)
		(width 0.249936)
		(layer "F.Cu")
		(net "P0V8_SERDES_VDDA_PEX1")
	)
	(segment
		(start 168.150032 -291.149786)
		(end 167.675052 -290.674806)
		(width 0.249936)
		(layer "F.Cu")
		(net "P0V8_SERDES_VDDA_PEX1")
	)
	(segment
		(start 183.82488 -294.4749)
		(end 183.3499 -294.94988)
		(width 0.249936)
		(layer "F.Cu")
		(net "P0V8_SERDES_VDDA_PEX1")
	)
	(segment
		(start 171.949872 -300.649894)
		(end 171.474892 -301.124874)
		(width 0.249936)
		(layer "F.Cu")
		(net "P0V8_SERDES_VDDA_PEX1")
	)
	(segment
		(start 179.07508 -292.574726)
		(end 178.599846 -293.04996)
		(width 0.249936)
		(layer "F.Cu")
		(net "P0V8_SERDES_VDDA_PEX1")
	)
	(segment
		(start 181.44998 -291.149786)
		(end 181.92496 -290.674806)
		(width 0.249936)
		(layer "F.Cu")
		(net "P0V8_SERDES_VDDA_PEX1")
	)
	(segment
		(start 180.02504 -290.674806)
		(end 180.50002 -291.149786)
		(width 0.249936)
		(layer "F.Cu")
		(net "P0V8_SERDES_VDDA_PEX1")
	)
	(segment
		(start 169.099992 -300.649894)
		(end 169.574972 -301.124874)
		(width 0.249936)
		(layer "F.Cu")
		(net "P0V8_SERDES_VDDA_PEX1")
	)
	(segment
		(start 174.325026 -290.674806)
		(end 174.800006 -291.149786)
		(width 0.249936)
		(layer "F.Cu")
		(net "P0V8_SERDES_VDDA_PEX1")
	)
	(segment
		(start 167.200072 -300.649894)
		(end 167.675052 -301.124874)
		(width 0.249936)
		(layer "F.Cu")
		(net "P0V8_SERDES_VDDA_PEX1")
	)
	(segment
		(start 177.174906 -292.574726)
		(end 176.699926 -293.04996)
		(width 0.249936)
		(layer "F.Cu")
		(net "P0V8_SERDES_VDDA_PEX1")
	)
	(segment
		(start 169.099992 -300.649894)
		(end 168.625012 -301.124874)
		(width 0.249936)
		(layer "F.Cu")
		(net "P0V8_SERDES_VDDA_PEX1")
	)
	(segment
		(start 177.498756 -292.89883)
		(end 177.174906 -292.574726)
		(width 0.249936)
		(layer "F.Cu")
		(net "P0V8_SERDES_VDDA_PEX1")
	)
	(segment
		(start 171.474892 -292.57498)
		(end 171.949872 -293.04996)
		(width 0.249936)
		(layer "F.Cu")
		(net "P0V8_SERDES_VDDA_PEX1")
	)
	(segment
		(start 183.82488 -296.37482)
		(end 184.29986 -295.89984)
		(width 0.249936)
		(layer "F.Cu")
		(net "P0V8_SERDES_VDDA_PEX1")
	)
	(segment
		(start 173.850046 -291.149786)
		(end 173.375066 -290.674806)
		(width 0.249936)
		(layer "F.Cu")
		(net "P0V8_SERDES_VDDA_PEX1")
	)
	(segment
		(start 180.02504 -292.574726)
		(end 180.50002 -293.04996)
		(width 0.249936)
		(layer "F.Cu")
		(net "P0V8_SERDES_VDDA_PEX1")
	)
	(segment
		(start 168.625012 -292.57498)
		(end 169.099992 -293.04996)
		(width 0.249936)
		(layer "F.Cu")
		(net "P0V8_SERDES_VDDA_PEX1")
	)
	(segment
		(start 168.625012 -290.674806)
		(end 168.150032 -291.149786)
		(width 0.249936)
		(layer "F.Cu")
		(net "P0V8_SERDES_VDDA_PEX1")
	)
	(segment
		(start 181.92496 -292.574726)
		(end 182.39994 -293.04996)
		(width 0.249936)
		(layer "F.Cu")
		(net "P0V8_SERDES_VDDA_PEX1")
	)
	(segment
		(start 172.425106 -292.57498)
		(end 172.900086 -293.04996)
		(width 0.249936)
		(layer "F.Cu")
		(net "P0V8_SERDES_VDDA_PEX1")
	)
	(segment
		(start 180.02504 -301.124874)
		(end 180.50002 -300.649894)
		(width 0.249936)
		(layer "F.Cu")
		(net "P0V8_SERDES_VDDA_PEX1")
	)
	(segment
		(start 178.124866 -290.674806)
		(end 177.649886 -291.149786)
		(width 0.249936)
		(layer "F.Cu")
		(net "P0V8_SERDES_VDDA_PEX1")
	)
	(segment
		(start 175.749966 -300.649894)
		(end 176.224946 -301.124874)
		(width 0.249936)
		(layer "F.Cu")
		(net "P0V8_SERDES_VDDA_PEX1")
	)
	(segment
		(start 178.599846 -293.04996)
		(end 178.124866 -292.574726)
		(width 0.249936)
		(layer "F.Cu")
		(net "P0V8_SERDES_VDDA_PEX1")
	)
	(segment
		(start 173.850046 -291.149786)
		(end 174.325026 -290.674806)
		(width 0.249936)
		(layer "F.Cu")
		(net "P0V8_SERDES_VDDA_PEX1")
	)
	(segment
		(start 178.599846 -291.149786)
		(end 178.124866 -290.674806)
		(width 0.249936)
		(layer "F.Cu")
		(net "P0V8_SERDES_VDDA_PEX1")
	)
	(segment
		(start 172.424852 -301.124874)
		(end 172.900086 -300.649894)
		(width 0.249936)
		(layer "F.Cu")
		(net "P0V8_SERDES_VDDA_PEX1")
	)
	(segment
		(start 167.200072 -300.649894)
		(end 166.725092 -301.124874)
		(width 0.249936)
		(layer "F.Cu")
		(net "P0V8_SERDES_VDDA_PEX1")
	)
	(segment
		(start 182.39994 -291.149786)
		(end 182.87492 -290.674806)
		(width 0.249936)
		(layer "F.Cu")
		(net "P0V8_SERDES_VDDA_PEX1")
	)
	(segment
		(start 171.474892 -299.224954)
		(end 170.999912 -298.74972)
		(width 0.249936)
		(layer "F.Cu")
		(net "P0V8_SERDES_VDDA_PEX1")
	)
	(segment
		(start 179.07508 -290.674806)
		(end 178.599846 -291.149786)
		(width 0.249936)
		(layer "F.Cu")
		(net "P0V8_SERDES_VDDA_PEX1")
	)
	(segment
		(start 167.675052 -292.57498)
		(end 168.150032 -293.04996)
		(width 0.249936)
		(layer "F.Cu")
		(net "P0V8_SERDES_VDDA_PEX1")
	)
	(segment
		(start 184.29986 -294.94988)
		(end 183.82488 -294.4749)
		(width 0.249936)
		(layer "F.Cu")
		(net "P0V8_SERDES_VDDA_PEX1")
	)
	(segment
		(start 180.50002 -300.649894)
		(end 180.975 -301.124874)
		(width 0.249936)
		(layer "F.Cu")
		(net "P0V8_SERDES_VDDA_PEX1")
	)
	(segment
		(start 182.87492 -297.32478)
		(end 183.3499 -296.8498)
		(width 0.249936)
		(layer "F.Cu")
		(net "P0V8_SERDES_VDDA_PEX1")
	)
	(segment
		(start 166.725092 -292.57498)
		(end 167.200072 -293.04996)
		(width 0.249936)
		(layer "F.Cu")
		(net "P0V8_SERDES_VDDA_PEX1")
	)
	(segment
		(start 169.574972 -290.674806)
		(end 170.049952 -291.149786)
		(width 0.249936)
		(layer "F.Cu")
		(net "P0V8_SERDES_VDDA_PEX1")
	)
	(segment
		(start 180.02504 -299.224954)
		(end 179.55006 -298.74972)
		(width 0.249936)
		(layer "F.Cu")
		(net "P0V8_SERDES_VDDA_PEX1")
	)
	(segment
		(start 169.574972 -292.57498)
		(end 170.049952 -293.04996)
		(width 0.249936)
		(layer "F.Cu")
		(net "P0V8_SERDES_VDDA_PEX1")
	)
	(segment
		(start 176.224946 -292.574726)
		(end 176.699926 -293.04996)
		(width 0.249936)
		(layer "F.Cu")
		(net "P0V8_SERDES_VDDA_PEX1")
	)
	(segment
		(start 181.44998 -293.04996)
		(end 181.92496 -292.574726)
		(width 0.249936)
		(layer "F.Cu")
		(net "P0V8_SERDES_VDDA_PEX1")
	)
	(segment
		(start 180.975 -301.124874)
		(end 181.44998 -300.649894)
		(width 0.249936)
		(layer "F.Cu")
		(net "P0V8_SERDES_VDDA_PEX1")
	)
	(segment
		(start 182.87492 -290.674806)
		(end 183.3499 -291.149786)
		(width 0.249936)
		(layer "F.Cu")
		(net "P0V8_SERDES_VDDA_PEX1")
	)
	(segment
		(start 170.524932 -301.124874)
		(end 170.999912 -300.649894)
		(width 0.249936)
		(layer "F.Cu")
		(net "P0V8_SERDES_VDDA_PEX1")
	)
	(segment
		(start 177.649886 -291.149786)
		(end 177.174906 -290.674806)
		(width 0.249936)
		(layer "F.Cu")
		(net "P0V8_SERDES_VDDA_PEX1")
	)
	(segment
		(start 183.3499 -293.04996)
		(end 183.82488 -292.574726)
		(width 0.249936)
		(layer "F.Cu")
		(net "P0V8_SERDES_VDDA_PEX1")
	)
	(segment
		(start 168.150032 -298.74972)
		(end 167.675052 -299.224954)
		(width 0.249936)
		(layer "F.Cu")
		(net "P0V8_SERDES_VDDA_PEX1")
	)
	(via
		(at 183.82488 -294.4749)
		(size 0.4064)
		(drill 0.2032)
		(layers "F.Cu" "B.Cu")
		(net "P0V8_SERDES_VDDA_PEX1")
	)
	(via
		(at 173.375066 -292.57498)
		(size 0.4064)
		(drill 0.2032)
		(layers "F.Cu" "B.Cu")
		(net "P0V8_SERDES_VDDA_PEX1")
	)
	(via
		(at 183.82488 -292.574726)
		(size 0.4064)
		(drill 0.2032)
		(layers "F.Cu" "B.Cu")
		(net "P0V8_SERDES_VDDA_PEX1")
	)
	(via
		(at 184.77484 -297.32478)
		(size 0.4064)
		(drill 0.2032)
		(layers "F.Cu" "B.Cu")
		(net "P0V8_SERDES_VDDA_PEX1")
	)
	(via
		(at 179.07508 -292.574726)
		(size 0.4064)
		(drill 0.2032)
		(layers "F.Cu" "B.Cu")
		(net "P0V8_SERDES_VDDA_PEX1")
	)
	(via
		(at 122.846338 -320.08064)
		(size 0.508)
		(drill 0.254)
		(layers "F.Cu" "B.Cu")
		(net "P0V8_SERDES_VDDA_PEX1")
	)
	(via
		(at 120.560338 -320.08064)
		(size 0.508)
		(drill 0.254)
		(layers "F.Cu" "B.Cu")
		(net "P0V8_SERDES_VDDA_PEX1")
	)
	(via
		(at 180.975 -299.224954)
		(size 0.4064)
		(drill 0.2032)
		(layers "F.Cu" "B.Cu")
		(net "P0V8_SERDES_VDDA_PEX1")
	)
	(via
		(at 184.77484 -294.4749)
		(size 0.4064)
		(drill 0.2032)
		(layers "F.Cu" "B.Cu")
		(net "P0V8_SERDES_VDDA_PEX1")
	)
	(via
		(at 183.82488 -290.674806)
		(size 0.4064)
		(drill 0.2032)
		(layers "F.Cu" "B.Cu")
		(net "P0V8_SERDES_VDDA_PEX1")
	)
	(via
		(at 178.124866 -292.574726)
		(size 0.4064)
		(drill 0.2032)
		(layers "F.Cu" "B.Cu")
		(net "P0V8_SERDES_VDDA_PEX1")
	)
	(via
		(at 183.82488 -296.37482)
		(size 0.4064)
		(drill 0.2032)
		(layers "F.Cu" "B.Cu")
		(net "P0V8_SERDES_VDDA_PEX1")
	)
	(via
		(at 127.418338 -320.08064)
		(size 0.508)
		(drill 0.254)
		(layers "F.Cu" "B.Cu")
		(net "P0V8_SERDES_VDDA_PEX1")
	)
	(via
		(at 179.07508 -299.224954)
		(size 0.4064)
		(drill 0.2032)
		(layers "F.Cu" "B.Cu")
		(net "P0V8_SERDES_VDDA_PEX1")
	)
	(via
		(at 128.180338 -319.31864)
		(size 0.508)
		(drill 0.254)
		(layers "F.Cu" "B.Cu")
		(net "P0V8_SERDES_VDDA_PEX1")
	)
	(via
		(at 182.87492 -299.224954)
		(size 0.4064)
		(drill 0.2032)
		(layers "F.Cu" "B.Cu")
		(net "P0V8_SERDES_VDDA_PEX1")
	)
	(via
		(at 182.87492 -297.32478)
		(size 0.4064)
		(drill 0.2032)
		(layers "F.Cu" "B.Cu")
		(net "P0V8_SERDES_VDDA_PEX1")
	)
	(via
		(at 172.425106 -292.57498)
		(size 0.4064)
		(drill 0.2032)
		(layers "F.Cu" "B.Cu")
		(net "P0V8_SERDES_VDDA_PEX1")
	)
	(via
		(at 182.87492 -294.4749)
		(size 0.4064)
		(drill 0.2032)
		(layers "F.Cu" "B.Cu")
		(net "P0V8_SERDES_VDDA_PEX1")
	)
	(via
		(at 170.524932 -299.224954)
		(size 0.4064)
		(drill 0.2032)
		(layers "F.Cu" "B.Cu")
		(net "P0V8_SERDES_VDDA_PEX1")
	)
	(via
		(at 172.424852 -290.674806)
		(size 0.4064)
		(drill 0.2032)
		(layers "F.Cu" "B.Cu")
		(net "P0V8_SERDES_VDDA_PEX1")
	)
	(via
		(at 123.608338 -319.31864)
		(size 0.508)
		(drill 0.254)
		(layers "F.Cu" "B.Cu")
		(net "P0V8_SERDES_VDDA_PEX1")
	)
	(via
		(at 170.524932 -290.674806)
		(size 0.4064)
		(drill 0.2032)
		(layers "F.Cu" "B.Cu")
		(net "P0V8_SERDES_VDDA_PEX1")
	)
	(via
		(at 180.02504 -301.124874)
		(size 0.4064)
		(drill 0.2032)
		(layers "F.Cu" "B.Cu")
		(net "P0V8_SERDES_VDDA_PEX1")
	)
	(via
		(at 122.084338 -319.31864)
		(size 0.508)
		(drill 0.254)
		(layers "F.Cu" "B.Cu")
		(net "P0V8_SERDES_VDDA_PEX1")
	)
	(via
		(at 174.325026 -292.57498)
		(size 0.4064)
		(drill 0.2032)
		(layers "F.Cu" "B.Cu")
		(net "P0V8_SERDES_VDDA_PEX1")
	)
	(via
		(at 166.725092 -301.124874)
		(size 0.4064)
		(drill 0.2032)
		(layers "F.Cu" "B.Cu")
		(net "P0V8_SERDES_VDDA_PEX1")
	)
	(via
		(at 180.02504 -299.224954)
		(size 0.4064)
		(drill 0.2032)
		(layers "F.Cu" "B.Cu")
		(net "P0V8_SERDES_VDDA_PEX1")
	)
	(via
		(at 124.370338 -319.31864)
		(size 0.508)
		(drill 0.254)
		(layers "F.Cu" "B.Cu")
		(net "P0V8_SERDES_VDDA_PEX1")
	)
	(via
		(at 174.325026 -301.124874)
		(size 0.4064)
		(drill 0.2032)
		(layers "F.Cu" "B.Cu")
		(net "P0V8_SERDES_VDDA_PEX1")
	)
	(via
		(at 181.92496 -299.224954)
		(size 0.4064)
		(drill 0.2032)
		(layers "F.Cu" "B.Cu")
		(net "P0V8_SERDES_VDDA_PEX1")
	)
	(via
		(at 173.375066 -290.674806)
		(size 0.4064)
		(drill 0.2032)
		(layers "F.Cu" "B.Cu")
		(net "P0V8_SERDES_VDDA_PEX1")
	)
	(via
		(at 168.625012 -290.674806)
		(size 0.4064)
		(drill 0.2032)
		(layers "F.Cu" "B.Cu")
		(net "P0V8_SERDES_VDDA_PEX1")
	)
	(via
		(at 122.846338 -319.31864)
		(size 0.508)
		(drill 0.254)
		(layers "F.Cu" "B.Cu")
		(net "P0V8_SERDES_VDDA_PEX1")
	)
	(via
		(at 180.975 -292.574726)
		(size 0.4064)
		(drill 0.2032)
		(layers "F.Cu" "B.Cu")
		(net "P0V8_SERDES_VDDA_PEX1")
	)
	(via
		(at 122.084338 -320.08064)
		(size 0.508)
		(drill 0.254)
		(layers "F.Cu" "B.Cu")
		(net "P0V8_SERDES_VDDA_PEX1")
	)
	(via
		(at 128.866138 -319.31864)
		(size 0.508)
		(drill 0.254)
		(layers "F.Cu" "B.Cu")
		(net "P0V8_SERDES_VDDA_PEX1")
	)
	(via
		(at 169.574972 -301.124874)
		(size 0.4064)
		(drill 0.2032)
		(layers "F.Cu" "B.Cu")
		(net "P0V8_SERDES_VDDA_PEX1")
	)
	(via
		(at 182.87492 -301.124874)
		(size 0.4064)
		(drill 0.2032)
		(layers "F.Cu" "B.Cu")
		(net "P0V8_SERDES_VDDA_PEX1")
	)
	(via
		(at 176.224946 -292.574726)
		(size 0.4064)
		(drill 0.2032)
		(layers "F.Cu" "B.Cu")
		(net "P0V8_SERDES_VDDA_PEX1")
	)
	(via
		(at 167.675052 -290.674806)
		(size 0.4064)
		(drill 0.2032)
		(layers "F.Cu" "B.Cu")
		(net "P0V8_SERDES_VDDA_PEX1")
	)
	(via
		(at 179.07508 -290.674806)
		(size 0.4064)
		(drill 0.2032)
		(layers "F.Cu" "B.Cu")
		(net "P0V8_SERDES_VDDA_PEX1")
	)
	(via
		(at 171.474892 -299.224954)
		(size 0.4064)
		(drill 0.2032)
		(layers "F.Cu" "B.Cu")
		(net "P0V8_SERDES_VDDA_PEX1")
	)
	(via
		(at 178.124866 -301.124874)
		(size 0.4064)
		(drill 0.2032)
		(layers "F.Cu" "B.Cu")
		(net "P0V8_SERDES_VDDA_PEX1")
	)
	(via
		(at 121.322338 -320.08064)
		(size 0.508)
		(drill 0.254)
		(layers "F.Cu" "B.Cu")
		(net "P0V8_SERDES_VDDA_PEX1")
	)
	(via
		(at 170.524932 -301.124874)
		(size 0.4064)
		(drill 0.2032)
		(layers "F.Cu" "B.Cu")
		(net "P0V8_SERDES_VDDA_PEX1")
	)
	(via
		(at 125.132338 -320.08064)
		(size 0.508)
		(drill 0.254)
		(layers "F.Cu" "B.Cu")
		(net "P0V8_SERDES_VDDA_PEX1")
	)
	(via
		(at 166.725092 -292.57498)
		(size 0.4064)
		(drill 0.2032)
		(layers "F.Cu" "B.Cu")
		(net "P0V8_SERDES_VDDA_PEX1")
	)
	(via
		(at 172.424852 -299.224954)
		(size 0.4064)
		(drill 0.2032)
		(layers "F.Cu" "B.Cu")
		(net "P0V8_SERDES_VDDA_PEX1")
	)
	(via
		(at 119.798338 -319.31864)
		(size 0.508)
		(drill 0.254)
		(layers "F.Cu" "B.Cu")
		(net "P0V8_SERDES_VDDA_PEX1")
	)
	(via
		(at 174.325026 -299.224954)
		(size 0.4064)
		(drill 0.2032)
		(layers "F.Cu" "B.Cu")
		(net "P0V8_SERDES_VDDA_PEX1")
	)
	(via
		(at 119.798338 -320.08064)
		(size 0.508)
		(drill 0.254)
		(layers "F.Cu" "B.Cu")
		(net "P0V8_SERDES_VDDA_PEX1")
	)
	(via
		(at 167.675052 -301.124874)
		(size 0.4064)
		(drill 0.2032)
		(layers "F.Cu" "B.Cu")
		(net "P0V8_SERDES_VDDA_PEX1")
	)
	(via
		(at 128.866138 -320.08064)
		(size 0.508)
		(drill 0.254)
		(layers "F.Cu" "B.Cu")
		(net "P0V8_SERDES_VDDA_PEX1")
	)
	(via
		(at 180.02504 -290.674806)
		(size 0.4064)
		(drill 0.2032)
		(layers "F.Cu" "B.Cu")
		(net "P0V8_SERDES_VDDA_PEX1")
	)
	(via
		(at 180.975 -290.674806)
		(size 0.4064)
		(drill 0.2032)
		(layers "F.Cu" "B.Cu")
		(net "P0V8_SERDES_VDDA_PEX1")
	)
	(via
		(at 125.132338 -319.31864)
		(size 0.508)
		(drill 0.254)
		(layers "F.Cu" "B.Cu")
		(net "P0V8_SERDES_VDDA_PEX1")
	)
	(via
		(at 169.574972 -292.57498)
		(size 0.4064)
		(drill 0.2032)
		(layers "F.Cu" "B.Cu")
		(net "P0V8_SERDES_VDDA_PEX1")
	)
	(via
		(at 182.87492 -292.574726)
		(size 0.4064)
		(drill 0.2032)
		(layers "F.Cu" "B.Cu")
		(net "P0V8_SERDES_VDDA_PEX1")
	)
	(via
		(at 119.322088 -311.078118)
		(size 0.6604)
		(drill 0.3302)
		(layers "F.Cu" "B.Cu")
		(net "P0V8_SERDES_VDDA_PEX1")
	)
	(via
		(at 171.474892 -301.124874)
		(size 0.4064)
		(drill 0.2032)
		(layers "F.Cu" "B.Cu")
		(net "P0V8_SERDES_VDDA_PEX1")
	)
	(via
		(at 177.174906 -301.124874)
		(size 0.4064)
		(drill 0.2032)
		(layers "F.Cu" "B.Cu")
		(net "P0V8_SERDES_VDDA_PEX1")
	)
	(via
		(at 125.894338 -319.31864)
		(size 0.508)
		(drill 0.254)
		(layers "F.Cu" "B.Cu")
		(net "P0V8_SERDES_VDDA_PEX1")
	)
	(via
		(at 119.139462 -314.475876)
		(size 0.6604)
		(drill 0.3302)
		(layers "F.Cu" "B.Cu")
		(net "P0V8_SERDES_VDDA_PEX1")
	)
	(via
		(at 173.375066 -299.224954)
		(size 0.4064)
		(drill 0.2032)
		(layers "F.Cu" "B.Cu")
		(net "P0V8_SERDES_VDDA_PEX1")
	)
	(via
		(at 124.370338 -320.08064)
		(size 0.508)
		(drill 0.254)
		(layers "F.Cu" "B.Cu")
		(net "P0V8_SERDES_VDDA_PEX1")
	)
	(via
		(at 127.418338 -319.31864)
		(size 0.508)
		(drill 0.254)
		(layers "F.Cu" "B.Cu")
		(net "P0V8_SERDES_VDDA_PEX1")
	)
	(via
		(at 118.746778 -312.667396)
		(size 0.6604)
		(drill 0.3302)
		(layers "F.Cu" "B.Cu")
		(net "P0V8_SERDES_VDDA_PEX1")
	)
	(via
		(at 174.325026 -290.674806)
		(size 0.4064)
		(drill 0.2032)
		(layers "F.Cu" "B.Cu")
		(net "P0V8_SERDES_VDDA_PEX1")
	)
	(via
		(at 169.574972 -299.224954)
		(size 0.4064)
		(drill 0.2032)
		(layers "F.Cu" "B.Cu")
		(net "P0V8_SERDES_VDDA_PEX1")
	)
	(via
		(at 181.92496 -290.674806)
		(size 0.4064)
		(drill 0.2032)
		(layers "F.Cu" "B.Cu")
		(net "P0V8_SERDES_VDDA_PEX1")
	)
	(via
		(at 168.625012 -301.124874)
		(size 0.4064)
		(drill 0.2032)
		(layers "F.Cu" "B.Cu")
		(net "P0V8_SERDES_VDDA_PEX1")
	)
	(via
		(at 177.174906 -290.674806)
		(size 0.4064)
		(drill 0.2032)
		(layers "F.Cu" "B.Cu")
		(net "P0V8_SERDES_VDDA_PEX1")
	)
	(via
		(at 180.02504 -292.574726)
		(size 0.4064)
		(drill 0.2032)
		(layers "F.Cu" "B.Cu")
		(net "P0V8_SERDES_VDDA_PEX1")
	)
	(via
		(at 183.82488 -301.124874)
		(size 0.4064)
		(drill 0.2032)
		(layers "F.Cu" "B.Cu")
		(net "P0V8_SERDES_VDDA_PEX1")
	)
	(via
		(at 177.174906 -299.224954)
		(size 0.4064)
		(drill 0.2032)
		(layers "F.Cu" "B.Cu")
		(net "P0V8_SERDES_VDDA_PEX1")
	)
	(via
		(at 167.675052 -299.224954)
		(size 0.4064)
		(drill 0.2032)
		(layers "F.Cu" "B.Cu")
		(net "P0V8_SERDES_VDDA_PEX1")
	)
	(via
		(at 123.608338 -320.08064)
		(size 0.508)
		(drill 0.254)
		(layers "F.Cu" "B.Cu")
		(net "P0V8_SERDES_VDDA_PEX1")
	)
	(via
		(at 181.92496 -301.124874)
		(size 0.4064)
		(drill 0.2032)
		(layers "F.Cu" "B.Cu")
		(net "P0V8_SERDES_VDDA_PEX1")
	)
	(via
		(at 183.82488 -297.32478)
		(size 0.4064)
		(drill 0.2032)
		(layers "F.Cu" "B.Cu")
		(net "P0V8_SERDES_VDDA_PEX1")
	)
	(via
		(at 176.224946 -290.674806)
		(size 0.4064)
		(drill 0.2032)
		(layers "F.Cu" "B.Cu")
		(net "P0V8_SERDES_VDDA_PEX1")
	)
	(via
		(at 171.474892 -290.674806)
		(size 0.4064)
		(drill 0.2032)
		(layers "F.Cu" "B.Cu")
		(net "P0V8_SERDES_VDDA_PEX1")
	)
	(via
		(at 183.82488 -299.224954)
		(size 0.4064)
		(drill 0.2032)
		(layers "F.Cu" "B.Cu")
		(net "P0V8_SERDES_VDDA_PEX1")
	)
	(via
		(at 168.625012 -299.224954)
		(size 0.4064)
		(drill 0.2032)
		(layers "F.Cu" "B.Cu")
		(net "P0V8_SERDES_VDDA_PEX1")
	)
	(via
		(at 178.124866 -290.674806)
		(size 0.4064)
		(drill 0.2032)
		(layers "F.Cu" "B.Cu")
		(net "P0V8_SERDES_VDDA_PEX1")
	)
	(via
		(at 176.224946 -301.124874)
		(size 0.4064)
		(drill 0.2032)
		(layers "F.Cu" "B.Cu")
		(net "P0V8_SERDES_VDDA_PEX1")
	)
	(via
		(at 170.524932 -292.57498)
		(size 0.4064)
		(drill 0.2032)
		(layers "F.Cu" "B.Cu")
		(net "P0V8_SERDES_VDDA_PEX1")
	)
	(via
		(at 184.77484 -296.37482)
		(size 0.4064)
		(drill 0.2032)
		(layers "F.Cu" "B.Cu")
		(net "P0V8_SERDES_VDDA_PEX1")
	)
	(via
		(at 182.87492 -290.674806)
		(size 0.4064)
		(drill 0.2032)
		(layers "F.Cu" "B.Cu")
		(net "P0V8_SERDES_VDDA_PEX1")
	)
	(via
		(at 166.725092 -290.674806)
		(size 0.4064)
		(drill 0.2032)
		(layers "F.Cu" "B.Cu")
		(net "P0V8_SERDES_VDDA_PEX1")
	)
	(via
		(at 176.224946 -299.224954)
		(size 0.4064)
		(drill 0.2032)
		(layers "F.Cu" "B.Cu")
		(net "P0V8_SERDES_VDDA_PEX1")
	)
	(via
		(at 126.656338 -319.31864)
		(size 0.508)
		(drill 0.254)
		(layers "F.Cu" "B.Cu")
		(net "P0V8_SERDES_VDDA_PEX1")
	)
	(via
		(at 126.656338 -320.08064)
		(size 0.508)
		(drill 0.254)
		(layers "F.Cu" "B.Cu")
		(net "P0V8_SERDES_VDDA_PEX1")
	)
	(via
		(at 166.725092 -299.224954)
		(size 0.4064)
		(drill 0.2032)
		(layers "F.Cu" "B.Cu")
		(net "P0V8_SERDES_VDDA_PEX1")
	)
	(via
		(at 180.975 -301.124874)
		(size 0.4064)
		(drill 0.2032)
		(layers "F.Cu" "B.Cu")
		(net "P0V8_SERDES_VDDA_PEX1")
	)
	(via
		(at 169.574972 -290.674806)
		(size 0.4064)
		(drill 0.2032)
		(layers "F.Cu" "B.Cu")
		(net "P0V8_SERDES_VDDA_PEX1")
	)
	(via
		(at 121.322338 -319.31864)
		(size 0.508)
		(drill 0.254)
		(layers "F.Cu" "B.Cu")
		(net "P0V8_SERDES_VDDA_PEX1")
	)
	(via
		(at 167.675052 -292.57498)
		(size 0.4064)
		(drill 0.2032)
		(layers "F.Cu" "B.Cu")
		(net "P0V8_SERDES_VDDA_PEX1")
	)
	(via
		(at 173.375066 -301.124874)
		(size 0.4064)
		(drill 0.2032)
		(layers "F.Cu" "B.Cu")
		(net "P0V8_SERDES_VDDA_PEX1")
	)
	(via
		(at 125.894338 -320.08064)
		(size 0.508)
		(drill 0.254)
		(layers "F.Cu" "B.Cu")
		(net "P0V8_SERDES_VDDA_PEX1")
	)
	(via
		(at 128.180338 -320.08064)
		(size 0.508)
		(drill 0.254)
		(layers "F.Cu" "B.Cu")
		(net "P0V8_SERDES_VDDA_PEX1")
	)
	(via
		(at 120.560338 -319.31864)
		(size 0.508)
		(drill 0.254)
		(layers "F.Cu" "B.Cu")
		(net "P0V8_SERDES_VDDA_PEX1")
	)
	(via
		(at 179.07508 -301.124874)
		(size 0.4064)
		(drill 0.2032)
		(layers "F.Cu" "B.Cu")
		(net "P0V8_SERDES_VDDA_PEX1")
	)
	(via
		(at 181.92496 -292.574726)
		(size 0.4064)
		(drill 0.2032)
		(layers "F.Cu" "B.Cu")
		(net "P0V8_SERDES_VDDA_PEX1")
	)
	(via
		(at 171.474892 -292.57498)
		(size 0.4064)
		(drill 0.2032)
		(layers "F.Cu" "B.Cu")
		(net "P0V8_SERDES_VDDA_PEX1")
	)
	(via
		(at 172.424852 -301.124874)
		(size 0.4064)
		(drill 0.2032)
		(layers "F.Cu" "B.Cu")
		(net "P0V8_SERDES_VDDA_PEX1")
	)
	(via
		(at 178.124866 -299.224954)
		(size 0.4064)
		(drill 0.2032)
		(layers "F.Cu" "B.Cu")
		(net "P0V8_SERDES_VDDA_PEX1")
	)
	(via
		(at 168.625012 -292.57498)
		(size 0.4064)
		(drill 0.2032)
		(layers "F.Cu" "B.Cu")
		(net "P0V8_SERDES_VDDA_PEX1")
	)
	(via
		(at 177.174906 -292.574726)
		(size 0.4064)
		(drill 0.2032)
		(layers "F.Cu" "B.Cu")
		(net "P0V8_SERDES_VDDA_PEX1")
	)
	(segment
		(start 185.250074 -304.449734)
		(end 185.725054 -304.924714)
		(width 0.249936)
		(layer "F.Cu")
		(net "P1V8_VDDA_PEX1")
	)
	(segment
		(start 161.025078 -298.27474)
		(end 161.500058 -297.79976)
		(width 0.249936)
		(layer "F.Cu")
		(net "P1V8_VDDA_PEX1")
	)
	(segment
		(start 184.29986 -299.699934)
		(end 184.77484 -300.174914)
		(width 0.249936)
		(layer "F.Cu")
		(net "P1V8_VDDA_PEX1")
	)
	(segment
		(start 165.299898 -302.549814)
		(end 164.824918 -303.024794)
		(width 0.249936)
		(layer "F.Cu")
		(net "P1V8_VDDA_PEX1")
	)
	(segment
		(start 185.250074 -287.349946)
		(end 185.725054 -286.874966)
		(width 0.249936)
		(layer "F.Cu")
		(net "P1V8_VDDA_PEX1")
	)
	(segment
		(start 187.149994 -299.699934)
		(end 187.624974 -300.174914)
		(width 0.249936)
		(layer "F.Cu")
		(net "P1V8_VDDA_PEX1")
	)
	(segment
		(start 161.500058 -299.699934)
		(end 161.025078 -300.174914)
		(width 0.249936)
		(layer "F.Cu")
		(net "P1V8_VDDA_PEX1")
	)
	(segment
		(start 161.500058 -299.699934)
		(end 161.025078 -299.224954)
		(width 0.249936)
		(layer "F.Cu")
		(net "P1V8_VDDA_PEX1")
	)
	(segment
		(start 165.299898 -289.249866)
		(end 164.824918 -288.774886)
		(width 0.249936)
		(layer "F.Cu")
		(net "P1V8_VDDA_PEX1")
	)
	(segment
		(start 161.025078 -299.224954)
		(end 161.500058 -298.74972)
		(width 0.249936)
		(layer "F.Cu")
		(net "P1V8_VDDA_PEX1")
	)
	(segment
		(start 161.500058 -298.74972)
		(end 161.025078 -298.27474)
		(width 0.249936)
		(layer "F.Cu")
		(net "P1V8_VDDA_PEX1")
	)
	(via
		(at 159.022542 -297.203368)
		(size 0.6604)
		(drill 0.3302)
		(layers "F.Cu" "B.Cu")
		(net "P1V8_VDDA_PEX1")
	)
	(via
		(at 161.025078 -298.27474)
		(size 0.4064)
		(drill 0.2032)
		(layers "F.Cu" "B.Cu")
		(net "P1V8_VDDA_PEX1")
	)
	(via
		(at 161.025078 -299.224954)
		(size 0.4064)
		(drill 0.2032)
		(layers "F.Cu" "B.Cu")
		(net "P1V8_VDDA_PEX1")
	)
	(via
		(at 142.762478 -261.763002)
		(size 0.508)
		(drill 0.254)
		(layers "F.Cu" "B.Cu")
		(net "P1V8_VDDA_PEX1")
	)
	(via
		(at 164.824918 -288.774886)
		(size 0.4064)
		(drill 0.2032)
		(layers "F.Cu" "B.Cu")
		(net "P1V8_VDDA_PEX1")
	)
	(via
		(at 187.624974 -300.174914)
		(size 0.4064)
		(drill 0.2032)
		(layers "F.Cu" "B.Cu")
		(net "P1V8_VDDA_PEX1")
	)
	(via
		(at 185.725054 -286.874966)
		(size 0.4064)
		(drill 0.2032)
		(layers "F.Cu" "B.Cu")
		(net "P1V8_VDDA_PEX1")
	)
	(via
		(at 185.725054 -304.924714)
		(size 0.4064)
		(drill 0.2032)
		(layers "F.Cu" "B.Cu")
		(net "P1V8_VDDA_PEX1")
	)
	(via
		(at 184.77484 -300.174914)
		(size 0.4064)
		(drill 0.2032)
		(layers "F.Cu" "B.Cu")
		(net "P1V8_VDDA_PEX1")
	)
	(via
		(at 164.824918 -303.024794)
		(size 0.4064)
		(drill 0.2032)
		(layers "F.Cu" "B.Cu")
		(net "P1V8_VDDA_PEX1")
	)
	(via
		(at 162.44951 -303.508918)
		(size 0.6604)
		(drill 0.3302)
		(layers "F.Cu" "B.Cu")
		(net "P1V8_VDDA_PEX1")
	)
	(via
		(at 161.025078 -300.174914)
		(size 0.4064)
		(drill 0.2032)
		(layers "F.Cu" "B.Cu")
		(net "P1V8_VDDA_PEX1")
	)
	(via
		(at 188.7728 -286.5374)
		(size 0.6604)
		(drill 0.3302)
		(layers "F.Cu" "B.Cu")
		(net "P1V8_VDDA_PEX1")
	)
	(via
		(at 142.000478 -261.763002)
		(size 0.508)
		(drill 0.254)
		(layers "F.Cu" "B.Cu")
		(net "P1V8_VDDA_PEX1")
	)
	(segment
		(start 187.624974 -300.174914)
		(end 188.041534 -300.174914)
		(width 0.3048)
		(layer "B.Cu")
		(net "P1V8_VDDA_PEX1")
	)
	(segment
		(start 165.033198 -288.774886)
		(end 164.824918 -288.774886)
		(width 0.3048)
		(layer "B.Cu")
		(net "P1V8_VDDA_PEX1")
	)
	(segment
		(start 187.208414 -300.174914)
		(end 187.624974 -300.174914)
		(width 0.3048)
		(layer "B.Cu")
		(net "P1V8_VDDA_PEX1")
	)
	(segment
		(start 159.327088 -296.898822)
		(end 159.022542 -297.203368)
		(width 0.13208)
		(layer "B.Cu")
		(net "P1V8_VDDA_PEX1")
	)
	(segment
		(start 160.373822 -296.898822)
		(end 159.327088 -296.898822)
		(width 0.13208)
		(layer "B.Cu")
		(net "P1V8_VDDA_PEX1")
	)
	(segment
		(start 160.6296 -297.1546)
		(end 160.373822 -296.898822)
		(width 0.13208)
		(layer "B.Cu")
		(net "P1V8_VDDA_PEX1")
	)
	(segment
		(start 185.725054 -304.508154)
		(end 185.725054 -304.924714)
		(width 0.3048)
		(layer "B.Cu")
		(net "P1V8_VDDA_PEX1")
	)
	(segment
		(start 164.0586 -303.508918)
		(end 164.408358 -303.15916)
		(width 0.13208)
		(layer "B.Cu")
		(net "P1V8_VDDA_PEX1")
	)
	(segment
		(start 162.44951 -303.508918)
		(end 164.0586 -303.508918)
		(width 0.13208)
		(layer "B.Cu")
		(net "P1V8_VDDA_PEX1")
	)
	(segment
		(start 184.983374 -300.174914)
		(end 184.77484 -300.174914)
		(width 0.3048)
		(layer "B.Cu")
		(net "P1V8_VDDA_PEX1")
	)
	(segment
		(start 160.6296 -297.628056)
		(end 160.6296 -297.1546)
		(width 0.13208)
		(layer "B.Cu")
		(net "P1V8_VDDA_PEX1")
	)
	(segment
		(start 185.725054 -305.341528)
		(end 185.725054 -304.924714)
		(width 0.3048)
		(layer "B.Cu")
		(net "P1V8_VDDA_PEX1")
	)
	(segment
		(start 164.408358 -303.15916)
		(end 164.408358 -303.024794)
		(width 0.13208)
		(layer "B.Cu")
		(net "P1V8_VDDA_PEX1")
	)
	(segment
		(start 160.816544 -297.815)
		(end 160.6296 -297.628056)
		(width 0.13208)
		(layer "B.Cu")
		(net "P1V8_VDDA_PEX1")
	)
	(segment
		(start 226.703128 -309.908448)
		(end 227.336604 -310.541924)
		(width 0.13208)
		(layer "F.Cu")
		(net "P1V25_PEX1_EN")
	)
	(segment
		(start 226.365054 -309.768494)
		(end 226.703128 -309.908448)
		(width 0.13208)
		(layer "F.Cu")
		(net "P1V25_PEX1_EN")
	)
	(segment
		(start 225.91903 -309.768494)
		(end 226.365054 -309.768494)
		(width 0.13208)
		(layer "F.Cu")
		(net "P1V25_PEX1_EN")
	)
	(segment
		(start 227.336604 -310.541924)
		(end 227.336604 -310.568848)
		(width 0.13208)
		(layer "F.Cu")
		(net "P1V25_PEX1_EN")
	)
	(via
		(at 226.703128 -309.908448)
		(size 0.508)
		(drill 0.254)
		(layers "F.Cu" "B.Cu")
		(net "P1V25_PEX1_EN")
	)
	(segment
		(start 228.418644 -309.745126)
		(end 228.24313 -309.745126)
		(width 0.254)
		(layer "F.Cu")
		(net "P1V25_PEX1_FB")
	)
	(segment
		(start 228.24313 -309.745126)
		(end 228.109272 -309.611268)
		(width 0.254)
		(layer "F.Cu")
		(net "P1V25_PEX1_FB")
	)
	(segment
		(start 226.53752 -309.368698)
		(end 226.54387 -309.375048)
		(width 0.254)
		(layer "F.Cu")
		(net "P1V25_PEX1_FB")
	)
	(segment
		(start 228.564694 -309.745126)
		(end 228.418644 -309.745126)
		(width 0.254)
		(layer "F.Cu")
		(net "P1V25_PEX1_FB")
	)
	(segment
		(start 226.844352 -309.375048)
		(end 227.414836 -309.611268)
		(width 0.254)
		(layer "F.Cu")
		(net "P1V25_PEX1_FB")
	)
	(segment
		(start 228.754178 -309.555642)
		(end 228.564694 -309.745126)
		(width 0.254)
		(layer "F.Cu")
		(net "P1V25_PEX1_FB")
	)
	(segment
		(start 225.91903 -309.368698)
		(end 226.53752 -309.368698)
		(width 0.1778)
		(layer "F.Cu")
		(net "P1V25_PEX1_FB")
	)
	(segment
		(start 229.0826 -309.555642)
		(end 228.754178 -309.555642)
		(width 0.254)
		(layer "F.Cu")
		(net "P1V25_PEX1_FB")
	)
	(segment
		(start 227.414836 -309.611268)
		(end 227.773484 -309.611268)
		(width 0.254)
		(layer "F.Cu")
		(net "P1V25_PEX1_FB")
	)
	(segment
		(start 228.109272 -309.611268)
		(end 227.773484 -309.611268)
		(width 0.254)
		(layer "F.Cu")
		(net "P1V25_PEX1_FB")
	)
	(segment
		(start 226.54387 -309.375048)
		(end 226.844352 -309.375048)
		(width 0.254)
		(layer "F.Cu")
		(net "P1V25_PEX1_FB")
	)
	(segment
		(start 229.0826 -310.571642)
		(end 229.0826 -309.555642)
		(width 0.254)
		(layer "F.Cu")
		(net "P1V25_PEX1_FB")
	)
	(via
		(at 228.418644 -309.745126)
		(size 0.508)
		(drill 0.254)
		(layers "F.Cu" "B.Cu")
		(net "P1V25_PEX1_FB")
	)
	(segment
		(start 229.5906 -307.695346)
		(end 229.490778 -307.795168)
		(width 0.254)
		(layer "F.Cu")
		(net "SH_P1V25_PEX1_FB_N")
	)
	(segment
		(start 230.62311 -307.833522)
		(end 230.89616 -307.560472)
		(width 0.254)
		(layer "F.Cu")
		(net "SH_P1V25_PEX1_FB_N")
	)
	(segment
		(start 225.91903 -308.968648)
		(end 226.892866 -308.968648)
		(width 0.1778)
		(layer "F.Cu")
		(net "SH_P1V25_PEX1_FB_N")
	)
	(segment
		(start 227.447348 -308.811168)
		(end 227.773484 -308.811168)
		(width 0.254)
		(layer "F.Cu")
		(net "SH_P1V25_PEX1_FB_N")
	)
	(segment
		(start 228.978714 -308.562502)
		(end 228.915722 -308.562502)
		(width 0.254)
		(layer "F.Cu")
		(net "SH_P1V25_PEX1_FB_N")
	)
	(segment
		(start 228.82352 -308.654704)
		(end 228.915722 -308.562502)
		(width 0.254)
		(layer "F.Cu")
		(net "SH_P1V25_PEX1_FB_N")
	)
	(segment
		(start 226.892866 -308.968648)
		(end 227.06711 -308.968648)
		(width 0.254)
		(layer "F.Cu")
		(net "SH_P1V25_PEX1_FB_N")
	)
	(segment
		(start 230.338884 -307.833522)
		(end 230.62311 -307.833522)
		(width 0.254)
		(layer "F.Cu")
		(net "SH_P1V25_PEX1_FB_N")
	)
	(segment
		(start 230.200708 -307.695346)
		(end 230.338884 -307.833522)
		(width 0.254)
		(layer "F.Cu")
		(net "SH_P1V25_PEX1_FB_N")
	)
	(segment
		(start 227.773484 -308.811168)
		(end 227.906072 -308.811168)
		(width 0.254)
		(layer "F.Cu")
		(net "SH_P1V25_PEX1_FB_N")
	)
	(segment
		(start 228.567488 -308.654704)
		(end 228.82352 -308.654704)
		(width 0.254)
		(layer "F.Cu")
		(net "SH_P1V25_PEX1_FB_N")
	)
	(segment
		(start 228.315012 -308.402228)
		(end 228.567488 -308.654704)
		(width 0.254)
		(layer "F.Cu")
		(net "SH_P1V25_PEX1_FB_N")
	)
	(segment
		(start 227.906072 -308.811168)
		(end 228.315012 -308.402228)
		(width 0.254)
		(layer "F.Cu")
		(net "SH_P1V25_PEX1_FB_N")
	)
	(segment
		(start 227.06711 -308.968648)
		(end 227.447348 -308.811168)
		(width 0.254)
		(layer "F.Cu")
		(net "SH_P1V25_PEX1_FB_N")
	)
	(segment
		(start 229.443788 -308.097428)
		(end 228.978714 -308.562502)
		(width 0.254)
		(layer "F.Cu")
		(net "SH_P1V25_PEX1_FB_N")
	)
	(segment
		(start 229.88778 -307.695346)
		(end 229.5906 -307.695346)
		(width 0.254)
		(layer "F.Cu")
		(net "SH_P1V25_PEX1_FB_N")
	)
	(segment
		(start 230.89616 -307.560472)
		(end 230.90378 -307.484272)
		(width 0.254)
		(layer "F.Cu")
		(net "SH_P1V25_PEX1_FB_N")
	)
	(segment
		(start 229.88778 -307.695346)
		(end 230.200708 -307.695346)
		(width 0.254)
		(layer "F.Cu")
		(net "SH_P1V25_PEX1_FB_N")
	)
	(segment
		(start 229.443788 -307.908706)
		(end 229.443788 -308.097428)
		(width 0.254)
		(layer "F.Cu")
		(net "SH_P1V25_PEX1_FB_N")
	)
	(segment
		(start 229.490778 -307.795168)
		(end 229.443788 -307.908706)
		(width 0.254)
		(layer "F.Cu")
		(net "SH_P1V25_PEX1_FB_N")
	)
	(via
		(at 228.315012 -308.402228)
		(size 0.508)
		(drill 0.254)
		(layers "F.Cu" "B.Cu")
		(net "SH_P1V25_PEX1_FB_N")
	)
	(segment
		(start 168.625012 -286.874966)
		(end 169.099992 -287.349946)
		(width 0.249936)
		(layer "F.Cu")
		(net "P1V25_SERDES_VDDPLL_PEX1")
	)
	(segment
		(start 170.524932 -304.924714)
		(end 170.999912 -304.449734)
		(width 0.249936)
		(layer "F.Cu")
		(net "P1V25_SERDES_VDDPLL_PEX1")
	)
	(segment
		(start 177.174906 -304.924714)
		(end 176.699926 -304.449734)
		(width 0.249936)
		(layer "F.Cu")
		(net "P1V25_SERDES_VDDPLL_PEX1")
	)
	(segment
		(start 178.124866 -304.924714)
		(end 177.649886 -304.449734)
		(width 0.249936)
		(layer "F.Cu")
		(net "P1V25_SERDES_VDDPLL_PEX1")
	)
	(segment
		(start 177.174906 -286.874966)
		(end 176.699926 -287.349946)
		(width 0.249936)
		(layer "F.Cu")
		(net "P1V25_SERDES_VDDPLL_PEX1")
	)
	(segment
		(start 174.325026 -286.874966)
		(end 174.800006 -287.349946)
		(width 0.249936)
		(layer "F.Cu")
		(net "P1V25_SERDES_VDDPLL_PEX1")
	)
	(segment
		(start 172.424852 -286.874966)
		(end 172.900086 -287.349946)
		(width 0.249936)
		(layer "F.Cu")
		(net "P1V25_SERDES_VDDPLL_PEX1")
	)
	(segment
		(start 183.82488 -286.874966)
		(end 183.3499 -287.349946)
		(width 0.249936)
		(layer "F.Cu")
		(net "P1V25_SERDES_VDDPLL_PEX1")
	)
	(segment
		(start 180.975 -286.874966)
		(end 180.50002 -287.349946)
		(width 0.249936)
		(layer "F.Cu")
		(net "P1V25_SERDES_VDDPLL_PEX1")
	)
	(segment
		(start 167.675052 -304.924714)
		(end 168.150032 -304.449734)
		(width 0.249936)
		(layer "F.Cu")
		(net "P1V25_SERDES_VDDPLL_PEX1")
	)
	(segment
		(start 167.675052 -286.874966)
		(end 168.150032 -287.349946)
		(width 0.249936)
		(layer "F.Cu")
		(net "P1V25_SERDES_VDDPLL_PEX1")
	)
	(segment
		(start 176.224946 -304.924714)
		(end 175.749966 -304.449734)
		(width 0.249936)
		(layer "F.Cu")
		(net "P1V25_SERDES_VDDPLL_PEX1")
	)
	(segment
		(start 171.474892 -304.924714)
		(end 171.949872 -304.449734)
		(width 0.249936)
		(layer "F.Cu")
		(net "P1V25_SERDES_VDDPLL_PEX1")
	)
	(segment
		(start 188.574934 -296.37482)
		(end 188.099954 -295.89984)
		(width 0.249936)
		(layer "F.Cu")
		(net "P1V25_SERDES_VDDPLL_PEX1")
	)
	(segment
		(start 179.07508 -304.924714)
		(end 178.599846 -304.449734)
		(width 0.249936)
		(layer "F.Cu")
		(net "P1V25_SERDES_VDDPLL_PEX1")
	)
	(segment
		(start 173.375066 -304.924714)
		(end 173.850046 -304.449734)
		(width 0.249936)
		(layer "F.Cu")
		(net "P1V25_SERDES_VDDPLL_PEX1")
	)
	(segment
		(start 178.124866 -286.874966)
		(end 177.649886 -287.349946)
		(width 0.249936)
		(layer "F.Cu")
		(net "P1V25_SERDES_VDDPLL_PEX1")
	)
	(segment
		(start 180.02504 -304.924714)
		(end 179.55006 -304.449734)
		(width 0.249936)
		(layer "F.Cu")
		(net "P1V25_SERDES_VDDPLL_PEX1")
	)
	(segment
		(start 181.92496 -286.874966)
		(end 181.44998 -287.349946)
		(width 0.249936)
		(layer "F.Cu")
		(net "P1V25_SERDES_VDDPLL_PEX1")
	)
	(segment
		(start 188.574934 -298.27474)
		(end 188.099954 -297.79976)
		(width 0.249936)
		(layer "F.Cu")
		(net "P1V25_SERDES_VDDPLL_PEX1")
	)
	(segment
		(start 182.87492 -304.924714)
		(end 182.39994 -304.449734)
		(width 0.249936)
		(layer "F.Cu")
		(net "P1V25_SERDES_VDDPLL_PEX1")
	)
	(segment
		(start 176.224946 -286.874966)
		(end 175.749966 -287.349946)
		(width 0.249936)
		(layer "F.Cu")
		(net "P1V25_SERDES_VDDPLL_PEX1")
	)
	(segment
		(start 182.87492 -286.874966)
		(end 182.39994 -287.349946)
		(width 0.249936)
		(layer "F.Cu")
		(net "P1V25_SERDES_VDDPLL_PEX1")
	)
	(segment
		(start 169.574972 -304.924714)
		(end 170.049952 -304.449734)
		(width 0.249936)
		(layer "F.Cu")
		(net "P1V25_SERDES_VDDPLL_PEX1")
	)
	(segment
		(start 181.92496 -304.924714)
		(end 181.44998 -304.449734)
		(width 0.249936)
		(layer "F.Cu")
		(net "P1V25_SERDES_VDDPLL_PEX1")
	)
	(segment
		(start 183.82488 -304.924714)
		(end 183.3499 -304.449734)
		(width 0.249936)
		(layer "F.Cu")
		(net "P1V25_SERDES_VDDPLL_PEX1")
	)
	(segment
		(start 188.574934 -293.52494)
		(end 188.099954 -293.99992)
		(width 0.249936)
		(layer "F.Cu")
		(net "P1V25_SERDES_VDDPLL_PEX1")
	)
	(segment
		(start 180.975 -304.924714)
		(end 180.50002 -304.449734)
		(width 0.249936)
		(layer "F.Cu")
		(net "P1V25_SERDES_VDDPLL_PEX1")
	)
	(segment
		(start 172.424852 -304.924714)
		(end 172.900086 -304.449734)
		(width 0.249936)
		(layer "F.Cu")
		(net "P1V25_SERDES_VDDPLL_PEX1")
	)
	(segment
		(start 170.524932 -286.874966)
		(end 170.999912 -287.349946)
		(width 0.249936)
		(layer "F.Cu")
		(net "P1V25_SERDES_VDDPLL_PEX1")
	)
	(segment
		(start 166.725092 -286.874966)
		(end 167.200072 -287.349946)
		(width 0.249936)
		(layer "F.Cu")
		(net "P1V25_SERDES_VDDPLL_PEX1")
	)
	(segment
		(start 188.574934 -294.4749)
		(end 188.099954 -294.94988)
		(width 0.249936)
		(layer "F.Cu")
		(net "P1V25_SERDES_VDDPLL_PEX1")
	)
	(segment
		(start 169.574972 -286.874966)
		(end 170.049952 -287.349946)
		(width 0.249936)
		(layer "F.Cu")
		(net "P1V25_SERDES_VDDPLL_PEX1")
	)
	(segment
		(start 166.725092 -304.924714)
		(end 167.200072 -304.449734)
		(width 0.249936)
		(layer "F.Cu")
		(net "P1V25_SERDES_VDDPLL_PEX1")
	)
	(segment
		(start 179.07508 -286.874966)
		(end 178.599846 -287.349946)
		(width 0.249936)
		(layer "F.Cu")
		(net "P1V25_SERDES_VDDPLL_PEX1")
	)
	(segment
		(start 171.474892 -286.874966)
		(end 171.949872 -287.349946)
		(width 0.249936)
		(layer "F.Cu")
		(net "P1V25_SERDES_VDDPLL_PEX1")
	)
	(segment
		(start 174.325026 -304.924714)
		(end 174.800006 -304.449734)
		(width 0.249936)
		(layer "F.Cu")
		(net "P1V25_SERDES_VDDPLL_PEX1")
	)
	(segment
		(start 168.625012 -304.924714)
		(end 169.099992 -304.449734)
		(width 0.249936)
		(layer "F.Cu")
		(net "P1V25_SERDES_VDDPLL_PEX1")
	)
	(segment
		(start 188.574934 -297.32478)
		(end 188.099954 -296.8498)
		(width 0.249936)
		(layer "F.Cu")
		(net "P1V25_SERDES_VDDPLL_PEX1")
	)
	(segment
		(start 180.02504 -286.874966)
		(end 179.55006 -287.349946)
		(width 0.249936)
		(layer "F.Cu")
		(net "P1V25_SERDES_VDDPLL_PEX1")
	)
	(segment
		(start 173.375066 -286.874966)
		(end 173.850046 -287.349946)
		(width 0.249936)
		(layer "F.Cu")
		(net "P1V25_SERDES_VDDPLL_PEX1")
	)
	(via
		(at 169.574972 -286.874966)
		(size 0.4064)
		(drill 0.2032)
		(layers "F.Cu" "B.Cu")
		(net "P1V25_SERDES_VDDPLL_PEX1")
	)
	(via
		(at 224.815146 -259.50799)
		(size 0.508)
		(drill 0.254)
		(layers "F.Cu" "B.Cu")
		(net "P1V25_SERDES_VDDPLL_PEX1")
	)
	(via
		(at 166.725092 -304.924714)
		(size 0.4064)
		(drill 0.2032)
		(layers "F.Cu" "B.Cu")
		(net "P1V25_SERDES_VDDPLL_PEX1")
	)
	(via
		(at 182.87492 -304.924714)
		(size 0.4064)
		(drill 0.2032)
		(layers "F.Cu" "B.Cu")
		(net "P1V25_SERDES_VDDPLL_PEX1")
	)
	(via
		(at 166.725092 -286.874966)
		(size 0.4064)
		(drill 0.2032)
		(layers "F.Cu" "B.Cu")
		(net "P1V25_SERDES_VDDPLL_PEX1")
	)
	(via
		(at 180.02504 -286.874966)
		(size 0.4064)
		(drill 0.2032)
		(layers "F.Cu" "B.Cu")
		(net "P1V25_SERDES_VDDPLL_PEX1")
	)
	(via
		(at 227.047298 -259.894832)
		(size 0.508)
		(drill 0.254)
		(layers "F.Cu" "B.Cu")
		(net "P1V25_SERDES_VDDPLL_PEX1")
	)
	(via
		(at 188.574934 -296.37482)
		(size 0.4064)
		(drill 0.2032)
		(layers "F.Cu" "B.Cu")
		(net "P1V25_SERDES_VDDPLL_PEX1")
	)
	(via
		(at 220.194124 -258.762754)
		(size 0.508)
		(drill 0.254)
		(layers "F.Cu" "B.Cu")
		(net "P1V25_SERDES_VDDPLL_PEX1")
	)
	(via
		(at 177.174906 -304.924714)
		(size 0.4064)
		(drill 0.2032)
		(layers "F.Cu" "B.Cu")
		(net "P1V25_SERDES_VDDPLL_PEX1")
	)
	(via
		(at 180.975 -286.874966)
		(size 0.4064)
		(drill 0.2032)
		(layers "F.Cu" "B.Cu")
		(net "P1V25_SERDES_VDDPLL_PEX1")
	)
	(via
		(at 183.82488 -304.924714)
		(size 0.4064)
		(drill 0.2032)
		(layers "F.Cu" "B.Cu")
		(net "P1V25_SERDES_VDDPLL_PEX1")
	)
	(via
		(at 169.574972 -304.924714)
		(size 0.4064)
		(drill 0.2032)
		(layers "F.Cu" "B.Cu")
		(net "P1V25_SERDES_VDDPLL_PEX1")
	)
	(via
		(at 174.325026 -304.924714)
		(size 0.4064)
		(drill 0.2032)
		(layers "F.Cu" "B.Cu")
		(net "P1V25_SERDES_VDDPLL_PEX1")
	)
	(via
		(at 225.740722 -259.062474)
		(size 0.508)
		(drill 0.254)
		(layers "F.Cu" "B.Cu")
		(net "P1V25_SERDES_VDDPLL_PEX1")
	)
	(via
		(at 226.285298 -260.797548)
		(size 0.508)
		(drill 0.254)
		(layers "F.Cu" "B.Cu")
		(net "P1V25_SERDES_VDDPLL_PEX1")
	)
	(via
		(at 176.224946 -286.874966)
		(size 0.4064)
		(drill 0.2032)
		(layers "F.Cu" "B.Cu")
		(net "P1V25_SERDES_VDDPLL_PEX1")
	)
	(via
		(at 167.675052 -286.874966)
		(size 0.4064)
		(drill 0.2032)
		(layers "F.Cu" "B.Cu")
		(net "P1V25_SERDES_VDDPLL_PEX1")
	)
	(via
		(at 221.70263 -258.822952)
		(size 0.508)
		(drill 0.254)
		(layers "F.Cu" "B.Cu")
		(net "P1V25_SERDES_VDDPLL_PEX1")
	)
	(via
		(at 168.625012 -286.874966)
		(size 0.4064)
		(drill 0.2032)
		(layers "F.Cu" "B.Cu")
		(net "P1V25_SERDES_VDDPLL_PEX1")
	)
	(via
		(at 228.571298 -259.894832)
		(size 0.508)
		(drill 0.254)
		(layers "F.Cu" "B.Cu")
		(net "P1V25_SERDES_VDDPLL_PEX1")
	)
	(via
		(at 183.82488 -286.874966)
		(size 0.4064)
		(drill 0.2032)
		(layers "F.Cu" "B.Cu")
		(net "P1V25_SERDES_VDDPLL_PEX1")
	)
	(via
		(at 171.474892 -286.874966)
		(size 0.4064)
		(drill 0.2032)
		(layers "F.Cu" "B.Cu")
		(net "P1V25_SERDES_VDDPLL_PEX1")
	)
	(via
		(at 180.02504 -304.924714)
		(size 0.4064)
		(drill 0.2032)
		(layers "F.Cu" "B.Cu")
		(net "P1V25_SERDES_VDDPLL_PEX1")
	)
	(via
		(at 220.189298 -260.797548)
		(size 0.508)
		(drill 0.254)
		(layers "F.Cu" "B.Cu")
		(net "P1V25_SERDES_VDDPLL_PEX1")
	)
	(via
		(at 178.124866 -286.874966)
		(size 0.4064)
		(drill 0.2032)
		(layers "F.Cu" "B.Cu")
		(net "P1V25_SERDES_VDDPLL_PEX1")
	)
	(via
		(at 228.571298 -260.797548)
		(size 0.508)
		(drill 0.254)
		(layers "F.Cu" "B.Cu")
		(net "P1V25_SERDES_VDDPLL_PEX1")
	)
	(via
		(at 170.524932 -286.874966)
		(size 0.4064)
		(drill 0.2032)
		(layers "F.Cu" "B.Cu")
		(net "P1V25_SERDES_VDDPLL_PEX1")
	)
	(via
		(at 223.210882 -258.762754)
		(size 0.508)
		(drill 0.254)
		(layers "F.Cu" "B.Cu")
		(net "P1V25_SERDES_VDDPLL_PEX1")
	)
	(via
		(at 223.237298 -260.797548)
		(size 0.508)
		(drill 0.254)
		(layers "F.Cu" "B.Cu")
		(net "P1V25_SERDES_VDDPLL_PEX1")
	)
	(via
		(at 223.247458 -259.686298)
		(size 0.508)
		(drill 0.254)
		(layers "F.Cu" "B.Cu")
		(net "P1V25_SERDES_VDDPLL_PEX1")
	)
	(via
		(at 219.377006 -260.343396)
		(size 0.508)
		(drill 0.254)
		(layers "F.Cu" "B.Cu")
		(net "P1V25_SERDES_VDDPLL_PEX1")
	)
	(via
		(at 218.665298 -259.894832)
		(size 0.508)
		(drill 0.254)
		(layers "F.Cu" "B.Cu")
		(net "P1V25_SERDES_VDDPLL_PEX1")
	)
	(via
		(at 218.705938 -258.802886)
		(size 0.508)
		(drill 0.254)
		(layers "F.Cu" "B.Cu")
		(net "P1V25_SERDES_VDDPLL_PEX1")
	)
	(via
		(at 222.475298 -259.894832)
		(size 0.508)
		(drill 0.254)
		(layers "F.Cu" "B.Cu")
		(net "P1V25_SERDES_VDDPLL_PEX1")
	)
	(via
		(at 221.713298 -260.797548)
		(size 0.508)
		(drill 0.254)
		(layers "F.Cu" "B.Cu")
		(net "P1V25_SERDES_VDDPLL_PEX1")
	)
	(via
		(at 227.430076 -260.85419)
		(size 0.508)
		(drill 0.254)
		(layers "F.Cu" "B.Cu")
		(net "P1V25_SERDES_VDDPLL_PEX1")
	)
	(via
		(at 188.574934 -297.32478)
		(size 0.4064)
		(drill 0.2032)
		(layers "F.Cu" "B.Cu")
		(net "P1V25_SERDES_VDDPLL_PEX1")
	)
	(via
		(at 223.999298 -259.894832)
		(size 0.508)
		(drill 0.254)
		(layers "F.Cu" "B.Cu")
		(net "P1V25_SERDES_VDDPLL_PEX1")
	)
	(via
		(at 178.124866 -304.924714)
		(size 0.4064)
		(drill 0.2032)
		(layers "F.Cu" "B.Cu")
		(net "P1V25_SERDES_VDDPLL_PEX1")
	)
	(via
		(at 172.424852 -286.874966)
		(size 0.4064)
		(drill 0.2032)
		(layers "F.Cu" "B.Cu")
		(net "P1V25_SERDES_VDDPLL_PEX1")
	)
	(via
		(at 188.574934 -298.27474)
		(size 0.4064)
		(drill 0.2032)
		(layers "F.Cu" "B.Cu")
		(net "P1V25_SERDES_VDDPLL_PEX1")
	)
	(via
		(at 219.444824 -259.273802)
		(size 0.508)
		(drill 0.254)
		(layers "F.Cu" "B.Cu")
		(net "P1V25_SERDES_VDDPLL_PEX1")
	)
	(via
		(at 179.07508 -304.924714)
		(size 0.4064)
		(drill 0.2032)
		(layers "F.Cu" "B.Cu")
		(net "P1V25_SERDES_VDDPLL_PEX1")
	)
	(via
		(at 180.975 -304.924714)
		(size 0.4064)
		(drill 0.2032)
		(layers "F.Cu" "B.Cu")
		(net "P1V25_SERDES_VDDPLL_PEX1")
	)
	(via
		(at 174.325026 -286.874966)
		(size 0.4064)
		(drill 0.2032)
		(layers "F.Cu" "B.Cu")
		(net "P1V25_SERDES_VDDPLL_PEX1")
	)
	(via
		(at 173.375066 -304.924714)
		(size 0.4064)
		(drill 0.2032)
		(layers "F.Cu" "B.Cu")
		(net "P1V25_SERDES_VDDPLL_PEX1")
	)
	(via
		(at 218.665298 -260.797548)
		(size 0.508)
		(drill 0.254)
		(layers "F.Cu" "B.Cu")
		(net "P1V25_SERDES_VDDPLL_PEX1")
	)
	(via
		(at 171.474892 -304.924714)
		(size 0.4064)
		(drill 0.2032)
		(layers "F.Cu" "B.Cu")
		(net "P1V25_SERDES_VDDPLL_PEX1")
	)
	(via
		(at 226.859338 -259.08635)
		(size 0.508)
		(drill 0.254)
		(layers "F.Cu" "B.Cu")
		(net "P1V25_SERDES_VDDPLL_PEX1")
	)
	(via
		(at 225.523298 -259.894832)
		(size 0.508)
		(drill 0.254)
		(layers "F.Cu" "B.Cu")
		(net "P1V25_SERDES_VDDPLL_PEX1")
	)
	(via
		(at 177.174906 -286.874966)
		(size 0.4064)
		(drill 0.2032)
		(layers "F.Cu" "B.Cu")
		(net "P1V25_SERDES_VDDPLL_PEX1")
	)
	(via
		(at 188.574934 -293.52494)
		(size 0.4064)
		(drill 0.2032)
		(layers "F.Cu" "B.Cu")
		(net "P1V25_SERDES_VDDPLL_PEX1")
	)
	(via
		(at 172.424852 -304.924714)
		(size 0.4064)
		(drill 0.2032)
		(layers "F.Cu" "B.Cu")
		(net "P1V25_SERDES_VDDPLL_PEX1")
	)
	(via
		(at 182.87492 -286.874966)
		(size 0.4064)
		(drill 0.2032)
		(layers "F.Cu" "B.Cu")
		(net "P1V25_SERDES_VDDPLL_PEX1")
	)
	(via
		(at 181.92496 -304.924714)
		(size 0.4064)
		(drill 0.2032)
		(layers "F.Cu" "B.Cu")
		(net "P1V25_SERDES_VDDPLL_PEX1")
	)
	(via
		(at 221.251526 -259.870956)
		(size 0.508)
		(drill 0.254)
		(layers "F.Cu" "B.Cu")
		(net "P1V25_SERDES_VDDPLL_PEX1")
	)
	(via
		(at 167.675052 -304.924714)
		(size 0.4064)
		(drill 0.2032)
		(layers "F.Cu" "B.Cu")
		(net "P1V25_SERDES_VDDPLL_PEX1")
	)
	(via
		(at 176.224946 -304.924714)
		(size 0.4064)
		(drill 0.2032)
		(layers "F.Cu" "B.Cu")
		(net "P1V25_SERDES_VDDPLL_PEX1")
	)
	(via
		(at 170.524932 -304.924714)
		(size 0.4064)
		(drill 0.2032)
		(layers "F.Cu" "B.Cu")
		(net "P1V25_SERDES_VDDPLL_PEX1")
	)
	(via
		(at 179.07508 -286.874966)
		(size 0.4064)
		(drill 0.2032)
		(layers "F.Cu" "B.Cu")
		(net "P1V25_SERDES_VDDPLL_PEX1")
	)
	(via
		(at 228.020118 -259.05841)
		(size 0.508)
		(drill 0.254)
		(layers "F.Cu" "B.Cu")
		(net "P1V25_SERDES_VDDPLL_PEX1")
	)
	(via
		(at 168.625012 -304.924714)
		(size 0.4064)
		(drill 0.2032)
		(layers "F.Cu" "B.Cu")
		(net "P1V25_SERDES_VDDPLL_PEX1")
	)
	(via
		(at 188.574934 -294.4749)
		(size 0.4064)
		(drill 0.2032)
		(layers "F.Cu" "B.Cu")
		(net "P1V25_SERDES_VDDPLL_PEX1")
	)
	(via
		(at 173.375066 -286.874966)
		(size 0.4064)
		(drill 0.2032)
		(layers "F.Cu" "B.Cu")
		(net "P1V25_SERDES_VDDPLL_PEX1")
	)
	(via
		(at 224.761298 -260.797548)
		(size 0.508)
		(drill 0.254)
		(layers "F.Cu" "B.Cu")
		(net "P1V25_SERDES_VDDPLL_PEX1")
	)
	(via
		(at 220.914214 -260.57733)
		(size 0.508)
		(drill 0.254)
		(layers "F.Cu" "B.Cu")
		(net "P1V25_SERDES_VDDPLL_PEX1")
	)
	(via
		(at 181.92496 -286.874966)
		(size 0.4064)
		(drill 0.2032)
		(layers "F.Cu" "B.Cu")
		(net "P1V25_SERDES_VDDPLL_PEX1")
	)
	(via
		(at 220.189298 -259.894832)
		(size 0.508)
		(drill 0.254)
		(layers "F.Cu" "B.Cu")
		(net "P1V25_SERDES_VDDPLL_PEX1")
	)
	(segment
		(start 226.34702 -307.768498)
		(end 227.124006 -307.446426)
		(width 0.1778)
		(layer "F.Cu")
		(net "P1V25_PEX1_CS")
	)
	(segment
		(start 227.621846 -307.081682)
		(end 227.257102 -307.446426)
		(width 0.254)
		(layer "F.Cu")
		(net "P1V25_PEX1_CS")
	)
	(segment
		(start 227.946458 -307.081682)
		(end 227.621846 -307.081682)
		(width 0.254)
		(layer "F.Cu")
		(net "P1V25_PEX1_CS")
	)
	(segment
		(start 227.124006 -307.446426)
		(end 227.257102 -307.446426)
		(width 0.1778)
		(layer "F.Cu")
		(net "P1V25_PEX1_CS")
	)
	(segment
		(start 225.91903 -307.768498)
		(end 226.34702 -307.768498)
		(width 0.1778)
		(layer "F.Cu")
		(net "P1V25_PEX1_CS")
	)
	(via
		(at 227.257102 -307.446426)
		(size 0.508)
		(drill 0.254)
		(layers "F.Cu" "B.Cu")
		(net "P1V25_PEX1_CS")
	)
	(segment
		(start 119.116094 -253.594362)
		(end 119.116094 -254.953008)
		(width 0.1524)
		(layer "F.Cu")
		(net "P0V8_PEX1_PWM2")
	)
	(segment
		(start 130.531108 -281.999182)
		(end 130.531108 -281.438858)
		(width 0.2032)
		(layer "F.Cu")
		(net "P0V8_PEX1_PWM2")
	)
	(segment
		(start 119.233442 -253.477014)
		(end 119.116094 -253.594362)
		(width 0.1524)
		(layer "F.Cu")
		(net "P0V8_PEX1_PWM2")
	)
	(segment
		(start 130.60934 -280.897838)
		(end 130.734562 -280.617168)
		(width 0.2032)
		(layer "F.Cu")
		(net "P0V8_PEX1_PWM2")
	)
	(segment
		(start 130.60934 -281.249882)
		(end 130.60934 -280.897838)
		(width 0.2032)
		(layer "F.Cu")
		(net "P0V8_PEX1_PWM2")
	)
	(segment
		(start 130.531108 -281.438858)
		(end 130.60934 -281.249882)
		(width 0.2032)
		(layer "F.Cu")
		(net "P0V8_PEX1_PWM2")
	)
	(segment
		(start 119.116094 -254.953008)
		(end 119.375682 -255.212596)
		(width 0.1524)
		(layer "F.Cu")
		(net "P0V8_PEX1_PWM2")
	)
	(segment
		(start 119.233442 -252.63094)
		(end 119.233442 -253.477014)
		(width 0.1524)
		(layer "F.Cu")
		(net "P0V8_PEX1_PWM2")
	)
	(segment
		(start 119.375682 -255.212596)
		(end 119.375682 -255.994916)
		(width 0.1524)
		(layer "F.Cu")
		(net "P0V8_PEX1_PWM2")
	)
	(segment
		(start 120.654572 -252.112272)
		(end 119.75211 -252.112272)
		(width 0.1524)
		(layer "F.Cu")
		(net "P0V8_PEX1_PWM2")
	)
	(segment
		(start 119.75211 -252.112272)
		(end 119.233442 -252.63094)
		(width 0.1524)
		(layer "F.Cu")
		(net "P0V8_PEX1_PWM2")
	)
	(via
		(at 120.654572 -252.112272)
		(size 0.508)
		(drill 0.254)
		(layers "F.Cu" "B.Cu")
		(net "P0V8_PEX1_PWM2")
	)
	(via
		(at 130.734562 -280.617168)
		(size 0.508)
		(drill 0.254)
		(layers "F.Cu" "B.Cu")
		(net "P0V8_PEX1_PWM2")
	)
	(segment
		(start 124.705364 -253.595378)
		(end 124.705364 -256.711196)
		(width 0.2032)
		(layer "In5.Cu")
		(net "P0V8_PEX1_PWM2")
	)
	(segment
		(start 120.654572 -252.112272)
		(end 123.222258 -252.112272)
		(width 0.2032)
		(layer "In5.Cu")
		(net "P0V8_PEX1_PWM2")
	)
	(segment
		(start 125.720348 -260.846062)
		(end 131.705096 -266.83081)
		(width 0.2032)
		(layer "In5.Cu")
		(net "P0V8_PEX1_PWM2")
	)
	(segment
		(start 125.720348 -257.72618)
		(end 125.720348 -260.846062)
		(width 0.2032)
		(layer "In5.Cu")
		(net "P0V8_PEX1_PWM2")
	)
	(segment
		(start 130.734562 -278.797766)
		(end 130.734562 -280.617168)
		(width 0.2032)
		(layer "In5.Cu")
		(net "P0V8_PEX1_PWM2")
	)
	(segment
		(start 131.705096 -266.83081)
		(end 131.705096 -277.827232)
		(width 0.2032)
		(layer "In5.Cu")
		(net "P0V8_PEX1_PWM2")
	)
	(segment
		(start 124.705364 -256.711196)
		(end 125.720348 -257.72618)
		(width 0.2032)
		(layer "In5.Cu")
		(net "P0V8_PEX1_PWM2")
	)
	(segment
		(start 123.222258 -252.112272)
		(end 124.705364 -253.595378)
		(width 0.2032)
		(layer "In5.Cu")
		(net "P0V8_PEX1_PWM2")
	)
	(segment
		(start 131.705096 -277.827232)
		(end 130.734562 -278.797766)
		(width 0.2032)
		(layer "In5.Cu")
		(net "P0V8_PEX1_PWM2")
	)
	(segment
		(start 356.082854 -255.445514)
		(end 356.91572 -254.612648)
		(width 0.13208)
		(layer "F.Cu")
		(net "SMB_VR_P0V8_PEX2_SCL")
	)
	(segment
		(start 356.91572 -253.092204)
		(end 356.91572 -254.126238)
		(width 0.13208)
		(layer "F.Cu")
		(net "SMB_VR_P0V8_PEX2_SCL")
	)
	(segment
		(start 354.957634 -255.445514)
		(end 356.082854 -255.445514)
		(width 0.13208)
		(layer "F.Cu")
		(net "SMB_VR_P0V8_PEX2_SCL")
	)
	(segment
		(start 356.91572 -254.612648)
		(end 356.91572 -254.126238)
		(width 0.13208)
		(layer "F.Cu")
		(net "SMB_VR_P0V8_PEX2_SCL")
	)
	(segment
		(start 357.19131 -252.816614)
		(end 356.91572 -253.092204)
		(width 0.13208)
		(layer "F.Cu")
		(net "SMB_VR_P0V8_PEX2_SCL")
	)
	(segment
		(start 354.776024 -255.627124)
		(end 354.957634 -255.445514)
		(width 0.13208)
		(layer "F.Cu")
		(net "SMB_VR_P0V8_PEX2_SCL")
	)
	(segment
		(start 354.776024 -255.994916)
		(end 354.776024 -255.627124)
		(width 0.13208)
		(layer "F.Cu")
		(net "SMB_VR_P0V8_PEX2_SCL")
	)
	(via
		(at 356.91572 -254.126238)
		(size 0.762)
		(drill 0.381)
		(layers "F.Cu" "B.Cu")
		(net "SMB_VR_P0V8_PEX2_SCL")
	)
	(segment
		(start 421.249856 -301.599854)
		(end 420.774876 -302.074834)
		(width 0.127)
		(layer "F.Cu")
		(net "VSENSE_P0V8_PEX3_SKT_VRTN")
	)
	(via
		(at 369.007136 -327.431908)
		(size 0.6604)
		(drill 0.3302)
		(layers "F.Cu" "B.Cu")
		(net "VSENSE_P0V8_PEX3_SKT_VRTN")
	)
	(via
		(at 420.774876 -302.074834)
		(size 0.4064)
		(drill 0.2032)
		(layers "F.Cu" "B.Cu")
		(net "VSENSE_P0V8_PEX3_SKT_VRTN")
	)
	(segment
		(start 407.284428 -320.657982)
		(end 407.284428 -320.294)
		(width 0.254)
		(layer "B.Cu")
		(net "VSENSE_P0V8_PEX3_SKT_VRTN")
	)
	(segment
		(start 407.284428 -320.255392)
		(end 407.368248 -320.171572)
		(width 0.09906)
		(layer "B.Cu")
		(net "VSENSE_P0V8_PEX3_SKT_VRTN")
	)
	(segment
		(start 408.096212 -307.193188)
		(end 419.043612 -307.193188)
		(width 0.09906)
		(layer "B.Cu")
		(net "VSENSE_P0V8_PEX3_SKT_VRTN")
	)
	(segment
		(start 407.368248 -320.171572)
		(end 407.368248 -307.921152)
		(width 0.09906)
		(layer "B.Cu")
		(net "VSENSE_P0V8_PEX3_SKT_VRTN")
	)
	(segment
		(start 369.007136 -327.431908)
		(end 369.286282 -327.711054)
		(width 0.254)
		(layer "B.Cu")
		(net "VSENSE_P0V8_PEX3_SKT_VRTN")
	)
	(segment
		(start 369.286282 -327.711054)
		(end 390.686036 -327.711054)
		(width 0.254)
		(layer "B.Cu")
		(net "VSENSE_P0V8_PEX3_SKT_VRTN")
	)
	(segment
		(start 419.505638 -302.443134)
		(end 421.014144 -302.443134)
		(width 0.09906)
		(layer "B.Cu")
		(net "VSENSE_P0V8_PEX3_SKT_VRTN")
	)
	(segment
		(start 419.243256 -302.705516)
		(end 419.505638 -302.443134)
		(width 0.09906)
		(layer "B.Cu")
		(net "VSENSE_P0V8_PEX3_SKT_VRTN")
	)
	(segment
		(start 406.980898 -320.961512)
		(end 407.284428 -320.657982)
		(width 0.254)
		(layer "B.Cu")
		(net "VSENSE_P0V8_PEX3_SKT_VRTN")
	)
	(segment
		(start 368.72799 -327.711054)
		(end 369.007136 -327.431908)
		(width 0.254)
		(layer "B.Cu")
		(net "VSENSE_P0V8_PEX3_SKT_VRTN")
	)
	(segment
		(start 419.243256 -306.993544)
		(end 419.243256 -302.705516)
		(width 0.09906)
		(layer "B.Cu")
		(net "VSENSE_P0V8_PEX3_SKT_VRTN")
	)
	(segment
		(start 407.368248 -307.921152)
		(end 408.096212 -307.193188)
		(width 0.09906)
		(layer "B.Cu")
		(net "VSENSE_P0V8_PEX3_SKT_VRTN")
	)
	(segment
		(start 421.143176 -302.173894)
		(end 421.044116 -302.074834)
		(width 0.09906)
		(layer "B.Cu")
		(net "VSENSE_P0V8_PEX3_SKT_VRTN")
	)
	(segment
		(start 421.044116 -302.074834)
		(end 420.774876 -302.074834)
		(width 0.09906)
		(layer "B.Cu")
		(net "VSENSE_P0V8_PEX3_SKT_VRTN")
	)
	(segment
		(start 421.014144 -302.443134)
		(end 421.143176 -302.314102)
		(width 0.09906)
		(layer "B.Cu")
		(net "VSENSE_P0V8_PEX3_SKT_VRTN")
	)
	(segment
		(start 419.043612 -307.193188)
		(end 419.243256 -306.993544)
		(width 0.09906)
		(layer "B.Cu")
		(net "VSENSE_P0V8_PEX3_SKT_VRTN")
	)
	(segment
		(start 407.284428 -320.294)
		(end 407.284428 -320.255392)
		(width 0.09906)
		(layer "B.Cu")
		(net "VSENSE_P0V8_PEX3_SKT_VRTN")
	)
	(segment
		(start 367.22304 -327.711054)
		(end 368.72799 -327.711054)
		(width 0.254)
		(layer "B.Cu")
		(net "VSENSE_P0V8_PEX3_SKT_VRTN")
	)
	(segment
		(start 390.686036 -327.711054)
		(end 406.980898 -320.961512)
		(width 0.254)
		(layer "B.Cu")
		(net "VSENSE_P0V8_PEX3_SKT_VRTN")
	)
	(segment
		(start 366.892586 -327.3552)
		(end 367.22304 -327.711054)
		(width 0.254)
		(layer "B.Cu")
		(net "VSENSE_P0V8_PEX3_SKT_VRTN")
	)
	(segment
		(start 421.143176 -302.314102)
		(end 421.143176 -302.173894)
		(width 0.09906)
		(layer "B.Cu")
		(net "VSENSE_P0V8_PEX3_SKT_VRTN")
	)
	(segment
		(start 119.775732 -260.795008)
		(end 119.775732 -261.488428)
		(width 0.13208)
		(layer "F.Cu")
		(net "NC_P0V8_PEX0_ISEN2")
	)
	(via
		(at 119.775732 -261.488428)
		(size 0.508)
		(drill 0.254)
		(layers "F.Cu" "B.Cu")
		(net "NC_P0V8_PEX0_ISEN2")
	)
	(via
		(at 120.384316 -260.909308)
		(size 0.6604)
		(drill 0.3302)
		(layers "F.Cu" "B.Cu")
		(net "NC_P0V8_PEX0_ISEN2")
	)
	(segment
		(start 121.642378 -260.909308)
		(end 120.384316 -260.909308)
		(width 0.13208)
		(layer "B.Cu")
		(net "NC_P0V8_PEX0_ISEN2")
	)
	(segment
		(start 120.384316 -260.909308)
		(end 120.354852 -260.909308)
		(width 0.13208)
		(layer "B.Cu")
		(net "NC_P0V8_PEX0_ISEN2")
	)
	(segment
		(start 120.354852 -260.909308)
		(end 119.775732 -261.488428)
		(width 0.13208)
		(layer "B.Cu")
		(net "NC_P0V8_PEX0_ISEN2")
	)
	(segment
		(start 346.16136 -262.703564)
		(end 346.16136 -261.687564)
		(width 0.254)
		(layer "F.Cu")
		(net "P0V8_PEX2_VR_CONFIG")
	)
	(segment
		(start 346.722446 -261.217664)
		(end 346.983812 -260.956298)
		(width 0.254)
		(layer "F.Cu")
		(net "P0V8_PEX2_VR_CONFIG")
	)
	(segment
		(start 346.983812 -260.956298)
		(end 346.983812 -260.047994)
		(width 0.254)
		(layer "F.Cu")
		(net "P0V8_PEX2_VR_CONFIG")
	)
	(segment
		(start 347.376242 -259.655564)
		(end 349.81007 -259.655564)
		(width 0.1524)
		(layer "F.Cu")
		(net "P0V8_PEX2_VR_CONFIG")
	)
	(segment
		(start 350.070674 -259.39496)
		(end 350.57588 -259.39496)
		(width 0.1524)
		(layer "F.Cu")
		(net "P0V8_PEX2_VR_CONFIG")
	)
	(segment
		(start 346.16136 -261.687564)
		(end 346.252546 -261.687564)
		(width 0.254)
		(layer "F.Cu")
		(net "P0V8_PEX2_VR_CONFIG")
	)
	(segment
		(start 346.983812 -260.047994)
		(end 347.376242 -259.655564)
		(width 0.1524)
		(layer "F.Cu")
		(net "P0V8_PEX2_VR_CONFIG")
	)
	(segment
		(start 349.81007 -259.655564)
		(end 350.070674 -259.39496)
		(width 0.1524)
		(layer "F.Cu")
		(net "P0V8_PEX2_VR_CONFIG")
	)
	(segment
		(start 346.252546 -261.687564)
		(end 346.722446 -261.217664)
		(width 0.254)
		(layer "F.Cu")
		(net "P0V8_PEX2_VR_CONFIG")
	)
	(via
		(at 346.722446 -261.217664)
		(size 0.508)
		(drill 0.254)
		(layers "F.Cu" "B.Cu")
		(net "P0V8_PEX2_VR_CONFIG")
	)
	(segment
		(start 348.242636 -257.13055)
		(end 348.877636 -257.13055)
		(width 0.254)
		(layer "F.Cu")
		(net "P0V8_PEX2_VINSEN")
	)
	(segment
		(start 349.14205 -257.394964)
		(end 350.57588 -257.394964)
		(width 0.2032)
		(layer "F.Cu")
		(net "P0V8_PEX2_VINSEN")
	)
	(segment
		(start 348.877636 -257.13055)
		(end 349.14205 -257.394964)
		(width 0.2032)
		(layer "F.Cu")
		(net "P0V8_PEX2_VINSEN")
	)
	(via
		(at 348.877636 -257.13055)
		(size 0.508)
		(drill 0.254)
		(layers "F.Cu" "B.Cu")
		(net "P0V8_PEX2_VINSEN")
	)
	(segment
		(start 347.66631 -256.626614)
		(end 348.3737 -256.626614)
		(width 0.254)
		(layer "B.Cu")
		(net "P0V8_PEX2_VINSEN")
	)
	(segment
		(start 348.3737 -256.626614)
		(end 348.877636 -257.13055)
		(width 0.254)
		(layer "B.Cu")
		(net "P0V8_PEX2_VINSEN")
	)
	(segment
		(start 346.65031 -256.626614)
		(end 347.66631 -256.626614)
		(width 0.254)
		(layer "B.Cu")
		(net "P0V8_PEX2_VINSEN")
	)
	(segment
		(start 104.309672 -280.84907)
		(end 104.811576 -281.350974)
		(width 0.2286)
		(layer "F.Cu")
		(net "SW_P0V8_PEX0_PHASE1")
	)
	(segment
		(start 104.811576 -281.350974)
		(end 104.811576 -281.999182)
		(width 0.2286)
		(layer "F.Cu")
		(net "SW_P0V8_PEX0_PHASE1")
	)
	(segment
		(start 107.061508 -281.657298)
		(end 107.52836 -280.530046)
		(width 0.1524)
		(layer "F.Cu")
		(net "P0V8_PEX0_LSET1")
	)
	(segment
		(start 107.323128 -280.295858)
		(end 107.52836 -280.50109)
		(width 0.1524)
		(layer "F.Cu")
		(net "P0V8_PEX0_LSET1")
	)
	(segment
		(start 107.061508 -281.999182)
		(end 107.061508 -281.657298)
		(width 0.1524)
		(layer "F.Cu")
		(net "P0V8_PEX0_LSET1")
	)
	(segment
		(start 107.52836 -280.530046)
		(end 107.52836 -280.50109)
		(width 0.1524)
		(layer "F.Cu")
		(net "P0V8_PEX0_LSET1")
	)
	(segment
		(start 107.323128 -279.886918)
		(end 107.323128 -280.295858)
		(width 0.1524)
		(layer "F.Cu")
		(net "P0V8_PEX0_LSET1")
	)
	(via
		(at 107.52836 -280.50109)
		(size 0.508)
		(drill 0.254)
		(layers "F.Cu" "B.Cu")
		(net "P0V8_PEX0_LSET1")
	)
	(segment
		(start 105.27157 -280.04897)
		(end 104.309672 -280.04897)
		(width 0.254)
		(layer "F.Cu")
		(net "SW_P0V8_PEX0_BOOT1_R")
	)
	(segment
		(start 112.972088 -281.350974)
		(end 112.972088 -281.999182)
		(width 0.2286)
		(layer "F.Cu")
		(net "SW_P0V8_PEX0_PHASE2")
	)
	(segment
		(start 112.470184 -280.84907)
		(end 112.972088 -281.350974)
		(width 0.2286)
		(layer "F.Cu")
		(net "SW_P0V8_PEX0_PHASE2")
	)
	(segment
		(start 125.322838 -282.293314)
		(end 125.246384 -282.477718)
		(width 0.2286)
		(layer "F.Cu")
		(net "SW_P0V8_PEX1_VOS1")
	)
	(segment
		(start 125.10008 -282.624022)
		(end 125.030738 -282.624022)
		(width 0.2286)
		(layer "F.Cu")
		(net "SW_P0V8_PEX1_VOS1")
	)
	(segment
		(start 125.322838 -281.963368)
		(end 125.322838 -282.293314)
		(width 0.2286)
		(layer "F.Cu")
		(net "SW_P0V8_PEX1_VOS1")
	)
	(segment
		(start 125.246384 -282.477718)
		(end 125.10008 -282.624022)
		(width 0.2286)
		(layer "F.Cu")
		(net "SW_P0V8_PEX1_VOS1")
	)
	(via
		(at 125.322838 -281.963368)
		(size 0.508)
		(drill 0.254)
		(layers "F.Cu" "B.Cu")
		(net "SW_P0V8_PEX1_VOS1")
	)
	(segment
		(start 126.078488 -282.440634)
		(end 125.97892 -282.341066)
		(width 0.254)
		(layer "B.Cu")
		(net "SW_P0V8_PEX1_VOS1")
	)
	(segment
		(start 125.97892 -282.341066)
		(end 125.700536 -282.341066)
		(width 0.254)
		(layer "B.Cu")
		(net "SW_P0V8_PEX1_VOS1")
	)
	(segment
		(start 125.700536 -282.341066)
		(end 125.322838 -281.963368)
		(width 0.254)
		(layer "B.Cu")
		(net "SW_P0V8_PEX1_VOS1")
	)
	(segment
		(start 133.48335 -282.293314)
		(end 133.406896 -282.477718)
		(width 0.2286)
		(layer "F.Cu")
		(net "SW_P0V8_PEX1_VOS2")
	)
	(segment
		(start 133.48335 -281.963368)
		(end 133.48335 -282.293314)
		(width 0.2286)
		(layer "F.Cu")
		(net "SW_P0V8_PEX1_VOS2")
	)
	(segment
		(start 133.406896 -282.477718)
		(end 133.260592 -282.624022)
		(width 0.2286)
		(layer "F.Cu")
		(net "SW_P0V8_PEX1_VOS2")
	)
	(segment
		(start 133.260592 -282.624022)
		(end 133.19125 -282.624022)
		(width 0.2286)
		(layer "F.Cu")
		(net "SW_P0V8_PEX1_VOS2")
	)
	(via
		(at 133.48335 -281.963368)
		(size 0.508)
		(drill 0.254)
		(layers "F.Cu" "B.Cu")
		(net "SW_P0V8_PEX1_VOS2")
	)
	(segment
		(start 134.239 -282.440634)
		(end 134.134606 -282.33624)
		(width 0.254)
		(layer "B.Cu")
		(net "SW_P0V8_PEX1_VOS2")
	)
	(segment
		(start 133.856222 -282.33624)
		(end 133.48335 -281.963368)
		(width 0.254)
		(layer "B.Cu")
		(net "SW_P0V8_PEX1_VOS2")
	)
	(segment
		(start 134.134606 -282.33624)
		(end 133.856222 -282.33624)
		(width 0.254)
		(layer "B.Cu")
		(net "SW_P0V8_PEX1_VOS2")
	)
	(segment
		(start 121.470674 -281.350974)
		(end 121.470674 -281.999182)
		(width 0.2286)
		(layer "F.Cu")
		(net "SW_P0V8_PEX1_PHASE1")
	)
	(segment
		(start 120.96877 -280.84907)
		(end 121.470674 -281.350974)
		(width 0.2286)
		(layer "F.Cu")
		(net "SW_P0V8_PEX1_PHASE1")
	)
	(segment
		(start 133.627114 -283.524198)
		(end 134.329678 -282.821634)
		(width 0.2286)
		(layer "F.Cu")
		(net "P0V8_PEX1_VCC2")
	)
	(segment
		(start 134.329678 -282.821634)
		(end 134.366 -282.821634)
		(width 0.2286)
		(layer "F.Cu")
		(net "P0V8_PEX1_VCC2")
	)
	(segment
		(start 133.19125 -283.524198)
		(end 133.627114 -283.524198)
		(width 0.2286)
		(layer "F.Cu")
		(net "P0V8_PEX1_VCC2")
	)
	(segment
		(start 134.366 -282.821634)
		(end 134.414514 -282.870148)
		(width 0.254)
		(layer "F.Cu")
		(net "P0V8_PEX1_VCC2")
	)
	(segment
		(start 134.414514 -282.870148)
		(end 134.414514 -283.437584)
		(width 0.254)
		(layer "F.Cu")
		(net "P0V8_PEX1_VCC2")
	)
	(via
		(at 134.414514 -283.437584)
		(size 0.508)
		(drill 0.254)
		(layers "F.Cu" "B.Cu")
		(net "P0V8_PEX1_VCC2")
	)
	(segment
		(start 132.8928 -282.580334)
		(end 133.731 -283.418534)
		(width 0.254)
		(layer "B.Cu")
		(net "P0V8_PEX1_VCC2")
	)
	(segment
		(start 132.8928 -282.573222)
		(end 132.8928 -282.580334)
		(width 0.254)
		(layer "B.Cu")
		(net "P0V8_PEX1_VCC2")
	)
	(segment
		(start 132.8928 -282.573222)
		(end 132.622798 -282.30322)
		(width 0.254)
		(layer "B.Cu")
		(net "P0V8_PEX1_VCC2")
	)
	(segment
		(start 133.75005 -283.437584)
		(end 133.731 -283.418534)
		(width 0.254)
		(layer "B.Cu")
		(net "P0V8_PEX1_VCC2")
	)
	(segment
		(start 132.622798 -282.30322)
		(end 132.498084 -282.30322)
		(width 0.254)
		(layer "B.Cu")
		(net "P0V8_PEX1_VCC2")
	)
	(segment
		(start 134.414514 -283.437584)
		(end 133.75005 -283.437584)
		(width 0.254)
		(layer "B.Cu")
		(net "P0V8_PEX1_VCC2")
	)
	(segment
		(start 132.354066 -282.159202)
		(end 132.027676 -282.159202)
		(width 0.254)
		(layer "B.Cu")
		(net "P0V8_PEX1_VCC2")
	)
	(segment
		(start 132.498084 -282.30322)
		(end 132.354066 -282.159202)
		(width 0.254)
		(layer "B.Cu")
		(net "P0V8_PEX1_VCC2")
	)
	(segment
		(start 132.027676 -282.159202)
		(end 131.92379 -282.263088)
		(width 0.254)
		(layer "B.Cu")
		(net "P0V8_PEX1_VCC2")
	)
	(via
		(at 125.476762 -276.046184)
		(size 0.508)
		(drill 0.254)
		(layers "F.Cu" "B.Cu")
		(net "SW_P12V_P0V8_PEX1_FLT")
	)
	(via
		(at 128.17094 -281.431238)
		(size 0.508)
		(drill 0.254)
		(layers "F.Cu" "B.Cu")
		(net "SW_P12V_P0V8_PEX1_FLT")
	)
	(via
		(at 120.603772 -283.489654)
		(size 0.508)
		(drill 0.254)
		(layers "F.Cu" "B.Cu")
		(net "SW_P12V_P0V8_PEX1_FLT")
	)
	(via
		(at 121.543318 -275.392896)
		(size 0.508)
		(drill 0.254)
		(layers "F.Cu" "B.Cu")
		(net "SW_P12V_P0V8_PEX1_FLT")
	)
	(via
		(at 120.603772 -284.175454)
		(size 0.508)
		(drill 0.254)
		(layers "F.Cu" "B.Cu")
		(net "SW_P12V_P0V8_PEX1_FLT")
	)
	(via
		(at 121.327418 -282.866592)
		(size 0.508)
		(drill 0.254)
		(layers "F.Cu" "B.Cu")
		(net "SW_P12V_P0V8_PEX1_FLT")
	)
	(via
		(at 120.908318 -274.757896)
		(size 0.508)
		(drill 0.254)
		(layers "F.Cu" "B.Cu")
		(net "SW_P12V_P0V8_PEX1_FLT")
	)
	(via
		(at 120.484392 -276.903434)
		(size 0.508)
		(drill 0.254)
		(layers "F.Cu" "B.Cu")
		(net "SW_P12V_P0V8_PEX1_FLT")
	)
	(via
		(at 120.010428 -281.431238)
		(size 0.508)
		(drill 0.254)
		(layers "F.Cu" "B.Cu")
		(net "SW_P12V_P0V8_PEX1_FLT")
	)
	(via
		(at 127.465074 -276.933152)
		(size 0.508)
		(drill 0.254)
		(layers "F.Cu" "B.Cu")
		(net "SW_P12V_P0V8_PEX1_FLT")
	)
	(via
		(at 120.908318 -276.027896)
		(size 0.508)
		(drill 0.254)
		(layers "F.Cu" "B.Cu")
		(net "SW_P12V_P0V8_PEX1_FLT")
	)
	(via
		(at 130.12293 -282.866592)
		(size 0.508)
		(drill 0.254)
		(layers "F.Cu" "B.Cu")
		(net "SW_P12V_P0V8_PEX1_FLT")
	)
	(via
		(at 128.19634 -282.091638)
		(size 0.508)
		(drill 0.254)
		(layers "F.Cu" "B.Cu")
		(net "SW_P12V_P0V8_PEX1_FLT")
	)
	(via
		(at 126.111762 -276.046184)
		(size 0.508)
		(drill 0.254)
		(layers "F.Cu" "B.Cu")
		(net "SW_P12V_P0V8_PEX1_FLT")
	)
	(via
		(at 119.477028 -281.786838)
		(size 0.508)
		(drill 0.254)
		(layers "F.Cu" "B.Cu")
		(net "SW_P12V_P0V8_PEX1_FLT")
	)
	(via
		(at 121.543318 -276.027896)
		(size 0.508)
		(drill 0.254)
		(layers "F.Cu" "B.Cu")
		(net "SW_P12V_P0V8_PEX1_FLT")
	)
	(via
		(at 121.962418 -282.866592)
		(size 0.508)
		(drill 0.254)
		(layers "F.Cu" "B.Cu")
		(net "SW_P12V_P0V8_PEX1_FLT")
	)
	(via
		(at 127.10414 -282.167838)
		(size 0.508)
		(drill 0.254)
		(layers "F.Cu" "B.Cu")
		(net "SW_P12V_P0V8_PEX1_FLT")
	)
	(via
		(at 127.381762 -275.411184)
		(size 0.508)
		(drill 0.254)
		(layers "F.Cu" "B.Cu")
		(net "SW_P12V_P0V8_PEX1_FLT")
	)
	(via
		(at 129.48793 -282.866592)
		(size 0.508)
		(drill 0.254)
		(layers "F.Cu" "B.Cu")
		(net "SW_P12V_P0V8_PEX1_FLT")
	)
	(via
		(at 127.10414 -282.904438)
		(size 0.508)
		(drill 0.254)
		(layers "F.Cu" "B.Cu")
		(net "SW_P12V_P0V8_PEX1_FLT")
	)
	(via
		(at 125.476762 -275.411184)
		(size 0.508)
		(drill 0.254)
		(layers "F.Cu" "B.Cu")
		(net "SW_P12V_P0V8_PEX1_FLT")
	)
	(via
		(at 126.111762 -275.411184)
		(size 0.508)
		(drill 0.254)
		(layers "F.Cu" "B.Cu")
		(net "SW_P12V_P0V8_PEX1_FLT")
	)
	(via
		(at 124.841762 -276.046184)
		(size 0.508)
		(drill 0.254)
		(layers "F.Cu" "B.Cu")
		(net "SW_P12V_P0V8_PEX1_FLT")
	)
	(via
		(at 128.764284 -283.489654)
		(size 0.508)
		(drill 0.254)
		(layers "F.Cu" "B.Cu")
		(net "SW_P12V_P0V8_PEX1_FLT")
	)
	(via
		(at 126.746762 -275.411184)
		(size 0.508)
		(drill 0.254)
		(layers "F.Cu" "B.Cu")
		(net "SW_P12V_P0V8_PEX1_FLT")
	)
	(via
		(at 128.764284 -284.175454)
		(size 0.508)
		(drill 0.254)
		(layers "F.Cu" "B.Cu")
		(net "SW_P12V_P0V8_PEX1_FLT")
	)
	(via
		(at 120.466358 -277.634192)
		(size 0.508)
		(drill 0.254)
		(layers "F.Cu" "B.Cu")
		(net "SW_P12V_P0V8_PEX1_FLT")
	)
	(via
		(at 118.943628 -282.167838)
		(size 0.508)
		(drill 0.254)
		(layers "F.Cu" "B.Cu")
		(net "SW_P12V_P0V8_PEX1_FLT")
	)
	(via
		(at 121.35231 -277.731728)
		(size 0.508)
		(drill 0.254)
		(layers "F.Cu" "B.Cu")
		(net "SW_P12V_P0V8_PEX1_FLT")
	)
	(via
		(at 127.66294 -282.548838)
		(size 0.508)
		(drill 0.254)
		(layers "F.Cu" "B.Cu")
		(net "SW_P12V_P0V8_PEX1_FLT")
	)
	(via
		(at 127.63754 -281.786838)
		(size 0.508)
		(drill 0.254)
		(layers "F.Cu" "B.Cu")
		(net "SW_P12V_P0V8_PEX1_FLT")
	)
	(via
		(at 128.39573 -282.866592)
		(size 0.508)
		(drill 0.254)
		(layers "F.Cu" "B.Cu")
		(net "SW_P12V_P0V8_PEX1_FLT")
	)
	(via
		(at 126.746762 -276.046184)
		(size 0.508)
		(drill 0.254)
		(layers "F.Cu" "B.Cu")
		(net "SW_P12V_P0V8_PEX1_FLT")
	)
	(via
		(at 120.908318 -275.392896)
		(size 0.508)
		(drill 0.254)
		(layers "F.Cu" "B.Cu")
		(net "SW_P12V_P0V8_PEX1_FLT")
	)
	(via
		(at 119.502428 -282.548838)
		(size 0.508)
		(drill 0.254)
		(layers "F.Cu" "B.Cu")
		(net "SW_P12V_P0V8_PEX1_FLT")
	)
	(via
		(at 127.10414 -281.431238)
		(size 0.508)
		(drill 0.254)
		(layers "F.Cu" "B.Cu")
		(net "SW_P12V_P0V8_PEX1_FLT")
	)
	(via
		(at 118.943628 -281.431238)
		(size 0.508)
		(drill 0.254)
		(layers "F.Cu" "B.Cu")
		(net "SW_P12V_P0V8_PEX1_FLT")
	)
	(via
		(at 120.035828 -282.091638)
		(size 0.508)
		(drill 0.254)
		(layers "F.Cu" "B.Cu")
		(net "SW_P12V_P0V8_PEX1_FLT")
	)
	(via
		(at 121.312178 -276.845268)
		(size 0.508)
		(drill 0.254)
		(layers "F.Cu" "B.Cu")
		(net "SW_P12V_P0V8_PEX1_FLT")
	)
	(via
		(at 127.465074 -277.644352)
		(size 0.508)
		(drill 0.254)
		(layers "F.Cu" "B.Cu")
		(net "SW_P12V_P0V8_PEX1_FLT")
	)
	(via
		(at 120.235218 -282.866592)
		(size 0.508)
		(drill 0.254)
		(layers "F.Cu" "B.Cu")
		(net "SW_P12V_P0V8_PEX1_FLT")
	)
	(via
		(at 118.943628 -282.904438)
		(size 0.508)
		(drill 0.254)
		(layers "F.Cu" "B.Cu")
		(net "SW_P12V_P0V8_PEX1_FLT")
	)
	(via
		(at 124.841762 -275.411184)
		(size 0.508)
		(drill 0.254)
		(layers "F.Cu" "B.Cu")
		(net "SW_P12V_P0V8_PEX1_FLT")
	)
	(via
		(at 127.381762 -276.046184)
		(size 0.508)
		(drill 0.254)
		(layers "F.Cu" "B.Cu")
		(net "SW_P12V_P0V8_PEX1_FLT")
	)
	(via
		(at 121.543318 -274.757896)
		(size 0.508)
		(drill 0.254)
		(layers "F.Cu" "B.Cu")
		(net "SW_P12V_P0V8_PEX1_FLT")
	)
	(segment
		(start 121.930668 -281.989276)
		(end 121.920762 -281.999182)
		(width 0.2286)
		(layer "F.Cu")
		(net "SW_P0V8_PEX1_BOOT1")
	)
	(segment
		(start 121.930668 -280.84907)
		(end 121.930668 -281.989276)
		(width 0.2286)
		(layer "F.Cu")
		(net "SW_P0V8_PEX1_BOOT1")
	)
	(segment
		(start 132.142738 -279.886918)
		(end 132.142738 -280.295858)
		(width 0.1524)
		(layer "F.Cu")
		(net "P0V8_PEX1_LSET2")
	)
	(segment
		(start 132.142738 -280.295858)
		(end 132.34797 -280.50109)
		(width 0.1524)
		(layer "F.Cu")
		(net "P0V8_PEX1_LSET2")
	)
	(segment
		(start 131.881118 -281.657298)
		(end 132.34797 -280.530046)
		(width 0.1524)
		(layer "F.Cu")
		(net "P0V8_PEX1_LSET2")
	)
	(segment
		(start 131.881118 -281.999182)
		(end 131.881118 -281.657298)
		(width 0.1524)
		(layer "F.Cu")
		(net "P0V8_PEX1_LSET2")
	)
	(segment
		(start 132.34797 -280.530046)
		(end 132.34797 -280.50109)
		(width 0.1524)
		(layer "F.Cu")
		(net "P0V8_PEX1_LSET2")
	)
	(via
		(at 132.34797 -280.50109)
		(size 0.508)
		(drill 0.254)
		(layers "F.Cu" "B.Cu")
		(net "P0V8_PEX1_LSET2")
	)
	(segment
		(start 121.930668 -280.04897)
		(end 120.96877 -280.04897)
		(width 0.254)
		(layer "F.Cu")
		(net "SW_P0V8_PEX1_BOOT1_R")
	)
	(segment
		(start 126.205488 -282.821634)
		(end 126.254002 -282.870148)
		(width 0.254)
		(layer "F.Cu")
		(net "P0V8_PEX1_VCC1")
	)
	(segment
		(start 125.466602 -283.524198)
		(end 126.169166 -282.821634)
		(width 0.2286)
		(layer "F.Cu")
		(net "P0V8_PEX1_VCC1")
	)
	(segment
		(start 126.169166 -282.821634)
		(end 126.205488 -282.821634)
		(width 0.2286)
		(layer "F.Cu")
		(net "P0V8_PEX1_VCC1")
	)
	(segment
		(start 125.030738 -283.524198)
		(end 125.466602 -283.524198)
		(width 0.2286)
		(layer "F.Cu")
		(net "P0V8_PEX1_VCC1")
	)
	(segment
		(start 126.254002 -282.870148)
		(end 126.254002 -283.437584)
		(width 0.254)
		(layer "F.Cu")
		(net "P0V8_PEX1_VCC1")
	)
	(via
		(at 126.254002 -283.437584)
		(size 0.508)
		(drill 0.254)
		(layers "F.Cu" "B.Cu")
		(net "P0V8_PEX1_VCC1")
	)
	(segment
		(start 124.13615 -282.192476)
		(end 124.258578 -282.314904)
		(width 0.254)
		(layer "B.Cu")
		(net "P0V8_PEX1_VCC1")
	)
	(segment
		(start 126.254002 -283.437584)
		(end 125.589538 -283.437584)
		(width 0.254)
		(layer "B.Cu")
		(net "P0V8_PEX1_VCC1")
	)
	(segment
		(start 125.570488 -283.418534)
		(end 125.570488 -283.409136)
		(width 0.254)
		(layer "B.Cu")
		(net "P0V8_PEX1_VCC1")
	)
	(segment
		(start 124.476256 -282.314904)
		(end 124.731526 -282.570174)
		(width 0.254)
		(layer "B.Cu")
		(net "P0V8_PEX1_VCC1")
	)
	(segment
		(start 123.730258 -282.238958)
		(end 123.77674 -282.192476)
		(width 0.254)
		(layer "B.Cu")
		(net "P0V8_PEX1_VCC1")
	)
	(segment
		(start 123.77674 -282.192476)
		(end 124.13615 -282.192476)
		(width 0.254)
		(layer "B.Cu")
		(net "P0V8_PEX1_VCC1")
	)
	(segment
		(start 125.570488 -283.409136)
		(end 124.731526 -282.570174)
		(width 0.254)
		(layer "B.Cu")
		(net "P0V8_PEX1_VCC1")
	)
	(segment
		(start 124.258578 -282.314904)
		(end 124.476256 -282.314904)
		(width 0.254)
		(layer "B.Cu")
		(net "P0V8_PEX1_VCC1")
	)
	(segment
		(start 125.589538 -283.437584)
		(end 125.570488 -283.418534)
		(width 0.254)
		(layer "B.Cu")
		(net "P0V8_PEX1_VCC1")
	)
	(segment
		(start 129.129282 -280.84907)
		(end 129.631186 -281.350974)
		(width 0.2286)
		(layer "F.Cu")
		(net "SW_P0V8_PEX1_PHASE2")
	)
	(segment
		(start 129.631186 -281.350974)
		(end 129.631186 -281.999182)
		(width 0.2286)
		(layer "F.Cu")
		(net "SW_P0V8_PEX1_PHASE2")
	)
	(segment
		(start 130.09118 -280.04897)
		(end 129.129282 -280.04897)
		(width 0.254)
		(layer "F.Cu")
		(net "SW_P0V8_PEX1_BOOT2_R")
	)
	(segment
		(start 130.09118 -280.84907)
		(end 130.09118 -281.989276)
		(width 0.2286)
		(layer "F.Cu")
		(net "SW_P0V8_PEX1_BOOT2")
	)
	(segment
		(start 130.09118 -281.989276)
		(end 130.081274 -281.999182)
		(width 0.2286)
		(layer "F.Cu")
		(net "SW_P0V8_PEX1_BOOT2")
	)
	(segment
		(start 123.982226 -279.886918)
		(end 123.982226 -280.295858)
		(width 0.1524)
		(layer "F.Cu")
		(net "P0V8_PEX1_LSET1")
	)
	(segment
		(start 123.720606 -281.657298)
		(end 124.187458 -280.530046)
		(width 0.1524)
		(layer "F.Cu")
		(net "P0V8_PEX1_LSET1")
	)
	(segment
		(start 123.720606 -281.999182)
		(end 123.720606 -281.657298)
		(width 0.1524)
		(layer "F.Cu")
		(net "P0V8_PEX1_LSET1")
	)
	(segment
		(start 124.187458 -280.530046)
		(end 124.187458 -280.50109)
		(width 0.1524)
		(layer "F.Cu")
		(net "P0V8_PEX1_LSET1")
	)
	(segment
		(start 123.982226 -280.295858)
		(end 124.187458 -280.50109)
		(width 0.1524)
		(layer "F.Cu")
		(net "P0V8_PEX1_LSET1")
	)
	(via
		(at 124.187458 -280.50109)
		(size 0.508)
		(drill 0.254)
		(layers "F.Cu" "B.Cu")
		(net "P0V8_PEX1_LSET1")
	)
	(segment
		(start 123.28144 -261.68477)
		(end 122.575828 -260.979158)
		(width 0.2032)
		(layer "F.Cu")
		(net "P0V8_PEX0_VSEN0")
	)
	(segment
		(start 124.76734 -262.17372)
		(end 123.40844 -262.17372)
		(width 0.254)
		(layer "F.Cu")
		(net "P0V8_PEX0_VSEN0")
	)
	(segment
		(start 122.575828 -260.979158)
		(end 122.575828 -260.795008)
		(width 0.2032)
		(layer "F.Cu")
		(net "P0V8_PEX0_VSEN0")
	)
	(segment
		(start 124.76734 -260.973062)
		(end 124.76734 -262.17372)
		(width 0.254)
		(layer "F.Cu")
		(net "P0V8_PEX0_VSEN0")
	)
	(segment
		(start 123.28144 -262.04672)
		(end 123.28144 -261.68477)
		(width 0.2032)
		(layer "F.Cu")
		(net "P0V8_PEX0_VSEN0")
	)
	(segment
		(start 123.40844 -262.17372)
		(end 123.28144 -262.04672)
		(width 0.254)
		(layer "F.Cu")
		(net "P0V8_PEX0_VSEN0")
	)
	(via
		(at 124.76734 -260.973062)
		(size 0.762)
		(drill 0.381)
		(layers "F.Cu" "B.Cu")
		(net "P0V8_PEX0_VSEN0")
	)
	(segment
		(start 189.049914 -302.549814)
		(end 189.524894 -302.074834)
		(width 0.127)
		(layer "F.Cu")
		(net "VSENSE_P0V8_PEX1_SKT_VSEN")
	)
	(via
		(at 189.524894 -302.074834)
		(size 0.4064)
		(drill 0.2032)
		(layers "F.Cu" "B.Cu")
		(net "VSENSE_P0V8_PEX1_SKT_VSEN")
	)
	(via
		(at 138.079734 -328.352404)
		(size 0.6604)
		(drill 0.3302)
		(layers "F.Cu" "B.Cu")
		(net "VSENSE_P0V8_PEX1_SKT_VSEN")
	)
	(segment
		(start 189.156594 -302.173894)
		(end 189.156594 -302.402494)
		(width 0.09906)
		(layer "B.Cu")
		(net "VSENSE_P0V8_PEX1_SKT_VSEN")
	)
	(segment
		(start 175.381666 -320.1289)
		(end 175.465486 -320.21272)
		(width 0.09906)
		(layer "B.Cu")
		(net "VSENSE_P0V8_PEX1_SKT_VSEN")
	)
	(segment
		(start 189.524894 -302.074834)
		(end 189.255654 -302.074834)
		(width 0.09906)
		(layer "B.Cu")
		(net "VSENSE_P0V8_PEX1_SKT_VSEN")
	)
	(segment
		(start 175.381666 -308.002686)
		(end 175.381666 -320.1289)
		(width 0.09906)
		(layer "B.Cu")
		(net "VSENSE_P0V8_PEX1_SKT_VSEN")
	)
	(segment
		(start 158.897828 -328.092054)
		(end 138.340084 -328.092054)
		(width 0.254)
		(layer "B.Cu")
		(net "VSENSE_P0V8_PEX1_SKT_VSEN")
	)
	(segment
		(start 187.256674 -302.858678)
		(end 187.256674 -307.078126)
		(width 0.09906)
		(layer "B.Cu")
		(net "VSENSE_P0V8_PEX1_SKT_VSEN")
	)
	(segment
		(start 137.819384 -328.092054)
		(end 138.079734 -328.352404)
		(width 0.254)
		(layer "B.Cu")
		(net "VSENSE_P0V8_PEX1_SKT_VSEN")
	)
	(segment
		(start 189.255654 -302.074834)
		(end 189.156594 -302.173894)
		(width 0.09906)
		(layer "B.Cu")
		(net "VSENSE_P0V8_PEX1_SKT_VSEN")
	)
	(segment
		(start 175.977804 -307.406548)
		(end 175.381666 -308.002686)
		(width 0.09906)
		(layer "B.Cu")
		(net "VSENSE_P0V8_PEX1_SKT_VSEN")
	)
	(segment
		(start 187.458858 -302.656494)
		(end 187.256674 -302.858678)
		(width 0.09906)
		(layer "B.Cu")
		(net "VSENSE_P0V8_PEX1_SKT_VSEN")
	)
	(segment
		(start 188.902594 -302.656494)
		(end 187.458858 -302.656494)
		(width 0.09906)
		(layer "B.Cu")
		(net "VSENSE_P0V8_PEX1_SKT_VSEN")
	)
	(segment
		(start 189.156594 -302.402494)
		(end 188.902594 -302.656494)
		(width 0.09906)
		(layer "B.Cu")
		(net "VSENSE_P0V8_PEX1_SKT_VSEN")
	)
	(segment
		(start 134.99719 -328.092054)
		(end 137.819384 -328.092054)
		(width 0.254)
		(layer "B.Cu")
		(net "VSENSE_P0V8_PEX1_SKT_VSEN")
	)
	(segment
		(start 134.692644 -328.422)
		(end 134.99719 -328.092054)
		(width 0.254)
		(layer "B.Cu")
		(net "VSENSE_P0V8_PEX1_SKT_VSEN")
	)
	(segment
		(start 174.705264 -321.544442)
		(end 158.897828 -328.092054)
		(width 0.254)
		(layer "B.Cu")
		(net "VSENSE_P0V8_PEX1_SKT_VSEN")
	)
	(segment
		(start 186.928252 -307.406548)
		(end 175.977804 -307.406548)
		(width 0.09906)
		(layer "B.Cu")
		(net "VSENSE_P0V8_PEX1_SKT_VSEN")
	)
	(segment
		(start 138.340084 -328.092054)
		(end 138.079734 -328.352404)
		(width 0.254)
		(layer "B.Cu")
		(net "VSENSE_P0V8_PEX1_SKT_VSEN")
	)
	(segment
		(start 175.465486 -320.21272)
		(end 175.465486 -320.251328)
		(width 0.09906)
		(layer "B.Cu")
		(net "VSENSE_P0V8_PEX1_SKT_VSEN")
	)
	(segment
		(start 175.465486 -320.251328)
		(end 175.465486 -320.78422)
		(width 0.254)
		(layer "B.Cu")
		(net "VSENSE_P0V8_PEX1_SKT_VSEN")
	)
	(segment
		(start 175.465486 -320.78422)
		(end 174.705264 -321.544442)
		(width 0.254)
		(layer "B.Cu")
		(net "VSENSE_P0V8_PEX1_SKT_VSEN")
	)
	(segment
		(start 187.256674 -307.078126)
		(end 186.928252 -307.406548)
		(width 0.09906)
		(layer "B.Cu")
		(net "VSENSE_P0V8_PEX1_SKT_VSEN")
	)
	(segment
		(start 124.878338 -257.038602)
		(end 126.706376 -255.210564)
		(width 0.13208)
		(layer "F.Cu")
		(net "FM_P0V8_PEX0_EN_R")
	)
	(segment
		(start 127.808228 -254.678942)
		(end 127.276606 -255.210564)
		(width 0.13208)
		(layer "F.Cu")
		(net "FM_P0V8_PEX0_EN_R")
	)
	(segment
		(start 129.085086 -254.678942)
		(end 127.808228 -254.678942)
		(width 0.13208)
		(layer "F.Cu")
		(net "FM_P0V8_PEX0_EN_R")
	)
	(segment
		(start 124.521976 -257.394964)
		(end 124.878338 -257.038602)
		(width 0.13208)
		(layer "F.Cu")
		(net "FM_P0V8_PEX0_EN_R")
	)
	(segment
		(start 127.276606 -255.210564)
		(end 127.258064 -255.210564)
		(width 0.13208)
		(layer "F.Cu")
		(net "FM_P0V8_PEX0_EN_R")
	)
	(segment
		(start 123.175776 -257.394964)
		(end 124.521976 -257.394964)
		(width 0.13208)
		(layer "F.Cu")
		(net "FM_P0V8_PEX0_EN_R")
	)
	(segment
		(start 129.290064 -254.88392)
		(end 129.085086 -254.678942)
		(width 0.13208)
		(layer "F.Cu")
		(net "FM_P0V8_PEX0_EN_R")
	)
	(segment
		(start 129.290064 -255.210564)
		(end 129.290064 -254.88392)
		(width 0.13208)
		(layer "F.Cu")
		(net "FM_P0V8_PEX0_EN_R")
	)
	(segment
		(start 126.706376 -255.210564)
		(end 127.258064 -255.210564)
		(width 0.13208)
		(layer "F.Cu")
		(net "FM_P0V8_PEX0_EN_R")
	)
	(via
		(at 124.878338 -257.038602)
		(size 0.762)
		(drill 0.381)
		(layers "F.Cu" "B.Cu")
		(net "FM_P0V8_PEX0_EN_R")
	)
	(segment
		(start 122.778012 -254.65659)
		(end 123.062238 -254.372364)
		(width 0.13208)
		(layer "F.Cu")
		(net "SMB_VR_P0V8_PEX0_SDA")
	)
	(segment
		(start 123.975114 -252.816614)
		(end 123.975114 -253.459488)
		(width 0.13208)
		(layer "F.Cu")
		(net "SMB_VR_P0V8_PEX0_SDA")
	)
	(segment
		(start 122.778012 -254.909066)
		(end 122.778012 -254.65659)
		(width 0.13208)
		(layer "F.Cu")
		(net "SMB_VR_P0V8_PEX0_SDA")
	)
	(segment
		(start 123.975114 -253.459488)
		(end 123.062238 -254.372364)
		(width 0.13208)
		(layer "F.Cu")
		(net "SMB_VR_P0V8_PEX0_SDA")
	)
	(segment
		(start 122.175778 -255.994916)
		(end 122.175778 -255.5113)
		(width 0.13208)
		(layer "F.Cu")
		(net "SMB_VR_P0V8_PEX0_SDA")
	)
	(segment
		(start 122.175778 -255.5113)
		(end 122.778012 -254.909066)
		(width 0.13208)
		(layer "F.Cu")
		(net "SMB_VR_P0V8_PEX0_SDA")
	)
	(via
		(at 123.062238 -254.372364)
		(size 0.762)
		(drill 0.381)
		(layers "F.Cu" "B.Cu")
		(net "SMB_VR_P0V8_PEX0_SDA")
	)
	(segment
		(start 132.527548 -248.47169)
		(end 174.257208 -248.47169)
		(width 0.13208)
		(layer "F.Cu")
		(net "SMB_HOTSWAP_SCL_R")
	)
	(segment
		(start 190.110618 -364.359952)
		(end 194.476878 -364.359952)
		(width 0.13208)
		(layer "F.Cu")
		(net "SMB_HOTSWAP_SCL_R")
	)
	(segment
		(start 203.5683 -371.80901)
		(end 203.5683 -371.194584)
		(width 0.13208)
		(layer "F.Cu")
		(net "SMB_HOTSWAP_SCL_R")
	)
	(segment
		(start 202.852274 -372.525036)
		(end 203.5683 -371.80901)
		(width 0.13208)
		(layer "F.Cu")
		(net "SMB_HOTSWAP_SCL_R")
	)
	(segment
		(start 194.476878 -364.359952)
		(end 195.30314 -365.186214)
		(width 0.13208)
		(layer "F.Cu")
		(net "SMB_HOTSWAP_SCL_R")
	)
	(segment
		(start 202.459082 -372.842282)
		(end 202.776328 -372.525036)
		(width 0.13208)
		(layer "F.Cu")
		(net "SMB_HOTSWAP_SCL_R")
	)
	(segment
		(start 130.504438 -247.36679)
		(end 131.422648 -247.36679)
		(width 0.13208)
		(layer "F.Cu")
		(net "SMB_HOTSWAP_SCL_R")
	)
	(segment
		(start 202.776328 -372.525036)
		(end 202.852274 -372.525036)
		(width 0.13208)
		(layer "F.Cu")
		(net "SMB_HOTSWAP_SCL_R")
	)
	(segment
		(start 188.088778 -262.30326)
		(end 208.214976 -262.30326)
		(width 0.13208)
		(layer "F.Cu")
		(net "SMB_HOTSWAP_SCL_R")
	)
	(segment
		(start 189.392052 -363.641386)
		(end 190.110618 -364.359952)
		(width 0.13208)
		(layer "F.Cu")
		(net "SMB_HOTSWAP_SCL_R")
	)
	(segment
		(start 187.122308 -363.641386)
		(end 189.392052 -363.641386)
		(width 0.13208)
		(layer "F.Cu")
		(net "SMB_HOTSWAP_SCL_R")
	)
	(segment
		(start 174.257208 -248.47169)
		(end 188.088778 -262.30326)
		(width 0.13208)
		(layer "F.Cu")
		(net "SMB_HOTSWAP_SCL_R")
	)
	(segment
		(start 131.422648 -247.36679)
		(end 132.527548 -248.47169)
		(width 0.13208)
		(layer "F.Cu")
		(net "SMB_HOTSWAP_SCL_R")
	)
	(segment
		(start 208.214976 -262.30326)
		(end 213.59749 -256.920746)
		(width 0.13208)
		(layer "F.Cu")
		(net "SMB_HOTSWAP_SCL_R")
	)
	(via
		(at 195.30314 -365.186214)
		(size 0.508)
		(drill 0.254)
		(layers "F.Cu" "B.Cu")
		(net "SMB_HOTSWAP_SCL_R")
	)
	(via
		(at 213.59749 -256.920746)
		(size 0.508)
		(drill 0.254)
		(layers "F.Cu" "B.Cu")
		(net "SMB_HOTSWAP_SCL_R")
	)
	(via
		(at 226.341178 -333.83347)
		(size 0.508)
		(drill 0.254)
		(layers "F.Cu" "B.Cu")
		(net "SMB_HOTSWAP_SCL_R")
	)
	(via
		(at 202.459082 -372.842282)
		(size 0.508)
		(drill 0.254)
		(layers "F.Cu" "B.Cu")
		(net "SMB_HOTSWAP_SCL_R")
	)
	(segment
		(start 226.341178 -333.83347)
		(end 223.853756 -331.346048)
		(width 0.13208)
		(layer "B.Cu")
		(net "SMB_HOTSWAP_SCL_R")
	)
	(segment
		(start 216.5731 -321.978274)
		(end 216.5731 -321.845432)
		(width 0.13208)
		(layer "B.Cu")
		(net "SMB_HOTSWAP_SCL_R")
	)
	(segment
		(start 215.907874 -321.756024)
		(end 215.739218 -321.756024)
		(width 0.13208)
		(layer "B.Cu")
		(net "SMB_HOTSWAP_SCL_R")
	)
	(segment
		(start 217.016838 -322.422012)
		(end 216.79535 -322.6435)
		(width 0.13208)
		(layer "B.Cu")
		(net "SMB_HOTSWAP_SCL_R")
	)
	(segment
		(start 215.739218 -321.756024)
		(end 215.464136 -321.480942)
		(width 0.13208)
		(layer "B.Cu")
		(net "SMB_HOTSWAP_SCL_R")
	)
	(segment
		(start 213.57209 -281.7876)
		(end 213.57209 -256.946146)
		(width 0.13208)
		(layer "B.Cu")
		(net "SMB_HOTSWAP_SCL_R")
	)
	(segment
		(start 216.351612 -322.368418)
		(end 216.351612 -322.199762)
		(width 0.13208)
		(layer "B.Cu")
		(net "SMB_HOTSWAP_SCL_R")
	)
	(segment
		(start 216.129362 -321.534536)
		(end 215.907874 -321.756024)
		(width 0.13208)
		(layer "B.Cu")
		(net "SMB_HOTSWAP_SCL_R")
	)
	(segment
		(start 216.79535 -322.6435)
		(end 216.626694 -322.6435)
		(width 0.13208)
		(layer "B.Cu")
		(net "SMB_HOTSWAP_SCL_R")
	)
	(segment
		(start 214.798148 -320.07048)
		(end 211.107782 -316.380114)
		(width 0.13208)
		(layer "B.Cu")
		(net "SMB_HOTSWAP_SCL_R")
	)
	(segment
		(start 215.374728 -320.64706)
		(end 215.241886 -320.64706)
		(width 0.13208)
		(layer "B.Cu")
		(net "SMB_HOTSWAP_SCL_R")
	)
	(segment
		(start 214.851742 -320.868548)
		(end 214.57666 -320.593466)
		(width 0.13208)
		(layer "B.Cu")
		(net "SMB_HOTSWAP_SCL_R")
	)
	(segment
		(start 215.464136 -321.312286)
		(end 215.685624 -321.090798)
		(width 0.13208)
		(layer "B.Cu")
		(net "SMB_HOTSWAP_SCL_R")
	)
	(segment
		(start 213.57209 -256.946146)
		(end 213.59749 -256.920746)
		(width 0.13208)
		(layer "B.Cu")
		(net "SMB_HOTSWAP_SCL_R")
	)
	(segment
		(start 215.241886 -320.64706)
		(end 215.020398 -320.868548)
		(width 0.13208)
		(layer "B.Cu")
		(net "SMB_HOTSWAP_SCL_R")
	)
	(segment
		(start 215.685624 -320.957956)
		(end 215.374728 -320.64706)
		(width 0.13208)
		(layer "B.Cu")
		(net "SMB_HOTSWAP_SCL_R")
	)
	(segment
		(start 215.464136 -321.480942)
		(end 215.464136 -321.312286)
		(width 0.13208)
		(layer "B.Cu")
		(net "SMB_HOTSWAP_SCL_R")
	)
	(segment
		(start 217.14968 -322.422012)
		(end 217.016838 -322.422012)
		(width 0.13208)
		(layer "B.Cu")
		(net "SMB_HOTSWAP_SCL_R")
	)
	(segment
		(start 214.798148 -320.203322)
		(end 214.798148 -320.07048)
		(width 0.13208)
		(layer "B.Cu")
		(net "SMB_HOTSWAP_SCL_R")
	)
	(segment
		(start 211.107782 -284.251908)
		(end 213.57209 -281.7876)
		(width 0.13208)
		(layer "B.Cu")
		(net "SMB_HOTSWAP_SCL_R")
	)
	(segment
		(start 223.853756 -331.346048)
		(end 223.853756 -329.126088)
		(width 0.13208)
		(layer "B.Cu")
		(net "SMB_HOTSWAP_SCL_R")
	)
	(segment
		(start 216.626694 -322.6435)
		(end 216.351612 -322.368418)
		(width 0.13208)
		(layer "B.Cu")
		(net "SMB_HOTSWAP_SCL_R")
	)
	(segment
		(start 223.853756 -329.126088)
		(end 217.14968 -322.422012)
		(width 0.13208)
		(layer "B.Cu")
		(net "SMB_HOTSWAP_SCL_R")
	)
	(segment
		(start 214.57666 -320.593466)
		(end 214.57666 -320.42481)
		(width 0.13208)
		(layer "B.Cu")
		(net "SMB_HOTSWAP_SCL_R")
	)
	(segment
		(start 215.685624 -321.090798)
		(end 215.685624 -320.957956)
		(width 0.13208)
		(layer "B.Cu")
		(net "SMB_HOTSWAP_SCL_R")
	)
	(segment
		(start 216.5731 -321.845432)
		(end 216.262204 -321.534536)
		(width 0.13208)
		(layer "B.Cu")
		(net "SMB_HOTSWAP_SCL_R")
	)
	(segment
		(start 214.57666 -320.42481)
		(end 214.798148 -320.203322)
		(width 0.13208)
		(layer "B.Cu")
		(net "SMB_HOTSWAP_SCL_R")
	)
	(segment
		(start 216.262204 -321.534536)
		(end 216.129362 -321.534536)
		(width 0.13208)
		(layer "B.Cu")
		(net "SMB_HOTSWAP_SCL_R")
	)
	(segment
		(start 215.020398 -320.868548)
		(end 214.851742 -320.868548)
		(width 0.13208)
		(layer "B.Cu")
		(net "SMB_HOTSWAP_SCL_R")
	)
	(segment
		(start 216.351612 -322.199762)
		(end 216.5731 -321.978274)
		(width 0.13208)
		(layer "B.Cu")
		(net "SMB_HOTSWAP_SCL_R")
	)
	(segment
		(start 211.107782 -316.380114)
		(end 211.107782 -284.251908)
		(width 0.13208)
		(layer "B.Cu")
		(net "SMB_HOTSWAP_SCL_R")
	)
	(segment
		(start 204.684122 -354.15728)
		(end 200.461626 -358.379776)
		(width 0.15494)
		(layer "In5.Cu")
		(net "SMB_HOTSWAP_SCL_R")
	)
	(segment
		(start 195.30314 -363.781594)
		(end 195.30314 -365.186214)
		(width 0.15494)
		(layer "In5.Cu")
		(net "SMB_HOTSWAP_SCL_R")
	)
	(segment
		(start 197.967092 -361.117642)
		(end 195.30314 -363.781594)
		(width 0.15494)
		(layer "In5.Cu")
		(net "SMB_HOTSWAP_SCL_R")
	)
	(segment
		(start 200.461626 -358.379776)
		(end 200.461626 -359.125774)
		(width 0.15494)
		(layer "In5.Cu")
		(net "SMB_HOTSWAP_SCL_R")
	)
	(segment
		(start 218.82735 -354.15728)
		(end 204.684122 -354.15728)
		(width 0.15494)
		(layer "In5.Cu")
		(net "SMB_HOTSWAP_SCL_R")
	)
	(segment
		(start 226.341178 -346.643452)
		(end 218.82735 -354.15728)
		(width 0.15494)
		(layer "In5.Cu")
		(net "SMB_HOTSWAP_SCL_R")
	)
	(segment
		(start 198.469758 -361.117642)
		(end 197.967092 -361.117642)
		(width 0.15494)
		(layer "In5.Cu")
		(net "SMB_HOTSWAP_SCL_R")
	)
	(segment
		(start 226.341178 -333.83347)
		(end 226.341178 -346.643452)
		(width 0.15494)
		(layer "In5.Cu")
		(net "SMB_HOTSWAP_SCL_R")
	)
	(segment
		(start 200.461626 -359.125774)
		(end 198.469758 -361.117642)
		(width 0.15494)
		(layer "In5.Cu")
		(net "SMB_HOTSWAP_SCL_R")
	)
	(segment
		(start 202.459082 -372.842282)
		(end 202.585066 -372.716298)
		(width 0.15494)
		(layer "In7.Cu")
		(net "SMB_HOTSWAP_SCL_R")
	)
	(segment
		(start 200.321672 -369.864894)
		(end 200.321672 -368.241072)
		(width 0.15494)
		(layer "In7.Cu")
		(net "SMB_HOTSWAP_SCL_R")
	)
	(segment
		(start 198.826882 -367.81613)
		(end 197.856348 -366.845596)
		(width 0.15494)
		(layer "In7.Cu")
		(net "SMB_HOTSWAP_SCL_R")
	)
	(segment
		(start 202.585066 -372.716298)
		(end 202.585066 -371.85092)
		(width 0.15494)
		(layer "In7.Cu")
		(net "SMB_HOTSWAP_SCL_R")
	)
	(segment
		(start 201.067416 -370.610638)
		(end 200.321672 -369.864894)
		(width 0.15494)
		(layer "In7.Cu")
		(net "SMB_HOTSWAP_SCL_R")
	)
	(segment
		(start 199.89673 -367.81613)
		(end 198.826882 -367.81613)
		(width 0.15494)
		(layer "In7.Cu")
		(net "SMB_HOTSWAP_SCL_R")
	)
	(segment
		(start 196.962522 -366.845596)
		(end 195.30314 -365.186214)
		(width 0.15494)
		(layer "In7.Cu")
		(net "SMB_HOTSWAP_SCL_R")
	)
	(segment
		(start 197.856348 -366.845596)
		(end 196.962522 -366.845596)
		(width 0.15494)
		(layer "In7.Cu")
		(net "SMB_HOTSWAP_SCL_R")
	)
	(segment
		(start 201.344784 -370.610638)
		(end 201.067416 -370.610638)
		(width 0.15494)
		(layer "In7.Cu")
		(net "SMB_HOTSWAP_SCL_R")
	)
	(segment
		(start 202.585066 -371.85092)
		(end 201.344784 -370.610638)
		(width 0.15494)
		(layer "In7.Cu")
		(net "SMB_HOTSWAP_SCL_R")
	)
	(segment
		(start 200.321672 -368.241072)
		(end 199.89673 -367.81613)
		(width 0.15494)
		(layer "In7.Cu")
		(net "SMB_HOTSWAP_SCL_R")
	)
	(segment
		(start 117.831108 -257.795014)
		(end 118.375684 -257.795014)
		(width 0.2032)
		(layer "F.Cu")
		(net "P0V8_PEX0_IINSEN")
	)
	(segment
		(start 117.05844 -257.76555)
		(end 117.801644 -257.76555)
		(width 0.2032)
		(layer "F.Cu")
		(net "P0V8_PEX0_IINSEN")
	)
	(segment
		(start 116.16944 -258.01955)
		(end 116.80444 -258.01955)
		(width 0.254)
		(layer "F.Cu")
		(net "P0V8_PEX0_IINSEN")
	)
	(segment
		(start 116.04244 -258.14655)
		(end 116.16944 -258.01955)
		(width 0.254)
		(layer "F.Cu")
		(net "P0V8_PEX0_IINSEN")
	)
	(segment
		(start 116.80444 -258.01955)
		(end 117.05844 -257.76555)
		(width 0.2032)
		(layer "F.Cu")
		(net "P0V8_PEX0_IINSEN")
	)
	(segment
		(start 117.801644 -257.76555)
		(end 117.831108 -257.795014)
		(width 0.2032)
		(layer "F.Cu")
		(net "P0V8_PEX0_IINSEN")
	)
	(via
		(at 115.720114 -258.01955)
		(size 0.6604)
		(drill 0.3302)
		(layers "F.Cu" "B.Cu")
		(net "P0V8_PEX0_IINSEN")
	)
	(via
		(at 116.80444 -258.01955)
		(size 0.508)
		(drill 0.254)
		(layers "F.Cu" "B.Cu")
		(net "P0V8_PEX0_IINSEN")
	)
	(segment
		(start 116.80444 -258.01955)
		(end 115.720114 -258.01955)
		(width 0.254)
		(layer "B.Cu")
		(net "P0V8_PEX0_IINSEN")
	)
	(segment
		(start 115.305078 -257.604514)
		(end 114.450114 -257.604514)
		(width 0.254)
		(layer "B.Cu")
		(net "P0V8_PEX0_IINSEN")
	)
	(segment
		(start 113.561114 -257.604514)
		(end 114.450114 -257.604514)
		(width 0.254)
		(layer "B.Cu")
		(net "P0V8_PEX0_IINSEN")
	)
	(segment
		(start 112.672114 -257.604514)
		(end 113.561114 -257.604514)
		(width 0.254)
		(layer "B.Cu")
		(net "P0V8_PEX0_IINSEN")
	)
	(segment
		(start 115.720114 -258.01955)
		(end 115.305078 -257.604514)
		(width 0.254)
		(layer "B.Cu")
		(net "P0V8_PEX0_IINSEN")
	)
	(segment
		(start 106.611674 -281.999182)
		(end 106.611674 -281.567128)
		(width 0.2286)
		(layer "F.Cu")
		(net "P0V8_PEX0_TSEN")
	)
	(segment
		(start 114.772186 -281.999182)
		(end 114.772186 -281.567128)
		(width 0.2286)
		(layer "F.Cu")
		(net "P0V8_PEX0_TSEN")
	)
	(segment
		(start 106.878628 -281.12212)
		(end 106.878628 -280.810208)
		(width 0.2286)
		(layer "F.Cu")
		(net "P0V8_PEX0_TSEN")
	)
	(segment
		(start 114.772186 -281.567128)
		(end 114.970052 -281.369262)
		(width 0.2286)
		(layer "F.Cu")
		(net "P0V8_PEX0_TSEN")
	)
	(segment
		(start 106.611674 -281.567128)
		(end 106.80954 -281.369262)
		(width 0.2286)
		(layer "F.Cu")
		(net "P0V8_PEX0_TSEN")
	)
	(segment
		(start 114.970052 -281.369262)
		(end 115.03914 -281.12212)
		(width 0.2286)
		(layer "F.Cu")
		(net "P0V8_PEX0_TSEN")
	)
	(segment
		(start 115.03914 -281.12212)
		(end 115.03914 -280.810208)
		(width 0.2286)
		(layer "F.Cu")
		(net "P0V8_PEX0_TSEN")
	)
	(segment
		(start 106.80954 -281.369262)
		(end 106.878628 -281.12212)
		(width 0.2286)
		(layer "F.Cu")
		(net "P0V8_PEX0_TSEN")
	)
	(via
		(at 115.03914 -280.810208)
		(size 0.508)
		(drill 0.254)
		(layers "F.Cu" "B.Cu")
		(net "P0V8_PEX0_TSEN")
	)
	(via
		(at 106.878628 -280.810208)
		(size 0.508)
		(drill 0.254)
		(layers "F.Cu" "B.Cu")
		(net "P0V8_PEX0_TSEN")
	)
	(via
		(at 114.831114 -264.12952)
		(size 0.508)
		(drill 0.254)
		(layers "F.Cu" "B.Cu")
		(net "P0V8_PEX0_TSEN")
	)
	(segment
		(start 114.831114 -261.88924)
		(end 114.831114 -264.12952)
		(width 0.254)
		(layer "B.Cu")
		(net "P0V8_PEX0_TSEN")
	)
	(segment
		(start 115.919758 -260.800596)
		(end 114.831114 -261.88924)
		(width 0.254)
		(layer "B.Cu")
		(net "P0V8_PEX0_TSEN")
	)
	(segment
		(start 106.878628 -280.190956)
		(end 106.878628 -280.810208)
		(width 0.254)
		(layer "In7.Cu")
		(net "P0V8_PEX0_TSEN")
	)
	(segment
		(start 115.03914 -280.810208)
		(end 115.03914 -280.129488)
		(width 0.254)
		(layer "In7.Cu")
		(net "P0V8_PEX0_TSEN")
	)
	(segment
		(start 107.37977 -279.689814)
		(end 106.878628 -280.190956)
		(width 0.254)
		(layer "In7.Cu")
		(net "P0V8_PEX0_TSEN")
	)
	(segment
		(start 107.687364 -278.34336)
		(end 107.37977 -278.650954)
		(width 0.254)
		(layer "In7.Cu")
		(net "P0V8_PEX0_TSEN")
	)
	(segment
		(start 114.299492 -279.38984)
		(end 114.299492 -278.84501)
		(width 0.254)
		(layer "In7.Cu")
		(net "P0V8_PEX0_TSEN")
	)
	(segment
		(start 105.42778 -278.863552)
		(end 107.372912 -276.91842)
		(width 0.254)
		(layer "In7.Cu")
		(net "P0V8_PEX0_TSEN")
	)
	(segment
		(start 114.299492 -278.84501)
		(end 113.797842 -278.34336)
		(width 0.254)
		(layer "In7.Cu")
		(net "P0V8_PEX0_TSEN")
	)
	(segment
		(start 107.37977 -278.650954)
		(end 107.37977 -279.689814)
		(width 0.254)
		(layer "In7.Cu")
		(net "P0V8_PEX0_TSEN")
	)
	(segment
		(start 107.372912 -276.91842)
		(end 107.372912 -268.59738)
		(width 0.254)
		(layer "In7.Cu")
		(net "P0V8_PEX0_TSEN")
	)
	(segment
		(start 109.679232 -279.537414)
		(end 108.485178 -278.34336)
		(width 0.254)
		(layer "In7.Cu")
		(net "P0V8_PEX0_TSEN")
	)
	(segment
		(start 108.485178 -278.34336)
		(end 107.687364 -278.34336)
		(width 0.254)
		(layer "In7.Cu")
		(net "P0V8_PEX0_TSEN")
	)
	(segment
		(start 109.286548 -266.683744)
		(end 111.564674 -266.683744)
		(width 0.254)
		(layer "In7.Cu")
		(net "P0V8_PEX0_TSEN")
	)
	(segment
		(start 113.797842 -278.34336)
		(end 113.123218 -278.34336)
		(width 0.254)
		(layer "In7.Cu")
		(net "P0V8_PEX0_TSEN")
	)
	(segment
		(start 105.73131 -279.66289)
		(end 105.42778 -279.35936)
		(width 0.254)
		(layer "In7.Cu")
		(net "P0V8_PEX0_TSEN")
	)
	(segment
		(start 106.878628 -280.190956)
		(end 106.350562 -279.66289)
		(width 0.254)
		(layer "In7.Cu")
		(net "P0V8_PEX0_TSEN")
	)
	(segment
		(start 107.372912 -268.59738)
		(end 109.286548 -266.683744)
		(width 0.254)
		(layer "In7.Cu")
		(net "P0V8_PEX0_TSEN")
	)
	(segment
		(start 115.03914 -280.129488)
		(end 114.299492 -279.38984)
		(width 0.254)
		(layer "In7.Cu")
		(net "P0V8_PEX0_TSEN")
	)
	(segment
		(start 106.350562 -279.66289)
		(end 105.73131 -279.66289)
		(width 0.254)
		(layer "In7.Cu")
		(net "P0V8_PEX0_TSEN")
	)
	(segment
		(start 111.929164 -279.537414)
		(end 109.679232 -279.537414)
		(width 0.254)
		(layer "In7.Cu")
		(net "P0V8_PEX0_TSEN")
	)
	(segment
		(start 113.123218 -278.34336)
		(end 111.929164 -279.537414)
		(width 0.254)
		(layer "In7.Cu")
		(net "P0V8_PEX0_TSEN")
	)
	(segment
		(start 105.42778 -279.35936)
		(end 105.42778 -278.863552)
		(width 0.254)
		(layer "In7.Cu")
		(net "P0V8_PEX0_TSEN")
	)
	(segment
		(start 111.564674 -266.683744)
		(end 114.118898 -264.12952)
		(width 0.254)
		(layer "In7.Cu")
		(net "P0V8_PEX0_TSEN")
	)
	(segment
		(start 114.118898 -264.12952)
		(end 114.831114 -264.12952)
		(width 0.254)
		(layer "In7.Cu")
		(net "P0V8_PEX0_TSEN")
	)
	(segment
		(start 123.941586 -256.994914)
		(end 125.875796 -255.060704)
		(width 0.13208)
		(layer "F.Cu")
		(net "P0V8_PEX0_AVRRDY")
	)
	(segment
		(start 125.875796 -255.060704)
		(end 126.741936 -254.194564)
		(width 0.13208)
		(layer "F.Cu")
		(net "P0V8_PEX0_AVRRDY")
	)
	(segment
		(start 127.258064 -253.879604)
		(end 127.258064 -254.194564)
		(width 0.13208)
		(layer "F.Cu")
		(net "P0V8_PEX0_AVRRDY")
	)
	(segment
		(start 126.741936 -254.194564)
		(end 127.258064 -254.194564)
		(width 0.13208)
		(layer "F.Cu")
		(net "P0V8_PEX0_AVRRDY")
	)
	(segment
		(start 129.290064 -253.178564)
		(end 129.290064 -253.571248)
		(width 0.13208)
		(layer "F.Cu")
		(net "P0V8_PEX0_AVRRDY")
	)
	(segment
		(start 127.439166 -253.698502)
		(end 127.258064 -253.879604)
		(width 0.13208)
		(layer "F.Cu")
		(net "P0V8_PEX0_AVRRDY")
	)
	(segment
		(start 123.175776 -256.994914)
		(end 123.941586 -256.994914)
		(width 0.13208)
		(layer "F.Cu")
		(net "P0V8_PEX0_AVRRDY")
	)
	(segment
		(start 129.16281 -253.698502)
		(end 127.439166 -253.698502)
		(width 0.13208)
		(layer "F.Cu")
		(net "P0V8_PEX0_AVRRDY")
	)
	(segment
		(start 129.290064 -253.571248)
		(end 129.16281 -253.698502)
		(width 0.13208)
		(layer "F.Cu")
		(net "P0V8_PEX0_AVRRDY")
	)
	(segment
		(start 129.290064 -254.194564)
		(end 129.290064 -253.825756)
		(width 0.13208)
		(layer "F.Cu")
		(net "P0V8_PEX0_AVRRDY")
	)
	(segment
		(start 129.290064 -253.825756)
		(end 129.16281 -253.698502)
		(width 0.13208)
		(layer "F.Cu")
		(net "P0V8_PEX0_AVRRDY")
	)
	(via
		(at 125.875796 -255.060704)
		(size 0.762)
		(drill 0.381)
		(layers "F.Cu" "B.Cu")
		(net "P0V8_PEX0_AVRRDY")
	)
	(segment
		(start 113.961164 -261.687564)
		(end 113.961164 -262.703564)
		(width 0.254)
		(layer "F.Cu")
		(net "P0V8_PEX0_VR_CONFIG")
	)
	(segment
		(start 117.930422 -259.39496)
		(end 117.669818 -259.655564)
		(width 0.1524)
		(layer "F.Cu")
		(net "P0V8_PEX0_VR_CONFIG")
	)
	(segment
		(start 114.52225 -261.217664)
		(end 114.05235 -261.687564)
		(width 0.254)
		(layer "F.Cu")
		(net "P0V8_PEX0_VR_CONFIG")
	)
	(segment
		(start 115.176046 -259.655564)
		(end 114.783616 -260.047994)
		(width 0.1524)
		(layer "F.Cu")
		(net "P0V8_PEX0_VR_CONFIG")
	)
	(segment
		(start 117.669818 -259.655564)
		(end 115.176046 -259.655564)
		(width 0.1524)
		(layer "F.Cu")
		(net "P0V8_PEX0_VR_CONFIG")
	)
	(segment
		(start 118.375684 -259.39496)
		(end 117.930422 -259.39496)
		(width 0.1524)
		(layer "F.Cu")
		(net "P0V8_PEX0_VR_CONFIG")
	)
	(segment
		(start 114.783616 -260.956298)
		(end 114.52225 -261.217664)
		(width 0.254)
		(layer "F.Cu")
		(net "P0V8_PEX0_VR_CONFIG")
	)
	(segment
		(start 114.05235 -261.687564)
		(end 113.961164 -261.687564)
		(width 0.254)
		(layer "F.Cu")
		(net "P0V8_PEX0_VR_CONFIG")
	)
	(segment
		(start 114.783616 -260.047994)
		(end 114.783616 -260.956298)
		(width 0.254)
		(layer "F.Cu")
		(net "P0V8_PEX0_VR_CONFIG")
	)
	(via
		(at 114.52225 -261.217664)
		(size 0.508)
		(drill 0.254)
		(layers "F.Cu" "B.Cu")
		(net "P0V8_PEX0_VR_CONFIG")
	)
	(segment
		(start 116.941854 -257.394964)
		(end 118.375684 -257.394964)
		(width 0.2032)
		(layer "F.Cu")
		(net "P0V8_PEX0_VINSEN")
	)
	(segment
		(start 116.04244 -257.13055)
		(end 116.67744 -257.13055)
		(width 0.254)
		(layer "F.Cu")
		(net "P0V8_PEX0_VINSEN")
	)
	(segment
		(start 116.67744 -257.13055)
		(end 116.941854 -257.394964)
		(width 0.2032)
		(layer "F.Cu")
		(net "P0V8_PEX0_VINSEN")
	)
	(via
		(at 116.67744 -257.13055)
		(size 0.508)
		(drill 0.254)
		(layers "F.Cu" "B.Cu")
		(net "P0V8_PEX0_VINSEN")
	)
	(segment
		(start 115.466114 -256.626614)
		(end 116.173504 -256.626614)
		(width 0.254)
		(layer "B.Cu")
		(net "P0V8_PEX0_VINSEN")
	)
	(segment
		(start 114.450114 -256.626614)
		(end 115.466114 -256.626614)
		(width 0.254)
		(layer "B.Cu")
		(net "P0V8_PEX0_VINSEN")
	)
	(segment
		(start 116.173504 -256.626614)
		(end 116.67744 -257.13055)
		(width 0.254)
		(layer "B.Cu")
		(net "P0V8_PEX0_VINSEN")
	)
	(segment
		(start 115.320064 -261.046214)
		(end 115.847114 -261.573264)
		(width 0.254)
		(layer "F.Cu")
		(net "SH_P0V8_PEX1_VSEN1_R")
	)
	(segment
		(start 115.320064 -260.290564)
		(end 115.320064 -261.046214)
		(width 0.254)
		(layer "F.Cu")
		(net "SH_P0V8_PEX1_VSEN1_R")
	)
	(segment
		(start 176.610518 -63.169292)
		(end 176.147222 -62.705996)
		(width 0.4572)
		(layer "F.Cu")
		(net "P5V_AUX")
	)
	(segment
		(start 452.167752 -55.405274)
		(end 452.167752 -55.083456)
		(width 0.254)
		(layer "F.Cu")
		(net "P5V_AUX")
	)
	(segment
		(start 316.84087 -57.16397)
		(end 316.84087 -57.71261)
		(width 0.254)
		(layer "F.Cu")
		(net "P5V_AUX")
	)
	(segment
		(start 292.710362 -63.652146)
		(end 292.710362 -63.169292)
		(width 0.4572)
		(layer "F.Cu")
		(net "P5V_AUX")
	)
	(segment
		(start 242.5319 -209.628486)
		(end 242.042442 -209.139028)
		(width 0.4572)
		(layer "F.Cu")
		(net "P5V_AUX")
	)
	(segment
		(start 374.167908 -55.405274)
		(end 374.167908 -55.083456)
		(width 0.254)
		(layer "F.Cu")
		(net "P5V_AUX")
	)
	(segment
		(start 379.775212 -59.174634)
		(end 380.419102 -59.174634)
		(width 0.4572)
		(layer "F.Cu")
		(net "P5V_AUX")
	)
	(segment
		(start 446.432686 -122.082052)
		(end 446.875662 -122.525028)
		(width 0.381)
		(layer "F.Cu")
		(net "P5V_AUX")
	)
	(segment
		(start 127.947166 -112.355376)
		(end 127.947166 -111.739426)
		(width 0.4572)
		(layer "F.Cu")
		(net "P5V_AUX")
	)
	(segment
		(start 200.219056 -58.80481)
		(end 200.219056 -59.174634)
		(width 0.254)
		(layer "F.Cu")
		(net "P5V_AUX")
	)
	(segment
		(start 400.51609 -55.722266)
		(end 400.484848 -55.722266)
		(width 0.254)
		(layer "F.Cu")
		(net "P5V_AUX")
	)
	(segment
		(start 257.969512 -216.00668)
		(end 257.744468 -216.231724)
		(width 0.4572)
		(layer "F.Cu")
		(net "P5V_AUX")
	)
	(segment
		(start 282.347162 -54.644036)
		(end 283.258514 -54.644036)
		(width 0.254)
		(layer "F.Cu")
		(net "P5V_AUX")
	)
	(segment
		(start 232.517442 -67.200018)
		(end 233.572558 -67.200018)
		(width 0.3556)
		(layer "F.Cu")
		(net "P5V_AUX")
	)
	(segment
		(start 239.460278 -65.472056)
		(end 239.943132 -65.472056)
		(width 0.4572)
		(layer "F.Cu")
		(net "P5V_AUX")
	)
	(segment
		(start 425.79798 -55.083456)
		(end 426.167804 -55.083456)
		(width 0.254)
		(layer "F.Cu")
		(net "P5V_AUX")
	)
	(segment
		(start 310.384698 -55.722266)
		(end 310.067706 -55.405274)
		(width 0.254)
		(layer "F.Cu")
		(net "P5V_AUX")
	)
	(segment
		(start 406.41905 -59.174634)
		(end 405.77516 -59.174634)
		(width 0.4572)
		(layer "F.Cu")
		(net "P5V_AUX")
	)
	(segment
		(start 284.415992 -55.722266)
		(end 284.38475 -55.722266)
		(width 0.254)
		(layer "F.Cu")
		(net "P5V_AUX")
	)
	(segment
		(start 148.21916 -58.80481)
		(end 148.21916 -59.174634)
		(width 0.254)
		(layer "F.Cu")
		(net "P5V_AUX")
	)
	(segment
		(start 238.48822 -55.038244)
		(end 238.48822 -55.408068)
		(width 0.254)
		(layer "F.Cu")
		(net "P5V_AUX")
	)
	(segment
		(start 11.0744 -123.639326)
		(end 10.51052 -123.075446)
		(width 0.254)
		(layer "F.Cu")
		(net "P5V_AUX")
	)
	(segment
		(start 126.610364 -122.640852)
		(end 126.610364 -122.931428)
		(width 0.4064)
		(layer "F.Cu")
		(net "P5V_AUX")
	)
	(segment
		(start 354.419154 -58.80481)
		(end 354.419154 -59.174634)
		(width 0.254)
		(layer "F.Cu")
		(net "P5V_AUX")
	)
	(segment
		(start 50.14722 -54.644036)
		(end 51.058572 -54.644036)
		(width 0.254)
		(layer "F.Cu")
		(net "P5V_AUX")
	)
	(segment
		(start 126.610364 -122.931428)
		(end 126.68377 -122.931428)
		(width 0.254)
		(layer "F.Cu")
		(net "P5V_AUX")
	)
	(segment
		(start 434.810408 -63.169292)
		(end 434.347112 -62.705996)
		(width 0.4572)
		(layer "F.Cu")
		(net "P5V_AUX")
	)
	(segment
		(start 77.867764 -55.405274)
		(end 77.867764 -55.083456)
		(width 0.13208)
		(layer "F.Cu")
		(net "P5V_AUX")
	)
	(segment
		(start 256.347214 -54.644036)
		(end 257.258566 -54.644036)
		(width 0.254)
		(layer "F.Cu")
		(net "P5V_AUX")
	)
	(segment
		(start 226.02952 -98.76917)
		(end 226.377754 -98.420936)
		(width 0.4572)
		(layer "F.Cu")
		(net "P5V_AUX")
	)
	(segment
		(start 224.241868 -99.94265)
		(end 225.077274 -99.596702)
		(width 0.254)
		(layer "F.Cu")
		(net "P5V_AUX")
	)
	(segment
		(start 32.641032 -57.71261)
		(end 32.237934 -58.685938)
		(width 0.254)
		(layer "F.Cu")
		(net "P5V_AUX")
	)
	(segment
		(start 446.723262 -96.106742)
		(end 447.166238 -95.663766)
		(width 0.381)
		(layer "F.Cu")
		(net "P5V_AUX")
	)
	(segment
		(start 257.744468 -216.231724)
		(end 257.535172 -216.231724)
		(width 0.4572)
		(layer "F.Cu")
		(net "P5V_AUX")
	)
	(segment
		(start 330.082906 -97.467928)
		(end 330.082906 -97.107248)
		(width 0.254)
		(layer "F.Cu")
		(net "P5V_AUX")
	)
	(segment
		(start 174.219108 -58.80481)
		(end 174.219108 -59.174634)
		(width 0.254)
		(layer "F.Cu")
		(net "P5V_AUX")
	)
	(segment
		(start 256.259584 -214.934292)
		(end 256.890012 -215.56472)
		(width 0.3048)
		(layer "F.Cu")
		(net "P5V_AUX")
	)
	(segment
		(start 117.789452 -129.469642)
		(end 117.685312 -129.469642)
		(width 0.254)
		(layer "F.Cu")
		(net "P5V_AUX")
	)
	(segment
		(start 432.53787 -58.685938)
		(end 432.418998 -58.80481)
		(width 0.254)
		(layer "F.Cu")
		(net "P5V_AUX")
	)
	(segment
		(start 264.437876 -58.685938)
		(end 264.319004 -58.80481)
		(width 0.254)
		(layer "F.Cu")
		(net "P5V_AUX")
	)
	(segment
		(start 10.51052 -122.640852)
		(end 10.51052 -122.931428)
		(width 0.4064)
		(layer "F.Cu")
		(net "P5V_AUX")
	)
	(segment
		(start 219.96781 -55.083456)
		(end 219.96781 -55.405274)
		(width 0.254)
		(layer "F.Cu")
		(net "P5V_AUX")
	)
	(segment
		(start 360.147362 -112.355376)
		(end 360.147362 -111.739426)
		(width 0.4572)
		(layer "F.Cu")
		(net "P5V_AUX")
	)
	(segment
		(start 6.237986 -58.685938)
		(end 6.119114 -58.80481)
		(width 0.254)
		(layer "F.Cu")
		(net "P5V_AUX")
	)
	(segment
		(start 97.882964 -97.467928)
		(end 97.882964 -97.107248)
		(width 0.254)
		(layer "F.Cu")
		(net "P5V_AUX")
	)
	(segment
		(start 141.967966 -55.405274)
		(end 141.967966 -55.083456)
		(width 0.254)
		(layer "F.Cu")
		(net "P5V_AUX")
	)
	(segment
		(start 98.132646 -122.082052)
		(end 98.575622 -122.525028)
		(width 0.381)
		(layer "F.Cu")
		(net "P5V_AUX")
	)
	(segment
		(start 124.610622 -63.169292)
		(end 124.147326 -62.705996)
		(width 0.4572)
		(layer "F.Cu")
		(net "P5V_AUX")
	)
	(segment
		(start 283.081984 -38.041072)
		(end 283.081984 -38.750748)
		(width 0.4572)
		(layer "F.Cu")
		(net "P5V_AUX")
	)
	(segment
		(start 456.218544 -120.53824)
		(end 456.218544 -119.718836)
		(width 0.4572)
		(layer "F.Cu")
		(net "P5V_AUX")
	)
	(segment
		(start 283.697934 -55.083456)
		(end 284.067758 -55.083456)
		(width 0.254)
		(layer "F.Cu")
		(net "P5V_AUX")
	)
	(segment
		(start 406.537922 -58.685938)
		(end 406.41905 -58.80481)
		(width 0.254)
		(layer "F.Cu")
		(net "P5V_AUX")
	)
	(segment
		(start 316.3189 -59.174634)
		(end 315.67501 -59.174634)
		(width 0.4572)
		(layer "F.Cu")
		(net "P5V_AUX")
	)
	(segment
		(start 58.11901 -59.174634)
		(end 57.47512 -59.174634)
		(width 0.4572)
		(layer "F.Cu")
		(net "P5V_AUX")
	)
	(segment
		(start 150.61057 -63.652146)
		(end 150.61057 -63.169292)
		(width 0.4572)
		(layer "F.Cu")
		(net "P5V_AUX")
	)
	(segment
		(start 360.531156 -124.894848)
		(end 360.22026 -124.894848)
		(width 0.254)
		(layer "F.Cu")
		(net "P5V_AUX")
	)
	(segment
		(start 309.258462 -54.644036)
		(end 309.697882 -55.083456)
		(width 0.254)
		(layer "F.Cu")
		(net "P5V_AUX")
	)
	(segment
		(start 358.034082 -136.767824)
		(end 357.12273 -136.767824)
		(width 0.254)
		(layer "F.Cu")
		(net "P5V_AUX")
	)
	(segment
		(start 225.738944 -98.76917)
		(end 226.02952 -98.76917)
		(width 0.4572)
		(layer "F.Cu")
		(net "P5V_AUX")
	)
	(segment
		(start 174.741078 -57.71261)
		(end 174.33798 -58.685938)
		(width 0.254)
		(layer "F.Cu")
		(net "P5V_AUX")
	)
	(segment
		(start 11.629898 -124.581666)
		(end 11.0744 -124.026168)
		(width 0.254)
		(layer "F.Cu")
		(net "P5V_AUX")
	)
	(segment
		(start 77.49794 -55.083456)
		(end 77.867764 -55.083456)
		(width 0.254)
		(layer "F.Cu")
		(net "P5V_AUX")
	)
	(segment
		(start 7.664958 -135.689594)
		(end 8.013192 -135.689594)
		(width 0.254)
		(layer "F.Cu")
		(net "P5V_AUX")
	)
	(segment
		(start 128.07696 -124.894848)
		(end 128.33096 -124.894848)
		(width 0.254)
		(layer "F.Cu")
		(net "P5V_AUX")
	)
	(segment
		(start 167.15867 -54.644036)
		(end 167.59809 -55.083456)
		(width 0.254)
		(layer "F.Cu")
		(net "P5V_AUX")
	)
	(segment
		(start 255.88976 -214.934292)
		(end 256.259584 -214.934292)
		(width 0.3048)
		(layer "F.Cu")
		(net "P5V_AUX")
	)
	(segment
		(start 122.640344 -135.699246)
		(end 123.774708 -135.699246)
		(width 0.254)
		(layer "F.Cu")
		(net "P5V_AUX")
	)
	(segment
		(start 168.316148 -55.722266)
		(end 168.284906 -55.722266)
		(width 0.254)
		(layer "F.Cu")
		(net "P5V_AUX")
	)
	(segment
		(start 225.621596 -99.05238)
		(end 225.738944 -98.76917)
		(width 0.4572)
		(layer "F.Cu")
		(net "P5V_AUX")
	)
	(segment
		(start 50.882042 -38.041072)
		(end 50.882042 -38.750748)
		(width 0.4572)
		(layer "F.Cu")
		(net "P5V_AUX")
	)
	(segment
		(start 32.119062 -59.174634)
		(end 31.475172 -59.174634)
		(width 0.4572)
		(layer "F.Cu")
		(net "P5V_AUX")
	)
	(segment
		(start 51.867816 -55.405274)
		(end 51.867816 -55.083456)
		(width 0.254)
		(layer "F.Cu")
		(net "P5V_AUX")
	)
	(segment
		(start 264.840974 -57.71261)
		(end 264.437876 -58.685938)
		(width 0.254)
		(layer "F.Cu")
		(net "P5V_AUX")
	)
	(segment
		(start 34.510472 -63.169292)
		(end 34.047176 -62.705996)
		(width 0.4572)
		(layer "F.Cu")
		(net "P5V_AUX")
	)
	(segment
		(start 446.723262 -96.56699)
		(end 446.723262 -96.106742)
		(width 0.381)
		(layer "F.Cu")
		(net "P5V_AUX")
	)
	(segment
		(start 318.71031 -63.652146)
		(end 318.71031 -63.169292)
		(width 0.4572)
		(layer "F.Cu")
		(net "P5V_AUX")
	)
	(segment
		(start 232.517442 -63.000128)
		(end 231.388158 -63.000128)
		(width 0.3556)
		(layer "F.Cu")
		(net "P5V_AUX")
	)
	(segment
		(start 148.338032 -58.685938)
		(end 148.21916 -58.80481)
		(width 0.254)
		(layer "F.Cu")
		(net "P5V_AUX")
	)
	(segment
		(start 174.741078 -57.16397)
		(end 174.741078 -57.71261)
		(width 0.254)
		(layer "F.Cu")
		(net "P5V_AUX")
	)
	(segment
		(start 148.74113 -57.71261)
		(end 148.338032 -58.685938)
		(width 0.254)
		(layer "F.Cu")
		(net "P5V_AUX")
	)
	(segment
		(start 223.695768 -100.856542)
		(end 223.695768 -100.48875)
		(width 0.254)
		(layer "F.Cu")
		(net "P5V_AUX")
	)
	(segment
		(start 117.558312 -129.342642)
		(end 117.558312 -128.947926)
		(width 0.254)
		(layer "F.Cu")
		(net "P5V_AUX")
	)
	(segment
		(start 316.3189 -58.80481)
		(end 316.3189 -59.174634)
		(width 0.254)
		(layer "F.Cu")
		(net "P5V_AUX")
	)
	(segment
		(start 229.437438 -69.000116)
		(end 227.916994 -69.000116)
		(width 0.3048)
		(layer "F.Cu")
		(net "P5V_AUX")
	)
	(segment
		(start 8.013192 -135.689594)
		(end 8.013446 -135.689848)
		(width 0.254)
		(layer "F.Cu")
		(net "P5V_AUX")
	)
	(segment
		(start 329.87234 -122.082052)
		(end 330.332588 -122.082052)
		(width 0.381)
		(layer "F.Cu")
		(net "P5V_AUX")
	)
	(segment
		(start 398.44726 -54.644036)
		(end 399.358612 -54.644036)
		(width 0.254)
		(layer "F.Cu")
		(net "P5V_AUX")
	)
	(segment
		(start 6.641084 -57.16397)
		(end 6.641084 -57.71261)
		(width 0.254)
		(layer "F.Cu")
		(net "P5V_AUX")
	)
	(segment
		(start 104.215946 -55.722266)
		(end 104.184704 -55.722266)
		(width 0.254)
		(layer "F.Cu")
		(net "P5V_AUX")
	)
	(segment
		(start 406.94102 -57.16397)
		(end 406.94102 -57.71261)
		(width 0.254)
		(layer "F.Cu")
		(net "P5V_AUX")
	)
	(segment
		(start 78.215998 -55.722266)
		(end 78.184756 -55.722266)
		(width 0.13208)
		(layer "F.Cu")
		(net "P5V_AUX")
	)
	(segment
		(start 233.518964 -68.189348)
		(end 233.582464 -68.189348)
		(width 0.3556)
		(layer "F.Cu")
		(net "P5V_AUX")
	)
	(segment
		(start 86.510368 -63.169292)
		(end 86.047072 -62.705996)
		(width 0.4572)
		(layer "F.Cu")
		(net "P5V_AUX")
	)
	(segment
		(start 98.423222 -96.106742)
		(end 98.866198 -95.663766)
		(width 0.381)
		(layer "F.Cu")
		(net "P5V_AUX")
	)
	(segment
		(start 98.575622 -122.91822)
		(end 98.333814 -123.160028)
		(width 0.381)
		(layer "F.Cu")
		(net "P5V_AUX")
	)
	(segment
		(start 318.71031 -63.169292)
		(end 318.247014 -62.705996)
		(width 0.4572)
		(layer "F.Cu")
		(net "P5V_AUX")
	)
	(segment
		(start 122.741182 -57.16397)
		(end 122.741182 -57.71261)
		(width 0.254)
		(layer "F.Cu")
		(net "P5V_AUX")
	)
	(segment
		(start 84.640928 -57.71261)
		(end 84.23783 -58.685938)
		(width 0.254)
		(layer "F.Cu")
		(net "P5V_AUX")
	)
	(segment
		(start 84.118958 -59.174634)
		(end 83.475068 -59.174634)
		(width 0.4572)
		(layer "F.Cu")
		(net "P5V_AUX")
	)
	(segment
		(start 399.798032 -55.083456)
		(end 400.167856 -55.083456)
		(width 0.254)
		(layer "F.Cu")
		(net "P5V_AUX")
	)
	(segment
		(start 142.3162 -55.722266)
		(end 142.284958 -55.722266)
		(width 0.254)
		(layer "F.Cu")
		(net "P5V_AUX")
	)
	(segment
		(start 336.067654 -55.083456)
		(end 336.067654 -55.405274)
		(width 0.254)
		(layer "F.Cu")
		(net "P5V_AUX")
	)
	(segment
		(start 359.327704 -123.59259)
		(end 358.81056 -123.075446)
		(width 0.254)
		(layer "F.Cu")
		(net "P5V_AUX")
	)
	(segment
		(start 8.510524 -63.652146)
		(end 8.510524 -63.169292)
		(width 0.4572)
		(layer "F.Cu")
		(net "P5V_AUX")
	)
	(segment
		(start 86.510368 -63.652146)
		(end 86.510368 -63.169292)
		(width 0.4572)
		(layer "F.Cu")
		(net "P5V_AUX")
	)
	(segment
		(start 23.326852 -174.417482)
		(end 23.326852 -173.374558)
		(width 0.254)
		(layer "F.Cu")
		(net "P5V_AUX")
	)
	(segment
		(start 141.158722 -54.644036)
		(end 141.598142 -55.083456)
		(width 0.254)
		(layer "F.Cu")
		(net "P5V_AUX")
	)
	(segment
		(start 330.623164 -96.56699)
		(end 330.623164 -96.106742)
		(width 0.381)
		(layer "F.Cu")
		(net "P5V_AUX")
	)
	(segment
		(start 451.358508 -54.644036)
		(end 451.797928 -55.083456)
		(width 0.254)
		(layer "F.Cu")
		(net "P5V_AUX")
	)
	(segment
		(start 241.022632 -136.767824)
		(end 240.583212 -136.328404)
		(width 0.254)
		(layer "F.Cu")
		(net "P5V_AUX")
	)
	(segment
		(start 140.982192 -38.041072)
		(end 140.982192 -38.750748)
		(width 0.4572)
		(layer "F.Cu")
		(net "P5V_AUX")
	)
	(segment
		(start 51.058572 -54.644036)
		(end 51.497992 -55.083456)
		(width 0.254)
		(layer "F.Cu")
		(net "P5V_AUX")
	)
	(segment
		(start 192.982088 -38.041072)
		(end 192.982088 -38.750748)
		(width 0.4572)
		(layer "F.Cu")
		(net "P5V_AUX")
	)
	(segment
		(start 200.337928 -58.685938)
		(end 200.219056 -58.80481)
		(width 0.254)
		(layer "F.Cu")
		(net "P5V_AUX")
	)
	(segment
		(start 331.459332 -95.663766)
		(end 331.70114 -95.905574)
		(width 0.381)
		(layer "F.Cu")
		(net "P5V_AUX")
	)
	(segment
		(start 115.838732 -126.90475)
		(end 116.393976 -127.459994)
		(width 0.254)
		(layer "F.Cu")
		(net "P5V_AUX")
	)
	(segment
		(start 258.06781 -55.405274)
		(end 258.06781 -55.083456)
		(width 0.254)
		(layer "F.Cu")
		(net "P5V_AUX")
	)
	(segment
		(start 117.685312 -129.469642)
		(end 117.558312 -129.342642)
		(width 0.254)
		(layer "F.Cu")
		(net "P5V_AUX")
	)
	(segment
		(start 219.158566 -54.644036)
		(end 219.597986 -55.083456)
		(width 0.254)
		(layer "F.Cu")
		(net "P5V_AUX")
	)
	(segment
		(start 98.866198 -95.663766)
		(end 99.25939 -95.663766)
		(width 0.381)
		(layer "F.Cu")
		(net "P5V_AUX")
	)
	(segment
		(start 328.971402 -121.541794)
		(end 329.332082 -121.541794)
		(width 0.254)
		(layer "F.Cu")
		(net "P5V_AUX")
	)
	(segment
		(start 11.629898 -124.620274)
		(end 11.629898 -124.581666)
		(width 0.254)
		(layer "F.Cu")
		(net "P5V_AUX")
	)
	(segment
		(start 42.211752 -270.903954)
		(end 46.693582 -270.903954)
		(width 0.508)
		(layer "F.Cu")
		(net "P5V_AUX")
	)
	(segment
		(start 244.431058 -124.894848)
		(end 244.179852 -124.894848)
		(width 0.254)
		(layer "F.Cu")
		(net "P5V_AUX")
	)
	(segment
		(start 212.871304 -120.271794)
		(end 213.231984 -120.271794)
		(width 0.254)
		(layer "F.Cu")
		(net "P5V_AUX")
	)
	(segment
		(start 84.640928 -57.16397)
		(end 84.640928 -57.71261)
		(width 0.254)
		(layer "F.Cu")
		(net "P5V_AUX")
	)
	(segment
		(start 240.086134 -135.910574)
		(end 240.086134 -136.20115)
		(width 0.254)
		(layer "F.Cu")
		(net "P5V_AUX")
	)
	(segment
		(start 60.51042 -63.169292)
		(end 60.047124 -62.705996)
		(width 0.4572)
		(layer "F.Cu")
		(net "P5V_AUX")
	)
	(segment
		(start 52.21605 -55.722266)
		(end 52.184808 -55.722266)
		(width 0.254)
		(layer "F.Cu")
		(net "P5V_AUX")
	)
	(segment
		(start 445.972438 -122.082052)
		(end 446.432686 -122.082052)
		(width 0.381)
		(layer "F.Cu")
		(net "P5V_AUX")
	)
	(segment
		(start 174.33798 -58.685938)
		(end 174.219108 -58.80481)
		(width 0.254)
		(layer "F.Cu")
		(net "P5V_AUX")
	)
	(segment
		(start 432.940968 -57.16397)
		(end 432.940968 -57.71261)
		(width 0.254)
		(layer "F.Cu")
		(net "P5V_AUX")
	)
	(segment
		(start 8.510524 -68.732146)
		(end 8.510524 -68.249292)
		(width 0.4572)
		(layer "F.Cu")
		(net "P5V_AUX")
	)
	(segment
		(start 284.38475 -55.722266)
		(end 284.067758 -55.405274)
		(width 0.254)
		(layer "F.Cu")
		(net "P5V_AUX")
	)
	(segment
		(start 264.319004 -59.174634)
		(end 263.675114 -59.174634)
		(width 0.4572)
		(layer "F.Cu")
		(net "P5V_AUX")
	)
	(segment
		(start 373.798084 -55.083456)
		(end 374.167908 -55.083456)
		(width 0.254)
		(layer "F.Cu")
		(net "P5V_AUX")
	)
	(segment
		(start 359.327704 -124.002292)
		(end 359.327704 -123.59259)
		(width 0.254)
		(layer "F.Cu")
		(net "P5V_AUX")
	)
	(segment
		(start 76.88199 -38.041072)
		(end 76.88199 -38.750748)
		(width 0.4572)
		(layer "F.Cu")
		(net "P5V_AUX")
	)
	(segment
		(start 426.167804 -55.405274)
		(end 426.167804 -55.083456)
		(width 0.254)
		(layer "F.Cu")
		(net "P5V_AUX")
	)
	(segment
		(start 60.51042 -63.652146)
		(end 60.51042 -63.169292)
		(width 0.4572)
		(layer "F.Cu")
		(net "P5V_AUX")
	)
	(segment
		(start 239.01019 -53.397404)
		(end 239.01019 -53.946044)
		(width 0.254)
		(layer "F.Cu")
		(net "P5V_AUX")
	)
	(segment
		(start 58.237882 -58.685938)
		(end 58.11901 -58.80481)
		(width 0.254)
		(layer "F.Cu")
		(net "P5V_AUX")
	)
	(segment
		(start 99.25939 -95.663766)
		(end 99.501198 -95.905574)
		(width 0.381)
		(layer "F.Cu")
		(net "P5V_AUX")
	)
	(segment
		(start 8.82269 -136.767824)
		(end 8.38327 -136.328404)
		(width 0.254)
		(layer "F.Cu")
		(net "P5V_AUX")
	)
	(segment
		(start 450.447156 -54.644036)
		(end 451.358508 -54.644036)
		(width 0.254)
		(layer "F.Cu")
		(net "P5V_AUX")
	)
	(segment
		(start 432.940968 -57.71261)
		(end 432.53787 -58.685938)
		(width 0.254)
		(layer "F.Cu")
		(net "P5V_AUX")
	)
	(segment
		(start 225.813366 -123.520962)
		(end 226.429316 -123.520962)
		(width 0.4572)
		(layer "F.Cu")
		(net "P5V_AUX")
	)
	(segment
		(start 357.12273 -136.767824)
		(end 356.68331 -136.328404)
		(width 0.254)
		(layer "F.Cu")
		(net "P5V_AUX")
	)
	(segment
		(start 25.498044 -55.083456)
		(end 25.867868 -55.083456)
		(width 0.254)
		(layer "F.Cu")
		(net "P5V_AUX")
	)
	(segment
		(start 432.418998 -58.80481)
		(end 432.418998 -59.174634)
		(width 0.254)
		(layer "F.Cu")
		(net "P5V_AUX")
	)
	(segment
		(start 8.510524 -63.169292)
		(end 8.047228 -62.705996)
		(width 0.4572)
		(layer "F.Cu")
		(net "P5V_AUX")
	)
	(segment
		(start 166.98214 -38.041072)
		(end 166.98214 -38.750748)
		(width 0.4572)
		(layer "F.Cu")
		(net "P5V_AUX")
	)
	(segment
		(start 447.166238 -95.663766)
		(end 447.55943 -95.663766)
		(width 0.381)
		(layer "F.Cu")
		(net "P5V_AUX")
	)
	(segment
		(start 373.358664 -54.644036)
		(end 373.798084 -55.083456)
		(width 0.254)
		(layer "F.Cu")
		(net "P5V_AUX")
	)
	(segment
		(start 25.058624 -54.644036)
		(end 25.498044 -55.083456)
		(width 0.254)
		(layer "F.Cu")
		(net "P5V_AUX")
	)
	(segment
		(start 8.38327 -136.328404)
		(end 8.013446 -136.328404)
		(width 0.254)
		(layer "F.Cu")
		(net "P5V_AUX")
	)
	(segment
		(start 244.179852 -124.894848)
		(end 243.9035 -124.780294)
		(width 0.254)
		(layer "F.Cu")
		(net "P5V_AUX")
	)
	(segment
		(start 142.284958 -55.722266)
		(end 141.967966 -55.405274)
		(width 0.254)
		(layer "F.Cu")
		(net "P5V_AUX")
	)
	(segment
		(start 242.710462 -123.075446)
		(end 242.710462 -122.931428)
		(width 0.254)
		(layer "F.Cu")
		(net "P5V_AUX")
	)
	(segment
		(start 238.48822 -55.408068)
		(end 237.84433 -55.408068)
		(width 0.4572)
		(layer "F.Cu")
		(net "P5V_AUX")
	)
	(segment
		(start 202.610466 -63.169292)
		(end 202.14717 -62.705996)
		(width 0.4572)
		(layer "F.Cu")
		(net "P5V_AUX")
	)
	(segment
		(start 358.81056 -123.075446)
		(end 358.81056 -122.931428)
		(width 0.254)
		(layer "F.Cu")
		(net "P5V_AUX")
	)
	(segment
		(start 32.641032 -57.16397)
		(end 32.641032 -57.71261)
		(width 0.254)
		(layer "F.Cu")
		(net "P5V_AUX")
	)
	(segment
		(start 5.684774 -394.145008)
		(end 5.684774 -394.754608)
		(width 0.4572)
		(layer "F.Cu")
		(net "P5V_AUX")
	)
	(segment
		(start 316.437772 -58.685938)
		(end 316.3189 -58.80481)
		(width 0.254)
		(layer "F.Cu")
		(net "P5V_AUX")
	)
	(segment
		(start 329.332082 -121.541794)
		(end 329.87234 -122.082052)
		(width 0.254)
		(layer "F.Cu")
		(net "P5V_AUX")
	)
	(segment
		(start 432.418998 -59.174634)
		(end 431.775108 -59.174634)
		(width 0.4572)
		(layer "F.Cu")
		(net "P5V_AUX")
	)
	(segment
		(start 194.284854 -55.722266)
		(end 193.967862 -55.405274)
		(width 0.254)
		(layer "F.Cu")
		(net "P5V_AUX")
	)
	(segment
		(start 335.69783 -55.083456)
		(end 336.067654 -55.083456)
		(width 0.254)
		(layer "F.Cu")
		(net "P5V_AUX")
	)
	(segment
		(start 200.219056 -59.174634)
		(end 199.575166 -59.174634)
		(width 0.4572)
		(layer "F.Cu")
		(net "P5V_AUX")
	)
	(segment
		(start 330.082906 -97.107248)
		(end 330.623164 -96.56699)
		(width 0.254)
		(layer "F.Cu")
		(net "P5V_AUX")
	)
	(segment
		(start 380.941072 -57.16397)
		(end 380.941072 -57.71261)
		(width 0.254)
		(layer "F.Cu")
		(net "P5V_AUX")
	)
	(segment
		(start 24.882094 -38.041072)
		(end 24.882094 -38.750748)
		(width 0.4572)
		(layer "F.Cu")
		(net "P5V_AUX")
	)
	(segment
		(start 122.219212 -58.80481)
		(end 122.219212 -59.174634)
		(width 0.254)
		(layer "F.Cu")
		(net "P5V_AUX")
	)
	(segment
		(start 174.219108 -59.174634)
		(end 173.575218 -59.174634)
		(width 0.4572)
		(layer "F.Cu")
		(net "P5V_AUX")
	)
	(segment
		(start 52.184808 -55.722266)
		(end 51.867816 -55.405274)
		(width 0.254)
		(layer "F.Cu")
		(net "P5V_AUX")
	)
	(segment
		(start 166.247318 -54.644036)
		(end 167.15867 -54.644036)
		(width 0.254)
		(layer "F.Cu")
		(net "P5V_AUX")
	)
	(segment
		(start 141.598142 -55.083456)
		(end 141.967966 -55.083456)
		(width 0.254)
		(layer "F.Cu")
		(net "P5V_AUX")
	)
	(segment
		(start 97.672398 -122.082052)
		(end 98.132646 -122.082052)
		(width 0.381)
		(layer "F.Cu")
		(net "P5V_AUX")
	)
	(segment
		(start 124.922534 -136.767824)
		(end 124.483114 -136.328404)
		(width 0.254)
		(layer "F.Cu")
		(net "P5V_AUX")
	)
	(segment
		(start 46.693582 -270.903954)
		(end 49.77257 -267.824966)
		(width 0.508)
		(layer "F.Cu")
		(net "P5V_AUX")
	)
	(segment
		(start 256.890012 -215.56472)
		(end 257.969512 -215.56472)
		(width 0.3048)
		(layer "F.Cu")
		(net "P5V_AUX")
	)
	(segment
		(start 266.710414 -63.652146)
		(end 266.710414 -63.169292)
		(width 0.4572)
		(layer "F.Cu")
		(net "P5V_AUX")
	)
	(segment
		(start 12.560046 -174.872142)
		(end 12.560046 -175.317404)
		(width 0.254)
		(layer "F.Cu")
		(net "P5V_AUX")
	)
	(segment
		(start 12.708636 -175.465994)
		(end 13.254228 -175.465994)
		(width 0.254)
		(layer "F.Cu")
		(net "P5V_AUX")
	)
	(segment
		(start 214.675466 -121.64822)
		(end 214.433658 -121.890028)
		(width 0.381)
		(layer "F.Cu")
		(net "P5V_AUX")
	)
	(segment
		(start 148.74113 -57.16397)
		(end 148.74113 -57.71261)
		(width 0.254)
		(layer "F.Cu")
		(net "P5V_AUX")
	)
	(segment
		(start 308.34711 -54.644036)
		(end 309.258462 -54.644036)
		(width 0.254)
		(layer "F.Cu")
		(net "P5V_AUX")
	)
	(segment
		(start 124.483114 -136.328404)
		(end 124.11329 -136.328404)
		(width 0.254)
		(layer "F.Cu")
		(net "P5V_AUX")
	)
	(segment
		(start 126.68377 -122.931428)
		(end 127.209296 -123.456954)
		(width 0.254)
		(layer "F.Cu")
		(net "P5V_AUX")
	)
	(segment
		(start 124.028962 -136.244076)
		(end 124.11329 -136.328404)
		(width 0.254)
		(layer "F.Cu")
		(net "P5V_AUX")
	)
	(segment
		(start 49.77257 -267.824966)
		(end 49.77257 -262.562848)
		(width 0.508)
		(layer "F.Cu")
		(net "P5V_AUX")
	)
	(segment
		(start 399.358612 -54.644036)
		(end 399.798032 -55.083456)
		(width 0.254)
		(layer "F.Cu")
		(net "P5V_AUX")
	)
	(segment
		(start 446.875662 -122.525028)
		(end 446.875662 -122.91822)
		(width 0.381)
		(layer "F.Cu")
		(net "P5V_AUX")
	)
	(segment
		(start 219.96781 -55.405274)
		(end 220.284802 -55.722266)
		(width 0.254)
		(layer "F.Cu")
		(net "P5V_AUX")
	)
	(segment
		(start 26.18486 -55.722266)
		(end 25.867868 -55.405274)
		(width 0.254)
		(layer "F.Cu")
		(net "P5V_AUX")
	)
	(segment
		(start 257.082036 -38.041072)
		(end 257.082036 -38.750748)
		(width 0.4572)
		(layer "F.Cu")
		(net "P5V_AUX")
	)
	(segment
		(start 408.81046 -63.169292)
		(end 408.347164 -62.705996)
		(width 0.4572)
		(layer "F.Cu")
		(net "P5V_AUX")
	)
	(segment
		(start 452.484744 -55.722266)
		(end 452.167752 -55.405274)
		(width 0.254)
		(layer "F.Cu")
		(net "P5V_AUX")
	)
	(segment
		(start 452.515986 -55.722266)
		(end 452.484744 -55.722266)
		(width 0.254)
		(layer "F.Cu")
		(net "P5V_AUX")
	)
	(segment
		(start 446.183004 -97.107248)
		(end 446.723262 -96.56699)
		(width 0.254)
		(layer "F.Cu")
		(net "P5V_AUX")
	)
	(segment
		(start 231.082088 -38.041072)
		(end 231.082088 -38.750748)
		(width 0.4572)
		(layer "F.Cu")
		(net "P5V_AUX")
	)
	(segment
		(start 399.182082 -38.041072)
		(end 399.182082 -38.750748)
		(width 0.4572)
		(layer "F.Cu")
		(net "P5V_AUX")
	)
	(segment
		(start 13.254228 -175.465994)
		(end 13.680694 -175.89246)
		(width 0.254)
		(layer "F.Cu")
		(net "P5V_AUX")
	)
	(segment
		(start 242.710462 -122.931428)
		(end 242.710462 -122.640852)
		(width 0.4064)
		(layer "F.Cu")
		(net "P5V_AUX")
	)
	(segment
		(start 193.158618 -54.644036)
		(end 193.598038 -55.083456)
		(width 0.254)
		(layer "F.Cu")
		(net "P5V_AUX")
	)
	(segment
		(start 335.25841 -54.644036)
		(end 335.69783 -55.083456)
		(width 0.254)
		(layer "F.Cu")
		(net "P5V_AUX")
	)
	(segment
		(start 148.21916 -59.174634)
		(end 147.57527 -59.174634)
		(width 0.4572)
		(layer "F.Cu")
		(net "P5V_AUX")
	)
	(segment
		(start 167.967914 -55.405274)
		(end 167.967914 -55.083456)
		(width 0.254)
		(layer "F.Cu")
		(net "P5V_AUX")
	)
	(segment
		(start 124.610622 -63.652146)
		(end 124.610622 -63.169292)
		(width 0.4572)
		(layer "F.Cu")
		(net "P5V_AUX")
	)
	(segment
		(start 168.284906 -55.722266)
		(end 167.967914 -55.405274)
		(width 0.254)
		(layer "F.Cu")
		(net "P5V_AUX")
	)
	(segment
		(start 214.23249 -120.812052)
		(end 214.675466 -121.255028)
		(width 0.381)
		(layer "F.Cu")
		(net "P5V_AUX")
	)
	(segment
		(start 98.575622 -122.525028)
		(end 98.575622 -122.91822)
		(width 0.381)
		(layer "F.Cu")
		(net "P5V_AUX")
	)
	(segment
		(start 406.94102 -57.71261)
		(end 406.537922 -58.685938)
		(width 0.254)
		(layer "F.Cu")
		(net "P5V_AUX")
	)
	(segment
		(start 127.209296 -123.456954)
		(end 127.209296 -124.104146)
		(width 0.254)
		(layer "F.Cu")
		(net "P5V_AUX")
	)
	(segment
		(start 176.610518 -63.652146)
		(end 176.610518 -63.169292)
		(width 0.4572)
		(layer "F.Cu")
		(net "P5V_AUX")
	)
	(segment
		(start 292.710362 -63.169292)
		(end 292.247066 -62.705996)
		(width 0.4572)
		(layer "F.Cu")
		(net "P5V_AUX")
	)
	(segment
		(start 12.355322 -113.117376)
		(end 12.355322 -112.501426)
		(width 0.4572)
		(layer "F.Cu")
		(net "P5V_AUX")
	)
	(segment
		(start 330.623164 -96.106742)
		(end 331.06614 -95.663766)
		(width 0.381)
		(layer "F.Cu")
		(net "P5V_AUX")
	)
	(segment
		(start 358.81056 -122.640852)
		(end 358.462326 -122.292618)
		(width 0.4064)
		(layer "F.Cu")
		(net "P5V_AUX")
	)
	(segment
		(start 373.182134 -38.041072)
		(end 373.182134 -38.750748)
		(width 0.4572)
		(layer "F.Cu")
		(net "P5V_AUX")
	)
	(segment
		(start 58.64098 -57.71261)
		(end 58.237882 -58.685938)
		(width 0.254)
		(layer "F.Cu")
		(net "P5V_AUX")
	)
	(segment
		(start 117.906546 -129.586736)
		(end 117.789452 -129.469642)
		(width 0.254)
		(layer "F.Cu")
		(net "P5V_AUX")
	)
	(segment
		(start 356.810564 -63.169292)
		(end 356.347268 -62.705996)
		(width 0.4572)
		(layer "F.Cu")
		(net "P5V_AUX")
	)
	(segment
		(start 290.437824 -58.685938)
		(end 290.318952 -58.80481)
		(width 0.254)
		(layer "F.Cu")
		(net "P5V_AUX")
	)
	(segment
		(start 103.497888 -55.083456)
		(end 103.867712 -55.083456)
		(width 0.254)
		(layer "F.Cu")
		(net "P5V_AUX")
	)
	(segment
		(start 238.607092 -54.919372)
		(end 238.48822 -55.038244)
		(width 0.254)
		(layer "F.Cu")
		(net "P5V_AUX")
	)
	(segment
		(start 21.851874 -175.89246)
		(end 23.326852 -174.417482)
		(width 0.254)
		(layer "F.Cu")
		(net "P5V_AUX")
	)
	(segment
		(start 124.028962 -135.9535)
		(end 124.028962 -136.244076)
		(width 0.254)
		(layer "F.Cu")
		(net "P5V_AUX")
	)
	(segment
		(start 264.840974 -57.16397)
		(end 264.840974 -57.71261)
		(width 0.254)
		(layer "F.Cu")
		(net "P5V_AUX")
	)
	(segment
		(start 290.318952 -58.80481)
		(end 290.318952 -59.174634)
		(width 0.254)
		(layer "F.Cu")
		(net "P5V_AUX")
	)
	(segment
		(start 34.510472 -63.652146)
		(end 34.510472 -63.169292)
		(width 0.4572)
		(layer "F.Cu")
		(net "P5V_AUX")
	)
	(segment
		(start 310.067706 -55.405274)
		(end 310.067706 -55.083456)
		(width 0.254)
		(layer "F.Cu")
		(net "P5V_AUX")
	)
	(segment
		(start 8.013446 -135.689848)
		(end 8.013446 -136.328404)
		(width 0.254)
		(layer "F.Cu")
		(net "P5V_AUX")
	)
	(segment
		(start 125.833886 -136.767824)
		(end 124.922534 -136.767824)
		(width 0.254)
		(layer "F.Cu")
		(net "P5V_AUX")
	)
	(segment
		(start 380.419102 -58.80481)
		(end 380.419102 -59.174634)
		(width 0.254)
		(layer "F.Cu")
		(net "P5V_AUX")
	)
	(segment
		(start 355.965252 -135.689594)
		(end 356.21214 -135.936482)
		(width 0.254)
		(layer "F.Cu")
		(net "P5V_AUX")
	)
	(segment
		(start 347.182186 -38.041072)
		(end 347.182186 -38.750748)
		(width 0.4572)
		(layer "F.Cu")
		(net "P5V_AUX")
	)
	(segment
		(start 356.21214 -136.227058)
		(end 356.313486 -136.328404)
		(width 0.254)
		(layer "F.Cu")
		(net "P5V_AUX")
	)
	(segment
		(start 232.517442 -68.399914)
		(end 233.308398 -68.399914)
		(width 0.3556)
		(layer "F.Cu")
		(net "P5V_AUX")
	)
	(segment
		(start 97.882964 -97.107248)
		(end 98.423222 -96.56699)
		(width 0.254)
		(layer "F.Cu")
		(net "P5V_AUX")
	)
	(segment
		(start 290.318952 -59.174634)
		(end 289.675062 -59.174634)
		(width 0.4572)
		(layer "F.Cu")
		(net "P5V_AUX")
	)
	(segment
		(start 239.865154 -135.689594)
		(end 240.086134 -135.910574)
		(width 0.254)
		(layer "F.Cu")
		(net "P5V_AUX")
	)
	(segment
		(start 336.067654 -55.405274)
		(end 336.384646 -55.722266)
		(width 0.254)
		(layer "F.Cu")
		(net "P5V_AUX")
	)
	(segment
		(start 330.775564 -122.91822)
		(end 330.533756 -123.160028)
		(width 0.381)
		(layer "F.Cu")
		(net "P5V_AUX")
	)
	(segment
		(start 354.538026 -58.685938)
		(end 354.419154 -58.80481)
		(width 0.254)
		(layer "F.Cu")
		(net "P5V_AUX")
	)
	(segment
		(start 380.941072 -57.71261)
		(end 380.537974 -58.685938)
		(width 0.254)
		(layer "F.Cu")
		(net "P5V_AUX")
	)
	(segment
		(start 150.61057 -63.169292)
		(end 150.147274 -62.705996)
		(width 0.4572)
		(layer "F.Cu")
		(net "P5V_AUX")
	)
	(segment
		(start 214.675466 -121.255028)
		(end 214.675466 -121.64822)
		(width 0.381)
		(layer "F.Cu")
		(net "P5V_AUX")
	)
	(segment
		(start 425.35856 -54.644036)
		(end 425.79798 -55.083456)
		(width 0.254)
		(layer "F.Cu")
		(net "P5V_AUX")
	)
	(segment
		(start 12.560046 -175.317404)
		(end 12.708636 -175.465994)
		(width 0.254)
		(layer "F.Cu")
		(net "P5V_AUX")
	)
	(segment
		(start 96.77146 -121.541794)
		(end 97.13214 -121.541794)
		(width 0.254)
		(layer "F.Cu")
		(net "P5V_AUX")
	)
	(segment
		(start 6.119114 -59.174634)
		(end 5.475224 -59.174634)
		(width 0.4572)
		(layer "F.Cu")
		(net "P5V_AUX")
	)
	(segment
		(start 193.598038 -55.083456)
		(end 193.967862 -55.083456)
		(width 0.254)
		(layer "F.Cu")
		(net "P5V_AUX")
	)
	(segment
		(start 115.47094 -126.90475)
		(end 115.838732 -126.90475)
		(width 0.254)
		(layer "F.Cu")
		(net "P5V_AUX")
	)
	(segment
		(start 232.517442 -63.600076)
		(end 233.572558 -63.600076)
		(width 0.3556)
		(layer "F.Cu")
		(net "P5V_AUX")
	)
	(segment
		(start 202.610466 -63.652146)
		(end 202.610466 -63.169292)
		(width 0.4572)
		(layer "F.Cu")
		(net "P5V_AUX")
	)
	(segment
		(start 406.41905 -58.80481)
		(end 406.41905 -59.174634)
		(width 0.254)
		(layer "F.Cu")
		(net "P5V_AUX")
	)
	(segment
		(start 400.484848 -55.722266)
		(end 400.167856 -55.405274)
		(width 0.254)
		(layer "F.Cu")
		(net "P5V_AUX")
	)
	(segment
		(start 213.772242 -120.812052)
		(end 214.23249 -120.812052)
		(width 0.381)
		(layer "F.Cu")
		(net "P5V_AUX")
	)
	(segment
		(start 10.51052 -123.075446)
		(end 10.51052 -122.931428)
		(width 0.254)
		(layer "F.Cu")
		(net "P5V_AUX")
	)
	(segment
		(start 309.081932 -38.041072)
		(end 309.081932 -38.750748)
		(width 0.4572)
		(layer "F.Cu")
		(net "P5V_AUX")
	)
	(segment
		(start 425.18203 -38.041072)
		(end 425.18203 -38.750748)
		(width 0.4572)
		(layer "F.Cu")
		(net "P5V_AUX")
	)
	(segment
		(start 12.231116 -124.894848)
		(end 11.904472 -124.894848)
		(width 0.254)
		(layer "F.Cu")
		(net "P5V_AUX")
	)
	(segment
		(start 103.058468 -54.644036)
		(end 103.497888 -55.083456)
		(width 0.254)
		(layer "F.Cu")
		(net "P5V_AUX")
	)
	(segment
		(start 232.517442 -61.799978)
		(end 231.388158 -61.799978)
		(width 0.3556)
		(layer "F.Cu")
		(net "P5V_AUX")
	)
	(segment
		(start 213.231984 -120.271794)
		(end 213.772242 -120.812052)
		(width 0.254)
		(layer "F.Cu")
		(net "P5V_AUX")
	)
	(segment
		(start 122.741182 -57.71261)
		(end 122.338084 -58.685938)
		(width 0.254)
		(layer "F.Cu")
		(net "P5V_AUX")
	)
	(segment
		(start 76.147168 -54.644036)
		(end 77.05852 -54.644036)
		(width 0.254)
		(layer "F.Cu")
		(net "P5V_AUX")
	)
	(segment
		(start 32.119062 -58.80481)
		(end 32.119062 -59.174634)
		(width 0.254)
		(layer "F.Cu")
		(net "P5V_AUX")
	)
	(segment
		(start 194.316096 -55.722266)
		(end 194.284854 -55.722266)
		(width 0.254)
		(layer "F.Cu")
		(net "P5V_AUX")
	)
	(segment
		(start 400.167856 -55.405274)
		(end 400.167856 -55.083456)
		(width 0.254)
		(layer "F.Cu")
		(net "P5V_AUX")
	)
	(segment
		(start 290.840922 -57.16397)
		(end 290.840922 -57.71261)
		(width 0.254)
		(layer "F.Cu")
		(net "P5V_AUX")
	)
	(segment
		(start 13.680694 -175.89246)
		(end 21.851874 -175.89246)
		(width 0.254)
		(layer "F.Cu")
		(net "P5V_AUX")
	)
	(segment
		(start 26.216102 -55.722266)
		(end 26.18486 -55.722266)
		(width 0.254)
		(layer "F.Cu")
		(net "P5V_AUX")
	)
	(segment
		(start 257.969512 -215.56472)
		(end 257.969512 -216.00668)
		(width 0.4572)
		(layer "F.Cu")
		(net "P5V_AUX")
	)
	(segment
		(start 51.497992 -55.083456)
		(end 51.867816 -55.083456)
		(width 0.254)
		(layer "F.Cu")
		(net "P5V_AUX")
	)
	(segment
		(start 227.916994 -69.000116)
		(end 227.826062 -69.091048)
		(width 0.3048)
		(layer "F.Cu")
		(net "P5V_AUX")
	)
	(segment
		(start 167.59809 -55.083456)
		(end 167.967914 -55.083456)
		(width 0.254)
		(layer "F.Cu")
		(net "P5V_AUX")
	)
	(segment
		(start 220.284802 -55.722266)
		(end 220.316044 -55.722266)
		(width 0.254)
		(layer "F.Cu")
		(net "P5V_AUX")
	)
	(segment
		(start 240.086134 -136.20115)
		(end 240.213388 -136.328404)
		(width 0.254)
		(layer "F.Cu")
		(net "P5V_AUX")
	)
	(segment
		(start 24.147272 -54.644036)
		(end 25.058624 -54.644036)
		(width 0.254)
		(layer "F.Cu")
		(net "P5V_AUX")
	)
	(segment
		(start 258.384802 -55.722266)
		(end 258.06781 -55.405274)
		(width 0.254)
		(layer "F.Cu")
		(net "P5V_AUX")
	)
	(segment
		(start 257.258566 -54.644036)
		(end 257.697986 -55.083456)
		(width 0.254)
		(layer "F.Cu")
		(net "P5V_AUX")
	)
	(segment
		(start 374.4849 -55.722266)
		(end 374.167908 -55.405274)
		(width 0.254)
		(layer "F.Cu")
		(net "P5V_AUX")
	)
	(segment
		(start 310.41594 -55.722266)
		(end 310.384698 -55.722266)
		(width 0.254)
		(layer "F.Cu")
		(net "P5V_AUX")
	)
	(segment
		(start 290.840922 -57.71261)
		(end 290.437824 -58.685938)
		(width 0.254)
		(layer "F.Cu")
		(net "P5V_AUX")
	)
	(segment
		(start 316.84087 -57.71261)
		(end 316.437772 -58.685938)
		(width 0.254)
		(layer "F.Cu")
		(net "P5V_AUX")
	)
	(segment
		(start 240.583212 -136.328404)
		(end 240.213388 -136.328404)
		(width 0.254)
		(layer "F.Cu")
		(net "P5V_AUX")
	)
	(segment
		(start 122.219212 -59.174634)
		(end 121.575322 -59.174634)
		(width 0.4572)
		(layer "F.Cu")
		(net "P5V_AUX")
	)
	(segment
		(start 140.24737 -54.644036)
		(end 141.158722 -54.644036)
		(width 0.254)
		(layer "F.Cu")
		(net "P5V_AUX")
	)
	(segment
		(start 11.904472 -124.894848)
		(end 11.629898 -124.620274)
		(width 0.254)
		(layer "F.Cu")
		(net "P5V_AUX")
	)
	(segment
		(start 382.810512 -63.169292)
		(end 382.347216 -62.705996)
		(width 0.4572)
		(layer "F.Cu")
		(net "P5V_AUX")
	)
	(segment
		(start 200.741026 -57.71261)
		(end 200.337928 -58.685938)
		(width 0.254)
		(layer "F.Cu")
		(net "P5V_AUX")
	)
	(segment
		(start 6.641084 -57.71261)
		(end 6.237986 -58.685938)
		(width 0.254)
		(layer "F.Cu")
		(net "P5V_AUX")
	)
	(segment
		(start 225.077274 -99.596702)
		(end 225.621596 -99.05238)
		(width 0.4572)
		(layer "F.Cu")
		(net "P5V_AUX")
	)
	(segment
		(start 6.119114 -58.80481)
		(end 6.119114 -59.174634)
		(width 0.254)
		(layer "F.Cu")
		(net "P5V_AUX")
	)
	(segment
		(start 232.517442 -66.60007)
		(end 231.388158 -66.60007)
		(width 0.3556)
		(layer "F.Cu")
		(net "P5V_AUX")
	)
	(segment
		(start 266.710414 -63.169292)
		(end 266.247118 -62.705996)
		(width 0.4572)
		(layer "F.Cu")
		(net "P5V_AUX")
	)
	(segment
		(start 114.982244 -38.041072)
		(end 114.982244 -38.750748)
		(width 0.4572)
		(layer "F.Cu")
		(net "P5V_AUX")
	)
	(segment
		(start 334.347058 -54.644036)
		(end 335.25841 -54.644036)
		(width 0.254)
		(layer "F.Cu")
		(net "P5V_AUX")
	)
	(segment
		(start 11.0744 -124.026168)
		(end 11.0744 -123.639326)
		(width 0.254)
		(layer "F.Cu")
		(net "P5V_AUX")
	)
	(segment
		(start 232.517442 -69.000116)
		(end 233.572558 -69.000116)
		(width 0.3556)
		(layer "F.Cu")
		(net "P5V_AUX")
	)
	(segment
		(start 243.227606 -123.59259)
		(end 242.710462 -123.075446)
		(width 0.254)
		(layer "F.Cu")
		(net "P5V_AUX")
	)
	(segment
		(start 116.393976 -127.78359)
		(end 117.558312 -128.947926)
		(width 0.254)
		(layer "F.Cu")
		(net "P5V_AUX")
	)
	(segment
		(start 243.227606 -124.1044)
		(end 243.227606 -123.59259)
		(width 0.254)
		(layer "F.Cu")
		(net "P5V_AUX")
	)
	(segment
		(start 58.64098 -57.16397)
		(end 58.64098 -57.71261)
		(width 0.254)
		(layer "F.Cu")
		(net "P5V_AUX")
	)
	(segment
		(start 445.43218 -121.541794)
		(end 445.972438 -122.082052)
		(width 0.254)
		(layer "F.Cu")
		(net "P5V_AUX")
	)
	(segment
		(start 426.516038 -55.722266)
		(end 426.484796 -55.722266)
		(width 0.254)
		(layer "F.Cu")
		(net "P5V_AUX")
	)
	(segment
		(start 264.319004 -58.80481)
		(end 264.319004 -59.174634)
		(width 0.254)
		(layer "F.Cu")
		(net "P5V_AUX")
	)
	(segment
		(start 25.867868 -55.405274)
		(end 25.867868 -55.083456)
		(width 0.254)
		(layer "F.Cu")
		(net "P5V_AUX")
	)
	(segment
		(start 239.943132 -65.472056)
		(end 240.406428 -65.00876)
		(width 0.4572)
		(layer "F.Cu")
		(net "P5V_AUX")
	)
	(segment
		(start 331.06614 -95.663766)
		(end 331.459332 -95.663766)
		(width 0.381)
		(layer "F.Cu")
		(net "P5V_AUX")
	)
	(segment
		(start 8.510524 -68.249292)
		(end 8.047228 -67.785996)
		(width 0.4572)
		(layer "F.Cu")
		(net "P5V_AUX")
	)
	(segment
		(start 330.775564 -122.525028)
		(end 330.775564 -122.91822)
		(width 0.381)
		(layer "F.Cu")
		(net "P5V_AUX")
	)
	(segment
		(start 382.810512 -63.652146)
		(end 382.810512 -63.169292)
		(width 0.4572)
		(layer "F.Cu")
		(net "P5V_AUX")
	)
	(segment
		(start 380.537974 -58.685938)
		(end 380.419102 -58.80481)
		(width 0.254)
		(layer "F.Cu")
		(net "P5V_AUX")
	)
	(segment
		(start 223.695768 -100.48875)
		(end 224.241868 -99.94265)
		(width 0.254)
		(layer "F.Cu")
		(net "P5V_AUX")
	)
	(segment
		(start 451.797928 -55.083456)
		(end 452.167752 -55.083456)
		(width 0.254)
		(layer "F.Cu")
		(net "P5V_AUX")
	)
	(segment
		(start 123.774708 -135.699246)
		(end 124.028962 -135.9535)
		(width 0.254)
		(layer "F.Cu")
		(net "P5V_AUX")
	)
	(segment
		(start 354.941124 -57.16397)
		(end 354.941124 -57.71261)
		(width 0.254)
		(layer "F.Cu")
		(net "P5V_AUX")
	)
	(segment
		(start 242.042442 -209.139028)
		(end 241.41049 -209.139028)
		(width 0.4572)
		(layer "F.Cu")
		(net "P5V_AUX")
	)
	(segment
		(start 447.55943 -95.663766)
		(end 447.801238 -95.905574)
		(width 0.381)
		(layer "F.Cu")
		(net "P5V_AUX")
	)
	(segment
		(start 104.184704 -55.722266)
		(end 103.867712 -55.405274)
		(width 0.254)
		(layer "F.Cu")
		(net "P5V_AUX")
	)
	(segment
		(start 354.419154 -59.174634)
		(end 353.775264 -59.174634)
		(width 0.4572)
		(layer "F.Cu")
		(net "P5V_AUX")
	)
	(segment
		(start 9.734042 -136.767824)
		(end 8.82269 -136.767824)
		(width 0.254)
		(layer "F.Cu")
		(net "P5V_AUX")
	)
	(segment
		(start 233.308398 -68.399914)
		(end 233.518964 -68.189348)
		(width 0.3556)
		(layer "F.Cu")
		(net "P5V_AUX")
	)
	(segment
		(start 77.05852 -54.644036)
		(end 77.49794 -55.083456)
		(width 0.254)
		(layer "F.Cu")
		(net "P5V_AUX")
	)
	(segment
		(start 283.258514 -54.644036)
		(end 283.697934 -55.083456)
		(width 0.254)
		(layer "F.Cu")
		(net "P5V_AUX")
	)
	(segment
		(start 340.118446 -120.53824)
		(end 340.118446 -119.718836)
		(width 0.4572)
		(layer "F.Cu")
		(net "P5V_AUX")
	)
	(segment
		(start 127.209296 -124.104146)
		(end 127.945388 -124.840238)
		(width 0.254)
		(layer "F.Cu")
		(net "P5V_AUX")
	)
	(segment
		(start 193.967862 -55.405274)
		(end 193.967862 -55.083456)
		(width 0.254)
		(layer "F.Cu")
		(net "P5V_AUX")
	)
	(segment
		(start 242.710462 -122.640852)
		(end 242.362228 -122.292618)
		(width 0.4064)
		(layer "F.Cu")
		(net "P5V_AUX")
	)
	(segment
		(start 242.50904 -209.990436)
		(end 242.5319 -209.967576)
		(width 0.4572)
		(layer "F.Cu")
		(net "P5V_AUX")
	)
	(segment
		(start 284.067758 -55.405274)
		(end 284.067758 -55.083456)
		(width 0.254)
		(layer "F.Cu")
		(net "P5V_AUX")
	)
	(segment
		(start 192.247266 -54.644036)
		(end 193.158618 -54.644036)
		(width 0.254)
		(layer "F.Cu")
		(net "P5V_AUX")
	)
	(segment
		(start 32.237934 -58.685938)
		(end 32.119062 -58.80481)
		(width 0.254)
		(layer "F.Cu")
		(net "P5V_AUX")
	)
	(segment
		(start 97.13214 -121.541794)
		(end 97.672398 -122.082052)
		(width 0.254)
		(layer "F.Cu")
		(net "P5V_AUX")
	)
	(segment
		(start 358.81056 -122.931428)
		(end 358.81056 -122.640852)
		(width 0.4064)
		(layer "F.Cu")
		(net "P5V_AUX")
	)
	(segment
		(start 98.423222 -96.56699)
		(end 98.423222 -96.106742)
		(width 0.381)
		(layer "F.Cu")
		(net "P5V_AUX")
	)
	(segment
		(start 258.416044 -55.722266)
		(end 258.384802 -55.722266)
		(width 0.254)
		(layer "F.Cu")
		(net "P5V_AUX")
	)
	(segment
		(start 84.118958 -58.80481)
		(end 84.118958 -59.174634)
		(width 0.254)
		(layer "F.Cu")
		(net "P5V_AUX")
	)
	(segment
		(start 103.867712 -55.405274)
		(end 103.867712 -55.083456)
		(width 0.254)
		(layer "F.Cu")
		(net "P5V_AUX")
	)
	(segment
		(start 107.918504 -120.53824)
		(end 107.918504 -119.718836)
		(width 0.4572)
		(layer "F.Cu")
		(net "P5V_AUX")
	)
	(segment
		(start 78.184756 -55.722266)
		(end 77.867764 -55.405274)
		(width 0.13208)
		(layer "F.Cu")
		(net "P5V_AUX")
	)
	(segment
		(start 243.9035 -124.780294)
		(end 243.227606 -124.1044)
		(width 0.254)
		(layer "F.Cu")
		(net "P5V_AUX")
	)
	(segment
		(start 408.81046 -63.652146)
		(end 408.81046 -63.169292)
		(width 0.4572)
		(layer "F.Cu")
		(net "P5V_AUX")
	)
	(segment
		(start 354.941124 -57.71261)
		(end 354.538026 -58.685938)
		(width 0.254)
		(layer "F.Cu")
		(net "P5V_AUX")
	)
	(segment
		(start 336.384646 -55.722266)
		(end 336.415888 -55.722266)
		(width 0.254)
		(layer "F.Cu")
		(net "P5V_AUX")
	)
	(segment
		(start 116.393976 -127.459994)
		(end 116.393976 -127.78359)
		(width 0.254)
		(layer "F.Cu")
		(net "P5V_AUX")
	)
	(segment
		(start 241.933984 -136.767824)
		(end 241.022632 -136.767824)
		(width 0.254)
		(layer "F.Cu")
		(net "P5V_AUX")
	)
	(segment
		(start 356.21214 -135.936482)
		(end 356.21214 -136.227058)
		(width 0.254)
		(layer "F.Cu")
		(net "P5V_AUX")
	)
	(segment
		(start 10.162286 -122.292618)
		(end 10.51052 -122.640852)
		(width 0.4064)
		(layer "F.Cu")
		(net "P5V_AUX")
	)
	(segment
		(start 257.697986 -55.083456)
		(end 258.06781 -55.083456)
		(width 0.254)
		(layer "F.Cu")
		(net "P5V_AUX")
	)
	(segment
		(start 446.183004 -97.467928)
		(end 446.183004 -97.107248)
		(width 0.254)
		(layer "F.Cu")
		(net "P5V_AUX")
	)
	(segment
		(start 446.875662 -122.91822)
		(end 446.633854 -123.160028)
		(width 0.381)
		(layer "F.Cu")
		(net "P5V_AUX")
	)
	(segment
		(start 126.26213 -122.292618)
		(end 126.610364 -122.640852)
		(width 0.4064)
		(layer "F.Cu")
		(net "P5V_AUX")
	)
	(segment
		(start 232.517442 -61.20003)
		(end 233.572558 -61.20003)
		(width 0.3556)
		(layer "F.Cu")
		(net "P5V_AUX")
	)
	(segment
		(start 241.41049 -209.139028)
		(end 241.38509 -209.113628)
		(width 0.4572)
		(layer "F.Cu")
		(net "P5V_AUX")
	)
	(segment
		(start 309.697882 -55.083456)
		(end 310.067706 -55.083456)
		(width 0.254)
		(layer "F.Cu")
		(net "P5V_AUX")
	)
	(segment
		(start 372.447312 -54.644036)
		(end 373.358664 -54.644036)
		(width 0.254)
		(layer "F.Cu")
		(net "P5V_AUX")
	)
	(segment
		(start 356.810564 -63.652146)
		(end 356.810564 -63.169292)
		(width 0.4572)
		(layer "F.Cu")
		(net "P5V_AUX")
	)
	(segment
		(start 218.247214 -54.644036)
		(end 219.158566 -54.644036)
		(width 0.254)
		(layer "F.Cu")
		(net "P5V_AUX")
	)
	(segment
		(start 424.447208 -54.644036)
		(end 425.35856 -54.644036)
		(width 0.254)
		(layer "F.Cu")
		(net "P5V_AUX")
	)
	(segment
		(start 102.147116 -54.644036)
		(end 103.058468 -54.644036)
		(width 0.254)
		(layer "F.Cu")
		(net "P5V_AUX")
	)
	(segment
		(start 58.11901 -58.80481)
		(end 58.11901 -59.174634)
		(width 0.254)
		(layer "F.Cu")
		(net "P5V_AUX")
	)
	(segment
		(start 200.741026 -57.16397)
		(end 200.741026 -57.71261)
		(width 0.254)
		(layer "F.Cu")
		(net "P5V_AUX")
	)
	(segment
		(start 445.0715 -121.541794)
		(end 445.43218 -121.541794)
		(width 0.254)
		(layer "F.Cu")
		(net "P5V_AUX")
	)
	(segment
		(start 122.338084 -58.685938)
		(end 122.219212 -58.80481)
		(width 0.254)
		(layer "F.Cu")
		(net "P5V_AUX")
	)
	(segment
		(start 374.516142 -55.722266)
		(end 374.4849 -55.722266)
		(width 0.254)
		(layer "F.Cu")
		(net "P5V_AUX")
	)
	(segment
		(start 434.810408 -63.652146)
		(end 434.810408 -63.169292)
		(width 0.4572)
		(layer "F.Cu")
		(net "P5V_AUX")
	)
	(segment
		(start 356.68331 -136.328404)
		(end 356.313486 -136.328404)
		(width 0.254)
		(layer "F.Cu")
		(net "P5V_AUX")
	)
	(segment
		(start 426.484796 -55.722266)
		(end 426.167804 -55.405274)
		(width 0.254)
		(layer "F.Cu")
		(net "P5V_AUX")
	)
	(segment
		(start 244.555264 -113.117376)
		(end 244.555264 -112.501426)
		(width 0.4572)
		(layer "F.Cu")
		(net "P5V_AUX")
	)
	(segment
		(start 239.01019 -53.946044)
		(end 238.607092 -54.919372)
		(width 0.254)
		(layer "F.Cu")
		(net "P5V_AUX")
	)
	(segment
		(start 219.597986 -55.083456)
		(end 219.96781 -55.083456)
		(width 0.254)
		(layer "F.Cu")
		(net "P5V_AUX")
	)
	(segment
		(start 330.332588 -122.082052)
		(end 330.775564 -122.525028)
		(width 0.381)
		(layer "F.Cu")
		(net "P5V_AUX")
	)
	(segment
		(start 127.945388 -124.840238)
		(end 128.07696 -124.894848)
		(width 0.254)
		(layer "F.Cu")
		(net "P5V_AUX")
	)
	(segment
		(start 242.5319 -209.967576)
		(end 242.5319 -209.628486)
		(width 0.4572)
		(layer "F.Cu")
		(net "P5V_AUX")
	)
	(segment
		(start 360.22026 -124.894848)
		(end 359.327704 -124.002292)
		(width 0.254)
		(layer "F.Cu")
		(net "P5V_AUX")
	)
	(segment
		(start 84.23783 -58.685938)
		(end 84.118958 -58.80481)
		(width 0.254)
		(layer "F.Cu")
		(net "P5V_AUX")
	)
	(via
		(at 334.81264 -132.093462)
		(size 0.508)
		(drill 0.254)
		(layers "F.Cu" "B.Cu")
		(net "P5V_AUX")
	)
	(via
		(at 231.388158 -66.60007)
		(size 0.508)
		(drill 0.254)
		(layers "F.Cu" "B.Cu")
		(net "P5V_AUX")
	)
	(via
		(at 257.738626 -238.333788)
		(size 0.508)
		(drill 0.254)
		(layers "F.Cu" "B.Cu")
		(net "P5V_AUX")
	)
	(via
		(at 50.882042 -38.750748)
		(size 0.508)
		(drill 0.254)
		(layers "F.Cu" "B.Cu")
		(net "P5V_AUX")
	)
	(via
		(at 382.347216 -62.705996)
		(size 0.508)
		(drill 0.254)
		(layers "F.Cu" "B.Cu")
		(net "P5V_AUX")
	)
	(via
		(at 302.861218 -229.56139)
		(size 0.508)
		(drill 0.254)
		(layers "F.Cu" "B.Cu")
		(net "P5V_AUX")
	)
	(via
		(at 243.174266 -209.952844)
		(size 0.508)
		(drill 0.254)
		(layers "F.Cu" "B.Cu")
		(net "P5V_AUX")
	)
	(via
		(at 220.316044 -55.722266)
		(size 0.508)
		(drill 0.254)
		(layers "F.Cu" "B.Cu")
		(net "P5V_AUX")
	)
	(via
		(at 10.162286 -122.292618)
		(size 0.508)
		(drill 0.254)
		(layers "F.Cu" "B.Cu")
		(net "P5V_AUX")
	)
	(via
		(at 119.856504 -238.057944)
		(size 0.508)
		(drill 0.254)
		(layers "F.Cu" "B.Cu")
		(net "P5V_AUX")
	)
	(via
		(at 244.555264 -112.501426)
		(size 0.508)
		(drill 0.254)
		(layers "F.Cu" "B.Cu")
		(net "P5V_AUX")
	)
	(via
		(at 353.775264 -59.174634)
		(size 0.508)
		(drill 0.254)
		(layers "F.Cu" "B.Cu")
		(net "P5V_AUX")
	)
	(via
		(at 108.477812 -258.111244)
		(size 0.508)
		(drill 0.254)
		(layers "F.Cu" "B.Cu")
		(net "P5V_AUX")
	)
	(via
		(at 447.801238 -95.905574)
		(size 0.508)
		(drill 0.254)
		(layers "F.Cu" "B.Cu")
		(net "P5V_AUX")
	)
	(via
		(at 425.18203 -38.750748)
		(size 0.508)
		(drill 0.254)
		(layers "F.Cu" "B.Cu")
		(net "P5V_AUX")
	)
	(via
		(at 21.415756 -174.271178)
		(size 0.508)
		(drill 0.254)
		(layers "F.Cu" "B.Cu")
		(net "P5V_AUX")
	)
	(via
		(at 341.24011 -261.346442)
		(size 0.508)
		(drill 0.254)
		(layers "F.Cu" "B.Cu")
		(net "P5V_AUX")
	)
	(via
		(at 340.52891 -261.346442)
		(size 0.508)
		(drill 0.254)
		(layers "F.Cu" "B.Cu")
		(net "P5V_AUX")
	)
	(via
		(at 374.516142 -55.722266)
		(size 0.508)
		(drill 0.254)
		(layers "F.Cu" "B.Cu")
		(net "P5V_AUX")
	)
	(via
		(at 336.415888 -55.722266)
		(size 0.508)
		(drill 0.254)
		(layers "F.Cu" "B.Cu")
		(net "P5V_AUX")
	)
	(via
		(at 233.582464 -68.189348)
		(size 0.508)
		(drill 0.254)
		(layers "F.Cu" "B.Cu")
		(net "P5V_AUX")
	)
	(via
		(at 202.14717 -62.705996)
		(size 0.508)
		(drill 0.254)
		(layers "F.Cu" "B.Cu")
		(net "P5V_AUX")
	)
	(via
		(at 233.572558 -63.600076)
		(size 0.508)
		(drill 0.254)
		(layers "F.Cu" "B.Cu")
		(net "P5V_AUX")
	)
	(via
		(at 239.567974 -160.664144)
		(size 0.508)
		(drill 0.254)
		(layers "F.Cu" "B.Cu")
		(net "P5V_AUX")
	)
	(via
		(at 426.516038 -55.722266)
		(size 0.508)
		(drill 0.254)
		(layers "F.Cu" "B.Cu")
		(net "P5V_AUX")
	)
	(via
		(at 318.247014 -62.705996)
		(size 0.508)
		(drill 0.254)
		(layers "F.Cu" "B.Cu")
		(net "P5V_AUX")
	)
	(via
		(at 258.416044 -55.722266)
		(size 0.508)
		(drill 0.254)
		(layers "F.Cu" "B.Cu")
		(net "P5V_AUX")
	)
	(via
		(at 113.561114 -259.020564)
		(size 0.508)
		(drill 0.254)
		(layers "F.Cu" "B.Cu")
		(net "P5V_AUX")
	)
	(via
		(at 8.047228 -62.705996)
		(size 0.508)
		(drill 0.254)
		(layers "F.Cu" "B.Cu")
		(net "P5V_AUX")
	)
	(via
		(at 226.429316 -123.520962)
		(size 0.508)
		(drill 0.254)
		(layers "F.Cu" "B.Cu")
		(net "P5V_AUX")
	)
	(via
		(at 83.475068 -59.174634)
		(size 0.508)
		(drill 0.254)
		(layers "F.Cu" "B.Cu")
		(net "P5V_AUX")
	)
	(via
		(at 454.498202 -246.16664)
		(size 0.508)
		(drill 0.254)
		(layers "F.Cu" "B.Cu")
		(net "P5V_AUX")
	)
	(via
		(at 145.568162 -239.091978)
		(size 0.508)
		(drill 0.254)
		(layers "F.Cu" "B.Cu")
		(net "P5V_AUX")
	)
	(via
		(at 266.247118 -62.705996)
		(size 0.508)
		(drill 0.254)
		(layers "F.Cu" "B.Cu")
		(net "P5V_AUX")
	)
	(via
		(at 124.147326 -62.705996)
		(size 0.508)
		(drill 0.254)
		(layers "F.Cu" "B.Cu")
		(net "P5V_AUX")
	)
	(via
		(at 8.047228 -67.785996)
		(size 0.508)
		(drill 0.254)
		(layers "F.Cu" "B.Cu")
		(net "P5V_AUX")
	)
	(via
		(at 109.182408 -258.923536)
		(size 0.508)
		(drill 0.254)
		(layers "F.Cu" "B.Cu")
		(net "P5V_AUX")
	)
	(via
		(at 233.572558 -69.000116)
		(size 0.508)
		(drill 0.254)
		(layers "F.Cu" "B.Cu")
		(net "P5V_AUX")
	)
	(via
		(at 239.865154 -135.689594)
		(size 0.508)
		(drill 0.254)
		(layers "F.Cu" "B.Cu")
		(net "P5V_AUX")
	)
	(via
		(at 241.080798 -169.33164)
		(size 0.508)
		(drill 0.254)
		(layers "F.Cu" "B.Cu")
		(net "P5V_AUX")
	)
	(via
		(at 176.147222 -62.705996)
		(size 0.508)
		(drill 0.254)
		(layers "F.Cu" "B.Cu")
		(net "P5V_AUX")
	)
	(via
		(at 26.216102 -55.722266)
		(size 0.508)
		(drill 0.254)
		(layers "F.Cu" "B.Cu")
		(net "P5V_AUX")
	)
	(via
		(at 194.316096 -55.722266)
		(size 0.508)
		(drill 0.254)
		(layers "F.Cu" "B.Cu")
		(net "P5V_AUX")
	)
	(via
		(at 166.98214 -38.750748)
		(size 0.508)
		(drill 0.254)
		(layers "F.Cu" "B.Cu")
		(net "P5V_AUX")
	)
	(via
		(at 34.047176 -62.705996)
		(size 0.508)
		(drill 0.254)
		(layers "F.Cu" "B.Cu")
		(net "P5V_AUX")
	)
	(via
		(at 153.302716 -63.698882)
		(size 0.6604)
		(drill 0.3302)
		(layers "F.Cu" "B.Cu")
		(net "P5V_AUX")
	)
	(via
		(at 109.940852 -286.720534)
		(size 0.508)
		(drill 0.254)
		(layers "F.Cu" "B.Cu")
		(net "P5V_AUX")
	)
	(via
		(at 347.182186 -38.750748)
		(size 0.508)
		(drill 0.254)
		(layers "F.Cu" "B.Cu")
		(net "P5V_AUX")
	)
	(via
		(at 199.575166 -59.174634)
		(size 0.508)
		(drill 0.254)
		(layers "F.Cu" "B.Cu")
		(net "P5V_AUX")
	)
	(via
		(at 314.460636 -160.010094)
		(size 0.508)
		(drill 0.254)
		(layers "F.Cu" "B.Cu")
		(net "P5V_AUX")
	)
	(via
		(at 14.236446 -210.113372)
		(size 0.508)
		(drill 0.254)
		(layers "F.Cu" "B.Cu")
		(net "P5V_AUX")
	)
	(via
		(at 335.6483 -132.148072)
		(size 0.508)
		(drill 0.254)
		(layers "F.Cu" "B.Cu")
		(net "P5V_AUX")
	)
	(via
		(at 237.909862 -133.816344)
		(size 0.508)
		(drill 0.254)
		(layers "F.Cu" "B.Cu")
		(net "P5V_AUX")
	)
	(via
		(at 142.3162 -55.722266)
		(size 0.508)
		(drill 0.254)
		(layers "F.Cu" "B.Cu")
		(net "P5V_AUX")
	)
	(via
		(at 231.388158 -61.799978)
		(size 0.508)
		(drill 0.254)
		(layers "F.Cu" "B.Cu")
		(net "P5V_AUX")
	)
	(via
		(at 5.684774 -394.754608)
		(size 0.508)
		(drill 0.254)
		(layers "F.Cu" "B.Cu")
		(net "P5V_AUX")
	)
	(via
		(at 242.50904 -209.990436)
		(size 0.508)
		(drill 0.254)
		(layers "F.Cu" "B.Cu")
		(net "P5V_AUX")
	)
	(via
		(at 231.082088 -38.750748)
		(size 0.508)
		(drill 0.254)
		(layers "F.Cu" "B.Cu")
		(net "P5V_AUX")
	)
	(via
		(at 237.84433 -55.408068)
		(size 0.508)
		(drill 0.254)
		(layers "F.Cu" "B.Cu")
		(net "P5V_AUX")
	)
	(via
		(at 9.49071 -177.566828)
		(size 0.508)
		(drill 0.254)
		(layers "F.Cu" "B.Cu")
		(net "P5V_AUX")
	)
	(via
		(at 78.215998 -55.722266)
		(size 0.508)
		(drill 0.254)
		(layers "F.Cu" "B.Cu")
		(net "P5V_AUX")
	)
	(via
		(at 340.118446 -119.718836)
		(size 0.508)
		(drill 0.254)
		(layers "F.Cu" "B.Cu")
		(net "P5V_AUX")
	)
	(via
		(at 8.77951 -177.566828)
		(size 0.508)
		(drill 0.254)
		(layers "F.Cu" "B.Cu")
		(net "P5V_AUX")
	)
	(via
		(at 358.462326 -122.292618)
		(size 0.508)
		(drill 0.254)
		(layers "F.Cu" "B.Cu")
		(net "P5V_AUX")
	)
	(via
		(at 314.325 -160.63087)
		(size 0.508)
		(drill 0.254)
		(layers "F.Cu" "B.Cu")
		(net "P5V_AUX")
	)
	(via
		(at 221.695264 -62.074806)
		(size 0.6604)
		(drill 0.3302)
		(layers "F.Cu" "B.Cu")
		(net "P5V_AUX")
	)
	(via
		(at 117.906546 -129.586736)
		(size 0.508)
		(drill 0.254)
		(layers "F.Cu" "B.Cu")
		(net "P5V_AUX")
	)
	(via
		(at 334.582516 -251.657358)
		(size 0.508)
		(drill 0.254)
		(layers "F.Cu" "B.Cu")
		(net "P5V_AUX")
	)
	(via
		(at 263.675114 -59.174634)
		(size 0.508)
		(drill 0.254)
		(layers "F.Cu" "B.Cu")
		(net "P5V_AUX")
	)
	(via
		(at 331.70114 -95.905574)
		(size 0.508)
		(drill 0.254)
		(layers "F.Cu" "B.Cu")
		(net "P5V_AUX")
	)
	(via
		(at 98.333814 -123.160028)
		(size 0.508)
		(drill 0.254)
		(layers "F.Cu" "B.Cu")
		(net "P5V_AUX")
	)
	(via
		(at 24.882094 -38.750748)
		(size 0.508)
		(drill 0.254)
		(layers "F.Cu" "B.Cu")
		(net "P5V_AUX")
	)
	(via
		(at 289.675062 -59.174634)
		(size 0.508)
		(drill 0.254)
		(layers "F.Cu" "B.Cu")
		(net "P5V_AUX")
	)
	(via
		(at 345.76131 -259.020564)
		(size 0.508)
		(drill 0.254)
		(layers "F.Cu" "B.Cu")
		(net "P5V_AUX")
	)
	(via
		(at 405.77516 -59.174634)
		(size 0.508)
		(drill 0.254)
		(layers "F.Cu" "B.Cu")
		(net "P5V_AUX")
	)
	(via
		(at 57.47512 -59.174634)
		(size 0.508)
		(drill 0.254)
		(layers "F.Cu" "B.Cu")
		(net "P5V_AUX")
	)
	(via
		(at 335.575656 -132.87502)
		(size 0.508)
		(drill 0.254)
		(layers "F.Cu" "B.Cu")
		(net "P5V_AUX")
	)
	(via
		(at 334.75803 -132.856732)
		(size 0.508)
		(drill 0.254)
		(layers "F.Cu" "B.Cu")
		(net "P5V_AUX")
	)
	(via
		(at 400.51609 -55.722266)
		(size 0.508)
		(drill 0.254)
		(layers "F.Cu" "B.Cu")
		(net "P5V_AUX")
	)
	(via
		(at 242.362228 -122.292618)
		(size 0.508)
		(drill 0.254)
		(layers "F.Cu" "B.Cu")
		(net "P5V_AUX")
	)
	(via
		(at 341.24011 -260.635242)
		(size 0.508)
		(drill 0.254)
		(layers "F.Cu" "B.Cu")
		(net "P5V_AUX")
	)
	(via
		(at 10.20191 -177.566828)
		(size 0.508)
		(drill 0.254)
		(layers "F.Cu" "B.Cu")
		(net "P5V_AUX")
	)
	(via
		(at 155.803854 -61.699902)
		(size 0.6604)
		(drill 0.3302)
		(layers "F.Cu" "B.Cu")
		(net "P5V_AUX")
	)
	(via
		(at 10.045446 -173.255432)
		(size 0.508)
		(drill 0.254)
		(layers "F.Cu" "B.Cu")
		(net "P5V_AUX")
	)
	(via
		(at 373.182134 -38.750748)
		(size 0.508)
		(drill 0.254)
		(layers "F.Cu" "B.Cu")
		(net "P5V_AUX")
	)
	(via
		(at 140.982192 -38.750748)
		(size 0.508)
		(drill 0.254)
		(layers "F.Cu" "B.Cu")
		(net "P5V_AUX")
	)
	(via
		(at 227.826062 -69.091048)
		(size 0.508)
		(drill 0.254)
		(layers "F.Cu" "B.Cu")
		(net "P5V_AUX")
	)
	(via
		(at 173.575218 -59.174634)
		(size 0.508)
		(drill 0.254)
		(layers "F.Cu" "B.Cu")
		(net "P5V_AUX")
	)
	(via
		(at 310.41594 -55.722266)
		(size 0.508)
		(drill 0.254)
		(layers "F.Cu" "B.Cu")
		(net "P5V_AUX")
	)
	(via
		(at 52.21605 -55.722266)
		(size 0.508)
		(drill 0.254)
		(layers "F.Cu" "B.Cu")
		(net "P5V_AUX")
	)
	(via
		(at 192.982088 -38.750748)
		(size 0.508)
		(drill 0.254)
		(layers "F.Cu" "B.Cu")
		(net "P5V_AUX")
	)
	(via
		(at 168.316148 -55.722266)
		(size 0.508)
		(drill 0.254)
		(layers "F.Cu" "B.Cu")
		(net "P5V_AUX")
	)
	(via
		(at 18.035524 -312.085736)
		(size 0.508)
		(drill 0.254)
		(layers "F.Cu" "B.Cu")
		(net "P5V_AUX")
	)
	(via
		(at 231.388158 -63.000128)
		(size 0.508)
		(drill 0.254)
		(layers "F.Cu" "B.Cu")
		(net "P5V_AUX")
	)
	(via
		(at 109.189012 -258.111244)
		(size 0.508)
		(drill 0.254)
		(layers "F.Cu" "B.Cu")
		(net "P5V_AUX")
	)
	(via
		(at 257.535172 -216.231724)
		(size 0.508)
		(drill 0.254)
		(layers "F.Cu" "B.Cu")
		(net "P5V_AUX")
	)
	(via
		(at 121.575322 -59.174634)
		(size 0.508)
		(drill 0.254)
		(layers "F.Cu" "B.Cu")
		(net "P5V_AUX")
	)
	(via
		(at 399.182082 -38.750748)
		(size 0.508)
		(drill 0.254)
		(layers "F.Cu" "B.Cu")
		(net "P5V_AUX")
	)
	(via
		(at 8.964422 -168.389808)
		(size 0.508)
		(drill 0.254)
		(layers "F.Cu" "B.Cu")
		(net "P5V_AUX")
	)
	(via
		(at 150.147274 -62.705996)
		(size 0.508)
		(drill 0.254)
		(layers "F.Cu" "B.Cu")
		(net "P5V_AUX")
	)
	(via
		(at 240.406428 -65.00876)
		(size 0.508)
		(drill 0.254)
		(layers "F.Cu" "B.Cu")
		(net "P5V_AUX")
	)
	(via
		(at 99.501198 -95.905574)
		(size 0.508)
		(drill 0.254)
		(layers "F.Cu" "B.Cu")
		(net "P5V_AUX")
	)
	(via
		(at 9.37514 -173.255432)
		(size 0.508)
		(drill 0.254)
		(layers "F.Cu" "B.Cu")
		(net "P5V_AUX")
	)
	(via
		(at 122.640344 -135.699246)
		(size 0.508)
		(drill 0.254)
		(layers "F.Cu" "B.Cu")
		(net "P5V_AUX")
	)
	(via
		(at 334.531462 -250.980194)
		(size 0.508)
		(drill 0.254)
		(layers "F.Cu" "B.Cu")
		(net "P5V_AUX")
	)
	(via
		(at 104.215946 -55.722266)
		(size 0.508)
		(drill 0.254)
		(layers "F.Cu" "B.Cu")
		(net "P5V_AUX")
	)
	(via
		(at 431.775108 -59.174634)
		(size 0.508)
		(drill 0.254)
		(layers "F.Cu" "B.Cu")
		(net "P5V_AUX")
	)
	(via
		(at 233.572558 -67.200018)
		(size 0.508)
		(drill 0.254)
		(layers "F.Cu" "B.Cu")
		(net "P5V_AUX")
	)
	(via
		(at 356.347268 -62.705996)
		(size 0.508)
		(drill 0.254)
		(layers "F.Cu" "B.Cu")
		(net "P5V_AUX")
	)
	(via
		(at 408.347164 -62.705996)
		(size 0.508)
		(drill 0.254)
		(layers "F.Cu" "B.Cu")
		(net "P5V_AUX")
	)
	(via
		(at 7.664958 -135.689594)
		(size 0.508)
		(drill 0.254)
		(layers "F.Cu" "B.Cu")
		(net "P5V_AUX")
	)
	(via
		(at 8.9535 -170.563032)
		(size 0.508)
		(drill 0.254)
		(layers "F.Cu" "B.Cu")
		(net "P5V_AUX")
	)
	(via
		(at 107.918504 -119.718836)
		(size 0.508)
		(drill 0.254)
		(layers "F.Cu" "B.Cu")
		(net "P5V_AUX")
	)
	(via
		(at 126.26213 -122.292618)
		(size 0.508)
		(drill 0.254)
		(layers "F.Cu" "B.Cu")
		(net "P5V_AUX")
	)
	(via
		(at 314.62853 -159.337502)
		(size 0.508)
		(drill 0.254)
		(layers "F.Cu" "B.Cu")
		(net "P5V_AUX")
	)
	(via
		(at 446.633854 -123.160028)
		(size 0.508)
		(drill 0.254)
		(layers "F.Cu" "B.Cu")
		(net "P5V_AUX")
	)
	(via
		(at 9.613138 -168.37914)
		(size 0.508)
		(drill 0.254)
		(layers "F.Cu" "B.Cu")
		(net "P5V_AUX")
	)
	(via
		(at 108.471208 -258.923536)
		(size 0.508)
		(drill 0.254)
		(layers "F.Cu" "B.Cu")
		(net "P5V_AUX")
	)
	(via
		(at 214.433658 -121.890028)
		(size 0.508)
		(drill 0.254)
		(layers "F.Cu" "B.Cu")
		(net "P5V_AUX")
	)
	(via
		(at 315.67501 -59.174634)
		(size 0.508)
		(drill 0.254)
		(layers "F.Cu" "B.Cu")
		(net "P5V_AUX")
	)
	(via
		(at 60.047124 -62.705996)
		(size 0.508)
		(drill 0.254)
		(layers "F.Cu" "B.Cu")
		(net "P5V_AUX")
	)
	(via
		(at 240.140236 -161.11855)
		(size 0.508)
		(drill 0.254)
		(layers "F.Cu" "B.Cu")
		(net "P5V_AUX")
	)
	(via
		(at 147.57527 -59.174634)
		(size 0.508)
		(drill 0.254)
		(layers "F.Cu" "B.Cu")
		(net "P5V_AUX")
	)
	(via
		(at 379.775212 -59.174634)
		(size 0.508)
		(drill 0.254)
		(layers "F.Cu" "B.Cu")
		(net "P5V_AUX")
	)
	(via
		(at 360.147362 -111.739426)
		(size 0.508)
		(drill 0.254)
		(layers "F.Cu" "B.Cu")
		(net "P5V_AUX")
	)
	(via
		(at 434.347112 -62.705996)
		(size 0.508)
		(drill 0.254)
		(layers "F.Cu" "B.Cu")
		(net "P5V_AUX")
	)
	(via
		(at 284.415992 -55.722266)
		(size 0.508)
		(drill 0.254)
		(layers "F.Cu" "B.Cu")
		(net "P5V_AUX")
	)
	(via
		(at 340.52891 -260.635242)
		(size 0.508)
		(drill 0.254)
		(layers "F.Cu" "B.Cu")
		(net "P5V_AUX")
	)
	(via
		(at 127.947166 -111.739426)
		(size 0.508)
		(drill 0.254)
		(layers "F.Cu" "B.Cu")
		(net "P5V_AUX")
	)
	(via
		(at 283.081984 -38.750748)
		(size 0.508)
		(drill 0.254)
		(layers "F.Cu" "B.Cu")
		(net "P5V_AUX")
	)
	(via
		(at 109.900212 -258.111244)
		(size 0.508)
		(drill 0.254)
		(layers "F.Cu" "B.Cu")
		(net "P5V_AUX")
	)
	(via
		(at 240.316512 -169.296588)
		(size 0.508)
		(drill 0.254)
		(layers "F.Cu" "B.Cu")
		(net "P5V_AUX")
	)
	(via
		(at 9.602216 -170.563032)
		(size 0.508)
		(drill 0.254)
		(layers "F.Cu" "B.Cu")
		(net "P5V_AUX")
	)
	(via
		(at 12.960604 -61.699902)
		(size 0.6604)
		(drill 0.3302)
		(layers "F.Cu" "B.Cu")
		(net "P5V_AUX")
	)
	(via
		(at 341.30615 -286.699452)
		(size 0.508)
		(drill 0.254)
		(layers "F.Cu" "B.Cu")
		(net "P5V_AUX")
	)
	(via
		(at 125.789944 -286.789876)
		(size 0.508)
		(drill 0.254)
		(layers "F.Cu" "B.Cu")
		(net "P5V_AUX")
	)
	(via
		(at 456.218544 -119.718836)
		(size 0.508)
		(drill 0.254)
		(layers "F.Cu" "B.Cu")
		(net "P5V_AUX")
	)
	(via
		(at 226.377754 -98.420936)
		(size 0.508)
		(drill 0.254)
		(layers "F.Cu" "B.Cu")
		(net "P5V_AUX")
	)
	(via
		(at 358.946958 -286.739076)
		(size 0.508)
		(drill 0.254)
		(layers "F.Cu" "B.Cu")
		(net "P5V_AUX")
	)
	(via
		(at 76.88199 -38.750748)
		(size 0.508)
		(drill 0.254)
		(layers "F.Cu" "B.Cu")
		(net "P5V_AUX")
	)
	(via
		(at 292.247066 -62.705996)
		(size 0.508)
		(drill 0.254)
		(layers "F.Cu" "B.Cu")
		(net "P5V_AUX")
	)
	(via
		(at 233.572558 -61.20003)
		(size 0.508)
		(drill 0.254)
		(layers "F.Cu" "B.Cu")
		(net "P5V_AUX")
	)
	(via
		(at 452.515986 -55.722266)
		(size 0.508)
		(drill 0.254)
		(layers "F.Cu" "B.Cu")
		(net "P5V_AUX")
	)
	(via
		(at 330.533756 -123.160028)
		(size 0.508)
		(drill 0.254)
		(layers "F.Cu" "B.Cu")
		(net "P5V_AUX")
	)
	(via
		(at 5.475224 -59.174634)
		(size 0.508)
		(drill 0.254)
		(layers "F.Cu" "B.Cu")
		(net "P5V_AUX")
	)
	(via
		(at 309.081932 -38.750748)
		(size 0.508)
		(drill 0.254)
		(layers "F.Cu" "B.Cu")
		(net "P5V_AUX")
	)
	(via
		(at 257.082036 -38.750748)
		(size 0.508)
		(drill 0.254)
		(layers "F.Cu" "B.Cu")
		(net "P5V_AUX")
	)
	(via
		(at 86.047072 -62.705996)
		(size 0.508)
		(drill 0.254)
		(layers "F.Cu" "B.Cu")
		(net "P5V_AUX")
	)
	(via
		(at 12.355322 -112.501426)
		(size 0.508)
		(drill 0.254)
		(layers "F.Cu" "B.Cu")
		(net "P5V_AUX")
	)
	(via
		(at 302.31334 -228.830886)
		(size 0.508)
		(drill 0.254)
		(layers "F.Cu" "B.Cu")
		(net "P5V_AUX")
	)
	(via
		(at 114.982244 -38.750748)
		(size 0.508)
		(drill 0.254)
		(layers "F.Cu" "B.Cu")
		(net "P5V_AUX")
	)
	(via
		(at 31.475172 -59.174634)
		(size 0.508)
		(drill 0.254)
		(layers "F.Cu" "B.Cu")
		(net "P5V_AUX")
	)
	(via
		(at 42.211752 -270.903954)
		(size 0.508)
		(drill 0.254)
		(layers "F.Cu" "B.Cu")
		(net "P5V_AUX")
	)
	(via
		(at 355.965252 -135.689594)
		(size 0.508)
		(drill 0.254)
		(layers "F.Cu" "B.Cu")
		(net "P5V_AUX")
	)
	(via
		(at 109.893608 -258.923536)
		(size 0.508)
		(drill 0.254)
		(layers "F.Cu" "B.Cu")
		(net "P5V_AUX")
	)
	(segment
		(start 227.826062 -69.091048)
		(end 226.918266 -69.091048)
		(width 0.4572)
		(layer "B.Cu")
		(net "P5V_AUX")
	)
	(segment
		(start 223.765364 -87.27186)
		(end 223.765364 -89.939114)
		(width 0.4572)
		(layer "B.Cu")
		(net "P5V_AUX")
	)
	(segment
		(start 340.118446 -121.249948)
		(end 340.118446 -119.718836)
		(width 0.4572)
		(layer "B.Cu")
		(net "P5V_AUX")
	)
	(segment
		(start 223.166686 -93.117162)
		(end 226.373944 -96.32442)
		(width 0.4572)
		(layer "B.Cu")
		(net "P5V_AUX")
	)
	(segment
		(start 109.900212 -252.60681)
		(end 109.900212 -258.111244)
		(width 0.4572)
		(layer "B.Cu")
		(net "P5V_AUX")
	)
	(segment
		(start 20.10664 -356.231444)
		(end 20.10664 -393.714986)
		(width 0.508)
		(layer "B.Cu")
		(net "P5V_AUX")
	)
	(segment
		(start 6.036564 -393.895834)
		(end 5.684774 -394.247624)
		(width 0.508)
		(layer "B.Cu")
		(net "P5V_AUX")
	)
	(segment
		(start 226.373944 -96.32442)
		(end 226.373944 -97.576894)
		(width 0.4572)
		(layer "B.Cu")
		(net "P5V_AUX")
	)
	(segment
		(start 125.357128 -286.35706)
		(end 125.789944 -286.789876)
		(width 0.4572)
		(layer "B.Cu")
		(net "P5V_AUX")
	)
	(segment
		(start 345.76131 -258.404614)
		(end 345.76131 -259.020564)
		(width 0.381)
		(layer "B.Cu")
		(net "P5V_AUX")
	)
	(segment
		(start 117.834918 -248.466102)
		(end 114.04092 -248.466102)
		(width 0.4572)
		(layer "B.Cu")
		(net "P5V_AUX")
	)
	(segment
		(start 17.599406 -319.978532)
		(end 16.312642 -321.265296)
		(width 0.508)
		(layer "B.Cu")
		(net "P5V_AUX")
	)
	(segment
		(start 11.530584 -396.193264)
		(end 11.240516 -395.903196)
		(width 0.508)
		(layer "B.Cu")
		(net "P5V_AUX")
	)
	(segment
		(start 119.856504 -239.352582)
		(end 118.977664 -240.231422)
		(width 0.4572)
		(layer "B.Cu")
		(net "P5V_AUX")
	)
	(segment
		(start 223.765364 -89.939114)
		(end 223.166686 -90.537792)
		(width 0.4572)
		(layer "B.Cu")
		(net "P5V_AUX")
	)
	(segment
		(start 109.682788 -286.46247)
		(end 109.940852 -286.720534)
		(width 0.4572)
		(layer "B.Cu")
		(net "P5V_AUX")
	)
	(segment
		(start 114.04092 -248.466102)
		(end 109.900212 -252.60681)
		(width 0.4572)
		(layer "B.Cu")
		(net "P5V_AUX")
	)
	(segment
		(start 17.599406 -312.521854)
		(end 17.599406 -319.978532)
		(width 0.508)
		(layer "B.Cu")
		(net "P5V_AUX")
	)
	(segment
		(start 118.977664 -247.323356)
		(end 117.834918 -248.466102)
		(width 0.4572)
		(layer "B.Cu")
		(net "P5V_AUX")
	)
	(segment
		(start 5.684774 -394.247624)
		(end 5.684774 -394.754608)
		(width 0.508)
		(layer "B.Cu")
		(net "P5V_AUX")
	)
	(segment
		(start 226.918266 -69.091048)
		(end 226.166934 -69.84238)
		(width 0.4572)
		(layer "B.Cu")
		(net "P5V_AUX")
	)
	(segment
		(start 109.682788 -285.980378)
		(end 109.682788 -286.46247)
		(width 0.4572)
		(layer "B.Cu")
		(net "P5V_AUX")
	)
	(segment
		(start 226.403916 -76.256388)
		(end 226.403916 -84.633308)
		(width 0.4572)
		(layer "B.Cu")
		(net "P5V_AUX")
	)
	(segment
		(start 223.166686 -90.537792)
		(end 223.166686 -93.117162)
		(width 0.4572)
		(layer "B.Cu")
		(net "P5V_AUX")
	)
	(segment
		(start 226.403916 -84.633308)
		(end 223.765364 -87.27186)
		(width 0.4572)
		(layer "B.Cu")
		(net "P5V_AUX")
	)
	(segment
		(start 226.373944 -97.576894)
		(end 226.377754 -97.580704)
		(width 0.4572)
		(layer "B.Cu")
		(net "P5V_AUX")
	)
	(segment
		(start 12.007342 -175.556164)
		(end 10.045446 -173.594268)
		(width 0.254)
		(layer "B.Cu")
		(net "P5V_AUX")
	)
	(segment
		(start 21.415756 -174.271178)
		(end 20.13077 -175.556164)
		(width 0.254)
		(layer "B.Cu")
		(net "P5V_AUX")
	)
	(segment
		(start 330.533756 -123.160028)
		(end 338.208366 -123.160028)
		(width 0.4572)
		(layer "B.Cu")
		(net "P5V_AUX")
	)
	(segment
		(start 20.13077 -175.556164)
		(end 12.007342 -175.556164)
		(width 0.254)
		(layer "B.Cu")
		(net "P5V_AUX")
	)
	(segment
		(start 18.035524 -312.085736)
		(end 17.599406 -312.521854)
		(width 0.508)
		(layer "B.Cu")
		(net "P5V_AUX")
	)
	(segment
		(start 358.604566 -286.007556)
		(end 358.604566 -286.396684)
		(width 0.4572)
		(layer "B.Cu")
		(net "P5V_AUX")
	)
	(segment
		(start 226.377754 -97.580704)
		(end 226.377754 -98.420936)
		(width 0.4572)
		(layer "B.Cu")
		(net "P5V_AUX")
	)
	(segment
		(start 16.312642 -321.265296)
		(end 16.312642 -352.437446)
		(width 0.508)
		(layer "B.Cu")
		(net "P5V_AUX")
	)
	(segment
		(start 338.208366 -123.160028)
		(end 340.118446 -121.249948)
		(width 0.4572)
		(layer "B.Cu")
		(net "P5V_AUX")
	)
	(segment
		(start 340.923372 -286.316674)
		(end 341.30615 -286.699452)
		(width 0.381)
		(layer "B.Cu")
		(net "P5V_AUX")
	)
	(segment
		(start 226.166934 -76.019406)
		(end 226.403916 -76.256388)
		(width 0.4572)
		(layer "B.Cu")
		(net "P5V_AUX")
	)
	(segment
		(start 20.10664 -393.714986)
		(end 17.628362 -396.193264)
		(width 0.508)
		(layer "B.Cu")
		(net "P5V_AUX")
	)
	(segment
		(start 358.604566 -286.396684)
		(end 358.946958 -286.739076)
		(width 0.4572)
		(layer "B.Cu")
		(net "P5V_AUX")
	)
	(segment
		(start 16.312642 -352.437446)
		(end 20.10664 -356.231444)
		(width 0.508)
		(layer "B.Cu")
		(net "P5V_AUX")
	)
	(segment
		(start 118.977664 -240.231422)
		(end 118.977664 -247.323356)
		(width 0.4572)
		(layer "B.Cu")
		(net "P5V_AUX")
	)
	(segment
		(start 119.856504 -238.057944)
		(end 119.856504 -239.352582)
		(width 0.4572)
		(layer "B.Cu")
		(net "P5V_AUX")
	)
	(segment
		(start 340.923372 -285.969202)
		(end 340.923372 -286.316674)
		(width 0.381)
		(layer "B.Cu")
		(net "P5V_AUX")
	)
	(segment
		(start 17.628362 -396.193264)
		(end 11.530584 -396.193264)
		(width 0.508)
		(layer "B.Cu")
		(net "P5V_AUX")
	)
	(segment
		(start 10.748264 -393.895834)
		(end 6.036564 -393.895834)
		(width 0.508)
		(layer "B.Cu")
		(net "P5V_AUX")
	)
	(segment
		(start 11.240516 -394.388086)
		(end 10.748264 -393.895834)
		(width 0.508)
		(layer "B.Cu")
		(net "P5V_AUX")
	)
	(segment
		(start 10.045446 -173.594268)
		(end 10.045446 -173.255432)
		(width 0.254)
		(layer "B.Cu")
		(net "P5V_AUX")
	)
	(segment
		(start 226.166934 -69.84238)
		(end 226.166934 -76.019406)
		(width 0.4572)
		(layer "B.Cu")
		(net "P5V_AUX")
	)
	(segment
		(start 113.561114 -258.404614)
		(end 113.561114 -259.020564)
		(width 0.381)
		(layer "B.Cu")
		(net "P5V_AUX")
	)
	(segment
		(start 11.240516 -395.903196)
		(end 11.240516 -394.388086)
		(width 0.508)
		(layer "B.Cu")
		(net "P5V_AUX")
	)
	(segment
		(start 125.357128 -286.000698)
		(end 125.357128 -286.35706)
		(width 0.4572)
		(layer "B.Cu")
		(net "P5V_AUX")
	)
	(segment
		(start 257.255518 -219.40901)
		(end 256.65049 -218.803982)
		(width 0.4572)
		(layer "In5.Cu")
		(net "P5V_AUX")
	)
	(segment
		(start 86.047072 -75.924156)
		(end 90.5764 -80.453484)
		(width 0.4572)
		(layer "In5.Cu")
		(net "P5V_AUX")
	)
	(segment
		(start 238.990886 -160.92424)
		(end 238.373666 -160.30702)
		(width 0.4572)
		(layer "In5.Cu")
		(net "P5V_AUX")
	)
	(segment
		(start 238.373666 -157.134306)
		(end 238.697008 -156.810964)
		(width 0.4572)
		(layer "In5.Cu")
		(net "P5V_AUX")
	)
	(segment
		(start 238.697008 -156.810964)
		(end 238.697008 -143.002)
		(width 0.4572)
		(layer "In5.Cu")
		(net "P5V_AUX")
	)
	(segment
		(start 238.373666 -160.30702)
		(end 238.373666 -157.134306)
		(width 0.4572)
		(layer "In5.Cu")
		(net "P5V_AUX")
	)
	(segment
		(start 247.408192 -188.200538)
		(end 246.300498 -189.308232)
		(width 0.4572)
		(layer "In5.Cu")
		(net "P5V_AUX")
	)
	(segment
		(start 257.738626 -235.209334)
		(end 255.843786 -233.314494)
		(width 0.4572)
		(layer "In5.Cu")
		(net "P5V_AUX")
	)
	(segment
		(start 246.300498 -197.869556)
		(end 244.230144 -199.93991)
		(width 0.4572)
		(layer "In5.Cu")
		(net "P5V_AUX")
	)
	(segment
		(start 256.65049 -218.803982)
		(end 256.65049 -217.116406)
		(width 0.4572)
		(layer "In5.Cu")
		(net "P5V_AUX")
	)
	(segment
		(start 90.5764 -84.40039)
		(end 99.501198 -93.325188)
		(width 0.4572)
		(layer "In5.Cu")
		(net "P5V_AUX")
	)
	(segment
		(start 244.230144 -199.93991)
		(end 244.230144 -207.724248)
		(width 0.4572)
		(layer "In5.Cu")
		(net "P5V_AUX")
	)
	(segment
		(start 256.65049 -217.116406)
		(end 257.535172 -216.231724)
		(width 0.4572)
		(layer "In5.Cu")
		(net "P5V_AUX")
	)
	(segment
		(start 99.501198 -93.325188)
		(end 99.501198 -95.905574)
		(width 0.4572)
		(layer "In5.Cu")
		(net "P5V_AUX")
	)
	(segment
		(start 246.239792 -180.893974)
		(end 248.169938 -182.82412)
		(width 0.4572)
		(layer "In5.Cu")
		(net "P5V_AUX")
	)
	(segment
		(start 239.865154 -141.833854)
		(end 239.865154 -135.689594)
		(width 0.4572)
		(layer "In5.Cu")
		(net "P5V_AUX")
	)
	(segment
		(start 255.843786 -233.314494)
		(end 255.843786 -231.761792)
		(width 0.4572)
		(layer "In5.Cu")
		(net "P5V_AUX")
	)
	(segment
		(start 244.230144 -207.724248)
		(end 242.5319 -209.422492)
		(width 0.4572)
		(layer "In5.Cu")
		(net "P5V_AUX")
	)
	(segment
		(start 238.697008 -143.002)
		(end 239.865154 -141.833854)
		(width 0.4572)
		(layer "In5.Cu")
		(net "P5V_AUX")
	)
	(segment
		(start 255.843786 -231.761792)
		(end 257.255518 -230.35006)
		(width 0.4572)
		(layer "In5.Cu")
		(net "P5V_AUX")
	)
	(segment
		(start 247.408192 -185.135012)
		(end 247.408192 -188.200538)
		(width 0.4572)
		(layer "In5.Cu")
		(net "P5V_AUX")
	)
	(segment
		(start 86.047072 -62.705996)
		(end 86.047072 -75.924156)
		(width 0.4572)
		(layer "In5.Cu")
		(net "P5V_AUX")
	)
	(segment
		(start 246.300498 -189.308232)
		(end 246.300498 -197.869556)
		(width 0.4572)
		(layer "In5.Cu")
		(net "P5V_AUX")
	)
	(segment
		(start 90.5764 -80.453484)
		(end 90.5764 -84.40039)
		(width 0.4572)
		(layer "In5.Cu")
		(net "P5V_AUX")
	)
	(segment
		(start 248.169938 -184.373266)
		(end 247.408192 -185.135012)
		(width 0.4572)
		(layer "In5.Cu")
		(net "P5V_AUX")
	)
	(segment
		(start 242.5319 -209.422492)
		(end 242.5319 -209.967576)
		(width 0.4572)
		(layer "In5.Cu")
		(net "P5V_AUX")
	)
	(segment
		(start 248.169938 -182.82412)
		(end 248.169938 -184.373266)
		(width 0.4572)
		(layer "In5.Cu")
		(net "P5V_AUX")
	)
	(segment
		(start 242.5319 -209.967576)
		(end 242.50904 -209.990436)
		(width 0.4572)
		(layer "In5.Cu")
		(net "P5V_AUX")
	)
	(segment
		(start 257.738626 -238.333788)
		(end 257.738626 -235.209334)
		(width 0.4572)
		(layer "In5.Cu")
		(net "P5V_AUX")
	)
	(segment
		(start 257.255518 -230.35006)
		(end 257.255518 -219.40901)
		(width 0.4572)
		(layer "In5.Cu")
		(net "P5V_AUX")
	)
	(segment
		(start 102.132892 -292.113208)
		(end 109.636814 -292.113208)
		(width 0.4572)
		(layer "In7.Cu")
		(net "P5V_AUX")
	)
	(segment
		(start 340.52891 -261.346442)
		(end 332.203806 -261.346442)
		(width 0.4572)
		(layer "In7.Cu")
		(net "P5V_AUX")
	)
	(segment
		(start 358.729534 -291.80663)
		(end 358.729534 -286.9565)
		(width 0.381)
		(layer "In7.Cu")
		(net "P5V_AUX")
	)
	(segment
		(start 110.036864 -291.713158)
		(end 110.036864 -286.816546)
		(width 0.381)
		(layer "In7.Cu")
		(net "P5V_AUX")
	)
	(segment
		(start 450.45757 -246.16664)
		(end 449.503038 -245.212108)
		(width 0.4572)
		(layer "In7.Cu")
		(net "P5V_AUX")
	)
	(segment
		(start 126.695962 -291.713158)
		(end 126.295912 -292.113208)
		(width 0.381)
		(layer "In7.Cu")
		(net "P5V_AUX")
	)
	(segment
		(start 329.948286 -293.59733)
		(end 332.789022 -293.59733)
		(width 0.4572)
		(layer "In7.Cu")
		(net "P5V_AUX")
	)
	(segment
		(start 100.64877 -293.59733)
		(end 102.132892 -292.113208)
		(width 0.4572)
		(layer "In7.Cu")
		(net "P5V_AUX")
	)
	(segment
		(start 358.729534 -286.9565)
		(end 358.946958 -286.739076)
		(width 0.381)
		(layer "In7.Cu")
		(net "P5V_AUX")
	)
	(segment
		(start 443.385448 -129.84226)
		(end 447.355722 -125.871986)
		(width 0.4572)
		(layer "In7.Cu")
		(net "P5V_AUX")
	)
	(segment
		(start 449.503038 -237.765082)
		(end 447.235072 -235.497116)
		(width 0.4572)
		(layer "In7.Cu")
		(net "P5V_AUX")
	)
	(segment
		(start 449.503038 -231.495854)
		(end 449.503038 -218.50985)
		(width 0.4572)
		(layer "In7.Cu")
		(net "P5V_AUX")
	)
	(segment
		(start 342.23706 -291.713158)
		(end 342.63711 -292.113208)
		(width 0.381)
		(layer "In7.Cu")
		(net "P5V_AUX")
	)
	(segment
		(start 454.498202 -246.16664)
		(end 450.45757 -246.16664)
		(width 0.4572)
		(layer "In7.Cu")
		(net "P5V_AUX")
	)
	(segment
		(start 125.887988 -286.789876)
		(end 126.695962 -287.59785)
		(width 0.381)
		(layer "In7.Cu")
		(net "P5V_AUX")
	)
	(segment
		(start 447.355722 -123.881896)
		(end 446.633854 -123.160028)
		(width 0.4572)
		(layer "In7.Cu")
		(net "P5V_AUX")
	)
	(segment
		(start 334.273144 -292.113208)
		(end 341.83701 -292.113208)
		(width 0.4572)
		(layer "In7.Cu")
		(net "P5V_AUX")
	)
	(segment
		(start 358.422956 -292.113208)
		(end 358.729534 -291.80663)
		(width 0.381)
		(layer "In7.Cu")
		(net "P5V_AUX")
	)
	(segment
		(start 110.436914 -292.113208)
		(end 110.036864 -291.713158)
		(width 0.381)
		(layer "In7.Cu")
		(net "P5V_AUX")
	)
	(segment
		(start 126.295912 -292.113208)
		(end 110.436914 -292.113208)
		(width 0.381)
		(layer "In7.Cu")
		(net "P5V_AUX")
	)
	(segment
		(start 97.802192 -284.574488)
		(end 95.30461 -287.07207)
		(width 0.4572)
		(layer "In7.Cu")
		(net "P5V_AUX")
	)
	(segment
		(start 449.503038 -245.212108)
		(end 449.503038 -237.765082)
		(width 0.4572)
		(layer "In7.Cu")
		(net "P5V_AUX")
	)
	(segment
		(start 109.636814 -292.113208)
		(end 110.036864 -291.713158)
		(width 0.4572)
		(layer "In7.Cu")
		(net "P5V_AUX")
	)
	(segment
		(start 126.695962 -287.59785)
		(end 126.695962 -291.713158)
		(width 0.381)
		(layer "In7.Cu")
		(net "P5V_AUX")
	)
	(segment
		(start 447.355722 -125.871986)
		(end 447.355722 -123.881896)
		(width 0.4572)
		(layer "In7.Cu")
		(net "P5V_AUX")
	)
	(segment
		(start 443.385448 -212.39226)
		(end 443.385448 -129.84226)
		(width 0.4572)
		(layer "In7.Cu")
		(net "P5V_AUX")
	)
	(segment
		(start 102.426516 -258.923536)
		(end 97.802192 -263.54786)
		(width 0.4572)
		(layer "In7.Cu")
		(net "P5V_AUX")
	)
	(segment
		(start 341.83701 -292.113208)
		(end 342.23706 -291.713158)
		(width 0.4572)
		(layer "In7.Cu")
		(net "P5V_AUX")
	)
	(segment
		(start 342.63711 -292.113208)
		(end 358.422956 -292.113208)
		(width 0.381)
		(layer "In7.Cu")
		(net "P5V_AUX")
	)
	(segment
		(start 95.30461 -287.07207)
		(end 95.30461 -291.15385)
		(width 0.4572)
		(layer "In7.Cu")
		(net "P5V_AUX")
	)
	(segment
		(start 332.789022 -293.59733)
		(end 334.273144 -292.113208)
		(width 0.4572)
		(layer "In7.Cu")
		(net "P5V_AUX")
	)
	(segment
		(start 330.675742 -285.24073)
		(end 327.651618 -288.264854)
		(width 0.4572)
		(layer "In7.Cu")
		(net "P5V_AUX")
	)
	(segment
		(start 327.651618 -288.264854)
		(end 327.651618 -291.300662)
		(width 0.4572)
		(layer "In7.Cu")
		(net "P5V_AUX")
	)
	(segment
		(start 125.789944 -286.789876)
		(end 125.887988 -286.789876)
		(width 0.381)
		(layer "In7.Cu")
		(net "P5V_AUX")
	)
	(segment
		(start 330.675742 -262.874506)
		(end 330.675742 -285.24073)
		(width 0.4572)
		(layer "In7.Cu")
		(net "P5V_AUX")
	)
	(segment
		(start 447.235072 -235.497116)
		(end 447.235072 -233.76382)
		(width 0.4572)
		(layer "In7.Cu")
		(net "P5V_AUX")
	)
	(segment
		(start 449.503038 -218.50985)
		(end 443.385448 -212.39226)
		(width 0.4572)
		(layer "In7.Cu")
		(net "P5V_AUX")
	)
	(segment
		(start 447.235072 -233.76382)
		(end 449.503038 -231.495854)
		(width 0.4572)
		(layer "In7.Cu")
		(net "P5V_AUX")
	)
	(segment
		(start 327.651618 -291.300662)
		(end 329.948286 -293.59733)
		(width 0.4572)
		(layer "In7.Cu")
		(net "P5V_AUX")
	)
	(segment
		(start 97.74809 -293.59733)
		(end 100.64877 -293.59733)
		(width 0.4572)
		(layer "In7.Cu")
		(net "P5V_AUX")
	)
	(segment
		(start 95.30461 -291.15385)
		(end 97.74809 -293.59733)
		(width 0.4572)
		(layer "In7.Cu")
		(net "P5V_AUX")
	)
	(segment
		(start 332.203806 -261.346442)
		(end 330.675742 -262.874506)
		(width 0.4572)
		(layer "In7.Cu")
		(net "P5V_AUX")
	)
	(segment
		(start 342.23706 -287.630362)
		(end 341.30615 -286.699452)
		(width 0.381)
		(layer "In7.Cu")
		(net "P5V_AUX")
	)
	(segment
		(start 342.23706 -291.713158)
		(end 342.23706 -287.630362)
		(width 0.381)
		(layer "In7.Cu")
		(net "P5V_AUX")
	)
	(segment
		(start 108.471208 -258.923536)
		(end 102.426516 -258.923536)
		(width 0.4572)
		(layer "In7.Cu")
		(net "P5V_AUX")
	)
	(segment
		(start 97.802192 -263.54786)
		(end 97.802192 -284.574488)
		(width 0.4572)
		(layer "In7.Cu")
		(net "P5V_AUX")
	)
	(segment
		(start 110.036864 -286.816546)
		(end 109.940852 -286.720534)
		(width 0.381)
		(layer "In7.Cu")
		(net "P5V_AUX")
	)
	(segment
		(start 226.377754 -98.420936)
		(end 221.652338 -98.420936)
		(width 0.4572)
		(layer "In9.Cu")
		(net "P5V_AUX")
	)
	(segment
		(start 213.409784 -106.459528)
		(end 215.302592 -108.352336)
		(width 0.4572)
		(layer "In9.Cu")
		(net "P5V_AUX")
	)
	(segment
		(start 216.411556 -98.95078)
		(end 213.409784 -101.952552)
		(width 0.4572)
		(layer "In9.Cu")
		(net "P5V_AUX")
	)
	(segment
		(start 215.302592 -108.352336)
		(end 215.302592 -121.021094)
		(width 0.4572)
		(layer "In9.Cu")
		(net "P5V_AUX")
	)
	(segment
		(start 215.302592 -121.021094)
		(end 214.433658 -121.890028)
		(width 0.4572)
		(layer "In9.Cu")
		(net "P5V_AUX")
	)
	(segment
		(start 213.409784 -101.952552)
		(end 213.409784 -106.459528)
		(width 0.4572)
		(layer "In9.Cu")
		(net "P5V_AUX")
	)
	(segment
		(start 221.652338 -98.420936)
		(end 221.122494 -98.95078)
		(width 0.4572)
		(layer "In9.Cu")
		(net "P5V_AUX")
	)
	(segment
		(start 221.122494 -98.95078)
		(end 216.411556 -98.95078)
		(width 0.4572)
		(layer "In9.Cu")
		(net "P5V_AUX")
	)
	(segment
		(start 25.15235 -276.900132)
		(end 31.574486 -276.900132)
		(width 0.508)
		(layer "In13.Cu")
		(net "P5V_AUX")
	)
	(segment
		(start 8.77951 -177.566828)
		(end 7.01548 -179.330858)
		(width 0.4572)
		(layer "In13.Cu")
		(net "P5V_AUX")
	)
	(segment
		(start 24.64435 -306.247546)
		(end 24.64435 -277.408132)
		(width 0.508)
		(layer "In13.Cu")
		(net "P5V_AUX")
	)
	(segment
		(start 37.008054 -271.466564)
		(end 41.649142 -271.466564)
		(width 0.508)
		(layer "In13.Cu")
		(net "P5V_AUX")
	)
	(segment
		(start 119.856504 -238.057944)
		(end 121.151142 -238.057944)
		(width 0.4572)
		(layer "In13.Cu")
		(net "P5V_AUX")
	)
	(segment
		(start 7.01548 -206.51978)
		(end 10.609072 -210.113372)
		(width 0.4572)
		(layer "In13.Cu")
		(net "P5V_AUX")
	)
	(segment
		(start 7.01548 -179.330858)
		(end 7.01548 -206.51978)
		(width 0.4572)
		(layer "In13.Cu")
		(net "P5V_AUX")
	)
	(segment
		(start 31.574486 -276.900132)
		(end 37.008054 -271.466564)
		(width 0.508)
		(layer "In13.Cu")
		(net "P5V_AUX")
	)
	(segment
		(start 24.64435 -277.408132)
		(end 25.15235 -276.900132)
		(width 0.508)
		(layer "In13.Cu")
		(net "P5V_AUX")
	)
	(segment
		(start 122.154188 -237.054898)
		(end 127.380492 -237.054898)
		(width 0.4572)
		(layer "In13.Cu")
		(net "P5V_AUX")
	)
	(segment
		(start 10.609072 -210.113372)
		(end 14.236446 -210.113372)
		(width 0.4572)
		(layer "In13.Cu")
		(net "P5V_AUX")
	)
	(segment
		(start 20.211542 -312.085736)
		(end 23.650702 -308.646576)
		(width 0.508)
		(layer "In13.Cu")
		(net "P5V_AUX")
	)
	(segment
		(start 41.649142 -271.466564)
		(end 42.211752 -270.903954)
		(width 0.508)
		(layer "In13.Cu")
		(net "P5V_AUX")
	)
	(segment
		(start 134.422388 -239.67694)
		(end 135.00735 -239.091978)
		(width 0.4572)
		(layer "In13.Cu")
		(net "P5V_AUX")
	)
	(segment
		(start 127.380492 -237.054898)
		(end 130.002534 -239.67694)
		(width 0.4572)
		(layer "In13.Cu")
		(net "P5V_AUX")
	)
	(segment
		(start 130.002534 -239.67694)
		(end 134.422388 -239.67694)
		(width 0.4572)
		(layer "In13.Cu")
		(net "P5V_AUX")
	)
	(segment
		(start 121.151142 -238.057944)
		(end 122.154188 -237.054898)
		(width 0.4572)
		(layer "In13.Cu")
		(net "P5V_AUX")
	)
	(segment
		(start 135.00735 -239.091978)
		(end 145.568162 -239.091978)
		(width 0.4572)
		(layer "In13.Cu")
		(net "P5V_AUX")
	)
	(segment
		(start 23.650702 -308.646576)
		(end 24.64435 -306.247546)
		(width 0.508)
		(layer "In13.Cu")
		(net "P5V_AUX")
	)
	(segment
		(start 18.035524 -312.085736)
		(end 20.211542 -312.085736)
		(width 0.508)
		(layer "In13.Cu")
		(net "P5V_AUX")
	)
	(segment
		(start 116.125752 -279.886918)
		(end 116.850414 -279.886918)
		(width 0.254)
		(layer "F.Cu")
		(net "P0V8_PEX0_VREF")
	)
	(segment
		(start 132.781294 -281.893518)
		(end 132.781294 -281.999182)
		(width 0.2286)
		(layer "F.Cu")
		(net "P0V8_PEX0_VREF")
	)
	(segment
		(start 116.122196 -281.893518)
		(end 116.122196 -281.999182)
		(width 0.2286)
		(layer "F.Cu")
		(net "P0V8_PEX0_VREF")
	)
	(segment
		(start 124.620782 -281.893518)
		(end 124.620782 -281.999182)
		(width 0.2286)
		(layer "F.Cu")
		(net "P0V8_PEX0_VREF")
	)
	(segment
		(start 133.37667 -280.344118)
		(end 133.37667 -281.04465)
		(width 0.2286)
		(layer "F.Cu")
		(net "P0V8_PEX0_VREF")
	)
	(segment
		(start 132.91947 -279.886918)
		(end 133.37667 -280.344118)
		(width 0.254)
		(layer "F.Cu")
		(net "P0V8_PEX0_VREF")
	)
	(segment
		(start 125.377448 -279.915366)
		(end 125.377448 -280.655014)
		(width 0.2286)
		(layer "F.Cu")
		(net "P0V8_PEX0_VREF")
	)
	(segment
		(start 108.377736 -281.477466)
		(end 107.961684 -281.893518)
		(width 0.2286)
		(layer "F.Cu")
		(net "P0V8_PEX0_VREF")
	)
	(segment
		(start 108.71835 -280.655014)
		(end 108.377736 -281.477466)
		(width 0.2286)
		(layer "F.Cu")
		(net "P0V8_PEX0_VREF")
	)
	(segment
		(start 116.850414 -279.886918)
		(end 116.878862 -279.915366)
		(width 0.2286)
		(layer "F.Cu")
		(net "P0V8_PEX0_VREF")
	)
	(segment
		(start 133.197346 -281.477466)
		(end 132.781294 -281.893518)
		(width 0.2286)
		(layer "F.Cu")
		(net "P0V8_PEX0_VREF")
	)
	(segment
		(start 108.71835 -279.915366)
		(end 108.71835 -280.655014)
		(width 0.2286)
		(layer "F.Cu")
		(net "P0V8_PEX0_VREF")
	)
	(segment
		(start 132.78485 -279.886918)
		(end 132.91947 -279.886918)
		(width 0.254)
		(layer "F.Cu")
		(net "P0V8_PEX0_VREF")
	)
	(segment
		(start 125.036834 -281.477466)
		(end 124.620782 -281.893518)
		(width 0.2286)
		(layer "F.Cu")
		(net "P0V8_PEX0_VREF")
	)
	(segment
		(start 125.377448 -280.655014)
		(end 125.036834 -281.477466)
		(width 0.2286)
		(layer "F.Cu")
		(net "P0V8_PEX0_VREF")
	)
	(segment
		(start 125.349 -279.886918)
		(end 125.377448 -279.915366)
		(width 0.2286)
		(layer "F.Cu")
		(net "P0V8_PEX0_VREF")
	)
	(segment
		(start 107.961684 -281.893518)
		(end 107.961684 -281.999182)
		(width 0.2286)
		(layer "F.Cu")
		(net "P0V8_PEX0_VREF")
	)
	(segment
		(start 113.161064 -260.671564)
		(end 112.545114 -260.671564)
		(width 0.381)
		(layer "F.Cu")
		(net "P0V8_PEX0_VREF")
	)
	(segment
		(start 108.689902 -279.886918)
		(end 108.71835 -279.915366)
		(width 0.2286)
		(layer "F.Cu")
		(net "P0V8_PEX0_VREF")
	)
	(segment
		(start 133.37667 -281.04465)
		(end 133.197346 -281.477466)
		(width 0.2286)
		(layer "F.Cu")
		(net "P0V8_PEX0_VREF")
	)
	(segment
		(start 107.96524 -279.886918)
		(end 108.689902 -279.886918)
		(width 0.254)
		(layer "F.Cu")
		(net "P0V8_PEX0_VREF")
	)
	(segment
		(start 124.624338 -279.886918)
		(end 125.349 -279.886918)
		(width 0.254)
		(layer "F.Cu")
		(net "P0V8_PEX0_VREF")
	)
	(segment
		(start 116.878862 -280.655014)
		(end 116.538248 -281.477466)
		(width 0.2286)
		(layer "F.Cu")
		(net "P0V8_PEX0_VREF")
	)
	(segment
		(start 116.538248 -281.477466)
		(end 116.122196 -281.893518)
		(width 0.2286)
		(layer "F.Cu")
		(net "P0V8_PEX0_VREF")
	)
	(segment
		(start 116.878862 -279.915366)
		(end 116.878862 -280.655014)
		(width 0.2286)
		(layer "F.Cu")
		(net "P0V8_PEX0_VREF")
	)
	(via
		(at 116.125752 -279.886918)
		(size 0.508)
		(drill 0.254)
		(layers "F.Cu" "B.Cu")
		(net "P0V8_PEX0_VREF")
	)
	(via
		(at 112.545114 -260.671564)
		(size 0.508)
		(drill 0.254)
		(layers "F.Cu" "B.Cu")
		(net "P0V8_PEX0_VREF")
	)
	(via
		(at 107.96524 -279.886918)
		(size 0.508)
		(drill 0.254)
		(layers "F.Cu" "B.Cu")
		(net "P0V8_PEX0_VREF")
	)
	(via
		(at 124.624338 -279.886918)
		(size 0.508)
		(drill 0.254)
		(layers "F.Cu" "B.Cu")
		(net "P0V8_PEX0_VREF")
	)
	(via
		(at 132.78485 -279.886918)
		(size 0.508)
		(drill 0.254)
		(layers "F.Cu" "B.Cu")
		(net "P0V8_PEX0_VREF")
	)
	(via
		(at 118.05793 -254.164338)
		(size 0.508)
		(drill 0.254)
		(layers "F.Cu" "B.Cu")
		(net "P0V8_PEX0_VREF")
	)
	(segment
		(start 119.965978 -254.164338)
		(end 121.041668 -253.088648)
		(width 0.381)
		(layer "B.Cu")
		(net "P0V8_PEX0_VREF")
	)
	(segment
		(start 123.533662 -253.088648)
		(end 125.366526 -254.921512)
		(width 0.381)
		(layer "B.Cu")
		(net "P0V8_PEX0_VREF")
	)
	(segment
		(start 118.05793 -254.164338)
		(end 119.965978 -254.164338)
		(width 0.381)
		(layer "B.Cu")
		(net "P0V8_PEX0_VREF")
	)
	(segment
		(start 125.366526 -258.135628)
		(end 126.113286 -258.882388)
		(width 0.381)
		(layer "B.Cu")
		(net "P0V8_PEX0_VREF")
	)
	(segment
		(start 121.041668 -253.088648)
		(end 123.533662 -253.088648)
		(width 0.381)
		(layer "B.Cu")
		(net "P0V8_PEX0_VREF")
	)
	(segment
		(start 126.113286 -258.882388)
		(end 126.113286 -260.13791)
		(width 0.381)
		(layer "B.Cu")
		(net "P0V8_PEX0_VREF")
	)
	(segment
		(start 125.366526 -254.921512)
		(end 125.366526 -258.135628)
		(width 0.381)
		(layer "B.Cu")
		(net "P0V8_PEX0_VREF")
	)
	(segment
		(start 131.292092 -275.837142)
		(end 131.292092 -268.074394)
		(width 0.254)
		(layer "In11.Cu")
		(net "P0V8_PEX0_VREF")
	)
	(segment
		(start 123.362466 -262.111744)
		(end 122.721624 -262.111744)
		(width 0.254)
		(layer "In11.Cu")
		(net "P0V8_PEX0_VREF")
	)
	(segment
		(start 111.54029 -279.37587)
		(end 109.705394 -279.37587)
		(width 0.254)
		(layer "In11.Cu")
		(net "P0V8_PEX0_VREF")
	)
	(segment
		(start 121.54789 -263.285478)
		(end 119.64035 -263.285478)
		(width 0.254)
		(layer "In11.Cu")
		(net "P0V8_PEX0_VREF")
	)
	(segment
		(start 126.7206 -263.502902)
		(end 123.362466 -262.111744)
		(width 0.254)
		(layer "In11.Cu")
		(net "P0V8_PEX0_VREF")
	)
	(segment
		(start 132.78485 -279.886918)
		(end 133.180836 -280.282904)
		(width 0.254)
		(layer "In11.Cu")
		(net "P0V8_PEX0_VREF")
	)
	(segment
		(start 118.071392 -279.170384)
		(end 116.958872 -280.282904)
		(width 0.254)
		(layer "In11.Cu")
		(net "P0V8_PEX0_VREF")
	)
	(segment
		(start 108.79836 -280.282904)
		(end 108.361226 -280.282904)
		(width 0.254)
		(layer "In11.Cu")
		(net "P0V8_PEX0_VREF")
	)
	(segment
		(start 116.95557 -266.56792)
		(end 112.575086 -270.948404)
		(width 0.254)
		(layer "In11.Cu")
		(net "P0V8_PEX0_VREF")
	)
	(segment
		(start 125.80366 -279.398222)
		(end 125.80366 -279.936702)
		(width 0.254)
		(layer "In11.Cu")
		(net "P0V8_PEX0_VREF")
	)
	(segment
		(start 121.273824 -264.346944)
		(end 120.547384 -264.346944)
		(width 0.254)
		(layer "In11.Cu")
		(net "P0V8_PEX0_VREF")
	)
	(segment
		(start 118.122954 -266.56792)
		(end 116.95557 -266.56792)
		(width 0.254)
		(layer "In11.Cu")
		(net "P0V8_PEX0_VREF")
	)
	(segment
		(start 116.521738 -280.282904)
		(end 116.125752 -279.886918)
		(width 0.254)
		(layer "In11.Cu")
		(net "P0V8_PEX0_VREF")
	)
	(segment
		(start 132.005324 -277.559262)
		(end 131.292092 -275.837142)
		(width 0.254)
		(layer "In11.Cu")
		(net "P0V8_PEX0_VREF")
	)
	(segment
		(start 133.180836 -280.282904)
		(end 133.446774 -280.282904)
		(width 0.254)
		(layer "In11.Cu")
		(net "P0V8_PEX0_VREF")
	)
	(segment
		(start 123.055634 -266.922504)
		(end 123.055634 -276.650196)
		(width 0.254)
		(layer "In11.Cu")
		(net "P0V8_PEX0_VREF")
	)
	(segment
		(start 120.120156 -265.269472)
		(end 120.39981 -265.549126)
		(width 0.254)
		(layer "In11.Cu")
		(net "P0V8_PEX0_VREF")
	)
	(segment
		(start 118.071392 -269.446502)
		(end 118.071392 -279.170384)
		(width 0.254)
		(layer "In11.Cu")
		(net "P0V8_PEX0_VREF")
	)
	(segment
		(start 131.292092 -268.074394)
		(end 126.7206 -263.502902)
		(width 0.254)
		(layer "In11.Cu")
		(net "P0V8_PEX0_VREF")
	)
	(segment
		(start 108.361226 -280.282904)
		(end 107.96524 -279.886918)
		(width 0.254)
		(layer "In11.Cu")
		(net "P0V8_PEX0_VREF")
	)
	(segment
		(start 120.547384 -264.346944)
		(end 120.146572 -264.747756)
		(width 0.254)
		(layer "In11.Cu")
		(net "P0V8_PEX0_VREF")
	)
	(segment
		(start 125.80366 -279.936702)
		(end 125.457458 -280.282904)
		(width 0.254)
		(layer "In11.Cu")
		(net "P0V8_PEX0_VREF")
	)
	(segment
		(start 133.739128 -279.293066)
		(end 132.005324 -277.559262)
		(width 0.254)
		(layer "In11.Cu")
		(net "P0V8_PEX0_VREF")
	)
	(segment
		(start 133.446774 -280.282904)
		(end 133.739128 -279.99055)
		(width 0.254)
		(layer "In11.Cu")
		(net "P0V8_PEX0_VREF")
	)
	(segment
		(start 119.156988 -265.002772)
		(end 119.421402 -265.267186)
		(width 0.254)
		(layer "In11.Cu")
		(net "P0V8_PEX0_VREF")
	)
	(segment
		(start 120.120156 -265.269472)
		(end 119.421402 -265.269472)
		(width 0.254)
		(layer "In11.Cu")
		(net "P0V8_PEX0_VREF")
	)
	(segment
		(start 119.421402 -265.269472)
		(end 118.122954 -266.56792)
		(width 0.254)
		(layer "In11.Cu")
		(net "P0V8_PEX0_VREF")
	)
	(segment
		(start 116.958872 -280.282904)
		(end 116.521738 -280.282904)
		(width 0.254)
		(layer "In11.Cu")
		(net "P0V8_PEX0_VREF")
	)
	(segment
		(start 120.39981 -265.549126)
		(end 120.39981 -267.118084)
		(width 0.254)
		(layer "In11.Cu")
		(net "P0V8_PEX0_VREF")
	)
	(segment
		(start 120.146572 -265.243056)
		(end 120.120156 -265.269472)
		(width 0.254)
		(layer "In11.Cu")
		(net "P0V8_PEX0_VREF")
	)
	(segment
		(start 120.39981 -267.118084)
		(end 118.071392 -269.446502)
		(width 0.254)
		(layer "In11.Cu")
		(net "P0V8_PEX0_VREF")
	)
	(segment
		(start 121.531126 -265.397996)
		(end 123.055634 -266.922504)
		(width 0.254)
		(layer "In11.Cu")
		(net "P0V8_PEX0_VREF")
	)
	(segment
		(start 119.156988 -263.76884)
		(end 119.156988 -265.002772)
		(width 0.254)
		(layer "In11.Cu")
		(net "P0V8_PEX0_VREF")
	)
	(segment
		(start 112.575086 -278.341074)
		(end 111.54029 -279.37587)
		(width 0.254)
		(layer "In11.Cu")
		(net "P0V8_PEX0_VREF")
	)
	(segment
		(start 125.020324 -280.282904)
		(end 124.624338 -279.886918)
		(width 0.254)
		(layer "In11.Cu")
		(net "P0V8_PEX0_VREF")
	)
	(segment
		(start 133.739128 -279.99055)
		(end 133.739128 -279.293066)
		(width 0.254)
		(layer "In11.Cu")
		(net "P0V8_PEX0_VREF")
	)
	(segment
		(start 122.721624 -262.111744)
		(end 121.54789 -263.285478)
		(width 0.254)
		(layer "In11.Cu")
		(net "P0V8_PEX0_VREF")
	)
	(segment
		(start 125.457458 -280.282904)
		(end 125.020324 -280.282904)
		(width 0.254)
		(layer "In11.Cu")
		(net "P0V8_PEX0_VREF")
	)
	(segment
		(start 112.575086 -270.948404)
		(end 112.575086 -278.341074)
		(width 0.254)
		(layer "In11.Cu")
		(net "P0V8_PEX0_VREF")
	)
	(segment
		(start 109.705394 -279.37587)
		(end 108.79836 -280.282904)
		(width 0.254)
		(layer "In11.Cu")
		(net "P0V8_PEX0_VREF")
	)
	(segment
		(start 120.146572 -264.747756)
		(end 120.146572 -265.243056)
		(width 0.254)
		(layer "In11.Cu")
		(net "P0V8_PEX0_VREF")
	)
	(segment
		(start 119.421402 -265.267186)
		(end 119.421402 -265.269472)
		(width 0.254)
		(layer "In11.Cu")
		(net "P0V8_PEX0_VREF")
	)
	(segment
		(start 121.531126 -264.604246)
		(end 121.273824 -264.346944)
		(width 0.254)
		(layer "In11.Cu")
		(net "P0V8_PEX0_VREF")
	)
	(segment
		(start 119.64035 -263.285478)
		(end 119.156988 -263.76884)
		(width 0.254)
		(layer "In11.Cu")
		(net "P0V8_PEX0_VREF")
	)
	(segment
		(start 123.055634 -276.650196)
		(end 125.80366 -279.398222)
		(width 0.254)
		(layer "In11.Cu")
		(net "P0V8_PEX0_VREF")
	)
	(segment
		(start 121.531126 -265.397996)
		(end 121.531126 -264.604246)
		(width 0.254)
		(layer "In11.Cu")
		(net "P0V8_PEX0_VREF")
	)
	(segment
		(start 19.85518 -35.876738)
		(end 19.099276 -35.876738)
		(width 0.4572)
		(layer "F.Cu")
		(net "P3V3_AUX")
	)
	(segment
		(start 399.443448 -169.351706)
		(end 399.443448 -170.77944)
		(width 0.4572)
		(layer "F.Cu")
		(net "P3V3_AUX")
	)
	(segment
		(start 117.226334 -40.82161)
		(end 117.07622 -40.971724)
		(width 0.4572)
		(layer "F.Cu")
		(net "P3V3_AUX")
	)
	(segment
		(start 124.808742 -167.074088)
		(end 125.59411 -167.074088)
		(width 0.4572)
		(layer "F.Cu")
		(net "P3V3_AUX")
	)
	(segment
		(start 279.121616 -404.674324)
		(end 279.121616 -404.073614)
		(width 0.4572)
		(layer "F.Cu")
		(net "P3V3_AUX")
	)
	(segment
		(start 183.847994 -187.701174)
		(end 184.553352 -186.995816)
		(width 0.381)
		(layer "F.Cu")
		(net "P3V3_AUX")
	)
	(segment
		(start 186.13755 -376.033792)
		(end 186.13755 -407.4414)
		(width 0.4572)
		(layer "F.Cu")
		(net "P3V3_AUX")
	)
	(segment
		(start 281.33548 -407.314908)
		(end 280.571448 -407.314908)
		(width 0.4572)
		(layer "F.Cu")
		(net "P3V3_AUX")
	)
	(segment
		(start 100.955094 -397.912336)
		(end 100.955094 -398.66824)
		(width 0.4572)
		(layer "F.Cu")
		(net "P3V3_AUX")
	)
	(segment
		(start 234.64266 -204.04201)
		(end 234.64266 -203.770738)
		(width 0.4572)
		(layer "F.Cu")
		(net "P3V3_AUX")
	)
	(segment
		(start 168.768014 -52.035456)
		(end 169.423334 -52.035456)
		(width 0.254)
		(layer "F.Cu")
		(net "P3V3_AUX")
	)
	(segment
		(start 384.904742 -142.88897)
		(end 384.904742 -141.87297)
		(width 0.4064)
		(layer "F.Cu")
		(net "P3V3_AUX")
	)
	(segment
		(start 226.175824 -279.139904)
		(end 226.175824 -280.10104)
		(width 0.254)
		(layer "F.Cu")
		(net "P3V3_AUX")
	)
	(segment
		(start 224.422208 -83.659472)
		(end 225.032062 -83.659472)
		(width 0.4572)
		(layer "F.Cu")
		(net "P3V3_AUX")
	)
	(segment
		(start 368.15522 -35.876738)
		(end 367.399316 -35.876738)
		(width 0.4572)
		(layer "F.Cu")
		(net "P3V3_AUX")
	)
	(segment
		(start 270.560292 -117.7544)
		(end 269.670022 -117.7544)
		(width 0.4064)
		(layer "F.Cu")
		(net "P3V3_AUX")
	)
	(segment
		(start 330.774802 -48.753014)
		(end 331.750162 -48.753014)
		(width 0.254)
		(layer "F.Cu")
		(net "P3V3_AUX")
	)
	(segment
		(start 298.34713 -197.58914)
		(end 297.944794 -197.991476)
		(width 0.4572)
		(layer "F.Cu")
		(net "P3V3_AUX")
	)
	(segment
		(start 283.223716 -168.397174)
		(end 283.223716 -167.742108)
		(width 0.4572)
		(layer "F.Cu")
		(net "P3V3_AUX")
	)
	(segment
		(start 215.464136 -184.702958)
		(end 215.464136 -182.013606)
		(width 0.3556)
		(layer "F.Cu")
		(net "P3V3_AUX")
	)
	(segment
		(start 336.931 -236.45495)
		(end 336.296 -236.45495)
		(width 0.4572)
		(layer "F.Cu")
		(net "P3V3_AUX")
	)
	(segment
		(start 167.16248 -22.555454)
		(end 167.818562 -22.555454)
		(width 0.4572)
		(layer "F.Cu")
		(net "P3V3_AUX")
	)
	(segment
		(start 47.550324 -48.753014)
		(end 46.574964 -48.753014)
		(width 0.254)
		(layer "F.Cu")
		(net "P3V3_AUX")
	)
	(segment
		(start 100.7745 -240.928144)
		(end 100.7745 -241.398044)
		(width 0.254)
		(layer "F.Cu")
		(net "P3V3_AUX")
	)
	(segment
		(start 309.710074 -47.92091)
		(end 309.508144 -47.71898)
		(width 0.254)
		(layer "F.Cu")
		(net "P3V3_AUX")
	)
	(segment
		(start 242.000786 -201.29627)
		(end 242.000786 -201.07783)
		(width 0.4572)
		(layer "F.Cu")
		(net "P3V3_AUX")
	)
	(segment
		(start 94.892368 -201.509376)
		(end 94.344744 -200.961752)
		(width 0.4572)
		(layer "F.Cu")
		(net "P3V3_AUX")
	)
	(segment
		(start 197.702932 -414.052004)
		(end 197.702932 -413.364172)
		(width 0.4572)
		(layer "F.Cu")
		(net "P3V3_AUX")
	)
	(segment
		(start 213.42985 -211.049362)
		(end 213.59622 -211.215732)
		(width 0.3556)
		(layer "F.Cu")
		(net "P3V3_AUX")
	)
	(segment
		(start 364.659672 -147.042378)
		(end 365.079788 -147.042378)
		(width 0.254)
		(layer "F.Cu")
		(net "P3V3_AUX")
	)
	(segment
		(start 199.682354 -36.286948)
		(end 199.047354 -36.286948)
		(width 0.4572)
		(layer "F.Cu")
		(net "P3V3_AUX")
	)
	(segment
		(start 339.749384 -241.712242)
		(end 337.99907 -241.712242)
		(width 0.3556)
		(layer "F.Cu")
		(net "P3V3_AUX")
	)
	(segment
		(start 268.804644 -142.88897)
		(end 268.804644 -141.87297)
		(width 0.4064)
		(layer "F.Cu")
		(net "P3V3_AUX")
	)
	(segment
		(start 425.860464 -21.603208)
		(end 425.36237 -22.101302)
		(width 0.4572)
		(layer "F.Cu")
		(net "P3V3_AUX")
	)
	(segment
		(start 378.880624 -241.811048)
		(end 377.75896 -241.811048)
		(width 0.2794)
		(layer "F.Cu")
		(net "P3V3_AUX")
	)
	(segment
		(start 363.07395 -209.931)
		(end 362.458 -209.931)
		(width 0.4572)
		(layer "F.Cu")
		(net "P3V3_AUX")
	)
	(segment
		(start 385.48564 -114.86515)
		(end 386.208524 -114.86515)
		(width 0.4064)
		(layer "F.Cu")
		(net "P3V3_AUX")
	)
	(segment
		(start 309.760366 -20.789392)
		(end 309.760366 -21.603208)
		(width 0.4572)
		(layer "F.Cu")
		(net "P3V3_AUX")
	)
	(segment
		(start 335.64195 -154.686)
		(end 335.026 -154.686)
		(width 0.4572)
		(layer "F.Cu")
		(net "P3V3_AUX")
	)
	(segment
		(start 130.090164 -258.131564)
		(end 130.699764 -258.131564)
		(width 0.381)
		(layer "F.Cu")
		(net "P3V3_AUX")
	)
	(segment
		(start 384.904742 -141.87297)
		(end 384.904742 -140.85697)
		(width 0.4064)
		(layer "F.Cu")
		(net "P3V3_AUX")
	)
	(segment
		(start 369.895628 -81.498694)
		(end 370.60124 -81.498694)
		(width 0.4572)
		(layer "F.Cu")
		(net "P3V3_AUX")
	)
	(segment
		(start 349.000064 -172.965872)
		(end 350.003618 -172.965872)
		(width 0.4572)
		(layer "F.Cu")
		(net "P3V3_AUX")
	)
	(segment
		(start 252.439678 -153.1112)
		(end 252.439678 -153.782522)
		(width 0.4064)
		(layer "F.Cu")
		(net "P3V3_AUX")
	)
	(segment
		(start 265.46683 -206.314548)
		(end 263.994646 -206.314548)
		(width 0.4572)
		(layer "F.Cu")
		(net "P3V3_AUX")
	)
	(segment
		(start 210.53552 -220.291406)
		(end 210.171284 -220.291406)
		(width 0.4572)
		(layer "F.Cu")
		(net "P3V3_AUX")
	)
	(segment
		(start 99.903534 -242.26901)
		(end 99.903534 -242.487196)
		(width 0.254)
		(layer "F.Cu")
		(net "P3V3_AUX")
	)
	(segment
		(start 277.089616 -405.474424)
		(end 277.089616 -406.157938)
		(width 0.4572)
		(layer "F.Cu")
		(net "P3V3_AUX")
	)
	(segment
		(start 328.962004 -205.20152)
		(end 328.839068 -205.078584)
		(width 0.4572)
		(layer "F.Cu")
		(net "P3V3_AUX")
	)
	(segment
		(start 335.508092 -47.71898)
		(end 335.508092 -47.403766)
		(width 0.254)
		(layer "F.Cu")
		(net "P3V3_AUX")
	)
	(segment
		(start 337.99907 -241.712242)
		(end 337.693 -241.406172)
		(width 0.3556)
		(layer "F.Cu")
		(net "P3V3_AUX")
	)
	(segment
		(start 414.676082 -199.981058)
		(end 414.001458 -199.981058)
		(width 0.4572)
		(layer "F.Cu")
		(net "P3V3_AUX")
	)
	(segment
		(start 103.51008 -47.92091)
		(end 103.30815 -47.71898)
		(width 0.254)
		(layer "F.Cu")
		(net "P3V3_AUX")
	)
	(segment
		(start 78.89367 -83.532218)
		(end 77.353922 -83.532218)
		(width 0.4064)
		(layer "F.Cu")
		(net "P3V3_AUX")
	)
	(segment
		(start 246.096028 -238.05896)
		(end 246.096028 -237.205012)
		(width 0.4572)
		(layer "F.Cu")
		(net "P3V3_AUX")
	)
	(segment
		(start 236.404658 -77.53477)
		(end 236.404658 -76.853034)
		(width 0.4572)
		(layer "F.Cu")
		(net "P3V3_AUX")
	)
	(segment
		(start 110.152942 -116.630704)
		(end 110.152942 -117.248178)
		(width 0.4572)
		(layer "F.Cu")
		(net "P3V3_AUX")
	)
	(segment
		(start 323.88937 -291.297868)
		(end 323.88937 -291.694616)
		(width 0.4572)
		(layer "F.Cu")
		(net "P3V3_AUX")
	)
	(segment
		(start 224.422208 -84.675472)
		(end 225.032062 -84.675472)
		(width 0.4572)
		(layer "F.Cu")
		(net "P3V3_AUX")
	)
	(segment
		(start 95.505778 -241.779552)
		(end 95.96501 -242.238784)
		(width 0.254)
		(layer "F.Cu")
		(net "P3V3_AUX")
	)
	(segment
		(start 249.333512 -210.606386)
		(end 248.717562 -210.606386)
		(width 0.4572)
		(layer "F.Cu")
		(net "P3V3_AUX")
	)
	(segment
		(start 120.73509 -91.462606)
		(end 120.119902 -91.462606)
		(width 0.4572)
		(layer "F.Cu")
		(net "P3V3_AUX")
	)
	(segment
		(start 207.111346 -226.928426)
		(end 207.111346 -227.235258)
		(width 0.4572)
		(layer "F.Cu")
		(net "P3V3_AUX")
	)
	(segment
		(start 278.443182 -401.937982)
		(end 278.451056 -401.930108)
		(width 0.4572)
		(layer "F.Cu")
		(net "P3V3_AUX")
	)
	(segment
		(start 283.461206 -168.634664)
		(end 283.223716 -168.397174)
		(width 0.4572)
		(layer "F.Cu")
		(net "P3V3_AUX")
	)
	(segment
		(start 304.055018 -35.876738)
		(end 303.299114 -35.876738)
		(width 0.4572)
		(layer "F.Cu")
		(net "P3V3_AUX")
	)
	(segment
		(start 362.296456 -386.172456)
		(end 361.67822 -386.172456)
		(width 0.4572)
		(layer "F.Cu")
		(net "P3V3_AUX")
	)
	(segment
		(start 80.21955 -7.469632)
		(end 79.637636 -7.469632)
		(width 0.4572)
		(layer "F.Cu")
		(net "P3V3_AUX")
	)
	(segment
		(start 275.963126 -402.73224)
		(end 275.963126 -403.46249)
		(width 0.4572)
		(layer "F.Cu")
		(net "P3V3_AUX")
	)
	(segment
		(start 305.37277 -47.193962)
		(end 304.774854 -47.791878)
		(width 0.254)
		(layer "F.Cu")
		(net "P3V3_AUX")
	)
	(segment
		(start 79.313024 -7.794244)
		(end 79.313024 -8.891778)
		(width 0.4572)
		(layer "F.Cu")
		(net "P3V3_AUX")
	)
	(segment
		(start 447.147188 -416.021266)
		(end 447.147188 -416.636962)
		(width 0.4572)
		(layer "F.Cu")
		(net "P3V3_AUX")
	)
	(segment
		(start 92.062046 -101.882448)
		(end 92.062046 -101.609398)
		(width 0.254)
		(layer "F.Cu")
		(net "P3V3_AUX")
	)
	(segment
		(start 167.660574 -20.789392)
		(end 167.660574 -21.603208)
		(width 0.4572)
		(layer "F.Cu")
		(net "P3V3_AUX")
	)
	(segment
		(start 414.371282 -203.562458)
		(end 413.518858 -203.562458)
		(width 0.4572)
		(layer "F.Cu")
		(net "P3V3_AUX")
	)
	(segment
		(start 163.546028 -47.193962)
		(end 163.272978 -47.193962)
		(width 0.254)
		(layer "F.Cu")
		(net "P3V3_AUX")
	)
	(segment
		(start 429.23968 -137.645648)
		(end 429.23968 -136.98601)
		(width 0.4064)
		(layer "F.Cu")
		(net "P3V3_AUX")
	)
	(segment
		(start 208.286858 -221.19082)
		(end 208.259172 -221.218506)
		(width 0.4572)
		(layer "F.Cu")
		(net "P3V3_AUX")
	)
	(segment
		(start 84.30895 -26.03373)
		(end 83.64982 -26.03373)
		(width 0.4572)
		(layer "F.Cu")
		(net "P3V3_AUX")
	)
	(segment
		(start 147.047458 -36.286948)
		(end 146.391884 -36.286948)
		(width 0.4572)
		(layer "F.Cu")
		(net "P3V3_AUX")
	)
	(segment
		(start 195.226178 -40.82161)
		(end 195.076064 -40.971724)
		(width 0.4572)
		(layer "F.Cu")
		(net "P3V3_AUX")
	)
	(segment
		(start 26.667968 -52.035456)
		(end 27.323288 -52.035456)
		(width 0.254)
		(layer "F.Cu")
		(net "P3V3_AUX")
	)
	(segment
		(start 338.898484 -5.747258)
		(end 339.508084 -5.747258)
		(width 0.4572)
		(layer "F.Cu")
		(net "P3V3_AUX")
	)
	(segment
		(start 290.256214 -61.487812)
		(end 290.886388 -61.487812)
		(width 0.4572)
		(layer "F.Cu")
		(net "P3V3_AUX")
	)
	(segment
		(start 54.454806 -23.361396)
		(end 54.454806 -23.970996)
		(width 0.4572)
		(layer "F.Cu")
		(net "P3V3_AUX")
	)
	(segment
		(start 254.781304 -338.813394)
		(end 253.038102 -337.070192)
		(width 0.4572)
		(layer "F.Cu")
		(net "P3V3_AUX")
	)
	(segment
		(start 357.768144 -390.28878)
		(end 357.768144 -382.789938)
		(width 0.4572)
		(layer "F.Cu")
		(net "P3V3_AUX")
	)
	(segment
		(start 440.362086 -101.882448)
		(end 440.362086 -101.609398)
		(width 0.254)
		(layer "F.Cu")
		(net "P3V3_AUX")
	)
	(segment
		(start 399.561304 -169.23385)
		(end 399.443448 -169.351706)
		(width 0.4572)
		(layer "F.Cu")
		(net "P3V3_AUX")
	)
	(segment
		(start 264.508996 -26.03373)
		(end 263.849866 -26.03373)
		(width 0.4572)
		(layer "F.Cu")
		(net "P3V3_AUX")
	)
	(segment
		(start 283.461206 -169.23385)
		(end 283.461206 -168.634664)
		(width 0.4572)
		(layer "F.Cu")
		(net "P3V3_AUX")
	)
	(segment
		(start 217.583512 -235.36656)
		(end 217.583512 -233.182668)
		(width 0.4572)
		(layer "F.Cu")
		(net "P3V3_AUX")
	)
	(segment
		(start 396.609316 -82.642202)
		(end 397.224758 -82.642202)
		(width 0.4572)
		(layer "F.Cu")
		(net "P3V3_AUX")
	)
	(segment
		(start 373.117618 -192.142872)
		(end 372.114064 -192.142872)
		(width 0.4572)
		(layer "F.Cu")
		(net "P3V3_AUX")
	)
	(segment
		(start 180.281326 -177.711862)
		(end 181.026816 -176.966372)
		(width 0.3556)
		(layer "F.Cu")
		(net "P3V3_AUX")
	)
	(segment
		(start 7.213346 -139.376404)
		(end 6.558026 -139.376404)
		(width 0.4064)
		(layer "F.Cu")
		(net "P3V3_AUX")
	)
	(segment
		(start 20.239736 -153.1112)
		(end 20.239736 -153.782522)
		(width 0.4064)
		(layer "F.Cu")
		(net "P3V3_AUX")
	)
	(segment
		(start 396.609316 -87.214202)
		(end 397.224758 -87.214202)
		(width 0.4572)
		(layer "F.Cu")
		(net "P3V3_AUX")
	)
	(segment
		(start 241.942112 -199.736964)
		(end 242.207034 -199.736964)
		(width 0.4572)
		(layer "F.Cu")
		(net "P3V3_AUX")
	)
	(segment
		(start 375.912634 -88.8238)
		(end 375.297446 -88.8238)
		(width 0.4572)
		(layer "F.Cu")
		(net "P3V3_AUX")
	)
	(segment
		(start 223.527112 -192.611756)
		(end 223.527112 -193.378328)
		(width 0.3556)
		(layer "F.Cu")
		(net "P3V3_AUX")
	)
	(segment
		(start 434.797708 -96.411542)
		(end 434.456078 -96.753172)
		(width 0.4572)
		(layer "F.Cu")
		(net "P3V3_AUX")
	)
	(segment
		(start 210.456272 -255.799082)
		(end 213.946486 -252.308868)
		(width 0.4572)
		(layer "F.Cu")
		(net "P3V3_AUX")
	)
	(segment
		(start 312.654696 -23.361396)
		(end 312.654696 -23.970996)
		(width 0.4572)
		(layer "F.Cu")
		(net "P3V3_AUX")
	)
	(segment
		(start 97.648268 -392.0998)
		(end 97.282 -392.0998)
		(width 0.4572)
		(layer "F.Cu")
		(net "P3V3_AUX")
	)
	(segment
		(start 139.385294 -88.956642)
		(end 140.090144 -88.956642)
		(width 0.381)
		(layer "F.Cu")
		(net "P3V3_AUX")
	)
	(segment
		(start 89.188544 -94.572836)
		(end 88.456262 -94.572836)
		(width 0.4572)
		(layer "F.Cu")
		(net "P3V3_AUX")
	)
	(segment
		(start 399.860516 -20.789392)
		(end 399.860516 -21.603208)
		(width 0.4572)
		(layer "F.Cu")
		(net "P3V3_AUX")
	)
	(segment
		(start 378.82195 -213.97595)
		(end 378.079 -213.97595)
		(width 0.4572)
		(layer "F.Cu")
		(net "P3V3_AUX")
	)
	(segment
		(start 339.773514 -241.736372)
		(end 339.749384 -241.712242)
		(width 0.3556)
		(layer "F.Cu")
		(net "P3V3_AUX")
	)
	(segment
		(start 94.705678 -244.808248)
		(end 94.034356 -244.808248)
		(width 0.254)
		(layer "F.Cu")
		(net "P3V3_AUX")
	)
	(segment
		(start 198.337424 -36.232592)
		(end 197.49516 -36.232592)
		(width 0.4572)
		(layer "F.Cu")
		(net "P3V3_AUX")
	)
	(segment
		(start 257.508248 -47.71898)
		(end 257.508248 -47.403766)
		(width 0.254)
		(layer "F.Cu")
		(net "P3V3_AUX")
	)
	(segment
		(start 230.834946 -278.551386)
		(end 231.444546 -278.551386)
		(width 0.4572)
		(layer "F.Cu")
		(net "P3V3_AUX")
	)
	(segment
		(start 363.07395 -213.995)
		(end 362.458 -213.995)
		(width 0.4572)
		(layer "F.Cu")
		(net "P3V3_AUX")
	)
	(segment
		(start 263.10971 -344.772488)
		(end 261.596378 -344.772488)
		(width 0.4572)
		(layer "F.Cu")
		(net "P3V3_AUX")
	)
	(segment
		(start 364.659672 -148.017738)
		(end 364.659672 -147.042378)
		(width 0.4064)
		(layer "F.Cu")
		(net "P3V3_AUX")
	)
	(segment
		(start 224.456244 -185.363612)
		(end 224.456244 -184.703212)
		(width 0.4572)
		(layer "F.Cu")
		(net "P3V3_AUX")
	)
	(segment
		(start 239.906556 -80.941418)
		(end 240.163858 -81.19872)
		(width 0.4572)
		(layer "F.Cu")
		(net "P3V3_AUX")
	)
	(segment
		(start 339.344 -236.45495)
		(end 338.68995 -236.45495)
		(width 0.4572)
		(layer "F.Cu")
		(net "P3V3_AUX")
	)
	(segment
		(start 133.9088 -98.96729)
		(end 134.55142 -99.60991)
		(width 0.4572)
		(layer "F.Cu")
		(net "P3V3_AUX")
	)
	(segment
		(start 17.185386 -273.216624)
		(end 17.794986 -273.216624)
		(width 0.4572)
		(layer "F.Cu")
		(net "P3V3_AUX")
	)
	(segment
		(start 434.456078 -96.753172)
		(end 434.456078 -97.33153)
		(width 0.4572)
		(layer "F.Cu")
		(net "P3V3_AUX")
	)
	(segment
		(start 283.82595 -83.566)
		(end 283.21 -83.566)
		(width 0.4572)
		(layer "F.Cu")
		(net "P3V3_AUX")
	)
	(segment
		(start 335.64195 -161.798)
		(end 335.026 -161.798)
		(width 0.4572)
		(layer "F.Cu")
		(net "P3V3_AUX")
	)
	(segment
		(start 324.316852 -292.122098)
		(end 325.20382 -292.122098)
		(width 0.4572)
		(layer "F.Cu")
		(net "P3V3_AUX")
	)
	(segment
		(start 277.717504 -394.762482)
		(end 277.082504 -394.762482)
		(width 0.4572)
		(layer "F.Cu")
		(net "P3V3_AUX")
	)
	(segment
		(start 432.60899 -26.03373)
		(end 431.94986 -26.03373)
		(width 0.4572)
		(layer "F.Cu")
		(net "P3V3_AUX")
	)
	(segment
		(start 196.702426 -89.78138)
		(end 196.702426 -89.1159)
		(width 0.4572)
		(layer "F.Cu")
		(net "P3V3_AUX")
	)
	(segment
		(start 83.582256 -36.286948)
		(end 82.947256 -36.286948)
		(width 0.4572)
		(layer "F.Cu")
		(net "P3V3_AUX")
	)
	(segment
		(start 295.270682 -137.848848)
		(end 294.52189 -137.848848)
		(width 0.4064)
		(layer "F.Cu")
		(net "P3V3_AUX")
	)
	(segment
		(start 167.243252 -169.351706)
		(end 167.243252 -170.77944)
		(width 0.4572)
		(layer "F.Cu")
		(net "P3V3_AUX")
	)
	(segment
		(start 335.604612 -197.344284)
		(end 336.383884 -197.344284)
		(width 0.3048)
		(layer "F.Cu")
		(net "P3V3_AUX")
	)
	(segment
		(start 128.058164 -253.178564)
		(end 128.667764 -253.178564)
		(width 0.381)
		(layer "F.Cu")
		(net "P3V3_AUX")
	)
	(segment
		(start 212.422994 -223.128332)
		(end 212.695282 -223.40062)
		(width 0.4572)
		(layer "F.Cu")
		(net "P3V3_AUX")
	)
	(segment
		(start 298.34713 -196.022976)
		(end 298.34713 -196.706236)
		(width 0.4572)
		(layer "F.Cu")
		(net "P3V3_AUX")
	)
	(segment
		(start 211.512404 -214.281766)
		(end 211.346034 -214.448136)
		(width 0.254)
		(layer "F.Cu")
		(net "P3V3_AUX")
	)
	(segment
		(start 16.779748 -147.042378)
		(end 17.650714 -147.913344)
		(width 0.254)
		(layer "F.Cu")
		(net "P3V3_AUX")
	)
	(segment
		(start 127.185166 -118.743476)
		(end 127.185166 -119.35587)
		(width 0.4572)
		(layer "F.Cu")
		(net "P3V3_AUX")
	)
	(segment
		(start 246.096028 -237.205012)
		(end 245.904258 -237.013242)
		(width 0.4572)
		(layer "F.Cu")
		(net "P3V3_AUX")
	)
	(segment
		(start 188.605668 -80.362806)
		(end 188.226954 -80.362806)
		(width 0.4572)
		(layer "F.Cu")
		(net "P3V3_AUX")
	)
	(segment
		(start 120.73509 -92.605606)
		(end 120.73509 -91.462606)
		(width 0.4572)
		(layer "F.Cu")
		(net "P3V3_AUX")
	)
	(segment
		(start 450.195188 -416.021266)
		(end 450.195188 -416.636962)
		(width 0.4572)
		(layer "F.Cu")
		(net "P3V3_AUX")
	)
	(segment
		(start 226.785424 -280.10104)
		(end 226.175824 -280.10104)
		(width 0.4572)
		(layer "F.Cu")
		(net "P3V3_AUX")
	)
	(segment
		(start 103.843582 -47.92091)
		(end 103.51008 -47.92091)
		(width 0.254)
		(layer "F.Cu")
		(net "P3V3_AUX")
	)
	(segment
		(start 359.192576 -252.045978)
		(end 359.820972 -252.045978)
		(width 0.4572)
		(layer "F.Cu")
		(net "P3V3_AUX")
	)
	(segment
		(start 104.643682 -44.87291)
		(end 105.315004 -44.87291)
		(width 0.254)
		(layer "F.Cu")
		(net "P3V3_AUX")
	)
	(segment
		(start 357.768144 -391.047478)
		(end 357.768144 -390.28878)
		(width 0.4572)
		(layer "F.Cu")
		(net "P3V3_AUX")
	)
	(segment
		(start 139.385294 -94.671642)
		(end 140.090144 -94.671642)
		(width 0.4572)
		(layer "F.Cu")
		(net "P3V3_AUX")
	)
	(segment
		(start 277.281894 -387.137656)
		(end 276.667468 -387.752082)
		(width 0.4318)
		(layer "F.Cu")
		(net "P3V3_AUX")
	)
	(segment
		(start 239.84966 -159.844994)
		(end 239.232186 -159.844994)
		(width 0.4572)
		(layer "F.Cu")
		(net "P3V3_AUX")
	)
	(segment
		(start 350.647 -173.08195)
		(end 351.38995 -173.08195)
		(width 0.4572)
		(layer "F.Cu")
		(net "P3V3_AUX")
	)
	(segment
		(start 451.623938 -231.88168)
		(end 451.623938 -232.69448)
		(width 0.2032)
		(layer "F.Cu")
		(net "P3V3_AUX")
	)
	(segment
		(start 451.362318 -22.555454)
		(end 452.0184 -22.555454)
		(width 0.4572)
		(layer "F.Cu")
		(net "P3V3_AUX")
	)
	(segment
		(start 103.458264 -188.573664)
		(end 103.1748 -188.2902)
		(width 0.2794)
		(layer "F.Cu")
		(net "P3V3_AUX")
	)
	(segment
		(start 310.843676 -44.87291)
		(end 311.514998 -44.87291)
		(width 0.254)
		(layer "F.Cu")
		(net "P3V3_AUX")
	)
	(segment
		(start 245.61546 -237.013242)
		(end 245.553484 -237.075218)
		(width 0.4572)
		(layer "F.Cu")
		(net "P3V3_AUX")
	)
	(segment
		(start 37.908484 -114.86515)
		(end 38.278562 -115.235228)
		(width 0.4064)
		(layer "F.Cu")
		(net "P3V3_AUX")
	)
	(segment
		(start 420.874952 -47.791878)
		(end 420.874952 -48.753014)
		(width 0.254)
		(layer "F.Cu")
		(net "P3V3_AUX")
	)
	(segment
		(start 218.88958 -87.123524)
		(end 218.88958 -86.576916)
		(width 0.4572)
		(layer "F.Cu")
		(net "P3V3_AUX")
	)
	(segment
		(start 225.256344 -181.85638)
		(end 225.256344 -182.51678)
		(width 0.4572)
		(layer "F.Cu")
		(net "P3V3_AUX")
	)
	(segment
		(start 249.850656 -147.913344)
		(end 250.118626 -147.913344)
		(width 0.254)
		(layer "F.Cu")
		(net "P3V3_AUX")
	)
	(segment
		(start 203.106274 -258.65074)
		(end 205.957932 -255.799082)
		(width 0.4572)
		(layer "F.Cu")
		(net "P3V3_AUX")
	)
	(segment
		(start 181.862476 -197.272402)
		(end 182.148734 -197.55866)
		(width 0.4572)
		(layer "F.Cu")
		(net "P3V3_AUX")
	)
	(segment
		(start 269.385542 -114.86515)
		(end 270.108426 -114.86515)
		(width 0.4064)
		(layer "F.Cu")
		(net "P3V3_AUX")
	)
	(segment
		(start 245.280434 -251.159772)
		(end 245.280434 -251.857256)
		(width 0.4572)
		(layer "F.Cu")
		(net "P3V3_AUX")
	)
	(segment
		(start 257.76047 -20.789392)
		(end 257.76047 -21.603208)
		(width 0.4572)
		(layer "F.Cu")
		(net "P3V3_AUX")
	)
	(segment
		(start 1.650746 -34.036254)
		(end 2.14884 -33.53816)
		(width 0.4572)
		(layer "F.Cu")
		(net "P3V3_AUX")
	)
	(segment
		(start 416.160458 -184.941718)
		(end 415.361882 -184.941718)
		(width 0.4572)
		(layer "F.Cu")
		(net "P3V3_AUX")
	)
	(segment
		(start 128.058164 -256.226564)
		(end 128.667764 -256.226564)
		(width 0.381)
		(layer "F.Cu")
		(net "P3V3_AUX")
	)
	(segment
		(start 197.66407 -158.219648)
		(end 197.039484 -158.219648)
		(width 0.4064)
		(layer "F.Cu")
		(net "P3V3_AUX")
	)
	(segment
		(start 357.643176 -396.80769)
		(end 357.643176 -396.063724)
		(width 0.4572)
		(layer "F.Cu")
		(net "P3V3_AUX")
	)
	(segment
		(start 99.79914 -240.928144)
		(end 100.7745 -240.928144)
		(width 0.254)
		(layer "F.Cu")
		(net "P3V3_AUX")
	)
	(segment
		(start 172.379894 -139.6492)
		(end 173.046644 -139.6492)
		(width 0.4572)
		(layer "F.Cu")
		(net "P3V3_AUX")
	)
	(segment
		(start 259.092446 -338.813394)
		(end 254.781304 -338.813394)
		(width 0.4572)
		(layer "F.Cu")
		(net "P3V3_AUX")
	)
	(segment
		(start 243.296948 -278.541988)
		(end 243.023898 -278.541988)
		(width 0.254)
		(layer "F.Cu")
		(net "P3V3_AUX")
	)
	(segment
		(start 95.177356 -201.509376)
		(end 94.892368 -201.509376)
		(width 0.4572)
		(layer "F.Cu")
		(net "P3V3_AUX")
	)
	(segment
		(start 357.44277 -398.580102)
		(end 357.44277 -399.219928)
		(width 0.4572)
		(layer "F.Cu")
		(net "P3V3_AUX")
	)
	(segment
		(start 51.843686 -47.92091)
		(end 51.510184 -47.92091)
		(width 0.254)
		(layer "F.Cu")
		(net "P3V3_AUX")
	)
	(segment
		(start 115.38966 -158.977076)
		(end 119.42318 -158.977076)
		(width 0.254)
		(layer "F.Cu")
		(net "P3V3_AUX")
	)
	(segment
		(start 329.692 -233.66095)
		(end 329.692 -232.918)
		(width 0.4572)
		(layer "F.Cu")
		(net "P3V3_AUX")
	)
	(segment
		(start 331.192378 -239.437672)
		(end 331.192378 -240.848896)
		(width 0.3556)
		(layer "F.Cu")
		(net "P3V3_AUX")
	)
	(segment
		(start 369.895628 -89.499694)
		(end 370.60124 -89.499694)
		(width 0.4572)
		(layer "F.Cu")
		(net "P3V3_AUX")
	)
	(segment
		(start 390.330436 -236.311186)
		(end 388.50697 -236.311186)
		(width 0.2794)
		(layer "F.Cu")
		(net "P3V3_AUX")
	)
	(segment
		(start 336.91322 -197.87362)
		(end 337.206336 -197.87362)
		(width 0.3048)
		(layer "F.Cu")
		(net "P3V3_AUX")
	)
	(segment
		(start 323.88937 -291.694616)
		(end 324.316852 -292.122098)
		(width 0.4572)
		(layer "F.Cu")
		(net "P3V3_AUX")
	)
	(segment
		(start 120.708928 -89.53373)
		(end 120.042432 -89.53373)
		(width 0.4572)
		(layer "F.Cu")
		(net "P3V3_AUX")
	)
	(segment
		(start 101.971094 -397.912336)
		(end 101.971094 -398.66824)
		(width 0.4572)
		(layer "F.Cu")
		(net "P3V3_AUX")
	)
	(segment
		(start 274.872704 -406.924256)
		(end 274.872704 -406.551892)
		(width 0.4572)
		(layer "F.Cu")
		(net "P3V3_AUX")
	)
	(segment
		(start 425.653962 -83.532218)
		(end 427.19371 -83.532218)
		(width 0.4064)
		(layer "F.Cu")
		(net "P3V3_AUX")
	)
	(segment
		(start 134.55142 -99.60991)
		(end 134.581392 -99.60991)
		(width 0.4572)
		(layer "F.Cu")
		(net "P3V3_AUX")
	)
	(segment
		(start 201.176636 -91.968574)
		(end 203.49845 -91.968574)
		(width 0.4572)
		(layer "F.Cu")
		(net "P3V3_AUX")
	)
	(segment
		(start 425.860464 -20.789392)
		(end 425.860464 -21.603208)
		(width 0.4572)
		(layer "F.Cu")
		(net "P3V3_AUX")
	)
	(segment
		(start 220.812868 -104.512618)
		(end 219.914216 -104.512618)
		(width 0.254)
		(layer "F.Cu")
		(net "P3V3_AUX")
	)
	(segment
		(start 98.57486 -47.791878)
		(end 98.57486 -48.753014)
		(width 0.254)
		(layer "F.Cu")
		(net "P3V3_AUX")
	)
	(segment
		(start 353.247452 -36.286948)
		(end 352.591878 -36.286948)
		(width 0.4572)
		(layer "F.Cu")
		(net "P3V3_AUX")
	)
	(segment
		(start 222.23095 -203.790296)
		(end 222.23095 -203.389484)
		(width 0.4572)
		(layer "F.Cu")
		(net "P3V3_AUX")
	)
	(segment
		(start 79.12608 -40.82161)
		(end 78.975966 -40.971724)
		(width 0.4572)
		(layer "F.Cu")
		(net "P3V3_AUX")
	)
	(segment
		(start 15.775686 -276.264624)
		(end 16.385286 -276.264624)
		(width 0.4572)
		(layer "F.Cu")
		(net "P3V3_AUX")
	)
	(segment
		(start 179.698142 -115.90909)
		(end 179.377594 -116.229638)
		(width 0.381)
		(layer "F.Cu")
		(net "P3V3_AUX")
	)
	(segment
		(start 368.809778 -241.54892)
		(end 369.961922 -241.54892)
		(width 0.4572)
		(layer "F.Cu")
		(net "P3V3_AUX")
	)
	(segment
		(start 364.540038 -261.206488)
		(end 365.24692 -261.206488)
		(width 0.4572)
		(layer "F.Cu")
		(net "P3V3_AUX")
	)
	(segment
		(start 354.356416 -61.487812)
		(end 354.98659 -61.487812)
		(width 0.4572)
		(layer "F.Cu")
		(net "P3V3_AUX")
	)
	(segment
		(start 224.695512 -231.816656)
		(end 224.695512 -232.471468)
		(width 0.4572)
		(layer "F.Cu")
		(net "P3V3_AUX")
	)
	(segment
		(start 221.415102 -44.87291)
		(end 220.74378 -44.87291)
		(width 0.254)
		(layer "F.Cu")
		(net "P3V3_AUX")
	)
	(segment
		(start 213.394544 -211.049362)
		(end 213.42985 -211.049362)
		(width 0.3556)
		(layer "F.Cu")
		(net "P3V3_AUX")
	)
	(segment
		(start 161.955226 -35.876738)
		(end 161.199322 -35.876738)
		(width 0.4572)
		(layer "F.Cu")
		(net "P3V3_AUX")
	)
	(segment
		(start 254.471678 -153.1112)
		(end 254.471678 -153.782522)
		(width 0.4064)
		(layer "F.Cu")
		(net "P3V3_AUX")
	)
	(segment
		(start 186.13755 -408.0764)
		(end 186.13755 -407.4414)
		(width 0.4572)
		(layer "F.Cu")
		(net "P3V3_AUX")
	)
	(segment
		(start 179.170584 -137.848848)
		(end 178.421792 -137.848848)
		(width 0.4064)
		(layer "F.Cu")
		(net "P3V3_AUX")
	)
	(segment
		(start 279.774396 -415.29)
		(end 279.774396 -416.00628)
		(width 0.4572)
		(layer "F.Cu")
		(net "P3V3_AUX")
	)
	(segment
		(start 434.456078 -97.33153)
		(end 435.667912 -98.543364)
		(width 0.4572)
		(layer "F.Cu")
		(net "P3V3_AUX")
	)
	(segment
		(start 196.554852 -23.361396)
		(end 196.554852 -23.970996)
		(width 0.4572)
		(layer "F.Cu")
		(net "P3V3_AUX")
	)
	(segment
		(start 451.60819 -47.71898)
		(end 451.60819 -47.403766)
		(width 0.254)
		(layer "F.Cu")
		(net "P3V3_AUX")
	)
	(segment
		(start 284.867858 -52.035456)
		(end 285.523178 -52.035456)
		(width 0.254)
		(layer "F.Cu")
		(net "P3V3_AUX")
	)
	(segment
		(start 337.037934 -9.139682)
		(end 338.092542 -9.139682)
		(width 0.4572)
		(layer "F.Cu")
		(net "P3V3_AUX")
	)
	(segment
		(start 205.422246 -209.866992)
		(end 206.15275 -210.597496)
		(width 0.4572)
		(layer "F.Cu")
		(net "P3V3_AUX")
	)
	(segment
		(start 311.093612 -83.532218)
		(end 311.099454 -83.526376)
		(width 0.4064)
		(layer "F.Cu")
		(net "P3V3_AUX")
	)
	(segment
		(start 362.462064 -198.585836)
		(end 362.458 -198.585836)
		(width 0.4572)
		(layer "F.Cu")
		(net "P3V3_AUX")
	)
	(segment
		(start 411.57779 -116.229638)
		(end 411.885384 -115.922044)
		(width 0.4572)
		(layer "F.Cu")
		(net "P3V3_AUX")
	)
	(segment
		(start 93.621098 -102.480364)
		(end 92.659962 -102.480364)
		(width 0.254)
		(layer "F.Cu")
		(net "P3V3_AUX")
	)
	(segment
		(start 51.308254 -47.71898)
		(end 51.308254 -47.403766)
		(width 0.254)
		(layer "F.Cu")
		(net "P3V3_AUX")
	)
	(segment
		(start 237.782354 -36.286948)
		(end 237.147354 -36.286948)
		(width 0.4572)
		(layer "F.Cu")
		(net "P3V3_AUX")
	)
	(segment
		(start 356.25405 -178.562)
		(end 356.87 -178.562)
		(width 0.4572)
		(layer "F.Cu")
		(net "P3V3_AUX")
	)
	(segment
		(start 220.972888 -233.182668)
		(end 221.647512 -233.182668)
		(width 0.4572)
		(layer "F.Cu")
		(net "P3V3_AUX")
	)
	(segment
		(start 311.326022 -40.82161)
		(end 311.175908 -40.971724)
		(width 0.4572)
		(layer "F.Cu")
		(net "P3V3_AUX")
	)
	(segment
		(start 231.352344 -182.61838)
		(end 231.352344 -183.27878)
		(width 0.4572)
		(layer "F.Cu")
		(net "P3V3_AUX")
	)
	(segment
		(start 313.139582 -137.645648)
		(end 313.139582 -136.98601)
		(width 0.4064)
		(layer "F.Cu")
		(net "P3V3_AUX")
	)
	(segment
		(start 1.650746 -34.490406)
		(end 1.650746 -34.036254)
		(width 0.4572)
		(layer "F.Cu")
		(net "P3V3_AUX")
	)
	(segment
		(start 352.720148 -147.654518)
		(end 353.336098 -147.654518)
		(width 0.4572)
		(layer "F.Cu")
		(net "P3V3_AUX")
	)
	(segment
		(start 219.162376 -22.101302)
		(end 219.162376 -22.555454)
		(width 0.4572)
		(layer "F.Cu")
		(net "P3V3_AUX")
	)
	(segment
		(start 30.291786 -36.286948)
		(end 30.23743 -36.232592)
		(width 0.4572)
		(layer "F.Cu")
		(net "P3V3_AUX")
	)
	(segment
		(start 20.575016 -48.753014)
		(end 21.550376 -48.753014)
		(width 0.254)
		(layer "F.Cu")
		(net "P3V3_AUX")
	)
	(segment
		(start 220.631512 -232.841292)
		(end 220.972888 -233.182668)
		(width 0.4572)
		(layer "F.Cu")
		(net "P3V3_AUX")
	)
	(segment
		(start 77.06233 -22.555454)
		(end 77.718412 -22.555454)
		(width 0.4572)
		(layer "F.Cu")
		(net "P3V3_AUX")
	)
	(segment
		(start 143.226282 -40.82161)
		(end 143.076168 -40.971724)
		(width 0.4572)
		(layer "F.Cu")
		(net "P3V3_AUX")
	)
	(segment
		(start 138.806682 -211.93887)
		(end 138.806682 -210.901534)
		(width 0.2794)
		(layer "F.Cu")
		(net "P3V3_AUX")
	)
	(segment
		(start 56.237378 -36.232592)
		(end 56.291734 -36.286948)
		(width 0.4572)
		(layer "F.Cu")
		(net "P3V3_AUX")
	)
	(segment
		(start 136.33958 -153.1112)
		(end 136.33958 -153.782522)
		(width 0.4064)
		(layer "F.Cu")
		(net "P3V3_AUX")
	)
	(segment
		(start 310.867806 -52.035456)
		(end 311.523126 -52.035456)
		(width 0.254)
		(layer "F.Cu")
		(net "P3V3_AUX")
	)
	(segment
		(start 79.801974 -89.1159)
		(end 79.234538 -88.548464)
		(width 0.381)
		(layer "F.Cu")
		(net "P3V3_AUX")
	)
	(segment
		(start 86.991444 -96.037654)
		(end 86.991444 -96.411542)
		(width 0.4572)
		(layer "F.Cu")
		(net "P3V3_AUX")
	)
	(segment
		(start 215.272874 -47.193962)
		(end 215.545924 -47.193962)
		(width 0.254)
		(layer "F.Cu")
		(net "P3V3_AUX")
	)
	(segment
		(start 335.64195 -142.875)
		(end 335.026 -142.875)
		(width 0.4572)
		(layer "F.Cu")
		(net "P3V3_AUX")
	)
	(segment
		(start 262.437372 -36.232592)
		(end 261.595108 -36.232592)
		(width 0.4572)
		(layer "F.Cu")
		(net "P3V3_AUX")
	)
	(segment
		(start 56.22925 -118.007384)
		(end 55.968646 -118.267988)
		(width 0.4064)
		(layer "F.Cu")
		(net "P3V3_AUX")
	)
	(segment
		(start 209.101436 -221.19082)
		(end 208.286858 -221.19082)
		(width 0.4572)
		(layer "F.Cu")
		(net "P3V3_AUX")
	)
	(segment
		(start 232.26776 -220.704156)
		(end 232.667556 -221.103952)
		(width 0.381)
		(layer "F.Cu")
		(net "P3V3_AUX")
	)
	(segment
		(start 400.943826 -44.87291)
		(end 401.615148 -44.87291)
		(width 0.254)
		(layer "F.Cu")
		(net "P3V3_AUX")
	)
	(segment
		(start 340.320884 -116.630704)
		(end 340.320884 -117.248178)
		(width 0.4572)
		(layer "F.Cu")
		(net "P3V3_AUX")
	)
	(segment
		(start 228.267768 -222.304102)
		(end 227.867972 -222.703898)
		(width 0.381)
		(layer "F.Cu")
		(net "P3V3_AUX")
	)
	(segment
		(start 340.961472 -196.51345)
		(end 341.571072 -196.51345)
		(width 0.4572)
		(layer "F.Cu")
		(net "P3V3_AUX")
	)
	(segment
		(start 411.57779 -116.550186)
		(end 411.57779 -116.229638)
		(width 0.4572)
		(layer "F.Cu")
		(net "P3V3_AUX")
	)
	(segment
		(start 228.39299 -95.089726)
		(end 227.734368 -95.089726)
		(width 0.254)
		(layer "F.Cu")
		(net "P3V3_AUX")
	)
	(segment
		(start 336.843624 -44.87291)
		(end 337.514946 -44.87291)
		(width 0.254)
		(layer "F.Cu")
		(net "P3V3_AUX")
	)
	(segment
		(start 461.456024 -278.67483)
		(end 462.065624 -278.67483)
		(width 0.4572)
		(layer "F.Cu")
		(net "P3V3_AUX")
	)
	(segment
		(start 19.885914 -414.369758)
		(end 19.885914 -414.985454)
		(width 0.4572)
		(layer "F.Cu")
		(net "P3V3_AUX")
	)
	(segment
		(start 349.980504 -90.645234)
		(end 349.268542 -90.645234)
		(width 0.4572)
		(layer "F.Cu")
		(net "P3V3_AUX")
	)
	(segment
		(start 229.554786 -240.946178)
		(end 229.495858 -240.88725)
		(width 0.4572)
		(layer "F.Cu")
		(net "P3V3_AUX")
	)
	(segment
		(start 332.994 -244.83695)
		(end 332.994 -244.221)
		(width 0.4572)
		(layer "F.Cu")
		(net "P3V3_AUX")
	)
	(segment
		(start 133.062726 -97.74047)
		(end 133.665468 -97.74047)
		(width 0.3048)
		(layer "F.Cu")
		(net "P3V3_AUX")
	)
	(segment
		(start 192.989708 -409.807918)
		(end 192.900808 -409.896818)
		(width 0.4572)
		(layer "F.Cu")
		(net "P3V3_AUX")
	)
	(segment
		(start 375.426224 -40.13581)
		(end 375.426224 -40.82161)
		(width 0.4572)
		(layer "F.Cu")
		(net "P3V3_AUX")
	)
	(segment
		(start 383.55905 -201.505312)
		(end 382.665986 -202.398376)
		(width 0.4572)
		(layer "F.Cu")
		(net "P3V3_AUX")
	)
	(segment
		(start 374.554496 -181.032404)
		(end 378.312934 -181.032404)
		(width 0.4572)
		(layer "F.Cu")
		(net "P3V3_AUX")
	)
	(segment
		(start 203.92009 -288.830766)
		(end 203.92009 -288.378138)
		(width 0.4572)
		(layer "F.Cu")
		(net "P3V3_AUX")
	)
	(segment
		(start 349.426276 -40.13581)
		(end 349.426276 -40.82161)
		(width 0.4572)
		(layer "F.Cu")
		(net "P3V3_AUX")
	)
	(segment
		(start 182.148734 -197.55866)
		(end 182.148734 -198.109332)
		(width 0.4572)
		(layer "F.Cu")
		(net "P3V3_AUX")
	)
	(segment
		(start 358.75595 -173.99)
		(end 358.14 -173.99)
		(width 0.4572)
		(layer "F.Cu")
		(net "P3V3_AUX")
	)
	(segment
		(start 413.188658 -193.730118)
		(end 412.957518 -193.730118)
		(width 0.4572)
		(layer "F.Cu")
		(net "P3V3_AUX")
	)
	(segment
		(start 205.36281 -90.104214)
		(end 206.222346 -90.104214)
		(width 0.4572)
		(layer "F.Cu")
		(net "P3V3_AUX")
	)
	(segment
		(start 253.645924 -47.193962)
		(end 253.372874 -47.193962)
		(width 0.254)
		(layer "F.Cu")
		(net "P3V3_AUX")
	)
	(segment
		(start 214.73668 -244.854984)
		(end 214.73668 -238.213392)
		(width 0.4572)
		(layer "F.Cu")
		(net "P3V3_AUX")
	)
	(segment
		(start 37.1856 -114.86515)
		(end 37.908484 -114.86515)
		(width 0.4064)
		(layer "F.Cu")
		(net "P3V3_AUX")
	)
	(segment
		(start 201.091546 -114.42954)
		(end 201.719942 -114.42954)
		(width 0.4064)
		(layer "F.Cu")
		(net "P3V3_AUX")
	)
	(segment
		(start 449.830444 -118.76024)
		(end 449.220844 -118.76024)
		(width 0.4572)
		(layer "F.Cu")
		(net "P3V3_AUX")
	)
	(segment
		(start 377.551696 -213.97595)
		(end 377.435618 -213.859872)
		(width 0.4572)
		(layer "F.Cu")
		(net "P3V3_AUX")
	)
	(segment
		(start 367.355628 -90.642694)
		(end 368.06124 -90.642694)
		(width 0.4572)
		(layer "F.Cu")
		(net "P3V3_AUX")
	)
	(segment
		(start 232.244646 -273.471386)
		(end 232.915968 -273.471386)
		(width 0.4572)
		(layer "F.Cu")
		(net "P3V3_AUX")
	)
	(segment
		(start 208.175352 -292.122098)
		(end 207.789526 -291.736272)
		(width 0.4572)
		(layer "F.Cu")
		(net "P3V3_AUX")
	)
	(segment
		(start 350.003618 -172.965872)
		(end 350.119696 -173.08195)
		(width 0.4572)
		(layer "F.Cu")
		(net "P3V3_AUX")
	)
	(segment
		(start 426.143674 -47.92091)
		(end 425.810172 -47.92091)
		(width 0.254)
		(layer "F.Cu")
		(net "P3V3_AUX")
	)
	(segment
		(start 400.943826 -42.84091)
		(end 401.615148 -42.84091)
		(width 0.254)
		(layer "F.Cu")
		(net "P3V3_AUX")
	)
	(segment
		(start 334.207866 -239.343184)
		(end 334.207866 -239.710722)
		(width 0.4572)
		(layer "F.Cu")
		(net "P3V3_AUX")
	)
	(segment
		(start 136.675114 -47.792386)
		(end 136.675114 -48.753014)
		(width 0.254)
		(layer "F.Cu")
		(net "P3V3_AUX")
	)
	(segment
		(start 375.912634 -89.9668)
		(end 375.297446 -89.9668)
		(width 0.4572)
		(layer "F.Cu")
		(net "P3V3_AUX")
	)
	(segment
		(start 181.423818 -196.833744)
		(end 181.862476 -197.272402)
		(width 0.3556)
		(layer "F.Cu")
		(net "P3V3_AUX")
	)
	(segment
		(start 92.11691 -292.122098)
		(end 91.689428 -291.694616)
		(width 0.4572)
		(layer "F.Cu")
		(net "P3V3_AUX")
	)
	(segment
		(start 224.422208 -79.595472)
		(end 225.041206 -79.595472)
		(width 0.4572)
		(layer "F.Cu")
		(net "P3V3_AUX")
	)
	(segment
		(start 63.07074 -137.848848)
		(end 62.321948 -137.848848)
		(width 0.4064)
		(layer "F.Cu")
		(net "P3V3_AUX")
	)
	(segment
		(start 256.771648 -350.722438)
		(end 256.130298 -350.722438)
		(width 0.4572)
		(layer "F.Cu")
		(net "P3V3_AUX")
	)
	(segment
		(start 444.67399 -411.900116)
		(end 445.318134 -411.900116)
		(width 0.4572)
		(layer "F.Cu")
		(net "P3V3_AUX")
	)
	(segment
		(start 51.560476 -21.603208)
		(end 51.560476 -20.789392)
		(width 0.4572)
		(layer "F.Cu")
		(net "P3V3_AUX")
	)
	(segment
		(start 283.508196 -47.71898)
		(end 283.508196 -47.403766)
		(width 0.254)
		(layer "F.Cu")
		(net "P3V3_AUX")
	)
	(segment
		(start 138.806682 -210.901534)
		(end 138.90117 -210.807046)
		(width 0.2794)
		(layer "F.Cu")
		(net "P3V3_AUX")
	)
	(segment
		(start 124.07519 -104.734868)
		(end 124.71019 -104.734868)
		(width 0.4572)
		(layer "F.Cu")
		(net "P3V3_AUX")
	)
	(segment
		(start 189.545976 -47.193962)
		(end 189.272926 -47.193962)
		(width 0.254)
		(layer "F.Cu")
		(net "P3V3_AUX")
	)
	(segment
		(start 358.75595 -181.102)
		(end 358.14 -181.102)
		(width 0.4572)
		(layer "F.Cu")
		(net "P3V3_AUX")
	)
	(segment
		(start 425.608242 -47.71898)
		(end 425.608242 -47.403766)
		(width 0.254)
		(layer "F.Cu")
		(net "P3V3_AUX")
	)
	(segment
		(start 212.93074 -179.194206)
		(end 210.765136 -179.194206)
		(width 0.4572)
		(layer "F.Cu")
		(net "P3V3_AUX")
	)
	(segment
		(start 203.174854 -374.059704)
		(end 203.025756 -374.208802)
		(width 0.4572)
		(layer "F.Cu")
		(net "P3V3_AUX")
	)
	(segment
		(start 16.479774 -412.087568)
		(end 17.024096 -412.087568)
		(width 0.4572)
		(layer "F.Cu")
		(net "P3V3_AUX")
	)
	(segment
		(start 212.713316 -223.382586)
		(end 212.695282 -223.40062)
		(width 0.3048)
		(layer "F.Cu")
		(net "P3V3_AUX")
	)
	(segment
		(start 167.943784 -47.92091)
		(end 167.610282 -47.92091)
		(width 0.254)
		(layer "F.Cu")
		(net "P3V3_AUX")
	)
	(segment
		(start 120.33758 -36.232592)
		(end 119.495316 -36.232592)
		(width 0.4572)
		(layer "F.Cu")
		(net "P3V3_AUX")
	)
	(segment
		(start 229.067614 -215.904064)
		(end 228.667818 -215.504268)
		(width 0.381)
		(layer "F.Cu")
		(net "P3V3_AUX")
	)
	(segment
		(start 81.564226 -158.219648)
		(end 80.93964 -158.219648)
		(width 0.4064)
		(layer "F.Cu")
		(net "P3V3_AUX")
	)
	(segment
		(start 56.291734 -36.286948)
		(end 56.947308 -36.286948)
		(width 0.4572)
		(layer "F.Cu")
		(net "P3V3_AUX")
	)
	(segment
		(start 375.912634 -83.1088)
		(end 375.297446 -83.1088)
		(width 0.4572)
		(layer "F.Cu")
		(net "P3V3_AUX")
	)
	(segment
		(start 229.554786 -241.644932)
		(end 229.554786 -240.946178)
		(width 0.4572)
		(layer "F.Cu")
		(net "P3V3_AUX")
	)
	(segment
		(start 87.819992 -288.830766)
		(end 87.819992 -288.378138)
		(width 0.4572)
		(layer "F.Cu")
		(net "P3V3_AUX")
	)
	(segment
		(start 208.999074 -213.313264)
		(end 209.733134 -213.313264)
		(width 0.4572)
		(layer "F.Cu")
		(net "P3V3_AUX")
	)
	(segment
		(start 336.1182 -236.27715)
		(end 336.1182 -234.66425)
		(width 0.4572)
		(layer "F.Cu")
		(net "P3V3_AUX")
	)
	(segment
		(start 309.760366 -21.603208)
		(end 309.262272 -22.101302)
		(width 0.4572)
		(layer "F.Cu")
		(net "P3V3_AUX")
	)
	(segment
		(start 376.40895 -176.18202)
		(end 375.741438 -176.18202)
		(width 0.4572)
		(layer "F.Cu")
		(net "P3V3_AUX")
	)
	(segment
		(start 362.29036 -254.194564)
		(end 362.89996 -254.194564)
		(width 0.381)
		(layer "F.Cu")
		(net "P3V3_AUX")
	)
	(segment
		(start 104.126538 -8.641588)
		(end 104.391714 -8.641588)
		(width 0.4572)
		(layer "F.Cu")
		(net "P3V3_AUX")
	)
	(segment
		(start 336.32648 -8.641588)
		(end 336.53984 -8.641588)
		(width 0.4572)
		(layer "F.Cu")
		(net "P3V3_AUX")
	)
	(segment
		(start 398.433036 -167.202866)
		(end 398.972278 -167.742108)
		(width 0.381)
		(layer "F.Cu")
		(net "P3V3_AUX")
	)
	(segment
		(start 279.841198 -407.615136)
		(end 280.141426 -407.314908)
		(width 0.4572)
		(layer "F.Cu")
		(net "P3V3_AUX")
	)
	(segment
		(start 446.415668 -411.900116)
		(end 446.74028 -412.224728)
		(width 0.4572)
		(layer "F.Cu")
		(net "P3V3_AUX")
	)
	(segment
		(start 213.868 -228.19995)
		(end 213.868 -227.65258)
		(width 0.4572)
		(layer "F.Cu")
		(net "P3V3_AUX")
	)
	(segment
		(start 167.898572 -180.372766)
		(end 167.898572 -179.728368)
		(width 0.4572)
		(layer "F.Cu")
		(net "P3V3_AUX")
	)
	(segment
		(start 167.123618 -168.397174)
		(end 167.123618 -167.742108)
		(width 0.4572)
		(layer "F.Cu")
		(net "P3V3_AUX")
	)
	(segment
		(start 135.125968 -100.154486)
		(end 135.125968 -100.978208)
		(width 0.4572)
		(layer "F.Cu")
		(net "P3V3_AUX")
	)
	(segment
		(start 312.802524 -89.1159)
		(end 311.677812 -89.1159)
		(width 0.381)
		(layer "F.Cu")
		(net "P3V3_AUX")
	)
	(segment
		(start 172.337476 -36.232592)
		(end 171.495212 -36.232592)
		(width 0.4572)
		(layer "F.Cu")
		(net "P3V3_AUX")
	)
	(segment
		(start 327.731374 -205.078584)
		(end 327.59142 -204.93863)
		(width 0.4572)
		(layer "F.Cu")
		(net "P3V3_AUX")
	)
	(segment
		(start 251.637546 -206.53248)
		(end 251.472954 -206.697072)
		(width 0.381)
		(layer "F.Cu")
		(net "P3V3_AUX")
	)
	(segment
		(start 133.831838 -206.4639)
		(end 134.953502 -206.4639)
		(width 0.2794)
		(layer "F.Cu")
		(net "P3V3_AUX")
	)
	(segment
		(start 350.647 -149.96795)
		(end 351.38995 -149.96795)
		(width 0.4572)
		(layer "F.Cu")
		(net "P3V3_AUX")
	)
	(segment
		(start 187.955174 -35.876738)
		(end 187.19927 -35.876738)
		(width 0.4572)
		(layer "F.Cu")
		(net "P3V3_AUX")
	)
	(segment
		(start 331.457046 -237.477046)
		(end 331.851 -237.871)
		(width 0.4572)
		(layer "F.Cu")
		(net "P3V3_AUX")
	)
	(segment
		(start 193.916808 -411.120844)
		(end 193.718434 -411.319218)
		(width 0.4572)
		(layer "F.Cu")
		(net "P3V3_AUX")
	)
	(segment
		(start 213.946486 -245.645178)
		(end 214.73668 -244.854984)
		(width 0.4572)
		(layer "F.Cu")
		(net "P3V3_AUX")
	)
	(segment
		(start 82.947256 -36.286948)
		(end 82.291682 -36.286948)
		(width 0.4572)
		(layer "F.Cu")
		(net "P3V3_AUX")
	)
	(segment
		(start 249.391678 -152.3111)
		(end 249.391678 -151.696928)
		(width 0.4064)
		(layer "F.Cu")
		(net "P3V3_AUX")
	)
	(segment
		(start 369.472972 -47.193962)
		(end 368.875056 -47.791878)
		(width 0.254)
		(layer "F.Cu")
		(net "P3V3_AUX")
	)
	(segment
		(start 383.673858 -211.765388)
		(end 383.673858 -211.709)
		(width 0.4572)
		(layer "F.Cu")
		(net "P3V3_AUX")
	)
	(segment
		(start 328.01814 -94.91472)
		(end 328.01814 -94.24924)
		(width 0.4572)
		(layer "F.Cu")
		(net "P3V3_AUX")
	)
	(segment
		(start 335.64195 -176.911)
		(end 335.026 -176.911)
		(width 0.4572)
		(layer "F.Cu")
		(net "P3V3_AUX")
	)
	(segment
		(start 249.970544 -356.015544)
		(end 250.732544 -356.015544)
		(width 0.4572)
		(layer "F.Cu")
		(net "P3V3_AUX")
	)
	(segment
		(start 102.958138 -198.893938)
		(end 103.378 -199.3138)
		(width 0.2794)
		(layer "F.Cu")
		(net "P3V3_AUX")
	)
	(segment
		(start 320.156332 -94.158308)
		(end 319.191386 -95.123254)
		(width 0.4572)
		(layer "F.Cu")
		(net "P3V3_AUX")
	)
	(segment
		(start 340.961472 -188.38545)
		(end 341.571072 -188.38545)
		(width 0.4572)
		(layer "F.Cu")
		(net "P3V3_AUX")
	)
	(segment
		(start 255.01346 -195.173346)
		(end 255.01346 -194.538346)
		(width 0.4572)
		(layer "F.Cu")
		(net "P3V3_AUX")
	)
	(segment
		(start 17.447006 -411.664658)
		(end 17.447006 -411.155134)
		(width 0.4572)
		(layer "F.Cu")
		(net "P3V3_AUX")
	)
	(segment
		(start 335.64195 -184.023)
		(end 335.026 -184.023)
		(width 0.4572)
		(layer "F.Cu")
		(net "P3V3_AUX")
	)
	(segment
		(start 356.25405 -167.64)
		(end 356.87 -167.64)
		(width 0.4572)
		(layer "F.Cu")
		(net "P3V3_AUX")
	)
	(segment
		(start 457.406502 -280.224484)
		(end 456.796902 -280.224484)
		(width 0.4572)
		(layer "F.Cu")
		(net "P3V3_AUX")
	)
	(segment
		(start 354.609146 -26.03373)
		(end 353.950016 -26.03373)
		(width 0.4572)
		(layer "F.Cu")
		(net "P3V3_AUX")
	)
	(segment
		(start 210.008216 -225.594164)
		(end 210.445096 -226.031044)
		(width 0.4064)
		(layer "F.Cu")
		(net "P3V3_AUX")
	)
	(segment
		(start 25.510236 -47.92091)
		(end 25.308306 -47.71898)
		(width 0.254)
		(layer "F.Cu")
		(net "P3V3_AUX")
	)
	(segment
		(start 258.86791 -52.035456)
		(end 259.52323 -52.035456)
		(width 0.254)
		(layer "F.Cu")
		(net "P3V3_AUX")
	)
	(segment
		(start 216.567512 -231.816656)
		(end 216.567512 -232.729532)
		(width 0.4572)
		(layer "F.Cu")
		(net "P3V3_AUX")
	)
	(segment
		(start 133.665468 -97.74047)
		(end 133.9088 -97.983802)
		(width 0.3048)
		(layer "F.Cu")
		(net "P3V3_AUX")
	)
	(segment
		(start 2.14884 -33.53816)
		(end 2.14884 -32.724344)
		(width 0.4572)
		(layer "F.Cu")
		(net "P3V3_AUX")
	)
	(segment
		(start 429.864266 -158.219648)
		(end 429.23968 -158.219648)
		(width 0.4064)
		(layer "F.Cu")
		(net "P3V3_AUX")
	)
	(segment
		(start 205.91399 -358.324658)
		(end 203.244704 -358.324658)
		(width 0.4572)
		(layer "F.Cu")
		(net "P3V3_AUX")
	)
	(segment
		(start 380.034038 -5.852922)
		(end 380.649734 -5.852922)
		(width 0.4572)
		(layer "F.Cu")
		(net "P3V3_AUX")
	)
	(segment
		(start 352.719894 -158.417768)
		(end 353.462844 -158.417768)
		(width 0.4572)
		(layer "F.Cu")
		(net "P3V3_AUX")
	)
	(segment
		(start 95.96501 -242.238784)
		(end 96.042226 -242.238784)
		(width 0.254)
		(layer "F.Cu")
		(net "P3V3_AUX")
	)
	(segment
		(start 219.408248 -47.71898)
		(end 219.408248 -47.403766)
		(width 0.254)
		(layer "F.Cu")
		(net "P3V3_AUX")
	)
	(segment
		(start 141.943836 -47.92091)
		(end 141.610334 -47.92091)
		(width 0.254)
		(layer "F.Cu")
		(net "P3V3_AUX")
	)
	(segment
		(start 376.53595 -186.817)
		(end 375.832878 -186.817)
		(width 0.4572)
		(layer "F.Cu")
		(net "P3V3_AUX")
	)
	(segment
		(start 222.5548 -23.361396)
		(end 222.5548 -23.970996)
		(width 0.4572)
		(layer "F.Cu")
		(net "P3V3_AUX")
	)
	(segment
		(start 283.34335 -169.351706)
		(end 283.34335 -170.77944)
		(width 0.4572)
		(layer "F.Cu")
		(net "P3V3_AUX")
	)
	(segment
		(start 245.553484 -237.075218)
		(end 245.129558 -237.499144)
		(width 0.4572)
		(layer "F.Cu")
		(net "P3V3_AUX")
	)
	(segment
		(start 436.120032 -288.378138)
		(end 436.277004 -288.221166)
		(width 0.4572)
		(layer "F.Cu")
		(net "P3V3_AUX")
	)
	(segment
		(start 194.999356 -83.526376)
		(end 194.993514 -83.532218)
		(width 0.4064)
		(layer "F.Cu")
		(net "P3V3_AUX")
	)
	(segment
		(start 225.867722 -220.704156)
		(end 225.467926 -221.103952)
		(width 0.381)
		(layer "F.Cu")
		(net "P3V3_AUX")
	)
	(segment
		(start 374.50395 -181.08295)
		(end 373.761 -181.08295)
		(width 0.4572)
		(layer "F.Cu")
		(net "P3V3_AUX")
	)
	(segment
		(start 374.943878 -42.84091)
		(end 375.6152 -42.84091)
		(width 0.254)
		(layer "F.Cu")
		(net "P3V3_AUX")
	)
	(segment
		(start 261.596378 -344.772488)
		(end 259.932932 -346.435934)
		(width 0.4572)
		(layer "F.Cu")
		(net "P3V3_AUX")
	)
	(segment
		(start 128.058164 -257.115564)
		(end 128.667764 -257.115564)
		(width 0.381)
		(layer "F.Cu")
		(net "P3V3_AUX")
	)
	(segment
		(start 209.103976 -292.122098)
		(end 209.738976 -292.122098)
		(width 0.4572)
		(layer "F.Cu")
		(net "P3V3_AUX")
	)
	(segment
		(start 167.16248 -22.101302)
		(end 167.16248 -22.555454)
		(width 0.4572)
		(layer "F.Cu")
		(net "P3V3_AUX")
	)
	(segment
		(start 458.18679 -365.14151)
		(end 458.18679 -364.501684)
		(width 0.4572)
		(layer "F.Cu")
		(net "P3V3_AUX")
	)
	(segment
		(start 400.528282 -85.3948)
		(end 399.99285 -85.3948)
		(width 0.4572)
		(layer "F.Cu")
		(net "P3V3_AUX")
	)
	(segment
		(start 123.749562 -157.812994)
		(end 123.132088 -157.812994)
		(width 0.4572)
		(layer "F.Cu")
		(net "P3V3_AUX")
	)
	(segment
		(start 252.055122 -35.876738)
		(end 251.299218 -35.876738)
		(width 0.4572)
		(layer "F.Cu")
		(net "P3V3_AUX")
	)
	(segment
		(start 212.451442 -244.416326)
		(end 212.451442 -245.025926)
		(width 0.3048)
		(layer "F.Cu")
		(net "P3V3_AUX")
	)
	(segment
		(start 123.31319 -139.376404)
		(end 122.65787 -139.376404)
		(width 0.4064)
		(layer "F.Cu")
		(net "P3V3_AUX")
	)
	(segment
		(start 383.855468 -243.44884)
		(end 384.088894 -243.215414)
		(width 0.2794)
		(layer "F.Cu")
		(net "P3V3_AUX")
	)
	(segment
		(start 131.367276 -193.5988)
		(end 131.422648 -193.543428)
		(width 0.3556)
		(layer "F.Cu")
		(net "P3V3_AUX")
	)
	(segment
		(start 206.504286 -208.212436)
		(end 205.422246 -209.294476)
		(width 0.4572)
		(layer "F.Cu")
		(net "P3V3_AUX")
	)
	(segment
		(start 309.42915 -83.656932)
		(end 309.553864 -83.532218)
		(width 0.4064)
		(layer "F.Cu")
		(net "P3V3_AUX")
	)
	(segment
		(start 375.912634 -81.9658)
		(end 375.297446 -81.9658)
		(width 0.4572)
		(layer "F.Cu")
		(net "P3V3_AUX")
	)
	(segment
		(start 455.031856 -52.0446)
		(end 455.355198 -51.721258)
		(width 0.4572)
		(layer "F.Cu")
		(net "P3V3_AUX")
	)
	(segment
		(start 440.960002 -102.480364)
		(end 440.362086 -101.882448)
		(width 0.254)
		(layer "F.Cu")
		(net "P3V3_AUX")
	)
	(segment
		(start 108.120942 -116.630704)
		(end 108.120942 -117.248178)
		(width 0.4572)
		(layer "F.Cu")
		(net "P3V3_AUX")
	)
	(segment
		(start 209.72018 -243.774976)
		(end 209.87893 -243.616226)
		(width 0.4572)
		(layer "F.Cu")
		(net "P3V3_AUX")
	)
	(segment
		(start 288.491676 -36.286948)
		(end 288.43732 -36.232592)
		(width 0.4572)
		(layer "F.Cu")
		(net "P3V3_AUX")
	)
	(segment
		(start 263.147302 -36.286948)
		(end 262.491728 -36.286948)
		(width 0.4572)
		(layer "F.Cu")
		(net "P3V3_AUX")
	)
	(segment
		(start 327.19137 -227.31095)
		(end 327.19137 -226.660202)
		(width 0.4572)
		(layer "F.Cu")
		(net "P3V3_AUX")
	)
	(segment
		(start 331.645768 -47.193962)
		(end 331.372718 -47.193962)
		(width 0.254)
		(layer "F.Cu")
		(net "P3V3_AUX")
	)
	(segment
		(start 11.593322 -119.505476)
		(end 11.593322 -120.11787)
		(width 0.4572)
		(layer "F.Cu")
		(net "P3V3_AUX")
	)
	(segment
		(start 257.262376 -22.555454)
		(end 257.918458 -22.555454)
		(width 0.4572)
		(layer "F.Cu")
		(net "P3V3_AUX")
	)
	(segment
		(start 243.023898 -278.541988)
		(end 242.425982 -279.139904)
		(width 0.254)
		(layer "F.Cu")
		(net "P3V3_AUX")
	)
	(segment
		(start 335.64195 -141.859)
		(end 335.026 -141.859)
		(width 0.4572)
		(layer "F.Cu")
		(net "P3V3_AUX")
	)
	(segment
		(start 248.97969 -147.042378)
		(end 249.850656 -147.913344)
		(width 0.254)
		(layer "F.Cu")
		(net "P3V3_AUX")
	)
	(segment
		(start 206.793592 -350.712532)
		(end 206.793592 -351.43186)
		(width 0.4572)
		(layer "F.Cu")
		(net "P3V3_AUX")
	)
	(segment
		(start 358.75595 -192.278)
		(end 358.14 -192.278)
		(width 0.4572)
		(layer "F.Cu")
		(net "P3V3_AUX")
	)
	(segment
		(start 376.2375 -8.29183)
		(end 375.912888 -8.616442)
		(width 0.4572)
		(layer "F.Cu")
		(net "P3V3_AUX")
	)
	(segment
		(start 312.802524 -89.78138)
		(end 312.802524 -89.1159)
		(width 0.4572)
		(layer "F.Cu")
		(net "P3V3_AUX")
	)
	(segment
		(start 21.172932 -47.193962)
		(end 20.575016 -47.791878)
		(width 0.254)
		(layer "F.Cu")
		(net "P3V3_AUX")
	)
	(segment
		(start 380.85395 -197.358)
		(end 380.177802 -197.358)
		(width 0.4572)
		(layer "F.Cu")
		(net "P3V3_AUX")
	)
	(segment
		(start 132.879592 -147.042378)
		(end 133.750558 -147.913344)
		(width 0.254)
		(layer "F.Cu")
		(net "P3V3_AUX")
	)
	(segment
		(start 205.422246 -211.328)
		(end 205.422246 -212.577426)
		(width 0.4572)
		(layer "F.Cu")
		(net "P3V3_AUX")
	)
	(segment
		(start 245.129558 -237.499144)
		(end 245.129558 -238.66348)
		(width 0.4572)
		(layer "F.Cu")
		(net "P3V3_AUX")
	)
	(segment
		(start 456.796902 -279.263348)
		(end 457.394818 -278.665432)
		(width 0.254)
		(layer "F.Cu")
		(net "P3V3_AUX")
	)
	(segment
		(start 210.171284 -220.291406)
		(end 209.857086 -219.977208)
		(width 0.4572)
		(layer "F.Cu")
		(net "P3V3_AUX")
	)
	(segment
		(start 219.914216 -104.512618)
		(end 219.253816 -103.852218)
		(width 0.254)
		(layer "F.Cu")
		(net "P3V3_AUX")
	)
	(segment
		(start 233.326178 -40.82161)
		(end 233.176064 -40.971724)
		(width 0.4572)
		(layer "F.Cu")
		(net "P3V3_AUX")
	)
	(segment
		(start 208.249266 -355.989382)
		(end 205.91399 -358.324658)
		(width 0.4572)
		(layer "F.Cu")
		(net "P3V3_AUX")
	)
	(segment
		(start 189.272926 -47.193962)
		(end 188.67501 -47.791878)
		(width 0.254)
		(layer "F.Cu")
		(net "P3V3_AUX")
	)
	(segment
		(start 244.221762 -180.633878)
		(end 244.221762 -178.919378)
		(width 0.4572)
		(layer "F.Cu")
		(net "P3V3_AUX")
	)
	(segment
		(start 378.312934 -181.032404)
		(end 379.24105 -180.104288)
		(width 0.4572)
		(layer "F.Cu")
		(net "P3V3_AUX")
	)
	(segment
		(start 365.491776 -152.3111)
		(end 365.491776 -151.696928)
		(width 0.4064)
		(layer "F.Cu")
		(net "P3V3_AUX")
	)
	(segment
		(start 194.52082 -366.086898)
		(end 193.34099 -367.266728)
		(width 0.4572)
		(layer "F.Cu")
		(net "P3V3_AUX")
	)
	(segment
		(start 141.610334 -47.92091)
		(end 141.408404 -47.71898)
		(width 0.254)
		(layer "F.Cu")
		(net "P3V3_AUX")
	)
	(segment
		(start 192.114932 -409.896818)
		(end 192.900808 -409.896818)
		(width 0.4572)
		(layer "F.Cu")
		(net "P3V3_AUX")
	)
	(segment
		(start 437.323484 -96.411542)
		(end 437.323484 -95.801942)
		(width 0.4572)
		(layer "F.Cu")
		(net "P3V3_AUX")
	)
	(segment
		(start 213.990936 -189.052454)
		(end 212.974936 -189.052454)
		(width 0.4572)
		(layer "F.Cu")
		(net "P3V3_AUX")
	)
	(segment
		(start 144.106646 -189.778132)
		(end 144.126712 -189.758066)
		(width 0.3556)
		(layer "F.Cu")
		(net "P3V3_AUX")
	)
	(segment
		(start 390.685782 -89.421462)
		(end 390.650984 -89.386664)
		(width 0.3048)
		(layer "F.Cu")
		(net "P3V3_AUX")
	)
	(segment
		(start 436.120032 -288.830766)
		(end 436.120032 -288.378138)
		(width 0.4572)
		(layer "F.Cu")
		(net "P3V3_AUX")
	)
	(segment
		(start 283.82595 -84.836)
		(end 283.21 -84.836)
		(width 0.4572)
		(layer "F.Cu")
		(net "P3V3_AUX")
	)
	(segment
		(start 375.912888 -9.713976)
		(end 375.912888 -10.35812)
		(width 0.4572)
		(layer "F.Cu")
		(net "P3V3_AUX")
	)
	(segment
		(start 404.955248 -381.50165)
		(end 404.953978 -381.50292)
		(width 0.4572)
		(layer "F.Cu")
		(net "P3V3_AUX")
	)
	(segment
		(start 350.003618 -184.903872)
		(end 350.119696 -185.01995)
		(width 0.4572)
		(layer "F.Cu")
		(net "P3V3_AUX")
	)
	(segment
		(start 350.647 -161.77895)
		(end 350.119696 -161.77895)
		(width 0.4572)
		(layer "F.Cu")
		(net "P3V3_AUX")
	)
	(segment
		(start 226.667568 -217.504264)
		(end 226.267772 -217.104468)
		(width 0.381)
		(layer "F.Cu")
		(net "P3V3_AUX")
	)
	(segment
		(start 363.07395 -194.691)
		(end 362.458 -194.691)
		(width 0.4572)
		(layer "F.Cu")
		(net "P3V3_AUX")
	)
	(segment
		(start 305.64582 -47.193962)
		(end 305.37277 -47.193962)
		(width 0.254)
		(layer "F.Cu")
		(net "P3V3_AUX")
	)
	(segment
		(start 194.993514 -83.532218)
		(end 193.453766 -83.532218)
		(width 0.4064)
		(layer "F.Cu")
		(net "P3V3_AUX")
	)
	(segment
		(start 97.648268 -390.819132)
		(end 97.648268 -391.0838)
		(width 0.4572)
		(layer "F.Cu")
		(net "P3V3_AUX")
	)
	(segment
		(start 213.946486 -252.308868)
		(end 213.946486 -245.645178)
		(width 0.4572)
		(layer "F.Cu")
		(net "P3V3_AUX")
	)
	(segment
		(start 340.961472 -191.43345)
		(end 341.571072 -191.43345)
		(width 0.4572)
		(layer "F.Cu")
		(net "P3V3_AUX")
	)
	(segment
		(start 213.961218 -222.45574)
		(end 213.50859 -222.45574)
		(width 0.3048)
		(layer "F.Cu")
		(net "P3V3_AUX")
	)
	(segment
		(start 139.385294 -96.957642)
		(end 140.090144 -96.957642)
		(width 0.4572)
		(layer "F.Cu")
		(net "P3V3_AUX")
	)
	(segment
		(start 198.214234 -140.534898)
		(end 197.537832 -140.534898)
		(width 0.4064)
		(layer "F.Cu")
		(net "P3V3_AUX")
	)
	(segment
		(start 242.232434 -251.159772)
		(end 242.232434 -251.857256)
		(width 0.4572)
		(layer "F.Cu")
		(net "P3V3_AUX")
	)
	(segment
		(start 6.309106 -26.03373)
		(end 5.699506 -26.03373)
		(width 0.4572)
		(layer "F.Cu")
		(net "P3V3_AUX")
	)
	(segment
		(start 146.391884 -36.286948)
		(end 146.337528 -36.232592)
		(width 0.4572)
		(layer "F.Cu")
		(net "P3V3_AUX")
	)
	(segment
		(start 380.034038 -7.884922)
		(end 380.649734 -7.884922)
		(width 0.4572)
		(layer "F.Cu")
		(net "P3V3_AUX")
	)
	(segment
		(start 11.116564 -277.814278)
		(end 11.116564 -276.853142)
		(width 0.254)
		(layer "F.Cu")
		(net "P3V3_AUX")
	)
	(segment
		(start 338.092542 -9.139682)
		(end 338.092542 -8.4836)
		(width 0.4572)
		(layer "F.Cu")
		(net "P3V3_AUX")
	)
	(segment
		(start 284.843728 -44.87291)
		(end 285.51505 -44.87291)
		(width 0.254)
		(layer "F.Cu")
		(net "P3V3_AUX")
	)
	(segment
		(start 328.839068 -205.078584)
		(end 328.311764 -205.078584)
		(width 0.4572)
		(layer "F.Cu")
		(net "P3V3_AUX")
	)
	(segment
		(start 238.889794 -201.028554)
		(end 239.439704 -200.478644)
		(width 0.4572)
		(layer "F.Cu")
		(net "P3V3_AUX")
	)
	(segment
		(start 238.342678 -201.798936)
		(end 238.342678 -202.741276)
		(width 0.4572)
		(layer "F.Cu")
		(net "P3V3_AUX")
	)
	(segment
		(start 32.056324 -61.487812)
		(end 32.686498 -61.487812)
		(width 0.4572)
		(layer "F.Cu")
		(net "P3V3_AUX")
	)
	(segment
		(start 336.867754 -52.035456)
		(end 337.523074 -52.035456)
		(width 0.254)
		(layer "F.Cu")
		(net "P3V3_AUX")
	)
	(segment
		(start 314.437268 -36.232592)
		(end 313.595004 -36.232592)
		(width 0.4572)
		(layer "F.Cu")
		(net "P3V3_AUX")
	)
	(segment
		(start 401.426172 -40.13581)
		(end 401.426172 -40.82161)
		(width 0.4572)
		(layer "F.Cu")
		(net "P3V3_AUX")
	)
	(segment
		(start 446.74028 -412.224728)
		(end 446.74028 -412.806642)
		(width 0.4572)
		(layer "F.Cu")
		(net "P3V3_AUX")
	)
	(segment
		(start 426.967904 -52.035456)
		(end 427.623224 -52.035456)
		(width 0.254)
		(layer "F.Cu")
		(net "P3V3_AUX")
	)
	(segment
		(start 313.40171 -140.534898)
		(end 312.965846 -140.099034)
		(width 0.4064)
		(layer "F.Cu")
		(net "P3V3_AUX")
	)
	(segment
		(start 258.94538 -208.019396)
		(end 259.56133 -208.019396)
		(width 0.4572)
		(layer "F.Cu")
		(net "P3V3_AUX")
	)
	(segment
		(start 429.501808 -140.534898)
		(end 429.065944 -140.099034)
		(width 0.4064)
		(layer "F.Cu")
		(net "P3V3_AUX")
	)
	(segment
		(start 225.867722 -219.904056)
		(end 225.467926 -220.303852)
		(width 0.381)
		(layer "F.Cu")
		(net "P3V3_AUX")
	)
	(segment
		(start 339.773514 -243.682266)
		(end 339.177122 -244.278658)
		(width 0.3556)
		(layer "F.Cu")
		(net "P3V3_AUX")
	)
	(segment
		(start 121.04751 -36.286948)
		(end 120.391936 -36.286948)
		(width 0.4572)
		(layer "F.Cu")
		(net "P3V3_AUX")
	)
	(segment
		(start 405.882348 -36.286948)
		(end 405.247348 -36.286948)
		(width 0.4572)
		(layer "F.Cu")
		(net "P3V3_AUX")
	)
	(segment
		(start 336.53984 -8.641588)
		(end 337.037934 -9.139682)
		(width 0.4572)
		(layer "F.Cu")
		(net "P3V3_AUX")
	)
	(segment
		(start 51.718464 -22.555454)
		(end 51.062382 -22.555454)
		(width 0.4572)
		(layer "F.Cu")
		(net "P3V3_AUX")
	)
	(segment
		(start 118.358412 -131.218686)
		(end 119.013732 -131.218686)
		(width 0.381)
		(layer "F.Cu")
		(net "P3V3_AUX")
	)
	(segment
		(start 188.67501 -47.791878)
		(end 188.67501 -48.753014)
		(width 0.254)
		(layer "F.Cu")
		(net "P3V3_AUX")
	)
	(segment
		(start 400.717512 -85.20557)
		(end 400.528282 -85.3948)
		(width 0.4572)
		(layer "F.Cu")
		(net "P3V3_AUX")
	)
	(segment
		(start 119.42318 -158.977076)
		(end 120.504712 -157.895544)
		(width 0.254)
		(layer "F.Cu")
		(net "P3V3_AUX")
	)
	(segment
		(start 453.623172 -52.035456)
		(end 453.632316 -52.0446)
		(width 0.4572)
		(layer "F.Cu")
		(net "P3V3_AUX")
	)
	(segment
		(start 80.93964 -137.645648)
		(end 80.93964 -136.98601)
		(width 0.4064)
		(layer "F.Cu")
		(net "P3V3_AUX")
	)
	(segment
		(start 276.667468 -387.752082)
		(end 275.871432 -387.752082)
		(width 0.4318)
		(layer "F.Cu")
		(net "P3V3_AUX")
	)
	(segment
		(start 251.637546 -204.79893)
		(end 251.637546 -206.53248)
		(width 0.381)
		(layer "F.Cu")
		(net "P3V3_AUX")
	)
	(segment
		(start 335.64195 -181.991)
		(end 335.026 -181.991)
		(width 0.4572)
		(layer "F.Cu")
		(net "P3V3_AUX")
	)
	(segment
		(start 122.156474 -61.487812)
		(end 122.786648 -61.487812)
		(width 0.4572)
		(layer "F.Cu")
		(net "P3V3_AUX")
	)
	(segment
		(start 322.864734 -226.698302)
		(end 321.848988 -226.698302)
		(width 0.3048)
		(layer "F.Cu")
		(net "P3V3_AUX")
	)
	(segment
		(start 406.484582 -366.62614)
		(end 406.484582 -365.888016)
		(width 0.4572)
		(layer "F.Cu")
		(net "P3V3_AUX")
	)
	(segment
		(start 457.986384 -366.913922)
		(end 458.832712 -366.913922)
		(width 0.4572)
		(layer "F.Cu")
		(net "P3V3_AUX")
	)
	(segment
		(start 404.537418 -36.232592)
		(end 403.695154 -36.232592)
		(width 0.4572)
		(layer "F.Cu")
		(net "P3V3_AUX")
	)
	(segment
		(start 148.156422 -61.487812)
		(end 148.786596 -61.487812)
		(width 0.4572)
		(layer "F.Cu")
		(net "P3V3_AUX")
	)
	(segment
		(start 208.728056 -214.737696)
		(end 208.27365 -215.192102)
		(width 0.3048)
		(layer "F.Cu")
		(net "P3V3_AUX")
	)
	(segment
		(start 57.582308 -36.286948)
		(end 56.947308 -36.286948)
		(width 0.4572)
		(layer "F.Cu")
		(net "P3V3_AUX")
	)
	(segment
		(start 350.119696 -161.77895)
		(end 350.003618 -161.662872)
		(width 0.4572)
		(layer "F.Cu")
		(net "P3V3_AUX")
	)
	(segment
		(start 309.24246 -83.656932)
		(end 309.42915 -83.656932)
		(width 0.4064)
		(layer "F.Cu")
		(net "P3V3_AUX")
	)
	(segment
		(start 363.07395 -205.867)
		(end 362.458 -205.867)
		(width 0.4572)
		(layer "F.Cu")
		(net "P3V3_AUX")
	)
	(segment
		(start 208.999074 -213.313264)
		(end 208.999074 -214.466678)
		(width 0.4572)
		(layer "F.Cu")
		(net "P3V3_AUX")
	)
	(segment
		(start 172.391832 -36.286948)
		(end 172.337476 -36.232592)
		(width 0.4572)
		(layer "F.Cu")
		(net "P3V3_AUX")
	)
	(segment
		(start 123.749562 -159.844994)
		(end 123.132088 -159.844994)
		(width 0.4572)
		(layer "F.Cu")
		(net "P3V3_AUX")
	)
	(segment
		(start 259.326126 -40.82161)
		(end 259.176012 -40.971724)
		(width 0.4572)
		(layer "F.Cu")
		(net "P3V3_AUX")
	)
	(segment
		(start 375.912634 -91.1098)
		(end 375.297446 -91.1098)
		(width 0.4572)
		(layer "F.Cu")
		(net "P3V3_AUX")
	)
	(segment
		(start 79.637636 -7.469632)
		(end 79.313024 -7.794244)
		(width 0.4572)
		(layer "F.Cu")
		(net "P3V3_AUX")
	)
	(segment
		(start 245.904258 -237.013242)
		(end 245.61546 -237.013242)
		(width 0.4572)
		(layer "F.Cu")
		(net "P3V3_AUX")
	)
	(segment
		(start 378.591826 -36.286948)
		(end 378.53747 -36.232592)
		(width 0.4572)
		(layer "F.Cu")
		(net "P3V3_AUX")
	)
	(segment
		(start 27.126184 -40.82161)
		(end 26.97607 -40.971724)
		(width 0.4572)
		(layer "F.Cu")
		(net "P3V3_AUX")
	)
	(segment
		(start 58.309002 -26.03373)
		(end 57.649872 -26.03373)
		(width 0.4572)
		(layer "F.Cu")
		(net "P3V3_AUX")
	)
	(segment
		(start 283.760418 -21.603208)
		(end 283.262324 -22.101302)
		(width 0.4572)
		(layer "F.Cu")
		(net "P3V3_AUX")
	)
	(segment
		(start 253.372874 -47.193962)
		(end 252.774958 -47.791878)
		(width 0.254)
		(layer "F.Cu")
		(net "P3V3_AUX")
	)
	(segment
		(start 319.51295 -84.94395)
		(end 319.278 -84.709)
		(width 0.4572)
		(layer "F.Cu")
		(net "P3V3_AUX")
	)
	(segment
		(start 400.143726 -47.92091)
		(end 399.810224 -47.92091)
		(width 0.254)
		(layer "F.Cu")
		(net "P3V3_AUX")
	)
	(segment
		(start 182.228236 -198.188834)
		(end 182.228236 -198.755)
		(width 0.4572)
		(layer "F.Cu")
		(net "P3V3_AUX")
	)
	(segment
		(start 331.457046 -237.271306)
		(end 331.457046 -237.477046)
		(width 0.4572)
		(layer "F.Cu")
		(net "P3V3_AUX")
	)
	(segment
		(start 330.835 -238.633)
		(end 331.23505 -239.03305)
		(width 0.4572)
		(layer "F.Cu")
		(net "P3V3_AUX")
	)
	(segment
		(start 452.124064 -222.98152)
		(end 452.124064 -222.0976)
		(width 0.2794)
		(layer "F.Cu")
		(net "P3V3_AUX")
	)
	(segment
		(start 363.07395 -198.755)
		(end 362.631228 -198.755)
		(width 0.4572)
		(layer "F.Cu")
		(net "P3V3_AUX")
	)
	(segment
		(start 212.249004 -214.281766)
		(end 211.512404 -214.281766)
		(width 0.4572)
		(layer "F.Cu")
		(net "P3V3_AUX")
	)
	(segment
		(start 356.12705 -171.45)
		(end 356.743 -171.45)
		(width 0.4572)
		(layer "F.Cu")
		(net "P3V3_AUX")
	)
	(segment
		(start 184.553352 -186.995816)
		(end 185.350658 -186.995816)
		(width 0.381)
		(layer "F.Cu")
		(net "P3V3_AUX")
	)
	(segment
		(start 278.774906 -48.753014)
		(end 279.750266 -48.753014)
		(width 0.254)
		(layer "F.Cu")
		(net "P3V3_AUX")
	)
	(segment
		(start 269.807436 -97.1804)
		(end 270.560292 -97.1804)
		(width 0.4064)
		(layer "F.Cu")
		(net "P3V3_AUX")
	)
	(segment
		(start 51.510184 -47.92091)
		(end 51.308254 -47.71898)
		(width 0.254)
		(layer "F.Cu")
		(net "P3V3_AUX")
	)
	(segment
		(start 325.616316 -232.664)
		(end 325.39305 -232.440734)
		(width 0.4572)
		(layer "F.Cu")
		(net "P3V3_AUX")
	)
	(segment
		(start 263.994646 -206.314548)
		(end 263.994646 -206.33436)
		(width 0.4572)
		(layer "F.Cu")
		(net "P3V3_AUX")
	)
	(segment
		(start 377.435618 -202.683872)
		(end 376.432064 -202.683872)
		(width 0.4572)
		(layer "F.Cu")
		(net "P3V3_AUX")
	)
	(segment
		(start 428.902622 -89.1159)
		(end 427.952662 -89.1159)
		(width 0.381)
		(layer "F.Cu")
		(net "P3V3_AUX")
	)
	(segment
		(start 131.367276 -195.391786)
		(end 131.367276 -193.5988)
		(width 0.3556)
		(layer "F.Cu")
		(net "P3V3_AUX")
	)
	(segment
		(start 394.155168 -35.876738)
		(end 393.399264 -35.876738)
		(width 0.4572)
		(layer "F.Cu")
		(net "P3V3_AUX")
	)
	(segment
		(start 98.57486 -48.753014)
		(end 99.55022 -48.753014)
		(width 0.254)
		(layer "F.Cu")
		(net "P3V3_AUX")
	)
	(segment
		(start 26.643838 -44.87291)
		(end 27.31516 -44.87291)
		(width 0.254)
		(layer "F.Cu")
		(net "P3V3_AUX")
	)
	(segment
		(start 233.067606 -217.504264)
		(end 233.467402 -217.104468)
		(width 0.381)
		(layer "F.Cu")
		(net "P3V3_AUX")
	)
	(segment
		(start 331.23505 -239.03305)
		(end 331.23505 -239.395)
		(width 0.4572)
		(layer "F.Cu")
		(net "P3V3_AUX")
	)
	(segment
		(start 407.67 -384.06705)
		(end 408.559 -384.06705)
		(width 0.4572)
		(layer "F.Cu")
		(net "P3V3_AUX")
	)
	(segment
		(start 283.760418 -20.789392)
		(end 283.760418 -21.603208)
		(width 0.4572)
		(layer "F.Cu")
		(net "P3V3_AUX")
	)
	(segment
		(start 283.262324 -22.101302)
		(end 283.262324 -22.555454)
		(width 0.4572)
		(layer "F.Cu")
		(net "P3V3_AUX")
	)
	(segment
		(start 5.090414 -368.23269)
		(end 5.995162 -368.23269)
		(width 0.4572)
		(layer "F.Cu")
		(net "P3V3_AUX")
	)
	(segment
		(start 337.058 -245.63705)
		(end 337.058 -246.253)
		(width 0.4572)
		(layer "F.Cu")
		(net "P3V3_AUX")
	)
	(segment
		(start 199.047354 -36.286948)
		(end 198.39178 -36.286948)
		(width 0.4572)
		(layer "F.Cu")
		(net "P3V3_AUX")
	)
	(segment
		(start 395.74597 -47.193962)
		(end 395.47292 -47.193962)
		(width 0.254)
		(layer "F.Cu")
		(net "P3V3_AUX")
	)
	(segment
		(start 210.384136 -179.194206)
		(end 210.765136 -179.194206)
		(width 0.4572)
		(layer "F.Cu")
		(net "P3V3_AUX")
	)
	(segment
		(start 390.650984 -89.386664)
		(end 388.24027 -89.386664)
		(width 0.3048)
		(layer "F.Cu")
		(net "P3V3_AUX")
	)
	(segment
		(start 119.112284 -137.993628)
		(end 119.084344 -137.965688)
		(width 0.254)
		(layer "F.Cu")
		(net "P3V3_AUX")
	)
	(segment
		(start 425.810172 -47.92091)
		(end 425.608242 -47.71898)
		(width 0.254)
		(layer "F.Cu")
		(net "P3V3_AUX")
	)
	(segment
		(start 412.957518 -193.730118)
		(end 412.496 -193.2686)
		(width 0.4572)
		(layer "F.Cu")
		(net "P3V3_AUX")
	)
	(segment
		(start 426.943774 -42.84091)
		(end 427.615096 -42.84091)
		(width 0.254)
		(layer "F.Cu")
		(net "P3V3_AUX")
	)
	(segment
		(start 281.859228 -167.202866)
		(end 282.277566 -167.202866)
		(width 0.381)
		(layer "F.Cu")
		(net "P3V3_AUX")
	)
	(segment
		(start 279.106884 -408.165046)
		(end 279.63368 -408.165046)
		(width 0.4572)
		(layer "F.Cu")
		(net "P3V3_AUX")
	)
	(segment
		(start 200.734676 -90.73261)
		(end 200.734676 -91.526614)
		(width 0.4572)
		(layer "F.Cu")
		(net "P3V3_AUX")
	)
	(segment
		(start 242.460018 -236.281976)
		(end 242.460018 -235.624116)
		(width 0.4572)
		(layer "F.Cu")
		(net "P3V3_AUX")
	)
	(segment
		(start 297.506136 -198.439786)
		(end 297.506136 -199.718676)
		(width 0.3556)
		(layer "F.Cu")
		(net "P3V3_AUX")
	)
	(segment
		(start 311.677812 -89.1159)
		(end 311.43448 -88.872568)
		(width 0.381)
		(layer "F.Cu")
		(net "P3V3_AUX")
	)
	(segment
		(start 219.610178 -47.92091)
		(end 219.408248 -47.71898)
		(width 0.254)
		(layer "F.Cu")
		(net "P3V3_AUX")
	)
	(segment
		(start 319.51295 -85.344)
		(end 319.51295 -84.94395)
		(width 0.4572)
		(layer "F.Cu")
		(net "P3V3_AUX")
	)
	(segment
		(start 288.429192 -117.5512)
		(end 288.429192 -118.016528)
		(width 0.4064)
		(layer "F.Cu")
		(net "P3V3_AUX")
	)
	(segment
		(start 435.291484 -96.411542)
		(end 434.797708 -96.411542)
		(width 0.4572)
		(layer "F.Cu")
		(net "P3V3_AUX")
	)
	(segment
		(start 352.639884 -234.71378)
		(end 352.639884 -234.114086)
		(width 0.4572)
		(layer "F.Cu")
		(net "P3V3_AUX")
	)
	(segment
		(start 399.561304 -168.634664)
		(end 399.323814 -168.397174)
		(width 0.4572)
		(layer "F.Cu")
		(net "P3V3_AUX")
	)
	(segment
		(start 207.728058 -227.50907)
		(end 207.556608 -227.68052)
		(width 0.4572)
		(layer "F.Cu")
		(net "P3V3_AUX")
	)
	(segment
		(start 17.024096 -412.087568)
		(end 17.447006 -411.664658)
		(width 0.4572)
		(layer "F.Cu")
		(net "P3V3_AUX")
	)
	(segment
		(start 82.11439 -140.534898)
		(end 81.47939 -140.534898)
		(width 0.4064)
		(layer "F.Cu")
		(net "P3V3_AUX")
	)
	(segment
		(start 6.056376 -61.487812)
		(end 6.056376 -60.781946)
		(width 0.4572)
		(layer "F.Cu")
		(net "P3V3_AUX")
	)
	(segment
		(start 219.05976 -233.182668)
		(end 219.520262 -233.182668)
		(width 0.4572)
		(layer "F.Cu")
		(net "P3V3_AUX")
	)
	(segment
		(start 36.604702 -140.85697)
		(end 36.074096 -140.326364)
		(width 0.4064)
		(layer "F.Cu")
		(net "P3V3_AUX")
	)
	(segment
		(start 215.650318 -48.753014)
		(end 214.674958 -48.753014)
		(width 0.254)
		(layer "F.Cu")
		(net "P3V3_AUX")
	)
	(segment
		(start 167.660574 -21.603208)
		(end 167.16248 -22.101302)
		(width 0.4572)
		(layer "F.Cu")
		(net "P3V3_AUX")
	)
	(segment
		(start 400.967956 -52.035456)
		(end 401.623276 -52.035456)
		(width 0.254)
		(layer "F.Cu")
		(net "P3V3_AUX")
	)
	(segment
		(start 152.704546 -141.87297)
		(end 152.704546 -140.85697)
		(width 0.4064)
		(layer "F.Cu")
		(net "P3V3_AUX")
	)
	(segment
		(start 396.609316 -84.928202)
		(end 397.224758 -84.928202)
		(width 0.4572)
		(layer "F.Cu")
		(net "P3V3_AUX")
	)
	(segment
		(start 335.64195 -148.971)
		(end 335.026 -148.971)
		(width 0.4572)
		(layer "F.Cu")
		(net "P3V3_AUX")
	)
	(segment
		(start 406.356312 -61.487812)
		(end 406.986486 -61.487812)
		(width 0.4572)
		(layer "F.Cu")
		(net "P3V3_AUX")
	)
	(segment
		(start 374.143778 -47.92091)
		(end 373.810276 -47.92091)
		(width 0.254)
		(layer "F.Cu")
		(net "P3V3_AUX")
	)
	(segment
		(start 251.472954 -206.697072)
		(end 251.128784 -206.697072)
		(width 0.4572)
		(layer "F.Cu")
		(net "P3V3_AUX")
	)
	(segment
		(start 257.76047 -21.603208)
		(end 257.262376 -22.101302)
		(width 0.4572)
		(layer "F.Cu")
		(net "P3V3_AUX")
	)
	(segment
		(start 399.362422 -22.101302)
		(end 399.362422 -22.555454)
		(width 0.4572)
		(layer "F.Cu")
		(net "P3V3_AUX")
	)
	(segment
		(start 359.385362 -118.743476)
		(end 359.385362 -119.35587)
		(width 0.4572)
		(layer "F.Cu")
		(net "P3V3_AUX")
	)
	(segment
		(start 207.428592 -350.712532)
		(end 206.793592 -350.712532)
		(width 0.4572)
		(layer "F.Cu")
		(net "P3V3_AUX")
	)
	(segment
		(start 319.191386 -95.123254)
		(end 319.191386 -96.411542)
		(width 0.4572)
		(layer "F.Cu")
		(net "P3V3_AUX")
	)
	(segment
		(start 98.9838 -390.3726)
		(end 98.0948 -390.3726)
		(width 0.4572)
		(layer "F.Cu")
		(net "P3V3_AUX")
	)
	(segment
		(start 181.026816 -176.966372)
		(end 181.1528 -176.966372)
		(width 0.3556)
		(layer "F.Cu")
		(net "P3V3_AUX")
	)
	(segment
		(start 368.875056 -48.753014)
		(end 369.850416 -48.753014)
		(width 0.254)
		(layer "F.Cu")
		(net "P3V3_AUX")
	)
	(segment
		(start 218.599512 -231.816656)
		(end 218.599512 -232.72242)
		(width 0.4572)
		(layer "F.Cu")
		(net "P3V3_AUX")
	)
	(segment
		(start 214.448136 -179.194206)
		(end 214.829136 -179.194206)
		(width 0.4572)
		(layer "F.Cu")
		(net "P3V3_AUX")
	)
	(segment
		(start 205.957932 -255.799082)
		(end 210.456272 -255.799082)
		(width 0.4572)
		(layer "F.Cu")
		(net "P3V3_AUX")
	)
	(segment
		(start 446.8749 -48.753014)
		(end 447.85026 -48.753014)
		(width 0.254)
		(layer "F.Cu")
		(net "P3V3_AUX")
	)
	(segment
		(start 238.385604 -184.7723)
		(end 238.385604 -182.855362)
		(width 0.4572)
		(layer "F.Cu")
		(net "P3V3_AUX")
	)
	(segment
		(start 335.64195 -170.053)
		(end 335.026 -170.053)
		(width 0.4572)
		(layer "F.Cu")
		(net "P3V3_AUX")
	)
	(segment
		(start 73.445878 -47.193962)
		(end 73.172828 -47.193962)
		(width 0.254)
		(layer "F.Cu")
		(net "P3V3_AUX")
	)
	(segment
		(start 283.461206 -169.23385)
		(end 283.34335 -169.351706)
		(width 0.4572)
		(layer "F.Cu")
		(net "P3V3_AUX")
	)
	(segment
		(start 335.64195 -146.939)
		(end 335.026 -146.939)
		(width 0.4572)
		(layer "F.Cu")
		(net "P3V3_AUX")
	)
	(segment
		(start 350.119696 -149.96795)
		(end 350.647 -149.96795)
		(width 0.4572)
		(layer "F.Cu")
		(net "P3V3_AUX")
	)
	(segment
		(start 162.675062 -48.753014)
		(end 163.650422 -48.753014)
		(width 0.254)
		(layer "F.Cu")
		(net "P3V3_AUX")
	)
	(segment
		(start 101.530404 -119.77624)
		(end 100.91801 -119.77624)
		(width 0.4572)
		(layer "F.Cu")
		(net "P3V3_AUX")
	)
	(segment
		(start 201.091546 -112.39754)
		(end 201.091546 -113.41354)
		(width 0.4064)
		(layer "F.Cu")
		(net "P3V3_AUX")
	)
	(segment
		(start 211.400136 -182.013606)
		(end 210.765136 -182.013606)
		(width 0.4572)
		(layer "F.Cu")
		(net "P3V3_AUX")
	)
	(segment
		(start 362.30814 -90.065098)
		(end 363.098588 -90.065098)
		(width 0.3048)
		(layer "F.Cu")
		(net "P3V3_AUX")
	)
	(segment
		(start 120.391936 -36.286948)
		(end 120.33758 -36.232592)
		(width 0.4572)
		(layer "F.Cu")
		(net "P3V3_AUX")
	)
	(segment
		(start 329.87488 -205.20152)
		(end 328.962004 -205.20152)
		(width 0.4572)
		(layer "F.Cu")
		(net "P3V3_AUX")
	)
	(segment
		(start 325.83882 -292.122098)
		(end 325.20382 -292.122098)
		(width 0.4572)
		(layer "F.Cu")
		(net "P3V3_AUX")
	)
	(segment
		(start 213.330282 -223.382586)
		(end 212.713316 -223.382586)
		(width 0.3048)
		(layer "F.Cu")
		(net "P3V3_AUX")
	)
	(segment
		(start 333.730346 -119.77624)
		(end 333.117952 -119.77624)
		(width 0.4572)
		(layer "F.Cu")
		(net "P3V3_AUX")
	)
	(segment
		(start 386.66039 -117.7544)
		(end 385.77012 -117.7544)
		(width 0.4064)
		(layer "F.Cu")
		(net "P3V3_AUX")
	)
	(segment
		(start 88.456262 -94.572836)
		(end 86.991444 -96.037654)
		(width 0.4572)
		(layer "F.Cu")
		(net "P3V3_AUX")
	)
	(segment
		(start 405.247348 -36.286948)
		(end 404.591774 -36.286948)
		(width 0.4572)
		(layer "F.Cu")
		(net "P3V3_AUX")
	)
	(segment
		(start 364.390432 -91.356942)
		(end 364.390432 -92.096336)
		(width 0.4572)
		(layer "F.Cu")
		(net "P3V3_AUX")
	)
	(segment
		(start 279.372822 -47.193962)
		(end 278.774906 -47.791878)
		(width 0.254)
		(layer "F.Cu")
		(net "P3V3_AUX")
	)
	(segment
		(start 440.41695 -292.122098)
		(end 441.303918 -292.122098)
		(width 0.4572)
		(layer "F.Cu")
		(net "P3V3_AUX")
	)
	(segment
		(start 241.624612 -63.017908)
		(end 241.624612 -63.648082)
		(width 0.4572)
		(layer "F.Cu")
		(net "P3V3_AUX")
	)
	(segment
		(start 210.419442 -242.955826)
		(end 211.030566 -242.344702)
		(width 0.4572)
		(layer "F.Cu")
		(net "P3V3_AUX")
	)
	(segment
		(start 219.94368 -47.92091)
		(end 219.610178 -47.92091)
		(width 0.254)
		(layer "F.Cu")
		(net "P3V3_AUX")
	)
	(segment
		(start 353.882452 -36.286948)
		(end 353.247452 -36.286948)
		(width 0.4572)
		(layer "F.Cu")
		(net "P3V3_AUX")
	)
	(segment
		(start 406.609042 -26.03373)
		(end 405.949912 -26.03373)
		(width 0.4572)
		(layer "F.Cu")
		(net "P3V3_AUX")
	)
	(segment
		(start 214.03818 -222.378778)
		(end 213.961218 -222.45574)
		(width 0.3048)
		(layer "F.Cu")
		(net "P3V3_AUX")
	)
	(segment
		(start 188.67501 -48.753014)
		(end 189.65037 -48.753014)
		(width 0.254)
		(layer "F.Cu")
		(net "P3V3_AUX")
	)
	(segment
		(start 308.807104 -84.092288)
		(end 309.24246 -83.656932)
		(width 0.4064)
		(layer "F.Cu")
		(net "P3V3_AUX")
	)
	(segment
		(start 229.929944 -242.82781)
		(end 229.554786 -242.452652)
		(width 0.4572)
		(layer "F.Cu")
		(net "P3V3_AUX")
	)
	(segment
		(start 336.843624 -42.84091)
		(end 337.514946 -42.84091)
		(width 0.254)
		(layer "F.Cu")
		(net "P3V3_AUX")
	)
	(segment
		(start 451.638416 -374.071642)
		(end 451.638416 -373.453406)
		(width 0.4572)
		(layer "F.Cu")
		(net "P3V3_AUX")
	)
	(segment
		(start 215.81872 -175.816006)
		(end 215.81872 -176.476406)
		(width 0.4572)
		(layer "F.Cu")
		(net "P3V3_AUX")
	)
	(segment
		(start 103.458264 -189.30112)
		(end 103.458264 -188.573664)
		(width 0.2794)
		(layer "F.Cu")
		(net "P3V3_AUX")
	)
	(segment
		(start 205.777592 -349.912432)
		(end 205.777592 -349.220536)
		(width 0.4572)
		(layer "F.Cu")
		(net "P3V3_AUX")
	)
	(segment
		(start 229.594664 -205.945486)
		(end 229.594664 -206.62011)
		(width 0.4572)
		(layer "F.Cu")
		(net "P3V3_AUX")
	)
	(segment
		(start 5.04317 -35.296348)
		(end 5.04317 -35.905948)
		(width 0.4572)
		(layer "F.Cu")
		(net "P3V3_AUX")
	)
	(segment
		(start 77.843634 -47.92091)
		(end 77.510132 -47.92091)
		(width 0.254)
		(layer "F.Cu")
		(net "P3V3_AUX")
	)
	(segment
		(start 383.55905 -212.344)
		(end 383.55905 -211.880196)
		(width 0.4572)
		(layer "F.Cu")
		(net "P3V3_AUX")
	)
	(segment
		(start 120.708928 -88.39073)
		(end 120.09374 -88.39073)
		(width 0.4572)
		(layer "F.Cu")
		(net "P3V3_AUX")
	)
	(segment
		(start 336.043524 -47.92091)
		(end 335.710022 -47.92091)
		(width 0.254)
		(layer "F.Cu")
		(net "P3V3_AUX")
	)
	(segment
		(start 142.705328 -189.778132)
		(end 144.106646 -189.778132)
		(width 0.3556)
		(layer "F.Cu")
		(net "P3V3_AUX")
	)
	(segment
		(start 316.256162 -61.487812)
		(end 316.886336 -61.487812)
		(width 0.4572)
		(layer "F.Cu")
		(net "P3V3_AUX")
	)
	(segment
		(start 404.52929 -117.5512)
		(end 404.52929 -117.89156)
		(width 0.4064)
		(layer "F.Cu")
		(net "P3V3_AUX")
	)
	(segment
		(start 321.848988 -226.698302)
		(end 321.251326 -227.295964)
		(width 0.3048)
		(layer "F.Cu")
		(net "P3V3_AUX")
	)
	(segment
		(start 373.810276 -47.92091)
		(end 373.608346 -47.71898)
		(width 0.254)
		(layer "F.Cu")
		(net "P3V3_AUX")
	)
	(segment
		(start 375.912634 -86.5378)
		(end 375.297446 -86.5378)
		(width 0.4572)
		(layer "F.Cu")
		(net "P3V3_AUX")
	)
	(segment
		(start 200.734676 -91.526614)
		(end 201.176636 -91.968574)
		(width 0.4572)
		(layer "F.Cu")
		(net "P3V3_AUX")
	)
	(segment
		(start 82.237326 -36.232592)
		(end 81.395062 -36.232592)
		(width 0.4572)
		(layer "F.Cu")
		(net "P3V3_AUX")
	)
	(segment
		(start 324.271386 -97.821242)
		(end 324.271386 -97.211642)
		(width 0.4572)
		(layer "F.Cu")
		(net "P3V3_AUX")
	)
	(segment
		(start 228.267768 -215.904064)
		(end 227.867972 -215.504268)
		(width 0.381)
		(layer "F.Cu")
		(net "P3V3_AUX")
	)
	(segment
		(start 17.650714 -147.913344)
		(end 17.918684 -147.913344)
		(width 0.254)
		(layer "F.Cu")
		(net "P3V3_AUX")
	)
	(segment
		(start 219.223844 -95.73895)
		(end 219.223844 -95.123)
		(width 0.4572)
		(layer "F.Cu")
		(net "P3V3_AUX")
	)
	(segment
		(start 208.27365 -215.192102)
		(end 208.27365 -215.536526)
		(width 0.3048)
		(layer "F.Cu")
		(net "P3V3_AUX")
	)
	(segment
		(start 193.162428 -22.555454)
		(end 193.81851 -22.555454)
		(width 0.4572)
		(layer "F.Cu")
		(net "P3V3_AUX")
	)
	(segment
		(start 242.000786 -203.005182)
		(end 242.000786 -201.29627)
		(width 0.4572)
		(layer "F.Cu")
		(net "P3V3_AUX")
	)
	(segment
		(start 63.27775 -116.550186)
		(end 63.27775 -116.229638)
		(width 0.4572)
		(layer "F.Cu")
		(net "P3V3_AUX")
	)
	(segment
		(start 244.671596 -178.919378)
		(end 245.306596 -179.554378)
		(width 0.4572)
		(layer "F.Cu")
		(net "P3V3_AUX")
	)
	(segment
		(start 139.385294 -93.528642)
		(end 140.090144 -93.528642)
		(width 0.4572)
		(layer "F.Cu")
		(net "P3V3_AUX")
	)
	(segment
		(start 378.53747 -36.232592)
		(end 377.695206 -36.232592)
		(width 0.4572)
		(layer "F.Cu")
		(net "P3V3_AUX")
	)
	(segment
		(start 174.4091 -26.03373)
		(end 173.74997 -26.03373)
		(width 0.4572)
		(layer "F.Cu")
		(net "P3V3_AUX")
	)
	(segment
		(start 427.952662 -89.1159)
		(end 427.534578 -88.697816)
		(width 0.381)
		(layer "F.Cu")
		(net "P3V3_AUX")
	)
	(segment
		(start 440.371484 -97.821242)
		(end 440.371484 -97.211642)
		(width 0.4572)
		(layer "F.Cu")
		(net "P3V3_AUX")
	)
	(segment
		(start 103.30815 -47.71898)
		(end 103.30815 -47.403766)
		(width 0.254)
		(layer "F.Cu")
		(net "P3V3_AUX")
	)
	(segment
		(start 258.84378 -44.87291)
		(end 259.515102 -44.87291)
		(width 0.254)
		(layer "F.Cu")
		(net "P3V3_AUX")
	)
	(segment
		(start 380.85395 -208.534)
		(end 380.097538 -208.534)
		(width 0.4572)
		(layer "F.Cu")
		(net "P3V3_AUX")
	)
	(segment
		(start 204.191108 -84.675472)
		(end 203.207366 -84.675472)
		(width 0.4572)
		(layer "F.Cu")
		(net "P3V3_AUX")
	)
	(segment
		(start 232.244646 -275.503386)
		(end 232.854246 -275.503386)
		(width 0.4572)
		(layer "F.Cu")
		(net "P3V3_AUX")
	)
	(segment
		(start 334.518 -239.03305)
		(end 334.207866 -239.343184)
		(width 0.4572)
		(layer "F.Cu")
		(net "P3V3_AUX")
	)
	(segment
		(start 77.560424 -20.789392)
		(end 77.560424 -21.603208)
		(width 0.4572)
		(layer "F.Cu")
		(net "P3V3_AUX")
	)
	(segment
		(start 349.426276 -40.82161)
		(end 349.276162 -40.971724)
		(width 0.4572)
		(layer "F.Cu")
		(net "P3V3_AUX")
	)
	(segment
		(start 226.055174 -35.876738)
		(end 225.29927 -35.876738)
		(width 0.4572)
		(layer "F.Cu")
		(net "P3V3_AUX")
	)
	(segment
		(start 213.868 -227.65258)
		(end 214.078058 -227.442522)
		(width 0.4572)
		(layer "F.Cu")
		(net "P3V3_AUX")
	)
	(segment
		(start 224.422208 -78.579472)
		(end 225.041206 -78.579472)
		(width 0.4572)
		(layer "F.Cu")
		(net "P3V3_AUX")
	)
	(segment
		(start 405.003 -384.06705)
		(end 404.34895 -384.06705)
		(width 0.4572)
		(layer "F.Cu")
		(net "P3V3_AUX")
	)
	(segment
		(start 363.098588 -90.065098)
		(end 363.470444 -90.436954)
		(width 0.3048)
		(layer "F.Cu")
		(net "P3V3_AUX")
	)
	(segment
		(start 231.08539 -205.937612)
		(end 230.699564 -205.00594)
		(width 0.381)
		(layer "F.Cu")
		(net "P3V3_AUX")
	)
	(segment
		(start 358.75595 -191.262)
		(end 358.14 -191.262)
		(width 0.4572)
		(layer "F.Cu")
		(net "P3V3_AUX")
	)
	(segment
		(start 447.472816 -47.193962)
		(end 446.8749 -47.791878)
		(width 0.254)
		(layer "F.Cu")
		(net "P3V3_AUX")
	)
	(segment
		(start 399.860516 -21.603208)
		(end 399.362422 -22.101302)
		(width 0.4572)
		(layer "F.Cu")
		(net "P3V3_AUX")
	)
	(segment
		(start 167.408352 -47.71898)
		(end 167.408352 -47.403766)
		(width 0.254)
		(layer "F.Cu")
		(net "P3V3_AUX")
	)
	(segment
		(start 277.281894 -386.498592)
		(end 277.281894 -387.137656)
		(width 0.4318)
		(layer "F.Cu")
		(net "P3V3_AUX")
	)
	(segment
		(start 139.385294 -87.813642)
		(end 140.090144 -87.813642)
		(width 0.4572)
		(layer "F.Cu")
		(net "P3V3_AUX")
	)
	(segment
		(start 220.631512 -231.816656)
		(end 220.631512 -232.841292)
		(width 0.4572)
		(layer "F.Cu")
		(net "P3V3_AUX")
	)
	(segment
		(start 258.642612 -212.765386)
		(end 259.258562 -212.765386)
		(width 0.4572)
		(layer "F.Cu")
		(net "P3V3_AUX")
	)
	(segment
		(start 361.542584 -379.655324)
		(end 360.902758 -379.655324)
		(width 0.4572)
		(layer "F.Cu")
		(net "P3V3_AUX")
	)
	(segment
		(start 362.29036 -258.131564)
		(end 362.89996 -258.131564)
		(width 0.381)
		(layer "F.Cu")
		(net "P3V3_AUX")
	)
	(segment
		(start 396.609316 -80.356202)
		(end 397.224758 -80.356202)
		(width 0.4572)
		(layer "F.Cu")
		(net "P3V3_AUX")
	)
	(segment
		(start 255.701546 -207.51165)
		(end 254.685546 -207.51165)
		(width 0.4572)
		(layer "F.Cu")
		(net "P3V3_AUX")
	)
	(segment
		(start 197.039484 -137.645648)
		(end 197.039484 -136.98601)
		(width 0.4064)
		(layer "F.Cu")
		(net "P3V3_AUX")
	)
	(segment
		(start 279.63368 -408.165046)
		(end 279.841198 -407.957528)
		(width 0.4572)
		(layer "F.Cu")
		(net "P3V3_AUX")
	)
	(segment
		(start 420.155116 -35.876738)
		(end 419.399212 -35.876738)
		(width 0.4572)
		(layer "F.Cu")
		(net "P3V3_AUX")
	)
	(segment
		(start 97.282 -392.0998)
		(end 97.0026 -392.3792)
		(width 0.4572)
		(layer "F.Cu")
		(net "P3V3_AUX")
	)
	(segment
		(start 179.746402 -177.711862)
		(end 180.281326 -177.711862)
		(width 0.3556)
		(layer "F.Cu")
		(net "P3V3_AUX")
	)
	(segment
		(start 130.090164 -254.194564)
		(end 130.699764 -254.194564)
		(width 0.381)
		(layer "F.Cu")
		(net "P3V3_AUX")
	)
	(segment
		(start 174.15637 -61.487812)
		(end 174.786544 -61.487812)
		(width 0.4572)
		(layer "F.Cu")
		(net "P3V3_AUX")
	)
	(segment
		(start 316.508892 -26.03373)
		(end 315.849762 -26.03373)
		(width 0.4572)
		(layer "F.Cu")
		(net "P3V3_AUX")
	)
	(segment
		(start 425.36237 -22.101302)
		(end 425.36237 -22.555454)
		(width 0.4572)
		(layer "F.Cu")
		(net "P3V3_AUX")
	)
	(segment
		(start 380.034038 -4.836922)
		(end 380.649734 -4.836922)
		(width 0.4572)
		(layer "F.Cu")
		(net "P3V3_AUX")
	)
	(segment
		(start 310.843676 -42.84091)
		(end 311.514998 -42.84091)
		(width 0.254)
		(layer "F.Cu")
		(net "P3V3_AUX")
	)
	(segment
		(start 375.912634 -87.6808)
		(end 375.297446 -87.6808)
		(width 0.4572)
		(layer "F.Cu")
		(net "P3V3_AUX")
	)
	(segment
		(start 337.693 -241.406172)
		(end 337.693 -240.808002)
		(width 0.3556)
		(layer "F.Cu")
		(net "P3V3_AUX")
	)
	(segment
		(start 233.326178 -40.13581)
		(end 233.326178 -40.82161)
		(width 0.4572)
		(layer "F.Cu")
		(net "P3V3_AUX")
	)
	(segment
		(start 373.362474 -22.555454)
		(end 374.018556 -22.555454)
		(width 0.4572)
		(layer "F.Cu")
		(net "P3V3_AUX")
	)
	(segment
		(start 229.437438 -68.399914)
		(end 228.128576 -68.399914)
		(width 0.3556)
		(layer "F.Cu")
		(net "P3V3_AUX")
	)
	(segment
		(start 80.602582 -89.1159)
		(end 79.801974 -89.1159)
		(width 0.381)
		(layer "F.Cu")
		(net "P3V3_AUX")
	)
	(segment
		(start 210.008216 -225.340164)
		(end 210.008216 -225.594164)
		(width 0.4064)
		(layer "F.Cu")
		(net "P3V3_AUX")
	)
	(segment
		(start 304.774854 -48.753014)
		(end 305.750214 -48.753014)
		(width 0.254)
		(layer "F.Cu")
		(net "P3V3_AUX")
	)
	(segment
		(start 193.4083 -47.71898)
		(end 193.4083 -47.403766)
		(width 0.254)
		(layer "F.Cu")
		(net "P3V3_AUX")
	)
	(segment
		(start 390.685782 -90.056462)
		(end 390.685782 -89.421462)
		(width 0.4572)
		(layer "F.Cu")
		(net "P3V3_AUX")
	)
	(segment
		(start 284.043628 -47.92091)
		(end 283.710126 -47.92091)
		(width 0.254)
		(layer "F.Cu")
		(net "P3V3_AUX")
	)
	(segment
		(start 193.660522 -21.603208)
		(end 193.162428 -22.101302)
		(width 0.4572)
		(layer "F.Cu")
		(net "P3V3_AUX")
	)
	(segment
		(start 221.415102 -42.84091)
		(end 220.74378 -42.84091)
		(width 0.254)
		(layer "F.Cu")
		(net "P3V3_AUX")
	)
	(segment
		(start 399.561304 -169.23385)
		(end 399.561304 -168.634664)
		(width 0.4572)
		(layer "F.Cu")
		(net "P3V3_AUX")
	)
	(segment
		(start 401.938998 -85.20557)
		(end 400.717512 -85.20557)
		(width 0.4572)
		(layer "F.Cu")
		(net "P3V3_AUX")
	)
	(segment
		(start 173.047406 -36.286948)
		(end 172.391832 -36.286948)
		(width 0.4572)
		(layer "F.Cu")
		(net "P3V3_AUX")
	)
	(segment
		(start 358.75595 -178.054)
		(end 358.14 -178.054)
		(width 0.4572)
		(layer "F.Cu")
		(net "P3V3_AUX")
	)
	(segment
		(start 462.865724 -273.59483)
		(end 463.537046 -273.59483)
		(width 0.4572)
		(layer "F.Cu")
		(net "P3V3_AUX")
	)
	(segment
		(start 230.66756 -222.304102)
		(end 231.067356 -222.703898)
		(width 0.381)
		(layer "F.Cu")
		(net "P3V3_AUX")
	)
	(segment
		(start 204.191108 -88.573356)
		(end 203.770992 -88.993472)
		(width 0.4572)
		(layer "F.Cu")
		(net "P3V3_AUX")
	)
	(segment
		(start 213.50859 -222.45574)
		(end 213.419436 -222.366586)
		(width 0.3048)
		(layer "F.Cu")
		(net "P3V3_AUX")
	)
	(segment
		(start 340.961472 -189.40145)
		(end 341.571072 -189.40145)
		(width 0.4572)
		(layer "F.Cu")
		(net "P3V3_AUX")
	)
	(segment
		(start 224.54743 -191.591438)
		(end 223.527112 -192.611756)
		(width 0.3556)
		(layer "F.Cu")
		(net "P3V3_AUX")
	)
	(segment
		(start 47.17288 -47.193962)
		(end 47.44593 -47.193962)
		(width 0.254)
		(layer "F.Cu")
		(net "P3V3_AUX")
	)
	(segment
		(start 243.035582 -280.10104)
		(end 242.425982 -280.10104)
		(width 0.4572)
		(layer "F.Cu")
		(net "P3V3_AUX")
	)
	(segment
		(start 6.644894 -72.90689)
		(end 6.763766 -73.025762)
		(width 0.4572)
		(layer "F.Cu")
		(net "P3V3_AUX")
	)
	(segment
		(start 320.019934 -288.830766)
		(end 320.019934 -288.378138)
		(width 0.4572)
		(layer "F.Cu")
		(net "P3V3_AUX")
	)
	(segment
		(start 56.28005 -139.6492)
		(end 56.9468 -139.6492)
		(width 0.4572)
		(layer "F.Cu")
		(net "P3V3_AUX")
	)
	(segment
		(start 63.27775 -116.229638)
		(end 63.585344 -115.922044)
		(width 0.4572)
		(layer "F.Cu")
		(net "P3V3_AUX")
	)
	(segment
		(start 397.959326 -167.202866)
		(end 398.433036 -167.202866)
		(width 0.381)
		(layer "F.Cu")
		(net "P3V3_AUX")
	)
	(segment
		(start 322.146676 -83.261454)
		(end 320.770504 -83.261454)
		(width 0.4572)
		(layer "F.Cu")
		(net "P3V3_AUX")
	)
	(segment
		(start 358.75595 -188.214)
		(end 358.14 -188.214)
		(width 0.4572)
		(layer "F.Cu")
		(net "P3V3_AUX")
	)
	(segment
		(start 163.272978 -47.193962)
		(end 162.675062 -47.791878)
		(width 0.254)
		(layer "F.Cu")
		(net "P3V3_AUX")
	)
	(segment
		(start 204.191108 -82.643472)
		(end 204.191108 -81.627472)
		(width 0.4572)
		(layer "F.Cu")
		(net "P3V3_AUX")
	)
	(segment
		(start 137.273538 -47.193962)
		(end 136.675114 -47.792386)
		(width 0.254)
		(layer "F.Cu")
		(net "P3V3_AUX")
	)
	(segment
		(start 222.130874 -50.927)
		(end 222.130874 -51.327812)
		(width 0.4572)
		(layer "F.Cu")
		(net "P3V3_AUX")
	)
	(segment
		(start 244.264434 -251.159772)
		(end 244.264434 -251.857256)
		(width 0.4572)
		(layer "F.Cu")
		(net "P3V3_AUX")
	)
	(segment
		(start 209.87893 -243.616226)
		(end 210.419442 -243.616226)
		(width 0.4572)
		(layer "F.Cu")
		(net "P3V3_AUX")
	)
	(segment
		(start 404.52929 -117.89156)
		(end 404.226522 -118.194328)
		(width 0.4064)
		(layer "F.Cu")
		(net "P3V3_AUX")
	)
	(segment
		(start 120.73509 -93.748606)
		(end 120.119902 -93.748606)
		(width 0.4572)
		(layer "F.Cu")
		(net "P3V3_AUX")
	)
	(segment
		(start 212.422994 -222.799402)
		(end 212.422994 -223.128332)
		(width 0.4572)
		(layer "F.Cu")
		(net "P3V3_AUX")
	)
	(segment
		(start 24.024844 -259.378958)
		(end 24.024844 -260.0706)
		(width 0.4572)
		(layer "F.Cu")
		(net "P3V3_AUX")
	)
	(segment
		(start 352.537522 -36.232592)
		(end 351.695258 -36.232592)
		(width 0.4572)
		(layer "F.Cu")
		(net "P3V3_AUX")
	)
	(segment
		(start 335.541112 -244.284246)
		(end 334.943704 -244.284246)
		(width 0.4572)
		(layer "F.Cu")
		(net "P3V3_AUX")
	)
	(segment
		(start 363.07395 -206.883)
		(end 362.458 -206.883)
		(width 0.4572)
		(layer "F.Cu")
		(net "P3V3_AUX")
	)
	(segment
		(start 369.961922 -241.54892)
		(end 369.961922 -240.57991)
		(width 0.3556)
		(layer "F.Cu")
		(net "P3V3_AUX")
	)
	(segment
		(start 45.855128 -35.876738)
		(end 45.099224 -35.876738)
		(width 0.4572)
		(layer "F.Cu")
		(net "P3V3_AUX")
	)
	(segment
		(start 334.943704 -244.284246)
		(end 334.899 -244.32895)
		(width 0.4572)
		(layer "F.Cu")
		(net "P3V3_AUX")
	)
	(segment
		(start 219.66047 -20.789392)
		(end 219.66047 -21.603208)
		(width 0.4572)
		(layer "F.Cu")
		(net "P3V3_AUX")
	)
	(segment
		(start 335.710022 -47.92091)
		(end 335.508092 -47.71898)
		(width 0.254)
		(layer "F.Cu")
		(net "P3V3_AUX")
	)
	(segment
		(start 203.478638 -82.767932)
		(end 203.603098 -82.643472)
		(width 0.4572)
		(layer "F.Cu")
		(net "P3V3_AUX")
	)
	(segment
		(start 210.419442 -243.616226)
		(end 210.419442 -242.955826)
		(width 0.4572)
		(layer "F.Cu")
		(net "P3V3_AUX")
	)
	(segment
		(start 98.95713 -219.559632)
		(end 98.193606 -219.559632)
		(width 0.381)
		(layer "F.Cu")
		(net "P3V3_AUX")
	)
	(segment
		(start 380.609094 -26.03373)
		(end 379.949964 -26.03373)
		(width 0.4572)
		(layer "F.Cu")
		(net "P3V3_AUX")
	)
	(segment
		(start 179.377594 -116.229638)
		(end 179.377594 -116.550186)
		(width 0.381)
		(layer "F.Cu")
		(net "P3V3_AUX")
	)
	(segment
		(start 212.919818 -210.174586)
		(end 212.919818 -210.574636)
		(width 0.4572)
		(layer "F.Cu")
		(net "P3V3_AUX")
	)
	(segment
		(start 238.509048 -26.03373)
		(end 237.849918 -26.03373)
		(width 0.4572)
		(layer "F.Cu")
		(net "P3V3_AUX")
	)
	(segment
		(start 356.25405 -179.578)
		(end 356.87 -179.578)
		(width 0.4572)
		(layer "F.Cu")
		(net "P3V3_AUX")
	)
	(segment
		(start 233.933746 -120.781318)
		(end 233.933746 -121.398792)
		(width 0.4572)
		(layer "F.Cu")
		(net "P3V3_AUX")
	)
	(segment
		(start 92.071444 -97.821242)
		(end 92.071444 -97.211642)
		(width 0.4572)
		(layer "F.Cu")
		(net "P3V3_AUX")
	)
	(segment
		(start 204.191108 -83.659472)
		(end 204.191108 -84.675472)
		(width 0.4572)
		(layer "F.Cu")
		(net "P3V3_AUX")
	)
	(segment
		(start 219.66047 -21.603208)
		(end 219.162376 -22.101302)
		(width 0.4572)
		(layer "F.Cu")
		(net "P3V3_AUX")
	)
	(segment
		(start 53.126132 -40.82161)
		(end 52.976018 -40.971724)
		(width 0.4572)
		(layer "F.Cu")
		(net "P3V3_AUX")
	)
	(segment
		(start 83.434174 -7.062724)
		(end 84.04987 -7.062724)
		(width 0.4572)
		(layer "F.Cu")
		(net "P3V3_AUX")
	)
	(segment
		(start 365.079788 -147.042378)
		(end 365.950754 -147.913344)
		(width 0.254)
		(layer "F.Cu")
		(net "P3V3_AUX")
	)
	(segment
		(start 6.763766 -74.322432)
		(end 6.763766 -75.087226)
		(width 0.4572)
		(layer "F.Cu")
		(net "P3V3_AUX")
	)
	(segment
		(start 140.124942 -259.378958)
		(end 140.124942 -260.0706)
		(width 0.4572)
		(layer "F.Cu")
		(net "P3V3_AUX")
	)
	(segment
		(start 275.710396 -414.4899)
		(end 275.710396 -413.773112)
		(width 0.4572)
		(layer "F.Cu")
		(net "P3V3_AUX")
	)
	(segment
		(start 248.494804 -275.503386)
		(end 249.104404 -275.503386)
		(width 0.4572)
		(layer "F.Cu")
		(net "P3V3_AUX")
	)
	(segment
		(start 260.6548 -23.361396)
		(end 260.6548 -23.970996)
		(width 0.4572)
		(layer "F.Cu")
		(net "P3V3_AUX")
	)
	(segment
		(start 142.768066 -52.035456)
		(end 143.423386 -52.035456)
		(width 0.254)
		(layer "F.Cu")
		(net "P3V3_AUX")
	)
	(segment
		(start 91.689428 -291.694616)
		(end 91.689428 -291.297868)
		(width 0.4572)
		(layer "F.Cu")
		(net "P3V3_AUX")
	)
	(segment
		(start 166.134288 -167.202866)
		(end 165.75913 -167.202866)
		(width 0.381)
		(layer "F.Cu")
		(net "P3V3_AUX")
	)
	(segment
		(start 208.249266 -351.533206)
		(end 208.249266 -355.989382)
		(width 0.4572)
		(layer "F.Cu")
		(net "P3V3_AUX")
	)
	(segment
		(start 339.773514 -241.736372)
		(end 339.773514 -243.682266)
		(width 0.3556)
		(layer "F.Cu")
		(net "P3V3_AUX")
	)
	(segment
		(start 257.553714 -345.653868)
		(end 256.939288 -345.653868)
		(width 0.4572)
		(layer "F.Cu")
		(net "P3V3_AUX")
	)
	(segment
		(start 211.610448 -209.966052)
		(end 206.784194 -209.966052)
		(width 0.4572)
		(layer "F.Cu")
		(net "P3V3_AUX")
	)
	(segment
		(start 365.33074 -261.122668)
		(end 365.33074 -259.858256)
		(width 0.3556)
		(layer "F.Cu")
		(net "P3V3_AUX")
	)
	(segment
		(start 335.64195 -173.101)
		(end 335.026 -173.101)
		(width 0.4572)
		(layer "F.Cu")
		(net "P3V3_AUX")
	)
	(segment
		(start 456.796902 -280.224484)
		(end 456.796902 -279.263348)
		(width 0.254)
		(layer "F.Cu")
		(net "P3V3_AUX")
	)
	(segment
		(start 427.19371 -83.532218)
		(end 427.199552 -83.526376)
		(width 0.4064)
		(layer "F.Cu")
		(net "P3V3_AUX")
	)
	(segment
		(start 236.492288 -97.658428)
		(end 236.492288 -98.295968)
		(width 0.254)
		(layer "F.Cu")
		(net "P3V3_AUX")
	)
	(segment
		(start 211.435442 -244.416326)
		(end 212.451442 -244.416326)
		(width 0.3048)
		(layer "F.Cu")
		(net "P3V3_AUX")
	)
	(segment
		(start 20.575016 -47.791878)
		(end 20.575016 -48.753014)
		(width 0.254)
		(layer "F.Cu")
		(net "P3V3_AUX")
	)
	(segment
		(start 414.280858 -180.699918)
		(end 413.5628 -180.699918)
		(width 0.4572)
		(layer "F.Cu")
		(net "P3V3_AUX")
	)
	(segment
		(start 374.50395 -192.25895)
		(end 373.761 -192.25895)
		(width 0.4572)
		(layer "F.Cu")
		(net "P3V3_AUX")
	)
	(segment
		(start 342.352884 -116.630704)
		(end 342.352884 -117.248178)
		(width 0.4572)
		(layer "F.Cu")
		(net "P3V3_AUX")
	)
	(segment
		(start 193.162428 -22.101302)
		(end 193.162428 -22.555454)
		(width 0.4572)
		(layer "F.Cu")
		(net "P3V3_AUX")
	)
	(segment
		(start 369.746022 -47.193962)
		(end 369.472972 -47.193962)
		(width 0.254)
		(layer "F.Cu")
		(net "P3V3_AUX")
	)
	(segment
		(start 223.813878 -190.283592)
		(end 224.109026 -190.57874)
		(width 0.4572)
		(layer "F.Cu")
		(net "P3V3_AUX")
	)
	(segment
		(start 330.774802 -47.791878)
		(end 330.774802 -48.753014)
		(width 0.254)
		(layer "F.Cu")
		(net "P3V3_AUX")
	)
	(segment
		(start 404.955248 -374.177052)
		(end 404.943056 -374.16486)
		(width 0.4572)
		(layer "F.Cu")
		(net "P3V3_AUX")
	)
	(segment
		(start 214.674958 -48.753014)
		(end 214.674958 -47.791878)
		(width 0.254)
		(layer "F.Cu")
		(net "P3V3_AUX")
	)
	(segment
		(start 349.000064 -149.851872)
		(end 350.003618 -149.851872)
		(width 0.4572)
		(layer "F.Cu")
		(net "P3V3_AUX")
	)
	(segment
		(start 257.710178 -47.92091)
		(end 257.508248 -47.71898)
		(width 0.254)
		(layer "F.Cu")
		(net "P3V3_AUX")
	)
	(segment
		(start 153.707338 -97.1804)
		(end 154.460194 -97.1804)
		(width 0.4064)
		(layer "F.Cu")
		(net "P3V3_AUX")
	)
	(segment
		(start 218.599512 -232.72242)
		(end 219.05976 -233.182668)
		(width 0.4572)
		(layer "F.Cu")
		(net "P3V3_AUX")
	)
	(segment
		(start 350.647 -185.01995)
		(end 351.38995 -185.01995)
		(width 0.4572)
		(layer "F.Cu")
		(net "P3V3_AUX")
	)
	(segment
		(start 368.418618 -241.15776)
		(end 368.809778 -241.54892)
		(width 0.4572)
		(layer "F.Cu")
		(net "P3V3_AUX")
	)
	(segment
		(start 244.221762 -178.919378)
		(end 244.671596 -178.919378)
		(width 0.4572)
		(layer "F.Cu")
		(net "P3V3_AUX")
	)
	(segment
		(start 224.422208 -80.611472)
		(end 225.041206 -80.611472)
		(width 0.4572)
		(layer "F.Cu")
		(net "P3V3_AUX")
	)
	(segment
		(start 219.425266 -122.758962)
		(end 218.812872 -122.758962)
		(width 0.4572)
		(layer "F.Cu")
		(net "P3V3_AUX")
	)
	(segment
		(start 124.796296 -167.086534)
		(end 124.808742 -167.074088)
		(width 0.3556)
		(layer "F.Cu")
		(net "P3V3_AUX")
	)
	(segment
		(start 277.795228 -401.937982)
		(end 278.443182 -401.937982)
		(width 0.4572)
		(layer "F.Cu")
		(net "P3V3_AUX")
	)
	(segment
		(start 242.425982 -279.139904)
		(end 242.425982 -280.10104)
		(width 0.254)
		(layer "F.Cu")
		(net "P3V3_AUX")
	)
	(segment
		(start 335.64195 -149.987)
		(end 335.026 -149.987)
		(width 0.4572)
		(layer "F.Cu")
		(net "P3V3_AUX")
	)
	(segment
		(start 204.191108 -87.977472)
		(end 204.191108 -88.573356)
		(width 0.4572)
		(layer "F.Cu")
		(net "P3V3_AUX")
	)
	(segment
		(start 105.8926 -9.139682)
		(end 105.8926 -8.4836)
		(width 0.4572)
		(layer "F.Cu")
		(net "P3V3_AUX")
	)
	(segment
		(start 382.665986 -202.398376)
		(end 382.14173 -202.398376)
		(width 0.4572)
		(layer "F.Cu")
		(net "P3V3_AUX")
	)
	(segment
		(start 7.649718 -157.812994)
		(end 7.032244 -157.812994)
		(width 0.4572)
		(layer "F.Cu")
		(net "P3V3_AUX")
	)
	(segment
		(start 314.314332 -140.534898)
		(end 313.40171 -140.534898)
		(width 0.4064)
		(layer "F.Cu")
		(net "P3V3_AUX")
	)
	(segment
		(start 53.126132 -40.13581)
		(end 53.126132 -40.82161)
		(width 0.4572)
		(layer "F.Cu")
		(net "P3V3_AUX")
	)
	(segment
		(start 368.875056 -47.791878)
		(end 368.875056 -48.753014)
		(width 0.254)
		(layer "F.Cu")
		(net "P3V3_AUX")
	)
	(segment
		(start 355.949758 -159.844994)
		(end 355.332284 -159.844994)
		(width 0.4572)
		(layer "F.Cu")
		(net "P3V3_AUX")
	)
	(segment
		(start 120.504712 -157.895544)
		(end 120.504712 -138.34872)
		(width 0.254)
		(layer "F.Cu")
		(net "P3V3_AUX")
	)
	(segment
		(start 120.73509 -96.034606)
		(end 120.119902 -96.034606)
		(width 0.4572)
		(layer "F.Cu")
		(net "P3V3_AUX")
	)
	(segment
		(start 232.428288 -97.658428)
		(end 232.428288 -98.295968)
		(width 0.254)
		(layer "F.Cu")
		(net "P3V3_AUX")
	)
	(segment
		(start 93.621098 -101.870764)
		(end 93.621098 -102.480364)
		(width 0.4572)
		(layer "F.Cu")
		(net "P3V3_AUX")
	)
	(segment
		(start 167.361108 -169.23385)
		(end 167.243252 -169.351706)
		(width 0.4572)
		(layer "F.Cu")
		(net "P3V3_AUX")
	)
	(segment
		(start 454.754742 -23.361396)
		(end 454.754742 -24.044402)
		(width 0.381)
		(layer "F.Cu")
		(net "P3V3_AUX")
	)
	(segment
		(start 224.422208 -82.643472)
		(end 225.032062 -82.643472)
		(width 0.4572)
		(layer "F.Cu")
		(net "P3V3_AUX")
	)
	(segment
		(start 325.612506 -195.218304)
		(end 325.002906 -195.218304)
		(width 0.4572)
		(layer "F.Cu")
		(net "P3V3_AUX")
	)
	(segment
		(start 219.162376 -22.555454)
		(end 219.818458 -22.555454)
		(width 0.4572)
		(layer "F.Cu")
		(net "P3V3_AUX")
	)
	(segment
		(start 144.126712 -189.758066)
		(end 144.126712 -190.53683)
		(width 0.4572)
		(layer "F.Cu")
		(net "P3V3_AUX")
	)
	(segment
		(start 309.262272 -22.101302)
		(end 309.262272 -22.555454)
		(width 0.4572)
		(layer "F.Cu")
		(net "P3V3_AUX")
	)
	(segment
		(start 427.534578 -88.697816)
		(end 427.534578 -88.248998)
		(width 0.381)
		(layer "F.Cu")
		(net "P3V3_AUX")
	)
	(segment
		(start 329.054714 -202.265534)
		(end 329.054714 -202.900534)
		(width 0.4572)
		(layer "F.Cu")
		(net "P3V3_AUX")
	)
	(segment
		(start 102.958138 -198.20128)
		(end 102.958138 -198.893938)
		(width 0.2794)
		(layer "F.Cu")
		(net "P3V3_AUX")
	)
	(segment
		(start 376.754898 -23.361396)
		(end 376.754898 -23.970996)
		(width 0.4572)
		(layer "F.Cu")
		(net "P3V3_AUX")
	)
	(segment
		(start 209.103976 -292.122098)
		(end 208.175352 -292.122098)
		(width 0.4572)
		(layer "F.Cu")
		(net "P3V3_AUX")
	)
	(segment
		(start 84.05622 -61.487812)
		(end 84.686394 -61.487812)
		(width 0.4572)
		(layer "F.Cu")
		(net "P3V3_AUX")
	)
	(segment
		(start 203.244704 -358.324658)
		(end 202.322684 -357.402638)
		(width 0.4572)
		(layer "F.Cu")
		(net "P3V3_AUX")
	)
	(segment
		(start 373.761 -181.08295)
		(end 373.233696 -181.08295)
		(width 0.4572)
		(layer "F.Cu")
		(net "P3V3_AUX")
	)
	(segment
		(start 322.057776 -94.428818)
		(end 321.787266 -94.158308)
		(width 0.4572)
		(layer "F.Cu")
		(net "P3V3_AUX")
	)
	(segment
		(start 193.453766 -83.532218)
		(end 192.793366 -83.532218)
		(width 0.4064)
		(layer "F.Cu")
		(net "P3V3_AUX")
	)
	(segment
		(start 451.860412 -21.603208)
		(end 451.362318 -22.101302)
		(width 0.4572)
		(layer "F.Cu")
		(net "P3V3_AUX")
	)
	(segment
		(start 263.782302 -36.286948)
		(end 263.147302 -36.286948)
		(width 0.4572)
		(layer "F.Cu")
		(net "P3V3_AUX")
	)
	(segment
		(start 315.147198 -36.286948)
		(end 314.491624 -36.286948)
		(width 0.4572)
		(layer "F.Cu")
		(net "P3V3_AUX")
	)
	(segment
		(start 242.000786 -201.07783)
		(end 241.42065 -200.497694)
		(width 0.4572)
		(layer "F.Cu")
		(net "P3V3_AUX")
	)
	(segment
		(start 256.224786 -259.378958)
		(end 256.224786 -260.0706)
		(width 0.4572)
		(layer "F.Cu")
		(net "P3V3_AUX")
	)
	(segment
		(start 16.02486 -410.248608)
		(end 15.380716 -410.248608)
		(width 0.4572)
		(layer "F.Cu")
		(net "P3V3_AUX")
	)
	(segment
		(start 283.82595 -86.106)
		(end 283.21 -86.106)
		(width 0.4572)
		(layer "F.Cu")
		(net "P3V3_AUX")
	)
	(segment
		(start 203.49845 -91.968574)
		(end 205.36281 -90.104214)
		(width 0.4572)
		(layer "F.Cu")
		(net "P3V3_AUX")
	)
	(segment
		(start 331.23505 -239.395)
		(end 331.192378 -239.437672)
		(width 0.3556)
		(layer "F.Cu")
		(net "P3V3_AUX")
	)
	(segment
		(start 256.939288 -345.653868)
		(end 256.775966 -345.490546)
		(width 0.4572)
		(layer "F.Cu")
		(net "P3V3_AUX")
	)
	(segment
		(start 225.867722 -216.704164)
		(end 225.467926 -216.304368)
		(width 0.381)
		(layer "F.Cu")
		(net "P3V3_AUX")
	)
	(segment
		(start 335.64195 -172.085)
		(end 335.026 -172.085)
		(width 0.4572)
		(layer "F.Cu")
		(net "P3V3_AUX")
	)
	(segment
		(start 230.869744 -204.04201)
		(end 231.499664 -204.04201)
		(width 0.381)
		(layer "F.Cu")
		(net "P3V3_AUX")
	)
	(segment
		(start 369.961922 -240.57991)
		(end 369.658138 -240.276126)
		(width 0.3556)
		(layer "F.Cu")
		(net "P3V3_AUX")
	)
	(segment
		(start 78.643734 -42.84091)
		(end 79.315056 -42.84091)
		(width 0.254)
		(layer "F.Cu")
		(net "P3V3_AUX")
	)
	(segment
		(start 350.003618 -161.662872)
		(end 349.000064 -161.662872)
		(width 0.4572)
		(layer "F.Cu")
		(net "P3V3_AUX")
	)
	(segment
		(start 169.22623 -40.13581)
		(end 169.22623 -40.82161)
		(width 0.4572)
		(layer "F.Cu")
		(net "P3V3_AUX")
	)
	(segment
		(start 226.77374 -278.541988)
		(end 226.175824 -279.139904)
		(width 0.254)
		(layer "F.Cu")
		(net "P3V3_AUX")
	)
	(segment
		(start 375.912888 -8.616442)
		(end 375.912888 -9.713976)
		(width 0.4572)
		(layer "F.Cu")
		(net "P3V3_AUX")
	)
	(segment
		(start 230.699564 -204.21219)
		(end 230.869744 -204.04201)
		(width 0.381)
		(layer "F.Cu")
		(net "P3V3_AUX")
	)
	(segment
		(start 332.512162 -237.271306)
		(end 332.512162 -237.885986)
		(width 0.4572)
		(layer "F.Cu")
		(net "P3V3_AUX")
	)
	(segment
		(start 388.398512 -242.056412)
		(end 389.109204 -242.056412)
		(width 0.2794)
		(layer "F.Cu")
		(net "P3V3_AUX")
	)
	(segment
		(start 297.944794 -197.991476)
		(end 297.944794 -198.001128)
		(width 0.3556)
		(layer "F.Cu")
		(net "P3V3_AUX")
	)
	(segment
		(start 211.400136 -184.702958)
		(end 211.400136 -182.013606)
		(width 0.3556)
		(layer "F.Cu")
		(net "P3V3_AUX")
	)
	(segment
		(start 11.726164 -277.814278)
		(end 11.116564 -277.814278)
		(width 0.4572)
		(layer "F.Cu")
		(net "P3V3_AUX")
	)
	(segment
		(start 400.098768 -180.372766)
		(end 400.098768 -179.728368)
		(width 0.4572)
		(layer "F.Cu")
		(net "P3V3_AUX")
	)
	(segment
		(start 52.643786 -44.87291)
		(end 53.315108 -44.87291)
		(width 0.254)
		(layer "F.Cu")
		(net "P3V3_AUX")
	)
	(segment
		(start 336.1182 -234.66425)
		(end 335.915 -234.46105)
		(width 0.4572)
		(layer "F.Cu")
		(net "P3V3_AUX")
	)
	(segment
		(start 355.513386 -139.376404)
		(end 354.858066 -139.376404)
		(width 0.4064)
		(layer "F.Cu")
		(net "P3V3_AUX")
	)
	(segment
		(start 363.314996 -379.85573)
		(end 363.314996 -379.088396)
		(width 0.4572)
		(layer "F.Cu")
		(net "P3V3_AUX")
	)
	(segment
		(start 201.091546 -113.41354)
		(end 201.091546 -114.42954)
		(width 0.4064)
		(layer "F.Cu")
		(net "P3V3_AUX")
	)
	(segment
		(start 299.659294 -85.44052)
		(end 299.659294 -86.132162)
		(width 0.4572)
		(layer "F.Cu")
		(net "P3V3_AUX")
	)
	(segment
		(start 218.326208 -85.810344)
		(end 217.422222 -85.810344)
		(width 0.4572)
		(layer "F.Cu")
		(net "P3V3_AUX")
	)
	(segment
		(start 139.385294 -91.242642)
		(end 140.090144 -91.242642)
		(width 0.4572)
		(layer "F.Cu")
		(net "P3V3_AUX")
	)
	(segment
		(start 83.434174 -4.014724)
		(end 84.04987 -4.014724)
		(width 0.4572)
		(layer "F.Cu")
		(net "P3V3_AUX")
	)
	(segment
		(start 173.682406 -36.286948)
		(end 173.047406 -36.286948)
		(width 0.4572)
		(layer "F.Cu")
		(net "P3V3_AUX")
	)
	(segment
		(start 462.865724 -275.62683)
		(end 463.475324 -275.62683)
		(width 0.4572)
		(layer "F.Cu")
		(net "P3V3_AUX")
	)
	(segment
		(start 206.15275 -210.597496)
		(end 205.422246 -211.328)
		(width 0.4572)
		(layer "F.Cu")
		(net "P3V3_AUX")
	)
	(segment
		(start 439.989468 -291.297868)
		(end 439.989468 -291.694616)
		(width 0.4572)
		(layer "F.Cu")
		(net "P3V3_AUX")
	)
	(segment
		(start 335.64195 -158.75)
		(end 335.026 -158.75)
		(width 0.4572)
		(layer "F.Cu")
		(net "P3V3_AUX")
	)
	(segment
		(start 247.322848 -182.794656)
		(end 247.322848 -183.404256)
		(width 0.4572)
		(layer "F.Cu")
		(net "P3V3_AUX")
	)
	(segment
		(start 350.119696 -173.08195)
		(end 350.647 -173.08195)
		(width 0.4572)
		(layer "F.Cu")
		(net "P3V3_AUX")
	)
	(segment
		(start 192.989708 -407.58364)
		(end 192.989708 -409.807918)
		(width 0.4572)
		(layer "F.Cu")
		(net "P3V3_AUX")
	)
	(segment
		(start 224.422208 -81.627472)
		(end 225.032062 -81.627472)
		(width 0.4572)
		(layer "F.Cu")
		(net "P3V3_AUX")
	)
	(segment
		(start 77.560424 -21.603208)
		(end 77.06233 -22.101302)
		(width 0.4572)
		(layer "F.Cu")
		(net "P3V3_AUX")
	)
	(segment
		(start 193.61023 -47.92091)
		(end 193.4083 -47.71898)
		(width 0.254)
		(layer "F.Cu")
		(net "P3V3_AUX")
	)
	(segment
		(start 256.775966 -345.490546)
		(end 256.775966 -344.916252)
		(width 0.4572)
		(layer "F.Cu")
		(net "P3V3_AUX")
	)
	(segment
		(start 399.323814 -168.397174)
		(end 399.323814 -167.742108)
		(width 0.4572)
		(layer "F.Cu")
		(net "P3V3_AUX")
	)
	(segment
		(start 147.682458 -36.286948)
		(end 147.047458 -36.286948)
		(width 0.4572)
		(layer "F.Cu")
		(net "P3V3_AUX")
	)
	(segment
		(start 194.767962 -52.035456)
		(end 195.423282 -52.035456)
		(width 0.254)
		(layer "F.Cu")
		(net "P3V3_AUX")
	)
	(segment
		(start 141.408404 -47.71898)
		(end 141.408404 -47.403766)
		(width 0.254)
		(layer "F.Cu")
		(net "P3V3_AUX")
	)
	(segment
		(start 120.73509 -97.177606)
		(end 120.119902 -97.177606)
		(width 0.4572)
		(layer "F.Cu")
		(net "P3V3_AUX")
	)
	(segment
		(start 204.191108 -80.611472)
		(end 204.191108 -79.595472)
		(width 0.4572)
		(layer "F.Cu")
		(net "P3V3_AUX")
	)
	(segment
		(start 384.904742 -140.85697)
		(end 384.374136 -140.326364)
		(width 0.4064)
		(layer "F.Cu")
		(net "P3V3_AUX")
	)
	(segment
		(start 208.259172 -221.218506)
		(end 208.259172 -222.723456)
		(width 0.4572)
		(layer "F.Cu")
		(net "P3V3_AUX")
	)
	(segment
		(start 283.99867 -180.372766)
		(end 283.99867 -179.728368)
		(width 0.4572)
		(layer "F.Cu")
		(net "P3V3_AUX")
	)
	(segment
		(start 206.793592 -351.43186)
		(end 206.704692 -351.52076)
		(width 0.4572)
		(layer "F.Cu")
		(net "P3V3_AUX")
	)
	(segment
		(start 441.835032 -288.830766)
		(end 441.200032 -288.830766)
		(width 0.4572)
		(layer "F.Cu")
		(net "P3V3_AUX")
	)
	(segment
		(start 331.372718 -47.193962)
		(end 330.774802 -47.791878)
		(width 0.254)
		(layer "F.Cu")
		(net "P3V3_AUX")
	)
	(segment
		(start 195.471034 -89.1159)
		(end 195.334382 -88.979248)
		(width 0.381)
		(layer "F.Cu")
		(net "P3V3_AUX")
	)
	(segment
		(start 38.36035 -117.7544)
		(end 37.47008 -117.7544)
		(width 0.4064)
		(layer "F.Cu")
		(net "P3V3_AUX")
	)
	(segment
		(start 426.943774 -44.87291)
		(end 427.615096 -44.87291)
		(width 0.254)
		(layer "F.Cu")
		(net "P3V3_AUX")
	)
	(segment
		(start 193.916808 -410.696918)
		(end 193.916808 -411.120844)
		(width 0.4572)
		(layer "F.Cu")
		(net "P3V3_AUX")
	)
	(segment
		(start 451.81012 -47.92091)
		(end 451.60819 -47.71898)
		(width 0.254)
		(layer "F.Cu")
		(net "P3V3_AUX")
	)
	(segment
		(start 73.172828 -47.193962)
		(end 72.574912 -47.791878)
		(width 0.254)
		(layer "F.Cu")
		(net "P3V3_AUX")
	)
	(segment
		(start 168.743884 -42.84091)
		(end 169.415206 -42.84091)
		(width 0.254)
		(layer "F.Cu")
		(net "P3V3_AUX")
	)
	(segment
		(start 239.906556 -80.451706)
		(end 239.906556 -80.941418)
		(width 0.4572)
		(layer "F.Cu")
		(net "P3V3_AUX")
	)
	(segment
		(start 211.346034 -214.448136)
		(end 211.346034 -215.557354)
		(width 0.254)
		(layer "F.Cu")
		(net "P3V3_AUX")
	)
	(segment
		(start 377.551696 -202.79995)
		(end 377.435618 -202.683872)
		(width 0.4572)
		(layer "F.Cu")
		(net "P3V3_AUX")
	)
	(segment
		(start 213.343236 -221.2848)
		(end 212.76437 -221.2848)
		(width 0.3048)
		(layer "F.Cu")
		(net "P3V3_AUX")
	)
	(segment
		(start 213.59622 -211.215732)
		(end 214.04834 -211.215732)
		(width 0.3556)
		(layer "F.Cu")
		(net "P3V3_AUX")
	)
	(segment
		(start 420.874952 -48.753014)
		(end 421.850312 -48.753014)
		(width 0.254)
		(layer "F.Cu")
		(net "P3V3_AUX")
	)
	(segment
		(start 340.961472 -192.44945)
		(end 341.571072 -192.44945)
		(width 0.4572)
		(layer "F.Cu")
		(net "P3V3_AUX")
	)
	(segment
		(start 72.574912 -47.791878)
		(end 72.574912 -48.753014)
		(width 0.254)
		(layer "F.Cu")
		(net "P3V3_AUX")
	)
	(segment
		(start 335.64195 -177.927)
		(end 335.026 -177.927)
		(width 0.4572)
		(layer "F.Cu")
		(net "P3V3_AUX")
	)
	(segment
		(start 117.226334 -40.13581)
		(end 117.226334 -40.82161)
		(width 0.4572)
		(layer "F.Cu")
		(net "P3V3_AUX")
	)
	(segment
		(start 142.743936 -44.87291)
		(end 143.415258 -44.87291)
		(width 0.254)
		(layer "F.Cu")
		(net "P3V3_AUX")
	)
	(segment
		(start 351.38995 -161.77895)
		(end 350.647 -161.77895)
		(width 0.4572)
		(layer "F.Cu")
		(net "P3V3_AUX")
	)
	(segment
		(start 398.972278 -167.742108)
		(end 399.323814 -167.742108)
		(width 0.381)
		(layer "F.Cu")
		(net "P3V3_AUX")
	)
	(segment
		(start 225.530664 -204.04201)
		(end 225.530664 -203.40701)
		(width 0.4572)
		(layer "F.Cu")
		(net "P3V3_AUX")
	)
	(segment
		(start 83.434174 -5.030724)
		(end 84.04987 -5.030724)
		(width 0.4572)
		(layer "F.Cu")
		(net "P3V3_AUX")
	)
	(segment
		(start 224.422208 -77.563472)
		(end 225.041206 -77.563472)
		(width 0.4572)
		(layer "F.Cu")
		(net "P3V3_AUX")
	)
	(segment
		(start 121.68251 -36.286948)
		(end 121.04751 -36.286948)
		(width 0.4572)
		(layer "F.Cu")
		(net "P3V3_AUX")
	)
	(segment
		(start 224.54743 -190.57874)
		(end 224.54743 -191.591438)
		(width 0.4572)
		(layer "F.Cu")
		(net "P3V3_AUX")
	)
	(segment
		(start 133.9088 -98.491802)
		(end 133.9088 -98.96729)
		(width 0.4572)
		(layer "F.Cu")
		(net "P3V3_AUX")
	)
	(segment
		(start 350.119696 -185.01995)
		(end 350.647 -185.01995)
		(width 0.4572)
		(layer "F.Cu")
		(net "P3V3_AUX")
	)
	(segment
		(start 20.901914 -414.369758)
		(end 20.901914 -414.985454)
		(width 0.4572)
		(layer "F.Cu")
		(net "P3V3_AUX")
	)
	(segment
		(start 216.226136 -179.194206)
		(end 214.829136 -179.194206)
		(width 0.4572)
		(layer "F.Cu")
		(net "P3V3_AUX")
	)
	(segment
		(start 340.961472 -187.36945)
		(end 341.571072 -187.36945)
		(width 0.4572)
		(layer "F.Cu")
		(net "P3V3_AUX")
	)
	(segment
		(start 237.561374 -172.96003)
		(end 236.832648 -172.96003)
		(width 0.4572)
		(layer "F.Cu")
		(net "P3V3_AUX")
	)
	(segment
		(start 326.629014 -232.297986)
		(end 326.263 -232.664)
		(width 0.4572)
		(layer "F.Cu")
		(net "P3V3_AUX")
	)
	(segment
		(start 6.763766 -73.025762)
		(end 6.763766 -74.322432)
		(width 0.4572)
		(layer "F.Cu")
		(net "P3V3_AUX")
	)
	(segment
		(start 210.445096 -226.158044)
		(end 210.475322 -226.18827)
		(width 0.4572)
		(layer "F.Cu")
		(net "P3V3_AUX")
	)
	(segment
		(start 245.129558 -238.66348)
		(end 244.537484 -239.255554)
		(width 0.4572)
		(layer "F.Cu")
		(net "P3V3_AUX")
	)
	(segment
		(start 106.698542 -5.747258)
		(end 107.308142 -5.747258)
		(width 0.4572)
		(layer "F.Cu")
		(net "P3V3_AUX")
	)
	(segment
		(start 350.003618 -149.851872)
		(end 350.119696 -149.96795)
		(width 0.4572)
		(layer "F.Cu")
		(net "P3V3_AUX")
	)
	(segment
		(start 441.938918 -292.122098)
		(end 441.303918 -292.122098)
		(width 0.4572)
		(layer "F.Cu")
		(net "P3V3_AUX")
	)
	(segment
		(start 376.819414 -8.29183)
		(end 376.2375 -8.29183)
		(width 0.4572)
		(layer "F.Cu")
		(net "P3V3_AUX")
	)
	(segment
		(start 17.191736 -152.3111)
		(end 17.191736 -151.696928)
		(width 0.4064)
		(layer "F.Cu")
		(net "P3V3_AUX")
	)
	(segment
		(start 196.702426 -89.1159)
		(end 195.471034 -89.1159)
		(width 0.381)
		(layer "F.Cu")
		(net "P3V3_AUX")
	)
	(segment
		(start 378.079 -202.79995)
		(end 377.551696 -202.79995)
		(width 0.4572)
		(layer "F.Cu")
		(net "P3V3_AUX")
	)
	(segment
		(start 46.574964 -48.753014)
		(end 46.574964 -47.791878)
		(width 0.254)
		(layer "F.Cu")
		(net "P3V3_AUX")
	)
	(segment
		(start 421.745918 -47.193962)
		(end 421.472868 -47.193962)
		(width 0.254)
		(layer "F.Cu")
		(net "P3V3_AUX")
	)
	(segment
		(start 236.832648 -172.96003)
		(end 236.832648 -174.558198)
		(width 0.4572)
		(layer "F.Cu")
		(net "P3V3_AUX")
	)
	(segment
		(start 335.64195 -164.973)
		(end 335.026 -164.973)
		(width 0.4572)
		(layer "F.Cu")
		(net "P3V3_AUX")
	)
	(segment
		(start 327.13295 -208.153)
		(end 326.413368 -208.153)
		(width 0.4572)
		(layer "F.Cu")
		(net "P3V3_AUX")
	)
	(segment
		(start 141.162532 -22.101302)
		(end 141.162532 -22.555454)
		(width 0.4572)
		(layer "F.Cu")
		(net "P3V3_AUX")
	)
	(segment
		(start 404.839678 -367.407952)
		(end 405.596344 -367.407952)
		(width 0.4572)
		(layer "F.Cu")
		(net "P3V3_AUX")
	)
	(segment
		(start 280.141426 -407.314908)
		(end 280.571448 -407.314908)
		(width 0.4572)
		(layer "F.Cu")
		(net "P3V3_AUX")
	)
	(segment
		(start 220.76791 -52.035456)
		(end 221.42323 -52.035456)
		(width 0.4572)
		(layer "F.Cu")
		(net "P3V3_AUX")
	)
	(segment
		(start 325.612506 -198.266304)
		(end 325.002906 -198.266304)
		(width 0.4572)
		(layer "F.Cu")
		(net "P3V3_AUX")
	)
	(segment
		(start 99.172776 -47.193962)
		(end 98.57486 -47.791878)
		(width 0.254)
		(layer "F.Cu")
		(net "P3V3_AUX")
	)
	(segment
		(start 360.25836 -256.226564)
		(end 360.86796 -256.226564)
		(width 0.381)
		(layer "F.Cu")
		(net "P3V3_AUX")
	)
	(segment
		(start 428.754794 -23.361396)
		(end 428.754794 -23.970996)
		(width 0.4572)
		(layer "F.Cu")
		(net "P3V3_AUX")
	)
	(segment
		(start 373.860568 -20.789392)
		(end 373.860568 -21.603208)
		(width 0.4572)
		(layer "F.Cu")
		(net "P3V3_AUX")
	)
	(segment
		(start 229.867714 -215.904064)
		(end 230.26751 -215.504268)
		(width 0.381)
		(layer "F.Cu")
		(net "P3V3_AUX")
	)
	(segment
		(start 370.571776 -153.1112)
		(end 370.571776 -153.782522)
		(width 0.4064)
		(layer "F.Cu")
		(net "P3V3_AUX")
	)
	(segment
		(start 220.848936 -176.826164)
		(end 220.705426 -176.969674)
		(width 0.4572)
		(layer "F.Cu")
		(net "P3V3_AUX")
	)
	(segment
		(start 51.062382 -22.555454)
		(end 51.062382 -22.101302)
		(width 0.4572)
		(layer "F.Cu")
		(net "P3V3_AUX")
	)
	(segment
		(start 212.76437 -221.2848)
		(end 212.698584 -221.350586)
		(width 0.3048)
		(layer "F.Cu")
		(net "P3V3_AUX")
	)
	(segment
		(start 458.452982 -116.630704)
		(end 458.452982 -117.248178)
		(width 0.4572)
		(layer "F.Cu")
		(net "P3V3_AUX")
	)
	(segment
		(start 172.329094 -118.016274)
		(end 172.080174 -118.265194)
		(width 0.4064)
		(layer "F.Cu")
		(net "P3V3_AUX")
	)
	(segment
		(start 335.64195 -169.037)
		(end 335.026 -169.037)
		(width 0.4572)
		(layer "F.Cu")
		(net "P3V3_AUX")
	)
	(segment
		(start 120.14962 -137.993628)
		(end 119.112284 -137.993628)
		(width 0.254)
		(layer "F.Cu")
		(net "P3V3_AUX")
	)
	(segment
		(start 431.882296 -36.286948)
		(end 431.247296 -36.286948)
		(width 0.4572)
		(layer "F.Cu")
		(net "P3V3_AUX")
	)
	(segment
		(start 356.25405 -165.608)
		(end 356.311962 -165.665912)
		(width 0.4572)
		(layer "F.Cu")
		(net "P3V3_AUX")
	)
	(segment
		(start 217.038936 -189.052454)
		(end 217.038936 -189.662054)
		(width 0.4572)
		(layer "F.Cu")
		(net "P3V3_AUX")
	)
	(segment
		(start 46.574964 -47.791878)
		(end 47.17288 -47.193962)
		(width 0.254)
		(layer "F.Cu")
		(net "P3V3_AUX")
	)
	(segment
		(start 372.324884 -259.378958)
		(end 372.324884 -260.0706)
		(width 0.4572)
		(layer "F.Cu")
		(net "P3V3_AUX")
	)
	(segment
		(start 213.330282 -224.398586)
		(end 213.330282 -223.382586)
		(width 0.4572)
		(layer "F.Cu")
		(net "P3V3_AUX")
	)
	(segment
		(start 363.470444 -90.436954)
		(end 364.390432 -91.356942)
		(width 0.4572)
		(layer "F.Cu")
		(net "P3V3_AUX")
	)
	(segment
		(start 313.764168 -158.219648)
		(end 313.139582 -158.219648)
		(width 0.4064)
		(layer "F.Cu")
		(net "P3V3_AUX")
	)
	(segment
		(start 242.589304 -199.354694)
		(end 241.981228 -198.746618)
		(width 0.4572)
		(layer "F.Cu")
		(net "P3V3_AUX")
	)
	(segment
		(start 325.39305 -232.440734)
		(end 325.39305 -232.156)
		(width 0.4572)
		(layer "F.Cu")
		(net "P3V3_AUX")
	)
	(segment
		(start 220.705426 -176.969674)
		(end 220.705426 -177.390552)
		(width 0.4572)
		(layer "F.Cu")
		(net "P3V3_AUX")
	)
	(segment
		(start 425.36237 -22.555454)
		(end 426.018452 -22.555454)
		(width 0.4572)
		(layer "F.Cu")
		(net "P3V3_AUX")
	)
	(segment
		(start 94.705678 -246.840248)
		(end 94.034356 -246.840248)
		(width 0.254)
		(layer "F.Cu")
		(net "P3V3_AUX")
	)
	(segment
		(start 122.409204 -26.03373)
		(end 121.750074 -26.03373)
		(width 0.4572)
		(layer "F.Cu")
		(net "P3V3_AUX")
	)
	(segment
		(start 214.194136 -179.448206)
		(end 214.448136 -179.194206)
		(width 0.4572)
		(layer "F.Cu")
		(net "P3V3_AUX")
	)
	(segment
		(start 445.54775 -236.4994)
		(end 444.8048 -236.4994)
		(width 0.4572)
		(layer "F.Cu")
		(net "P3V3_AUX")
	)
	(segment
		(start 218.614244 -178.09718)
		(end 217.979244 -178.09718)
		(width 0.4572)
		(layer "F.Cu")
		(net "P3V3_AUX")
	)
	(segment
		(start 376.53595 -188.849)
		(end 375.858786 -188.849)
		(width 0.4572)
		(layer "F.Cu")
		(net "P3V3_AUX")
	)
	(segment
		(start 358.75595 -185.166)
		(end 358.14 -185.166)
		(width 0.4572)
		(layer "F.Cu")
		(net "P3V3_AUX")
	)
	(segment
		(start 231.08539 -206.526384)
		(end 231.08539 -205.937612)
		(width 0.4572)
		(layer "F.Cu")
		(net "P3V3_AUX")
	)
	(segment
		(start 71.855076 -35.876738)
		(end 71.099172 -35.876738)
		(width 0.4572)
		(layer "F.Cu")
		(net "P3V3_AUX")
	)
	(segment
		(start 299.659294 -86.132162)
		(end 299.647864 -86.143592)
		(width 0.4572)
		(layer "F.Cu")
		(net "P3V3_AUX")
	)
	(segment
		(start 231.412288 -97.658428)
		(end 231.412288 -98.295968)
		(width 0.254)
		(layer "F.Cu")
		(net "P3V3_AUX")
	)
	(segment
		(start 227.04679 -278.541988)
		(end 226.77374 -278.541988)
		(width 0.254)
		(layer "F.Cu")
		(net "P3V3_AUX")
	)
	(segment
		(start 379.2474 -36.286948)
		(end 378.591826 -36.286948)
		(width 0.4572)
		(layer "F.Cu")
		(net "P3V3_AUX")
	)
	(segment
		(start 383.55905 -201.168)
		(end 383.55905 -201.505312)
		(width 0.4572)
		(layer "F.Cu")
		(net "P3V3_AUX")
	)
	(segment
		(start 233.949494 -181.08168)
		(end 233.949494 -181.708044)
		(width 0.4572)
		(layer "F.Cu")
		(net "P3V3_AUX")
	)
	(segment
		(start 78.643734 -44.87291)
		(end 79.315056 -44.87291)
		(width 0.254)
		(layer "F.Cu")
		(net "P3V3_AUX")
	)
	(segment
		(start 167.610282 -47.92091)
		(end 167.408352 -47.71898)
		(width 0.254)
		(layer "F.Cu")
		(net "P3V3_AUX")
	)
	(segment
		(start 358.75595 -177.038)
		(end 358.14 -177.038)
		(width 0.4572)
		(layer "F.Cu")
		(net "P3V3_AUX")
	)
	(segment
		(start 17.185386 -271.184624)
		(end 17.856708 -271.184624)
		(width 0.4572)
		(layer "F.Cu")
		(net "P3V3_AUX")
	)
	(segment
		(start 335.64195 -153.67)
		(end 335.026 -153.67)
		(width 0.4572)
		(layer "F.Cu")
		(net "P3V3_AUX")
	)
	(segment
		(start 314.491624 -36.286948)
		(end 314.437268 -36.232592)
		(width 0.4572)
		(layer "F.Cu")
		(net "P3V3_AUX")
	)
	(segment
		(start 399.19275 -86.7664)
		(end 399.19275 -87.409274)
		(width 0.4572)
		(layer "F.Cu")
		(net "P3V3_AUX")
	)
	(segment
		(start 252.774958 -47.791878)
		(end 252.774958 -48.753014)
		(width 0.254)
		(layer "F.Cu")
		(net "P3V3_AUX")
	)
	(segment
		(start 219.253816 -103.852218)
		(end 219.253816 -103.641652)
		(width 0.254)
		(layer "F.Cu")
		(net "P3V3_AUX")
	)
	(segment
		(start 204.191108 -79.595472)
		(end 204.191108 -78.579472)
		(width 0.4572)
		(layer "F.Cu")
		(net "P3V3_AUX")
	)
	(segment
		(start 211.030566 -242.344702)
		(end 211.030566 -242.03787)
		(width 0.4572)
		(layer "F.Cu")
		(net "P3V3_AUX")
	)
	(segment
		(start 378.079 -213.97595)
		(end 377.551696 -213.97595)
		(width 0.4572)
		(layer "F.Cu")
		(net "P3V3_AUX")
	)
	(segment
		(start 98.0948 -390.3726)
		(end 97.648268 -390.819132)
		(width 0.4572)
		(layer "F.Cu")
		(net "P3V3_AUX")
	)
	(segment
		(start 27.126184 -40.13581)
		(end 27.126184 -40.82161)
		(width 0.4572)
		(layer "F.Cu")
		(net "P3V3_AUX")
	)
	(segment
		(start 167.123618 -167.742108)
		(end 166.67353 -167.742108)
		(width 0.381)
		(layer "F.Cu")
		(net "P3V3_AUX")
	)
	(segment
		(start 285.326074 -40.82161)
		(end 285.17596 -40.971724)
		(width 0.4572)
		(layer "F.Cu")
		(net "P3V3_AUX")
	)
	(segment
		(start 236.706664 -206.91221)
		(end 236.706664 -207.52181)
		(width 0.4572)
		(layer "F.Cu")
		(net "P3V3_AUX")
	)
	(segment
		(start 385.907534 -97.1804)
		(end 386.66039 -97.1804)
		(width 0.4064)
		(layer "F.Cu")
		(net "P3V3_AUX")
	)
	(segment
		(start 135.955278 -35.876738)
		(end 135.199374 -35.876738)
		(width 0.4572)
		(layer "F.Cu")
		(net "P3V3_AUX")
	)
	(segment
		(start 207.428592 -350.712532)
		(end 208.249266 -351.533206)
		(width 0.4572)
		(layer "F.Cu")
		(net "P3V3_AUX")
	)
	(segment
		(start 429.065944 -140.099034)
		(end 429.065944 -139.734798)
		(width 0.4064)
		(layer "F.Cu")
		(net "P3V3_AUX")
	)
	(segment
		(start 228.18598 -176.956212)
		(end 227.520754 -176.956212)
		(width 0.3556)
		(layer "F.Cu")
		(net "P3V3_AUX")
	)
	(segment
		(start 449.179188 -416.021266)
		(end 449.179188 -416.636962)
		(width 0.4572)
		(layer "F.Cu")
		(net "P3V3_AUX")
	)
	(segment
		(start 133.831838 -209.463894)
		(end 132.710174 -209.463894)
		(width 0.2794)
		(layer "F.Cu")
		(net "P3V3_AUX")
	)
	(segment
		(start 362.631228 -198.755)
		(end 362.462064 -198.585836)
		(width 0.4572)
		(layer "F.Cu")
		(net "P3V3_AUX")
	)
	(segment
		(start 378.880624 -238.811054)
		(end 380.002288 -238.811054)
		(width 0.2794)
		(layer "F.Cu")
		(net "P3V3_AUX")
	)
	(segment
		(start 200.156318 -61.487812)
		(end 200.786492 -61.487812)
		(width 0.4572)
		(layer "F.Cu")
		(net "P3V3_AUX")
	)
	(segment
		(start 132.459476 -148.017738)
		(end 132.459476 -147.042378)
		(width 0.4064)
		(layer "F.Cu")
		(net "P3V3_AUX")
	)
	(segment
		(start 330.327 -245.63705)
		(end 330.327 -246.427498)
		(width 0.4572)
		(layer "F.Cu")
		(net "P3V3_AUX")
	)
	(segment
		(start 244.537484 -239.255554)
		(end 244.537484 -239.883442)
		(width 0.4572)
		(layer "F.Cu")
		(net "P3V3_AUX")
	)
	(segment
		(start 120.73509 -94.891606)
		(end 120.119902 -94.891606)
		(width 0.4572)
		(layer "F.Cu")
		(net "P3V3_AUX")
	)
	(segment
		(start 375.656856 -173.13402)
		(end 375.309638 -173.481238)
		(width 0.4572)
		(layer "F.Cu")
		(net "P3V3_AUX")
	)
	(segment
		(start 252.774958 -48.753014)
		(end 253.750318 -48.753014)
		(width 0.254)
		(layer "F.Cu")
		(net "P3V3_AUX")
	)
	(segment
		(start 430.41443 -140.534898)
		(end 429.501808 -140.534898)
		(width 0.4064)
		(layer "F.Cu")
		(net "P3V3_AUX")
	)
	(segment
		(start 16.02486 -410.248608)
		(end 16.02486 -411.632654)
		(width 0.4572)
		(layer "F.Cu")
		(net "P3V3_AUX")
	)
	(segment
		(start 331.978 -245.63705)
		(end 331.978 -246.38)
		(width 0.4572)
		(layer "F.Cu")
		(net "P3V3_AUX")
	)
	(segment
		(start 379.24105 -180.104288)
		(end 379.24105 -179.451)
		(width 0.4572)
		(layer "F.Cu")
		(net "P3V3_AUX")
	)
	(segment
		(start 222.482664 -204.04201)
		(end 222.23095 -203.790296)
		(width 0.4572)
		(layer "F.Cu")
		(net "P3V3_AUX")
	)
	(segment
		(start 243.793264 -119.505476)
		(end 243.793264 -120.11787)
		(width 0.4572)
		(layer "F.Cu")
		(net "P3V3_AUX")
	)
	(segment
		(start 374.50395 -181.08295)
		(end 374.554496 -181.032404)
		(width 0.4572)
		(layer "F.Cu")
		(net "P3V3_AUX")
	)
	(segment
		(start 239.84966 -157.812994)
		(end 239.232186 -157.812994)
		(width 0.4572)
		(layer "F.Cu")
		(net "P3V3_AUX")
	)
	(segment
		(start 407.020014 -372.877842)
		(end 407.77922 -372.877842)
		(width 0.4572)
		(layer "F.Cu")
		(net "P3V3_AUX")
	)
	(segment
		(start 228.971348 -177.74158)
		(end 228.491542 -177.261774)
		(width 0.4572)
		(layer "F.Cu")
		(net "P3V3_AUX")
	)
	(segment
		(start 356.311962 -165.665912)
		(end 356.877366 -165.665912)
		(width 0.4572)
		(layer "F.Cu")
		(net "P3V3_AUX")
	)
	(segment
		(start 11.71448 -276.255226)
		(end 11.98753 -276.255226)
		(width 0.254)
		(layer "F.Cu")
		(net "P3V3_AUX")
	)
	(segment
		(start 363.07395 -201.803)
		(end 362.458 -201.803)
		(width 0.4572)
		(layer "F.Cu")
		(net "P3V3_AUX")
	)
	(segment
		(start 218.88958 -86.576916)
		(end 218.99118 -86.475316)
		(width 0.4572)
		(layer "F.Cu")
		(net "P3V3_AUX")
	)
	(segment
		(start 216.567512 -232.729532)
		(end 217.020648 -233.182668)
		(width 0.4572)
		(layer "F.Cu")
		(net "P3V3_AUX")
	)
	(segment
		(start 152.704546 -142.88897)
		(end 152.704546 -141.87297)
		(width 0.4064)
		(layer "F.Cu")
		(net "P3V3_AUX")
	)
	(segment
		(start 325.734934 -288.830766)
		(end 325.099934 -288.830766)
		(width 0.4572)
		(layer "F.Cu")
		(net "P3V3_AUX")
	)
	(segment
		(start 228.491542 -177.261774)
		(end 228.18598 -176.956212)
		(width 0.3556)
		(layer "F.Cu")
		(net "P3V3_AUX")
	)
	(segment
		(start 275.26869 -407.320242)
		(end 274.872704 -406.924256)
		(width 0.4572)
		(layer "F.Cu")
		(net "P3V3_AUX")
	)
	(segment
		(start 335.64195 -185.039)
		(end 335.026 -185.039)
		(width 0.4572)
		(layer "F.Cu")
		(net "P3V3_AUX")
	)
	(segment
		(start 380.85395 -210.566)
		(end 380.141734 -210.566)
		(width 0.4572)
		(layer "F.Cu")
		(net "P3V3_AUX")
	)
	(segment
		(start 379.24105 -190.627)
		(end 379.857 -190.627)
		(width 0.4572)
		(layer "F.Cu")
		(net "P3V3_AUX")
	)
	(segment
		(start 358.75595 -184.15)
		(end 358.14 -184.15)
		(width 0.4572)
		(layer "F.Cu")
		(net "P3V3_AUX")
	)
	(segment
		(start 120.73509 -98.320606)
		(end 120.119902 -98.320606)
		(width 0.4572)
		(layer "F.Cu")
		(net "P3V3_AUX")
	)
	(segment
		(start 352.591878 -36.286948)
		(end 352.537522 -36.232592)
		(width 0.4572)
		(layer "F.Cu")
		(net "P3V3_AUX")
	)
	(segment
		(start 222.576644 -176.52238)
		(end 223.186244 -176.52238)
		(width 0.4572)
		(layer "F.Cu")
		(net "P3V3_AUX")
	)
	(segment
		(start 325.82104 -102.480364)
		(end 324.859904 -102.480364)
		(width 0.254)
		(layer "F.Cu")
		(net "P3V3_AUX")
	)
	(segment
		(start 340.961472 -194.48145)
		(end 340.961472 -193.46545)
		(width 0.4572)
		(layer "F.Cu")
		(net "P3V3_AUX")
	)
	(segment
		(start 335.64195 -160.782)
		(end 335.026 -160.782)
		(width 0.4572)
		(layer "F.Cu")
		(net "P3V3_AUX")
	)
	(segment
		(start 120.73509 -99.463606)
		(end 120.119902 -99.463606)
		(width 0.4572)
		(layer "F.Cu")
		(net "P3V3_AUX")
	)
	(segment
		(start 131.422648 -193.543428)
		(end 132.219446 -193.543428)
		(width 0.4572)
		(layer "F.Cu")
		(net "P3V3_AUX")
	)
	(segment
		(start 369.895628 -86.070694)
		(end 370.60124 -86.070694)
		(width 0.4572)
		(layer "F.Cu")
		(net "P3V3_AUX")
	)
	(segment
		(start 338.328 -245.63705)
		(end 338.328 -246.253)
		(width 0.4572)
		(layer "F.Cu")
		(net "P3V3_AUX")
	)
	(segment
		(start 25.843738 -47.92091)
		(end 25.510236 -47.92091)
		(width 0.254)
		(layer "F.Cu")
		(net "P3V3_AUX")
	)
	(segment
		(start 383.855468 -244.286024)
		(end 383.855468 -243.44884)
		(width 0.2794)
		(layer "F.Cu")
		(net "P3V3_AUX")
	)
	(segment
		(start 79.234538 -88.548464)
		(end 79.234538 -88.248998)
		(width 0.381)
		(layer "F.Cu")
		(net "P3V3_AUX")
	)
	(segment
		(start 124.796296 -168.484804)
		(end 124.796296 -167.086534)
		(width 0.3556)
		(layer "F.Cu")
		(net "P3V3_AUX")
	)
	(segment
		(start 210.475322 -226.825556)
		(end 209.82178 -226.825556)
		(width 0.4572)
		(layer "F.Cu")
		(net "P3V3_AUX")
	)
	(segment
		(start 93.003878 -292.122098)
		(end 92.11691 -292.122098)
		(width 0.4572)
		(layer "F.Cu")
		(net "P3V3_AUX")
	)
	(segment
		(start 215.464136 -182.013606)
		(end 214.829136 -182.013606)
		(width 0.4572)
		(layer "F.Cu")
		(net "P3V3_AUX")
	)
	(segment
		(start 239.413288 -139.376404)
		(end 238.757968 -139.376404)
		(width 0.4064)
		(layer "F.Cu")
		(net "P3V3_AUX")
	)
	(segment
		(start 201.439272 -357.402638)
		(end 196.724016 -362.117894)
		(width 0.4572)
		(layer "F.Cu")
		(net "P3V3_AUX")
	)
	(segment
		(start 241.981228 -198.746618)
		(end 241.961162 -198.746618)
		(width 0.4572)
		(layer "F.Cu")
		(net "P3V3_AUX")
	)
	(segment
		(start 206.704692 -351.52076)
		(end 206.704692 -352.51771)
		(width 0.4572)
		(layer "F.Cu")
		(net "P3V3_AUX")
	)
	(segment
		(start 457.955142 -375.090182)
		(end 459.572868 -375.090182)
		(width 0.4572)
		(layer "F.Cu")
		(net "P3V3_AUX")
	)
	(segment
		(start 404.953978 -381.50292)
		(end 404.198582 -381.50292)
		(width 0.4572)
		(layer "F.Cu")
		(net "P3V3_AUX")
	)
	(segment
		(start 278.05507 -35.876738)
		(end 277.299166 -35.876738)
		(width 0.4572)
		(layer "F.Cu")
		(net "P3V3_AUX")
	)
	(segment
		(start 72.574912 -48.753014)
		(end 73.550272 -48.753014)
		(width 0.254)
		(layer "F.Cu")
		(net "P3V3_AUX")
	)
	(segment
		(start 282.816808 -167.742108)
		(end 283.223716 -167.742108)
		(width 0.381)
		(layer "F.Cu")
		(net "P3V3_AUX")
	)
	(segment
		(start 295.477692 -116.229638)
		(end 295.477692 -116.550186)
		(width 0.4572)
		(layer "F.Cu")
		(net "P3V3_AUX")
	)
	(segment
		(start 280.475182 -402.738082)
		(end 280.475182 -403.347682)
		(width 0.4572)
		(layer "F.Cu")
		(net "P3V3_AUX")
	)
	(segment
		(start 421.1828 -80.739742)
		(end 421.1828 -80.019906)
		(width 0.4572)
		(layer "F.Cu")
		(net "P3V3_AUX")
	)
	(segment
		(start 399.810224 -47.92091)
		(end 399.608294 -47.71898)
		(width 0.254)
		(layer "F.Cu")
		(net "P3V3_AUX")
	)
	(segment
		(start 363.07395 -210.947)
		(end 362.458 -210.947)
		(width 0.4572)
		(layer "F.Cu")
		(net "P3V3_AUX")
	)
	(segment
		(start 99.445826 -47.193962)
		(end 99.172776 -47.193962)
		(width 0.254)
		(layer "F.Cu")
		(net "P3V3_AUX")
	)
	(segment
		(start 257.262376 -22.101302)
		(end 257.262376 -22.555454)
		(width 0.4572)
		(layer "F.Cu")
		(net "P3V3_AUX")
	)
	(segment
		(start 447.745866 -47.193962)
		(end 447.472816 -47.193962)
		(width 0.254)
		(layer "F.Cu")
		(net "P3V3_AUX")
	)
	(segment
		(start 58.056272 -61.487812)
		(end 58.686446 -61.487812)
		(width 0.4572)
		(layer "F.Cu")
		(net "P3V3_AUX")
	)
	(segment
		(start 404.58009 -139.6492)
		(end 405.24684 -139.6492)
		(width 0.4572)
		(layer "F.Cu")
		(net "P3V3_AUX")
	)
	(segment
		(start 26.643838 -42.84091)
		(end 27.31516 -42.84091)
		(width 0.254)
		(layer "F.Cu")
		(net "P3V3_AUX")
	)
	(segment
		(start 169.22623 -40.82161)
		(end 169.076116 -40.971724)
		(width 0.4572)
		(layer "F.Cu")
		(net "P3V3_AUX")
	)
	(segment
		(start 80.602582 -89.78138)
		(end 80.602582 -89.1159)
		(width 0.4572)
		(layer "F.Cu")
		(net "P3V3_AUX")
	)
	(segment
		(start 401.426172 -40.82161)
		(end 401.276058 -40.971724)
		(width 0.4572)
		(layer "F.Cu")
		(net "P3V3_AUX")
	)
	(segment
		(start 180.503322 -115.90909)
		(end 179.698142 -115.90909)
		(width 0.381)
		(layer "F.Cu")
		(net "P3V3_AUX")
	)
	(segment
		(start 356.877366 -165.665912)
		(end 356.928166 -165.615112)
		(width 0.4572)
		(layer "F.Cu")
		(net "P3V3_AUX")
	)
	(segment
		(start 95.818198 -94.91472)
		(end 95.818198 -94.24924)
		(width 0.4572)
		(layer "F.Cu")
		(net "P3V3_AUX")
	)
	(segment
		(start 411.37078 -137.848848)
		(end 410.621988 -137.848848)
		(width 0.4064)
		(layer "F.Cu")
		(net "P3V3_AUX")
	)
	(segment
		(start 247.085104 -278.551386)
		(end 247.694704 -278.551386)
		(width 0.4572)
		(layer "F.Cu")
		(net "P3V3_AUX")
	)
	(segment
		(start 358.75595 -180.086)
		(end 358.14 -180.086)
		(width 0.4572)
		(layer "F.Cu")
		(net "P3V3_AUX")
	)
	(segment
		(start 380.85395 -199.39)
		(end 380.176024 -199.39)
		(width 0.4572)
		(layer "F.Cu")
		(net "P3V3_AUX")
	)
	(segment
		(start 204.191108 -77.14615)
		(end 204.711808 -76.62545)
		(width 0.4572)
		(layer "F.Cu")
		(net "P3V3_AUX")
	)
	(segment
		(start 183.175402 -187.701174)
		(end 183.847994 -187.701174)
		(width 0.4572)
		(layer "F.Cu")
		(net "P3V3_AUX")
	)
	(segment
		(start 367.826798 -241.15776)
		(end 368.418618 -241.15776)
		(width 0.4572)
		(layer "F.Cu")
		(net "P3V3_AUX")
	)
	(segment
		(start 204.191108 -81.627472)
		(end 204.191108 -80.611472)
		(width 0.4572)
		(layer "F.Cu")
		(net "P3V3_AUX")
	)
	(segment
		(start 236.437424 -36.232592)
		(end 235.59516 -36.232592)
		(width 0.4572)
		(layer "F.Cu")
		(net "P3V3_AUX")
	)
	(segment
		(start 55.395114 -36.232592)
		(end 56.237378 -36.232592)
		(width 0.4572)
		(layer "F.Cu")
		(net "P3V3_AUX")
	)
	(segment
		(start 77.510132 -47.92091)
		(end 77.308202 -47.71898)
		(width 0.254)
		(layer "F.Cu")
		(net "P3V3_AUX")
	)
	(segment
		(start 325.82104 -101.870764)
		(end 325.82104 -102.480364)
		(width 0.4572)
		(layer "F.Cu")
		(net "P3V3_AUX")
	)
	(segment
		(start 309.553864 -83.532218)
		(end 311.093612 -83.532218)
		(width 0.4064)
		(layer "F.Cu")
		(net "P3V3_AUX")
	)
	(segment
		(start 230.699564 -205.00594)
		(end 230.699564 -204.21219)
		(width 0.381)
		(layer "F.Cu")
		(net "P3V3_AUX")
	)
	(segment
		(start 389.109204 -242.056412)
		(end 389.354568 -241.811048)
		(width 0.2794)
		(layer "F.Cu")
		(net "P3V3_AUX")
	)
	(segment
		(start 196.084444 -366.086898)
		(end 194.52082 -366.086898)
		(width 0.4572)
		(layer "F.Cu")
		(net "P3V3_AUX")
	)
	(segment
		(start 181.1528 -176.966372)
		(end 181.1528 -177.717704)
		(width 0.4572)
		(layer "F.Cu")
		(net "P3V3_AUX")
	)
	(segment
		(start 6.914388 -365.392208)
		(end 7.58444 -365.392208)
		(width 0.4572)
		(layer "F.Cu")
		(net "P3V3_AUX")
	)
	(segment
		(start 79.313024 -8.891778)
		(end 79.313024 -9.535922)
		(width 0.4572)
		(layer "F.Cu")
		(net "P3V3_AUX")
	)
	(segment
		(start 427.42612 -40.82161)
		(end 427.276006 -40.971724)
		(width 0.4572)
		(layer "F.Cu")
		(net "P3V3_AUX")
	)
	(segment
		(start 203.92009 -288.378138)
		(end 204.077062 -288.221166)
		(width 0.4572)
		(layer "F.Cu")
		(net "P3V3_AUX")
	)
	(segment
		(start 431.247296 -36.286948)
		(end 430.591722 -36.286948)
		(width 0.4572)
		(layer "F.Cu")
		(net "P3V3_AUX")
	)
	(segment
		(start 358.365806 -231.428798)
		(end 359.088182 -231.428798)
		(width 0.4572)
		(layer "F.Cu")
		(net "P3V3_AUX")
	)
	(segment
		(start 224.456244 -184.703212)
		(end 222.942658 -184.703212)
		(width 0.3556)
		(layer "F.Cu")
		(net "P3V3_AUX")
	)
	(segment
		(start 396.609316 -89.500202)
		(end 397.224758 -89.500202)
		(width 0.4572)
		(layer "F.Cu")
		(net "P3V3_AUX")
	)
	(segment
		(start 152.704546 -140.85697)
		(end 152.17394 -140.326364)
		(width 0.4064)
		(layer "F.Cu")
		(net "P3V3_AUX")
	)
	(segment
		(start 312.965846 -140.099034)
		(end 312.965846 -139.734798)
		(width 0.4064)
		(layer "F.Cu")
		(net "P3V3_AUX")
	)
	(segment
		(start 97.648268 -396.1638)
		(end 97.032318 -396.1638)
		(width 0.4572)
		(layer "F.Cu")
		(net "P3V3_AUX")
	)
	(segment
		(start 52.667916 -52.035456)
		(end 53.323236 -52.035456)
		(width 0.254)
		(layer "F.Cu")
		(net "P3V3_AUX")
	)
	(segment
		(start 238.889794 -201.25182)
		(end 238.342678 -201.798936)
		(width 0.4572)
		(layer "F.Cu")
		(net "P3V3_AUX")
	)
	(segment
		(start 458.155548 -373.31777)
		(end 458.155548 -372.677944)
		(width 0.4572)
		(layer "F.Cu")
		(net "P3V3_AUX")
	)
	(segment
		(start 357.567738 -392.81989)
		(end 357.567738 -393.459716)
		(width 0.4572)
		(layer "F.Cu")
		(net "P3V3_AUX")
	)
	(segment
		(start 194.743832 -42.84091)
		(end 195.415154 -42.84091)
		(width 0.254)
		(layer "F.Cu")
		(net "P3V3_AUX")
	)
	(segment
		(start 373.362474 -22.101302)
		(end 373.362474 -22.555454)
		(width 0.4572)
		(layer "F.Cu")
		(net "P3V3_AUX")
	)
	(segment
		(start 326.629014 -231.986074)
		(end 326.629014 -232.297986)
		(width 0.4572)
		(layer "F.Cu")
		(net "P3V3_AUX")
	)
	(segment
		(start 212.919818 -210.574636)
		(end 213.394544 -211.049362)
		(width 0.4572)
		(layer "F.Cu")
		(net "P3V3_AUX")
	)
	(segment
		(start 148.409152 -26.03373)
		(end 147.750022 -26.03373)
		(width 0.4572)
		(layer "F.Cu")
		(net "P3V3_AUX")
	)
	(segment
		(start 268.804644 -140.85697)
		(end 268.19479 -140.85697)
		(width 0.4064)
		(layer "F.Cu")
		(net "P3V3_AUX")
	)
	(segment
		(start 374.968008 -52.035456)
		(end 375.623328 -52.035456)
		(width 0.254)
		(layer "F.Cu")
		(net "P3V3_AUX")
	)
	(segment
		(start 120.504712 -138.34872)
		(end 120.14962 -137.993628)
		(width 0.254)
		(layer "F.Cu")
		(net "P3V3_AUX")
	)
	(segment
		(start 413.366458 -189.056518)
		(end 413.366458 -189.578488)
		(width 0.4572)
		(layer "F.Cu")
		(net "P3V3_AUX")
	)
	(segment
		(start 364.08487 -392.066018)
		(end 364.08487 -392.684254)
		(width 0.4572)
		(layer "F.Cu")
		(net "P3V3_AUX")
	)
	(segment
		(start 212.974936 -189.052454)
		(end 212.974936 -189.662054)
		(width 0.4572)
		(layer "F.Cu")
		(net "P3V3_AUX")
	)
	(segment
		(start 258.84378 -42.84091)
		(end 259.515102 -42.84091)
		(width 0.254)
		(layer "F.Cu")
		(net "P3V3_AUX")
	)
	(segment
		(start 373.233696 -192.25895)
		(end 373.117618 -192.142872)
		(width 0.4572)
		(layer "F.Cu")
		(net "P3V3_AUX")
	)
	(segment
		(start 310.043576 -47.92091)
		(end 309.710074 -47.92091)
		(width 0.254)
		(layer "F.Cu")
		(net "P3V3_AUX")
	)
	(segment
		(start 452.967852 -52.035456)
		(end 453.623172 -52.035456)
		(width 0.4572)
		(layer "F.Cu")
		(net "P3V3_AUX")
	)
	(segment
		(start 335.64195 -157.734)
		(end 335.026 -157.734)
		(width 0.4572)
		(layer "F.Cu")
		(net "P3V3_AUX")
	)
	(segment
		(start 365.413036 -250.46305)
		(end 366.18418 -250.46305)
		(width 0.4572)
		(layer "F.Cu")
		(net "P3V3_AUX")
	)
	(segment
		(start 404.955248 -375.71426)
		(end 404.955248 -374.177052)
		(width 0.4572)
		(layer "F.Cu")
		(net "P3V3_AUX")
	)
	(segment
		(start 268.804644 -141.87297)
		(end 268.804644 -140.85697)
		(width 0.4064)
		(layer "F.Cu")
		(net "P3V3_AUX")
	)
	(segment
		(start 430.591722 -36.286948)
		(end 430.537366 -36.232592)
		(width 0.4572)
		(layer "F.Cu")
		(net "P3V3_AUX")
	)
	(segment
		(start 204.191108 -77.563472)
		(end 204.191108 -77.14615)
		(width 0.4572)
		(layer "F.Cu")
		(net "P3V3_AUX")
	)
	(segment
		(start 77.308202 -47.71898)
		(end 77.308202 -47.403766)
		(width 0.254)
		(layer "F.Cu")
		(net "P3V3_AUX")
	)
	(segment
		(start 202.322684 -357.402638)
		(end 201.439272 -357.402638)
		(width 0.4572)
		(layer "F.Cu")
		(net "P3V3_AUX")
	)
	(segment
		(start 11.116564 -276.853142)
		(end 11.71448 -276.255226)
		(width 0.254)
		(layer "F.Cu")
		(net "P3V3_AUX")
	)
	(segment
		(start 133.9088 -97.983802)
		(end 133.9088 -98.491802)
		(width 0.3048)
		(layer "F.Cu")
		(net "P3V3_AUX")
	)
	(segment
		(start 143.226282 -40.13581)
		(end 143.226282 -40.82161)
		(width 0.4572)
		(layer "F.Cu")
		(net "P3V3_AUX")
	)
	(segment
		(start 441.921138 -102.480364)
		(end 440.960002 -102.480364)
		(width 0.254)
		(layer "F.Cu")
		(net "P3V3_AUX")
	)
	(segment
		(start 379.8824 -36.286948)
		(end 379.2474 -36.286948)
		(width 0.4572)
		(layer "F.Cu")
		(net "P3V3_AUX")
	)
	(segment
		(start 186.772804 -415.15919)
		(end 187.53455 -415.15919)
		(width 0.4572)
		(layer "F.Cu")
		(net "P3V3_AUX")
	)
	(segment
		(start 204.191108 -85.691472)
		(end 203.23937 -85.691472)
		(width 0.4572)
		(layer "F.Cu")
		(net "P3V3_AUX")
	)
	(segment
		(start 369.895628 -88.356694)
		(end 370.60124 -88.356694)
		(width 0.4572)
		(layer "F.Cu")
		(net "P3V3_AUX")
	)
	(segment
		(start 104.643682 -42.84091)
		(end 105.315004 -42.84091)
		(width 0.254)
		(layer "F.Cu")
		(net "P3V3_AUX")
	)
	(segment
		(start 451.362318 -22.101302)
		(end 451.362318 -22.555454)
		(width 0.4572)
		(layer "F.Cu")
		(net "P3V3_AUX")
	)
	(segment
		(start 363.959902 -397.82623)
		(end 363.959902 -398.444466)
		(width 0.4572)
		(layer "F.Cu")
		(net "P3V3_AUX")
	)
	(segment
		(start 375.912634 -84.2518)
		(end 375.297446 -84.2518)
		(width 0.4572)
		(layer "F.Cu")
		(net "P3V3_AUX")
	)
	(segment
		(start 229.495858 -240.88725)
		(end 227.602796 -240.88725)
		(width 0.4572)
		(layer "F.Cu")
		(net "P3V3_AUX")
	)
	(segment
		(start 206.784194 -209.966052)
		(end 206.15275 -210.597496)
		(width 0.4572)
		(layer "F.Cu")
		(net "P3V3_AUX")
	)
	(segment
		(start 309.508144 -47.71898)
		(end 309.508144 -47.403766)
		(width 0.254)
		(layer "F.Cu")
		(net "P3V3_AUX")
	)
	(segment
		(start 193.660522 -20.789392)
		(end 193.660522 -21.603208)
		(width 0.4572)
		(layer "F.Cu")
		(net "P3V3_AUX")
	)
	(segment
		(start 228.39299 -91.025726)
		(end 227.734368 -91.025726)
		(width 0.254)
		(layer "F.Cu")
		(net "P3V3_AUX")
	)
	(segment
		(start 230.349044 -178.38039)
		(end 230.349044 -177.74158)
		(width 0.4572)
		(layer "F.Cu")
		(net "P3V3_AUX")
	)
	(segment
		(start 321.787266 -94.158308)
		(end 320.156332 -94.158308)
		(width 0.4572)
		(layer "F.Cu")
		(net "P3V3_AUX")
	)
	(segment
		(start 279.645872 -47.193962)
		(end 279.372822 -47.193962)
		(width 0.254)
		(layer "F.Cu")
		(net "P3V3_AUX")
	)
	(segment
		(start 186.789568 -406.99436)
		(end 187.424568 -406.99436)
		(width 0.4572)
		(layer "F.Cu")
		(net "P3V3_AUX")
	)
	(segment
		(start 218.99118 -86.475316)
		(end 218.326208 -85.810344)
		(width 0.4572)
		(layer "F.Cu")
		(net "P3V3_AUX")
	)
	(segment
		(start 399.99285 -85.3948)
		(end 399.99285 -84.721446)
		(width 0.4572)
		(layer "F.Cu")
		(net "P3V3_AUX")
	)
	(segment
		(start 233.067606 -218.30411)
		(end 233.467402 -217.904314)
		(width 0.381)
		(layer "F.Cu")
		(net "P3V3_AUX")
	)
	(segment
		(start 209.926936 -189.052454)
		(end 209.926936 -189.770258)
		(width 0.4572)
		(layer "F.Cu")
		(net "P3V3_AUX")
	)
	(segment
		(start 441.921138 -101.870764)
		(end 441.921138 -102.480364)
		(width 0.4572)
		(layer "F.Cu")
		(net "P3V3_AUX")
	)
	(segment
		(start 246.000778 -238.15421)
		(end 246.096028 -238.05896)
		(width 0.4572)
		(layer "F.Cu")
		(net "P3V3_AUX")
	)
	(segment
		(start 342.155272 -35.876738)
		(end 341.399368 -35.876738)
		(width 0.4572)
		(layer "F.Cu")
		(net "P3V3_AUX")
	)
	(segment
		(start 340.961472 -193.46545)
		(end 341.571072 -193.46545)
		(width 0.4572)
		(layer "F.Cu")
		(net "P3V3_AUX")
	)
	(segment
		(start 311.43448 -88.872568)
		(end 311.43448 -88.248998)
		(width 0.381)
		(layer "F.Cu")
		(net "P3V3_AUX")
	)
	(segment
		(start 240.679224 -178.3207)
		(end 240.679224 -177.6857)
		(width 0.4572)
		(layer "F.Cu")
		(net "P3V3_AUX")
	)
	(segment
		(start 380.356364 -61.487812)
		(end 380.986538 -61.487812)
		(width 0.4572)
		(layer "F.Cu")
		(net "P3V3_AUX")
	)
	(segment
		(start 230.991664 -206.62011)
		(end 231.08539 -206.526384)
		(width 0.4572)
		(layer "F.Cu")
		(net "P3V3_AUX")
	)
	(segment
		(start 51.062382 -22.101302)
		(end 51.560476 -21.603208)
		(width 0.4572)
		(layer "F.Cu")
		(net "P3V3_AUX")
	)
	(segment
		(start 262.491728 -36.286948)
		(end 262.437372 -36.232592)
		(width 0.4572)
		(layer "F.Cu")
		(net "P3V3_AUX")
	)
	(segment
		(start 92.659962 -102.480364)
		(end 92.062046 -101.882448)
		(width 0.254)
		(layer "F.Cu")
		(net "P3V3_AUX")
	)
	(segment
		(start 396.609316 -83.785202)
		(end 397.224758 -83.785202)
		(width 0.4572)
		(layer "F.Cu")
		(net "P3V3_AUX")
	)
	(segment
		(start 77.353922 -83.532218)
		(end 76.693522 -83.532218)
		(width 0.4064)
		(layer "F.Cu")
		(net "P3V3_AUX")
	)
	(segment
		(start 193.943732 -47.92091)
		(end 193.61023 -47.92091)
		(width 0.254)
		(layer "F.Cu")
		(net "P3V3_AUX")
	)
	(segment
		(start 363.07395 -201.803)
		(end 363.07395 -202.819)
		(width 0.4572)
		(layer "F.Cu")
		(net "P3V3_AUX")
	)
	(segment
		(start 254.685546 -207.51165)
		(end 254.685546 -208.14665)
		(width 0.4572)
		(layer "F.Cu")
		(net "P3V3_AUX")
	)
	(segment
		(start 93.638878 -292.122098)
		(end 93.003878 -292.122098)
		(width 0.4572)
		(layer "F.Cu")
		(net "P3V3_AUX")
	)
	(segment
		(start 139.385294 -95.814642)
		(end 140.090144 -95.814642)
		(width 0.4572)
		(layer "F.Cu")
		(net "P3V3_AUX")
	)
	(segment
		(start 209.63509 -288.830766)
		(end 209.00009 -288.830766)
		(width 0.4572)
		(layer "F.Cu")
		(net "P3V3_AUX")
	)
	(segment
		(start 132.459476 -147.042378)
		(end 132.879592 -147.042378)
		(width 0.254)
		(layer "F.Cu")
		(net "P3V3_AUX")
	)
	(segment
		(start 427.42612 -40.13581)
		(end 427.42612 -40.82161)
		(width 0.4572)
		(layer "F.Cu")
		(net "P3V3_AUX")
	)
	(segment
		(start 358.75595 -189.23)
		(end 358.14 -189.23)
		(width 0.4572)
		(layer "F.Cu")
		(net "P3V3_AUX")
	)
	(segment
		(start 78.667864 -52.035456)
		(end 79.323184 -52.035456)
		(width 0.254)
		(layer "F.Cu")
		(net "P3V3_AUX")
	)
	(segment
		(start 145.28165 -209.463894)
		(end 144.159986 -209.463894)
		(width 0.2794)
		(layer "F.Cu")
		(net "P3V3_AUX")
	)
	(segment
		(start 104.391714 -8.641588)
		(end 104.889808 -9.139682)
		(width 0.4572)
		(layer "F.Cu")
		(net "P3V3_AUX")
	)
	(segment
		(start 210.445096 -226.031044)
		(end 210.445096 -226.158044)
		(width 0.4064)
		(layer "F.Cu")
		(net "P3V3_AUX")
	)
	(segment
		(start 6.056376 -66.567812)
		(end 6.68655 -66.567812)
		(width 0.4572)
		(layer "F.Cu")
		(net "P3V3_AUX")
	)
	(segment
		(start 222.130874 -51.327812)
		(end 221.42323 -52.035456)
		(width 0.4572)
		(layer "F.Cu")
		(net "P3V3_AUX")
	)
	(segment
		(start 30.23743 -36.232592)
		(end 29.395166 -36.232592)
		(width 0.4572)
		(layer "F.Cu")
		(net "P3V3_AUX")
	)
	(segment
		(start 444.118238 -94.91472)
		(end 444.118238 -94.24924)
		(width 0.4572)
		(layer "F.Cu")
		(net "P3V3_AUX")
	)
	(segment
		(start 446.8749 -47.791878)
		(end 446.8749 -48.753014)
		(width 0.254)
		(layer "F.Cu")
		(net "P3V3_AUX")
	)
	(segment
		(start 356.12705 -183.388)
		(end 356.743 -183.388)
		(width 0.4572)
		(layer "F.Cu")
		(net "P3V3_AUX")
	)
	(segment
		(start 445.318134 -411.900116)
		(end 446.415668 -411.900116)
		(width 0.4572)
		(layer "F.Cu")
		(net "P3V3_AUX")
	)
	(segment
		(start 327.19137 -226.660202)
		(end 327.193656 -226.657916)
		(width 0.4572)
		(layer "F.Cu")
		(net "P3V3_AUX")
	)
	(segment
		(start 226.667568 -220.704156)
		(end 226.267772 -221.103952)
		(width 0.381)
		(layer "F.Cu")
		(net "P3V3_AUX")
	)
	(segment
		(start 25.308306 -47.71898)
		(end 25.308306 -47.403766)
		(width 0.254)
		(layer "F.Cu")
		(net "P3V3_AUX")
	)
	(segment
		(start 289.78225 -36.286948)
		(end 289.14725 -36.286948)
		(width 0.4572)
		(layer "F.Cu")
		(net "P3V3_AUX")
	)
	(segment
		(start 200.409048 -26.03373)
		(end 199.749918 -26.03373)
		(width 0.4572)
		(layer "F.Cu")
		(net "P3V3_AUX")
	)
	(segment
		(start 247.018048 -356.900226)
		(end 249.085862 -356.900226)
		(width 0.4572)
		(layer "F.Cu")
		(net "P3V3_AUX")
	)
	(segment
		(start 153.285444 -114.86515)
		(end 154.008328 -114.86515)
		(width 0.4064)
		(layer "F.Cu")
		(net "P3V3_AUX")
	)
	(segment
		(start 207.789526 -291.736272)
		(end 207.789526 -291.297868)
		(width 0.4572)
		(layer "F.Cu")
		(net "P3V3_AUX")
	)
	(segment
		(start 154.008328 -114.86515)
		(end 154.378406 -115.235228)
		(width 0.4064)
		(layer "F.Cu")
		(net "P3V3_AUX")
	)
	(segment
		(start 162.675062 -47.791878)
		(end 162.675062 -48.753014)
		(width 0.254)
		(layer "F.Cu")
		(net "P3V3_AUX")
	)
	(segment
		(start 240.163858 -81.19872)
		(end 240.724182 -81.19872)
		(width 0.4572)
		(layer "F.Cu")
		(net "P3V3_AUX")
	)
	(segment
		(start 106.035094 -397.912336)
		(end 106.035094 -398.674336)
		(width 0.4572)
		(layer "F.Cu")
		(net "P3V3_AUX")
	)
	(segment
		(start 289.14725 -36.286948)
		(end 288.491676 -36.286948)
		(width 0.4572)
		(layer "F.Cu")
		(net "P3V3_AUX")
	)
	(segment
		(start 369.895628 -87.213694)
		(end 370.60124 -87.213694)
		(width 0.4572)
		(layer "F.Cu")
		(net "P3V3_AUX")
	)
	(segment
		(start 373.117618 -180.966872)
		(end 372.114064 -180.966872)
		(width 0.4572)
		(layer "F.Cu")
		(net "P3V3_AUX")
	)
	(segment
		(start 378.82195 -202.79995)
		(end 378.079 -202.79995)
		(width 0.4572)
		(layer "F.Cu")
		(net "P3V3_AUX")
	)
	(segment
		(start 278.987504 -394.762482)
		(end 279.622504 -394.762482)
		(width 0.4572)
		(layer "F.Cu")
		(net "P3V3_AUX")
	)
	(segment
		(start 32.309054 -26.03373)
		(end 31.649924 -26.03373)
		(width 0.4572)
		(layer "F.Cu")
		(net "P3V3_AUX")
	)
	(segment
		(start 263.994646 -206.33436)
		(end 263.969754 -206.33436)
		(width 0.4572)
		(layer "F.Cu")
		(net "P3V3_AUX")
	)
	(segment
		(start 430.537366 -36.232592)
		(end 429.695102 -36.232592)
		(width 0.4572)
		(layer "F.Cu")
		(net "P3V3_AUX")
	)
	(segment
		(start 408.559 -384.06705)
		(end 408.559 -384.81)
		(width 0.4572)
		(layer "F.Cu")
		(net "P3V3_AUX")
	)
	(segment
		(start 304.774854 -47.791878)
		(end 304.774854 -48.753014)
		(width 0.254)
		(layer "F.Cu")
		(net "P3V3_AUX")
	)
	(segment
		(start 349.980504 -91.788234)
		(end 349.268542 -91.788234)
		(width 0.4572)
		(layer "F.Cu")
		(net "P3V3_AUX")
	)
	(segment
		(start 133.750558 -147.913344)
		(end 134.018528 -147.913344)
		(width 0.254)
		(layer "F.Cu")
		(net "P3V3_AUX")
	)
	(segment
		(start 95.505778 -241.760248)
		(end 95.505778 -241.779552)
		(width 0.254)
		(layer "F.Cu")
		(net "P3V3_AUX")
	)
	(segment
		(start 168.171368 -169.23385)
		(end 167.361108 -169.23385)
		(width 0.4572)
		(layer "F.Cu")
		(net "P3V3_AUX")
	)
	(segment
		(start 428.902622 -89.78138)
		(end 428.902622 -89.1159)
		(width 0.4572)
		(layer "F.Cu")
		(net "P3V3_AUX")
	)
	(segment
		(start 134.581392 -99.60991)
		(end 135.125968 -100.154486)
		(width 0.4572)
		(layer "F.Cu")
		(net "P3V3_AUX")
	)
	(segment
		(start 210.475322 -226.18827)
		(end 210.475322 -226.825556)
		(width 0.4572)
		(layer "F.Cu")
		(net "P3V3_AUX")
	)
	(segment
		(start 228.128576 -68.399914)
		(end 228.104192 -68.424298)
		(width 0.3556)
		(layer "F.Cu")
		(net "P3V3_AUX")
	)
	(segment
		(start 218.080844 -95.73895)
		(end 218.080844 -95.123)
		(width 0.4572)
		(layer "F.Cu")
		(net "P3V3_AUX")
	)
	(segment
		(start 451.860412 -20.789392)
		(end 451.860412 -21.603208)
		(width 0.4572)
		(layer "F.Cu")
		(net "P3V3_AUX")
	)
	(segment
		(start 456.82408 -226.681538)
		(end 457.708 -226.681538)
		(width 0.2794)
		(layer "F.Cu")
		(net "P3V3_AUX")
	)
	(segment
		(start 324.261988 -101.882448)
		(end 324.261988 -101.609398)
		(width 0.254)
		(layer "F.Cu")
		(net "P3V3_AUX")
	)
	(segment
		(start 236.49178 -36.286948)
		(end 236.437424 -36.232592)
		(width 0.4572)
		(layer "F.Cu")
		(net "P3V3_AUX")
	)
	(segment
		(start 16.02486 -411.632654)
		(end 16.479774 -412.087568)
		(width 0.4572)
		(layer "F.Cu")
		(net "P3V3_AUX")
	)
	(segment
		(start 168.743884 -44.87291)
		(end 169.415206 -44.87291)
		(width 0.254)
		(layer "F.Cu")
		(net "P3V3_AUX")
	)
	(segment
		(start 214.73668 -238.213392)
		(end 217.583512 -235.36656)
		(width 0.4572)
		(layer "F.Cu")
		(net "P3V3_AUX")
	)
	(segment
		(start 296.773092 -115.902486)
		(end 295.804844 -115.902486)
		(width 0.4572)
		(layer "F.Cu")
		(net "P3V3_AUX")
	)
	(segment
		(start 133.29158 -152.3111)
		(end 133.29158 -151.696928)
		(width 0.4064)
		(layer "F.Cu")
		(net "P3V3_AUX")
	)
	(segment
		(start 395.47292 -47.193962)
		(end 394.875004 -47.791878)
		(width 0.254)
		(layer "F.Cu")
		(net "P3V3_AUX")
	)
	(segment
		(start 196.724016 -362.117894)
		(end 196.724016 -365.447326)
		(width 0.4572)
		(layer "F.Cu")
		(net "P3V3_AUX")
	)
	(segment
		(start 283.262324 -22.555454)
		(end 283.918406 -22.555454)
		(width 0.4572)
		(layer "F.Cu")
		(net "P3V3_AUX")
	)
	(segment
		(start 12.095734 -339.196426)
		(end 12.095734 -341.292688)
		(width 0.4572)
		(layer "F.Cu")
		(net "P3V3_AUX")
	)
	(segment
		(start 12.312904 -45.111924)
		(end 12.312904 -45.926248)
		(width 0.4572)
		(layer "F.Cu")
		(net "P3V3_AUX")
	)
	(segment
		(start 457.394818 -278.665432)
		(end 457.667868 -278.665432)
		(width 0.254)
		(layer "F.Cu")
		(net "P3V3_AUX")
	)
	(segment
		(start 248.559574 -147.042378)
		(end 248.97969 -147.042378)
		(width 0.254)
		(layer "F.Cu")
		(net "P3V3_AUX")
	)
	(segment
		(start 360.25836 -257.115564)
		(end 360.86796 -257.115564)
		(width 0.381)
		(layer "F.Cu")
		(net "P3V3_AUX")
	)
	(segment
		(start 282.277566 -167.202866)
		(end 282.816808 -167.742108)
		(width 0.381)
		(layer "F.Cu")
		(net "P3V3_AUX")
	)
	(segment
		(start 369.895628 -84.927694)
		(end 370.60124 -84.927694)
		(width 0.4572)
		(layer "F.Cu")
		(net "P3V3_AUX")
	)
	(segment
		(start 399.362422 -22.555454)
		(end 400.018504 -22.555454)
		(width 0.4572)
		(layer "F.Cu")
		(net "P3V3_AUX")
	)
	(segment
		(start 210.130136 -179.448206)
		(end 210.384136 -179.194206)
		(width 0.4572)
		(layer "F.Cu")
		(net "P3V3_AUX")
	)
	(segment
		(start 311.326022 -40.13581)
		(end 311.326022 -40.82161)
		(width 0.4572)
		(layer "F.Cu")
		(net "P3V3_AUX")
	)
	(segment
		(start 364.234984 -249.284998)
		(end 365.413036 -250.46305)
		(width 0.4572)
		(layer "F.Cu")
		(net "P3V3_AUX")
	)
	(segment
		(start 195.334382 -88.979248)
		(end 195.334382 -88.248998)
		(width 0.381)
		(layer "F.Cu")
		(net "P3V3_AUX")
	)
	(segment
		(start 195.226178 -40.13581)
		(end 195.226178 -40.82161)
		(width 0.4572)
		(layer "F.Cu")
		(net "P3V3_AUX")
	)
	(segment
		(start 172.329094 -117.5512)
		(end 172.329094 -118.016274)
		(width 0.4064)
		(layer "F.Cu")
		(net "P3V3_AUX")
	)
	(segment
		(start 220.812868 -103.537258)
		(end 220.812868 -104.512618)
		(width 0.4064)
		(layer "F.Cu")
		(net "P3V3_AUX")
	)
	(segment
		(start 421.472868 -47.193962)
		(end 420.874952 -47.791878)
		(width 0.254)
		(layer "F.Cu")
		(net "P3V3_AUX")
	)
	(segment
		(start 365.950754 -147.913344)
		(end 366.218724 -147.913344)
		(width 0.254)
		(layer "F.Cu")
		(net "P3V3_AUX")
	)
	(segment
		(start 89.023444 -96.411542)
		(end 89.023444 -95.801942)
		(width 0.4572)
		(layer "F.Cu")
		(net "P3V3_AUX")
	)
	(segment
		(start 243.238528 -215.05291)
		(end 243.8654 -215.05291)
		(width 0.4572)
		(layer "F.Cu")
		(net "P3V3_AUX")
	)
	(segment
		(start 231.149144 -174.69358)
		(end 231.765348 -174.69358)
		(width 0.4572)
		(layer "F.Cu")
		(net "P3V3_AUX")
	)
	(segment
		(start 37.607494 -97.1804)
		(end 38.36035 -97.1804)
		(width 0.4064)
		(layer "F.Cu")
		(net "P3V3_AUX")
	)
	(segment
		(start 216.827862 -211.193126)
		(end 216.025984 -211.193126)
		(width 0.3048)
		(layer "F.Cu")
		(net "P3V3_AUX")
	)
	(segment
		(start 394.875004 -48.753014)
		(end 395.850364 -48.753014)
		(width 0.254)
		(layer "F.Cu")
		(net "P3V3_AUX")
	)
	(segment
		(start 172.080174 -118.265194)
		(end 171.510198 -118.265194)
		(width 0.4064)
		(layer "F.Cu")
		(net "P3V3_AUX")
	)
	(segment
		(start 104.667812 -52.035456)
		(end 105.323132 -52.035456)
		(width 0.254)
		(layer "F.Cu")
		(net "P3V3_AUX")
	)
	(segment
		(start 432.35626 -61.487812)
		(end 432.986434 -61.487812)
		(width 0.4572)
		(layer "F.Cu")
		(net "P3V3_AUX")
	)
	(segment
		(start 368.539776 -153.1112)
		(end 368.539776 -153.782522)
		(width 0.4064)
		(layer "F.Cu")
		(net "P3V3_AUX")
	)
	(segment
		(start 100.7745 -241.398044)
		(end 99.903534 -242.26901)
		(width 0.254)
		(layer "F.Cu")
		(net "P3V3_AUX")
	)
	(segment
		(start 87.819992 -288.378138)
		(end 87.976964 -288.221166)
		(width 0.4572)
		(layer "F.Cu")
		(net "P3V3_AUX")
	)
	(segment
		(start 349.000064 -184.903872)
		(end 350.003618 -184.903872)
		(width 0.4572)
		(layer "F.Cu")
		(net "P3V3_AUX")
	)
	(segment
		(start 329.311 -244.221)
		(end 329.311 -244.83695)
		(width 0.4572)
		(layer "F.Cu")
		(net "P3V3_AUX")
	)
	(segment
		(start 373.233696 -181.08295)
		(end 373.117618 -180.966872)
		(width 0.4572)
		(layer "F.Cu")
		(net "P3V3_AUX")
	)
	(segment
		(start 270.108426 -114.86515)
		(end 270.478504 -115.235228)
		(width 0.4064)
		(layer "F.Cu")
		(net "P3V3_AUX")
	)
	(segment
		(start 203.770992 -88.993472)
		(end 202.473814 -88.993472)
		(width 0.4572)
		(layer "F.Cu")
		(net "P3V3_AUX")
	)
	(segment
		(start 138.37158 -153.1112)
		(end 138.37158 -153.782522)
		(width 0.4064)
		(layer "F.Cu")
		(net "P3V3_AUX")
	)
	(segment
		(start 365.24692 -261.206488)
		(end 365.33074 -261.122668)
		(width 0.3556)
		(layer "F.Cu")
		(net "P3V3_AUX")
	)
	(segment
		(start 452.943722 -42.84091)
		(end 453.615044 -42.84091)
		(width 0.254)
		(layer "F.Cu")
		(net "P3V3_AUX")
	)
	(segment
		(start 209.72018 -245.026434)
		(end 209.72018 -243.774976)
		(width 0.4572)
		(layer "F.Cu")
		(net "P3V3_AUX")
	)
	(segment
		(start 373.860568 -21.603208)
		(end 373.362474 -22.101302)
		(width 0.4572)
		(layer "F.Cu")
		(net "P3V3_AUX")
	)
	(segment
		(start 204.191108 -78.579472)
		(end 204.191108 -77.563472)
		(width 0.4572)
		(layer "F.Cu")
		(net "P3V3_AUX")
	)
	(segment
		(start 456.420982 -116.630704)
		(end 456.420982 -117.248178)
		(width 0.4572)
		(layer "F.Cu")
		(net "P3V3_AUX")
	)
	(segment
		(start 213.17966 -179.443126)
		(end 212.93074 -179.194206)
		(width 0.4572)
		(layer "F.Cu")
		(net "P3V3_AUX")
	)
	(segment
		(start 415.057082 -196.755258)
		(end 414.103058 -196.755258)
		(width 0.4572)
		(layer "F.Cu")
		(net "P3V3_AUX")
	)
	(segment
		(start 394.875004 -47.791878)
		(end 394.875004 -48.753014)
		(width 0.254)
		(layer "F.Cu")
		(net "P3V3_AUX")
	)
	(segment
		(start 413.366458 -189.578488)
		(end 413.599122 -189.811152)
		(width 0.4572)
		(layer "F.Cu")
		(net "P3V3_AUX")
	)
	(segment
		(start 453.632316 -52.0446)
		(end 455.031856 -52.0446)
		(width 0.4572)
		(layer "F.Cu")
		(net "P3V3_AUX")
	)
	(segment
		(start 78.899512 -83.526376)
		(end 78.89367 -83.532218)
		(width 0.4064)
		(layer "F.Cu")
		(net "P3V3_AUX")
	)
	(segment
		(start 358.75595 -172.974)
		(end 358.14 -172.974)
		(width 0.4572)
		(layer "F.Cu")
		(net "P3V3_AUX")
	)
	(segment
		(start 464.381088 -281.723084)
		(end 465.05241 -281.723084)
		(width 0.4572)
		(layer "F.Cu")
		(net "P3V3_AUX")
	)
	(segment
		(start 170.554904 -23.361396)
		(end 170.554904 -23.970996)
		(width 0.4572)
		(layer "F.Cu")
		(net "P3V3_AUX")
	)
	(segment
		(start 220.705426 -177.390552)
		(end 220.705426 -178.027076)
		(width 0.4572)
		(layer "F.Cu")
		(net "P3V3_AUX")
	)
	(segment
		(start 452.143622 -47.92091)
		(end 451.81012 -47.92091)
		(width 0.254)
		(layer "F.Cu")
		(net "P3V3_AUX")
	)
	(segment
		(start 325.39305 -232.156)
		(end 325.39305 -231.41305)
		(width 0.4572)
		(layer "F.Cu")
		(net "P3V3_AUX")
	)
	(segment
		(start 369.895628 -83.784694)
		(end 370.60124 -83.784694)
		(width 0.4572)
		(layer "F.Cu")
		(net "P3V3_AUX")
	)
	(segment
		(start 80.454754 -23.361396)
		(end 80.454754 -23.970996)
		(width 0.4572)
		(layer "F.Cu")
		(net "P3V3_AUX")
	)
	(segment
		(start 277.742396 -415.29)
		(end 277.742396 -416.106102)
		(width 0.4572)
		(layer "F.Cu")
		(net "P3V3_AUX")
	)
	(segment
		(start 31.58236 -36.286948)
		(end 30.94736 -36.286948)
		(width 0.4572)
		(layer "F.Cu")
		(net "P3V3_AUX")
	)
	(segment
		(start 375.426224 -40.82161)
		(end 375.27611 -40.971724)
		(width 0.4572)
		(layer "F.Cu")
		(net "P3V3_AUX")
	)
	(segment
		(start 284.843728 -42.84091)
		(end 285.51505 -42.84091)
		(width 0.254)
		(layer "F.Cu")
		(net "P3V3_AUX")
	)
	(segment
		(start 16.359632 -148.017738)
		(end 16.359632 -147.042378)
		(width 0.4064)
		(layer "F.Cu")
		(net "P3V3_AUX")
	)
	(segment
		(start 328.311764 -205.078584)
		(end 327.731374 -205.078584)
		(width 0.4572)
		(layer "F.Cu")
		(net "P3V3_AUX")
	)
	(segment
		(start 279.121616 -404.073614)
		(end 279.018492 -403.97049)
		(width 0.4572)
		(layer "F.Cu")
		(net "P3V3_AUX")
	)
	(segment
		(start 231.264968 -79.005684)
		(end 231.916478 -79.005684)
		(width 0.1778)
		(layer "F.Cu")
		(net "P3V3_AUX")
	)
	(segment
		(start 139.385294 -90.099642)
		(end 140.090144 -90.099642)
		(width 0.4572)
		(layer "F.Cu")
		(net "P3V3_AUX")
	)
	(segment
		(start 141.660626 -21.603208)
		(end 141.162532 -22.101302)
		(width 0.4572)
		(layer "F.Cu")
		(net "P3V3_AUX")
	)
	(segment
		(start 79.12608 -40.13581)
		(end 79.12608 -40.82161)
		(width 0.4572)
		(layer "F.Cu")
		(net "P3V3_AUX")
	)
	(segment
		(start 56.22925 -117.5512)
		(end 56.22925 -118.007384)
		(width 0.4064)
		(layer "F.Cu")
		(net "P3V3_AUX")
	)
	(segment
		(start 275.871432 -387.752082)
		(end 275.153882 -387.752082)
		(width 0.4572)
		(layer "F.Cu")
		(net "P3V3_AUX")
	)
	(segment
		(start 144.554956 -23.361396)
		(end 144.554956 -23.970996)
		(width 0.4572)
		(layer "F.Cu")
		(net "P3V3_AUX")
	)
	(segment
		(start 242.207034 -199.736964)
		(end 242.589304 -199.354694)
		(width 0.4572)
		(layer "F.Cu")
		(net "P3V3_AUX")
	)
	(segment
		(start 216.480136 -179.448206)
		(end 216.226136 -179.194206)
		(width 0.4572)
		(layer "F.Cu")
		(net "P3V3_AUX")
	)
	(segment
		(start 225.867722 -217.504264)
		(end 225.467926 -217.104468)
		(width 0.381)
		(layer "F.Cu")
		(net "P3V3_AUX")
	)
	(segment
		(start 213.409022 -221.350586)
		(end 213.343236 -221.2848)
		(width 0.3048)
		(layer "F.Cu")
		(net "P3V3_AUX")
	)
	(segment
		(start 22.271736 -153.1112)
		(end 22.271736 -153.782522)
		(width 0.4064)
		(layer "F.Cu")
		(net "P3V3_AUX")
	)
	(segment
		(start 299.647864 -86.143592)
		(end 297.614848 -86.143592)
		(width 0.4572)
		(layer "F.Cu")
		(net "P3V3_AUX")
	)
	(segment
		(start 264.256266 -61.487812)
		(end 264.88644 -61.487812)
		(width 0.4572)
		(layer "F.Cu")
		(net "P3V3_AUX")
	)
	(segment
		(start 320.019934 -288.378138)
		(end 320.176906 -288.221166)
		(width 0.4572)
		(layer "F.Cu")
		(net "P3V3_AUX")
	)
	(segment
		(start 337.206336 -197.87362)
		(end 337.902296 -197.87362)
		(width 0.4572)
		(layer "F.Cu")
		(net "P3V3_AUX")
	)
	(segment
		(start 16.359632 -147.042378)
		(end 16.779748 -147.042378)
		(width 0.254)
		(layer "F.Cu")
		(net "P3V3_AUX")
	)
	(segment
		(start 203.025756 -374.208802)
		(end 203.025756 -374.826022)
		(width 0.4572)
		(layer "F.Cu")
		(net "P3V3_AUX")
	)
	(segment
		(start 216.937844 -95.73895)
		(end 216.937844 -95.123)
		(width 0.4572)
		(layer "F.Cu")
		(net "P3V3_AUX")
	)
	(segment
		(start 345.36126 -262.703564)
		(end 344.74531 -262.703564)
		(width 0.381)
		(layer "F.Cu")
		(net "P3V3_AUX")
	)
	(segment
		(start 36.604702 -141.87297)
		(end 36.604702 -140.85697)
		(width 0.4064)
		(layer "F.Cu")
		(net "P3V3_AUX")
	)
	(segment
		(start 286.654748 -23.361396)
		(end 286.654748 -23.970996)
		(width 0.4572)
		(layer "F.Cu")
		(net "P3V3_AUX")
	)
	(segment
		(start 376.40895 -173.13402)
		(end 375.656856 -173.13402)
		(width 0.4572)
		(layer "F.Cu")
		(net "P3V3_AUX")
	)
	(segment
		(start 288.429192 -118.016528)
		(end 288.195766 -118.249954)
		(width 0.4064)
		(layer "F.Cu")
		(net "P3V3_AUX")
	)
	(segment
		(start 327.533 -240.55705)
		(end 327.533 -241.173)
		(width 0.4572)
		(layer "F.Cu")
		(net "P3V3_AUX")
	)
	(segment
		(start 324.859904 -102.480364)
		(end 324.261988 -101.882448)
		(width 0.254)
		(layer "F.Cu")
		(net "P3V3_AUX")
	)
	(segment
		(start 17.853914 -414.369758)
		(end 17.853914 -414.985454)
		(width 0.4572)
		(layer "F.Cu")
		(net "P3V3_AUX")
	)
	(segment
		(start 298.34713 -196.706236)
		(end 298.34713 -197.58914)
		(width 0.4572)
		(layer "F.Cu")
		(net "P3V3_AUX")
	)
	(segment
		(start 335.64195 -145.923)
		(end 335.026 -145.923)
		(width 0.4572)
		(layer "F.Cu")
		(net "P3V3_AUX")
	)
	(segment
		(start 363.07395 -199.771)
		(end 363.07395 -198.755)
		(width 0.4572)
		(layer "F.Cu")
		(net "P3V3_AUX")
	)
	(segment
		(start 278.451056 -401.930108)
		(end 278.451056 -400.000978)
		(width 0.4572)
		(layer "F.Cu")
		(net "P3V3_AUX")
	)
	(segment
		(start 142.743936 -42.84091)
		(end 143.415258 -42.84091)
		(width 0.254)
		(layer "F.Cu")
		(net "P3V3_AUX")
	)
	(segment
		(start 389.354568 -241.811048)
		(end 390.330436 -241.811048)
		(width 0.2794)
		(layer "F.Cu")
		(net "P3V3_AUX")
	)
	(segment
		(start 325.612506 -199.282304)
		(end 325.002906 -199.282304)
		(width 0.4572)
		(layer "F.Cu")
		(net "P3V3_AUX")
	)
	(segment
		(start 404.955248 -380.064264)
		(end 404.955248 -381.50165)
		(width 0.4572)
		(layer "F.Cu")
		(net "P3V3_AUX")
	)
	(segment
		(start 386.208524 -114.86515)
		(end 386.578602 -115.235228)
		(width 0.4064)
		(layer "F.Cu")
		(net "P3V3_AUX")
	)
	(segment
		(start 355.949758 -157.812994)
		(end 355.332284 -157.812994)
		(width 0.4572)
		(layer "F.Cu")
		(net "P3V3_AUX")
	)
	(segment
		(start 234.64266 -203.770738)
		(end 234.277408 -203.405486)
		(width 0.4572)
		(layer "F.Cu")
		(net "P3V3_AUX")
	)
	(segment
		(start 455.355198 -51.721258)
		(end 455.355198 -50.981864)
		(width 0.4572)
		(layer "F.Cu")
		(net "P3V3_AUX")
	)
	(segment
		(start 288.479992 -139.6492)
		(end 289.146742 -139.6492)
		(width 0.4572)
		(layer "F.Cu")
		(net "P3V3_AUX")
	)
	(segment
		(start 154.460194 -117.7544)
		(end 153.569924 -117.7544)
		(width 0.4064)
		(layer "F.Cu")
		(net "P3V3_AUX")
	)
	(segment
		(start 452.943722 -44.87291)
		(end 453.615044 -44.87291)
		(width 0.254)
		(layer "F.Cu")
		(net "P3V3_AUX")
	)
	(segment
		(start 290.508944 -26.03373)
		(end 289.849814 -26.03373)
		(width 0.4572)
		(layer "F.Cu")
		(net "P3V3_AUX")
	)
	(segment
		(start 224.109026 -190.57874)
		(end 224.54743 -190.57874)
		(width 0.4572)
		(layer "F.Cu")
		(net "P3V3_AUX")
	)
	(segment
		(start 220.848936 -175.94834)
		(end 220.848936 -176.826164)
		(width 0.4572)
		(layer "F.Cu")
		(net "P3V3_AUX")
	)
	(segment
		(start 145.28165 -203.964032)
		(end 144.159986 -203.964032)
		(width 0.2794)
		(layer "F.Cu")
		(net "P3V3_AUX")
	)
	(segment
		(start 357.768144 -382.789938)
		(end 360.902758 -379.655324)
		(width 0.4572)
		(layer "F.Cu")
		(net "P3V3_AUX")
	)
	(segment
		(start 326.263 -232.664)
		(end 325.616316 -232.664)
		(width 0.4572)
		(layer "F.Cu")
		(net "P3V3_AUX")
	)
	(segment
		(start 230.156512 -242.82781)
		(end 229.929944 -242.82781)
		(width 0.4572)
		(layer "F.Cu")
		(net "P3V3_AUX")
	)
	(segment
		(start 196.724016 -365.447326)
		(end 196.084444 -366.086898)
		(width 0.4572)
		(layer "F.Cu")
		(net "P3V3_AUX")
	)
	(segment
		(start 315.782198 -36.286948)
		(end 315.147198 -36.286948)
		(width 0.4572)
		(layer "F.Cu")
		(net "P3V3_AUX")
	)
	(segment
		(start 224.422208 -85.684868)
		(end 224.422208 -84.675472)
		(width 0.4572)
		(layer "F.Cu")
		(net "P3V3_AUX")
	)
	(segment
		(start 248.559574 -148.017738)
		(end 248.559574 -147.042378)
		(width 0.4064)
		(layer "F.Cu")
		(net "P3V3_AUX")
	)
	(segment
		(start 336.383884 -197.344284)
		(end 336.91322 -197.87362)
		(width 0.3048)
		(layer "F.Cu")
		(net "P3V3_AUX")
	)
	(segment
		(start 217.020648 -233.182668)
		(end 217.583512 -233.182668)
		(width 0.4572)
		(layer "F.Cu")
		(net "P3V3_AUX")
	)
	(segment
		(start 285.326074 -40.13581)
		(end 285.326074 -40.82161)
		(width 0.4572)
		(layer "F.Cu")
		(net "P3V3_AUX")
	)
	(segment
		(start 335.64195 -180.975)
		(end 335.026 -180.975)
		(width 0.4572)
		(layer "F.Cu")
		(net "P3V3_AUX")
	)
	(segment
		(start 141.660626 -20.789392)
		(end 141.660626 -21.603208)
		(width 0.4572)
		(layer "F.Cu")
		(net "P3V3_AUX")
	)
	(segment
		(start 139.385294 -92.385642)
		(end 140.090144 -92.385642)
		(width 0.4572)
		(layer "F.Cu")
		(net "P3V3_AUX")
	)
	(segment
		(start 258.04368 -47.92091)
		(end 257.710178 -47.92091)
		(width 0.254)
		(layer "F.Cu")
		(net "P3V3_AUX")
	)
	(segment
		(start 424.993562 -83.532218)
		(end 425.653962 -83.532218)
		(width 0.4064)
		(layer "F.Cu")
		(net "P3V3_AUX")
	)
	(segment
		(start 228.39299 -90.009726)
		(end 227.734368 -90.009726)
		(width 0.254)
		(layer "F.Cu")
		(net "P3V3_AUX")
	)
	(segment
		(start 360.25836 -253.178564)
		(end 360.86796 -253.178564)
		(width 0.381)
		(layer "F.Cu")
		(net "P3V3_AUX")
	)
	(segment
		(start 305.082702 -80.739742)
		(end 305.082702 -80.019906)
		(width 0.4572)
		(layer "F.Cu")
		(net "P3V3_AUX")
	)
	(segment
		(start 288.43732 -36.232592)
		(end 287.595056 -36.232592)
		(width 0.4572)
		(layer "F.Cu")
		(net "P3V3_AUX")
	)
	(segment
		(start 238.889794 -201.25182)
		(end 238.889794 -201.028554)
		(width 0.4572)
		(layer "F.Cu")
		(net "P3V3_AUX")
	)
	(segment
		(start 295.804844 -115.902486)
		(end 295.477692 -116.229638)
		(width 0.4572)
		(layer "F.Cu")
		(net "P3V3_AUX")
	)
	(segment
		(start 363.07395 -212.979)
		(end 362.458 -212.979)
		(width 0.4572)
		(layer "F.Cu")
		(net "P3V3_AUX")
	)
	(segment
		(start 82.291682 -36.286948)
		(end 82.237326 -36.232592)
		(width 0.4572)
		(layer "F.Cu")
		(net "P3V3_AUX")
	)
	(segment
		(start 374.943878 -44.87291)
		(end 375.6152 -44.87291)
		(width 0.254)
		(layer "F.Cu")
		(net "P3V3_AUX")
	)
	(segment
		(start 439.989468 -291.694616)
		(end 440.41695 -292.122098)
		(width 0.4572)
		(layer "F.Cu")
		(net "P3V3_AUX")
	)
	(segment
		(start 104.889808 -9.139682)
		(end 105.8926 -9.139682)
		(width 0.4572)
		(layer "F.Cu")
		(net "P3V3_AUX")
	)
	(segment
		(start 334.899 -244.32895)
		(end 334.772 -244.20195)
		(width 0.381)
		(layer "F.Cu")
		(net "P3V3_AUX")
	)
	(segment
		(start 404.943056 -374.16486)
		(end 404.31085 -374.16486)
		(width 0.4572)
		(layer "F.Cu")
		(net "P3V3_AUX")
	)
	(segment
		(start 251.128784 -206.697072)
		(end 250.825254 -206.393542)
		(width 0.4572)
		(layer "F.Cu")
		(net "P3V3_AUX")
	)
	(segment
		(start 136.675114 -48.753014)
		(end 137.650474 -48.753014)
		(width 0.254)
		(layer "F.Cu")
		(net "P3V3_AUX")
	)
	(segment
		(start 214.674958 -47.791878)
		(end 215.272874 -47.193962)
		(width 0.254)
		(layer "F.Cu")
		(net "P3V3_AUX")
	)
	(segment
		(start 335.64195 -165.989)
		(end 335.026 -165.989)
		(width 0.4572)
		(layer "F.Cu")
		(net "P3V3_AUX")
	)
	(segment
		(start 404.591774 -36.286948)
		(end 404.537418 -36.232592)
		(width 0.4572)
		(layer "F.Cu")
		(net "P3V3_AUX")
	)
	(segment
		(start 283.710126 -47.92091)
		(end 283.508196 -47.71898)
		(width 0.254)
		(layer "F.Cu")
		(net "P3V3_AUX")
	)
	(segment
		(start 230.349044 -177.74158)
		(end 228.971348 -177.74158)
		(width 0.4572)
		(layer "F.Cu")
		(net "P3V3_AUX")
	)
	(segment
		(start 321.223386 -96.411542)
		(end 321.223386 -95.801942)
		(width 0.4572)
		(layer "F.Cu")
		(net "P3V3_AUX")
	)
	(segment
		(start 146.337528 -36.232592)
		(end 145.495264 -36.232592)
		(width 0.4572)
		(layer "F.Cu")
		(net "P3V3_AUX")
	)
	(segment
		(start 52.643786 -42.84091)
		(end 53.315108 -42.84091)
		(width 0.254)
		(layer "F.Cu")
		(net "P3V3_AUX")
	)
	(segment
		(start 207.111346 -227.235258)
		(end 207.556608 -227.68052)
		(width 0.4572)
		(layer "F.Cu")
		(net "P3V3_AUX")
	)
	(segment
		(start 194.743832 -44.87291)
		(end 195.415154 -44.87291)
		(width 0.254)
		(layer "F.Cu")
		(net "P3V3_AUX")
	)
	(segment
		(start 77.06233 -22.101302)
		(end 77.06233 -22.555454)
		(width 0.4572)
		(layer "F.Cu")
		(net "P3V3_AUX")
	)
	(segment
		(start 334.772 -244.20195)
		(end 334.772 -242.807998)
		(width 0.381)
		(layer "F.Cu")
		(net "P3V3_AUX")
	)
	(segment
		(start 72.88276 -80.739742)
		(end 72.88276 -80.019906)
		(width 0.4572)
		(layer "F.Cu")
		(net "P3V3_AUX")
	)
	(segment
		(start 21.445982 -47.193962)
		(end 21.172932 -47.193962)
		(width 0.254)
		(layer "F.Cu")
		(net "P3V3_AUX")
	)
	(segment
		(start 309.262272 -22.555454)
		(end 309.918354 -22.555454)
		(width 0.4572)
		(layer "F.Cu")
		(net "P3V3_AUX")
	)
	(segment
		(start 369.658138 -240.276126)
		(end 369.2652 -240.276126)
		(width 0.3556)
		(layer "F.Cu")
		(net "P3V3_AUX")
	)
	(segment
		(start 113.161064 -262.703564)
		(end 112.545114 -262.703564)
		(width 0.381)
		(layer "F.Cu")
		(net "P3V3_AUX")
	)
	(segment
		(start 352.639884 -234.114086)
		(end 352.80092 -233.95305)
		(width 0.4572)
		(layer "F.Cu")
		(net "P3V3_AUX")
	)
	(segment
		(start 30.94736 -36.286948)
		(end 30.291786 -36.286948)
		(width 0.4572)
		(layer "F.Cu")
		(net "P3V3_AUX")
	)
	(segment
		(start 235.965746 -120.781318)
		(end 235.965746 -121.398792)
		(width 0.4572)
		(layer "F.Cu")
		(net "P3V3_AUX")
	)
	(segment
		(start 229.554786 -242.452652)
		(end 229.554786 -241.644932)
		(width 0.4572)
		(layer "F.Cu")
		(net "P3V3_AUX")
	)
	(segment
		(start 203.106274 -260.46176)
		(end 203.106274 -258.65074)
		(width 0.4572)
		(layer "F.Cu")
		(net "P3V3_AUX")
	)
	(segment
		(start 279.841198 -407.957528)
		(end 279.841198 -407.615136)
		(width 0.4572)
		(layer "F.Cu")
		(net "P3V3_AUX")
	)
	(segment
		(start 237.750604 -184.7723)
		(end 238.385604 -184.7723)
		(width 0.4572)
		(layer "F.Cu")
		(net "P3V3_AUX")
	)
	(segment
		(start 259.326126 -40.13581)
		(end 259.326126 -40.82161)
		(width 0.4572)
		(layer "F.Cu")
		(net "P3V3_AUX")
	)
	(segment
		(start 193.34099 -367.266728)
		(end 193.34099 -368.830352)
		(width 0.4572)
		(layer "F.Cu")
		(net "P3V3_AUX")
	)
	(segment
		(start 336.296 -236.45495)
		(end 336.1182 -236.27715)
		(width 0.4572)
		(layer "F.Cu")
		(net "P3V3_AUX")
	)
	(segment
		(start 198.39178 -36.286948)
		(end 198.337424 -36.232592)
		(width 0.4572)
		(layer "F.Cu")
		(net "P3V3_AUX")
	)
	(segment
		(start 363.07395 -195.707)
		(end 362.458 -195.707)
		(width 0.4572)
		(layer "F.Cu")
		(net "P3V3_AUX")
	)
	(segment
		(start 237.147354 -36.286948)
		(end 236.49178 -36.286948)
		(width 0.4572)
		(layer "F.Cu")
		(net "P3V3_AUX")
	)
	(segment
		(start 320.770504 -83.261454)
		(end 320.56705 -83.058)
		(width 0.4572)
		(layer "F.Cu")
		(net "P3V3_AUX")
	)
	(segment
		(start 451.669658 -365.895382)
		(end 451.669658 -365.277146)
		(width 0.4572)
		(layer "F.Cu")
		(net "P3V3_AUX")
	)
	(segment
		(start 188.982604 -80.739742)
		(end 188.605668 -80.362806)
		(width 0.4572)
		(layer "F.Cu")
		(net "P3V3_AUX")
	)
	(segment
		(start 297.944794 -198.001128)
		(end 297.506136 -198.439786)
		(width 0.3556)
		(layer "F.Cu")
		(net "P3V3_AUX")
	)
	(segment
		(start 108.15828 -193.001138)
		(end 109.030262 -193.001138)
		(width 0.2794)
		(layer "F.Cu")
		(net "P3V3_AUX")
	)
	(segment
		(start 182.148734 -198.109332)
		(end 182.228236 -198.188834)
		(width 0.4572)
		(layer "F.Cu")
		(net "P3V3_AUX")
	)
	(segment
		(start 222.690944 -97.96907)
		(end 222.690944 -97.31375)
		(width 0.4064)
		(layer "F.Cu")
		(net "P3V3_AUX")
	)
	(segment
		(start 187.78347 -411.99181)
		(end 188.39307 -411.99181)
		(width 0.4572)
		(layer "F.Cu")
		(net "P3V3_AUX")
	)
	(segment
		(start 410.572458 -210.341718)
		(end 409.731718 -210.341718)
		(width 0.4572)
		(layer "F.Cu")
		(net "P3V3_AUX")
	)
	(segment
		(start 208.185766 -227.50907)
		(end 207.728058 -227.50907)
		(width 0.4572)
		(layer "F.Cu")
		(net "P3V3_AUX")
	)
	(segment
		(start 7.649718 -159.844994)
		(end 7.032244 -159.844994)
		(width 0.4572)
		(layer "F.Cu")
		(net "P3V3_AUX")
	)
	(segment
		(start 388.50697 -236.311186)
		(end 387.925818 -236.892338)
		(width 0.2794)
		(layer "F.Cu")
		(net "P3V3_AUX")
	)
	(segment
		(start 205.422246 -209.294476)
		(end 205.422246 -209.866992)
		(width 0.4572)
		(layer "F.Cu")
		(net "P3V3_AUX")
	)
	(segment
		(start 248.494804 -273.471386)
		(end 249.166126 -273.471386)
		(width 0.4572)
		(layer "F.Cu")
		(net "P3V3_AUX")
	)
	(segment
		(start 202.473814 -88.993472)
		(end 200.734676 -90.73261)
		(width 0.4572)
		(layer "F.Cu")
		(net "P3V3_AUX")
	)
	(segment
		(start 203.603098 -82.643472)
		(end 204.191108 -82.643472)
		(width 0.4572)
		(layer "F.Cu")
		(net "P3V3_AUX")
	)
	(segment
		(start 377.435618 -213.859872)
		(end 376.432064 -213.859872)
		(width 0.4572)
		(layer "F.Cu")
		(net "P3V3_AUX")
	)
	(segment
		(start 180.135276 -196.833744)
		(end 181.423818 -196.833744)
		(width 0.3556)
		(layer "F.Cu")
		(net "P3V3_AUX")
	)
	(segment
		(start 92.899992 -288.830766)
		(end 92.899992 -288.11855)
		(width 0.4572)
		(layer "F.Cu")
		(net "P3V3_AUX")
	)
	(segment
		(start 249.085862 -356.900226)
		(end 249.970544 -356.015544)
		(width 0.4572)
		(layer "F.Cu")
		(net "P3V3_AUX")
	)
	(segment
		(start 193.34099 -368.830352)
		(end 186.13755 -376.033792)
		(width 0.4572)
		(layer "F.Cu")
		(net "P3V3_AUX")
	)
	(segment
		(start 137.54608 -47.193962)
		(end 137.273538 -47.193962)
		(width 0.254)
		(layer "F.Cu")
		(net "P3V3_AUX")
	)
	(segment
		(start 373.608346 -47.71898)
		(end 373.608346 -47.403766)
		(width 0.254)
		(layer "F.Cu")
		(net "P3V3_AUX")
	)
	(segment
		(start 340.961472 -190.41745)
		(end 341.571072 -190.41745)
		(width 0.4572)
		(layer "F.Cu")
		(net "P3V3_AUX")
	)
	(segment
		(start 36.604702 -142.88897)
		(end 36.604702 -141.87297)
		(width 0.4064)
		(layer "F.Cu")
		(net "P3V3_AUX")
	)
	(segment
		(start 278.774906 -47.791878)
		(end 278.774906 -48.753014)
		(width 0.254)
		(layer "F.Cu")
		(net "P3V3_AUX")
	)
	(segment
		(start 2.306828 -34.490406)
		(end 1.650746 -34.490406)
		(width 0.4572)
		(layer "F.Cu")
		(net "P3V3_AUX")
	)
	(segment
		(start 166.67353 -167.742108)
		(end 166.134288 -167.202866)
		(width 0.381)
		(layer "F.Cu")
		(net "P3V3_AUX")
	)
	(segment
		(start 141.162532 -22.555454)
		(end 141.818614 -22.555454)
		(width 0.4572)
		(layer "F.Cu")
		(net "P3V3_AUX")
	)
	(segment
		(start 320.56705 -83.058)
		(end 320.56705 -82.31505)
		(width 0.4572)
		(layer "F.Cu")
		(net "P3V3_AUX")
	)
	(segment
		(start 208.999074 -214.466678)
		(end 208.728056 -214.737696)
		(width 0.4572)
		(layer "F.Cu")
		(net "P3V3_AUX")
	)
	(segment
		(start 402.754846 -23.361396)
		(end 402.754846 -23.970996)
		(width 0.4572)
		(layer "F.Cu")
		(net "P3V3_AUX")
	)
	(segment
		(start 222.663512 -231.816656)
		(end 222.663512 -232.471468)
		(width 0.4572)
		(layer "F.Cu")
		(net "P3V3_AUX")
	)
	(segment
		(start 109.95533 -35.876738)
		(end 109.199426 -35.876738)
		(width 0.4572)
		(layer "F.Cu")
		(net "P3V3_AUX")
	)
	(segment
		(start 383.55905 -211.880196)
		(end 383.673858 -211.765388)
		(width 0.4572)
		(layer "F.Cu")
		(net "P3V3_AUX")
	)
	(segment
		(start 399.608294 -47.71898)
		(end 399.608294 -47.403766)
		(width 0.254)
		(layer "F.Cu")
		(net "P3V3_AUX")
	)
	(segment
		(start 373.761 -192.25895)
		(end 373.233696 -192.25895)
		(width 0.4572)
		(layer "F.Cu")
		(net "P3V3_AUX")
	)
	(segment
		(start 369.895628 -82.641694)
		(end 370.60124 -82.641694)
		(width 0.4572)
		(layer "F.Cu")
		(net "P3V3_AUX")
	)
	(via
		(at 404.31085 -374.16486)
		(size 0.508)
		(drill 0.254)
		(layers "F.Cu" "B.Cu")
		(net "P3V3_AUX")
	)
	(via
		(at 129.350262 -116.037106)
		(size 0.508)
		(drill 0.254)
		(layers "F.Cu" "B.Cu")
		(net "P3V3_AUX")
	)
	(via
		(at 112.523016 -140.33246)
		(size 0.508)
		(drill 0.254)
		(layers "F.Cu" "B.Cu")
		(net "P3V3_AUX")
	)
	(via
		(at 277.082504 -394.762482)
		(size 0.508)
		(drill 0.254)
		(layers "F.Cu" "B.Cu")
		(net "P3V3_AUX")
	)
	(via
		(at 5.995162 -368.23269)
		(size 0.508)
		(drill 0.254)
		(layers "F.Cu" "B.Cu")
		(net "P3V3_AUX")
	)
	(via
		(at 80.93964 -136.98601)
		(size 0.508)
		(drill 0.254)
		(layers "F.Cu" "B.Cu")
		(net "P3V3_AUX")
	)
	(via
		(at 362.185458 -116.672106)
		(size 0.508)
		(drill 0.254)
		(layers "F.Cu" "B.Cu")
		(net "P3V3_AUX")
	)
	(via
		(at 327.28027 -123.33732)
		(size 0.508)
		(drill 0.254)
		(layers "F.Cu" "B.Cu")
		(net "P3V3_AUX")
	)
	(via
		(at 5.04317 -35.905948)
		(size 0.508)
		(drill 0.254)
		(layers "F.Cu" "B.Cu")
		(net "P3V3_AUX")
	)
	(via
		(at 275.153882 -387.752082)
		(size 0.508)
		(drill 0.254)
		(layers "F.Cu" "B.Cu")
		(net "P3V3_AUX")
	)
	(via
		(at 254.471678 -153.782522)
		(size 0.508)
		(drill 0.254)
		(layers "F.Cu" "B.Cu")
		(net "P3V3_AUX")
	)
	(via
		(at 4.988052 -57.48528)
		(size 0.508)
		(drill 0.254)
		(layers "F.Cu" "B.Cu")
		(net "P3V3_AUX")
	)
	(via
		(at 440.371484 -97.821242)
		(size 0.508)
		(drill 0.254)
		(layers "F.Cu" "B.Cu")
		(net "P3V3_AUX")
	)
	(via
		(at 379.271276 -56.38038)
		(size 0.508)
		(drill 0.254)
		(layers "F.Cu" "B.Cu")
		(net "P3V3_AUX")
	)
	(via
		(at 325.82104 -101.870764)
		(size 0.508)
		(drill 0.254)
		(layers "F.Cu" "B.Cu")
		(net "P3V3_AUX")
	)
	(via
		(at 405.19604 -138.95705)
		(size 0.508)
		(drill 0.254)
		(layers "F.Cu" "B.Cu")
		(net "P3V3_AUX")
	)
	(via
		(at 55.316882 -55.39359)
		(size 0.508)
		(drill 0.254)
		(layers "F.Cu" "B.Cu")
		(net "P3V3_AUX")
	)
	(via
		(at 261.516876 -55.39359)
		(size 0.508)
		(drill 0.254)
		(layers "F.Cu" "B.Cu")
		(net "P3V3_AUX")
	)
	(via
		(at 143.370554 -30.376876)
		(size 0.508)
		(drill 0.254)
		(layers "F.Cu" "B.Cu")
		(net "P3V3_AUX")
	)
	(via
		(at 249.970544 -356.015544)
		(size 0.508)
		(drill 0.254)
		(layers "F.Cu" "B.Cu")
		(net "P3V3_AUX")
	)
	(via
		(at 375.858786 -188.849)
		(size 0.508)
		(drill 0.254)
		(layers "F.Cu" "B.Cu")
		(net "P3V3_AUX")
	)
	(via
		(at 89.023444 -95.801942)
		(size 0.508)
		(drill 0.254)
		(layers "F.Cu" "B.Cu")
		(net "P3V3_AUX")
	)
	(via
		(at 259.56133 -208.019396)
		(size 0.508)
		(drill 0.254)
		(layers "F.Cu" "B.Cu")
		(net "P3V3_AUX")
	)
	(via
		(at 441.921138 -101.870764)
		(size 0.508)
		(drill 0.254)
		(layers "F.Cu" "B.Cu")
		(net "P3V3_AUX")
	)
	(via
		(at 309.508144 -47.403766)
		(size 0.508)
		(drill 0.254)
		(layers "F.Cu" "B.Cu")
		(net "P3V3_AUX")
	)
	(via
		(at 327.75652 -125.180344)
		(size 0.508)
		(drill 0.254)
		(layers "F.Cu" "B.Cu")
		(net "P3V3_AUX")
	)
	(via
		(at 118.071392 -117.999764)
		(size 0.508)
		(drill 0.254)
		(layers "F.Cu" "B.Cu")
		(net "P3V3_AUX")
	)
	(via
		(at 373.61495 -233.82605)
		(size 0.508)
		(drill 0.254)
		(layers "F.Cu" "B.Cu")
		(net "P3V3_AUX")
	)
	(via
		(at 351.617026 -55.39359)
		(size 0.508)
		(drill 0.254)
		(layers "F.Cu" "B.Cu")
		(net "P3V3_AUX")
	)
	(via
		(at 17.853914 -414.985454)
		(size 0.508)
		(drill 0.254)
		(layers "F.Cu" "B.Cu")
		(net "P3V3_AUX")
	)
	(via
		(at 380.649734 -5.852922)
		(size 0.508)
		(drill 0.254)
		(layers "F.Cu" "B.Cu")
		(net "P3V3_AUX")
	)
	(via
		(at 232.854246 -275.503386)
		(size 0.508)
		(drill 0.254)
		(layers "F.Cu" "B.Cu")
		(net "P3V3_AUX")
	)
	(via
		(at 169.076116 -40.971724)
		(size 0.508)
		(drill 0.254)
		(layers "F.Cu" "B.Cu")
		(net "P3V3_AUX")
	)
	(via
		(at 405.949912 -26.03373)
		(size 0.508)
		(drill 0.254)
		(layers "F.Cu" "B.Cu")
		(net "P3V3_AUX")
	)
	(via
		(at 429.864266 -158.219648)
		(size 0.508)
		(drill 0.254)
		(layers "F.Cu" "B.Cu")
		(net "P3V3_AUX")
	)
	(via
		(at 153.707338 -97.1804)
		(size 0.508)
		(drill 0.254)
		(layers "F.Cu" "B.Cu")
		(net "P3V3_AUX")
	)
	(via
		(at 359.385362 -119.35587)
		(size 0.508)
		(drill 0.254)
		(layers "F.Cu" "B.Cu")
		(net "P3V3_AUX")
	)
	(via
		(at 122.65787 -139.376404)
		(size 0.508)
		(drill 0.254)
		(layers "F.Cu" "B.Cu")
		(net "P3V3_AUX")
	)
	(via
		(at 384.088894 -243.215414)
		(size 0.508)
		(drill 0.254)
		(layers "F.Cu" "B.Cu")
		(net "P3V3_AUX")
	)
	(via
		(at 356.87 -167.64)
		(size 0.508)
		(drill 0.254)
		(layers "F.Cu" "B.Cu")
		(net "P3V3_AUX")
	)
	(via
		(at 30.971236 -55.11038)
		(size 0.508)
		(drill 0.254)
		(layers "F.Cu" "B.Cu")
		(net "P3V3_AUX")
	)
	(via
		(at 287.516824 -55.39359)
		(size 0.508)
		(drill 0.254)
		(layers "F.Cu" "B.Cu")
		(net "P3V3_AUX")
	)
	(via
		(at 115.572286 -138.255248)
		(size 0.508)
		(drill 0.254)
		(layers "F.Cu" "B.Cu")
		(net "P3V3_AUX")
	)
	(via
		(at 289.18789 -57.48528)
		(size 0.508)
		(drill 0.254)
		(layers "F.Cu" "B.Cu")
		(net "P3V3_AUX")
	)
	(via
		(at 91.247214 -113.538254)
		(size 0.508)
		(drill 0.254)
		(layers "F.Cu" "B.Cu")
		(net "P3V3_AUX")
	)
	(via
		(at 4.971288 -55.74538)
		(size 0.508)
		(drill 0.254)
		(layers "F.Cu" "B.Cu")
		(net "P3V3_AUX")
	)
	(via
		(at 332.92161 -209.039714)
		(size 0.508)
		(drill 0.254)
		(layers "F.Cu" "B.Cu")
		(net "P3V3_AUX")
	)
	(via
		(at 81.47939 -140.534898)
		(size 0.508)
		(drill 0.254)
		(layers "F.Cu" "B.Cu")
		(net "P3V3_AUX")
	)
	(via
		(at 263.171178 -56.38038)
		(size 0.508)
		(drill 0.254)
		(layers "F.Cu" "B.Cu")
		(net "P3V3_AUX")
	)
	(via
		(at 452.124064 -222.0976)
		(size 0.508)
		(drill 0.254)
		(layers "F.Cu" "B.Cu")
		(net "P3V3_AUX")
	)
	(via
		(at 395.850364 -48.753014)
		(size 0.508)
		(drill 0.254)
		(layers "F.Cu" "B.Cu")
		(net "P3V3_AUX")
	)
	(via
		(at 147.071334 -55.74538)
		(size 0.508)
		(drill 0.254)
		(layers "F.Cu" "B.Cu")
		(net "P3V3_AUX")
	)
	(via
		(at 233.933746 -121.398792)
		(size 0.508)
		(drill 0.254)
		(layers "F.Cu" "B.Cu")
		(net "P3V3_AUX")
	)
	(via
		(at 452.771002 -248.83364)
		(size 0.508)
		(drill 0.254)
		(layers "F.Cu" "B.Cu")
		(net "P3V3_AUX")
	)
	(via
		(at 213.419436 -222.366586)
		(size 0.508)
		(drill 0.254)
		(layers "F.Cu" "B.Cu")
		(net "P3V3_AUX")
	)
	(via
		(at 206.504286 -208.212436)
		(size 0.508)
		(drill 0.254)
		(layers "F.Cu" "B.Cu")
		(net "P3V3_AUX")
	)
	(via
		(at 281.33548 -407.314908)
		(size 0.508)
		(drill 0.254)
		(layers "F.Cu" "B.Cu")
		(net "P3V3_AUX")
	)
	(via
		(at 228.759512 -233.182668)
		(size 0.508)
		(drill 0.254)
		(layers "F.Cu" "B.Cu")
		(net "P3V3_AUX")
	)
	(via
		(at 353.336098 -147.654518)
		(size 0.508)
		(drill 0.254)
		(layers "F.Cu" "B.Cu")
		(net "P3V3_AUX")
	)
	(via
		(at 25.308306 -47.403766)
		(size 0.508)
		(drill 0.254)
		(layers "F.Cu" "B.Cu")
		(net "P3V3_AUX")
	)
	(via
		(at 83.582256 -36.286948)
		(size 0.508)
		(drill 0.254)
		(layers "F.Cu" "B.Cu")
		(net "P3V3_AUX")
	)
	(via
		(at 290.886388 -61.487812)
		(size 0.508)
		(drill 0.254)
		(layers "F.Cu" "B.Cu")
		(net "P3V3_AUX")
	)
	(via
		(at 219.818458 -22.555454)
		(size 0.508)
		(drill 0.254)
		(layers "F.Cu" "B.Cu")
		(net "P3V3_AUX")
	)
	(via
		(at 78.975966 -40.971724)
		(size 0.508)
		(drill 0.254)
		(layers "F.Cu" "B.Cu")
		(net "P3V3_AUX")
	)
	(via
		(at 256.130298 -350.722438)
		(size 0.508)
		(drill 0.254)
		(layers "F.Cu" "B.Cu")
		(net "P3V3_AUX")
	)
	(via
		(at 363.959902 -398.444466)
		(size 0.508)
		(drill 0.254)
		(layers "F.Cu" "B.Cu")
		(net "P3V3_AUX")
	)
	(via
		(at 335.026 -184.023)
		(size 0.508)
		(drill 0.254)
		(layers "F.Cu" "B.Cu")
		(net "P3V3_AUX")
	)
	(via
		(at 404.582122 -54.96179)
		(size 0.508)
		(drill 0.254)
		(layers "F.Cu" "B.Cu")
		(net "P3V3_AUX")
	)
	(via
		(at 332.92161 -207.769714)
		(size 0.508)
		(drill 0.254)
		(layers "F.Cu" "B.Cu")
		(net "P3V3_AUX")
	)
	(via
		(at 171.510198 -118.265194)
		(size 0.508)
		(drill 0.254)
		(layers "F.Cu" "B.Cu")
		(net "P3V3_AUX")
	)
	(via
		(at 95.818198 -94.24924)
		(size 0.508)
		(drill 0.254)
		(layers "F.Cu" "B.Cu")
		(net "P3V3_AUX")
	)
	(via
		(at 336.296 -236.45495)
		(size 0.508)
		(drill 0.254)
		(layers "F.Cu" "B.Cu")
		(net "P3V3_AUX")
	)
	(via
		(at 358.14 -173.99)
		(size 0.508)
		(drill 0.254)
		(layers "F.Cu" "B.Cu")
		(net "P3V3_AUX")
	)
	(via
		(at 288.195766 -118.249954)
		(size 0.508)
		(drill 0.254)
		(layers "F.Cu" "B.Cu")
		(net "P3V3_AUX")
	)
	(via
		(at 279.018492 -403.97049)
		(size 0.508)
		(drill 0.254)
		(layers "F.Cu" "B.Cu")
		(net "P3V3_AUX")
	)
	(via
		(at 330.835 -238.633)
		(size 0.508)
		(drill 0.254)
		(layers "F.Cu" "B.Cu")
		(net "P3V3_AUX")
	)
	(via
		(at 359.820972 -252.045978)
		(size 0.508)
		(drill 0.254)
		(layers "F.Cu" "B.Cu")
		(net "P3V3_AUX")
	)
	(via
		(at 375.623328 -52.035456)
		(size 0.508)
		(drill 0.254)
		(layers "F.Cu" "B.Cu")
		(net "P3V3_AUX")
	)
	(via
		(at 401.615148 -42.84091)
		(size 0.508)
		(drill 0.254)
		(layers "F.Cu" "B.Cu")
		(net "P3V3_AUX")
	)
	(via
		(at 256.224786 -260.0706)
		(size 0.508)
		(drill 0.254)
		(layers "F.Cu" "B.Cu")
		(net "P3V3_AUX")
	)
	(via
		(at 405.24684 -139.6492)
		(size 0.508)
		(drill 0.254)
		(layers "F.Cu" "B.Cu")
		(net "P3V3_AUX")
	)
	(via
		(at 56.987948 -57.48528)
		(size 0.508)
		(drill 0.254)
		(layers "F.Cu" "B.Cu")
		(net "P3V3_AUX")
	)
	(via
		(at 342.2142 -286.596328)
		(size 0.508)
		(drill 0.254)
		(layers "F.Cu" "B.Cu")
		(net "P3V3_AUX")
	)
	(via
		(at 378.82195 -202.79995)
		(size 0.508)
		(drill 0.254)
		(layers "F.Cu" "B.Cu")
		(net "P3V3_AUX")
	)
	(via
		(at 87.976964 -288.221166)
		(size 0.508)
		(drill 0.254)
		(layers "F.Cu" "B.Cu")
		(net "P3V3_AUX")
	)
	(via
		(at 375.297446 -91.1098)
		(size 0.508)
		(drill 0.254)
		(layers "F.Cu" "B.Cu")
		(net "P3V3_AUX")
	)
	(via
		(at 70.071742 -117.723666)
		(size 0.508)
		(drill 0.254)
		(layers "F.Cu" "B.Cu")
		(net "P3V3_AUX")
	)
	(via
		(at 143.415258 -42.84091)
		(size 0.508)
		(drill 0.254)
		(layers "F.Cu" "B.Cu")
		(net "P3V3_AUX")
	)
	(via
		(at 245.306596 -179.554378)
		(size 0.508)
		(drill 0.254)
		(layers "F.Cu" "B.Cu")
		(net "P3V3_AUX")
	)
	(via
		(at 458.155548 -372.677944)
		(size 0.508)
		(drill 0.254)
		(layers "F.Cu" "B.Cu")
		(net "P3V3_AUX")
	)
	(via
		(at 401.615148 -44.87291)
		(size 0.508)
		(drill 0.254)
		(layers "F.Cu" "B.Cu")
		(net "P3V3_AUX")
	)
	(via
		(at 233.47045 -29.614876)
		(size 0.508)
		(drill 0.254)
		(layers "F.Cu" "B.Cu")
		(net "P3V3_AUX")
	)
	(via
		(at 370.60124 -88.356694)
		(size 0.508)
		(drill 0.254)
		(layers "F.Cu" "B.Cu")
		(net "P3V3_AUX")
	)
	(via
		(at 226.267772 -217.104468)
		(size 0.4572)
		(drill 0.254)
		(layers "F.Cu" "B.Cu")
		(net "P3V3_AUX")
	)
	(via
		(at 14.393418 -116.799106)
		(size 0.508)
		(drill 0.254)
		(layers "F.Cu" "B.Cu")
		(net "P3V3_AUX")
	)
	(via
		(at 431.271172 -56.38038)
		(size 0.508)
		(drill 0.254)
		(layers "F.Cu" "B.Cu")
		(net "P3V3_AUX")
	)
	(via
		(at 57.649872 -26.03373)
		(size 0.508)
		(drill 0.254)
		(layers "F.Cu" "B.Cu")
		(net "P3V3_AUX")
	)
	(via
		(at 375.832878 -186.817)
		(size 0.508)
		(drill 0.254)
		(layers "F.Cu" "B.Cu")
		(net "P3V3_AUX")
	)
	(via
		(at 237.68431 -223.092518)
		(size 0.508)
		(drill 0.254)
		(layers "F.Cu" "B.Cu")
		(net "P3V3_AUX")
	)
	(via
		(at 54.605682 -55.39359)
		(size 0.508)
		(drill 0.254)
		(layers "F.Cu" "B.Cu")
		(net "P3V3_AUX")
	)
	(via
		(at 98.9838 -390.3726)
		(size 0.508)
		(drill 0.254)
		(layers "F.Cu" "B.Cu")
		(net "P3V3_AUX")
	)
	(via
		(at 275.963126 -403.46249)
		(size 0.508)
		(drill 0.254)
		(layers "F.Cu" "B.Cu")
		(net "P3V3_AUX")
	)
	(via
		(at 358.14 -177.038)
		(size 0.508)
		(drill 0.254)
		(layers "F.Cu" "B.Cu")
		(net "P3V3_AUX")
	)
	(via
		(at 80.602582 -89.78138)
		(size 0.508)
		(drill 0.254)
		(layers "F.Cu" "B.Cu")
		(net "P3V3_AUX")
	)
	(via
		(at 335.026 -165.989)
		(size 0.508)
		(drill 0.254)
		(layers "F.Cu" "B.Cu")
		(net "P3V3_AUX")
	)
	(via
		(at 341.571072 -193.46545)
		(size 0.508)
		(drill 0.254)
		(layers "F.Cu" "B.Cu")
		(net "P3V3_AUX")
	)
	(via
		(at 12.509246 -212.780372)
		(size 0.508)
		(drill 0.254)
		(layers "F.Cu" "B.Cu")
		(net "P3V3_AUX")
	)
	(via
		(at 257.553714 -345.653868)
		(size 0.508)
		(drill 0.254)
		(layers "F.Cu" "B.Cu")
		(net "P3V3_AUX")
	)
	(via
		(at 354.98659 -61.487812)
		(size 0.508)
		(drill 0.254)
		(layers "F.Cu" "B.Cu")
		(net "P3V3_AUX")
	)
	(via
		(at 406.986486 -61.487812)
		(size 0.508)
		(drill 0.254)
		(layers "F.Cu" "B.Cu")
		(net "P3V3_AUX")
	)
	(via
		(at 209.926936 -189.770258)
		(size 0.508)
		(drill 0.254)
		(layers "F.Cu" "B.Cu")
		(net "P3V3_AUX")
	)
	(via
		(at 279.750266 -48.753014)
		(size 0.508)
		(drill 0.254)
		(layers "F.Cu" "B.Cu")
		(net "P3V3_AUX")
	)
	(via
		(at 115.572286 -138.915648)
		(size 0.508)
		(drill 0.254)
		(layers "F.Cu" "B.Cu")
		(net "P3V3_AUX")
	)
	(via
		(at 370.60124 -87.213694)
		(size 0.508)
		(drill 0.254)
		(layers "F.Cu" "B.Cu")
		(net "P3V3_AUX")
	)
	(via
		(at 349.268542 -90.645234)
		(size 0.508)
		(drill 0.254)
		(layers "F.Cu" "B.Cu")
		(net "P3V3_AUX")
	)
	(via
		(at 242.589304 -199.354694)
		(size 0.508)
		(drill 0.254)
		(layers "F.Cu" "B.Cu")
		(net "P3V3_AUX")
	)
	(via
		(at 404.34895 -384.06705)
		(size 0.508)
		(drill 0.254)
		(layers "F.Cu" "B.Cu")
		(net "P3V3_AUX")
	)
	(via
		(at 19.885914 -414.985454)
		(size 0.508)
		(drill 0.254)
		(layers "F.Cu" "B.Cu")
		(net "P3V3_AUX")
	)
	(via
		(at 373.608346 -47.403766)
		(size 0.508)
		(drill 0.254)
		(layers "F.Cu" "B.Cu")
		(net "P3V3_AUX")
	)
	(via
		(at 289.171126 -55.11038)
		(size 0.508)
		(drill 0.254)
		(layers "F.Cu" "B.Cu")
		(net "P3V3_AUX")
	)
	(via
		(at 339.177122 -244.278658)
		(size 0.508)
		(drill 0.254)
		(layers "F.Cu" "B.Cu")
		(net "P3V3_AUX")
	)
	(via
		(at 195.415154 -44.87291)
		(size 0.508)
		(drill 0.254)
		(layers "F.Cu" "B.Cu")
		(net "P3V3_AUX")
	)
	(via
		(at 338.092542 -8.4836)
		(size 0.508)
		(drill 0.254)
		(layers "F.Cu" "B.Cu")
		(net "P3V3_AUX")
	)
	(via
		(at 56.971184 -55.11038)
		(size 0.508)
		(drill 0.254)
		(layers "F.Cu" "B.Cu")
		(net "P3V3_AUX")
	)
	(via
		(at 370.60124 -83.784694)
		(size 0.508)
		(drill 0.254)
		(layers "F.Cu" "B.Cu")
		(net "P3V3_AUX")
	)
	(via
		(at 325.39305 -231.41305)
		(size 0.508)
		(drill 0.254)
		(layers "F.Cu" "B.Cu")
		(net "P3V3_AUX")
	)
	(via
		(at 368.06124 -90.642694)
		(size 0.508)
		(drill 0.254)
		(layers "F.Cu" "B.Cu")
		(net "P3V3_AUX")
	)
	(via
		(at 289.78225 -36.286948)
		(size 0.508)
		(drill 0.254)
		(layers "F.Cu" "B.Cu")
		(net "P3V3_AUX")
	)
	(via
		(at 2.785364 -40.404542)
		(size 0.508)
		(drill 0.254)
		(layers "F.Cu" "B.Cu")
		(net "P3V3_AUX")
	)
	(via
		(at 249.391678 -151.696928)
		(size 0.508)
		(drill 0.254)
		(layers "F.Cu" "B.Cu")
		(net "P3V3_AUX")
	)
	(via
		(at 352.80092 -233.95305)
		(size 0.508)
		(drill 0.254)
		(layers "F.Cu" "B.Cu")
		(net "P3V3_AUX")
	)
	(via
		(at 207.22336 -112.799114)
		(size 0.508)
		(drill 0.254)
		(layers "F.Cu" "B.Cu")
		(net "P3V3_AUX")
	)
	(via
		(at 63.585344 -115.922044)
		(size 0.508)
		(drill 0.254)
		(layers "F.Cu" "B.Cu")
		(net "P3V3_AUX")
	)
	(via
		(at 6.763766 -75.087226)
		(size 0.508)
		(drill 0.254)
		(layers "F.Cu" "B.Cu")
		(net "P3V3_AUX")
	)
	(via
		(at 167.123618 -168.397174)
		(size 0.508)
		(drill 0.254)
		(layers "F.Cu" "B.Cu")
		(net "P3V3_AUX")
	)
	(via
		(at 263.171178 -55.74538)
		(size 0.508)
		(drill 0.254)
		(layers "F.Cu" "B.Cu")
		(net "P3V3_AUX")
	)
	(via
		(at 335.026 -170.053)
		(size 0.508)
		(drill 0.254)
		(layers "F.Cu" "B.Cu")
		(net "P3V3_AUX")
	)
	(via
		(at 22.271736 -153.782522)
		(size 0.508)
		(drill 0.254)
		(layers "F.Cu" "B.Cu")
		(net "P3V3_AUX")
	)
	(via
		(at 132.459476 -148.017738)
		(size 0.508)
		(drill 0.254)
		(layers "F.Cu" "B.Cu")
		(net "P3V3_AUX")
	)
	(via
		(at 216.025984 -211.193126)
		(size 0.508)
		(drill 0.254)
		(layers "F.Cu" "B.Cu")
		(net "P3V3_AUX")
	)
	(via
		(at 6.056376 -60.781946)
		(size 0.508)
		(drill 0.254)
		(layers "F.Cu" "B.Cu")
		(net "P3V3_AUX")
	)
	(via
		(at 54.454806 -23.970996)
		(size 0.508)
		(drill 0.254)
		(layers "F.Cu" "B.Cu")
		(net "P3V3_AUX")
	)
	(via
		(at 225.256344 -181.85638)
		(size 0.508)
		(drill 0.254)
		(layers "F.Cu" "B.Cu")
		(net "P3V3_AUX")
	)
	(via
		(at 170.554904 -23.970996)
		(size 0.508)
		(drill 0.254)
		(layers "F.Cu" "B.Cu")
		(net "P3V3_AUX")
	)
	(via
		(at 378.82195 -213.97595)
		(size 0.508)
		(drill 0.254)
		(layers "F.Cu" "B.Cu")
		(net "P3V3_AUX")
	)
	(via
		(at 105.315004 -44.87291)
		(size 0.508)
		(drill 0.254)
		(layers "F.Cu" "B.Cu")
		(net "P3V3_AUX")
	)
	(via
		(at 382.14173 -202.398376)
		(size 0.508)
		(drill 0.254)
		(layers "F.Cu" "B.Cu")
		(net "P3V3_AUX")
	)
	(via
		(at 198.382128 -54.96179)
		(size 0.508)
		(drill 0.254)
		(layers "F.Cu" "B.Cu")
		(net "P3V3_AUX")
	)
	(via
		(at 401.570444 -29.614876)
		(size 0.508)
		(drill 0.254)
		(layers "F.Cu" "B.Cu")
		(net "P3V3_AUX")
	)
	(via
		(at 108.120942 -117.248178)
		(size 0.508)
		(drill 0.254)
		(layers "F.Cu" "B.Cu")
		(net "P3V3_AUX")
	)
	(via
		(at 128.566164 -201.478896)
		(size 0.508)
		(drill 0.254)
		(layers "F.Cu" "B.Cu")
		(net "P3V3_AUX")
	)
	(via
		(at 237.782354 -36.286948)
		(size 0.508)
		(drill 0.254)
		(layers "F.Cu" "B.Cu")
		(net "P3V3_AUX")
	)
	(via
		(at 109.030262 -193.001138)
		(size 0.508)
		(drill 0.254)
		(layers "F.Cu" "B.Cu")
		(net "P3V3_AUX")
	)
	(via
		(at 250.732544 -356.015544)
		(size 0.508)
		(drill 0.254)
		(layers "F.Cu" "B.Cu")
		(net "P3V3_AUX")
	)
	(via
		(at 17.794986 -273.216624)
		(size 0.508)
		(drill 0.254)
		(layers "F.Cu" "B.Cu")
		(net "P3V3_AUX")
	)
	(via
		(at 337.902296 -197.87362)
		(size 0.508)
		(drill 0.254)
		(layers "F.Cu" "B.Cu")
		(net "P3V3_AUX")
	)
	(via
		(at 13.649706 -123.225052)
		(size 0.508)
		(drill 0.254)
		(layers "F.Cu" "B.Cu")
		(net "P3V3_AUX")
	)
	(via
		(at 140.090144 -87.813642)
		(size 0.508)
		(drill 0.254)
		(layers "F.Cu" "B.Cu")
		(net "P3V3_AUX")
	)
	(via
		(at 403.616922 -55.39359)
		(size 0.508)
		(drill 0.254)
		(layers "F.Cu" "B.Cu")
		(net "P3V3_AUX")
	)
	(via
		(at 129.350262 -115.402106)
		(size 0.508)
		(drill 0.254)
		(layers "F.Cu" "B.Cu")
		(net "P3V3_AUX")
	)
	(via
		(at 312.965846 -139.734798)
		(size 0.508)
		(drill 0.254)
		(layers "F.Cu" "B.Cu")
		(net "P3V3_AUX")
	)
	(via
		(at 108.89996 -140.35786)
		(size 0.508)
		(drill 0.254)
		(layers "F.Cu" "B.Cu")
		(net "P3V3_AUX")
	)
	(via
		(at 400.018504 -22.555454)
		(size 0.508)
		(drill 0.254)
		(layers "F.Cu" "B.Cu")
		(net "P3V3_AUX")
	)
	(via
		(at 356.743 -171.45)
		(size 0.508)
		(drill 0.254)
		(layers "F.Cu" "B.Cu")
		(net "P3V3_AUX")
	)
	(via
		(at 227.867972 -222.703898)
		(size 0.4572)
		(drill 0.254)
		(layers "F.Cu" "B.Cu")
		(net "P3V3_AUX")
	)
	(via
		(at 129.985262 -115.402106)
		(size 0.508)
		(drill 0.254)
		(layers "F.Cu" "B.Cu")
		(net "P3V3_AUX")
	)
	(via
		(at 256.788158 -213.801198)
		(size 0.508)
		(drill 0.254)
		(layers "F.Cu" "B.Cu")
		(net "P3V3_AUX")
	)
	(via
		(at 147.750022 -26.03373)
		(size 0.508)
		(drill 0.254)
		(layers "F.Cu" "B.Cu")
		(net "P3V3_AUX")
	)
	(via
		(at 311.175908 -40.971724)
		(size 0.508)
		(drill 0.254)
		(layers "F.Cu" "B.Cu")
		(net "P3V3_AUX")
	)
	(via
		(at 130.10134 -120.85955)
		(size 0.508)
		(drill 0.254)
		(layers "F.Cu" "B.Cu")
		(net "P3V3_AUX")
	)
	(via
		(at 362.458 -205.867)
		(size 0.508)
		(drill 0.254)
		(layers "F.Cu" "B.Cu")
		(net "P3V3_AUX")
	)
	(via
		(at 232.667556 -221.103952)
		(size 0.4572)
		(drill 0.254)
		(layers "F.Cu" "B.Cu")
		(net "P3V3_AUX")
	)
	(via
		(at 227.734368 -95.089726)
		(size 0.508)
		(drill 0.254)
		(layers "F.Cu" "B.Cu")
		(net "P3V3_AUX")
	)
	(via
		(at 329.311 -244.221)
		(size 0.508)
		(drill 0.254)
		(layers "F.Cu" "B.Cu")
		(net "P3V3_AUX")
	)
	(via
		(at 106.51236 -140.35786)
		(size 0.508)
		(drill 0.254)
		(layers "F.Cu" "B.Cu")
		(net "P3V3_AUX")
	)
	(via
		(at 212.695282 -223.40062)
		(size 0.508)
		(drill 0.254)
		(layers "F.Cu" "B.Cu")
		(net "P3V3_AUX")
	)
	(via
		(at 459.744572 -329.169776)
		(size 0.508)
		(drill 0.254)
		(layers "F.Cu" "B.Cu")
		(net "P3V3_AUX")
	)
	(via
		(at 181.1528 -177.717704)
		(size 0.508)
		(drill 0.254)
		(layers "F.Cu" "B.Cu")
		(net "P3V3_AUX")
	)
	(via
		(at 322.864734 -226.698302)
		(size 0.508)
		(drill 0.254)
		(layers "F.Cu" "B.Cu")
		(net "P3V3_AUX")
	)
	(via
		(at 376.754898 -23.970996)
		(size 0.508)
		(drill 0.254)
		(layers "F.Cu" "B.Cu")
		(net "P3V3_AUX")
	)
	(via
		(at 452.871332 -242.13693)
		(size 0.508)
		(drill 0.254)
		(layers "F.Cu" "B.Cu")
		(net "P3V3_AUX")
	)
	(via
		(at 249.166126 -273.471386)
		(size 0.508)
		(drill 0.254)
		(layers "F.Cu" "B.Cu")
		(net "P3V3_AUX")
	)
	(via
		(at 286.805624 -55.39359)
		(size 0.508)
		(drill 0.254)
		(layers "F.Cu" "B.Cu")
		(net "P3V3_AUX")
	)
	(via
		(at 351.38995 -173.08195)
		(size 0.508)
		(drill 0.254)
		(layers "F.Cu" "B.Cu")
		(net "P3V3_AUX")
	)
	(via
		(at 30.988 -57.48528)
		(size 0.508)
		(drill 0.254)
		(layers "F.Cu" "B.Cu")
		(net "P3V3_AUX")
	)
	(via
		(at 379.28804 -57.48528)
		(size 0.508)
		(drill 0.254)
		(layers "F.Cu" "B.Cu")
		(net "P3V3_AUX")
	)
	(via
		(at 386.641086 -238.212884)
		(size 0.508)
		(drill 0.254)
		(layers "F.Cu" "B.Cu")
		(net "P3V3_AUX")
	)
	(via
		(at 362.458 -195.707)
		(size 0.508)
		(drill 0.254)
		(layers "F.Cu" "B.Cu")
		(net "P3V3_AUX")
	)
	(via
		(at 112.472216 -138.27506)
		(size 0.508)
		(drill 0.254)
		(layers "F.Cu" "B.Cu")
		(net "P3V3_AUX")
	)
	(via
		(at 414.103058 -196.755258)
		(size 0.508)
		(drill 0.254)
		(layers "F.Cu" "B.Cu")
		(net "P3V3_AUX")
	)
	(via
		(at 338.68995 -236.45495)
		(size 0.508)
		(drill 0.254)
		(layers "F.Cu" "B.Cu")
		(net "P3V3_AUX")
	)
	(via
		(at 225.041206 -80.611472)
		(size 0.508)
		(drill 0.254)
		(layers "F.Cu" "B.Cu")
		(net "P3V3_AUX")
	)
	(via
		(at 335.026 -157.734)
		(size 0.508)
		(drill 0.254)
		(layers "F.Cu" "B.Cu")
		(net "P3V3_AUX")
	)
	(via
		(at 327.080626 -119.380254)
		(size 0.508)
		(drill 0.254)
		(layers "F.Cu" "B.Cu")
		(net "P3V3_AUX")
	)
	(via
		(at 427.615096 -44.87291)
		(size 0.508)
		(drill 0.254)
		(layers "F.Cu" "B.Cu")
		(net "P3V3_AUX")
	)
	(via
		(at 129.74955 -123.225052)
		(size 0.508)
		(drill 0.254)
		(layers "F.Cu" "B.Cu")
		(net "P3V3_AUX")
	)
	(via
		(at 375.297446 -89.9668)
		(size 0.508)
		(drill 0.254)
		(layers "F.Cu" "B.Cu")
		(net "P3V3_AUX")
	)
	(via
		(at 458.18679 -364.501684)
		(size 0.508)
		(drill 0.254)
		(layers "F.Cu" "B.Cu")
		(net "P3V3_AUX")
	)
	(via
		(at 120.382284 -54.96179)
		(size 0.508)
		(drill 0.254)
		(layers "F.Cu" "B.Cu")
		(net "P3V3_AUX")
	)
	(via
		(at 94.344744 -200.961752)
		(size 0.508)
		(drill 0.254)
		(layers "F.Cu" "B.Cu")
		(net "P3V3_AUX")
	)
	(via
		(at 109.571536 -138.27506)
		(size 0.508)
		(drill 0.254)
		(layers "F.Cu" "B.Cu")
		(net "P3V3_AUX")
	)
	(via
		(at 120.119902 -93.748606)
		(size 0.508)
		(drill 0.254)
		(layers "F.Cu" "B.Cu")
		(net "P3V3_AUX")
	)
	(via
		(at 413.599122 -189.811152)
		(size 0.508)
		(drill 0.254)
		(layers "F.Cu" "B.Cu")
		(net "P3V3_AUX")
	)
	(via
		(at 341.571072 -192.44945)
		(size 0.508)
		(drill 0.254)
		(layers "F.Cu" "B.Cu")
		(net "P3V3_AUX")
	)
	(via
		(at 299.683932 -224.39757)
		(size 0.508)
		(drill 0.254)
		(layers "F.Cu" "B.Cu")
		(net "P3V3_AUX")
	)
	(via
		(at 443.288674 -124.215144)
		(size 0.508)
		(drill 0.254)
		(layers "F.Cu" "B.Cu")
		(net "P3V3_AUX")
	)
	(via
		(at 233.467402 -217.904314)
		(size 0.4572)
		(drill 0.254)
		(layers "F.Cu" "B.Cu")
		(net "P3V3_AUX")
	)
	(via
		(at 259.176012 -40.971724)
		(size 0.508)
		(drill 0.254)
		(layers "F.Cu" "B.Cu")
		(net "P3V3_AUX")
	)
	(via
		(at 246.201438 -121.57075)
		(size 0.508)
		(drill 0.254)
		(layers "F.Cu" "B.Cu")
		(net "P3V3_AUX")
	)
	(via
		(at 236.404658 -76.853034)
		(size 0.508)
		(drill 0.254)
		(layers "F.Cu" "B.Cu")
		(net "P3V3_AUX")
	)
	(via
		(at 255.268476 -242.664488)
		(size 0.508)
		(drill 0.254)
		(layers "F.Cu" "B.Cu")
		(net "P3V3_AUX")
	)
	(via
		(at 135.125968 -100.978208)
		(size 0.508)
		(drill 0.254)
		(layers "F.Cu" "B.Cu")
		(net "P3V3_AUX")
	)
	(via
		(at 393.399264 -35.876738)
		(size 0.508)
		(drill 0.254)
		(layers "F.Cu" "B.Cu")
		(net "P3V3_AUX")
	)
	(via
		(at 128.749552 -250.233434)
		(size 0.508)
		(drill 0.254)
		(layers "F.Cu" "B.Cu")
		(net "P3V3_AUX")
	)
	(via
		(at 217.038936 -189.662054)
		(size 0.508)
		(drill 0.254)
		(layers "F.Cu" "B.Cu")
		(net "P3V3_AUX")
	)
	(via
		(at 15.459456 -402.204936)
		(size 0.508)
		(drill 0.254)
		(layers "F.Cu" "B.Cu")
		(net "P3V3_AUX")
	)
	(via
		(at 304.455576 -250.263406)
		(size 0.508)
		(drill 0.254)
		(layers "F.Cu" "B.Cu")
		(net "P3V3_AUX")
	)
	(via
		(at 141.818614 -22.555454)
		(size 0.508)
		(drill 0.254)
		(layers "F.Cu" "B.Cu")
		(net "P3V3_AUX")
	)
	(via
		(at 332.512162 -237.885986)
		(size 0.508)
		(drill 0.254)
		(layers "F.Cu" "B.Cu")
		(net "P3V3_AUX")
	)
	(via
		(at 260.6548 -23.970996)
		(size 0.508)
		(drill 0.254)
		(layers "F.Cu" "B.Cu")
		(net "P3V3_AUX")
	)
	(via
		(at 313.139582 -136.98601)
		(size 0.508)
		(drill 0.254)
		(layers "F.Cu" "B.Cu")
		(net "P3V3_AUX")
	)
	(via
		(at 255.01346 -194.538346)
		(size 0.508)
		(drill 0.254)
		(layers "F.Cu" "B.Cu")
		(net "P3V3_AUX")
	)
	(via
		(at 385.77012 -117.7544)
		(size 0.508)
		(drill 0.254)
		(layers "F.Cu" "B.Cu")
		(net "P3V3_AUX")
	)
	(via
		(at 450.542406 -236.388402)
		(size 0.508)
		(drill 0.254)
		(layers "F.Cu" "B.Cu")
		(net "P3V3_AUX")
	)
	(via
		(at 444.73241 -229.12197)
		(size 0.508)
		(drill 0.254)
		(layers "F.Cu" "B.Cu")
		(net "P3V3_AUX")
	)
	(via
		(at 222.663512 -232.471468)
		(size 0.508)
		(drill 0.254)
		(layers "F.Cu" "B.Cu")
		(net "P3V3_AUX")
	)
	(via
		(at 237.357158 -53.718714)
		(size 0.508)
		(drill 0.254)
		(layers "F.Cu" "B.Cu")
		(net "P3V3_AUX")
	)
	(via
		(at 30.971236 -55.74538)
		(size 0.508)
		(drill 0.254)
		(layers "F.Cu" "B.Cu")
		(net "P3V3_AUX")
	)
	(via
		(at 458.452982 -117.248178)
		(size 0.508)
		(drill 0.254)
		(layers "F.Cu" "B.Cu")
		(net "P3V3_AUX")
	)
	(via
		(at 410.621988 -137.848848)
		(size 0.508)
		(drill 0.254)
		(layers "F.Cu" "B.Cu")
		(net "P3V3_AUX")
	)
	(via
		(at 257.918458 -22.555454)
		(size 0.508)
		(drill 0.254)
		(layers "F.Cu" "B.Cu")
		(net "P3V3_AUX")
	)
	(via
		(at 246.59336 -116.799106)
		(size 0.508)
		(drill 0.254)
		(layers "F.Cu" "B.Cu")
		(net "P3V3_AUX")
	)
	(via
		(at 377.75896 -241.811048)
		(size 0.508)
		(drill 0.254)
		(layers "F.Cu" "B.Cu")
		(net "P3V3_AUX")
	)
	(via
		(at 362.733336 -122.53595)
		(size 0.508)
		(drill 0.254)
		(layers "F.Cu" "B.Cu")
		(net "P3V3_AUX")
	)
	(via
		(at 435.667912 -98.543364)
		(size 0.508)
		(drill 0.254)
		(layers "F.Cu" "B.Cu")
		(net "P3V3_AUX")
	)
	(via
		(at 197.416928 -55.39359)
		(size 0.508)
		(drill 0.254)
		(layers "F.Cu" "B.Cu")
		(net "P3V3_AUX")
	)
	(via
		(at 77.718412 -22.555454)
		(size 0.508)
		(drill 0.254)
		(layers "F.Cu" "B.Cu")
		(net "P3V3_AUX")
	)
	(via
		(at 451.958202 -248.83364)
		(size 0.508)
		(drill 0.254)
		(layers "F.Cu" "B.Cu")
		(net "P3V3_AUX")
	)
	(via
		(at 79.315056 -44.87291)
		(size 0.508)
		(drill 0.254)
		(layers "F.Cu" "B.Cu")
		(net "P3V3_AUX")
	)
	(via
		(at 360.902758 -379.655324)
		(size 0.508)
		(drill 0.254)
		(layers "F.Cu" "B.Cu")
		(net "P3V3_AUX")
	)
	(via
		(at 253.038102 -336.358992)
		(size 0.508)
		(drill 0.254)
		(layers "F.Cu" "B.Cu")
		(net "P3V3_AUX")
	)
	(via
		(at 374.50395 -181.08295)
		(size 0.508)
		(drill 0.254)
		(layers "F.Cu" "B.Cu")
		(net "P3V3_AUX")
	)
	(via
		(at 218.080844 -95.123)
		(size 0.508)
		(drill 0.254)
		(layers "F.Cu" "B.Cu")
		(net "P3V3_AUX")
	)
	(via
		(at 95.556578 -125.180344)
		(size 0.508)
		(drill 0.254)
		(layers "F.Cu" "B.Cu")
		(net "P3V3_AUX")
	)
	(via
		(at 257.508248 -47.403766)
		(size 0.508)
		(drill 0.254)
		(layers "F.Cu" "B.Cu")
		(net "P3V3_AUX")
	)
	(via
		(at 227.734368 -91.025726)
		(size 0.508)
		(drill 0.254)
		(layers "F.Cu" "B.Cu")
		(net "P3V3_AUX")
	)
	(via
		(at 413.5628 -180.699918)
		(size 0.508)
		(drill 0.254)
		(layers "F.Cu" "B.Cu")
		(net "P3V3_AUX")
	)
	(via
		(at 339.508084 -5.747258)
		(size 0.508)
		(drill 0.254)
		(layers "F.Cu" "B.Cu")
		(net "P3V3_AUX")
	)
	(via
		(at 15.380716 -410.248608)
		(size 0.508)
		(drill 0.254)
		(layers "F.Cu" "B.Cu")
		(net "P3V3_AUX")
	)
	(via
		(at 357.99395 -286.826452)
		(size 0.508)
		(drill 0.254)
		(layers "F.Cu" "B.Cu")
		(net "P3V3_AUX")
	)
	(via
		(at 218.88958 -87.123524)
		(size 0.508)
		(drill 0.254)
		(layers "F.Cu" "B.Cu")
		(net "P3V3_AUX")
	)
	(via
		(at 283.918406 -22.555454)
		(size 0.508)
		(drill 0.254)
		(layers "F.Cu" "B.Cu")
		(net "P3V3_AUX")
	)
	(via
		(at 187.53455 -415.15919)
		(size 0.508)
		(drill 0.254)
		(layers "F.Cu" "B.Cu")
		(net "P3V3_AUX")
	)
	(via
		(at 233.47045 -30.376876)
		(size 0.508)
		(drill 0.254)
		(layers "F.Cu" "B.Cu")
		(net "P3V3_AUX")
	)
	(via
		(at 229.594664 -205.945486)
		(size 0.508)
		(drill 0.254)
		(layers "F.Cu" "B.Cu")
		(net "P3V3_AUX")
	)
	(via
		(at 358.14 -178.054)
		(size 0.508)
		(drill 0.254)
		(layers "F.Cu" "B.Cu")
		(net "P3V3_AUX")
	)
	(via
		(at 142.494254 -204.949806)
		(size 0.508)
		(drill 0.254)
		(layers "F.Cu" "B.Cu")
		(net "P3V3_AUX")
	)
	(via
		(at 305.082702 -80.019906)
		(size 0.508)
		(drill 0.254)
		(layers "F.Cu" "B.Cu")
		(net "P3V3_AUX")
	)
	(via
		(at 163.650422 -48.753014)
		(size 0.508)
		(drill 0.254)
		(layers "F.Cu" "B.Cu")
		(net "P3V3_AUX")
	)
	(via
		(at 337.514946 -44.87291)
		(size 0.508)
		(drill 0.254)
		(layers "F.Cu" "B.Cu")
		(net "P3V3_AUX")
	)
	(via
		(at 358.14 -191.262)
		(size 0.508)
		(drill 0.254)
		(layers "F.Cu" "B.Cu")
		(net "P3V3_AUX")
	)
	(via
		(at 222.861378 -210.316318)
		(size 0.508)
		(drill 0.254)
		(layers "F.Cu" "B.Cu")
		(net "P3V3_AUX")
	)
	(via
		(at 225.29927 -35.876738)
		(size 0.508)
		(drill 0.254)
		(layers "F.Cu" "B.Cu")
		(net "P3V3_AUX")
	)
	(via
		(at 154.378406 -115.235228)
		(size 0.508)
		(drill 0.254)
		(layers "F.Cu" "B.Cu")
		(net "P3V3_AUX")
	)
	(via
		(at 380.254002 -237.236)
		(size 0.508)
		(drill 0.254)
		(layers "F.Cu" "B.Cu")
		(net "P3V3_AUX")
	)
	(via
		(at 53.315108 -44.87291)
		(size 0.508)
		(drill 0.254)
		(layers "F.Cu" "B.Cu")
		(net "P3V3_AUX")
	)
	(via
		(at 436.277004 -288.221166)
		(size 0.508)
		(drill 0.254)
		(layers "F.Cu" "B.Cu")
		(net "P3V3_AUX")
	)
	(via
		(at 7.032244 -159.844994)
		(size 0.508)
		(drill 0.254)
		(layers "F.Cu" "B.Cu")
		(net "P3V3_AUX")
	)
	(via
		(at 5.699506 -26.03373)
		(size 0.508)
		(drill 0.254)
		(layers "F.Cu" "B.Cu")
		(net "P3V3_AUX")
	)
	(via
		(at 397.224758 -89.500202)
		(size 0.508)
		(drill 0.254)
		(layers "F.Cu" "B.Cu")
		(net "P3V3_AUX")
	)
	(via
		(at 108.89996 -138.27506)
		(size 0.508)
		(drill 0.254)
		(layers "F.Cu" "B.Cu")
		(net "P3V3_AUX")
	)
	(via
		(at 349.268542 -91.788234)
		(size 0.508)
		(drill 0.254)
		(layers "F.Cu" "B.Cu")
		(net "P3V3_AUX")
	)
	(via
		(at 247.322848 -183.404256)
		(size 0.508)
		(drill 0.254)
		(layers "F.Cu" "B.Cu")
		(net "P3V3_AUX")
	)
	(via
		(at 228.667818 -223.503998)
		(size 0.4572)
		(drill 0.254)
		(layers "F.Cu" "B.Cu")
		(net "P3V3_AUX")
	)
	(via
		(at 114.910616 -138.27506)
		(size 0.508)
		(drill 0.254)
		(layers "F.Cu" "B.Cu")
		(net "P3V3_AUX")
	)
	(via
		(at 362.458 -194.691)
		(size 0.508)
		(drill 0.254)
		(layers "F.Cu" "B.Cu")
		(net "P3V3_AUX")
	)
	(via
		(at 298.34713 -196.022976)
		(size 0.508)
		(drill 0.254)
		(layers "F.Cu" "B.Cu")
		(net "P3V3_AUX")
	)
	(via
		(at 289.171126 -56.38038)
		(size 0.508)
		(drill 0.254)
		(layers "F.Cu" "B.Cu")
		(net "P3V3_AUX")
	)
	(via
		(at 269.807436 -97.1804)
		(size 0.508)
		(drill 0.254)
		(layers "F.Cu" "B.Cu")
		(net "P3V3_AUX")
	)
	(via
		(at 465.05241 -281.723084)
		(size 0.508)
		(drill 0.254)
		(layers "F.Cu" "B.Cu")
		(net "P3V3_AUX")
	)
	(via
		(at 7.58444 -365.392208)
		(size 0.508)
		(drill 0.254)
		(layers "F.Cu" "B.Cu")
		(net "P3V3_AUX")
	)
	(via
		(at 210.765136 -182.013606)
		(size 0.508)
		(drill 0.254)
		(layers "F.Cu" "B.Cu")
		(net "P3V3_AUX")
	)
	(via
		(at 204.077062 -288.221166)
		(size 0.508)
		(drill 0.254)
		(layers "F.Cu" "B.Cu")
		(net "P3V3_AUX")
	)
	(via
		(at 279.774396 -416.00628)
		(size 0.508)
		(drill 0.254)
		(layers "F.Cu" "B.Cu")
		(net "P3V3_AUX")
	)
	(via
		(at 173.74997 -26.03373)
		(size 0.508)
		(drill 0.254)
		(layers "F.Cu" "B.Cu")
		(net "P3V3_AUX")
	)
	(via
		(at 113.269268 -128.638046)
		(size 0.508)
		(drill 0.254)
		(layers "F.Cu" "B.Cu")
		(net "P3V3_AUX")
	)
	(via
		(at 399.323814 -168.397174)
		(size 0.508)
		(drill 0.254)
		(layers "F.Cu" "B.Cu")
		(net "P3V3_AUX")
	)
	(via
		(at 227.867972 -215.504268)
		(size 0.4572)
		(drill 0.254)
		(layers "F.Cu" "B.Cu")
		(net "P3V3_AUX")
	)
	(via
		(at 240.216944 -208.126838)
		(size 0.508)
		(drill 0.254)
		(layers "F.Cu" "B.Cu")
		(net "P3V3_AUX")
	)
	(via
		(at 214.829136 -182.013606)
		(size 0.508)
		(drill 0.254)
		(layers "F.Cu" "B.Cu")
		(net "P3V3_AUX")
	)
	(via
		(at 390.685782 -90.056462)
		(size 0.508)
		(drill 0.254)
		(layers "F.Cu" "B.Cu")
		(net "P3V3_AUX")
	)
	(via
		(at 225.032062 -83.659472)
		(size 0.508)
		(drill 0.254)
		(layers "F.Cu" "B.Cu")
		(net "P3V3_AUX")
	)
	(via
		(at 95.080328 -123.33732)
		(size 0.508)
		(drill 0.254)
		(layers "F.Cu" "B.Cu")
		(net "P3V3_AUX")
	)
	(via
		(at 221.415102 -42.84091)
		(size 0.508)
		(drill 0.254)
		(layers "F.Cu" "B.Cu")
		(net "P3V3_AUX")
	)
	(via
		(at 140.090144 -90.099642)
		(size 0.508)
		(drill 0.254)
		(layers "F.Cu" "B.Cu")
		(net "P3V3_AUX")
	)
	(via
		(at 397.224758 -84.928202)
		(size 0.508)
		(drill 0.254)
		(layers "F.Cu" "B.Cu")
		(net "P3V3_AUX")
	)
	(via
		(at 367.399316 -35.876738)
		(size 0.508)
		(drill 0.254)
		(layers "F.Cu" "B.Cu")
		(net "P3V3_AUX")
	)
	(via
		(at 113.29035 -129.924048)
		(size 0.508)
		(drill 0.254)
		(layers "F.Cu" "B.Cu")
		(net "P3V3_AUX")
	)
	(via
		(at 56.282082 -54.96179)
		(size 0.508)
		(drill 0.254)
		(layers "F.Cu" "B.Cu")
		(net "P3V3_AUX")
	)
	(via
		(at 144.126712 -190.53683)
		(size 0.508)
		(drill 0.254)
		(layers "F.Cu" "B.Cu")
		(net "P3V3_AUX")
	)
	(via
		(at 237.849918 -26.03373)
		(size 0.508)
		(drill 0.254)
		(layers "F.Cu" "B.Cu")
		(net "P3V3_AUX")
	)
	(via
		(at 224.456244 -185.363612)
		(size 0.508)
		(drill 0.254)
		(layers "F.Cu" "B.Cu")
		(net "P3V3_AUX")
	)
	(via
		(at 14.001496 -120.85955)
		(size 0.508)
		(drill 0.254)
		(layers "F.Cu" "B.Cu")
		(net "P3V3_AUX")
	)
	(via
		(at 244.264434 -251.857256)
		(size 0.508)
		(drill 0.254)
		(layers "F.Cu" "B.Cu")
		(net "P3V3_AUX")
	)
	(via
		(at 13.758418 -116.799106)
		(size 0.508)
		(drill 0.254)
		(layers "F.Cu" "B.Cu")
		(net "P3V3_AUX")
	)
	(via
		(at 146.382232 -54.96179)
		(size 0.508)
		(drill 0.254)
		(layers "F.Cu" "B.Cu")
		(net "P3V3_AUX")
	)
	(via
		(at 94.988634 -124.215144)
		(size 0.508)
		(drill 0.254)
		(layers "F.Cu" "B.Cu")
		(net "P3V3_AUX")
	)
	(via
		(at 123.132088 -157.812994)
		(size 0.508)
		(drill 0.254)
		(layers "F.Cu" "B.Cu")
		(net "P3V3_AUX")
	)
	(via
		(at 364.234984 -249.284998)
		(size 0.508)
		(drill 0.254)
		(layers "F.Cu" "B.Cu")
		(net "P3V3_AUX")
	)
	(via
		(at 105.315004 -42.84091)
		(size 0.508)
		(drill 0.254)
		(layers "F.Cu" "B.Cu")
		(net "P3V3_AUX")
	)
	(via
		(at 137.650474 -48.753014)
		(size 0.508)
		(drill 0.254)
		(layers "F.Cu" "B.Cu")
		(net "P3V3_AUX")
	)
	(via
		(at 94.869 -194.8942)
		(size 0.508)
		(drill 0.254)
		(layers "F.Cu" "B.Cu")
		(net "P3V3_AUX")
	)
	(via
		(at 225.041206 -78.579472)
		(size 0.508)
		(drill 0.254)
		(layers "F.Cu" "B.Cu")
		(net "P3V3_AUX")
	)
	(via
		(at 245.280434 -251.857256)
		(size 0.508)
		(drill 0.254)
		(layers "F.Cu" "B.Cu")
		(net "P3V3_AUX")
	)
	(via
		(at 376.661934 -236.556296)
		(size 0.508)
		(drill 0.254)
		(layers "F.Cu" "B.Cu")
		(net "P3V3_AUX")
	)
	(via
		(at 431.94986 -26.03373)
		(size 0.508)
		(drill 0.254)
		(layers "F.Cu" "B.Cu")
		(net "P3V3_AUX")
	)
	(via
		(at 379.271276 -55.74538)
		(size 0.508)
		(drill 0.254)
		(layers "F.Cu" "B.Cu")
		(net "P3V3_AUX")
	)
	(via
		(at 299.650658 -225.094038)
		(size 0.508)
		(drill 0.254)
		(layers "F.Cu" "B.Cu")
		(net "P3V3_AUX")
	)
	(via
		(at 112.523016 -139.67206)
		(size 0.508)
		(drill 0.254)
		(layers "F.Cu" "B.Cu")
		(net "P3V3_AUX")
	)
	(via
		(at 461.166972 -329.169776)
		(size 0.508)
		(drill 0.254)
		(layers "F.Cu" "B.Cu")
		(net "P3V3_AUX")
	)
	(via
		(at 233.949494 -181.708044)
		(size 0.508)
		(drill 0.254)
		(layers "F.Cu" "B.Cu")
		(net "P3V3_AUX")
	)
	(via
		(at 386.578602 -115.235228)
		(size 0.508)
		(drill 0.254)
		(layers "F.Cu" "B.Cu")
		(net "P3V3_AUX")
	)
	(via
		(at 358.14 -185.166)
		(size 0.508)
		(drill 0.254)
		(layers "F.Cu" "B.Cu")
		(net "P3V3_AUX")
	)
	(via
		(at 335.026 -169.037)
		(size 0.508)
		(drill 0.254)
		(layers "F.Cu" "B.Cu")
		(net "P3V3_AUX")
	)
	(via
		(at 335.026 -158.75)
		(size 0.508)
		(drill 0.254)
		(layers "F.Cu" "B.Cu")
		(net "P3V3_AUX")
	)
	(via
		(at 38.278562 -115.235228)
		(size 0.508)
		(drill 0.254)
		(layers "F.Cu" "B.Cu")
		(net "P3V3_AUX")
	)
	(via
		(at 213.394544 -211.049362)
		(size 0.508)
		(drill 0.254)
		(layers "F.Cu" "B.Cu")
		(net "P3V3_AUX")
	)
	(via
		(at 55.968646 -118.267988)
		(size 0.508)
		(drill 0.254)
		(layers "F.Cu" "B.Cu")
		(net "P3V3_AUX")
	)
	(via
		(at 285.470346 -30.376876)
		(size 0.508)
		(drill 0.254)
		(layers "F.Cu" "B.Cu")
		(net "P3V3_AUX")
	)
	(via
		(at 335.541112 -244.284246)
		(size 0.508)
		(drill 0.254)
		(layers "F.Cu" "B.Cu")
		(net "P3V3_AUX")
	)
	(via
		(at 463.475324 -275.62683)
		(size 0.508)
		(drill 0.254)
		(layers "F.Cu" "B.Cu")
		(net "P3V3_AUX")
	)
	(via
		(at 268.19479 -140.85697)
		(size 0.508)
		(drill 0.254)
		(layers "F.Cu" "B.Cu")
		(net "P3V3_AUX")
	)
	(via
		(at 126.676658 -286.704786)
		(size 0.508)
		(drill 0.254)
		(layers "F.Cu" "B.Cu")
		(net "P3V3_AUX")
	)
	(via
		(at 119.0879 -138.578844)
		(size 0.508)
		(drill 0.254)
		(layers "F.Cu" "B.Cu")
		(net "P3V3_AUX")
	)
	(via
		(at 456.420982 -117.248178)
		(size 0.508)
		(drill 0.254)
		(layers "F.Cu" "B.Cu")
		(net "P3V3_AUX")
	)
	(via
		(at 248.717562 -210.606386)
		(size 0.508)
		(drill 0.254)
		(layers "F.Cu" "B.Cu")
		(net "P3V3_AUX")
	)
	(via
		(at 120.119902 -91.462606)
		(size 0.508)
		(drill 0.254)
		(layers "F.Cu" "B.Cu")
		(net "P3V3_AUX")
	)
	(via
		(at 335.026 -180.975)
		(size 0.508)
		(drill 0.254)
		(layers "F.Cu" "B.Cu")
		(net "P3V3_AUX")
	)
	(via
		(at 364.08487 -392.684254)
		(size 0.508)
		(drill 0.254)
		(layers "F.Cu" "B.Cu")
		(net "P3V3_AUX")
	)
	(via
		(at 53.323236 -52.035456)
		(size 0.508)
		(drill 0.254)
		(layers "F.Cu" "B.Cu")
		(net "P3V3_AUX")
	)
	(via
		(at 225.032062 -82.643472)
		(size 0.508)
		(drill 0.254)
		(layers "F.Cu" "B.Cu")
		(net "P3V3_AUX")
	)
	(via
		(at 4.282186 -54.96179)
		(size 0.508)
		(drill 0.254)
		(layers "F.Cu" "B.Cu")
		(net "P3V3_AUX")
	)
	(via
		(at 199.749918 -26.03373)
		(size 0.508)
		(drill 0.254)
		(layers "F.Cu" "B.Cu")
		(net "P3V3_AUX")
	)
	(via
		(at 353.271328 -55.11038)
		(size 0.508)
		(drill 0.254)
		(layers "F.Cu" "B.Cu")
		(net "P3V3_AUX")
	)
	(via
		(at 341.571072 -187.36945)
		(size 0.508)
		(drill 0.254)
		(layers "F.Cu" "B.Cu")
		(net "P3V3_AUX")
	)
	(via
		(at 167.818562 -22.555454)
		(size 0.508)
		(drill 0.254)
		(layers "F.Cu" "B.Cu")
		(net "P3V3_AUX")
	)
	(via
		(at 358.14 -192.278)
		(size 0.508)
		(drill 0.254)
		(layers "F.Cu" "B.Cu")
		(net "P3V3_AUX")
	)
	(via
		(at 219.223844 -95.123)
		(size 0.508)
		(drill 0.254)
		(layers "F.Cu" "B.Cu")
		(net "P3V3_AUX")
	)
	(via
		(at 90.485214 -113.538254)
		(size 0.508)
		(drill 0.254)
		(layers "F.Cu" "B.Cu")
		(net "P3V3_AUX")
	)
	(via
		(at 325.002906 -199.282304)
		(size 0.508)
		(drill 0.254)
		(layers "F.Cu" "B.Cu")
		(net "P3V3_AUX")
	)
	(via
		(at 37.607494 -97.1804)
		(size 0.508)
		(drill 0.254)
		(layers "F.Cu" "B.Cu")
		(net "P3V3_AUX")
	)
	(via
		(at 225.467926 -220.303852)
		(size 0.4572)
		(drill 0.254)
		(layers "F.Cu" "B.Cu")
		(net "P3V3_AUX")
	)
	(via
		(at 335.026 -160.782)
		(size 0.508)
		(drill 0.254)
		(layers "F.Cu" "B.Cu")
		(net "P3V3_AUX")
	)
	(via
		(at 11.726164 -277.814278)
		(size 0.508)
		(drill 0.254)
		(layers "F.Cu" "B.Cu")
		(net "P3V3_AUX")
	)
	(via
		(at 340.320884 -117.248178)
		(size 0.508)
		(drill 0.254)
		(layers "F.Cu" "B.Cu")
		(net "P3V3_AUX")
	)
	(via
		(at 243.793264 -120.11787)
		(size 0.508)
		(drill 0.254)
		(layers "F.Cu" "B.Cu")
		(net "P3V3_AUX")
	)
	(via
		(at 17.191736 -151.696928)
		(size 0.508)
		(drill 0.254)
		(layers "F.Cu" "B.Cu")
		(net "P3V3_AUX")
	)
	(via
		(at 235.686092 -51.627024)
		(size 0.508)
		(drill 0.254)
		(layers "F.Cu" "B.Cu")
		(net "P3V3_AUX")
	)
	(via
		(at 244.491002 -123.222512)
		(size 0.508)
		(drill 0.254)
		(layers "F.Cu" "B.Cu")
		(net "P3V3_AUX")
	)
	(via
		(at 353.882452 -36.286948)
		(size 0.508)
		(drill 0.254)
		(layers "F.Cu" "B.Cu")
		(net "P3V3_AUX")
	)
	(via
		(at 148.786596 -61.487812)
		(size 0.508)
		(drill 0.254)
		(layers "F.Cu" "B.Cu")
		(net "P3V3_AUX")
	)
	(via
		(at 324.085458 -114.323114)
		(size 0.508)
		(drill 0.254)
		(layers "F.Cu" "B.Cu")
		(net "P3V3_AUX")
	)
	(via
		(at 362.89996 -254.194564)
		(size 0.508)
		(drill 0.254)
		(layers "F.Cu" "B.Cu")
		(net "P3V3_AUX")
	)
	(via
		(at 370.60124 -89.499694)
		(size 0.508)
		(drill 0.254)
		(layers "F.Cu" "B.Cu")
		(net "P3V3_AUX")
	)
	(via
		(at 335.026 -181.991)
		(size 0.508)
		(drill 0.254)
		(layers "F.Cu" "B.Cu")
		(net "P3V3_AUX")
	)
	(via
		(at 362.185458 -116.037106)
		(size 0.508)
		(drill 0.254)
		(layers "F.Cu" "B.Cu")
		(net "P3V3_AUX")
	)
	(via
		(at 94.880684 -119.380254)
		(size 0.508)
		(drill 0.254)
		(layers "F.Cu" "B.Cu")
		(net "P3V3_AUX")
	)
	(via
		(at 361.550458 -116.037106)
		(size 0.508)
		(drill 0.254)
		(layers "F.Cu" "B.Cu")
		(net "P3V3_AUX")
	)
	(via
		(at 311.523126 -52.035456)
		(size 0.508)
		(drill 0.254)
		(layers "F.Cu" "B.Cu")
		(net "P3V3_AUX")
	)
	(via
		(at 443.2046 -228.64064)
		(size 0.508)
		(drill 0.254)
		(layers "F.Cu" "B.Cu")
		(net "P3V3_AUX")
	)
	(via
		(at 327.193656 -226.657916)
		(size 0.508)
		(drill 0.254)
		(layers "F.Cu" "B.Cu")
		(net "P3V3_AUX")
	)
	(via
		(at 188.39307 -411.99181)
		(size 0.508)
		(drill 0.254)
		(layers "F.Cu" "B.Cu")
		(net "P3V3_AUX")
	)
	(via
		(at 128.038352 -250.233434)
		(size 0.508)
		(drill 0.254)
		(layers "F.Cu" "B.Cu")
		(net "P3V3_AUX")
	)
	(via
		(at 140.090144 -93.528642)
		(size 0.508)
		(drill 0.254)
		(layers "F.Cu" "B.Cu")
		(net "P3V3_AUX")
	)
	(via
		(at 14.748256 -402.204936)
		(size 0.508)
		(drill 0.254)
		(layers "F.Cu" "B.Cu")
		(net "P3V3_AUX")
	)
	(via
		(at 140.090144 -96.957642)
		(size 0.508)
		(drill 0.254)
		(layers "F.Cu" "B.Cu")
		(net "P3V3_AUX")
	)
	(via
		(at 237.340394 -52.613814)
		(size 0.508)
		(drill 0.254)
		(layers "F.Cu" "B.Cu")
		(net "P3V3_AUX")
	)
	(via
		(at 236.492288 -98.295968)
		(size 0.508)
		(drill 0.254)
		(layers "F.Cu" "B.Cu")
		(net "P3V3_AUX")
	)
	(via
		(at 195.415154 -42.84091)
		(size 0.508)
		(drill 0.254)
		(layers "F.Cu" "B.Cu")
		(net "P3V3_AUX")
	)
	(via
		(at 225.032062 -84.675472)
		(size 0.508)
		(drill 0.254)
		(layers "F.Cu" "B.Cu")
		(net "P3V3_AUX")
	)
	(via
		(at 178.421792 -137.848848)
		(size 0.508)
		(drill 0.254)
		(layers "F.Cu" "B.Cu")
		(net "P3V3_AUX")
	)
	(via
		(at 358.14 -181.102)
		(size 0.508)
		(drill 0.254)
		(layers "F.Cu" "B.Cu")
		(net "P3V3_AUX")
	)
	(via
		(at 212.249004 -214.281766)
		(size 0.508)
		(drill 0.254)
		(layers "F.Cu" "B.Cu")
		(net "P3V3_AUX")
	)
	(via
		(at 415.361882 -184.941718)
		(size 0.508)
		(drill 0.254)
		(layers "F.Cu" "B.Cu")
		(net "P3V3_AUX")
	)
	(via
		(at 173.046644 -139.6492)
		(size 0.508)
		(drill 0.254)
		(layers "F.Cu" "B.Cu")
		(net "P3V3_AUX")
	)
	(via
		(at 108.89996 -141.01826)
		(size 0.508)
		(drill 0.254)
		(layers "F.Cu" "B.Cu")
		(net "P3V3_AUX")
	)
	(via
		(at 147.682458 -36.286948)
		(size 0.508)
		(drill 0.254)
		(layers "F.Cu" "B.Cu")
		(net "P3V3_AUX")
	)
	(via
		(at 380.25705 -244.094)
		(size 0.508)
		(drill 0.254)
		(layers "F.Cu" "B.Cu")
		(net "P3V3_AUX")
	)
	(via
		(at 36.074096 -140.326364)
		(size 0.508)
		(drill 0.254)
		(layers "F.Cu" "B.Cu")
		(net "P3V3_AUX")
	)
	(via
		(at 412.496 -193.2686)
		(size 0.508)
		(drill 0.254)
		(layers "F.Cu" "B.Cu")
		(net "P3V3_AUX")
	)
	(via
		(at 443.856618 -125.891544)
		(size 0.508)
		(drill 0.254)
		(layers "F.Cu" "B.Cu")
		(net "P3V3_AUX")
	)
	(via
		(at 349.570548 -29.614876)
		(size 0.508)
		(drill 0.254)
		(layers "F.Cu" "B.Cu")
		(net "P3V3_AUX")
	)
	(via
		(at 200.786492 -61.487812)
		(size 0.508)
		(drill 0.254)
		(layers "F.Cu" "B.Cu")
		(net "P3V3_AUX")
	)
	(via
		(at 173.071282 -56.38038)
		(size 0.508)
		(drill 0.254)
		(layers "F.Cu" "B.Cu")
		(net "P3V3_AUX")
	)
	(via
		(at 301.536354 -233.934)
		(size 0.508)
		(drill 0.254)
		(layers "F.Cu" "B.Cu")
		(net "P3V3_AUX")
	)
	(via
		(at 222.23095 -203.389484)
		(size 0.508)
		(drill 0.254)
		(layers "F.Cu" "B.Cu")
		(net "P3V3_AUX")
	)
	(via
		(at 215.650318 -48.753014)
		(size 0.508)
		(drill 0.254)
		(layers "F.Cu" "B.Cu")
		(net "P3V3_AUX")
	)
	(via
		(at 311.514998 -44.87291)
		(size 0.508)
		(drill 0.254)
		(layers "F.Cu" "B.Cu")
		(net "P3V3_AUX")
	)
	(via
		(at 379.8824 -36.286948)
		(size 0.508)
		(drill 0.254)
		(layers "F.Cu" "B.Cu")
		(net "P3V3_AUX")
	)
	(via
		(at 14.001496 -121.57075)
		(size 0.508)
		(drill 0.254)
		(layers "F.Cu" "B.Cu")
		(net "P3V3_AUX")
	)
	(via
		(at 381.162052 -221.955106)
		(size 0.508)
		(drill 0.254)
		(layers "F.Cu" "B.Cu")
		(net "P3V3_AUX")
	)
	(via
		(at 353.462844 -158.417768)
		(size 0.508)
		(drill 0.254)
		(layers "F.Cu" "B.Cu")
		(net "P3V3_AUX")
	)
	(via
		(at 362.458 -209.931)
		(size 0.508)
		(drill 0.254)
		(layers "F.Cu" "B.Cu")
		(net "P3V3_AUX")
	)
	(via
		(at 99.79914 -240.928144)
		(size 0.508)
		(drill 0.254)
		(layers "F.Cu" "B.Cu")
		(net "P3V3_AUX")
	)
	(via
		(at 454.754742 -24.044402)
		(size 0.508)
		(drill 0.254)
		(layers "F.Cu" "B.Cu")
		(net "P3V3_AUX")
	)
	(via
		(at 115.572286 -139.626848)
		(size 0.508)
		(drill 0.254)
		(layers "F.Cu" "B.Cu")
		(net "P3V3_AUX")
	)
	(via
		(at 113.92535 -132.003546)
		(size 0.508)
		(drill 0.254)
		(layers "F.Cu" "B.Cu")
		(net "P3V3_AUX")
	)
	(via
		(at 302.806608 -224.637346)
		(size 0.508)
		(drill 0.254)
		(layers "F.Cu" "B.Cu")
		(net "P3V3_AUX")
	)
	(via
		(at 421.1828 -80.019906)
		(size 0.508)
		(drill 0.254)
		(layers "F.Cu" "B.Cu")
		(net "P3V3_AUX")
	)
	(via
		(at 397.224758 -80.356202)
		(size 0.508)
		(drill 0.254)
		(layers "F.Cu" "B.Cu")
		(net "P3V3_AUX")
	)
	(via
		(at 375.297446 -81.9658)
		(size 0.508)
		(drill 0.254)
		(layers "F.Cu" "B.Cu")
		(net "P3V3_AUX")
	)
	(via
		(at 264.88644 -61.487812)
		(size 0.508)
		(drill 0.254)
		(layers "F.Cu" "B.Cu")
		(net "P3V3_AUX")
	)
	(via
		(at 335.508092 -47.403766)
		(size 0.508)
		(drill 0.254)
		(layers "F.Cu" "B.Cu")
		(net "P3V3_AUX")
	)
	(via
		(at 235.965746 -121.398792)
		(size 0.508)
		(drill 0.254)
		(layers "F.Cu" "B.Cu")
		(net "P3V3_AUX")
	)
	(via
		(at 443.856618 -125.180344)
		(size 0.508)
		(drill 0.254)
		(layers "F.Cu" "B.Cu")
		(net "P3V3_AUX")
	)
	(via
		(at 236.706664 -207.52181)
		(size 0.508)
		(drill 0.254)
		(layers "F.Cu" "B.Cu")
		(net "P3V3_AUX")
	)
	(via
		(at 327.91527 -123.33732)
		(size 0.508)
		(drill 0.254)
		(layers "F.Cu" "B.Cu")
		(net "P3V3_AUX")
	)
	(via
		(at 203.106274 -260.46176)
		(size 0.508)
		(drill 0.254)
		(layers "F.Cu" "B.Cu")
		(net "P3V3_AUX")
	)
	(via
		(at 337.514946 -42.84091)
		(size 0.508)
		(drill 0.254)
		(layers "F.Cu" "B.Cu")
		(net "P3V3_AUX")
	)
	(via
		(at 27.270456 -30.376876)
		(size 0.508)
		(drill 0.254)
		(layers "F.Cu" "B.Cu")
		(net "P3V3_AUX")
	)
	(via
		(at 130.10134 -121.57075)
		(size 0.508)
		(drill 0.254)
		(layers "F.Cu" "B.Cu")
		(net "P3V3_AUX")
	)
	(via
		(at 256.830576 -214.46236)
		(size 0.508)
		(drill 0.254)
		(layers "F.Cu" "B.Cu")
		(net "P3V3_AUX")
	)
	(via
		(at 173.682406 -36.286948)
		(size 0.508)
		(drill 0.254)
		(layers "F.Cu" "B.Cu")
		(net "P3V3_AUX")
	)
	(via
		(at 335.026 -142.875)
		(size 0.508)
		(drill 0.254)
		(layers "F.Cu" "B.Cu")
		(net "P3V3_AUX")
	)
	(via
		(at 224.695512 -232.471468)
		(size 0.508)
		(drill 0.254)
		(layers "F.Cu" "B.Cu")
		(net "P3V3_AUX")
	)
	(via
		(at 222.690944 -97.31375)
		(size 0.508)
		(drill 0.254)
		(layers "F.Cu" "B.Cu")
		(net "P3V3_AUX")
	)
	(via
		(at 341.571072 -189.40145)
		(size 0.508)
		(drill 0.254)
		(layers "F.Cu" "B.Cu")
		(net "P3V3_AUX")
	)
	(via
		(at 80.60563 -55.39359)
		(size 0.508)
		(drill 0.254)
		(layers "F.Cu" "B.Cu")
		(net "P3V3_AUX")
	)
	(via
		(at 113.904268 -128.638046)
		(size 0.508)
		(drill 0.254)
		(layers "F.Cu" "B.Cu")
		(net "P3V3_AUX")
	)
	(via
		(at 315.187838 -57.48528)
		(size 0.508)
		(drill 0.254)
		(layers "F.Cu" "B.Cu")
		(net "P3V3_AUX")
	)
	(via
		(at 314.481972 -54.96179)
		(size 0.508)
		(drill 0.254)
		(layers "F.Cu" "B.Cu")
		(net "P3V3_AUX")
	)
	(via
		(at 169.423334 -52.035456)
		(size 0.508)
		(drill 0.254)
		(layers "F.Cu" "B.Cu")
		(net "P3V3_AUX")
	)
	(via
		(at 231.08539 -205.937612)
		(size 0.508)
		(drill 0.254)
		(layers "F.Cu" "B.Cu")
		(net "P3V3_AUX")
	)
	(via
		(at 451.669658 -365.277146)
		(size 0.508)
		(drill 0.254)
		(layers "F.Cu" "B.Cu")
		(net "P3V3_AUX")
	)
	(via
		(at 249.872754 -273.98345)
		(size 0.508)
		(drill 0.254)
		(layers "F.Cu" "B.Cu")
		(net "P3V3_AUX")
	)
	(via
		(at 135.205216 -204.888846)
		(size 0.508)
		(drill 0.254)
		(layers "F.Cu" "B.Cu")
		(net "P3V3_AUX")
	)
	(via
		(at 327.75652 -125.891544)
		(size 0.508)
		(drill 0.254)
		(layers "F.Cu" "B.Cu")
		(net "P3V3_AUX")
	)
	(via
		(at 121.08815 -57.48528)
		(size 0.508)
		(drill 0.254)
		(layers "F.Cu" "B.Cu")
		(net "P3V3_AUX")
	)
	(via
		(at 132.710174 -209.463894)
		(size 0.508)
		(drill 0.254)
		(layers "F.Cu" "B.Cu")
		(net "P3V3_AUX")
	)
	(via
		(at 439.423556 -114.323114)
		(size 0.508)
		(drill 0.254)
		(layers "F.Cu" "B.Cu")
		(net "P3V3_AUX")
	)
	(via
		(at 443.815724 -119.380254)
		(size 0.508)
		(drill 0.254)
		(layers "F.Cu" "B.Cu")
		(net "P3V3_AUX")
	)
	(via
		(at 362.185458 -115.402106)
		(size 0.508)
		(drill 0.254)
		(layers "F.Cu" "B.Cu")
		(net "P3V3_AUX")
	)
	(via
		(at 230.349044 -178.38039)
		(size 0.508)
		(drill 0.254)
		(layers "F.Cu" "B.Cu")
		(net "P3V3_AUX")
	)
	(via
		(at 361.550458 -116.672106)
		(size 0.508)
		(drill 0.254)
		(layers "F.Cu" "B.Cu")
		(net "P3V3_AUX")
	)
	(via
		(at 277.795228 -401.937982)
		(size 0.508)
		(drill 0.254)
		(layers "F.Cu" "B.Cu")
		(net "P3V3_AUX")
	)
	(via
		(at 457.708 -226.681538)
		(size 0.508)
		(drill 0.254)
		(layers "F.Cu" "B.Cu")
		(net "P3V3_AUX")
	)
	(via
		(at 217.979244 -178.09718)
		(size 0.508)
		(drill 0.254)
		(layers "F.Cu" "B.Cu")
		(net "P3V3_AUX")
	)
	(via
		(at 440.185556 -114.323114)
		(size 0.508)
		(drill 0.254)
		(layers "F.Cu" "B.Cu")
		(net "P3V3_AUX")
	)
	(via
		(at 315.171074 -56.38038)
		(size 0.508)
		(drill 0.254)
		(layers "F.Cu" "B.Cu")
		(net "P3V3_AUX")
	)
	(via
		(at 263.171178 -55.11038)
		(size 0.508)
		(drill 0.254)
		(layers "F.Cu" "B.Cu")
		(net "P3V3_AUX")
	)
	(via
		(at 84.04987 -5.030724)
		(size 0.508)
		(drill 0.254)
		(layers "F.Cu" "B.Cu")
		(net "P3V3_AUX")
	)
	(via
		(at 358.14 -189.23)
		(size 0.508)
		(drill 0.254)
		(layers "F.Cu" "B.Cu")
		(net "P3V3_AUX")
	)
	(via
		(at 174.786544 -61.487812)
		(size 0.508)
		(drill 0.254)
		(layers "F.Cu" "B.Cu")
		(net "P3V3_AUX")
	)
	(via
		(at 372.324884 -260.0706)
		(size 0.508)
		(drill 0.254)
		(layers "F.Cu" "B.Cu")
		(net "P3V3_AUX")
	)
	(via
		(at 240.679224 -177.6857)
		(size 0.508)
		(drill 0.254)
		(layers "F.Cu" "B.Cu")
		(net "P3V3_AUX")
	)
	(via
		(at 109.571536 -141.01826)
		(size 0.508)
		(drill 0.254)
		(layers "F.Cu" "B.Cu")
		(net "P3V3_AUX")
	)
	(via
		(at 353.271328 -56.38038)
		(size 0.508)
		(drill 0.254)
		(layers "F.Cu" "B.Cu")
		(net "P3V3_AUX")
	)
	(via
		(at 199.682354 -36.286948)
		(size 0.508)
		(drill 0.254)
		(layers "F.Cu" "B.Cu")
		(net "P3V3_AUX")
	)
	(via
		(at 105.323132 -52.035456)
		(size 0.508)
		(drill 0.254)
		(layers "F.Cu" "B.Cu")
		(net "P3V3_AUX")
	)
	(via
		(at 322.680838 -113.558574)
		(size 0.508)
		(drill 0.254)
		(layers "F.Cu" "B.Cu")
		(net "P3V3_AUX")
	)
	(via
		(at 80.454754 -23.970996)
		(size 0.508)
		(drill 0.254)
		(layers "F.Cu" "B.Cu")
		(net "P3V3_AUX")
	)
	(via
		(at 230.26751 -215.504268)
		(size 0.4572)
		(drill 0.254)
		(layers "F.Cu" "B.Cu")
		(net "P3V3_AUX")
	)
	(via
		(at 227.734368 -90.009726)
		(size 0.508)
		(drill 0.254)
		(layers "F.Cu" "B.Cu")
		(net "P3V3_AUX")
	)
	(via
		(at 432.986434 -61.487812)
		(size 0.508)
		(drill 0.254)
		(layers "F.Cu" "B.Cu")
		(net "P3V3_AUX")
	)
	(via
		(at 109.199426 -35.876738)
		(size 0.508)
		(drill 0.254)
		(layers "F.Cu" "B.Cu")
		(net "P3V3_AUX")
	)
	(via
		(at 262.482076 -54.96179)
		(size 0.508)
		(drill 0.254)
		(layers "F.Cu" "B.Cu")
		(net "P3V3_AUX")
	)
	(via
		(at 219.408248 -47.403766)
		(size 0.508)
		(drill 0.254)
		(layers "F.Cu" "B.Cu")
		(net "P3V3_AUX")
	)
	(via
		(at 233.176064 -40.971724)
		(size 0.508)
		(drill 0.254)
		(layers "F.Cu" "B.Cu")
		(net "P3V3_AUX")
	)
	(via
		(at 375.297446 -87.6808)
		(size 0.508)
		(drill 0.254)
		(layers "F.Cu" "B.Cu")
		(net "P3V3_AUX")
	)
	(via
		(at 356.87 -179.578)
		(size 0.508)
		(drill 0.254)
		(layers "F.Cu" "B.Cu")
		(net "P3V3_AUX")
	)
	(via
		(at 105.8926 -8.4836)
		(size 0.508)
		(drill 0.254)
		(layers "F.Cu" "B.Cu")
		(net "P3V3_AUX")
	)
	(via
		(at 2.785364 -41.166542)
		(size 0.508)
		(drill 0.254)
		(layers "F.Cu" "B.Cu")
		(net "P3V3_AUX")
	)
	(via
		(at 407.77922 -372.877842)
		(size 0.508)
		(drill 0.254)
		(layers "F.Cu" "B.Cu")
		(net "P3V3_AUX")
	)
	(via
		(at 192.114932 -409.896818)
		(size 0.508)
		(drill 0.254)
		(layers "F.Cu" "B.Cu")
		(net "P3V3_AUX")
	)
	(via
		(at 358.14 -172.974)
		(size 0.508)
		(drill 0.254)
		(layers "F.Cu" "B.Cu")
		(net "P3V3_AUX")
	)
	(via
		(at 133.532372 -221.950534)
		(size 0.508)
		(drill 0.254)
		(layers "F.Cu" "B.Cu")
		(net "P3V3_AUX")
	)
	(via
		(at 84.04987 -4.014724)
		(size 0.508)
		(drill 0.254)
		(layers "F.Cu" "B.Cu")
		(net "P3V3_AUX")
	)
	(via
		(at 315.171074 -55.74538)
		(size 0.508)
		(drill 0.254)
		(layers "F.Cu" "B.Cu")
		(net "P3V3_AUX")
	)
	(via
		(at 120.119902 -98.320606)
		(size 0.508)
		(drill 0.254)
		(layers "F.Cu" "B.Cu")
		(net "P3V3_AUX")
	)
	(via
		(at 84.686394 -61.487812)
		(size 0.508)
		(drill 0.254)
		(layers "F.Cu" "B.Cu")
		(net "P3V3_AUX")
	)
	(via
		(at 380.141734 -210.566)
		(size 0.508)
		(drill 0.254)
		(layers "F.Cu" "B.Cu")
		(net "P3V3_AUX")
	)
	(via
		(at 130.53314 -122.53595)
		(size 0.508)
		(drill 0.254)
		(layers "F.Cu" "B.Cu")
		(net "P3V3_AUX")
	)
	(via
		(at 375.297446 -84.2518)
		(size 0.508)
		(drill 0.254)
		(layers "F.Cu" "B.Cu")
		(net "P3V3_AUX")
	)
	(via
		(at 81.31683 -55.39359)
		(size 0.508)
		(drill 0.254)
		(layers "F.Cu" "B.Cu")
		(net "P3V3_AUX")
	)
	(via
		(at 231.765348 -174.69358)
		(size 0.508)
		(drill 0.254)
		(layers "F.Cu" "B.Cu")
		(net "P3V3_AUX")
	)
	(via
		(at 354.858066 -139.376404)
		(size 0.508)
		(drill 0.254)
		(layers "F.Cu" "B.Cu")
		(net "P3V3_AUX")
	)
	(via
		(at 356.924356 -245.128796)
		(size 0.508)
		(drill 0.254)
		(layers "F.Cu" "B.Cu")
		(net "P3V3_AUX")
	)
	(via
		(at 12.095734 -341.292688)
		(size 0.508)
		(drill 0.254)
		(layers "F.Cu" "B.Cu")
		(net "P3V3_AUX")
	)
	(via
		(at 357.44277 -399.219928)
		(size 0.508)
		(drill 0.254)
		(layers "F.Cu" "B.Cu")
		(net "P3V3_AUX")
	)
	(via
		(at 362.458 -201.803)
		(size 0.508)
		(drill 0.254)
		(layers "F.Cu" "B.Cu")
		(net "P3V3_AUX")
	)
	(via
		(at 239.232186 -157.812994)
		(size 0.508)
		(drill 0.254)
		(layers "F.Cu" "B.Cu")
		(net "P3V3_AUX")
	)
	(via
		(at 289.146742 -139.6492)
		(size 0.508)
		(drill 0.254)
		(layers "F.Cu" "B.Cu")
		(net "P3V3_AUX")
	)
	(via
		(at 374.50395 -192.25895)
		(size 0.508)
		(drill 0.254)
		(layers "F.Cu" "B.Cu")
		(net "P3V3_AUX")
	)
	(via
		(at 51.718464 -22.555454)
		(size 0.508)
		(drill 0.254)
		(layers "F.Cu" "B.Cu")
		(net "P3V3_AUX")
	)
	(via
		(at 141.408404 -47.403766)
		(size 0.508)
		(drill 0.254)
		(layers "F.Cu" "B.Cu")
		(net "P3V3_AUX")
	)
	(via
		(at 309.918354 -22.555454)
		(size 0.508)
		(drill 0.254)
		(layers "F.Cu" "B.Cu")
		(net "P3V3_AUX")
	)
	(via
		(at 27.270456 -29.614876)
		(size 0.508)
		(drill 0.254)
		(layers "F.Cu" "B.Cu")
		(net "P3V3_AUX")
	)
	(via
		(at 209.857086 -219.977208)
		(size 0.508)
		(drill 0.254)
		(layers "F.Cu" "B.Cu")
		(net "P3V3_AUX")
	)
	(via
		(at 240.724182 -81.19872)
		(size 0.508)
		(drill 0.254)
		(layers "F.Cu" "B.Cu")
		(net "P3V3_AUX")
	)
	(via
		(at 285.470346 -29.614876)
		(size 0.508)
		(drill 0.254)
		(layers "F.Cu" "B.Cu")
		(net "P3V3_AUX")
	)
	(via
		(at 140.090144 -92.385642)
		(size 0.508)
		(drill 0.254)
		(layers "F.Cu" "B.Cu")
		(net "P3V3_AUX")
	)
	(via
		(at 109.054392 -286.789368)
		(size 0.508)
		(drill 0.254)
		(layers "F.Cu" "B.Cu")
		(net "P3V3_AUX")
	)
	(via
		(at 453.615044 -44.87291)
		(size 0.508)
		(drill 0.254)
		(layers "F.Cu" "B.Cu")
		(net "P3V3_AUX")
	)
	(via
		(at 212.974936 -189.662054)
		(size 0.508)
		(drill 0.254)
		(layers "F.Cu" "B.Cu")
		(net "P3V3_AUX")
	)
	(via
		(at 349.570548 -30.376876)
		(size 0.508)
		(drill 0.254)
		(layers "F.Cu" "B.Cu")
		(net "P3V3_AUX")
	)
	(via
		(at 277.742396 -416.106102)
		(size 0.508)
		(drill 0.254)
		(layers "F.Cu" "B.Cu")
		(net "P3V3_AUX")
	)
	(via
		(at 256.798826 -241.000788)
		(size 0.508)
		(drill 0.254)
		(layers "F.Cu" "B.Cu")
		(net "P3V3_AUX")
	)
	(via
		(at 388.398512 -242.056412)
		(size 0.508)
		(drill 0.254)
		(layers "F.Cu" "B.Cu")
		(net "P3V3_AUX")
	)
	(via
		(at 302.552354 -237.819184)
		(size 0.508)
		(drill 0.254)
		(layers "F.Cu" "B.Cu")
		(net "P3V3_AUX")
	)
	(via
		(at 335.026 -172.085)
		(size 0.508)
		(drill 0.254)
		(layers "F.Cu" "B.Cu")
		(net "P3V3_AUX")
	)
	(via
		(at 241.624612 -63.648082)
		(size 0.508)
		(drill 0.254)
		(layers "F.Cu" "B.Cu")
		(net "P3V3_AUX")
	)
	(via
		(at 114.910616 -138.93546)
		(size 0.508)
		(drill 0.254)
		(layers "F.Cu" "B.Cu")
		(net "P3V3_AUX")
	)
	(via
		(at 380.986538 -61.487812)
		(size 0.508)
		(drill 0.254)
		(layers "F.Cu" "B.Cu")
		(net "P3V3_AUX")
	)
	(via
		(at 347.330776 -254.955802)
		(size 0.508)
		(drill 0.254)
		(layers "F.Cu" "B.Cu")
		(net "P3V3_AUX")
	)
	(via
		(at 225.041206 -77.563472)
		(size 0.508)
		(drill 0.254)
		(layers "F.Cu" "B.Cu")
		(net "P3V3_AUX")
	)
	(via
		(at 370.571776 -153.782522)
		(size 0.508)
		(drill 0.254)
		(layers "F.Cu" "B.Cu")
		(net "P3V3_AUX")
	)
	(via
		(at 220.812868 -103.537258)
		(size 0.508)
		(drill 0.254)
		(layers "F.Cu" "B.Cu")
		(net "P3V3_AUX")
	)
	(via
		(at 62.874144 -153.083006)
		(size 0.508)
		(drill 0.254)
		(layers "F.Cu" "B.Cu")
		(net "P3V3_AUX")
	)
	(via
		(at 167.898572 -179.728368)
		(size 0.508)
		(drill 0.254)
		(layers "F.Cu" "B.Cu")
		(net "P3V3_AUX")
	)
	(via
		(at 65.14465 -107.210352)
		(size 0.508)
		(drill 0.254)
		(layers "F.Cu" "B.Cu")
		(net "P3V3_AUX")
	)
	(via
		(at 263.849866 -26.03373)
		(size 0.508)
		(drill 0.254)
		(layers "F.Cu" "B.Cu")
		(net "P3V3_AUX")
	)
	(via
		(at 313.516772 -55.39359)
		(size 0.508)
		(drill 0.254)
		(layers "F.Cu" "B.Cu")
		(net "P3V3_AUX")
	)
	(via
		(at 2.605786 -55.39359)
		(size 0.508)
		(drill 0.254)
		(layers "F.Cu" "B.Cu")
		(net "P3V3_AUX")
	)
	(via
		(at 249.104404 -275.503386)
		(size 0.508)
		(drill 0.254)
		(layers "F.Cu" "B.Cu")
		(net "P3V3_AUX")
	)
	(via
		(at 361.949746 -123.225052)
		(size 0.508)
		(drill 0.254)
		(layers "F.Cu" "B.Cu")
		(net "P3V3_AUX")
	)
	(via
		(at 241.42065 -200.497694)
		(size 0.508)
		(drill 0.254)
		(layers "F.Cu" "B.Cu")
		(net "P3V3_AUX")
	)
	(via
		(at 170.70578 -55.39359)
		(size 0.508)
		(drill 0.254)
		(layers "F.Cu" "B.Cu")
		(net "P3V3_AUX")
	)
	(via
		(at 358.14 -188.214)
		(size 0.508)
		(drill 0.254)
		(layers "F.Cu" "B.Cu")
		(net "P3V3_AUX")
	)
	(via
		(at 94.034356 -246.840248)
		(size 0.508)
		(drill 0.254)
		(layers "F.Cu" "B.Cu")
		(net "P3V3_AUX")
	)
	(via
		(at 231.352344 -183.27878)
		(size 0.508)
		(drill 0.254)
		(layers "F.Cu" "B.Cu")
		(net "P3V3_AUX")
	)
	(via
		(at 195.37045 -29.614876)
		(size 0.508)
		(drill 0.254)
		(layers "F.Cu" "B.Cu")
		(net "P3V3_AUX")
	)
	(via
		(at 236.92358 -223.071182)
		(size 0.508)
		(drill 0.254)
		(layers "F.Cu" "B.Cu")
		(net "P3V3_AUX")
	)
	(via
		(at 98.193606 -219.559632)
		(size 0.508)
		(drill 0.254)
		(layers "F.Cu" "B.Cu")
		(net "P3V3_AUX")
	)
	(via
		(at 120.09374 -88.39073)
		(size 0.508)
		(drill 0.254)
		(layers "F.Cu" "B.Cu")
		(net "P3V3_AUX")
	)
	(via
		(at 312.654696 -23.970996)
		(size 0.508)
		(drill 0.254)
		(layers "F.Cu" "B.Cu")
		(net "P3V3_AUX")
	)
	(via
		(at 173.071282 -55.11038)
		(size 0.508)
		(drill 0.254)
		(layers "F.Cu" "B.Cu")
		(net "P3V3_AUX")
	)
	(via
		(at 100.557076 -361.5944)
		(size 0.4572)
		(drill 0.254)
		(layers "F.Cu" "B.Cu")
		(net "P3V3_AUX")
	)
	(via
		(at 119.013732 -131.218686)
		(size 0.508)
		(drill 0.254)
		(layers "F.Cu" "B.Cu")
		(net "P3V3_AUX")
	)
	(via
		(at 95.5802 -194.8942)
		(size 0.508)
		(drill 0.254)
		(layers "F.Cu" "B.Cu")
		(net "P3V3_AUX")
	)
	(via
		(at 4.971288 -56.38038)
		(size 0.508)
		(drill 0.254)
		(layers "F.Cu" "B.Cu")
		(net "P3V3_AUX")
	)
	(via
		(at 351.38995 -149.96795)
		(size 0.508)
		(drill 0.254)
		(layers "F.Cu" "B.Cu")
		(net "P3V3_AUX")
	)
	(via
		(at 193.4083 -47.403766)
		(size 0.508)
		(drill 0.254)
		(layers "F.Cu" "B.Cu")
		(net "P3V3_AUX")
	)
	(via
		(at 129.11455 -123.225052)
		(size 0.508)
		(drill 0.254)
		(layers "F.Cu" "B.Cu")
		(net "P3V3_AUX")
	)
	(via
		(at 251.615702 -337.070192)
		(size 0.508)
		(drill 0.254)
		(layers "F.Cu" "B.Cu")
		(net "P3V3_AUX")
	)
	(via
		(at 351.436432 -157.080458)
		(size 0.508)
		(drill 0.254)
		(layers "F.Cu" "B.Cu")
		(net "P3V3_AUX")
	)
	(via
		(at 358.108504 -230.593392)
		(size 0.508)
		(drill 0.254)
		(layers "F.Cu" "B.Cu")
		(net "P3V3_AUX")
	)
	(via
		(at 360.5911 -123.222512)
		(size 0.508)
		(drill 0.254)
		(layers "F.Cu" "B.Cu")
		(net "P3V3_AUX")
	)
	(via
		(at 375.570496 -30.376876)
		(size 0.508)
		(drill 0.254)
		(layers "F.Cu" "B.Cu")
		(net "P3V3_AUX")
	)
	(via
		(at 17.469612 -221.950534)
		(size 0.508)
		(drill 0.254)
		(layers "F.Cu" "B.Cu")
		(net "P3V3_AUX")
	)
	(via
		(at 460.455772 -329.880976)
		(size 0.508)
		(drill 0.254)
		(layers "F.Cu" "B.Cu")
		(net "P3V3_AUX")
	)
	(via
		(at 375.309638 -173.481238)
		(size 0.508)
		(drill 0.254)
		(layers "F.Cu" "B.Cu")
		(net "P3V3_AUX")
	)
	(via
		(at 7.032244 -157.812994)
		(size 0.508)
		(drill 0.254)
		(layers "F.Cu" "B.Cu")
		(net "P3V3_AUX")
	)
	(via
		(at 131.611878 -204.209142)
		(size 0.508)
		(drill 0.254)
		(layers "F.Cu" "B.Cu")
		(net "P3V3_AUX")
	)
	(via
		(at 114.539268 -128.638046)
		(size 0.508)
		(drill 0.254)
		(layers "F.Cu" "B.Cu")
		(net "P3V3_AUX")
	)
	(via
		(at 193.718434 -411.319218)
		(size 0.508)
		(drill 0.254)
		(layers "F.Cu" "B.Cu")
		(net "P3V3_AUX")
	)
	(via
		(at 222.576644 -176.52238)
		(size 0.508)
		(drill 0.254)
		(layers "F.Cu" "B.Cu")
		(net "P3V3_AUX")
	)
	(via
		(at 335.026 -176.911)
		(size 0.508)
		(drill 0.254)
		(layers "F.Cu" "B.Cu")
		(net "P3V3_AUX")
	)
	(via
		(at 362.301536 -120.93575)
		(size 0.508)
		(drill 0.254)
		(layers "F.Cu" "B.Cu")
		(net "P3V3_AUX")
	)
	(via
		(at 128.390904 -123.222512)
		(size 0.508)
		(drill 0.254)
		(layers "F.Cu" "B.Cu")
		(net "P3V3_AUX")
	)
	(via
		(at 379.857 -190.627)
		(size 0.508)
		(drill 0.254)
		(layers "F.Cu" "B.Cu")
		(net "P3V3_AUX")
	)
	(via
		(at 180.503322 -115.90909)
		(size 0.508)
		(drill 0.254)
		(layers "F.Cu" "B.Cu")
		(net "P3V3_AUX")
	)
	(via
		(at 355.332284 -159.844994)
		(size 0.508)
		(drill 0.254)
		(layers "F.Cu" "B.Cu")
		(net "P3V3_AUX")
	)
	(via
		(at 245.95836 -117.434106)
		(size 0.508)
		(drill 0.254)
		(layers "F.Cu" "B.Cu")
		(net "P3V3_AUX")
	)
	(via
		(at 248.559574 -148.017738)
		(size 0.508)
		(drill 0.254)
		(layers "F.Cu" "B.Cu")
		(net "P3V3_AUX")
	)
	(via
		(at 361.67822 -386.172456)
		(size 0.508)
		(drill 0.254)
		(layers "F.Cu" "B.Cu")
		(net "P3V3_AUX")
	)
	(via
		(at 135.208264 -211.746846)
		(size 0.508)
		(drill 0.254)
		(layers "F.Cu" "B.Cu")
		(net "P3V3_AUX")
	)
	(via
		(at 356.87 -178.562)
		(size 0.508)
		(drill 0.254)
		(layers "F.Cu" "B.Cu")
		(net "P3V3_AUX")
	)
	(via
		(at 335.026 -146.939)
		(size 0.508)
		(drill 0.254)
		(layers "F.Cu" "B.Cu")
		(net "P3V3_AUX")
	)
	(via
		(at 220.705426 -178.027076)
		(size 0.508)
		(drill 0.254)
		(layers "F.Cu" "B.Cu")
		(net "P3V3_AUX")
	)
	(via
		(at 167.408352 -47.403766)
		(size 0.508)
		(drill 0.254)
		(layers "F.Cu" "B.Cu")
		(net "P3V3_AUX")
	)
	(via
		(at 351.38995 -161.77895)
		(size 0.508)
		(drill 0.254)
		(layers "F.Cu" "B.Cu")
		(net "P3V3_AUX")
	)
	(via
		(at 256.011426 -241.000788)
		(size 0.508)
		(drill 0.254)
		(layers "F.Cu" "B.Cu")
		(net "P3V3_AUX")
	)
	(via
		(at 404.226522 -118.194328)
		(size 0.508)
		(drill 0.254)
		(layers "F.Cu" "B.Cu")
		(net "P3V3_AUX")
	)
	(via
		(at 201.925682 -338.84362)
		(size 0.508)
		(drill 0.254)
		(layers "F.Cu" "B.Cu")
		(net "P3V3_AUX")
	)
	(via
		(at 134.953502 -206.4639)
		(size 0.508)
		(drill 0.254)
		(layers "F.Cu" "B.Cu")
		(net "P3V3_AUX")
	)
	(via
		(at 212.67166 -225.42246)
		(size 0.508)
		(drill 0.254)
		(layers "F.Cu" "B.Cu")
		(net "P3V3_AUX")
	)
	(via
		(at 14.393418 -117.434106)
		(size 0.508)
		(drill 0.254)
		(layers "F.Cu" "B.Cu")
		(net "P3V3_AUX")
	)
	(via
		(at 325.734934 -288.830766)
		(size 0.508)
		(drill 0.254)
		(layers "F.Cu" "B.Cu")
		(net "P3V3_AUX")
	)
	(via
		(at 320.56705 -82.31505)
		(size 0.508)
		(drill 0.254)
		(layers "F.Cu" "B.Cu")
		(net "P3V3_AUX")
	)
	(via
		(at 117.370606 -29.614876)
		(size 0.508)
		(drill 0.254)
		(layers "F.Cu" "B.Cu")
		(net "P3V3_AUX")
	)
	(via
		(at 335.026 -185.039)
		(size 0.508)
		(drill 0.254)
		(layers "F.Cu" "B.Cu")
		(net "P3V3_AUX")
	)
	(via
		(at 431.271172 -55.11038)
		(size 0.508)
		(drill 0.254)
		(layers "F.Cu" "B.Cu")
		(net "P3V3_AUX")
	)
	(via
		(at 225.467926 -217.104468)
		(size 0.4572)
		(drill 0.254)
		(layers "F.Cu" "B.Cu")
		(net "P3V3_AUX")
	)
	(via
		(at 51.308254 -47.403766)
		(size 0.508)
		(drill 0.254)
		(layers "F.Cu" "B.Cu")
		(net "P3V3_AUX")
	)
	(via
		(at 222.965772 -209.350356)
		(size 0.508)
		(drill 0.254)
		(layers "F.Cu" "B.Cu")
		(net "P3V3_AUX")
	)
	(via
		(at 226.267772 -221.103952)
		(size 0.4572)
		(drill 0.254)
		(layers "F.Cu" "B.Cu")
		(net "P3V3_AUX")
	)
	(via
		(at 21.550376 -48.753014)
		(size 0.508)
		(drill 0.254)
		(layers "F.Cu" "B.Cu")
		(net "P3V3_AUX")
	)
	(via
		(at 81.564226 -158.219648)
		(size 0.508)
		(drill 0.254)
		(layers "F.Cu" "B.Cu")
		(net "P3V3_AUX")
	)
	(via
		(at 127.185166 -119.35587)
		(size 0.508)
		(drill 0.254)
		(layers "F.Cu" "B.Cu")
		(net "P3V3_AUX")
	)
	(via
		(at 245.95836 -116.164106)
		(size 0.508)
		(drill 0.254)
		(layers "F.Cu" "B.Cu")
		(net "P3V3_AUX")
	)
	(via
		(at 289.171126 -55.74538)
		(size 0.508)
		(drill 0.254)
		(layers "F.Cu" "B.Cu")
		(net "P3V3_AUX")
	)
	(via
		(at 129.985262 -116.037106)
		(size 0.508)
		(drill 0.254)
		(layers "F.Cu" "B.Cu")
		(net "P3V3_AUX")
	)
	(via
		(at 79.270352 -29.614876)
		(size 0.508)
		(drill 0.254)
		(layers "F.Cu" "B.Cu")
		(net "P3V3_AUX")
	)
	(via
		(at 246.201438 -120.85955)
		(size 0.508)
		(drill 0.254)
		(layers "F.Cu" "B.Cu")
		(net "P3V3_AUX")
	)
	(via
		(at 461.456024 -278.67483)
		(size 0.508)
		(drill 0.254)
		(layers "F.Cu" "B.Cu")
		(net "P3V3_AUX")
	)
	(via
		(at 425.608242 -47.403766)
		(size 0.508)
		(drill 0.254)
		(layers "F.Cu" "B.Cu")
		(net "P3V3_AUX")
	)
	(via
		(at 129.350262 -116.672106)
		(size 0.508)
		(drill 0.254)
		(layers "F.Cu" "B.Cu")
		(net "P3V3_AUX")
	)
	(via
		(at 327.715626 -119.380254)
		(size 0.508)
		(drill 0.254)
		(layers "F.Cu" "B.Cu")
		(net "P3V3_AUX")
	)
	(via
		(at 144.159986 -209.463894)
		(size 0.508)
		(drill 0.254)
		(layers "F.Cu" "B.Cu")
		(net "P3V3_AUX")
	)
	(via
		(at 143.370554 -29.614876)
		(size 0.508)
		(drill 0.254)
		(layers "F.Cu" "B.Cu")
		(net "P3V3_AUX")
	)
	(via
		(at 451.623938 -232.69448)
		(size 0.508)
		(drill 0.254)
		(layers "F.Cu" "B.Cu")
		(net "P3V3_AUX")
	)
	(via
		(at 427.570392 -30.376876)
		(size 0.508)
		(drill 0.254)
		(layers "F.Cu" "B.Cu")
		(net "P3V3_AUX")
	)
	(via
		(at 97.0026 -392.3792)
		(size 0.508)
		(drill 0.254)
		(layers "F.Cu" "B.Cu")
		(net "P3V3_AUX")
	)
	(via
		(at 283.21 -84.836)
		(size 0.508)
		(drill 0.254)
		(layers "F.Cu" "B.Cu")
		(net "P3V3_AUX")
	)
	(via
		(at 399.19275 -87.409274)
		(size 0.508)
		(drill 0.254)
		(layers "F.Cu" "B.Cu")
		(net "P3V3_AUX")
	)
	(via
		(at 269.670022 -117.7544)
		(size 0.508)
		(drill 0.254)
		(layers "F.Cu" "B.Cu")
		(net "P3V3_AUX")
	)
	(via
		(at 299.659294 -85.44052)
		(size 0.508)
		(drill 0.254)
		(layers "F.Cu" "B.Cu")
		(net "P3V3_AUX")
	)
	(via
		(at 286.654748 -23.970996)
		(size 0.508)
		(drill 0.254)
		(layers "F.Cu" "B.Cu")
		(net "P3V3_AUX")
	)
	(via
		(at 207.428592 -350.712532)
		(size 0.508)
		(drill 0.254)
		(layers "F.Cu" "B.Cu")
		(net "P3V3_AUX")
	)
	(via
		(at 237.750604 -184.7723)
		(size 0.508)
		(drill 0.254)
		(layers "F.Cu" "B.Cu")
		(net "P3V3_AUX")
	)
	(via
		(at 368.539776 -153.782522)
		(size 0.508)
		(drill 0.254)
		(layers "F.Cu" "B.Cu")
		(net "P3V3_AUX")
	)
	(via
		(at 209.738976 -292.122098)
		(size 0.508)
		(drill 0.254)
		(layers "F.Cu" "B.Cu")
		(net "P3V3_AUX")
	)
	(via
		(at 370.60124 -82.641694)
		(size 0.508)
		(drill 0.254)
		(layers "F.Cu" "B.Cu")
		(net "P3V3_AUX")
	)
	(via
		(at 6.558026 -139.376404)
		(size 0.508)
		(drill 0.254)
		(layers "F.Cu" "B.Cu")
		(net "P3V3_AUX")
	)
	(via
		(at 364.540038 -261.206488)
		(size 0.508)
		(drill 0.254)
		(layers "F.Cu" "B.Cu")
		(net "P3V3_AUX")
	)
	(via
		(at 252.326902 -336.358992)
		(size 0.508)
		(drill 0.254)
		(layers "F.Cu" "B.Cu")
		(net "P3V3_AUX")
	)
	(via
		(at 169.415206 -44.87291)
		(size 0.508)
		(drill 0.254)
		(layers "F.Cu" "B.Cu")
		(net "P3V3_AUX")
	)
	(via
		(at 142.446502 -213.505796)
		(size 0.508)
		(drill 0.254)
		(layers "F.Cu" "B.Cu")
		(net "P3V3_AUX")
	)
	(via
		(at 136.33958 -153.782522)
		(size 0.508)
		(drill 0.254)
		(layers "F.Cu" "B.Cu")
		(net "P3V3_AUX")
	)
	(via
		(at 206.617824 -112.134396)
		(size 0.508)
		(drill 0.254)
		(layers "F.Cu" "B.Cu")
		(net "P3V3_AUX")
	)
	(via
		(at 14.037056 -402.204936)
		(size 0.508)
		(drill 0.254)
		(layers "F.Cu" "B.Cu")
		(net "P3V3_AUX")
	)
	(via
		(at 100.894642 -202.385168)
		(size 0.508)
		(drill 0.254)
		(layers "F.Cu" "B.Cu")
		(net "P3V3_AUX")
	)
	(via
		(at 370.60124 -81.498694)
		(size 0.508)
		(drill 0.254)
		(layers "F.Cu" "B.Cu")
		(net "P3V3_AUX")
	)
	(via
		(at 458.832712 -366.913922)
		(size 0.508)
		(drill 0.254)
		(layers "F.Cu" "B.Cu")
		(net "P3V3_AUX")
	)
	(via
		(at 303.077626 -238.938562)
		(size 0.508)
		(drill 0.254)
		(layers "F.Cu" "B.Cu")
		(net "P3V3_AUX")
	)
	(via
		(at 101.0666 -200.406)
		(size 0.508)
		(drill 0.254)
		(layers "F.Cu" "B.Cu")
		(net "P3V3_AUX")
	)
	(via
		(at 109.571536 -140.35786)
		(size 0.508)
		(drill 0.254)
		(layers "F.Cu" "B.Cu")
		(net "P3V3_AUX")
	)
	(via
		(at 246.633238 -122.53595)
		(size 0.508)
		(drill 0.254)
		(layers "F.Cu" "B.Cu")
		(net "P3V3_AUX")
	)
	(via
		(at 367.491518 -339.304884)
		(size 0.508)
		(drill 0.254)
		(layers "F.Cu" "B.Cu")
		(net "P3V3_AUX")
	)
	(via
		(at 106.035094 -398.674336)
		(size 0.508)
		(drill 0.254)
		(layers "F.Cu" "B.Cu")
		(net "P3V3_AUX")
	)
	(via
		(at 463.537046 -273.59483)
		(size 0.508)
		(drill 0.254)
		(layers "F.Cu" "B.Cu")
		(net "P3V3_AUX")
	)
	(via
		(at 322.057776 -94.428818)
		(size 0.508)
		(drill 0.254)
		(layers "F.Cu" "B.Cu")
		(net "P3V3_AUX")
	)
	(via
		(at 367.289588 -235.458)
		(size 0.508)
		(drill 0.254)
		(layers "F.Cu" "B.Cu")
		(net "P3V3_AUX")
	)
	(via
		(at 315.782198 -36.286948)
		(size 0.508)
		(drill 0.254)
		(layers "F.Cu" "B.Cu")
		(net "P3V3_AUX")
	)
	(via
		(at 12.29106 -123.222512)
		(size 0.508)
		(drill 0.254)
		(layers "F.Cu" "B.Cu")
		(net "P3V3_AUX")
	)
	(via
		(at 108.89996 -138.93546)
		(size 0.508)
		(drill 0.254)
		(layers "F.Cu" "B.Cu")
		(net "P3V3_AUX")
	)
	(via
		(at 335.026 -141.859)
		(size 0.508)
		(drill 0.254)
		(layers "F.Cu" "B.Cu")
		(net "P3V3_AUX")
	)
	(via
		(at 402.754846 -23.970996)
		(size 0.508)
		(drill 0.254)
		(layers "F.Cu" "B.Cu")
		(net "P3V3_AUX")
	)
	(via
		(at 375.912888 -10.35812)
		(size 0.508)
		(drill 0.254)
		(layers "F.Cu" "B.Cu")
		(net "P3V3_AUX")
	)
	(via
		(at 120.119902 -99.463606)
		(size 0.508)
		(drill 0.254)
		(layers "F.Cu" "B.Cu")
		(net "P3V3_AUX")
	)
	(via
		(at 452.160132 -242.13693)
		(size 0.508)
		(drill 0.254)
		(layers "F.Cu" "B.Cu")
		(net "P3V3_AUX")
	)
	(via
		(at 450.542406 -235.626402)
		(size 0.508)
		(drill 0.254)
		(layers "F.Cu" "B.Cu")
		(net "P3V3_AUX")
	)
	(via
		(at 294.52189 -137.848848)
		(size 0.508)
		(drill 0.254)
		(layers "F.Cu" "B.Cu")
		(net "P3V3_AUX")
	)
	(via
		(at 259.258562 -212.765386)
		(size 0.508)
		(drill 0.254)
		(layers "F.Cu" "B.Cu")
		(net "P3V3_AUX")
	)
	(via
		(at 144.628362 -241.758978)
		(size 0.508)
		(drill 0.254)
		(layers "F.Cu" "B.Cu")
		(net "P3V3_AUX")
	)
	(via
		(at 375.27611 -40.971724)
		(size 0.508)
		(drill 0.254)
		(layers "F.Cu" "B.Cu")
		(net "P3V3_AUX")
	)
	(via
		(at 130.699764 -258.131564)
		(size 0.508)
		(drill 0.254)
		(layers "F.Cu" "B.Cu")
		(net "P3V3_AUX")
	)
	(via
		(at 186.171586 -117.723666)
		(size 0.508)
		(drill 0.254)
		(layers "F.Cu" "B.Cu")
		(net "P3V3_AUX")
	)
	(via
		(at 169.415206 -42.84091)
		(size 0.508)
		(drill 0.254)
		(layers "F.Cu" "B.Cu")
		(net "P3V3_AUX")
	)
	(via
		(at 365.491776 -151.696928)
		(size 0.508)
		(drill 0.254)
		(layers "F.Cu" "B.Cu")
		(net "P3V3_AUX")
	)
	(via
		(at 315.171074 -55.11038)
		(size 0.508)
		(drill 0.254)
		(layers "F.Cu" "B.Cu")
		(net "P3V3_AUX")
	)
	(via
		(at 242.460018 -235.624116)
		(size 0.508)
		(drill 0.254)
		(layers "F.Cu" "B.Cu")
		(net "P3V3_AUX")
	)
	(via
		(at 122.786648 -61.487812)
		(size 0.508)
		(drill 0.254)
		(layers "F.Cu" "B.Cu")
		(net "P3V3_AUX")
	)
	(via
		(at 30.282134 -54.96179)
		(size 0.508)
		(drill 0.254)
		(layers "F.Cu" "B.Cu")
		(net "P3V3_AUX")
	)
	(via
		(at 19.099276 -35.876738)
		(size 0.508)
		(drill 0.254)
		(layers "F.Cu" "B.Cu")
		(net "P3V3_AUX")
	)
	(via
		(at 13.758418 -116.164106)
		(size 0.508)
		(drill 0.254)
		(layers "F.Cu" "B.Cu")
		(net "P3V3_AUX")
	)
	(via
		(at 427.570392 -29.614876)
		(size 0.508)
		(drill 0.254)
		(layers "F.Cu" "B.Cu")
		(net "P3V3_AUX")
	)
	(via
		(at 375.741438 -176.18202)
		(size 0.508)
		(drill 0.254)
		(layers "F.Cu" "B.Cu")
		(net "P3V3_AUX")
	)
	(via
		(at 360.86796 -256.226564)
		(size 0.508)
		(drill 0.254)
		(layers "F.Cu" "B.Cu")
		(net "P3V3_AUX")
	)
	(via
		(at 187.19927 -35.876738)
		(size 0.508)
		(drill 0.254)
		(layers "F.Cu" "B.Cu")
		(net "P3V3_AUX")
	)
	(via
		(at 358.743504 -230.593392)
		(size 0.508)
		(drill 0.254)
		(layers "F.Cu" "B.Cu")
		(net "P3V3_AUX")
	)
	(via
		(at 242.232434 -251.857256)
		(size 0.508)
		(drill 0.254)
		(layers "F.Cu" "B.Cu")
		(net "P3V3_AUX")
	)
	(via
		(at 362.458 -212.979)
		(size 0.508)
		(drill 0.254)
		(layers "F.Cu" "B.Cu")
		(net "P3V3_AUX")
	)
	(via
		(at 236.205522 -94.6404)
		(size 0.508)
		(drill 0.254)
		(layers "F.Cu" "B.Cu")
		(net "P3V3_AUX")
	)
	(via
		(at 209.82178 -226.825556)
		(size 0.508)
		(drill 0.254)
		(layers "F.Cu" "B.Cu")
		(net "P3V3_AUX")
	)
	(via
		(at 192.793366 -83.532218)
		(size 0.508)
		(drill 0.254)
		(layers "F.Cu" "B.Cu")
		(net "P3V3_AUX")
	)
	(via
		(at 56.9468 -139.6492)
		(size 0.508)
		(drill 0.254)
		(layers "F.Cu" "B.Cu")
		(net "P3V3_AUX")
	)
	(via
		(at 359.378504 -230.593392)
		(size 0.508)
		(drill 0.254)
		(layers "F.Cu" "B.Cu")
		(net "P3V3_AUX")
	)
	(via
		(at 203.025756 -374.826022)
		(size 0.508)
		(drill 0.254)
		(layers "F.Cu" "B.Cu")
		(net "P3V3_AUX")
	)
	(via
		(at 279.622504 -394.762482)
		(size 0.508)
		(drill 0.254)
		(layers "F.Cu" "B.Cu")
		(net "P3V3_AUX")
	)
	(via
		(at 212.451442 -245.025926)
		(size 0.508)
		(drill 0.254)
		(layers "F.Cu" "B.Cu")
		(net "P3V3_AUX")
	)
	(via
		(at 376.764296 -238.588296)
		(size 0.508)
		(drill 0.254)
		(layers "F.Cu" "B.Cu")
		(net "P3V3_AUX")
	)
	(via
		(at 195.076064 -40.971724)
		(size 0.508)
		(drill 0.254)
		(layers "F.Cu" "B.Cu")
		(net "P3V3_AUX")
	)
	(via
		(at 147.574254 -205.987142)
		(size 0.508)
		(drill 0.254)
		(layers "F.Cu" "B.Cu")
		(net "P3V3_AUX")
	)
	(via
		(at 255.580388 -249.005598)
		(size 0.508)
		(drill 0.254)
		(layers "F.Cu" "B.Cu")
		(net "P3V3_AUX")
	)
	(via
		(at 143.076168 -40.971724)
		(size 0.508)
		(drill 0.254)
		(layers "F.Cu" "B.Cu")
		(net "P3V3_AUX")
	)
	(via
		(at 397.224758 -87.214202)
		(size 0.508)
		(drill 0.254)
		(layers "F.Cu" "B.Cu")
		(net "P3V3_AUX")
	)
	(via
		(at 350.905826 -55.39359)
		(size 0.508)
		(drill 0.254)
		(layers "F.Cu" "B.Cu")
		(net "P3V3_AUX")
	)
	(via
		(at 82.971132 -56.38038)
		(size 0.508)
		(drill 0.254)
		(layers "F.Cu" "B.Cu")
		(net "P3V3_AUX")
	)
	(via
		(at 103.1748 -188.2902)
		(size 0.508)
		(drill 0.254)
		(layers "F.Cu" "B.Cu")
		(net "P3V3_AUX")
	)
	(via
		(at 360.86796 -257.115564)
		(size 0.508)
		(drill 0.254)
		(layers "F.Cu" "B.Cu")
		(net "P3V3_AUX")
	)
	(via
		(at 365.732314 -221.950534)
		(size 0.508)
		(drill 0.254)
		(layers "F.Cu" "B.Cu")
		(net "P3V3_AUX")
	)
	(via
		(at 210.545172 -122.06732)
		(size 0.508)
		(drill 0.254)
		(layers "F.Cu" "B.Cu")
		(net "P3V3_AUX")
	)
	(via
		(at 197.537832 -140.534898)
		(size 0.508)
		(drill 0.254)
		(layers "F.Cu" "B.Cu")
		(net "P3V3_AUX")
	)
	(via
		(at 352.582226 -54.96179)
		(size 0.508)
		(drill 0.254)
		(layers "F.Cu" "B.Cu")
		(net "P3V3_AUX")
	)
	(via
		(at 377.616974 -55.39359)
		(size 0.508)
		(drill 0.254)
		(layers "F.Cu" "B.Cu")
		(net "P3V3_AUX")
	)
	(via
		(at 120.119902 -94.891606)
		(size 0.508)
		(drill 0.254)
		(layers "F.Cu" "B.Cu")
		(net "P3V3_AUX")
	)
	(via
		(at 285.523178 -52.035456)
		(size 0.508)
		(drill 0.254)
		(layers "F.Cu" "B.Cu")
		(net "P3V3_AUX")
	)
	(via
		(at 426.018452 -22.555454)
		(size 0.508)
		(drill 0.254)
		(layers "F.Cu" "B.Cu")
		(net "P3V3_AUX")
	)
	(via
		(at 378.582174 -54.96179)
		(size 0.508)
		(drill 0.254)
		(layers "F.Cu" "B.Cu")
		(net "P3V3_AUX")
	)
	(via
		(at 115.13058 -254.955802)
		(size 0.508)
		(drill 0.254)
		(layers "F.Cu" "B.Cu")
		(net "P3V3_AUX")
	)
	(via
		(at 252.326902 -337.070192)
		(size 0.508)
		(drill 0.254)
		(layers "F.Cu" "B.Cu")
		(net "P3V3_AUX")
	)
	(via
		(at 383.673858 -211.709)
		(size 0.508)
		(drill 0.254)
		(layers "F.Cu" "B.Cu")
		(net "P3V3_AUX")
	)
	(via
		(at 259.470398 -30.376876)
		(size 0.508)
		(drill 0.254)
		(layers "F.Cu" "B.Cu")
		(net "P3V3_AUX")
	)
	(via
		(at 335.026 -153.67)
		(size 0.508)
		(drill 0.254)
		(layers "F.Cu" "B.Cu")
		(net "P3V3_AUX")
	)
	(via
		(at 444.015368 -123.33732)
		(size 0.508)
		(drill 0.254)
		(layers "F.Cu" "B.Cu")
		(net "P3V3_AUX")
	)
	(via
		(at 253.038102 -337.070192)
		(size 0.508)
		(drill 0.254)
		(layers "F.Cu" "B.Cu")
		(net "P3V3_AUX")
	)
	(via
		(at 443.380368 -123.33732)
		(size 0.508)
		(drill 0.254)
		(layers "F.Cu" "B.Cu")
		(net "P3V3_AUX")
	)
	(via
		(at 120.119902 -97.177606)
		(size 0.508)
		(drill 0.254)
		(layers "F.Cu" "B.Cu")
		(net "P3V3_AUX")
	)
	(via
		(at 315.849762 -26.03373)
		(size 0.508)
		(drill 0.254)
		(layers "F.Cu" "B.Cu")
		(net "P3V3_AUX")
	)
	(via
		(at 252.439678 -153.782522)
		(size 0.508)
		(drill 0.254)
		(layers "F.Cu" "B.Cu")
		(net "P3V3_AUX")
	)
	(via
		(at 183.175402 -187.701174)
		(size 0.508)
		(drill 0.254)
		(layers "F.Cu" "B.Cu")
		(net "P3V3_AUX")
	)
	(via
		(at 173.088046 -57.48528)
		(size 0.508)
		(drill 0.254)
		(layers "F.Cu" "B.Cu")
		(net "P3V3_AUX")
	)
	(via
		(at 358.14 -184.15)
		(size 0.508)
		(drill 0.254)
		(layers "F.Cu" "B.Cu")
		(net "P3V3_AUX")
	)
	(via
		(at 211.89061 -122.971052)
		(size 0.508)
		(drill 0.254)
		(layers "F.Cu" "B.Cu")
		(net "P3V3_AUX")
	)
	(via
		(at 335.026 -164.973)
		(size 0.508)
		(drill 0.254)
		(layers "F.Cu" "B.Cu")
		(net "P3V3_AUX")
	)
	(via
		(at 277.299166 -35.876738)
		(size 0.508)
		(drill 0.254)
		(layers "F.Cu" "B.Cu")
		(net "P3V3_AUX")
	)
	(via
		(at 114.910616 -140.96746)
		(size 0.508)
		(drill 0.254)
		(layers "F.Cu" "B.Cu")
		(net "P3V3_AUX")
	)
	(via
		(at 229.554786 -241.644932)
		(size 0.508)
		(drill 0.254)
		(layers "F.Cu" "B.Cu")
		(net "P3V3_AUX")
	)
	(via
		(at 82.987896 -57.48528)
		(size 0.508)
		(drill 0.254)
		(layers "F.Cu" "B.Cu")
		(net "P3V3_AUX")
	)
	(via
		(at 110.152942 -117.248178)
		(size 0.508)
		(drill 0.254)
		(layers "F.Cu" "B.Cu")
		(net "P3V3_AUX")
	)
	(via
		(at 232.428288 -98.295968)
		(size 0.508)
		(drill 0.254)
		(layers "F.Cu" "B.Cu")
		(net "P3V3_AUX")
	)
	(via
		(at 195.37045 -30.376876)
		(size 0.508)
		(drill 0.254)
		(layers "F.Cu" "B.Cu")
		(net "P3V3_AUX")
	)
	(via
		(at 270.478504 -115.235228)
		(size 0.508)
		(drill 0.254)
		(layers "F.Cu" "B.Cu")
		(net "P3V3_AUX")
	)
	(via
		(at 106.46156 -138.37666)
		(size 0.508)
		(drill 0.254)
		(layers "F.Cu" "B.Cu")
		(net "P3V3_AUX")
	)
	(via
		(at 225.530664 -203.40701)
		(size 0.508)
		(drill 0.254)
		(layers "F.Cu" "B.Cu")
		(net "P3V3_AUX")
	)
	(via
		(at 234.974892 -51.627024)
		(size 0.508)
		(drill 0.254)
		(layers "F.Cu" "B.Cu")
		(net "P3V3_AUX")
	)
	(via
		(at 361.314746 -123.225052)
		(size 0.508)
		(drill 0.254)
		(layers "F.Cu" "B.Cu")
		(net "P3V3_AUX")
	)
	(via
		(at 405.271224 -55.74538)
		(size 0.508)
		(drill 0.254)
		(layers "F.Cu" "B.Cu")
		(net "P3V3_AUX")
	)
	(via
		(at 275.710396 -413.773112)
		(size 0.508)
		(drill 0.254)
		(layers "F.Cu" "B.Cu")
		(net "P3V3_AUX")
	)
	(via
		(at 413.673544 -107.210352)
		(size 0.508)
		(drill 0.254)
		(layers "F.Cu" "B.Cu")
		(net "P3V3_AUX")
	)
	(via
		(at 225.467926 -221.103952)
		(size 0.4572)
		(drill 0.254)
		(layers "F.Cu" "B.Cu")
		(net "P3V3_AUX")
	)
	(via
		(at 203.478638 -82.767932)
		(size 0.508)
		(drill 0.254)
		(layers "F.Cu" "B.Cu")
		(net "P3V3_AUX")
	)
	(via
		(at 232.915968 -273.471386)
		(size 0.508)
		(drill 0.254)
		(layers "F.Cu" "B.Cu")
		(net "P3V3_AUX")
	)
	(via
		(at 195.423282 -52.035456)
		(size 0.508)
		(drill 0.254)
		(layers "F.Cu" "B.Cu")
		(net "P3V3_AUX")
	)
	(via
		(at 222.62465 -210.914488)
		(size 0.508)
		(drill 0.254)
		(layers "F.Cu" "B.Cu")
		(net "P3V3_AUX")
	)
	(via
		(at 259.932932 -346.435934)
		(size 0.508)
		(drill 0.254)
		(layers "F.Cu" "B.Cu")
		(net "P3V3_AUX")
	)
	(via
		(at 376.905774 -55.39359)
		(size 0.508)
		(drill 0.254)
		(layers "F.Cu" "B.Cu")
		(net "P3V3_AUX")
	)
	(via
		(at 338.328 -246.253)
		(size 0.508)
		(drill 0.254)
		(layers "F.Cu" "B.Cu")
		(net "P3V3_AUX")
	)
	(via
		(at 223.813878 -190.283592)
		(size 0.508)
		(drill 0.254)
		(layers "F.Cu" "B.Cu")
		(net "P3V3_AUX")
	)
	(via
		(at 93.621098 -101.870764)
		(size 0.508)
		(drill 0.254)
		(layers "F.Cu" "B.Cu")
		(net "P3V3_AUX")
	)
	(via
		(at 6.68655 -66.567812)
		(size 0.508)
		(drill 0.254)
		(layers "F.Cu" "B.Cu")
		(net "P3V3_AUX")
	)
	(via
		(at 431.287936 -57.48528)
		(size 0.508)
		(drill 0.254)
		(layers "F.Cu" "B.Cu")
		(net "P3V3_AUX")
	)
	(via
		(at 449.179188 -416.636962)
		(size 0.508)
		(drill 0.254)
		(layers "F.Cu" "B.Cu")
		(net "P3V3_AUX")
	)
	(via
		(at 418.371782 -117.723666)
		(size 0.508)
		(drill 0.254)
		(layers "F.Cu" "B.Cu")
		(net "P3V3_AUX")
	)
	(via
		(at 359.088182 -231.428798)
		(size 0.508)
		(drill 0.254)
		(layers "F.Cu" "B.Cu")
		(net "P3V3_AUX")
	)
	(via
		(at 196.554852 -23.970996)
		(size 0.508)
		(drill 0.254)
		(layers "F.Cu" "B.Cu")
		(net "P3V3_AUX")
	)
	(via
		(at 460.455772 -329.169776)
		(size 0.508)
		(drill 0.254)
		(layers "F.Cu" "B.Cu")
		(net "P3V3_AUX")
	)
	(via
		(at 3.316986 -55.39359)
		(size 0.508)
		(drill 0.254)
		(layers "F.Cu" "B.Cu")
		(net "P3V3_AUX")
	)
	(via
		(at 237.340394 -51.343814)
		(size 0.508)
		(drill 0.254)
		(layers "F.Cu" "B.Cu")
		(net "P3V3_AUX")
	)
	(via
		(at 312.802524 -89.78138)
		(size 0.508)
		(drill 0.254)
		(layers "F.Cu" "B.Cu")
		(net "P3V3_AUX")
	)
	(via
		(at 247.085104 -278.551386)
		(size 0.508)
		(drill 0.254)
		(layers "F.Cu" "B.Cu")
		(net "P3V3_AUX")
	)
	(via
		(at 387.925818 -236.892338)
		(size 0.508)
		(drill 0.254)
		(layers "F.Cu" "B.Cu")
		(net "P3V3_AUX")
	)
	(via
		(at 73.550272 -48.753014)
		(size 0.508)
		(drill 0.254)
		(layers "F.Cu" "B.Cu")
		(net "P3V3_AUX")
	)
	(via
		(at 430.58207 -54.96179)
		(size 0.508)
		(drill 0.254)
		(layers "F.Cu" "B.Cu")
		(net "P3V3_AUX")
	)
	(via
		(at 397.224758 -82.642202)
		(size 0.508)
		(drill 0.254)
		(layers "F.Cu" "B.Cu")
		(net "P3V3_AUX")
	)
	(via
		(at 101.605842 -202.385168)
		(size 0.508)
		(drill 0.254)
		(layers "F.Cu" "B.Cu")
		(net "P3V3_AUX")
	)
	(via
		(at 228.104192 -68.424298)
		(size 0.508)
		(drill 0.254)
		(layers "F.Cu" "B.Cu")
		(net "P3V3_AUX")
	)
	(via
		(at 209.101436 -221.19082)
		(size 0.508)
		(drill 0.254)
		(layers "F.Cu" "B.Cu")
		(net "P3V3_AUX")
	)
	(via
		(at 362.458 -210.947)
		(size 0.508)
		(drill 0.254)
		(layers "F.Cu" "B.Cu")
		(net "P3V3_AUX")
	)
	(via
		(at 84.04987 -7.062724)
		(size 0.508)
		(drill 0.254)
		(layers "F.Cu" "B.Cu")
		(net "P3V3_AUX")
	)
	(via
		(at 197.66407 -158.219648)
		(size 0.508)
		(drill 0.254)
		(layers "F.Cu" "B.Cu")
		(net "P3V3_AUX")
	)
	(via
		(at 438.760616 -113.591086)
		(size 0.508)
		(drill 0.254)
		(layers "F.Cu" "B.Cu")
		(net "P3V3_AUX")
	)
	(via
		(at 335.026 -161.798)
		(size 0.508)
		(drill 0.254)
		(layers "F.Cu" "B.Cu")
		(net "P3V3_AUX")
	)
	(via
		(at 351.436432 -145.269458)
		(size 0.508)
		(drill 0.254)
		(layers "F.Cu" "B.Cu")
		(net "P3V3_AUX")
	)
	(via
		(at 207.98536 -112.799114)
		(size 0.508)
		(drill 0.254)
		(layers "F.Cu" "B.Cu")
		(net "P3V3_AUX")
	)
	(via
		(at 332.994 -244.221)
		(size 0.508)
		(drill 0.254)
		(layers "F.Cu" "B.Cu")
		(net "P3V3_AUX")
	)
	(via
		(at 280.475182 -403.347682)
		(size 0.508)
		(drill 0.254)
		(layers "F.Cu" "B.Cu")
		(net "P3V3_AUX")
	)
	(via
		(at 120.042432 -89.53373)
		(size 0.508)
		(drill 0.254)
		(layers "F.Cu" "B.Cu")
		(net "P3V3_AUX")
	)
	(via
		(at 121.071386 -55.11038)
		(size 0.508)
		(drill 0.254)
		(layers "F.Cu" "B.Cu")
		(net "P3V3_AUX")
	)
	(via
		(at 76.693522 -83.532218)
		(size 0.508)
		(drill 0.254)
		(layers "F.Cu" "B.Cu")
		(net "P3V3_AUX")
	)
	(via
		(at 370.60124 -86.070694)
		(size 0.508)
		(drill 0.254)
		(layers "F.Cu" "B.Cu")
		(net "P3V3_AUX")
	)
	(via
		(at 201.925682 -338.13242)
		(size 0.508)
		(drill 0.254)
		(layers "F.Cu" "B.Cu")
		(net "P3V3_AUX")
	)
	(via
		(at 71.62292 -242.297204)
		(size 0.508)
		(drill 0.254)
		(layers "F.Cu" "B.Cu")
		(net "P3V3_AUX")
	)
	(via
		(at 92.899992 -288.11855)
		(size 0.508)
		(drill 0.254)
		(layers "F.Cu" "B.Cu")
		(net "P3V3_AUX")
	)
	(via
		(at 362.458 -198.585836)
		(size 0.508)
		(drill 0.254)
		(layers "F.Cu" "B.Cu")
		(net "P3V3_AUX")
	)
	(via
		(at 335.026 -173.101)
		(size 0.508)
		(drill 0.254)
		(layers "F.Cu" "B.Cu")
		(net "P3V3_AUX")
	)
	(via
		(at 199.07123 -55.11038)
		(size 0.508)
		(drill 0.254)
		(layers "F.Cu" "B.Cu")
		(net "P3V3_AUX")
	)
	(via
		(at 379.271276 -55.11038)
		(size 0.508)
		(drill 0.254)
		(layers "F.Cu" "B.Cu")
		(net "P3V3_AUX")
	)
	(via
		(at 199.087994 -57.48528)
		(size 0.508)
		(drill 0.254)
		(layers "F.Cu" "B.Cu")
		(net "P3V3_AUX")
	)
	(via
		(at 461.166972 -329.880976)
		(size 0.508)
		(drill 0.254)
		(layers "F.Cu" "B.Cu")
		(net "P3V3_AUX")
	)
	(via
		(at 323.323458 -114.323114)
		(size 0.508)
		(drill 0.254)
		(layers "F.Cu" "B.Cu")
		(net "P3V3_AUX")
	)
	(via
		(at 107.308142 -5.747258)
		(size 0.508)
		(drill 0.254)
		(layers "F.Cu" "B.Cu")
		(net "P3V3_AUX")
	)
	(via
		(at 225.467926 -216.304368)
		(size 0.4572)
		(drill 0.254)
		(layers "F.Cu" "B.Cu")
		(net "P3V3_AUX")
	)
	(via
		(at 114.910616 -140.30706)
		(size 0.508)
		(drill 0.254)
		(layers "F.Cu" "B.Cu")
		(net "P3V3_AUX")
	)
	(via
		(at 207.308958 -112.126268)
		(size 0.508)
		(drill 0.254)
		(layers "F.Cu" "B.Cu")
		(net "P3V3_AUX")
	)
	(via
		(at 246.484648 -123.225052)
		(size 0.508)
		(drill 0.254)
		(layers "F.Cu" "B.Cu")
		(net "P3V3_AUX")
	)
	(via
		(at 319.278 -84.709)
		(size 0.508)
		(drill 0.254)
		(layers "F.Cu" "B.Cu")
		(net "P3V3_AUX")
	)
	(via
		(at 193.81851 -22.555454)
		(size 0.508)
		(drill 0.254)
		(layers "F.Cu" "B.Cu")
		(net "P3V3_AUX")
	)
	(via
		(at 385.907534 -97.1804)
		(size 0.508)
		(drill 0.254)
		(layers "F.Cu" "B.Cu")
		(net "P3V3_AUX")
	)
	(via
		(at 231.916478 -79.005684)
		(size 0.508)
		(drill 0.254)
		(layers "F.Cu" "B.Cu")
		(net "P3V3_AUX")
	)
	(via
		(at 363.314996 -379.088396)
		(size 0.508)
		(drill 0.254)
		(layers "F.Cu" "B.Cu")
		(net "P3V3_AUX")
	)
	(via
		(at 100.91801 -119.77624)
		(size 0.508)
		(drill 0.254)
		(layers "F.Cu" "B.Cu")
		(net "P3V3_AUX")
	)
	(via
		(at 121.68251 -36.286948)
		(size 0.508)
		(drill 0.254)
		(layers "F.Cu" "B.Cu")
		(net "P3V3_AUX")
	)
	(via
		(at 237.561374 -172.96003)
		(size 0.508)
		(drill 0.254)
		(layers "F.Cu" "B.Cu")
		(net "P3V3_AUX")
	)
	(via
		(at 303.873408 -241.562382)
		(size 0.508)
		(drill 0.254)
		(layers "F.Cu" "B.Cu")
		(net "P3V3_AUX")
	)
	(via
		(at 92.071444 -97.821242)
		(size 0.508)
		(drill 0.254)
		(layers "F.Cu" "B.Cu")
		(net "P3V3_AUX")
	)
	(via
		(at 20.239736 -153.782522)
		(size 0.508)
		(drill 0.254)
		(layers "F.Cu" "B.Cu")
		(net "P3V3_AUX")
	)
	(via
		(at 103.30815 -47.403766)
		(size 0.508)
		(drill 0.254)
		(layers "F.Cu" "B.Cu")
		(net "P3V3_AUX")
	)
	(via
		(at 199.07123 -55.74538)
		(size 0.508)
		(drill 0.254)
		(layers "F.Cu" "B.Cu")
		(net "P3V3_AUX")
	)
	(via
		(at 254.685546 -208.14665)
		(size 0.508)
		(drill 0.254)
		(layers "F.Cu" "B.Cu")
		(net "P3V3_AUX")
	)
	(via
		(at 333.117952 -119.77624)
		(size 0.508)
		(drill 0.254)
		(layers "F.Cu" "B.Cu")
		(net "P3V3_AUX")
	)
	(via
		(at 245.95836 -116.799106)
		(size 0.508)
		(drill 0.254)
		(layers "F.Cu" "B.Cu")
		(net "P3V3_AUX")
	)
	(via
		(at 112.472216 -138.93546)
		(size 0.508)
		(drill 0.254)
		(layers "F.Cu" "B.Cu")
		(net "P3V3_AUX")
	)
	(via
		(at 217.583512 -233.182668)
		(size 0.508)
		(drill 0.254)
		(layers "F.Cu" "B.Cu")
		(net "P3V3_AUX")
	)
	(via
		(at 231.412288 -98.295968)
		(size 0.508)
		(drill 0.254)
		(layers "F.Cu" "B.Cu")
		(net "P3V3_AUX")
	)
	(via
		(at 135.199374 -35.876738)
		(size 0.508)
		(drill 0.254)
		(layers "F.Cu" "B.Cu")
		(net "P3V3_AUX")
	)
	(via
		(at 188.226954 -80.362806)
		(size 0.508)
		(drill 0.254)
		(layers "F.Cu" "B.Cu")
		(net "P3V3_AUX")
	)
	(via
		(at 118.833392 -117.999764)
		(size 0.508)
		(drill 0.254)
		(layers "F.Cu" "B.Cu")
		(net "P3V3_AUX")
	)
	(via
		(at 246.59336 -117.434106)
		(size 0.508)
		(drill 0.254)
		(layers "F.Cu" "B.Cu")
		(net "P3V3_AUX")
	)
	(via
		(at 13.758418 -117.434106)
		(size 0.508)
		(drill 0.254)
		(layers "F.Cu" "B.Cu")
		(net "P3V3_AUX")
	)
	(via
		(at 97.032318 -396.1638)
		(size 0.508)
		(drill 0.254)
		(layers "F.Cu" "B.Cu")
		(net "P3V3_AUX")
	)
	(via
		(at 341.571072 -196.51345)
		(size 0.508)
		(drill 0.254)
		(layers "F.Cu" "B.Cu")
		(net "P3V3_AUX")
	)
	(via
		(at 144.159986 -203.964032)
		(size 0.508)
		(drill 0.254)
		(layers "F.Cu" "B.Cu")
		(net "P3V3_AUX")
	)
	(via
		(at 402.905722 -55.39359)
		(size 0.508)
		(drill 0.254)
		(layers "F.Cu" "B.Cu")
		(net "P3V3_AUX")
	)
	(via
		(at 429.23968 -136.98601)
		(size 0.508)
		(drill 0.254)
		(layers "F.Cu" "B.Cu")
		(net "P3V3_AUX")
	)
	(via
		(at 380.649734 -4.836922)
		(size 0.508)
		(drill 0.254)
		(layers "F.Cu" "B.Cu")
		(net "P3V3_AUX")
	)
	(via
		(at 329.692 -232.918)
		(size 0.508)
		(drill 0.254)
		(layers "F.Cu" "B.Cu")
		(net "P3V3_AUX")
	)
	(via
		(at 13.296646 -212.780372)
		(size 0.508)
		(drill 0.254)
		(layers "F.Cu" "B.Cu")
		(net "P3V3_AUX")
	)
	(via
		(at 202.473814 -88.993472)
		(size 0.508)
		(drill 0.254)
		(layers "F.Cu" "B.Cu")
		(net "P3V3_AUX")
	)
	(via
		(at 411.885384 -115.922044)
		(size 0.508)
		(drill 0.254)
		(layers "F.Cu" "B.Cu")
		(net "P3V3_AUX")
	)
	(via
		(at 100.955094 -398.66824)
		(size 0.508)
		(drill 0.254)
		(layers "F.Cu" "B.Cu")
		(net "P3V3_AUX")
	)
	(via
		(at 32.686498 -61.487812)
		(size 0.508)
		(drill 0.254)
		(layers "F.Cu" "B.Cu")
		(net "P3V3_AUX")
	)
	(via
		(at 379.949964 -26.03373)
		(size 0.508)
		(drill 0.254)
		(layers "F.Cu" "B.Cu")
		(net "P3V3_AUX")
	)
	(via
		(at 375.6152 -44.87291)
		(size 0.508)
		(drill 0.254)
		(layers "F.Cu" "B.Cu")
		(net "P3V3_AUX")
	)
	(via
		(at 341.571072 -191.43345)
		(size 0.508)
		(drill 0.254)
		(layers "F.Cu" "B.Cu")
		(net "P3V3_AUX")
	)
	(via
		(at 387.498082 -245.999)
		(size 0.508)
		(drill 0.254)
		(layers "F.Cu" "B.Cu")
		(net "P3V3_AUX")
	)
	(via
		(at 225.032062 -81.627472)
		(size 0.508)
		(drill 0.254)
		(layers "F.Cu" "B.Cu")
		(net "P3V3_AUX")
	)
	(via
		(at 362.584746 -123.225052)
		(size 0.508)
		(drill 0.254)
		(layers "F.Cu" "B.Cu")
		(net "P3V3_AUX")
	)
	(via
		(at 143.028162 -241.758978)
		(size 0.508)
		(drill 0.254)
		(layers "F.Cu" "B.Cu")
		(net "P3V3_AUX")
	)
	(via
		(at 103.378 -199.3138)
		(size 0.508)
		(drill 0.254)
		(layers "F.Cu" "B.Cu")
		(net "P3V3_AUX")
	)
	(via
		(at 56.896 -138.95705)
		(size 0.508)
		(drill 0.254)
		(layers "F.Cu" "B.Cu")
		(net "P3V3_AUX")
	)
	(via
		(at 236.651292 -51.195224)
		(size 0.508)
		(drill 0.254)
		(layers "F.Cu" "B.Cu")
		(net "P3V3_AUX")
	)
	(via
		(at 245.214648 -123.225052)
		(size 0.508)
		(drill 0.254)
		(layers "F.Cu" "B.Cu")
		(net "P3V3_AUX")
	)
	(via
		(at 204.711808 -76.62545)
		(size 0.508)
		(drill 0.254)
		(layers "F.Cu" "B.Cu")
		(net "P3V3_AUX")
	)
	(via
		(at 47.550324 -48.753014)
		(size 0.508)
		(drill 0.254)
		(layers "F.Cu" "B.Cu")
		(net "P3V3_AUX")
	)
	(via
		(at 123.132088 -159.844994)
		(size 0.508)
		(drill 0.254)
		(layers "F.Cu" "B.Cu")
		(net "P3V3_AUX")
	)
	(via
		(at 327.188576 -124.215144)
		(size 0.508)
		(drill 0.254)
		(layers "F.Cu" "B.Cu")
		(net "P3V3_AUX")
	)
	(via
		(at 13.014706 -123.225052)
		(size 0.508)
		(drill 0.254)
		(layers "F.Cu" "B.Cu")
		(net "P3V3_AUX")
	)
	(via
		(at 58.686446 -61.487812)
		(size 0.508)
		(drill 0.254)
		(layers "F.Cu" "B.Cu")
		(net "P3V3_AUX")
	)
	(via
		(at 405.287988 -57.48528)
		(size 0.508)
		(drill 0.254)
		(layers "F.Cu" "B.Cu")
		(net "P3V3_AUX")
	)
	(via
		(at 14.393418 -116.164106)
		(size 0.508)
		(drill 0.254)
		(layers "F.Cu" "B.Cu")
		(net "P3V3_AUX")
	)
	(via
		(at 112.545114 -262.703564)
		(size 0.508)
		(drill 0.254)
		(layers "F.Cu" "B.Cu")
		(net "P3V3_AUX")
	)
	(via
		(at 278.1935 -389.0264)
		(size 0.508)
		(drill 0.254)
		(layers "F.Cu" "B.Cu")
		(net "P3V3_AUX")
	)
	(via
		(at 406.484582 -365.888016)
		(size 0.508)
		(drill 0.254)
		(layers "F.Cu" "B.Cu")
		(net "P3V3_AUX")
	)
	(via
		(at 172.38218 -54.96179)
		(size 0.508)
		(drill 0.254)
		(layers "F.Cu" "B.Cu")
		(net "P3V3_AUX")
	)
	(via
		(at 56.971184 -55.74538)
		(size 0.508)
		(drill 0.254)
		(layers "F.Cu" "B.Cu")
		(net "P3V3_AUX")
	)
	(via
		(at 238.757968 -139.376404)
		(size 0.508)
		(drill 0.254)
		(layers "F.Cu" "B.Cu")
		(net "P3V3_AUX")
	)
	(via
		(at 106.51236 -139.69746)
		(size 0.508)
		(drill 0.254)
		(layers "F.Cu" "B.Cu")
		(net "P3V3_AUX")
	)
	(via
		(at 228.667818 -215.504268)
		(size 0.4572)
		(drill 0.254)
		(layers "F.Cu" "B.Cu")
		(net "P3V3_AUX")
	)
	(via
		(at 113.92535 -129.924048)
		(size 0.508)
		(drill 0.254)
		(layers "F.Cu" "B.Cu")
		(net "P3V3_AUX")
	)
	(via
		(at 380.177802 -197.358)
		(size 0.508)
		(drill 0.254)
		(layers "F.Cu" "B.Cu")
		(net "P3V3_AUX")
	)
	(via
		(at 360.013504 -230.593392)
		(size 0.508)
		(drill 0.254)
		(layers "F.Cu" "B.Cu")
		(net "P3V3_AUX")
	)
	(via
		(at 132.219446 -193.543428)
		(size 0.508)
		(drill 0.254)
		(layers "F.Cu" "B.Cu")
		(net "P3V3_AUX")
	)
	(via
		(at 161.199322 -35.876738)
		(size 0.508)
		(drill 0.254)
		(layers "F.Cu" "B.Cu")
		(net "P3V3_AUX")
	)
	(via
		(at 101.971094 -398.66824)
		(size 0.508)
		(drill 0.254)
		(layers "F.Cu" "B.Cu")
		(net "P3V3_AUX")
	)
	(via
		(at 30.971236 -56.38038)
		(size 0.508)
		(drill 0.254)
		(layers "F.Cu" "B.Cu")
		(net "P3V3_AUX")
	)
	(via
		(at 358.14 -180.086)
		(size 0.508)
		(drill 0.254)
		(layers "F.Cu" "B.Cu")
		(net "P3V3_AUX")
	)
	(via
		(at 404.198582 -381.50292)
		(size 0.508)
		(drill 0.254)
		(layers "F.Cu" "B.Cu")
		(net "P3V3_AUX")
	)
	(via
		(at 263.187942 -57.48528)
		(size 0.508)
		(drill 0.254)
		(layers "F.Cu" "B.Cu")
		(net "P3V3_AUX")
	)
	(via
		(at 255.198626 -241.000788)
		(size 0.508)
		(drill 0.254)
		(layers "F.Cu" "B.Cu")
		(net "P3V3_AUX")
	)
	(via
		(at 79.323184 -52.035456)
		(size 0.508)
		(drill 0.254)
		(layers "F.Cu" "B.Cu")
		(net "P3V3_AUX")
	)
	(via
		(at 316.886336 -61.487812)
		(size 0.508)
		(drill 0.254)
		(layers "F.Cu" "B.Cu")
		(net "P3V3_AUX")
	)
	(via
		(at 325.83882 -292.122098)
		(size 0.508)
		(drill 0.254)
		(layers "F.Cu" "B.Cu")
		(net "P3V3_AUX")
	)
	(via
		(at 375.570496 -29.614876)
		(size 0.508)
		(drill 0.254)
		(layers "F.Cu" "B.Cu")
		(net "P3V3_AUX")
	)
	(via
		(at 259.515102 -44.87291)
		(size 0.508)
		(drill 0.254)
		(layers "F.Cu" "B.Cu")
		(net "P3V3_AUX")
	)
	(via
		(at 53.270404 -29.614876)
		(size 0.508)
		(drill 0.254)
		(layers "F.Cu" "B.Cu")
		(net "P3V3_AUX")
	)
	(via
		(at 239.485932 -208.13522)
		(size 0.508)
		(drill 0.254)
		(layers "F.Cu" "B.Cu")
		(net "P3V3_AUX")
	)
	(via
		(at 399.99285 -84.721446)
		(size 0.508)
		(drill 0.254)
		(layers "F.Cu" "B.Cu")
		(net "P3V3_AUX")
	)
	(via
		(at 409.731718 -210.341718)
		(size 0.508)
		(drill 0.254)
		(layers "F.Cu" "B.Cu")
		(net "P3V3_AUX")
	)
	(via
		(at 431.271172 -55.74538)
		(size 0.508)
		(drill 0.254)
		(layers "F.Cu" "B.Cu")
		(net "P3V3_AUX")
	)
	(via
		(at 325.002906 -195.218304)
		(size 0.508)
		(drill 0.254)
		(layers "F.Cu" "B.Cu")
		(net "P3V3_AUX")
	)
	(via
		(at 225.041206 -79.595472)
		(size 0.508)
		(drill 0.254)
		(layers "F.Cu" "B.Cu")
		(net "P3V3_AUX")
	)
	(via
		(at 143.415258 -44.87291)
		(size 0.508)
		(drill 0.254)
		(layers "F.Cu" "B.Cu")
		(net "P3V3_AUX")
	)
	(via
		(at 27.31516 -42.84091)
		(size 0.508)
		(drill 0.254)
		(layers "F.Cu" "B.Cu")
		(net "P3V3_AUX")
	)
	(via
		(at 344.74531 -262.703564)
		(size 0.508)
		(drill 0.254)
		(layers "F.Cu" "B.Cu")
		(net "P3V3_AUX")
	)
	(via
		(at 451.638416 -373.453406)
		(size 0.508)
		(drill 0.254)
		(layers "F.Cu" "B.Cu")
		(net "P3V3_AUX")
	)
	(via
		(at 325.002906 -198.266304)
		(size 0.508)
		(drill 0.254)
		(layers "F.Cu" "B.Cu")
		(net "P3V3_AUX")
	)
	(via
		(at 326.413368 -208.153)
		(size 0.508)
		(drill 0.254)
		(layers "F.Cu" "B.Cu")
		(net "P3V3_AUX")
	)
	(via
		(at 93.638878 -292.122098)
		(size 0.508)
		(drill 0.254)
		(layers "F.Cu" "B.Cu")
		(net "P3V3_AUX")
	)
	(via
		(at 128.667764 -256.226564)
		(size 0.508)
		(drill 0.254)
		(layers "F.Cu" "B.Cu")
		(net "P3V3_AUX")
	)
	(via
		(at 302.271684 -117.723666)
		(size 0.508)
		(drill 0.254)
		(layers "F.Cu" "B.Cu")
		(net "P3V3_AUX")
	)
	(via
		(at 118.705884 -55.39359)
		(size 0.508)
		(drill 0.254)
		(layers "F.Cu" "B.Cu")
		(net "P3V3_AUX")
	)
	(via
		(at 283.223716 -168.397174)
		(size 0.508)
		(drill 0.254)
		(layers "F.Cu" "B.Cu")
		(net "P3V3_AUX")
	)
	(via
		(at 2.306828 -34.490406)
		(size 0.508)
		(drill 0.254)
		(layers "F.Cu" "B.Cu")
		(net "P3V3_AUX")
	)
	(via
		(at 12.312904 -45.926248)
		(size 0.508)
		(drill 0.254)
		(layers "F.Cu" "B.Cu")
		(net "P3V3_AUX")
	)
	(via
		(at 31.58236 -36.286948)
		(size 0.508)
		(drill 0.254)
		(layers "F.Cu" "B.Cu")
		(net "P3V3_AUX")
	)
	(via
		(at 357.643176 -396.063724)
		(size 0.508)
		(drill 0.254)
		(layers "F.Cu" "B.Cu")
		(net "P3V3_AUX")
	)
	(via
		(at 427.623224 -52.035456)
		(size 0.508)
		(drill 0.254)
		(layers "F.Cu" "B.Cu")
		(net "P3V3_AUX")
	)
	(via
		(at 444.8048 -236.4994)
		(size 0.508)
		(drill 0.254)
		(layers "F.Cu" "B.Cu")
		(net "P3V3_AUX")
	)
	(via
		(at 300.228 -237.871)
		(size 0.508)
		(drill 0.254)
		(layers "F.Cu" "B.Cu")
		(net "P3V3_AUX")
	)
	(via
		(at 79.315056 -42.84091)
		(size 0.508)
		(drill 0.254)
		(layers "F.Cu" "B.Cu")
		(net "P3V3_AUX")
	)
	(via
		(at 186.13755 -407.4414)
		(size 0.508)
		(drill 0.254)
		(layers "F.Cu" "B.Cu")
		(net "P3V3_AUX")
	)
	(via
		(at 197.702932 -413.364172)
		(size 0.508)
		(drill 0.254)
		(layers "F.Cu" "B.Cu")
		(net "P3V3_AUX")
	)
	(via
		(at 91.885516 -114.323114)
		(size 0.508)
		(drill 0.254)
		(layers "F.Cu" "B.Cu")
		(net "P3V3_AUX")
	)
	(via
		(at 443.180724 -119.380254)
		(size 0.508)
		(drill 0.254)
		(layers "F.Cu" "B.Cu")
		(net "P3V3_AUX")
	)
	(via
		(at 259.470398 -29.614876)
		(size 0.508)
		(drill 0.254)
		(layers "F.Cu" "B.Cu")
		(net "P3V3_AUX")
	)
	(via
		(at 428.90567 -55.39359)
		(size 0.508)
		(drill 0.254)
		(layers "F.Cu" "B.Cu")
		(net "P3V3_AUX")
	)
	(via
		(at 437.323484 -95.801942)
		(size 0.508)
		(drill 0.254)
		(layers "F.Cu" "B.Cu")
		(net "P3V3_AUX")
	)
	(via
		(at 293.281608 -200.928224)
		(size 0.508)
		(drill 0.254)
		(layers "F.Cu" "B.Cu")
		(net "P3V3_AUX")
	)
	(via
		(at 52.976018 -40.971724)
		(size 0.508)
		(drill 0.254)
		(layers "F.Cu" "B.Cu")
		(net "P3V3_AUX")
	)
	(via
		(at 308.807104 -84.092288)
		(size 0.508)
		(drill 0.254)
		(layers "F.Cu" "B.Cu")
		(net "P3V3_AUX")
	)
	(via
		(at 453.582532 -242.84813)
		(size 0.508)
		(drill 0.254)
		(layers "F.Cu" "B.Cu")
		(net "P3V3_AUX")
	)
	(via
		(at 337.523074 -52.035456)
		(size 0.508)
		(drill 0.254)
		(layers "F.Cu" "B.Cu")
		(net "P3V3_AUX")
	)
	(via
		(at 253.750318 -48.753014)
		(size 0.508)
		(drill 0.254)
		(layers "F.Cu" "B.Cu")
		(net "P3V3_AUX")
	)
	(via
		(at 342.352884 -117.248178)
		(size 0.508)
		(drill 0.254)
		(layers "F.Cu" "B.Cu")
		(net "P3V3_AUX")
	)
	(via
		(at 329.054714 -202.900534)
		(size 0.508)
		(drill 0.254)
		(layers "F.Cu" "B.Cu")
		(net "P3V3_AUX")
	)
	(via
		(at 351.38995 -185.01995)
		(size 0.508)
		(drill 0.254)
		(layers "F.Cu" "B.Cu")
		(net "P3V3_AUX")
	)
	(via
		(at 129.985262 -116.672106)
		(size 0.508)
		(drill 0.254)
		(layers "F.Cu" "B.Cu")
		(net "P3V3_AUX")
	)
	(via
		(at 302.749712 -250.777756)
		(size 0.508)
		(drill 0.254)
		(layers "F.Cu" "B.Cu")
		(net "P3V3_AUX")
	)
	(via
		(at 79.270352 -30.376876)
		(size 0.508)
		(drill 0.254)
		(layers "F.Cu" "B.Cu")
		(net "P3V3_AUX")
	)
	(via
		(at 94.034356 -244.808248)
		(size 0.508)
		(drill 0.254)
		(layers "F.Cu" "B.Cu")
		(net "P3V3_AUX")
	)
	(via
		(at 243.035582 -280.10104)
		(size 0.508)
		(drill 0.254)
		(layers "F.Cu" "B.Cu")
		(net "P3V3_AUX")
	)
	(via
		(at 263.969754 -206.33436)
		(size 0.508)
		(drill 0.254)
		(layers "F.Cu" "B.Cu")
		(net "P3V3_AUX")
	)
	(via
		(at 29.316934 -55.39359)
		(size 0.508)
		(drill 0.254)
		(layers "F.Cu" "B.Cu")
		(net "P3V3_AUX")
	)
	(via
		(at 173.071282 -55.74538)
		(size 0.508)
		(drill 0.254)
		(layers "F.Cu" "B.Cu")
		(net "P3V3_AUX")
	)
	(via
		(at 201.719942 -114.42954)
		(size 0.508)
		(drill 0.254)
		(layers "F.Cu" "B.Cu")
		(net "P3V3_AUX")
	)
	(via
		(at 452.0184 -22.555454)
		(size 0.508)
		(drill 0.254)
		(layers "F.Cu" "B.Cu")
		(net "P3V3_AUX")
	)
	(via
		(at 128.667764 -257.115564)
		(size 0.508)
		(drill 0.254)
		(layers "F.Cu" "B.Cu")
		(net "P3V3_AUX")
	)
	(via
		(at 226.785424 -280.10104)
		(size 0.508)
		(drill 0.254)
		(layers "F.Cu" "B.Cu")
		(net "P3V3_AUX")
	)
	(via
		(at 408.559 -384.81)
		(size 0.508)
		(drill 0.254)
		(layers "F.Cu" "B.Cu")
		(net "P3V3_AUX")
	)
	(via
		(at 219.520262 -233.182668)
		(size 0.508)
		(drill 0.254)
		(layers "F.Cu" "B.Cu")
		(net "P3V3_AUX")
	)
	(via
		(at 324.050152 -285.518352)
		(size 0.508)
		(drill 0.254)
		(layers "F.Cu" "B.Cu")
		(net "P3V3_AUX")
	)
	(via
		(at 421.850312 -48.753014)
		(size 0.508)
		(drill 0.254)
		(layers "F.Cu" "B.Cu")
		(net "P3V3_AUX")
	)
	(via
		(at 400.098768 -179.728368)
		(size 0.508)
		(drill 0.254)
		(layers "F.Cu" "B.Cu")
		(net "P3V3_AUX")
	)
	(via
		(at 79.313024 -9.535922)
		(size 0.508)
		(drill 0.254)
		(layers "F.Cu" "B.Cu")
		(net "P3V3_AUX")
	)
	(via
		(at 117.380004 -116.95049)
		(size 0.508)
		(drill 0.254)
		(layers "F.Cu" "B.Cu")
		(net "P3V3_AUX")
	)
	(via
		(at 147.071334 -56.38038)
		(size 0.508)
		(drill 0.254)
		(layers "F.Cu" "B.Cu")
		(net "P3V3_AUX")
	)
	(via
		(at 53.315108 -42.84091)
		(size 0.508)
		(drill 0.254)
		(layers "F.Cu" "B.Cu")
		(net "P3V3_AUX")
	)
	(via
		(at 447.147188 -416.636962)
		(size 0.508)
		(drill 0.254)
		(layers "F.Cu" "B.Cu")
		(net "P3V3_AUX")
	)
	(via
		(at 115.572286 -140.287248)
		(size 0.508)
		(drill 0.254)
		(layers "F.Cu" "B.Cu")
		(net "P3V3_AUX")
	)
	(via
		(at 283.99867 -179.728368)
		(size 0.508)
		(drill 0.254)
		(layers "F.Cu" "B.Cu")
		(net "P3V3_AUX")
	)
	(via
		(at 427.615096 -42.84091)
		(size 0.508)
		(drill 0.254)
		(layers "F.Cu" "B.Cu")
		(net "P3V3_AUX")
	)
	(via
		(at 428.902622 -89.78138)
		(size 0.508)
		(drill 0.254)
		(layers "F.Cu" "B.Cu")
		(net "P3V3_AUX")
	)
	(via
		(at 71.099172 -35.876738)
		(size 0.508)
		(drill 0.254)
		(layers "F.Cu" "B.Cu")
		(net "P3V3_AUX")
	)
	(via
		(at 323.442838 -113.558574)
		(size 0.508)
		(drill 0.254)
		(layers "F.Cu" "B.Cu")
		(net "P3V3_AUX")
	)
	(via
		(at 401.276058 -40.971724)
		(size 0.508)
		(drill 0.254)
		(layers "F.Cu" "B.Cu")
		(net "P3V3_AUX")
	)
	(via
		(at 138.90117 -210.807046)
		(size 0.508)
		(drill 0.254)
		(layers "F.Cu" "B.Cu")
		(net "P3V3_AUX")
	)
	(via
		(at 311.470294 -29.614876)
		(size 0.508)
		(drill 0.254)
		(layers "F.Cu" "B.Cu")
		(net "P3V3_AUX")
	)
	(via
		(at 375.297446 -86.5378)
		(size 0.508)
		(drill 0.254)
		(layers "F.Cu" "B.Cu")
		(net "P3V3_AUX")
	)
	(via
		(at 131.71551 -206.241142)
		(size 0.508)
		(drill 0.254)
		(layers "F.Cu" "B.Cu")
		(net "P3V3_AUX")
	)
	(via
		(at 109.571536 -138.93546)
		(size 0.508)
		(drill 0.254)
		(layers "F.Cu" "B.Cu")
		(net "P3V3_AUX")
	)
	(via
		(at 221.647512 -233.182668)
		(size 0.508)
		(drill 0.254)
		(layers "F.Cu" "B.Cu")
		(net "P3V3_AUX")
	)
	(via
		(at 27.31516 -44.87291)
		(size 0.508)
		(drill 0.254)
		(layers "F.Cu" "B.Cu")
		(net "P3V3_AUX")
	)
	(via
		(at 305.750214 -48.753014)
		(size 0.508)
		(drill 0.254)
		(layers "F.Cu" "B.Cu")
		(net "P3V3_AUX")
	)
	(via
		(at 335.026 -177.927)
		(size 0.508)
		(drill 0.254)
		(layers "F.Cu" "B.Cu")
		(net "P3V3_AUX")
	)
	(via
		(at 26.97607 -40.971724)
		(size 0.508)
		(drill 0.254)
		(layers "F.Cu" "B.Cu")
		(net "P3V3_AUX")
	)
	(via
		(at 413.518858 -203.562458)
		(size 0.508)
		(drill 0.254)
		(layers "F.Cu" "B.Cu")
		(net "P3V3_AUX")
	)
	(via
		(at 95.556578 -125.891544)
		(size 0.508)
		(drill 0.254)
		(layers "F.Cu" "B.Cu")
		(net "P3V3_AUX")
	)
	(via
		(at 72.88276 -80.019906)
		(size 0.508)
		(drill 0.254)
		(layers "F.Cu" "B.Cu")
		(net "P3V3_AUX")
	)
	(via
		(at 353.950016 -26.03373)
		(size 0.508)
		(drill 0.254)
		(layers "F.Cu" "B.Cu")
		(net "P3V3_AUX")
	)
	(via
		(at 320.176906 -288.221166)
		(size 0.508)
		(drill 0.254)
		(layers "F.Cu" "B.Cu")
		(net "P3V3_AUX")
	)
	(via
		(at 259.515102 -42.84091)
		(size 0.508)
		(drill 0.254)
		(layers "F.Cu" "B.Cu")
		(net "P3V3_AUX")
	)
	(via
		(at 364.659672 -148.017738)
		(size 0.508)
		(drill 0.254)
		(layers "F.Cu" "B.Cu")
		(net "P3V3_AUX")
	)
	(via
		(at 453.623172 -52.035456)
		(size 0.508)
		(drill 0.254)
		(layers "F.Cu" "B.Cu")
		(net "P3V3_AUX")
	)
	(via
		(at 140.090144 -88.956642)
		(size 0.508)
		(drill 0.254)
		(layers "F.Cu" "B.Cu")
		(net "P3V3_AUX")
	)
	(via
		(at 337.058 -246.253)
		(size 0.508)
		(drill 0.254)
		(layers "F.Cu" "B.Cu")
		(net "P3V3_AUX")
	)
	(via
		(at 248.892314 -222.653606)
		(size 0.508)
		(drill 0.254)
		(layers "F.Cu" "B.Cu")
		(net "P3V3_AUX")
	)
	(via
		(at 399.608294 -47.403766)
		(size 0.508)
		(drill 0.254)
		(layers "F.Cu" "B.Cu")
		(net "P3V3_AUX")
	)
	(via
		(at 370.60124 -84.927694)
		(size 0.508)
		(drill 0.254)
		(layers "F.Cu" "B.Cu")
		(net "P3V3_AUX")
	)
	(via
		(at 135.636 -214.122)
		(size 0.508)
		(drill 0.254)
		(layers "F.Cu" "B.Cu")
		(net "P3V3_AUX")
	)
	(via
		(at 96.042226 -242.238784)
		(size 0.508)
		(drill 0.254)
		(layers "F.Cu" "B.Cu")
		(net "P3V3_AUX")
	)
	(via
		(at 439.522616 -113.591086)
		(size 0.508)
		(drill 0.254)
		(layers "F.Cu" "B.Cu")
		(net "P3V3_AUX")
	)
	(via
		(at 20.901914 -414.985454)
		(size 0.508)
		(drill 0.254)
		(layers "F.Cu" "B.Cu")
		(net "P3V3_AUX")
	)
	(via
		(at 140.090144 -94.671642)
		(size 0.508)
		(drill 0.254)
		(layers "F.Cu" "B.Cu")
		(net "P3V3_AUX")
	)
	(via
		(at 362.458 -213.995)
		(size 0.508)
		(drill 0.254)
		(layers "F.Cu" "B.Cu")
		(net "P3V3_AUX")
	)
	(via
		(at 449.220844 -118.76024)
		(size 0.508)
		(drill 0.254)
		(layers "F.Cu" "B.Cu")
		(net "P3V3_AUX")
	)
	(via
		(at 285.17596 -40.971724)
		(size 0.508)
		(drill 0.254)
		(layers "F.Cu" "B.Cu")
		(net "P3V3_AUX")
	)
	(via
		(at 209.733134 -213.313264)
		(size 0.508)
		(drill 0.254)
		(layers "F.Cu" "B.Cu")
		(net "P3V3_AUX")
	)
	(via
		(at 233.467402 -217.104468)
		(size 0.4572)
		(drill 0.254)
		(layers "F.Cu" "B.Cu")
		(net "P3V3_AUX")
	)
	(via
		(at 211.088478 -122.945144)
		(size 0.508)
		(drill 0.254)
		(layers "F.Cu" "B.Cu")
		(net "P3V3_AUX")
	)
	(via
		(at 452.871332 -242.84813)
		(size 0.508)
		(drill 0.254)
		(layers "F.Cu" "B.Cu")
		(net "P3V3_AUX")
	)
	(via
		(at 91.123516 -114.323114)
		(size 0.508)
		(drill 0.254)
		(layers "F.Cu" "B.Cu")
		(net "P3V3_AUX")
	)
	(via
		(at 143.423386 -52.035456)
		(size 0.508)
		(drill 0.254)
		(layers "F.Cu" "B.Cu")
		(net "P3V3_AUX")
	)
	(via
		(at 364.390432 -92.096336)
		(size 0.508)
		(drill 0.254)
		(layers "F.Cu" "B.Cu")
		(net "P3V3_AUX")
	)
	(via
		(at 82.28203 -54.96179)
		(size 0.508)
		(drill 0.254)
		(layers "F.Cu" "B.Cu")
		(net "P3V3_AUX")
	)
	(via
		(at 313.764168 -158.219648)
		(size 0.508)
		(drill 0.254)
		(layers "F.Cu" "B.Cu")
		(net "P3V3_AUX")
	)
	(via
		(at 130.38455 -123.225052)
		(size 0.508)
		(drill 0.254)
		(layers "F.Cu" "B.Cu")
		(net "P3V3_AUX")
	)
	(via
		(at 214.078058 -227.442522)
		(size 0.508)
		(drill 0.254)
		(layers "F.Cu" "B.Cu")
		(net "P3V3_AUX")
	)
	(via
		(at 353.288092 -57.48528)
		(size 0.508)
		(drill 0.254)
		(layers "F.Cu" "B.Cu")
		(net "P3V3_AUX")
	)
	(via
		(at 443.9666 -228.64064)
		(size 0.508)
		(drill 0.254)
		(layers "F.Cu" "B.Cu")
		(net "P3V3_AUX")
	)
	(via
		(at 263.782302 -36.286948)
		(size 0.508)
		(drill 0.254)
		(layers "F.Cu" "B.Cu")
		(net "P3V3_AUX")
	)
	(via
		(at 356.743 -183.388)
		(size 0.508)
		(drill 0.254)
		(layers "F.Cu" "B.Cu")
		(net "P3V3_AUX")
	)
	(via
		(at 209.72018 -245.026434)
		(size 0.508)
		(drill 0.254)
		(layers "F.Cu" "B.Cu")
		(net "P3V3_AUX")
	)
	(via
		(at 119.417084 -55.39359)
		(size 0.508)
		(drill 0.254)
		(layers "F.Cu" "B.Cu")
		(net "P3V3_AUX")
	)
	(via
		(at 17.856708 -271.184624)
		(size 0.508)
		(drill 0.254)
		(layers "F.Cu" "B.Cu")
		(net "P3V3_AUX")
	)
	(via
		(at 239.439704 -200.478644)
		(size 0.508)
		(drill 0.254)
		(layers "F.Cu" "B.Cu")
		(net "P3V3_AUX")
	)
	(via
		(at 106.51236 -141.01826)
		(size 0.508)
		(drill 0.254)
		(layers "F.Cu" "B.Cu")
		(net "P3V3_AUX")
	)
	(via
		(at 221.415102 -44.87291)
		(size 0.508)
		(drill 0.254)
		(layers "F.Cu" "B.Cu")
		(net "P3V3_AUX")
	)
	(via
		(at 296.773092 -115.902486)
		(size 0.508)
		(drill 0.254)
		(layers "F.Cu" "B.Cu")
		(net "P3V3_AUX")
	)
	(via
		(at 444.67399 -411.900116)
		(size 0.508)
		(drill 0.254)
		(layers "F.Cu" "B.Cu")
		(net "P3V3_AUX")
	)
	(via
		(at 153.569924 -117.7544)
		(size 0.508)
		(drill 0.254)
		(layers "F.Cu" "B.Cu")
		(net "P3V3_AUX")
	)
	(via
		(at 144.705832 -55.39359)
		(size 0.508)
		(drill 0.254)
		(layers "F.Cu" "B.Cu")
		(net "P3V3_AUX")
	)
	(via
		(at 453.582532 -242.13693)
		(size 0.508)
		(drill 0.254)
		(layers "F.Cu" "B.Cu")
		(net "P3V3_AUX")
	)
	(via
		(at 168.171368 -169.23385)
		(size 0.508)
		(drill 0.254)
		(layers "F.Cu" "B.Cu")
		(net "P3V3_AUX")
	)
	(via
		(at 453.615044 -42.84091)
		(size 0.508)
		(drill 0.254)
		(layers "F.Cu" "B.Cu")
		(net "P3V3_AUX")
	)
	(via
		(at 55.94477 -159.956246)
		(size 0.508)
		(drill 0.254)
		(layers "F.Cu" "B.Cu")
		(net "P3V3_AUX")
	)
	(via
		(at 199.07123 -56.38038)
		(size 0.508)
		(drill 0.254)
		(layers "F.Cu" "B.Cu")
		(net "P3V3_AUX")
	)
	(via
		(at 250.825254 -206.393542)
		(size 0.508)
		(drill 0.254)
		(layers "F.Cu" "B.Cu")
		(net "P3V3_AUX")
	)
	(via
		(at 405.596344 -367.407952)
		(size 0.508)
		(drill 0.254)
		(layers "F.Cu" "B.Cu")
		(net "P3V3_AUX")
	)
	(via
		(at 302.569626 -245.810278)
		(size 0.508)
		(drill 0.254)
		(layers "F.Cu" "B.Cu")
		(net "P3V3_AUX")
	)
	(via
		(at 77.308202 -47.403766)
		(size 0.508)
		(drill 0.254)
		(layers "F.Cu" "B.Cu")
		(net "P3V3_AUX")
	)
	(via
		(at 427.276006 -40.971724)
		(size 0.508)
		(drill 0.254)
		(layers "F.Cu" "B.Cu")
		(net "P3V3_AUX")
	)
	(via
		(at 384.374136 -140.326364)
		(size 0.508)
		(drill 0.254)
		(layers "F.Cu" "B.Cu")
		(net "P3V3_AUX")
	)
	(via
		(at 331.978 -246.38)
		(size 0.508)
		(drill 0.254)
		(layers "F.Cu" "B.Cu")
		(net "P3V3_AUX")
	)
	(via
		(at 147.071334 -55.11038)
		(size 0.508)
		(drill 0.254)
		(layers "F.Cu" "B.Cu")
		(net "P3V3_AUX")
	)
	(via
		(at 259.52323 -52.035456)
		(size 0.508)
		(drill 0.254)
		(layers "F.Cu" "B.Cu")
		(net "P3V3_AUX")
	)
	(via
		(at 135.796528 -215.85682)
		(size 0.508)
		(drill 0.254)
		(layers "F.Cu" "B.Cu")
		(net "P3V3_AUX")
	)
	(via
		(at 245.849648 -123.225052)
		(size 0.508)
		(drill 0.254)
		(layers "F.Cu" "B.Cu")
		(net "P3V3_AUX")
	)
	(via
		(at 278.15032 -384.403092)
		(size 0.508)
		(drill 0.254)
		(layers "F.Cu" "B.Cu")
		(net "P3V3_AUX")
	)
	(via
		(at 221.42323 -52.035456)
		(size 0.508)
		(drill 0.254)
		(layers "F.Cu" "B.Cu")
		(net "P3V3_AUX")
	)
	(via
		(at 321.223386 -95.801942)
		(size 0.508)
		(drill 0.254)
		(layers "F.Cu" "B.Cu")
		(net "P3V3_AUX")
	)
	(via
		(at 138.37158 -153.782522)
		(size 0.508)
		(drill 0.254)
		(layers "F.Cu" "B.Cu")
		(net "P3V3_AUX")
	)
	(via
		(at 37.47008 -117.7544)
		(size 0.508)
		(drill 0.254)
		(layers "F.Cu" "B.Cu")
		(net "P3V3_AUX")
	)
	(via
		(at 145.417032 -55.39359)
		(size 0.508)
		(drill 0.254)
		(layers "F.Cu" "B.Cu")
		(net "P3V3_AUX")
	)
	(via
		(at 274.872704 -406.551892)
		(size 0.508)
		(drill 0.254)
		(layers "F.Cu" "B.Cu")
		(net "P3V3_AUX")
	)
	(via
		(at 211.656422 -124.621544)
		(size 0.508)
		(drill 0.254)
		(layers "F.Cu" "B.Cu")
		(net "P3V3_AUX")
	)
	(via
		(at 451.079616 -234.834684)
		(size 0.508)
		(drill 0.254)
		(layers "F.Cu" "B.Cu")
		(net "P3V3_AUX")
	)
	(via
		(at 207.556608 -227.68052)
		(size 0.508)
		(drill 0.254)
		(layers "F.Cu" "B.Cu")
		(net "P3V3_AUX")
	)
	(via
		(at 353.271328 -55.74538)
		(size 0.508)
		(drill 0.254)
		(layers "F.Cu" "B.Cu")
		(net "P3V3_AUX")
	)
	(via
		(at 196.702426 -89.78138)
		(size 0.508)
		(drill 0.254)
		(layers "F.Cu" "B.Cu")
		(net "P3V3_AUX")
	)
	(via
		(at 283.21 -83.566)
		(size 0.508)
		(drill 0.254)
		(layers "F.Cu" "B.Cu")
		(net "P3V3_AUX")
	)
	(via
		(at 360.86796 -253.178564)
		(size 0.508)
		(drill 0.254)
		(layers "F.Cu" "B.Cu")
		(net "P3V3_AUX")
	)
	(via
		(at 211.815172 -122.06732)
		(size 0.508)
		(drill 0.254)
		(layers "F.Cu" "B.Cu")
		(net "P3V3_AUX")
	)
	(via
		(at 441.938918 -292.122098)
		(size 0.508)
		(drill 0.254)
		(layers "F.Cu" "B.Cu")
		(net "P3V3_AUX")
	)
	(via
		(at 114.910616 -139.64666)
		(size 0.508)
		(drill 0.254)
		(layers "F.Cu" "B.Cu")
		(net "P3V3_AUX")
	)
	(via
		(at 311.514998 -42.84091)
		(size 0.508)
		(drill 0.254)
		(layers "F.Cu" "B.Cu")
		(net "P3V3_AUX")
	)
	(via
		(at 14.284706 -123.225052)
		(size 0.508)
		(drill 0.254)
		(layers "F.Cu" "B.Cu")
		(net "P3V3_AUX")
	)
	(via
		(at 121.071386 -56.38038)
		(size 0.508)
		(drill 0.254)
		(layers "F.Cu" "B.Cu")
		(net "P3V3_AUX")
	)
	(via
		(at 89.188544 -94.572836)
		(size 0.508)
		(drill 0.254)
		(layers "F.Cu" "B.Cu")
		(net "P3V3_AUX")
	)
	(via
		(at 212.698584 -221.350586)
		(size 0.508)
		(drill 0.254)
		(layers "F.Cu" "B.Cu")
		(net "P3V3_AUX")
	)
	(via
		(at 335.026 -154.686)
		(size 0.508)
		(drill 0.254)
		(layers "F.Cu" "B.Cu")
		(net "P3V3_AUX")
	)
	(via
		(at 83.64982 -26.03373)
		(size 0.508)
		(drill 0.254)
		(layers "F.Cu" "B.Cu")
		(net "P3V3_AUX")
	)
	(via
		(at 99.55022 -48.753014)
		(size 0.508)
		(drill 0.254)
		(layers "F.Cu" "B.Cu")
		(net "P3V3_AUX")
	)
	(via
		(at 401.570444 -30.376876)
		(size 0.508)
		(drill 0.254)
		(layers "F.Cu" "B.Cu")
		(net "P3V3_AUX")
	)
	(via
		(at 15.775686 -276.264624)
		(size 0.508)
		(drill 0.254)
		(layers "F.Cu" "B.Cu")
		(net "P3V3_AUX")
	)
	(via
		(at 327.533 -241.173)
		(size 0.508)
		(drill 0.254)
		(layers "F.Cu" "B.Cu")
		(net "P3V3_AUX")
	)
	(via
		(at 121.071386 -55.74538)
		(size 0.508)
		(drill 0.254)
		(layers "F.Cu" "B.Cu")
		(net "P3V3_AUX")
	)
	(via
		(at 118.142004 -116.95049)
		(size 0.508)
		(drill 0.254)
		(layers "F.Cu" "B.Cu")
		(net "P3V3_AUX")
	)
	(via
		(at 331.851 -237.871)
		(size 0.508)
		(drill 0.254)
		(layers "F.Cu" "B.Cu")
		(net "P3V3_AUX")
	)
	(via
		(at 94.445328 -123.33732)
		(size 0.508)
		(drill 0.254)
		(layers "F.Cu" "B.Cu")
		(net "P3V3_AUX")
	)
	(via
		(at 451.60819 -47.403766)
		(size 0.508)
		(drill 0.254)
		(layers "F.Cu" "B.Cu")
		(net "P3V3_AUX")
	)
	(via
		(at 369.850416 -48.753014)
		(size 0.508)
		(drill 0.254)
		(layers "F.Cu" "B.Cu")
		(net "P3V3_AUX")
	)
	(via
		(at 349.276162 -40.971724)
		(size 0.508)
		(drill 0.254)
		(layers "F.Cu" "B.Cu")
		(net "P3V3_AUX")
	)
	(via
		(at 169.370502 -29.614876)
		(size 0.508)
		(drill 0.254)
		(layers "F.Cu" "B.Cu")
		(net "P3V3_AUX")
	)
	(via
		(at 234.277408 -203.405486)
		(size 0.508)
		(drill 0.254)
		(layers "F.Cu" "B.Cu")
		(net "P3V3_AUX")
	)
	(via
		(at 140.124942 -260.0706)
		(size 0.508)
		(drill 0.254)
		(layers "F.Cu" "B.Cu")
		(net "P3V3_AUX")
	)
	(via
		(at 239.232186 -159.844994)
		(size 0.508)
		(drill 0.254)
		(layers "F.Cu" "B.Cu")
		(net "P3V3_AUX")
	)
	(via
		(at 133.29158 -151.696928)
		(size 0.508)
		(drill 0.254)
		(layers "F.Cu" "B.Cu")
		(net "P3V3_AUX")
	)
	(via
		(at 380.002288 -238.811054)
		(size 0.508)
		(drill 0.254)
		(layers "F.Cu" "B.Cu")
		(net "P3V3_AUX")
	)
	(via
		(at 405.271224 -56.38038)
		(size 0.508)
		(drill 0.254)
		(layers "F.Cu" "B.Cu")
		(net "P3V3_AUX")
	)
	(via
		(at 429.61687 -55.39359)
		(size 0.508)
		(drill 0.254)
		(layers "F.Cu" "B.Cu")
		(net "P3V3_AUX")
	)
	(via
		(at 289.849814 -26.03373)
		(size 0.508)
		(drill 0.254)
		(layers "F.Cu" "B.Cu")
		(net "P3V3_AUX")
	)
	(via
		(at 452.160132 -242.84813)
		(size 0.508)
		(drill 0.254)
		(layers "F.Cu" "B.Cu")
		(net "P3V3_AUX")
	)
	(via
		(at 285.51505 -44.87291)
		(size 0.508)
		(drill 0.254)
		(layers "F.Cu" "B.Cu")
		(net "P3V3_AUX")
	)
	(via
		(at 106.46156 -139.03706)
		(size 0.508)
		(drill 0.254)
		(layers "F.Cu" "B.Cu")
		(net "P3V3_AUX")
	)
	(via
		(at 117.07622 -40.971724)
		(size 0.508)
		(drill 0.254)
		(layers "F.Cu" "B.Cu")
		(net "P3V3_AUX")
	)
	(via
		(at 277.089616 -406.157938)
		(size 0.508)
		(drill 0.254)
		(layers "F.Cu" "B.Cu")
		(net "P3V3_AUX")
	)
	(via
		(at 144.554956 -23.970996)
		(size 0.508)
		(drill 0.254)
		(layers "F.Cu" "B.Cu")
		(net "P3V3_AUX")
	)
	(via
		(at 251.299218 -35.876738)
		(size 0.508)
		(drill 0.254)
		(layers "F.Cu" "B.Cu")
		(net "P3V3_AUX")
	)
	(via
		(at 285.51505 -42.84091)
		(size 0.508)
		(drill 0.254)
		(layers "F.Cu" "B.Cu")
		(net "P3V3_AUX")
	)
	(via
		(at 367.826798 -241.15776)
		(size 0.508)
		(drill 0.254)
		(layers "F.Cu" "B.Cu")
		(net "P3V3_AUX")
	)
	(via
		(at 140.090144 -95.814642)
		(size 0.508)
		(drill 0.254)
		(layers "F.Cu" "B.Cu")
		(net "P3V3_AUX")
	)
	(via
		(at 428.754794 -23.970996)
		(size 0.508)
		(drill 0.254)
		(layers "F.Cu" "B.Cu")
		(net "P3V3_AUX")
	)
	(via
		(at 355.332284 -157.812994)
		(size 0.508)
		(drill 0.254)
		(layers "F.Cu" "B.Cu")
		(net "P3V3_AUX")
	)
	(via
		(at 380.176024 -199.39)
		(size 0.508)
		(drill 0.254)
		(layers "F.Cu" "B.Cu")
		(net "P3V3_AUX")
	)
	(via
		(at 341.571072 -190.41745)
		(size 0.508)
		(drill 0.254)
		(layers "F.Cu" "B.Cu")
		(net "P3V3_AUX")
	)
	(via
		(at 95.515684 -119.380254)
		(size 0.508)
		(drill 0.254)
		(layers "F.Cu" "B.Cu")
		(net "P3V3_AUX")
	)
	(via
		(at 230.834946 -278.551386)
		(size 0.508)
		(drill 0.254)
		(layers "F.Cu" "B.Cu")
		(net "P3V3_AUX")
	)
	(via
		(at 128.667764 -253.178564)
		(size 0.508)
		(drill 0.254)
		(layers "F.Cu" "B.Cu")
		(net "P3V3_AUX")
	)
	(via
		(at 53.270404 -30.376876)
		(size 0.508)
		(drill 0.254)
		(layers "F.Cu" "B.Cu")
		(net "P3V3_AUX")
	)
	(via
		(at 362.458 -206.883)
		(size 0.508)
		(drill 0.254)
		(layers "F.Cu" "B.Cu")
		(net "P3V3_AUX")
	)
	(via
		(at 142.831312 -243.155978)
		(size 0.508)
		(drill 0.254)
		(layers "F.Cu" "B.Cu")
		(net "P3V3_AUX")
	)
	(via
		(at 95.715328 -123.33732)
		(size 0.508)
		(drill 0.254)
		(layers "F.Cu" "B.Cu")
		(net "P3V3_AUX")
	)
	(via
		(at 335.026 -145.923)
		(size 0.508)
		(drill 0.254)
		(layers "F.Cu" "B.Cu")
		(net "P3V3_AUX")
	)
	(via
		(at 283.21 -86.106)
		(size 0.508)
		(drill 0.254)
		(layers "F.Cu" "B.Cu")
		(net "P3V3_AUX")
	)
	(via
		(at 453.558402 -248.83364)
		(size 0.508)
		(drill 0.254)
		(layers "F.Cu" "B.Cu")
		(net "P3V3_AUX")
	)
	(via
		(at 331.750162 -48.753014)
		(size 0.508)
		(drill 0.254)
		(layers "F.Cu" "B.Cu")
		(net "P3V3_AUX")
	)
	(via
		(at 431.882296 -36.286948)
		(size 0.508)
		(drill 0.254)
		(layers "F.Cu" "B.Cu")
		(net "P3V3_AUX")
	)
	(via
		(at 211.180172 -122.06732)
		(size 0.508)
		(drill 0.254)
		(layers "F.Cu" "B.Cu")
		(net "P3V3_AUX")
	)
	(via
		(at 324.271386 -97.821242)
		(size 0.508)
		(drill 0.254)
		(layers "F.Cu" "B.Cu")
		(net "P3V3_AUX")
	)
	(via
		(at 419.399212 -35.876738)
		(size 0.508)
		(drill 0.254)
		(layers "F.Cu" "B.Cu")
		(net "P3V3_AUX")
	)
	(via
		(at 401.623276 -52.035456)
		(size 0.508)
		(drill 0.254)
		(layers "F.Cu" "B.Cu")
		(net "P3V3_AUX")
	)
	(via
		(at 362.89996 -258.131564)
		(size 0.508)
		(drill 0.254)
		(layers "F.Cu" "B.Cu")
		(net "P3V3_AUX")
	)
	(via
		(at 222.5548 -23.970996)
		(size 0.508)
		(drill 0.254)
		(layers "F.Cu" "B.Cu")
		(net "P3V3_AUX")
	)
	(via
		(at 457.406502 -280.224484)
		(size 0.508)
		(drill 0.254)
		(layers "F.Cu" "B.Cu")
		(net "P3V3_AUX")
	)
	(via
		(at 311.470294 -30.376876)
		(size 0.508)
		(drill 0.254)
		(layers "F.Cu" "B.Cu")
		(net "P3V3_AUX")
	)
	(via
		(at 375.6152 -42.84091)
		(size 0.508)
		(drill 0.254)
		(layers "F.Cu" "B.Cu")
		(net "P3V3_AUX")
	)
	(via
		(at 189.65037 -48.753014)
		(size 0.508)
		(drill 0.254)
		(layers "F.Cu" "B.Cu")
		(net "P3V3_AUX")
	)
	(via
		(at 182.228236 -198.755)
		(size 0.508)
		(drill 0.254)
		(layers "F.Cu" "B.Cu")
		(net "P3V3_AUX")
	)
	(via
		(at 218.812872 -122.758962)
		(size 0.508)
		(drill 0.254)
		(layers "F.Cu" "B.Cu")
		(net "P3V3_AUX")
	)
	(via
		(at 362.301536 -121.57075)
		(size 0.508)
		(drill 0.254)
		(layers "F.Cu" "B.Cu")
		(net "P3V3_AUX")
	)
	(via
		(at 405.271224 -55.11038)
		(size 0.508)
		(drill 0.254)
		(layers "F.Cu" "B.Cu")
		(net "P3V3_AUX")
	)
	(via
		(at 357.567738 -393.459716)
		(size 0.508)
		(drill 0.254)
		(layers "F.Cu" "B.Cu")
		(net "P3V3_AUX")
	)
	(via
		(at 397.224758 -83.785202)
		(size 0.508)
		(drill 0.254)
		(layers "F.Cu" "B.Cu")
		(net "P3V3_AUX")
	)
	(via
		(at 459.572868 -375.090182)
		(size 0.508)
		(drill 0.254)
		(layers "F.Cu" "B.Cu")
		(net "P3V3_AUX")
	)
	(via
		(at 124.309124 -202.579732)
		(size 0.508)
		(drill 0.254)
		(layers "F.Cu" "B.Cu")
		(net "P3V3_AUX")
	)
	(via
		(at 328.01814 -94.24924)
		(size 0.508)
		(drill 0.254)
		(layers "F.Cu" "B.Cu")
		(net "P3V3_AUX")
	)
	(via
		(at 196.705728 -55.39359)
		(size 0.508)
		(drill 0.254)
		(layers "F.Cu" "B.Cu")
		(net "P3V3_AUX")
	)
	(via
		(at 130.699764 -254.194564)
		(size 0.508)
		(drill 0.254)
		(layers "F.Cu" "B.Cu")
		(net "P3V3_AUX")
	)
	(via
		(at 171.41698 -55.39359)
		(size 0.508)
		(drill 0.254)
		(layers "F.Cu" "B.Cu")
		(net "P3V3_AUX")
	)
	(via
		(at 28.605734 -55.39359)
		(size 0.508)
		(drill 0.254)
		(layers "F.Cu" "B.Cu")
		(net "P3V3_AUX")
	)
	(via
		(at 459.744572 -329.880976)
		(size 0.508)
		(drill 0.254)
		(layers "F.Cu" "B.Cu")
		(net "P3V3_AUX")
	)
	(via
		(at 24.024844 -260.0706)
		(size 0.508)
		(drill 0.254)
		(layers "F.Cu" "B.Cu")
		(net "P3V3_AUX")
	)
	(via
		(at 243.8654 -215.05291)
		(size 0.508)
		(drill 0.254)
		(layers "F.Cu" "B.Cu")
		(net "P3V3_AUX")
	)
	(via
		(at 197.039484 -136.98601)
		(size 0.508)
		(drill 0.254)
		(layers "F.Cu" "B.Cu")
		(net "P3V3_AUX")
	)
	(via
		(at 82.971132 -55.11038)
		(size 0.508)
		(drill 0.254)
		(layers "F.Cu" "B.Cu")
		(net "P3V3_AUX")
	)
	(via
		(at 172.995844 -138.95705)
		(size 0.508)
		(drill 0.254)
		(layers "F.Cu" "B.Cu")
		(net "P3V3_AUX")
	)
	(via
		(at 327.59142 -204.93863)
		(size 0.508)
		(drill 0.254)
		(layers "F.Cu" "B.Cu")
		(net "P3V3_AUX")
	)
	(via
		(at 4.971288 -55.11038)
		(size 0.508)
		(drill 0.254)
		(layers "F.Cu" "B.Cu")
		(net "P3V3_AUX")
	)
	(via
		(at 341.399368 -35.876738)
		(size 0.508)
		(drill 0.254)
		(layers "F.Cu" "B.Cu")
		(net "P3V3_AUX")
	)
	(via
		(at 250.166886 -274.592034)
		(size 0.508)
		(drill 0.254)
		(layers "F.Cu" "B.Cu")
		(net "P3V3_AUX")
	)
	(via
		(at 283.508196 -47.403766)
		(size 0.508)
		(drill 0.254)
		(layers "F.Cu" "B.Cu")
		(net "P3V3_AUX")
	)
	(via
		(at 303.299114 -35.876738)
		(size 0.508)
		(drill 0.254)
		(layers "F.Cu" "B.Cu")
		(net "P3V3_AUX")
	)
	(via
		(at 380.097538 -208.534)
		(size 0.508)
		(drill 0.254)
		(layers "F.Cu" "B.Cu")
		(net "P3V3_AUX")
	)
	(via
		(at 334.207866 -239.710722)
		(size 0.508)
		(drill 0.254)
		(layers "F.Cu" "B.Cu")
		(net "P3V3_AUX")
	)
	(via
		(at 312.805572 -55.39359)
		(size 0.508)
		(drill 0.254)
		(layers "F.Cu" "B.Cu")
		(net "P3V3_AUX")
	)
	(via
		(at 405.882348 -36.286948)
		(size 0.508)
		(drill 0.254)
		(layers "F.Cu" "B.Cu")
		(net "P3V3_AUX")
	)
	(via
		(at 237.340394 -51.978814)
		(size 0.508)
		(drill 0.254)
		(layers "F.Cu" "B.Cu")
		(net "P3V3_AUX")
	)
	(via
		(at 27.323288 -52.035456)
		(size 0.508)
		(drill 0.254)
		(layers "F.Cu" "B.Cu")
		(net "P3V3_AUX")
	)
	(via
		(at 16.359632 -148.017738)
		(size 0.508)
		(drill 0.254)
		(layers "F.Cu" "B.Cu")
		(net "P3V3_AUX")
	)
	(via
		(at 330.327 -246.427498)
		(size 0.508)
		(drill 0.254)
		(layers "F.Cu" "B.Cu")
		(net "P3V3_AUX")
	)
	(via
		(at 341.571072 -188.38545)
		(size 0.508)
		(drill 0.254)
		(layers "F.Cu" "B.Cu")
		(net "P3V3_AUX")
	)
	(via
		(at 210.765136 -179.194206)
		(size 0.508)
		(drill 0.254)
		(layers "F.Cu" "B.Cu")
		(net "P3V3_AUX")
	)
	(via
		(at 375.297446 -88.8238)
		(size 0.508)
		(drill 0.254)
		(layers "F.Cu" "B.Cu")
		(net "P3V3_AUX")
	)
	(via
		(at 117.370606 -30.376876)
		(size 0.508)
		(drill 0.254)
		(layers "F.Cu" "B.Cu")
		(net "P3V3_AUX")
	)
	(via
		(at 143.840962 -241.758978)
		(size 0.508)
		(drill 0.254)
		(layers "F.Cu" "B.Cu")
		(net "P3V3_AUX")
	)
	(via
		(at 203.207366 -84.675472)
		(size 0.508)
		(drill 0.254)
		(layers "F.Cu" "B.Cu")
		(net "P3V3_AUX")
	)
	(via
		(at 380.739142 -247.762522)
		(size 0.508)
		(drill 0.254)
		(layers "F.Cu" "B.Cu")
		(net "P3V3_AUX")
	)
	(via
		(at 297.54703 -107.210352)
		(size 0.508)
		(drill 0.254)
		(layers "F.Cu" "B.Cu")
		(net "P3V3_AUX")
	)
	(via
		(at 335.026 -149.987)
		(size 0.508)
		(drill 0.254)
		(layers "F.Cu" "B.Cu")
		(net "P3V3_AUX")
	)
	(via
		(at 108.89996 -139.69746)
		(size 0.508)
		(drill 0.254)
		(layers "F.Cu" "B.Cu")
		(net "P3V3_AUX")
	)
	(via
		(at 205.777592 -349.220536)
		(size 0.508)
		(drill 0.254)
		(layers "F.Cu" "B.Cu")
		(net "P3V3_AUX")
	)
	(via
		(at 361.550458 -115.402106)
		(size 0.508)
		(drill 0.254)
		(layers "F.Cu" "B.Cu")
		(net "P3V3_AUX")
	)
	(via
		(at 214.829136 -179.194206)
		(size 0.508)
		(drill 0.254)
		(layers "F.Cu" "B.Cu")
		(net "P3V3_AUX")
	)
	(via
		(at 289.095942 -138.95705)
		(size 0.508)
		(drill 0.254)
		(layers "F.Cu" "B.Cu")
		(net "P3V3_AUX")
	)
	(via
		(at 152.17394 -140.326364)
		(size 0.508)
		(drill 0.254)
		(layers "F.Cu" "B.Cu")
		(net "P3V3_AUX")
	)
	(via
		(at 62.321948 -137.848848)
		(size 0.508)
		(drill 0.254)
		(layers "F.Cu" "B.Cu")
		(net "P3V3_AUX")
	)
	(via
		(at 332.92161 -208.404714)
		(size 0.508)
		(drill 0.254)
		(layers "F.Cu" "B.Cu")
		(net "P3V3_AUX")
	)
	(via
		(at 424.993562 -83.532218)
		(size 0.508)
		(drill 0.254)
		(layers "F.Cu" "B.Cu")
		(net "P3V3_AUX")
	)
	(via
		(at 11.696446 -212.780372)
		(size 0.508)
		(drill 0.254)
		(layers "F.Cu" "B.Cu")
		(net "P3V3_AUX")
	)
	(via
		(at 231.067356 -222.703898)
		(size 0.4572)
		(drill 0.254)
		(layers "F.Cu" "B.Cu")
		(net "P3V3_AUX")
	)
	(via
		(at 288.482024 -54.96179)
		(size 0.508)
		(drill 0.254)
		(layers "F.Cu" "B.Cu")
		(net "P3V3_AUX")
	)
	(via
		(at 203.23937 -85.691472)
		(size 0.508)
		(drill 0.254)
		(layers "F.Cu" "B.Cu")
		(net "P3V3_AUX")
	)
	(via
		(at 112.523016 -140.99286)
		(size 0.508)
		(drill 0.254)
		(layers "F.Cu" "B.Cu")
		(net "P3V3_AUX")
	)
	(via
		(at 357.768144 -390.28878)
		(size 0.508)
		(drill 0.254)
		(layers "F.Cu" "B.Cu")
		(net "P3V3_AUX")
	)
	(via
		(at 301.607474 -220.55836)
		(size 0.508)
		(drill 0.254)
		(layers "F.Cu" "B.Cu")
		(net "P3V3_AUX")
	)
	(via
		(at 251.615702 -336.358992)
		(size 0.508)
		(drill 0.254)
		(layers "F.Cu" "B.Cu")
		(net "P3V3_AUX")
	)
	(via
		(at 374.018556 -22.555454)
		(size 0.508)
		(drill 0.254)
		(layers "F.Cu" "B.Cu")
		(net "P3V3_AUX")
	)
	(via
		(at 414.001458 -199.981058)
		(size 0.508)
		(drill 0.254)
		(layers "F.Cu" "B.Cu")
		(net "P3V3_AUX")
	)
	(via
		(at 124.71019 -104.734868)
		(size 0.508)
		(drill 0.254)
		(layers "F.Cu" "B.Cu")
		(net "P3V3_AUX")
	)
	(via
		(at 169.370502 -30.376876)
		(size 0.508)
		(drill 0.254)
		(layers "F.Cu" "B.Cu")
		(net "P3V3_AUX")
	)
	(via
		(at 11.593322 -120.11787)
		(size 0.508)
		(drill 0.254)
		(layers "F.Cu" "B.Cu")
		(net "P3V3_AUX")
	)
	(via
		(at 120.119902 -96.034606)
		(size 0.508)
		(drill 0.254)
		(layers "F.Cu" "B.Cu")
		(net "P3V3_AUX")
	)
	(via
		(at 211.656422 -123.910344)
		(size 0.508)
		(drill 0.254)
		(layers "F.Cu" "B.Cu")
		(net "P3V3_AUX")
	)
	(via
		(at 441.835032 -288.830766)
		(size 0.508)
		(drill 0.254)
		(layers "F.Cu" "B.Cu")
		(net "P3V3_AUX")
	)
	(via
		(at 246.000778 -238.15421)
		(size 0.508)
		(drill 0.254)
		(layers "F.Cu" "B.Cu")
		(net "P3V3_AUX")
	)
	(via
		(at 99.845876 -361.5944)
		(size 0.4572)
		(drill 0.254)
		(layers "F.Cu" "B.Cu")
		(net "P3V3_AUX")
	)
	(via
		(at 187.424568 -406.99436)
		(size 0.508)
		(drill 0.254)
		(layers "F.Cu" "B.Cu")
		(net "P3V3_AUX")
	)
	(via
		(at 56.971184 -56.38038)
		(size 0.508)
		(drill 0.254)
		(layers "F.Cu" "B.Cu")
		(net "P3V3_AUX")
	)
	(via
		(at 121.750074 -26.03373)
		(size 0.508)
		(drill 0.254)
		(layers "F.Cu" "B.Cu")
		(net "P3V3_AUX")
	)
	(via
		(at 442.745368 -123.33732)
		(size 0.508)
		(drill 0.254)
		(layers "F.Cu" "B.Cu")
		(net "P3V3_AUX")
	)
	(via
		(at 147.088098 -57.48528)
		(size 0.508)
		(drill 0.254)
		(layers "F.Cu" "B.Cu")
		(net "P3V3_AUX")
	)
	(via
		(at 209.63509 -288.830766)
		(size 0.508)
		(drill 0.254)
		(layers "F.Cu" "B.Cu")
		(net "P3V3_AUX")
	)
	(via
		(at 335.026 -148.971)
		(size 0.508)
		(drill 0.254)
		(layers "F.Cu" "B.Cu")
		(net "P3V3_AUX")
	)
	(via
		(at 45.099224 -35.876738)
		(size 0.508)
		(drill 0.254)
		(layers "F.Cu" "B.Cu")
		(net "P3V3_AUX")
	)
	(via
		(at 375.297446 -83.1088)
		(size 0.508)
		(drill 0.254)
		(layers "F.Cu" "B.Cu")
		(net "P3V3_AUX")
	)
	(via
		(at 82.971132 -55.74538)
		(size 0.508)
		(drill 0.254)
		(layers "F.Cu" "B.Cu")
		(net "P3V3_AUX")
	)
	(via
		(at 260.805676 -55.39359)
		(size 0.508)
		(drill 0.254)
		(layers "F.Cu" "B.Cu")
		(net "P3V3_AUX")
	)
	(via
		(at 216.937844 -95.123)
		(size 0.508)
		(drill 0.254)
		(layers "F.Cu" "B.Cu")
		(net "P3V3_AUX")
	)
	(via
		(at 96.4692 -195.3768)
		(size 0.508)
		(drill 0.254)
		(layers "F.Cu" "B.Cu")
		(net "P3V3_AUX")
	)
	(via
		(at 356.928166 -165.615112)
		(size 0.508)
		(drill 0.254)
		(layers "F.Cu" "B.Cu")
		(net "P3V3_AUX")
	)
	(via
		(at 113.29035 -132.003546)
		(size 0.508)
		(drill 0.254)
		(layers "F.Cu" "B.Cu")
		(net "P3V3_AUX")
	)
	(via
		(at 429.065944 -139.734798)
		(size 0.508)
		(drill 0.254)
		(layers "F.Cu" "B.Cu")
		(net "P3V3_AUX")
	)
	(via
		(at 246.59336 -116.164106)
		(size 0.508)
		(drill 0.254)
		(layers "F.Cu" "B.Cu")
		(net "P3V3_AUX")
	)
	(via
		(at 444.118238 -94.24924)
		(size 0.508)
		(drill 0.254)
		(layers "F.Cu" "B.Cu")
		(net "P3V3_AUX")
	)
	(via
		(at 215.81872 -176.476406)
		(size 0.508)
		(drill 0.254)
		(layers "F.Cu" "B.Cu")
		(net "P3V3_AUX")
	)
	(via
		(at 14.433296 -122.53595)
		(size 0.508)
		(drill 0.254)
		(layers "F.Cu" "B.Cu")
		(net "P3V3_AUX")
	)
	(via
		(at 115.572286 -140.947648)
		(size 0.508)
		(drill 0.254)
		(layers "F.Cu" "B.Cu")
		(net "P3V3_AUX")
	)
	(via
		(at 140.090144 -91.242642)
		(size 0.508)
		(drill 0.254)
		(layers "F.Cu" "B.Cu")
		(net "P3V3_AUX")
	)
	(via
		(at 447.85026 -48.753014)
		(size 0.508)
		(drill 0.254)
		(layers "F.Cu" "B.Cu")
		(net "P3V3_AUX")
	)
	(via
		(at 31.649924 -26.03373)
		(size 0.508)
		(drill 0.254)
		(layers "F.Cu" "B.Cu")
		(net "P3V3_AUX")
	)
	(via
		(at 212.900006 -214.238586)
		(size 0.508)
		(drill 0.254)
		(layers "F.Cu" "B.Cu")
		(net "P3V3_AUX")
	)
	(via
		(at 326.64527 -123.33732)
		(size 0.508)
		(drill 0.254)
		(layers "F.Cu" "B.Cu")
		(net "P3V3_AUX")
	)
	(via
		(at 125.59411 -167.074088)
		(size 0.508)
		(drill 0.254)
		(layers "F.Cu" "B.Cu")
		(net "P3V3_AUX")
	)
	(via
		(at 450.195188 -416.636962)
		(size 0.508)
		(drill 0.254)
		(layers "F.Cu" "B.Cu")
		(net "P3V3_AUX")
	)
	(via
		(at 109.571536 -139.69746)
		(size 0.508)
		(drill 0.254)
		(layers "F.Cu" "B.Cu")
		(net "P3V3_AUX")
	)
	(via
		(at 57.582308 -36.286948)
		(size 0.508)
		(drill 0.254)
		(layers "F.Cu" "B.Cu")
		(net "P3V3_AUX")
	)
	(via
		(at 380.649734 -7.884922)
		(size 0.508)
		(drill 0.254)
		(layers "F.Cu" "B.Cu")
		(net "P3V3_AUX")
	)
	(segment
		(start 304.328576 -242.01755)
		(end 303.873408 -241.562382)
		(width 0.4572)
		(layer "B.Cu")
		(net "P3V3_AUX")
	)
	(segment
		(start 372.321582 -235.739432)
		(end 372.444518 -235.739432)
		(width 0.4572)
		(layer "B.Cu")
		(net "P3V3_AUX")
	)
	(segment
		(start 138.66241 -211.045806)
		(end 138.90117 -210.807046)
		(width 0.4572)
		(layer "B.Cu")
		(net "P3V3_AUX")
	)
	(segment
		(start 304.328576 -242.262406)
		(end 304.328576 -242.01755)
		(width 0.4572)
		(layer "B.Cu")
		(net "P3V3_AUX")
	)
	(segment
		(start 386.680202 -237.29696)
		(end 386.680202 -238.173768)
		(width 0.4572)
		(layer "B.Cu")
		(net "P3V3_AUX")
	)
	(segment
		(start 367.491518 -340.4616)
		(end 361.076748 -346.87637)
		(width 0.4572)
		(layer "B.Cu")
		(net "P3V3_AUX")
	)
	(segment
		(start 277.33371 -389.498078)
		(end 277.721822 -389.498078)
		(width 0.4572)
		(layer "B.Cu")
		(net "P3V3_AUX")
	)
	(segment
		(start 148.209254 -205.987142)
		(end 148.209254 -204.46619)
		(width 0.3048)
		(layer "B.Cu")
		(net "P3V3_AUX")
	)
	(segment
		(start 375.98858 -238.588296)
		(end 376.764296 -238.588296)
		(width 0.4572)
		(layer "B.Cu")
		(net "P3V3_AUX")
	)
	(segment
		(start 132.821172 -209.352896)
		(end 132.710174 -209.463894)
		(width 0.4572)
		(layer "B.Cu")
		(net "P3V3_AUX")
	)
	(segment
		(start 135.636 -214.122)
		(end 135.208264 -213.694264)
		(width 0.4572)
		(layer "B.Cu")
		(net "P3V3_AUX")
	)
	(segment
		(start 294.871902 -198.849742)
		(end 294.871902 -199.86498)
		(width 0.381)
		(layer "B.Cu")
		(net "P3V3_AUX")
	)
	(segment
		(start 61.197236 -107.612688)
		(end 61.197236 -108.465366)
		(width 0.4572)
		(layer "B.Cu")
		(net "P3V3_AUX")
	)
	(segment
		(start 209.3722 -289.093656)
		(end 204.413358 -289.093656)
		(width 0.4572)
		(layer "B.Cu")
		(net "P3V3_AUX")
	)
	(segment
		(start 256.888234 -255.983232)
		(end 256.224786 -256.64668)
		(width 0.4572)
		(layer "B.Cu")
		(net "P3V3_AUX")
	)
	(segment
		(start 207.879188 -227.35794)
		(end 207.556608 -227.68052)
		(width 0.4572)
		(layer "B.Cu")
		(net "P3V3_AUX")
	)
	(segment
		(start 143.358362 -243.683028)
		(end 143.790162 -243.683028)
		(width 0.4572)
		(layer "B.Cu")
		(net "P3V3_AUX")
	)
	(segment
		(start 124.731272 -202.157584)
		(end 124.731272 -201.93635)
		(width 0.4572)
		(layer "B.Cu")
		(net "P3V3_AUX")
	)
	(segment
		(start 230.474774 -174.69358)
		(end 230.187754 -174.40656)
		(width 0.4572)
		(layer "B.Cu")
		(net "P3V3_AUX")
	)
	(segment
		(start 213.401148 -220.322902)
		(end 213.401148 -221.338648)
		(width 0.3048)
		(layer "B.Cu")
		(net "P3V3_AUX")
	)
	(segment
		(start 142.831312 -243.155978)
		(end 143.358362 -243.683028)
		(width 0.4572)
		(layer "B.Cu")
		(net "P3V3_AUX")
	)
	(segment
		(start 301.604172 -117.723666)
		(end 301.604172 -117.108478)
		(width 0.4572)
		(layer "B.Cu")
		(net "P3V3_AUX")
	)
	(segment
		(start 320.227198 -83.01863)
		(end 320.20637 -83.123278)
		(width 0.4572)
		(layer "B.Cu")
		(net "P3V3_AUX")
	)
	(segment
		(start 408.559 -384.81)
		(end 408.559 -384.429)
		(width 0.4572)
		(layer "B.Cu")
		(net "P3V3_AUX")
	)
	(segment
		(start 320.56705 -82.31505)
		(end 320.56705 -82.51063)
		(width 0.4572)
		(layer "B.Cu")
		(net "P3V3_AUX")
	)
	(segment
		(start 127.395732 -203.392278)
		(end 128.566164 -202.221846)
		(width 0.4572)
		(layer "B.Cu")
		(net "P3V3_AUX")
	)
	(segment
		(start 380.25705 -244.094)
		(end 380.25705 -244.729)
		(width 0.4572)
		(layer "B.Cu")
		(net "P3V3_AUX")
	)
	(segment
		(start 361.076748 -359.722674)
		(end 363.314996 -361.960922)
		(width 0.4572)
		(layer "B.Cu")
		(net "P3V3_AUX")
	)
	(segment
		(start 134.953502 -206.4639)
		(end 134.883398 -206.393796)
		(width 0.4572)
		(layer "B.Cu")
		(net "P3V3_AUX")
	)
	(segment
		(start 351.245932 -155.321)
		(end 351.245932 -156.337)
		(width 0.4572)
		(layer "B.Cu")
		(net "P3V3_AUX")
	)
	(segment
		(start 144.17675 -203.980796)
		(end 144.159986 -203.964032)
		(width 0.4572)
		(layer "B.Cu")
		(net "P3V3_AUX")
	)
	(segment
		(start 303.077626 -251.10567)
		(end 302.749712 -250.777756)
		(width 0.4572)
		(layer "B.Cu")
		(net "P3V3_AUX")
	)
	(segment
		(start 11.499596 -214.177372)
		(end 12.026646 -214.704422)
		(width 0.381)
		(layer "B.Cu")
		(net "P3V3_AUX")
	)
	(segment
		(start 329.407266 -231.515412)
		(end 329.43038 -231.538526)
		(width 0.4572)
		(layer "B.Cu")
		(net "P3V3_AUX")
	)
	(segment
		(start 255.580388 -249.005598)
		(end 255.049528 -249.005598)
		(width 0.4572)
		(layer "B.Cu")
		(net "P3V3_AUX")
	)
	(segment
		(start 365.795814 -222.721932)
		(end 365.795814 -224.341182)
		(width 0.3556)
		(layer "B.Cu")
		(net "P3V3_AUX")
	)
	(segment
		(start 300.012354 -237.655354)
		(end 300.228 -237.871)
		(width 0.4572)
		(layer "B.Cu")
		(net "P3V3_AUX")
	)
	(segment
		(start 377.869958 -241.70005)
		(end 377.75896 -241.811048)
		(width 0.4572)
		(layer "B.Cu")
		(net "P3V3_AUX")
	)
	(segment
		(start 243.047266 -235.036868)
		(end 242.460018 -235.624116)
		(width 0.4572)
		(layer "B.Cu")
		(net "P3V3_AUX")
	)
	(segment
		(start 293.397178 -109.481366)
		(end 293.397178 -108.465366)
		(width 0.4572)
		(layer "B.Cu")
		(net "P3V3_AUX")
	)
	(segment
		(start 356.924356 -244.139974)
		(end 356.924356 -245.128796)
		(width 0.4572)
		(layer "B.Cu")
		(net "P3V3_AUX")
	)
	(segment
		(start 55.764684 -139.199366)
		(end 55.764684 -140.181076)
		(width 0.4572)
		(layer "B.Cu")
		(net "P3V3_AUX")
	)
	(segment
		(start 456.279758 -251.35586)
		(end 457.03617 -252.112272)
		(width 0.381)
		(layer "B.Cu")
		(net "P3V3_AUX")
	)
	(segment
		(start 351.245932 -143.51)
		(end 351.245932 -144.526)
		(width 0.4572)
		(layer "B.Cu")
		(net "P3V3_AUX")
	)
	(segment
		(start 293.397178 -110.497366)
		(end 293.397178 -109.481366)
		(width 0.4572)
		(layer "B.Cu")
		(net "P3V3_AUX")
	)
	(segment
		(start 403.301708 -381.939546)
		(end 403.738334 -381.50292)
		(width 0.4572)
		(layer "B.Cu")
		(net "P3V3_AUX")
	)
	(segment
		(start 320.56705 -82.51063)
		(end 320.227198 -83.01863)
		(width 0.4572)
		(layer "B.Cu")
		(net "P3V3_AUX")
	)
	(segment
		(start 303.839626 -243.737384)
		(end 303.839626 -242.751356)
		(width 0.4572)
		(layer "B.Cu")
		(net "P3V3_AUX")
	)
	(segment
		(start 141.793214 -213.505796)
		(end 142.446502 -213.505796)
		(width 0.4572)
		(layer "B.Cu")
		(net "P3V3_AUX")
	)
	(segment
		(start 144.40535 -244.298216)
		(end 143.790162 -243.683028)
		(width 0.4572)
		(layer "B.Cu")
		(net "P3V3_AUX")
	)
	(segment
		(start 228.801422 -224.611946)
		(end 228.801422 -223.637602)
		(width 0.4572)
		(layer "B.Cu")
		(net "P3V3_AUX")
	)
	(segment
		(start 135.208264 -212.381846)
		(end 135.208264 -211.746846)
		(width 0.4572)
		(layer "B.Cu")
		(net "P3V3_AUX")
	)
	(segment
		(start 172.106844 -138.95705)
		(end 171.864528 -139.199366)
		(width 0.4572)
		(layer "B.Cu")
		(net "P3V3_AUX")
	)
	(segment
		(start 213.535006 -214.24646)
		(end 212.90788 -214.24646)
		(width 0.4572)
		(layer "B.Cu")
		(net "P3V3_AUX")
	)
	(segment
		(start 133.532372 -221.950534)
		(end 133.532372 -222.658432)
		(width 0.4572)
		(layer "B.Cu")
		(net "P3V3_AUX")
	)
	(segment
		(start 135.205216 -204.060806)
		(end 135.205216 -204.888846)
		(width 0.4572)
		(layer "B.Cu")
		(net "P3V3_AUX")
	)
	(segment
		(start 404.30704 -138.95705)
		(end 404.064724 -139.199366)
		(width 0.4572)
		(layer "B.Cu")
		(net "P3V3_AUX")
	)
	(segment
		(start 65.14465 -107.210352)
		(end 61.599572 -107.210352)
		(width 0.4572)
		(layer "B.Cu")
		(net "P3V3_AUX")
	)
	(segment
		(start 254.282956 -195.26885)
		(end 255.01346 -194.538346)
		(width 0.4572)
		(layer "B.Cu")
		(net "P3V3_AUX")
	)
	(segment
		(start 135.208264 -211.090256)
		(end 135.198866 -211.080858)
		(width 0.4572)
		(layer "B.Cu")
		(net "P3V3_AUX")
	)
	(segment
		(start 130.939794 -204.209142)
		(end 131.611878 -204.209142)
		(width 0.4572)
		(layer "B.Cu")
		(net "P3V3_AUX")
	)
	(segment
		(start 302.338232 -246.041672)
		(end 302.569626 -245.810278)
		(width 0.4572)
		(layer "B.Cu")
		(net "P3V3_AUX")
	)
	(segment
		(start 204.413358 -289.093656)
		(end 204.077062 -288.75736)
		(width 0.4572)
		(layer "B.Cu")
		(net "P3V3_AUX")
	)
	(segment
		(start 461.338676 -360.483912)
		(end 411.888686 -360.483912)
		(width 0.4572)
		(layer "B.Cu")
		(net "P3V3_AUX")
	)
	(segment
		(start 389.89 -241.78895)
		(end 389.23087 -241.78895)
		(width 0.4572)
		(layer "B.Cu")
		(net "P3V3_AUX")
	)
	(segment
		(start 69.40423 -117.723666)
		(end 69.40423 -117.108478)
		(width 0.4572)
		(layer "B.Cu")
		(net "P3V3_AUX")
	)
	(segment
		(start 255.960626 -242.924838)
		(end 255.528826 -242.924838)
		(width 0.4572)
		(layer "B.Cu")
		(net "P3V3_AUX")
	)
	(segment
		(start 366.66805 -235.458)
		(end 367.289588 -235.458)
		(width 0.4572)
		(layer "B.Cu")
		(net "P3V3_AUX")
	)
	(segment
		(start 228.6635 -174.40656)
		(end 227.643436 -175.426624)
		(width 0.4572)
		(layer "B.Cu")
		(net "P3V3_AUX")
	)
	(segment
		(start 349.013018 -202.76312)
		(end 350.012 -203.762102)
		(width 0.4572)
		(layer "B.Cu")
		(net "P3V3_AUX")
	)
	(segment
		(start 133.595872 -222.721932)
		(end 133.595872 -224.341182)
		(width 0.3556)
		(layer "B.Cu")
		(net "P3V3_AUX")
	)
	(segment
		(start 69.40423 -117.108478)
		(end 69.999352 -116.513356)
		(width 0.4572)
		(layer "B.Cu")
		(net "P3V3_AUX")
	)
	(segment
		(start 126.328678 -286.007048)
		(end 126.328678 -286.356806)
		(width 0.4572)
		(layer "B.Cu")
		(net "P3V3_AUX")
	)
	(segment
		(start 403.301708 -383.743708)
		(end 403.301708 -381.939546)
		(width 0.4572)
		(layer "B.Cu")
		(net "P3V3_AUX")
	)
	(segment
		(start 228.759512 -233.182668)
		(end 228.716332 -233.182668)
		(width 0.254)
		(layer "B.Cu")
		(net "P3V3_AUX")
	)
	(segment
		(start 404.198582 -374.277128)
		(end 404.31085 -374.16486)
		(width 0.4572)
		(layer "B.Cu")
		(net "P3V3_AUX")
	)
	(segment
		(start 301.607474 -221.294452)
		(end 301.607474 -220.55836)
		(width 0.4572)
		(layer "B.Cu")
		(net "P3V3_AUX")
	)
	(segment
		(start 142.831312 -241.955828)
		(end 143.028162 -241.758978)
		(width 0.4572)
		(layer "B.Cu")
		(net "P3V3_AUX")
	)
	(segment
		(start 458.512672 -250.83516)
		(end 458.473556 -250.796044)
		(width 0.381)
		(layer "B.Cu")
		(net "P3V3_AUX")
	)
	(segment
		(start 133.532372 -222.658432)
		(end 133.595872 -222.721932)
		(width 0.3556)
		(layer "B.Cu")
		(net "P3V3_AUX")
	)
	(segment
		(start 407.77922 -372.877842)
		(end 406.119076 -372.877842)
		(width 0.4572)
		(layer "B.Cu")
		(net "P3V3_AUX")
	)
	(segment
		(start 61.599572 -107.210352)
		(end 61.197236 -107.612688)
		(width 0.4572)
		(layer "B.Cu")
		(net "P3V3_AUX")
	)
	(segment
		(start 128.566164 -201.478896)
		(end 128.566164 -202.221846)
		(width 0.4572)
		(layer "B.Cu")
		(net "P3V3_AUX")
	)
	(segment
		(start 304.455576 -249.755406)
		(end 304.328576 -249.628406)
		(width 0.4572)
		(layer "B.Cu")
		(net "P3V3_AUX")
	)
	(segment
		(start 351.245932 -156.337)
		(end 351.245932 -156.889958)
		(width 0.4572)
		(layer "B.Cu")
		(net "P3V3_AUX")
	)
	(segment
		(start 299.650658 -225.780346)
		(end 299.650658 -225.094038)
		(width 0.4572)
		(layer "B.Cu")
		(net "P3V3_AUX")
	)
	(segment
		(start 294.871902 -199.86498)
		(end 294.475408 -200.261474)
		(width 0.4572)
		(layer "B.Cu")
		(net "P3V3_AUX")
	)
	(segment
		(start 388.490206 -236.32795)
		(end 387.925818 -236.892338)
		(width 0.4572)
		(layer "B.Cu")
		(net "P3V3_AUX")
	)
	(segment
		(start 402.930106 -373.424196)
		(end 402.930106 -368.291364)
		(width 0.4572)
		(layer "B.Cu")
		(net "P3V3_AUX")
	)
	(segment
		(start 300.425866 -246.041672)
		(end 302.338232 -246.041672)
		(width 0.4572)
		(layer "B.Cu")
		(net "P3V3_AUX")
	)
	(segment
		(start 458.025754 -252.112272)
		(end 458.512672 -251.625354)
		(width 0.381)
		(layer "B.Cu")
		(net "P3V3_AUX")
	)
	(segment
		(start 404.31085 -374.16486)
		(end 403.67077 -374.16486)
		(width 0.4572)
		(layer "B.Cu")
		(net "P3V3_AUX")
	)
	(segment
		(start 213.413086 -221.350586)
		(end 212.698584 -221.350586)
		(width 0.3048)
		(layer "B.Cu")
		(net "P3V3_AUX")
	)
	(segment
		(start 458.473556 -250.796044)
		(end 458.473556 -250.20524)
		(width 0.381)
		(layer "B.Cu")
		(net "P3V3_AUX")
	)
	(segment
		(start 257.502152 -244.466364)
		(end 255.960626 -242.924838)
		(width 0.4572)
		(layer "B.Cu")
		(net "P3V3_AUX")
	)
	(segment
		(start 287.964626 -139.199366)
		(end 287.964626 -140.181076)
		(width 0.4572)
		(layer "B.Cu")
		(net "P3V3_AUX")
	)
	(segment
		(start 457.03617 -252.112272)
		(end 458.025754 -252.112272)
		(width 0.381)
		(layer "B.Cu")
		(net "P3V3_AUX")
	)
	(segment
		(start 304.093626 -239.576356)
		(end 303.077626 -239.576356)
		(width 0.4572)
		(layer "B.Cu")
		(net "P3V3_AUX")
	)
	(segment
		(start 303.077626 -251.387356)
		(end 303.077626 -251.10567)
		(width 0.4572)
		(layer "B.Cu")
		(net "P3V3_AUX")
	)
	(segment
		(start 303.077626 -239.576356)
		(end 303.077626 -238.938562)
		(width 0.4572)
		(layer "B.Cu")
		(net "P3V3_AUX")
	)
	(segment
		(start 231.765348 -174.69358)
		(end 230.474774 -174.69358)
		(width 0.4572)
		(layer "B.Cu")
		(net "P3V3_AUX")
	)
	(segment
		(start 383.295652 -243.39296)
		(end 383.911348 -243.39296)
		(width 0.4572)
		(layer "B.Cu")
		(net "P3V3_AUX")
	)
	(segment
		(start 61.197236 -109.481366)
		(end 61.197236 -108.465366)
		(width 0.4572)
		(layer "B.Cu")
		(net "P3V3_AUX")
	)
	(segment
		(start 17.533112 -222.721932)
		(end 17.533112 -224.341182)
		(width 0.3556)
		(layer "B.Cu")
		(net "P3V3_AUX")
	)
	(segment
		(start 454.75017 -250.254516)
		(end 455.307446 -250.811792)
		(width 0.381)
		(layer "B.Cu")
		(net "P3V3_AUX")
	)
	(segment
		(start 341.905082 -285.959804)
		(end 341.905082 -286.28721)
		(width 0.381)
		(layer "B.Cu")
		(net "P3V3_AUX")
	)
	(segment
		(start 255.528826 -242.924838)
		(end 255.268476 -242.664488)
		(width 0.4572)
		(layer "B.Cu")
		(net "P3V3_AUX")
	)
	(segment
		(start 299.983398 -226.41179)
		(end 299.650658 -226.07905)
		(width 0.4572)
		(layer "B.Cu")
		(net "P3V3_AUX")
	)
	(segment
		(start 403.738334 -381.50292)
		(end 404.198582 -381.50292)
		(width 0.4572)
		(layer "B.Cu")
		(net "P3V3_AUX")
	)
	(segment
		(start 365.732314 -221.950534)
		(end 365.732314 -222.658432)
		(width 0.4572)
		(layer "B.Cu")
		(net "P3V3_AUX")
	)
	(segment
		(start 60.118244 -153.074624)
		(end 61.872622 -153.074624)
		(width 0.4572)
		(layer "B.Cu")
		(net "P3V3_AUX")
	)
	(segment
		(start 304.328576 -249.628406)
		(end 303.839626 -249.139456)
		(width 0.4572)
		(layer "B.Cu")
		(net "P3V3_AUX")
	)
	(segment
		(start 135.117586 -215.85682)
		(end 135.796528 -215.85682)
		(width 0.4572)
		(layer "B.Cu")
		(net "P3V3_AUX")
	)
	(segment
		(start 144.841214 -209.441796)
		(end 144.182084 -209.441796)
		(width 0.4572)
		(layer "B.Cu")
		(net "P3V3_AUX")
	)
	(segment
		(start 126.328678 -286.356806)
		(end 126.676658 -286.704786)
		(width 0.4572)
		(layer "B.Cu")
		(net "P3V3_AUX")
	)
	(segment
		(start 300.6725 -226.41179)
		(end 299.983398 -226.41179)
		(width 0.4572)
		(layer "B.Cu")
		(net "P3V3_AUX")
	)
	(segment
		(start 105.619042 -396.073884)
		(end 105.619042 -398.258284)
		(width 0.4572)
		(layer "B.Cu")
		(net "P3V3_AUX")
	)
	(segment
		(start 372.444518 -235.739432)
		(end 373.61495 -234.569)
		(width 0.4572)
		(layer "B.Cu")
		(net "P3V3_AUX")
	)
	(segment
		(start 213.306406 -226.441762)
		(end 213.306406 -226.67087)
		(width 0.4572)
		(layer "B.Cu")
		(net "P3V3_AUX")
	)
	(segment
		(start 350.012 -203.762102)
		(end 350.012 -207.37195)
		(width 0.4572)
		(layer "B.Cu")
		(net "P3V3_AUX")
	)
	(segment
		(start 233.867198 -218.30411)
		(end 233.467402 -217.904314)
		(width 0.3048)
		(layer "B.Cu")
		(net "P3V3_AUX")
	)
	(segment
		(start 262.045196 -243.332508)
		(end 262.045196 -243.811044)
		(width 0.4572)
		(layer "B.Cu")
		(net "P3V3_AUX")
	)
	(segment
		(start 55.7022 -158.343092)
		(end 55.73903 -158.379922)
		(width 0.4572)
		(layer "B.Cu")
		(net "P3V3_AUX")
	)
	(segment
		(start 130.939794 -206.241142)
		(end 131.71551 -206.241142)
		(width 0.4572)
		(layer "B.Cu")
		(net "P3V3_AUX")
	)
	(segment
		(start 141.631416 -204.949806)
		(end 142.494254 -204.949806)
		(width 0.4572)
		(layer "B.Cu")
		(net "P3V3_AUX")
	)
	(segment
		(start 252.230636 -195.26885)
		(end 254.282956 -195.26885)
		(width 0.4572)
		(layer "B.Cu")
		(net "P3V3_AUX")
	)
	(segment
		(start 226.667568 -220.704156)
		(end 226.267772 -221.103952)
		(width 0.3048)
		(layer "B.Cu")
		(net "P3V3_AUX")
	)
	(segment
		(start 302.552354 -237.819184)
		(end 302.552354 -237.136686)
		(width 0.4572)
		(layer "B.Cu")
		(net "P3V3_AUX")
	)
	(segment
		(start 403.813518 -366.518444)
		(end 403.813518 -367.407952)
		(width 0.4572)
		(layer "B.Cu")
		(net "P3V3_AUX")
	)
	(segment
		(start 228.106224 -232.57256)
		(end 228.106224 -231.938068)
		(width 0.254)
		(layer "B.Cu")
		(net "P3V3_AUX")
	)
	(segment
		(start 383.911348 -243.39296)
		(end 384.088894 -243.215414)
		(width 0.4572)
		(layer "B.Cu")
		(net "P3V3_AUX")
	)
	(segment
		(start 144.182084 -209.441796)
		(end 144.159986 -209.463894)
		(width 0.4572)
		(layer "B.Cu")
		(net "P3V3_AUX")
	)
	(segment
		(start 463.949542 -357.873046)
		(end 461.338676 -360.483912)
		(width 0.4572)
		(layer "B.Cu")
		(net "P3V3_AUX")
	)
	(segment
		(start 171.864528 -139.199366)
		(end 171.864528 -140.181076)
		(width 0.4572)
		(layer "B.Cu")
		(net "P3V3_AUX")
	)
	(segment
		(start 141.793214 -211.857844)
		(end 141.793214 -213.505796)
		(width 0.3556)
		(layer "B.Cu")
		(net "P3V3_AUX")
	)
	(segment
		(start 380.166372 -248.203974)
		(end 380.29769 -248.203974)
		(width 0.4572)
		(layer "B.Cu")
		(net "P3V3_AUX")
	)
	(segment
		(start 142.831312 -243.155978)
		(end 142.831312 -241.955828)
		(width 0.4572)
		(layer "B.Cu")
		(net "P3V3_AUX")
	)
	(segment
		(start 135.208264 -211.746846)
		(end 135.208264 -211.090256)
		(width 0.4572)
		(layer "B.Cu")
		(net "P3V3_AUX")
	)
	(segment
		(start 249.695716 -224.341182)
		(end 249.695716 -222.721932)
		(width 0.3556)
		(layer "B.Cu")
		(net "P3V3_AUX")
	)
	(segment
		(start 228.716332 -233.182668)
		(end 228.106224 -232.57256)
		(width 0.254)
		(layer "B.Cu")
		(net "P3V3_AUX")
	)
	(segment
		(start 408.559 -384.429)
		(end 408.051 -383.921)
		(width 0.4572)
		(layer "B.Cu")
		(net "P3V3_AUX")
	)
	(segment
		(start 146.76755 -244.298216)
		(end 144.40535 -244.298216)
		(width 0.4572)
		(layer "B.Cu")
		(net "P3V3_AUX")
	)
	(segment
		(start 17.469612 -221.950534)
		(end 17.469612 -222.658432)
		(width 0.4572)
		(layer "B.Cu")
		(net "P3V3_AUX")
	)
	(segment
		(start 381.162052 -221.955106)
		(end 381.162052 -222.590106)
		(width 0.4572)
		(layer "B.Cu")
		(net "P3V3_AUX")
	)
	(segment
		(start 230.187754 -174.40656)
		(end 228.6635 -174.40656)
		(width 0.4572)
		(layer "B.Cu")
		(net "P3V3_AUX")
	)
	(segment
		(start 409.497276 -107.612688)
		(end 409.497276 -108.465366)
		(width 0.4572)
		(layer "B.Cu")
		(net "P3V3_AUX")
	)
	(segment
		(start 254.592328 -253.098046)
		(end 256.888234 -255.393952)
		(width 0.4572)
		(layer "B.Cu")
		(net "P3V3_AUX")
	)
	(segment
		(start 409.497276 -110.497366)
		(end 409.497276 -109.481366)
		(width 0.4572)
		(layer "B.Cu")
		(net "P3V3_AUX")
	)
	(segment
		(start 301.604172 -117.108478)
		(end 302.199294 -116.513356)
		(width 0.4572)
		(layer "B.Cu")
		(net "P3V3_AUX")
	)
	(segment
		(start 404.832058 -374.16486)
		(end 404.31085 -374.16486)
		(width 0.4572)
		(layer "B.Cu")
		(net "P3V3_AUX")
	)
	(segment
		(start 261.71398 -243.001292)
		(end 262.045196 -243.332508)
		(width 0.4572)
		(layer "B.Cu")
		(net "P3V3_AUX")
	)
	(segment
		(start 228.801422 -223.637602)
		(end 228.667818 -223.503998)
		(width 0.4572)
		(layer "B.Cu")
		(net "P3V3_AUX")
	)
	(segment
		(start 55.94477 -159.956246)
		(end 56.200802 -160.212278)
		(width 0.4572)
		(layer "B.Cu")
		(net "P3V3_AUX")
	)
	(segment
		(start 228.746304 -224.667064)
		(end 228.801422 -224.611946)
		(width 0.4572)
		(layer "B.Cu")
		(net "P3V3_AUX")
	)
	(segment
		(start 248.892314 -222.653606)
		(end 249.62739 -222.653606)
		(width 0.4572)
		(layer "B.Cu")
		(net "P3V3_AUX")
	)
	(segment
		(start 402.930106 -368.291364)
		(end 403.813518 -367.407952)
		(width 0.4572)
		(layer "B.Cu")
		(net "P3V3_AUX")
	)
	(segment
		(start 227.267008 -175.803052)
		(end 227.071936 -175.803052)
		(width 0.2794)
		(layer "B.Cu")
		(net "P3V3_AUX")
	)
	(segment
		(start 388.963408 -242.056412)
		(end 388.398512 -242.056412)
		(width 0.4572)
		(layer "B.Cu")
		(net "P3V3_AUX")
	)
	(segment
		(start 341.905082 -286.28721)
		(end 342.2142 -286.596328)
		(width 0.381)
		(layer "B.Cu")
		(net "P3V3_AUX")
	)
	(segment
		(start 380.002288 -238.811054)
		(end 379.932184 -238.74095)
		(width 0.4572)
		(layer "B.Cu")
		(net "P3V3_AUX")
	)
	(segment
		(start 403.62505 -384.06705)
		(end 403.301708 -383.743708)
		(width 0.4572)
		(layer "B.Cu")
		(net "P3V3_AUX")
	)
	(segment
		(start 293.520368 -200.689464)
		(end 293.520368 -200.261474)
		(width 0.4572)
		(layer "B.Cu")
		(net "P3V3_AUX")
	)
	(segment
		(start 405.19604 -138.95705)
		(end 404.30704 -138.95705)
		(width 0.4572)
		(layer "B.Cu")
		(net "P3V3_AUX")
	)
	(segment
		(start 383.295652 -244.53596)
		(end 383.295652 -243.39296)
		(width 0.4572)
		(layer "B.Cu")
		(net "P3V3_AUX")
	)
	(segment
		(start 299.285914 -223.999552)
		(end 299.683932 -224.39757)
		(width 0.4572)
		(layer "B.Cu")
		(net "P3V3_AUX")
	)
	(segment
		(start 243.047266 -234.59313)
		(end 243.047266 -235.036868)
		(width 0.4572)
		(layer "B.Cu")
		(net "P3V3_AUX")
	)
	(segment
		(start 105.619042 -398.258284)
		(end 106.035094 -398.674336)
		(width 0.4572)
		(layer "B.Cu")
		(net "P3V3_AUX")
	)
	(segment
		(start 232.892092 -79.305912)
		(end 232.216706 -79.305912)
		(width 0.4572)
		(layer "B.Cu")
		(net "P3V3_AUX")
	)
	(segment
		(start 230.991664 -206.031338)
		(end 231.08539 -205.937612)
		(width 0.4572)
		(layer "B.Cu")
		(net "P3V3_AUX")
	)
	(segment
		(start 249.62739 -222.653606)
		(end 249.632216 -222.658432)
		(width 0.4572)
		(layer "B.Cu")
		(net "P3V3_AUX")
	)
	(segment
		(start 70.071742 -117.723666)
		(end 69.40423 -117.723666)
		(width 0.4572)
		(layer "B.Cu")
		(net "P3V3_AUX")
	)
	(segment
		(start 133.538214 -209.352896)
		(end 132.821172 -209.352896)
		(width 0.4572)
		(layer "B.Cu")
		(net "P3V3_AUX")
	)
	(segment
		(start 61.197236 -110.497366)
		(end 61.197236 -109.481366)
		(width 0.4572)
		(layer "B.Cu")
		(net "P3V3_AUX")
	)
	(segment
		(start 451.958202 -248.83364)
		(end 452.691246 -249.566684)
		(width 0.381)
		(layer "B.Cu")
		(net "P3V3_AUX")
	)
	(segment
		(start 302.877474 -224.56648)
		(end 302.806608 -224.637346)
		(width 0.4572)
		(layer "B.Cu")
		(net "P3V3_AUX")
	)
	(segment
		(start 381.162052 -222.590106)
		(end 382.683004 -222.590106)
		(width 0.3048)
		(layer "B.Cu")
		(net "P3V3_AUX")
	)
	(segment
		(start 225.530664 -204.04201)
		(end 225.530664 -203.40701)
		(width 0.4572)
		(layer "B.Cu")
		(net "P3V3_AUX")
	)
	(segment
		(start 11.499596 -212.977222)
		(end 11.696446 -212.780372)
		(width 0.381)
		(layer "B.Cu")
		(net "P3V3_AUX")
	)
	(segment
		(start 138.246866 -211.045806)
		(end 138.66241 -211.045806)
		(width 0.4572)
		(layer "B.Cu")
		(net "P3V3_AUX")
	)
	(segment
		(start 185.504074 -117.723666)
		(end 185.504074 -117.108478)
		(width 0.4572)
		(layer "B.Cu")
		(net "P3V3_AUX")
	)
	(segment
		(start 301.069248 -226.53879)
		(end 300.942248 -226.41179)
		(width 0.3556)
		(layer "B.Cu")
		(net "P3V3_AUX")
	)
	(segment
		(start 417.70427 -117.108478)
		(end 418.299392 -116.513356)
		(width 0.4572)
		(layer "B.Cu")
		(net "P3V3_AUX")
	)
	(segment
		(start 203.106274 -259.711698)
		(end 203.106274 -260.46176)
		(width 0.4572)
		(layer "B.Cu")
		(net "P3V3_AUX")
	)
	(segment
		(start 213.330282 -223.382586)
		(end 213.312248 -223.40062)
		(width 0.3048)
		(layer "B.Cu")
		(net "P3V3_AUX")
	)
	(segment
		(start 408.051 -383.921)
		(end 404.495 -383.921)
		(width 0.4572)
		(layer "B.Cu")
		(net "P3V3_AUX")
	)
	(segment
		(start 230.991664 -206.62011)
		(end 230.991664 -206.031338)
		(width 0.4572)
		(layer "B.Cu")
		(net "P3V3_AUX")
	)
	(segment
		(start 413.673544 -107.210352)
		(end 409.899612 -107.210352)
		(width 0.4572)
		(layer "B.Cu")
		(net "P3V3_AUX")
	)
	(segment
		(start 233.867706 -218.30411)
		(end 233.867198 -218.30411)
		(width 0.3048)
		(layer "B.Cu")
		(net "P3V3_AUX")
	)
	(segment
		(start 289.095942 -138.95705)
		(end 288.206942 -138.95705)
		(width 0.4572)
		(layer "B.Cu")
		(net "P3V3_AUX")
	)
	(segment
		(start 418.371782 -117.723666)
		(end 417.70427 -117.723666)
		(width 0.4572)
		(layer "B.Cu")
		(net "P3V3_AUX")
	)
	(segment
		(start 453.947784 -249.500136)
		(end 454.529698 -249.500136)
		(width 0.381)
		(layer "B.Cu")
		(net "P3V3_AUX")
	)
	(segment
		(start 226.667568 -217.504264)
		(end 226.267772 -217.104468)
		(width 0.3048)
		(layer "B.Cu")
		(net "P3V3_AUX")
	)
	(segment
		(start 452.691246 -249.566684)
		(end 453.613266 -249.566684)
		(width 0.381)
		(layer "B.Cu")
		(net "P3V3_AUX")
	)
	(segment
		(start 293.397178 -107.612688)
		(end 293.397178 -108.465366)
		(width 0.4572)
		(layer "B.Cu")
		(net "P3V3_AUX")
	)
	(segment
		(start 329.43038 -232.120948)
		(end 329.407266 -232.144062)
		(width 0.4572)
		(layer "B.Cu")
		(net "P3V3_AUX")
	)
	(segment
		(start 409.497276 -109.481366)
		(end 409.497276 -108.465366)
		(width 0.4572)
		(layer "B.Cu")
		(net "P3V3_AUX")
	)
	(segment
		(start 12.026646 -214.704422)
		(end 12.458446 -214.704422)
		(width 0.381)
		(layer "B.Cu")
		(net "P3V3_AUX")
	)
	(segment
		(start 404.064724 -139.199366)
		(end 404.064724 -140.181076)
		(width 0.4572)
		(layer "B.Cu")
		(net "P3V3_AUX")
	)
	(segment
		(start 361.076748 -346.87637)
		(end 361.076748 -359.722674)
		(width 0.4572)
		(layer "B.Cu")
		(net "P3V3_AUX")
	)
	(segment
		(start 343.80297 -201.05243)
		(end 345.51366 -202.76312)
		(width 0.4572)
		(layer "B.Cu")
		(net "P3V3_AUX")
	)
	(segment
		(start 300.942248 -226.41179)
		(end 300.6725 -226.41179)
		(width 0.3556)
		(layer "B.Cu")
		(net "P3V3_AUX")
	)
	(segment
		(start 379.932184 -238.74095)
		(end 379.349 -238.74095)
		(width 0.4572)
		(layer "B.Cu")
		(net "P3V3_AUX")
	)
	(segment
		(start 367.491518 -339.304884)
		(end 367.491518 -340.4616)
		(width 0.4572)
		(layer "B.Cu")
		(net "P3V3_AUX")
	)
	(segment
		(start 357.620316 -286.452818)
		(end 357.99395 -286.826452)
		(width 0.4572)
		(layer "B.Cu")
		(net "P3V3_AUX")
	)
	(segment
		(start 363.314996 -361.960922)
		(end 363.314996 -379.088396)
		(width 0.4572)
		(layer "B.Cu")
		(net "P3V3_AUX")
	)
	(segment
		(start 243.168932 -234.471464)
		(end 243.047266 -234.59313)
		(width 0.4572)
		(layer "B.Cu")
		(net "P3V3_AUX")
	)
	(segment
		(start 351.245932 -144.526)
		(end 351.245932 -145.078958)
		(width 0.4572)
		(layer "B.Cu")
		(net "P3V3_AUX")
	)
	(segment
		(start 235.986828 -94.421706)
		(end 236.205522 -94.6404)
		(width 0.254)
		(layer "B.Cu")
		(net "P3V3_AUX")
	)
	(segment
		(start 362.748068 -379.655324)
		(end 363.314996 -379.088396)
		(width 0.4572)
		(layer "B.Cu")
		(net "P3V3_AUX")
	)
	(segment
		(start 303.839626 -242.751356)
		(end 304.328576 -242.262406)
		(width 0.4572)
		(layer "B.Cu")
		(net "P3V3_AUX")
	)
	(segment
		(start 300.012354 -237.136686)
		(end 300.012354 -237.655354)
		(width 0.4572)
		(layer "B.Cu")
		(net "P3V3_AUX")
	)
	(segment
		(start 378.587 -241.70005)
		(end 377.869958 -241.70005)
		(width 0.4572)
		(layer "B.Cu")
		(net "P3V3_AUX")
	)
	(segment
		(start 209.63509 -288.830766)
		(end 209.3722 -289.093656)
		(width 0.4572)
		(layer "B.Cu")
		(net "P3V3_AUX")
	)
	(segment
		(start 389.23087 -241.78895)
		(end 388.963408 -242.056412)
		(width 0.4572)
		(layer "B.Cu")
		(net "P3V3_AUX")
	)
	(segment
		(start 222.23095 -203.790296)
		(end 222.23095 -203.389484)
		(width 0.4572)
		(layer "B.Cu")
		(net "P3V3_AUX")
	)
	(segment
		(start 222.482664 -204.04201)
		(end 222.23095 -203.790296)
		(width 0.4572)
		(layer "B.Cu")
		(net "P3V3_AUX")
	)
	(segment
		(start 380.25705 -243.43741)
		(end 380.25705 -244.094)
		(width 0.4572)
		(layer "B.Cu")
		(net "P3V3_AUX")
	)
	(segment
		(start 172.995844 -138.95705)
		(end 172.106844 -138.95705)
		(width 0.4572)
		(layer "B.Cu")
		(net "P3V3_AUX")
	)
	(segment
		(start 213.401148 -219.306902)
		(end 213.401148 -220.322902)
		(width 0.3048)
		(layer "B.Cu")
		(net "P3V3_AUX")
	)
	(segment
		(start 277.721822 -389.498078)
		(end 278.1935 -389.0264)
		(width 0.4572)
		(layer "B.Cu")
		(net "P3V3_AUX")
	)
	(segment
		(start 293.281608 -200.928224)
		(end 293.520368 -200.689464)
		(width 0.4572)
		(layer "B.Cu")
		(net "P3V3_AUX")
	)
	(segment
		(start 404.34895 -384.06705)
		(end 403.62505 -384.06705)
		(width 0.4572)
		(layer "B.Cu")
		(net "P3V3_AUX")
	)
	(segment
		(start 329.43038 -231.538526)
		(end 329.43038 -232.120948)
		(width 0.4572)
		(layer "B.Cu")
		(net "P3V3_AUX")
	)
	(segment
		(start 348.077536 -254.55372)
		(end 347.732858 -254.55372)
		(width 0.4572)
		(layer "B.Cu")
		(net "P3V3_AUX")
	)
	(segment
		(start 235.29417 -94.421706)
		(end 235.986828 -94.421706)
		(width 0.254)
		(layer "B.Cu")
		(net "P3V3_AUX")
	)
	(segment
		(start 213.306406 -226.67087)
		(end 214.078058 -227.442522)
		(width 0.4572)
		(layer "B.Cu")
		(net "P3V3_AUX")
	)
	(segment
		(start 411.888686 -360.483912)
		(end 406.484582 -365.888016)
		(width 0.4572)
		(layer "B.Cu")
		(net "P3V3_AUX")
	)
	(segment
		(start 256.888234 -255.393952)
		(end 256.888234 -255.983232)
		(width 0.4572)
		(layer "B.Cu")
		(net "P3V3_AUX")
	)
	(segment
		(start 403.67077 -374.16486)
		(end 402.930106 -373.424196)
		(width 0.4572)
		(layer "B.Cu")
		(net "P3V3_AUX")
	)
	(segment
		(start 386.680202 -238.173768)
		(end 386.641086 -238.212884)
		(width 0.4572)
		(layer "B.Cu")
		(net "P3V3_AUX")
	)
	(segment
		(start 255.198626 -242.594638)
		(end 255.198626 -241.000788)
		(width 0.4572)
		(layer "B.Cu")
		(net "P3V3_AUX")
	)
	(segment
		(start 461.166972 -329.880976)
		(end 463.949542 -332.663546)
		(width 0.4572)
		(layer "B.Cu")
		(net "P3V3_AUX")
	)
	(segment
		(start 360.902758 -379.655324)
		(end 362.748068 -379.655324)
		(width 0.4572)
		(layer "B.Cu")
		(net "P3V3_AUX")
	)
	(segment
		(start 417.70427 -117.723666)
		(end 417.70427 -117.108478)
		(width 0.4572)
		(layer "B.Cu")
		(net "P3V3_AUX")
	)
	(segment
		(start 406.119076 -372.877842)
		(end 404.832058 -374.16486)
		(width 0.4572)
		(layer "B.Cu")
		(net "P3V3_AUX")
	)
	(segment
		(start 458.512672 -251.625354)
		(end 458.512672 -250.83516)
		(width 0.381)
		(layer "B.Cu")
		(net "P3V3_AUX")
	)
	(segment
		(start 328.78014 -201.05243)
		(end 343.80297 -201.05243)
		(width 0.4572)
		(layer "B.Cu")
		(net "P3V3_AUX")
	)
	(segment
		(start 207.510126 -222.65767)
		(end 207.634586 -222.65767)
		(width 0.4572)
		(layer "B.Cu")
		(net "P3V3_AUX")
	)
	(segment
		(start 108.711238 -286.446214)
		(end 109.054392 -286.789368)
		(width 0.4572)
		(layer "B.Cu")
		(net "P3V3_AUX")
	)
	(segment
		(start 55.73903 -159.750506)
		(end 55.94477 -159.956246)
		(width 0.4572)
		(layer "B.Cu")
		(net "P3V3_AUX")
	)
	(segment
		(start 214.829136 -179.194206)
		(end 210.765136 -179.194206)
		(width 0.4572)
		(layer "B.Cu")
		(net "P3V3_AUX")
	)
	(segment
		(start 213.401148 -221.338648)
		(end 213.413086 -221.350586)
		(width 0.3048)
		(layer "B.Cu")
		(net "P3V3_AUX")
	)
	(segment
		(start 406.484582 -365.888016)
		(end 406.233376 -365.63681)
		(width 0.4572)
		(layer "B.Cu")
		(net "P3V3_AUX")
	)
	(segment
		(start 357.620316 -286.013398)
		(end 357.620316 -286.452818)
		(width 0.4572)
		(layer "B.Cu")
		(net "P3V3_AUX")
	)
	(segment
		(start 406.232614 -365.636556)
		(end 404.695406 -365.636556)
		(width 0.4572)
		(layer "B.Cu")
		(net "P3V3_AUX")
	)
	(segment
		(start 55.73903 -158.379922)
		(end 55.73903 -159.750506)
		(width 0.4572)
		(layer "B.Cu")
		(net "P3V3_AUX")
	)
	(segment
		(start 302.061626 -251.387356)
		(end 303.077626 -251.387356)
		(width 0.4572)
		(layer "B.Cu")
		(net "P3V3_AUX")
	)
	(segment
		(start 134.883398 -206.393796)
		(end 134.300214 -206.393796)
		(width 0.4572)
		(layer "B.Cu")
		(net "P3V3_AUX")
	)
	(segment
		(start 230.66756 -222.304102)
		(end 231.067356 -222.703898)
		(width 0.3048)
		(layer "B.Cu")
		(net "P3V3_AUX")
	)
	(segment
		(start 13.051282 -215.297258)
		(end 15.38351 -215.297258)
		(width 0.381)
		(layer "B.Cu")
		(net "P3V3_AUX")
	)
	(segment
		(start 389.89 -236.32795)
		(end 388.490206 -236.32795)
		(width 0.4572)
		(layer "B.Cu")
		(net "P3V3_AUX")
	)
	(segment
		(start 262.045196 -243.811044)
		(end 261.389876 -244.466364)
		(width 0.4572)
		(layer "B.Cu")
		(net "P3V3_AUX")
	)
	(segment
		(start 17.469612 -222.658432)
		(end 17.533112 -222.721932)
		(width 0.3556)
		(layer "B.Cu")
		(net "P3V3_AUX")
	)
	(segment
		(start 386.842 -245.85295)
		(end 387.352032 -245.85295)
		(width 0.4572)
		(layer "B.Cu")
		(net "P3V3_AUX")
	)
	(segment
		(start 256.224786 -256.64668)
		(end 256.224786 -260.0706)
		(width 0.4572)
		(layer "B.Cu")
		(net "P3V3_AUX")
	)
	(segment
		(start 56.007 -138.95705)
		(end 55.764684 -139.199366)
		(width 0.4572)
		(layer "B.Cu")
		(net "P3V3_AUX")
	)
	(segment
		(start 293.799514 -107.210352)
		(end 293.397178 -107.612688)
		(width 0.4572)
		(layer "B.Cu")
		(net "P3V3_AUX")
	)
	(segment
		(start 207.879188 -227.04679)
		(end 207.879188 -227.35794)
		(width 0.4572)
		(layer "B.Cu")
		(net "P3V3_AUX")
	)
	(segment
		(start 352.11893 -233.95305)
		(end 352.80092 -233.95305)
		(width 0.4572)
		(layer "B.Cu")
		(net "P3V3_AUX")
	)
	(segment
		(start 261.71398 -242.372388)
		(end 261.71398 -243.001292)
		(width 0.4572)
		(layer "B.Cu")
		(net "P3V3_AUX")
	)
	(segment
		(start 329.407266 -232.633266)
		(end 329.692 -232.918)
		(width 0.4572)
		(layer "B.Cu")
		(net "P3V3_AUX")
	)
	(segment
		(start 455.307446 -251.35586)
		(end 456.279758 -251.35586)
		(width 0.381)
		(layer "B.Cu")
		(net "P3V3_AUX")
	)
	(segment
		(start 138.246866 -212.188806)
		(end 138.246866 -211.045806)
		(width 0.4572)
		(layer "B.Cu")
		(net "P3V3_AUX")
	)
	(segment
		(start 454.529698 -249.500136)
		(end 454.75017 -249.720608)
		(width 0.381)
		(layer "B.Cu")
		(net "P3V3_AUX")
	)
	(segment
		(start 207.634586 -222.65767)
		(end 209.101436 -221.19082)
		(width 0.4572)
		(layer "B.Cu")
		(net "P3V3_AUX")
	)
	(segment
		(start 213.312248 -223.40062)
		(end 212.695282 -223.40062)
		(width 0.3048)
		(layer "B.Cu")
		(net "P3V3_AUX")
	)
	(segment
		(start 299.650658 -226.07905)
		(end 299.650658 -225.780346)
		(width 0.4572)
		(layer "B.Cu")
		(net "P3V3_AUX")
	)
	(segment
		(start 301.536354 -234.558586)
		(end 301.536354 -233.934)
		(width 0.4572)
		(layer "B.Cu")
		(net "P3V3_AUX")
	)
	(segment
		(start 403.813518 -367.407952)
		(end 405.596344 -367.407952)
		(width 0.4572)
		(layer "B.Cu")
		(net "P3V3_AUX")
	)
	(segment
		(start 404.198582 -381.50292)
		(end 404.198582 -374.277128)
		(width 0.4572)
		(layer "B.Cu")
		(net "P3V3_AUX")
	)
	(segment
		(start 147.574254 -205.987142)
		(end 148.209254 -205.987142)
		(width 0.4572)
		(layer "B.Cu")
		(net "P3V3_AUX")
	)
	(segment
		(start 302.877474 -223.999552)
		(end 302.877474 -224.56648)
		(width 0.4572)
		(layer "B.Cu")
		(net "P3V3_AUX")
	)
	(segment
		(start 261.389876 -244.466364)
		(end 257.502152 -244.466364)
		(width 0.4572)
		(layer "B.Cu")
		(net "P3V3_AUX")
	)
	(segment
		(start 375.98858 -236.556296)
		(end 376.661934 -236.556296)
		(width 0.4572)
		(layer "B.Cu")
		(net "P3V3_AUX")
	)
	(segment
		(start 378.88545 -238.2774)
		(end 378.079 -238.2774)
		(width 0.4572)
		(layer "B.Cu")
		(net "P3V3_AUX")
	)
	(segment
		(start 347.732858 -254.55372)
		(end 347.330776 -254.955802)
		(width 0.4572)
		(layer "B.Cu")
		(net "P3V3_AUX")
	)
	(segment
		(start 345.51366 -202.76312)
		(end 349.013018 -202.76312)
		(width 0.4572)
		(layer "B.Cu")
		(net "P3V3_AUX")
	)
	(segment
		(start 62.865762 -153.074624)
		(end 62.874144 -153.083006)
		(width 0.4572)
		(layer "B.Cu")
		(net "P3V3_AUX")
	)
	(segment
		(start 185.504074 -117.108478)
		(end 186.099196 -116.513356)
		(width 0.4572)
		(layer "B.Cu")
		(net "P3V3_AUX")
	)
	(segment
		(start 454.75017 -249.720608)
		(end 454.75017 -250.254516)
		(width 0.381)
		(layer "B.Cu")
		(net "P3V3_AUX")
	)
	(segment
		(start 351.245932 -156.889958)
		(end 351.436432 -157.080458)
		(width 0.4572)
		(layer "B.Cu")
		(net "P3V3_AUX")
	)
	(segment
		(start 56.896 -138.95705)
		(end 56.007 -138.95705)
		(width 0.4572)
		(layer "B.Cu")
		(net "P3V3_AUX")
	)
	(segment
		(start 133.836664 -205.930246)
		(end 133.030214 -205.930246)
		(width 0.4572)
		(layer "B.Cu")
		(net "P3V3_AUX")
	)
	(segment
		(start 302.271684 -117.723666)
		(end 301.604172 -117.723666)
		(width 0.4572)
		(layer "B.Cu")
		(net "P3V3_AUX")
	)
	(segment
		(start 55.73903 -158.379922)
		(end 57.861962 -158.379922)
		(width 0.4572)
		(layer "B.Cu")
		(net "P3V3_AUX")
	)
	(segment
		(start 213.30666 -225.42246)
		(end 212.67166 -225.42246)
		(width 0.4572)
		(layer "B.Cu")
		(net "P3V3_AUX")
	)
	(segment
		(start 351.245932 -145.078958)
		(end 351.436432 -145.269458)
		(width 0.4572)
		(layer "B.Cu")
		(net "P3V3_AUX")
	)
	(segment
		(start 299.067474 -223.999552)
		(end 299.285914 -223.999552)
		(width 0.4572)
		(layer "B.Cu")
		(net "P3V3_AUX")
	)
	(segment
		(start 387.352032 -245.85295)
		(end 387.498082 -245.999)
		(width 0.4572)
		(layer "B.Cu")
		(net "P3V3_AUX")
	)
	(segment
		(start 11.499596 -214.177372)
		(end 11.499596 -212.977222)
		(width 0.381)
		(layer "B.Cu")
		(net "P3V3_AUX")
	)
	(segment
		(start 108.711238 -285.976568)
		(end 108.711238 -286.446214)
		(width 0.4572)
		(layer "B.Cu")
		(net "P3V3_AUX")
	)
	(segment
		(start 303.839626 -249.139456)
		(end 303.839626 -248.087388)
		(width 0.4572)
		(layer "B.Cu")
		(net "P3V3_AUX")
	)
	(segment
		(start 254.592328 -249.462798)
		(end 254.592328 -253.098046)
		(width 0.4572)
		(layer "B.Cu")
		(net "P3V3_AUX")
	)
	(segment
		(start 12.458446 -214.704422)
		(end 13.051282 -215.297258)
		(width 0.381)
		(layer "B.Cu")
		(net "P3V3_AUX")
	)
	(segment
		(start 135.208264 -213.694264)
		(end 135.208264 -213.524846)
		(width 0.4572)
		(layer "B.Cu")
		(net "P3V3_AUX")
	)
	(segment
		(start 453.613266 -249.566684)
		(end 453.947784 -249.500136)
		(width 0.381)
		(layer "B.Cu")
		(net "P3V3_AUX")
	)
	(segment
		(start 463.949542 -332.663546)
		(end 463.949542 -357.873046)
		(width 0.4572)
		(layer "B.Cu")
		(net "P3V3_AUX")
	)
	(segment
		(start 61.872622 -153.074624)
		(end 62.865762 -153.074624)
		(width 0.4572)
		(layer "B.Cu")
		(net "P3V3_AUX")
	)
	(segment
		(start 186.171586 -117.723666)
		(end 185.504074 -117.723666)
		(width 0.4572)
		(layer "B.Cu")
		(net "P3V3_AUX")
	)
	(segment
		(start 255.268476 -242.664488)
		(end 255.198626 -242.594638)
		(width 0.4572)
		(layer "B.Cu")
		(net "P3V3_AUX")
	)
	(segment
		(start 404.495 -383.921)
		(end 404.34895 -384.06705)
		(width 0.4572)
		(layer "B.Cu")
		(net "P3V3_AUX")
	)
	(segment
		(start 278.94915 -384.403092)
		(end 278.15032 -384.403092)
		(width 0.4572)
		(layer "B.Cu")
		(net "P3V3_AUX")
	)
	(segment
		(start 380.739142 -246.354092)
		(end 380.25705 -245.872)
		(width 0.4572)
		(layer "B.Cu")
		(net "P3V3_AUX")
	)
	(segment
		(start 380.247652 -243.428012)
		(end 380.25705 -243.43741)
		(width 0.4572)
		(layer "B.Cu")
		(net "P3V3_AUX")
	)
	(segment
		(start 301.069248 -227.520754)
		(end 301.069248 -226.53879)
		(width 0.3556)
		(layer "B.Cu")
		(net "P3V3_AUX")
	)
	(segment
		(start 227.643436 -175.426624)
		(end 227.267008 -175.803052)
		(width 0.2794)
		(layer "B.Cu")
		(net "P3V3_AUX")
	)
	(segment
		(start 134.300214 -206.393796)
		(end 133.836664 -205.930246)
		(width 0.4572)
		(layer "B.Cu")
		(net "P3V3_AUX")
	)
	(segment
		(start 124.309124 -202.579732)
		(end 124.731272 -202.157584)
		(width 0.4572)
		(layer "B.Cu")
		(net "P3V3_AUX")
	)
	(segment
		(start 329.407266 -232.144062)
		(end 329.407266 -232.633266)
		(width 0.4572)
		(layer "B.Cu")
		(net "P3V3_AUX")
	)
	(segment
		(start 379.349 -238.74095)
		(end 378.88545 -238.2774)
		(width 0.4572)
		(layer "B.Cu")
		(net "P3V3_AUX")
	)
	(segment
		(start 365.732314 -222.658432)
		(end 365.795814 -222.721932)
		(width 0.3556)
		(layer "B.Cu")
		(net "P3V3_AUX")
	)
	(segment
		(start 297.54703 -107.210352)
		(end 293.799514 -107.210352)
		(width 0.4572)
		(layer "B.Cu")
		(net "P3V3_AUX")
	)
	(segment
		(start 373.61495 -234.569)
		(end 373.61495 -233.82605)
		(width 0.4572)
		(layer "B.Cu")
		(net "P3V3_AUX")
	)
	(segment
		(start 213.330282 -224.398586)
		(end 213.330282 -225.398838)
		(width 0.4572)
		(layer "B.Cu")
		(net "P3V3_AUX")
	)
	(segment
		(start 304.455576 -250.263406)
		(end 304.455576 -249.755406)
		(width 0.4572)
		(layer "B.Cu")
		(net "P3V3_AUX")
	)
	(segment
		(start 228.106224 -231.938068)
		(end 228.418644 -231.625648)
		(width 0.254)
		(layer "B.Cu")
		(net "P3V3_AUX")
	)
	(segment
		(start 255.049528 -249.005598)
		(end 254.592328 -249.462798)
		(width 0.4572)
		(layer "B.Cu")
		(net "P3V3_AUX")
	)
	(segment
		(start 386.842 -244.204998)
		(end 386.842 -245.85295)
		(width 0.254)
		(layer "B.Cu")
		(net "P3V3_AUX")
	)
	(segment
		(start 213.330282 -225.398838)
		(end 213.30666 -225.42246)
		(width 0.4572)
		(layer "B.Cu")
		(net "P3V3_AUX")
	)
	(segment
		(start 380.739142 -247.762522)
		(end 380.739142 -246.354092)
		(width 0.4572)
		(layer "B.Cu")
		(net "P3V3_AUX")
	)
	(segment
		(start 212.90788 -214.24646)
		(end 212.900006 -214.238586)
		(width 0.4572)
		(layer "B.Cu")
		(net "P3V3_AUX")
	)
	(segment
		(start 288.206942 -138.95705)
		(end 287.964626 -139.199366)
		(width 0.4572)
		(layer "B.Cu")
		(net "P3V3_AUX")
	)
	(segment
		(start 56.200802 -160.212278)
		(end 56.200802 -160.674812)
		(width 0.4572)
		(layer "B.Cu")
		(net "P3V3_AUX")
	)
	(segment
		(start 409.899612 -107.210352)
		(end 409.497276 -107.612688)
		(width 0.4572)
		(layer "B.Cu")
		(net "P3V3_AUX")
	)
	(segment
		(start 232.216706 -79.305912)
		(end 231.916478 -79.005684)
		(width 0.4572)
		(layer "B.Cu")
		(net "P3V3_AUX")
	)
	(segment
		(start 144.841214 -203.980796)
		(end 144.17675 -203.980796)
		(width 0.4572)
		(layer "B.Cu")
		(net "P3V3_AUX")
	)
	(segment
		(start 406.233376 -365.63681)
		(end 406.232614 -365.636556)
		(width 0.4572)
		(layer "B.Cu")
		(net "P3V3_AUX")
	)
	(segment
		(start 204.077062 -288.75736)
		(end 204.077062 -288.221166)
		(width 0.4572)
		(layer "B.Cu")
		(net "P3V3_AUX")
	)
	(segment
		(start 294.475408 -200.261474)
		(end 293.520368 -200.261474)
		(width 0.4572)
		(layer "B.Cu")
		(net "P3V3_AUX")
	)
	(segment
		(start 380.29769 -248.203974)
		(end 380.739142 -247.762522)
		(width 0.4572)
		(layer "B.Cu")
		(net "P3V3_AUX")
	)
	(segment
		(start 455.307446 -250.811792)
		(end 455.307446 -251.35586)
		(width 0.381)
		(layer "B.Cu")
		(net "P3V3_AUX")
	)
	(segment
		(start 213.535006 -215.272874)
		(end 213.535006 -214.24646)
		(width 0.4572)
		(layer "B.Cu")
		(net "P3V3_AUX")
	)
	(segment
		(start 404.695406 -365.636556)
		(end 403.813518 -366.518444)
		(width 0.4572)
		(layer "B.Cu")
		(net "P3V3_AUX")
	)
	(segment
		(start 228.267768 -222.304102)
		(end 227.867972 -222.703898)
		(width 0.3048)
		(layer "B.Cu")
		(net "P3V3_AUX")
	)
	(segment
		(start 127.272796 -203.392278)
		(end 127.395732 -203.392278)
		(width 0.4572)
		(layer "B.Cu")
		(net "P3V3_AUX")
	)
	(segment
		(start 380.254002 -236.40796)
		(end 380.254002 -237.236)
		(width 0.4572)
		(layer "B.Cu")
		(net "P3V3_AUX")
	)
	(segment
		(start 249.695716 -222.721932)
		(end 249.632216 -222.658432)
		(width 0.3556)
		(layer "B.Cu")
		(net "P3V3_AUX")
	)
	(segment
		(start 108.138214 -285.038038)
		(end 108.138214 -284.024324)
		(width 0.4572)
		(layer "In5.Cu")
		(net "P3V3_AUX")
	)
	(segment
		(start 12.095734 -345.85783)
		(end 13.1953 -357.023162)
		(width 0.4572)
		(layer "In5.Cu")
		(net "P3V3_AUX")
	)
	(segment
		(start 107.771438 -283.657548)
		(end 104.586278 -283.657548)
		(width 0.4572)
		(layer "In5.Cu")
		(net "P3V3_AUX")
	)
	(segment
		(start 347.27769 -260.359144)
		(end 348.191328 -259.445506)
		(width 0.4572)
		(layer "In5.Cu")
		(net "P3V3_AUX")
	)
	(segment
		(start 102.606094 -283.70022)
		(end 94.770448 -283.70022)
		(width 0.4572)
		(layer "In5.Cu")
		(net "P3V3_AUX")
	)
	(segment
		(start 388.398512 -242.056412)
		(end 389.098282 -241.356642)
		(width 0.4572)
		(layer "In5.Cu")
		(net "P3V3_AUX")
	)
	(segment
		(start 328.952606 -280.615898)
		(end 336.326226 -280.615898)
		(width 0.4572)
		(layer "In5.Cu")
		(net "P3V3_AUX")
	)
	(segment
		(start 340.361016 -282.622752)
		(end 340.361016 -284.395418)
		(width 0.4572)
		(layer "In5.Cu")
		(net "P3V3_AUX")
	)
	(segment
		(start 111.181134 -262.246364)
		(end 111.181134 -258.66471)
		(width 0.4572)
		(layer "In5.Cu")
		(net "P3V3_AUX")
	)
	(segment
		(start 388.080504 -236.892338)
		(end 387.925818 -236.892338)
		(width 0.4572)
		(layer "In5.Cu")
		(net "P3V3_AUX")
	)
	(segment
		(start 348.55658 -252.210316)
		(end 350.980502 -249.786394)
		(width 0.4572)
		(layer "In5.Cu")
		(net "P3V3_AUX")
	)
	(segment
		(start 104.45369 -283.52496)
		(end 102.781354 -283.52496)
		(width 0.4572)
		(layer "In5.Cu")
		(net "P3V3_AUX")
	)
	(segment
		(start 115.13058 -255.428242)
		(end 115.13058 -254.955802)
		(width 0.4572)
		(layer "In5.Cu")
		(net "P3V3_AUX")
	)
	(segment
		(start 5.995162 -368.23269)
		(end 5.995162 -366.177322)
		(width 0.4572)
		(layer "In5.Cu")
		(net "P3V3_AUX")
	)
	(segment
		(start 17.267174 -380.692914)
		(end 15.41145 -371.364256)
		(width 0.4572)
		(layer "In5.Cu")
		(net "P3V3_AUX")
	)
	(segment
		(start 111.638334 -262.703564)
		(end 111.181134 -262.246364)
		(width 0.4572)
		(layer "In5.Cu")
		(net "P3V3_AUX")
	)
	(segment
		(start 348.191328 -259.445506)
		(end 348.191328 -257.935222)
		(width 0.4572)
		(layer "In5.Cu")
		(net "P3V3_AUX")
	)
	(segment
		(start 389.098282 -241.356642)
		(end 389.098282 -237.910116)
		(width 0.4572)
		(layer "In5.Cu")
		(net "P3V3_AUX")
	)
	(segment
		(start 22.787356 -392.71321)
		(end 20.064222 -389.990076)
		(width 0.4572)
		(layer "In5.Cu")
		(net "P3V3_AUX")
	)
	(segment
		(start 348.55658 -253.729998)
		(end 348.55658 -252.210316)
		(width 0.4572)
		(layer "In5.Cu")
		(net "P3V3_AUX")
	)
	(segment
		(start 345.164664 -262.703564)
		(end 345.767406 -262.100822)
		(width 0.4572)
		(layer "In5.Cu")
		(net "P3V3_AUX")
	)
	(segment
		(start 345.767406 -262.100822)
		(end 345.767406 -260.590538)
		(width 0.4572)
		(layer "In5.Cu")
		(net "P3V3_AUX")
	)
	(segment
		(start 109.054392 -286.789368)
		(end 109.054392 -285.954216)
		(width 0.4572)
		(layer "In5.Cu")
		(net "P3V3_AUX")
	)
	(segment
		(start 342.2142 -286.248602)
		(end 342.2142 -286.596328)
		(width 0.4572)
		(layer "In5.Cu")
		(net "P3V3_AUX")
	)
	(segment
		(start 5.995162 -366.177322)
		(end 6.780276 -365.392208)
		(width 0.4572)
		(layer "In5.Cu")
		(net "P3V3_AUX")
	)
	(segment
		(start 387.925818 -236.928152)
		(end 386.641086 -238.212884)
		(width 0.4572)
		(layer "In5.Cu")
		(net "P3V3_AUX")
	)
	(segment
		(start 389.098282 -237.910116)
		(end 388.080504 -236.892338)
		(width 0.4572)
		(layer "In5.Cu")
		(net "P3V3_AUX")
	)
	(segment
		(start 387.925818 -236.892338)
		(end 387.925818 -236.928152)
		(width 0.4572)
		(layer "In5.Cu")
		(net "P3V3_AUX")
	)
	(segment
		(start 19.075908 -387.228588)
		(end 17.267174 -380.692914)
		(width 0.4572)
		(layer "In5.Cu")
		(net "P3V3_AUX")
	)
	(segment
		(start 12.279884 -368.23269)
		(end 5.995162 -368.23269)
		(width 0.4572)
		(layer "In5.Cu")
		(net "P3V3_AUX")
	)
	(segment
		(start 20.064222 -389.990076)
		(end 19.075908 -387.228588)
		(width 0.4572)
		(layer "In5.Cu")
		(net "P3V3_AUX")
	)
	(segment
		(start 13.1953 -362.933488)
		(end 10.73658 -365.392208)
		(width 0.4572)
		(layer "In5.Cu")
		(net "P3V3_AUX")
	)
	(segment
		(start 12.095734 -341.292688)
		(end 12.095734 -345.85783)
		(width 0.4572)
		(layer "In5.Cu")
		(net "P3V3_AUX")
	)
	(segment
		(start 21.79701 -400.174968)
		(end 22.787356 -399.184622)
		(width 0.4572)
		(layer "In5.Cu")
		(net "P3V3_AUX")
	)
	(segment
		(start 94.770448 -283.70022)
		(end 92.899992 -285.570676)
		(width 0.4572)
		(layer "In5.Cu")
		(net "P3V3_AUX")
	)
	(segment
		(start 345.767406 -260.590538)
		(end 345.9988 -260.359144)
		(width 0.4572)
		(layer "In5.Cu")
		(net "P3V3_AUX")
	)
	(segment
		(start 350.980502 -249.786394)
		(end 356.876096 -249.786394)
		(width 0.4572)
		(layer "In5.Cu")
		(net "P3V3_AUX")
	)
	(segment
		(start 111.638334 -258.20751)
		(end 112.351312 -258.20751)
		(width 0.4572)
		(layer "In5.Cu")
		(net "P3V3_AUX")
	)
	(segment
		(start 339.713316 -281.975052)
		(end 340.361016 -282.622752)
		(width 0.4572)
		(layer "In5.Cu")
		(net "P3V3_AUX")
	)
	(segment
		(start 104.586278 -283.657548)
		(end 104.45369 -283.52496)
		(width 0.4572)
		(layer "In5.Cu")
		(net "P3V3_AUX")
	)
	(segment
		(start 340.361016 -284.395418)
		(end 342.2142 -286.248602)
		(width 0.4572)
		(layer "In5.Cu")
		(net "P3V3_AUX")
	)
	(segment
		(start 347.330776 -257.07467)
		(end 347.330776 -254.955802)
		(width 0.4572)
		(layer "In5.Cu")
		(net "P3V3_AUX")
	)
	(segment
		(start 112.351312 -258.20751)
		(end 115.13058 -255.428242)
		(width 0.4572)
		(layer "In5.Cu")
		(net "P3V3_AUX")
	)
	(segment
		(start 111.181134 -258.66471)
		(end 111.638334 -258.20751)
		(width 0.4572)
		(layer "In5.Cu")
		(net "P3V3_AUX")
	)
	(segment
		(start 92.899992 -285.570676)
		(end 92.899992 -288.11855)
		(width 0.4572)
		(layer "In5.Cu")
		(net "P3V3_AUX")
	)
	(segment
		(start 344.74531 -262.703564)
		(end 345.164664 -262.703564)
		(width 0.4572)
		(layer "In5.Cu")
		(net "P3V3_AUX")
	)
	(segment
		(start 359.13568 -252.045978)
		(end 359.820972 -252.045978)
		(width 0.4572)
		(layer "In5.Cu")
		(net "P3V3_AUX")
	)
	(segment
		(start 337.68538 -281.975052)
		(end 339.713316 -281.975052)
		(width 0.4572)
		(layer "In5.Cu")
		(net "P3V3_AUX")
	)
	(segment
		(start 18.997676 -400.91614)
		(end 19.738848 -400.174968)
		(width 0.4572)
		(layer "In5.Cu")
		(net "P3V3_AUX")
	)
	(segment
		(start 19.738848 -400.174968)
		(end 21.79701 -400.174968)
		(width 0.4572)
		(layer "In5.Cu")
		(net "P3V3_AUX")
	)
	(segment
		(start 109.054392 -285.954216)
		(end 108.138214 -285.038038)
		(width 0.4572)
		(layer "In5.Cu")
		(net "P3V3_AUX")
	)
	(segment
		(start 112.545114 -262.703564)
		(end 111.638334 -262.703564)
		(width 0.4572)
		(layer "In5.Cu")
		(net "P3V3_AUX")
	)
	(segment
		(start 15.41145 -371.364256)
		(end 12.279884 -368.23269)
		(width 0.4572)
		(layer "In5.Cu")
		(net "P3V3_AUX")
	)
	(segment
		(start 108.138214 -284.024324)
		(end 107.771438 -283.657548)
		(width 0.4572)
		(layer "In5.Cu")
		(net "P3V3_AUX")
	)
	(segment
		(start 102.781354 -283.52496)
		(end 102.606094 -283.70022)
		(width 0.4572)
		(layer "In5.Cu")
		(net "P3V3_AUX")
	)
	(segment
		(start 356.876096 -249.786394)
		(end 359.13568 -252.045978)
		(width 0.4572)
		(layer "In5.Cu")
		(net "P3V3_AUX")
	)
	(segment
		(start 324.050152 -285.518352)
		(end 328.952606 -280.615898)
		(width 0.4572)
		(layer "In5.Cu")
		(net "P3V3_AUX")
	)
	(segment
		(start 16.748252 -400.91614)
		(end 18.997676 -400.91614)
		(width 0.4572)
		(layer "In5.Cu")
		(net "P3V3_AUX")
	)
	(segment
		(start 345.9988 -260.359144)
		(end 347.27769 -260.359144)
		(width 0.4572)
		(layer "In5.Cu")
		(net "P3V3_AUX")
	)
	(segment
		(start 6.780276 -365.392208)
		(end 7.58444 -365.392208)
		(width 0.4572)
		(layer "In5.Cu")
		(net "P3V3_AUX")
	)
	(segment
		(start 348.191328 -257.935222)
		(end 347.330776 -257.07467)
		(width 0.4572)
		(layer "In5.Cu")
		(net "P3V3_AUX")
	)
	(segment
		(start 336.326226 -280.615898)
		(end 337.68538 -281.975052)
		(width 0.4572)
		(layer "In5.Cu")
		(net "P3V3_AUX")
	)
	(segment
		(start 22.787356 -399.184622)
		(end 22.787356 -392.71321)
		(width 0.4572)
		(layer "In5.Cu")
		(net "P3V3_AUX")
	)
	(segment
		(start 347.330776 -254.955802)
		(end 348.55658 -253.729998)
		(width 0.4572)
		(layer "In5.Cu")
		(net "P3V3_AUX")
	)
	(segment
		(start 13.1953 -357.023162)
		(end 13.1953 -362.933488)
		(width 0.4572)
		(layer "In5.Cu")
		(net "P3V3_AUX")
	)
	(segment
		(start 10.73658 -365.392208)
		(end 7.58444 -365.392208)
		(width 0.4572)
		(layer "In5.Cu")
		(net "P3V3_AUX")
	)
	(segment
		(start 122.349768 -282.176474)
		(end 120.874028 -280.700734)
		(width 0.4572)
		(layer "In7.Cu")
		(net "P3V3_AUX")
	)
	(segment
		(start 340.817454 -283.116528)
		(end 340.817454 -284.331918)
		(width 0.4572)
		(layer "In7.Cu")
		(net "P3V3_AUX")
	)
	(segment
		(start 109.898434 -281.074622)
		(end 109.736128 -281.466544)
		(width 0.4572)
		(layer "In7.Cu")
		(net "P3V3_AUX")
	)
	(segment
		(start 248.132092 -249.005598)
		(end 245.280434 -251.857256)
		(width 0.4572)
		(layer "In7.Cu")
		(net "P3V3_AUX")
	)
	(segment
		(start 114.036094 -281.964384)
		(end 112.724692 -280.652982)
		(width 0.4572)
		(layer "In7.Cu")
		(net "P3V3_AUX")
	)
	(segment
		(start 115.894358 -281.964384)
		(end 114.036094 -281.964384)
		(width 0.4572)
		(layer "In7.Cu")
		(net "P3V3_AUX")
	)
	(segment
		(start 109.736128 -282.261564)
		(end 108.706158 -283.291534)
		(width 0.4572)
		(layer "In7.Cu")
		(net "P3V3_AUX")
	)
	(segment
		(start 202.175872 -368.129566)
		(end 202.175872 -370.105686)
		(width 0.4572)
		(layer "In7.Cu")
		(net "P3V3_AUX")
	)
	(segment
		(start 349.428308 -282.63342)
		(end 348.616778 -282.63342)
		(width 0.4572)
		(layer "In7.Cu")
		(net "P3V3_AUX")
	)
	(segment
		(start 204.197966 -373.617998)
		(end 204.197966 -374.359424)
		(width 0.4572)
		(layer "In7.Cu")
		(net "P3V3_AUX")
	)
	(segment
		(start 350.50095 -281.072336)
		(end 350.50095 -281.560778)
		(width 0.4572)
		(layer "In7.Cu")
		(net "P3V3_AUX")
	)
	(segment
		(start 116.552472 -282.622498)
		(end 115.894358 -281.964384)
		(width 0.4572)
		(layer "In7.Cu")
		(net "P3V3_AUX")
	)
	(segment
		(start 205.777592 -352.662744)
		(end 200.579736 -357.8606)
		(width 0.4572)
		(layer "In7.Cu")
		(net "P3V3_AUX")
	)
	(segment
		(start 357.99395 -286.826452)
		(end 357.99395 -285.35884)
		(width 0.4572)
		(layer "In7.Cu")
		(net "P3V3_AUX")
	)
	(segment
		(start 257.553714 -345.653868)
		(end 258.016502 -345.19108)
		(width 0.4572)
		(layer "In7.Cu")
		(net "P3V3_AUX")
	)
	(segment
		(start 110.320074 -280.652982)
		(end 109.898434 -281.074622)
		(width 0.4572)
		(layer "In7.Cu")
		(net "P3V3_AUX")
	)
	(segment
		(start 199.016366 -367.095786)
		(end 201.142092 -367.095786)
		(width 0.4572)
		(layer "In7.Cu")
		(net "P3V3_AUX")
	)
	(segment
		(start 126.676658 -286.704786)
		(end 126.676658 -285.994094)
		(width 0.4572)
		(layer "In7.Cu")
		(net "P3V3_AUX")
	)
	(segment
		(start 342.2142 -285.728664)
		(end 342.2142 -286.596328)
		(width 0.4572)
		(layer "In7.Cu")
		(net "P3V3_AUX")
	)
	(segment
		(start 202.175872 -370.105686)
		(end 203.228448 -371.158262)
		(width 0.4572)
		(layer "In7.Cu")
		(net "P3V3_AUX")
	)
	(segment
		(start 342.408002 -280.61031)
		(end 342.19896 -280.819352)
		(width 0.4572)
		(layer "In7.Cu")
		(net "P3V3_AUX")
	)
	(segment
		(start 350.50095 -281.560778)
		(end 349.428308 -282.63342)
		(width 0.4572)
		(layer "In7.Cu")
		(net "P3V3_AUX")
	)
	(segment
		(start 200.579736 -358.958896)
		(end 198.21779 -361.320842)
		(width 0.4572)
		(layer "In7.Cu")
		(net "P3V3_AUX")
	)
	(segment
		(start 357.476806 -283.04744)
		(end 356.637844 -282.208478)
		(width 0.4572)
		(layer "In7.Cu")
		(net "P3V3_AUX")
	)
	(segment
		(start 198.21779 -366.29721)
		(end 199.016366 -367.095786)
		(width 0.4572)
		(layer "In7.Cu")
		(net "P3V3_AUX")
	)
	(segment
		(start 118.676674 -280.700734)
		(end 118.219474 -281.157934)
		(width 0.4572)
		(layer "In7.Cu")
		(net "P3V3_AUX")
	)
	(segment
		(start 342.19896 -280.819352)
		(end 342.03513 -281.215084)
		(width 0.4572)
		(layer "In7.Cu")
		(net "P3V3_AUX")
	)
	(segment
		(start 117.412516 -282.622498)
		(end 116.552472 -282.622498)
		(width 0.4572)
		(layer "In7.Cu")
		(net "P3V3_AUX")
	)
	(segment
		(start 124.974096 -284.291532)
		(end 124.974096 -282.645358)
		(width 0.4572)
		(layer "In7.Cu")
		(net "P3V3_AUX")
	)
	(segment
		(start 205.777592 -349.220536)
		(end 205.777592 -352.662744)
		(width 0.4572)
		(layer "In7.Cu")
		(net "P3V3_AUX")
	)
	(segment
		(start 203.228448 -371.158262)
		(end 203.228448 -372.64848)
		(width 0.4572)
		(layer "In7.Cu")
		(net "P3V3_AUX")
	)
	(segment
		(start 354.206556 -282.208478)
		(end 352.688144 -280.690066)
		(width 0.4572)
		(layer "In7.Cu")
		(net "P3V3_AUX")
	)
	(segment
		(start 108.706158 -283.291534)
		(end 108.706158 -286.441134)
		(width 0.4572)
		(layer "In7.Cu")
		(net "P3V3_AUX")
	)
	(segment
		(start 118.219474 -281.157934)
		(end 118.219474 -281.81554)
		(width 0.4572)
		(layer "In7.Cu")
		(net "P3V3_AUX")
	)
	(segment
		(start 346.413582 -282.214066)
		(end 344.809826 -280.61031)
		(width 0.4572)
		(layer "In7.Cu")
		(net "P3V3_AUX")
	)
	(segment
		(start 348.616778 -282.63342)
		(end 348.197424 -282.214066)
		(width 0.4572)
		(layer "In7.Cu")
		(net "P3V3_AUX")
	)
	(segment
		(start 112.724692 -280.652982)
		(end 110.320074 -280.652982)
		(width 0.4572)
		(layer "In7.Cu")
		(net "P3V3_AUX")
	)
	(segment
		(start 203.228448 -372.64848)
		(end 204.197966 -373.617998)
		(width 0.4572)
		(layer "In7.Cu")
		(net "P3V3_AUX")
	)
	(segment
		(start 357.99395 -285.35884)
		(end 357.476806 -284.841696)
		(width 0.4572)
		(layer "In7.Cu")
		(net "P3V3_AUX")
	)
	(segment
		(start 356.637844 -282.208478)
		(end 354.206556 -282.208478)
		(width 0.4572)
		(layer "In7.Cu")
		(net "P3V3_AUX")
	)
	(segment
		(start 124.974096 -282.645358)
		(end 124.505212 -282.176474)
		(width 0.4572)
		(layer "In7.Cu")
		(net "P3V3_AUX")
	)
	(segment
		(start 348.197424 -282.214066)
		(end 346.413582 -282.214066)
		(width 0.4572)
		(layer "In7.Cu")
		(net "P3V3_AUX")
	)
	(segment
		(start 126.676658 -285.994094)
		(end 124.974096 -284.291532)
		(width 0.4572)
		(layer "In7.Cu")
		(net "P3V3_AUX")
	)
	(segment
		(start 109.736128 -281.466544)
		(end 109.736128 -282.261564)
		(width 0.4572)
		(layer "In7.Cu")
		(net "P3V3_AUX")
	)
	(segment
		(start 352.688144 -280.690066)
		(end 350.88322 -280.690066)
		(width 0.4572)
		(layer "In7.Cu")
		(net "P3V3_AUX")
	)
	(segment
		(start 120.874028 -280.700734)
		(end 118.676674 -280.700734)
		(width 0.4572)
		(layer "In7.Cu")
		(net "P3V3_AUX")
	)
	(segment
		(start 204.197966 -374.359424)
		(end 203.731368 -374.826022)
		(width 0.4572)
		(layer "In7.Cu")
		(net "P3V3_AUX")
	)
	(segment
		(start 198.21779 -361.320842)
		(end 198.21779 -366.29721)
		(width 0.4572)
		(layer "In7.Cu")
		(net "P3V3_AUX")
	)
	(segment
		(start 342.009476 -281.924506)
		(end 340.817454 -283.116528)
		(width 0.4572)
		(layer "In7.Cu")
		(net "P3V3_AUX")
	)
	(segment
		(start 255.580388 -249.005598)
		(end 248.132092 -249.005598)
		(width 0.4572)
		(layer "In7.Cu")
		(net "P3V3_AUX")
	)
	(segment
		(start 200.579736 -357.8606)
		(end 200.579736 -358.958896)
		(width 0.4572)
		(layer "In7.Cu")
		(net "P3V3_AUX")
	)
	(segment
		(start 118.219474 -281.81554)
		(end 117.412516 -282.622498)
		(width 0.4572)
		(layer "In7.Cu")
		(net "P3V3_AUX")
	)
	(segment
		(start 342.009476 -281.343608)
		(end 342.009476 -281.924506)
		(width 0.4572)
		(layer "In7.Cu")
		(net "P3V3_AUX")
	)
	(segment
		(start 207.059276 -339.1281)
		(end 207.059276 -339.128354)
		(width 0.1651)
		(layer "In7.Cu")
		(net "P3V3_AUX")
	)
	(segment
		(start 201.142092 -367.095786)
		(end 202.175872 -368.129566)
		(width 0.4572)
		(layer "In7.Cu")
		(net "P3V3_AUX")
	)
	(segment
		(start 350.88322 -280.690066)
		(end 350.50095 -281.072336)
		(width 0.4572)
		(layer "In7.Cu")
		(net "P3V3_AUX")
	)
	(segment
		(start 357.476806 -284.841696)
		(end 357.476806 -283.04744)
		(width 0.4572)
		(layer "In7.Cu")
		(net "P3V3_AUX")
	)
	(segment
		(start 124.505212 -282.176474)
		(end 122.349768 -282.176474)
		(width 0.4572)
		(layer "In7.Cu")
		(net "P3V3_AUX")
	)
	(segment
		(start 203.731368 -374.826022)
		(end 203.025756 -374.826022)
		(width 0.4572)
		(layer "In7.Cu")
		(net "P3V3_AUX")
	)
	(segment
		(start 108.706158 -286.441134)
		(end 109.054392 -286.789368)
		(width 0.4572)
		(layer "In7.Cu")
		(net "P3V3_AUX")
	)
	(segment
		(start 344.809826 -280.61031)
		(end 342.408002 -280.61031)
		(width 0.4572)
		(layer "In7.Cu")
		(net "P3V3_AUX")
	)
	(segment
		(start 342.03513 -281.215084)
		(end 342.009476 -281.343608)
		(width 0.4572)
		(layer "In7.Cu")
		(net "P3V3_AUX")
	)
	(segment
		(start 340.817454 -284.331918)
		(end 342.2142 -285.728664)
		(width 0.4572)
		(layer "In7.Cu")
		(net "P3V3_AUX")
	)
	(segment
		(start 208.711546 -291.757608)
		(end 209.076036 -292.122098)
		(width 0.4572)
		(layer "In9.Cu")
		(net "P3V3_AUX")
	)
	(segment
		(start 274.444714 -371.449092)
		(end 278.299672 -375.30405)
		(width 0.4572)
		(layer "In9.Cu")
		(net "P3V3_AUX")
	)
	(segment
		(start 208.711546 -289.75431)
		(end 208.711546 -291.757608)
		(width 0.4572)
		(layer "In9.Cu")
		(net "P3V3_AUX")
	)
	(segment
		(start 259.932932 -346.435934)
		(end 258.33578 -346.435934)
		(width 0.4572)
		(layer "In9.Cu")
		(net "P3V3_AUX")
	)
	(segment
		(start 260.714998 -345.653868)
		(end 263.12495 -345.653868)
		(width 0.4572)
		(layer "In9.Cu")
		(net "P3V3_AUX")
	)
	(segment
		(start 276.908768 -389.0264)
		(end 278.1935 -389.0264)
		(width 0.4572)
		(layer "In9.Cu")
		(net "P3V3_AUX")
	)
	(segment
		(start 275.153882 -387.752082)
		(end 275.63445 -387.752082)
		(width 0.4572)
		(layer "In9.Cu")
		(net "P3V3_AUX")
	)
	(segment
		(start 209.076036 -292.122098)
		(end 209.738976 -292.122098)
		(width 0.4572)
		(layer "In9.Cu")
		(net "P3V3_AUX")
	)
	(segment
		(start 259.932932 -346.435934)
		(end 260.714998 -345.653868)
		(width 0.4572)
		(layer "In9.Cu")
		(net "P3V3_AUX")
	)
	(segment
		(start 272.93951 -371.449092)
		(end 274.444714 -371.449092)
		(width 0.4572)
		(layer "In9.Cu")
		(net "P3V3_AUX")
	)
	(segment
		(start 264.19556 -355.971094)
		(end 270.413734 -362.189268)
		(width 0.4572)
		(layer "In9.Cu")
		(net "P3V3_AUX")
	)
	(segment
		(start 258.33578 -346.435934)
		(end 257.553714 -345.653868)
		(width 0.4572)
		(layer "In9.Cu")
		(net "P3V3_AUX")
	)
	(segment
		(start 364.540038 -261.206488)
		(end 369.638834 -261.206488)
		(width 0.4572)
		(layer "In9.Cu")
		(net "P3V3_AUX")
	)
	(segment
		(start 278.299672 -375.30405)
		(end 278.299672 -384.25374)
		(width 0.4572)
		(layer "In9.Cu")
		(net "P3V3_AUX")
	)
	(segment
		(start 264.19556 -346.724478)
		(end 264.19556 -355.971094)
		(width 0.4572)
		(layer "In9.Cu")
		(net "P3V3_AUX")
	)
	(segment
		(start 263.12495 -345.653868)
		(end 264.19556 -346.724478)
		(width 0.4572)
		(layer "In9.Cu")
		(net "P3V3_AUX")
	)
	(segment
		(start 369.638834 -261.206488)
		(end 370.774722 -260.0706)
		(width 0.4572)
		(layer "In9.Cu")
		(net "P3V3_AUX")
	)
	(segment
		(start 275.63445 -387.752082)
		(end 276.908768 -389.0264)
		(width 0.4572)
		(layer "In9.Cu")
		(net "P3V3_AUX")
	)
	(segment
		(start 278.299672 -384.25374)
		(end 278.15032 -384.403092)
		(width 0.4572)
		(layer "In9.Cu")
		(net "P3V3_AUX")
	)
	(segment
		(start 370.774722 -260.0706)
		(end 372.324884 -260.0706)
		(width 0.4572)
		(layer "In9.Cu")
		(net "P3V3_AUX")
	)
	(segment
		(start 270.413734 -368.923316)
		(end 272.93951 -371.449092)
		(width 0.4572)
		(layer "In9.Cu")
		(net "P3V3_AUX")
	)
	(segment
		(start 209.63509 -288.830766)
		(end 208.711546 -289.75431)
		(width 0.4572)
		(layer "In9.Cu")
		(net "P3V3_AUX")
	)
	(segment
		(start 270.413734 -362.189268)
		(end 270.413734 -368.923316)
		(width 0.4572)
		(layer "In9.Cu")
		(net "P3V3_AUX")
	)
	(segment
		(start 325.734934 -287.203134)
		(end 324.050152 -285.518352)
		(width 0.4572)
		(layer "In11.Cu")
		(net "P3V3_AUX")
	)
	(segment
		(start 92.899992 -288.11855)
		(end 92.899992 -289.174174)
		(width 0.4572)
		(layer "In11.Cu")
		(net "P3V3_AUX")
	)
	(segment
		(start 92.45473 -291.328094)
		(end 92.45473 -289.619436)
		(width 0.4572)
		(layer "In11.Cu")
		(net "P3V3_AUX")
	)
	(segment
		(start 325.734934 -288.830766)
		(end 325.734934 -287.203134)
		(width 0.4572)
		(layer "In11.Cu")
		(net "P3V3_AUX")
	)
	(segment
		(start 92.45473 -289.619436)
		(end 92.499434 -289.574732)
		(width 0.4572)
		(layer "In11.Cu")
		(net "P3V3_AUX")
	)
	(segment
		(start 88.22817 -289.574732)
		(end 87.976964 -289.323526)
		(width 0.4572)
		(layer "In11.Cu")
		(net "P3V3_AUX")
	)
	(segment
		(start 325.734934 -280.702512)
		(end 325.734934 -283.83357)
		(width 0.4572)
		(layer "In11.Cu")
		(net "P3V3_AUX")
	)
	(segment
		(start 327.61809 -254.259588)
		(end 327.61809 -259.877814)
		(width 0.4572)
		(layer "In11.Cu")
		(net "P3V3_AUX")
	)
	(segment
		(start 93.638878 -292.122098)
		(end 93.248734 -292.122098)
		(width 0.4572)
		(layer "In11.Cu")
		(net "P3V3_AUX")
	)
	(segment
		(start 92.499434 -289.574732)
		(end 88.22817 -289.574732)
		(width 0.4572)
		(layer "In11.Cu")
		(net "P3V3_AUX")
	)
	(segment
		(start 327.511156 -254.152654)
		(end 327.61809 -254.259588)
		(width 0.4572)
		(layer "In11.Cu")
		(net "P3V3_AUX")
	)
	(segment
		(start 93.248734 -292.122098)
		(end 92.45473 -291.328094)
		(width 0.4572)
		(layer "In11.Cu")
		(net "P3V3_AUX")
	)
	(segment
		(start 87.976964 -284.063694)
		(end 82.8294 -271.638014)
		(width 0.4572)
		(layer "In11.Cu")
		(net "P3V3_AUX")
	)
	(segment
		(start 87.976964 -289.323526)
		(end 87.976964 -288.221166)
		(width 0.4572)
		(layer "In11.Cu")
		(net "P3V3_AUX")
	)
	(segment
		(start 325.734934 -283.83357)
		(end 324.050152 -285.518352)
		(width 0.4572)
		(layer "In11.Cu")
		(net "P3V3_AUX")
	)
	(segment
		(start 87.976964 -288.221166)
		(end 87.976964 -284.063694)
		(width 0.4572)
		(layer "In11.Cu")
		(net "P3V3_AUX")
	)
	(segment
		(start 92.899992 -289.174174)
		(end 92.499434 -289.574732)
		(width 0.4572)
		(layer "In11.Cu")
		(net "P3V3_AUX")
	)
	(segment
		(start 329.972416 -276.46503)
		(end 325.734934 -280.702512)
		(width 0.4572)
		(layer "In11.Cu")
		(net "P3V3_AUX")
	)
	(segment
		(start 329.972416 -262.23214)
		(end 329.972416 -276.46503)
		(width 0.4572)
		(layer "In11.Cu")
		(net "P3V3_AUX")
	)
	(segment
		(start 82.8294 -259.8674)
		(end 71.62292 -248.66092)
		(width 0.4572)
		(layer "In11.Cu")
		(net "P3V3_AUX")
	)
	(segment
		(start 82.8294 -271.638014)
		(end 82.8294 -259.8674)
		(width 0.4572)
		(layer "In11.Cu")
		(net "P3V3_AUX")
	)
	(segment
		(start 327.61809 -259.877814)
		(end 329.972416 -262.23214)
		(width 0.4572)
		(layer "In11.Cu")
		(net "P3V3_AUX")
	)
	(segment
		(start 71.62292 -248.66092)
		(end 71.62292 -242.297204)
		(width 0.4572)
		(layer "In11.Cu")
		(net "P3V3_AUX")
	)
	(segment
		(start 18.739104 -262.090916)
		(end 22.317456 -262.090916)
		(width 0.4572)
		(layer "In13.Cu")
		(net "P3V3_AUX")
	)
	(segment
		(start 224.1677 -45.39996)
		(end 224.1677 -50.701956)
		(width 0.4572)
		(layer "In13.Cu")
		(net "P3V3_AUX")
	)
	(segment
		(start 96.042226 -242.238784)
		(end 96.366584 -241.914426)
		(width 0.4572)
		(layer "In13.Cu")
		(net "P3V3_AUX")
	)
	(segment
		(start 340.28634 -45.39488)
		(end 340.28634 -50.68316)
		(width 0.4572)
		(layer "In13.Cu")
		(net "P3V3_AUX")
	)
	(segment
		(start 202.026266 -179.522628)
		(end 193.84772 -187.701174)
		(width 0.4572)
		(layer "In13.Cu")
		(net "P3V3_AUX")
	)
	(segment
		(start 221.415102 -44.87291)
		(end 223.64065 -44.87291)
		(width 0.4572)
		(layer "In13.Cu")
		(net "P3V3_AUX")
	)
	(segment
		(start 209.724498 -179.522628)
		(end 202.026266 -179.522628)
		(width 0.4572)
		(layer "In13.Cu")
		(net "P3V3_AUX")
	)
	(segment
		(start 223.64065 -44.87291)
		(end 224.1677 -45.39996)
		(width 0.4572)
		(layer "In13.Cu")
		(net "P3V3_AUX")
	)
	(segment
		(start 98.085656 -241.914426)
		(end 99.071938 -240.928144)
		(width 0.4572)
		(layer "In13.Cu")
		(net "P3V3_AUX")
	)
	(segment
		(start 222.8342 -52.035456)
		(end 221.42323 -52.035456)
		(width 0.4572)
		(layer "In13.Cu")
		(net "P3V3_AUX")
	)
	(segment
		(start 210.765136 -179.194206)
		(end 210.05292 -179.194206)
		(width 0.4572)
		(layer "In13.Cu")
		(net "P3V3_AUX")
	)
	(segment
		(start 139.532868 -260.662674)
		(end 133.230874 -260.662674)
		(width 0.4572)
		(layer "In13.Cu")
		(net "P3V3_AUX")
	)
	(segment
		(start 289.095942 -139.5984)
		(end 289.146742 -139.6492)
		(width 0.4572)
		(layer "In13.Cu")
		(net "P3V3_AUX")
	)
	(segment
		(start 339.76437 -44.87291)
		(end 340.28634 -45.39488)
		(width 0.4572)
		(layer "In13.Cu")
		(net "P3V3_AUX")
	)
	(segment
		(start 289.095942 -138.95705)
		(end 289.095942 -139.5984)
		(width 0.4572)
		(layer "In13.Cu")
		(net "P3V3_AUX")
	)
	(segment
		(start 140.124942 -260.0706)
		(end 139.532868 -260.662674)
		(width 0.4572)
		(layer "In13.Cu")
		(net "P3V3_AUX")
	)
	(segment
		(start 18.728436 -262.080248)
		(end 18.739104 -262.090916)
		(width 0.4572)
		(layer "In13.Cu")
		(net "P3V3_AUX")
	)
	(segment
		(start 337.514946 -44.87291)
		(end 339.76437 -44.87291)
		(width 0.4572)
		(layer "In13.Cu")
		(net "P3V3_AUX")
	)
	(segment
		(start 293.413688 -138.95705)
		(end 289.095942 -138.95705)
		(width 0.4572)
		(layer "In13.Cu")
		(net "P3V3_AUX")
	)
	(segment
		(start 193.84772 -187.701174)
		(end 183.175402 -187.701174)
		(width 0.4572)
		(layer "In13.Cu")
		(net "P3V3_AUX")
	)
	(segment
		(start 104.435656 -51.597052)
		(end 104.87406 -52.035456)
		(width 0.4572)
		(layer "In13.Cu")
		(net "P3V3_AUX")
	)
	(segment
		(start 210.05292 -179.194206)
		(end 209.724498 -179.522628)
		(width 0.4572)
		(layer "In13.Cu")
		(net "P3V3_AUX")
	)
	(segment
		(start 224.1677 -50.701956)
		(end 222.8342 -52.035456)
		(width 0.4572)
		(layer "In13.Cu")
		(net "P3V3_AUX")
	)
	(segment
		(start 340.28634 -50.68316)
		(end 338.934044 -52.035456)
		(width 0.4572)
		(layer "In13.Cu")
		(net "P3V3_AUX")
	)
	(segment
		(start 99.071938 -240.928144)
		(end 99.79914 -240.928144)
		(width 0.4572)
		(layer "In13.Cu")
		(net "P3V3_AUX")
	)
	(segment
		(start 338.934044 -52.035456)
		(end 337.523074 -52.035456)
		(width 0.4572)
		(layer "In13.Cu")
		(net "P3V3_AUX")
	)
	(segment
		(start 133.230874 -260.662674)
		(end 130.699764 -258.131564)
		(width 0.4572)
		(layer "In13.Cu")
		(net "P3V3_AUX")
	)
	(segment
		(start 104.87406 -52.035456)
		(end 105.323132 -52.035456)
		(width 0.4572)
		(layer "In13.Cu")
		(net "P3V3_AUX")
	)
	(segment
		(start 294.52189 -137.848848)
		(end 293.413688 -138.95705)
		(width 0.4572)
		(layer "In13.Cu")
		(net "P3V3_AUX")
	)
	(segment
		(start 24.024844 -260.383528)
		(end 24.024844 -260.0706)
		(width 0.4572)
		(layer "In13.Cu")
		(net "P3V3_AUX")
	)
	(segment
		(start 104.435656 -48.531272)
		(end 104.435656 -51.597052)
		(width 0.4572)
		(layer "In13.Cu")
		(net "P3V3_AUX")
	)
	(segment
		(start 96.366584 -241.914426)
		(end 98.085656 -241.914426)
		(width 0.4572)
		(layer "In13.Cu")
		(net "P3V3_AUX")
	)
	(segment
		(start 103.30815 -47.403766)
		(end 104.435656 -48.531272)
		(width 0.4572)
		(layer "In13.Cu")
		(net "P3V3_AUX")
	)
	(segment
		(start 22.317456 -262.090916)
		(end 24.024844 -260.383528)
		(width 0.4572)
		(layer "In13.Cu")
		(net "P3V3_AUX")
	)
	(segment
		(start 209.63509 -288.830766)
		(end 215.429846 -283.03601)
		(width 0.4572)
		(layer "In15.Cu")
		(net "P3V3_AUX")
	)
	(segment
		(start 243.93525 -279.201372)
		(end 246.435118 -279.201372)
		(width 0.4572)
		(layer "In15.Cu")
		(net "P3V3_AUX")
	)
	(segment
		(start 226.785424 -280.10104)
		(end 227.685092 -279.201372)
		(width 0.4572)
		(layer "In15.Cu")
		(net "P3V3_AUX")
	)
	(segment
		(start 230.18496 -279.201372)
		(end 230.834946 -278.551386)
		(width 0.4572)
		(layer "In15.Cu")
		(net "P3V3_AUX")
	)
	(segment
		(start 243.035582 -280.10104)
		(end 243.93525 -279.201372)
		(width 0.4572)
		(layer "In15.Cu")
		(net "P3V3_AUX")
	)
	(segment
		(start 460.806038 -279.324816)
		(end 461.456024 -278.67483)
		(width 0.4572)
		(layer "In15.Cu")
		(net "P3V3_AUX")
	)
	(segment
		(start 215.429846 -283.03601)
		(end 223.850454 -283.03601)
		(width 0.4572)
		(layer "In15.Cu")
		(net "P3V3_AUX")
	)
	(segment
		(start 458.30617 -279.324816)
		(end 460.806038 -279.324816)
		(width 0.4572)
		(layer "In15.Cu")
		(net "P3V3_AUX")
	)
	(segment
		(start 227.685092 -279.201372)
		(end 230.18496 -279.201372)
		(width 0.4572)
		(layer "In15.Cu")
		(net "P3V3_AUX")
	)
	(segment
		(start 457.406502 -280.224484)
		(end 458.30617 -279.324816)
		(width 0.4572)
		(layer "In15.Cu")
		(net "P3V3_AUX")
	)
	(segment
		(start 246.435118 -279.201372)
		(end 247.085104 -278.551386)
		(width 0.4572)
		(layer "In15.Cu")
		(net "P3V3_AUX")
	)
	(segment
		(start 223.850454 -283.03601)
		(end 226.785424 -280.10104)
		(width 0.4572)
		(layer "In15.Cu")
		(net "P3V3_AUX")
	)
	(segment
		(start 122.575828 -255.627124)
		(end 122.757438 -255.445514)
		(width 0.13208)
		(layer "F.Cu")
		(net "SMB_VR_P0V8_PEX0_SCL")
	)
	(segment
		(start 124.715524 -254.612648)
		(end 124.715524 -254.126238)
		(width 0.13208)
		(layer "F.Cu")
		(net "SMB_VR_P0V8_PEX0_SCL")
	)
	(segment
		(start 124.715524 -253.092204)
		(end 124.715524 -254.126238)
		(width 0.13208)
		(layer "F.Cu")
		(net "SMB_VR_P0V8_PEX0_SCL")
	)
	(segment
		(start 124.991114 -252.816614)
		(end 124.715524 -253.092204)
		(width 0.13208)
		(layer "F.Cu")
		(net "SMB_VR_P0V8_PEX0_SCL")
	)
	(segment
		(start 123.882658 -255.445514)
		(end 124.715524 -254.612648)
		(width 0.13208)
		(layer "F.Cu")
		(net "SMB_VR_P0V8_PEX0_SCL")
	)
	(segment
		(start 122.575828 -255.994916)
		(end 122.575828 -255.627124)
		(width 0.13208)
		(layer "F.Cu")
		(net "SMB_VR_P0V8_PEX0_SCL")
	)
	(segment
		(start 122.757438 -255.445514)
		(end 123.882658 -255.445514)
		(width 0.13208)
		(layer "F.Cu")
		(net "SMB_VR_P0V8_PEX0_SCL")
	)
	(via
		(at 124.715524 -254.126238)
		(size 0.762)
		(drill 0.381)
		(layers "F.Cu" "B.Cu")
		(net "SMB_VR_P0V8_PEX0_SCL")
	)
	(segment
		(start 123.175776 -260.19506)
		(end 125.832616 -260.19506)
		(width 0.13208)
		(layer "F.Cu")
		(net "FM_P0V8_PEX1_EN_R")
	)
	(segment
		(start 127.230124 -261.592568)
		(end 127.230124 -261.786624)
		(width 0.13208)
		(layer "F.Cu")
		(net "FM_P0V8_PEX1_EN_R")
	)
	(segment
		(start 125.832616 -260.19506)
		(end 126.256542 -260.618986)
		(width 0.13208)
		(layer "F.Cu")
		(net "FM_P0V8_PEX1_EN_R")
	)
	(segment
		(start 127.441452 -262.442198)
		(end 127.258064 -262.25881)
		(width 0.13208)
		(layer "F.Cu")
		(net "FM_P0V8_PEX1_EN_R")
	)
	(segment
		(start 126.256542 -260.618986)
		(end 127.230124 -261.592568)
		(width 0.13208)
		(layer "F.Cu")
		(net "FM_P0V8_PEX1_EN_R")
	)
	(segment
		(start 129.290064 -261.814564)
		(end 129.290064 -262.259572)
		(width 0.13208)
		(layer "F.Cu")
		(net "FM_P0V8_PEX1_EN_R")
	)
	(segment
		(start 127.230124 -261.786624)
		(end 127.258064 -261.814564)
		(width 0.13208)
		(layer "F.Cu")
		(net "FM_P0V8_PEX1_EN_R")
	)
	(segment
		(start 129.107438 -262.442198)
		(end 127.441452 -262.442198)
		(width 0.13208)
		(layer "F.Cu")
		(net "FM_P0V8_PEX1_EN_R")
	)
	(segment
		(start 127.258064 -262.25881)
		(end 127.258064 -261.814564)
		(width 0.13208)
		(layer "F.Cu")
		(net "FM_P0V8_PEX1_EN_R")
	)
	(segment
		(start 129.290064 -262.259572)
		(end 129.107438 -262.442198)
		(width 0.13208)
		(layer "F.Cu")
		(net "FM_P0V8_PEX1_EN_R")
	)
	(via
		(at 126.256542 -260.618986)
		(size 0.762)
		(drill 0.381)
		(layers "F.Cu" "B.Cu")
		(net "FM_P0V8_PEX1_EN_R")
	)
	(segment
		(start 117.512338 -256.994914)
		(end 118.375684 -256.994914)
		(width 0.1778)
		(layer "F.Cu")
		(net "P0V8_PEX0_VDD")
	)
	(segment
		(start 116.67744 -255.18872)
		(end 116.67744 -255.82372)
		(width 0.254)
		(layer "F.Cu")
		(net "P0V8_PEX0_VDD")
	)
	(segment
		(start 116.67744 -256.160016)
		(end 117.512338 -256.994914)
		(width 0.1778)
		(layer "F.Cu")
		(net "P0V8_PEX0_VDD")
	)
	(segment
		(start 116.67744 -255.82372)
		(end 116.67744 -256.160016)
		(width 0.1778)
		(layer "F.Cu")
		(net "P0V8_PEX0_VDD")
	)
	(via
		(at 116.67744 -253.17577)
		(size 0.6604)
		(drill 0.3302)
		(layers "F.Cu" "B.Cu")
		(net "P0V8_PEX0_VDD")
	)
	(via
		(at 116.67744 -255.18872)
		(size 0.508)
		(drill 0.254)
		(layers "F.Cu" "B.Cu")
		(net "P0V8_PEX0_VDD")
	)
	(segment
		(start 116.66474 -255.20142)
		(end 116.66474 -255.86055)
		(width 0.381)
		(layer "B.Cu")
		(net "P0V8_PEX0_VDD")
	)
	(segment
		(start 116.67744 -253.17577)
		(end 116.67744 -254.55372)
		(width 0.4572)
		(layer "B.Cu")
		(net "P0V8_PEX0_VDD")
	)
	(segment
		(start 116.67744 -255.18872)
		(end 116.66474 -255.20142)
		(width 0.381)
		(layer "B.Cu")
		(net "P0V8_PEX0_VDD")
	)
	(segment
		(start 116.67744 -254.55372)
		(end 116.67744 -255.18872)
		(width 0.381)
		(layer "B.Cu")
		(net "P0V8_PEX0_VDD")
	)
	(segment
		(start 123.175776 -257.795014)
		(end 125.03404 -257.795014)
		(width 0.13208)
		(layer "F.Cu")
		(net "P0V8_PEX0_VRHOT_R")
	)
	(segment
		(start 126.60249 -256.226564)
		(end 127.258064 -256.226564)
		(width 0.13208)
		(layer "F.Cu")
		(net "P0V8_PEX0_VRHOT_R")
	)
	(segment
		(start 125.03404 -257.795014)
		(end 126.60249 -256.226564)
		(width 0.13208)
		(layer "F.Cu")
		(net "P0V8_PEX0_VRHOT_R")
	)
	(via
		(at 126.60249 -256.226564)
		(size 0.508)
		(drill 0.254)
		(layers "F.Cu" "B.Cu")
		(net "P0V8_PEX0_VRHOT_R")
	)
	(segment
		(start 72.949816 -301.599854)
		(end 72.474836 -302.074834)
		(width 0.127)
		(layer "F.Cu")
		(net "VSENSE_P0V8_PEX0_SKT_VRTN")
	)
	(via
		(at 72.474836 -302.074834)
		(size 0.4064)
		(drill 0.2032)
		(layers "F.Cu" "B.Cu")
		(net "VSENSE_P0V8_PEX0_SKT_VRTN")
	)
	(via
		(at 82.723482 -327.140062)
		(size 0.6604)
		(drill 0.3302)
		(layers "F.Cu" "B.Cu")
		(net "VSENSE_P0V8_PEX0_SKT_VRTN")
	)
	(segment
		(start 72.714104 -302.443134)
		(end 71.195184 -302.443134)
		(width 0.09906)
		(layer "B.Cu")
		(net "VSENSE_P0V8_PEX0_SKT_VRTN")
	)
	(segment
		(start 70.943216 -302.695102)
		(end 70.943216 -307.008784)
		(width 0.09906)
		(layer "B.Cu")
		(net "VSENSE_P0V8_PEX0_SKT_VRTN")
	)
	(segment
		(start 59.068208 -307.834792)
		(end 59.068208 -320.086228)
		(width 0.09906)
		(layer "B.Cu")
		(net "VSENSE_P0V8_PEX0_SKT_VRTN")
	)
	(segment
		(start 70.758812 -307.193188)
		(end 59.709812 -307.193188)
		(width 0.09906)
		(layer "B.Cu")
		(net "VSENSE_P0V8_PEX0_SKT_VRTN")
	)
	(segment
		(start 58.984388 -320.208656)
		(end 58.984388 -321.124072)
		(width 0.254)
		(layer "B.Cu")
		(net "VSENSE_P0V8_PEX0_SKT_VRTN")
	)
	(segment
		(start 71.195184 -302.443134)
		(end 70.943216 -302.695102)
		(width 0.09906)
		(layer "B.Cu")
		(net "VSENSE_P0V8_PEX0_SKT_VRTN")
	)
	(segment
		(start 72.843136 -302.173894)
		(end 72.843136 -302.314102)
		(width 0.09906)
		(layer "B.Cu")
		(net "VSENSE_P0V8_PEX0_SKT_VRTN")
	)
	(segment
		(start 59.068208 -320.086228)
		(end 58.984388 -320.170048)
		(width 0.09906)
		(layer "B.Cu")
		(net "VSENSE_P0V8_PEX0_SKT_VRTN")
	)
	(segment
		(start 72.843136 -302.314102)
		(end 72.714104 -302.443134)
		(width 0.09906)
		(layer "B.Cu")
		(net "VSENSE_P0V8_PEX0_SKT_VRTN")
	)
	(segment
		(start 82.976974 -326.88657)
		(end 90.651838 -326.88657)
		(width 0.254)
		(layer "B.Cu")
		(net "VSENSE_P0V8_PEX0_SKT_VRTN")
	)
	(segment
		(start 82.46999 -326.88657)
		(end 82.723482 -327.140062)
		(width 0.254)
		(layer "B.Cu")
		(net "VSENSE_P0V8_PEX0_SKT_VRTN")
	)
	(segment
		(start 72.744076 -302.074834)
		(end 72.843136 -302.173894)
		(width 0.09906)
		(layer "B.Cu")
		(net "VSENSE_P0V8_PEX0_SKT_VRTN")
	)
	(segment
		(start 90.651838 -326.88657)
		(end 98.017838 -323.835522)
		(width 0.254)
		(layer "B.Cu")
		(net "VSENSE_P0V8_PEX0_SKT_VRTN")
	)
	(segment
		(start 60.243974 -322.383658)
		(end 71.115428 -326.88657)
		(width 0.254)
		(layer "B.Cu")
		(net "VSENSE_P0V8_PEX0_SKT_VRTN")
	)
	(segment
		(start 58.984388 -320.170048)
		(end 58.984388 -320.208656)
		(width 0.09906)
		(layer "B.Cu")
		(net "VSENSE_P0V8_PEX0_SKT_VRTN")
	)
	(segment
		(start 82.723482 -327.140062)
		(end 82.976974 -326.88657)
		(width 0.254)
		(layer "B.Cu")
		(net "VSENSE_P0V8_PEX0_SKT_VRTN")
	)
	(segment
		(start 71.115428 -326.88657)
		(end 82.46999 -326.88657)
		(width 0.254)
		(layer "B.Cu")
		(net "VSENSE_P0V8_PEX0_SKT_VRTN")
	)
	(segment
		(start 98.017838 -323.835522)
		(end 100.18268 -323.835522)
		(width 0.254)
		(layer "B.Cu")
		(net "VSENSE_P0V8_PEX0_SKT_VRTN")
	)
	(segment
		(start 70.943216 -307.008784)
		(end 70.758812 -307.193188)
		(width 0.09906)
		(layer "B.Cu")
		(net "VSENSE_P0V8_PEX0_SKT_VRTN")
	)
	(segment
		(start 58.984388 -321.124072)
		(end 60.243974 -322.383658)
		(width 0.254)
		(layer "B.Cu")
		(net "VSENSE_P0V8_PEX0_SKT_VRTN")
	)
	(segment
		(start 100.18268 -323.835522)
		(end 100.50018 -324.178422)
		(width 0.254)
		(layer "B.Cu")
		(net "VSENSE_P0V8_PEX0_SKT_VRTN")
	)
	(segment
		(start 59.709812 -307.193188)
		(end 59.068208 -307.834792)
		(width 0.09906)
		(layer "B.Cu")
		(net "VSENSE_P0V8_PEX0_SKT_VRTN")
	)
	(segment
		(start 72.474836 -302.074834)
		(end 72.744076 -302.074834)
		(width 0.09906)
		(layer "B.Cu")
		(net "VSENSE_P0V8_PEX0_SKT_VRTN")
	)
	(segment
		(start 72.949816 -302.549814)
		(end 73.424796 -302.074834)
		(width 0.127)
		(layer "F.Cu")
		(net "VSENSE_P0V8_PEX0_SKT_VSEN")
	)
	(via
		(at 81.438496 -326.249792)
		(size 0.6604)
		(drill 0.3302)
		(layers "F.Cu" "B.Cu")
		(net "VSENSE_P0V8_PEX0_SKT_VSEN")
	)
	(via
		(at 73.424796 -302.074834)
		(size 0.4064)
		(drill 0.2032)
		(layers "F.Cu" "B.Cu")
		(net "VSENSE_P0V8_PEX0_SKT_VSEN")
	)
	(segment
		(start 73.056496 -302.402494)
		(end 72.802496 -302.656494)
		(width 0.09906)
		(layer "B.Cu")
		(net "VSENSE_P0V8_PEX0_SKT_VSEN")
	)
	(segment
		(start 59.365388 -320.966084)
		(end 60.459874 -322.06057)
		(width 0.254)
		(layer "B.Cu")
		(net "VSENSE_P0V8_PEX0_SKT_VSEN")
	)
	(segment
		(start 73.056496 -302.173894)
		(end 73.056496 -302.402494)
		(width 0.09906)
		(layer "B.Cu")
		(net "VSENSE_P0V8_PEX0_SKT_VSEN")
	)
	(segment
		(start 73.155556 -302.074834)
		(end 73.056496 -302.173894)
		(width 0.09906)
		(layer "B.Cu")
		(net "VSENSE_P0V8_PEX0_SKT_VSEN")
	)
	(segment
		(start 60.459874 -322.06057)
		(end 71.191374 -326.50557)
		(width 0.254)
		(layer "B.Cu")
		(net "VSENSE_P0V8_PEX0_SKT_VSEN")
	)
	(segment
		(start 71.191374 -326.50557)
		(end 81.182718 -326.50557)
		(width 0.254)
		(layer "B.Cu")
		(net "VSENSE_P0V8_PEX0_SKT_VSEN")
	)
	(segment
		(start 97.941892 -323.454522)
		(end 100.18268 -323.454522)
		(width 0.254)
		(layer "B.Cu")
		(net "VSENSE_P0V8_PEX0_SKT_VSEN")
	)
	(segment
		(start 59.281568 -320.086228)
		(end 59.365388 -320.170048)
		(width 0.09906)
		(layer "B.Cu")
		(net "VSENSE_P0V8_PEX0_SKT_VSEN")
	)
	(segment
		(start 59.365388 -320.208656)
		(end 59.365388 -320.966084)
		(width 0.254)
		(layer "B.Cu")
		(net "VSENSE_P0V8_PEX0_SKT_VSEN")
	)
	(segment
		(start 72.802496 -302.656494)
		(end 71.283576 -302.656494)
		(width 0.09906)
		(layer "B.Cu")
		(net "VSENSE_P0V8_PEX0_SKT_VSEN")
	)
	(segment
		(start 59.365388 -320.170048)
		(end 59.365388 -320.208656)
		(width 0.09906)
		(layer "B.Cu")
		(net "VSENSE_P0V8_PEX0_SKT_VSEN")
	)
	(segment
		(start 59.798204 -307.406548)
		(end 59.281568 -307.923184)
		(width 0.09906)
		(layer "B.Cu")
		(net "VSENSE_P0V8_PEX0_SKT_VSEN")
	)
	(segment
		(start 81.694274 -326.50557)
		(end 90.575892 -326.50557)
		(width 0.254)
		(layer "B.Cu")
		(net "VSENSE_P0V8_PEX0_SKT_VSEN")
	)
	(segment
		(start 70.847204 -307.406548)
		(end 59.798204 -307.406548)
		(width 0.09906)
		(layer "B.Cu")
		(net "VSENSE_P0V8_PEX0_SKT_VSEN")
	)
	(segment
		(start 71.283576 -302.656494)
		(end 71.156576 -302.783494)
		(width 0.09906)
		(layer "B.Cu")
		(net "VSENSE_P0V8_PEX0_SKT_VSEN")
	)
	(segment
		(start 81.438496 -326.249792)
		(end 81.694274 -326.50557)
		(width 0.254)
		(layer "B.Cu")
		(net "VSENSE_P0V8_PEX0_SKT_VSEN")
	)
	(segment
		(start 100.18268 -323.454522)
		(end 100.50018 -323.111622)
		(width 0.254)
		(layer "B.Cu")
		(net "VSENSE_P0V8_PEX0_SKT_VSEN")
	)
	(segment
		(start 71.156576 -302.783494)
		(end 71.156576 -307.097176)
		(width 0.09906)
		(layer "B.Cu")
		(net "VSENSE_P0V8_PEX0_SKT_VSEN")
	)
	(segment
		(start 59.281568 -307.923184)
		(end 59.281568 -320.086228)
		(width 0.09906)
		(layer "B.Cu")
		(net "VSENSE_P0V8_PEX0_SKT_VSEN")
	)
	(segment
		(start 90.575892 -326.50557)
		(end 97.941892 -323.454522)
		(width 0.254)
		(layer "B.Cu")
		(net "VSENSE_P0V8_PEX0_SKT_VSEN")
	)
	(segment
		(start 71.156576 -307.097176)
		(end 70.847204 -307.406548)
		(width 0.09906)
		(layer "B.Cu")
		(net "VSENSE_P0V8_PEX0_SKT_VSEN")
	)
	(segment
		(start 81.182718 -326.50557)
		(end 81.438496 -326.249792)
		(width 0.254)
		(layer "B.Cu")
		(net "VSENSE_P0V8_PEX0_SKT_VSEN")
	)
	(segment
		(start 73.424796 -302.074834)
		(end 73.155556 -302.074834)
		(width 0.09906)
		(layer "B.Cu")
		(net "VSENSE_P0V8_PEX0_SKT_VSEN")
	)
	(segment
		(start 123.175776 -258.59486)
		(end 126.177294 -258.59486)
		(width 0.13208)
		(layer "F.Cu")
		(net "P0V8_PEX1_BVRRDY")
	)
	(segment
		(start 129.182114 -257.620262)
		(end 129.290064 -257.728212)
		(width 0.13208)
		(layer "F.Cu")
		(net "P0V8_PEX1_BVRRDY")
	)
	(segment
		(start 126.177294 -258.59486)
		(end 126.64059 -258.131564)
		(width 0.13208)
		(layer "F.Cu")
		(net "P0V8_PEX1_BVRRDY")
	)
	(segment
		(start 127.258064 -258.131564)
		(end 127.258064 -257.747262)
		(width 0.13208)
		(layer "F.Cu")
		(net "P0V8_PEX1_BVRRDY")
	)
	(segment
		(start 126.64059 -258.131564)
		(end 127.258064 -258.131564)
		(width 0.13208)
		(layer "F.Cu")
		(net "P0V8_PEX1_BVRRDY")
	)
	(segment
		(start 127.258064 -257.747262)
		(end 127.385064 -257.620262)
		(width 0.13208)
		(layer "F.Cu")
		(net "P0V8_PEX1_BVRRDY")
	)
	(segment
		(start 129.290064 -257.728212)
		(end 129.290064 -258.131564)
		(width 0.13208)
		(layer "F.Cu")
		(net "P0V8_PEX1_BVRRDY")
	)
	(segment
		(start 127.385064 -257.620262)
		(end 129.182114 -257.620262)
		(width 0.13208)
		(layer "F.Cu")
		(net "P0V8_PEX1_BVRRDY")
	)
	(segment
		(start 129.290064 -258.131564)
		(end 129.290064 -259.147564)
		(width 0.13208)
		(layer "F.Cu")
		(net "P0V8_PEX1_BVRRDY")
	)
	(via
		(at 126.64059 -258.131564)
		(size 0.508)
		(drill 0.254)
		(layers "F.Cu" "B.Cu")
		(net "P0V8_PEX1_BVRRDY")
	)
	(segment
		(start 124.978668 -259.204714)
		(end 124.388372 -259.79501)
		(width 0.13208)
		(layer "F.Cu")
		(net "NC_P0V8_PEX0_SVID_ALERT_N_R")
	)
	(segment
		(start 125.03785 -259.145532)
		(end 127.224282 -259.145532)
		(width 0.13208)
		(layer "F.Cu")
		(net "NC_P0V8_PEX0_SVID_ALERT_N_R")
	)
	(segment
		(start 124.388372 -259.79501)
		(end 123.175776 -259.79501)
		(width 0.13208)
		(layer "F.Cu")
		(net "NC_P0V8_PEX0_SVID_ALERT_N_R")
	)
	(segment
		(start 124.978668 -259.204714)
		(end 125.03785 -259.145532)
		(width 0.13208)
		(layer "F.Cu")
		(net "NC_P0V8_PEX0_SVID_ALERT_N_R")
	)
	(via
		(at 124.978668 -259.204714)
		(size 0.762)
		(drill 0.381)
		(layers "F.Cu" "B.Cu")
		(net "NC_P0V8_PEX0_SVID_ALERT_N_R")
	)
	(segment
		(start 117.993668 -259.79501)
		(end 117.517164 -260.271514)
		(width 0.1778)
		(layer "F.Cu")
		(net "P0V8_PEX1_VSEN1")
	)
	(segment
		(start 118.375684 -259.79501)
		(end 117.993668 -259.79501)
		(width 0.1778)
		(layer "F.Cu")
		(net "P0V8_PEX1_VSEN1")
	)
	(segment
		(start 117.517164 -260.271514)
		(end 117.117114 -260.271514)
		(width 0.1778)
		(layer "F.Cu")
		(net "P0V8_PEX1_VSEN1")
	)
	(segment
		(start 117.098064 -260.290564)
		(end 117.117114 -260.271514)
		(width 0.254)
		(layer "F.Cu")
		(net "P0V8_PEX1_VSEN1")
	)
	(segment
		(start 116.120164 -260.290564)
		(end 117.098064 -260.290564)
		(width 0.254)
		(layer "F.Cu")
		(net "P0V8_PEX1_VSEN1")
	)
	(segment
		(start 114.58956 -259.535422)
		(end 114.850418 -259.274564)
		(width 0.254)
		(layer "F.Cu")
		(net "P0V8_PEX0_ADDR")
	)
	(segment
		(start 114.958114 -259.274564)
		(end 117.60581 -259.274564)
		(width 0.1524)
		(layer "F.Cu")
		(net "P0V8_PEX0_ADDR")
	)
	(segment
		(start 114.342418 -259.782564)
		(end 113.961164 -259.782564)
		(width 0.254)
		(layer "F.Cu")
		(net "P0V8_PEX0_ADDR")
	)
	(segment
		(start 113.961164 -259.782564)
		(end 113.961164 -260.671564)
		(width 0.254)
		(layer "F.Cu")
		(net "P0V8_PEX0_ADDR")
	)
	(segment
		(start 117.60581 -259.274564)
		(end 117.885464 -258.99491)
		(width 0.1524)
		(layer "F.Cu")
		(net "P0V8_PEX0_ADDR")
	)
	(segment
		(start 114.850418 -259.274564)
		(end 114.958114 -259.274564)
		(width 0.254)
		(layer "F.Cu")
		(net "P0V8_PEX0_ADDR")
	)
	(segment
		(start 114.58956 -259.535422)
		(end 114.342418 -259.782564)
		(width 0.254)
		(layer "F.Cu")
		(net "P0V8_PEX0_ADDR")
	)
	(segment
		(start 117.885464 -258.99491)
		(end 118.375684 -258.99491)
		(width 0.1524)
		(layer "F.Cu")
		(net "P0V8_PEX0_ADDR")
	)
	(via
		(at 114.58956 -259.535422)
		(size 0.508)
		(drill 0.254)
		(layers "F.Cu" "B.Cu")
		(net "P0V8_PEX0_ADDR")
	)
	(segment
		(start 117.39499 -258.27355)
		(end 117.804946 -258.27355)
		(width 0.1524)
		(layer "F.Cu")
		(net "P0V8_PEX1_TSEN_R")
	)
	(segment
		(start 117.804946 -258.27355)
		(end 117.883432 -258.195064)
		(width 0.1524)
		(layer "F.Cu")
		(net "P0V8_PEX1_TSEN_R")
	)
	(segment
		(start 117.883432 -258.195064)
		(end 118.375684 -258.195064)
		(width 0.1524)
		(layer "F.Cu")
		(net "P0V8_PEX1_TSEN_R")
	)
	(via
		(at 117.39499 -258.27355)
		(size 0.508)
		(drill 0.254)
		(layers "F.Cu" "B.Cu")
		(net "P0V8_PEX1_TSEN_R")
	)
	(via
		(at 118.082314 -258.843526)
		(size 0.6604)
		(drill 0.3302)
		(layers "F.Cu" "B.Cu")
		(net "P0V8_PEX1_TSEN_R")
	)
	(segment
		(start 117.987064 -257.699764)
		(end 117.548914 -257.699764)
		(width 0.254)
		(layer "B.Cu")
		(net "P0V8_PEX1_TSEN_R")
	)
	(segment
		(start 117.987064 -257.699764)
		(end 118.082314 -257.795014)
		(width 0.254)
		(layer "B.Cu")
		(net "P0V8_PEX1_TSEN_R")
	)
	(segment
		(start 117.95379 -259.99567)
		(end 118.082314 -259.867146)
		(width 0.254)
		(layer "B.Cu")
		(net "P0V8_PEX1_TSEN_R")
	)
	(segment
		(start 118.082314 -259.867146)
		(end 118.082314 -258.843526)
		(width 0.254)
		(layer "B.Cu")
		(net "P0V8_PEX1_TSEN_R")
	)
	(segment
		(start 118.082314 -257.795014)
		(end 118.082314 -258.843526)
		(width 0.254)
		(layer "B.Cu")
		(net "P0V8_PEX1_TSEN_R")
	)
	(segment
		(start 117.39499 -257.853688)
		(end 117.39499 -258.27355)
		(width 0.254)
		(layer "B.Cu")
		(net "P0V8_PEX1_TSEN_R")
	)
	(segment
		(start 117.548914 -257.699764)
		(end 117.39499 -257.853688)
		(width 0.254)
		(layer "B.Cu")
		(net "P0V8_PEX1_TSEN_R")
	)
	(segment
		(start 174.325026 -297.32478)
		(end 174.800006 -296.8498)
		(width 0.249936)
		(layer "F.Cu")
		(net "P0V8_PEX1")
	)
	(segment
		(start 180.50002 -294.94988)
		(end 180.975 -294.4749)
		(width 0.249936)
		(layer "F.Cu")
		(net "P0V8_PEX1")
	)
	(segment
		(start 177.649886 -293.99992)
		(end 177.174906 -294.4749)
		(width 0.249936)
		(layer "F.Cu")
		(net "P0V8_PEX1")
	)
	(segment
		(start 166.249858 -299.699934)
		(end 165.774878 -300.174914)
		(width 0.249936)
		(layer "F.Cu")
		(net "P0V8_PEX1")
	)
	(segment
		(start 172.900086 -296.8498)
		(end 173.375066 -296.37482)
		(width 0.249936)
		(layer "F.Cu")
		(net "P0V8_PEX1")
	)
	(segment
		(start 167.200072 -296.8498)
		(end 167.675052 -296.37482)
		(width 0.249936)
		(layer "F.Cu")
		(net "P0V8_PEX1")
	)
	(segment
		(start 171.474892 -296.37482)
		(end 170.999912 -296.8498)
		(width 0.249936)
		(layer "F.Cu")
		(net "P0V8_PEX1")
	)
	(segment
		(start 179.55006 -297.79976)
		(end 180.02504 -298.27474)
		(width 0.249936)
		(layer "F.Cu")
		(net "P0V8_PEX1")
	)
	(segment
		(start 166.249858 -297.79976)
		(end 165.774878 -298.27474)
		(width 0.249936)
		(layer "F.Cu")
		(net "P0V8_PEX1")
	)
	(segment
		(start 179.55006 -293.99992)
		(end 179.07508 -294.4749)
		(width 0.249936)
		(layer "F.Cu")
		(net "P0V8_PEX1")
	)
	(segment
		(start 178.124866 -296.37482)
		(end 178.599846 -296.8498)
		(width 0.249936)
		(layer "F.Cu")
		(net "P0V8_PEX1")
	)
	(segment
		(start 180.975 -294.4749)
		(end 181.44998 -293.99992)
		(width 0.249936)
		(layer "F.Cu")
		(net "P0V8_PEX1")
	)
	(segment
		(start 170.049952 -297.79976)
		(end 170.524932 -297.32478)
		(width 0.249936)
		(layer "F.Cu")
		(net "P0V8_PEX1")
	)
	(segment
		(start 170.524932 -294.4749)
		(end 170.999912 -294.94988)
		(width 0.249936)
		(layer "F.Cu")
		(net "P0V8_PEX1")
	)
	(segment
		(start 165.774878 -291.624766)
		(end 165.299898 -291.149786)
		(width 0.249936)
		(layer "F.Cu")
		(net "P0V8_PEX1")
	)
	(segment
		(start 183.3499 -293.99992)
		(end 183.82488 -293.52494)
		(width 0.249936)
		(layer "F.Cu")
		(net "P0V8_PEX1")
	)
	(segment
		(start 165.774878 -298.27474)
		(end 165.299898 -298.74972)
		(width 0.249936)
		(layer "F.Cu")
		(net "P0V8_PEX1")
	)
	(segment
		(start 183.3499 -297.79976)
		(end 183.82488 -298.27474)
		(width 0.249936)
		(layer "F.Cu")
		(net "P0V8_PEX1")
	)
	(segment
		(start 169.574972 -296.37482)
		(end 169.099992 -296.8498)
		(width 0.249936)
		(layer "F.Cu")
		(net "P0V8_PEX1")
	)
	(segment
		(start 167.675052 -296.37482)
		(end 168.150032 -295.89984)
		(width 0.249936)
		(layer "F.Cu")
		(net "P0V8_PEX1")
	)
	(segment
		(start 165.299898 -294.94988)
		(end 164.824918 -294.4749)
		(width 0.249936)
		(layer "F.Cu")
		(net "P0V8_PEX1")
	)
	(segment
		(start 165.774878 -296.37482)
		(end 165.299898 -296.8498)
		(width 0.249936)
		(layer "F.Cu")
		(net "P0V8_PEX1")
	)
	(segment
		(start 166.249858 -292.099746)
		(end 165.774878 -291.624766)
		(width 0.249936)
		(layer "F.Cu")
		(net "P0V8_PEX1")
	)
	(segment
		(start 166.725092 -297.32478)
		(end 167.200072 -296.8498)
		(width 0.249936)
		(layer "F.Cu")
		(net "P0V8_PEX1")
	)
	(segment
		(start 170.049952 -293.99992)
		(end 169.574972 -293.52494)
		(width 0.249936)
		(layer "F.Cu")
		(net "P0V8_PEX1")
	)
	(segment
		(start 174.325026 -294.4749)
		(end 174.800006 -294.94988)
		(width 0.249936)
		(layer "F.Cu")
		(net "P0V8_PEX1")
	)
	(segment
		(start 173.850046 -297.79976)
		(end 173.375066 -298.27474)
		(width 0.249936)
		(layer "F.Cu")
		(net "P0V8_PEX1")
	)
	(segment
		(start 179.07508 -294.4749)
		(end 178.599846 -294.94988)
		(width 0.249936)
		(layer "F.Cu")
		(net "P0V8_PEX1")
	)
	(segment
		(start 170.049952 -297.79976)
		(end 169.574972 -298.27474)
		(width 0.249936)
		(layer "F.Cu")
		(net "P0V8_PEX1")
	)
	(segment
		(start 170.049952 -293.99992)
		(end 170.524932 -294.4749)
		(width 0.249936)
		(layer "F.Cu")
		(net "P0V8_PEX1")
	)
	(segment
		(start 165.774878 -293.52494)
		(end 165.299898 -293.04996)
		(width 0.249936)
		(layer "F.Cu")
		(net "P0V8_PEX1")
	)
	(segment
		(start 168.150032 -297.79976)
		(end 167.675052 -298.27474)
		(width 0.249936)
		(layer "F.Cu")
		(net "P0V8_PEX1")
	)
	(segment
		(start 180.50002 -296.8498)
		(end 180.02504 -296.37482)
		(width 0.249936)
		(layer "F.Cu")
		(net "P0V8_PEX1")
	)
	(segment
		(start 172.424852 -297.32478)
		(end 171.949872 -297.79976)
		(width 0.249936)
		(layer "F.Cu")
		(net "P0V8_PEX1")
	)
	(segment
		(start 177.174906 -297.32478)
		(end 176.699926 -296.8498)
		(width 0.249936)
		(layer "F.Cu")
		(net "P0V8_PEX1")
	)
	(segment
		(start 171.949872 -293.99992)
		(end 171.474892 -293.52494)
		(width 0.249936)
		(layer "F.Cu")
		(net "P0V8_PEX1")
	)
	(segment
		(start 169.099992 -296.8498)
		(end 168.625012 -297.32478)
		(width 0.249936)
		(layer "F.Cu")
		(net "P0V8_PEX1")
	)
	(segment
		(start 179.07508 -297.32478)
		(end 178.599846 -296.8498)
		(width 0.249936)
		(layer "F.Cu")
		(net "P0V8_PEX1")
	)
	(segment
		(start 164.824918 -301.124874)
		(end 165.299898 -300.649894)
		(width 0.249936)
		(layer "F.Cu")
		(net "P0V8_PEX1")
	)
	(segment
		(start 177.649886 -295.89984)
		(end 178.124866 -296.37482)
		(width 0.249936)
		(layer "F.Cu")
		(net "P0V8_PEX1")
	)
	(segment
		(start 175.749966 -297.79976)
		(end 176.224946 -298.27474)
		(width 0.249936)
		(layer "F.Cu")
		(net "P0V8_PEX1")
	)
	(segment
		(start 173.850046 -293.99992)
		(end 174.325026 -294.4749)
		(width 0.249936)
		(layer "F.Cu")
		(net "P0V8_PEX1")
	)
	(segment
		(start 171.949872 -297.79976)
		(end 171.474892 -298.27474)
		(width 0.249936)
		(layer "F.Cu")
		(net "P0V8_PEX1")
	)
	(segment
		(start 166.249858 -297.79976)
		(end 166.725092 -297.32478)
		(width 0.249936)
		(layer "F.Cu")
		(net "P0V8_PEX1")
	)
	(segment
		(start 179.55006 -293.99992)
		(end 180.02504 -293.52494)
		(width 0.249936)
		(layer "F.Cu")
		(net "P0V8_PEX1")
	)
	(segment
		(start 169.099992 -294.94988)
		(end 168.625012 -294.4749)
		(width 0.249936)
		(layer "F.Cu")
		(net "P0V8_PEX1")
	)
	(segment
		(start 177.649886 -293.99992)
		(end 178.124866 -293.52494)
		(width 0.249936)
		(layer "F.Cu")
		(net "P0V8_PEX1")
	)
	(segment
		(start 173.850046 -297.79976)
		(end 174.325026 -297.32478)
		(width 0.249936)
		(layer "F.Cu")
		(net "P0V8_PEX1")
	)
	(segment
		(start 172.900086 -296.8498)
		(end 172.424852 -297.32478)
		(width 0.249936)
		(layer "F.Cu")
		(net "P0V8_PEX1")
	)
	(segment
		(start 165.299898 -293.04996)
		(end 164.824918 -292.574726)
		(width 0.249936)
		(layer "F.Cu")
		(net "P0V8_PEX1")
	)
	(segment
		(start 166.249858 -293.99992)
		(end 165.774878 -293.52494)
		(width 0.249936)
		(layer "F.Cu")
		(net "P0V8_PEX1")
	)
	(segment
		(start 181.44998 -297.79976)
		(end 180.975 -297.32478)
		(width 0.249936)
		(layer "F.Cu")
		(net "P0V8_PEX1")
	)
	(segment
		(start 168.150032 -293.99992)
		(end 167.675052 -293.52494)
		(width 0.249936)
		(layer "F.Cu")
		(net "P0V8_PEX1")
	)
	(segment
		(start 172.900086 -294.94988)
		(end 172.424852 -294.4749)
		(width 0.249936)
		(layer "F.Cu")
		(net "P0V8_PEX1")
	)
	(segment
		(start 170.049952 -295.89984)
		(end 169.574972 -296.37482)
		(width 0.249936)
		(layer "F.Cu")
		(net "P0V8_PEX1")
	)
	(segment
		(start 165.299898 -296.8498)
		(end 164.824918 -297.32478)
		(width 0.249936)
		(layer "F.Cu")
		(net "P0V8_PEX1")
	)
	(segment
		(start 166.725092 -294.4749)
		(end 166.249858 -293.99992)
		(width 0.249936)
		(layer "F.Cu")
		(net "P0V8_PEX1")
	)
	(segment
		(start 179.55006 -297.79976)
		(end 179.07508 -297.32478)
		(width 0.249936)
		(layer "F.Cu")
		(net "P0V8_PEX1")
	)
	(segment
		(start 181.44998 -295.89984)
		(end 181.92496 -296.37482)
		(width 0.249936)
		(layer "F.Cu")
		(net "P0V8_PEX1")
	)
	(segment
		(start 171.949872 -295.89984)
		(end 171.474892 -296.37482)
		(width 0.249936)
		(layer "F.Cu")
		(net "P0V8_PEX1")
	)
	(segment
		(start 175.749966 -293.99992)
		(end 176.224946 -293.52494)
		(width 0.249936)
		(layer "F.Cu")
		(net "P0V8_PEX1")
	)
	(segment
		(start 181.92496 -293.52494)
		(end 181.44998 -293.99992)
		(width 0.249936)
		(layer "F.Cu")
		(net "P0V8_PEX1")
	)
	(segment
		(start 166.249858 -295.89984)
		(end 165.774878 -296.37482)
		(width 0.249936)
		(layer "F.Cu")
		(net "P0V8_PEX1")
	)
	(segment
		(start 177.649886 -297.79976)
		(end 177.174906 -297.32478)
		(width 0.249936)
		(layer "F.Cu")
		(net "P0V8_PEX1")
	)
	(segment
		(start 177.649886 -297.79976)
		(end 178.124866 -298.27474)
		(width 0.249936)
		(layer "F.Cu")
		(net "P0V8_PEX1")
	)
	(segment
		(start 180.975 -297.32478)
		(end 180.50002 -296.8498)
		(width 0.249936)
		(layer "F.Cu")
		(net "P0V8_PEX1")
	)
	(segment
		(start 177.174906 -294.4749)
		(end 176.699926 -294.94988)
		(width 0.249936)
		(layer "F.Cu")
		(net "P0V8_PEX1")
	)
	(segment
		(start 165.299898 -298.74972)
		(end 164.824918 -299.224954)
		(width 0.249936)
		(layer "F.Cu")
		(net "P0V8_PEX1")
	)
	(segment
		(start 168.625012 -294.4749)
		(end 168.150032 -293.99992)
		(width 0.249936)
		(layer "F.Cu")
		(net "P0V8_PEX1")
	)
	(segment
		(start 172.424852 -294.4749)
		(end 171.949872 -293.99992)
		(width 0.249936)
		(layer "F.Cu")
		(net "P0V8_PEX1")
	)
	(segment
		(start 170.524932 -297.32478)
		(end 170.999912 -296.8498)
		(width 0.249936)
		(layer "F.Cu")
		(net "P0V8_PEX1")
	)
	(segment
		(start 173.375066 -296.37482)
		(end 173.850046 -295.89984)
		(width 0.249936)
		(layer "F.Cu")
		(net "P0V8_PEX1")
	)
	(segment
		(start 181.92496 -298.27474)
		(end 181.44998 -297.79976)
		(width 0.249936)
		(layer "F.Cu")
		(net "P0V8_PEX1")
	)
	(segment
		(start 165.299898 -291.149786)
		(end 164.824918 -290.674806)
		(width 0.249936)
		(layer "F.Cu")
		(net "P0V8_PEX1")
	)
	(segment
		(start 180.02504 -296.37482)
		(end 179.55006 -295.89984)
		(width 0.249936)
		(layer "F.Cu")
		(net "P0V8_PEX1")
	)
	(segment
		(start 173.850046 -293.99992)
		(end 173.375066 -293.52494)
		(width 0.249936)
		(layer "F.Cu")
		(net "P0V8_PEX1")
	)
	(segment
		(start 167.200072 -294.94988)
		(end 166.725092 -294.4749)
		(width 0.249936)
		(layer "F.Cu")
		(net "P0V8_PEX1")
	)
	(segment
		(start 175.749966 -295.89984)
		(end 176.224946 -296.37482)
		(width 0.249936)
		(layer "F.Cu")
		(net "P0V8_PEX1")
	)
	(segment
		(start 165.774878 -300.174914)
		(end 165.299898 -300.649894)
		(width 0.249936)
		(layer "F.Cu")
		(net "P0V8_PEX1")
	)
	(via
		(at 134.181596 -294.851836)
		(size 0.508)
		(drill 0.254)
		(layers "F.Cu" "B.Cu")
		(net "P0V8_PEX1")
	)
	(via
		(at 125.430534 -299.572934)
		(size 0.508)
		(drill 0.254)
		(layers "F.Cu" "B.Cu")
		(net "P0V8_PEX1")
	)
	(via
		(at 132.879084 -295.880536)
		(size 0.508)
		(drill 0.254)
		(layers "F.Cu" "B.Cu")
		(net "P0V8_PEX1")
	)
	(via
		(at 132.244084 -296.515536)
		(size 0.508)
		(drill 0.254)
		(layers "F.Cu" "B.Cu")
		(net "P0V8_PEX1")
	)
	(via
		(at 130.698748 -315.517276)
		(size 0.508)
		(drill 0.254)
		(layers "F.Cu" "B.Cu")
		(net "P0V8_PEX1")
	)
	(via
		(at 172.424852 -297.32478)
		(size 0.4064)
		(drill 0.2032)
		(layers "F.Cu" "B.Cu")
		(net "P0V8_PEX1")
	)
	(via
		(at 130.698748 -314.501276)
		(size 0.508)
		(drill 0.254)
		(layers "F.Cu" "B.Cu")
		(net "P0V8_PEX1")
	)
	(via
		(at 132.879084 -297.150536)
		(size 0.508)
		(drill 0.254)
		(layers "F.Cu" "B.Cu")
		(net "P0V8_PEX1")
	)
	(via
		(at 165.774878 -293.52494)
		(size 0.4064)
		(drill 0.2032)
		(layers "F.Cu" "B.Cu")
		(net "P0V8_PEX1")
	)
	(via
		(at 127.603504 -297.150536)
		(size 0.508)
		(drill 0.254)
		(layers "F.Cu" "B.Cu")
		(net "P0V8_PEX1")
	)
	(via
		(at 181.92496 -293.52494)
		(size 0.4064)
		(drill 0.2032)
		(layers "F.Cu" "B.Cu")
		(net "P0V8_PEX1")
	)
	(via
		(at 178.124866 -298.27474)
		(size 0.4064)
		(drill 0.2032)
		(layers "F.Cu" "B.Cu")
		(net "P0V8_PEX1")
	)
	(via
		(at 130.698748 -316.533276)
		(size 0.508)
		(drill 0.254)
		(layers "F.Cu" "B.Cu")
		(net "P0V8_PEX1")
	)
	(via
		(at 132.858764 -302.290734)
		(size 0.508)
		(drill 0.254)
		(layers "F.Cu" "B.Cu")
		(net "P0V8_PEX1")
	)
	(via
		(at 164.824918 -297.32478)
		(size 0.4064)
		(drill 0.2032)
		(layers "F.Cu" "B.Cu")
		(net "P0V8_PEX1")
	)
	(via
		(at 171.474892 -298.27474)
		(size 0.4064)
		(drill 0.2032)
		(layers "F.Cu" "B.Cu")
		(net "P0V8_PEX1")
	)
	(via
		(at 125.175772 -295.880536)
		(size 0.508)
		(drill 0.254)
		(layers "F.Cu" "B.Cu")
		(net "P0V8_PEX1")
	)
	(via
		(at 132.270754 -299.572934)
		(size 0.508)
		(drill 0.254)
		(layers "F.Cu" "B.Cu")
		(net "P0V8_PEX1")
	)
	(via
		(at 174.325026 -294.4749)
		(size 0.4064)
		(drill 0.2032)
		(layers "F.Cu" "B.Cu")
		(net "P0V8_PEX1")
	)
	(via
		(at 125.175772 -298.420536)
		(size 0.508)
		(drill 0.254)
		(layers "F.Cu" "B.Cu")
		(net "P0V8_PEX1")
	)
	(via
		(at 128.238504 -295.880536)
		(size 0.508)
		(drill 0.254)
		(layers "F.Cu" "B.Cu")
		(net "P0V8_PEX1")
	)
	(via
		(at 169.574972 -298.27474)
		(size 0.4064)
		(drill 0.2032)
		(layers "F.Cu" "B.Cu")
		(net "P0V8_PEX1")
	)
	(via
		(at 132.879084 -298.420536)
		(size 0.508)
		(drill 0.254)
		(layers "F.Cu" "B.Cu")
		(net "P0V8_PEX1")
	)
	(via
		(at 121.798334 -300.154086)
		(size 0.508)
		(drill 0.254)
		(layers "F.Cu" "B.Cu")
		(net "P0V8_PEX1")
	)
	(via
		(at 165.774878 -291.624766)
		(size 0.4064)
		(drill 0.2032)
		(layers "F.Cu" "B.Cu")
		(net "P0V8_PEX1")
	)
	(via
		(at 179.07508 -297.32478)
		(size 0.4064)
		(drill 0.2032)
		(layers "F.Cu" "B.Cu")
		(net "P0V8_PEX1")
	)
	(via
		(at 126.634748 -311.453276)
		(size 0.508)
		(drill 0.254)
		(layers "F.Cu" "B.Cu")
		(net "P0V8_PEX1")
	)
	(via
		(at 125.430534 -300.842934)
		(size 0.508)
		(drill 0.254)
		(layers "F.Cu" "B.Cu")
		(net "P0V8_PEX1")
	)
	(via
		(at 128.238504 -297.150536)
		(size 0.508)
		(drill 0.254)
		(layers "F.Cu" "B.Cu")
		(net "P0V8_PEX1")
	)
	(via
		(at 127.650748 -316.533276)
		(size 0.508)
		(drill 0.254)
		(layers "F.Cu" "B.Cu")
		(net "P0V8_PEX1")
	)
	(via
		(at 120.535192 -297.785536)
		(size 0.508)
		(drill 0.254)
		(layers "F.Cu" "B.Cu")
		(net "P0V8_PEX1")
	)
	(via
		(at 132.244084 -297.150536)
		(size 0.508)
		(drill 0.254)
		(layers "F.Cu" "B.Cu")
		(net "P0V8_PEX1")
	)
	(via
		(at 176.224946 -298.27474)
		(size 0.4064)
		(drill 0.2032)
		(layers "F.Cu" "B.Cu")
		(net "P0V8_PEX1")
	)
	(via
		(at 165.774878 -296.37482)
		(size 0.4064)
		(drill 0.2032)
		(layers "F.Cu" "B.Cu")
		(net "P0V8_PEX1")
	)
	(via
		(at 130.698748 -313.485276)
		(size 0.508)
		(drill 0.254)
		(layers "F.Cu" "B.Cu")
		(net "P0V8_PEX1")
	)
	(via
		(at 127.603504 -297.785536)
		(size 0.508)
		(drill 0.254)
		(layers "F.Cu" "B.Cu")
		(net "P0V8_PEX1")
	)
	(via
		(at 125.175772 -297.785536)
		(size 0.508)
		(drill 0.254)
		(layers "F.Cu" "B.Cu")
		(net "P0V8_PEX1")
	)
	(via
		(at 121.170192 -295.245536)
		(size 0.508)
		(drill 0.254)
		(layers "F.Cu" "B.Cu")
		(net "P0V8_PEX1")
	)
	(via
		(at 128.638554 -301.424086)
		(size 0.508)
		(drill 0.254)
		(layers "F.Cu" "B.Cu")
		(net "P0V8_PEX1")
	)
	(via
		(at 164.824918 -292.574726)
		(size 0.4064)
		(drill 0.2032)
		(layers "F.Cu" "B.Cu")
		(net "P0V8_PEX1")
	)
	(via
		(at 131.714748 -311.453276)
		(size 0.508)
		(drill 0.254)
		(layers "F.Cu" "B.Cu")
		(net "P0V8_PEX1")
	)
	(via
		(at 173.375066 -296.37482)
		(size 0.4064)
		(drill 0.2032)
		(layers "F.Cu" "B.Cu")
		(net "P0V8_PEX1")
	)
	(via
		(at 121.170192 -295.880536)
		(size 0.508)
		(drill 0.254)
		(layers "F.Cu" "B.Cu")
		(net "P0V8_PEX1")
	)
	(via
		(at 164.824918 -301.124874)
		(size 0.4064)
		(drill 0.2032)
		(layers "F.Cu" "B.Cu")
		(net "P0V8_PEX1")
	)
	(via
		(at 130.698748 -310.437276)
		(size 0.508)
		(drill 0.254)
		(layers "F.Cu" "B.Cu")
		(net "P0V8_PEX1")
	)
	(via
		(at 176.224946 -293.52494)
		(size 0.4064)
		(drill 0.2032)
		(layers "F.Cu" "B.Cu")
		(net "P0V8_PEX1")
	)
	(via
		(at 131.714748 -312.469276)
		(size 0.508)
		(drill 0.254)
		(layers "F.Cu" "B.Cu")
		(net "P0V8_PEX1")
	)
	(via
		(at 172.424852 -294.4749)
		(size 0.4064)
		(drill 0.2032)
		(layers "F.Cu" "B.Cu")
		(net "P0V8_PEX1")
	)
	(via
		(at 128.238504 -298.420536)
		(size 0.508)
		(drill 0.254)
		(layers "F.Cu" "B.Cu")
		(net "P0V8_PEX1")
	)
	(via
		(at 121.210324 -302.925734)
		(size 0.508)
		(drill 0.254)
		(layers "F.Cu" "B.Cu")
		(net "P0V8_PEX1")
	)
	(via
		(at 165.774878 -298.27474)
		(size 0.4064)
		(drill 0.2032)
		(layers "F.Cu" "B.Cu")
		(net "P0V8_PEX1")
	)
	(via
		(at 120.535192 -295.880536)
		(size 0.508)
		(drill 0.254)
		(layers "F.Cu" "B.Cu")
		(net "P0V8_PEX1")
	)
	(via
		(at 125.810772 -298.420536)
		(size 0.508)
		(drill 0.254)
		(layers "F.Cu" "B.Cu")
		(net "P0V8_PEX1")
	)
	(via
		(at 120.535192 -296.515536)
		(size 0.508)
		(drill 0.254)
		(layers "F.Cu" "B.Cu")
		(net "P0V8_PEX1")
	)
	(via
		(at 169.574972 -296.37482)
		(size 0.4064)
		(drill 0.2032)
		(layers "F.Cu" "B.Cu")
		(net "P0V8_PEX1")
	)
	(via
		(at 125.430534 -300.207934)
		(size 0.508)
		(drill 0.254)
		(layers "F.Cu" "B.Cu")
		(net "P0V8_PEX1")
	)
	(via
		(at 167.675052 -296.37482)
		(size 0.4064)
		(drill 0.2032)
		(layers "F.Cu" "B.Cu")
		(net "P0V8_PEX1")
	)
	(via
		(at 167.675052 -298.27474)
		(size 0.4064)
		(drill 0.2032)
		(layers "F.Cu" "B.Cu")
		(net "P0V8_PEX1")
	)
	(via
		(at 125.618748 -315.517276)
		(size 0.508)
		(drill 0.254)
		(layers "F.Cu" "B.Cu")
		(net "P0V8_PEX1")
	)
	(via
		(at 126.634748 -313.485276)
		(size 0.508)
		(drill 0.254)
		(layers "F.Cu" "B.Cu")
		(net "P0V8_PEX1")
	)
	(via
		(at 177.174906 -294.4749)
		(size 0.4064)
		(drill 0.2032)
		(layers "F.Cu" "B.Cu")
		(net "P0V8_PEX1")
	)
	(via
		(at 132.879084 -295.245536)
		(size 0.508)
		(drill 0.254)
		(layers "F.Cu" "B.Cu")
		(net "P0V8_PEX1")
	)
	(via
		(at 129.682748 -311.453276)
		(size 0.508)
		(drill 0.254)
		(layers "F.Cu" "B.Cu")
		(net "P0V8_PEX1")
	)
	(via
		(at 128.050544 -302.290734)
		(size 0.508)
		(drill 0.254)
		(layers "F.Cu" "B.Cu")
		(net "P0V8_PEX1")
	)
	(via
		(at 164.824918 -290.674806)
		(size 0.4064)
		(drill 0.2032)
		(layers "F.Cu" "B.Cu")
		(net "P0V8_PEX1")
	)
	(via
		(at 183.82488 -293.52494)
		(size 0.4064)
		(drill 0.2032)
		(layers "F.Cu" "B.Cu")
		(net "P0V8_PEX1")
	)
	(via
		(at 132.270754 -300.842934)
		(size 0.508)
		(drill 0.254)
		(layers "F.Cu" "B.Cu")
		(net "P0V8_PEX1")
	)
	(via
		(at 165.774878 -300.174914)
		(size 0.4064)
		(drill 0.2032)
		(layers "F.Cu" "B.Cu")
		(net "P0V8_PEX1")
	)
	(via
		(at 181.92496 -296.37482)
		(size 0.4064)
		(drill 0.2032)
		(layers "F.Cu" "B.Cu")
		(net "P0V8_PEX1")
	)
	(via
		(at 129.682748 -310.437276)
		(size 0.508)
		(drill 0.254)
		(layers "F.Cu" "B.Cu")
		(net "P0V8_PEX1")
	)
	(via
		(at 127.650748 -311.453276)
		(size 0.508)
		(drill 0.254)
		(layers "F.Cu" "B.Cu")
		(net "P0V8_PEX1")
	)
	(via
		(at 130.698748 -312.469276)
		(size 0.508)
		(drill 0.254)
		(layers "F.Cu" "B.Cu")
		(net "P0V8_PEX1")
	)
	(via
		(at 129.682748 -316.533276)
		(size 0.508)
		(drill 0.254)
		(layers "F.Cu" "B.Cu")
		(net "P0V8_PEX1")
	)
	(via
		(at 125.810772 -295.245536)
		(size 0.508)
		(drill 0.254)
		(layers "F.Cu" "B.Cu")
		(net "P0V8_PEX1")
	)
	(via
		(at 128.638554 -300.154086)
		(size 0.508)
		(drill 0.254)
		(layers "F.Cu" "B.Cu")
		(net "P0V8_PEX1")
	)
	(via
		(at 129.682748 -314.501276)
		(size 0.508)
		(drill 0.254)
		(layers "F.Cu" "B.Cu")
		(net "P0V8_PEX1")
	)
	(via
		(at 121.170192 -296.515536)
		(size 0.508)
		(drill 0.254)
		(layers "F.Cu" "B.Cu")
		(net "P0V8_PEX1")
	)
	(via
		(at 121.798334 -301.424086)
		(size 0.508)
		(drill 0.254)
		(layers "F.Cu" "B.Cu")
		(net "P0V8_PEX1")
	)
	(via
		(at 126.634748 -312.469276)
		(size 0.508)
		(drill 0.254)
		(layers "F.Cu" "B.Cu")
		(net "P0V8_PEX1")
	)
	(via
		(at 167.675052 -293.52494)
		(size 0.4064)
		(drill 0.2032)
		(layers "F.Cu" "B.Cu")
		(net "P0V8_PEX1")
	)
	(via
		(at 180.975 -294.4749)
		(size 0.4064)
		(drill 0.2032)
		(layers "F.Cu" "B.Cu")
		(net "P0V8_PEX1")
	)
	(via
		(at 131.714748 -313.485276)
		(size 0.508)
		(drill 0.254)
		(layers "F.Cu" "B.Cu")
		(net "P0V8_PEX1")
	)
	(via
		(at 179.07508 -294.4749)
		(size 0.4064)
		(drill 0.2032)
		(layers "F.Cu" "B.Cu")
		(net "P0V8_PEX1")
	)
	(via
		(at 132.858764 -302.925734)
		(size 0.508)
		(drill 0.254)
		(layers "F.Cu" "B.Cu")
		(net "P0V8_PEX1")
	)
	(via
		(at 128.238504 -297.785536)
		(size 0.508)
		(drill 0.254)
		(layers "F.Cu" "B.Cu")
		(net "P0V8_PEX1")
	)
	(via
		(at 129.682748 -315.517276)
		(size 0.508)
		(drill 0.254)
		(layers "F.Cu" "B.Cu")
		(net "P0V8_PEX1")
	)
	(via
		(at 125.810772 -295.880536)
		(size 0.508)
		(drill 0.254)
		(layers "F.Cu" "B.Cu")
		(net "P0V8_PEX1")
	)
	(via
		(at 129.682748 -312.469276)
		(size 0.508)
		(drill 0.254)
		(layers "F.Cu" "B.Cu")
		(net "P0V8_PEX1")
	)
	(via
		(at 120.535192 -298.420536)
		(size 0.508)
		(drill 0.254)
		(layers "F.Cu" "B.Cu")
		(net "P0V8_PEX1")
	)
	(via
		(at 129.682748 -313.485276)
		(size 0.508)
		(drill 0.254)
		(layers "F.Cu" "B.Cu")
		(net "P0V8_PEX1")
	)
	(via
		(at 128.666748 -313.485276)
		(size 0.508)
		(drill 0.254)
		(layers "F.Cu" "B.Cu")
		(net "P0V8_PEX1")
	)
	(via
		(at 127.650748 -310.437276)
		(size 0.508)
		(drill 0.254)
		(layers "F.Cu" "B.Cu")
		(net "P0V8_PEX1")
	)
	(via
		(at 132.244084 -298.420536)
		(size 0.508)
		(drill 0.254)
		(layers "F.Cu" "B.Cu")
		(net "P0V8_PEX1")
	)
	(via
		(at 132.879084 -297.785536)
		(size 0.508)
		(drill 0.254)
		(layers "F.Cu" "B.Cu")
		(net "P0V8_PEX1")
	)
	(via
		(at 181.92496 -298.27474)
		(size 0.4064)
		(drill 0.2032)
		(layers "F.Cu" "B.Cu")
		(net "P0V8_PEX1")
	)
	(via
		(at 126.634748 -316.533276)
		(size 0.508)
		(drill 0.254)
		(layers "F.Cu" "B.Cu")
		(net "P0V8_PEX1")
	)
	(via
		(at 178.124866 -296.37482)
		(size 0.4064)
		(drill 0.2032)
		(layers "F.Cu" "B.Cu")
		(net "P0V8_PEX1")
	)
	(via
		(at 169.574972 -293.52494)
		(size 0.4064)
		(drill 0.2032)
		(layers "F.Cu" "B.Cu")
		(net "P0V8_PEX1")
	)
	(via
		(at 180.02504 -293.52494)
		(size 0.4064)
		(drill 0.2032)
		(layers "F.Cu" "B.Cu")
		(net "P0V8_PEX1")
	)
	(via
		(at 125.618748 -311.453276)
		(size 0.508)
		(drill 0.254)
		(layers "F.Cu" "B.Cu")
		(net "P0V8_PEX1")
	)
	(via
		(at 126.018544 -302.925734)
		(size 0.508)
		(drill 0.254)
		(layers "F.Cu" "B.Cu")
		(net "P0V8_PEX1")
	)
	(via
		(at 125.618748 -310.437276)
		(size 0.508)
		(drill 0.254)
		(layers "F.Cu" "B.Cu")
		(net "P0V8_PEX1")
	)
	(via
		(at 128.238504 -295.245536)
		(size 0.508)
		(drill 0.254)
		(layers "F.Cu" "B.Cu")
		(net "P0V8_PEX1")
	)
	(via
		(at 170.524932 -294.4749)
		(size 0.4064)
		(drill 0.2032)
		(layers "F.Cu" "B.Cu")
		(net "P0V8_PEX1")
	)
	(via
		(at 170.524932 -297.32478)
		(size 0.4064)
		(drill 0.2032)
		(layers "F.Cu" "B.Cu")
		(net "P0V8_PEX1")
	)
	(via
		(at 177.174906 -297.32478)
		(size 0.4064)
		(drill 0.2032)
		(layers "F.Cu" "B.Cu")
		(net "P0V8_PEX1")
	)
	(via
		(at 127.650748 -312.469276)
		(size 0.508)
		(drill 0.254)
		(layers "F.Cu" "B.Cu")
		(net "P0V8_PEX1")
	)
	(via
		(at 124.630434 -302.290734)
		(size 0.508)
		(drill 0.254)
		(layers "F.Cu" "B.Cu")
		(net "P0V8_PEX1")
	)
	(via
		(at 178.124866 -293.52494)
		(size 0.4064)
		(drill 0.2032)
		(layers "F.Cu" "B.Cu")
		(net "P0V8_PEX1")
	)
	(via
		(at 166.725092 -294.4749)
		(size 0.4064)
		(drill 0.2032)
		(layers "F.Cu" "B.Cu")
		(net "P0V8_PEX1")
	)
	(via
		(at 132.270754 -300.207934)
		(size 0.508)
		(drill 0.254)
		(layers "F.Cu" "B.Cu")
		(net "P0V8_PEX1")
	)
	(via
		(at 128.666748 -311.453276)
		(size 0.508)
		(drill 0.254)
		(layers "F.Cu" "B.Cu")
		(net "P0V8_PEX1")
	)
	(via
		(at 132.244084 -295.880536)
		(size 0.508)
		(drill 0.254)
		(layers "F.Cu" "B.Cu")
		(net "P0V8_PEX1")
	)
	(via
		(at 121.798334 -300.789086)
		(size 0.508)
		(drill 0.254)
		(layers "F.Cu" "B.Cu")
		(net "P0V8_PEX1")
	)
	(via
		(at 176.224946 -296.37482)
		(size 0.4064)
		(drill 0.2032)
		(layers "F.Cu" "B.Cu")
		(net "P0V8_PEX1")
	)
	(via
		(at 125.810772 -297.150536)
		(size 0.508)
		(drill 0.254)
		(layers "F.Cu" "B.Cu")
		(net "P0V8_PEX1")
	)
	(via
		(at 180.02504 -298.27474)
		(size 0.4064)
		(drill 0.2032)
		(layers "F.Cu" "B.Cu")
		(net "P0V8_PEX1")
	)
	(via
		(at 132.730748 -311.453276)
		(size 0.508)
		(drill 0.254)
		(layers "F.Cu" "B.Cu")
		(net "P0V8_PEX1")
	)
	(via
		(at 128.238504 -296.515536)
		(size 0.508)
		(drill 0.254)
		(layers "F.Cu" "B.Cu")
		(net "P0V8_PEX1")
	)
	(via
		(at 128.666748 -315.517276)
		(size 0.508)
		(drill 0.254)
		(layers "F.Cu" "B.Cu")
		(net "P0V8_PEX1")
	)
	(via
		(at 125.175772 -296.515536)
		(size 0.508)
		(drill 0.254)
		(layers "F.Cu" "B.Cu")
		(net "P0V8_PEX1")
	)
	(via
		(at 134.239 -281.01671)
		(size 0.508)
		(drill 0.254)
		(layers "F.Cu" "B.Cu")
		(net "P0V8_PEX1")
	)
	(via
		(at 173.375066 -298.27474)
		(size 0.4064)
		(drill 0.2032)
		(layers "F.Cu" "B.Cu")
		(net "P0V8_PEX1")
	)
	(via
		(at 128.666748 -314.501276)
		(size 0.508)
		(drill 0.254)
		(layers "F.Cu" "B.Cu")
		(net "P0V8_PEX1")
	)
	(via
		(at 171.474892 -296.37482)
		(size 0.4064)
		(drill 0.2032)
		(layers "F.Cu" "B.Cu")
		(net "P0V8_PEX1")
	)
	(via
		(at 121.798334 -299.519086)
		(size 0.508)
		(drill 0.254)
		(layers "F.Cu" "B.Cu")
		(net "P0V8_PEX1")
	)
	(via
		(at 166.725092 -297.32478)
		(size 0.4064)
		(drill 0.2032)
		(layers "F.Cu" "B.Cu")
		(net "P0V8_PEX1")
	)
	(via
		(at 168.625012 -297.32478)
		(size 0.4064)
		(drill 0.2032)
		(layers "F.Cu" "B.Cu")
		(net "P0V8_PEX1")
	)
	(via
		(at 127.650748 -315.517276)
		(size 0.508)
		(drill 0.254)
		(layers "F.Cu" "B.Cu")
		(net "P0V8_PEX1")
	)
	(via
		(at 132.244084 -295.245536)
		(size 0.508)
		(drill 0.254)
		(layers "F.Cu" "B.Cu")
		(net "P0V8_PEX1")
	)
	(via
		(at 125.175772 -295.245536)
		(size 0.508)
		(drill 0.254)
		(layers "F.Cu" "B.Cu")
		(net "P0V8_PEX1")
	)
	(via
		(at 168.625012 -294.4749)
		(size 0.4064)
		(drill 0.2032)
		(layers "F.Cu" "B.Cu")
		(net "P0V8_PEX1")
	)
	(via
		(at 120.535192 -297.150536)
		(size 0.508)
		(drill 0.254)
		(layers "F.Cu" "B.Cu")
		(net "P0V8_PEX1")
	)
	(via
		(at 164.824918 -299.224954)
		(size 0.4064)
		(drill 0.2032)
		(layers "F.Cu" "B.Cu")
		(net "P0V8_PEX1")
	)
	(via
		(at 174.325026 -297.32478)
		(size 0.4064)
		(drill 0.2032)
		(layers "F.Cu" "B.Cu")
		(net "P0V8_PEX1")
	)
	(via
		(at 121.170192 -297.785536)
		(size 0.508)
		(drill 0.254)
		(layers "F.Cu" "B.Cu")
		(net "P0V8_PEX1")
	)
	(via
		(at 126.634748 -310.437276)
		(size 0.508)
		(drill 0.254)
		(layers "F.Cu" "B.Cu")
		(net "P0V8_PEX1")
	)
	(via
		(at 180.02504 -296.37482)
		(size 0.4064)
		(drill 0.2032)
		(layers "F.Cu" "B.Cu")
		(net "P0V8_PEX1")
	)
	(via
		(at 125.810772 -297.785536)
		(size 0.508)
		(drill 0.254)
		(layers "F.Cu" "B.Cu")
		(net "P0V8_PEX1")
	)
	(via
		(at 127.650748 -314.501276)
		(size 0.508)
		(drill 0.254)
		(layers "F.Cu" "B.Cu")
		(net "P0V8_PEX1")
	)
	(via
		(at 127.650748 -294.1828)
		(size 0.508)
		(drill 0.254)
		(layers "F.Cu" "B.Cu")
		(net "P0V8_PEX1")
	)
	(via
		(at 128.638554 -300.789086)
		(size 0.508)
		(drill 0.254)
		(layers "F.Cu" "B.Cu")
		(net "P0V8_PEX1")
	)
	(via
		(at 171.474892 -293.52494)
		(size 0.4064)
		(drill 0.2032)
		(layers "F.Cu" "B.Cu")
		(net "P0V8_PEX1")
	)
	(via
		(at 128.050544 -302.925734)
		(size 0.508)
		(drill 0.254)
		(layers "F.Cu" "B.Cu")
		(net "P0V8_PEX1")
	)
	(via
		(at 125.618748 -314.501276)
		(size 0.508)
		(drill 0.254)
		(layers "F.Cu" "B.Cu")
		(net "P0V8_PEX1")
	)
	(via
		(at 126.634748 -314.501276)
		(size 0.508)
		(drill 0.254)
		(layers "F.Cu" "B.Cu")
		(net "P0V8_PEX1")
	)
	(via
		(at 128.666748 -316.533276)
		(size 0.508)
		(drill 0.254)
		(layers "F.Cu" "B.Cu")
		(net "P0V8_PEX1")
	)
	(via
		(at 126.078488 -280.999692)
		(size 0.508)
		(drill 0.254)
		(layers "F.Cu" "B.Cu")
		(net "P0V8_PEX1")
	)
	(via
		(at 164.824918 -294.4749)
		(size 0.4064)
		(drill 0.2032)
		(layers "F.Cu" "B.Cu")
		(net "P0V8_PEX1")
	)
	(via
		(at 130.698748 -311.453276)
		(size 0.508)
		(drill 0.254)
		(layers "F.Cu" "B.Cu")
		(net "P0V8_PEX1")
	)
	(via
		(at 183.82488 -298.27474)
		(size 0.4064)
		(drill 0.2032)
		(layers "F.Cu" "B.Cu")
		(net "P0V8_PEX1")
	)
	(via
		(at 132.879084 -296.515536)
		(size 0.508)
		(drill 0.254)
		(layers "F.Cu" "B.Cu")
		(net "P0V8_PEX1")
	)
	(via
		(at 126.018544 -302.290734)
		(size 0.508)
		(drill 0.254)
		(layers "F.Cu" "B.Cu")
		(net "P0V8_PEX1")
	)
	(via
		(at 119.0879 -294.851836)
		(size 0.508)
		(drill 0.254)
		(layers "F.Cu" "B.Cu")
		(net "P0V8_PEX1")
	)
	(via
		(at 173.375066 -293.52494)
		(size 0.4064)
		(drill 0.2032)
		(layers "F.Cu" "B.Cu")
		(net "P0V8_PEX1")
	)
	(via
		(at 120.535192 -295.245536)
		(size 0.508)
		(drill 0.254)
		(layers "F.Cu" "B.Cu")
		(net "P0V8_PEX1")
	)
	(via
		(at 125.175772 -297.150536)
		(size 0.508)
		(drill 0.254)
		(layers "F.Cu" "B.Cu")
		(net "P0V8_PEX1")
	)
	(via
		(at 127.603504 -296.515536)
		(size 0.508)
		(drill 0.254)
		(layers "F.Cu" "B.Cu")
		(net "P0V8_PEX1")
	)
	(via
		(at 132.270754 -301.477934)
		(size 0.508)
		(drill 0.254)
		(layers "F.Cu" "B.Cu")
		(net "P0V8_PEX1")
	)
	(via
		(at 125.810772 -296.515536)
		(size 0.508)
		(drill 0.254)
		(layers "F.Cu" "B.Cu")
		(net "P0V8_PEX1")
	)
	(via
		(at 125.618748 -316.533276)
		(size 0.508)
		(drill 0.254)
		(layers "F.Cu" "B.Cu")
		(net "P0V8_PEX1")
	)
	(via
		(at 127.603504 -295.245536)
		(size 0.508)
		(drill 0.254)
		(layers "F.Cu" "B.Cu")
		(net "P0V8_PEX1")
	)
	(via
		(at 128.638554 -299.519086)
		(size 0.508)
		(drill 0.254)
		(layers "F.Cu" "B.Cu")
		(net "P0V8_PEX1")
	)
	(via
		(at 131.714748 -310.437276)
		(size 0.508)
		(drill 0.254)
		(layers "F.Cu" "B.Cu")
		(net "P0V8_PEX1")
	)
	(via
		(at 127.603504 -298.420536)
		(size 0.508)
		(drill 0.254)
		(layers "F.Cu" "B.Cu")
		(net "P0V8_PEX1")
	)
	(via
		(at 180.975 -297.32478)
		(size 0.4064)
		(drill 0.2032)
		(layers "F.Cu" "B.Cu")
		(net "P0V8_PEX1")
	)
	(via
		(at 125.618748 -313.485276)
		(size 0.508)
		(drill 0.254)
		(layers "F.Cu" "B.Cu")
		(net "P0V8_PEX1")
	)
	(via
		(at 127.650748 -313.485276)
		(size 0.508)
		(drill 0.254)
		(layers "F.Cu" "B.Cu")
		(net "P0V8_PEX1")
	)
	(via
		(at 121.170192 -297.150536)
		(size 0.508)
		(drill 0.254)
		(layers "F.Cu" "B.Cu")
		(net "P0V8_PEX1")
	)
	(via
		(at 121.210324 -302.290734)
		(size 0.508)
		(drill 0.254)
		(layers "F.Cu" "B.Cu")
		(net "P0V8_PEX1")
	)
	(via
		(at 132.730748 -310.437276)
		(size 0.508)
		(drill 0.254)
		(layers "F.Cu" "B.Cu")
		(net "P0V8_PEX1")
	)
	(via
		(at 124.630434 -302.925734)
		(size 0.508)
		(drill 0.254)
		(layers "F.Cu" "B.Cu")
		(net "P0V8_PEX1")
	)
	(via
		(at 128.666748 -312.469276)
		(size 0.508)
		(drill 0.254)
		(layers "F.Cu" "B.Cu")
		(net "P0V8_PEX1")
	)
	(via
		(at 126.634748 -315.517276)
		(size 0.508)
		(drill 0.254)
		(layers "F.Cu" "B.Cu")
		(net "P0V8_PEX1")
	)
	(via
		(at 125.430534 -301.477934)
		(size 0.508)
		(drill 0.254)
		(layers "F.Cu" "B.Cu")
		(net "P0V8_PEX1")
	)
	(via
		(at 121.170192 -298.420536)
		(size 0.508)
		(drill 0.254)
		(layers "F.Cu" "B.Cu")
		(net "P0V8_PEX1")
	)
	(via
		(at 132.244084 -297.785536)
		(size 0.508)
		(drill 0.254)
		(layers "F.Cu" "B.Cu")
		(net "P0V8_PEX1")
	)
	(via
		(at 128.666748 -310.437276)
		(size 0.508)
		(drill 0.254)
		(layers "F.Cu" "B.Cu")
		(net "P0V8_PEX1")
	)
	(via
		(at 125.618748 -312.469276)
		(size 0.508)
		(drill 0.254)
		(layers "F.Cu" "B.Cu")
		(net "P0V8_PEX1")
	)
	(via
		(at 127.603504 -295.880536)
		(size 0.508)
		(drill 0.254)
		(layers "F.Cu" "B.Cu")
		(net "P0V8_PEX1")
	)
	(segment
		(start 184.03316 -298.27474)
		(end 183.82488 -298.27474)
		(width 0.3048)
		(layer "B.Cu")
		(net "P0V8_PEX1")
	)
	(segment
		(start 126.078488 -281.640534)
		(end 126.078488 -280.999692)
		(width 0.254)
		(layer "B.Cu")
		(net "P0V8_PEX1")
	)
	(segment
		(start 134.239 -281.640534)
		(end 134.239 -281.01671)
		(width 0.254)
		(layer "B.Cu")
		(net "P0V8_PEX1")
	)
	(segment
		(start 184.03316 -293.52494)
		(end 183.82488 -293.52494)
		(width 0.3048)
		(layer "B.Cu")
		(net "P0V8_PEX1")
	)
	(segment
		(start 133.336284 -286.179514)
		(end 134.952994 -284.562804)
		(width 0.254)
		(layer "In5.Cu")
		(net "P0V8_PEX1")
	)
	(segment
		(start 134.952994 -284.562804)
		(end 134.952994 -282.540456)
		(width 0.254)
		(layer "In5.Cu")
		(net "P0V8_PEX1")
	)
	(segment
		(start 133.336284 -294.788336)
		(end 133.336284 -286.179514)
		(width 0.254)
		(layer "In5.Cu")
		(net "P0V8_PEX1")
	)
	(segment
		(start 134.952994 -282.540456)
		(end 134.239 -281.826462)
		(width 0.254)
		(layer "In5.Cu")
		(net "P0V8_PEX1")
	)
	(segment
		(start 132.879084 -295.245536)
		(end 133.336284 -294.788336)
		(width 0.254)
		(layer "In5.Cu")
		(net "P0V8_PEX1")
	)
	(segment
		(start 125.175772 -283.316934)
		(end 126.078488 -282.414218)
		(width 0.254)
		(layer "In5.Cu")
		(net "P0V8_PEX1")
	)
	(segment
		(start 134.239 -281.826462)
		(end 134.239 -281.01671)
		(width 0.254)
		(layer "In5.Cu")
		(net "P0V8_PEX1")
	)
	(segment
		(start 125.175772 -295.245536)
		(end 125.175772 -283.316934)
		(width 0.254)
		(layer "In5.Cu")
		(net "P0V8_PEX1")
	)
	(segment
		(start 126.078488 -282.414218)
		(end 126.078488 -280.999692)
		(width 0.254)
		(layer "In5.Cu")
		(net "P0V8_PEX1")
	)
	(via
		(at 105.41381 -276.40407)
		(size 0.508)
		(drill 0.254)
		(layers "F.Cu" "B.Cu")
		(net "SW_P12V_P0V8_PEX0_FLT")
	)
	(via
		(at 109.443012 -275.416264)
		(size 0.508)
		(drill 0.254)
		(layers "F.Cu" "B.Cu")
		(net "SW_P12V_P0V8_PEX0_FLT")
	)
	(via
		(at 103.37673 -282.091638)
		(size 0.508)
		(drill 0.254)
		(layers "F.Cu" "B.Cu")
		(net "SW_P12V_P0V8_PEX0_FLT")
	)
	(via
		(at 104.645206 -274.955254)
		(size 0.508)
		(drill 0.254)
		(layers "F.Cu" "B.Cu")
		(net "SW_P12V_P0V8_PEX0_FLT")
	)
	(via
		(at 103.88981 -275.64207)
		(size 0.508)
		(drill 0.254)
		(layers "F.Cu" "B.Cu")
		(net "SW_P12V_P0V8_PEX0_FLT")
	)
	(via
		(at 103.847138 -277.102824)
		(size 0.508)
		(drill 0.254)
		(layers "F.Cu" "B.Cu")
		(net "SW_P12V_P0V8_PEX0_FLT")
	)
	(via
		(at 103.944674 -284.175454)
		(size 0.508)
		(drill 0.254)
		(layers "F.Cu" "B.Cu")
		(net "SW_P12V_P0V8_PEX0_FLT")
	)
	(via
		(at 104.65181 -275.64207)
		(size 0.508)
		(drill 0.254)
		(layers "F.Cu" "B.Cu")
		(net "SW_P12V_P0V8_PEX0_FLT")
	)
	(via
		(at 102.28453 -282.904438)
		(size 0.508)
		(drill 0.254)
		(layers "F.Cu" "B.Cu")
		(net "SW_P12V_P0V8_PEX0_FLT")
	)
	(via
		(at 110.078012 -274.781264)
		(size 0.508)
		(drill 0.254)
		(layers "F.Cu" "B.Cu")
		(net "SW_P12V_P0V8_PEX0_FLT")
	)
	(via
		(at 110.445042 -281.431238)
		(size 0.508)
		(drill 0.254)
		(layers "F.Cu" "B.Cu")
		(net "SW_P12V_P0V8_PEX0_FLT")
	)
	(via
		(at 110.445042 -282.904438)
		(size 0.508)
		(drill 0.254)
		(layers "F.Cu" "B.Cu")
		(net "SW_P12V_P0V8_PEX0_FLT")
	)
	(via
		(at 112.105186 -284.175454)
		(size 0.508)
		(drill 0.254)
		(layers "F.Cu" "B.Cu")
		(net "SW_P12V_P0V8_PEX0_FLT")
	)
	(via
		(at 111.003842 -282.548838)
		(size 0.508)
		(drill 0.254)
		(layers "F.Cu" "B.Cu")
		(net "SW_P12V_P0V8_PEX0_FLT")
	)
	(via
		(at 102.84333 -282.548838)
		(size 0.508)
		(drill 0.254)
		(layers "F.Cu" "B.Cu")
		(net "SW_P12V_P0V8_PEX0_FLT")
	)
	(via
		(at 102.28453 -281.431238)
		(size 0.508)
		(drill 0.254)
		(layers "F.Cu" "B.Cu")
		(net "SW_P12V_P0V8_PEX0_FLT")
	)
	(via
		(at 110.805976 -277.644352)
		(size 0.508)
		(drill 0.254)
		(layers "F.Cu" "B.Cu")
		(net "SW_P12V_P0V8_PEX0_FLT")
	)
	(via
		(at 110.445042 -282.167838)
		(size 0.508)
		(drill 0.254)
		(layers "F.Cu" "B.Cu")
		(net "SW_P12V_P0V8_PEX0_FLT")
	)
	(via
		(at 105.41381 -275.64207)
		(size 0.508)
		(drill 0.254)
		(layers "F.Cu" "B.Cu")
		(net "SW_P12V_P0V8_PEX0_FLT")
	)
	(via
		(at 104.66832 -282.866592)
		(size 0.508)
		(drill 0.254)
		(layers "F.Cu" "B.Cu")
		(net "SW_P12V_P0V8_PEX0_FLT")
	)
	(via
		(at 111.537242 -282.091638)
		(size 0.508)
		(drill 0.254)
		(layers "F.Cu" "B.Cu")
		(net "SW_P12V_P0V8_PEX0_FLT")
	)
	(via
		(at 110.978442 -281.786838)
		(size 0.508)
		(drill 0.254)
		(layers "F.Cu" "B.Cu")
		(net "SW_P12V_P0V8_PEX0_FLT")
	)
	(via
		(at 111.511842 -281.431238)
		(size 0.508)
		(drill 0.254)
		(layers "F.Cu" "B.Cu")
		(net "SW_P12V_P0V8_PEX0_FLT")
	)
	(via
		(at 103.88981 -276.27707)
		(size 0.508)
		(drill 0.254)
		(layers "F.Cu" "B.Cu")
		(net "SW_P12V_P0V8_PEX0_FLT")
	)
	(via
		(at 109.443012 -274.781264)
		(size 0.508)
		(drill 0.254)
		(layers "F.Cu" "B.Cu")
		(net "SW_P12V_P0V8_PEX0_FLT")
	)
	(via
		(at 103.35133 -281.431238)
		(size 0.508)
		(drill 0.254)
		(layers "F.Cu" "B.Cu")
		(net "SW_P12V_P0V8_PEX0_FLT")
	)
	(via
		(at 110.078012 -277.321264)
		(size 0.508)
		(drill 0.254)
		(layers "F.Cu" "B.Cu")
		(net "SW_P12V_P0V8_PEX0_FLT")
	)
	(via
		(at 110.078012 -276.686264)
		(size 0.508)
		(drill 0.254)
		(layers "F.Cu" "B.Cu")
		(net "SW_P12V_P0V8_PEX0_FLT")
	)
	(via
		(at 102.81793 -281.786838)
		(size 0.508)
		(drill 0.254)
		(layers "F.Cu" "B.Cu")
		(net "SW_P12V_P0V8_PEX0_FLT")
	)
	(via
		(at 103.883206 -274.955254)
		(size 0.508)
		(drill 0.254)
		(layers "F.Cu" "B.Cu")
		(net "SW_P12V_P0V8_PEX0_FLT")
	)
	(via
		(at 110.078012 -275.416264)
		(size 0.508)
		(drill 0.254)
		(layers "F.Cu" "B.Cu")
		(net "SW_P12V_P0V8_PEX0_FLT")
	)
	(via
		(at 112.828832 -282.866592)
		(size 0.508)
		(drill 0.254)
		(layers "F.Cu" "B.Cu")
		(net "SW_P12V_P0V8_PEX0_FLT")
	)
	(via
		(at 109.443012 -276.051264)
		(size 0.508)
		(drill 0.254)
		(layers "F.Cu" "B.Cu")
		(net "SW_P12V_P0V8_PEX0_FLT")
	)
	(via
		(at 102.28453 -282.167838)
		(size 0.508)
		(drill 0.254)
		(layers "F.Cu" "B.Cu")
		(net "SW_P12V_P0V8_PEX0_FLT")
	)
	(via
		(at 110.078012 -276.051264)
		(size 0.508)
		(drill 0.254)
		(layers "F.Cu" "B.Cu")
		(net "SW_P12V_P0V8_PEX0_FLT")
	)
	(via
		(at 104.65181 -276.40407)
		(size 0.508)
		(drill 0.254)
		(layers "F.Cu" "B.Cu")
		(net "SW_P12V_P0V8_PEX0_FLT")
	)
	(via
		(at 105.407206 -274.955254)
		(size 0.508)
		(drill 0.254)
		(layers "F.Cu" "B.Cu")
		(net "SW_P12V_P0V8_PEX0_FLT")
	)
	(via
		(at 113.463832 -282.866592)
		(size 0.508)
		(drill 0.254)
		(layers "F.Cu" "B.Cu")
		(net "SW_P12V_P0V8_PEX0_FLT")
	)
	(via
		(at 111.736632 -282.866592)
		(size 0.508)
		(drill 0.254)
		(layers "F.Cu" "B.Cu")
		(net "SW_P12V_P0V8_PEX0_FLT")
	)
	(via
		(at 104.723438 -277.171658)
		(size 0.508)
		(drill 0.254)
		(layers "F.Cu" "B.Cu")
		(net "SW_P12V_P0V8_PEX0_FLT")
	)
	(via
		(at 112.105186 -283.489654)
		(size 0.508)
		(drill 0.254)
		(layers "F.Cu" "B.Cu")
		(net "SW_P12V_P0V8_PEX0_FLT")
	)
	(via
		(at 110.805976 -276.933152)
		(size 0.508)
		(drill 0.254)
		(layers "F.Cu" "B.Cu")
		(net "SW_P12V_P0V8_PEX0_FLT")
	)
	(via
		(at 105.30332 -282.866592)
		(size 0.508)
		(drill 0.254)
		(layers "F.Cu" "B.Cu")
		(net "SW_P12V_P0V8_PEX0_FLT")
	)
	(via
		(at 103.57612 -282.866592)
		(size 0.508)
		(drill 0.254)
		(layers "F.Cu" "B.Cu")
		(net "SW_P12V_P0V8_PEX0_FLT")
	)
	(via
		(at 103.847138 -277.864824)
		(size 0.508)
		(drill 0.254)
		(layers "F.Cu" "B.Cu")
		(net "SW_P12V_P0V8_PEX0_FLT")
	)
	(segment
		(start 189.049914 -301.599854)
		(end 188.574934 -302.074834)
		(width 0.127)
		(layer "F.Cu")
		(net "VSENSE_P0V8_PEX1_SKT_VRTN")
	)
	(via
		(at 188.574934 -302.074834)
		(size 0.4064)
		(drill 0.2032)
		(layers "F.Cu" "B.Cu")
		(net "VSENSE_P0V8_PEX1_SKT_VRTN")
	)
	(via
		(at 136.797288 -327.442322)
		(size 0.6604)
		(drill 0.3302)
		(layers "F.Cu" "B.Cu")
		(net "VSENSE_P0V8_PEX1_SKT_VRTN")
	)
	(segment
		(start 175.084486 -320.626232)
		(end 174.489364 -321.221354)
		(width 0.254)
		(layer "B.Cu")
		(net "VSENSE_P0V8_PEX1_SKT_VRTN")
	)
	(segment
		(start 174.489364 -321.221354)
		(end 158.821882 -327.711054)
		(width 0.254)
		(layer "B.Cu")
		(net "VSENSE_P0V8_PEX1_SKT_VRTN")
	)
	(segment
		(start 137.06602 -327.711054)
		(end 136.797288 -327.442322)
		(width 0.254)
		(layer "B.Cu")
		(net "VSENSE_P0V8_PEX1_SKT_VRTN")
	)
	(segment
		(start 175.168306 -307.914294)
		(end 175.168306 -320.1289)
		(width 0.09906)
		(layer "B.Cu")
		(net "VSENSE_P0V8_PEX1_SKT_VRTN")
	)
	(segment
		(start 188.844174 -302.074834)
		(end 188.943234 -302.173894)
		(width 0.09906)
		(layer "B.Cu")
		(net "VSENSE_P0V8_PEX1_SKT_VRTN")
	)
	(segment
		(start 175.889412 -307.193188)
		(end 175.168306 -307.914294)
		(width 0.09906)
		(layer "B.Cu")
		(net "VSENSE_P0V8_PEX1_SKT_VRTN")
	)
	(segment
		(start 187.043314 -306.989734)
		(end 186.83986 -307.193188)
		(width 0.09906)
		(layer "B.Cu")
		(net "VSENSE_P0V8_PEX1_SKT_VRTN")
	)
	(segment
		(start 187.043314 -302.770286)
		(end 187.043314 -306.989734)
		(width 0.09906)
		(layer "B.Cu")
		(net "VSENSE_P0V8_PEX1_SKT_VRTN")
	)
	(segment
		(start 175.168306 -320.1289)
		(end 175.084486 -320.21272)
		(width 0.09906)
		(layer "B.Cu")
		(net "VSENSE_P0V8_PEX1_SKT_VRTN")
	)
	(segment
		(start 134.692644 -327.3552)
		(end 135.023098 -327.711054)
		(width 0.254)
		(layer "B.Cu")
		(net "VSENSE_P0V8_PEX1_SKT_VRTN")
	)
	(segment
		(start 188.943234 -302.314102)
		(end 188.814202 -302.443134)
		(width 0.09906)
		(layer "B.Cu")
		(net "VSENSE_P0V8_PEX1_SKT_VRTN")
	)
	(segment
		(start 158.821882 -327.711054)
		(end 137.06602 -327.711054)
		(width 0.254)
		(layer "B.Cu")
		(net "VSENSE_P0V8_PEX1_SKT_VRTN")
	)
	(segment
		(start 135.023098 -327.711054)
		(end 136.528556 -327.711054)
		(width 0.254)
		(layer "B.Cu")
		(net "VSENSE_P0V8_PEX1_SKT_VRTN")
	)
	(segment
		(start 175.084486 -320.21272)
		(end 175.084486 -320.251328)
		(width 0.09906)
		(layer "B.Cu")
		(net "VSENSE_P0V8_PEX1_SKT_VRTN")
	)
	(segment
		(start 187.370466 -302.443134)
		(end 187.043314 -302.770286)
		(width 0.09906)
		(layer "B.Cu")
		(net "VSENSE_P0V8_PEX1_SKT_VRTN")
	)
	(segment
		(start 188.943234 -302.173894)
		(end 188.943234 -302.314102)
		(width 0.09906)
		(layer "B.Cu")
		(net "VSENSE_P0V8_PEX1_SKT_VRTN")
	)
	(segment
		(start 188.814202 -302.443134)
		(end 187.370466 -302.443134)
		(width 0.09906)
		(layer "B.Cu")
		(net "VSENSE_P0V8_PEX1_SKT_VRTN")
	)
	(segment
		(start 188.574934 -302.074834)
		(end 188.844174 -302.074834)
		(width 0.09906)
		(layer "B.Cu")
		(net "VSENSE_P0V8_PEX1_SKT_VRTN")
	)
	(segment
		(start 136.528556 -327.711054)
		(end 136.797288 -327.442322)
		(width 0.254)
		(layer "B.Cu")
		(net "VSENSE_P0V8_PEX1_SKT_VRTN")
	)
	(segment
		(start 186.83986 -307.193188)
		(end 175.889412 -307.193188)
		(width 0.09906)
		(layer "B.Cu")
		(net "VSENSE_P0V8_PEX1_SKT_VRTN")
	)
	(segment
		(start 175.084486 -320.251328)
		(end 175.084486 -320.626232)
		(width 0.254)
		(layer "B.Cu")
		(net "VSENSE_P0V8_PEX1_SKT_VRTN")
	)
	(segment
		(start 123.175776 -258.195064)
		(end 125.226318 -258.195064)
		(width 0.13208)
		(layer "F.Cu")
		(net "P0V8_PEX0_PINALRT")
	)
	(segment
		(start 125.898402 -257.91668)
		(end 126.699518 -257.115564)
		(width 0.13208)
		(layer "F.Cu")
		(net "P0V8_PEX0_PINALRT")
	)
	(segment
		(start 125.226318 -258.195064)
		(end 125.898402 -257.91668)
		(width 0.13208)
		(layer "F.Cu")
		(net "P0V8_PEX0_PINALRT")
	)
	(segment
		(start 126.699518 -257.115564)
		(end 127.258064 -257.115564)
		(width 0.13208)
		(layer "F.Cu")
		(net "P0V8_PEX0_PINALRT")
	)
	(via
		(at 125.898402 -257.91668)
		(size 0.762)
		(drill 0.381)
		(layers "F.Cu" "B.Cu")
		(net "P0V8_PEX0_PINALRT")
	)
	(segment
		(start 125.56744 -262.17372)
		(end 125.56744 -262.70077)
		(width 0.254)
		(layer "F.Cu")
		(net "SH_P0V8_PEX0_VSEN0_R")
	)
	(segment
		(start 125.91669 -263.05002)
		(end 125.91669 -263.57072)
		(width 0.254)
		(layer "F.Cu")
		(net "SH_P0V8_PEX0_VSEN0_R")
	)
	(segment
		(start 125.56744 -262.70077)
		(end 125.91669 -263.05002)
		(width 0.254)
		(layer "F.Cu")
		(net "SH_P0V8_PEX0_VSEN0_R")
	)
	(segment
		(start 125.91669 -263.57072)
		(end 127.361188 -263.57072)
		(width 0.254)
		(layer "F.Cu")
		(net "SH_P0V8_PEX0_VSEN0_R")
	)
	(via
		(at 127.361188 -263.57072)
		(size 0.762)
		(drill 0.381)
		(layers "F.Cu" "B.Cu")
		(net "SH_P0V8_PEX0_VSEN0_R")
	)
	(segment
		(start 117.706902 -282.821634)
		(end 117.755416 -282.870148)
		(width 0.254)
		(layer "F.Cu")
		(net "P0V8_PEX0_VCC2")
	)
	(segment
		(start 117.67058 -282.821634)
		(end 117.706902 -282.821634)
		(width 0.2286)
		(layer "F.Cu")
		(net "P0V8_PEX0_VCC2")
	)
	(segment
		(start 117.755416 -282.870148)
		(end 117.755416 -283.437584)
		(width 0.254)
		(layer "F.Cu")
		(net "P0V8_PEX0_VCC2")
	)
	(segment
		(start 116.968016 -283.524198)
		(end 117.67058 -282.821634)
		(width 0.2286)
		(layer "F.Cu")
		(net "P0V8_PEX0_VCC2")
	)
	(segment
		(start 116.532152 -283.524198)
		(end 116.968016 -283.524198)
		(width 0.2286)
		(layer "F.Cu")
		(net "P0V8_PEX0_VCC2")
	)
	(via
		(at 117.755416 -283.437584)
		(size 0.508)
		(drill 0.254)
		(layers "F.Cu" "B.Cu")
		(net "P0V8_PEX0_VCC2")
	)
	(segment
		(start 116.224558 -282.566872)
		(end 116.751862 -282.566872)
		(width 0.254)
		(layer "B.Cu")
		(net "P0V8_PEX0_VCC2")
	)
	(segment
		(start 117.090952 -283.437584)
		(end 117.071902 -283.418534)
		(width 0.254)
		(layer "B.Cu")
		(net "P0V8_PEX0_VCC2")
	)
	(segment
		(start 117.755416 -283.437584)
		(end 117.090952 -283.437584)
		(width 0.254)
		(layer "B.Cu")
		(net "P0V8_PEX0_VCC2")
	)
	(segment
		(start 116.216684 -282.558998)
		(end 116.224558 -282.566872)
		(width 0.254)
		(layer "B.Cu")
		(net "P0V8_PEX0_VCC2")
	)
	(segment
		(start 117.071902 -282.886912)
		(end 117.071902 -283.418534)
		(width 0.254)
		(layer "B.Cu")
		(net "P0V8_PEX0_VCC2")
	)
	(segment
		(start 115.233704 -282.251404)
		(end 115.237006 -282.248102)
		(width 0.254)
		(layer "B.Cu")
		(net "P0V8_PEX0_VCC2")
	)
	(segment
		(start 116.751862 -282.566872)
		(end 117.071902 -282.886912)
		(width 0.254)
		(layer "B.Cu")
		(net "P0V8_PEX0_VCC2")
	)
	(segment
		(start 116.094256 -282.558998)
		(end 116.216684 -282.558998)
		(width 0.254)
		(layer "B.Cu")
		(net "P0V8_PEX0_VCC2")
	)
	(segment
		(start 115.78336 -282.248102)
		(end 116.094256 -282.558998)
		(width 0.254)
		(layer "B.Cu")
		(net "P0V8_PEX0_VCC2")
	)
	(segment
		(start 115.237006 -282.248102)
		(end 115.78336 -282.248102)
		(width 0.254)
		(layer "B.Cu")
		(net "P0V8_PEX0_VCC2")
	)
	(segment
		(start 117.596666 -258.79044)
		(end 117.792246 -258.59486)
		(width 0.1524)
		(layer "F.Cu")
		(net "P0V8_PEX0_TSEN_R")
	)
	(segment
		(start 116.81079 -258.79044)
		(end 117.596666 -258.79044)
		(width 0.1524)
		(layer "F.Cu")
		(net "P0V8_PEX0_TSEN_R")
	)
	(segment
		(start 117.792246 -258.59486)
		(end 118.375684 -258.59486)
		(width 0.1524)
		(layer "F.Cu")
		(net "P0V8_PEX0_TSEN_R")
	)
	(via
		(at 116.81079 -258.79044)
		(size 0.508)
		(drill 0.254)
		(layers "F.Cu" "B.Cu")
		(net "P0V8_PEX0_TSEN_R")
	)
	(segment
		(start 116.935758 -258.915408)
		(end 116.81079 -258.79044)
		(width 0.254)
		(layer "B.Cu")
		(net "P0V8_PEX0_TSEN_R")
	)
	(segment
		(start 115.919758 -260.000496)
		(end 116.935758 -260.000496)
		(width 0.254)
		(layer "B.Cu")
		(net "P0V8_PEX0_TSEN_R")
	)
	(segment
		(start 116.935758 -260.000496)
		(end 116.935758 -258.915408)
		(width 0.254)
		(layer "B.Cu")
		(net "P0V8_PEX0_TSEN_R")
	)
	(segment
		(start 113.432082 -280.04897)
		(end 112.470184 -280.04897)
		(width 0.254)
		(layer "F.Cu")
		(net "SW_P0V8_PEX0_BOOT2_R")
	)
	(segment
		(start 131.62915 -281.369262)
		(end 131.698238 -281.12212)
		(width 0.2286)
		(layer "F.Cu")
		(net "P0V8_PEX1_TSEN")
	)
	(segment
		(start 131.698238 -281.12212)
		(end 131.698238 -280.810208)
		(width 0.2286)
		(layer "F.Cu")
		(net "P0V8_PEX1_TSEN")
	)
	(segment
		(start 131.431284 -281.999182)
		(end 131.431284 -281.567128)
		(width 0.2286)
		(layer "F.Cu")
		(net "P0V8_PEX1_TSEN")
	)
	(segment
		(start 123.537726 -281.12212)
		(end 123.537726 -280.810208)
		(width 0.2286)
		(layer "F.Cu")
		(net "P0V8_PEX1_TSEN")
	)
	(segment
		(start 131.431284 -281.567128)
		(end 131.62915 -281.369262)
		(width 0.2286)
		(layer "F.Cu")
		(net "P0V8_PEX1_TSEN")
	)
	(segment
		(start 123.468638 -281.369262)
		(end 123.537726 -281.12212)
		(width 0.2286)
		(layer "F.Cu")
		(net "P0V8_PEX1_TSEN")
	)
	(segment
		(start 123.270772 -281.567128)
		(end 123.468638 -281.369262)
		(width 0.2286)
		(layer "F.Cu")
		(net "P0V8_PEX1_TSEN")
	)
	(segment
		(start 123.270772 -281.999182)
		(end 123.270772 -281.567128)
		(width 0.2286)
		(layer "F.Cu")
		(net "P0V8_PEX1_TSEN")
	)
	(via
		(at 117.95379 -263.787636)
		(size 0.508)
		(drill 0.254)
		(layers "F.Cu" "B.Cu")
		(net "P0V8_PEX1_TSEN")
	)
	(via
		(at 123.537726 -280.810208)
		(size 0.508)
		(drill 0.254)
		(layers "F.Cu" "B.Cu")
		(net "P0V8_PEX1_TSEN")
	)
	(via
		(at 131.698238 -280.810208)
		(size 0.508)
		(drill 0.254)
		(layers "F.Cu" "B.Cu")
		(net "P0V8_PEX1_TSEN")
	)
	(segment
		(start 118.419626 -261.261606)
		(end 118.419626 -263.3218)
		(width 0.254)
		(layer "B.Cu")
		(net "P0V8_PEX1_TSEN")
	)
	(segment
		(start 117.95379 -260.79577)
		(end 118.419626 -261.261606)
		(width 0.254)
		(layer "B.Cu")
		(net "P0V8_PEX1_TSEN")
	)
	(segment
		(start 118.419626 -263.3218)
		(end 117.95379 -263.787636)
		(width 0.254)
		(layer "B.Cu")
		(net "P0V8_PEX1_TSEN")
	)
	(segment
		(start 123.537726 -280.190956)
		(end 124.038868 -279.689814)
		(width 0.254)
		(layer "In7.Cu")
		(net "P0V8_PEX1_TSEN")
	)
	(segment
		(start 130.95859 -278.84501)
		(end 130.95859 -279.38984)
		(width 0.254)
		(layer "In7.Cu")
		(net "P0V8_PEX1_TSEN")
	)
	(segment
		(start 123.537726 -280.810208)
		(end 123.537726 -280.190956)
		(width 0.254)
		(layer "In7.Cu")
		(net "P0V8_PEX1_TSEN")
	)
	(segment
		(start 123.00966 -279.66289)
		(end 123.537726 -280.190956)
		(width 0.254)
		(layer "In7.Cu")
		(net "P0V8_PEX1_TSEN")
	)
	(segment
		(start 124.038868 -279.689814)
		(end 124.038868 -278.650954)
		(width 0.254)
		(layer "In7.Cu")
		(net "P0V8_PEX1_TSEN")
	)
	(segment
		(start 124.038868 -278.650954)
		(end 124.346462 -278.34336)
		(width 0.254)
		(layer "In7.Cu")
		(net "P0V8_PEX1_TSEN")
	)
	(segment
		(start 117.95379 -263.787636)
		(end 117.95379 -278.52497)
		(width 0.254)
		(layer "In7.Cu")
		(net "P0V8_PEX1_TSEN")
	)
	(segment
		(start 126.33833 -279.537414)
		(end 128.588262 -279.537414)
		(width 0.254)
		(layer "In7.Cu")
		(net "P0V8_PEX1_TSEN")
	)
	(segment
		(start 129.782316 -278.34336)
		(end 130.45694 -278.34336)
		(width 0.254)
		(layer "In7.Cu")
		(net "P0V8_PEX1_TSEN")
	)
	(segment
		(start 125.144276 -278.34336)
		(end 126.33833 -279.537414)
		(width 0.254)
		(layer "In7.Cu")
		(net "P0V8_PEX1_TSEN")
	)
	(segment
		(start 119.09171 -279.66289)
		(end 123.00966 -279.66289)
		(width 0.254)
		(layer "In7.Cu")
		(net "P0V8_PEX1_TSEN")
	)
	(segment
		(start 130.45694 -278.34336)
		(end 130.95859 -278.84501)
		(width 0.254)
		(layer "In7.Cu")
		(net "P0V8_PEX1_TSEN")
	)
	(segment
		(start 130.95859 -279.38984)
		(end 131.698238 -280.129488)
		(width 0.254)
		(layer "In7.Cu")
		(net "P0V8_PEX1_TSEN")
	)
	(segment
		(start 117.95379 -278.52497)
		(end 119.09171 -279.66289)
		(width 0.254)
		(layer "In7.Cu")
		(net "P0V8_PEX1_TSEN")
	)
	(segment
		(start 131.698238 -280.129488)
		(end 131.698238 -280.810208)
		(width 0.254)
		(layer "In7.Cu")
		(net "P0V8_PEX1_TSEN")
	)
	(segment
		(start 124.346462 -278.34336)
		(end 125.144276 -278.34336)
		(width 0.254)
		(layer "In7.Cu")
		(net "P0V8_PEX1_TSEN")
	)
	(segment
		(start 128.588262 -279.537414)
		(end 129.782316 -278.34336)
		(width 0.254)
		(layer "In7.Cu")
		(net "P0V8_PEX1_TSEN")
	)
	(segment
		(start 113.432082 -280.84907)
		(end 113.432082 -281.989276)
		(width 0.2286)
		(layer "F.Cu")
		(net "SW_P0V8_PEX0_BOOT2")
	)
	(segment
		(start 113.432082 -281.989276)
		(end 113.422176 -281.999182)
		(width 0.2286)
		(layer "F.Cu")
		(net "SW_P0V8_PEX0_BOOT2")
	)
	(segment
		(start 115.48364 -279.886918)
		(end 115.48364 -280.295858)
		(width 0.1524)
		(layer "F.Cu")
		(net "P0V8_PEX0_LSET2")
	)
	(segment
		(start 115.48364 -280.295858)
		(end 115.688872 -280.50109)
		(width 0.1524)
		(layer "F.Cu")
		(net "P0V8_PEX0_LSET2")
	)
	(segment
		(start 115.22202 -281.999182)
		(end 115.22202 -281.657298)
		(width 0.1524)
		(layer "F.Cu")
		(net "P0V8_PEX0_LSET2")
	)
	(segment
		(start 115.22202 -281.657298)
		(end 115.688872 -280.530046)
		(width 0.1524)
		(layer "F.Cu")
		(net "P0V8_PEX0_LSET2")
	)
	(segment
		(start 115.688872 -280.530046)
		(end 115.688872 -280.50109)
		(width 0.1524)
		(layer "F.Cu")
		(net "P0V8_PEX0_LSET2")
	)
	(via
		(at 115.688872 -280.50109)
		(size 0.508)
		(drill 0.254)
		(layers "F.Cu" "B.Cu")
		(net "P0V8_PEX0_LSET2")
	)
	(segment
		(start 105.27157 -280.84907)
		(end 105.27157 -281.989276)
		(width 0.2286)
		(layer "F.Cu")
		(net "SW_P0V8_PEX0_BOOT1")
	)
	(segment
		(start 105.27157 -281.989276)
		(end 105.261664 -281.999182)
		(width 0.2286)
		(layer "F.Cu")
		(net "SW_P0V8_PEX0_BOOT1")
	)
	(segment
		(start 108.440982 -282.624022)
		(end 108.37164 -282.624022)
		(width 0.2286)
		(layer "F.Cu")
		(net "SW_P0V8_PEX0_VOS1")
	)
	(segment
		(start 108.587286 -282.477718)
		(end 108.440982 -282.624022)
		(width 0.2286)
		(layer "F.Cu")
		(net "SW_P0V8_PEX0_VOS1")
	)
	(segment
		(start 108.66374 -282.293314)
		(end 108.587286 -282.477718)
		(width 0.2286)
		(layer "F.Cu")
		(net "SW_P0V8_PEX0_VOS1")
	)
	(segment
		(start 108.66374 -281.963368)
		(end 108.66374 -282.293314)
		(width 0.2286)
		(layer "F.Cu")
		(net "SW_P0V8_PEX0_VOS1")
	)
	(via
		(at 108.66374 -281.963368)
		(size 0.508)
		(drill 0.254)
		(layers "F.Cu" "B.Cu")
		(net "SW_P0V8_PEX0_VOS1")
	)
	(segment
		(start 109.63148 -282.460192)
		(end 109.599984 -282.491688)
		(width 0.254)
		(layer "B.Cu")
		(net "SW_P0V8_PEX0_VOS1")
	)
	(segment
		(start 109.599984 -282.491688)
		(end 109.19206 -282.491688)
		(width 0.254)
		(layer "B.Cu")
		(net "SW_P0V8_PEX0_VOS1")
	)
	(segment
		(start 109.19206 -282.491688)
		(end 108.66374 -281.963368)
		(width 0.254)
		(layer "B.Cu")
		(net "SW_P0V8_PEX0_VOS1")
	)
	(segment
		(start 109.510068 -282.821634)
		(end 109.54639 -282.821634)
		(width 0.2286)
		(layer "F.Cu")
		(net "P0V8_PEX0_VCC1")
	)
	(segment
		(start 108.37164 -283.524198)
		(end 108.807504 -283.524198)
		(width 0.2286)
		(layer "F.Cu")
		(net "P0V8_PEX0_VCC1")
	)
	(segment
		(start 109.54639 -282.821634)
		(end 109.594904 -282.870148)
		(width 0.254)
		(layer "F.Cu")
		(net "P0V8_PEX0_VCC1")
	)
	(segment
		(start 109.594904 -282.870148)
		(end 109.594904 -283.437584)
		(width 0.254)
		(layer "F.Cu")
		(net "P0V8_PEX0_VCC1")
	)
	(segment
		(start 108.807504 -283.524198)
		(end 109.510068 -282.821634)
		(width 0.2286)
		(layer "F.Cu")
		(net "P0V8_PEX0_VCC1")
	)
	(via
		(at 109.594904 -283.437584)
		(size 0.508)
		(drill 0.254)
		(layers "F.Cu" "B.Cu")
		(net "P0V8_PEX0_VCC1")
	)
	(segment
		(start 107.205018 -282.146756)
		(end 107.564428 -282.146756)
		(width 0.254)
		(layer "B.Cu")
		(net "P0V8_PEX0_VCC1")
	)
	(segment
		(start 107.564428 -282.146756)
		(end 107.985814 -282.568142)
		(width 0.254)
		(layer "B.Cu")
		(net "P0V8_PEX0_VCC1")
	)
	(segment
		(start 108.060998 -282.568142)
		(end 108.91139 -283.418534)
		(width 0.254)
		(layer "B.Cu")
		(net "P0V8_PEX0_VCC1")
	)
	(segment
		(start 108.91139 -283.418534)
		(end 109.575854 -283.418534)
		(width 0.254)
		(layer "B.Cu")
		(net "P0V8_PEX0_VCC1")
	)
	(segment
		(start 107.10037 -282.251404)
		(end 107.205018 -282.146756)
		(width 0.254)
		(layer "B.Cu")
		(net "P0V8_PEX0_VCC1")
	)
	(segment
		(start 108.059982 -282.568142)
		(end 108.060998 -282.568142)
		(width 0.254)
		(layer "B.Cu")
		(net "P0V8_PEX0_VCC1")
	)
	(segment
		(start 109.575854 -283.418534)
		(end 109.594904 -283.437584)
		(width 0.254)
		(layer "B.Cu")
		(net "P0V8_PEX0_VCC1")
	)
	(segment
		(start 107.985814 -282.568142)
		(end 108.059982 -282.568142)
		(width 0.254)
		(layer "B.Cu")
		(net "P0V8_PEX0_VCC1")
	)
	(segment
		(start 116.824252 -282.293314)
		(end 116.747798 -282.477718)
		(width 0.2286)
		(layer "F.Cu")
		(net "SW_P0V8_PEX0_VOS2")
	)
	(segment
		(start 116.601494 -282.624022)
		(end 116.532152 -282.624022)
		(width 0.2286)
		(layer "F.Cu")
		(net "SW_P0V8_PEX0_VOS2")
	)
	(segment
		(start 116.824252 -281.963368)
		(end 116.824252 -282.293314)
		(width 0.2286)
		(layer "F.Cu")
		(net "SW_P0V8_PEX0_VOS2")
	)
	(segment
		(start 116.747798 -282.477718)
		(end 116.601494 -282.624022)
		(width 0.2286)
		(layer "F.Cu")
		(net "SW_P0V8_PEX0_VOS2")
	)
	(via
		(at 116.824252 -281.963368)
		(size 0.508)
		(drill 0.254)
		(layers "F.Cu" "B.Cu")
		(net "SW_P0V8_PEX0_VOS2")
	)
	(segment
		(start 117.301264 -282.44038)
		(end 116.824252 -281.963368)
		(width 0.254)
		(layer "B.Cu")
		(net "SW_P0V8_PEX0_VOS2")
	)
	(segment
		(start 117.847364 -282.44038)
		(end 117.301264 -282.44038)
		(width 0.254)
		(layer "B.Cu")
		(net "SW_P0V8_PEX0_VOS2")
	)
	(segment
		(start 62.974982 -304.924714)
		(end 62.499748 -304.449734)
		(width 0.249936)
		(layer "F.Cu")
		(net "P1V25_SERDES_VDDPLL_PEX0")
	)
	(segment
		(start 63.924942 -304.924714)
		(end 63.449962 -304.449734)
		(width 0.249936)
		(layer "F.Cu")
		(net "P1V25_SERDES_VDDPLL_PEX0")
	)
	(segment
		(start 57.274968 -286.874966)
		(end 57.749948 -287.349946)
		(width 0.249936)
		(layer "F.Cu")
		(net "P1V25_SERDES_VDDPLL_PEX0")
	)
	(segment
		(start 50.624994 -304.924714)
		(end 51.099974 -304.449734)
		(width 0.249936)
		(layer "F.Cu")
		(net "P1V25_SERDES_VDDPLL_PEX0")
	)
	(segment
		(start 72.474836 -294.4749)
		(end 71.999856 -294.94988)
		(width 0.249936)
		(layer "F.Cu")
		(net "P1V25_SERDES_VDDPLL_PEX0")
	)
	(segment
		(start 61.074808 -304.924714)
		(end 60.599828 -304.449734)
		(width 0.249936)
		(layer "F.Cu")
		(net "P1V25_SERDES_VDDPLL_PEX0")
	)
	(segment
		(start 72.474836 -298.27474)
		(end 71.999856 -297.79976)
		(width 0.249936)
		(layer "F.Cu")
		(net "P1V25_SERDES_VDDPLL_PEX0")
	)
	(segment
		(start 52.524914 -286.874966)
		(end 52.999894 -287.349946)
		(width 0.249936)
		(layer "F.Cu")
		(net "P1V25_SERDES_VDDPLL_PEX0")
	)
	(segment
		(start 54.424834 -286.874966)
		(end 54.899814 -287.349946)
		(width 0.249936)
		(layer "F.Cu")
		(net "P1V25_SERDES_VDDPLL_PEX0")
	)
	(segment
		(start 72.474836 -296.37482)
		(end 71.999856 -295.89984)
		(width 0.249936)
		(layer "F.Cu")
		(net "P1V25_SERDES_VDDPLL_PEX0")
	)
	(segment
		(start 56.324754 -304.924714)
		(end 56.799988 -304.449734)
		(width 0.249936)
		(layer "F.Cu")
		(net "P1V25_SERDES_VDDPLL_PEX0")
	)
	(segment
		(start 54.424834 -304.924714)
		(end 54.899814 -304.449734)
		(width 0.249936)
		(layer "F.Cu")
		(net "P1V25_SERDES_VDDPLL_PEX0")
	)
	(segment
		(start 64.874902 -304.924714)
		(end 64.399922 -304.449734)
		(width 0.249936)
		(layer "F.Cu")
		(net "P1V25_SERDES_VDDPLL_PEX0")
	)
	(segment
		(start 50.624994 -286.874966)
		(end 51.099974 -287.349946)
		(width 0.249936)
		(layer "F.Cu")
		(net "P1V25_SERDES_VDDPLL_PEX0")
	)
	(segment
		(start 60.124848 -304.924714)
		(end 59.649868 -304.449734)
		(width 0.249936)
		(layer "F.Cu")
		(net "P1V25_SERDES_VDDPLL_PEX0")
	)
	(segment
		(start 64.874902 -286.874966)
		(end 64.399922 -287.349946)
		(width 0.249936)
		(layer "F.Cu")
		(net "P1V25_SERDES_VDDPLL_PEX0")
	)
	(segment
		(start 61.074808 -286.874966)
		(end 60.599828 -287.349946)
		(width 0.249936)
		(layer "F.Cu")
		(net "P1V25_SERDES_VDDPLL_PEX0")
	)
	(segment
		(start 52.524914 -304.924714)
		(end 52.999894 -304.449734)
		(width 0.249936)
		(layer "F.Cu")
		(net "P1V25_SERDES_VDDPLL_PEX0")
	)
	(segment
		(start 57.274968 -304.924714)
		(end 57.749948 -304.449734)
		(width 0.249936)
		(layer "F.Cu")
		(net "P1V25_SERDES_VDDPLL_PEX0")
	)
	(segment
		(start 72.474836 -297.32478)
		(end 71.999856 -296.8498)
		(width 0.249936)
		(layer "F.Cu")
		(net "P1V25_SERDES_VDDPLL_PEX0")
	)
	(segment
		(start 72.474836 -293.52494)
		(end 71.999856 -293.99992)
		(width 0.249936)
		(layer "F.Cu")
		(net "P1V25_SERDES_VDDPLL_PEX0")
	)
	(segment
		(start 66.774822 -286.874966)
		(end 66.299842 -287.349946)
		(width 0.249936)
		(layer "F.Cu")
		(net "P1V25_SERDES_VDDPLL_PEX0")
	)
	(segment
		(start 58.224928 -286.874966)
		(end 58.699908 -287.349946)
		(width 0.249936)
		(layer "F.Cu")
		(net "P1V25_SERDES_VDDPLL_PEX0")
	)
	(segment
		(start 62.974982 -286.874966)
		(end 62.499748 -287.349946)
		(width 0.249936)
		(layer "F.Cu")
		(net "P1V25_SERDES_VDDPLL_PEX0")
	)
	(segment
		(start 62.024768 -286.874966)
		(end 61.549788 -287.349946)
		(width 0.249936)
		(layer "F.Cu")
		(net "P1V25_SERDES_VDDPLL_PEX0")
	)
	(segment
		(start 51.574954 -286.874966)
		(end 52.049934 -287.349946)
		(width 0.249936)
		(layer "F.Cu")
		(net "P1V25_SERDES_VDDPLL_PEX0")
	)
	(segment
		(start 63.924942 -286.874966)
		(end 63.449962 -287.349946)
		(width 0.249936)
		(layer "F.Cu")
		(net "P1V25_SERDES_VDDPLL_PEX0")
	)
	(segment
		(start 65.824862 -304.924714)
		(end 65.349882 -304.449734)
		(width 0.249936)
		(layer "F.Cu")
		(net "P1V25_SERDES_VDDPLL_PEX0")
	)
	(segment
		(start 62.024768 -304.924714)
		(end 61.549788 -304.449734)
		(width 0.249936)
		(layer "F.Cu")
		(net "P1V25_SERDES_VDDPLL_PEX0")
	)
	(segment
		(start 60.124848 -286.874966)
		(end 59.649868 -287.349946)
		(width 0.249936)
		(layer "F.Cu")
		(net "P1V25_SERDES_VDDPLL_PEX0")
	)
	(segment
		(start 66.774822 -304.924714)
		(end 66.299842 -304.449734)
		(width 0.249936)
		(layer "F.Cu")
		(net "P1V25_SERDES_VDDPLL_PEX0")
	)
	(segment
		(start 53.474874 -286.874966)
		(end 53.949854 -287.349946)
		(width 0.249936)
		(layer "F.Cu")
		(net "P1V25_SERDES_VDDPLL_PEX0")
	)
	(segment
		(start 58.224928 -304.924714)
		(end 58.699908 -304.449734)
		(width 0.249936)
		(layer "F.Cu")
		(net "P1V25_SERDES_VDDPLL_PEX0")
	)
	(segment
		(start 55.374794 -286.874966)
		(end 55.849774 -287.349946)
		(width 0.249936)
		(layer "F.Cu")
		(net "P1V25_SERDES_VDDPLL_PEX0")
	)
	(segment
		(start 65.824862 -286.874966)
		(end 65.349882 -287.349946)
		(width 0.249936)
		(layer "F.Cu")
		(net "P1V25_SERDES_VDDPLL_PEX0")
	)
	(segment
		(start 53.474874 -304.924714)
		(end 53.949854 -304.449734)
		(width 0.249936)
		(layer "F.Cu")
		(net "P1V25_SERDES_VDDPLL_PEX0")
	)
	(segment
		(start 55.374794 -304.924714)
		(end 55.849774 -304.449734)
		(width 0.249936)
		(layer "F.Cu")
		(net "P1V25_SERDES_VDDPLL_PEX0")
	)
	(segment
		(start 51.574954 -304.924714)
		(end 52.049934 -304.449734)
		(width 0.249936)
		(layer "F.Cu")
		(net "P1V25_SERDES_VDDPLL_PEX0")
	)
	(segment
		(start 56.324754 -286.874966)
		(end 56.799988 -287.349946)
		(width 0.249936)
		(layer "F.Cu")
		(net "P1V25_SERDES_VDDPLL_PEX0")
	)
	(segment
		(start 67.724782 -286.874966)
		(end 67.249802 -287.349946)
		(width 0.249936)
		(layer "F.Cu")
		(net "P1V25_SERDES_VDDPLL_PEX0")
	)
	(segment
		(start 67.724782 -304.924714)
		(end 67.249802 -304.449734)
		(width 0.249936)
		(layer "F.Cu")
		(net "P1V25_SERDES_VDDPLL_PEX0")
	)
	(via
		(at 72.474836 -293.52494)
		(size 0.4064)
		(drill 0.2032)
		(layers "F.Cu" "B.Cu")
		(net "P1V25_SERDES_VDDPLL_PEX0")
	)
	(via
		(at 63.924942 -286.874966)
		(size 0.4064)
		(drill 0.2032)
		(layers "F.Cu" "B.Cu")
		(net "P1V25_SERDES_VDDPLL_PEX0")
	)
	(via
		(at 61.074808 -286.874966)
		(size 0.4064)
		(drill 0.2032)
		(layers "F.Cu" "B.Cu")
		(net "P1V25_SERDES_VDDPLL_PEX0")
	)
	(via
		(at 58.224928 -286.874966)
		(size 0.4064)
		(drill 0.2032)
		(layers "F.Cu" "B.Cu")
		(net "P1V25_SERDES_VDDPLL_PEX0")
	)
	(via
		(at 11.988038 -257.60807)
		(size 0.508)
		(drill 0.254)
		(layers "F.Cu" "B.Cu")
		(net "P1V25_SERDES_VDDPLL_PEX0")
	)
	(via
		(at 62.024768 -304.924714)
		(size 0.4064)
		(drill 0.2032)
		(layers "F.Cu" "B.Cu")
		(net "P1V25_SERDES_VDDPLL_PEX0")
	)
	(via
		(at 67.724782 -286.874966)
		(size 0.4064)
		(drill 0.2032)
		(layers "F.Cu" "B.Cu")
		(net "P1V25_SERDES_VDDPLL_PEX0")
	)
	(via
		(at 66.774822 -286.874966)
		(size 0.4064)
		(drill 0.2032)
		(layers "F.Cu" "B.Cu")
		(net "P1V25_SERDES_VDDPLL_PEX0")
	)
	(via
		(at 3.606038 -258.510786)
		(size 0.508)
		(drill 0.254)
		(layers "F.Cu" "B.Cu")
		(net "P1V25_SERDES_VDDPLL_PEX0")
	)
	(via
		(at 53.474874 -286.874966)
		(size 0.4064)
		(drill 0.2032)
		(layers "F.Cu" "B.Cu")
		(net "P1V25_SERDES_VDDPLL_PEX0")
	)
	(via
		(at 53.474874 -304.924714)
		(size 0.4064)
		(drill 0.2032)
		(layers "F.Cu" "B.Cu")
		(net "P1V25_SERDES_VDDPLL_PEX0")
	)
	(via
		(at 72.474836 -298.27474)
		(size 0.4064)
		(drill 0.2032)
		(layers "F.Cu" "B.Cu")
		(net "P1V25_SERDES_VDDPLL_PEX0")
	)
	(via
		(at 57.274968 -286.874966)
		(size 0.4064)
		(drill 0.2032)
		(layers "F.Cu" "B.Cu")
		(net "P1V25_SERDES_VDDPLL_PEX0")
	)
	(via
		(at 72.474836 -296.37482)
		(size 0.4064)
		(drill 0.2032)
		(layers "F.Cu" "B.Cu")
		(net "P1V25_SERDES_VDDPLL_PEX0")
	)
	(via
		(at 55.374794 -304.924714)
		(size 0.4064)
		(drill 0.2032)
		(layers "F.Cu" "B.Cu")
		(net "P1V25_SERDES_VDDPLL_PEX0")
	)
	(via
		(at 62.974982 -304.924714)
		(size 0.4064)
		(drill 0.2032)
		(layers "F.Cu" "B.Cu")
		(net "P1V25_SERDES_VDDPLL_PEX0")
	)
	(via
		(at 50.624994 -286.874966)
		(size 0.4064)
		(drill 0.2032)
		(layers "F.Cu" "B.Cu")
		(net "P1V25_SERDES_VDDPLL_PEX0")
	)
	(via
		(at 9.278366 -255.605534)
		(size 0.508)
		(drill 0.254)
		(layers "F.Cu" "B.Cu")
		(net "P1V25_SERDES_VDDPLL_PEX0")
	)
	(via
		(at 12.365482 -255.65354)
		(size 0.508)
		(drill 0.254)
		(layers "F.Cu" "B.Cu")
		(net "P1V25_SERDES_VDDPLL_PEX0")
	)
	(via
		(at 67.724782 -304.924714)
		(size 0.4064)
		(drill 0.2032)
		(layers "F.Cu" "B.Cu")
		(net "P1V25_SERDES_VDDPLL_PEX0")
	)
	(via
		(at 7.741666 -255.653286)
		(size 0.508)
		(drill 0.254)
		(layers "F.Cu" "B.Cu")
		(net "P1V25_SERDES_VDDPLL_PEX0")
	)
	(via
		(at 6.64337 -256.53619)
		(size 0.508)
		(drill 0.254)
		(layers "F.Cu" "B.Cu")
		(net "P1V25_SERDES_VDDPLL_PEX0")
	)
	(via
		(at 8.178038 -258.510786)
		(size 0.508)
		(drill 0.254)
		(layers "F.Cu" "B.Cu")
		(net "P1V25_SERDES_VDDPLL_PEX0")
	)
	(via
		(at 62.024768 -286.874966)
		(size 0.4064)
		(drill 0.2032)
		(layers "F.Cu" "B.Cu")
		(net "P1V25_SERDES_VDDPLL_PEX0")
	)
	(via
		(at 13.512038 -258.510786)
		(size 0.508)
		(drill 0.254)
		(layers "F.Cu" "B.Cu")
		(net "P1V25_SERDES_VDDPLL_PEX0")
	)
	(via
		(at 57.274968 -304.924714)
		(size 0.4064)
		(drill 0.2032)
		(layers "F.Cu" "B.Cu")
		(net "P1V25_SERDES_VDDPLL_PEX0")
	)
	(via
		(at 7.416038 -257.60807)
		(size 0.508)
		(drill 0.254)
		(layers "F.Cu" "B.Cu")
		(net "P1V25_SERDES_VDDPLL_PEX0")
	)
	(via
		(at 58.224928 -304.924714)
		(size 0.4064)
		(drill 0.2032)
		(layers "F.Cu" "B.Cu")
		(net "P1V25_SERDES_VDDPLL_PEX0")
	)
	(via
		(at 55.374794 -286.874966)
		(size 0.4064)
		(drill 0.2032)
		(layers "F.Cu" "B.Cu")
		(net "P1V25_SERDES_VDDPLL_PEX0")
	)
	(via
		(at 9.861042 -256.355342)
		(size 0.508)
		(drill 0.254)
		(layers "F.Cu" "B.Cu")
		(net "P1V25_SERDES_VDDPLL_PEX0")
	)
	(via
		(at 72.474836 -294.4749)
		(size 0.4064)
		(drill 0.2032)
		(layers "F.Cu" "B.Cu")
		(net "P1V25_SERDES_VDDPLL_PEX0")
	)
	(via
		(at 60.124848 -304.924714)
		(size 0.4064)
		(drill 0.2032)
		(layers "F.Cu" "B.Cu")
		(net "P1V25_SERDES_VDDPLL_PEX0")
	)
	(via
		(at 9.702038 -258.510786)
		(size 0.508)
		(drill 0.254)
		(layers "F.Cu" "B.Cu")
		(net "P1V25_SERDES_VDDPLL_PEX0")
	)
	(via
		(at 5.134864 -256.475992)
		(size 0.508)
		(drill 0.254)
		(layers "F.Cu" "B.Cu")
		(net "P1V25_SERDES_VDDPLL_PEX0")
	)
	(via
		(at 64.874902 -286.874966)
		(size 0.4064)
		(drill 0.2032)
		(layers "F.Cu" "B.Cu")
		(net "P1V25_SERDES_VDDPLL_PEX0")
	)
	(via
		(at 3.646678 -256.516124)
		(size 0.508)
		(drill 0.254)
		(layers "F.Cu" "B.Cu")
		(net "P1V25_SERDES_VDDPLL_PEX0")
	)
	(via
		(at 56.324754 -304.924714)
		(size 0.4064)
		(drill 0.2032)
		(layers "F.Cu" "B.Cu")
		(net "P1V25_SERDES_VDDPLL_PEX0")
	)
	(via
		(at 10.464038 -257.60807)
		(size 0.508)
		(drill 0.254)
		(layers "F.Cu" "B.Cu")
		(net "P1V25_SERDES_VDDPLL_PEX0")
	)
	(via
		(at 6.654038 -258.510786)
		(size 0.508)
		(drill 0.254)
		(layers "F.Cu" "B.Cu")
		(net "P1V25_SERDES_VDDPLL_PEX0")
	)
	(via
		(at 50.624994 -304.924714)
		(size 0.4064)
		(drill 0.2032)
		(layers "F.Cu" "B.Cu")
		(net "P1V25_SERDES_VDDPLL_PEX0")
	)
	(via
		(at 72.474836 -297.32478)
		(size 0.4064)
		(drill 0.2032)
		(layers "F.Cu" "B.Cu")
		(net "P1V25_SERDES_VDDPLL_PEX0")
	)
	(via
		(at 11.429746 -256.41554)
		(size 0.508)
		(drill 0.254)
		(layers "F.Cu" "B.Cu")
		(net "P1V25_SERDES_VDDPLL_PEX0")
	)
	(via
		(at 5.130038 -257.60807)
		(size 0.508)
		(drill 0.254)
		(layers "F.Cu" "B.Cu")
		(net "P1V25_SERDES_VDDPLL_PEX0")
	)
	(via
		(at 54.424834 -304.924714)
		(size 0.4064)
		(drill 0.2032)
		(layers "F.Cu" "B.Cu")
		(net "P1V25_SERDES_VDDPLL_PEX0")
	)
	(via
		(at 56.324754 -286.874966)
		(size 0.4064)
		(drill 0.2032)
		(layers "F.Cu" "B.Cu")
		(net "P1V25_SERDES_VDDPLL_PEX0")
	)
	(via
		(at 54.424834 -286.874966)
		(size 0.4064)
		(drill 0.2032)
		(layers "F.Cu" "B.Cu")
		(net "P1V25_SERDES_VDDPLL_PEX0")
	)
	(via
		(at 65.824862 -286.874966)
		(size 0.4064)
		(drill 0.2032)
		(layers "F.Cu" "B.Cu")
		(net "P1V25_SERDES_VDDPLL_PEX0")
	)
	(via
		(at 10.78738 -255.711452)
		(size 0.508)
		(drill 0.254)
		(layers "F.Cu" "B.Cu")
		(net "P1V25_SERDES_VDDPLL_PEX0")
	)
	(via
		(at 5.130038 -258.510786)
		(size 0.508)
		(drill 0.254)
		(layers "F.Cu" "B.Cu")
		(net "P1V25_SERDES_VDDPLL_PEX0")
	)
	(via
		(at 6.211824 -255.625854)
		(size 0.508)
		(drill 0.254)
		(layers "F.Cu" "B.Cu")
		(net "P1V25_SERDES_VDDPLL_PEX0")
	)
	(via
		(at 12.837414 -256.435606)
		(size 0.508)
		(drill 0.254)
		(layers "F.Cu" "B.Cu")
		(net "P1V25_SERDES_VDDPLL_PEX0")
	)
	(via
		(at 8.151622 -256.475992)
		(size 0.508)
		(drill 0.254)
		(layers "F.Cu" "B.Cu")
		(net "P1V25_SERDES_VDDPLL_PEX0")
	)
	(via
		(at 3.606038 -257.60807)
		(size 0.508)
		(drill 0.254)
		(layers "F.Cu" "B.Cu")
		(net "P1V25_SERDES_VDDPLL_PEX0")
	)
	(via
		(at 52.524914 -304.924714)
		(size 0.4064)
		(drill 0.2032)
		(layers "F.Cu" "B.Cu")
		(net "P1V25_SERDES_VDDPLL_PEX0")
	)
	(via
		(at 62.974982 -286.874966)
		(size 0.4064)
		(drill 0.2032)
		(layers "F.Cu" "B.Cu")
		(net "P1V25_SERDES_VDDPLL_PEX0")
	)
	(via
		(at 4.326382 -255.732026)
		(size 0.508)
		(drill 0.254)
		(layers "F.Cu" "B.Cu")
		(net "P1V25_SERDES_VDDPLL_PEX0")
	)
	(via
		(at 60.124848 -286.874966)
		(size 0.4064)
		(drill 0.2032)
		(layers "F.Cu" "B.Cu")
		(net "P1V25_SERDES_VDDPLL_PEX0")
	)
	(via
		(at 51.574954 -304.924714)
		(size 0.4064)
		(drill 0.2032)
		(layers "F.Cu" "B.Cu")
		(net "P1V25_SERDES_VDDPLL_PEX0")
	)
	(via
		(at 51.574954 -286.874966)
		(size 0.4064)
		(drill 0.2032)
		(layers "F.Cu" "B.Cu")
		(net "P1V25_SERDES_VDDPLL_PEX0")
	)
	(via
		(at 63.924942 -304.924714)
		(size 0.4064)
		(drill 0.2032)
		(layers "F.Cu" "B.Cu")
		(net "P1V25_SERDES_VDDPLL_PEX0")
	)
	(via
		(at 11.226038 -258.510786)
		(size 0.508)
		(drill 0.254)
		(layers "F.Cu" "B.Cu")
		(net "P1V25_SERDES_VDDPLL_PEX0")
	)
	(via
		(at 12.370816 -258.567428)
		(size 0.508)
		(drill 0.254)
		(layers "F.Cu" "B.Cu")
		(net "P1V25_SERDES_VDDPLL_PEX0")
	)
	(via
		(at 13.512038 -257.60807)
		(size 0.508)
		(drill 0.254)
		(layers "F.Cu" "B.Cu")
		(net "P1V25_SERDES_VDDPLL_PEX0")
	)
	(via
		(at 61.074808 -304.924714)
		(size 0.4064)
		(drill 0.2032)
		(layers "F.Cu" "B.Cu")
		(net "P1V25_SERDES_VDDPLL_PEX0")
	)
	(via
		(at 8.940038 -257.60807)
		(size 0.508)
		(drill 0.254)
		(layers "F.Cu" "B.Cu")
		(net "P1V25_SERDES_VDDPLL_PEX0")
	)
	(via
		(at 65.824862 -304.924714)
		(size 0.4064)
		(drill 0.2032)
		(layers "F.Cu" "B.Cu")
		(net "P1V25_SERDES_VDDPLL_PEX0")
	)
	(via
		(at 64.874902 -304.924714)
		(size 0.4064)
		(drill 0.2032)
		(layers "F.Cu" "B.Cu")
		(net "P1V25_SERDES_VDDPLL_PEX0")
	)
	(via
		(at 52.524914 -286.874966)
		(size 0.4064)
		(drill 0.2032)
		(layers "F.Cu" "B.Cu")
		(net "P1V25_SERDES_VDDPLL_PEX0")
	)
	(via
		(at 66.774822 -304.924714)
		(size 0.4064)
		(drill 0.2032)
		(layers "F.Cu" "B.Cu")
		(net "P1V25_SERDES_VDDPLL_PEX0")
	)
	(segment
		(start 316.180724 -356.831646)
		(end 316.180724 -357.46309)
		(width 0.13462)
		(layer "F.Cu")
		(net "P5E_PEX2_STN5_TX_C_DN<82>")
	)
	(segment
		(start 316.500764 -356.511606)
		(end 316.180724 -356.831646)
		(width 0.13462)
		(layer "F.Cu")
		(net "P5E_PEX2_STN5_TX_C_DN<82>")
	)
	(segment
		(start 316.180724 -357.46309)
		(end 316.475364 -357.75773)
		(width 0.13462)
		(layer "F.Cu")
		(net "P5E_PEX2_STN5_TX_C_DN<82>")
	)
	(segment
		(start 335.890108 -405.207978)
		(end 336.017108 -405.080978)
		(width 0.1651)
		(layer "In7.Cu")
		(net "P5E_PEX2_STN5_TX_C_DN<82>")
	)
	(segment
		(start 326.80402 -388.37362)
		(end 325.6534 -385.70662)
		(width 0.1651)
		(layer "In7.Cu")
		(net "P5E_PEX2_STN5_TX_C_DN<82>")
	)
	(segment
		(start 336.80146 -394.64488)
		(end 335.43748 -393.27836)
		(width 0.1651)
		(layer "In7.Cu")
		(net "P5E_PEX2_STN5_TX_C_DN<82>")
	)
	(segment
		(start 335.43748 -393.27836)
		(end 329.07224 -390.6393)
		(width 0.1651)
		(layer "In7.Cu")
		(net "P5E_PEX2_STN5_TX_C_DN<82>")
	)
	(segment
		(start 336.564224 -405.080978)
		(end 337.01609 -404.629112)
		(width 0.1651)
		(layer "In7.Cu")
		(net "P5E_PEX2_STN5_TX_C_DN<82>")
	)
	(segment
		(start 316.184534 -359.262426)
		(end 316.184534 -358.04856)
		(width 0.1651)
		(layer "In7.Cu")
		(net "P5E_PEX2_STN5_TX_C_DN<82>")
	)
	(segment
		(start 325.6534 -385.70662)
		(end 316.184534 -359.262426)
		(width 0.1651)
		(layer "In7.Cu")
		(net "P5E_PEX2_STN5_TX_C_DN<82>")
	)
	(segment
		(start 335.890108 -405.589994)
		(end 335.890108 -405.207978)
		(width 0.1651)
		(layer "In7.Cu")
		(net "P5E_PEX2_STN5_TX_C_DN<82>")
	)
	(segment
		(start 336.017108 -405.080978)
		(end 336.564224 -405.080978)
		(width 0.1651)
		(layer "In7.Cu")
		(net "P5E_PEX2_STN5_TX_C_DN<82>")
	)
	(segment
		(start 316.184534 -358.04856)
		(end 316.475364 -357.75773)
		(width 0.1651)
		(layer "In7.Cu")
		(net "P5E_PEX2_STN5_TX_C_DN<82>")
	)
	(segment
		(start 337.01609 -404.629112)
		(end 337.01609 -395.224)
		(width 0.1651)
		(layer "In7.Cu")
		(net "P5E_PEX2_STN5_TX_C_DN<82>")
	)
	(segment
		(start 337.01609 -395.224)
		(end 336.80146 -394.64488)
		(width 0.1651)
		(layer "In7.Cu")
		(net "P5E_PEX2_STN5_TX_C_DN<82>")
	)
	(segment
		(start 329.07224 -390.6393)
		(end 326.80402 -388.37362)
		(width 0.1651)
		(layer "In7.Cu")
		(net "P5E_PEX2_STN5_TX_C_DN<82>")
	)
	(segment
		(start 315.906404 -357.46309)
		(end 315.611764 -357.75773)
		(width 0.13462)
		(layer "F.Cu")
		(net "P5E_PEX2_STN5_TX_C_DP<82>")
	)
	(segment
		(start 315.906404 -356.831646)
		(end 315.906404 -357.46309)
		(width 0.13462)
		(layer "F.Cu")
		(net "P5E_PEX2_STN5_TX_C_DP<82>")
	)
	(segment
		(start 315.586364 -356.511606)
		(end 315.906404 -356.831646)
		(width 0.13462)
		(layer "F.Cu")
		(net "P5E_PEX2_STN5_TX_C_DP<82>")
	)
	(segment
		(start 336.017108 -404.799038)
		(end 336.447384 -404.799038)
		(width 0.1651)
		(layer "In7.Cu")
		(net "P5E_PEX2_STN5_TX_C_DP<82>")
	)
	(segment
		(start 334.820006 -393.328144)
		(end 334.703928 -393.37615)
		(width 0.1651)
		(layer "In7.Cu")
		(net "P5E_PEX2_STN5_TX_C_DP<82>")
	)
	(segment
		(start 332.544928 -392.4808)
		(end 332.08722 -392.290808)
		(width 0.1651)
		(layer "In7.Cu")
		(net "P5E_PEX2_STN5_TX_C_DP<82>")
	)
	(segment
		(start 335.63941 -394.00607)
		(end 335.639664 -393.88034)
		(width 0.1651)
		(layer "In7.Cu")
		(net "P5E_PEX2_STN5_TX_C_DP<82>")
	)
	(segment
		(start 328.912474 -390.878314)
		(end 326.56653 -388.53491)
		(width 0.1651)
		(layer "In7.Cu")
		(net "P5E_PEX2_STN5_TX_C_DP<82>")
	)
	(segment
		(start 332.661006 -392.432794)
		(end 332.544928 -392.4808)
		(width 0.1651)
		(layer "In7.Cu")
		(net "P5E_PEX2_STN5_TX_C_DP<82>")
	)
	(segment
		(start 336.73415 -395.2748)
		(end 336.558382 -394.800582)
		(width 0.1651)
		(layer "In7.Cu")
		(net "P5E_PEX2_STN5_TX_C_DP<82>")
	)
	(segment
		(start 335.989676 -394.356844)
		(end 335.63941 -394.00607)
		(width 0.1651)
		(layer "In7.Cu")
		(net "P5E_PEX2_STN5_TX_C_DP<82>")
	)
	(segment
		(start 326.56653 -388.53491)
		(end 325.390764 -385.810252)
		(width 0.1651)
		(layer "In7.Cu")
		(net "P5E_PEX2_STN5_TX_C_DP<82>")
	)
	(segment
		(start 332.03896 -392.17473)
		(end 328.912474 -390.878314)
		(width 0.1651)
		(layer "In7.Cu")
		(net "P5E_PEX2_STN5_TX_C_DP<82>")
	)
	(segment
		(start 334.24622 -393.186158)
		(end 334.19796 -393.07008)
		(width 0.1651)
		(layer "In7.Cu")
		(net "P5E_PEX2_STN5_TX_C_DP<82>")
	)
	(segment
		(start 336.447384 -404.799038)
		(end 336.73415 -404.512272)
		(width 0.1651)
		(layer "In7.Cu")
		(net "P5E_PEX2_STN5_TX_C_DP<82>")
	)
	(segment
		(start 335.639664 -393.88034)
		(end 335.27746 -393.517628)
		(width 0.1651)
		(layer "In7.Cu")
		(net "P5E_PEX2_STN5_TX_C_DP<82>")
	)
	(segment
		(start 335.890108 -404.672038)
		(end 336.017108 -404.799038)
		(width 0.1651)
		(layer "In7.Cu")
		(net "P5E_PEX2_STN5_TX_C_DP<82>")
	)
	(segment
		(start 336.73415 -404.512272)
		(end 336.73415 -395.2748)
		(width 0.1651)
		(layer "In7.Cu")
		(net "P5E_PEX2_STN5_TX_C_DP<82>")
	)
	(segment
		(start 334.19796 -393.07008)
		(end 333.740506 -392.880596)
		(width 0.1651)
		(layer "In7.Cu")
		(net "P5E_PEX2_STN5_TX_C_DP<82>")
	)
	(segment
		(start 332.08722 -392.290808)
		(end 332.03896 -392.17473)
		(width 0.1651)
		(layer "In7.Cu")
		(net "P5E_PEX2_STN5_TX_C_DP<82>")
	)
	(segment
		(start 336.558382 -394.800582)
		(end 336.115406 -394.356844)
		(width 0.1651)
		(layer "In7.Cu")
		(net "P5E_PEX2_STN5_TX_C_DP<82>")
	)
	(segment
		(start 333.740506 -392.880596)
		(end 333.624428 -392.928602)
		(width 0.1651)
		(layer "In7.Cu")
		(net "P5E_PEX2_STN5_TX_C_DP<82>")
	)
	(segment
		(start 325.390764 -385.810252)
		(end 315.902594 -359.311956)
		(width 0.1651)
		(layer "In7.Cu")
		(net "P5E_PEX2_STN5_TX_C_DP<82>")
	)
	(segment
		(start 315.902594 -358.04856)
		(end 315.611764 -357.75773)
		(width 0.1651)
		(layer "In7.Cu")
		(net "P5E_PEX2_STN5_TX_C_DP<82>")
	)
	(segment
		(start 333.11846 -392.622278)
		(end 332.661006 -392.432794)
		(width 0.1651)
		(layer "In7.Cu")
		(net "P5E_PEX2_STN5_TX_C_DP<82>")
	)
	(segment
		(start 336.115406 -394.356844)
		(end 335.989676 -394.356844)
		(width 0.1651)
		(layer "In7.Cu")
		(net "P5E_PEX2_STN5_TX_C_DP<82>")
	)
	(segment
		(start 315.902594 -359.311956)
		(end 315.902594 -358.04856)
		(width 0.1651)
		(layer "In7.Cu")
		(net "P5E_PEX2_STN5_TX_C_DP<82>")
	)
	(segment
		(start 333.624428 -392.928602)
		(end 333.16672 -392.73861)
		(width 0.1651)
		(layer "In7.Cu")
		(net "P5E_PEX2_STN5_TX_C_DP<82>")
	)
	(segment
		(start 335.890108 -404.290022)
		(end 335.890108 -404.672038)
		(width 0.1651)
		(layer "In7.Cu")
		(net "P5E_PEX2_STN5_TX_C_DP<82>")
	)
	(segment
		(start 334.703928 -393.37615)
		(end 334.24622 -393.186158)
		(width 0.1651)
		(layer "In7.Cu")
		(net "P5E_PEX2_STN5_TX_C_DP<82>")
	)
	(segment
		(start 333.16672 -392.73861)
		(end 333.11846 -392.622278)
		(width 0.1651)
		(layer "In7.Cu")
		(net "P5E_PEX2_STN5_TX_C_DP<82>")
	)
	(segment
		(start 335.27746 -393.517628)
		(end 334.820006 -393.328144)
		(width 0.1651)
		(layer "In7.Cu")
		(net "P5E_PEX2_STN5_TX_C_DP<82>")
	)
	(segment
		(start 52.999894 -291.149786)
		(end 52.524914 -290.674806)
		(width 0.249936)
		(layer "F.Cu")
		(net "P0V8_SERDES_VDDA_PEX0")
	)
	(segment
		(start 67.249802 -291.149786)
		(end 67.724782 -290.674806)
		(width 0.249936)
		(layer "F.Cu")
		(net "P0V8_SERDES_VDDA_PEX0")
	)
	(segment
		(start 56.799988 -291.149786)
		(end 57.274968 -290.674806)
		(width 0.249936)
		(layer "F.Cu")
		(net "P0V8_SERDES_VDDA_PEX0")
	)
	(segment
		(start 54.424834 -299.224954)
		(end 53.949854 -298.74972)
		(width 0.249936)
		(layer "F.Cu")
		(net "P0V8_SERDES_VDDA_PEX0")
	)
	(segment
		(start 65.824862 -301.124874)
		(end 66.299842 -300.649894)
		(width 0.249936)
		(layer "F.Cu")
		(net "P0V8_SERDES_VDDA_PEX0")
	)
	(segment
		(start 68.199762 -295.89984)
		(end 68.674742 -296.37482)
		(width 0.249936)
		(layer "F.Cu")
		(net "P0V8_SERDES_VDDA_PEX0")
	)
	(segment
		(start 62.024768 -299.224954)
		(end 62.499748 -298.74972)
		(width 0.249936)
		(layer "F.Cu")
		(net "P0V8_SERDES_VDDA_PEX0")
	)
	(segment
		(start 53.474874 -301.124874)
		(end 53.949854 -300.649894)
		(width 0.249936)
		(layer "F.Cu")
		(net "P0V8_SERDES_VDDA_PEX0")
	)
	(segment
		(start 53.474874 -299.224954)
		(end 53.949854 -298.74972)
		(width 0.249936)
		(layer "F.Cu")
		(net "P0V8_SERDES_VDDA_PEX0")
	)
	(segment
		(start 55.374794 -292.57498)
		(end 55.849774 -293.04996)
		(width 0.249936)
		(layer "F.Cu")
		(net "P0V8_SERDES_VDDA_PEX0")
	)
	(segment
		(start 63.924942 -290.674806)
		(end 64.399922 -291.149786)
		(width 0.249936)
		(layer "F.Cu")
		(net "P0V8_SERDES_VDDA_PEX0")
	)
	(segment
		(start 68.199762 -294.94988)
		(end 68.674742 -294.4749)
		(width 0.249936)
		(layer "F.Cu")
		(net "P0V8_SERDES_VDDA_PEX0")
	)
	(segment
		(start 57.749948 -300.649894)
		(end 57.274968 -301.124874)
		(width 0.249936)
		(layer "F.Cu")
		(net "P0V8_SERDES_VDDA_PEX0")
	)
	(segment
		(start 55.374794 -290.674806)
		(end 55.849774 -291.149786)
		(width 0.249936)
		(layer "F.Cu")
		(net "P0V8_SERDES_VDDA_PEX0")
	)
	(segment
		(start 62.974982 -292.574726)
		(end 63.449962 -293.04996)
		(width 0.249936)
		(layer "F.Cu")
		(net "P0V8_SERDES_VDDA_PEX0")
	)
	(segment
		(start 55.849774 -300.649894)
		(end 55.374794 -301.124874)
		(width 0.249936)
		(layer "F.Cu")
		(net "P0V8_SERDES_VDDA_PEX0")
	)
	(segment
		(start 63.924942 -301.124874)
		(end 63.449962 -300.649894)
		(width 0.249936)
		(layer "F.Cu")
		(net "P0V8_SERDES_VDDA_PEX0")
	)
	(segment
		(start 61.074808 -301.124874)
		(end 60.599828 -300.649894)
		(width 0.249936)
		(layer "F.Cu")
		(net "P0V8_SERDES_VDDA_PEX0")
	)
	(segment
		(start 57.274968 -292.57498)
		(end 57.749948 -293.04996)
		(width 0.249936)
		(layer "F.Cu")
		(net "P0V8_SERDES_VDDA_PEX0")
	)
	(segment
		(start 66.774822 -290.674806)
		(end 67.249802 -291.149786)
		(width 0.249936)
		(layer "F.Cu")
		(net "P0V8_SERDES_VDDA_PEX0")
	)
	(segment
		(start 58.224928 -301.124874)
		(end 58.699908 -300.649894)
		(width 0.249936)
		(layer "F.Cu")
		(net "P0V8_SERDES_VDDA_PEX0")
	)
	(segment
		(start 58.224928 -299.224954)
		(end 58.699908 -298.74972)
		(width 0.249936)
		(layer "F.Cu")
		(net "P0V8_SERDES_VDDA_PEX0")
	)
	(segment
		(start 52.524914 -299.224954)
		(end 52.049934 -298.74972)
		(width 0.249936)
		(layer "F.Cu")
		(net "P0V8_SERDES_VDDA_PEX0")
	)
	(segment
		(start 52.049934 -298.74972)
		(end 51.574954 -299.224954)
		(width 0.249936)
		(layer "F.Cu")
		(net "P0V8_SERDES_VDDA_PEX0")
	)
	(segment
		(start 56.324754 -290.674806)
		(end 56.799988 -291.149786)
		(width 0.249936)
		(layer "F.Cu")
		(net "P0V8_SERDES_VDDA_PEX0")
	)
	(segment
		(start 58.224928 -290.674806)
		(end 57.749948 -291.149786)
		(width 0.249936)
		(layer "F.Cu")
		(net "P0V8_SERDES_VDDA_PEX0")
	)
	(segment
		(start 54.424834 -290.674806)
		(end 53.949854 -291.149786)
		(width 0.249936)
		(layer "F.Cu")
		(net "P0V8_SERDES_VDDA_PEX0")
	)
	(segment
		(start 65.349882 -298.74972)
		(end 64.874902 -299.224954)
		(width 0.249936)
		(layer "F.Cu")
		(net "P0V8_SERDES_VDDA_PEX0")
	)
	(segment
		(start 67.249802 -300.649894)
		(end 67.724782 -301.124874)
		(width 0.249936)
		(layer "F.Cu")
		(net "P0V8_SERDES_VDDA_PEX0")
	)
	(segment
		(start 55.849774 -298.74972)
		(end 56.324754 -299.224954)
		(width 0.249936)
		(layer "F.Cu")
		(net "P0V8_SERDES_VDDA_PEX0")
	)
	(segment
		(start 62.499748 -293.04996)
		(end 62.974982 -292.574726)
		(width 0.249936)
		(layer "F.Cu")
		(net "P0V8_SERDES_VDDA_PEX0")
	)
	(segment
		(start 64.874902 -299.224954)
		(end 64.399922 -298.74972)
		(width 0.249936)
		(layer "F.Cu")
		(net "P0V8_SERDES_VDDA_PEX0")
	)
	(segment
		(start 51.099974 -291.149786)
		(end 50.624994 -290.674806)
		(width 0.249936)
		(layer "F.Cu")
		(net "P0V8_SERDES_VDDA_PEX0")
	)
	(segment
		(start 57.749948 -298.74972)
		(end 58.224928 -299.224954)
		(width 0.249936)
		(layer "F.Cu")
		(net "P0V8_SERDES_VDDA_PEX0")
	)
	(segment
		(start 64.399922 -293.04996)
		(end 63.924942 -292.574726)
		(width 0.249936)
		(layer "F.Cu")
		(net "P0V8_SERDES_VDDA_PEX0")
	)
	(segment
		(start 66.299842 -293.04996)
		(end 65.824862 -292.574726)
		(width 0.249936)
		(layer "F.Cu")
		(net "P0V8_SERDES_VDDA_PEX0")
	)
	(segment
		(start 62.974982 -290.674806)
		(end 63.449962 -291.149786)
		(width 0.249936)
		(layer "F.Cu")
		(net "P0V8_SERDES_VDDA_PEX0")
	)
	(segment
		(start 53.474874 -292.57498)
		(end 53.949854 -293.04996)
		(width 0.249936)
		(layer "F.Cu")
		(net "P0V8_SERDES_VDDA_PEX0")
	)
	(segment
		(start 62.499748 -291.149786)
		(end 62.974982 -290.674806)
		(width 0.249936)
		(layer "F.Cu")
		(net "P0V8_SERDES_VDDA_PEX0")
	)
	(segment
		(start 55.374794 -301.124874)
		(end 54.899814 -300.649894)
		(width 0.249936)
		(layer "F.Cu")
		(net "P0V8_SERDES_VDDA_PEX0")
	)
	(segment
		(start 61.549788 -300.649894)
		(end 61.074808 -301.124874)
		(width 0.249936)
		(layer "F.Cu")
		(net "P0V8_SERDES_VDDA_PEX0")
	)
	(segment
		(start 60.124848 -299.224954)
		(end 60.599828 -298.74972)
		(width 0.249936)
		(layer "F.Cu")
		(net "P0V8_SERDES_VDDA_PEX0")
	)
	(segment
		(start 61.549788 -291.149786)
		(end 62.024768 -290.674806)
		(width 0.249936)
		(layer "F.Cu")
		(net "P0V8_SERDES_VDDA_PEX0")
	)
	(segment
		(start 57.749948 -298.74972)
		(end 57.274968 -299.224954)
		(width 0.249936)
		(layer "F.Cu")
		(net "P0V8_SERDES_VDDA_PEX0")
	)
	(segment
		(start 57.274968 -299.224954)
		(end 56.799988 -298.74972)
		(width 0.249936)
		(layer "F.Cu")
		(net "P0V8_SERDES_VDDA_PEX0")
	)
	(segment
		(start 66.299842 -294.94988)
		(end 66.774822 -294.4749)
		(width 0.249936)
		(layer "F.Cu")
		(net "P0V8_SERDES_VDDA_PEX0")
	)
	(segment
		(start 54.899814 -300.649894)
		(end 54.424834 -301.124874)
		(width 0.249936)
		(layer "F.Cu")
		(net "P0V8_SERDES_VDDA_PEX0")
	)
	(segment
		(start 55.849774 -300.649894)
		(end 56.324754 -301.124874)
		(width 0.249936)
		(layer "F.Cu")
		(net "P0V8_SERDES_VDDA_PEX0")
	)
	(segment
		(start 67.724782 -294.4749)
		(end 68.199762 -294.94988)
		(width 0.249936)
		(layer "F.Cu")
		(net "P0V8_SERDES_VDDA_PEX0")
	)
	(segment
		(start 66.774822 -292.574726)
		(end 67.249802 -293.04996)
		(width 0.249936)
		(layer "F.Cu")
		(net "P0V8_SERDES_VDDA_PEX0")
	)
	(segment
		(start 66.774822 -297.32478)
		(end 66.299842 -296.8498)
		(width 0.249936)
		(layer "F.Cu")
		(net "P0V8_SERDES_VDDA_PEX0")
	)
	(segment
		(start 65.824862 -292.574726)
		(end 65.349882 -293.04996)
		(width 0.249936)
		(layer "F.Cu")
		(net "P0V8_SERDES_VDDA_PEX0")
	)
	(segment
		(start 67.724782 -297.32478)
		(end 68.199762 -296.8498)
		(width 0.249936)
		(layer "F.Cu")
		(net "P0V8_SERDES_VDDA_PEX0")
	)
	(segment
		(start 63.449962 -298.74972)
		(end 63.924942 -299.224954)
		(width 0.249936)
		(layer "F.Cu")
		(net "P0V8_SERDES_VDDA_PEX0")
	)
	(segment
		(start 68.199762 -296.8498)
		(end 68.674742 -297.32478)
		(width 0.249936)
		(layer "F.Cu")
		(net "P0V8_SERDES_VDDA_PEX0")
	)
	(segment
		(start 52.999894 -291.149786)
		(end 53.474874 -290.674806)
		(width 0.249936)
		(layer "F.Cu")
		(net "P0V8_SERDES_VDDA_PEX0")
	)
	(segment
		(start 61.549788 -293.04996)
		(end 61.074808 -292.574726)
		(width 0.249936)
		(layer "F.Cu")
		(net "P0V8_SERDES_VDDA_PEX0")
	)
	(segment
		(start 68.199762 -295.89984)
		(end 67.724782 -296.37482)
		(width 0.249936)
		(layer "F.Cu")
		(net "P0V8_SERDES_VDDA_PEX0")
	)
	(segment
		(start 55.849774 -291.149786)
		(end 56.324754 -290.674806)
		(width 0.249936)
		(layer "F.Cu")
		(net "P0V8_SERDES_VDDA_PEX0")
	)
	(segment
		(start 57.274968 -301.124874)
		(end 56.799988 -300.649894)
		(width 0.249936)
		(layer "F.Cu")
		(net "P0V8_SERDES_VDDA_PEX0")
	)
	(segment
		(start 52.999894 -298.74972)
		(end 52.524914 -299.224954)
		(width 0.249936)
		(layer "F.Cu")
		(net "P0V8_SERDES_VDDA_PEX0")
	)
	(segment
		(start 54.424834 -292.57498)
		(end 54.899814 -293.04996)
		(width 0.249936)
		(layer "F.Cu")
		(net "P0V8_SERDES_VDDA_PEX0")
	)
	(segment
		(start 56.325008 -292.57498)
		(end 56.799988 -293.04996)
		(width 0.249936)
		(layer "F.Cu")
		(net "P0V8_SERDES_VDDA_PEX0")
	)
	(segment
		(start 61.549788 -293.04996)
		(end 62.024768 -292.574726)
		(width 0.249936)
		(layer "F.Cu")
		(net "P0V8_SERDES_VDDA_PEX0")
	)
	(segment
		(start 54.899814 -298.74972)
		(end 54.424834 -299.224954)
		(width 0.249936)
		(layer "F.Cu")
		(net "P0V8_SERDES_VDDA_PEX0")
	)
	(segment
		(start 52.999894 -300.649894)
		(end 53.474874 -301.124874)
		(width 0.249936)
		(layer "F.Cu")
		(net "P0V8_SERDES_VDDA_PEX0")
	)
	(segment
		(start 55.374794 -299.224954)
		(end 54.899814 -298.74972)
		(width 0.249936)
		(layer "F.Cu")
		(net "P0V8_SERDES_VDDA_PEX0")
	)
	(segment
		(start 66.299842 -298.74972)
		(end 66.774822 -299.224954)
		(width 0.249936)
		(layer "F.Cu")
		(net "P0V8_SERDES_VDDA_PEX0")
	)
	(segment
		(start 65.824862 -299.224954)
		(end 66.299842 -298.74972)
		(width 0.249936)
		(layer "F.Cu")
		(net "P0V8_SERDES_VDDA_PEX0")
	)
	(segment
		(start 62.499748 -298.74972)
		(end 62.974982 -299.224954)
		(width 0.249936)
		(layer "F.Cu")
		(net "P0V8_SERDES_VDDA_PEX0")
	)
	(segment
		(start 63.449962 -291.149786)
		(end 63.924942 -290.674806)
		(width 0.249936)
		(layer "F.Cu")
		(net "P0V8_SERDES_VDDA_PEX0")
	)
	(segment
		(start 51.574954 -290.674806)
		(end 51.099974 -291.149786)
		(width 0.249936)
		(layer "F.Cu")
		(net "P0V8_SERDES_VDDA_PEX0")
	)
	(segment
		(start 52.524914 -292.57498)
		(end 52.999894 -293.04996)
		(width 0.249936)
		(layer "F.Cu")
		(net "P0V8_SERDES_VDDA_PEX0")
	)
	(segment
		(start 64.399922 -300.649894)
		(end 63.924942 -301.124874)
		(width 0.249936)
		(layer "F.Cu")
		(net "P0V8_SERDES_VDDA_PEX0")
	)
	(segment
		(start 65.349882 -298.74972)
		(end 65.824862 -299.224954)
		(width 0.249936)
		(layer "F.Cu")
		(net "P0V8_SERDES_VDDA_PEX0")
	)
	(segment
		(start 54.424834 -301.124874)
		(end 53.949854 -300.649894)
		(width 0.249936)
		(layer "F.Cu")
		(net "P0V8_SERDES_VDDA_PEX0")
	)
	(segment
		(start 54.899814 -291.149786)
		(end 54.424834 -290.674806)
		(width 0.249936)
		(layer "F.Cu")
		(net "P0V8_SERDES_VDDA_PEX0")
	)
	(segment
		(start 65.349882 -300.649894)
		(end 64.874902 -301.124874)
		(width 0.249936)
		(layer "F.Cu")
		(net "P0V8_SERDES_VDDA_PEX0")
	)
	(segment
		(start 63.924942 -292.574726)
		(end 63.449962 -293.04996)
		(width 0.249936)
		(layer "F.Cu")
		(net "P0V8_SERDES_VDDA_PEX0")
	)
	(segment
		(start 59.649868 -293.04996)
		(end 60.124848 -292.574726)
		(width 0.249936)
		(layer "F.Cu")
		(net "P0V8_SERDES_VDDA_PEX0")
	)
	(segment
		(start 59.649868 -291.149786)
		(end 60.124848 -290.674806)
		(width 0.249936)
		(layer "F.Cu")
		(net "P0V8_SERDES_VDDA_PEX0")
	)
	(segment
		(start 66.299842 -293.04996)
		(end 66.774822 -292.574726)
		(width 0.249936)
		(layer "F.Cu")
		(net "P0V8_SERDES_VDDA_PEX0")
	)
	(segment
		(start 62.974982 -299.224954)
		(end 63.449962 -298.74972)
		(width 0.249936)
		(layer "F.Cu")
		(net "P0V8_SERDES_VDDA_PEX0")
	)
	(segment
		(start 60.124848 -292.574726)
		(end 60.599828 -293.04996)
		(width 0.249936)
		(layer "F.Cu")
		(net "P0V8_SERDES_VDDA_PEX0")
	)
	(segment
		(start 51.099974 -300.649894)
		(end 50.624994 -301.124874)
		(width 0.249936)
		(layer "F.Cu")
		(net "P0V8_SERDES_VDDA_PEX0")
	)
	(segment
		(start 52.049934 -291.149786)
		(end 51.574954 -290.674806)
		(width 0.249936)
		(layer "F.Cu")
		(net "P0V8_SERDES_VDDA_PEX0")
	)
	(segment
		(start 52.524914 -290.674806)
		(end 52.049934 -291.149786)
		(width 0.249936)
		(layer "F.Cu")
		(net "P0V8_SERDES_VDDA_PEX0")
	)
	(segment
		(start 51.099974 -300.649894)
		(end 51.574954 -301.124874)
		(width 0.249936)
		(layer "F.Cu")
		(net "P0V8_SERDES_VDDA_PEX0")
	)
	(segment
		(start 61.074808 -290.674806)
		(end 61.549788 -291.149786)
		(width 0.249936)
		(layer "F.Cu")
		(net "P0V8_SERDES_VDDA_PEX0")
	)
	(segment
		(start 57.749948 -300.649894)
		(end 58.224928 -301.124874)
		(width 0.249936)
		(layer "F.Cu")
		(net "P0V8_SERDES_VDDA_PEX0")
	)
	(segment
		(start 50.624994 -292.57498)
		(end 51.099974 -293.04996)
		(width 0.249936)
		(layer "F.Cu")
		(net "P0V8_SERDES_VDDA_PEX0")
	)
	(segment
		(start 62.024768 -301.124874)
		(end 62.499748 -300.649894)
		(width 0.249936)
		(layer "F.Cu")
		(net "P0V8_SERDES_VDDA_PEX0")
	)
	(segment
		(start 61.074808 -292.574726)
		(end 60.599828 -293.04996)
		(width 0.249936)
		(layer "F.Cu")
		(net "P0V8_SERDES_VDDA_PEX0")
	)
	(segment
		(start 65.824862 -290.674806)
		(end 65.349882 -291.149786)
		(width 0.249936)
		(layer "F.Cu")
		(net "P0V8_SERDES_VDDA_PEX0")
	)
	(segment
		(start 52.524914 -301.124874)
		(end 52.049934 -300.649894)
		(width 0.249936)
		(layer "F.Cu")
		(net "P0V8_SERDES_VDDA_PEX0")
	)
	(segment
		(start 52.999894 -298.74972)
		(end 53.474874 -299.224954)
		(width 0.249936)
		(layer "F.Cu")
		(net "P0V8_SERDES_VDDA_PEX0")
	)
	(segment
		(start 56.324754 -299.224954)
		(end 56.799988 -298.74972)
		(width 0.249936)
		(layer "F.Cu")
		(net "P0V8_SERDES_VDDA_PEX0")
	)
	(segment
		(start 62.974982 -301.124874)
		(end 63.449962 -300.649894)
		(width 0.249936)
		(layer "F.Cu")
		(net "P0V8_SERDES_VDDA_PEX0")
	)
	(segment
		(start 59.649868 -300.649894)
		(end 60.124848 -301.124874)
		(width 0.249936)
		(layer "F.Cu")
		(net "P0V8_SERDES_VDDA_PEX0")
	)
	(segment
		(start 63.924942 -299.224954)
		(end 64.399922 -298.74972)
		(width 0.249936)
		(layer "F.Cu")
		(net "P0V8_SERDES_VDDA_PEX0")
	)
	(segment
		(start 60.124848 -301.124874)
		(end 60.599828 -300.649894)
		(width 0.249936)
		(layer "F.Cu")
		(net "P0V8_SERDES_VDDA_PEX0")
	)
	(segment
		(start 58.224928 -292.57498)
		(end 58.699908 -293.04996)
		(width 0.249936)
		(layer "F.Cu")
		(net "P0V8_SERDES_VDDA_PEX0")
	)
	(segment
		(start 51.574954 -301.124874)
		(end 52.049934 -300.649894)
		(width 0.249936)
		(layer "F.Cu")
		(net "P0V8_SERDES_VDDA_PEX0")
	)
	(segment
		(start 64.874902 -292.574726)
		(end 65.349882 -293.04996)
		(width 0.249936)
		(layer "F.Cu")
		(net "P0V8_SERDES_VDDA_PEX0")
	)
	(segment
		(start 62.024768 -290.674806)
		(end 62.499748 -291.149786)
		(width 0.249936)
		(layer "F.Cu")
		(net "P0V8_SERDES_VDDA_PEX0")
	)
	(segment
		(start 65.349882 -300.649894)
		(end 65.824862 -301.124874)
		(width 0.249936)
		(layer "F.Cu")
		(net "P0V8_SERDES_VDDA_PEX0")
	)
	(segment
		(start 64.399922 -293.04996)
		(end 64.874902 -292.574726)
		(width 0.249936)
		(layer "F.Cu")
		(net "P0V8_SERDES_VDDA_PEX0")
	)
	(segment
		(start 51.574954 -292.57498)
		(end 52.049934 -293.04996)
		(width 0.249936)
		(layer "F.Cu")
		(net "P0V8_SERDES_VDDA_PEX0")
	)
	(segment
		(start 67.249802 -296.8498)
		(end 67.724782 -297.32478)
		(width 0.249936)
		(layer "F.Cu")
		(net "P0V8_SERDES_VDDA_PEX0")
	)
	(segment
		(start 61.074808 -299.224954)
		(end 60.599828 -298.74972)
		(width 0.249936)
		(layer "F.Cu")
		(net "P0V8_SERDES_VDDA_PEX0")
	)
	(segment
		(start 64.874902 -301.124874)
		(end 64.399922 -300.649894)
		(width 0.249936)
		(layer "F.Cu")
		(net "P0V8_SERDES_VDDA_PEX0")
	)
	(segment
		(start 51.099974 -298.74972)
		(end 50.624994 -299.224954)
		(width 0.249936)
		(layer "F.Cu")
		(net "P0V8_SERDES_VDDA_PEX0")
	)
	(segment
		(start 58.699908 -291.149786)
		(end 58.224928 -290.674806)
		(width 0.249936)
		(layer "F.Cu")
		(net "P0V8_SERDES_VDDA_PEX0")
	)
	(segment
		(start 67.249802 -298.74972)
		(end 67.724782 -299.224954)
		(width 0.249936)
		(layer "F.Cu")
		(net "P0V8_SERDES_VDDA_PEX0")
	)
	(segment
		(start 67.249802 -294.94988)
		(end 67.724782 -294.4749)
		(width 0.249936)
		(layer "F.Cu")
		(net "P0V8_SERDES_VDDA_PEX0")
	)
	(segment
		(start 60.599828 -291.149786)
		(end 61.074808 -290.674806)
		(width 0.249936)
		(layer "F.Cu")
		(net "P0V8_SERDES_VDDA_PEX0")
	)
	(segment
		(start 51.574954 -299.224954)
		(end 51.099974 -298.74972)
		(width 0.249936)
		(layer "F.Cu")
		(net "P0V8_SERDES_VDDA_PEX0")
	)
	(segment
		(start 55.849774 -298.74972)
		(end 55.374794 -299.224954)
		(width 0.249936)
		(layer "F.Cu")
		(net "P0V8_SERDES_VDDA_PEX0")
	)
	(segment
		(start 67.724782 -296.37482)
		(end 67.249802 -295.89984)
		(width 0.249936)
		(layer "F.Cu")
		(net "P0V8_SERDES_VDDA_PEX0")
	)
	(segment
		(start 61.549788 -300.649894)
		(end 62.024768 -301.124874)
		(width 0.249936)
		(layer "F.Cu")
		(net "P0V8_SERDES_VDDA_PEX0")
	)
	(segment
		(start 54.899814 -291.149786)
		(end 55.374794 -290.674806)
		(width 0.249936)
		(layer "F.Cu")
		(net "P0V8_SERDES_VDDA_PEX0")
	)
	(segment
		(start 61.549788 -298.74972)
		(end 62.024768 -299.224954)
		(width 0.249936)
		(layer "F.Cu")
		(net "P0V8_SERDES_VDDA_PEX0")
	)
	(segment
		(start 57.274968 -290.674806)
		(end 57.749948 -291.149786)
		(width 0.249936)
		(layer "F.Cu")
		(net "P0V8_SERDES_VDDA_PEX0")
	)
	(segment
		(start 66.774822 -294.4749)
		(end 67.249802 -294.94988)
		(width 0.249936)
		(layer "F.Cu")
		(net "P0V8_SERDES_VDDA_PEX0")
	)
	(segment
		(start 66.299842 -291.149786)
		(end 66.774822 -290.674806)
		(width 0.249936)
		(layer "F.Cu")
		(net "P0V8_SERDES_VDDA_PEX0")
	)
	(segment
		(start 60.124848 -290.674806)
		(end 60.599828 -291.149786)
		(width 0.249936)
		(layer "F.Cu")
		(net "P0V8_SERDES_VDDA_PEX0")
	)
	(segment
		(start 67.249802 -293.04996)
		(end 67.724782 -292.574726)
		(width 0.249936)
		(layer "F.Cu")
		(net "P0V8_SERDES_VDDA_PEX0")
	)
	(segment
		(start 52.999894 -300.649894)
		(end 52.524914 -301.124874)
		(width 0.249936)
		(layer "F.Cu")
		(net "P0V8_SERDES_VDDA_PEX0")
	)
	(segment
		(start 66.299842 -291.149786)
		(end 65.824862 -290.674806)
		(width 0.249936)
		(layer "F.Cu")
		(net "P0V8_SERDES_VDDA_PEX0")
	)
	(segment
		(start 64.874902 -290.674806)
		(end 65.349882 -291.149786)
		(width 0.249936)
		(layer "F.Cu")
		(net "P0V8_SERDES_VDDA_PEX0")
	)
	(segment
		(start 66.299842 -300.649894)
		(end 66.774822 -301.124874)
		(width 0.249936)
		(layer "F.Cu")
		(net "P0V8_SERDES_VDDA_PEX0")
	)
	(segment
		(start 62.024768 -292.574726)
		(end 62.499748 -293.04996)
		(width 0.249936)
		(layer "F.Cu")
		(net "P0V8_SERDES_VDDA_PEX0")
	)
	(segment
		(start 59.649868 -298.74972)
		(end 60.124848 -299.224954)
		(width 0.249936)
		(layer "F.Cu")
		(net "P0V8_SERDES_VDDA_PEX0")
	)
	(segment
		(start 53.474874 -290.674806)
		(end 53.949854 -291.149786)
		(width 0.249936)
		(layer "F.Cu")
		(net "P0V8_SERDES_VDDA_PEX0")
	)
	(segment
		(start 56.324754 -301.124874)
		(end 56.799988 -300.649894)
		(width 0.249936)
		(layer "F.Cu")
		(net "P0V8_SERDES_VDDA_PEX0")
	)
	(segment
		(start 62.499748 -300.649894)
		(end 62.974982 -301.124874)
		(width 0.249936)
		(layer "F.Cu")
		(net "P0V8_SERDES_VDDA_PEX0")
	)
	(segment
		(start 67.249802 -296.8498)
		(end 66.774822 -297.32478)
		(width 0.249936)
		(layer "F.Cu")
		(net "P0V8_SERDES_VDDA_PEX0")
	)
	(segment
		(start 64.399922 -291.149786)
		(end 64.874902 -290.674806)
		(width 0.249936)
		(layer "F.Cu")
		(net "P0V8_SERDES_VDDA_PEX0")
	)
	(segment
		(start 61.549788 -298.74972)
		(end 61.074808 -299.224954)
		(width 0.249936)
		(layer "F.Cu")
		(net "P0V8_SERDES_VDDA_PEX0")
	)
	(via
		(at 65.824862 -301.124874)
		(size 0.4064)
		(drill 0.2032)
		(layers "F.Cu" "B.Cu")
		(net "P0V8_SERDES_VDDA_PEX0")
	)
	(via
		(at 112.700308 -320.08064)
		(size 0.508)
		(drill 0.254)
		(layers "F.Cu" "B.Cu")
		(net "P0V8_SERDES_VDDA_PEX0")
	)
	(via
		(at 51.574954 -292.57498)
		(size 0.4064)
		(drill 0.2032)
		(layers "F.Cu" "B.Cu")
		(net "P0V8_SERDES_VDDA_PEX0")
	)
	(via
		(at 62.024768 -301.124874)
		(size 0.4064)
		(drill 0.2032)
		(layers "F.Cu" "B.Cu")
		(net "P0V8_SERDES_VDDA_PEX0")
	)
	(via
		(at 67.724782 -294.4749)
		(size 0.4064)
		(drill 0.2032)
		(layers "F.Cu" "B.Cu")
		(net "P0V8_SERDES_VDDA_PEX0")
	)
	(via
		(at 68.674742 -297.32478)
		(size 0.4064)
		(drill 0.2032)
		(layers "F.Cu" "B.Cu")
		(net "P0V8_SERDES_VDDA_PEX0")
	)
	(via
		(at 61.074808 -299.224954)
		(size 0.4064)
		(drill 0.2032)
		(layers "F.Cu" "B.Cu")
		(net "P0V8_SERDES_VDDA_PEX0")
	)
	(via
		(at 52.524914 -290.674806)
		(size 0.4064)
		(drill 0.2032)
		(layers "F.Cu" "B.Cu")
		(net "P0V8_SERDES_VDDA_PEX0")
	)
	(via
		(at 54.424834 -292.57498)
		(size 0.4064)
		(drill 0.2032)
		(layers "F.Cu" "B.Cu")
		(net "P0V8_SERDES_VDDA_PEX0")
	)
	(via
		(at 67.724782 -299.224954)
		(size 0.4064)
		(drill 0.2032)
		(layers "F.Cu" "B.Cu")
		(net "P0V8_SERDES_VDDA_PEX0")
	)
	(via
		(at 53.474874 -290.674806)
		(size 0.4064)
		(drill 0.2032)
		(layers "F.Cu" "B.Cu")
		(net "P0V8_SERDES_VDDA_PEX0")
	)
	(via
		(at 109.652308 -320.08064)
		(size 0.508)
		(drill 0.254)
		(layers "F.Cu" "B.Cu")
		(net "P0V8_SERDES_VDDA_PEX0")
	)
	(via
		(at 68.674742 -294.4749)
		(size 0.4064)
		(drill 0.2032)
		(layers "F.Cu" "B.Cu")
		(net "P0V8_SERDES_VDDA_PEX0")
	)
	(via
		(at 110.414308 -319.31864)
		(size 0.508)
		(drill 0.254)
		(layers "F.Cu" "B.Cu")
		(net "P0V8_SERDES_VDDA_PEX0")
	)
	(via
		(at 65.824862 -290.674806)
		(size 0.4064)
		(drill 0.2032)
		(layers "F.Cu" "B.Cu")
		(net "P0V8_SERDES_VDDA_PEX0")
	)
	(via
		(at 116.984018 -312.475626)
		(size 0.6604)
		(drill 0.3302)
		(layers "F.Cu" "B.Cu")
		(net "P0V8_SERDES_VDDA_PEX0")
	)
	(via
		(at 57.274968 -299.224954)
		(size 0.4064)
		(drill 0.2032)
		(layers "F.Cu" "B.Cu")
		(net "P0V8_SERDES_VDDA_PEX0")
	)
	(via
		(at 62.974982 -292.574726)
		(size 0.4064)
		(drill 0.2032)
		(layers "F.Cu" "B.Cu")
		(net "P0V8_SERDES_VDDA_PEX0")
	)
	(via
		(at 106.604308 -320.08064)
		(size 0.508)
		(drill 0.254)
		(layers "F.Cu" "B.Cu")
		(net "P0V8_SERDES_VDDA_PEX0")
	)
	(via
		(at 51.574954 -301.124874)
		(size 0.4064)
		(drill 0.2032)
		(layers "F.Cu" "B.Cu")
		(net "P0V8_SERDES_VDDA_PEX0")
	)
	(via
		(at 55.374794 -292.57498)
		(size 0.4064)
		(drill 0.2032)
		(layers "F.Cu" "B.Cu")
		(net "P0V8_SERDES_VDDA_PEX0")
	)
	(via
		(at 62.974982 -301.124874)
		(size 0.4064)
		(drill 0.2032)
		(layers "F.Cu" "B.Cu")
		(net "P0V8_SERDES_VDDA_PEX0")
	)
	(via
		(at 52.524914 -292.57498)
		(size 0.4064)
		(drill 0.2032)
		(layers "F.Cu" "B.Cu")
		(net "P0V8_SERDES_VDDA_PEX0")
	)
	(via
		(at 62.024768 -292.574726)
		(size 0.4064)
		(drill 0.2032)
		(layers "F.Cu" "B.Cu")
		(net "P0V8_SERDES_VDDA_PEX0")
	)
	(via
		(at 106.604308 -319.31864)
		(size 0.508)
		(drill 0.254)
		(layers "F.Cu" "B.Cu")
		(net "P0V8_SERDES_VDDA_PEX0")
	)
	(via
		(at 61.074808 -292.574726)
		(size 0.4064)
		(drill 0.2032)
		(layers "F.Cu" "B.Cu")
		(net "P0V8_SERDES_VDDA_PEX0")
	)
	(via
		(at 57.274968 -301.124874)
		(size 0.4064)
		(drill 0.2032)
		(layers "F.Cu" "B.Cu")
		(net "P0V8_SERDES_VDDA_PEX0")
	)
	(via
		(at 65.824862 -292.574726)
		(size 0.4064)
		(drill 0.2032)
		(layers "F.Cu" "B.Cu")
		(net "P0V8_SERDES_VDDA_PEX0")
	)
	(via
		(at 62.024768 -290.674806)
		(size 0.4064)
		(drill 0.2032)
		(layers "F.Cu" "B.Cu")
		(net "P0V8_SERDES_VDDA_PEX0")
	)
	(via
		(at 57.274968 -290.674806)
		(size 0.4064)
		(drill 0.2032)
		(layers "F.Cu" "B.Cu")
		(net "P0V8_SERDES_VDDA_PEX0")
	)
	(via
		(at 55.374794 -299.224954)
		(size 0.4064)
		(drill 0.2032)
		(layers "F.Cu" "B.Cu")
		(net "P0V8_SERDES_VDDA_PEX0")
	)
	(via
		(at 63.924942 -290.674806)
		(size 0.4064)
		(drill 0.2032)
		(layers "F.Cu" "B.Cu")
		(net "P0V8_SERDES_VDDA_PEX0")
	)
	(via
		(at 109.652308 -319.31864)
		(size 0.508)
		(drill 0.254)
		(layers "F.Cu" "B.Cu")
		(net "P0V8_SERDES_VDDA_PEX0")
	)
	(via
		(at 54.424834 -299.224954)
		(size 0.4064)
		(drill 0.2032)
		(layers "F.Cu" "B.Cu")
		(net "P0V8_SERDES_VDDA_PEX0")
	)
	(via
		(at 114.224308 -320.08064)
		(size 0.508)
		(drill 0.254)
		(layers "F.Cu" "B.Cu")
		(net "P0V8_SERDES_VDDA_PEX0")
	)
	(via
		(at 113.462308 -319.31864)
		(size 0.508)
		(drill 0.254)
		(layers "F.Cu" "B.Cu")
		(net "P0V8_SERDES_VDDA_PEX0")
	)
	(via
		(at 67.724782 -296.37482)
		(size 0.4064)
		(drill 0.2032)
		(layers "F.Cu" "B.Cu")
		(net "P0V8_SERDES_VDDA_PEX0")
	)
	(via
		(at 56.324754 -299.224954)
		(size 0.4064)
		(drill 0.2032)
		(layers "F.Cu" "B.Cu")
		(net "P0V8_SERDES_VDDA_PEX0")
	)
	(via
		(at 64.874902 -301.124874)
		(size 0.4064)
		(drill 0.2032)
		(layers "F.Cu" "B.Cu")
		(net "P0V8_SERDES_VDDA_PEX0")
	)
	(via
		(at 56.324754 -290.674806)
		(size 0.4064)
		(drill 0.2032)
		(layers "F.Cu" "B.Cu")
		(net "P0V8_SERDES_VDDA_PEX0")
	)
	(via
		(at 51.574954 -299.224954)
		(size 0.4064)
		(drill 0.2032)
		(layers "F.Cu" "B.Cu")
		(net "P0V8_SERDES_VDDA_PEX0")
	)
	(via
		(at 113.462308 -320.08064)
		(size 0.508)
		(drill 0.254)
		(layers "F.Cu" "B.Cu")
		(net "P0V8_SERDES_VDDA_PEX0")
	)
	(via
		(at 63.924942 -292.574726)
		(size 0.4064)
		(drill 0.2032)
		(layers "F.Cu" "B.Cu")
		(net "P0V8_SERDES_VDDA_PEX0")
	)
	(via
		(at 60.124848 -299.224954)
		(size 0.4064)
		(drill 0.2032)
		(layers "F.Cu" "B.Cu")
		(net "P0V8_SERDES_VDDA_PEX0")
	)
	(via
		(at 58.224928 -290.674806)
		(size 0.4064)
		(drill 0.2032)
		(layers "F.Cu" "B.Cu")
		(net "P0V8_SERDES_VDDA_PEX0")
	)
	(via
		(at 111.938308 -320.08064)
		(size 0.508)
		(drill 0.254)
		(layers "F.Cu" "B.Cu")
		(net "P0V8_SERDES_VDDA_PEX0")
	)
	(via
		(at 50.624994 -290.674806)
		(size 0.4064)
		(drill 0.2032)
		(layers "F.Cu" "B.Cu")
		(net "P0V8_SERDES_VDDA_PEX0")
	)
	(via
		(at 65.824862 -299.224954)
		(size 0.4064)
		(drill 0.2032)
		(layers "F.Cu" "B.Cu")
		(net "P0V8_SERDES_VDDA_PEX0")
	)
	(via
		(at 107.366308 -320.08064)
		(size 0.508)
		(drill 0.254)
		(layers "F.Cu" "B.Cu")
		(net "P0V8_SERDES_VDDA_PEX0")
	)
	(via
		(at 58.224928 -292.57498)
		(size 0.4064)
		(drill 0.2032)
		(layers "F.Cu" "B.Cu")
		(net "P0V8_SERDES_VDDA_PEX0")
	)
	(via
		(at 111.938308 -319.31864)
		(size 0.508)
		(drill 0.254)
		(layers "F.Cu" "B.Cu")
		(net "P0V8_SERDES_VDDA_PEX0")
	)
	(via
		(at 66.774822 -297.32478)
		(size 0.4064)
		(drill 0.2032)
		(layers "F.Cu" "B.Cu")
		(net "P0V8_SERDES_VDDA_PEX0")
	)
	(via
		(at 61.074808 -290.674806)
		(size 0.4064)
		(drill 0.2032)
		(layers "F.Cu" "B.Cu")
		(net "P0V8_SERDES_VDDA_PEX0")
	)
	(via
		(at 66.774822 -301.124874)
		(size 0.4064)
		(drill 0.2032)
		(layers "F.Cu" "B.Cu")
		(net "P0V8_SERDES_VDDA_PEX0")
	)
	(via
		(at 108.128308 -320.08064)
		(size 0.508)
		(drill 0.254)
		(layers "F.Cu" "B.Cu")
		(net "P0V8_SERDES_VDDA_PEX0")
	)
	(via
		(at 52.524914 -301.124874)
		(size 0.4064)
		(drill 0.2032)
		(layers "F.Cu" "B.Cu")
		(net "P0V8_SERDES_VDDA_PEX0")
	)
	(via
		(at 66.774822 -292.574726)
		(size 0.4064)
		(drill 0.2032)
		(layers "F.Cu" "B.Cu")
		(net "P0V8_SERDES_VDDA_PEX0")
	)
	(via
		(at 57.274968 -292.57498)
		(size 0.4064)
		(drill 0.2032)
		(layers "F.Cu" "B.Cu")
		(net "P0V8_SERDES_VDDA_PEX0")
	)
	(via
		(at 54.424834 -290.674806)
		(size 0.4064)
		(drill 0.2032)
		(layers "F.Cu" "B.Cu")
		(net "P0V8_SERDES_VDDA_PEX0")
	)
	(via
		(at 51.574954 -290.674806)
		(size 0.4064)
		(drill 0.2032)
		(layers "F.Cu" "B.Cu")
		(net "P0V8_SERDES_VDDA_PEX0")
	)
	(via
		(at 108.890308 -320.08064)
		(size 0.508)
		(drill 0.254)
		(layers "F.Cu" "B.Cu")
		(net "P0V8_SERDES_VDDA_PEX0")
	)
	(via
		(at 112.700308 -319.31864)
		(size 0.508)
		(drill 0.254)
		(layers "F.Cu" "B.Cu")
		(net "P0V8_SERDES_VDDA_PEX0")
	)
	(via
		(at 62.974982 -290.674806)
		(size 0.4064)
		(drill 0.2032)
		(layers "F.Cu" "B.Cu")
		(net "P0V8_SERDES_VDDA_PEX0")
	)
	(via
		(at 58.224928 -299.224954)
		(size 0.4064)
		(drill 0.2032)
		(layers "F.Cu" "B.Cu")
		(net "P0V8_SERDES_VDDA_PEX0")
	)
	(via
		(at 107.366308 -319.31864)
		(size 0.508)
		(drill 0.254)
		(layers "F.Cu" "B.Cu")
		(net "P0V8_SERDES_VDDA_PEX0")
	)
	(via
		(at 54.424834 -301.124874)
		(size 0.4064)
		(drill 0.2032)
		(layers "F.Cu" "B.Cu")
		(net "P0V8_SERDES_VDDA_PEX0")
	)
	(via
		(at 66.774822 -299.224954)
		(size 0.4064)
		(drill 0.2032)
		(layers "F.Cu" "B.Cu")
		(net "P0V8_SERDES_VDDA_PEX0")
	)
	(via
		(at 116.72824 -314.76823)
		(size 0.6604)
		(drill 0.3302)
		(layers "F.Cu" "B.Cu")
		(net "P0V8_SERDES_VDDA_PEX0")
	)
	(via
		(at 53.474874 -292.57498)
		(size 0.4064)
		(drill 0.2032)
		(layers "F.Cu" "B.Cu")
		(net "P0V8_SERDES_VDDA_PEX0")
	)
	(via
		(at 111.176308 -320.08064)
		(size 0.508)
		(drill 0.254)
		(layers "F.Cu" "B.Cu")
		(net "P0V8_SERDES_VDDA_PEX0")
	)
	(via
		(at 60.124848 -290.674806)
		(size 0.4064)
		(drill 0.2032)
		(layers "F.Cu" "B.Cu")
		(net "P0V8_SERDES_VDDA_PEX0")
	)
	(via
		(at 53.474874 -301.124874)
		(size 0.4064)
		(drill 0.2032)
		(layers "F.Cu" "B.Cu")
		(net "P0V8_SERDES_VDDA_PEX0")
	)
	(via
		(at 63.924942 -299.224954)
		(size 0.4064)
		(drill 0.2032)
		(layers "F.Cu" "B.Cu")
		(net "P0V8_SERDES_VDDA_PEX0")
	)
	(via
		(at 50.624994 -292.57498)
		(size 0.4064)
		(drill 0.2032)
		(layers "F.Cu" "B.Cu")
		(net "P0V8_SERDES_VDDA_PEX0")
	)
	(via
		(at 108.128308 -319.31864)
		(size 0.508)
		(drill 0.254)
		(layers "F.Cu" "B.Cu")
		(net "P0V8_SERDES_VDDA_PEX0")
	)
	(via
		(at 67.724782 -292.574726)
		(size 0.4064)
		(drill 0.2032)
		(layers "F.Cu" "B.Cu")
		(net "P0V8_SERDES_VDDA_PEX0")
	)
	(via
		(at 66.774822 -290.674806)
		(size 0.4064)
		(drill 0.2032)
		(layers "F.Cu" "B.Cu")
		(net "P0V8_SERDES_VDDA_PEX0")
	)
	(via
		(at 60.124848 -292.574726)
		(size 0.4064)
		(drill 0.2032)
		(layers "F.Cu" "B.Cu")
		(net "P0V8_SERDES_VDDA_PEX0")
	)
	(via
		(at 62.024768 -299.224954)
		(size 0.4064)
		(drill 0.2032)
		(layers "F.Cu" "B.Cu")
		(net "P0V8_SERDES_VDDA_PEX0")
	)
	(via
		(at 67.724782 -301.124874)
		(size 0.4064)
		(drill 0.2032)
		(layers "F.Cu" "B.Cu")
		(net "P0V8_SERDES_VDDA_PEX0")
	)
	(via
		(at 68.674742 -296.37482)
		(size 0.4064)
		(drill 0.2032)
		(layers "F.Cu" "B.Cu")
		(net "P0V8_SERDES_VDDA_PEX0")
	)
	(via
		(at 53.474874 -299.224954)
		(size 0.4064)
		(drill 0.2032)
		(layers "F.Cu" "B.Cu")
		(net "P0V8_SERDES_VDDA_PEX0")
	)
	(via
		(at 56.325008 -292.57498)
		(size 0.4064)
		(drill 0.2032)
		(layers "F.Cu" "B.Cu")
		(net "P0V8_SERDES_VDDA_PEX0")
	)
	(via
		(at 111.176308 -319.31864)
		(size 0.508)
		(drill 0.254)
		(layers "F.Cu" "B.Cu")
		(net "P0V8_SERDES_VDDA_PEX0")
	)
	(via
		(at 64.874902 -292.574726)
		(size 0.4064)
		(drill 0.2032)
		(layers "F.Cu" "B.Cu")
		(net "P0V8_SERDES_VDDA_PEX0")
	)
	(via
		(at 64.874902 -290.674806)
		(size 0.4064)
		(drill 0.2032)
		(layers "F.Cu" "B.Cu")
		(net "P0V8_SERDES_VDDA_PEX0")
	)
	(via
		(at 52.524914 -299.224954)
		(size 0.4064)
		(drill 0.2032)
		(layers "F.Cu" "B.Cu")
		(net "P0V8_SERDES_VDDA_PEX0")
	)
	(via
		(at 67.724782 -297.32478)
		(size 0.4064)
		(drill 0.2032)
		(layers "F.Cu" "B.Cu")
		(net "P0V8_SERDES_VDDA_PEX0")
	)
	(via
		(at 60.124848 -301.124874)
		(size 0.4064)
		(drill 0.2032)
		(layers "F.Cu" "B.Cu")
		(net "P0V8_SERDES_VDDA_PEX0")
	)
	(via
		(at 116.20754 -310.922924)
		(size 0.6604)
		(drill 0.3302)
		(layers "F.Cu" "B.Cu")
		(net "P0V8_SERDES_VDDA_PEX0")
	)
	(via
		(at 55.374794 -301.124874)
		(size 0.4064)
		(drill 0.2032)
		(layers "F.Cu" "B.Cu")
		(net "P0V8_SERDES_VDDA_PEX0")
	)
	(via
		(at 114.224308 -319.31864)
		(size 0.508)
		(drill 0.254)
		(layers "F.Cu" "B.Cu")
		(net "P0V8_SERDES_VDDA_PEX0")
	)
	(via
		(at 63.924942 -301.124874)
		(size 0.4064)
		(drill 0.2032)
		(layers "F.Cu" "B.Cu")
		(net "P0V8_SERDES_VDDA_PEX0")
	)
	(via
		(at 50.624994 -299.224954)
		(size 0.4064)
		(drill 0.2032)
		(layers "F.Cu" "B.Cu")
		(net "P0V8_SERDES_VDDA_PEX0")
	)
	(via
		(at 61.074808 -301.124874)
		(size 0.4064)
		(drill 0.2032)
		(layers "F.Cu" "B.Cu")
		(net "P0V8_SERDES_VDDA_PEX0")
	)
	(via
		(at 62.974982 -299.224954)
		(size 0.4064)
		(drill 0.2032)
		(layers "F.Cu" "B.Cu")
		(net "P0V8_SERDES_VDDA_PEX0")
	)
	(via
		(at 64.874902 -299.224954)
		(size 0.4064)
		(drill 0.2032)
		(layers "F.Cu" "B.Cu")
		(net "P0V8_SERDES_VDDA_PEX0")
	)
	(via
		(at 108.890308 -319.31864)
		(size 0.508)
		(drill 0.254)
		(layers "F.Cu" "B.Cu")
		(net "P0V8_SERDES_VDDA_PEX0")
	)
	(via
		(at 110.414308 -320.08064)
		(size 0.508)
		(drill 0.254)
		(layers "F.Cu" "B.Cu")
		(net "P0V8_SERDES_VDDA_PEX0")
	)
	(via
		(at 56.324754 -301.124874)
		(size 0.4064)
		(drill 0.2032)
		(layers "F.Cu" "B.Cu")
		(net "P0V8_SERDES_VDDA_PEX0")
	)
	(via
		(at 66.774822 -294.4749)
		(size 0.4064)
		(drill 0.2032)
		(layers "F.Cu" "B.Cu")
		(net "P0V8_SERDES_VDDA_PEX0")
	)
	(via
		(at 67.724782 -290.674806)
		(size 0.4064)
		(drill 0.2032)
		(layers "F.Cu" "B.Cu")
		(net "P0V8_SERDES_VDDA_PEX0")
	)
	(via
		(at 50.624994 -301.124874)
		(size 0.4064)
		(drill 0.2032)
		(layers "F.Cu" "B.Cu")
		(net "P0V8_SERDES_VDDA_PEX0")
	)
	(via
		(at 55.374794 -290.674806)
		(size 0.4064)
		(drill 0.2032)
		(layers "F.Cu" "B.Cu")
		(net "P0V8_SERDES_VDDA_PEX0")
	)
	(via
		(at 58.224928 -301.124874)
		(size 0.4064)
		(drill 0.2032)
		(layers "F.Cu" "B.Cu")
		(net "P0V8_SERDES_VDDA_PEX0")
	)
	(segment
		(start 53.474874 -288.774886)
		(end 53.949854 -289.249866)
		(width 0.249936)
		(layer "F.Cu")
		(net "P1V25_PEX0")
	)
	(segment
		(start 61.549788 -302.549814)
		(end 62.024768 -303.024794)
		(width 0.249936)
		(layer "F.Cu")
		(net "P1V25_PEX0")
	)
	(segment
		(start 52.049934 -302.549814)
		(end 52.524914 -303.024794)
		(width 0.249936)
		(layer "F.Cu")
		(net "P1V25_PEX0")
	)
	(segment
		(start 67.249802 -289.249866)
		(end 67.724782 -288.774886)
		(width 0.249936)
		(layer "F.Cu")
		(net "P1V25_PEX0")
	)
	(segment
		(start 52.524914 -303.024794)
		(end 52.999894 -302.549814)
		(width 0.249936)
		(layer "F.Cu")
		(net "P1V25_PEX0")
	)
	(segment
		(start 54.424834 -303.024794)
		(end 53.949854 -302.549814)
		(width 0.249936)
		(layer "F.Cu")
		(net "P1V25_PEX0")
	)
	(segment
		(start 66.774822 -288.774886)
		(end 67.249802 -289.249866)
		(width 0.249936)
		(layer "F.Cu")
		(net "P1V25_PEX0")
	)
	(segment
		(start 60.599828 -302.549814)
		(end 61.074808 -303.024794)
		(width 0.249936)
		(layer "F.Cu")
		(net "P1V25_PEX0")
	)
	(segment
		(start 57.749948 -289.249866)
		(end 58.224928 -288.774886)
		(width 0.249936)
		(layer "F.Cu")
		(net "P1V25_PEX0")
	)
	(segment
		(start 70.574916 -297.32478)
		(end 70.099936 -296.8498)
		(width 0.249936)
		(layer "F.Cu")
		(net "P1V25_PEX0")
	)
	(segment
		(start 59.649868 -289.249866)
		(end 60.124848 -288.774886)
		(width 0.249936)
		(layer "F.Cu")
		(net "P1V25_PEX0")
	)
	(segment
		(start 57.274968 -303.024794)
		(end 56.799988 -302.549814)
		(width 0.249936)
		(layer "F.Cu")
		(net "P1V25_PEX0")
	)
	(segment
		(start 57.749948 -302.549814)
		(end 57.274968 -303.024794)
		(width 0.249936)
		(layer "F.Cu")
		(net "P1V25_PEX0")
	)
	(segment
		(start 54.899814 -289.249866)
		(end 54.424834 -288.774886)
		(width 0.249936)
		(layer "F.Cu")
		(net "P1V25_PEX0")
	)
	(segment
		(start 60.124848 -303.024794)
		(end 59.649868 -302.549814)
		(width 0.249936)
		(layer "F.Cu")
		(net "P1V25_PEX0")
	)
	(segment
		(start 62.024768 -288.774886)
		(end 62.499748 -289.249866)
		(width 0.249936)
		(layer "F.Cu")
		(net "P1V25_PEX0")
	)
	(segment
		(start 62.499748 -302.549814)
		(end 62.974982 -303.024794)
		(width 0.249936)
		(layer "F.Cu")
		(net "P1V25_PEX0")
	)
	(segment
		(start 57.749948 -289.249866)
		(end 57.274968 -288.774886)
		(width 0.249936)
		(layer "F.Cu")
		(net "P1V25_PEX0")
	)
	(segment
		(start 67.249802 -302.549814)
		(end 67.724782 -303.024794)
		(width 0.249936)
		(layer "F.Cu")
		(net "P1V25_PEX0")
	)
	(segment
		(start 57.274968 -288.774886)
		(end 56.799988 -289.249866)
		(width 0.249936)
		(layer "F.Cu")
		(net "P1V25_PEX0")
	)
	(segment
		(start 66.299842 -289.249866)
		(end 66.774822 -288.774886)
		(width 0.249936)
		(layer "F.Cu")
		(net "P1V25_PEX0")
	)
	(segment
		(start 70.574916 -293.52494)
		(end 70.099936 -293.99992)
		(width 0.249936)
		(layer "F.Cu")
		(net "P1V25_PEX0")
	)
	(segment
		(start 51.099974 -289.249866)
		(end 50.624994 -288.774886)
		(width 0.249936)
		(layer "F.Cu")
		(net "P1V25_PEX0")
	)
	(segment
		(start 61.074808 -288.774886)
		(end 60.599828 -289.249866)
		(width 0.249936)
		(layer "F.Cu")
		(net "P1V25_PEX0")
	)
	(segment
		(start 51.574954 -303.024794)
		(end 52.049934 -302.549814)
		(width 0.249936)
		(layer "F.Cu")
		(net "P1V25_PEX0")
	)
	(segment
		(start 66.299842 -289.249866)
		(end 65.824862 -288.774886)
		(width 0.249936)
		(layer "F.Cu")
		(net "P1V25_PEX0")
	)
	(segment
		(start 55.374794 -303.024794)
		(end 55.849774 -302.549814)
		(width 0.249936)
		(layer "F.Cu")
		(net "P1V25_PEX0")
	)
	(segment
		(start 60.599828 -302.549814)
		(end 60.124848 -303.024794)
		(width 0.249936)
		(layer "F.Cu")
		(net "P1V25_PEX0")
	)
	(segment
		(start 54.899814 -302.549814)
		(end 54.424834 -303.024794)
		(width 0.249936)
		(layer "F.Cu")
		(net "P1V25_PEX0")
	)
	(segment
		(start 56.324754 -303.024794)
		(end 56.799988 -302.549814)
		(width 0.249936)
		(layer "F.Cu")
		(net "P1V25_PEX0")
	)
	(segment
		(start 53.949854 -302.549814)
		(end 53.474874 -303.024794)
		(width 0.249936)
		(layer "F.Cu")
		(net "P1V25_PEX0")
	)
	(segment
		(start 57.749948 -302.549814)
		(end 58.224928 -303.024794)
		(width 0.249936)
		(layer "F.Cu")
		(net "P1V25_PEX0")
	)
	(segment
		(start 62.499748 -289.249866)
		(end 62.974982 -288.774886)
		(width 0.249936)
		(layer "F.Cu")
		(net "P1V25_PEX0")
	)
	(segment
		(start 55.374794 -288.774886)
		(end 54.899814 -289.249866)
		(width 0.249936)
		(layer "F.Cu")
		(net "P1V25_PEX0")
	)
	(segment
		(start 54.899814 -302.549814)
		(end 55.374794 -303.024794)
		(width 0.249936)
		(layer "F.Cu")
		(net "P1V25_PEX0")
	)
	(segment
		(start 54.424834 -288.774886)
		(end 53.949854 -289.249866)
		(width 0.249936)
		(layer "F.Cu")
		(net "P1V25_PEX0")
	)
	(segment
		(start 64.399922 -289.249866)
		(end 63.924942 -288.774886)
		(width 0.249936)
		(layer "F.Cu")
		(net "P1V25_PEX0")
	)
	(segment
		(start 70.099936 -297.79976)
		(end 70.574916 -297.32478)
		(width 0.249936)
		(layer "F.Cu")
		(net "P1V25_PEX0")
	)
	(segment
		(start 52.999894 -289.249866)
		(end 52.524914 -288.774886)
		(width 0.249936)
		(layer "F.Cu")
		(net "P1V25_PEX0")
	)
	(segment
		(start 62.974982 -288.774886)
		(end 63.449962 -289.249866)
		(width 0.249936)
		(layer "F.Cu")
		(net "P1V25_PEX0")
	)
	(segment
		(start 70.099936 -295.89984)
		(end 70.574916 -296.37482)
		(width 0.249936)
		(layer "F.Cu")
		(net "P1V25_PEX0")
	)
	(segment
		(start 51.574954 -288.774886)
		(end 51.099974 -289.249866)
		(width 0.249936)
		(layer "F.Cu")
		(net "P1V25_PEX0")
	)
	(segment
		(start 65.824862 -288.774886)
		(end 65.349882 -289.249866)
		(width 0.249936)
		(layer "F.Cu")
		(net "P1V25_PEX0")
	)
	(segment
		(start 60.124848 -288.774886)
		(end 60.599828 -289.249866)
		(width 0.249936)
		(layer "F.Cu")
		(net "P1V25_PEX0")
	)
	(segment
		(start 55.849774 -302.549814)
		(end 56.324754 -303.024794)
		(width 0.249936)
		(layer "F.Cu")
		(net "P1V25_PEX0")
	)
	(segment
		(start 65.349882 -302.549814)
		(end 65.824862 -303.024794)
		(width 0.249936)
		(layer "F.Cu")
		(net "P1V25_PEX0")
	)
	(segment
		(start 63.449962 -302.549814)
		(end 63.924942 -303.024794)
		(width 0.249936)
		(layer "F.Cu")
		(net "P1V25_PEX0")
	)
	(segment
		(start 56.324754 -288.774886)
		(end 56.799988 -289.249866)
		(width 0.249936)
		(layer "F.Cu")
		(net "P1V25_PEX0")
	)
	(segment
		(start 58.224928 -303.024794)
		(end 58.699908 -302.549814)
		(width 0.249936)
		(layer "F.Cu")
		(net "P1V25_PEX0")
	)
	(segment
		(start 52.524914 -288.774886)
		(end 52.049934 -289.249866)
		(width 0.249936)
		(layer "F.Cu")
		(net "P1V25_PEX0")
	)
	(segment
		(start 63.924942 -288.774886)
		(end 63.449962 -289.249866)
		(width 0.249936)
		(layer "F.Cu")
		(net "P1V25_PEX0")
	)
	(segment
		(start 70.574916 -296.37482)
		(end 70.099936 -296.8498)
		(width 0.249936)
		(layer "F.Cu")
		(net "P1V25_PEX0")
	)
	(segment
		(start 17.406366 -306.28209)
		(end 18.020538 -306.28209)
		(width 0.254)
		(layer "F.Cu")
		(net "P1V25_PEX0")
	)
	(segment
		(start 55.849774 -289.249866)
		(end 55.374794 -288.774886)
		(width 0.249936)
		(layer "F.Cu")
		(net "P1V25_PEX0")
	)
	(segment
		(start 53.474874 -303.024794)
		(end 52.999894 -302.549814)
		(width 0.249936)
		(layer "F.Cu")
		(net "P1V25_PEX0")
	)
	(segment
		(start 70.099936 -297.79976)
		(end 70.574916 -298.27474)
		(width 0.249936)
		(layer "F.Cu")
		(net "P1V25_PEX0")
	)
	(segment
		(start 64.874902 -288.774886)
		(end 65.349882 -289.249866)
		(width 0.249936)
		(layer "F.Cu")
		(net "P1V25_PEX0")
	)
	(segment
		(start 70.574916 -294.4749)
		(end 70.099936 -294.94988)
		(width 0.249936)
		(layer "F.Cu")
		(net "P1V25_PEX0")
	)
	(segment
		(start 55.849774 -289.249866)
		(end 56.324754 -288.774886)
		(width 0.249936)
		(layer "F.Cu")
		(net "P1V25_PEX0")
	)
	(segment
		(start 61.549788 -289.249866)
		(end 61.074808 -288.774886)
		(width 0.249936)
		(layer "F.Cu")
		(net "P1V25_PEX0")
	)
	(segment
		(start 58.224928 -288.774886)
		(end 58.699908 -289.249866)
		(width 0.249936)
		(layer "F.Cu")
		(net "P1V25_PEX0")
	)
	(segment
		(start 51.099974 -302.549814)
		(end 51.574954 -303.024794)
		(width 0.249936)
		(layer "F.Cu")
		(net "P1V25_PEX0")
	)
	(segment
		(start 64.399922 -289.249866)
		(end 64.874902 -288.774886)
		(width 0.249936)
		(layer "F.Cu")
		(net "P1V25_PEX0")
	)
	(segment
		(start 51.099974 -302.549814)
		(end 50.624994 -303.024794)
		(width 0.249936)
		(layer "F.Cu")
		(net "P1V25_PEX0")
	)
	(segment
		(start 64.399922 -302.549814)
		(end 64.874902 -303.024794)
		(width 0.249936)
		(layer "F.Cu")
		(net "P1V25_PEX0")
	)
	(segment
		(start 66.299842 -302.549814)
		(end 66.774822 -303.024794)
		(width 0.249936)
		(layer "F.Cu")
		(net "P1V25_PEX0")
	)
	(segment
		(start 61.549788 -289.249866)
		(end 62.024768 -288.774886)
		(width 0.249936)
		(layer "F.Cu")
		(net "P1V25_PEX0")
	)
	(segment
		(start 52.999894 -289.249866)
		(end 53.474874 -288.774886)
		(width 0.249936)
		(layer "F.Cu")
		(net "P1V25_PEX0")
	)
	(segment
		(start 52.049934 -289.249866)
		(end 51.574954 -288.774886)
		(width 0.249936)
		(layer "F.Cu")
		(net "P1V25_PEX0")
	)
	(via
		(at 11.147806 -270.535654)
		(size 0.508)
		(drill 0.254)
		(layers "F.Cu" "B.Cu")
		(net "P1V25_PEX0")
	)
	(via
		(at 54.424834 -303.024794)
		(size 0.4064)
		(drill 0.2032)
		(layers "F.Cu" "B.Cu")
		(net "P1V25_PEX0")
	)
	(via
		(at 7.265924 -274.365212)
		(size 0.508)
		(drill 0.254)
		(layers "F.Cu" "B.Cu")
		(net "P1V25_PEX0")
	)
	(via
		(at 55.374794 -303.024794)
		(size 0.4064)
		(drill 0.2032)
		(layers "F.Cu" "B.Cu")
		(net "P1V25_PEX0")
	)
	(via
		(at 9.827006 -269.900654)
		(size 0.508)
		(drill 0.254)
		(layers "F.Cu" "B.Cu")
		(net "P1V25_PEX0")
	)
	(via
		(at 67.724782 -288.774886)
		(size 0.4064)
		(drill 0.2032)
		(layers "F.Cu" "B.Cu")
		(net "P1V25_PEX0")
	)
	(via
		(at 51.574954 -303.024794)
		(size 0.4064)
		(drill 0.2032)
		(layers "F.Cu" "B.Cu")
		(net "P1V25_PEX0")
	)
	(via
		(at 50.624994 -288.774886)
		(size 0.4064)
		(drill 0.2032)
		(layers "F.Cu" "B.Cu")
		(net "P1V25_PEX0")
	)
	(via
		(at 6.605524 -275.000212)
		(size 0.508)
		(drill 0.254)
		(layers "F.Cu" "B.Cu")
		(net "P1V25_PEX0")
	)
	(via
		(at 5.167884 -271.644364)
		(size 0.6604)
		(drill 0.3302)
		(layers "F.Cu" "B.Cu")
		(net "P1V25_PEX0")
	)
	(via
		(at 64.874902 -288.774886)
		(size 0.4064)
		(drill 0.2032)
		(layers "F.Cu" "B.Cu")
		(net "P1V25_PEX0")
	)
	(via
		(at 64.874902 -303.024794)
		(size 0.4064)
		(drill 0.2032)
		(layers "F.Cu" "B.Cu")
		(net "P1V25_PEX0")
	)
	(via
		(at 57.274968 -303.024794)
		(size 0.4064)
		(drill 0.2032)
		(layers "F.Cu" "B.Cu")
		(net "P1V25_PEX0")
	)
	(via
		(at 61.074808 -288.774886)
		(size 0.4064)
		(drill 0.2032)
		(layers "F.Cu" "B.Cu")
		(net "P1V25_PEX0")
	)
	(via
		(at 6.704584 -270.009366)
		(size 0.508)
		(drill 0.254)
		(layers "F.Cu" "B.Cu")
		(net "P1V25_PEX0")
	)
	(via
		(at 62.024768 -303.024794)
		(size 0.4064)
		(drill 0.2032)
		(layers "F.Cu" "B.Cu")
		(net "P1V25_PEX0")
	)
	(via
		(at 7.364984 -270.009366)
		(size 0.508)
		(drill 0.254)
		(layers "F.Cu" "B.Cu")
		(net "P1V25_PEX0")
	)
	(via
		(at 5.284724 -275.000212)
		(size 0.508)
		(drill 0.254)
		(layers "F.Cu" "B.Cu")
		(net "P1V25_PEX0")
	)
	(via
		(at 5.284724 -274.365212)
		(size 0.508)
		(drill 0.254)
		(layers "F.Cu" "B.Cu")
		(net "P1V25_PEX0")
	)
	(via
		(at 6.044184 -270.644366)
		(size 0.508)
		(drill 0.254)
		(layers "F.Cu" "B.Cu")
		(net "P1V25_PEX0")
	)
	(via
		(at 63.924942 -303.024794)
		(size 0.4064)
		(drill 0.2032)
		(layers "F.Cu" "B.Cu")
		(net "P1V25_PEX0")
	)
	(via
		(at 9.12495 -273.218402)
		(size 0.508)
		(drill 0.254)
		(layers "F.Cu" "B.Cu")
		(net "P1V25_PEX0")
	)
	(via
		(at 70.574916 -296.37482)
		(size 0.4064)
		(drill 0.2032)
		(layers "F.Cu" "B.Cu")
		(net "P1V25_PEX0")
	)
	(via
		(at 18.020538 -306.28209)
		(size 0.508)
		(drill 0.254)
		(layers "F.Cu" "B.Cu")
		(net "P1V25_PEX0")
	)
	(via
		(at 62.974982 -288.774886)
		(size 0.4064)
		(drill 0.2032)
		(layers "F.Cu" "B.Cu")
		(net "P1V25_PEX0")
	)
	(via
		(at 5.945124 -275.000212)
		(size 0.508)
		(drill 0.254)
		(layers "F.Cu" "B.Cu")
		(net "P1V25_PEX0")
	)
	(via
		(at 52.524914 -303.024794)
		(size 0.4064)
		(drill 0.2032)
		(layers "F.Cu" "B.Cu")
		(net "P1V25_PEX0")
	)
	(via
		(at 5.383784 -270.644366)
		(size 0.508)
		(drill 0.254)
		(layers "F.Cu" "B.Cu")
		(net "P1V25_PEX0")
	)
	(via
		(at 5.383784 -270.009366)
		(size 0.508)
		(drill 0.254)
		(layers "F.Cu" "B.Cu")
		(net "P1V25_PEX0")
	)
	(via
		(at 70.574916 -298.27474)
		(size 0.4064)
		(drill 0.2032)
		(layers "F.Cu" "B.Cu")
		(net "P1V25_PEX0")
	)
	(via
		(at 58.224928 -288.774886)
		(size 0.4064)
		(drill 0.2032)
		(layers "F.Cu" "B.Cu")
		(net "P1V25_PEX0")
	)
	(via
		(at 6.704584 -270.644366)
		(size 0.508)
		(drill 0.254)
		(layers "F.Cu" "B.Cu")
		(net "P1V25_PEX0")
	)
	(via
		(at 62.024768 -288.774886)
		(size 0.4064)
		(drill 0.2032)
		(layers "F.Cu" "B.Cu")
		(net "P1V25_PEX0")
	)
	(via
		(at 60.124848 -303.024794)
		(size 0.4064)
		(drill 0.2032)
		(layers "F.Cu" "B.Cu")
		(net "P1V25_PEX0")
	)
	(via
		(at 66.774822 -288.774886)
		(size 0.4064)
		(drill 0.2032)
		(layers "F.Cu" "B.Cu")
		(net "P1V25_PEX0")
	)
	(via
		(at 62.974982 -303.024794)
		(size 0.4064)
		(drill 0.2032)
		(layers "F.Cu" "B.Cu")
		(net "P1V25_PEX0")
	)
	(via
		(at 6.605524 -274.365212)
		(size 0.508)
		(drill 0.254)
		(layers "F.Cu" "B.Cu")
		(net "P1V25_PEX0")
	)
	(via
		(at 77.22489 -294.4749)
		(size 0.4064)
		(drill 0.2032)
		(layers "F.Cu" "B.Cu")
		(net "P1V25_PEX0")
	)
	(via
		(at 70.574916 -297.32478)
		(size 0.4064)
		(drill 0.2032)
		(layers "F.Cu" "B.Cu")
		(net "P1V25_PEX0")
	)
	(via
		(at 9.166606 -269.900654)
		(size 0.508)
		(drill 0.254)
		(layers "F.Cu" "B.Cu")
		(net "P1V25_PEX0")
	)
	(via
		(at 70.574916 -294.4749)
		(size 0.4064)
		(drill 0.2032)
		(layers "F.Cu" "B.Cu")
		(net "P1V25_PEX0")
	)
	(via
		(at 56.324754 -303.024794)
		(size 0.4064)
		(drill 0.2032)
		(layers "F.Cu" "B.Cu")
		(net "P1V25_PEX0")
	)
	(via
		(at 5.3848 -277.3172)
		(size 0.6604)
		(drill 0.3302)
		(layers "F.Cu" "B.Cu")
		(net "P1V25_PEX0")
	)
	(via
		(at 66.774822 -303.024794)
		(size 0.4064)
		(drill 0.2032)
		(layers "F.Cu" "B.Cu")
		(net "P1V25_PEX0")
	)
	(via
		(at 63.924942 -288.774886)
		(size 0.4064)
		(drill 0.2032)
		(layers "F.Cu" "B.Cu")
		(net "P1V25_PEX0")
	)
	(via
		(at 10.487406 -269.900654)
		(size 0.508)
		(drill 0.254)
		(layers "F.Cu" "B.Cu")
		(net "P1V25_PEX0")
	)
	(via
		(at 77.22489 -296.37482)
		(size 0.4064)
		(drill 0.2032)
		(layers "F.Cu" "B.Cu")
		(net "P1V25_PEX0")
	)
	(via
		(at 67.724782 -303.024794)
		(size 0.4064)
		(drill 0.2032)
		(layers "F.Cu" "B.Cu")
		(net "P1V25_PEX0")
	)
	(via
		(at 53.474874 -303.024794)
		(size 0.4064)
		(drill 0.2032)
		(layers "F.Cu" "B.Cu")
		(net "P1V25_PEX0")
	)
	(via
		(at 56.324754 -288.774886)
		(size 0.4064)
		(drill 0.2032)
		(layers "F.Cu" "B.Cu")
		(net "P1V25_PEX0")
	)
	(via
		(at 9.150096 -271.704562)
		(size 0.6604)
		(drill 0.3302)
		(layers "F.Cu" "B.Cu")
		(net "P1V25_PEX0")
	)
	(via
		(at 55.374794 -288.774886)
		(size 0.4064)
		(drill 0.2032)
		(layers "F.Cu" "B.Cu")
		(net "P1V25_PEX0")
	)
	(via
		(at 7.265924 -275.000212)
		(size 0.508)
		(drill 0.254)
		(layers "F.Cu" "B.Cu")
		(net "P1V25_PEX0")
	)
	(via
		(at 51.574954 -288.774886)
		(size 0.4064)
		(drill 0.2032)
		(layers "F.Cu" "B.Cu")
		(net "P1V25_PEX0")
	)
	(via
		(at 6.044184 -270.009366)
		(size 0.508)
		(drill 0.254)
		(layers "F.Cu" "B.Cu")
		(net "P1V25_PEX0")
	)
	(via
		(at 57.274968 -288.774886)
		(size 0.4064)
		(drill 0.2032)
		(layers "F.Cu" "B.Cu")
		(net "P1V25_PEX0")
	)
	(via
		(at 9.166606 -270.535654)
		(size 0.508)
		(drill 0.254)
		(layers "F.Cu" "B.Cu")
		(net "P1V25_PEX0")
	)
	(via
		(at 53.474874 -288.774886)
		(size 0.4064)
		(drill 0.2032)
		(layers "F.Cu" "B.Cu")
		(net "P1V25_PEX0")
	)
	(via
		(at 11.147806 -269.900654)
		(size 0.508)
		(drill 0.254)
		(layers "F.Cu" "B.Cu")
		(net "P1V25_PEX0")
	)
	(via
		(at 52.524914 -288.774886)
		(size 0.4064)
		(drill 0.2032)
		(layers "F.Cu" "B.Cu")
		(net "P1V25_PEX0")
	)
	(via
		(at 60.124848 -288.774886)
		(size 0.4064)
		(drill 0.2032)
		(layers "F.Cu" "B.Cu")
		(net "P1V25_PEX0")
	)
	(via
		(at 8.48995 -273.218402)
		(size 0.508)
		(drill 0.254)
		(layers "F.Cu" "B.Cu")
		(net "P1V25_PEX0")
	)
	(via
		(at 65.824862 -288.774886)
		(size 0.4064)
		(drill 0.2032)
		(layers "F.Cu" "B.Cu")
		(net "P1V25_PEX0")
	)
	(via
		(at 78.17485 -296.37482)
		(size 0.4064)
		(drill 0.2032)
		(layers "F.Cu" "B.Cu")
		(net "P1V25_PEX0")
	)
	(via
		(at 61.074808 -303.024794)
		(size 0.4064)
		(drill 0.2032)
		(layers "F.Cu" "B.Cu")
		(net "P1V25_PEX0")
	)
	(via
		(at 5.945124 -274.365212)
		(size 0.508)
		(drill 0.254)
		(layers "F.Cu" "B.Cu")
		(net "P1V25_PEX0")
	)
	(via
		(at 50.624994 -303.024794)
		(size 0.4064)
		(drill 0.2032)
		(layers "F.Cu" "B.Cu")
		(net "P1V25_PEX0")
	)
	(via
		(at 70.574916 -293.52494)
		(size 0.4064)
		(drill 0.2032)
		(layers "F.Cu" "B.Cu")
		(net "P1V25_PEX0")
	)
	(via
		(at 54.424834 -288.774886)
		(size 0.4064)
		(drill 0.2032)
		(layers "F.Cu" "B.Cu")
		(net "P1V25_PEX0")
	)
	(via
		(at 65.824862 -303.024794)
		(size 0.4064)
		(drill 0.2032)
		(layers "F.Cu" "B.Cu")
		(net "P1V25_PEX0")
	)
	(via
		(at 58.224928 -303.024794)
		(size 0.4064)
		(drill 0.2032)
		(layers "F.Cu" "B.Cu")
		(net "P1V25_PEX0")
	)
	(via
		(at 10.487406 -270.535654)
		(size 0.508)
		(drill 0.254)
		(layers "F.Cu" "B.Cu")
		(net "P1V25_PEX0")
	)
	(via
		(at 7.364984 -270.644366)
		(size 0.508)
		(drill 0.254)
		(layers "F.Cu" "B.Cu")
		(net "P1V25_PEX0")
	)
	(via
		(at 9.827006 -270.535654)
		(size 0.508)
		(drill 0.254)
		(layers "F.Cu" "B.Cu")
		(net "P1V25_PEX0")
	)
	(segment
		(start 34.821114 -295.27881)
		(end 35.382454 -295.84015)
		(width 0.254)
		(layer "In9.Cu")
		(net "P1V25_PEX0")
	)
	(segment
		(start 18.020538 -306.28209)
		(end 18.363184 -305.939444)
		(width 0.254)
		(layer "In9.Cu")
		(net "P1V25_PEX0")
	)
	(segment
		(start 58.35777 -295.84015)
		(end 59.012328 -296.494708)
		(width 0.254)
		(layer "In9.Cu")
		(net "P1V25_PEX0")
	)
	(segment
		(start 29.682694 -302.397414)
		(end 29.682694 -296.637456)
		(width 0.254)
		(layer "In9.Cu")
		(net "P1V25_PEX0")
	)
	(segment
		(start 31.04134 -295.27881)
		(end 34.821114 -295.27881)
		(width 0.254)
		(layer "In9.Cu")
		(net "P1V25_PEX0")
	)
	(segment
		(start 59.012328 -296.494708)
		(end 59.012328 -302.090074)
		(width 0.254)
		(layer "In9.Cu")
		(net "P1V25_PEX0")
	)
	(segment
		(start 29.682694 -296.637456)
		(end 31.04134 -295.27881)
		(width 0.254)
		(layer "In9.Cu")
		(net "P1V25_PEX0")
	)
	(segment
		(start 59.012328 -302.090074)
		(end 59.563254 -302.641)
		(width 0.254)
		(layer "In9.Cu")
		(net "P1V25_PEX0")
	)
	(segment
		(start 59.741054 -302.641)
		(end 60.124848 -303.024794)
		(width 0.254)
		(layer "In9.Cu")
		(net "P1V25_PEX0")
	)
	(segment
		(start 35.382454 -295.84015)
		(end 58.35777 -295.84015)
		(width 0.254)
		(layer "In9.Cu")
		(net "P1V25_PEX0")
	)
	(segment
		(start 22.260052 -305.939444)
		(end 25.32888 -302.870616)
		(width 0.254)
		(layer "In9.Cu")
		(net "P1V25_PEX0")
	)
	(segment
		(start 29.209492 -302.870616)
		(end 29.682694 -302.397414)
		(width 0.254)
		(layer "In9.Cu")
		(net "P1V25_PEX0")
	)
	(segment
		(start 59.563254 -302.641)
		(end 59.741054 -302.641)
		(width 0.254)
		(layer "In9.Cu")
		(net "P1V25_PEX0")
	)
	(segment
		(start 18.363184 -305.939444)
		(end 22.260052 -305.939444)
		(width 0.254)
		(layer "In9.Cu")
		(net "P1V25_PEX0")
	)
	(segment
		(start 25.32888 -302.870616)
		(end 29.209492 -302.870616)
		(width 0.254)
		(layer "In9.Cu")
		(net "P1V25_PEX0")
	)
	(segment
		(start 50.14976 -297.79976)
		(end 50.624994 -297.32478)
		(width 0.249936)
		(layer "F.Cu")
		(net "P0V8_PEX0")
	)
	(segment
		(start 48.72482 -301.124874)
		(end 49.1998 -300.649894)
		(width 0.249936)
		(layer "F.Cu")
		(net "P0V8_PEX0")
	)
	(segment
		(start 58.224928 -294.4749)
		(end 57.749948 -293.99992)
		(width 0.249936)
		(layer "F.Cu")
		(net "P0V8_PEX0")
	)
	(segment
		(start 56.324754 -294.4749)
		(end 55.849774 -293.99992)
		(width 0.249936)
		(layer "F.Cu")
		(net "P0V8_PEX0")
	)
	(segment
		(start 55.849774 -295.89984)
		(end 55.374794 -296.37482)
		(width 0.249936)
		(layer "F.Cu")
		(net "P0V8_PEX0")
	)
	(segment
		(start 54.899814 -294.94988)
		(end 54.424834 -294.4749)
		(width 0.249936)
		(layer "F.Cu")
		(net "P0V8_PEX0")
	)
	(segment
		(start 49.1998 -296.8498)
		(end 49.67478 -296.37482)
		(width 0.249936)
		(layer "F.Cu")
		(net "P0V8_PEX0")
	)
	(segment
		(start 50.624994 -297.32478)
		(end 51.099974 -296.8498)
		(width 0.249936)
		(layer "F.Cu")
		(net "P0V8_PEX0")
	)
	(segment
		(start 60.599828 -296.8498)
		(end 61.074808 -297.32478)
		(width 0.249936)
		(layer "F.Cu")
		(net "P0V8_PEX0")
	)
	(segment
		(start 52.049934 -297.79976)
		(end 51.574954 -298.27474)
		(width 0.249936)
		(layer "F.Cu")
		(net "P0V8_PEX0")
	)
	(segment
		(start 62.499748 -296.8498)
		(end 62.974982 -297.32478)
		(width 0.249936)
		(layer "F.Cu")
		(net "P0V8_PEX0")
	)
	(segment
		(start 62.974982 -297.32478)
		(end 63.449962 -297.79976)
		(width 0.249936)
		(layer "F.Cu")
		(net "P0V8_PEX0")
	)
	(segment
		(start 61.549788 -295.89984)
		(end 62.024768 -296.37482)
		(width 0.249936)
		(layer "F.Cu")
		(net "P0V8_PEX0")
	)
	(segment
		(start 61.549788 -297.79976)
		(end 62.024768 -298.27474)
		(width 0.249936)
		(layer "F.Cu")
		(net "P0V8_PEX0")
	)
	(segment
		(start 65.824862 -293.52494)
		(end 65.349882 -293.99992)
		(width 0.249936)
		(layer "F.Cu")
		(net "P0V8_PEX0")
	)
	(segment
		(start 50.14976 -292.099746)
		(end 49.67478 -291.624766)
		(width 0.249936)
		(layer "F.Cu")
		(net "P0V8_PEX0")
	)
	(segment
		(start 67.249802 -293.99992)
		(end 67.724782 -293.52494)
		(width 0.249936)
		(layer "F.Cu")
		(net "P0V8_PEX0")
	)
	(segment
		(start 55.849774 -297.79976)
		(end 55.374794 -298.27474)
		(width 0.249936)
		(layer "F.Cu")
		(net "P0V8_PEX0")
	)
	(segment
		(start 49.67478 -296.37482)
		(end 50.14976 -295.89984)
		(width 0.249936)
		(layer "F.Cu")
		(net "P0V8_PEX0")
	)
	(segment
		(start 63.924942 -296.37482)
		(end 64.399922 -296.8498)
		(width 0.249936)
		(layer "F.Cu")
		(net "P0V8_PEX0")
	)
	(segment
		(start 49.67478 -291.624766)
		(end 49.1998 -291.149786)
		(width 0.249936)
		(layer "F.Cu")
		(net "P0V8_PEX0")
	)
	(segment
		(start 58.699908 -294.94988)
		(end 58.224928 -294.4749)
		(width 0.249936)
		(layer "F.Cu")
		(net "P0V8_PEX0")
	)
	(segment
		(start 63.449962 -293.99992)
		(end 63.924942 -293.52494)
		(width 0.249936)
		(layer "F.Cu")
		(net "P0V8_PEX0")
	)
	(segment
		(start 52.999894 -294.94988)
		(end 52.524914 -294.4749)
		(width 0.249936)
		(layer "F.Cu")
		(net "P0V8_PEX0")
	)
	(segment
		(start 58.224928 -297.32478)
		(end 57.749948 -297.79976)
		(width 0.249936)
		(layer "F.Cu")
		(net "P0V8_PEX0")
	)
	(segment
		(start 54.424834 -294.4749)
		(end 53.949854 -293.99992)
		(width 0.249936)
		(layer "F.Cu")
		(net "P0V8_PEX0")
	)
	(segment
		(start 63.449962 -297.79976)
		(end 63.924942 -298.27474)
		(width 0.249936)
		(layer "F.Cu")
		(net "P0V8_PEX0")
	)
	(segment
		(start 62.499748 -294.94988)
		(end 62.974982 -294.4749)
		(width 0.249936)
		(layer "F.Cu")
		(net "P0V8_PEX0")
	)
	(segment
		(start 50.14976 -297.79976)
		(end 49.67478 -298.27474)
		(width 0.249936)
		(layer "F.Cu")
		(net "P0V8_PEX0")
	)
	(segment
		(start 64.399922 -294.94988)
		(end 64.874902 -294.4749)
		(width 0.249936)
		(layer "F.Cu")
		(net "P0V8_PEX0")
	)
	(segment
		(start 61.549788 -293.99992)
		(end 62.024768 -293.52494)
		(width 0.249936)
		(layer "F.Cu")
		(net "P0V8_PEX0")
	)
	(segment
		(start 49.67478 -293.52494)
		(end 49.1998 -293.04996)
		(width 0.249936)
		(layer "F.Cu")
		(net "P0V8_PEX0")
	)
	(segment
		(start 50.14976 -299.699934)
		(end 49.67478 -300.174914)
		(width 0.249936)
		(layer "F.Cu")
		(net "P0V8_PEX0")
	)
	(segment
		(start 51.099974 -296.8498)
		(end 51.574954 -296.37482)
		(width 0.249936)
		(layer "F.Cu")
		(net "P0V8_PEX0")
	)
	(segment
		(start 50.14976 -293.99992)
		(end 49.67478 -293.52494)
		(width 0.249936)
		(layer "F.Cu")
		(net "P0V8_PEX0")
	)
	(segment
		(start 50.624994 -294.4749)
		(end 51.099974 -294.94988)
		(width 0.249936)
		(layer "F.Cu")
		(net "P0V8_PEX0")
	)
	(segment
		(start 49.67478 -300.174914)
		(end 49.1998 -300.649894)
		(width 0.249936)
		(layer "F.Cu")
		(net "P0V8_PEX0")
	)
	(segment
		(start 56.799988 -296.8498)
		(end 56.324754 -297.32478)
		(width 0.249936)
		(layer "F.Cu")
		(net "P0V8_PEX0")
	)
	(segment
		(start 63.449962 -295.89984)
		(end 63.924942 -296.37482)
		(width 0.249936)
		(layer "F.Cu")
		(net "P0V8_PEX0")
	)
	(segment
		(start 60.599828 -294.94988)
		(end 61.074808 -294.4749)
		(width 0.249936)
		(layer "F.Cu")
		(net "P0V8_PEX0")
	)
	(segment
		(start 49.1998 -294.94988)
		(end 48.72482 -294.4749)
		(width 0.249936)
		(layer "F.Cu")
		(net "P0V8_PEX0")
	)
	(segment
		(start 59.649868 -295.89984)
		(end 60.124848 -296.37482)
		(width 0.249936)
		(layer "F.Cu")
		(net "P0V8_PEX0")
	)
	(segment
		(start 56.324754 -297.32478)
		(end 55.849774 -297.79976)
		(width 0.249936)
		(layer "F.Cu")
		(net "P0V8_PEX0")
	)
	(segment
		(start 51.574954 -296.37482)
		(end 52.049934 -295.89984)
		(width 0.249936)
		(layer "F.Cu")
		(net "P0V8_PEX0")
	)
	(segment
		(start 57.274968 -296.37482)
		(end 57.749948 -295.89984)
		(width 0.249936)
		(layer "F.Cu")
		(net "P0V8_PEX0")
	)
	(segment
		(start 56.799988 -296.8498)
		(end 57.274968 -296.37482)
		(width 0.249936)
		(layer "F.Cu")
		(net "P0V8_PEX0")
	)
	(segment
		(start 58.699908 -296.8498)
		(end 58.224928 -297.32478)
		(width 0.249936)
		(layer "F.Cu")
		(net "P0V8_PEX0")
	)
	(segment
		(start 64.874902 -294.4749)
		(end 65.349882 -293.99992)
		(width 0.249936)
		(layer "F.Cu")
		(net "P0V8_PEX0")
	)
	(segment
		(start 65.349882 -295.89984)
		(end 65.824862 -296.37482)
		(width 0.249936)
		(layer "F.Cu")
		(net "P0V8_PEX0")
	)
	(segment
		(start 64.399922 -296.8498)
		(end 64.874902 -297.32478)
		(width 0.249936)
		(layer "F.Cu")
		(net "P0V8_PEX0")
	)
	(segment
		(start 59.649868 -297.79976)
		(end 60.124848 -298.27474)
		(width 0.249936)
		(layer "F.Cu")
		(net "P0V8_PEX0")
	)
	(segment
		(start 62.024768 -296.37482)
		(end 62.499748 -296.8498)
		(width 0.249936)
		(layer "F.Cu")
		(net "P0V8_PEX0")
	)
	(segment
		(start 56.799988 -294.94988)
		(end 56.324754 -294.4749)
		(width 0.249936)
		(layer "F.Cu")
		(net "P0V8_PEX0")
	)
	(segment
		(start 53.949854 -295.89984)
		(end 53.474874 -296.37482)
		(width 0.249936)
		(layer "F.Cu")
		(net "P0V8_PEX0")
	)
	(segment
		(start 57.749948 -297.79976)
		(end 57.274968 -298.27474)
		(width 0.249936)
		(layer "F.Cu")
		(net "P0V8_PEX0")
	)
	(segment
		(start 64.874902 -297.32478)
		(end 65.349882 -297.79976)
		(width 0.249936)
		(layer "F.Cu")
		(net "P0V8_PEX0")
	)
	(segment
		(start 53.949854 -297.79976)
		(end 53.474874 -298.27474)
		(width 0.249936)
		(layer "F.Cu")
		(net "P0V8_PEX0")
	)
	(segment
		(start 59.649868 -293.99992)
		(end 60.124848 -293.52494)
		(width 0.249936)
		(layer "F.Cu")
		(net "P0V8_PEX0")
	)
	(segment
		(start 52.999894 -296.8498)
		(end 52.524914 -297.32478)
		(width 0.249936)
		(layer "F.Cu")
		(net "P0V8_PEX0")
	)
	(segment
		(start 65.824862 -298.27474)
		(end 65.349882 -297.79976)
		(width 0.249936)
		(layer "F.Cu")
		(net "P0V8_PEX0")
	)
	(segment
		(start 49.1998 -291.149786)
		(end 48.72482 -290.674806)
		(width 0.249936)
		(layer "F.Cu")
		(net "P0V8_PEX0")
	)
	(segment
		(start 53.949854 -293.99992)
		(end 53.474874 -293.52494)
		(width 0.249936)
		(layer "F.Cu")
		(net "P0V8_PEX0")
	)
	(segment
		(start 53.474874 -296.37482)
		(end 52.999894 -296.8498)
		(width 0.249936)
		(layer "F.Cu")
		(net "P0V8_PEX0")
	)
	(segment
		(start 61.074808 -294.4749)
		(end 61.549788 -293.99992)
		(width 0.249936)
		(layer "F.Cu")
		(net "P0V8_PEX0")
	)
	(segment
		(start 50.14976 -293.99992)
		(end 50.624994 -294.4749)
		(width 0.249936)
		(layer "F.Cu")
		(net "P0V8_PEX0")
	)
	(segment
		(start 49.1998 -293.04996)
		(end 48.72482 -292.574726)
		(width 0.249936)
		(layer "F.Cu")
		(net "P0V8_PEX0")
	)
	(segment
		(start 52.524914 -294.4749)
		(end 52.049934 -293.99992)
		(width 0.249936)
		(layer "F.Cu")
		(net "P0V8_PEX0")
	)
	(segment
		(start 49.1998 -296.8498)
		(end 48.72482 -297.32478)
		(width 0.249936)
		(layer "F.Cu")
		(net "P0V8_PEX0")
	)
	(segment
		(start 55.374794 -296.37482)
		(end 54.899814 -296.8498)
		(width 0.249936)
		(layer "F.Cu")
		(net "P0V8_PEX0")
	)
	(segment
		(start 49.67478 -298.27474)
		(end 49.1998 -298.74972)
		(width 0.249936)
		(layer "F.Cu")
		(net "P0V8_PEX0")
	)
	(segment
		(start 57.749948 -293.99992)
		(end 57.274968 -293.52494)
		(width 0.249936)
		(layer "F.Cu")
		(net "P0V8_PEX0")
	)
	(segment
		(start 62.974982 -294.4749)
		(end 63.449962 -293.99992)
		(width 0.249936)
		(layer "F.Cu")
		(net "P0V8_PEX0")
	)
	(segment
		(start 52.049934 -293.99992)
		(end 51.574954 -293.52494)
		(width 0.249936)
		(layer "F.Cu")
		(net "P0V8_PEX0")
	)
	(segment
		(start 49.1998 -298.74972)
		(end 48.72482 -299.224954)
		(width 0.249936)
		(layer "F.Cu")
		(net "P0V8_PEX0")
	)
	(segment
		(start 61.074808 -297.32478)
		(end 61.549788 -297.79976)
		(width 0.249936)
		(layer "F.Cu")
		(net "P0V8_PEX0")
	)
	(segment
		(start 53.949854 -297.79976)
		(end 54.424834 -297.32478)
		(width 0.249936)
		(layer "F.Cu")
		(net "P0V8_PEX0")
	)
	(segment
		(start 54.424834 -297.32478)
		(end 54.899814 -296.8498)
		(width 0.249936)
		(layer "F.Cu")
		(net "P0V8_PEX0")
	)
	(segment
		(start 55.849774 -293.99992)
		(end 55.374794 -293.52494)
		(width 0.249936)
		(layer "F.Cu")
		(net "P0V8_PEX0")
	)
	(segment
		(start 67.249802 -297.79976)
		(end 67.724782 -298.27474)
		(width 0.249936)
		(layer "F.Cu")
		(net "P0V8_PEX0")
	)
	(via
		(at 60.124848 -296.37482)
		(size 0.4064)
		(drill 0.2032)
		(layers "F.Cu" "B.Cu")
		(net "P0V8_PEX0")
	)
	(via
		(at 109.998002 -314.306712)
		(size 0.508)
		(drill 0.254)
		(layers "F.Cu" "B.Cu")
		(net "P0V8_PEX0")
	)
	(via
		(at 108.982002 -314.306712)
		(size 0.508)
		(drill 0.254)
		(layers "F.Cu" "B.Cu")
		(net "P0V8_PEX0")
	)
	(via
		(at 110.045246 -300.789086)
		(size 0.508)
		(drill 0.254)
		(layers "F.Cu" "B.Cu")
		(net "P0V8_PEX0")
	)
	(via
		(at 48.72482 -294.4749)
		(size 0.4064)
		(drill 0.2032)
		(layers "F.Cu" "B.Cu")
		(net "P0V8_PEX0")
	)
	(via
		(at 106.950002 -316.338712)
		(size 0.508)
		(drill 0.254)
		(layers "F.Cu" "B.Cu")
		(net "P0V8_PEX0")
	)
	(via
		(at 67.724782 -293.52494)
		(size 0.4064)
		(drill 0.2032)
		(layers "F.Cu" "B.Cu")
		(net "P0V8_PEX0")
	)
	(via
		(at 49.67478 -300.174914)
		(size 0.4064)
		(drill 0.2032)
		(layers "F.Cu" "B.Cu")
		(net "P0V8_PEX0")
	)
	(via
		(at 64.874902 -297.32478)
		(size 0.4064)
		(drill 0.2032)
		(layers "F.Cu" "B.Cu")
		(net "P0V8_PEX0")
	)
	(via
		(at 106.950002 -312.274712)
		(size 0.508)
		(drill 0.254)
		(layers "F.Cu" "B.Cu")
		(net "P0V8_PEX0")
	)
	(via
		(at 113.677446 -300.207934)
		(size 0.508)
		(drill 0.254)
		(layers "F.Cu" "B.Cu")
		(net "P0V8_PEX0")
	)
	(via
		(at 49.67478 -296.37482)
		(size 0.4064)
		(drill 0.2032)
		(layers "F.Cu" "B.Cu")
		(net "P0V8_PEX0")
	)
	(via
		(at 116.219986 -296.515536)
		(size 0.508)
		(drill 0.254)
		(layers "F.Cu" "B.Cu")
		(net "P0V8_PEX0")
	)
	(via
		(at 110.944406 -295.245536)
		(size 0.508)
		(drill 0.254)
		(layers "F.Cu" "B.Cu")
		(net "P0V8_PEX0")
	)
	(via
		(at 48.72482 -301.124874)
		(size 0.4064)
		(drill 0.2032)
		(layers "F.Cu" "B.Cu")
		(net "P0V8_PEX0")
	)
	(via
		(at 111.579406 -295.880536)
		(size 0.508)
		(drill 0.254)
		(layers "F.Cu" "B.Cu")
		(net "P0V8_PEX0")
	)
	(via
		(at 49.67478 -298.27474)
		(size 0.4064)
		(drill 0.2032)
		(layers "F.Cu" "B.Cu")
		(net "P0V8_PEX0")
	)
	(via
		(at 62.024768 -296.37482)
		(size 0.4064)
		(drill 0.2032)
		(layers "F.Cu" "B.Cu")
		(net "P0V8_PEX0")
	)
	(via
		(at 104.511094 -297.785536)
		(size 0.508)
		(drill 0.254)
		(layers "F.Cu" "B.Cu")
		(net "P0V8_PEX0")
	)
	(via
		(at 109.151674 -295.880536)
		(size 0.508)
		(drill 0.254)
		(layers "F.Cu" "B.Cu")
		(net "P0V8_PEX0")
	)
	(via
		(at 116.219986 -297.785536)
		(size 0.508)
		(drill 0.254)
		(layers "F.Cu" "B.Cu")
		(net "P0V8_PEX0")
	)
	(via
		(at 104.511094 -298.420536)
		(size 0.508)
		(drill 0.254)
		(layers "F.Cu" "B.Cu")
		(net "P0V8_PEX0")
	)
	(via
		(at 108.982002 -310.242712)
		(size 0.508)
		(drill 0.254)
		(layers "F.Cu" "B.Cu")
		(net "P0V8_PEX0")
	)
	(via
		(at 60.124848 -298.27474)
		(size 0.4064)
		(drill 0.2032)
		(layers "F.Cu" "B.Cu")
		(net "P0V8_PEX0")
	)
	(via
		(at 54.424834 -294.4749)
		(size 0.4064)
		(drill 0.2032)
		(layers "F.Cu" "B.Cu")
		(net "P0V8_PEX0")
	)
	(via
		(at 104.511094 -296.515536)
		(size 0.508)
		(drill 0.254)
		(layers "F.Cu" "B.Cu")
		(net "P0V8_PEX0")
	)
	(via
		(at 115.584986 -297.785536)
		(size 0.508)
		(drill 0.254)
		(layers "F.Cu" "B.Cu")
		(net "P0V8_PEX0")
	)
	(via
		(at 107.966002 -315.322712)
		(size 0.508)
		(drill 0.254)
		(layers "F.Cu" "B.Cu")
		(net "P0V8_PEX0")
	)
	(via
		(at 49.67478 -291.624766)
		(size 0.4064)
		(drill 0.2032)
		(layers "F.Cu" "B.Cu")
		(net "P0V8_PEX0")
	)
	(via
		(at 103.876094 -296.515536)
		(size 0.508)
		(drill 0.254)
		(layers "F.Cu" "B.Cu")
		(net "P0V8_PEX0")
	)
	(via
		(at 51.574954 -296.37482)
		(size 0.4064)
		(drill 0.2032)
		(layers "F.Cu" "B.Cu")
		(net "P0V8_PEX0")
	)
	(via
		(at 102.428802 -294.851836)
		(size 0.508)
		(drill 0.254)
		(layers "F.Cu" "B.Cu")
		(net "P0V8_PEX0")
	)
	(via
		(at 111.579406 -297.785536)
		(size 0.508)
		(drill 0.254)
		(layers "F.Cu" "B.Cu")
		(net "P0V8_PEX0")
	)
	(via
		(at 103.876094 -297.785536)
		(size 0.508)
		(drill 0.254)
		(layers "F.Cu" "B.Cu")
		(net "P0V8_PEX0")
	)
	(via
		(at 51.574954 -298.27474)
		(size 0.4064)
		(drill 0.2032)
		(layers "F.Cu" "B.Cu")
		(net "P0V8_PEX0")
	)
	(via
		(at 115.584986 -295.245536)
		(size 0.508)
		(drill 0.254)
		(layers "F.Cu" "B.Cu")
		(net "P0V8_PEX0")
	)
	(via
		(at 56.324754 -297.32478)
		(size 0.4064)
		(drill 0.2032)
		(layers "F.Cu" "B.Cu")
		(net "P0V8_PEX0")
	)
	(via
		(at 113.677446 -300.842934)
		(size 0.508)
		(drill 0.254)
		(layers "F.Cu" "B.Cu")
		(net "P0V8_PEX0")
	)
	(via
		(at 104.918002 -312.274712)
		(size 0.508)
		(drill 0.254)
		(layers "F.Cu" "B.Cu")
		(net "P0V8_PEX0")
	)
	(via
		(at 63.924942 -298.27474)
		(size 0.4064)
		(drill 0.2032)
		(layers "F.Cu" "B.Cu")
		(net "P0V8_PEX0")
	)
	(via
		(at 48.72482 -297.32478)
		(size 0.4064)
		(drill 0.2032)
		(layers "F.Cu" "B.Cu")
		(net "P0V8_PEX0")
	)
	(via
		(at 108.982002 -315.322712)
		(size 0.508)
		(drill 0.254)
		(layers "F.Cu" "B.Cu")
		(net "P0V8_PEX0")
	)
	(via
		(at 51.574954 -293.52494)
		(size 0.4064)
		(drill 0.2032)
		(layers "F.Cu" "B.Cu")
		(net "P0V8_PEX0")
	)
	(via
		(at 104.918002 -315.322712)
		(size 0.508)
		(drill 0.254)
		(layers "F.Cu" "B.Cu")
		(net "P0V8_PEX0")
	)
	(via
		(at 108.982002 -312.274712)
		(size 0.508)
		(drill 0.254)
		(layers "F.Cu" "B.Cu")
		(net "P0V8_PEX0")
	)
	(via
		(at 109.151674 -297.785536)
		(size 0.508)
		(drill 0.254)
		(layers "F.Cu" "B.Cu")
		(net "P0V8_PEX0")
	)
	(via
		(at 108.516674 -295.880536)
		(size 0.508)
		(drill 0.254)
		(layers "F.Cu" "B.Cu")
		(net "P0V8_PEX0")
	)
	(via
		(at 103.876094 -297.150536)
		(size 0.508)
		(drill 0.254)
		(layers "F.Cu" "B.Cu")
		(net "P0V8_PEX0")
	)
	(via
		(at 102.886002 -316.338712)
		(size 0.508)
		(drill 0.254)
		(layers "F.Cu" "B.Cu")
		(net "P0V8_PEX0")
	)
	(via
		(at 55.374794 -298.27474)
		(size 0.4064)
		(drill 0.2032)
		(layers "F.Cu" "B.Cu")
		(net "P0V8_PEX0")
	)
	(via
		(at 103.205026 -301.424086)
		(size 0.508)
		(drill 0.254)
		(layers "F.Cu" "B.Cu")
		(net "P0V8_PEX0")
	)
	(via
		(at 110.944406 -298.420536)
		(size 0.508)
		(drill 0.254)
		(layers "F.Cu" "B.Cu")
		(net "P0V8_PEX0")
	)
	(via
		(at 109.457236 -302.925734)
		(size 0.508)
		(drill 0.254)
		(layers "F.Cu" "B.Cu")
		(net "P0V8_PEX0")
	)
	(via
		(at 101.870002 -315.322712)
		(size 0.508)
		(drill 0.254)
		(layers "F.Cu" "B.Cu")
		(net "P0V8_PEX0")
	)
	(via
		(at 55.374794 -296.37482)
		(size 0.4064)
		(drill 0.2032)
		(layers "F.Cu" "B.Cu")
		(net "P0V8_PEX0")
	)
	(via
		(at 101.870002 -313.290712)
		(size 0.508)
		(drill 0.254)
		(layers "F.Cu" "B.Cu")
		(net "P0V8_PEX0")
	)
	(via
		(at 109.151674 -296.515536)
		(size 0.508)
		(drill 0.254)
		(layers "F.Cu" "B.Cu")
		(net "P0V8_PEX0")
	)
	(via
		(at 111.579406 -295.245536)
		(size 0.508)
		(drill 0.254)
		(layers "F.Cu" "B.Cu")
		(net "P0V8_PEX0")
	)
	(via
		(at 103.902002 -314.306712)
		(size 0.508)
		(drill 0.254)
		(layers "F.Cu" "B.Cu")
		(net "P0V8_PEX0")
	)
	(via
		(at 103.902002 -311.258712)
		(size 0.508)
		(drill 0.254)
		(layers "F.Cu" "B.Cu")
		(net "P0V8_PEX0")
	)
	(via
		(at 53.474874 -298.27474)
		(size 0.4064)
		(drill 0.2032)
		(layers "F.Cu" "B.Cu")
		(net "P0V8_PEX0")
	)
	(via
		(at 117.522498 -294.851836)
		(size 0.508)
		(drill 0.254)
		(layers "F.Cu" "B.Cu")
		(net "P0V8_PEX0")
	)
	(via
		(at 107.425236 -302.925734)
		(size 0.508)
		(drill 0.254)
		(layers "F.Cu" "B.Cu")
		(net "P0V8_PEX0")
	)
	(via
		(at 101.870002 -314.306712)
		(size 0.508)
		(drill 0.254)
		(layers "F.Cu" "B.Cu")
		(net "P0V8_PEX0")
	)
	(via
		(at 109.998002 -311.258712)
		(size 0.508)
		(drill 0.254)
		(layers "F.Cu" "B.Cu")
		(net "P0V8_PEX0")
	)
	(via
		(at 65.824862 -293.52494)
		(size 0.4064)
		(drill 0.2032)
		(layers "F.Cu" "B.Cu")
		(net "P0V8_PEX0")
	)
	(via
		(at 109.998002 -316.338712)
		(size 0.508)
		(drill 0.254)
		(layers "F.Cu" "B.Cu")
		(net "P0V8_PEX0")
	)
	(via
		(at 107.966002 -316.338712)
		(size 0.508)
		(drill 0.254)
		(layers "F.Cu" "B.Cu")
		(net "P0V8_PEX0")
	)
	(via
		(at 103.205026 -300.154086)
		(size 0.508)
		(drill 0.254)
		(layers "F.Cu" "B.Cu")
		(net "P0V8_PEX0")
	)
	(via
		(at 106.837226 -301.477934)
		(size 0.508)
		(drill 0.254)
		(layers "F.Cu" "B.Cu")
		(net "P0V8_PEX0")
	)
	(via
		(at 63.924942 -293.52494)
		(size 0.4064)
		(drill 0.2032)
		(layers "F.Cu" "B.Cu")
		(net "P0V8_PEX0")
	)
	(via
		(at 110.045246 -301.424086)
		(size 0.508)
		(drill 0.254)
		(layers "F.Cu" "B.Cu")
		(net "P0V8_PEX0")
	)
	(via
		(at 110.944406 -297.150536)
		(size 0.508)
		(drill 0.254)
		(layers "F.Cu" "B.Cu")
		(net "P0V8_PEX0")
	)
	(via
		(at 106.950002 -311.258712)
		(size 0.508)
		(drill 0.254)
		(layers "F.Cu" "B.Cu")
		(net "P0V8_PEX0")
	)
	(via
		(at 52.524914 -294.4749)
		(size 0.4064)
		(drill 0.2032)
		(layers "F.Cu" "B.Cu")
		(net "P0V8_PEX0")
	)
	(via
		(at 108.982002 -311.258712)
		(size 0.508)
		(drill 0.254)
		(layers "F.Cu" "B.Cu")
		(net "P0V8_PEX0")
	)
	(via
		(at 105.934002 -312.274712)
		(size 0.508)
		(drill 0.254)
		(layers "F.Cu" "B.Cu")
		(net "P0V8_PEX0")
	)
	(via
		(at 53.474874 -296.37482)
		(size 0.4064)
		(drill 0.2032)
		(layers "F.Cu" "B.Cu")
		(net "P0V8_PEX0")
	)
	(via
		(at 65.824862 -298.27474)
		(size 0.4064)
		(drill 0.2032)
		(layers "F.Cu" "B.Cu")
		(net "P0V8_PEX0")
	)
	(via
		(at 109.151674 -297.150536)
		(size 0.508)
		(drill 0.254)
		(layers "F.Cu" "B.Cu")
		(net "P0V8_PEX0")
	)
	(via
		(at 62.024768 -298.27474)
		(size 0.4064)
		(drill 0.2032)
		(layers "F.Cu" "B.Cu")
		(net "P0V8_PEX0")
	)
	(via
		(at 104.511094 -297.150536)
		(size 0.508)
		(drill 0.254)
		(layers "F.Cu" "B.Cu")
		(net "P0V8_PEX0")
	)
	(via
		(at 108.516674 -296.515536)
		(size 0.508)
		(drill 0.254)
		(layers "F.Cu" "B.Cu")
		(net "P0V8_PEX0")
	)
	(via
		(at 116.219986 -295.880536)
		(size 0.508)
		(drill 0.254)
		(layers "F.Cu" "B.Cu")
		(net "P0V8_PEX0")
	)
	(via
		(at 115.584986 -295.880536)
		(size 0.508)
		(drill 0.254)
		(layers "F.Cu" "B.Cu")
		(net "P0V8_PEX0")
	)
	(via
		(at 109.998002 -315.322712)
		(size 0.508)
		(drill 0.254)
		(layers "F.Cu" "B.Cu")
		(net "P0V8_PEX0")
	)
	(via
		(at 113.677446 -301.477934)
		(size 0.508)
		(drill 0.254)
		(layers "F.Cu" "B.Cu")
		(net "P0V8_PEX0")
	)
	(via
		(at 106.837226 -300.207934)
		(size 0.508)
		(drill 0.254)
		(layers "F.Cu" "B.Cu")
		(net "P0V8_PEX0")
	)
	(via
		(at 64.874902 -294.4749)
		(size 0.4064)
		(drill 0.2032)
		(layers "F.Cu" "B.Cu")
		(net "P0V8_PEX0")
	)
	(via
		(at 65.824862 -296.37482)
		(size 0.4064)
		(drill 0.2032)
		(layers "F.Cu" "B.Cu")
		(net "P0V8_PEX0")
	)
	(via
		(at 111.579406 -298.420536)
		(size 0.508)
		(drill 0.254)
		(layers "F.Cu" "B.Cu")
		(net "P0V8_PEX0")
	)
	(via
		(at 109.998002 -313.290712)
		(size 0.508)
		(drill 0.254)
		(layers "F.Cu" "B.Cu")
		(net "P0V8_PEX0")
	)
	(via
		(at 61.074808 -297.32478)
		(size 0.4064)
		(drill 0.2032)
		(layers "F.Cu" "B.Cu")
		(net "P0V8_PEX0")
	)
	(via
		(at 58.224928 -294.4749)
		(size 0.4064)
		(drill 0.2032)
		(layers "F.Cu" "B.Cu")
		(net "P0V8_PEX0")
	)
	(via
		(at 104.511094 -295.880536)
		(size 0.508)
		(drill 0.254)
		(layers "F.Cu" "B.Cu")
		(net "P0V8_PEX0")
	)
	(via
		(at 103.902002 -313.290712)
		(size 0.508)
		(drill 0.254)
		(layers "F.Cu" "B.Cu")
		(net "P0V8_PEX0")
	)
	(via
		(at 67.724782 -298.27474)
		(size 0.4064)
		(drill 0.2032)
		(layers "F.Cu" "B.Cu")
		(net "P0V8_PEX0")
	)
	(via
		(at 106.837226 -299.572934)
		(size 0.508)
		(drill 0.254)
		(layers "F.Cu" "B.Cu")
		(net "P0V8_PEX0")
	)
	(via
		(at 104.511094 -295.245536)
		(size 0.508)
		(drill 0.254)
		(layers "F.Cu" "B.Cu")
		(net "P0V8_PEX0")
	)
	(via
		(at 60.124848 -293.52494)
		(size 0.4064)
		(drill 0.2032)
		(layers "F.Cu" "B.Cu")
		(net "P0V8_PEX0")
	)
	(via
		(at 103.902002 -315.322712)
		(size 0.508)
		(drill 0.254)
		(layers "F.Cu" "B.Cu")
		(net "P0V8_PEX0")
	)
	(via
		(at 106.950002 -313.290712)
		(size 0.508)
		(drill 0.254)
		(layers "F.Cu" "B.Cu")
		(net "P0V8_PEX0")
	)
	(via
		(at 116.219986 -297.150536)
		(size 0.508)
		(drill 0.254)
		(layers "F.Cu" "B.Cu")
		(net "P0V8_PEX0")
	)
	(via
		(at 108.516674 -297.785536)
		(size 0.508)
		(drill 0.254)
		(layers "F.Cu" "B.Cu")
		(net "P0V8_PEX0")
	)
	(via
		(at 102.617016 -302.290734)
		(size 0.508)
		(drill 0.254)
		(layers "F.Cu" "B.Cu")
		(net "P0V8_PEX0")
	)
	(via
		(at 117.579902 -281.01671)
		(size 0.508)
		(drill 0.254)
		(layers "F.Cu" "B.Cu")
		(net "P0V8_PEX0")
	)
	(via
		(at 104.918002 -313.290712)
		(size 0.508)
		(drill 0.254)
		(layers "F.Cu" "B.Cu")
		(net "P0V8_PEX0")
	)
	(via
		(at 110.944406 -295.880536)
		(size 0.508)
		(drill 0.254)
		(layers "F.Cu" "B.Cu")
		(net "P0V8_PEX0")
	)
	(via
		(at 103.205026 -300.789086)
		(size 0.508)
		(drill 0.254)
		(layers "F.Cu" "B.Cu")
		(net "P0V8_PEX0")
	)
	(via
		(at 106.950002 -315.322712)
		(size 0.508)
		(drill 0.254)
		(layers "F.Cu" "B.Cu")
		(net "P0V8_PEX0")
	)
	(via
		(at 115.584986 -296.515536)
		(size 0.508)
		(drill 0.254)
		(layers "F.Cu" "B.Cu")
		(net "P0V8_PEX0")
	)
	(via
		(at 111.031528 -294.199564)
		(size 0.508)
		(drill 0.254)
		(layers "F.Cu" "B.Cu")
		(net "P0V8_PEX0")
	)
	(via
		(at 52.524914 -297.32478)
		(size 0.4064)
		(drill 0.2032)
		(layers "F.Cu" "B.Cu")
		(net "P0V8_PEX0")
	)
	(via
		(at 54.424834 -297.32478)
		(size 0.4064)
		(drill 0.2032)
		(layers "F.Cu" "B.Cu")
		(net "P0V8_PEX0")
	)
	(via
		(at 48.72482 -299.224954)
		(size 0.4064)
		(drill 0.2032)
		(layers "F.Cu" "B.Cu")
		(net "P0V8_PEX0")
	)
	(via
		(at 100.854002 -311.258712)
		(size 0.508)
		(drill 0.254)
		(layers "F.Cu" "B.Cu")
		(net "P0V8_PEX0")
	)
	(via
		(at 108.516674 -298.420536)
		(size 0.508)
		(drill 0.254)
		(layers "F.Cu" "B.Cu")
		(net "P0V8_PEX0")
	)
	(via
		(at 108.982002 -316.338712)
		(size 0.508)
		(drill 0.254)
		(layers "F.Cu" "B.Cu")
		(net "P0V8_PEX0")
	)
	(via
		(at 114.265456 -302.925734)
		(size 0.508)
		(drill 0.254)
		(layers "F.Cu" "B.Cu")
		(net "P0V8_PEX0")
	)
	(via
		(at 106.950002 -310.242712)
		(size 0.508)
		(drill 0.254)
		(layers "F.Cu" "B.Cu")
		(net "P0V8_PEX0")
	)
	(via
		(at 48.72482 -292.574726)
		(size 0.4064)
		(drill 0.2032)
		(layers "F.Cu" "B.Cu")
		(net "P0V8_PEX0")
	)
	(via
		(at 110.045246 -300.154086)
		(size 0.508)
		(drill 0.254)
		(layers "F.Cu" "B.Cu")
		(net "P0V8_PEX0")
	)
	(via
		(at 107.966002 -313.290712)
		(size 0.508)
		(drill 0.254)
		(layers "F.Cu" "B.Cu")
		(net "P0V8_PEX0")
	)
	(via
		(at 49.67478 -293.52494)
		(size 0.4064)
		(drill 0.2032)
		(layers "F.Cu" "B.Cu")
		(net "P0V8_PEX0")
	)
	(via
		(at 109.137958 -281.16657)
		(size 0.508)
		(drill 0.254)
		(layers "F.Cu" "B.Cu")
		(net "P0V8_PEX0")
	)
	(via
		(at 108.516674 -295.245536)
		(size 0.508)
		(drill 0.254)
		(layers "F.Cu" "B.Cu")
		(net "P0V8_PEX0")
	)
	(via
		(at 104.918002 -311.258712)
		(size 0.508)
		(drill 0.254)
		(layers "F.Cu" "B.Cu")
		(net "P0V8_PEX0")
	)
	(via
		(at 106.837226 -300.842934)
		(size 0.508)
		(drill 0.254)
		(layers "F.Cu" "B.Cu")
		(net "P0V8_PEX0")
	)
	(via
		(at 108.982002 -313.290712)
		(size 0.508)
		(drill 0.254)
		(layers "F.Cu" "B.Cu")
		(net "P0V8_PEX0")
	)
	(via
		(at 108.516674 -297.150536)
		(size 0.508)
		(drill 0.254)
		(layers "F.Cu" "B.Cu")
		(net "P0V8_PEX0")
	)
	(via
		(at 102.886002 -314.306712)
		(size 0.508)
		(drill 0.254)
		(layers "F.Cu" "B.Cu")
		(net "P0V8_PEX0")
	)
	(via
		(at 102.886002 -315.322712)
		(size 0.508)
		(drill 0.254)
		(layers "F.Cu" "B.Cu")
		(net "P0V8_PEX0")
	)
	(via
		(at 57.274968 -298.27474)
		(size 0.4064)
		(drill 0.2032)
		(layers "F.Cu" "B.Cu")
		(net "P0V8_PEX0")
	)
	(via
		(at 102.886002 -313.290712)
		(size 0.508)
		(drill 0.254)
		(layers "F.Cu" "B.Cu")
		(net "P0V8_PEX0")
	)
	(via
		(at 106.037126 -302.925734)
		(size 0.508)
		(drill 0.254)
		(layers "F.Cu" "B.Cu")
		(net "P0V8_PEX0")
	)
	(via
		(at 48.72482 -290.674806)
		(size 0.4064)
		(drill 0.2032)
		(layers "F.Cu" "B.Cu")
		(net "P0V8_PEX0")
	)
	(via
		(at 115.584986 -297.150536)
		(size 0.508)
		(drill 0.254)
		(layers "F.Cu" "B.Cu")
		(net "P0V8_PEX0")
	)
	(via
		(at 107.966002 -310.242712)
		(size 0.508)
		(drill 0.254)
		(layers "F.Cu" "B.Cu")
		(net "P0V8_PEX0")
	)
	(via
		(at 107.425236 -302.290734)
		(size 0.508)
		(drill 0.254)
		(layers "F.Cu" "B.Cu")
		(net "P0V8_PEX0")
	)
	(via
		(at 58.224928 -297.32478)
		(size 0.4064)
		(drill 0.2032)
		(layers "F.Cu" "B.Cu")
		(net "P0V8_PEX0")
	)
	(via
		(at 62.974982 -297.32478)
		(size 0.4064)
		(drill 0.2032)
		(layers "F.Cu" "B.Cu")
		(net "P0V8_PEX0")
	)
	(via
		(at 116.219986 -295.245536)
		(size 0.508)
		(drill 0.254)
		(layers "F.Cu" "B.Cu")
		(net "P0V8_PEX0")
	)
	(via
		(at 103.902002 -316.338712)
		(size 0.508)
		(drill 0.254)
		(layers "F.Cu" "B.Cu")
		(net "P0V8_PEX0")
	)
	(via
		(at 110.944406 -296.515536)
		(size 0.508)
		(drill 0.254)
		(layers "F.Cu" "B.Cu")
		(net "P0V8_PEX0")
	)
	(via
		(at 105.934002 -315.322712)
		(size 0.508)
		(drill 0.254)
		(layers "F.Cu" "B.Cu")
		(net "P0V8_PEX0")
	)
	(via
		(at 50.624994 -294.4749)
		(size 0.4064)
		(drill 0.2032)
		(layers "F.Cu" "B.Cu")
		(net "P0V8_PEX0")
	)
	(via
		(at 109.998002 -312.274712)
		(size 0.508)
		(drill 0.254)
		(layers "F.Cu" "B.Cu")
		(net "P0V8_PEX0")
	)
	(via
		(at 101.870002 -312.274712)
		(size 0.508)
		(drill 0.254)
		(layers "F.Cu" "B.Cu")
		(net "P0V8_PEX0")
	)
	(via
		(at 113.677446 -299.572934)
		(size 0.508)
		(drill 0.254)
		(layers "F.Cu" "B.Cu")
		(net "P0V8_PEX0")
	)
	(via
		(at 100.854002 -310.242712)
		(size 0.508)
		(drill 0.254)
		(layers "F.Cu" "B.Cu")
		(net "P0V8_PEX0")
	)
	(via
		(at 109.151674 -298.420536)
		(size 0.508)
		(drill 0.254)
		(layers "F.Cu" "B.Cu")
		(net "P0V8_PEX0")
	)
	(via
		(at 110.944406 -297.785536)
		(size 0.508)
		(drill 0.254)
		(layers "F.Cu" "B.Cu")
		(net "P0V8_PEX0")
	)
	(via
		(at 103.902002 -312.274712)
		(size 0.508)
		(drill 0.254)
		(layers "F.Cu" "B.Cu")
		(net "P0V8_PEX0")
	)
	(via
		(at 107.966002 -314.306712)
		(size 0.508)
		(drill 0.254)
		(layers "F.Cu" "B.Cu")
		(net "P0V8_PEX0")
	)
	(via
		(at 104.918002 -314.306712)
		(size 0.508)
		(drill 0.254)
		(layers "F.Cu" "B.Cu")
		(net "P0V8_PEX0")
	)
	(via
		(at 55.374794 -293.52494)
		(size 0.4064)
		(drill 0.2032)
		(layers "F.Cu" "B.Cu")
		(net "P0V8_PEX0")
	)
	(via
		(at 105.934002 -316.338712)
		(size 0.508)
		(drill 0.254)
		(layers "F.Cu" "B.Cu")
		(net "P0V8_PEX0")
	)
	(via
		(at 101.870002 -311.258712)
		(size 0.508)
		(drill 0.254)
		(layers "F.Cu" "B.Cu")
		(net "P0V8_PEX0")
	)
	(via
		(at 50.624994 -297.32478)
		(size 0.4064)
		(drill 0.2032)
		(layers "F.Cu" "B.Cu")
		(net "P0V8_PEX0")
	)
	(via
		(at 103.876094 -295.245536)
		(size 0.508)
		(drill 0.254)
		(layers "F.Cu" "B.Cu")
		(net "P0V8_PEX0")
	)
	(via
		(at 102.617016 -302.925734)
		(size 0.508)
		(drill 0.254)
		(layers "F.Cu" "B.Cu")
		(net "P0V8_PEX0")
	)
	(via
		(at 104.918002 -316.338712)
		(size 0.508)
		(drill 0.254)
		(layers "F.Cu" "B.Cu")
		(net "P0V8_PEX0")
	)
	(via
		(at 105.934002 -310.242712)
		(size 0.508)
		(drill 0.254)
		(layers "F.Cu" "B.Cu")
		(net "P0V8_PEX0")
	)
	(via
		(at 104.918002 -310.242712)
		(size 0.508)
		(drill 0.254)
		(layers "F.Cu" "B.Cu")
		(net "P0V8_PEX0")
	)
	(via
		(at 111.579406 -297.150536)
		(size 0.508)
		(drill 0.254)
		(layers "F.Cu" "B.Cu")
		(net "P0V8_PEX0")
	)
	(via
		(at 103.205026 -299.519086)
		(size 0.508)
		(drill 0.254)
		(layers "F.Cu" "B.Cu")
		(net "P0V8_PEX0")
	)
	(via
		(at 105.934002 -311.258712)
		(size 0.508)
		(drill 0.254)
		(layers "F.Cu" "B.Cu")
		(net "P0V8_PEX0")
	)
	(via
		(at 62.974982 -294.4749)
		(size 0.4064)
		(drill 0.2032)
		(layers "F.Cu" "B.Cu")
		(net "P0V8_PEX0")
	)
	(via
		(at 102.886002 -310.242712)
		(size 0.508)
		(drill 0.254)
		(layers "F.Cu" "B.Cu")
		(net "P0V8_PEX0")
	)
	(via
		(at 101.870002 -310.242712)
		(size 0.508)
		(drill 0.254)
		(layers "F.Cu" "B.Cu")
		(net "P0V8_PEX0")
	)
	(via
		(at 57.274968 -296.37482)
		(size 0.4064)
		(drill 0.2032)
		(layers "F.Cu" "B.Cu")
		(net "P0V8_PEX0")
	)
	(via
		(at 53.474874 -293.52494)
		(size 0.4064)
		(drill 0.2032)
		(layers "F.Cu" "B.Cu")
		(net "P0V8_PEX0")
	)
	(via
		(at 102.886002 -312.274712)
		(size 0.508)
		(drill 0.254)
		(layers "F.Cu" "B.Cu")
		(net "P0V8_PEX0")
	)
	(via
		(at 107.966002 -312.274712)
		(size 0.508)
		(drill 0.254)
		(layers "F.Cu" "B.Cu")
		(net "P0V8_PEX0")
	)
	(via
		(at 103.876094 -295.880536)
		(size 0.508)
		(drill 0.254)
		(layers "F.Cu" "B.Cu")
		(net "P0V8_PEX0")
	)
	(via
		(at 103.902002 -310.242712)
		(size 0.508)
		(drill 0.254)
		(layers "F.Cu" "B.Cu")
		(net "P0V8_PEX0")
	)
	(via
		(at 63.924942 -296.37482)
		(size 0.4064)
		(drill 0.2032)
		(layers "F.Cu" "B.Cu")
		(net "P0V8_PEX0")
	)
	(via
		(at 103.876094 -298.420536)
		(size 0.508)
		(drill 0.254)
		(layers "F.Cu" "B.Cu")
		(net "P0V8_PEX0")
	)
	(via
		(at 106.950002 -314.306712)
		(size 0.508)
		(drill 0.254)
		(layers "F.Cu" "B.Cu")
		(net "P0V8_PEX0")
	)
	(via
		(at 116.219986 -298.420536)
		(size 0.508)
		(drill 0.254)
		(layers "F.Cu" "B.Cu")
		(net "P0V8_PEX0")
	)
	(via
		(at 110.045246 -299.519086)
		(size 0.508)
		(drill 0.254)
		(layers "F.Cu" "B.Cu")
		(net "P0V8_PEX0")
	)
	(via
		(at 100.854002 -312.274712)
		(size 0.508)
		(drill 0.254)
		(layers "F.Cu" "B.Cu")
		(net "P0V8_PEX0")
	)
	(via
		(at 56.324754 -294.4749)
		(size 0.4064)
		(drill 0.2032)
		(layers "F.Cu" "B.Cu")
		(net "P0V8_PEX0")
	)
	(via
		(at 62.024768 -293.52494)
		(size 0.4064)
		(drill 0.2032)
		(layers "F.Cu" "B.Cu")
		(net "P0V8_PEX0")
	)
	(via
		(at 105.934002 -314.306712)
		(size 0.508)
		(drill 0.254)
		(layers "F.Cu" "B.Cu")
		(net "P0V8_PEX0")
	)
	(via
		(at 61.074808 -294.4749)
		(size 0.4064)
		(drill 0.2032)
		(layers "F.Cu" "B.Cu")
		(net "P0V8_PEX0")
	)
	(via
		(at 109.151674 -295.245536)
		(size 0.508)
		(drill 0.254)
		(layers "F.Cu" "B.Cu")
		(net "P0V8_PEX0")
	)
	(via
		(at 102.886002 -311.258712)
		(size 0.508)
		(drill 0.254)
		(layers "F.Cu" "B.Cu")
		(net "P0V8_PEX0")
	)
	(via
		(at 106.037126 -302.290734)
		(size 0.508)
		(drill 0.254)
		(layers "F.Cu" "B.Cu")
		(net "P0V8_PEX0")
	)
	(via
		(at 109.998002 -310.242712)
		(size 0.508)
		(drill 0.254)
		(layers "F.Cu" "B.Cu")
		(net "P0V8_PEX0")
	)
	(via
		(at 111.579406 -296.515536)
		(size 0.508)
		(drill 0.254)
		(layers "F.Cu" "B.Cu")
		(net "P0V8_PEX0")
	)
	(via
		(at 109.457236 -302.290734)
		(size 0.508)
		(drill 0.254)
		(layers "F.Cu" "B.Cu")
		(net "P0V8_PEX0")
	)
	(via
		(at 114.265456 -302.290734)
		(size 0.508)
		(drill 0.254)
		(layers "F.Cu" "B.Cu")
		(net "P0V8_PEX0")
	)
	(via
		(at 115.584986 -298.420536)
		(size 0.508)
		(drill 0.254)
		(layers "F.Cu" "B.Cu")
		(net "P0V8_PEX0")
	)
	(via
		(at 107.966002 -311.258712)
		(size 0.508)
		(drill 0.254)
		(layers "F.Cu" "B.Cu")
		(net "P0V8_PEX0")
	)
	(via
		(at 105.934002 -313.290712)
		(size 0.508)
		(drill 0.254)
		(layers "F.Cu" "B.Cu")
		(net "P0V8_PEX0")
	)
	(via
		(at 57.274968 -293.52494)
		(size 0.4064)
		(drill 0.2032)
		(layers "F.Cu" "B.Cu")
		(net "P0V8_PEX0")
	)
	(via
		(at 100.854002 -313.290712)
		(size 0.508)
		(drill 0.254)
		(layers "F.Cu" "B.Cu")
		(net "P0V8_PEX0")
	)
	(segment
		(start 67.933062 -298.27474)
		(end 67.724782 -298.27474)
		(width 0.3048)
		(layer "B.Cu")
		(net "P0V8_PEX0")
	)
	(segment
		(start 49.4665 -300.174914)
		(end 49.67478 -300.174914)
		(width 0.3048)
		(layer "B.Cu")
		(net "P0V8_PEX0")
	)
	(segment
		(start 117.847364 -281.284172)
		(end 117.579902 -281.01671)
		(width 0.254)
		(layer "B.Cu")
		(net "P0V8_PEX0")
	)
	(segment
		(start 109.63148 -281.660092)
		(end 109.137958 -281.16657)
		(width 0.254)
		(layer "B.Cu")
		(net "P0V8_PEX0")
	)
	(segment
		(start 117.847364 -281.64028)
		(end 117.847364 -281.284172)
		(width 0.254)
		(layer "B.Cu")
		(net "P0V8_PEX0")
	)
	(segment
		(start 67.933062 -293.52494)
		(end 67.724782 -293.52494)
		(width 0.3048)
		(layer "B.Cu")
		(net "P0V8_PEX0")
	)
	(segment
		(start 109.137958 -281.16657)
		(end 109.41939 -281.448002)
		(width 0.254)
		(layer "In5.Cu")
		(net "P0V8_PEX0")
	)
	(segment
		(start 116.219986 -295.245536)
		(end 116.677186 -294.788336)
		(width 0.254)
		(layer "In5.Cu")
		(net "P0V8_PEX0")
	)
	(segment
		(start 117.579902 -282.431236)
		(end 117.579902 -281.01671)
		(width 0.254)
		(layer "In5.Cu")
		(net "P0V8_PEX0")
	)
	(segment
		(start 109.821218 -287.602168)
		(end 109.821218 -291.386514)
		(width 0.254)
		(layer "In5.Cu")
		(net "P0V8_PEX0")
	)
	(segment
		(start 108.891832 -284.841442)
		(end 110.54842 -286.49803)
		(width 0.254)
		(layer "In5.Cu")
		(net "P0V8_PEX0")
	)
	(segment
		(start 109.41939 -282.414218)
		(end 108.891832 -282.941776)
		(width 0.254)
		(layer "In5.Cu")
		(net "P0V8_PEX0")
	)
	(segment
		(start 109.821218 -291.386514)
		(end 108.516674 -292.691058)
		(width 0.254)
		(layer "In5.Cu")
		(net "P0V8_PEX0")
	)
	(segment
		(start 116.677186 -294.788336)
		(end 116.677186 -286.328104)
		(width 0.254)
		(layer "In5.Cu")
		(net "P0V8_PEX0")
	)
	(segment
		(start 108.516674 -292.691058)
		(end 108.516674 -295.245536)
		(width 0.254)
		(layer "In5.Cu")
		(net "P0V8_PEX0")
	)
	(segment
		(start 118.421404 -283.272738)
		(end 117.579902 -282.431236)
		(width 0.254)
		(layer "In5.Cu")
		(net "P0V8_PEX0")
	)
	(segment
		(start 110.54842 -286.874966)
		(end 109.821218 -287.602168)
		(width 0.254)
		(layer "In5.Cu")
		(net "P0V8_PEX0")
	)
	(segment
		(start 108.891832 -282.941776)
		(end 108.891832 -284.841442)
		(width 0.254)
		(layer "In5.Cu")
		(net "P0V8_PEX0")
	)
	(segment
		(start 109.41939 -281.448002)
		(end 109.41939 -282.414218)
		(width 0.254)
		(layer "In5.Cu")
		(net "P0V8_PEX0")
	)
	(segment
		(start 110.54842 -286.49803)
		(end 110.54842 -286.874966)
		(width 0.254)
		(layer "In5.Cu")
		(net "P0V8_PEX0")
	)
	(segment
		(start 118.421404 -284.583886)
		(end 118.421404 -283.272738)
		(width 0.254)
		(layer "In5.Cu")
		(net "P0V8_PEX0")
	)
	(segment
		(start 116.677186 -286.328104)
		(end 118.421404 -284.583886)
		(width 0.254)
		(layer "In5.Cu")
		(net "P0V8_PEX0")
	)
	(segment
		(start 392.9253 -344.219022)
		(end 393.245848 -344.53957)
		(width 0.13462)
		(layer "F.Cu")
		(net "P5E_PEX3_STN5_TX_C_DP<82>")
	)
	(segment
		(start 393.245848 -345.169998)
		(end 392.9507 -345.465146)
		(width 0.13462)
		(layer "F.Cu")
		(net "P5E_PEX3_STN5_TX_C_DP<82>")
	)
	(segment
		(start 393.245848 -344.53957)
		(end 393.245848 -345.169998)
		(width 0.13462)
		(layer "F.Cu")
		(net "P5E_PEX3_STN5_TX_C_DP<82>")
	)
	(segment
		(start 394.714222 -364.213394)
		(end 396.80388 -368.00282)
		(width 0.1651)
		(layer "In7.Cu")
		(net "P5E_PEX3_STN5_TX_C_DP<82>")
	)
	(segment
		(start 394.388848 -363.62386)
		(end 394.35405 -363.74451)
		(width 0.1651)
		(layer "In7.Cu")
		(net "P5E_PEX3_STN5_TX_C_DP<82>")
	)
	(segment
		(start 391.68705 -347.764354)
		(end 391.68705 -358.7242)
		(width 0.1651)
		(layer "In7.Cu")
		(net "P5E_PEX3_STN5_TX_C_DP<82>")
	)
	(segment
		(start 393.260072 -361.577128)
		(end 393.225274 -361.698032)
		(width 0.1651)
		(layer "In7.Cu")
		(net "P5E_PEX3_STN5_TX_C_DP<82>")
	)
	(segment
		(start 393.24153 -345.755976)
		(end 393.24153 -346.209874)
		(width 0.1651)
		(layer "In7.Cu")
		(net "P5E_PEX3_STN5_TX_C_DP<82>")
	)
	(segment
		(start 391.68705 -358.7242)
		(end 393.260072 -361.577128)
		(width 0.1651)
		(layer "In7.Cu")
		(net "P5E_PEX3_STN5_TX_C_DP<82>")
	)
	(segment
		(start 394.35405 -363.74451)
		(end 394.593572 -364.178596)
		(width 0.1651)
		(layer "In7.Cu")
		(net "P5E_PEX3_STN5_TX_C_DP<82>")
	)
	(segment
		(start 397.31188 -369.89004)
		(end 397.070072 -386.243322)
		(width 0.1651)
		(layer "In7.Cu")
		(net "P5E_PEX3_STN5_TX_C_DP<82>")
	)
	(segment
		(start 393.82446 -362.600494)
		(end 393.789662 -362.721398)
		(width 0.1651)
		(layer "In7.Cu")
		(net "P5E_PEX3_STN5_TX_C_DP<82>")
	)
	(segment
		(start 379.89002 -404.672038)
		(end 379.89002 -404.290022)
		(width 0.1651)
		(layer "In7.Cu")
		(net "P5E_PEX3_STN5_TX_C_DP<82>")
	)
	(segment
		(start 384.353308 -392.137646)
		(end 381.26924 -395.19352)
		(width 0.1651)
		(layer "In7.Cu")
		(net "P5E_PEX3_STN5_TX_C_DP<82>")
	)
	(segment
		(start 394.593572 -364.178596)
		(end 394.714222 -364.213394)
		(width 0.1651)
		(layer "In7.Cu")
		(net "P5E_PEX3_STN5_TX_C_DP<82>")
	)
	(segment
		(start 380.734062 -404.512272)
		(end 380.447296 -404.799038)
		(width 0.1651)
		(layer "In7.Cu")
		(net "P5E_PEX3_STN5_TX_C_DP<82>")
	)
	(segment
		(start 396.577312 -387.169406)
		(end 384.353308 -392.137646)
		(width 0.1651)
		(layer "In7.Cu")
		(net "P5E_PEX3_STN5_TX_C_DP<82>")
	)
	(segment
		(start 393.585446 -362.166916)
		(end 393.82446 -362.600494)
		(width 0.1651)
		(layer "In7.Cu")
		(net "P5E_PEX3_STN5_TX_C_DP<82>")
	)
	(segment
		(start 396.80388 -368.00282)
		(end 397.31188 -369.89004)
		(width 0.1651)
		(layer "In7.Cu")
		(net "P5E_PEX3_STN5_TX_C_DP<82>")
	)
	(segment
		(start 392.9507 -345.465146)
		(end 393.24153 -345.755976)
		(width 0.1651)
		(layer "In7.Cu")
		(net "P5E_PEX3_STN5_TX_C_DP<82>")
	)
	(segment
		(start 394.149834 -363.190282)
		(end 394.388848 -363.62386)
		(width 0.1651)
		(layer "In7.Cu")
		(net "P5E_PEX3_STN5_TX_C_DP<82>")
	)
	(segment
		(start 380.734062 -396.38986)
		(end 380.734062 -404.512272)
		(width 0.1651)
		(layer "In7.Cu")
		(net "P5E_PEX3_STN5_TX_C_DP<82>")
	)
	(segment
		(start 394.02893 -363.15523)
		(end 394.149834 -363.190282)
		(width 0.1651)
		(layer "In7.Cu")
		(net "P5E_PEX3_STN5_TX_C_DP<82>")
	)
	(segment
		(start 380.447296 -404.799038)
		(end 380.01702 -404.799038)
		(width 0.1651)
		(layer "In7.Cu")
		(net "P5E_PEX3_STN5_TX_C_DP<82>")
	)
	(segment
		(start 381.26924 -395.19352)
		(end 380.734062 -396.38986)
		(width 0.1651)
		(layer "In7.Cu")
		(net "P5E_PEX3_STN5_TX_C_DP<82>")
	)
	(segment
		(start 393.789662 -362.721398)
		(end 394.02893 -363.15523)
		(width 0.1651)
		(layer "In7.Cu")
		(net "P5E_PEX3_STN5_TX_C_DP<82>")
	)
	(segment
		(start 380.01702 -404.799038)
		(end 379.89002 -404.672038)
		(width 0.1651)
		(layer "In7.Cu")
		(net "P5E_PEX3_STN5_TX_C_DP<82>")
	)
	(segment
		(start 393.24153 -346.209874)
		(end 391.68705 -347.764354)
		(width 0.1651)
		(layer "In7.Cu")
		(net "P5E_PEX3_STN5_TX_C_DP<82>")
	)
	(segment
		(start 393.225274 -361.698032)
		(end 393.464542 -362.131864)
		(width 0.1651)
		(layer "In7.Cu")
		(net "P5E_PEX3_STN5_TX_C_DP<82>")
	)
	(segment
		(start 393.464542 -362.131864)
		(end 393.585446 -362.166916)
		(width 0.1651)
		(layer "In7.Cu")
		(net "P5E_PEX3_STN5_TX_C_DP<82>")
	)
	(segment
		(start 397.070072 -386.243322)
		(end 396.577312 -387.169406)
		(width 0.1651)
		(layer "In7.Cu")
		(net "P5E_PEX3_STN5_TX_C_DP<82>")
	)
	(segment
		(start 393.8397 -344.219022)
		(end 393.520168 -344.538554)
		(width 0.13462)
		(layer "F.Cu")
		(net "P5E_PEX3_STN5_TX_C_DN<82>")
	)
	(segment
		(start 393.520168 -345.171014)
		(end 393.8143 -345.465146)
		(width 0.13462)
		(layer "F.Cu")
		(net "P5E_PEX3_STN5_TX_C_DN<82>")
	)
	(segment
		(start 393.520168 -344.538554)
		(end 393.520168 -345.171014)
		(width 0.13462)
		(layer "F.Cu")
		(net "P5E_PEX3_STN5_TX_C_DN<82>")
	)
	(segment
		(start 397.594582 -369.854734)
		(end 397.067532 -367.896394)
		(width 0.1651)
		(layer "In7.Cu")
		(net "P5E_PEX3_STN5_TX_C_DN<82>")
	)
	(segment
		(start 381.505206 -395.356842)
		(end 384.511804 -392.377676)
		(width 0.1651)
		(layer "In7.Cu")
		(net "P5E_PEX3_STN5_TX_C_DN<82>")
	)
	(segment
		(start 380.01702 -405.080978)
		(end 380.564136 -405.080978)
		(width 0.1651)
		(layer "In7.Cu")
		(net "P5E_PEX3_STN5_TX_C_DN<82>")
	)
	(segment
		(start 379.89002 -405.207978)
		(end 380.01702 -405.080978)
		(width 0.1651)
		(layer "In7.Cu")
		(net "P5E_PEX3_STN5_TX_C_DN<82>")
	)
	(segment
		(start 391.96899 -358.651556)
		(end 391.96899 -347.881194)
		(width 0.1651)
		(layer "In7.Cu")
		(net "P5E_PEX3_STN5_TX_C_DN<82>")
	)
	(segment
		(start 393.52347 -345.755976)
		(end 393.8143 -345.465146)
		(width 0.1651)
		(layer "In7.Cu")
		(net "P5E_PEX3_STN5_TX_C_DN<82>")
	)
	(segment
		(start 397.067532 -367.896394)
		(end 391.96899 -358.651556)
		(width 0.1651)
		(layer "In7.Cu")
		(net "P5E_PEX3_STN5_TX_C_DN<82>")
	)
	(segment
		(start 391.96899 -347.881194)
		(end 393.52347 -346.326714)
		(width 0.1651)
		(layer "In7.Cu")
		(net "P5E_PEX3_STN5_TX_C_DN<82>")
	)
	(segment
		(start 381.016002 -396.450058)
		(end 381.505206 -395.356842)
		(width 0.1651)
		(layer "In7.Cu")
		(net "P5E_PEX3_STN5_TX_C_DN<82>")
	)
	(segment
		(start 384.511804 -392.377676)
		(end 396.778226 -387.392164)
		(width 0.1651)
		(layer "In7.Cu")
		(net "P5E_PEX3_STN5_TX_C_DN<82>")
	)
	(segment
		(start 381.016002 -404.629112)
		(end 381.016002 -396.450058)
		(width 0.1651)
		(layer "In7.Cu")
		(net "P5E_PEX3_STN5_TX_C_DN<82>")
	)
	(segment
		(start 380.564136 -405.080978)
		(end 381.016002 -404.629112)
		(width 0.1651)
		(layer "In7.Cu")
		(net "P5E_PEX3_STN5_TX_C_DN<82>")
	)
	(segment
		(start 396.778226 -387.392164)
		(end 397.350996 -386.315712)
		(width 0.1651)
		(layer "In7.Cu")
		(net "P5E_PEX3_STN5_TX_C_DN<82>")
	)
	(segment
		(start 379.89002 -405.589994)
		(end 379.89002 -405.207978)
		(width 0.1651)
		(layer "In7.Cu")
		(net "P5E_PEX3_STN5_TX_C_DN<82>")
	)
	(segment
		(start 397.350996 -386.315712)
		(end 397.594582 -369.854734)
		(width 0.1651)
		(layer "In7.Cu")
		(net "P5E_PEX3_STN5_TX_C_DN<82>")
	)
	(segment
		(start 393.52347 -346.326714)
		(end 393.52347 -345.755976)
		(width 0.1651)
		(layer "In7.Cu")
		(net "P5E_PEX3_STN5_TX_C_DN<82>")
	)
	(segment
		(start 190.00851 -142.917926)
		(end 195.524882 -142.917926)
		(width 0.13462)
		(layer "F.Cu")
		(net "P5E_PEX1_STN0_TX_C_DN<8>")
	)
	(segment
		(start 189.357508 -142.755112)
		(end 189.845696 -142.755112)
		(width 0.13462)
		(layer "F.Cu")
		(net "P5E_PEX1_STN0_TX_C_DN<8>")
	)
	(segment
		(start 195.524882 -142.917926)
		(end 195.852542 -142.590266)
		(width 0.13462)
		(layer "F.Cu")
		(net "P5E_PEX1_STN0_TX_C_DN<8>")
	)
	(segment
		(start 189.845696 -142.755112)
		(end 190.00851 -142.917926)
		(width 0.13462)
		(layer "F.Cu")
		(net "P5E_PEX1_STN0_TX_C_DN<8>")
	)
	(segment
		(start 181.598062 -121.072148)
		(end 181.302914 -121.367296)
		(width 0.13462)
		(layer "F.Cu")
		(net "P5E_PEX1_STN0_RX_DP<1>")
	)
	(segment
		(start 184.757314 -121.234962)
		(end 184.26938 -121.234962)
		(width 0.13462)
		(layer "F.Cu")
		(net "P5E_PEX1_STN0_RX_DP<1>")
	)
	(segment
		(start 184.26938 -121.234962)
		(end 184.106566 -121.072148)
		(width 0.13462)
		(layer "F.Cu")
		(net "P5E_PEX1_STN0_RX_DP<1>")
	)
	(segment
		(start 184.106566 -121.072148)
		(end 181.598062 -121.072148)
		(width 0.13462)
		(layer "F.Cu")
		(net "P5E_PEX1_STN0_RX_DP<1>")
	)
	(segment
		(start 186.368182 -122.20448)
		(end 186.42965 -122.354086)
		(width 0.1651)
		(layer "In5.Cu")
		(net "P5E_PEX1_STN0_RX_DP<1>")
	)
	(segment
		(start 192.983358 -127.694182)
		(end 192.974214 -127.819658)
		(width 0.1651)
		(layer "In5.Cu")
		(net "P5E_PEX1_STN0_RX_DP<1>")
	)
	(segment
		(start 192.974214 -127.819658)
		(end 193.29781 -128.19507)
		(width 0.1651)
		(layer "In5.Cu")
		(net "P5E_PEX1_STN0_RX_DP<1>")
	)
	(segment
		(start 191.447674 -126.049786)
		(end 191.771524 -126.425198)
		(width 0.1651)
		(layer "In5.Cu")
		(net "P5E_PEX1_STN0_RX_DP<1>")
	)
	(segment
		(start 204.948536 -168.536366)
		(end 204.285342 -232.123996)
		(width 0.1651)
		(layer "In5.Cu")
		(net "P5E_PEX1_STN0_RX_DP<1>")
	)
	(segment
		(start 201.31278 -134.61873)
		(end 201.771758 -135.332724)
		(width 0.1651)
		(layer "In5.Cu")
		(net "P5E_PEX1_STN0_RX_DP<1>")
	)
	(segment
		(start 192.210944 -126.934722)
		(end 192.53454 -127.310134)
		(width 0.1651)
		(layer "In5.Cu")
		(net "P5E_PEX1_STN0_RX_DP<1>")
	)
	(segment
		(start 186.42965 -122.354086)
		(end 186.887104 -122.544586)
		(width 0.1651)
		(layer "In5.Cu")
		(net "P5E_PEX1_STN0_RX_DP<1>")
	)
	(segment
		(start 184.116726 -121.266966)
		(end 184.116726 -121.266712)
		(width 0.1651)
		(layer "In5.Cu")
		(net "P5E_PEX1_STN0_RX_DP<1>")
	)
	(segment
		(start 181.593744 -121.076466)
		(end 183.659526 -121.076466)
		(width 0.1651)
		(layer "In5.Cu")
		(net "P5E_PEX1_STN0_RX_DP<1>")
	)
	(segment
		(start 192.220088 -126.809246)
		(end 192.210944 -126.934722)
		(width 0.1651)
		(layer "In5.Cu")
		(net "P5E_PEX1_STN0_RX_DP<1>")
	)
	(segment
		(start 192.53454 -127.310134)
		(end 192.660016 -127.319278)
		(width 0.1651)
		(layer "In5.Cu")
		(net "P5E_PEX1_STN0_RX_DP<1>")
	)
	(segment
		(start 200.021698 -286.733996)
		(end 199.975978 -286.779716)
		(width 0.1143)
		(layer "In5.Cu")
		(net "P5E_PEX1_STN0_RX_DP<1>")
	)
	(segment
		(start 187.49391 -122.67311)
		(end 187.555378 -122.822716)
		(width 0.1651)
		(layer "In5.Cu")
		(net "P5E_PEX1_STN0_RX_DP<1>")
	)
	(segment
		(start 203.400914 -285.886398)
		(end 202.020424 -286.733996)
		(width 0.1651)
		(layer "In5.Cu")
		(net "P5E_PEX1_STN0_RX_DP<1>")
	)
	(segment
		(start 187.555378 -122.822716)
		(end 188.012832 -123.013216)
		(width 0.1651)
		(layer "In5.Cu")
		(net "P5E_PEX1_STN0_RX_DP<1>")
	)
	(segment
		(start 191.896746 -126.434342)
		(end 192.220088 -126.809246)
		(width 0.1651)
		(layer "In5.Cu")
		(net "P5E_PEX1_STN0_RX_DP<1>")
	)
	(segment
		(start 190.993268 -125.386846)
		(end 191.456818 -125.924564)
		(width 0.1651)
		(layer "In5.Cu")
		(net "P5E_PEX1_STN0_RX_DP<1>")
	)
	(segment
		(start 197.979792 -287.235646)
		(end 197.865492 -287.349946)
		(width 0.1143)
		(layer "In5.Cu")
		(net "P5E_PEX1_STN0_RX_DP<1>")
	)
	(segment
		(start 184.785254 -121.54535)
		(end 185.242454 -121.735596)
		(width 0.1651)
		(layer "In5.Cu")
		(net "P5E_PEX1_STN0_RX_DP<1>")
	)
	(segment
		(start 214.367364 -273.294602)
		(end 211.952332 -277.634192)
		(width 0.1651)
		(layer "In5.Cu")
		(net "P5E_PEX1_STN0_RX_DP<1>")
	)
	(segment
		(start 200.050146 -286.733996)
		(end 200.021698 -286.733996)
		(width 0.1143)
		(layer "In5.Cu")
		(net "P5E_PEX1_STN0_RX_DP<1>")
	)
	(segment
		(start 214.515192 -269.313406)
		(end 214.367364 -273.294602)
		(width 0.1651)
		(layer "In5.Cu")
		(net "P5E_PEX1_STN0_RX_DP<1>")
	)
	(segment
		(start 188.162438 -122.951494)
		(end 188.797438 -123.215908)
		(width 0.1651)
		(layer "In5.Cu")
		(net "P5E_PEX1_STN0_RX_DP<1>")
	)
	(segment
		(start 199.072246 -133.37159)
		(end 201.31278 -134.61873)
		(width 0.1651)
		(layer "In5.Cu")
		(net "P5E_PEX1_STN0_RX_DP<1>")
	)
	(segment
		(start 188.012832 -123.013216)
		(end 188.162438 -122.951494)
		(width 0.1651)
		(layer "In5.Cu")
		(net "P5E_PEX1_STN0_RX_DP<1>")
	)
	(segment
		(start 197.865492 -287.349946)
		(end 197.600062 -287.349946)
		(width 0.1143)
		(layer "In5.Cu")
		(net "P5E_PEX1_STN0_RX_DP<1>")
	)
	(segment
		(start 185.910982 -122.014234)
		(end 186.368182 -122.20448)
		(width 0.1651)
		(layer "In5.Cu")
		(net "P5E_PEX1_STN0_RX_DP<1>")
	)
	(segment
		(start 201.771758 -135.332724)
		(end 204.183996 -146.3929)
		(width 0.1651)
		(layer "In5.Cu")
		(net "P5E_PEX1_STN0_RX_DP<1>")
	)
	(segment
		(start 184.178194 -121.416572)
		(end 184.635648 -121.606818)
		(width 0.1651)
		(layer "In5.Cu")
		(net "P5E_PEX1_STN0_RX_DP<1>")
	)
	(segment
		(start 211.952332 -277.634192)
		(end 203.400914 -285.886398)
		(width 0.1651)
		(layer "In5.Cu")
		(net "P5E_PEX1_STN0_RX_DP<1>")
	)
	(segment
		(start 192.660016 -127.319278)
		(end 192.983358 -127.694182)
		(width 0.1651)
		(layer "In5.Cu")
		(net "P5E_PEX1_STN0_RX_DP<1>")
	)
	(segment
		(start 181.302914 -121.367296)
		(end 181.593744 -121.076466)
		(width 0.1651)
		(layer "In5.Cu")
		(net "P5E_PEX1_STN0_RX_DP<1>")
	)
	(segment
		(start 204.440536 -149.910546)
		(end 204.948536 -168.536366)
		(width 0.1651)
		(layer "In5.Cu")
		(net "P5E_PEX1_STN0_RX_DP<1>")
	)
	(segment
		(start 184.116726 -121.266712)
		(end 184.178194 -121.416572)
		(width 0.1651)
		(layer "In5.Cu")
		(net "P5E_PEX1_STN0_RX_DP<1>")
	)
	(segment
		(start 198.64324 -132.942584)
		(end 199.072246 -133.37159)
		(width 0.1651)
		(layer "In5.Cu")
		(net "P5E_PEX1_STN0_RX_DP<1>")
	)
	(segment
		(start 187.03671 -122.482864)
		(end 187.49391 -122.67311)
		(width 0.1651)
		(layer "In5.Cu")
		(net "P5E_PEX1_STN0_RX_DP<1>")
	)
	(segment
		(start 199.975978 -286.779716)
		(end 198.19493 -286.779716)
		(width 0.1143)
		(layer "In5.Cu")
		(net "P5E_PEX1_STN0_RX_DP<1>")
	)
	(segment
		(start 193.423286 -128.204214)
		(end 196.482462 -131.751578)
		(width 0.1651)
		(layer "In5.Cu")
		(net "P5E_PEX1_STN0_RX_DP<1>")
	)
	(segment
		(start 183.659526 -121.076466)
		(end 184.116726 -121.266966)
		(width 0.1651)
		(layer "In5.Cu")
		(net "P5E_PEX1_STN0_RX_DP<1>")
	)
	(segment
		(start 204.183996 -146.3929)
		(end 204.440536 -149.910546)
		(width 0.1651)
		(layer "In5.Cu")
		(net "P5E_PEX1_STN0_RX_DP<1>")
	)
	(segment
		(start 193.29781 -128.19507)
		(end 193.423286 -128.204214)
		(width 0.1651)
		(layer "In5.Cu")
		(net "P5E_PEX1_STN0_RX_DP<1>")
	)
	(segment
		(start 191.456818 -125.924564)
		(end 191.447674 -126.049786)
		(width 0.1651)
		(layer "In5.Cu")
		(net "P5E_PEX1_STN0_RX_DP<1>")
	)
	(segment
		(start 188.797438 -123.215908)
		(end 190.993268 -125.386846)
		(width 0.1651)
		(layer "In5.Cu")
		(net "P5E_PEX1_STN0_RX_DP<1>")
	)
	(segment
		(start 197.979792 -286.994854)
		(end 197.979792 -287.235646)
		(width 0.1143)
		(layer "In5.Cu")
		(net "P5E_PEX1_STN0_RX_DP<1>")
	)
	(segment
		(start 204.285342 -232.123996)
		(end 205.74 -239.260888)
		(width 0.1651)
		(layer "In5.Cu")
		(net "P5E_PEX1_STN0_RX_DP<1>")
	)
	(segment
		(start 185.242454 -121.735596)
		(end 185.303922 -121.885202)
		(width 0.1651)
		(layer "In5.Cu")
		(net "P5E_PEX1_STN0_RX_DP<1>")
	)
	(segment
		(start 185.303922 -121.885202)
		(end 185.761376 -122.075702)
		(width 0.1651)
		(layer "In5.Cu")
		(net "P5E_PEX1_STN0_RX_DP<1>")
	)
	(segment
		(start 185.761376 -122.075702)
		(end 185.910982 -122.014234)
		(width 0.1651)
		(layer "In5.Cu")
		(net "P5E_PEX1_STN0_RX_DP<1>")
	)
	(segment
		(start 196.482462 -131.751578)
		(end 198.64324 -132.942584)
		(width 0.1651)
		(layer "In5.Cu")
		(net "P5E_PEX1_STN0_RX_DP<1>")
	)
	(segment
		(start 184.635648 -121.606818)
		(end 184.785254 -121.54535)
		(width 0.1651)
		(layer "In5.Cu")
		(net "P5E_PEX1_STN0_RX_DP<1>")
	)
	(segment
		(start 191.771524 -126.425198)
		(end 191.896746 -126.434342)
		(width 0.1651)
		(layer "In5.Cu")
		(net "P5E_PEX1_STN0_RX_DP<1>")
	)
	(segment
		(start 202.020424 -286.733996)
		(end 200.050146 -286.733996)
		(width 0.1651)
		(layer "In5.Cu")
		(net "P5E_PEX1_STN0_RX_DP<1>")
	)
	(segment
		(start 205.74 -239.260888)
		(end 214.515192 -269.313406)
		(width 0.1651)
		(layer "In5.Cu")
		(net "P5E_PEX1_STN0_RX_DP<1>")
	)
	(segment
		(start 198.19493 -286.779716)
		(end 197.979792 -286.994854)
		(width 0.1143)
		(layer "In5.Cu")
		(net "P5E_PEX1_STN0_RX_DP<1>")
	)
	(segment
		(start 186.887104 -122.544586)
		(end 187.03671 -122.482864)
		(width 0.1651)
		(layer "In5.Cu")
		(net "P5E_PEX1_STN0_RX_DP<1>")
	)
	(segment
		(start 184.757314 -155.954984)
		(end 184.26938 -155.954984)
		(width 0.13462)
		(layer "F.Cu")
		(net "P5E_PEX1_STN0_RX_DP<15>")
	)
	(segment
		(start 184.106566 -155.79217)
		(end 181.598062 -155.79217)
		(width 0.13462)
		(layer "F.Cu")
		(net "P5E_PEX1_STN0_RX_DP<15>")
	)
	(segment
		(start 181.598062 -155.79217)
		(end 181.302914 -156.087318)
		(width 0.13462)
		(layer "F.Cu")
		(net "P5E_PEX1_STN0_RX_DP<15>")
	)
	(segment
		(start 184.26938 -155.954984)
		(end 184.106566 -155.79217)
		(width 0.13462)
		(layer "F.Cu")
		(net "P5E_PEX1_STN0_RX_DP<15>")
	)
	(segment
		(start 183.192166 -159.06877)
		(end 183.099964 -158.999428)
		(width 0.1651)
		(layer "In5.Cu")
		(net "P5E_PEX1_STN0_RX_DP<15>")
	)
	(segment
		(start 183.021732 -158.443676)
		(end 183.091074 -158.351474)
		(width 0.1651)
		(layer "In5.Cu")
		(net "P5E_PEX1_STN0_RX_DP<15>")
	)
	(segment
		(start 182.92064 -157.144212)
		(end 182.797196 -156.267404)
		(width 0.1651)
		(layer "In5.Cu")
		(net "P5E_PEX1_STN0_RX_DP<15>")
	)
	(segment
		(start 183.099964 -158.999428)
		(end 183.021732 -158.443676)
		(width 0.1651)
		(layer "In5.Cu")
		(net "P5E_PEX1_STN0_RX_DP<15>")
	)
	(segment
		(start 181.593744 -155.796488)
		(end 181.302914 -156.087318)
		(width 0.1651)
		(layer "In5.Cu")
		(net "P5E_PEX1_STN0_RX_DP<15>")
	)
	(segment
		(start 183.730646 -162.8902)
		(end 183.192166 -159.06877)
		(width 0.1651)
		(layer "In5.Cu")
		(net "P5E_PEX1_STN0_RX_DP<15>")
	)
	(segment
		(start 182.8927 -157.764226)
		(end 182.823358 -157.273498)
		(width 0.1651)
		(layer "In5.Cu")
		(net "P5E_PEX1_STN0_RX_DP<15>")
	)
	(segment
		(start 190.949834 -274.049744)
		(end 190.949834 -273.784314)
		(width 0.1143)
		(layer "In5.Cu")
		(net "P5E_PEX1_STN0_RX_DP<15>")
	)
	(segment
		(start 183.021986 -157.861254)
		(end 182.8927 -157.764226)
		(width 0.1651)
		(layer "In5.Cu")
		(net "P5E_PEX1_STN0_RX_DP<15>")
	)
	(segment
		(start 190.379858 -271.600168)
		(end 190.334138 -271.554448)
		(width 0.1143)
		(layer "In5.Cu")
		(net "P5E_PEX1_STN0_RX_DP<15>")
	)
	(segment
		(start 183.091074 -158.351474)
		(end 183.021986 -157.861254)
		(width 0.1651)
		(layer "In5.Cu")
		(net "P5E_PEX1_STN0_RX_DP<15>")
	)
	(segment
		(start 190.949834 -273.784314)
		(end 190.835534 -273.670014)
		(width 0.1143)
		(layer "In5.Cu")
		(net "P5E_PEX1_STN0_RX_DP<15>")
	)
	(segment
		(start 190.334138 -271.554448)
		(end 190.334138 -271.526)
		(width 0.1143)
		(layer "In5.Cu")
		(net "P5E_PEX1_STN0_RX_DP<15>")
	)
	(segment
		(start 190.334138 -270.204692)
		(end 190.806578 -267.744956)
		(width 0.1651)
		(layer "In5.Cu")
		(net "P5E_PEX1_STN0_RX_DP<15>")
	)
	(segment
		(start 190.835534 -273.670014)
		(end 190.594742 -273.670014)
		(width 0.1143)
		(layer "In5.Cu")
		(net "P5E_PEX1_STN0_RX_DP<15>")
	)
	(segment
		(start 182.823358 -157.273498)
		(end 182.92064 -157.144212)
		(width 0.1651)
		(layer "In5.Cu")
		(net "P5E_PEX1_STN0_RX_DP<15>")
	)
	(segment
		(start 190.806578 -267.744956)
		(end 190.637414 -261.285482)
		(width 0.1651)
		(layer "In5.Cu")
		(net "P5E_PEX1_STN0_RX_DP<15>")
	)
	(segment
		(start 190.637414 -261.285482)
		(end 183.730646 -162.8902)
		(width 0.1651)
		(layer "In5.Cu")
		(net "P5E_PEX1_STN0_RX_DP<15>")
	)
	(segment
		(start 190.379858 -273.45513)
		(end 190.379858 -271.600168)
		(width 0.1143)
		(layer "In5.Cu")
		(net "P5E_PEX1_STN0_RX_DP<15>")
	)
	(segment
		(start 190.594742 -273.670014)
		(end 190.379858 -273.45513)
		(width 0.1143)
		(layer "In5.Cu")
		(net "P5E_PEX1_STN0_RX_DP<15>")
	)
	(segment
		(start 190.334138 -271.526)
		(end 190.334138 -270.204692)
		(width 0.1651)
		(layer "In5.Cu")
		(net "P5E_PEX1_STN0_RX_DP<15>")
	)
	(segment
		(start 182.32628 -155.796488)
		(end 181.593744 -155.796488)
		(width 0.1651)
		(layer "In5.Cu")
		(net "P5E_PEX1_STN0_RX_DP<15>")
	)
	(segment
		(start 182.797196 -156.267404)
		(end 182.32628 -155.796488)
		(width 0.1651)
		(layer "In5.Cu")
		(net "P5E_PEX1_STN0_RX_DP<15>")
	)
	(segment
		(start 195.540122 -122.872246)
		(end 195.852542 -123.184666)
		(width 0.13462)
		(layer "F.Cu")
		(net "P5E_PEX1_STN0_TX_C_DP<2>")
	)
	(segment
		(start 190.00851 -122.872246)
		(end 195.540122 -122.872246)
		(width 0.13462)
		(layer "F.Cu")
		(net "P5E_PEX1_STN0_TX_C_DP<2>")
	)
	(segment
		(start 189.845696 -123.03506)
		(end 190.00851 -122.872246)
		(width 0.13462)
		(layer "F.Cu")
		(net "P5E_PEX1_STN0_TX_C_DP<2>")
	)
	(segment
		(start 189.357508 -123.03506)
		(end 189.845696 -123.03506)
		(width 0.13462)
		(layer "F.Cu")
		(net "P5E_PEX1_STN0_TX_C_DP<2>")
	)
	(segment
		(start 195.524882 -130.207766)
		(end 195.852542 -129.880106)
		(width 0.13462)
		(layer "F.Cu")
		(net "P5E_PEX1_STN0_TX_C_DN<4>")
	)
	(segment
		(start 190.00851 -130.207766)
		(end 195.524882 -130.207766)
		(width 0.13462)
		(layer "F.Cu")
		(net "P5E_PEX1_STN0_TX_C_DN<4>")
	)
	(segment
		(start 189.845696 -130.044952)
		(end 190.00851 -130.207766)
		(width 0.13462)
		(layer "F.Cu")
		(net "P5E_PEX1_STN0_TX_C_DN<4>")
	)
	(segment
		(start 189.357508 -130.044952)
		(end 189.845696 -130.044952)
		(width 0.13462)
		(layer "F.Cu")
		(net "P5E_PEX1_STN0_TX_C_DN<4>")
	)
	(segment
		(start 189.845696 -133.645148)
		(end 190.00851 -133.807962)
		(width 0.13462)
		(layer "F.Cu")
		(net "P5E_PEX1_STN0_TX_C_DN<6>")
	)
	(segment
		(start 190.00851 -133.807962)
		(end 195.524882 -133.807962)
		(width 0.13462)
		(layer "F.Cu")
		(net "P5E_PEX1_STN0_TX_C_DN<6>")
	)
	(segment
		(start 189.357508 -133.645148)
		(end 189.845696 -133.645148)
		(width 0.13462)
		(layer "F.Cu")
		(net "P5E_PEX1_STN0_TX_C_DN<6>")
	)
	(segment
		(start 195.524882 -133.807962)
		(end 195.852542 -133.480302)
		(width 0.13462)
		(layer "F.Cu")
		(net "P5E_PEX1_STN0_TX_C_DN<6>")
	)
	(segment
		(start 189.357508 -149.954996)
		(end 189.845696 -149.954996)
		(width 0.13462)
		(layer "F.Cu")
		(net "P5E_PEX1_STN0_TX_C_DP<12>")
	)
	(segment
		(start 189.845696 -149.954996)
		(end 190.00851 -150.11781)
		(width 0.13462)
		(layer "F.Cu")
		(net "P5E_PEX1_STN0_TX_C_DP<12>")
	)
	(segment
		(start 195.524882 -150.11781)
		(end 195.852542 -149.79015)
		(width 0.13462)
		(layer "F.Cu")
		(net "P5E_PEX1_STN0_TX_C_DP<12>")
	)
	(segment
		(start 190.00851 -150.11781)
		(end 195.524882 -150.11781)
		(width 0.13462)
		(layer "F.Cu")
		(net "P5E_PEX1_STN0_TX_C_DP<12>")
	)
	(segment
		(start 198.175626 -135.882126)
		(end 198.49465 -136.20115)
		(width 0.13462)
		(layer "F.Cu")
		(net "P5E_PEX1_STN0_TX_C_DP<7>")
	)
	(segment
		(start 189.357508 -136.04494)
		(end 189.845696 -136.04494)
		(width 0.13462)
		(layer "F.Cu")
		(net "P5E_PEX1_STN0_TX_C_DP<7>")
	)
	(segment
		(start 189.845696 -136.04494)
		(end 190.00851 -135.882126)
		(width 0.13462)
		(layer "F.Cu")
		(net "P5E_PEX1_STN0_TX_C_DP<7>")
	)
	(segment
		(start 190.00851 -135.882126)
		(end 198.175626 -135.882126)
		(width 0.13462)
		(layer "F.Cu")
		(net "P5E_PEX1_STN0_TX_C_DP<7>")
	)
	(segment
		(start 184.106566 -150.11781)
		(end 183.451246 -150.11781)
		(width 0.13462)
		(layer "F.Cu")
		(net "P5E_PEX1_STN0_RX_DN<12>")
	)
	(segment
		(start 184.26938 -149.954996)
		(end 184.106566 -150.11781)
		(width 0.13462)
		(layer "F.Cu")
		(net "P5E_PEX1_STN0_RX_DN<12>")
	)
	(segment
		(start 184.757314 -149.954996)
		(end 184.26938 -149.954996)
		(width 0.13462)
		(layer "F.Cu")
		(net "P5E_PEX1_STN0_RX_DN<12>")
	)
	(segment
		(start 183.451246 -150.11781)
		(end 183.157114 -149.823678)
		(width 0.13462)
		(layer "F.Cu")
		(net "P5E_PEX1_STN0_RX_DN<12>")
	)
	(segment
		(start 189.232286 -158.336488)
		(end 190.402464 -161.1503)
		(width 0.1651)
		(layer "In5.Cu")
		(net "P5E_PEX1_STN0_RX_DN<12>")
	)
	(segment
		(start 183.157114 -149.823678)
		(end 183.447944 -150.114508)
		(width 0.1651)
		(layer "In5.Cu")
		(net "P5E_PEX1_STN0_RX_DN<12>")
	)
	(segment
		(start 193.465958 -270.786098)
		(end 193.465958 -271.570958)
		(width 0.1651)
		(layer "In5.Cu")
		(net "P5E_PEX1_STN0_RX_DN<12>")
	)
	(segment
		(start 185.549032 -151.59863)
		(end 186.967622 -154.97175)
		(width 0.1651)
		(layer "In5.Cu")
		(net "P5E_PEX1_STN0_RX_DN<12>")
	)
	(segment
		(start 193.420238 -275.27631)
		(end 193.523616 -275.379688)
		(width 0.1143)
		(layer "In5.Cu")
		(net "P5E_PEX1_STN0_RX_DN<12>")
	)
	(segment
		(start 184.038494 -150.114508)
		(end 185.549032 -151.59863)
		(width 0.1651)
		(layer "In5.Cu")
		(net "P5E_PEX1_STN0_RX_DN<12>")
	)
	(segment
		(start 193.465958 -271.570958)
		(end 193.465958 -271.599406)
		(width 0.1143)
		(layer "In5.Cu")
		(net "P5E_PEX1_STN0_RX_DN<12>")
	)
	(segment
		(start 183.447944 -150.114508)
		(end 184.038494 -150.114508)
		(width 0.1651)
		(layer "In5.Cu")
		(net "P5E_PEX1_STN0_RX_DN<12>")
	)
	(segment
		(start 193.465958 -271.599406)
		(end 193.420238 -271.645126)
		(width 0.1143)
		(layer "In5.Cu")
		(net "P5E_PEX1_STN0_RX_DN<12>")
	)
	(segment
		(start 193.995548 -268.061186)
		(end 193.465958 -270.786098)
		(width 0.1651)
		(layer "In5.Cu")
		(net "P5E_PEX1_STN0_RX_DN<12>")
	)
	(segment
		(start 193.799714 -275.265388)
		(end 193.799714 -274.999958)
		(width 0.1143)
		(layer "In5.Cu")
		(net "P5E_PEX1_STN0_RX_DN<12>")
	)
	(segment
		(start 193.420238 -271.645126)
		(end 193.420238 -275.27631)
		(width 0.1143)
		(layer "In5.Cu")
		(net "P5E_PEX1_STN0_RX_DN<12>")
	)
	(segment
		(start 186.967622 -154.97175)
		(end 189.232286 -158.336488)
		(width 0.1651)
		(layer "In5.Cu")
		(net "P5E_PEX1_STN0_RX_DN<12>")
	)
	(segment
		(start 190.402464 -161.1503)
		(end 193.93281 -260.768084)
		(width 0.1651)
		(layer "In5.Cu")
		(net "P5E_PEX1_STN0_RX_DN<12>")
	)
	(segment
		(start 193.93281 -260.768084)
		(end 193.995548 -268.061186)
		(width 0.1651)
		(layer "In5.Cu")
		(net "P5E_PEX1_STN0_RX_DN<12>")
	)
	(segment
		(start 193.685414 -275.379688)
		(end 193.799714 -275.265388)
		(width 0.1143)
		(layer "In5.Cu")
		(net "P5E_PEX1_STN0_RX_DN<12>")
	)
	(segment
		(start 193.523616 -275.379688)
		(end 193.685414 -275.379688)
		(width 0.1143)
		(layer "In5.Cu")
		(net "P5E_PEX1_STN0_RX_DN<12>")
	)
	(segment
		(start 195.525136 -153.717752)
		(end 195.852542 -153.390346)
		(width 0.13462)
		(layer "F.Cu")
		(net "P5E_PEX1_STN0_TX_C_DP<14>")
	)
	(segment
		(start 190.008764 -153.717752)
		(end 195.525136 -153.717752)
		(width 0.13462)
		(layer "F.Cu")
		(net "P5E_PEX1_STN0_TX_C_DP<14>")
	)
	(segment
		(start 189.357508 -153.554938)
		(end 189.84595 -153.554938)
		(width 0.13462)
		(layer "F.Cu")
		(net "P5E_PEX1_STN0_TX_C_DP<14>")
	)
	(segment
		(start 189.84595 -153.554938)
		(end 190.008764 -153.717752)
		(width 0.13462)
		(layer "F.Cu")
		(net "P5E_PEX1_STN0_TX_C_DP<14>")
	)
	(segment
		(start 183.451246 -153.717752)
		(end 183.157114 -153.42362)
		(width 0.13462)
		(layer "F.Cu")
		(net "P5E_PEX1_STN0_RX_DN<14>")
	)
	(segment
		(start 184.757314 -153.554938)
		(end 184.269126 -153.554938)
		(width 0.13462)
		(layer "F.Cu")
		(net "P5E_PEX1_STN0_RX_DN<14>")
	)
	(segment
		(start 184.106312 -153.717752)
		(end 183.451246 -153.717752)
		(width 0.13462)
		(layer "F.Cu")
		(net "P5E_PEX1_STN0_RX_DN<14>")
	)
	(segment
		(start 184.269126 -153.554938)
		(end 184.106312 -153.717752)
		(width 0.13462)
		(layer "F.Cu")
		(net "P5E_PEX1_STN0_RX_DN<14>")
	)
	(segment
		(start 184.883298 -160.386776)
		(end 184.998614 -162.064446)
		(width 0.1651)
		(layer "In5.Cu")
		(net "P5E_PEX1_STN0_RX_DN<14>")
	)
	(segment
		(start 191.566038 -271.599152)
		(end 191.520318 -271.644872)
		(width 0.1143)
		(layer "In5.Cu")
		(net "P5E_PEX1_STN0_RX_DN<14>")
	)
	(segment
		(start 184.615582 -154.733752)
		(end 184.88279 -158.632144)
		(width 0.1651)
		(layer "In5.Cu")
		(net "P5E_PEX1_STN0_RX_DN<14>")
	)
	(segment
		(start 183.446674 -153.71318)
		(end 183.879744 -153.71318)
		(width 0.1651)
		(layer "In5.Cu")
		(net "P5E_PEX1_STN0_RX_DN<14>")
	)
	(segment
		(start 191.785494 -275.379434)
		(end 191.899794 -275.265134)
		(width 0.1143)
		(layer "In5.Cu")
		(net "P5E_PEX1_STN0_RX_DN<14>")
	)
	(segment
		(start 191.899794 -275.265134)
		(end 191.899794 -274.999704)
		(width 0.1143)
		(layer "In5.Cu")
		(net "P5E_PEX1_STN0_RX_DN<14>")
	)
	(segment
		(start 191.520318 -271.644872)
		(end 191.520318 -275.276056)
		(width 0.1143)
		(layer "In5.Cu")
		(net "P5E_PEX1_STN0_RX_DN<14>")
	)
	(segment
		(start 184.883298 -158.632652)
		(end 184.883298 -160.386776)
		(width 0.1651)
		(layer "In5.Cu")
		(net "P5E_PEX1_STN0_RX_DN<14>")
	)
	(segment
		(start 192.061084 -267.81125)
		(end 191.566038 -270.457168)
		(width 0.1651)
		(layer "In5.Cu")
		(net "P5E_PEX1_STN0_RX_DN<14>")
	)
	(segment
		(start 191.845692 -258.322826)
		(end 192.061084 -267.81125)
		(width 0.1651)
		(layer "In5.Cu")
		(net "P5E_PEX1_STN0_RX_DN<14>")
	)
	(segment
		(start 184.998614 -162.064446)
		(end 185.414666 -164.671502)
		(width 0.1651)
		(layer "In5.Cu")
		(net "P5E_PEX1_STN0_RX_DN<14>")
	)
	(segment
		(start 191.566038 -270.457168)
		(end 191.566038 -271.570704)
		(width 0.1651)
		(layer "In5.Cu")
		(net "P5E_PEX1_STN0_RX_DN<14>")
	)
	(segment
		(start 191.623696 -275.379434)
		(end 191.785494 -275.379434)
		(width 0.1143)
		(layer "In5.Cu")
		(net "P5E_PEX1_STN0_RX_DN<14>")
	)
	(segment
		(start 191.520318 -275.276056)
		(end 191.623696 -275.379434)
		(width 0.1143)
		(layer "In5.Cu")
		(net "P5E_PEX1_STN0_RX_DN<14>")
	)
	(segment
		(start 191.566038 -271.570704)
		(end 191.566038 -271.599152)
		(width 0.1143)
		(layer "In5.Cu")
		(net "P5E_PEX1_STN0_RX_DN<14>")
	)
	(segment
		(start 184.378092 -154.211528)
		(end 184.615582 -154.733752)
		(width 0.1651)
		(layer "In5.Cu")
		(net "P5E_PEX1_STN0_RX_DN<14>")
	)
	(segment
		(start 183.157114 -153.42362)
		(end 183.446674 -153.71318)
		(width 0.1651)
		(layer "In5.Cu")
		(net "P5E_PEX1_STN0_RX_DN<14>")
	)
	(segment
		(start 183.879744 -153.71318)
		(end 184.378092 -154.211528)
		(width 0.1651)
		(layer "In5.Cu")
		(net "P5E_PEX1_STN0_RX_DN<14>")
	)
	(segment
		(start 185.414666 -164.671502)
		(end 191.845692 -258.322826)
		(width 0.1651)
		(layer "In5.Cu")
		(net "P5E_PEX1_STN0_RX_DN<14>")
	)
	(segment
		(start 184.88279 -158.632144)
		(end 184.883298 -158.632652)
		(width 0.1651)
		(layer "In5.Cu")
		(net "P5E_PEX1_STN0_RX_DN<14>")
	)
	(segment
		(start 184.757314 -152.355042)
		(end 184.26938 -152.355042)
		(width 0.13462)
		(layer "F.Cu")
		(net "P5E_PEX1_STN0_RX_DP<13>")
	)
	(segment
		(start 184.26938 -152.355042)
		(end 184.106566 -152.192228)
		(width 0.13462)
		(layer "F.Cu")
		(net "P5E_PEX1_STN0_RX_DP<13>")
	)
	(segment
		(start 184.106566 -152.192228)
		(end 181.598062 -152.192228)
		(width 0.13462)
		(layer "F.Cu")
		(net "P5E_PEX1_STN0_RX_DP<13>")
	)
	(segment
		(start 181.598062 -152.192228)
		(end 181.302914 -152.487376)
		(width 0.13462)
		(layer "F.Cu")
		(net "P5E_PEX1_STN0_RX_DP<13>")
	)
	(segment
		(start 192.735454 -273.670014)
		(end 192.849754 -273.784314)
		(width 0.1143)
		(layer "In5.Cu")
		(net "P5E_PEX1_STN0_RX_DP<13>")
	)
	(segment
		(start 187.533534 -158.233364)
		(end 187.656724 -158.25724)
		(width 0.1651)
		(layer "In5.Cu")
		(net "P5E_PEX1_STN0_RX_DP<13>")
	)
	(segment
		(start 187.002674 -157.288992)
		(end 187.279788 -157.699202)
		(width 0.1651)
		(layer "In5.Cu")
		(net "P5E_PEX1_STN0_RX_DP<13>")
	)
	(segment
		(start 186.87923 -157.265116)
		(end 187.002674 -157.288992)
		(width 0.1651)
		(layer "In5.Cu")
		(net "P5E_PEX1_STN0_RX_DP<13>")
	)
	(segment
		(start 185.581798 -155.185618)
		(end 186.625738 -156.730954)
		(width 0.1651)
		(layer "In5.Cu")
		(net "P5E_PEX1_STN0_RX_DP<13>")
	)
	(segment
		(start 187.656724 -158.25724)
		(end 188.115448 -158.936436)
		(width 0.1651)
		(layer "In5.Cu")
		(net "P5E_PEX1_STN0_RX_DP<13>")
	)
	(segment
		(start 192.494662 -273.670014)
		(end 192.735454 -273.670014)
		(width 0.1143)
		(layer "In5.Cu")
		(net "P5E_PEX1_STN0_RX_DP<13>")
	)
	(segment
		(start 192.279778 -271.600168)
		(end 192.279778 -273.45513)
		(width 0.1143)
		(layer "In5.Cu")
		(net "P5E_PEX1_STN0_RX_DP<13>")
	)
	(segment
		(start 192.75044 -267.84427)
		(end 192.234058 -270.513048)
		(width 0.1651)
		(layer "In5.Cu")
		(net "P5E_PEX1_STN0_RX_DP<13>")
	)
	(segment
		(start 187.279788 -157.699202)
		(end 187.255912 -157.822646)
		(width 0.1651)
		(layer "In5.Cu")
		(net "P5E_PEX1_STN0_RX_DP<13>")
	)
	(segment
		(start 192.234058 -270.513048)
		(end 192.234058 -271.526)
		(width 0.1651)
		(layer "In5.Cu")
		(net "P5E_PEX1_STN0_RX_DP<13>")
	)
	(segment
		(start 181.302914 -152.487376)
		(end 181.593744 -152.196546)
		(width 0.1651)
		(layer "In5.Cu")
		(net "P5E_PEX1_STN0_RX_DP<13>")
	)
	(segment
		(start 188.115448 -158.936436)
		(end 189.121542 -161.356548)
		(width 0.1651)
		(layer "In5.Cu")
		(net "P5E_PEX1_STN0_RX_DP<13>")
	)
	(segment
		(start 184.720738 -153.119074)
		(end 185.581798 -155.185618)
		(width 0.1651)
		(layer "In5.Cu")
		(net "P5E_PEX1_STN0_RX_DP<13>")
	)
	(segment
		(start 192.849754 -273.784314)
		(end 192.849754 -274.049744)
		(width 0.1143)
		(layer "In5.Cu")
		(net "P5E_PEX1_STN0_RX_DP<13>")
	)
	(segment
		(start 192.234058 -271.554448)
		(end 192.279778 -271.600168)
		(width 0.1143)
		(layer "In5.Cu")
		(net "P5E_PEX1_STN0_RX_DP<13>")
	)
	(segment
		(start 183.79821 -152.196546)
		(end 184.720738 -153.119074)
		(width 0.1651)
		(layer "In5.Cu")
		(net "P5E_PEX1_STN0_RX_DP<13>")
	)
	(segment
		(start 186.625738 -156.730954)
		(end 186.601862 -156.854398)
		(width 0.1651)
		(layer "In5.Cu")
		(net "P5E_PEX1_STN0_RX_DP<13>")
	)
	(segment
		(start 189.121542 -161.356548)
		(end 192.675764 -260.651244)
		(width 0.1651)
		(layer "In5.Cu")
		(net "P5E_PEX1_STN0_RX_DP<13>")
	)
	(segment
		(start 192.675764 -260.651244)
		(end 192.75044 -267.84427)
		(width 0.1651)
		(layer "In5.Cu")
		(net "P5E_PEX1_STN0_RX_DP<13>")
	)
	(segment
		(start 192.279778 -273.45513)
		(end 192.494662 -273.670014)
		(width 0.1143)
		(layer "In5.Cu")
		(net "P5E_PEX1_STN0_RX_DP<13>")
	)
	(segment
		(start 192.234058 -271.526)
		(end 192.234058 -271.554448)
		(width 0.1143)
		(layer "In5.Cu")
		(net "P5E_PEX1_STN0_RX_DP<13>")
	)
	(segment
		(start 187.255912 -157.822646)
		(end 187.533534 -158.233364)
		(width 0.1651)
		(layer "In5.Cu")
		(net "P5E_PEX1_STN0_RX_DP<13>")
	)
	(segment
		(start 181.593744 -152.196546)
		(end 183.79821 -152.196546)
		(width 0.1651)
		(layer "In5.Cu")
		(net "P5E_PEX1_STN0_RX_DP<13>")
	)
	(segment
		(start 186.601862 -156.854398)
		(end 186.87923 -157.265116)
		(width 0.1651)
		(layer "In5.Cu")
		(net "P5E_PEX1_STN0_RX_DP<13>")
	)
	(segment
		(start 190.00851 -124.39777)
		(end 198.173594 -124.39777)
		(width 0.13462)
		(layer "F.Cu")
		(net "P5E_PEX1_STN0_TX_C_DN<3>")
	)
	(segment
		(start 189.357508 -124.234956)
		(end 189.845696 -124.234956)
		(width 0.13462)
		(layer "F.Cu")
		(net "P5E_PEX1_STN0_TX_C_DN<3>")
	)
	(segment
		(start 198.173594 -124.39777)
		(end 198.49465 -124.076714)
		(width 0.13462)
		(layer "F.Cu")
		(net "P5E_PEX1_STN0_TX_C_DN<3>")
	)
	(segment
		(start 189.845696 -124.234956)
		(end 190.00851 -124.39777)
		(width 0.13462)
		(layer "F.Cu")
		(net "P5E_PEX1_STN0_TX_C_DN<3>")
	)
	(segment
		(start 198.175626 -148.592286)
		(end 198.49465 -148.91131)
		(width 0.13462)
		(layer "F.Cu")
		(net "P5E_PEX1_STN0_TX_C_DP<11>")
	)
	(segment
		(start 189.845696 -148.7551)
		(end 190.00851 -148.592286)
		(width 0.13462)
		(layer "F.Cu")
		(net "P5E_PEX1_STN0_TX_C_DP<11>")
	)
	(segment
		(start 189.357508 -148.7551)
		(end 189.845696 -148.7551)
		(width 0.13462)
		(layer "F.Cu")
		(net "P5E_PEX1_STN0_TX_C_DP<11>")
	)
	(segment
		(start 190.00851 -148.592286)
		(end 198.175626 -148.592286)
		(width 0.13462)
		(layer "F.Cu")
		(net "P5E_PEX1_STN0_TX_C_DP<11>")
	)
	(segment
		(start 184.757314 -154.15514)
		(end 184.26938 -154.15514)
		(width 0.13462)
		(layer "F.Cu")
		(net "P5E_PEX1_STN0_RX_DP<14>")
	)
	(segment
		(start 183.452262 -153.992072)
		(end 183.157114 -154.28722)
		(width 0.13462)
		(layer "F.Cu")
		(net "P5E_PEX1_STN0_RX_DP<14>")
	)
	(segment
		(start 184.106312 -153.992072)
		(end 183.452262 -153.992072)
		(width 0.13462)
		(layer "F.Cu")
		(net "P5E_PEX1_STN0_RX_DP<14>")
	)
	(segment
		(start 184.26938 -154.15514)
		(end 184.106312 -153.992072)
		(width 0.13462)
		(layer "F.Cu")
		(net "P5E_PEX1_STN0_RX_DP<14>")
	)
	(segment
		(start 183.449214 -153.99512)
		(end 183.157114 -154.28722)
		(width 0.1651)
		(layer "In5.Cu")
		(net "P5E_PEX1_STN0_RX_DP<14>")
	)
	(segment
		(start 191.899794 -275.949664)
		(end 191.899794 -275.684234)
		(width 0.1143)
		(layer "In5.Cu")
		(net "P5E_PEX1_STN0_RX_DP<14>")
	)
	(segment
		(start 184.381902 -156.597604)
		(end 184.4548 -156.514038)
		(width 0.1651)
		(layer "In5.Cu")
		(net "P5E_PEX1_STN0_RX_DP<14>")
	)
	(segment
		(start 191.544702 -275.569934)
		(end 191.329818 -275.35505)
		(width 0.1143)
		(layer "In5.Cu")
		(net "P5E_PEX1_STN0_RX_DP<14>")
	)
	(segment
		(start 191.329818 -271.644872)
		(end 191.284098 -271.599152)
		(width 0.1143)
		(layer "In5.Cu")
		(net "P5E_PEX1_STN0_RX_DP<14>")
	)
	(segment
		(start 191.329818 -275.35505)
		(end 191.329818 -271.644872)
		(width 0.1143)
		(layer "In5.Cu")
		(net "P5E_PEX1_STN0_RX_DP<14>")
	)
	(segment
		(start 191.785494 -275.569934)
		(end 191.544702 -275.569934)
		(width 0.1143)
		(layer "In5.Cu")
		(net "P5E_PEX1_STN0_RX_DP<14>")
	)
	(segment
		(start 191.284098 -271.570704)
		(end 191.284098 -270.431006)
		(width 0.1651)
		(layer "In5.Cu")
		(net "P5E_PEX1_STN0_RX_DP<14>")
	)
	(segment
		(start 184.601358 -160.396682)
		(end 184.601358 -158.642304)
		(width 0.1651)
		(layer "In5.Cu")
		(net "P5E_PEX1_STN0_RX_DP<14>")
	)
	(segment
		(start 184.421018 -156.020008)
		(end 184.299098 -155.913836)
		(width 0.1651)
		(layer "In5.Cu")
		(net "P5E_PEX1_STN0_RX_DP<14>")
	)
	(segment
		(start 191.563752 -258.33578)
		(end 185.13425 -164.703506)
		(width 0.1651)
		(layer "In5.Cu")
		(net "P5E_PEX1_STN0_RX_DP<14>")
	)
	(segment
		(start 184.337706 -154.803856)
		(end 184.142634 -154.37485)
		(width 0.1651)
		(layer "In5.Cu")
		(net "P5E_PEX1_STN0_RX_DP<14>")
	)
	(segment
		(start 184.4548 -156.514038)
		(end 184.421018 -156.020008)
		(width 0.1651)
		(layer "In5.Cu")
		(net "P5E_PEX1_STN0_RX_DP<14>")
	)
	(segment
		(start 191.899794 -275.684234)
		(end 191.785494 -275.569934)
		(width 0.1143)
		(layer "In5.Cu")
		(net "P5E_PEX1_STN0_RX_DP<14>")
	)
	(segment
		(start 184.420764 -157.163516)
		(end 184.381902 -156.597604)
		(width 0.1651)
		(layer "In5.Cu")
		(net "P5E_PEX1_STN0_RX_DP<14>")
	)
	(segment
		(start 184.601358 -158.642304)
		(end 184.600596 -158.641796)
		(width 0.1651)
		(layer "In5.Cu")
		(net "P5E_PEX1_STN0_RX_DP<14>")
	)
	(segment
		(start 191.284098 -270.431006)
		(end 191.778382 -267.788136)
		(width 0.1651)
		(layer "In5.Cu")
		(net "P5E_PEX1_STN0_RX_DP<14>")
	)
	(segment
		(start 184.600596 -158.641796)
		(end 184.504584 -157.236414)
		(width 0.1651)
		(layer "In5.Cu")
		(net "P5E_PEX1_STN0_RX_DP<14>")
	)
	(segment
		(start 184.299098 -155.913836)
		(end 184.265316 -155.419552)
		(width 0.1651)
		(layer "In5.Cu")
		(net "P5E_PEX1_STN0_RX_DP<14>")
	)
	(segment
		(start 184.371488 -155.297632)
		(end 184.337706 -154.803856)
		(width 0.1651)
		(layer "In5.Cu")
		(net "P5E_PEX1_STN0_RX_DP<14>")
	)
	(segment
		(start 184.142634 -154.37485)
		(end 183.762904 -153.99512)
		(width 0.1651)
		(layer "In5.Cu")
		(net "P5E_PEX1_STN0_RX_DP<14>")
	)
	(segment
		(start 185.13425 -164.703506)
		(end 184.718198 -162.09645)
		(width 0.1651)
		(layer "In5.Cu")
		(net "P5E_PEX1_STN0_RX_DP<14>")
	)
	(segment
		(start 184.504584 -157.236414)
		(end 184.420764 -157.163516)
		(width 0.1651)
		(layer "In5.Cu")
		(net "P5E_PEX1_STN0_RX_DP<14>")
	)
	(segment
		(start 184.718198 -162.09645)
		(end 184.601358 -160.396682)
		(width 0.1651)
		(layer "In5.Cu")
		(net "P5E_PEX1_STN0_RX_DP<14>")
	)
	(segment
		(start 191.778382 -267.788136)
		(end 191.563752 -258.33578)
		(width 0.1651)
		(layer "In5.Cu")
		(net "P5E_PEX1_STN0_RX_DP<14>")
	)
	(segment
		(start 183.762904 -153.99512)
		(end 183.449214 -153.99512)
		(width 0.1651)
		(layer "In5.Cu")
		(net "P5E_PEX1_STN0_RX_DP<14>")
	)
	(segment
		(start 184.265316 -155.419552)
		(end 184.371488 -155.297632)
		(width 0.1651)
		(layer "In5.Cu")
		(net "P5E_PEX1_STN0_RX_DP<14>")
	)
	(segment
		(start 191.284098 -271.599152)
		(end 191.284098 -271.570704)
		(width 0.1143)
		(layer "In5.Cu")
		(net "P5E_PEX1_STN0_RX_DP<14>")
	)
	(segment
		(start 189.84595 -118.834916)
		(end 190.008764 -118.99773)
		(width 0.13462)
		(layer "F.Cu")
		(net "P5E_PEX1_STN0_TX_C_DN<0>")
	)
	(segment
		(start 189.357508 -118.834916)
		(end 189.84595 -118.834916)
		(width 0.13462)
		(layer "F.Cu")
		(net "P5E_PEX1_STN0_TX_C_DN<0>")
	)
	(segment
		(start 195.525136 -118.99773)
		(end 195.852542 -118.670324)
		(width 0.13462)
		(layer "F.Cu")
		(net "P5E_PEX1_STN0_TX_C_DN<0>")
	)
	(segment
		(start 190.008764 -118.99773)
		(end 195.525136 -118.99773)
		(width 0.13462)
		(layer "F.Cu")
		(net "P5E_PEX1_STN0_TX_C_DN<0>")
	)
	(segment
		(start 189.845696 -119.435118)
		(end 190.008764 -119.27205)
		(width 0.13462)
		(layer "F.Cu")
		(net "P5E_PEX1_STN0_TX_C_DP<0>")
	)
	(segment
		(start 190.008764 -119.27205)
		(end 195.539868 -119.27205)
		(width 0.13462)
		(layer "F.Cu")
		(net "P5E_PEX1_STN0_TX_C_DP<0>")
	)
	(segment
		(start 189.357508 -119.435118)
		(end 189.845696 -119.435118)
		(width 0.13462)
		(layer "F.Cu")
		(net "P5E_PEX1_STN0_TX_C_DP<0>")
	)
	(segment
		(start 195.539868 -119.27205)
		(end 195.852542 -119.584724)
		(width 0.13462)
		(layer "F.Cu")
		(net "P5E_PEX1_STN0_TX_C_DP<0>")
	)
	(segment
		(start 190.00851 -143.192246)
		(end 195.540122 -143.192246)
		(width 0.13462)
		(layer "F.Cu")
		(net "P5E_PEX1_STN0_TX_C_DP<8>")
	)
	(segment
		(start 195.540122 -143.192246)
		(end 195.852542 -143.504666)
		(width 0.13462)
		(layer "F.Cu")
		(net "P5E_PEX1_STN0_TX_C_DP<8>")
	)
	(segment
		(start 189.845696 -143.35506)
		(end 190.00851 -143.192246)
		(width 0.13462)
		(layer "F.Cu")
		(net "P5E_PEX1_STN0_TX_C_DP<8>")
	)
	(segment
		(start 189.357508 -143.35506)
		(end 189.845696 -143.35506)
		(width 0.13462)
		(layer "F.Cu")
		(net "P5E_PEX1_STN0_TX_C_DP<8>")
	)
	(segment
		(start 184.106566 -143.192246)
		(end 184.26938 -143.35506)
		(width 0.13462)
		(layer "F.Cu")
		(net "P5E_PEX1_STN0_RX_DP<8>")
	)
	(segment
		(start 183.157114 -143.48714)
		(end 183.452008 -143.192246)
		(width 0.13462)
		(layer "F.Cu")
		(net "P5E_PEX1_STN0_RX_DP<8>")
	)
	(segment
		(start 183.452008 -143.192246)
		(end 184.106566 -143.192246)
		(width 0.13462)
		(layer "F.Cu")
		(net "P5E_PEX1_STN0_RX_DP<8>")
	)
	(segment
		(start 184.26938 -143.35506)
		(end 184.757314 -143.35506)
		(width 0.13462)
		(layer "F.Cu")
		(net "P5E_PEX1_STN0_RX_DP<8>")
	)
	(segment
		(start 193.998342 -160.044384)
		(end 194.09156 -160.636966)
		(width 0.1651)
		(layer "In5.Cu")
		(net "P5E_PEX1_STN0_RX_DP<8>")
	)
	(segment
		(start 198.455788 -272.14957)
		(end 198.455788 -273.279616)
		(width 0.1143)
		(layer "In5.Cu")
		(net "P5E_PEX1_STN0_RX_DP<8>")
	)
	(segment
		(start 184.324244 -143.810482)
		(end 184.736232 -144.086072)
		(width 0.1651)
		(layer "In5.Cu")
		(net "P5E_PEX1_STN0_RX_DP<8>")
	)
	(segment
		(start 187.460128 -147.448016)
		(end 187.72759 -147.864576)
		(width 0.1651)
		(layer "In5.Cu")
		(net "P5E_PEX1_STN0_RX_DP<8>")
	)
	(segment
		(start 185.570876 -144.506188)
		(end 186.409838 -145.812764)
		(width 0.1651)
		(layer "In5.Cu")
		(net "P5E_PEX1_STN0_RX_DP<8>")
	)
	(segment
		(start 198.455788 -273.279616)
		(end 197.979792 -273.755612)
		(width 0.1143)
		(layer "In5.Cu")
		(net "P5E_PEX1_STN0_RX_DP<8>")
	)
	(segment
		(start 187.034424 -146.996658)
		(end 187.30214 -147.413726)
		(width 0.1651)
		(layer "In5.Cu")
		(net "P5E_PEX1_STN0_RX_DP<8>")
	)
	(segment
		(start 187.068714 -146.83867)
		(end 187.034424 -146.996658)
		(width 0.1651)
		(layer "In5.Cu")
		(net "P5E_PEX1_STN0_RX_DP<8>")
	)
	(segment
		(start 186.409838 -145.812764)
		(end 186.375548 -145.970752)
		(width 0.1651)
		(layer "In5.Cu")
		(net "P5E_PEX1_STN0_RX_DP<8>")
	)
	(segment
		(start 186.375548 -145.970752)
		(end 186.643264 -146.38782)
		(width 0.1651)
		(layer "In5.Cu")
		(net "P5E_PEX1_STN0_RX_DP<8>")
	)
	(segment
		(start 188.627512 -149.430486)
		(end 188.750448 -149.457156)
		(width 0.1651)
		(layer "In5.Cu")
		(net "P5E_PEX1_STN0_RX_DP<8>")
	)
	(segment
		(start 198.410068 -271.552162)
		(end 198.410068 -272.075402)
		(width 0.1651)
		(layer "In5.Cu")
		(net "P5E_PEX1_STN0_RX_DP<8>")
	)
	(segment
		(start 187.6933 -148.022564)
		(end 187.961016 -148.439632)
		(width 0.1651)
		(layer "In5.Cu")
		(net "P5E_PEX1_STN0_RX_DP<8>")
	)
	(segment
		(start 186.643264 -146.38782)
		(end 186.801252 -146.42211)
		(width 0.1651)
		(layer "In5.Cu")
		(net "P5E_PEX1_STN0_RX_DP<8>")
	)
	(segment
		(start 186.801252 -146.42211)
		(end 187.068714 -146.83867)
		(width 0.1651)
		(layer "In5.Cu")
		(net "P5E_PEX1_STN0_RX_DP<8>")
	)
	(segment
		(start 198.363332 -270.778986)
		(end 198.410068 -271.552162)
		(width 0.1651)
		(layer "In5.Cu")
		(net "P5E_PEX1_STN0_RX_DP<8>")
	)
	(segment
		(start 197.703694 -265.22934)
		(end 198.363332 -270.778986)
		(width 0.1651)
		(layer "In5.Cu")
		(net "P5E_PEX1_STN0_RX_DP<8>")
	)
	(segment
		(start 189.67069 -151.590248)
		(end 191.163702 -153.018744)
		(width 0.1651)
		(layer "In5.Cu")
		(net "P5E_PEX1_STN0_RX_DP<8>")
	)
	(segment
		(start 187.72759 -147.864576)
		(end 187.6933 -148.022564)
		(width 0.1651)
		(layer "In5.Cu")
		(net "P5E_PEX1_STN0_RX_DP<8>")
	)
	(segment
		(start 198.410068 -272.075402)
		(end 198.410068 -272.10385)
		(width 0.1143)
		(layer "In5.Cu")
		(net "P5E_PEX1_STN0_RX_DP<8>")
	)
	(segment
		(start 197.979792 -274.885404)
		(end 197.865492 -274.999704)
		(width 0.1143)
		(layer "In5.Cu")
		(net "P5E_PEX1_STN0_RX_DP<8>")
	)
	(segment
		(start 184.736232 -144.086072)
		(end 184.894728 -144.054322)
		(width 0.1651)
		(layer "In5.Cu")
		(net "P5E_PEX1_STN0_RX_DP<8>")
	)
	(segment
		(start 194.09156 -160.636966)
		(end 197.703694 -265.22934)
		(width 0.1651)
		(layer "In5.Cu")
		(net "P5E_PEX1_STN0_RX_DP<8>")
	)
	(segment
		(start 197.865492 -274.999704)
		(end 197.600062 -274.999704)
		(width 0.1143)
		(layer "In5.Cu")
		(net "P5E_PEX1_STN0_RX_DP<8>")
	)
	(segment
		(start 198.410068 -272.10385)
		(end 198.455788 -272.14957)
		(width 0.1143)
		(layer "In5.Cu")
		(net "P5E_PEX1_STN0_RX_DP<8>")
	)
	(segment
		(start 183.610758 -143.19631)
		(end 184.292748 -143.651986)
		(width 0.1651)
		(layer "In5.Cu")
		(net "P5E_PEX1_STN0_RX_DP<8>")
	)
	(segment
		(start 184.292748 -143.651986)
		(end 184.324244 -143.810482)
		(width 0.1651)
		(layer "In5.Cu")
		(net "P5E_PEX1_STN0_RX_DP<8>")
	)
	(segment
		(start 191.163702 -153.018744)
		(end 192.506854 -154.825954)
		(width 0.1651)
		(layer "In5.Cu")
		(net "P5E_PEX1_STN0_RX_DP<8>")
	)
	(segment
		(start 187.30214 -147.413726)
		(end 187.460128 -147.448016)
		(width 0.1651)
		(layer "In5.Cu")
		(net "P5E_PEX1_STN0_RX_DP<8>")
	)
	(segment
		(start 197.979792 -273.755612)
		(end 197.979792 -274.885404)
		(width 0.1143)
		(layer "In5.Cu")
		(net "P5E_PEX1_STN0_RX_DP<8>")
	)
	(segment
		(start 187.961016 -148.439632)
		(end 188.119004 -148.473922)
		(width 0.1651)
		(layer "In5.Cu")
		(net "P5E_PEX1_STN0_RX_DP<8>")
	)
	(segment
		(start 188.119004 -148.473922)
		(end 188.386466 -148.890482)
		(width 0.1651)
		(layer "In5.Cu")
		(net "P5E_PEX1_STN0_RX_DP<8>")
	)
	(segment
		(start 189.11189 -150.020528)
		(end 189.67069 -151.590248)
		(width 0.1651)
		(layer "In5.Cu")
		(net "P5E_PEX1_STN0_RX_DP<8>")
	)
	(segment
		(start 188.359796 -149.013418)
		(end 188.627512 -149.430486)
		(width 0.1651)
		(layer "In5.Cu")
		(net "P5E_PEX1_STN0_RX_DP<8>")
	)
	(segment
		(start 183.447944 -143.19631)
		(end 183.610758 -143.19631)
		(width 0.1651)
		(layer "In5.Cu")
		(net "P5E_PEX1_STN0_RX_DP<8>")
	)
	(segment
		(start 188.750448 -149.457156)
		(end 189.11189 -150.020528)
		(width 0.1651)
		(layer "In5.Cu")
		(net "P5E_PEX1_STN0_RX_DP<8>")
	)
	(segment
		(start 192.506854 -154.825954)
		(end 193.998342 -160.044384)
		(width 0.1651)
		(layer "In5.Cu")
		(net "P5E_PEX1_STN0_RX_DP<8>")
	)
	(segment
		(start 188.386466 -148.890482)
		(end 188.359796 -149.013418)
		(width 0.1651)
		(layer "In5.Cu")
		(net "P5E_PEX1_STN0_RX_DP<8>")
	)
	(segment
		(start 184.894728 -144.054322)
		(end 185.570876 -144.506188)
		(width 0.1651)
		(layer "In5.Cu")
		(net "P5E_PEX1_STN0_RX_DP<8>")
	)
	(segment
		(start 183.157114 -143.48714)
		(end 183.447944 -143.19631)
		(width 0.1651)
		(layer "In5.Cu")
		(net "P5E_PEX1_STN0_RX_DP<8>")
	)
	(segment
		(start 198.173594 -151.917908)
		(end 198.49465 -151.596852)
		(width 0.13462)
		(layer "F.Cu")
		(net "P5E_PEX1_STN0_TX_C_DN<13>")
	)
	(segment
		(start 189.845696 -151.755094)
		(end 190.00851 -151.917908)
		(width 0.13462)
		(layer "F.Cu")
		(net "P5E_PEX1_STN0_TX_C_DN<13>")
	)
	(segment
		(start 189.357508 -151.755094)
		(end 189.845696 -151.755094)
		(width 0.13462)
		(layer "F.Cu")
		(net "P5E_PEX1_STN0_TX_C_DN<13>")
	)
	(segment
		(start 190.00851 -151.917908)
		(end 198.173594 -151.917908)
		(width 0.13462)
		(layer "F.Cu")
		(net "P5E_PEX1_STN0_TX_C_DN<13>")
	)
	(segment
		(start 195.540122 -150.39213)
		(end 195.852542 -150.70455)
		(width 0.13462)
		(layer "F.Cu")
		(net "P5E_PEX1_STN0_TX_C_DN<12>")
	)
	(segment
		(start 190.00851 -150.39213)
		(end 195.540122 -150.39213)
		(width 0.13462)
		(layer "F.Cu")
		(net "P5E_PEX1_STN0_TX_C_DN<12>")
	)
	(segment
		(start 189.845696 -150.554944)
		(end 190.00851 -150.39213)
		(width 0.13462)
		(layer "F.Cu")
		(net "P5E_PEX1_STN0_TX_C_DN<12>")
	)
	(segment
		(start 189.357508 -150.554944)
		(end 189.845696 -150.554944)
		(width 0.13462)
		(layer "F.Cu")
		(net "P5E_PEX1_STN0_TX_C_DN<12>")
	)
	(segment
		(start 184.106566 -148.592286)
		(end 181.598062 -148.592286)
		(width 0.13462)
		(layer "F.Cu")
		(net "P5E_PEX1_STN0_RX_DP<11>")
	)
	(segment
		(start 184.26938 -148.7551)
		(end 184.106566 -148.592286)
		(width 0.13462)
		(layer "F.Cu")
		(net "P5E_PEX1_STN0_RX_DP<11>")
	)
	(segment
		(start 184.757314 -148.7551)
		(end 184.26938 -148.7551)
		(width 0.13462)
		(layer "F.Cu")
		(net "P5E_PEX1_STN0_RX_DP<11>")
	)
	(segment
		(start 181.598062 -148.592286)
		(end 181.302914 -148.887434)
		(width 0.13462)
		(layer "F.Cu")
		(net "P5E_PEX1_STN0_RX_DP<11>")
	)
	(segment
		(start 185.20283 -150.114)
		(end 185.20283 -150.23973)
		(width 0.1651)
		(layer "In5.Cu")
		(net "P5E_PEX1_STN0_RX_DP<11>")
	)
	(segment
		(start 181.593744 -148.596604)
		(end 183.685434 -148.596604)
		(width 0.1651)
		(layer "In5.Cu")
		(net "P5E_PEX1_STN0_RX_DP<11>")
	)
	(segment
		(start 191.092836 -161.107882)
		(end 191.092836 -161.108136)
		(width 0.1651)
		(layer "In5.Cu")
		(net "P5E_PEX1_STN0_RX_DP<11>")
	)
	(segment
		(start 194.179698 -271.600168)
		(end 194.179698 -273.45513)
		(width 0.1143)
		(layer "In5.Cu")
		(net "P5E_PEX1_STN0_RX_DP<11>")
	)
	(segment
		(start 191.093344 -161.111946)
		(end 191.136016 -161.304478)
		(width 0.1651)
		(layer "In5.Cu")
		(net "P5E_PEX1_STN0_RX_DP<11>")
	)
	(segment
		(start 191.049656 -160.910778)
		(end 191.092836 -161.107882)
		(width 0.1651)
		(layer "In5.Cu")
		(net "P5E_PEX1_STN0_RX_DP<11>")
	)
	(segment
		(start 183.685434 -148.596604)
		(end 184.376568 -149.287738)
		(width 0.1651)
		(layer "In5.Cu")
		(net "P5E_PEX1_STN0_RX_DP<11>")
	)
	(segment
		(start 189.85103 -158.044388)
		(end 191.049656 -160.910778)
		(width 0.1651)
		(layer "In5.Cu")
		(net "P5E_PEX1_STN0_RX_DP<11>")
	)
	(segment
		(start 184.376568 -149.287738)
		(end 184.376568 -149.413468)
		(width 0.1651)
		(layer "In5.Cu")
		(net "P5E_PEX1_STN0_RX_DP<11>")
	)
	(segment
		(start 191.136016 -161.304478)
		(end 194.641216 -260.519164)
		(width 0.1651)
		(layer "In5.Cu")
		(net "P5E_PEX1_STN0_RX_DP<11>")
	)
	(segment
		(start 185.20283 -150.23973)
		(end 185.55335 -150.59025)
		(width 0.1651)
		(layer "In5.Cu")
		(net "P5E_PEX1_STN0_RX_DP<11>")
	)
	(segment
		(start 184.852818 -149.763988)
		(end 185.20283 -150.114)
		(width 0.1651)
		(layer "In5.Cu")
		(net "P5E_PEX1_STN0_RX_DP<11>")
	)
	(segment
		(start 194.133978 -271.554448)
		(end 194.179698 -271.600168)
		(width 0.1143)
		(layer "In5.Cu")
		(net "P5E_PEX1_STN0_RX_DP<11>")
	)
	(segment
		(start 187.72378 -154.844242)
		(end 189.85103 -158.044388)
		(width 0.1651)
		(layer "In5.Cu")
		(net "P5E_PEX1_STN0_RX_DP<11>")
	)
	(segment
		(start 186.14517 -151.05634)
		(end 187.72378 -154.844242)
		(width 0.1651)
		(layer "In5.Cu")
		(net "P5E_PEX1_STN0_RX_DP<11>")
	)
	(segment
		(start 194.179698 -273.45513)
		(end 194.394582 -273.670014)
		(width 0.1143)
		(layer "In5.Cu")
		(net "P5E_PEX1_STN0_RX_DP<11>")
	)
	(segment
		(start 185.55335 -150.59025)
		(end 185.67908 -150.59025)
		(width 0.1651)
		(layer "In5.Cu")
		(net "P5E_PEX1_STN0_RX_DP<11>")
	)
	(segment
		(start 194.394582 -273.670014)
		(end 194.635374 -273.670014)
		(width 0.1143)
		(layer "In5.Cu")
		(net "P5E_PEX1_STN0_RX_DP<11>")
	)
	(segment
		(start 191.092836 -161.108136)
		(end 191.092582 -161.108136)
		(width 0.1651)
		(layer "In5.Cu")
		(net "P5E_PEX1_STN0_RX_DP<11>")
	)
	(segment
		(start 194.133978 -271.526)
		(end 194.133978 -271.554448)
		(width 0.1143)
		(layer "In5.Cu")
		(net "P5E_PEX1_STN0_RX_DP<11>")
	)
	(segment
		(start 185.67908 -150.59025)
		(end 186.14517 -151.05634)
		(width 0.1651)
		(layer "In5.Cu")
		(net "P5E_PEX1_STN0_RX_DP<11>")
	)
	(segment
		(start 184.727088 -149.763988)
		(end 184.852818 -149.763988)
		(width 0.1651)
		(layer "In5.Cu")
		(net "P5E_PEX1_STN0_RX_DP<11>")
	)
	(segment
		(start 194.133978 -270.887444)
		(end 194.133978 -271.526)
		(width 0.1651)
		(layer "In5.Cu")
		(net "P5E_PEX1_STN0_RX_DP<11>")
	)
	(segment
		(start 181.302914 -148.887434)
		(end 181.593744 -148.596604)
		(width 0.1651)
		(layer "In5.Cu")
		(net "P5E_PEX1_STN0_RX_DP<11>")
	)
	(segment
		(start 194.641216 -260.519164)
		(end 194.676014 -268.129258)
		(width 0.1651)
		(layer "In5.Cu")
		(net "P5E_PEX1_STN0_RX_DP<11>")
	)
	(segment
		(start 194.635374 -273.670014)
		(end 194.749674 -273.784314)
		(width 0.1143)
		(layer "In5.Cu")
		(net "P5E_PEX1_STN0_RX_DP<11>")
	)
	(segment
		(start 191.092582 -161.108136)
		(end 191.093344 -161.111946)
		(width 0.1651)
		(layer "In5.Cu")
		(net "P5E_PEX1_STN0_RX_DP<11>")
	)
	(segment
		(start 194.676014 -268.129258)
		(end 194.133978 -270.887444)
		(width 0.1651)
		(layer "In5.Cu")
		(net "P5E_PEX1_STN0_RX_DP<11>")
	)
	(segment
		(start 184.376568 -149.413468)
		(end 184.727088 -149.763988)
		(width 0.1651)
		(layer "In5.Cu")
		(net "P5E_PEX1_STN0_RX_DP<11>")
	)
	(segment
		(start 194.749674 -273.784314)
		(end 194.749674 -274.049744)
		(width 0.1143)
		(layer "In5.Cu")
		(net "P5E_PEX1_STN0_RX_DP<11>")
	)
	(segment
		(start 184.757314 -130.044952)
		(end 184.26938 -130.044952)
		(width 0.13462)
		(layer "F.Cu")
		(net "P5E_PEX1_STN0_RX_DN<4>")
	)
	(segment
		(start 184.26938 -130.044952)
		(end 184.106566 -130.207766)
		(width 0.13462)
		(layer "F.Cu")
		(net "P5E_PEX1_STN0_RX_DN<4>")
	)
	(segment
		(start 183.451246 -130.207766)
		(end 183.157114 -129.913634)
		(width 0.13462)
		(layer "F.Cu")
		(net "P5E_PEX1_STN0_RX_DN<4>")
	)
	(segment
		(start 184.106566 -130.207766)
		(end 183.451246 -130.207766)
		(width 0.13462)
		(layer "F.Cu")
		(net "P5E_PEX1_STN0_RX_DN<4>")
	)
	(segment
		(start 198.169022 -148.308314)
		(end 199.296528 -149.578568)
		(width 0.1651)
		(layer "In5.Cu")
		(net "P5E_PEX1_STN0_RX_DN<4>")
	)
	(segment
		(start 183.876442 -130.204464)
		(end 190.061342 -133.472428)
		(width 0.1651)
		(layer "In5.Cu")
		(net "P5E_PEX1_STN0_RX_DN<4>")
	)
	(segment
		(start 194.669664 -138.063478)
		(end 195.43141 -139.993624)
		(width 0.1651)
		(layer "In5.Cu")
		(net "P5E_PEX1_STN0_RX_DN<4>")
	)
	(segment
		(start 196.270118 -284.25267)
		(end 196.270118 -284.385512)
		(width 0.1143)
		(layer "In5.Cu")
		(net "P5E_PEX1_STN0_RX_DN<4>")
	)
	(segment
		(start 201.80554 -151.490172)
		(end 202.17257 -168.331642)
		(width 0.1651)
		(layer "In5.Cu")
		(net "P5E_PEX1_STN0_RX_DN<4>")
	)
	(segment
		(start 183.157114 -129.913634)
		(end 183.447944 -130.204464)
		(width 0.1651)
		(layer "In5.Cu")
		(net "P5E_PEX1_STN0_RX_DN<4>")
	)
	(segment
		(start 201.440288 -150.649178)
		(end 201.80554 -151.490172)
		(width 0.1651)
		(layer "In5.Cu")
		(net "P5E_PEX1_STN0_RX_DN<4>")
	)
	(segment
		(start 211.875624 -269.73022)
		(end 211.775548 -272.573242)
		(width 0.1651)
		(layer "In5.Cu")
		(net "P5E_PEX1_STN0_RX_DN<4>")
	)
	(segment
		(start 200.024746 -284.165802)
		(end 199.996298 -284.165802)
		(width 0.1143)
		(layer "In5.Cu")
		(net "P5E_PEX1_STN0_RX_DN<4>")
	)
	(segment
		(start 202.232006 -283.398722)
		(end 201.139044 -284.165802)
		(width 0.1651)
		(layer "In5.Cu")
		(net "P5E_PEX1_STN0_RX_DN<4>")
	)
	(segment
		(start 201.139044 -284.165802)
		(end 200.024746 -284.165802)
		(width 0.1651)
		(layer "In5.Cu")
		(net "P5E_PEX1_STN0_RX_DN<4>")
	)
	(segment
		(start 196.402706 -284.120082)
		(end 196.270118 -284.25267)
		(width 0.1143)
		(layer "In5.Cu")
		(net "P5E_PEX1_STN0_RX_DN<4>")
	)
	(segment
		(start 201.570844 -232.2322)
		(end 203.44638 -240.890298)
		(width 0.1651)
		(layer "In5.Cu")
		(net "P5E_PEX1_STN0_RX_DN<4>")
	)
	(segment
		(start 199.950578 -284.120082)
		(end 196.402706 -284.120082)
		(width 0.1143)
		(layer "In5.Cu")
		(net "P5E_PEX1_STN0_RX_DN<4>")
	)
	(segment
		(start 196.57822 -147.649184)
		(end 196.921374 -148.009864)
		(width 0.1651)
		(layer "In5.Cu")
		(net "P5E_PEX1_STN0_RX_DN<4>")
	)
	(segment
		(start 196.270118 -284.385512)
		(end 196.384418 -284.499812)
		(width 0.1143)
		(layer "In5.Cu")
		(net "P5E_PEX1_STN0_RX_DN<4>")
	)
	(segment
		(start 211.775548 -272.573242)
		(end 209.817462 -276.06625)
		(width 0.1651)
		(layer "In5.Cu")
		(net "P5E_PEX1_STN0_RX_DN<4>")
	)
	(segment
		(start 183.447944 -130.204464)
		(end 183.876442 -130.204464)
		(width 0.1651)
		(layer "In5.Cu")
		(net "P5E_PEX1_STN0_RX_DN<4>")
	)
	(segment
		(start 209.817462 -276.06625)
		(end 202.232006 -283.398722)
		(width 0.1651)
		(layer "In5.Cu")
		(net "P5E_PEX1_STN0_RX_DN<4>")
	)
	(segment
		(start 203.44638 -240.890298)
		(end 211.875624 -269.73022)
		(width 0.1651)
		(layer "In5.Cu")
		(net "P5E_PEX1_STN0_RX_DN<4>")
	)
	(segment
		(start 193.858134 -136.865868)
		(end 194.669664 -138.063478)
		(width 0.1651)
		(layer "In5.Cu")
		(net "P5E_PEX1_STN0_RX_DN<4>")
	)
	(segment
		(start 195.43141 -139.993624)
		(end 196.57822 -147.649184)
		(width 0.1651)
		(layer "In5.Cu")
		(net "P5E_PEX1_STN0_RX_DN<4>")
	)
	(segment
		(start 199.296528 -149.578568)
		(end 201.440288 -150.649178)
		(width 0.1651)
		(layer "In5.Cu")
		(net "P5E_PEX1_STN0_RX_DN<4>")
	)
	(segment
		(start 202.17257 -168.331642)
		(end 201.570844 -232.2322)
		(width 0.1651)
		(layer "In5.Cu")
		(net "P5E_PEX1_STN0_RX_DN<4>")
	)
	(segment
		(start 196.921374 -148.009864)
		(end 198.169022 -148.308314)
		(width 0.1651)
		(layer "In5.Cu")
		(net "P5E_PEX1_STN0_RX_DN<4>")
	)
	(segment
		(start 190.061342 -133.472428)
		(end 193.858134 -136.865868)
		(width 0.1651)
		(layer "In5.Cu")
		(net "P5E_PEX1_STN0_RX_DN<4>")
	)
	(segment
		(start 199.996298 -284.165802)
		(end 199.950578 -284.120082)
		(width 0.1143)
		(layer "In5.Cu")
		(net "P5E_PEX1_STN0_RX_DN<4>")
	)
	(segment
		(start 196.384418 -284.499812)
		(end 196.649848 -284.499812)
		(width 0.1143)
		(layer "In5.Cu")
		(net "P5E_PEX1_STN0_RX_DN<4>")
	)
	(segment
		(start 189.845696 -121.234962)
		(end 190.00851 -121.072148)
		(width 0.13462)
		(layer "F.Cu")
		(net "P5E_PEX1_STN0_TX_C_DP<1>")
	)
	(segment
		(start 189.357508 -121.234962)
		(end 189.845696 -121.234962)
		(width 0.13462)
		(layer "F.Cu")
		(net "P5E_PEX1_STN0_TX_C_DP<1>")
	)
	(segment
		(start 190.00851 -121.072148)
		(end 198.175626 -121.072148)
		(width 0.13462)
		(layer "F.Cu")
		(net "P5E_PEX1_STN0_TX_C_DP<1>")
	)
	(segment
		(start 198.175626 -121.072148)
		(end 198.49465 -121.391172)
		(width 0.13462)
		(layer "F.Cu")
		(net "P5E_PEX1_STN0_TX_C_DP<1>")
	)
	(segment
		(start 189.845696 -132.444998)
		(end 190.00851 -132.282184)
		(width 0.13462)
		(layer "F.Cu")
		(net "P5E_PEX1_STN0_TX_C_DP<5>")
	)
	(segment
		(start 190.00851 -132.282184)
		(end 198.175626 -132.282184)
		(width 0.13462)
		(layer "F.Cu")
		(net "P5E_PEX1_STN0_TX_C_DP<5>")
	)
	(segment
		(start 189.357508 -132.444998)
		(end 189.845696 -132.444998)
		(width 0.13462)
		(layer "F.Cu")
		(net "P5E_PEX1_STN0_TX_C_DP<5>")
	)
	(segment
		(start 198.175626 -132.282184)
		(end 198.49465 -132.601208)
		(width 0.13462)
		(layer "F.Cu")
		(net "P5E_PEX1_STN0_TX_C_DP<5>")
	)
	(segment
		(start 184.106566 -132.282184)
		(end 181.598062 -132.282184)
		(width 0.13462)
		(layer "F.Cu")
		(net "P5E_PEX1_STN0_RX_DP<5>")
	)
	(segment
		(start 184.26938 -132.444998)
		(end 184.106566 -132.282184)
		(width 0.13462)
		(layer "F.Cu")
		(net "P5E_PEX1_STN0_RX_DP<5>")
	)
	(segment
		(start 181.598062 -132.282184)
		(end 181.302914 -132.577332)
		(width 0.13462)
		(layer "F.Cu")
		(net "P5E_PEX1_STN0_RX_DP<5>")
	)
	(segment
		(start 184.757314 -132.444998)
		(end 184.26938 -132.444998)
		(width 0.13462)
		(layer "F.Cu")
		(net "P5E_PEX1_STN0_RX_DP<5>")
	)
	(segment
		(start 200.666858 -282.933902)
		(end 200.017634 -282.933902)
		(width 0.1651)
		(layer "In5.Cu")
		(net "P5E_PEX1_STN0_RX_DP<5>")
	)
	(segment
		(start 188.64834 -135.068564)
		(end 189.091316 -135.291068)
		(width 0.1651)
		(layer "In5.Cu")
		(net "P5E_PEX1_STN0_RX_DP<5>")
	)
	(segment
		(start 184.238138 -132.726938)
		(end 184.288938 -132.880354)
		(width 0.1651)
		(layer "In5.Cu")
		(net "P5E_PEX1_STN0_RX_DP<5>")
	)
	(segment
		(start 183.36006 -132.286502)
		(end 184.237884 -132.727192)
		(width 0.1651)
		(layer "In5.Cu")
		(net "P5E_PEX1_STN0_RX_DP<5>")
	)
	(segment
		(start 187.507372 -134.368032)
		(end 187.558426 -134.521448)
		(width 0.1651)
		(layer "In5.Cu")
		(net "P5E_PEX1_STN0_RX_DP<5>")
	)
	(segment
		(start 191.417702 -136.747504)
		(end 191.577214 -136.72185)
		(width 0.1651)
		(layer "In5.Cu")
		(net "P5E_PEX1_STN0_RX_DP<5>")
	)
	(segment
		(start 186.417458 -133.82117)
		(end 186.468512 -133.974586)
		(width 0.1651)
		(layer "In5.Cu")
		(net "P5E_PEX1_STN0_RX_DP<5>")
	)
	(segment
		(start 200.017634 -282.933902)
		(end 199.989186 -282.933902)
		(width 0.1143)
		(layer "In5.Cu")
		(net "P5E_PEX1_STN0_RX_DP<5>")
	)
	(segment
		(start 192.798954 -137.604246)
		(end 193.465958 -138.618976)
		(width 0.1651)
		(layer "In5.Cu")
		(net "P5E_PEX1_STN0_RX_DP<5>")
	)
	(segment
		(start 189.091316 -135.291068)
		(end 189.244732 -135.240014)
		(width 0.1651)
		(layer "In5.Cu")
		(net "P5E_PEX1_STN0_RX_DP<5>")
	)
	(segment
		(start 185.97499 -133.599174)
		(end 186.417458 -133.82117)
		(width 0.1651)
		(layer "In5.Cu")
		(net "P5E_PEX1_STN0_RX_DP<5>")
	)
	(segment
		(start 190.99022 -136.29767)
		(end 191.015874 -136.457182)
		(width 0.1651)
		(layer "In5.Cu")
		(net "P5E_PEX1_STN0_RX_DP<5>")
	)
	(segment
		(start 181.593744 -132.286502)
		(end 183.36006 -132.286502)
		(width 0.1651)
		(layer "In5.Cu")
		(net "P5E_PEX1_STN0_RX_DP<5>")
	)
	(segment
		(start 189.244732 -135.240014)
		(end 190.166244 -135.702548)
		(width 0.1651)
		(layer "In5.Cu")
		(net "P5E_PEX1_STN0_RX_DP<5>")
	)
	(segment
		(start 186.911488 -134.19709)
		(end 187.064904 -134.146036)
		(width 0.1651)
		(layer "In5.Cu")
		(net "P5E_PEX1_STN0_RX_DP<5>")
	)
	(segment
		(start 195.720462 -151.399748)
		(end 195.720716 -151.400002)
		(width 0.1651)
		(layer "In5.Cu")
		(net "P5E_PEX1_STN0_RX_DP<5>")
	)
	(segment
		(start 193.465958 -138.618976)
		(end 193.731388 -139.23772)
		(width 0.1651)
		(layer "In5.Cu")
		(net "P5E_PEX1_STN0_RX_DP<5>")
	)
	(segment
		(start 181.302914 -132.577332)
		(end 181.593744 -132.286502)
		(width 0.1651)
		(layer "In5.Cu")
		(net "P5E_PEX1_STN0_RX_DP<5>")
	)
	(segment
		(start 195.720716 -151.400002)
		(end 197.10146 -160.728406)
		(width 0.1651)
		(layer "In5.Cu")
		(net "P5E_PEX1_STN0_RX_DP<5>")
	)
	(segment
		(start 210.548982 -272.229834)
		(end 208.846166 -275.243798)
		(width 0.1651)
		(layer "In5.Cu")
		(net "P5E_PEX1_STN0_RX_DP<5>")
	)
	(segment
		(start 199.313546 -222.619316)
		(end 200.35012 -233.359452)
		(width 0.1651)
		(layer "In5.Cu")
		(net "P5E_PEX1_STN0_RX_DP<5>")
	)
	(segment
		(start 210.600798 -270.270224)
		(end 210.548982 -272.229834)
		(width 0.1651)
		(layer "In5.Cu")
		(net "P5E_PEX1_STN0_RX_DP<5>")
	)
	(segment
		(start 194.339718 -142.071598)
		(end 195.720462 -151.39924)
		(width 0.1651)
		(layer "In5.Cu")
		(net "P5E_PEX1_STN0_RX_DP<5>")
	)
	(segment
		(start 199.943466 -282.979622)
		(end 198.19493 -282.979622)
		(width 0.1143)
		(layer "In5.Cu")
		(net "P5E_PEX1_STN0_RX_DP<5>")
	)
	(segment
		(start 197.979792 -283.435552)
		(end 197.865492 -283.549852)
		(width 0.1143)
		(layer "In5.Cu")
		(net "P5E_PEX1_STN0_RX_DP<5>")
	)
	(segment
		(start 187.064904 -134.146036)
		(end 187.507372 -134.368032)
		(width 0.1651)
		(layer "In5.Cu")
		(net "P5E_PEX1_STN0_RX_DP<5>")
	)
	(segment
		(start 197.865492 -283.549852)
		(end 197.600062 -283.549852)
		(width 0.1143)
		(layer "In5.Cu")
		(net "P5E_PEX1_STN0_RX_DP<5>")
	)
	(segment
		(start 185.327798 -133.274054)
		(end 185.378852 -133.42747)
		(width 0.1651)
		(layer "In5.Cu")
		(net "P5E_PEX1_STN0_RX_DP<5>")
	)
	(segment
		(start 185.378852 -133.42747)
		(end 185.821574 -133.649974)
		(width 0.1651)
		(layer "In5.Cu")
		(net "P5E_PEX1_STN0_RX_DP<5>")
	)
	(segment
		(start 197.10146 -160.728406)
		(end 199.313546 -222.619316)
		(width 0.1651)
		(layer "In5.Cu")
		(net "P5E_PEX1_STN0_RX_DP<5>")
	)
	(segment
		(start 184.237884 -132.727192)
		(end 184.238138 -132.726938)
		(width 0.1651)
		(layer "In5.Cu")
		(net "P5E_PEX1_STN0_RX_DP<5>")
	)
	(segment
		(start 197.979792 -283.19476)
		(end 197.979792 -283.435552)
		(width 0.1143)
		(layer "In5.Cu")
		(net "P5E_PEX1_STN0_RX_DP<5>")
	)
	(segment
		(start 184.731914 -133.102858)
		(end 184.88533 -133.052058)
		(width 0.1651)
		(layer "In5.Cu")
		(net "P5E_PEX1_STN0_RX_DP<5>")
	)
	(segment
		(start 201.496676 -282.388056)
		(end 200.666858 -282.933902)
		(width 0.1651)
		(layer "In5.Cu")
		(net "P5E_PEX1_STN0_RX_DP<5>")
	)
	(segment
		(start 202.975464 -244.204744)
		(end 210.600798 -270.270224)
		(width 0.1651)
		(layer "In5.Cu")
		(net "P5E_PEX1_STN0_RX_DP<5>")
	)
	(segment
		(start 208.846166 -275.243798)
		(end 201.496676 -282.388056)
		(width 0.1651)
		(layer "In5.Cu")
		(net "P5E_PEX1_STN0_RX_DP<5>")
	)
	(segment
		(start 188.154818 -134.693152)
		(end 188.597286 -134.915148)
		(width 0.1651)
		(layer "In5.Cu")
		(net "P5E_PEX1_STN0_RX_DP<5>")
	)
	(segment
		(start 198.19493 -282.979622)
		(end 197.979792 -283.19476)
		(width 0.1143)
		(layer "In5.Cu")
		(net "P5E_PEX1_STN0_RX_DP<5>")
	)
	(segment
		(start 190.166244 -135.702548)
		(end 190.99022 -136.29767)
		(width 0.1651)
		(layer "In5.Cu")
		(net "P5E_PEX1_STN0_RX_DP<5>")
	)
	(segment
		(start 184.288938 -132.880354)
		(end 184.731914 -133.102858)
		(width 0.1651)
		(layer "In5.Cu")
		(net "P5E_PEX1_STN0_RX_DP<5>")
	)
	(segment
		(start 188.597286 -134.915148)
		(end 188.64834 -135.068564)
		(width 0.1651)
		(layer "In5.Cu")
		(net "P5E_PEX1_STN0_RX_DP<5>")
	)
	(segment
		(start 187.558426 -134.521448)
		(end 188.001148 -134.743952)
		(width 0.1651)
		(layer "In5.Cu")
		(net "P5E_PEX1_STN0_RX_DP<5>")
	)
	(segment
		(start 191.577214 -136.72185)
		(end 192.798954 -137.604246)
		(width 0.1651)
		(layer "In5.Cu")
		(net "P5E_PEX1_STN0_RX_DP<5>")
	)
	(segment
		(start 185.821574 -133.649974)
		(end 185.97499 -133.599174)
		(width 0.1651)
		(layer "In5.Cu")
		(net "P5E_PEX1_STN0_RX_DP<5>")
	)
	(segment
		(start 186.468512 -133.974586)
		(end 186.911488 -134.19709)
		(width 0.1651)
		(layer "In5.Cu")
		(net "P5E_PEX1_STN0_RX_DP<5>")
	)
	(segment
		(start 188.001148 -134.743952)
		(end 188.154818 -134.693152)
		(width 0.1651)
		(layer "In5.Cu")
		(net "P5E_PEX1_STN0_RX_DP<5>")
	)
	(segment
		(start 195.720462 -151.39924)
		(end 195.720462 -151.399748)
		(width 0.1651)
		(layer "In5.Cu")
		(net "P5E_PEX1_STN0_RX_DP<5>")
	)
	(segment
		(start 193.731388 -139.23772)
		(end 194.339718 -142.071598)
		(width 0.1651)
		(layer "In5.Cu")
		(net "P5E_PEX1_STN0_RX_DP<5>")
	)
	(segment
		(start 184.88533 -133.052058)
		(end 185.327798 -133.274054)
		(width 0.1651)
		(layer "In5.Cu")
		(net "P5E_PEX1_STN0_RX_DP<5>")
	)
	(segment
		(start 199.989186 -282.933902)
		(end 199.943466 -282.979622)
		(width 0.1143)
		(layer "In5.Cu")
		(net "P5E_PEX1_STN0_RX_DP<5>")
	)
	(segment
		(start 200.35012 -233.359452)
		(end 202.975464 -244.204744)
		(width 0.1651)
		(layer "In5.Cu")
		(net "P5E_PEX1_STN0_RX_DP<5>")
	)
	(segment
		(start 191.015874 -136.457182)
		(end 191.417702 -136.747504)
		(width 0.1651)
		(layer "In5.Cu")
		(net "P5E_PEX1_STN0_RX_DP<5>")
	)
	(segment
		(start 190.00851 -132.007864)
		(end 198.173594 -132.007864)
		(width 0.13462)
		(layer "F.Cu")
		(net "P5E_PEX1_STN0_TX_C_DN<5>")
	)
	(segment
		(start 189.357508 -131.84505)
		(end 189.845696 -131.84505)
		(width 0.13462)
		(layer "F.Cu")
		(net "P5E_PEX1_STN0_TX_C_DN<5>")
	)
	(segment
		(start 198.173594 -132.007864)
		(end 198.49465 -131.686808)
		(width 0.13462)
		(layer "F.Cu")
		(net "P5E_PEX1_STN0_TX_C_DN<5>")
	)
	(segment
		(start 189.845696 -131.84505)
		(end 190.00851 -132.007864)
		(width 0.13462)
		(layer "F.Cu")
		(net "P5E_PEX1_STN0_TX_C_DN<5>")
	)
	(segment
		(start 184.269126 -118.834916)
		(end 184.106312 -118.99773)
		(width 0.13462)
		(layer "F.Cu")
		(net "P5E_PEX1_STN0_RX_DN<0>")
	)
	(segment
		(start 183.451246 -118.99773)
		(end 183.157114 -118.703598)
		(width 0.13462)
		(layer "F.Cu")
		(net "P5E_PEX1_STN0_RX_DN<0>")
	)
	(segment
		(start 184.106312 -118.99773)
		(end 183.451246 -118.99773)
		(width 0.13462)
		(layer "F.Cu")
		(net "P5E_PEX1_STN0_RX_DN<0>")
	)
	(segment
		(start 184.757314 -118.834916)
		(end 184.269126 -118.834916)
		(width 0.13462)
		(layer "F.Cu")
		(net "P5E_PEX1_STN0_RX_DN<0>")
	)
	(segment
		(start 205.753462 -149.82825)
		(end 206.20609 -168.524174)
		(width 0.1651)
		(layer "In5.Cu")
		(net "P5E_PEX1_STN0_RX_DN<0>")
	)
	(segment
		(start 200.024746 -287.965896)
		(end 199.996298 -287.965896)
		(width 0.1143)
		(layer "In5.Cu")
		(net "P5E_PEX1_STN0_RX_DN<0>")
	)
	(segment
		(start 183.983122 -118.994428)
		(end 188.768736 -120.97512)
		(width 0.1651)
		(layer "In5.Cu")
		(net "P5E_PEX1_STN0_RX_DN<0>")
	)
	(segment
		(start 205.539848 -231.87533)
		(end 207.06715 -239.218724)
		(width 0.1651)
		(layer "In5.Cu")
		(net "P5E_PEX1_STN0_RX_DN<0>")
	)
	(segment
		(start 196.270118 -288.185606)
		(end 196.384418 -288.299906)
		(width 0.1143)
		(layer "In5.Cu")
		(net "P5E_PEX1_STN0_RX_DN<0>")
	)
	(segment
		(start 183.447944 -118.994428)
		(end 183.983122 -118.994428)
		(width 0.1651)
		(layer "In5.Cu")
		(net "P5E_PEX1_STN0_RX_DN<0>")
	)
	(segment
		(start 215.588596 -273.725132)
		(end 212.9409 -278.399748)
		(width 0.1651)
		(layer "In5.Cu")
		(net "P5E_PEX1_STN0_RX_DN<0>")
	)
	(segment
		(start 212.9409 -278.399748)
		(end 203.834492 -287.19272)
		(width 0.1651)
		(layer "In5.Cu")
		(net "P5E_PEX1_STN0_RX_DN<0>")
	)
	(segment
		(start 205.355952 -145.583656)
		(end 205.753462 -149.82825)
		(width 0.1651)
		(layer "In5.Cu")
		(net "P5E_PEX1_STN0_RX_DN<0>")
	)
	(segment
		(start 196.384418 -288.299906)
		(end 196.649848 -288.299906)
		(width 0.1143)
		(layer "In5.Cu")
		(net "P5E_PEX1_STN0_RX_DN<0>")
	)
	(segment
		(start 215.774524 -269.124938)
		(end 215.588596 -273.725132)
		(width 0.1651)
		(layer "In5.Cu")
		(net "P5E_PEX1_STN0_RX_DN<0>")
	)
	(segment
		(start 183.157114 -118.703598)
		(end 183.447944 -118.994428)
		(width 0.1651)
		(layer "In5.Cu")
		(net "P5E_PEX1_STN0_RX_DN<0>")
	)
	(segment
		(start 199.950578 -287.920176)
		(end 196.402706 -287.920176)
		(width 0.1143)
		(layer "In5.Cu")
		(net "P5E_PEX1_STN0_RX_DN<0>")
	)
	(segment
		(start 196.270118 -288.052764)
		(end 196.270118 -288.185606)
		(width 0.1143)
		(layer "In5.Cu")
		(net "P5E_PEX1_STN0_RX_DN<0>")
	)
	(segment
		(start 202.276202 -131.877562)
		(end 205.355952 -145.583656)
		(width 0.1651)
		(layer "In5.Cu")
		(net "P5E_PEX1_STN0_RX_DN<0>")
	)
	(segment
		(start 202.608942 -287.965896)
		(end 200.024746 -287.965896)
		(width 0.1651)
		(layer "In5.Cu")
		(net "P5E_PEX1_STN0_RX_DN<0>")
	)
	(segment
		(start 196.402706 -287.920176)
		(end 196.270118 -288.052764)
		(width 0.1143)
		(layer "In5.Cu")
		(net "P5E_PEX1_STN0_RX_DN<0>")
	)
	(segment
		(start 190.292736 -122.49404)
		(end 201.489056 -130.84302)
		(width 0.1651)
		(layer "In5.Cu")
		(net "P5E_PEX1_STN0_RX_DN<0>")
	)
	(segment
		(start 206.20609 -168.524174)
		(end 205.539848 -231.87533)
		(width 0.1651)
		(layer "In5.Cu")
		(net "P5E_PEX1_STN0_RX_DN<0>")
	)
	(segment
		(start 188.768736 -120.97512)
		(end 190.292736 -122.49404)
		(width 0.1651)
		(layer "In5.Cu")
		(net "P5E_PEX1_STN0_RX_DN<0>")
	)
	(segment
		(start 199.996298 -287.965896)
		(end 199.950578 -287.920176)
		(width 0.1143)
		(layer "In5.Cu")
		(net "P5E_PEX1_STN0_RX_DN<0>")
	)
	(segment
		(start 203.834492 -287.19272)
		(end 202.608942 -287.965896)
		(width 0.1651)
		(layer "In5.Cu")
		(net "P5E_PEX1_STN0_RX_DN<0>")
	)
	(segment
		(start 207.06715 -239.218724)
		(end 215.774524 -269.124938)
		(width 0.1651)
		(layer "In5.Cu")
		(net "P5E_PEX1_STN0_RX_DN<0>")
	)
	(segment
		(start 201.489056 -130.84302)
		(end 202.276202 -131.877562)
		(width 0.1651)
		(layer "In5.Cu")
		(net "P5E_PEX1_STN0_RX_DN<0>")
	)
	(segment
		(start 184.26938 -146.355054)
		(end 184.106566 -146.517868)
		(width 0.13462)
		(layer "F.Cu")
		(net "P5E_PEX1_STN0_RX_DN<10>")
	)
	(segment
		(start 184.106566 -146.517868)
		(end 183.451246 -146.517868)
		(width 0.13462)
		(layer "F.Cu")
		(net "P5E_PEX1_STN0_RX_DN<10>")
	)
	(segment
		(start 184.757314 -146.355054)
		(end 184.26938 -146.355054)
		(width 0.13462)
		(layer "F.Cu")
		(net "P5E_PEX1_STN0_RX_DN<10>")
	)
	(segment
		(start 183.451246 -146.517868)
		(end 183.157114 -146.223736)
		(width 0.13462)
		(layer "F.Cu")
		(net "P5E_PEX1_STN0_RX_DN<10>")
	)
	(segment
		(start 195.423536 -275.379688)
		(end 195.585334 -275.379688)
		(width 0.1143)
		(layer "In5.Cu")
		(net "P5E_PEX1_STN0_RX_DN<10>")
	)
	(segment
		(start 195.892166 -260.494272)
		(end 195.927726 -268.182852)
		(width 0.1651)
		(layer "In5.Cu")
		(net "P5E_PEX1_STN0_RX_DN<10>")
	)
	(segment
		(start 195.927726 -268.182852)
		(end 195.365878 -271.041114)
		(width 0.1651)
		(layer "In5.Cu")
		(net "P5E_PEX1_STN0_RX_DN<10>")
	)
	(segment
		(start 195.699634 -275.265388)
		(end 195.699634 -274.999958)
		(width 0.1143)
		(layer "In5.Cu")
		(net "P5E_PEX1_STN0_RX_DN<10>")
	)
	(segment
		(start 195.365878 -271.570958)
		(end 195.365878 -271.599406)
		(width 0.1143)
		(layer "In5.Cu")
		(net "P5E_PEX1_STN0_RX_DN<10>")
	)
	(segment
		(start 190.930022 -155.949396)
		(end 191.264032 -156.471112)
		(width 0.1651)
		(layer "In5.Cu")
		(net "P5E_PEX1_STN0_RX_DN<10>")
	)
	(segment
		(start 184.04586 -146.514566)
		(end 185.718704 -148.18741)
		(width 0.1651)
		(layer "In5.Cu")
		(net "P5E_PEX1_STN0_RX_DN<10>")
	)
	(segment
		(start 187.362338 -150.631906)
		(end 188.287406 -152.90165)
		(width 0.1651)
		(layer "In5.Cu")
		(net "P5E_PEX1_STN0_RX_DN<10>")
	)
	(segment
		(start 192.37833 -161.011616)
		(end 195.892166 -260.494272)
		(width 0.1651)
		(layer "In5.Cu")
		(net "P5E_PEX1_STN0_RX_DN<10>")
	)
	(segment
		(start 195.320158 -275.27631)
		(end 195.423536 -275.379688)
		(width 0.1143)
		(layer "In5.Cu")
		(net "P5E_PEX1_STN0_RX_DN<10>")
	)
	(segment
		(start 195.320158 -271.645126)
		(end 195.320158 -275.27631)
		(width 0.1143)
		(layer "In5.Cu")
		(net "P5E_PEX1_STN0_RX_DN<10>")
	)
	(segment
		(start 188.287406 -152.90165)
		(end 189.972442 -155.166822)
		(width 0.1651)
		(layer "In5.Cu")
		(net "P5E_PEX1_STN0_RX_DN<10>")
	)
	(segment
		(start 195.365878 -271.599406)
		(end 195.320158 -271.645126)
		(width 0.1143)
		(layer "In5.Cu")
		(net "P5E_PEX1_STN0_RX_DN<10>")
	)
	(segment
		(start 191.264032 -156.471112)
		(end 192.37833 -161.011616)
		(width 0.1651)
		(layer "In5.Cu")
		(net "P5E_PEX1_STN0_RX_DN<10>")
	)
	(segment
		(start 195.365878 -271.041114)
		(end 195.365878 -271.570958)
		(width 0.1651)
		(layer "In5.Cu")
		(net "P5E_PEX1_STN0_RX_DN<10>")
	)
	(segment
		(start 185.718704 -148.18741)
		(end 187.362338 -150.631906)
		(width 0.1651)
		(layer "In5.Cu")
		(net "P5E_PEX1_STN0_RX_DN<10>")
	)
	(segment
		(start 195.585334 -275.379688)
		(end 195.699634 -275.265388)
		(width 0.1143)
		(layer "In5.Cu")
		(net "P5E_PEX1_STN0_RX_DN<10>")
	)
	(segment
		(start 189.972442 -155.166822)
		(end 190.930022 -155.949396)
		(width 0.1651)
		(layer "In5.Cu")
		(net "P5E_PEX1_STN0_RX_DN<10>")
	)
	(segment
		(start 183.157114 -146.223736)
		(end 183.447944 -146.514566)
		(width 0.1651)
		(layer "In5.Cu")
		(net "P5E_PEX1_STN0_RX_DN<10>")
	)
	(segment
		(start 183.447944 -146.514566)
		(end 184.04586 -146.514566)
		(width 0.1651)
		(layer "In5.Cu")
		(net "P5E_PEX1_STN0_RX_DN<10>")
	)
	(segment
		(start 184.26938 -144.554956)
		(end 184.106566 -144.71777)
		(width 0.13462)
		(layer "F.Cu")
		(net "P5E_PEX1_STN0_RX_DN<9>")
	)
	(segment
		(start 184.757314 -144.554956)
		(end 184.26938 -144.554956)
		(width 0.13462)
		(layer "F.Cu")
		(net "P5E_PEX1_STN0_RX_DN<9>")
	)
	(segment
		(start 184.106566 -144.71777)
		(end 181.598062 -144.71777)
		(width 0.13462)
		(layer "F.Cu")
		(net "P5E_PEX1_STN0_RX_DN<9>")
	)
	(segment
		(start 181.597554 -144.718278)
		(end 181.302914 -144.423638)
		(width 0.13462)
		(layer "F.Cu")
		(net "P5E_PEX1_STN0_RX_DN<9>")
	)
	(segment
		(start 181.598062 -144.71777)
		(end 181.597554 -144.718278)
		(width 0.13462)
		(layer "F.Cu")
		(net "P5E_PEX1_STN0_RX_DN<9>")
	)
	(segment
		(start 181.593744 -144.714468)
		(end 183.324246 -144.714468)
		(width 0.1651)
		(layer "In5.Cu")
		(net "P5E_PEX1_STN0_RX_DN<9>")
	)
	(segment
		(start 196.373496 -273.479514)
		(end 196.535294 -273.479514)
		(width 0.1143)
		(layer "In5.Cu")
		(net "P5E_PEX1_STN0_RX_DN<9>")
	)
	(segment
		(start 196.900038 -261.973314)
		(end 196.900038 -268.288008)
		(width 0.1651)
		(layer "In5.Cu")
		(net "P5E_PEX1_STN0_RX_DN<9>")
	)
	(segment
		(start 193.317368 -160.462976)
		(end 196.900038 -261.973314)
		(width 0.1651)
		(layer "In5.Cu")
		(net "P5E_PEX1_STN0_RX_DN<9>")
	)
	(segment
		(start 184.178702 -145.071846)
		(end 186.493658 -147.418806)
		(width 0.1651)
		(layer "In5.Cu")
		(net "P5E_PEX1_STN0_RX_DN<9>")
	)
	(segment
		(start 191.938656 -155.292806)
		(end 193.317368 -160.462976)
		(width 0.1651)
		(layer "In5.Cu")
		(net "P5E_PEX1_STN0_RX_DN<9>")
	)
	(segment
		(start 196.535294 -273.479514)
		(end 196.649594 -273.365214)
		(width 0.1143)
		(layer "In5.Cu")
		(net "P5E_PEX1_STN0_RX_DN<9>")
	)
	(segment
		(start 181.302914 -144.423638)
		(end 181.593744 -144.714468)
		(width 0.1651)
		(layer "In5.Cu")
		(net "P5E_PEX1_STN0_RX_DN<9>")
	)
	(segment
		(start 196.315838 -271.554448)
		(end 196.270118 -271.600168)
		(width 0.1143)
		(layer "In5.Cu")
		(net "P5E_PEX1_STN0_RX_DN<9>")
	)
	(segment
		(start 183.324246 -144.714468)
		(end 184.178702 -145.071846)
		(width 0.1651)
		(layer "In5.Cu")
		(net "P5E_PEX1_STN0_RX_DN<9>")
	)
	(segment
		(start 196.649594 -273.365214)
		(end 196.649594 -273.099784)
		(width 0.1143)
		(layer "In5.Cu")
		(net "P5E_PEX1_STN0_RX_DN<9>")
	)
	(segment
		(start 189.18174 -152.48255)
		(end 191.938656 -155.292806)
		(width 0.1651)
		(layer "In5.Cu")
		(net "P5E_PEX1_STN0_RX_DN<9>")
	)
	(segment
		(start 188.435996 -150.41118)
		(end 189.18174 -152.48255)
		(width 0.1651)
		(layer "In5.Cu")
		(net "P5E_PEX1_STN0_RX_DN<9>")
	)
	(segment
		(start 196.900038 -268.288008)
		(end 196.315838 -271.225518)
		(width 0.1651)
		(layer "In5.Cu")
		(net "P5E_PEX1_STN0_RX_DN<9>")
	)
	(segment
		(start 186.493658 -147.418806)
		(end 188.435996 -150.41118)
		(width 0.1651)
		(layer "In5.Cu")
		(net "P5E_PEX1_STN0_RX_DN<9>")
	)
	(segment
		(start 196.315838 -271.225518)
		(end 196.315838 -271.526)
		(width 0.1651)
		(layer "In5.Cu")
		(net "P5E_PEX1_STN0_RX_DN<9>")
	)
	(segment
		(start 196.270118 -273.376136)
		(end 196.373496 -273.479514)
		(width 0.1143)
		(layer "In5.Cu")
		(net "P5E_PEX1_STN0_RX_DN<9>")
	)
	(segment
		(start 196.270118 -271.600168)
		(end 196.270118 -273.376136)
		(width 0.1143)
		(layer "In5.Cu")
		(net "P5E_PEX1_STN0_RX_DN<9>")
	)
	(segment
		(start 196.315838 -271.526)
		(end 196.315838 -271.554448)
		(width 0.1143)
		(layer "In5.Cu")
		(net "P5E_PEX1_STN0_RX_DN<9>")
	)
	(segment
		(start 184.757314 -146.955002)
		(end 184.26938 -146.955002)
		(width 0.13462)
		(layer "F.Cu")
		(net "P5E_PEX1_STN0_RX_DP<10>")
	)
	(segment
		(start 184.106566 -146.792188)
		(end 183.452262 -146.792188)
		(width 0.13462)
		(layer "F.Cu")
		(net "P5E_PEX1_STN0_RX_DP<10>")
	)
	(segment
		(start 184.26938 -146.955002)
		(end 184.106566 -146.792188)
		(width 0.13462)
		(layer "F.Cu")
		(net "P5E_PEX1_STN0_RX_DP<10>")
	)
	(segment
		(start 183.452262 -146.792188)
		(end 183.157114 -147.087336)
		(width 0.13462)
		(layer "F.Cu")
		(net "P5E_PEX1_STN0_RX_DP<10>")
	)
	(segment
		(start 195.083938 -271.013428)
		(end 195.083938 -271.570958)
		(width 0.1651)
		(layer "In5.Cu")
		(net "P5E_PEX1_STN0_RX_DP<10>")
	)
	(segment
		(start 184.279032 -147.146518)
		(end 184.279032 -147.272248)
		(width 0.1651)
		(layer "In5.Cu")
		(net "P5E_PEX1_STN0_RX_DP<10>")
	)
	(segment
		(start 190.716662 -156.139388)
		(end 191.001142 -156.583888)
		(width 0.1651)
		(layer "In5.Cu")
		(net "P5E_PEX1_STN0_RX_DP<10>")
	)
	(segment
		(start 195.645532 -268.155928)
		(end 195.083938 -271.013428)
		(width 0.1651)
		(layer "In5.Cu")
		(net "P5E_PEX1_STN0_RX_DP<10>")
	)
	(segment
		(start 184.629552 -147.622768)
		(end 184.755282 -147.622768)
		(width 0.1651)
		(layer "In5.Cu")
		(net "P5E_PEX1_STN0_RX_DP<10>")
	)
	(segment
		(start 183.447944 -146.796506)
		(end 183.92902 -146.796506)
		(width 0.1651)
		(layer "In5.Cu")
		(net "P5E_PEX1_STN0_RX_DP<10>")
	)
	(segment
		(start 195.083938 -271.570958)
		(end 195.083938 -271.599406)
		(width 0.1143)
		(layer "In5.Cu")
		(net "P5E_PEX1_STN0_RX_DP<10>")
	)
	(segment
		(start 195.699634 -275.684488)
		(end 195.699634 -275.949918)
		(width 0.1143)
		(layer "In5.Cu")
		(net "P5E_PEX1_STN0_RX_DP<10>")
	)
	(segment
		(start 185.751978 -148.901658)
		(end 186.028584 -149.313138)
		(width 0.1651)
		(layer "In5.Cu")
		(net "P5E_PEX1_STN0_RX_DP<10>")
	)
	(segment
		(start 195.129658 -275.355304)
		(end 195.344542 -275.570188)
		(width 0.1143)
		(layer "In5.Cu")
		(net "P5E_PEX1_STN0_RX_DP<10>")
	)
	(segment
		(start 188.039502 -153.04135)
		(end 189.766956 -155.363164)
		(width 0.1651)
		(layer "In5.Cu")
		(net "P5E_PEX1_STN0_RX_DP<10>")
	)
	(segment
		(start 185.50001 -148.367496)
		(end 185.776362 -148.778468)
		(width 0.1651)
		(layer "In5.Cu")
		(net "P5E_PEX1_STN0_RX_DP<10>")
	)
	(segment
		(start 192.097406 -161.050732)
		(end 195.610226 -260.49986)
		(width 0.1651)
		(layer "In5.Cu")
		(net "P5E_PEX1_STN0_RX_DP<10>")
	)
	(segment
		(start 183.92902 -146.796506)
		(end 184.279032 -147.146518)
		(width 0.1651)
		(layer "In5.Cu")
		(net "P5E_PEX1_STN0_RX_DP<10>")
	)
	(segment
		(start 195.610226 -260.49986)
		(end 195.645532 -268.155928)
		(width 0.1651)
		(layer "In5.Cu")
		(net "P5E_PEX1_STN0_RX_DP<10>")
	)
	(segment
		(start 187.112148 -150.765256)
		(end 188.039502 -153.04135)
		(width 0.1651)
		(layer "In5.Cu")
		(net "P5E_PEX1_STN0_RX_DP<10>")
	)
	(segment
		(start 185.776362 -148.778468)
		(end 185.751978 -148.901658)
		(width 0.1651)
		(layer "In5.Cu")
		(net "P5E_PEX1_STN0_RX_DP<10>")
	)
	(segment
		(start 189.766956 -155.363164)
		(end 190.716662 -156.139388)
		(width 0.1651)
		(layer "In5.Cu")
		(net "P5E_PEX1_STN0_RX_DP<10>")
	)
	(segment
		(start 186.028584 -149.313138)
		(end 186.152028 -149.337268)
		(width 0.1651)
		(layer "In5.Cu")
		(net "P5E_PEX1_STN0_RX_DP<10>")
	)
	(segment
		(start 195.585334 -275.570188)
		(end 195.699634 -275.684488)
		(width 0.1143)
		(layer "In5.Cu")
		(net "P5E_PEX1_STN0_RX_DP<10>")
	)
	(segment
		(start 195.129658 -271.645126)
		(end 195.129658 -275.355304)
		(width 0.1143)
		(layer "In5.Cu")
		(net "P5E_PEX1_STN0_RX_DP<10>")
	)
	(segment
		(start 195.083938 -271.599406)
		(end 195.129658 -271.645126)
		(width 0.1143)
		(layer "In5.Cu")
		(net "P5E_PEX1_STN0_RX_DP<10>")
	)
	(segment
		(start 183.157114 -147.087336)
		(end 183.447944 -146.796506)
		(width 0.1651)
		(layer "In5.Cu")
		(net "P5E_PEX1_STN0_RX_DP<10>")
	)
	(segment
		(start 195.344542 -275.570188)
		(end 195.585334 -275.570188)
		(width 0.1143)
		(layer "In5.Cu")
		(net "P5E_PEX1_STN0_RX_DP<10>")
	)
	(segment
		(start 186.152028 -149.337268)
		(end 187.112148 -150.765256)
		(width 0.1651)
		(layer "In5.Cu")
		(net "P5E_PEX1_STN0_RX_DP<10>")
	)
	(segment
		(start 191.001142 -156.583888)
		(end 192.097406 -161.050732)
		(width 0.1651)
		(layer "In5.Cu")
		(net "P5E_PEX1_STN0_RX_DP<10>")
	)
	(segment
		(start 184.279032 -147.272248)
		(end 184.629552 -147.622768)
		(width 0.1651)
		(layer "In5.Cu")
		(net "P5E_PEX1_STN0_RX_DP<10>")
	)
	(segment
		(start 184.755282 -147.622768)
		(end 185.50001 -148.367496)
		(width 0.1651)
		(layer "In5.Cu")
		(net "P5E_PEX1_STN0_RX_DP<10>")
	)
	(segment
		(start 198.173594 -144.71777)
		(end 198.49465 -144.396714)
		(width 0.13462)
		(layer "F.Cu")
		(net "P5E_PEX1_STN0_TX_C_DN<9>")
	)
	(segment
		(start 190.00851 -144.71777)
		(end 198.173594 -144.71777)
		(width 0.13462)
		(layer "F.Cu")
		(net "P5E_PEX1_STN0_TX_C_DN<9>")
	)
	(segment
		(start 189.845696 -144.554956)
		(end 190.00851 -144.71777)
		(width 0.13462)
		(layer "F.Cu")
		(net "P5E_PEX1_STN0_TX_C_DN<9>")
	)
	(segment
		(start 189.357508 -144.554956)
		(end 189.845696 -144.554956)
		(width 0.13462)
		(layer "F.Cu")
		(net "P5E_PEX1_STN0_TX_C_DN<9>")
	)
	(segment
		(start 184.757314 -151.755094)
		(end 184.26938 -151.755094)
		(width 0.13462)
		(layer "F.Cu")
		(net "P5E_PEX1_STN0_RX_DN<13>")
	)
	(segment
		(start 184.106566 -151.917908)
		(end 181.598062 -151.917908)
		(width 0.13462)
		(layer "F.Cu")
		(net "P5E_PEX1_STN0_RX_DN<13>")
	)
	(segment
		(start 181.598062 -151.917908)
		(end 181.597554 -151.918416)
		(width 0.13462)
		(layer "F.Cu")
		(net "P5E_PEX1_STN0_RX_DN<13>")
	)
	(segment
		(start 184.26938 -151.755094)
		(end 184.106566 -151.917908)
		(width 0.13462)
		(layer "F.Cu")
		(net "P5E_PEX1_STN0_RX_DN<13>")
	)
	(segment
		(start 181.597554 -151.918416)
		(end 181.302914 -151.623776)
		(width 0.13462)
		(layer "F.Cu")
		(net "P5E_PEX1_STN0_RX_DN<13>")
	)
	(segment
		(start 185.83148 -155.050998)
		(end 188.36513 -158.80207)
		(width 0.1651)
		(layer "In5.Cu")
		(net "P5E_PEX1_STN0_RX_DN<13>")
	)
	(segment
		(start 184.959498 -152.959054)
		(end 185.83148 -155.050998)
		(width 0.1651)
		(layer "In5.Cu")
		(net "P5E_PEX1_STN0_RX_DN<13>")
	)
	(segment
		(start 192.849754 -273.365214)
		(end 192.849754 -273.099784)
		(width 0.1143)
		(layer "In5.Cu")
		(net "P5E_PEX1_STN0_RX_DN<13>")
	)
	(segment
		(start 192.470278 -273.376136)
		(end 192.573656 -273.479514)
		(width 0.1143)
		(layer "In5.Cu")
		(net "P5E_PEX1_STN0_RX_DN<13>")
	)
	(segment
		(start 189.401704 -161.295334)
		(end 192.957704 -260.64464)
		(width 0.1651)
		(layer "In5.Cu")
		(net "P5E_PEX1_STN0_RX_DN<13>")
	)
	(segment
		(start 192.470278 -271.600168)
		(end 192.470278 -273.376136)
		(width 0.1143)
		(layer "In5.Cu")
		(net "P5E_PEX1_STN0_RX_DN<13>")
	)
	(segment
		(start 192.573656 -273.479514)
		(end 192.735454 -273.479514)
		(width 0.1143)
		(layer "In5.Cu")
		(net "P5E_PEX1_STN0_RX_DN<13>")
	)
	(segment
		(start 188.36513 -158.80207)
		(end 189.401704 -161.295334)
		(width 0.1651)
		(layer "In5.Cu")
		(net "P5E_PEX1_STN0_RX_DN<13>")
	)
	(segment
		(start 192.957704 -260.64464)
		(end 193.032888 -267.869924)
		(width 0.1651)
		(layer "In5.Cu")
		(net "P5E_PEX1_STN0_RX_DN<13>")
	)
	(segment
		(start 181.302914 -151.623776)
		(end 181.593744 -151.914606)
		(width 0.1651)
		(layer "In5.Cu")
		(net "P5E_PEX1_STN0_RX_DN<13>")
	)
	(segment
		(start 193.032888 -267.869924)
		(end 192.515998 -270.540226)
		(width 0.1651)
		(layer "In5.Cu")
		(net "P5E_PEX1_STN0_RX_DN<13>")
	)
	(segment
		(start 192.515998 -271.526)
		(end 192.515998 -271.554448)
		(width 0.1143)
		(layer "In5.Cu")
		(net "P5E_PEX1_STN0_RX_DN<13>")
	)
	(segment
		(start 181.593744 -151.914606)
		(end 183.91505 -151.914606)
		(width 0.1651)
		(layer "In5.Cu")
		(net "P5E_PEX1_STN0_RX_DN<13>")
	)
	(segment
		(start 192.515998 -270.540226)
		(end 192.515998 -271.526)
		(width 0.1651)
		(layer "In5.Cu")
		(net "P5E_PEX1_STN0_RX_DN<13>")
	)
	(segment
		(start 192.515998 -271.554448)
		(end 192.470278 -271.600168)
		(width 0.1143)
		(layer "In5.Cu")
		(net "P5E_PEX1_STN0_RX_DN<13>")
	)
	(segment
		(start 183.91505 -151.914606)
		(end 184.959498 -152.959054)
		(width 0.1651)
		(layer "In5.Cu")
		(net "P5E_PEX1_STN0_RX_DN<13>")
	)
	(segment
		(start 192.735454 -273.479514)
		(end 192.849754 -273.365214)
		(width 0.1143)
		(layer "In5.Cu")
		(net "P5E_PEX1_STN0_RX_DN<13>")
	)
	(segment
		(start 184.26938 -135.444992)
		(end 184.106566 -135.607806)
		(width 0.13462)
		(layer "F.Cu")
		(net "P5E_PEX1_STN0_RX_DN<7>")
	)
	(segment
		(start 181.597554 -135.608314)
		(end 181.302914 -135.313674)
		(width 0.13462)
		(layer "F.Cu")
		(net "P5E_PEX1_STN0_RX_DN<7>")
	)
	(segment
		(start 184.106566 -135.607806)
		(end 181.598062 -135.607806)
		(width 0.13462)
		(layer "F.Cu")
		(net "P5E_PEX1_STN0_RX_DN<7>")
	)
	(segment
		(start 184.757314 -135.444992)
		(end 184.26938 -135.444992)
		(width 0.13462)
		(layer "F.Cu")
		(net "P5E_PEX1_STN0_RX_DN<7>")
	)
	(segment
		(start 181.598062 -135.607806)
		(end 181.597554 -135.608314)
		(width 0.13462)
		(layer "F.Cu")
		(net "P5E_PEX1_STN0_RX_DN<7>")
	)
	(segment
		(start 198.273924 -281.270202)
		(end 198.170292 -281.373834)
		(width 0.1143)
		(layer "In5.Cu")
		(net "P5E_PEX1_STN0_RX_DN<7>")
	)
	(segment
		(start 189.3697 -138.752834)
		(end 189.78753 -139.464288)
		(width 0.1651)
		(layer "In5.Cu")
		(net "P5E_PEX1_STN0_RX_DN<7>")
	)
	(segment
		(start 190.063882 -140.537438)
		(end 190.921132 -141.394688)
		(width 0.1651)
		(layer "In5.Cu")
		(net "P5E_PEX1_STN0_RX_DN<7>")
	)
	(segment
		(start 200.288906 -281.315922)
		(end 200.050146 -281.315922)
		(width 0.1651)
		(layer "In5.Cu")
		(net "P5E_PEX1_STN0_RX_DN<7>")
	)
	(segment
		(start 191.105536 -141.708632)
		(end 191.105536 -141.708378)
		(width 0.1651)
		(layer "In5.Cu")
		(net "P5E_PEX1_STN0_RX_DN<7>")
	)
	(segment
		(start 195.379848 -160.455102)
		(end 195.379848 -160.476184)
		(width 0.1651)
		(layer "In5.Cu")
		(net "P5E_PEX1_STN0_RX_DN<7>")
	)
	(segment
		(start 181.302914 -135.313674)
		(end 181.593744 -135.604504)
		(width 0.1651)
		(layer "In5.Cu")
		(net "P5E_PEX1_STN0_RX_DN<7>")
	)
	(segment
		(start 181.593744 -135.604504)
		(end 183.573674 -135.604504)
		(width 0.1651)
		(layer "In5.Cu")
		(net "P5E_PEX1_STN0_RX_DN<7>")
	)
	(segment
		(start 183.573674 -135.604504)
		(end 188.06668 -137.43178)
		(width 0.1651)
		(layer "In5.Cu")
		(net "P5E_PEX1_STN0_RX_DN<7>")
	)
	(segment
		(start 189.78753 -139.464288)
		(end 189.78753 -139.870434)
		(width 0.1651)
		(layer "In5.Cu")
		(net "P5E_PEX1_STN0_RX_DN<7>")
	)
	(segment
		(start 198.170292 -281.535632)
		(end 198.284592 -281.649932)
		(width 0.1143)
		(layer "In5.Cu")
		(net "P5E_PEX1_STN0_RX_DN<7>")
	)
	(segment
		(start 198.170292 -281.373834)
		(end 198.170292 -281.535632)
		(width 0.1143)
		(layer "In5.Cu")
		(net "P5E_PEX1_STN0_RX_DN<7>")
	)
	(segment
		(start 200.050146 -281.315922)
		(end 200.021698 -281.315922)
		(width 0.1143)
		(layer "In5.Cu")
		(net "P5E_PEX1_STN0_RX_DN<7>")
	)
	(segment
		(start 188.06668 -137.43178)
		(end 189.3697 -138.752834)
		(width 0.1651)
		(layer "In5.Cu")
		(net "P5E_PEX1_STN0_RX_DN<7>")
	)
	(segment
		(start 200.772268 -280.46807)
		(end 200.498456 -281.107134)
		(width 0.1651)
		(layer "In5.Cu")
		(net "P5E_PEX1_STN0_RX_DN<7>")
	)
	(segment
		(start 198.284592 -281.649932)
		(end 198.550022 -281.649932)
		(width 0.1143)
		(layer "In5.Cu")
		(net "P5E_PEX1_STN0_RX_DN<7>")
	)
	(segment
		(start 200.853548 -276.643084)
		(end 200.772268 -280.46807)
		(width 0.1651)
		(layer "In5.Cu")
		(net "P5E_PEX1_STN0_RX_DN<7>")
	)
	(segment
		(start 199.809862 -271.010634)
		(end 200.853548 -276.643084)
		(width 0.1651)
		(layer "In5.Cu")
		(net "P5E_PEX1_STN0_RX_DN<7>")
	)
	(segment
		(start 200.498456 -281.107134)
		(end 200.288906 -281.315922)
		(width 0.1651)
		(layer "In5.Cu")
		(net "P5E_PEX1_STN0_RX_DN<7>")
	)
	(segment
		(start 199.975978 -281.270202)
		(end 198.273924 -281.270202)
		(width 0.1143)
		(layer "In5.Cu")
		(net "P5E_PEX1_STN0_RX_DN<7>")
	)
	(segment
		(start 189.78753 -139.870434)
		(end 190.063882 -140.537438)
		(width 0.1651)
		(layer "In5.Cu")
		(net "P5E_PEX1_STN0_RX_DN<7>")
	)
	(segment
		(start 198.934324 -264.832846)
		(end 199.809862 -271.010634)
		(width 0.1651)
		(layer "In5.Cu")
		(net "P5E_PEX1_STN0_RX_DN<7>")
	)
	(segment
		(start 195.379848 -160.476184)
		(end 198.934324 -264.832846)
		(width 0.1651)
		(layer "In5.Cu")
		(net "P5E_PEX1_STN0_RX_DN<7>")
	)
	(segment
		(start 190.921132 -141.394688)
		(end 191.105536 -141.708632)
		(width 0.1651)
		(layer "In5.Cu")
		(net "P5E_PEX1_STN0_RX_DN<7>")
	)
	(segment
		(start 200.021698 -281.315922)
		(end 199.975978 -281.270202)
		(width 0.1143)
		(layer "In5.Cu")
		(net "P5E_PEX1_STN0_RX_DN<7>")
	)
	(segment
		(start 195.373752 -160.449006)
		(end 195.379848 -160.455102)
		(width 0.1651)
		(layer "In5.Cu")
		(net "P5E_PEX1_STN0_RX_DN<7>")
	)
	(segment
		(start 191.10579 -141.708886)
		(end 195.373752 -160.449006)
		(width 0.1651)
		(layer "In5.Cu")
		(net "P5E_PEX1_STN0_RX_DN<7>")
	)
	(segment
		(start 191.105536 -141.708378)
		(end 191.10579 -141.708886)
		(width 0.1651)
		(layer "In5.Cu")
		(net "P5E_PEX1_STN0_RX_DN<7>")
	)
	(segment
		(start 184.106566 -148.317966)
		(end 181.598062 -148.317966)
		(width 0.13462)
		(layer "F.Cu")
		(net "P5E_PEX1_STN0_RX_DN<11>")
	)
	(segment
		(start 184.26938 -148.155152)
		(end 184.106566 -148.317966)
		(width 0.13462)
		(layer "F.Cu")
		(net "P5E_PEX1_STN0_RX_DN<11>")
	)
	(segment
		(start 181.597554 -148.318474)
		(end 181.302914 -148.023834)
		(width 0.13462)
		(layer "F.Cu")
		(net "P5E_PEX1_STN0_RX_DN<11>")
	)
	(segment
		(start 184.757314 -148.155152)
		(end 184.26938 -148.155152)
		(width 0.13462)
		(layer "F.Cu")
		(net "P5E_PEX1_STN0_RX_DN<11>")
	)
	(segment
		(start 181.598062 -148.317966)
		(end 181.597554 -148.318474)
		(width 0.13462)
		(layer "F.Cu")
		(net "P5E_PEX1_STN0_RX_DN<11>")
	)
	(segment
		(start 183.802274 -148.314664)
		(end 186.38393 -150.89632)
		(width 0.1651)
		(layer "In5.Cu")
		(net "P5E_PEX1_STN0_RX_DN<11>")
	)
	(segment
		(start 186.38393 -150.89632)
		(end 187.973716 -154.710638)
		(width 0.1651)
		(layer "In5.Cu")
		(net "P5E_PEX1_STN0_RX_DN<11>")
	)
	(segment
		(start 194.415918 -270.91513)
		(end 194.415918 -271.526)
		(width 0.1651)
		(layer "In5.Cu")
		(net "P5E_PEX1_STN0_RX_DN<11>")
	)
	(segment
		(start 194.635374 -273.479514)
		(end 194.749674 -273.365214)
		(width 0.1143)
		(layer "In5.Cu")
		(net "P5E_PEX1_STN0_RX_DN<11>")
	)
	(segment
		(start 194.370198 -271.600168)
		(end 194.370198 -273.376136)
		(width 0.1143)
		(layer "In5.Cu")
		(net "P5E_PEX1_STN0_RX_DN<11>")
	)
	(segment
		(start 191.319658 -160.825434)
		(end 191.41694 -161.269172)
		(width 0.1651)
		(layer "In5.Cu")
		(net "P5E_PEX1_STN0_RX_DN<11>")
	)
	(segment
		(start 194.923156 -260.513576)
		(end 194.958208 -268.156182)
		(width 0.1651)
		(layer "In5.Cu")
		(net "P5E_PEX1_STN0_RX_DN<11>")
	)
	(segment
		(start 190.100966 -157.91053)
		(end 191.319658 -160.825434)
		(width 0.1651)
		(layer "In5.Cu")
		(net "P5E_PEX1_STN0_RX_DN<11>")
	)
	(segment
		(start 194.370198 -273.376136)
		(end 194.473576 -273.479514)
		(width 0.1143)
		(layer "In5.Cu")
		(net "P5E_PEX1_STN0_RX_DN<11>")
	)
	(segment
		(start 194.415918 -271.554448)
		(end 194.370198 -271.600168)
		(width 0.1143)
		(layer "In5.Cu")
		(net "P5E_PEX1_STN0_RX_DN<11>")
	)
	(segment
		(start 187.973716 -154.710638)
		(end 190.100966 -157.91053)
		(width 0.1651)
		(layer "In5.Cu")
		(net "P5E_PEX1_STN0_RX_DN<11>")
	)
	(segment
		(start 181.302914 -148.023834)
		(end 181.593744 -148.314664)
		(width 0.1651)
		(layer "In5.Cu")
		(net "P5E_PEX1_STN0_RX_DN<11>")
	)
	(segment
		(start 194.415918 -271.526)
		(end 194.415918 -271.554448)
		(width 0.1143)
		(layer "In5.Cu")
		(net "P5E_PEX1_STN0_RX_DN<11>")
	)
	(segment
		(start 194.958208 -268.156182)
		(end 194.415918 -270.91513)
		(width 0.1651)
		(layer "In5.Cu")
		(net "P5E_PEX1_STN0_RX_DN<11>")
	)
	(segment
		(start 194.749674 -273.365214)
		(end 194.749674 -273.099784)
		(width 0.1143)
		(layer "In5.Cu")
		(net "P5E_PEX1_STN0_RX_DN<11>")
	)
	(segment
		(start 191.41694 -161.269172)
		(end 194.923156 -260.513576)
		(width 0.1651)
		(layer "In5.Cu")
		(net "P5E_PEX1_STN0_RX_DN<11>")
	)
	(segment
		(start 194.473576 -273.479514)
		(end 194.635374 -273.479514)
		(width 0.1143)
		(layer "In5.Cu")
		(net "P5E_PEX1_STN0_RX_DN<11>")
	)
	(segment
		(start 181.593744 -148.314664)
		(end 183.802274 -148.314664)
		(width 0.1651)
		(layer "In5.Cu")
		(net "P5E_PEX1_STN0_RX_DN<11>")
	)
	(segment
		(start 184.106566 -130.482086)
		(end 183.452262 -130.482086)
		(width 0.13462)
		(layer "F.Cu")
		(net "P5E_PEX1_STN0_RX_DP<4>")
	)
	(segment
		(start 183.452262 -130.482086)
		(end 183.157114 -130.777234)
		(width 0.13462)
		(layer "F.Cu")
		(net "P5E_PEX1_STN0_RX_DP<4>")
	)
	(segment
		(start 184.757314 -130.6449)
		(end 184.26938 -130.6449)
		(width 0.13462)
		(layer "F.Cu")
		(net "P5E_PEX1_STN0_RX_DP<4>")
	)
	(segment
		(start 184.26938 -130.6449)
		(end 184.106566 -130.482086)
		(width 0.13462)
		(layer "F.Cu")
		(net "P5E_PEX1_STN0_RX_DP<4>")
	)
	(segment
		(start 195.157344 -140.067284)
		(end 196.312536 -147.778978)
		(width 0.1651)
		(layer "In5.Cu")
		(net "P5E_PEX1_STN0_RX_DP<4>")
	)
	(segment
		(start 211.59216 -269.76578)
		(end 211.496148 -272.49501)
		(width 0.1651)
		(layer "In5.Cu")
		(net "P5E_PEX1_STN0_RX_DP<4>")
	)
	(segment
		(start 196.323712 -283.929582)
		(end 196.079618 -284.173676)
		(width 0.1143)
		(layer "In5.Cu")
		(net "P5E_PEX1_STN0_RX_DP<4>")
	)
	(segment
		(start 201.222356 -150.85568)
		(end 201.524616 -151.55164)
		(width 0.1651)
		(layer "In5.Cu")
		(net "P5E_PEX1_STN0_RX_DP<4>")
	)
	(segment
		(start 191.668146 -135.287004)
		(end 193.644012 -137.053066)
		(width 0.1651)
		(layer "In5.Cu")
		(net "P5E_PEX1_STN0_RX_DP<4>")
	)
	(segment
		(start 185.560208 -131.412996)
		(end 185.607706 -131.567682)
		(width 0.1651)
		(layer "In5.Cu")
		(net "P5E_PEX1_STN0_RX_DP<4>")
	)
	(segment
		(start 183.157114 -130.777234)
		(end 183.447944 -130.486404)
		(width 0.1651)
		(layer "In5.Cu")
		(net "P5E_PEX1_STN0_RX_DP<4>")
	)
	(segment
		(start 200.024746 -283.883862)
		(end 199.996298 -283.883862)
		(width 0.1143)
		(layer "In5.Cu")
		(net "P5E_PEX1_STN0_RX_DP<4>")
	)
	(segment
		(start 191.137286 -134.965694)
		(end 191.506602 -135.295894)
		(width 0.1651)
		(layer "In5.Cu")
		(net "P5E_PEX1_STN0_RX_DP<4>")
	)
	(segment
		(start 211.496148 -272.49501)
		(end 209.591656 -275.89226)
		(width 0.1651)
		(layer "In5.Cu")
		(net "P5E_PEX1_STN0_RX_DP<4>")
	)
	(segment
		(start 199.121776 -149.80666)
		(end 201.222356 -150.85568)
		(width 0.1651)
		(layer "In5.Cu")
		(net "P5E_PEX1_STN0_RX_DP<4>")
	)
	(segment
		(start 191.128142 -134.80415)
		(end 191.137286 -134.965694)
		(width 0.1651)
		(layer "In5.Cu")
		(net "P5E_PEX1_STN0_RX_DP<4>")
	)
	(segment
		(start 185.607706 -131.567682)
		(end 186.045856 -131.799076)
		(width 0.1651)
		(layer "In5.Cu")
		(net "P5E_PEX1_STN0_RX_DP<4>")
	)
	(segment
		(start 186.638438 -131.982718)
		(end 186.685936 -132.137404)
		(width 0.1651)
		(layer "In5.Cu")
		(net "P5E_PEX1_STN0_RX_DP<4>")
	)
	(segment
		(start 187.716668 -132.55244)
		(end 187.764166 -132.706872)
		(width 0.1651)
		(layer "In5.Cu")
		(net "P5E_PEX1_STN0_RX_DP<4>")
	)
	(segment
		(start 202.05192 -283.180536)
		(end 201.049636 -283.883862)
		(width 0.1651)
		(layer "In5.Cu")
		(net "P5E_PEX1_STN0_RX_DP<4>")
	)
	(segment
		(start 196.079618 -284.173676)
		(end 196.079618 -284.385512)
		(width 0.1143)
		(layer "In5.Cu")
		(net "P5E_PEX1_STN0_RX_DP<4>")
	)
	(segment
		(start 187.124086 -132.368798)
		(end 187.278772 -132.3213)
		(width 0.1651)
		(layer "In5.Cu")
		(net "P5E_PEX1_STN0_RX_DP<4>")
	)
	(segment
		(start 189.899036 -133.7056)
		(end 191.128142 -134.80415)
		(width 0.1651)
		(layer "In5.Cu")
		(net "P5E_PEX1_STN0_RX_DP<4>")
	)
	(segment
		(start 189.435232 -133.460744)
		(end 189.899036 -133.7056)
		(width 0.1651)
		(layer "In5.Cu")
		(net "P5E_PEX1_STN0_RX_DP<4>")
	)
	(segment
		(start 201.288396 -232.261156)
		(end 203.172822 -240.959894)
		(width 0.1651)
		(layer "In5.Cu")
		(net "P5E_PEX1_STN0_RX_DP<4>")
	)
	(segment
		(start 189.2808 -133.508242)
		(end 189.435232 -133.460744)
		(width 0.1651)
		(layer "In5.Cu")
		(net "P5E_PEX1_STN0_RX_DP<4>")
	)
	(segment
		(start 186.045856 -131.799076)
		(end 186.200542 -131.751578)
		(width 0.1651)
		(layer "In5.Cu")
		(net "P5E_PEX1_STN0_RX_DP<4>")
	)
	(segment
		(start 184.52973 -130.99796)
		(end 184.96788 -131.229608)
		(width 0.1651)
		(layer "In5.Cu")
		(net "P5E_PEX1_STN0_RX_DP<4>")
	)
	(segment
		(start 188.842396 -133.276594)
		(end 189.2808 -133.508242)
		(width 0.1651)
		(layer "In5.Cu")
		(net "P5E_PEX1_STN0_RX_DP<4>")
	)
	(segment
		(start 184.482232 -130.843528)
		(end 184.52973 -130.99796)
		(width 0.1651)
		(layer "In5.Cu")
		(net "P5E_PEX1_STN0_RX_DP<4>")
	)
	(segment
		(start 195.965318 -284.499812)
		(end 195.699888 -284.499812)
		(width 0.1143)
		(layer "In5.Cu")
		(net "P5E_PEX1_STN0_RX_DP<4>")
	)
	(segment
		(start 209.591656 -275.89226)
		(end 202.05192 -283.180536)
		(width 0.1651)
		(layer "In5.Cu")
		(net "P5E_PEX1_STN0_RX_DP<4>")
	)
	(segment
		(start 187.278772 -132.3213)
		(end 187.716668 -132.55244)
		(width 0.1651)
		(layer "In5.Cu")
		(net "P5E_PEX1_STN0_RX_DP<4>")
	)
	(segment
		(start 201.524616 -151.55164)
		(end 201.890376 -168.33342)
		(width 0.1651)
		(layer "In5.Cu")
		(net "P5E_PEX1_STN0_RX_DP<4>")
	)
	(segment
		(start 194.418712 -138.195812)
		(end 195.157344 -140.067284)
		(width 0.1651)
		(layer "In5.Cu")
		(net "P5E_PEX1_STN0_RX_DP<4>")
	)
	(segment
		(start 188.20257 -132.93852)
		(end 188.357002 -132.891022)
		(width 0.1651)
		(layer "In5.Cu")
		(net "P5E_PEX1_STN0_RX_DP<4>")
	)
	(segment
		(start 196.774816 -148.26488)
		(end 198.016876 -148.56206)
		(width 0.1651)
		(layer "In5.Cu")
		(net "P5E_PEX1_STN0_RX_DP<4>")
	)
	(segment
		(start 193.644012 -137.053066)
		(end 194.418712 -138.195812)
		(width 0.1651)
		(layer "In5.Cu")
		(net "P5E_PEX1_STN0_RX_DP<4>")
	)
	(segment
		(start 184.96788 -131.229608)
		(end 185.122312 -131.181856)
		(width 0.1651)
		(layer "In5.Cu")
		(net "P5E_PEX1_STN0_RX_DP<4>")
	)
	(segment
		(start 186.685936 -132.137404)
		(end 187.124086 -132.368798)
		(width 0.1651)
		(layer "In5.Cu")
		(net "P5E_PEX1_STN0_RX_DP<4>")
	)
	(segment
		(start 188.794898 -133.122162)
		(end 188.842396 -133.276594)
		(width 0.1651)
		(layer "In5.Cu")
		(net "P5E_PEX1_STN0_RX_DP<4>")
	)
	(segment
		(start 191.506602 -135.295894)
		(end 191.668146 -135.287004)
		(width 0.1651)
		(layer "In5.Cu")
		(net "P5E_PEX1_STN0_RX_DP<4>")
	)
	(segment
		(start 196.312536 -147.778978)
		(end 196.774816 -148.26488)
		(width 0.1651)
		(layer "In5.Cu")
		(net "P5E_PEX1_STN0_RX_DP<4>")
	)
	(segment
		(start 187.764166 -132.706872)
		(end 188.20257 -132.93852)
		(width 0.1651)
		(layer "In5.Cu")
		(net "P5E_PEX1_STN0_RX_DP<4>")
	)
	(segment
		(start 198.016876 -148.56206)
		(end 199.121776 -149.80666)
		(width 0.1651)
		(layer "In5.Cu")
		(net "P5E_PEX1_STN0_RX_DP<4>")
	)
	(segment
		(start 203.172822 -240.959894)
		(end 211.59216 -269.76578)
		(width 0.1651)
		(layer "In5.Cu")
		(net "P5E_PEX1_STN0_RX_DP<4>")
	)
	(segment
		(start 183.447944 -130.486404)
		(end 183.806338 -130.486404)
		(width 0.1651)
		(layer "In5.Cu")
		(net "P5E_PEX1_STN0_RX_DP<4>")
	)
	(segment
		(start 199.996298 -283.883862)
		(end 199.950578 -283.929582)
		(width 0.1143)
		(layer "In5.Cu")
		(net "P5E_PEX1_STN0_RX_DP<4>")
	)
	(segment
		(start 199.950578 -283.929582)
		(end 196.323712 -283.929582)
		(width 0.1143)
		(layer "In5.Cu")
		(net "P5E_PEX1_STN0_RX_DP<4>")
	)
	(segment
		(start 188.357002 -132.891022)
		(end 188.794898 -133.122162)
		(width 0.1651)
		(layer "In5.Cu")
		(net "P5E_PEX1_STN0_RX_DP<4>")
	)
	(segment
		(start 201.049636 -283.883862)
		(end 200.024746 -283.883862)
		(width 0.1651)
		(layer "In5.Cu")
		(net "P5E_PEX1_STN0_RX_DP<4>")
	)
	(segment
		(start 201.890376 -168.33342)
		(end 201.288396 -232.261156)
		(width 0.1651)
		(layer "In5.Cu")
		(net "P5E_PEX1_STN0_RX_DP<4>")
	)
	(segment
		(start 196.079618 -284.385512)
		(end 195.965318 -284.499812)
		(width 0.1143)
		(layer "In5.Cu")
		(net "P5E_PEX1_STN0_RX_DP<4>")
	)
	(segment
		(start 186.200542 -131.751578)
		(end 186.638438 -131.982718)
		(width 0.1651)
		(layer "In5.Cu")
		(net "P5E_PEX1_STN0_RX_DP<4>")
	)
	(segment
		(start 183.806338 -130.486404)
		(end 184.482232 -130.843528)
		(width 0.1651)
		(layer "In5.Cu")
		(net "P5E_PEX1_STN0_RX_DP<4>")
	)
	(segment
		(start 185.122312 -131.181856)
		(end 185.560208 -131.412996)
		(width 0.1651)
		(layer "In5.Cu")
		(net "P5E_PEX1_STN0_RX_DP<4>")
	)
	(segment
		(start 184.106566 -135.882126)
		(end 181.598062 -135.882126)
		(width 0.13462)
		(layer "F.Cu")
		(net "P5E_PEX1_STN0_RX_DP<7>")
	)
	(segment
		(start 184.26938 -136.04494)
		(end 184.106566 -135.882126)
		(width 0.13462)
		(layer "F.Cu")
		(net "P5E_PEX1_STN0_RX_DP<7>")
	)
	(segment
		(start 181.598062 -135.882126)
		(end 181.302914 -136.177274)
		(width 0.13462)
		(layer "F.Cu")
		(net "P5E_PEX1_STN0_RX_DP<7>")
	)
	(segment
		(start 184.757314 -136.04494)
		(end 184.26938 -136.04494)
		(width 0.13462)
		(layer "F.Cu")
		(net "P5E_PEX1_STN0_RX_DP<7>")
	)
	(segment
		(start 189.824868 -140.697204)
		(end 190.696342 -141.568678)
		(width 0.1651)
		(layer "In5.Cu")
		(net "P5E_PEX1_STN0_RX_DP<7>")
	)
	(segment
		(start 191.779398 -146.451574)
		(end 191.916304 -146.53768)
		(width 0.1651)
		(layer "In5.Cu")
		(net "P5E_PEX1_STN0_RX_DP<7>")
	)
	(segment
		(start 186.56808 -137.250424)
		(end 187.027312 -137.437114)
		(width 0.1651)
		(layer "In5.Cu")
		(net "P5E_PEX1_STN0_RX_DP<7>")
	)
	(segment
		(start 197.979792 -281.535632)
		(end 197.865492 -281.649932)
		(width 0.1143)
		(layer "In5.Cu")
		(net "P5E_PEX1_STN0_RX_DP<7>")
	)
	(segment
		(start 198.652892 -264.857484)
		(end 199.531478 -271.0561)
		(width 0.1651)
		(layer "In5.Cu")
		(net "P5E_PEX1_STN0_RX_DP<7>")
	)
	(segment
		(start 185.375804 -136.64184)
		(end 185.438542 -136.791192)
		(width 0.1651)
		(layer "In5.Cu")
		(net "P5E_PEX1_STN0_RX_DP<7>")
	)
	(segment
		(start 189.144148 -138.926062)
		(end 189.50559 -139.540996)
		(width 0.1651)
		(layer "In5.Cu")
		(net "P5E_PEX1_STN0_RX_DP<7>")
	)
	(segment
		(start 200.172066 -281.033982)
		(end 200.050146 -281.033982)
		(width 0.1651)
		(layer "In5.Cu")
		(net "P5E_PEX1_STN0_RX_DP<7>")
	)
	(segment
		(start 185.89752 -136.977628)
		(end 186.046618 -136.91489)
		(width 0.1651)
		(layer "In5.Cu")
		(net "P5E_PEX1_STN0_RX_DP<7>")
	)
	(segment
		(start 191.237616 -144.073626)
		(end 191.374776 -144.159732)
		(width 0.1651)
		(layer "In5.Cu")
		(net "P5E_PEX1_STN0_RX_DP<7>")
	)
	(segment
		(start 186.046618 -136.91489)
		(end 186.505342 -137.101326)
		(width 0.1651)
		(layer "In5.Cu")
		(net "P5E_PEX1_STN0_RX_DP<7>")
	)
	(segment
		(start 191.21374 -143.453612)
		(end 191.127634 -143.590518)
		(width 0.1651)
		(layer "In5.Cu")
		(net "P5E_PEX1_STN0_RX_DP<7>")
	)
	(segment
		(start 187.176156 -137.374376)
		(end 187.90666 -137.671302)
		(width 0.1651)
		(layer "In5.Cu")
		(net "P5E_PEX1_STN0_RX_DP<7>")
	)
	(segment
		(start 199.975978 -281.079702)
		(end 198.19493 -281.079702)
		(width 0.1143)
		(layer "In5.Cu")
		(net "P5E_PEX1_STN0_RX_DP<7>")
	)
	(segment
		(start 191.374776 -144.159732)
		(end 191.484504 -144.642586)
		(width 0.1651)
		(layer "In5.Cu")
		(net "P5E_PEX1_STN0_RX_DP<7>")
	)
	(segment
		(start 200.260712 -280.94559)
		(end 200.172066 -281.033982)
		(width 0.1651)
		(layer "In5.Cu")
		(net "P5E_PEX1_STN0_RX_DP<7>")
	)
	(segment
		(start 200.570846 -276.665944)
		(end 200.491344 -280.407364)
		(width 0.1651)
		(layer "In5.Cu")
		(net "P5E_PEX1_STN0_RX_DP<7>")
	)
	(segment
		(start 187.027312 -137.437114)
		(end 187.176156 -137.374376)
		(width 0.1651)
		(layer "In5.Cu")
		(net "P5E_PEX1_STN0_RX_DP<7>")
	)
	(segment
		(start 195.098924 -160.51276)
		(end 198.652892 -264.857484)
		(width 0.1651)
		(layer "In5.Cu")
		(net "P5E_PEX1_STN0_RX_DP<7>")
	)
	(segment
		(start 200.491344 -280.407364)
		(end 200.260712 -280.94559)
		(width 0.1651)
		(layer "In5.Cu")
		(net "P5E_PEX1_STN0_RX_DP<7>")
	)
	(segment
		(start 181.302914 -136.177274)
		(end 181.593744 -135.886444)
		(width 0.1651)
		(layer "In5.Cu")
		(net "P5E_PEX1_STN0_RX_DP<7>")
	)
	(segment
		(start 189.50559 -139.540996)
		(end 189.50559 -139.926568)
		(width 0.1651)
		(layer "In5.Cu")
		(net "P5E_PEX1_STN0_RX_DP<7>")
	)
	(segment
		(start 187.90666 -137.671302)
		(end 189.144148 -138.926062)
		(width 0.1651)
		(layer "In5.Cu")
		(net "P5E_PEX1_STN0_RX_DP<7>")
	)
	(segment
		(start 199.531478 -271.0561)
		(end 200.570846 -276.665944)
		(width 0.1651)
		(layer "In5.Cu")
		(net "P5E_PEX1_STN0_RX_DP<7>")
	)
	(segment
		(start 198.19493 -281.079702)
		(end 197.979792 -281.29484)
		(width 0.1143)
		(layer "In5.Cu")
		(net "P5E_PEX1_STN0_RX_DP<7>")
	)
	(segment
		(start 191.669416 -145.968466)
		(end 191.779398 -146.451574)
		(width 0.1651)
		(layer "In5.Cu")
		(net "P5E_PEX1_STN0_RX_DP<7>")
	)
	(segment
		(start 197.865492 -281.649932)
		(end 197.600062 -281.649932)
		(width 0.1143)
		(layer "In5.Cu")
		(net "P5E_PEX1_STN0_RX_DP<7>")
	)
	(segment
		(start 197.979792 -281.29484)
		(end 197.979792 -281.535632)
		(width 0.1143)
		(layer "In5.Cu")
		(net "P5E_PEX1_STN0_RX_DP<7>")
	)
	(segment
		(start 191.484504 -144.642586)
		(end 191.398652 -144.779492)
		(width 0.1651)
		(layer "In5.Cu")
		(net "P5E_PEX1_STN0_RX_DP<7>")
	)
	(segment
		(start 184.91708 -136.455404)
		(end 185.375804 -136.64184)
		(width 0.1651)
		(layer "In5.Cu")
		(net "P5E_PEX1_STN0_RX_DP<7>")
	)
	(segment
		(start 191.64554 -145.348706)
		(end 191.755268 -145.83156)
		(width 0.1651)
		(layer "In5.Cu")
		(net "P5E_PEX1_STN0_RX_DP<7>")
	)
	(segment
		(start 191.916558 -146.538696)
		(end 195.09867 -160.511744)
		(width 0.1651)
		(layer "In5.Cu")
		(net "P5E_PEX1_STN0_RX_DP<7>")
	)
	(segment
		(start 185.438542 -136.791192)
		(end 185.89752 -136.977628)
		(width 0.1651)
		(layer "In5.Cu")
		(net "P5E_PEX1_STN0_RX_DP<7>")
	)
	(segment
		(start 191.398652 -144.779492)
		(end 191.508634 -145.2626)
		(width 0.1651)
		(layer "In5.Cu")
		(net "P5E_PEX1_STN0_RX_DP<7>")
	)
	(segment
		(start 200.050146 -281.033982)
		(end 200.021698 -281.033982)
		(width 0.1143)
		(layer "In5.Cu")
		(net "P5E_PEX1_STN0_RX_DP<7>")
	)
	(segment
		(start 190.696342 -141.568678)
		(end 190.84036 -141.814042)
		(width 0.1651)
		(layer "In5.Cu")
		(net "P5E_PEX1_STN0_RX_DP<7>")
	)
	(segment
		(start 191.916304 -146.53768)
		(end 191.916558 -146.538696)
		(width 0.1651)
		(layer "In5.Cu")
		(net "P5E_PEX1_STN0_RX_DP<7>")
	)
	(segment
		(start 190.84036 -141.814042)
		(end 191.21374 -143.453612)
		(width 0.1651)
		(layer "In5.Cu")
		(net "P5E_PEX1_STN0_RX_DP<7>")
	)
	(segment
		(start 191.508634 -145.2626)
		(end 191.64554 -145.348706)
		(width 0.1651)
		(layer "In5.Cu")
		(net "P5E_PEX1_STN0_RX_DP<7>")
	)
	(segment
		(start 191.127634 -143.590518)
		(end 191.237616 -144.073626)
		(width 0.1651)
		(layer "In5.Cu")
		(net "P5E_PEX1_STN0_RX_DP<7>")
	)
	(segment
		(start 200.021698 -281.033982)
		(end 199.975978 -281.079702)
		(width 0.1143)
		(layer "In5.Cu")
		(net "P5E_PEX1_STN0_RX_DP<7>")
	)
	(segment
		(start 183.518302 -135.886444)
		(end 184.246266 -136.182608)
		(width 0.1651)
		(layer "In5.Cu")
		(net "P5E_PEX1_STN0_RX_DP<7>")
	)
	(segment
		(start 181.593744 -135.886444)
		(end 183.518302 -135.886444)
		(width 0.1651)
		(layer "In5.Cu")
		(net "P5E_PEX1_STN0_RX_DP<7>")
	)
	(segment
		(start 191.755268 -145.83156)
		(end 191.669416 -145.968466)
		(width 0.1651)
		(layer "In5.Cu")
		(net "P5E_PEX1_STN0_RX_DP<7>")
	)
	(segment
		(start 186.505342 -137.101326)
		(end 186.56808 -137.250424)
		(width 0.1651)
		(layer "In5.Cu")
		(net "P5E_PEX1_STN0_RX_DP<7>")
	)
	(segment
		(start 184.768236 -136.518396)
		(end 184.91708 -136.455404)
		(width 0.1651)
		(layer "In5.Cu")
		(net "P5E_PEX1_STN0_RX_DP<7>")
	)
	(segment
		(start 184.246266 -136.182608)
		(end 184.309258 -136.331706)
		(width 0.1651)
		(layer "In5.Cu")
		(net "P5E_PEX1_STN0_RX_DP<7>")
	)
	(segment
		(start 195.09867 -160.511744)
		(end 195.098924 -160.51276)
		(width 0.1651)
		(layer "In5.Cu")
		(net "P5E_PEX1_STN0_RX_DP<7>")
	)
	(segment
		(start 189.50559 -139.926568)
		(end 189.824868 -140.697204)
		(width 0.1651)
		(layer "In5.Cu")
		(net "P5E_PEX1_STN0_RX_DP<7>")
	)
	(segment
		(start 184.309258 -136.331706)
		(end 184.768236 -136.518396)
		(width 0.1651)
		(layer "In5.Cu")
		(net "P5E_PEX1_STN0_RX_DP<7>")
	)
	(segment
		(start 184.106566 -150.39213)
		(end 183.452262 -150.39213)
		(width 0.13462)
		(layer "F.Cu")
		(net "P5E_PEX1_STN0_RX_DP<12>")
	)
	(segment
		(start 184.757314 -150.554944)
		(end 184.26938 -150.554944)
		(width 0.13462)
		(layer "F.Cu")
		(net "P5E_PEX1_STN0_RX_DP<12>")
	)
	(segment
		(start 184.26938 -150.554944)
		(end 184.106566 -150.39213)
		(width 0.13462)
		(layer "F.Cu")
		(net "P5E_PEX1_STN0_RX_DP<12>")
	)
	(segment
		(start 183.452262 -150.39213)
		(end 183.157114 -150.687278)
		(width 0.13462)
		(layer "F.Cu")
		(net "P5E_PEX1_STN0_RX_DP<12>")
	)
	(segment
		(start 185.775854 -152.865582)
		(end 185.967624 -153.32202)
		(width 0.1651)
		(layer "In5.Cu")
		(net "P5E_PEX1_STN0_RX_DP<12>")
	)
	(segment
		(start 193.713354 -268.035278)
		(end 193.184018 -270.75892)
		(width 0.1651)
		(layer "In5.Cu")
		(net "P5E_PEX1_STN0_RX_DP<12>")
	)
	(segment
		(start 186.112404 -153.895298)
		(end 186.22899 -153.942796)
		(width 0.1651)
		(layer "In5.Cu")
		(net "P5E_PEX1_STN0_RX_DP<12>")
	)
	(segment
		(start 193.685414 -275.570188)
		(end 193.799714 -275.684488)
		(width 0.1143)
		(layer "In5.Cu")
		(net "P5E_PEX1_STN0_RX_DP<12>")
	)
	(segment
		(start 185.967624 -153.32202)
		(end 185.920126 -153.438352)
		(width 0.1651)
		(layer "In5.Cu")
		(net "P5E_PEX1_STN0_RX_DP<12>")
	)
	(segment
		(start 185.920126 -153.438352)
		(end 186.112404 -153.895298)
		(width 0.1651)
		(layer "In5.Cu")
		(net "P5E_PEX1_STN0_RX_DP<12>")
	)
	(segment
		(start 193.184018 -271.599406)
		(end 193.229738 -271.645126)
		(width 0.1143)
		(layer "In5.Cu")
		(net "P5E_PEX1_STN0_RX_DP<12>")
	)
	(segment
		(start 193.184018 -270.75892)
		(end 193.184018 -271.570958)
		(width 0.1651)
		(layer "In5.Cu")
		(net "P5E_PEX1_STN0_RX_DP<12>")
	)
	(segment
		(start 188.982604 -158.4706)
		(end 190.122302 -161.211514)
		(width 0.1651)
		(layer "In5.Cu")
		(net "P5E_PEX1_STN0_RX_DP<12>")
	)
	(segment
		(start 190.122302 -161.211514)
		(end 193.65087 -260.77418)
		(width 0.1651)
		(layer "In5.Cu")
		(net "P5E_PEX1_STN0_RX_DP<12>")
	)
	(segment
		(start 193.184018 -271.570958)
		(end 193.184018 -271.599406)
		(width 0.1143)
		(layer "In5.Cu")
		(net "P5E_PEX1_STN0_RX_DP<12>")
	)
	(segment
		(start 193.229738 -271.645126)
		(end 193.229738 -275.355304)
		(width 0.1143)
		(layer "In5.Cu")
		(net "P5E_PEX1_STN0_RX_DP<12>")
	)
	(segment
		(start 193.444622 -275.570188)
		(end 193.685414 -275.570188)
		(width 0.1143)
		(layer "In5.Cu")
		(net "P5E_PEX1_STN0_RX_DP<12>")
	)
	(segment
		(start 185.514742 -152.244806)
		(end 185.467244 -152.361392)
		(width 0.1651)
		(layer "In5.Cu")
		(net "P5E_PEX1_STN0_RX_DP<12>")
	)
	(segment
		(start 193.229738 -275.355304)
		(end 193.444622 -275.570188)
		(width 0.1143)
		(layer "In5.Cu")
		(net "P5E_PEX1_STN0_RX_DP<12>")
	)
	(segment
		(start 185.659522 -152.818084)
		(end 185.775854 -152.865582)
		(width 0.1651)
		(layer "In5.Cu")
		(net "P5E_PEX1_STN0_RX_DP<12>")
	)
	(segment
		(start 185.311034 -151.760174)
		(end 185.514742 -152.244806)
		(width 0.1651)
		(layer "In5.Cu")
		(net "P5E_PEX1_STN0_RX_DP<12>")
	)
	(segment
		(start 185.467244 -152.361392)
		(end 185.659522 -152.818084)
		(width 0.1651)
		(layer "In5.Cu")
		(net "P5E_PEX1_STN0_RX_DP<12>")
	)
	(segment
		(start 193.799714 -275.684488)
		(end 193.799714 -275.949918)
		(width 0.1143)
		(layer "In5.Cu")
		(net "P5E_PEX1_STN0_RX_DP<12>")
	)
	(segment
		(start 186.718194 -155.10637)
		(end 188.982604 -158.4706)
		(width 0.1651)
		(layer "In5.Cu")
		(net "P5E_PEX1_STN0_RX_DP<12>")
	)
	(segment
		(start 186.22899 -153.942796)
		(end 186.718194 -155.10637)
		(width 0.1651)
		(layer "In5.Cu")
		(net "P5E_PEX1_STN0_RX_DP<12>")
	)
	(segment
		(start 183.157114 -150.687278)
		(end 183.447944 -150.396448)
		(width 0.1651)
		(layer "In5.Cu")
		(net "P5E_PEX1_STN0_RX_DP<12>")
	)
	(segment
		(start 193.65087 -260.77418)
		(end 193.713354 -268.035278)
		(width 0.1651)
		(layer "In5.Cu")
		(net "P5E_PEX1_STN0_RX_DP<12>")
	)
	(segment
		(start 183.922924 -150.396448)
		(end 185.311034 -151.760174)
		(width 0.1651)
		(layer "In5.Cu")
		(net "P5E_PEX1_STN0_RX_DP<12>")
	)
	(segment
		(start 183.447944 -150.396448)
		(end 183.922924 -150.396448)
		(width 0.1651)
		(layer "In5.Cu")
		(net "P5E_PEX1_STN0_RX_DP<12>")
	)
	(segment
		(start 189.357508 -155.355036)
		(end 189.845696 -155.355036)
		(width 0.13462)
		(layer "F.Cu")
		(net "P5E_PEX1_STN0_TX_C_DN<15>")
	)
	(segment
		(start 189.845696 -155.355036)
		(end 190.00851 -155.51785)
		(width 0.13462)
		(layer "F.Cu")
		(net "P5E_PEX1_STN0_TX_C_DN<15>")
	)
	(segment
		(start 190.00851 -155.51785)
		(end 198.173594 -155.51785)
		(width 0.13462)
		(layer "F.Cu")
		(net "P5E_PEX1_STN0_TX_C_DN<15>")
	)
	(segment
		(start 198.173594 -155.51785)
		(end 198.49465 -155.196794)
		(width 0.13462)
		(layer "F.Cu")
		(net "P5E_PEX1_STN0_TX_C_DN<15>")
	)
	(segment
		(start 184.106566 -144.99209)
		(end 181.598062 -144.99209)
		(width 0.13462)
		(layer "F.Cu")
		(net "P5E_PEX1_STN0_RX_DP<9>")
	)
	(segment
		(start 184.26938 -145.154904)
		(end 184.106566 -144.99209)
		(width 0.13462)
		(layer "F.Cu")
		(net "P5E_PEX1_STN0_RX_DP<9>")
	)
	(segment
		(start 181.598062 -144.99209)
		(end 181.302914 -145.287238)
		(width 0.13462)
		(layer "F.Cu")
		(net "P5E_PEX1_STN0_RX_DP<9>")
	)
	(segment
		(start 184.757314 -145.154904)
		(end 184.26938 -145.154904)
		(width 0.13462)
		(layer "F.Cu")
		(net "P5E_PEX1_STN0_RX_DP<9>")
	)
	(segment
		(start 183.267604 -144.996408)
		(end 184.017666 -145.310352)
		(width 0.1651)
		(layer "In5.Cu")
		(net "P5E_PEX1_STN0_RX_DP<9>")
	)
	(segment
		(start 196.618098 -268.260068)
		(end 196.033898 -271.197578)
		(width 0.1651)
		(layer "In5.Cu")
		(net "P5E_PEX1_STN0_RX_DP<9>")
	)
	(segment
		(start 184.978802 -146.284696)
		(end 185.326528 -146.637248)
		(width 0.1651)
		(layer "In5.Cu")
		(net "P5E_PEX1_STN0_RX_DP<9>")
	)
	(segment
		(start 185.799476 -147.116546)
		(end 186.272678 -147.596352)
		(width 0.1651)
		(layer "In5.Cu")
		(net "P5E_PEX1_STN0_RX_DP<9>")
	)
	(segment
		(start 185.673746 -147.115784)
		(end 185.799476 -147.116546)
		(width 0.1651)
		(layer "In5.Cu")
		(net "P5E_PEX1_STN0_RX_DP<9>")
	)
	(segment
		(start 188.937138 -152.63622)
		(end 191.685164 -155.437332)
		(width 0.1651)
		(layer "In5.Cu")
		(net "P5E_PEX1_STN0_RX_DP<9>")
	)
	(segment
		(start 196.033898 -271.554448)
		(end 196.079618 -271.600168)
		(width 0.1143)
		(layer "In5.Cu")
		(net "P5E_PEX1_STN0_RX_DP<9>")
	)
	(segment
		(start 196.535294 -273.670014)
		(end 196.649594 -273.784314)
		(width 0.1143)
		(layer "In5.Cu")
		(net "P5E_PEX1_STN0_RX_DP<9>")
	)
	(segment
		(start 184.505854 -145.805398)
		(end 184.505092 -145.931128)
		(width 0.1651)
		(layer "In5.Cu")
		(net "P5E_PEX1_STN0_RX_DP<9>")
	)
	(segment
		(start 184.505092 -145.931128)
		(end 184.853072 -146.283934)
		(width 0.1651)
		(layer "In5.Cu")
		(net "P5E_PEX1_STN0_RX_DP<9>")
	)
	(segment
		(start 181.593744 -144.996408)
		(end 183.267604 -144.996408)
		(width 0.1651)
		(layer "In5.Cu")
		(net "P5E_PEX1_STN0_RX_DP<9>")
	)
	(segment
		(start 196.618098 -261.978394)
		(end 196.618098 -268.260068)
		(width 0.1651)
		(layer "In5.Cu")
		(net "P5E_PEX1_STN0_RX_DP<9>")
	)
	(segment
		(start 184.017666 -145.310352)
		(end 184.505854 -145.805398)
		(width 0.1651)
		(layer "In5.Cu")
		(net "P5E_PEX1_STN0_RX_DP<9>")
	)
	(segment
		(start 186.272678 -147.596352)
		(end 188.181742 -150.537418)
		(width 0.1651)
		(layer "In5.Cu")
		(net "P5E_PEX1_STN0_RX_DP<9>")
	)
	(segment
		(start 188.181742 -150.537418)
		(end 188.937138 -152.63622)
		(width 0.1651)
		(layer "In5.Cu")
		(net "P5E_PEX1_STN0_RX_DP<9>")
	)
	(segment
		(start 191.685164 -155.437332)
		(end 193.036698 -160.504886)
		(width 0.1651)
		(layer "In5.Cu")
		(net "P5E_PEX1_STN0_RX_DP<9>")
	)
	(segment
		(start 196.033898 -271.197578)
		(end 196.033898 -271.526)
		(width 0.1651)
		(layer "In5.Cu")
		(net "P5E_PEX1_STN0_RX_DP<9>")
	)
	(segment
		(start 196.079618 -273.45513)
		(end 196.294502 -273.670014)
		(width 0.1143)
		(layer "In5.Cu")
		(net "P5E_PEX1_STN0_RX_DP<9>")
	)
	(segment
		(start 184.853072 -146.283934)
		(end 184.978802 -146.284696)
		(width 0.1651)
		(layer "In5.Cu")
		(net "P5E_PEX1_STN0_RX_DP<9>")
	)
	(segment
		(start 181.302914 -145.287238)
		(end 181.593744 -144.996408)
		(width 0.1651)
		(layer "In5.Cu")
		(net "P5E_PEX1_STN0_RX_DP<9>")
	)
	(segment
		(start 185.325766 -146.762978)
		(end 185.673746 -147.115784)
		(width 0.1651)
		(layer "In5.Cu")
		(net "P5E_PEX1_STN0_RX_DP<9>")
	)
	(segment
		(start 196.079618 -271.600168)
		(end 196.079618 -273.45513)
		(width 0.1143)
		(layer "In5.Cu")
		(net "P5E_PEX1_STN0_RX_DP<9>")
	)
	(segment
		(start 185.326528 -146.637248)
		(end 185.325766 -146.762978)
		(width 0.1651)
		(layer "In5.Cu")
		(net "P5E_PEX1_STN0_RX_DP<9>")
	)
	(segment
		(start 196.294502 -273.670014)
		(end 196.535294 -273.670014)
		(width 0.1143)
		(layer "In5.Cu")
		(net "P5E_PEX1_STN0_RX_DP<9>")
	)
	(segment
		(start 196.033898 -271.526)
		(end 196.033898 -271.554448)
		(width 0.1143)
		(layer "In5.Cu")
		(net "P5E_PEX1_STN0_RX_DP<9>")
	)
	(segment
		(start 196.649594 -273.784314)
		(end 196.649594 -274.049744)
		(width 0.1143)
		(layer "In5.Cu")
		(net "P5E_PEX1_STN0_RX_DP<9>")
	)
	(segment
		(start 193.036698 -160.504886)
		(end 196.618098 -261.978394)
		(width 0.1651)
		(layer "In5.Cu")
		(net "P5E_PEX1_STN0_RX_DP<9>")
	)
	(segment
		(start 181.598062 -132.007864)
		(end 181.597554 -132.008372)
		(width 0.13462)
		(layer "F.Cu")
		(net "P5E_PEX1_STN0_RX_DN<5>")
	)
	(segment
		(start 184.757314 -131.84505)
		(end 184.26938 -131.84505)
		(width 0.13462)
		(layer "F.Cu")
		(net "P5E_PEX1_STN0_RX_DN<5>")
	)
	(segment
		(start 184.26938 -131.84505)
		(end 184.106566 -132.007864)
		(width 0.13462)
		(layer "F.Cu")
		(net "P5E_PEX1_STN0_RX_DN<5>")
	)
	(segment
		(start 181.597554 -132.008372)
		(end 181.302914 -131.713732)
		(width 0.13462)
		(layer "F.Cu")
		(net "P5E_PEX1_STN0_RX_DN<5>")
	)
	(segment
		(start 184.106566 -132.007864)
		(end 181.598062 -132.007864)
		(width 0.13462)
		(layer "F.Cu")
		(net "P5E_PEX1_STN0_RX_DN<5>")
	)
	(segment
		(start 200.75144 -283.215842)
		(end 200.017634 -283.215842)
		(width 0.1651)
		(layer "In5.Cu")
		(net "P5E_PEX1_STN0_RX_DN<5>")
	)
	(segment
		(start 193.715386 -138.484864)
		(end 194.00139 -139.151868)
		(width 0.1651)
		(layer "In5.Cu")
		(net "P5E_PEX1_STN0_RX_DN<5>")
	)
	(segment
		(start 198.273924 -283.170122)
		(end 198.170292 -283.273754)
		(width 0.1143)
		(layer "In5.Cu")
		(net "P5E_PEX1_STN0_RX_DN<5>")
	)
	(segment
		(start 198.170292 -283.435552)
		(end 198.284592 -283.549852)
		(width 0.1143)
		(layer "In5.Cu")
		(net "P5E_PEX1_STN0_RX_DN<5>")
	)
	(segment
		(start 200.629012 -233.312462)
		(end 203.248006 -244.131846)
		(width 0.1651)
		(layer "In5.Cu")
		(net "P5E_PEX1_STN0_RX_DN<5>")
	)
	(segment
		(start 199.595232 -222.600774)
		(end 200.629012 -233.312462)
		(width 0.1651)
		(layer "In5.Cu")
		(net "P5E_PEX1_STN0_RX_DN<5>")
	)
	(segment
		(start 209.071718 -275.417788)
		(end 201.674222 -282.609036)
		(width 0.1651)
		(layer "In5.Cu")
		(net "P5E_PEX1_STN0_RX_DN<5>")
	)
	(segment
		(start 199.989186 -283.215842)
		(end 199.943466 -283.170122)
		(width 0.1143)
		(layer "In5.Cu")
		(net "P5E_PEX1_STN0_RX_DN<5>")
	)
	(segment
		(start 193.006218 -137.405872)
		(end 193.715386 -138.484864)
		(width 0.1651)
		(layer "In5.Cu")
		(net "P5E_PEX1_STN0_RX_DN<5>")
	)
	(segment
		(start 200.017634 -283.215842)
		(end 199.989186 -283.215842)
		(width 0.1143)
		(layer "In5.Cu")
		(net "P5E_PEX1_STN0_RX_DN<5>")
	)
	(segment
		(start 190.313056 -135.46074)
		(end 193.006218 -137.405872)
		(width 0.1651)
		(layer "In5.Cu")
		(net "P5E_PEX1_STN0_RX_DN<5>")
	)
	(segment
		(start 183.427116 -132.004562)
		(end 190.313056 -135.46074)
		(width 0.1651)
		(layer "In5.Cu")
		(net "P5E_PEX1_STN0_RX_DN<5>")
	)
	(segment
		(start 210.884008 -270.233394)
		(end 210.829144 -272.307558)
		(width 0.1651)
		(layer "In5.Cu")
		(net "P5E_PEX1_STN0_RX_DN<5>")
	)
	(segment
		(start 210.829144 -272.307558)
		(end 209.071718 -275.417788)
		(width 0.1651)
		(layer "In5.Cu")
		(net "P5E_PEX1_STN0_RX_DN<5>")
	)
	(segment
		(start 198.284592 -283.549852)
		(end 198.550022 -283.549852)
		(width 0.1143)
		(layer "In5.Cu")
		(net "P5E_PEX1_STN0_RX_DN<5>")
	)
	(segment
		(start 199.943466 -283.170122)
		(end 198.273924 -283.170122)
		(width 0.1143)
		(layer "In5.Cu")
		(net "P5E_PEX1_STN0_RX_DN<5>")
	)
	(segment
		(start 181.593744 -132.004562)
		(end 183.427116 -132.004562)
		(width 0.1651)
		(layer "In5.Cu")
		(net "P5E_PEX1_STN0_RX_DN<5>")
	)
	(segment
		(start 198.170292 -283.273754)
		(end 198.170292 -283.435552)
		(width 0.1143)
		(layer "In5.Cu")
		(net "P5E_PEX1_STN0_RX_DN<5>")
	)
	(segment
		(start 194.00139 -139.151868)
		(end 194.61734 -142.021306)
		(width 0.1651)
		(layer "In5.Cu")
		(net "P5E_PEX1_STN0_RX_DN<5>")
	)
	(segment
		(start 203.248006 -244.131846)
		(end 210.884008 -270.233394)
		(width 0.1651)
		(layer "In5.Cu")
		(net "P5E_PEX1_STN0_RX_DN<5>")
	)
	(segment
		(start 197.382892 -160.702752)
		(end 199.595232 -222.600774)
		(width 0.1651)
		(layer "In5.Cu")
		(net "P5E_PEX1_STN0_RX_DN<5>")
	)
	(segment
		(start 181.302914 -131.713732)
		(end 181.593744 -132.004562)
		(width 0.1651)
		(layer "In5.Cu")
		(net "P5E_PEX1_STN0_RX_DN<5>")
	)
	(segment
		(start 201.674222 -282.609036)
		(end 200.75144 -283.215842)
		(width 0.1651)
		(layer "In5.Cu")
		(net "P5E_PEX1_STN0_RX_DN<5>")
	)
	(segment
		(start 194.61734 -142.021306)
		(end 197.382892 -160.702752)
		(width 0.1651)
		(layer "In5.Cu")
		(net "P5E_PEX1_STN0_RX_DN<5>")
	)
	(segment
		(start 198.173594 -120.797828)
		(end 198.49465 -120.476772)
		(width 0.13462)
		(layer "F.Cu")
		(net "P5E_PEX1_STN0_TX_C_DN<1>")
	)
	(segment
		(start 189.357508 -120.635014)
		(end 189.845696 -120.635014)
		(width 0.13462)
		(layer "F.Cu")
		(net "P5E_PEX1_STN0_TX_C_DN<1>")
	)
	(segment
		(start 189.845696 -120.635014)
		(end 190.00851 -120.797828)
		(width 0.13462)
		(layer "F.Cu")
		(net "P5E_PEX1_STN0_TX_C_DN<1>")
	)
	(segment
		(start 190.00851 -120.797828)
		(end 198.173594 -120.797828)
		(width 0.13462)
		(layer "F.Cu")
		(net "P5E_PEX1_STN0_TX_C_DN<1>")
	)
	(segment
		(start 195.540122 -130.482086)
		(end 195.852542 -130.794506)
		(width 0.13462)
		(layer "F.Cu")
		(net "P5E_PEX1_STN0_TX_C_DP<4>")
	)
	(segment
		(start 189.845696 -130.6449)
		(end 190.00851 -130.482086)
		(width 0.13462)
		(layer "F.Cu")
		(net "P5E_PEX1_STN0_TX_C_DP<4>")
	)
	(segment
		(start 190.00851 -130.482086)
		(end 195.540122 -130.482086)
		(width 0.13462)
		(layer "F.Cu")
		(net "P5E_PEX1_STN0_TX_C_DP<4>")
	)
	(segment
		(start 189.357508 -130.6449)
		(end 189.845696 -130.6449)
		(width 0.13462)
		(layer "F.Cu")
		(net "P5E_PEX1_STN0_TX_C_DP<4>")
	)
	(segment
		(start 189.845696 -124.834904)
		(end 190.00851 -124.67209)
		(width 0.13462)
		(layer "F.Cu")
		(net "P5E_PEX1_STN0_TX_C_DP<3>")
	)
	(segment
		(start 198.175626 -124.67209)
		(end 198.49465 -124.991114)
		(width 0.13462)
		(layer "F.Cu")
		(net "P5E_PEX1_STN0_TX_C_DP<3>")
	)
	(segment
		(start 190.00851 -124.67209)
		(end 198.175626 -124.67209)
		(width 0.13462)
		(layer "F.Cu")
		(net "P5E_PEX1_STN0_TX_C_DP<3>")
	)
	(segment
		(start 189.357508 -124.834904)
		(end 189.845696 -124.834904)
		(width 0.13462)
		(layer "F.Cu")
		(net "P5E_PEX1_STN0_TX_C_DP<3>")
	)
	(segment
		(start 184.26938 -155.355036)
		(end 184.106566 -155.51785)
		(width 0.13462)
		(layer "F.Cu")
		(net "P5E_PEX1_STN0_RX_DN<15>")
	)
	(segment
		(start 184.757314 -155.355036)
		(end 184.26938 -155.355036)
		(width 0.13462)
		(layer "F.Cu")
		(net "P5E_PEX1_STN0_RX_DN<15>")
	)
	(segment
		(start 181.597554 -155.518358)
		(end 181.302914 -155.223718)
		(width 0.13462)
		(layer "F.Cu")
		(net "P5E_PEX1_STN0_RX_DN<15>")
	)
	(segment
		(start 181.598062 -155.51785)
		(end 181.597554 -155.518358)
		(width 0.13462)
		(layer "F.Cu")
		(net "P5E_PEX1_STN0_RX_DN<15>")
	)
	(segment
		(start 184.106566 -155.51785)
		(end 181.598062 -155.51785)
		(width 0.13462)
		(layer "F.Cu")
		(net "P5E_PEX1_STN0_RX_DN<15>")
	)
	(segment
		(start 182.44312 -155.514548)
		(end 183.063388 -156.134562)
		(width 0.1651)
		(layer "In5.Cu")
		(net "P5E_PEX1_STN0_RX_DN<15>")
	)
	(segment
		(start 190.570358 -273.376136)
		(end 190.673736 -273.479514)
		(width 0.1143)
		(layer "In5.Cu")
		(net "P5E_PEX1_STN0_RX_DN<15>")
	)
	(segment
		(start 190.949834 -273.365214)
		(end 190.949834 -273.099784)
		(width 0.1143)
		(layer "In5.Cu")
		(net "P5E_PEX1_STN0_RX_DN<15>")
	)
	(segment
		(start 190.616078 -271.526)
		(end 190.616078 -271.554448)
		(width 0.1143)
		(layer "In5.Cu")
		(net "P5E_PEX1_STN0_RX_DN<15>")
	)
	(segment
		(start 190.616078 -271.554448)
		(end 190.570358 -271.600168)
		(width 0.1143)
		(layer "In5.Cu")
		(net "P5E_PEX1_STN0_RX_DN<15>")
	)
	(segment
		(start 190.919354 -261.27202)
		(end 191.08928 -267.76807)
		(width 0.1651)
		(layer "In5.Cu")
		(net "P5E_PEX1_STN0_RX_DN<15>")
	)
	(segment
		(start 190.673736 -273.479514)
		(end 190.835534 -273.479514)
		(width 0.1143)
		(layer "In5.Cu")
		(net "P5E_PEX1_STN0_RX_DN<15>")
	)
	(segment
		(start 190.835534 -273.479514)
		(end 190.949834 -273.365214)
		(width 0.1143)
		(layer "In5.Cu")
		(net "P5E_PEX1_STN0_RX_DN<15>")
	)
	(segment
		(start 190.570358 -271.600168)
		(end 190.570358 -273.376136)
		(width 0.1143)
		(layer "In5.Cu")
		(net "P5E_PEX1_STN0_RX_DN<15>")
	)
	(segment
		(start 190.616078 -270.231616)
		(end 190.616078 -271.526)
		(width 0.1651)
		(layer "In5.Cu")
		(net "P5E_PEX1_STN0_RX_DN<15>")
	)
	(segment
		(start 183.063388 -156.134562)
		(end 184.011316 -162.860736)
		(width 0.1651)
		(layer "In5.Cu")
		(net "P5E_PEX1_STN0_RX_DN<15>")
	)
	(segment
		(start 181.302914 -155.223718)
		(end 181.593744 -155.514548)
		(width 0.1651)
		(layer "In5.Cu")
		(net "P5E_PEX1_STN0_RX_DN<15>")
	)
	(segment
		(start 191.08928 -267.76807)
		(end 190.616078 -270.231616)
		(width 0.1651)
		(layer "In5.Cu")
		(net "P5E_PEX1_STN0_RX_DN<15>")
	)
	(segment
		(start 184.011316 -162.860482)
		(end 190.919354 -261.27202)
		(width 0.1651)
		(layer "In5.Cu")
		(net "P5E_PEX1_STN0_RX_DN<15>")
	)
	(segment
		(start 184.011316 -162.860736)
		(end 184.011316 -162.860482)
		(width 0.1651)
		(layer "In5.Cu")
		(net "P5E_PEX1_STN0_RX_DN<15>")
	)
	(segment
		(start 181.593744 -155.514548)
		(end 182.44312 -155.514548)
		(width 0.1651)
		(layer "In5.Cu")
		(net "P5E_PEX1_STN0_RX_DN<15>")
	)
	(segment
		(start 189.845696 -154.15514)
		(end 190.008764 -153.992072)
		(width 0.13462)
		(layer "F.Cu")
		(net "P5E_PEX1_STN0_TX_C_DN<14>")
	)
	(segment
		(start 190.008764 -153.992072)
		(end 195.539868 -153.992072)
		(width 0.13462)
		(layer "F.Cu")
		(net "P5E_PEX1_STN0_TX_C_DN<14>")
	)
	(segment
		(start 195.539868 -153.992072)
		(end 195.852542 -154.304746)
		(width 0.13462)
		(layer "F.Cu")
		(net "P5E_PEX1_STN0_TX_C_DN<14>")
	)
	(segment
		(start 189.357508 -154.15514)
		(end 189.845696 -154.15514)
		(width 0.13462)
		(layer "F.Cu")
		(net "P5E_PEX1_STN0_TX_C_DN<14>")
	)
	(segment
		(start 184.757314 -124.834904)
		(end 184.26938 -124.834904)
		(width 0.13462)
		(layer "F.Cu")
		(net "P5E_PEX1_STN0_RX_DP<3>")
	)
	(segment
		(start 181.598062 -124.67209)
		(end 181.302914 -124.967238)
		(width 0.13462)
		(layer "F.Cu")
		(net "P5E_PEX1_STN0_RX_DP<3>")
	)
	(segment
		(start 184.26938 -124.834904)
		(end 184.106566 -124.67209)
		(width 0.13462)
		(layer "F.Cu")
		(net "P5E_PEX1_STN0_RX_DP<3>")
	)
	(segment
		(start 184.106566 -124.67209)
		(end 181.598062 -124.67209)
		(width 0.13462)
		(layer "F.Cu")
		(net "P5E_PEX1_STN0_RX_DP<3>")
	)
	(segment
		(start 197.979792 -285.335472)
		(end 197.865492 -285.449772)
		(width 0.1143)
		(layer "In5.Cu")
		(net "P5E_PEX1_STN0_RX_DP<3>")
	)
	(segment
		(start 200.021698 -284.833822)
		(end 199.975978 -284.879542)
		(width 0.1143)
		(layer "In5.Cu")
		(net "P5E_PEX1_STN0_RX_DP<3>")
	)
	(segment
		(start 210.352894 -276.487382)
		(end 202.400662 -284.196028)
		(width 0.1651)
		(layer "In5.Cu")
		(net "P5E_PEX1_STN0_RX_DP<3>")
	)
	(segment
		(start 192.058036 -131.381246)
		(end 192.312036 -131.806188)
		(width 0.1651)
		(layer "In5.Cu")
		(net "P5E_PEX1_STN0_RX_DP<3>")
	)
	(segment
		(start 184.112662 -124.822966)
		(end 184.20334 -124.957078)
		(width 0.1651)
		(layer "In5.Cu")
		(net "P5E_PEX1_STN0_RX_DP<3>")
	)
	(segment
		(start 204.019912 -240.358422)
		(end 212.554566 -269.578836)
		(width 0.1651)
		(layer "In5.Cu")
		(net "P5E_PEX1_STN0_RX_DP<3>")
	)
	(segment
		(start 197.979792 -285.09468)
		(end 197.979792 -285.335472)
		(width 0.1143)
		(layer "In5.Cu")
		(net "P5E_PEX1_STN0_RX_DP<3>")
	)
	(segment
		(start 186.203336 -125.364494)
		(end 186.203336 -125.364748)
		(width 0.1651)
		(layer "In5.Cu")
		(net "P5E_PEX1_STN0_RX_DP<3>")
	)
	(segment
		(start 191.432942 -130.334512)
		(end 191.432688 -130.334512)
		(width 0.1651)
		(layer "In5.Cu")
		(net "P5E_PEX1_STN0_RX_DP<3>")
	)
	(segment
		(start 191.647064 -130.916426)
		(end 191.901318 -131.341876)
		(width 0.1651)
		(layer "In5.Cu")
		(net "P5E_PEX1_STN0_RX_DP<3>")
	)
	(segment
		(start 189.989206 -127.918464)
		(end 189.949582 -128.075182)
		(width 0.1651)
		(layer "In5.Cu")
		(net "P5E_PEX1_STN0_RX_DP<3>")
	)
	(segment
		(start 188.75883 -126.426722)
		(end 189.57163 -127.219456)
		(width 0.1651)
		(layer "In5.Cu")
		(net "P5E_PEX1_STN0_RX_DP<3>")
	)
	(segment
		(start 192.272412 -131.96316)
		(end 192.526666 -132.38861)
		(width 0.1651)
		(layer "In5.Cu")
		(net "P5E_PEX1_STN0_RX_DP<3>")
	)
	(segment
		(start 191.276224 -130.295142)
		(end 191.432942 -130.334512)
		(width 0.1651)
		(layer "In5.Cu")
		(net "P5E_PEX1_STN0_RX_DP<3>")
	)
	(segment
		(start 201.300588 -284.833822)
		(end 200.050146 -284.833822)
		(width 0.1651)
		(layer "In5.Cu")
		(net "P5E_PEX1_STN0_RX_DP<3>")
	)
	(segment
		(start 181.302914 -124.967238)
		(end 181.593744 -124.676408)
		(width 0.1651)
		(layer "In5.Cu")
		(net "P5E_PEX1_STN0_RX_DP<3>")
	)
	(segment
		(start 195.93814 -137.875264)
		(end 198.150988 -139.342368)
		(width 0.1651)
		(layer "In5.Cu")
		(net "P5E_PEX1_STN0_RX_DP<3>")
	)
	(segment
		(start 191.432688 -130.334512)
		(end 191.686688 -130.759454)
		(width 0.1651)
		(layer "In5.Cu")
		(net "P5E_PEX1_STN0_RX_DP<3>")
	)
	(segment
		(start 186.265058 -125.514354)
		(end 186.722512 -125.704346)
		(width 0.1651)
		(layer "In5.Cu")
		(net "P5E_PEX1_STN0_RX_DP<3>")
	)
	(segment
		(start 191.021716 -129.869692)
		(end 191.276224 -130.295142)
		(width 0.1651)
		(layer "In5.Cu")
		(net "P5E_PEX1_STN0_RX_DP<3>")
	)
	(segment
		(start 198.19493 -284.879542)
		(end 197.979792 -285.09468)
		(width 0.1143)
		(layer "In5.Cu")
		(net "P5E_PEX1_STN0_RX_DP<3>")
	)
	(segment
		(start 201.687176 -144.429226)
		(end 202.482196 -150.0505)
		(width 0.1651)
		(layer "In5.Cu")
		(net "P5E_PEX1_STN0_RX_DP<3>")
	)
	(segment
		(start 191.686688 -130.759454)
		(end 191.647064 -130.916426)
		(width 0.1651)
		(layer "In5.Cu")
		(net "P5E_PEX1_STN0_RX_DP<3>")
	)
	(segment
		(start 202.28941 -232.225596)
		(end 204.019912 -240.358422)
		(width 0.1651)
		(layer "In5.Cu")
		(net "P5E_PEX1_STN0_RX_DP<3>")
	)
	(segment
		(start 192.526666 -132.38861)
		(end 192.683384 -132.42798)
		(width 0.1651)
		(layer "In5.Cu")
		(net "P5E_PEX1_STN0_RX_DP<3>")
	)
	(segment
		(start 199.975978 -284.879542)
		(end 198.19493 -284.879542)
		(width 0.1143)
		(layer "In5.Cu")
		(net "P5E_PEX1_STN0_RX_DP<3>")
	)
	(segment
		(start 198.472298 -140.240512)
		(end 201.687176 -144.429226)
		(width 0.1651)
		(layer "In5.Cu")
		(net "P5E_PEX1_STN0_RX_DP<3>")
	)
	(segment
		(start 189.57163 -127.219456)
		(end 189.989206 -127.918464)
		(width 0.1651)
		(layer "In5.Cu")
		(net "P5E_PEX1_STN0_RX_DP<3>")
	)
	(segment
		(start 202.400662 -284.196028)
		(end 201.300588 -284.833822)
		(width 0.1651)
		(layer "In5.Cu")
		(net "P5E_PEX1_STN0_RX_DP<3>")
	)
	(segment
		(start 192.312036 -131.806188)
		(end 192.272412 -131.96316)
		(width 0.1651)
		(layer "In5.Cu")
		(net "P5E_PEX1_STN0_RX_DP<3>")
	)
	(segment
		(start 186.722512 -125.704346)
		(end 186.871864 -125.642624)
		(width 0.1651)
		(layer "In5.Cu")
		(net "P5E_PEX1_STN0_RX_DP<3>")
	)
	(segment
		(start 191.901318 -131.341876)
		(end 192.058036 -131.381246)
		(width 0.1651)
		(layer "In5.Cu")
		(net "P5E_PEX1_STN0_RX_DP<3>")
	)
	(segment
		(start 202.944476 -168.404286)
		(end 202.28941 -232.225596)
		(width 0.1651)
		(layer "In5.Cu")
		(net "P5E_PEX1_STN0_RX_DP<3>")
	)
	(segment
		(start 197.865492 -285.449772)
		(end 197.600062 -285.449772)
		(width 0.1143)
		(layer "In5.Cu")
		(net "P5E_PEX1_STN0_RX_DP<3>")
	)
	(segment
		(start 184.20334 -124.957078)
		(end 184.68975 -125.051058)
		(width 0.1651)
		(layer "In5.Cu")
		(net "P5E_PEX1_STN0_RX_DP<3>")
	)
	(segment
		(start 200.050146 -284.833822)
		(end 200.021698 -284.833822)
		(width 0.1143)
		(layer "In5.Cu")
		(net "P5E_PEX1_STN0_RX_DP<3>")
	)
	(segment
		(start 202.482196 -150.0505)
		(end 202.944476 -168.404286)
		(width 0.1651)
		(layer "In5.Cu")
		(net "P5E_PEX1_STN0_RX_DP<3>")
	)
	(segment
		(start 190.20409 -128.500632)
		(end 190.360808 -128.540256)
		(width 0.1651)
		(layer "In5.Cu")
		(net "P5E_PEX1_STN0_RX_DP<3>")
	)
	(segment
		(start 191.06134 -129.712974)
		(end 191.021716 -129.869692)
		(width 0.1651)
		(layer "In5.Cu")
		(net "P5E_PEX1_STN0_RX_DP<3>")
	)
	(segment
		(start 190.360808 -128.540256)
		(end 191.06134 -129.712974)
		(width 0.1651)
		(layer "In5.Cu")
		(net "P5E_PEX1_STN0_RX_DP<3>")
	)
	(segment
		(start 189.949582 -128.075182)
		(end 190.20409 -128.500632)
		(width 0.1651)
		(layer "In5.Cu")
		(net "P5E_PEX1_STN0_RX_DP<3>")
	)
	(segment
		(start 184.823608 -124.960634)
		(end 185.586116 -125.107954)
		(width 0.1651)
		(layer "In5.Cu")
		(net "P5E_PEX1_STN0_RX_DP<3>")
	)
	(segment
		(start 186.871864 -125.642624)
		(end 188.75883 -126.426722)
		(width 0.1651)
		(layer "In5.Cu")
		(net "P5E_PEX1_STN0_RX_DP<3>")
	)
	(segment
		(start 212.444838 -272.77822)
		(end 210.352894 -276.487382)
		(width 0.1651)
		(layer "In5.Cu")
		(net "P5E_PEX1_STN0_RX_DP<3>")
	)
	(segment
		(start 185.586116 -125.107954)
		(end 186.203336 -125.364494)
		(width 0.1651)
		(layer "In5.Cu")
		(net "P5E_PEX1_STN0_RX_DP<3>")
	)
	(segment
		(start 186.203336 -125.364748)
		(end 186.265058 -125.514354)
		(width 0.1651)
		(layer "In5.Cu")
		(net "P5E_PEX1_STN0_RX_DP<3>")
	)
	(segment
		(start 212.554566 -269.578836)
		(end 212.444838 -272.77822)
		(width 0.1651)
		(layer "In5.Cu")
		(net "P5E_PEX1_STN0_RX_DP<3>")
	)
	(segment
		(start 181.593744 -124.676408)
		(end 183.354726 -124.676408)
		(width 0.1651)
		(layer "In5.Cu")
		(net "P5E_PEX1_STN0_RX_DP<3>")
	)
	(segment
		(start 184.68975 -125.051058)
		(end 184.823608 -124.960634)
		(width 0.1651)
		(layer "In5.Cu")
		(net "P5E_PEX1_STN0_RX_DP<3>")
	)
	(segment
		(start 183.354726 -124.676408)
		(end 184.112662 -124.822966)
		(width 0.1651)
		(layer "In5.Cu")
		(net "P5E_PEX1_STN0_RX_DP<3>")
	)
	(segment
		(start 192.683384 -132.42798)
		(end 195.93814 -137.875264)
		(width 0.1651)
		(layer "In5.Cu")
		(net "P5E_PEX1_STN0_RX_DP<3>")
	)
	(segment
		(start 198.150988 -139.342368)
		(end 198.472298 -140.240512)
		(width 0.1651)
		(layer "In5.Cu")
		(net "P5E_PEX1_STN0_RX_DP<3>")
	)
	(segment
		(start 198.173594 -135.607806)
		(end 198.49465 -135.28675)
		(width 0.13462)
		(layer "F.Cu")
		(net "P5E_PEX1_STN0_TX_C_DN<7>")
	)
	(segment
		(start 189.357508 -135.444992)
		(end 189.845696 -135.444992)
		(width 0.13462)
		(layer "F.Cu")
		(net "P5E_PEX1_STN0_TX_C_DN<7>")
	)
	(segment
		(start 190.00851 -135.607806)
		(end 198.173594 -135.607806)
		(width 0.13462)
		(layer "F.Cu")
		(net "P5E_PEX1_STN0_TX_C_DN<7>")
	)
	(segment
		(start 189.845696 -135.444992)
		(end 190.00851 -135.607806)
		(width 0.13462)
		(layer "F.Cu")
		(net "P5E_PEX1_STN0_TX_C_DN<7>")
	)
	(segment
		(start 183.157114 -122.303794)
		(end 183.451246 -122.597926)
		(width 0.13462)
		(layer "F.Cu")
		(net "P5E_PEX1_STN0_RX_DN<2>")
	)
	(segment
		(start 183.157114 -122.30354)
		(end 183.157114 -122.303794)
		(width 0.13462)
		(layer "F.Cu")
		(net "P5E_PEX1_STN0_RX_DN<2>")
	)
	(segment
		(start 184.106566 -122.597926)
		(end 184.26938 -122.435112)
		(width 0.13462)
		(layer "F.Cu")
		(net "P5E_PEX1_STN0_RX_DN<2>")
	)
	(segment
		(start 184.26938 -122.435112)
		(end 184.757314 -122.435112)
		(width 0.13462)
		(layer "F.Cu")
		(net "P5E_PEX1_STN0_RX_DN<2>")
	)
	(segment
		(start 183.451246 -122.597926)
		(end 184.106566 -122.597926)
		(width 0.13462)
		(layer "F.Cu")
		(net "P5E_PEX1_STN0_RX_DN<2>")
	)
	(segment
		(start 184.074562 -122.59437)
		(end 188.789056 -124.55398)
		(width 0.1651)
		(layer "In5.Cu")
		(net "P5E_PEX1_STN0_RX_DN<2>")
	)
	(segment
		(start 203.040488 -285.298642)
		(end 201.619358 -286.034226)
		(width 0.1651)
		(layer "In5.Cu")
		(net "P5E_PEX1_STN0_RX_DN<2>")
	)
	(segment
		(start 190.704216 -126.48184)
		(end 195.748656 -134.04088)
		(width 0.1651)
		(layer "In5.Cu")
		(net "P5E_PEX1_STN0_RX_DN<2>")
	)
	(segment
		(start 202.835764 -143.552926)
		(end 203.746608 -149.960838)
		(width 0.1651)
		(layer "In5.Cu")
		(net "P5E_PEX1_STN0_RX_DN<2>")
	)
	(segment
		(start 211.338668 -277.258272)
		(end 203.040488 -285.298642)
		(width 0.1651)
		(layer "In5.Cu")
		(net "P5E_PEX1_STN0_RX_DN<2>")
	)
	(segment
		(start 196.270118 -286.15259)
		(end 196.270118 -286.285432)
		(width 0.1143)
		(layer "In5.Cu")
		(net "P5E_PEX1_STN0_RX_DN<2>")
	)
	(segment
		(start 203.746608 -149.960838)
		(end 204.24267 -168.455086)
		(width 0.1651)
		(layer "In5.Cu")
		(net "P5E_PEX1_STN0_RX_DN<2>")
	)
	(segment
		(start 196.402706 -286.020002)
		(end 196.270118 -286.15259)
		(width 0.1143)
		(layer "In5.Cu")
		(net "P5E_PEX1_STN0_RX_DN<2>")
	)
	(segment
		(start 201.587862 -286.065722)
		(end 200.024746 -286.065722)
		(width 0.1651)
		(layer "In5.Cu")
		(net "P5E_PEX1_STN0_RX_DN<2>")
	)
	(segment
		(start 213.835488 -269.474696)
		(end 213.667086 -273.153378)
		(width 0.1651)
		(layer "In5.Cu")
		(net "P5E_PEX1_STN0_RX_DN<2>")
	)
	(segment
		(start 183.447944 -122.59437)
		(end 184.074562 -122.59437)
		(width 0.1651)
		(layer "In5.Cu")
		(net "P5E_PEX1_STN0_RX_DN<2>")
	)
	(segment
		(start 200.043542 -138.329924)
		(end 202.835764 -143.552926)
		(width 0.1651)
		(layer "In5.Cu")
		(net "P5E_PEX1_STN0_RX_DN<2>")
	)
	(segment
		(start 203.536296 -232.139744)
		(end 205.183994 -239.882426)
		(width 0.1651)
		(layer "In5.Cu")
		(net "P5E_PEX1_STN0_RX_DN<2>")
	)
	(segment
		(start 213.667086 -273.153378)
		(end 211.338668 -277.258272)
		(width 0.1651)
		(layer "In5.Cu")
		(net "P5E_PEX1_STN0_RX_DN<2>")
	)
	(segment
		(start 196.384418 -286.399732)
		(end 196.649848 -286.399732)
		(width 0.1143)
		(layer "In5.Cu")
		(net "P5E_PEX1_STN0_RX_DN<2>")
	)
	(segment
		(start 204.24267 -168.455086)
		(end 203.536296 -232.139744)
		(width 0.1651)
		(layer "In5.Cu")
		(net "P5E_PEX1_STN0_RX_DN<2>")
	)
	(segment
		(start 188.789056 -124.55398)
		(end 190.704216 -126.48184)
		(width 0.1651)
		(layer "In5.Cu")
		(net "P5E_PEX1_STN0_RX_DN<2>")
	)
	(segment
		(start 199.996298 -286.065722)
		(end 199.950578 -286.020002)
		(width 0.1143)
		(layer "In5.Cu")
		(net "P5E_PEX1_STN0_RX_DN<2>")
	)
	(segment
		(start 195.748656 -134.04088)
		(end 200.043542 -138.329924)
		(width 0.1651)
		(layer "In5.Cu")
		(net "P5E_PEX1_STN0_RX_DN<2>")
	)
	(segment
		(start 205.183994 -239.882426)
		(end 213.835488 -269.474696)
		(width 0.1651)
		(layer "In5.Cu")
		(net "P5E_PEX1_STN0_RX_DN<2>")
	)
	(segment
		(start 183.157114 -122.30354)
		(end 183.447944 -122.59437)
		(width 0.1651)
		(layer "In5.Cu")
		(net "P5E_PEX1_STN0_RX_DN<2>")
	)
	(segment
		(start 200.024746 -286.065722)
		(end 199.996298 -286.065722)
		(width 0.1143)
		(layer "In5.Cu")
		(net "P5E_PEX1_STN0_RX_DN<2>")
	)
	(segment
		(start 201.619358 -286.034226)
		(end 201.587862 -286.065722)
		(width 0.1651)
		(layer "In5.Cu")
		(net "P5E_PEX1_STN0_RX_DN<2>")
	)
	(segment
		(start 199.950578 -286.020002)
		(end 196.402706 -286.020002)
		(width 0.1143)
		(layer "In5.Cu")
		(net "P5E_PEX1_STN0_RX_DN<2>")
	)
	(segment
		(start 196.270118 -286.285432)
		(end 196.384418 -286.399732)
		(width 0.1143)
		(layer "In5.Cu")
		(net "P5E_PEX1_STN0_RX_DN<2>")
	)
	(segment
		(start 181.598062 -124.39777)
		(end 181.597554 -124.398278)
		(width 0.13462)
		(layer "F.Cu")
		(net "P5E_PEX1_STN0_RX_DN<3>")
	)
	(segment
		(start 184.757314 -124.234956)
		(end 184.26938 -124.234956)
		(width 0.13462)
		(layer "F.Cu")
		(net "P5E_PEX1_STN0_RX_DN<3>")
	)
	(segment
		(start 184.106566 -124.39777)
		(end 181.598062 -124.39777)
		(width 0.13462)
		(layer "F.Cu")
		(net "P5E_PEX1_STN0_RX_DN<3>")
	)
	(segment
		(start 181.597554 -124.398278)
		(end 181.302914 -124.103638)
		(width 0.13462)
		(layer "F.Cu")
		(net "P5E_PEX1_STN0_RX_DN<3>")
	)
	(segment
		(start 184.26938 -124.234956)
		(end 184.106566 -124.39777)
		(width 0.13462)
		(layer "F.Cu")
		(net "P5E_PEX1_STN0_RX_DN<3>")
	)
	(segment
		(start 201.376534 -285.115762)
		(end 200.050146 -285.115762)
		(width 0.1651)
		(layer "In5.Cu")
		(net "P5E_PEX1_STN0_RX_DN<3>")
	)
	(segment
		(start 212.83803 -269.543276)
		(end 212.724492 -272.856706)
		(width 0.1651)
		(layer "In5.Cu")
		(net "P5E_PEX1_STN0_RX_DN<3>")
	)
	(segment
		(start 196.147436 -137.67562)
		(end 198.385176 -139.15898)
		(width 0.1651)
		(layer "In5.Cu")
		(net "P5E_PEX1_STN0_RX_DN<3>")
	)
	(segment
		(start 200.050146 -285.115762)
		(end 200.021698 -285.115762)
		(width 0.1143)
		(layer "In5.Cu")
		(net "P5E_PEX1_STN0_RX_DN<3>")
	)
	(segment
		(start 210.5787 -276.661626)
		(end 202.572112 -284.422596)
		(width 0.1651)
		(layer "In5.Cu")
		(net "P5E_PEX1_STN0_RX_DN<3>")
	)
	(segment
		(start 200.021698 -285.115762)
		(end 199.975978 -285.070042)
		(width 0.1143)
		(layer "In5.Cu")
		(net "P5E_PEX1_STN0_RX_DN<3>")
	)
	(segment
		(start 181.302914 -124.103638)
		(end 181.593744 -124.394468)
		(width 0.1651)
		(layer "In5.Cu")
		(net "P5E_PEX1_STN0_RX_DN<3>")
	)
	(segment
		(start 198.385176 -139.15898)
		(end 198.722996 -140.10386)
		(width 0.1651)
		(layer "In5.Cu")
		(net "P5E_PEX1_STN0_RX_DN<3>")
	)
	(segment
		(start 204.293724 -240.289334)
		(end 212.83803 -269.543276)
		(width 0.1651)
		(layer "In5.Cu")
		(net "P5E_PEX1_STN0_RX_DN<3>")
	)
	(segment
		(start 212.724492 -272.856706)
		(end 210.5787 -276.661626)
		(width 0.1651)
		(layer "In5.Cu")
		(net "P5E_PEX1_STN0_RX_DN<3>")
	)
	(segment
		(start 202.571858 -232.197402)
		(end 204.293724 -240.289334)
		(width 0.1651)
		(layer "In5.Cu")
		(net "P5E_PEX1_STN0_RX_DN<3>")
	)
	(segment
		(start 198.170292 -285.335472)
		(end 198.284592 -285.449772)
		(width 0.1143)
		(layer "In5.Cu")
		(net "P5E_PEX1_STN0_RX_DN<3>")
	)
	(segment
		(start 201.956162 -144.316196)
		(end 202.763882 -150.027132)
		(width 0.1651)
		(layer "In5.Cu")
		(net "P5E_PEX1_STN0_RX_DN<3>")
	)
	(segment
		(start 198.170292 -285.173674)
		(end 198.170292 -285.335472)
		(width 0.1143)
		(layer "In5.Cu")
		(net "P5E_PEX1_STN0_RX_DN<3>")
	)
	(segment
		(start 198.722996 -140.10386)
		(end 201.956162 -144.316196)
		(width 0.1651)
		(layer "In5.Cu")
		(net "P5E_PEX1_STN0_RX_DN<3>")
	)
	(segment
		(start 202.572112 -284.422596)
		(end 201.376534 -285.115762)
		(width 0.1651)
		(layer "In5.Cu")
		(net "P5E_PEX1_STN0_RX_DN<3>")
	)
	(segment
		(start 203.22667 -168.402254)
		(end 202.571858 -232.197402)
		(width 0.1651)
		(layer "In5.Cu")
		(net "P5E_PEX1_STN0_RX_DN<3>")
	)
	(segment
		(start 198.284592 -285.449772)
		(end 198.550022 -285.449772)
		(width 0.1143)
		(layer "In5.Cu")
		(net "P5E_PEX1_STN0_RX_DN<3>")
	)
	(segment
		(start 198.273924 -285.070042)
		(end 198.170292 -285.173674)
		(width 0.1143)
		(layer "In5.Cu")
		(net "P5E_PEX1_STN0_RX_DN<3>")
	)
	(segment
		(start 188.91631 -126.186438)
		(end 189.794896 -127.04318)
		(width 0.1651)
		(layer "In5.Cu")
		(net "P5E_PEX1_STN0_RX_DN<3>")
	)
	(segment
		(start 202.763882 -150.027132)
		(end 203.22667 -168.402254)
		(width 0.1651)
		(layer "In5.Cu")
		(net "P5E_PEX1_STN0_RX_DN<3>")
	)
	(segment
		(start 181.593744 -124.394468)
		(end 183.381904 -124.394468)
		(width 0.1651)
		(layer "In5.Cu")
		(net "P5E_PEX1_STN0_RX_DN<3>")
	)
	(segment
		(start 185.667904 -124.836428)
		(end 188.91631 -126.186438)
		(width 0.1651)
		(layer "In5.Cu")
		(net "P5E_PEX1_STN0_RX_DN<3>")
	)
	(segment
		(start 199.975978 -285.070042)
		(end 198.273924 -285.070042)
		(width 0.1143)
		(layer "In5.Cu")
		(net "P5E_PEX1_STN0_RX_DN<3>")
	)
	(segment
		(start 183.381904 -124.394468)
		(end 185.667904 -124.836428)
		(width 0.1651)
		(layer "In5.Cu")
		(net "P5E_PEX1_STN0_RX_DN<3>")
	)
	(segment
		(start 189.794896 -127.04318)
		(end 196.147436 -137.67562)
		(width 0.1651)
		(layer "In5.Cu")
		(net "P5E_PEX1_STN0_RX_DN<3>")
	)
	(segment
		(start 184.26938 -120.635014)
		(end 184.106566 -120.797828)
		(width 0.13462)
		(layer "F.Cu")
		(net "P5E_PEX1_STN0_RX_DN<1>")
	)
	(segment
		(start 181.598062 -120.797828)
		(end 181.597554 -120.798336)
		(width 0.13462)
		(layer "F.Cu")
		(net "P5E_PEX1_STN0_RX_DN<1>")
	)
	(segment
		(start 184.757314 -120.635014)
		(end 184.26938 -120.635014)
		(width 0.13462)
		(layer "F.Cu")
		(net "P5E_PEX1_STN0_RX_DN<1>")
	)
	(segment
		(start 181.597554 -120.798336)
		(end 181.302914 -120.503696)
		(width 0.13462)
		(layer "F.Cu")
		(net "P5E_PEX1_STN0_RX_DN<1>")
	)
	(segment
		(start 184.106566 -120.797828)
		(end 181.598062 -120.797828)
		(width 0.13462)
		(layer "F.Cu")
		(net "P5E_PEX1_STN0_RX_DN<1>")
	)
	(segment
		(start 199.243696 -133.14426)
		(end 201.511916 -134.40664)
		(width 0.1651)
		(layer "In5.Cu")
		(net "P5E_PEX1_STN0_RX_DN<1>")
	)
	(segment
		(start 214.646764 -273.37258)
		(end 212.178392 -277.807928)
		(width 0.1651)
		(layer "In5.Cu")
		(net "P5E_PEX1_STN0_RX_DN<1>")
	)
	(segment
		(start 191.199516 -125.19406)
		(end 196.663056 -131.52882)
		(width 0.1651)
		(layer "In5.Cu")
		(net "P5E_PEX1_STN0_RX_DN<1>")
	)
	(segment
		(start 181.302914 -120.503696)
		(end 181.593744 -120.794526)
		(width 0.1651)
		(layer "In5.Cu")
		(net "P5E_PEX1_STN0_RX_DN<1>")
	)
	(segment
		(start 204.722222 -149.896322)
		(end 205.23073 -168.53408)
		(width 0.1651)
		(layer "In5.Cu")
		(net "P5E_PEX1_STN0_RX_DN<1>")
	)
	(segment
		(start 198.170292 -287.073848)
		(end 198.170292 -287.235646)
		(width 0.1143)
		(layer "In5.Cu")
		(net "P5E_PEX1_STN0_RX_DN<1>")
	)
	(segment
		(start 198.170292 -287.235646)
		(end 198.284592 -287.349946)
		(width 0.1143)
		(layer "In5.Cu")
		(net "P5E_PEX1_STN0_RX_DN<1>")
	)
	(segment
		(start 198.273924 -286.970216)
		(end 198.170292 -287.073848)
		(width 0.1143)
		(layer "In5.Cu")
		(net "P5E_PEX1_STN0_RX_DN<1>")
	)
	(segment
		(start 200.050146 -287.015936)
		(end 200.021698 -287.015936)
		(width 0.1143)
		(layer "In5.Cu")
		(net "P5E_PEX1_STN0_RX_DN<1>")
	)
	(segment
		(start 205.23073 -168.53408)
		(end 204.56779 -232.097072)
		(width 0.1651)
		(layer "In5.Cu")
		(net "P5E_PEX1_STN0_RX_DN<1>")
	)
	(segment
		(start 181.593744 -120.794526)
		(end 183.715914 -120.794526)
		(width 0.1651)
		(layer "In5.Cu")
		(net "P5E_PEX1_STN0_RX_DN<1>")
	)
	(segment
		(start 203.57465 -286.11068)
		(end 202.10018 -287.015936)
		(width 0.1651)
		(layer "In5.Cu")
		(net "P5E_PEX1_STN0_RX_DN<1>")
	)
	(segment
		(start 199.975978 -286.970216)
		(end 198.273924 -286.970216)
		(width 0.1143)
		(layer "In5.Cu")
		(net "P5E_PEX1_STN0_RX_DN<1>")
	)
	(segment
		(start 206.014066 -239.19307)
		(end 214.798656 -269.2781)
		(width 0.1651)
		(layer "In5.Cu")
		(net "P5E_PEX1_STN0_RX_DN<1>")
	)
	(segment
		(start 196.663056 -131.52882)
		(end 198.814436 -132.715)
		(width 0.1651)
		(layer "In5.Cu")
		(net "P5E_PEX1_STN0_RX_DN<1>")
	)
	(segment
		(start 214.798656 -269.2781)
		(end 214.646764 -273.37258)
		(width 0.1651)
		(layer "In5.Cu")
		(net "P5E_PEX1_STN0_RX_DN<1>")
	)
	(segment
		(start 202.10018 -287.015936)
		(end 200.050146 -287.015936)
		(width 0.1651)
		(layer "In5.Cu")
		(net "P5E_PEX1_STN0_RX_DN<1>")
	)
	(segment
		(start 183.715914 -120.794526)
		(end 188.956696 -122.97664)
		(width 0.1651)
		(layer "In5.Cu")
		(net "P5E_PEX1_STN0_RX_DN<1>")
	)
	(segment
		(start 212.178392 -277.807928)
		(end 203.57465 -286.11068)
		(width 0.1651)
		(layer "In5.Cu")
		(net "P5E_PEX1_STN0_RX_DN<1>")
	)
	(segment
		(start 201.511916 -134.40664)
		(end 202.036426 -135.222996)
		(width 0.1651)
		(layer "In5.Cu")
		(net "P5E_PEX1_STN0_RX_DN<1>")
	)
	(segment
		(start 202.036426 -135.222996)
		(end 204.463904 -146.35226)
		(width 0.1651)
		(layer "In5.Cu")
		(net "P5E_PEX1_STN0_RX_DN<1>")
	)
	(segment
		(start 198.814436 -132.715)
		(end 199.243696 -133.14426)
		(width 0.1651)
		(layer "In5.Cu")
		(net "P5E_PEX1_STN0_RX_DN<1>")
	)
	(segment
		(start 188.956696 -122.97664)
		(end 191.199516 -125.19406)
		(width 0.1651)
		(layer "In5.Cu")
		(net "P5E_PEX1_STN0_RX_DN<1>")
	)
	(segment
		(start 204.463904 -146.35226)
		(end 204.722222 -149.896322)
		(width 0.1651)
		(layer "In5.Cu")
		(net "P5E_PEX1_STN0_RX_DN<1>")
	)
	(segment
		(start 204.56779 -232.097072)
		(end 206.014066 -239.19307)
		(width 0.1651)
		(layer "In5.Cu")
		(net "P5E_PEX1_STN0_RX_DN<1>")
	)
	(segment
		(start 198.284592 -287.349946)
		(end 198.550022 -287.349946)
		(width 0.1143)
		(layer "In5.Cu")
		(net "P5E_PEX1_STN0_RX_DN<1>")
	)
	(segment
		(start 200.021698 -287.015936)
		(end 199.975978 -286.970216)
		(width 0.1143)
		(layer "In5.Cu")
		(net "P5E_PEX1_STN0_RX_DN<1>")
	)
	(segment
		(start 184.106566 -134.082282)
		(end 184.26938 -134.245096)
		(width 0.13462)
		(layer "F.Cu")
		(net "P5E_PEX1_STN0_RX_DP<6>")
	)
	(segment
		(start 183.452008 -134.082282)
		(end 184.106566 -134.082282)
		(width 0.13462)
		(layer "F.Cu")
		(net "P5E_PEX1_STN0_RX_DP<6>")
	)
	(segment
		(start 183.157114 -134.377176)
		(end 183.452008 -134.082282)
		(width 0.13462)
		(layer "F.Cu")
		(net "P5E_PEX1_STN0_RX_DP<6>")
	)
	(segment
		(start 184.26938 -134.245096)
		(end 184.757314 -134.245096)
		(width 0.13462)
		(layer "F.Cu")
		(net "P5E_PEX1_STN0_RX_DP<6>")
	)
	(segment
		(start 199.950578 -282.029662)
		(end 196.323712 -282.029662)
		(width 0.1143)
		(layer "In5.Cu")
		(net "P5E_PEX1_STN0_RX_DP<6>")
	)
	(segment
		(start 183.157114 -134.377176)
		(end 183.447944 -134.086346)
		(width 0.1651)
		(layer "In5.Cu")
		(net "P5E_PEX1_STN0_RX_DP<6>")
	)
	(segment
		(start 199.61225 -264.723118)
		(end 200.788524 -272.551398)
		(width 0.1651)
		(layer "In5.Cu")
		(net "P5E_PEX1_STN0_RX_DP<6>")
	)
	(segment
		(start 192.567306 -139.025376)
		(end 192.703958 -139.813284)
		(width 0.1651)
		(layer "In5.Cu")
		(net "P5E_PEX1_STN0_RX_DP<6>")
	)
	(segment
		(start 185.16981 -134.964678)
		(end 185.324496 -134.917942)
		(width 0.1651)
		(layer "In5.Cu")
		(net "P5E_PEX1_STN0_RX_DP<6>")
	)
	(segment
		(start 201.564494 -280.582116)
		(end 201.35596 -281.074368)
		(width 0.1651)
		(layer "In5.Cu")
		(net "P5E_PEX1_STN0_RX_DP<6>")
	)
	(segment
		(start 200.788524 -272.551398)
		(end 201.651362 -277.085044)
		(width 0.1651)
		(layer "In5.Cu")
		(net "P5E_PEX1_STN0_RX_DP<6>")
	)
	(segment
		(start 185.324496 -134.917942)
		(end 185.760868 -135.15213)
		(width 0.1651)
		(layer "In5.Cu")
		(net "P5E_PEX1_STN0_RX_DP<6>")
	)
	(segment
		(start 189.921642 -137.385806)
		(end 190.358014 -137.619994)
		(width 0.1651)
		(layer "In5.Cu")
		(net "P5E_PEX1_STN0_RX_DP<6>")
	)
	(segment
		(start 184.733184 -134.729982)
		(end 185.16981 -134.964678)
		(width 0.1651)
		(layer "In5.Cu")
		(net "P5E_PEX1_STN0_RX_DP<6>")
	)
	(segment
		(start 189.766702 -137.432288)
		(end 189.921642 -137.385806)
		(width 0.1651)
		(layer "In5.Cu")
		(net "P5E_PEX1_STN0_RX_DP<6>")
	)
	(segment
		(start 196.323712 -282.029662)
		(end 196.079618 -282.273756)
		(width 0.1143)
		(layer "In5.Cu")
		(net "P5E_PEX1_STN0_RX_DP<6>")
	)
	(segment
		(start 185.760868 -135.15213)
		(end 185.80735 -135.306816)
		(width 0.1651)
		(layer "In5.Cu")
		(net "P5E_PEX1_STN0_RX_DP<6>")
	)
	(segment
		(start 201.651362 -277.085044)
		(end 201.651362 -277.085552)
		(width 0.1651)
		(layer "In5.Cu")
		(net "P5E_PEX1_STN0_RX_DP<6>")
	)
	(segment
		(start 183.447944 -134.086346)
		(end 183.775604 -134.086346)
		(width 0.1651)
		(layer "In5.Cu")
		(net "P5E_PEX1_STN0_RX_DP<6>")
	)
	(segment
		(start 201.651362 -277.085552)
		(end 201.564494 -280.582116)
		(width 0.1651)
		(layer "In5.Cu")
		(net "P5E_PEX1_STN0_RX_DP<6>")
	)
	(segment
		(start 186.88177 -135.88365)
		(end 187.318396 -136.118092)
		(width 0.1651)
		(layer "In5.Cu")
		(net "P5E_PEX1_STN0_RX_DP<6>")
	)
	(segment
		(start 188.847222 -136.808972)
		(end 189.283594 -137.04316)
		(width 0.1651)
		(layer "In5.Cu")
		(net "P5E_PEX1_STN0_RX_DP<6>")
	)
	(segment
		(start 195.965318 -282.599892)
		(end 195.699888 -282.599892)
		(width 0.1143)
		(layer "In5.Cu")
		(net "P5E_PEX1_STN0_RX_DP<6>")
	)
	(segment
		(start 201.35596 -281.074368)
		(end 200.91527 -281.606244)
		(width 0.1651)
		(layer "In5.Cu")
		(net "P5E_PEX1_STN0_RX_DP<6>")
	)
	(segment
		(start 183.775604 -134.086346)
		(end 184.686448 -134.575296)
		(width 0.1651)
		(layer "In5.Cu")
		(net "P5E_PEX1_STN0_RX_DP<6>")
	)
	(segment
		(start 190.358014 -137.619994)
		(end 190.404496 -137.77468)
		(width 0.1651)
		(layer "In5.Cu")
		(net "P5E_PEX1_STN0_RX_DP<6>")
	)
	(segment
		(start 188.692282 -136.855708)
		(end 188.847222 -136.808972)
		(width 0.1651)
		(layer "In5.Cu")
		(net "P5E_PEX1_STN0_RX_DP<6>")
	)
	(segment
		(start 187.318396 -136.118092)
		(end 187.473336 -136.07161)
		(width 0.1651)
		(layer "In5.Cu")
		(net "P5E_PEX1_STN0_RX_DP<6>")
	)
	(segment
		(start 200.91527 -281.606244)
		(end 200.350628 -281.983942)
		(width 0.1651)
		(layer "In5.Cu")
		(net "P5E_PEX1_STN0_RX_DP<6>")
	)
	(segment
		(start 187.473336 -136.07161)
		(end 188.209174 -136.46658)
		(width 0.1651)
		(layer "In5.Cu")
		(net "P5E_PEX1_STN0_RX_DP<6>")
	)
	(segment
		(start 200.024746 -281.983942)
		(end 199.996298 -281.983942)
		(width 0.1143)
		(layer "In5.Cu")
		(net "P5E_PEX1_STN0_RX_DP<6>")
	)
	(segment
		(start 188.209174 -136.46658)
		(end 188.255656 -136.621266)
		(width 0.1651)
		(layer "In5.Cu")
		(net "P5E_PEX1_STN0_RX_DP<6>")
	)
	(segment
		(start 188.255656 -136.621266)
		(end 188.692282 -136.855708)
		(width 0.1651)
		(layer "In5.Cu")
		(net "P5E_PEX1_STN0_RX_DP<6>")
	)
	(segment
		(start 192.703958 -139.813284)
		(end 192.703958 -140.932662)
		(width 0.1651)
		(layer "In5.Cu")
		(net "P5E_PEX1_STN0_RX_DP<6>")
	)
	(segment
		(start 186.398916 -135.494776)
		(end 186.835288 -135.728964)
		(width 0.1651)
		(layer "In5.Cu")
		(net "P5E_PEX1_STN0_RX_DP<6>")
	)
	(segment
		(start 184.686448 -134.575296)
		(end 184.733184 -134.729982)
		(width 0.1651)
		(layer "In5.Cu")
		(net "P5E_PEX1_STN0_RX_DP<6>")
	)
	(segment
		(start 190.404496 -137.77468)
		(end 190.841122 -138.009122)
		(width 0.1651)
		(layer "In5.Cu")
		(net "P5E_PEX1_STN0_RX_DP<6>")
	)
	(segment
		(start 199.996298 -281.983942)
		(end 199.950578 -282.029662)
		(width 0.1143)
		(layer "In5.Cu")
		(net "P5E_PEX1_STN0_RX_DP<6>")
	)
	(segment
		(start 186.835288 -135.728964)
		(end 186.88177 -135.88365)
		(width 0.1651)
		(layer "In5.Cu")
		(net "P5E_PEX1_STN0_RX_DP<6>")
	)
	(segment
		(start 196.079618 -282.273756)
		(end 196.079618 -282.485592)
		(width 0.1143)
		(layer "In5.Cu")
		(net "P5E_PEX1_STN0_RX_DP<6>")
	)
	(segment
		(start 196.079618 -282.485592)
		(end 195.965318 -282.599892)
		(width 0.1143)
		(layer "In5.Cu")
		(net "P5E_PEX1_STN0_RX_DP<6>")
	)
	(segment
		(start 189.283594 -137.04316)
		(end 189.330076 -137.197846)
		(width 0.1651)
		(layer "In5.Cu")
		(net "P5E_PEX1_STN0_RX_DP<6>")
	)
	(segment
		(start 190.996062 -137.96264)
		(end 190.996316 -137.96264)
		(width 0.1651)
		(layer "In5.Cu")
		(net "P5E_PEX1_STN0_RX_DP<6>")
	)
	(segment
		(start 189.330076 -137.197846)
		(end 189.766702 -137.432288)
		(width 0.1651)
		(layer "In5.Cu")
		(net "P5E_PEX1_STN0_RX_DP<6>")
	)
	(segment
		(start 196.05625 -160.27273)
		(end 199.61225 -264.723118)
		(width 0.1651)
		(layer "In5.Cu")
		(net "P5E_PEX1_STN0_RX_DP<6>")
	)
	(segment
		(start 186.243976 -135.541258)
		(end 186.398916 -135.494776)
		(width 0.1651)
		(layer "In5.Cu")
		(net "P5E_PEX1_STN0_RX_DP<6>")
	)
	(segment
		(start 190.841122 -138.009122)
		(end 190.996062 -137.96264)
		(width 0.1651)
		(layer "In5.Cu")
		(net "P5E_PEX1_STN0_RX_DP<6>")
	)
	(segment
		(start 185.80735 -135.306816)
		(end 186.243976 -135.541258)
		(width 0.1651)
		(layer "In5.Cu")
		(net "P5E_PEX1_STN0_RX_DP<6>")
	)
	(segment
		(start 200.350628 -281.983942)
		(end 200.024746 -281.983942)
		(width 0.1651)
		(layer "In5.Cu")
		(net "P5E_PEX1_STN0_RX_DP<6>")
	)
	(segment
		(start 192.703958 -140.932662)
		(end 196.05625 -160.27273)
		(width 0.1651)
		(layer "In5.Cu")
		(net "P5E_PEX1_STN0_RX_DP<6>")
	)
	(segment
		(start 192.230756 -138.625326)
		(end 192.567306 -139.025376)
		(width 0.1651)
		(layer "In5.Cu")
		(net "P5E_PEX1_STN0_RX_DP<6>")
	)
	(segment
		(start 190.996316 -137.96264)
		(end 192.230756 -138.625326)
		(width 0.1651)
		(layer "In5.Cu")
		(net "P5E_PEX1_STN0_RX_DP<6>")
	)
	(segment
		(start 184.26938 -119.435118)
		(end 184.106312 -119.27205)
		(width 0.13462)
		(layer "F.Cu")
		(net "P5E_PEX1_STN0_RX_DP<0>")
	)
	(segment
		(start 184.757314 -119.435118)
		(end 184.26938 -119.435118)
		(width 0.13462)
		(layer "F.Cu")
		(net "P5E_PEX1_STN0_RX_DP<0>")
	)
	(segment
		(start 183.452262 -119.27205)
		(end 183.157114 -119.567198)
		(width 0.13462)
		(layer "F.Cu")
		(net "P5E_PEX1_STN0_RX_DP<0>")
	)
	(segment
		(start 184.106312 -119.27205)
		(end 183.452262 -119.27205)
		(width 0.13462)
		(layer "F.Cu")
		(net "P5E_PEX1_STN0_RX_DP<0>")
	)
	(segment
		(start 184.384442 -119.465598)
		(end 184.446418 -119.615204)
		(width 0.1651)
		(layer "In5.Cu")
		(net "P5E_PEX1_STN0_RX_DP<0>")
	)
	(segment
		(start 212.715602 -278.22525)
		(end 203.659486 -286.969708)
		(width 0.1651)
		(layer "In5.Cu")
		(net "P5E_PEX1_STN0_RX_DP<0>")
	)
	(segment
		(start 194.433444 -126.076456)
		(end 194.59321 -126.053088)
		(width 0.1651)
		(layer "In5.Cu")
		(net "P5E_PEX1_STN0_RX_DP<0>")
	)
	(segment
		(start 184.384442 -119.465852)
		(end 184.384442 -119.465598)
		(width 0.1651)
		(layer "In5.Cu")
		(net "P5E_PEX1_STN0_RX_DP<0>")
	)
	(segment
		(start 201.28865 -131.045458)
		(end 202.014582 -131.999482)
		(width 0.1651)
		(layer "In5.Cu")
		(net "P5E_PEX1_STN0_RX_DP<0>")
	)
	(segment
		(start 186.031124 -120.271032)
		(end 186.180476 -120.209056)
		(width 0.1651)
		(layer "In5.Cu")
		(net "P5E_PEX1_STN0_RX_DP<0>")
	)
	(segment
		(start 193.035428 -124.891038)
		(end 193.058542 -125.051058)
		(width 0.1651)
		(layer "In5.Cu")
		(net "P5E_PEX1_STN0_RX_DP<0>")
	)
	(segment
		(start 185.053732 -119.742712)
		(end 185.510932 -119.931942)
		(width 0.1651)
		(layer "In5.Cu")
		(net "P5E_PEX1_STN0_RX_DP<0>")
	)
	(segment
		(start 185.511186 -119.931942)
		(end 185.573162 -120.081548)
		(width 0.1651)
		(layer "In5.Cu")
		(net "P5E_PEX1_STN0_RX_DP<0>")
	)
	(segment
		(start 205.471776 -149.84476)
		(end 205.923896 -168.526206)
		(width 0.1651)
		(layer "In5.Cu")
		(net "P5E_PEX1_STN0_RX_DP<0>")
	)
	(segment
		(start 183.447944 -119.276368)
		(end 183.926734 -119.276368)
		(width 0.1651)
		(layer "In5.Cu")
		(net "P5E_PEX1_STN0_RX_DP<0>")
	)
	(segment
		(start 192.638426 -124.595128)
		(end 193.035428 -124.891038)
		(width 0.1651)
		(layer "In5.Cu")
		(net "P5E_PEX1_STN0_RX_DP<0>")
	)
	(segment
		(start 205.2574 -231.903016)
		(end 206.793338 -239.28705)
		(width 0.1651)
		(layer "In5.Cu")
		(net "P5E_PEX1_STN0_RX_DP<0>")
	)
	(segment
		(start 186.180476 -120.209056)
		(end 186.637676 -120.398286)
		(width 0.1651)
		(layer "In5.Cu")
		(net "P5E_PEX1_STN0_RX_DP<0>")
	)
	(segment
		(start 187.30722 -120.6754)
		(end 188.609224 -121.214388)
		(width 0.1651)
		(layer "In5.Cu")
		(net "P5E_PEX1_STN0_RX_DP<0>")
	)
	(segment
		(start 196.079618 -288.185606)
		(end 195.965318 -288.299906)
		(width 0.1143)
		(layer "In5.Cu")
		(net "P5E_PEX1_STN0_RX_DP<0>")
	)
	(segment
		(start 195.965318 -288.299906)
		(end 195.699888 -288.299906)
		(width 0.1143)
		(layer "In5.Cu")
		(net "P5E_PEX1_STN0_RX_DP<0>")
	)
	(segment
		(start 205.923896 -168.526206)
		(end 205.2574 -231.903016)
		(width 0.1651)
		(layer "In5.Cu")
		(net "P5E_PEX1_STN0_RX_DP<0>")
	)
	(segment
		(start 193.615818 -125.324108)
		(end 194.01282 -125.620018)
		(width 0.1651)
		(layer "In5.Cu")
		(net "P5E_PEX1_STN0_RX_DP<0>")
	)
	(segment
		(start 202.014582 -131.999482)
		(end 205.076806 -145.627852)
		(width 0.1651)
		(layer "In5.Cu")
		(net "P5E_PEX1_STN0_RX_DP<0>")
	)
	(segment
		(start 183.157114 -119.567198)
		(end 183.447944 -119.276368)
		(width 0.1651)
		(layer "In5.Cu")
		(net "P5E_PEX1_STN0_RX_DP<0>")
	)
	(segment
		(start 196.323712 -287.729676)
		(end 196.079618 -287.97377)
		(width 0.1143)
		(layer "In5.Cu")
		(net "P5E_PEX1_STN0_RX_DP<0>")
	)
	(segment
		(start 200.024746 -287.683956)
		(end 199.996298 -287.683956)
		(width 0.1143)
		(layer "In5.Cu")
		(net "P5E_PEX1_STN0_RX_DP<0>")
	)
	(segment
		(start 203.659486 -286.969708)
		(end 202.527408 -287.683956)
		(width 0.1651)
		(layer "In5.Cu")
		(net "P5E_PEX1_STN0_RX_DP<0>")
	)
	(segment
		(start 183.926734 -119.276368)
		(end 184.384442 -119.465852)
		(width 0.1651)
		(layer "In5.Cu")
		(net "P5E_PEX1_STN0_RX_DP<0>")
	)
	(segment
		(start 215.490806 -269.159482)
		(end 215.30945 -273.645376)
		(width 0.1651)
		(layer "In5.Cu")
		(net "P5E_PEX1_STN0_RX_DP<0>")
	)
	(segment
		(start 186.699906 -120.547892)
		(end 187.157868 -120.737376)
		(width 0.1651)
		(layer "In5.Cu")
		(net "P5E_PEX1_STN0_RX_DP<0>")
	)
	(segment
		(start 192.478406 -124.618496)
		(end 192.638426 -124.595128)
		(width 0.1651)
		(layer "In5.Cu")
		(net "P5E_PEX1_STN0_RX_DP<0>")
	)
	(segment
		(start 193.058542 -125.051058)
		(end 193.456052 -125.347476)
		(width 0.1651)
		(layer "In5.Cu")
		(net "P5E_PEX1_STN0_RX_DP<0>")
	)
	(segment
		(start 184.90438 -119.804688)
		(end 185.053732 -119.742712)
		(width 0.1651)
		(layer "In5.Cu")
		(net "P5E_PEX1_STN0_RX_DP<0>")
	)
	(segment
		(start 202.527408 -287.683956)
		(end 200.024746 -287.683956)
		(width 0.1651)
		(layer "In5.Cu")
		(net "P5E_PEX1_STN0_RX_DP<0>")
	)
	(segment
		(start 215.30945 -273.645376)
		(end 212.715602 -278.22525)
		(width 0.1651)
		(layer "In5.Cu")
		(net "P5E_PEX1_STN0_RX_DP<0>")
	)
	(segment
		(start 185.510932 -119.931942)
		(end 185.511186 -119.931942)
		(width 0.1651)
		(layer "In5.Cu")
		(net "P5E_PEX1_STN0_RX_DP<0>")
	)
	(segment
		(start 192.08115 -124.322332)
		(end 192.478406 -124.618496)
		(width 0.1651)
		(layer "In5.Cu")
		(net "P5E_PEX1_STN0_RX_DP<0>")
	)
	(segment
		(start 186.637676 -120.398286)
		(end 186.63793 -120.398286)
		(width 0.1651)
		(layer "In5.Cu")
		(net "P5E_PEX1_STN0_RX_DP<0>")
	)
	(segment
		(start 193.456052 -125.347476)
		(end 193.615818 -125.324108)
		(width 0.1651)
		(layer "In5.Cu")
		(net "P5E_PEX1_STN0_RX_DP<0>")
	)
	(segment
		(start 188.609224 -121.214388)
		(end 190.107824 -122.708162)
		(width 0.1651)
		(layer "In5.Cu")
		(net "P5E_PEX1_STN0_RX_DP<0>")
	)
	(segment
		(start 186.63793 -120.398286)
		(end 186.699906 -120.547892)
		(width 0.1651)
		(layer "In5.Cu")
		(net "P5E_PEX1_STN0_RX_DP<0>")
	)
	(segment
		(start 194.035934 -125.780038)
		(end 194.433444 -126.076456)
		(width 0.1651)
		(layer "In5.Cu")
		(net "P5E_PEX1_STN0_RX_DP<0>")
	)
	(segment
		(start 196.079618 -287.97377)
		(end 196.079618 -288.185606)
		(width 0.1143)
		(layer "In5.Cu")
		(net "P5E_PEX1_STN0_RX_DP<0>")
	)
	(segment
		(start 194.01282 -125.620018)
		(end 194.035934 -125.780038)
		(width 0.1651)
		(layer "In5.Cu")
		(net "P5E_PEX1_STN0_RX_DP<0>")
	)
	(segment
		(start 184.446418 -119.615204)
		(end 184.90438 -119.804688)
		(width 0.1651)
		(layer "In5.Cu")
		(net "P5E_PEX1_STN0_RX_DP<0>")
	)
	(segment
		(start 205.076806 -145.627852)
		(end 205.471776 -149.84476)
		(width 0.1651)
		(layer "In5.Cu")
		(net "P5E_PEX1_STN0_RX_DP<0>")
	)
	(segment
		(start 199.996298 -287.683956)
		(end 199.950578 -287.729676)
		(width 0.1143)
		(layer "In5.Cu")
		(net "P5E_PEX1_STN0_RX_DP<0>")
	)
	(segment
		(start 185.573162 -120.081548)
		(end 186.031124 -120.271032)
		(width 0.1651)
		(layer "In5.Cu")
		(net "P5E_PEX1_STN0_RX_DP<0>")
	)
	(segment
		(start 199.950578 -287.729676)
		(end 196.323712 -287.729676)
		(width 0.1143)
		(layer "In5.Cu")
		(net "P5E_PEX1_STN0_RX_DP<0>")
	)
	(segment
		(start 206.793338 -239.28705)
		(end 215.490806 -269.159482)
		(width 0.1651)
		(layer "In5.Cu")
		(net "P5E_PEX1_STN0_RX_DP<0>")
	)
	(segment
		(start 194.59321 -126.053088)
		(end 201.28865 -131.045458)
		(width 0.1651)
		(layer "In5.Cu")
		(net "P5E_PEX1_STN0_RX_DP<0>")
	)
	(segment
		(start 190.107824 -122.708162)
		(end 192.058036 -124.162312)
		(width 0.1651)
		(layer "In5.Cu")
		(net "P5E_PEX1_STN0_RX_DP<0>")
	)
	(segment
		(start 187.157868 -120.737376)
		(end 187.30722 -120.6754)
		(width 0.1651)
		(layer "In5.Cu")
		(net "P5E_PEX1_STN0_RX_DP<0>")
	)
	(segment
		(start 192.058036 -124.162312)
		(end 192.08115 -124.322332)
		(width 0.1651)
		(layer "In5.Cu")
		(net "P5E_PEX1_STN0_RX_DP<0>")
	)
	(segment
		(start 184.106566 -142.917926)
		(end 184.26938 -142.755112)
		(width 0.13462)
		(layer "F.Cu")
		(net "P5E_PEX1_STN0_RX_DN<8>")
	)
	(segment
		(start 184.26938 -142.755112)
		(end 184.757314 -142.755112)
		(width 0.13462)
		(layer "F.Cu")
		(net "P5E_PEX1_STN0_RX_DN<8>")
	)
	(segment
		(start 183.451246 -142.917926)
		(end 184.106566 -142.917926)
		(width 0.13462)
		(layer "F.Cu")
		(net "P5E_PEX1_STN0_RX_DN<8>")
	)
	(segment
		(start 183.157114 -142.62354)
		(end 183.157114 -142.623794)
		(width 0.13462)
		(layer "F.Cu")
		(net "P5E_PEX1_STN0_RX_DN<8>")
	)
	(segment
		(start 183.157114 -142.623794)
		(end 183.451246 -142.917926)
		(width 0.13462)
		(layer "F.Cu")
		(net "P5E_PEX1_STN0_RX_DN<8>")
	)
	(segment
		(start 198.6915 -271.535144)
		(end 198.692008 -271.535652)
		(width 0.1651)
		(layer "In5.Cu")
		(net "P5E_PEX1_STN0_RX_DN<8>")
	)
	(segment
		(start 194.372992 -160.610042)
		(end 197.985126 -265.20775)
		(width 0.1651)
		(layer "In5.Cu")
		(net "P5E_PEX1_STN0_RX_DN<8>")
	)
	(segment
		(start 198.170292 -274.885404)
		(end 198.284592 -274.999704)
		(width 0.1143)
		(layer "In5.Cu")
		(net "P5E_PEX1_STN0_RX_DN<8>")
	)
	(segment
		(start 183.157114 -142.62354)
		(end 183.447944 -142.91437)
		(width 0.1651)
		(layer "In5.Cu")
		(net "P5E_PEX1_STN0_RX_DN<8>")
	)
	(segment
		(start 191.376046 -152.831292)
		(end 192.763902 -154.698954)
		(width 0.1651)
		(layer "In5.Cu")
		(net "P5E_PEX1_STN0_RX_DN<8>")
	)
	(segment
		(start 197.985126 -265.20775)
		(end 198.64451 -270.75384)
		(width 0.1651)
		(layer "In5.Cu")
		(net "P5E_PEX1_STN0_RX_DN<8>")
	)
	(segment
		(start 192.763902 -154.698954)
		(end 194.274186 -159.983424)
		(width 0.1651)
		(layer "In5.Cu")
		(net "P5E_PEX1_STN0_RX_DN<8>")
	)
	(segment
		(start 198.170292 -273.834606)
		(end 198.170292 -274.885404)
		(width 0.1143)
		(layer "In5.Cu")
		(net "P5E_PEX1_STN0_RX_DN<8>")
	)
	(segment
		(start 183.447944 -142.91437)
		(end 183.696356 -142.91437)
		(width 0.1651)
		(layer "In5.Cu")
		(net "P5E_PEX1_STN0_RX_DN<8>")
	)
	(segment
		(start 183.696356 -142.91437)
		(end 185.776616 -144.304258)
		(width 0.1651)
		(layer "In5.Cu")
		(net "P5E_PEX1_STN0_RX_DN<8>")
	)
	(segment
		(start 185.776616 -144.304258)
		(end 189.366906 -149.895306)
		(width 0.1651)
		(layer "In5.Cu")
		(net "P5E_PEX1_STN0_RX_DN<8>")
	)
	(segment
		(start 189.366906 -149.895306)
		(end 189.914022 -151.432514)
		(width 0.1651)
		(layer "In5.Cu")
		(net "P5E_PEX1_STN0_RX_DN<8>")
	)
	(segment
		(start 198.284592 -274.999704)
		(end 198.550022 -274.999704)
		(width 0.1143)
		(layer "In5.Cu")
		(net "P5E_PEX1_STN0_RX_DN<8>")
	)
	(segment
		(start 189.914022 -151.432514)
		(end 191.376046 -152.831292)
		(width 0.1651)
		(layer "In5.Cu")
		(net "P5E_PEX1_STN0_RX_DN<8>")
	)
	(segment
		(start 198.646288 -273.35861)
		(end 198.170292 -273.834606)
		(width 0.1143)
		(layer "In5.Cu")
		(net "P5E_PEX1_STN0_RX_DN<8>")
	)
	(segment
		(start 198.646288 -272.14957)
		(end 198.646288 -273.35861)
		(width 0.1143)
		(layer "In5.Cu")
		(net "P5E_PEX1_STN0_RX_DN<8>")
	)
	(segment
		(start 198.692008 -272.075402)
		(end 198.692008 -272.10385)
		(width 0.1143)
		(layer "In5.Cu")
		(net "P5E_PEX1_STN0_RX_DN<8>")
	)
	(segment
		(start 194.274186 -159.983424)
		(end 194.372992 -160.610042)
		(width 0.1651)
		(layer "In5.Cu")
		(net "P5E_PEX1_STN0_RX_DN<8>")
	)
	(segment
		(start 198.692008 -271.535652)
		(end 198.692008 -272.075402)
		(width 0.1651)
		(layer "In5.Cu")
		(net "P5E_PEX1_STN0_RX_DN<8>")
	)
	(segment
		(start 198.64451 -270.75384)
		(end 198.6915 -271.535144)
		(width 0.1651)
		(layer "In5.Cu")
		(net "P5E_PEX1_STN0_RX_DN<8>")
	)
	(segment
		(start 198.692008 -272.10385)
		(end 198.646288 -272.14957)
		(width 0.1143)
		(layer "In5.Cu")
		(net "P5E_PEX1_STN0_RX_DN<8>")
	)
	(segment
		(start 189.845696 -145.154904)
		(end 190.00851 -144.99209)
		(width 0.13462)
		(layer "F.Cu")
		(net "P5E_PEX1_STN0_TX_C_DP<9>")
	)
	(segment
		(start 198.175626 -144.99209)
		(end 198.49465 -145.311114)
		(width 0.13462)
		(layer "F.Cu")
		(net "P5E_PEX1_STN0_TX_C_DP<9>")
	)
	(segment
		(start 190.00851 -144.99209)
		(end 198.175626 -144.99209)
		(width 0.13462)
		(layer "F.Cu")
		(net "P5E_PEX1_STN0_TX_C_DP<9>")
	)
	(segment
		(start 189.357508 -145.154904)
		(end 189.845696 -145.154904)
		(width 0.13462)
		(layer "F.Cu")
		(net "P5E_PEX1_STN0_TX_C_DP<9>")
	)
	(segment
		(start 189.845696 -148.155152)
		(end 190.00851 -148.317966)
		(width 0.13462)
		(layer "F.Cu")
		(net "P5E_PEX1_STN0_TX_C_DN<11>")
	)
	(segment
		(start 189.357508 -148.155152)
		(end 189.845696 -148.155152)
		(width 0.13462)
		(layer "F.Cu")
		(net "P5E_PEX1_STN0_TX_C_DN<11>")
	)
	(segment
		(start 190.00851 -148.317966)
		(end 198.173594 -148.317966)
		(width 0.13462)
		(layer "F.Cu")
		(net "P5E_PEX1_STN0_TX_C_DN<11>")
	)
	(segment
		(start 198.173594 -148.317966)
		(end 198.49465 -147.99691)
		(width 0.13462)
		(layer "F.Cu")
		(net "P5E_PEX1_STN0_TX_C_DN<11>")
	)
	(segment
		(start 189.845696 -146.955002)
		(end 190.00851 -146.792188)
		(width 0.13462)
		(layer "F.Cu")
		(net "P5E_PEX1_STN0_TX_C_DP<10>")
	)
	(segment
		(start 195.540122 -146.792188)
		(end 195.852542 -147.104608)
		(width 0.13462)
		(layer "F.Cu")
		(net "P5E_PEX1_STN0_TX_C_DP<10>")
	)
	(segment
		(start 189.357508 -146.955002)
		(end 189.845696 -146.955002)
		(width 0.13462)
		(layer "F.Cu")
		(net "P5E_PEX1_STN0_TX_C_DP<10>")
	)
	(segment
		(start 190.00851 -146.792188)
		(end 195.540122 -146.792188)
		(width 0.13462)
		(layer "F.Cu")
		(net "P5E_PEX1_STN0_TX_C_DP<10>")
	)
	(segment
		(start 190.00851 -155.79217)
		(end 198.175626 -155.79217)
		(width 0.13462)
		(layer "F.Cu")
		(net "P5E_PEX1_STN0_TX_C_DP<15>")
	)
	(segment
		(start 189.845696 -155.954984)
		(end 190.00851 -155.79217)
		(width 0.13462)
		(layer "F.Cu")
		(net "P5E_PEX1_STN0_TX_C_DP<15>")
	)
	(segment
		(start 198.175626 -155.79217)
		(end 198.49465 -156.111194)
		(width 0.13462)
		(layer "F.Cu")
		(net "P5E_PEX1_STN0_TX_C_DP<15>")
	)
	(segment
		(start 189.357508 -155.954984)
		(end 189.845696 -155.954984)
		(width 0.13462)
		(layer "F.Cu")
		(net "P5E_PEX1_STN0_TX_C_DP<15>")
	)
	(segment
		(start 189.845696 -134.245096)
		(end 190.00851 -134.082282)
		(width 0.13462)
		(layer "F.Cu")
		(net "P5E_PEX1_STN0_TX_C_DP<6>")
	)
	(segment
		(start 195.540122 -134.082282)
		(end 195.852542 -134.394702)
		(width 0.13462)
		(layer "F.Cu")
		(net "P5E_PEX1_STN0_TX_C_DP<6>")
	)
	(segment
		(start 190.00851 -134.082282)
		(end 195.540122 -134.082282)
		(width 0.13462)
		(layer "F.Cu")
		(net "P5E_PEX1_STN0_TX_C_DP<6>")
	)
	(segment
		(start 189.357508 -134.245096)
		(end 189.845696 -134.245096)
		(width 0.13462)
		(layer "F.Cu")
		(net "P5E_PEX1_STN0_TX_C_DP<6>")
	)
	(segment
		(start 195.524882 -146.517868)
		(end 195.852542 -146.190208)
		(width 0.13462)
		(layer "F.Cu")
		(net "P5E_PEX1_STN0_TX_C_DN<10>")
	)
	(segment
		(start 189.845696 -146.355054)
		(end 190.00851 -146.517868)
		(width 0.13462)
		(layer "F.Cu")
		(net "P5E_PEX1_STN0_TX_C_DN<10>")
	)
	(segment
		(start 190.00851 -146.517868)
		(end 195.524882 -146.517868)
		(width 0.13462)
		(layer "F.Cu")
		(net "P5E_PEX1_STN0_TX_C_DN<10>")
	)
	(segment
		(start 189.357508 -146.355054)
		(end 189.845696 -146.355054)
		(width 0.13462)
		(layer "F.Cu")
		(net "P5E_PEX1_STN0_TX_C_DN<10>")
	)
	(segment
		(start 189.357508 -152.355042)
		(end 189.845696 -152.355042)
		(width 0.13462)
		(layer "F.Cu")
		(net "P5E_PEX1_STN0_TX_C_DP<13>")
	)
	(segment
		(start 190.00851 -152.192228)
		(end 198.175626 -152.192228)
		(width 0.13462)
		(layer "F.Cu")
		(net "P5E_PEX1_STN0_TX_C_DP<13>")
	)
	(segment
		(start 198.175626 -152.192228)
		(end 198.49465 -152.511252)
		(width 0.13462)
		(layer "F.Cu")
		(net "P5E_PEX1_STN0_TX_C_DP<13>")
	)
	(segment
		(start 189.845696 -152.355042)
		(end 190.00851 -152.192228)
		(width 0.13462)
		(layer "F.Cu")
		(net "P5E_PEX1_STN0_TX_C_DP<13>")
	)
	(segment
		(start 184.106566 -133.807962)
		(end 184.26938 -133.645148)
		(width 0.13462)
		(layer "F.Cu")
		(net "P5E_PEX1_STN0_RX_DN<6>")
	)
	(segment
		(start 184.26938 -133.645148)
		(end 184.757314 -133.645148)
		(width 0.13462)
		(layer "F.Cu")
		(net "P5E_PEX1_STN0_RX_DN<6>")
	)
	(segment
		(start 183.157114 -133.513576)
		(end 183.157114 -133.51383)
		(width 0.13462)
		(layer "F.Cu")
		(net "P5E_PEX1_STN0_RX_DN<6>")
	)
	(segment
		(start 183.157114 -133.51383)
		(end 183.451246 -133.807962)
		(width 0.13462)
		(layer "F.Cu")
		(net "P5E_PEX1_STN0_RX_DN<6>")
	)
	(segment
		(start 183.451246 -133.807962)
		(end 184.106566 -133.807962)
		(width 0.13462)
		(layer "F.Cu")
		(net "P5E_PEX1_STN0_RX_DN<6>")
	)
	(segment
		(start 201.066654 -272.504154)
		(end 201.933302 -277.058374)
		(width 0.1651)
		(layer "In5.Cu")
		(net "P5E_PEX1_STN0_RX_DN<6>")
	)
	(segment
		(start 196.337428 -160.243774)
		(end 199.893682 -264.69721)
		(width 0.1651)
		(layer "In5.Cu")
		(net "P5E_PEX1_STN0_RX_DN<6>")
	)
	(segment
		(start 201.106278 -281.817826)
		(end 200.436226 -282.265882)
		(width 0.1651)
		(layer "In5.Cu")
		(net "P5E_PEX1_STN0_RX_DN<6>")
	)
	(segment
		(start 192.985898 -139.7889)
		(end 192.985898 -140.908278)
		(width 0.1651)
		(layer "In5.Cu")
		(net "P5E_PEX1_STN0_RX_DN<6>")
	)
	(segment
		(start 192.832228 -138.902186)
		(end 192.985898 -139.7889)
		(width 0.1651)
		(layer "In5.Cu")
		(net "P5E_PEX1_STN0_RX_DN<6>")
	)
	(segment
		(start 201.933302 -277.089108)
		(end 201.845164 -280.642822)
		(width 0.1651)
		(layer "In5.Cu")
		(net "P5E_PEX1_STN0_RX_DN<6>")
	)
	(segment
		(start 201.845164 -280.642822)
		(end 201.599546 -281.22245)
		(width 0.1651)
		(layer "In5.Cu")
		(net "P5E_PEX1_STN0_RX_DN<6>")
	)
	(segment
		(start 201.599546 -281.22245)
		(end 201.106278 -281.817826)
		(width 0.1651)
		(layer "In5.Cu")
		(net "P5E_PEX1_STN0_RX_DN<6>")
	)
	(segment
		(start 200.436226 -282.265882)
		(end 200.024746 -282.265882)
		(width 0.1651)
		(layer "In5.Cu")
		(net "P5E_PEX1_STN0_RX_DN<6>")
	)
	(segment
		(start 183.846724 -133.804406)
		(end 192.411858 -138.402314)
		(width 0.1651)
		(layer "In5.Cu")
		(net "P5E_PEX1_STN0_RX_DN<6>")
	)
	(segment
		(start 196.270118 -282.485592)
		(end 196.384418 -282.599892)
		(width 0.1143)
		(layer "In5.Cu")
		(net "P5E_PEX1_STN0_RX_DN<6>")
	)
	(segment
		(start 192.985898 -140.908278)
		(end 196.337428 -160.243774)
		(width 0.1651)
		(layer "In5.Cu")
		(net "P5E_PEX1_STN0_RX_DN<6>")
	)
	(segment
		(start 199.893682 -264.69721)
		(end 201.066654 -272.504154)
		(width 0.1651)
		(layer "In5.Cu")
		(net "P5E_PEX1_STN0_RX_DN<6>")
	)
	(segment
		(start 199.950578 -282.220162)
		(end 196.402706 -282.220162)
		(width 0.1143)
		(layer "In5.Cu")
		(net "P5E_PEX1_STN0_RX_DN<6>")
	)
	(segment
		(start 200.024746 -282.265882)
		(end 199.996298 -282.265882)
		(width 0.1143)
		(layer "In5.Cu")
		(net "P5E_PEX1_STN0_RX_DN<6>")
	)
	(segment
		(start 183.447944 -133.804406)
		(end 183.846724 -133.804406)
		(width 0.1651)
		(layer "In5.Cu")
		(net "P5E_PEX1_STN0_RX_DN<6>")
	)
	(segment
		(start 196.384418 -282.599892)
		(end 196.649848 -282.599892)
		(width 0.1143)
		(layer "In5.Cu")
		(net "P5E_PEX1_STN0_RX_DN<6>")
	)
	(segment
		(start 196.270118 -282.35275)
		(end 196.270118 -282.485592)
		(width 0.1143)
		(layer "In5.Cu")
		(net "P5E_PEX1_STN0_RX_DN<6>")
	)
	(segment
		(start 199.996298 -282.265882)
		(end 199.950578 -282.220162)
		(width 0.1143)
		(layer "In5.Cu")
		(net "P5E_PEX1_STN0_RX_DN<6>")
	)
	(segment
		(start 201.933302 -277.058374)
		(end 201.933302 -277.089108)
		(width 0.1651)
		(layer "In5.Cu")
		(net "P5E_PEX1_STN0_RX_DN<6>")
	)
	(segment
		(start 196.402706 -282.220162)
		(end 196.270118 -282.35275)
		(width 0.1143)
		(layer "In5.Cu")
		(net "P5E_PEX1_STN0_RX_DN<6>")
	)
	(segment
		(start 183.157114 -133.513576)
		(end 183.447944 -133.804406)
		(width 0.1651)
		(layer "In5.Cu")
		(net "P5E_PEX1_STN0_RX_DN<6>")
	)
	(segment
		(start 192.411858 -138.402314)
		(end 192.832228 -138.902186)
		(width 0.1651)
		(layer "In5.Cu")
		(net "P5E_PEX1_STN0_RX_DN<6>")
	)
	(segment
		(start 189.845696 -122.435112)
		(end 190.00851 -122.597926)
		(width 0.13462)
		(layer "F.Cu")
		(net "P5E_PEX1_STN0_TX_C_DN<2>")
	)
	(segment
		(start 189.357508 -122.435112)
		(end 189.845696 -122.435112)
		(width 0.13462)
		(layer "F.Cu")
		(net "P5E_PEX1_STN0_TX_C_DN<2>")
	)
	(segment
		(start 190.00851 -122.597926)
		(end 195.524882 -122.597926)
		(width 0.13462)
		(layer "F.Cu")
		(net "P5E_PEX1_STN0_TX_C_DN<2>")
	)
	(segment
		(start 195.524882 -122.597926)
		(end 195.852542 -122.270266)
		(width 0.13462)
		(layer "F.Cu")
		(net "P5E_PEX1_STN0_TX_C_DN<2>")
	)
	(segment
		(start 183.157114 -123.16714)
		(end 183.452008 -122.872246)
		(width 0.13462)
		(layer "F.Cu")
		(net "P5E_PEX1_STN0_RX_DP<2>")
	)
	(segment
		(start 183.452008 -122.872246)
		(end 184.106566 -122.872246)
		(width 0.13462)
		(layer "F.Cu")
		(net "P5E_PEX1_STN0_RX_DP<2>")
	)
	(segment
		(start 184.106566 -122.872246)
		(end 184.26938 -123.03506)
		(width 0.13462)
		(layer "F.Cu")
		(net "P5E_PEX1_STN0_RX_DP<2>")
	)
	(segment
		(start 184.26938 -123.03506)
		(end 184.757314 -123.03506)
		(width 0.13462)
		(layer "F.Cu")
		(net "P5E_PEX1_STN0_RX_DP<2>")
	)
	(segment
		(start 203.253848 -232.167938)
		(end 204.910436 -239.951514)
		(width 0.1651)
		(layer "In5.Cu")
		(net "P5E_PEX1_STN0_RX_DP<2>")
	)
	(segment
		(start 190.48476 -126.661164)
		(end 191.912494 -128.800606)
		(width 0.1651)
		(layer "In5.Cu")
		(net "P5E_PEX1_STN0_RX_DP<2>")
	)
	(segment
		(start 193.509646 -131.399788)
		(end 193.668142 -131.431284)
		(width 0.1651)
		(layer "In5.Cu")
		(net "P5E_PEX1_STN0_RX_DP<2>")
	)
	(segment
		(start 192.314322 -129.40284)
		(end 192.58915 -129.814574)
		(width 0.1651)
		(layer "In5.Cu")
		(net "P5E_PEX1_STN0_RX_DP<2>")
	)
	(segment
		(start 186.120786 -123.874276)
		(end 186.270138 -123.812554)
		(width 0.1651)
		(layer "In5.Cu")
		(net "P5E_PEX1_STN0_RX_DP<2>")
	)
	(segment
		(start 187.246768 -124.342144)
		(end 187.39612 -124.280676)
		(width 0.1651)
		(layer "In5.Cu")
		(net "P5E_PEX1_STN0_RX_DP<2>")
	)
	(segment
		(start 199.814434 -138.49985)
		(end 202.563476 -143.64208)
		(width 0.1651)
		(layer "In5.Cu")
		(net "P5E_PEX1_STN0_RX_DP<2>")
	)
	(segment
		(start 185.144156 -123.344432)
		(end 185.601356 -123.534424)
		(width 0.1651)
		(layer "In5.Cu")
		(net "P5E_PEX1_STN0_RX_DP<2>")
	)
	(segment
		(start 196.323712 -285.829502)
		(end 196.079618 -286.073596)
		(width 0.1143)
		(layer "In5.Cu")
		(net "P5E_PEX1_STN0_RX_DP<2>")
	)
	(segment
		(start 187.39612 -124.280676)
		(end 188.628782 -124.79274)
		(width 0.1651)
		(layer "In5.Cu")
		(net "P5E_PEX1_STN0_RX_DP<2>")
	)
	(segment
		(start 184.994804 -123.406154)
		(end 185.144156 -123.344432)
		(width 0.1651)
		(layer "In5.Cu")
		(net "P5E_PEX1_STN0_RX_DP<2>")
	)
	(segment
		(start 199.950578 -285.829502)
		(end 196.323712 -285.829502)
		(width 0.1143)
		(layer "In5.Cu")
		(net "P5E_PEX1_STN0_RX_DP<2>")
	)
	(segment
		(start 184.537096 -123.215908)
		(end 184.994804 -123.406154)
		(width 0.1651)
		(layer "In5.Cu")
		(net "P5E_PEX1_STN0_RX_DP<2>")
	)
	(segment
		(start 200.024746 -285.783782)
		(end 199.996298 -285.783782)
		(width 0.1143)
		(layer "In5.Cu")
		(net "P5E_PEX1_STN0_RX_DP<2>")
	)
	(segment
		(start 203.465176 -149.98446)
		(end 203.960476 -168.457372)
		(width 0.1651)
		(layer "In5.Cu")
		(net "P5E_PEX1_STN0_RX_DP<2>")
	)
	(segment
		(start 183.447944 -122.87631)
		(end 184.018174 -122.87631)
		(width 0.1651)
		(layer "In5.Cu")
		(net "P5E_PEX1_STN0_RX_DP<2>")
	)
	(segment
		(start 192.314576 -129.40284)
		(end 192.314322 -129.40284)
		(width 0.1651)
		(layer "In5.Cu")
		(net "P5E_PEX1_STN0_RX_DP<2>")
	)
	(segment
		(start 192.58915 -129.814574)
		(end 192.5574 -129.973324)
		(width 0.1651)
		(layer "In5.Cu")
		(net "P5E_PEX1_STN0_RX_DP<2>")
	)
	(segment
		(start 201.489818 -285.783782)
		(end 200.024746 -285.783782)
		(width 0.1651)
		(layer "In5.Cu")
		(net "P5E_PEX1_STN0_RX_DP<2>")
	)
	(segment
		(start 213.551516 -269.508732)
		(end 213.388448 -273.073114)
		(width 0.1651)
		(layer "In5.Cu")
		(net "P5E_PEX1_STN0_RX_DP<2>")
	)
	(segment
		(start 202.563476 -143.64208)
		(end 203.465176 -149.98446)
		(width 0.1651)
		(layer "In5.Cu")
		(net "P5E_PEX1_STN0_RX_DP<2>")
	)
	(segment
		(start 185.601356 -123.534424)
		(end 185.663078 -123.68403)
		(width 0.1651)
		(layer "In5.Cu")
		(net "P5E_PEX1_STN0_RX_DP<2>")
	)
	(segment
		(start 192.991232 -130.417062)
		(end 193.26606 -130.828796)
		(width 0.1651)
		(layer "In5.Cu")
		(net "P5E_PEX1_STN0_RX_DP<2>")
	)
	(segment
		(start 191.912494 -128.800606)
		(end 191.880744 -128.959102)
		(width 0.1651)
		(layer "In5.Cu")
		(net "P5E_PEX1_STN0_RX_DP<2>")
	)
	(segment
		(start 196.079618 -286.285432)
		(end 195.965318 -286.399732)
		(width 0.1143)
		(layer "In5.Cu")
		(net "P5E_PEX1_STN0_RX_DP<2>")
	)
	(segment
		(start 211.113116 -277.083774)
		(end 202.874118 -285.067248)
		(width 0.1651)
		(layer "In5.Cu")
		(net "P5E_PEX1_STN0_RX_DP<2>")
	)
	(segment
		(start 192.5574 -129.973324)
		(end 192.832736 -130.385566)
		(width 0.1651)
		(layer "In5.Cu")
		(net "P5E_PEX1_STN0_RX_DP<2>")
	)
	(segment
		(start 195.529708 -134.220712)
		(end 199.814434 -138.49985)
		(width 0.1651)
		(layer "In5.Cu")
		(net "P5E_PEX1_STN0_RX_DP<2>")
	)
	(segment
		(start 186.727338 -124.002546)
		(end 186.78906 -124.152152)
		(width 0.1651)
		(layer "In5.Cu")
		(net "P5E_PEX1_STN0_RX_DP<2>")
	)
	(segment
		(start 193.23431 -130.987546)
		(end 193.509646 -131.399788)
		(width 0.1651)
		(layer "In5.Cu")
		(net "P5E_PEX1_STN0_RX_DP<2>")
	)
	(segment
		(start 188.628782 -124.79274)
		(end 190.48476 -126.661164)
		(width 0.1651)
		(layer "In5.Cu")
		(net "P5E_PEX1_STN0_RX_DP<2>")
	)
	(segment
		(start 196.079618 -286.073596)
		(end 196.079618 -286.285432)
		(width 0.1143)
		(layer "In5.Cu")
		(net "P5E_PEX1_STN0_RX_DP<2>")
	)
	(segment
		(start 183.157114 -123.16714)
		(end 183.447944 -122.87631)
		(width 0.1651)
		(layer "In5.Cu")
		(net "P5E_PEX1_STN0_RX_DP<2>")
	)
	(segment
		(start 193.668142 -131.431284)
		(end 195.529708 -134.220712)
		(width 0.1651)
		(layer "In5.Cu")
		(net "P5E_PEX1_STN0_RX_DP<2>")
	)
	(segment
		(start 213.388448 -273.073114)
		(end 211.113116 -277.083774)
		(width 0.1651)
		(layer "In5.Cu")
		(net "P5E_PEX1_STN0_RX_DP<2>")
	)
	(segment
		(start 191.880744 -128.959102)
		(end 192.15608 -129.371344)
		(width 0.1651)
		(layer "In5.Cu")
		(net "P5E_PEX1_STN0_RX_DP<2>")
	)
	(segment
		(start 193.26606 -130.828796)
		(end 193.23431 -130.987546)
		(width 0.1651)
		(layer "In5.Cu")
		(net "P5E_PEX1_STN0_RX_DP<2>")
	)
	(segment
		(start 202.874118 -285.067248)
		(end 201.489818 -285.783782)
		(width 0.1651)
		(layer "In5.Cu")
		(net "P5E_PEX1_STN0_RX_DP<2>")
	)
	(segment
		(start 203.960476 -168.457372)
		(end 203.253848 -232.167938)
		(width 0.1651)
		(layer "In5.Cu")
		(net "P5E_PEX1_STN0_RX_DP<2>")
	)
	(segment
		(start 185.663078 -123.68403)
		(end 186.120786 -123.874276)
		(width 0.1651)
		(layer "In5.Cu")
		(net "P5E_PEX1_STN0_RX_DP<2>")
	)
	(segment
		(start 184.475374 -123.066302)
		(end 184.537096 -123.215908)
		(width 0.1651)
		(layer "In5.Cu")
		(net "P5E_PEX1_STN0_RX_DP<2>")
	)
	(segment
		(start 186.78906 -124.152152)
		(end 187.246768 -124.342144)
		(width 0.1651)
		(layer "In5.Cu")
		(net "P5E_PEX1_STN0_RX_DP<2>")
	)
	(segment
		(start 192.15608 -129.371344)
		(end 192.314576 -129.40284)
		(width 0.1651)
		(layer "In5.Cu")
		(net "P5E_PEX1_STN0_RX_DP<2>")
	)
	(segment
		(start 192.832736 -130.385566)
		(end 192.991232 -130.417062)
		(width 0.1651)
		(layer "In5.Cu")
		(net "P5E_PEX1_STN0_RX_DP<2>")
	)
	(segment
		(start 204.910436 -239.951514)
		(end 213.551516 -269.508732)
		(width 0.1651)
		(layer "In5.Cu")
		(net "P5E_PEX1_STN0_RX_DP<2>")
	)
	(segment
		(start 186.270138 -123.812554)
		(end 186.727338 -124.002546)
		(width 0.1651)
		(layer "In5.Cu")
		(net "P5E_PEX1_STN0_RX_DP<2>")
	)
	(segment
		(start 184.018174 -122.87631)
		(end 184.475374 -123.066302)
		(width 0.1651)
		(layer "In5.Cu")
		(net "P5E_PEX1_STN0_RX_DP<2>")
	)
	(segment
		(start 195.965318 -286.399732)
		(end 195.699888 -286.399732)
		(width 0.1143)
		(layer "In5.Cu")
		(net "P5E_PEX1_STN0_RX_DP<2>")
	)
	(segment
		(start 199.996298 -285.783782)
		(end 199.950578 -285.829502)
		(width 0.1143)
		(layer "In5.Cu")
		(net "P5E_PEX1_STN0_RX_DP<2>")
	)
	(segment
		(start 39.559484 -142.34795)
		(end 39.8272 -142.080234)
		(width 0.13208)
		(layer "F.Cu")
		(net "NIC0_BIF1_N")
	)
	(segment
		(start 41.062402 -142.080234)
		(end 41.177718 -141.964918)
		(width 0.13208)
		(layer "F.Cu")
		(net "NIC0_BIF1_N")
	)
	(segment
		(start 38.382702 -142.22095)
		(end 38.509702 -142.34795)
		(width 0.13208)
		(layer "F.Cu")
		(net "NIC0_BIF1_N")
	)
	(segment
		(start 38.509702 -142.34795)
		(end 39.559484 -142.34795)
		(width 0.13208)
		(layer "F.Cu")
		(net "NIC0_BIF1_N")
	)
	(segment
		(start 41.177718 -141.964918)
		(end 46.042326 -141.964918)
		(width 0.13208)
		(layer "F.Cu")
		(net "NIC0_BIF1_N")
	)
	(segment
		(start 39.8272 -142.080234)
		(end 40.381428 -142.080234)
		(width 0.13208)
		(layer "F.Cu")
		(net "NIC0_BIF1_N")
	)
	(segment
		(start 40.381428 -142.080234)
		(end 41.062402 -142.080234)
		(width 0.13208)
		(layer "F.Cu")
		(net "NIC0_BIF1_N")
	)
	(segment
		(start 38.382702 -141.87297)
		(end 38.382702 -142.22095)
		(width 0.13208)
		(layer "F.Cu")
		(net "NIC0_BIF1_N")
	)
	(segment
		(start 37.404802 -141.87297)
		(end 38.382702 -141.87297)
		(width 0.13208)
		(layer "F.Cu")
		(net "NIC0_BIF1_N")
	)
	(via
		(at 40.381428 -142.080234)
		(size 0.762)
		(drill 0.381)
		(layers "F.Cu" "B.Cu")
		(net "NIC0_BIF1_N")
	)
	(segment
		(start 299.563536 -115.234974)
		(end 299.512736 -115.285774)
		(width 0.13208)
		(layer "F.Cu")
		(net "RST_NIC5_PERST1_R_N")
	)
	(segment
		(start 312.405268 -88.375998)
		(end 312.696352 -88.375998)
		(width 0.13208)
		(layer "F.Cu")
		(net "RST_NIC5_PERST1_R_N")
	)
	(segment
		(start 312.823606 -88.248744)
		(end 312.823606 -87.749126)
		(width 0.13208)
		(layer "F.Cu")
		(net "RST_NIC5_PERST1_R_N")
	)
	(segment
		(start 312.696352 -88.375998)
		(end 312.823606 -88.248744)
		(width 0.13208)
		(layer "F.Cu")
		(net "RST_NIC5_PERST1_R_N")
	)
	(segment
		(start 300.857412 -115.234974)
		(end 299.563536 -115.234974)
		(width 0.13208)
		(layer "F.Cu")
		(net "RST_NIC5_PERST1_R_N")
	)
	(via
		(at 312.405268 -88.375998)
		(size 0.508)
		(drill 0.254)
		(layers "F.Cu" "B.Cu")
		(net "RST_NIC5_PERST1_R_N")
	)
	(via
		(at 299.512736 -115.285774)
		(size 0.508)
		(drill 0.254)
		(layers "F.Cu" "B.Cu")
		(net "RST_NIC5_PERST1_R_N")
	)
	(segment
		(start 304.406554 -97.780856)
		(end 304.406554 -105.228898)
		(width 0.15494)
		(layer "In11.Cu")
		(net "RST_NIC5_PERST1_R_N")
	)
	(segment
		(start 306.20716 -93.711268)
		(end 306.20716 -95.98025)
		(width 0.15494)
		(layer "In11.Cu")
		(net "RST_NIC5_PERST1_R_N")
	)
	(segment
		(start 305.327812 -108.076746)
		(end 305.075844 -108.328714)
		(width 0.15494)
		(layer "In11.Cu")
		(net "RST_NIC5_PERST1_R_N")
	)
	(segment
		(start 303.833276 -108.328714)
		(end 301.096426 -111.065564)
		(width 0.15494)
		(layer "In11.Cu")
		(net "RST_NIC5_PERST1_R_N")
	)
	(segment
		(start 305.075844 -108.328714)
		(end 303.833276 -108.328714)
		(width 0.15494)
		(layer "In11.Cu")
		(net "RST_NIC5_PERST1_R_N")
	)
	(segment
		(start 312.405268 -88.375998)
		(end 311.54243 -88.375998)
		(width 0.15494)
		(layer "In11.Cu")
		(net "RST_NIC5_PERST1_R_N")
	)
	(segment
		(start 301.096426 -114.270536)
		(end 300.081188 -115.285774)
		(width 0.15494)
		(layer "In11.Cu")
		(net "RST_NIC5_PERST1_R_N")
	)
	(segment
		(start 305.327812 -106.150156)
		(end 305.327812 -108.076746)
		(width 0.15494)
		(layer "In11.Cu")
		(net "RST_NIC5_PERST1_R_N")
	)
	(segment
		(start 304.406554 -105.228898)
		(end 305.327812 -106.150156)
		(width 0.15494)
		(layer "In11.Cu")
		(net "RST_NIC5_PERST1_R_N")
	)
	(segment
		(start 300.081188 -115.285774)
		(end 299.512736 -115.285774)
		(width 0.15494)
		(layer "In11.Cu")
		(net "RST_NIC5_PERST1_R_N")
	)
	(segment
		(start 311.54243 -88.375998)
		(end 306.20716 -93.711268)
		(width 0.15494)
		(layer "In11.Cu")
		(net "RST_NIC5_PERST1_R_N")
	)
	(segment
		(start 306.20716 -95.98025)
		(end 304.406554 -97.780856)
		(width 0.15494)
		(layer "In11.Cu")
		(net "RST_NIC5_PERST1_R_N")
	)
	(segment
		(start 301.096426 -111.065564)
		(end 301.096426 -114.270536)
		(width 0.15494)
		(layer "In11.Cu")
		(net "RST_NIC5_PERST1_R_N")
	)
	(segment
		(start 39.500048 -156.481526)
		(end 40.193468 -156.481526)
		(width 0.13208)
		(layer "F.Cu")
		(net "NIC0_DATA_OUT")
	)
	(segment
		(start 43.003978 -156.481526)
		(end 43.52544 -155.960064)
		(width 0.13208)
		(layer "F.Cu")
		(net "NIC0_DATA_OUT")
	)
	(segment
		(start 39.00805 -156.3624)
		(end 39.380922 -156.3624)
		(width 0.13208)
		(layer "F.Cu")
		(net "NIC0_DATA_OUT")
	)
	(segment
		(start 43.52544 -155.960064)
		(end 46.042326 -155.960064)
		(width 0.13208)
		(layer "F.Cu")
		(net "NIC0_DATA_OUT")
	)
	(segment
		(start 39.380922 -156.3624)
		(end 39.500048 -156.481526)
		(width 0.13208)
		(layer "F.Cu")
		(net "NIC0_DATA_OUT")
	)
	(segment
		(start 40.193468 -156.481526)
		(end 43.003978 -156.481526)
		(width 0.13208)
		(layer "F.Cu")
		(net "NIC0_DATA_OUT")
	)
	(via
		(at 40.193468 -156.481526)
		(size 0.762)
		(drill 0.381)
		(layers "F.Cu" "B.Cu")
		(net "NIC0_DATA_OUT")
	)
	(segment
		(start 296.415968 -101.782372)
		(end 297.149012 -101.782372)
		(width 0.13208)
		(layer "F.Cu")
		(net "NCSI_NIC5_TX_EN")
	)
	(segment
		(start 291.595048 -101.782372)
		(end 296.415968 -101.782372)
		(width 0.13208)
		(layer "F.Cu")
		(net "NCSI_NIC5_TX_EN")
	)
	(segment
		(start 298.29125 -100.640134)
		(end 300.857412 -100.640134)
		(width 0.13208)
		(layer "F.Cu")
		(net "NCSI_NIC5_TX_EN")
	)
	(segment
		(start 297.149012 -101.782372)
		(end 298.29125 -100.640134)
		(width 0.13208)
		(layer "F.Cu")
		(net "NCSI_NIC5_TX_EN")
	)
	(via
		(at 296.415968 -101.782372)
		(size 0.762)
		(drill 0.381)
		(layers "F.Cu" "B.Cu")
		(net "NCSI_NIC5_TX_EN")
	)
	(segment
		(start 88.664796 -32.589978)
		(end 88.185498 -32.589978)
		(width 0.13462)
		(layer "F.Cu")
		(net "P5E_PEX0_STN2_RX_DP<34>")
	)
	(segment
		(start 88.01862 -32.4231)
		(end 87.363808 -32.4231)
		(width 0.13462)
		(layer "F.Cu")
		(net "P5E_PEX0_STN2_RX_DP<34>")
	)
	(segment
		(start 88.185498 -32.589978)
		(end 88.01862 -32.4231)
		(width 0.13462)
		(layer "F.Cu")
		(net "P5E_PEX0_STN2_RX_DP<34>")
	)
	(segment
		(start 87.363808 -32.4231)
		(end 87.064596 -32.722312)
		(width 0.13462)
		(layer "F.Cu")
		(net "P5E_PEX0_STN2_RX_DP<34>")
	)
	(segment
		(start 87.064596 -32.722312)
		(end 87.290148 -32.49676)
		(width 0.1651)
		(layer "In7.Cu")
		(net "P5E_PEX0_STN2_RX_DP<34>")
	)
	(segment
		(start 87.447628 -32.431482)
		(end 87.684102 -32.431482)
		(width 0.1651)
		(layer "In7.Cu")
		(net "P5E_PEX0_STN2_RX_DP<34>")
	)
	(segment
		(start 56.183784 -271.392904)
		(end 56.183784 -271.421352)
		(width 0.1143)
		(layer "In7.Cu")
		(net "P5E_PEX0_STN2_RX_DP<34>")
	)
	(segment
		(start 87.600536 -37.779198)
		(end 87.631016 -39.714678)
		(width 0.1651)
		(layer "In7.Cu")
		(net "P5E_PEX0_STN2_RX_DP<34>")
	)
	(segment
		(start 87.684102 -32.431482)
		(end 88.15832 -32.905954)
		(width 0.1651)
		(layer "In7.Cu")
		(net "P5E_PEX0_STN2_RX_DP<34>")
	)
	(segment
		(start 88.148414 -33.547812)
		(end 88.032082 -33.660334)
		(width 0.1651)
		(layer "In7.Cu")
		(net "P5E_PEX0_STN2_RX_DP<34>")
	)
	(segment
		(start 56.444896 -275.570188)
		(end 56.685688 -275.570188)
		(width 0.1143)
		(layer "In7.Cu")
		(net "P5E_PEX0_STN2_RX_DP<34>")
	)
	(segment
		(start 88.944704 -49.45253)
		(end 88.761316 -61.197744)
		(width 0.1651)
		(layer "In7.Cu")
		(net "P5E_PEX0_STN2_RX_DP<34>")
	)
	(segment
		(start 87.796116 -36.729162)
		(end 87.600536 -37.779198)
		(width 0.1651)
		(layer "In7.Cu")
		(net "P5E_PEX0_STN2_RX_DP<34>")
	)
	(segment
		(start 56.183784 -271.421352)
		(end 56.229504 -271.467072)
		(width 0.1143)
		(layer "In7.Cu")
		(net "P5E_PEX0_STN2_RX_DP<34>")
	)
	(segment
		(start 56.799988 -275.684488)
		(end 56.799988 -275.949918)
		(width 0.1143)
		(layer "In7.Cu")
		(net "P5E_PEX0_STN2_RX_DP<34>")
	)
	(segment
		(start 88.136984 -34.271966)
		(end 88.12657 -34.95675)
		(width 0.1651)
		(layer "In7.Cu")
		(net "P5E_PEX0_STN2_RX_DP<34>")
	)
	(segment
		(start 77.775054 -116.573554)
		(end 77.460094 -143.730472)
		(width 0.1651)
		(layer "In7.Cu")
		(net "P5E_PEX0_STN2_RX_DP<34>")
	)
	(segment
		(start 56.183784 -270.641064)
		(end 56.183784 -271.392904)
		(width 0.1651)
		(layer "In7.Cu")
		(net "P5E_PEX0_STN2_RX_DP<34>")
	)
	(segment
		(start 87.919814 -36.066984)
		(end 87.815674 -36.138104)
		(width 0.1651)
		(layer "In7.Cu")
		(net "P5E_PEX0_STN2_RX_DP<34>")
	)
	(segment
		(start 76.072746 -154.509978)
		(end 56.512714 -266.82319)
		(width 0.1651)
		(layer "In7.Cu")
		(net "P5E_PEX0_STN2_RX_DP<34>")
	)
	(segment
		(start 56.512714 -266.82319)
		(end 56.183784 -270.641064)
		(width 0.1651)
		(layer "In7.Cu")
		(net "P5E_PEX0_STN2_RX_DP<34>")
	)
	(segment
		(start 87.631016 -39.714678)
		(end 87.630762 -39.714678)
		(width 0.1651)
		(layer "In7.Cu")
		(net "P5E_PEX0_STN2_RX_DP<34>")
	)
	(segment
		(start 56.229504 -271.467072)
		(end 56.229504 -275.354796)
		(width 0.1143)
		(layer "In7.Cu")
		(net "P5E_PEX0_STN2_RX_DP<34>")
	)
	(segment
		(start 87.815674 -36.138104)
		(end 87.724996 -36.625276)
		(width 0.1651)
		(layer "In7.Cu")
		(net "P5E_PEX0_STN2_RX_DP<34>")
	)
	(segment
		(start 87.724996 -36.625276)
		(end 87.796116 -36.729162)
		(width 0.1651)
		(layer "In7.Cu")
		(net "P5E_PEX0_STN2_RX_DP<34>")
	)
	(segment
		(start 87.63127 -39.731442)
		(end 88.944704 -49.45253)
		(width 0.1651)
		(layer "In7.Cu")
		(net "P5E_PEX0_STN2_RX_DP<34>")
	)
	(segment
		(start 77.460094 -143.730472)
		(end 76.072746 -154.509978)
		(width 0.1651)
		(layer "In7.Cu")
		(net "P5E_PEX0_STN2_RX_DP<34>")
	)
	(segment
		(start 87.630762 -39.714678)
		(end 87.63127 -39.731442)
		(width 0.1651)
		(layer "In7.Cu")
		(net "P5E_PEX0_STN2_RX_DP<34>")
	)
	(segment
		(start 88.15832 -32.905954)
		(end 88.148414 -33.547812)
		(width 0.1651)
		(layer "In7.Cu")
		(net "P5E_PEX0_STN2_RX_DP<34>")
	)
	(segment
		(start 88.761316 -61.197744)
		(end 77.775054 -116.573554)
		(width 0.1651)
		(layer "In7.Cu")
		(net "P5E_PEX0_STN2_RX_DP<34>")
	)
	(segment
		(start 56.229504 -275.354796)
		(end 56.444896 -275.570188)
		(width 0.1143)
		(layer "In7.Cu")
		(net "P5E_PEX0_STN2_RX_DP<34>")
	)
	(segment
		(start 56.685688 -275.570188)
		(end 56.799988 -275.684488)
		(width 0.1143)
		(layer "In7.Cu")
		(net "P5E_PEX0_STN2_RX_DP<34>")
	)
	(segment
		(start 88.024462 -34.155888)
		(end 88.136984 -34.271966)
		(width 0.1651)
		(layer "In7.Cu")
		(net "P5E_PEX0_STN2_RX_DP<34>")
	)
	(segment
		(start 87.290148 -32.49676)
		(end 87.447628 -32.431482)
		(width 0.1651)
		(layer "In7.Cu")
		(net "P5E_PEX0_STN2_RX_DP<34>")
	)
	(segment
		(start 88.12657 -34.95675)
		(end 87.919814 -36.066984)
		(width 0.1651)
		(layer "In7.Cu")
		(net "P5E_PEX0_STN2_RX_DP<34>")
	)
	(segment
		(start 88.032082 -33.660334)
		(end 88.024462 -34.155888)
		(width 0.1651)
		(layer "In7.Cu")
		(net "P5E_PEX0_STN2_RX_DP<34>")
	)
	(segment
		(start 420.46779 -30.03169)
		(end 420.1541 -30.34538)
		(width 0.13462)
		(layer "F.Cu")
		(net "P5E_PEX3_STN2_TX_C_DN<37>")
	)
	(segment
		(start 416.223196 -30.34538)
		(end 416.068002 -30.190186)
		(width 0.13462)
		(layer "F.Cu")
		(net "P5E_PEX3_STN2_TX_C_DN<37>")
	)
	(segment
		(start 420.1541 -30.34538)
		(end 416.223196 -30.34538)
		(width 0.13462)
		(layer "F.Cu")
		(net "P5E_PEX3_STN2_TX_C_DN<37>")
	)
	(segment
		(start 416.068002 -30.190186)
		(end 415.564828 -30.190186)
		(width 0.13462)
		(layer "F.Cu")
		(net "P5E_PEX3_STN2_TX_C_DN<37>")
	)
	(segment
		(start 305.457606 -99.439984)
		(end 307.891942 -99.439984)
		(width 0.13208)
		(layer "F.Cu")
		(net "NIC5_DATA_OUT")
	)
	(via
		(at 307.891942 -99.439984)
		(size 0.508)
		(drill 0.254)
		(layers "F.Cu" "B.Cu")
		(net "NIC5_DATA_OUT")
	)
	(segment
		(start 309.341774 -98.021648)
		(end 307.923438 -99.439984)
		(width 0.13208)
		(layer "B.Cu")
		(net "NIC5_DATA_OUT")
	)
	(segment
		(start 307.923438 -99.439984)
		(end 307.891942 -99.439984)
		(width 0.13208)
		(layer "B.Cu")
		(net "NIC5_DATA_OUT")
	)
	(segment
		(start 219.724986 -14.100302)
		(end 219.724986 -14.735302)
		(width 0.381)
		(layer "F.Cu")
		(net "P3V3_SSD7")
	)
	(segment
		(start 215.985598 -27.492198)
		(end 215.854026 -27.492198)
		(width 0.381)
		(layer "F.Cu")
		(net "P3V3_SSD7")
	)
	(segment
		(start 213.571582 -25.742392)
		(end 213.571582 -26.360882)
		(width 0.4572)
		(layer "F.Cu")
		(net "P3V3_SSD7")
	)
	(segment
		(start 200.068688 -30.971236)
		(end 199.49414 -30.396688)
		(width 0.381)
		(layer "F.Cu")
		(net "P3V3_SSD7")
	)
	(segment
		(start 202.278996 -59.978036)
		(end 202.278996 -60.633356)
		(width 0.381)
		(layer "F.Cu")
		(net "P3V3_SSD7")
	)
	(segment
		(start 209.364834 -24.790146)
		(end 210.333336 -24.790146)
		(width 0.381)
		(layer "F.Cu")
		(net "P3V3_SSD7")
	)
	(segment
		(start 218.769438 -20.467574)
		(end 218.156536 -20.467574)
		(width 0.508)
		(layer "F.Cu")
		(net "P3V3_SSD7")
	)
	(segment
		(start 199.794114 -32.787336)
		(end 200.068688 -32.512762)
		(width 0.381)
		(layer "F.Cu")
		(net "P3V3_SSD7")
	)
	(segment
		(start 215.854026 -27.492198)
		(end 215.333072 -26.971244)
		(width 0.381)
		(layer "F.Cu")
		(net "P3V3_SSD7")
	)
	(segment
		(start 210.575144 -25.031954)
		(end 212.0265 -25.031954)
		(width 0.381)
		(layer "F.Cu")
		(net "P3V3_SSD7")
	)
	(segment
		(start 218.156536 -17.419574)
		(end 218.766136 -17.419574)
		(width 0.508)
		(layer "F.Cu")
		(net "P3V3_SSD7")
	)
	(segment
		(start 201.471784 -24.807418)
		(end 200.853294 -24.807418)
		(width 0.4572)
		(layer "F.Cu")
		(net "P3V3_SSD7")
	)
	(segment
		(start 199.794114 -34.248852)
		(end 199.794114 -32.787336)
		(width 0.381)
		(layer "F.Cu")
		(net "P3V3_SSD7")
	)
	(segment
		(start 186.946794 -37.47516)
		(end 186.241182 -37.47516)
		(width 0.4572)
		(layer "F.Cu")
		(net "P3V3_SSD7")
	)
	(segment
		(start 212.0265 -25.031954)
		(end 212.669882 -25.031954)
		(width 0.4572)
		(layer "F.Cu")
		(net "P3V3_SSD7")
	)
	(segment
		(start 210.333336 -24.790146)
		(end 210.575144 -25.031954)
		(width 0.381)
		(layer "F.Cu")
		(net "P3V3_SSD7")
	)
	(segment
		(start 200.068688 -32.512762)
		(end 200.068688 -30.971236)
		(width 0.381)
		(layer "F.Cu")
		(net "P3V3_SSD7")
	)
	(segment
		(start 219.66047 -14.799818)
		(end 219.66047 -16.439388)
		(width 0.381)
		(layer "F.Cu")
		(net "P3V3_SSD7")
	)
	(segment
		(start 219.724986 -14.735302)
		(end 219.66047 -14.799818)
		(width 0.381)
		(layer "F.Cu")
		(net "P3V3_SSD7")
	)
	(via
		(at 218.766136 -17.419574)
		(size 0.508)
		(drill 0.254)
		(layers "F.Cu" "B.Cu")
		(net "P3V3_SSD7")
	)
	(via
		(at 202.376532 -51.320192)
		(size 0.508)
		(drill 0.254)
		(layers "F.Cu" "B.Cu")
		(net "P3V3_SSD7")
	)
	(via
		(at 218.769438 -20.467574)
		(size 0.508)
		(drill 0.254)
		(layers "F.Cu" "B.Cu")
		(net "P3V3_SSD7")
	)
	(via
		(at 201.699876 -52.528724)
		(size 0.508)
		(drill 0.254)
		(layers "F.Cu" "B.Cu")
		(net "P3V3_SSD7")
	)
	(via
		(at 201.22896 -49.574704)
		(size 0.508)
		(drill 0.254)
		(layers "F.Cu" "B.Cu")
		(net "P3V3_SSD7")
	)
	(via
		(at 201.614532 -51.243992)
		(size 0.508)
		(drill 0.254)
		(layers "F.Cu" "B.Cu")
		(net "P3V3_SSD7")
	)
	(via
		(at 202.376532 -50.608992)
		(size 0.508)
		(drill 0.254)
		(layers "F.Cu" "B.Cu")
		(net "P3V3_SSD7")
	)
	(via
		(at 219.724986 -14.100302)
		(size 0.508)
		(drill 0.254)
		(layers "F.Cu" "B.Cu")
		(net "P3V3_SSD7")
	)
	(via
		(at 200.614534 -53.469286)
		(size 0.508)
		(drill 0.254)
		(layers "F.Cu" "B.Cu")
		(net "P3V3_SSD7")
	)
	(via
		(at 212.669882 -25.031954)
		(size 0.508)
		(drill 0.254)
		(layers "F.Cu" "B.Cu")
		(net "P3V3_SSD7")
	)
	(via
		(at 200.59396 -50.478182)
		(size 0.6604)
		(drill 0.3302)
		(layers "F.Cu" "B.Cu")
		(net "P3V3_SSD7")
	)
	(via
		(at 200.853294 -24.807418)
		(size 0.508)
		(drill 0.254)
		(layers "F.Cu" "B.Cu")
		(net "P3V3_SSD7")
	)
	(via
		(at 201.249534 -53.469286)
		(size 0.508)
		(drill 0.254)
		(layers "F.Cu" "B.Cu")
		(net "P3V3_SSD7")
	)
	(via
		(at 200.59396 -49.574704)
		(size 0.508)
		(drill 0.254)
		(layers "F.Cu" "B.Cu")
		(net "P3V3_SSD7")
	)
	(via
		(at 186.241182 -37.47516)
		(size 0.508)
		(drill 0.254)
		(layers "F.Cu" "B.Cu")
		(net "P3V3_SSD7")
	)
	(via
		(at 201.064876 -52.528724)
		(size 0.508)
		(drill 0.254)
		(layers "F.Cu" "B.Cu")
		(net "P3V3_SSD7")
	)
	(via
		(at 198.410576 -30.376876)
		(size 0.508)
		(drill 0.254)
		(layers "F.Cu" "B.Cu")
		(net "P3V3_SSD7")
	)
	(via
		(at 201.614532 -50.608992)
		(size 0.508)
		(drill 0.254)
		(layers "F.Cu" "B.Cu")
		(net "P3V3_SSD7")
	)
	(via
		(at 215.333072 -26.971244)
		(size 0.508)
		(drill 0.254)
		(layers "F.Cu" "B.Cu")
		(net "P3V3_SSD7")
	)
	(via
		(at 201.86396 -49.574704)
		(size 0.508)
		(drill 0.254)
		(layers "F.Cu" "B.Cu")
		(net "P3V3_SSD7")
	)
	(via
		(at 198.410576 -29.614876)
		(size 0.508)
		(drill 0.254)
		(layers "F.Cu" "B.Cu")
		(net "P3V3_SSD7")
	)
	(via
		(at 202.49896 -49.574704)
		(size 0.508)
		(drill 0.254)
		(layers "F.Cu" "B.Cu")
		(net "P3V3_SSD7")
	)
	(via
		(at 213.571582 -26.360882)
		(size 0.508)
		(drill 0.254)
		(layers "F.Cu" "B.Cu")
		(net "P3V3_SSD7")
	)
	(via
		(at 202.278996 -60.633356)
		(size 0.508)
		(drill 0.254)
		(layers "F.Cu" "B.Cu")
		(net "P3V3_SSD7")
	)
	(segment
		(start 187.08878 -38.322758)
		(end 186.241182 -37.47516)
		(width 0.508)
		(layer "In9.Cu")
		(net "P3V3_SSD7")
	)
	(segment
		(start 188.70422 -38.322758)
		(end 187.08878 -38.322758)
		(width 0.508)
		(layer "In9.Cu")
		(net "P3V3_SSD7")
	)
	(segment
		(start 195.863718 -37.872924)
		(end 189.154054 -37.872924)
		(width 0.508)
		(layer "In9.Cu")
		(net "P3V3_SSD7")
	)
	(segment
		(start 189.154054 -37.872924)
		(end 188.70422 -38.322758)
		(width 0.508)
		(layer "In9.Cu")
		(net "P3V3_SSD7")
	)
	(segment
		(start 258.969002 -304.253138)
		(end 263.886188 -302.215804)
		(width 0.1651)
		(layer "In5.Cu")
		(net "P5E_PEX2_STN7_RX_DN<113>")
	)
	(segment
		(start 251.479812 -316.67958)
		(end 251.68225 -316.226952)
		(width 0.1651)
		(layer "In5.Cu")
		(net "P5E_PEX2_STN7_RX_DN<113>")
	)
	(segment
		(start 252.118114 -315.002672)
		(end 252.320044 -314.550552)
		(width 0.1651)
		(layer "In5.Cu")
		(net "P5E_PEX2_STN7_RX_DN<113>")
	)
	(segment
		(start 251.3457 -316.730888)
		(end 251.479812 -316.67958)
		(width 0.1651)
		(layer "In5.Cu")
		(net "P5E_PEX2_STN7_RX_DN<113>")
	)
	(segment
		(start 252.169422 -315.137038)
		(end 252.118114 -315.002672)
		(width 0.1651)
		(layer "In5.Cu")
		(net "P5E_PEX2_STN7_RX_DN<113>")
	)
	(segment
		(start 280.162 -378.9426)
		(end 279.629108 -373.121682)
		(width 0.1651)
		(layer "In5.Cu")
		(net "P5E_PEX2_STN7_RX_DN<113>")
	)
	(segment
		(start 288.8234 -393.5984)
		(end 284.48508 -390.972548)
		(width 0.1651)
		(layer "In5.Cu")
		(net "P5E_PEX2_STN7_RX_DN<113>")
	)
	(segment
		(start 254.594868 -309.709312)
		(end 254.54356 -309.5752)
		(width 0.1651)
		(layer "In5.Cu")
		(net "P5E_PEX2_STN7_RX_DN<113>")
	)
	(segment
		(start 269.315184 -302.549814)
		(end 269.049754 -302.549814)
		(width 0.1143)
		(layer "In5.Cu")
		(net "P5E_PEX2_STN7_RX_DN<113>")
	)
	(segment
		(start 250.7361 -318.094868)
		(end 251.3457 -316.730888)
		(width 0.1651)
		(layer "In5.Cu")
		(net "P5E_PEX2_STN7_RX_DN<113>")
	)
	(segment
		(start 258.061206 -336.337402)
		(end 252.80493 -327.89368)
		(width 0.1651)
		(layer "In5.Cu")
		(net "P5E_PEX2_STN7_RX_DN<113>")
	)
	(segment
		(start 251.832872 -315.64072)
		(end 251.966984 -315.589412)
		(width 0.1651)
		(layer "In5.Cu")
		(net "P5E_PEX2_STN7_RX_DN<113>")
	)
	(segment
		(start 267.7922 -302.215804)
		(end 267.820648 -302.215804)
		(width 0.1143)
		(layer "In5.Cu")
		(net "P5E_PEX2_STN7_RX_DN<113>")
	)
	(segment
		(start 255.08204 -308.619398)
		(end 255.030732 -308.485286)
		(width 0.1651)
		(layer "In5.Cu")
		(net "P5E_PEX2_STN7_RX_DN<113>")
	)
	(segment
		(start 254.54356 -309.5752)
		(end 254.74549 -309.12308)
		(width 0.1651)
		(layer "In5.Cu")
		(net "P5E_PEX2_STN7_RX_DN<113>")
	)
	(segment
		(start 254.056388 -310.665368)
		(end 254.258318 -310.213248)
		(width 0.1651)
		(layer "In5.Cu")
		(net "P5E_PEX2_STN7_RX_DN<113>")
	)
	(segment
		(start 278.92629 -371.724428)
		(end 267.73886 -360.332782)
		(width 0.1651)
		(layer "In5.Cu")
		(net "P5E_PEX2_STN7_RX_DN<113>")
	)
	(segment
		(start 267.866368 -302.170084)
		(end 269.315184 -302.170084)
		(width 0.1143)
		(layer "In5.Cu")
		(net "P5E_PEX2_STN7_RX_DN<113>")
	)
	(segment
		(start 280.481532 -385.564888)
		(end 280.162 -378.9426)
		(width 0.1651)
		(layer "In5.Cu")
		(net "P5E_PEX2_STN7_RX_DN<113>")
	)
	(segment
		(start 267.73886 -360.332782)
		(end 258.061206 -336.337402)
		(width 0.1651)
		(layer "In5.Cu")
		(net "P5E_PEX2_STN7_RX_DN<113>")
	)
	(segment
		(start 263.886188 -302.215804)
		(end 267.7922 -302.215804)
		(width 0.1651)
		(layer "In5.Cu")
		(net "P5E_PEX2_STN7_RX_DN<113>")
	)
	(segment
		(start 289.689794 -410.589984)
		(end 289.689794 -410.207968)
		(width 0.1651)
		(layer "In5.Cu")
		(net "P5E_PEX2_STN7_RX_DN<113>")
	)
	(segment
		(start 253.771146 -311.303416)
		(end 253.905258 -311.252108)
		(width 0.1651)
		(layer "In5.Cu")
		(net "P5E_PEX2_STN7_RX_DN<113>")
	)
	(segment
		(start 269.429484 -302.435514)
		(end 269.315184 -302.549814)
		(width 0.1143)
		(layer "In5.Cu")
		(net "P5E_PEX2_STN7_RX_DN<113>")
	)
	(segment
		(start 254.107696 -310.79948)
		(end 254.056388 -310.665368)
		(width 0.1651)
		(layer "In5.Cu")
		(net "P5E_PEX2_STN7_RX_DN<113>")
	)
	(segment
		(start 290.815776 -409.629102)
		(end 290.815776 -395.9606)
		(width 0.1651)
		(layer "In5.Cu")
		(net "P5E_PEX2_STN7_RX_DN<113>")
	)
	(segment
		(start 253.905258 -311.252108)
		(end 254.107696 -310.79948)
		(width 0.1651)
		(layer "In5.Cu")
		(net "P5E_PEX2_STN7_RX_DN<113>")
	)
	(segment
		(start 267.820648 -302.215804)
		(end 267.866368 -302.170084)
		(width 0.1143)
		(layer "In5.Cu")
		(net "P5E_PEX2_STN7_RX_DN<113>")
	)
	(segment
		(start 284.48508 -390.972548)
		(end 281.79395 -388.52729)
		(width 0.1651)
		(layer "In5.Cu")
		(net "P5E_PEX2_STN7_RX_DN<113>")
	)
	(segment
		(start 254.879602 -309.071772)
		(end 255.08204 -308.619398)
		(width 0.1651)
		(layer "In5.Cu")
		(net "P5E_PEX2_STN7_RX_DN<113>")
	)
	(segment
		(start 250.7361 -323.103494)
		(end 250.7361 -318.094868)
		(width 0.1651)
		(layer "In5.Cu")
		(net "P5E_PEX2_STN7_RX_DN<113>")
	)
	(segment
		(start 290.5506 -395.3002)
		(end 288.8234 -393.5984)
		(width 0.1651)
		(layer "In5.Cu")
		(net "P5E_PEX2_STN7_RX_DN<113>")
	)
	(segment
		(start 252.80493 -327.89368)
		(end 250.7361 -323.103494)
		(width 0.1651)
		(layer "In5.Cu")
		(net "P5E_PEX2_STN7_RX_DN<113>")
	)
	(segment
		(start 252.320044 -314.550552)
		(end 252.454156 -314.499244)
		(width 0.1651)
		(layer "In5.Cu")
		(net "P5E_PEX2_STN7_RX_DN<113>")
	)
	(segment
		(start 279.629108 -373.121682)
		(end 278.92629 -371.724428)
		(width 0.1651)
		(layer "In5.Cu")
		(net "P5E_PEX2_STN7_RX_DN<113>")
	)
	(segment
		(start 252.605286 -313.912504)
		(end 253.771146 -311.303416)
		(width 0.1651)
		(layer "In5.Cu")
		(net "P5E_PEX2_STN7_RX_DN<113>")
	)
	(segment
		(start 255.267968 -307.954172)
		(end 258.969002 -304.253138)
		(width 0.1651)
		(layer "In5.Cu")
		(net "P5E_PEX2_STN7_RX_DN<113>")
	)
	(segment
		(start 255.030732 -308.485286)
		(end 255.267968 -307.954172)
		(width 0.1651)
		(layer "In5.Cu")
		(net "P5E_PEX2_STN7_RX_DN<113>")
	)
	(segment
		(start 252.656594 -314.04687)
		(end 252.605286 -313.912504)
		(width 0.1651)
		(layer "In5.Cu")
		(net "P5E_PEX2_STN7_RX_DN<113>")
	)
	(segment
		(start 289.689794 -410.207968)
		(end 289.816794 -410.080968)
		(width 0.1651)
		(layer "In5.Cu")
		(net "P5E_PEX2_STN7_RX_DN<113>")
	)
	(segment
		(start 269.429484 -302.284384)
		(end 269.429484 -302.435514)
		(width 0.1143)
		(layer "In5.Cu")
		(net "P5E_PEX2_STN7_RX_DN<113>")
	)
	(segment
		(start 290.815776 -395.9606)
		(end 290.5506 -395.3002)
		(width 0.1651)
		(layer "In5.Cu")
		(net "P5E_PEX2_STN7_RX_DN<113>")
	)
	(segment
		(start 252.454156 -314.499244)
		(end 252.656594 -314.04687)
		(width 0.1651)
		(layer "In5.Cu")
		(net "P5E_PEX2_STN7_RX_DN<113>")
	)
	(segment
		(start 254.74549 -309.12308)
		(end 254.879602 -309.071772)
		(width 0.1651)
		(layer "In5.Cu")
		(net "P5E_PEX2_STN7_RX_DN<113>")
	)
	(segment
		(start 289.816794 -410.080968)
		(end 290.36391 -410.080968)
		(width 0.1651)
		(layer "In5.Cu")
		(net "P5E_PEX2_STN7_RX_DN<113>")
	)
	(segment
		(start 290.36391 -410.080968)
		(end 290.815776 -409.629102)
		(width 0.1651)
		(layer "In5.Cu")
		(net "P5E_PEX2_STN7_RX_DN<113>")
	)
	(segment
		(start 251.966984 -315.589412)
		(end 252.169422 -315.137038)
		(width 0.1651)
		(layer "In5.Cu")
		(net "P5E_PEX2_STN7_RX_DN<113>")
	)
	(segment
		(start 281.79395 -388.52729)
		(end 280.481532 -385.564888)
		(width 0.1651)
		(layer "In5.Cu")
		(net "P5E_PEX2_STN7_RX_DN<113>")
	)
	(segment
		(start 251.630942 -316.09284)
		(end 251.832872 -315.64072)
		(width 0.1651)
		(layer "In5.Cu")
		(net "P5E_PEX2_STN7_RX_DN<113>")
	)
	(segment
		(start 269.315184 -302.170084)
		(end 269.429484 -302.284384)
		(width 0.1143)
		(layer "In5.Cu")
		(net "P5E_PEX2_STN7_RX_DN<113>")
	)
	(segment
		(start 254.258318 -310.213248)
		(end 254.39243 -310.16194)
		(width 0.1651)
		(layer "In5.Cu")
		(net "P5E_PEX2_STN7_RX_DN<113>")
	)
	(segment
		(start 254.39243 -310.16194)
		(end 254.594868 -309.709312)
		(width 0.1651)
		(layer "In5.Cu")
		(net "P5E_PEX2_STN7_RX_DN<113>")
	)
	(segment
		(start 251.68225 -316.226952)
		(end 251.630942 -316.09284)
		(width 0.1651)
		(layer "In5.Cu")
		(net "P5E_PEX2_STN7_RX_DN<113>")
	)
	(segment
		(start 384.96494 -33.790128)
		(end 384.48742 -33.790128)
		(width 0.13462)
		(layer "F.Cu")
		(net "P5E_PEX3_STN2_RX_DN<43>")
	)
	(segment
		(start 381.79883 -33.9471)
		(end 381.51054 -33.65881)
		(width 0.13462)
		(layer "F.Cu")
		(net "P5E_PEX3_STN2_RX_DN<43>")
	)
	(segment
		(start 384.48742 -33.790128)
		(end 384.330448 -33.9471)
		(width 0.13462)
		(layer "F.Cu")
		(net "P5E_PEX3_STN2_RX_DN<43>")
	)
	(segment
		(start 384.330448 -33.9471)
		(end 381.79883 -33.9471)
		(width 0.13462)
		(layer "F.Cu")
		(net "P5E_PEX3_STN2_RX_DN<43>")
	)
	(segment
		(start 395.7574 -262.822944)
		(end 396.035022 -248.471436)
		(width 0.1651)
		(layer "In7.Cu")
		(net "P5E_PEX3_STN2_RX_DN<43>")
	)
	(segment
		(start 382.15189 -33.94964)
		(end 381.80137 -33.94964)
		(width 0.1651)
		(layer "In7.Cu")
		(net "P5E_PEX3_STN2_RX_DN<43>")
	)
	(segment
		(start 383.18821 -35.355276)
		(end 383.18821 -34.98596)
		(width 0.1651)
		(layer "In7.Cu")
		(net "P5E_PEX3_STN2_RX_DN<43>")
	)
	(segment
		(start 396.321026 -273.479514)
		(end 396.17015 -273.328638)
		(width 0.1143)
		(layer "In7.Cu")
		(net "P5E_PEX3_STN2_RX_DN<43>")
	)
	(segment
		(start 388.374636 -131.985766)
		(end 388.50824 -119.592598)
		(width 0.1651)
		(layer "In7.Cu")
		(net "P5E_PEX3_STN2_RX_DN<43>")
	)
	(segment
		(start 384.86842 -65.250314)
		(end 384.47726 -55.479696)
		(width 0.1651)
		(layer "In7.Cu")
		(net "P5E_PEX3_STN2_RX_DN<43>")
	)
	(segment
		(start 383.18821 -34.98596)
		(end 382.15189 -33.94964)
		(width 0.1651)
		(layer "In7.Cu")
		(net "P5E_PEX3_STN2_RX_DN<43>")
	)
	(segment
		(start 388.070598 -105.13822)
		(end 384.86842 -65.250314)
		(width 0.1651)
		(layer "In7.Cu")
		(net "P5E_PEX3_STN2_RX_DN<43>")
	)
	(segment
		(start 396.17015 -273.328638)
		(end 396.17015 -271.41932)
		(width 0.1143)
		(layer "In7.Cu")
		(net "P5E_PEX3_STN2_RX_DN<43>")
	)
	(segment
		(start 387.63575 -141.670024)
		(end 387.669532 -138.51128)
		(width 0.1651)
		(layer "In7.Cu")
		(net "P5E_PEX3_STN2_RX_DN<43>")
	)
	(segment
		(start 396.21587 -271.345152)
		(end 396.21587 -267.871956)
		(width 0.1651)
		(layer "In7.Cu")
		(net "P5E_PEX3_STN2_RX_DN<43>")
	)
	(segment
		(start 383.256536 -39.76497)
		(end 383.18821 -35.355276)
		(width 0.1651)
		(layer "In7.Cu")
		(net "P5E_PEX3_STN2_RX_DN<43>")
	)
	(segment
		(start 388.50824 -119.592598)
		(end 388.070598 -105.13822)
		(width 0.1651)
		(layer "In7.Cu")
		(net "P5E_PEX3_STN2_RX_DN<43>")
	)
	(segment
		(start 384.47726 -55.479696)
		(end 384.570986 -49.492662)
		(width 0.1651)
		(layer "In7.Cu")
		(net "P5E_PEX3_STN2_RX_DN<43>")
	)
	(segment
		(start 396.43558 -273.479514)
		(end 396.321026 -273.479514)
		(width 0.1143)
		(layer "In7.Cu")
		(net "P5E_PEX3_STN2_RX_DN<43>")
	)
	(segment
		(start 396.21587 -267.871956)
		(end 395.7574 -263.216136)
		(width 0.1651)
		(layer "In7.Cu")
		(net "P5E_PEX3_STN2_RX_DN<43>")
	)
	(segment
		(start 396.54988 -273.099784)
		(end 396.54988 -273.365214)
		(width 0.1143)
		(layer "In7.Cu")
		(net "P5E_PEX3_STN2_RX_DN<43>")
	)
	(segment
		(start 396.035022 -248.471436)
		(end 387.63575 -141.670024)
		(width 0.1651)
		(layer "In7.Cu")
		(net "P5E_PEX3_STN2_RX_DN<43>")
	)
	(segment
		(start 396.17015 -271.41932)
		(end 396.21587 -271.3736)
		(width 0.1143)
		(layer "In7.Cu")
		(net "P5E_PEX3_STN2_RX_DN<43>")
	)
	(segment
		(start 395.7574 -263.216136)
		(end 395.7574 -262.822944)
		(width 0.1651)
		(layer "In7.Cu")
		(net "P5E_PEX3_STN2_RX_DN<43>")
	)
	(segment
		(start 396.21587 -271.3736)
		(end 396.21587 -271.345152)
		(width 0.1143)
		(layer "In7.Cu")
		(net "P5E_PEX3_STN2_RX_DN<43>")
	)
	(segment
		(start 381.80137 -33.94964)
		(end 381.51054 -33.65881)
		(width 0.1651)
		(layer "In7.Cu")
		(net "P5E_PEX3_STN2_RX_DN<43>")
	)
	(segment
		(start 396.54988 -273.365214)
		(end 396.43558 -273.479514)
		(width 0.1143)
		(layer "In7.Cu")
		(net "P5E_PEX3_STN2_RX_DN<43>")
	)
	(segment
		(start 387.669532 -138.51128)
		(end 388.374636 -131.985766)
		(width 0.1651)
		(layer "In7.Cu")
		(net "P5E_PEX3_STN2_RX_DN<43>")
	)
	(segment
		(start 384.570986 -49.492662)
		(end 383.256536 -39.76497)
		(width 0.1651)
		(layer "In7.Cu")
		(net "P5E_PEX3_STN2_RX_DN<43>")
	)
	(segment
		(start 192.76949 -20.467574)
		(end 192.156588 -20.467574)
		(width 0.508)
		(layer "F.Cu")
		(net "P3V3_SSD6")
	)
	(segment
		(start 183.364886 -24.790146)
		(end 184.333388 -24.790146)
		(width 0.381)
		(layer "F.Cu")
		(net "P3V3_SSD6")
	)
	(segment
		(start 193.725038 -14.735302)
		(end 193.660522 -14.799818)
		(width 0.381)
		(layer "F.Cu")
		(net "P3V3_SSD6")
	)
	(segment
		(start 174.06874 -30.971236)
		(end 173.494192 -30.396688)
		(width 0.381)
		(layer "F.Cu")
		(net "P3V3_SSD6")
	)
	(segment
		(start 173.794166 -34.248852)
		(end 173.794166 -32.787336)
		(width 0.381)
		(layer "F.Cu")
		(net "P3V3_SSD6")
	)
	(segment
		(start 160.946846 -37.47516)
		(end 160.241234 -37.47516)
		(width 0.4572)
		(layer "F.Cu")
		(net "P3V3_SSD6")
	)
	(segment
		(start 174.06874 -32.512762)
		(end 174.06874 -30.971236)
		(width 0.381)
		(layer "F.Cu")
		(net "P3V3_SSD6")
	)
	(segment
		(start 176.279048 -59.978036)
		(end 176.279048 -60.633356)
		(width 0.381)
		(layer "F.Cu")
		(net "P3V3_SSD6")
	)
	(segment
		(start 175.471836 -24.807418)
		(end 174.853346 -24.807418)
		(width 0.4572)
		(layer "F.Cu")
		(net "P3V3_SSD6")
	)
	(segment
		(start 173.794166 -32.787336)
		(end 174.06874 -32.512762)
		(width 0.381)
		(layer "F.Cu")
		(net "P3V3_SSD6")
	)
	(segment
		(start 189.98565 -27.492198)
		(end 189.854078 -27.492198)
		(width 0.381)
		(layer "F.Cu")
		(net "P3V3_SSD6")
	)
	(segment
		(start 186.026552 -25.031954)
		(end 186.669934 -25.031954)
		(width 0.4572)
		(layer "F.Cu")
		(net "P3V3_SSD6")
	)
	(segment
		(start 193.660522 -14.799818)
		(end 193.660522 -16.439388)
		(width 0.381)
		(layer "F.Cu")
		(net "P3V3_SSD6")
	)
	(segment
		(start 184.333388 -24.790146)
		(end 184.575196 -25.031954)
		(width 0.381)
		(layer "F.Cu")
		(net "P3V3_SSD6")
	)
	(segment
		(start 189.854078 -27.492198)
		(end 189.333124 -26.971244)
		(width 0.381)
		(layer "F.Cu")
		(net "P3V3_SSD6")
	)
	(segment
		(start 184.575196 -25.031954)
		(end 186.026552 -25.031954)
		(width 0.381)
		(layer "F.Cu")
		(net "P3V3_SSD6")
	)
	(segment
		(start 193.725038 -14.100302)
		(end 193.725038 -14.735302)
		(width 0.381)
		(layer "F.Cu")
		(net "P3V3_SSD6")
	)
	(segment
		(start 187.571634 -25.742392)
		(end 187.571634 -26.360882)
		(width 0.4572)
		(layer "F.Cu")
		(net "P3V3_SSD6")
	)
	(segment
		(start 192.156588 -17.419574)
		(end 192.766188 -17.419574)
		(width 0.508)
		(layer "F.Cu")
		(net "P3V3_SSD6")
	)
	(via
		(at 187.571634 -26.360882)
		(size 0.508)
		(drill 0.254)
		(layers "F.Cu" "B.Cu")
		(net "P3V3_SSD6")
	)
	(via
		(at 175.699928 -52.528724)
		(size 0.508)
		(drill 0.254)
		(layers "F.Cu" "B.Cu")
		(net "P3V3_SSD6")
	)
	(via
		(at 189.333124 -26.971244)
		(size 0.508)
		(drill 0.254)
		(layers "F.Cu" "B.Cu")
		(net "P3V3_SSD6")
	)
	(via
		(at 192.766188 -17.419574)
		(size 0.508)
		(drill 0.254)
		(layers "F.Cu" "B.Cu")
		(net "P3V3_SSD6")
	)
	(via
		(at 186.669934 -25.031954)
		(size 0.508)
		(drill 0.254)
		(layers "F.Cu" "B.Cu")
		(net "P3V3_SSD6")
	)
	(via
		(at 176.279048 -60.633356)
		(size 0.508)
		(drill 0.254)
		(layers "F.Cu" "B.Cu")
		(net "P3V3_SSD6")
	)
	(via
		(at 172.410628 -30.376876)
		(size 0.508)
		(drill 0.254)
		(layers "F.Cu" "B.Cu")
		(net "P3V3_SSD6")
	)
	(via
		(at 175.249586 -53.469286)
		(size 0.508)
		(drill 0.254)
		(layers "F.Cu" "B.Cu")
		(net "P3V3_SSD6")
	)
	(via
		(at 172.410628 -29.614876)
		(size 0.508)
		(drill 0.254)
		(layers "F.Cu" "B.Cu")
		(net "P3V3_SSD6")
	)
	(via
		(at 193.725038 -14.100302)
		(size 0.508)
		(drill 0.254)
		(layers "F.Cu" "B.Cu")
		(net "P3V3_SSD6")
	)
	(via
		(at 175.614584 -50.608992)
		(size 0.508)
		(drill 0.254)
		(layers "F.Cu" "B.Cu")
		(net "P3V3_SSD6")
	)
	(via
		(at 174.853346 -24.807418)
		(size 0.508)
		(drill 0.254)
		(layers "F.Cu" "B.Cu")
		(net "P3V3_SSD6")
	)
	(via
		(at 174.594012 -50.478182)
		(size 0.6604)
		(drill 0.3302)
		(layers "F.Cu" "B.Cu")
		(net "P3V3_SSD6")
	)
	(via
		(at 160.241234 -37.47516)
		(size 0.508)
		(drill 0.254)
		(layers "F.Cu" "B.Cu")
		(net "P3V3_SSD6")
	)
	(via
		(at 174.594012 -49.574704)
		(size 0.508)
		(drill 0.254)
		(layers "F.Cu" "B.Cu")
		(net "P3V3_SSD6")
	)
	(via
		(at 176.376584 -50.608992)
		(size 0.508)
		(drill 0.254)
		(layers "F.Cu" "B.Cu")
		(net "P3V3_SSD6")
	)
	(via
		(at 174.614586 -53.469286)
		(size 0.508)
		(drill 0.254)
		(layers "F.Cu" "B.Cu")
		(net "P3V3_SSD6")
	)
	(via
		(at 176.499012 -49.574704)
		(size 0.508)
		(drill 0.254)
		(layers "F.Cu" "B.Cu")
		(net "P3V3_SSD6")
	)
	(via
		(at 175.064928 -52.528724)
		(size 0.508)
		(drill 0.254)
		(layers "F.Cu" "B.Cu")
		(net "P3V3_SSD6")
	)
	(via
		(at 192.76949 -20.467574)
		(size 0.508)
		(drill 0.254)
		(layers "F.Cu" "B.Cu")
		(net "P3V3_SSD6")
	)
	(via
		(at 175.229012 -49.574704)
		(size 0.508)
		(drill 0.254)
		(layers "F.Cu" "B.Cu")
		(net "P3V3_SSD6")
	)
	(via
		(at 175.614584 -51.243992)
		(size 0.508)
		(drill 0.254)
		(layers "F.Cu" "B.Cu")
		(net "P3V3_SSD6")
	)
	(via
		(at 176.376584 -51.320192)
		(size 0.508)
		(drill 0.254)
		(layers "F.Cu" "B.Cu")
		(net "P3V3_SSD6")
	)
	(via
		(at 175.864012 -49.574704)
		(size 0.508)
		(drill 0.254)
		(layers "F.Cu" "B.Cu")
		(net "P3V3_SSD6")
	)
	(segment
		(start 162.704272 -38.322758)
		(end 161.088832 -38.322758)
		(width 0.508)
		(layer "In9.Cu")
		(net "P3V3_SSD6")
	)
	(segment
		(start 169.86377 -37.872924)
		(end 163.154106 -37.872924)
		(width 0.508)
		(layer "In9.Cu")
		(net "P3V3_SSD6")
	)
	(segment
		(start 161.088832 -38.322758)
		(end 160.241234 -37.47516)
		(width 0.508)
		(layer "In9.Cu")
		(net "P3V3_SSD6")
	)
	(segment
		(start 163.154106 -37.872924)
		(end 162.704272 -38.322758)
		(width 0.508)
		(layer "In9.Cu")
		(net "P3V3_SSD6")
	)
	(segment
		(start 358.485948 -28.99029)
		(end 358.311958 -28.8163)
		(width 0.13462)
		(layer "F.Cu")
		(net "P5E_PEX3_STN2_RX_DP<44>")
	)
	(segment
		(start 358.964992 -28.99029)
		(end 358.485948 -28.99029)
		(width 0.13462)
		(layer "F.Cu")
		(net "P5E_PEX3_STN2_RX_DP<44>")
	)
	(segment
		(start 357.670862 -28.8163)
		(end 357.364792 -29.12237)
		(width 0.13462)
		(layer "F.Cu")
		(net "P5E_PEX3_STN2_RX_DP<44>")
	)
	(segment
		(start 358.311958 -28.8163)
		(end 357.670862 -28.8163)
		(width 0.13462)
		(layer "F.Cu")
		(net "P5E_PEX3_STN2_RX_DP<44>")
	)
	(segment
		(start 358.964992 -28.990036)
		(end 358.964992 -28.99029)
		(width 0.13462)
		(layer "F.Cu")
		(net "P5E_PEX3_STN2_RX_DP<44>")
	)
	(segment
		(start 395.244828 -275.570188)
		(end 395.029436 -275.354796)
		(width 0.1143)
		(layer "In7.Cu")
		(net "P5E_PEX3_STN2_RX_DP<44>")
	)
	(segment
		(start 361.150662 -32.754824)
		(end 361.19816 -32.638492)
		(width 0.1651)
		(layer "In7.Cu")
		(net "P5E_PEX3_STN2_RX_DP<44>")
	)
	(segment
		(start 361.17911 -49.388014)
		(end 363.325156 -39.137844)
		(width 0.1651)
		(layer "In7.Cu")
		(net "P5E_PEX3_STN2_RX_DP<44>")
	)
	(segment
		(start 395.59992 -275.949918)
		(end 395.59992 -275.684488)
		(width 0.1143)
		(layer "In7.Cu")
		(net "P5E_PEX3_STN2_RX_DP<44>")
	)
	(segment
		(start 361.324906 -61.849762)
		(end 361.324906 -60.073794)
		(width 0.1651)
		(layer "In7.Cu")
		(net "P5E_PEX3_STN2_RX_DP<44>")
	)
	(segment
		(start 363.325156 -39.137844)
		(end 363.348524 -37.742622)
		(width 0.1651)
		(layer "In7.Cu")
		(net "P5E_PEX3_STN2_RX_DP<44>")
	)
	(segment
		(start 361.055158 -57.335674)
		(end 361.17911 -49.388014)
		(width 0.1651)
		(layer "In7.Cu")
		(net "P5E_PEX3_STN2_RX_DP<44>")
	)
	(segment
		(start 394.983716 -269.523718)
		(end 394.030708 -263.48055)
		(width 0.1651)
		(layer "In7.Cu")
		(net "P5E_PEX3_STN2_RX_DP<44>")
	)
	(segment
		(start 359.460292 -30.634432)
		(end 358.796082 -29.64053)
		(width 0.1651)
		(layer "In7.Cu")
		(net "P5E_PEX3_STN2_RX_DP<44>")
	)
	(segment
		(start 361.91317 -34.335974)
		(end 361.796838 -34.288476)
		(width 0.1651)
		(layer "In7.Cu")
		(net "P5E_PEX3_STN2_RX_DP<44>")
	)
	(segment
		(start 394.983716 -271.392904)
		(end 394.983716 -269.523718)
		(width 0.1651)
		(layer "In7.Cu")
		(net "P5E_PEX3_STN2_RX_DP<44>")
	)
	(segment
		(start 392.501628 -238.07547)
		(end 374.78716 -144.398238)
		(width 0.1651)
		(layer "In7.Cu")
		(net "P5E_PEX3_STN2_RX_DP<44>")
	)
	(segment
		(start 361.324906 -60.073794)
		(end 361.055158 -57.335674)
		(width 0.1651)
		(layer "In7.Cu")
		(net "P5E_PEX3_STN2_RX_DP<44>")
	)
	(segment
		(start 361.19816 -32.638492)
		(end 361.004358 -32.178498)
		(width 0.1651)
		(layer "In7.Cu")
		(net "P5E_PEX3_STN2_RX_DP<44>")
	)
	(segment
		(start 361.651804 -33.715452)
		(end 361.459526 -33.259014)
		(width 0.1651)
		(layer "In7.Cu")
		(net "P5E_PEX3_STN2_RX_DP<44>")
	)
	(segment
		(start 357.987092 -28.83154)
		(end 357.719884 -28.83154)
		(width 0.1651)
		(layer "In7.Cu")
		(net "P5E_PEX3_STN2_RX_DP<44>")
	)
	(segment
		(start 357.719884 -28.83154)
		(end 357.610156 -28.877006)
		(width 0.1651)
		(layer "In7.Cu")
		(net "P5E_PEX3_STN2_RX_DP<44>")
	)
	(segment
		(start 361.796838 -34.288476)
		(end 361.604306 -33.831784)
		(width 0.1651)
		(layer "In7.Cu")
		(net "P5E_PEX3_STN2_RX_DP<44>")
	)
	(segment
		(start 363.348524 -37.742622)
		(end 361.91317 -34.335974)
		(width 0.1651)
		(layer "In7.Cu")
		(net "P5E_PEX3_STN2_RX_DP<44>")
	)
	(segment
		(start 361.459526 -33.259014)
		(end 361.343194 -33.211516)
		(width 0.1651)
		(layer "In7.Cu")
		(net "P5E_PEX3_STN2_RX_DP<44>")
	)
	(segment
		(start 395.48562 -275.570188)
		(end 395.244828 -275.570188)
		(width 0.1143)
		(layer "In7.Cu")
		(net "P5E_PEX3_STN2_RX_DP<44>")
	)
	(segment
		(start 394.10767 -255.61925)
		(end 392.501628 -238.07547)
		(width 0.1651)
		(layer "In7.Cu")
		(net "P5E_PEX3_STN2_RX_DP<44>")
	)
	(segment
		(start 371.500146 -119.40921)
		(end 361.135422 -85.214206)
		(width 0.1651)
		(layer "In7.Cu")
		(net "P5E_PEX3_STN2_RX_DP<44>")
	)
	(segment
		(start 395.029436 -275.354796)
		(end 395.029436 -271.467072)
		(width 0.1143)
		(layer "In7.Cu")
		(net "P5E_PEX3_STN2_RX_DP<44>")
	)
	(segment
		(start 361.004358 -32.178498)
		(end 359.460292 -30.634432)
		(width 0.1651)
		(layer "In7.Cu")
		(net "P5E_PEX3_STN2_RX_DP<44>")
	)
	(segment
		(start 361.343194 -33.211516)
		(end 361.150662 -32.754824)
		(width 0.1651)
		(layer "In7.Cu")
		(net "P5E_PEX3_STN2_RX_DP<44>")
	)
	(segment
		(start 395.029436 -271.467072)
		(end 394.983716 -271.421352)
		(width 0.1143)
		(layer "In7.Cu")
		(net "P5E_PEX3_STN2_RX_DP<44>")
	)
	(segment
		(start 358.796082 -29.64053)
		(end 357.987092 -28.83154)
		(width 0.1651)
		(layer "In7.Cu")
		(net "P5E_PEX3_STN2_RX_DP<44>")
	)
	(segment
		(start 394.983716 -271.421352)
		(end 394.983716 -271.392904)
		(width 0.1143)
		(layer "In7.Cu")
		(net "P5E_PEX3_STN2_RX_DP<44>")
	)
	(segment
		(start 394.030708 -263.48055)
		(end 394.10767 -255.61925)
		(width 0.1651)
		(layer "In7.Cu")
		(net "P5E_PEX3_STN2_RX_DP<44>")
	)
	(segment
		(start 395.59992 -275.684488)
		(end 395.48562 -275.570188)
		(width 0.1143)
		(layer "In7.Cu")
		(net "P5E_PEX3_STN2_RX_DP<44>")
	)
	(segment
		(start 361.135422 -85.214206)
		(end 361.324906 -61.849762)
		(width 0.1651)
		(layer "In7.Cu")
		(net "P5E_PEX3_STN2_RX_DP<44>")
	)
	(segment
		(start 361.604306 -33.831784)
		(end 361.651804 -33.715452)
		(width 0.1651)
		(layer "In7.Cu")
		(net "P5E_PEX3_STN2_RX_DP<44>")
	)
	(segment
		(start 357.610156 -28.877006)
		(end 357.364792 -29.12237)
		(width 0.1651)
		(layer "In7.Cu")
		(net "P5E_PEX3_STN2_RX_DP<44>")
	)
	(segment
		(start 374.78716 -144.398238)
		(end 371.500146 -119.40921)
		(width 0.1651)
		(layer "In7.Cu")
		(net "P5E_PEX3_STN2_RX_DP<44>")
	)
	(segment
		(start 296.106596 -103.814372)
		(end 297.131232 -103.814372)
		(width 0.13208)
		(layer "F.Cu")
		(net "NCSI_NIC5_TXD0")
	)
	(segment
		(start 299.101764 -101.84003)
		(end 300.857412 -101.84003)
		(width 0.13208)
		(layer "F.Cu")
		(net "NCSI_NIC5_TXD0")
	)
	(segment
		(start 298.3357 -102.606094)
		(end 299.101764 -101.84003)
		(width 0.13208)
		(layer "F.Cu")
		(net "NCSI_NIC5_TXD0")
	)
	(segment
		(start 298.3357 -102.609904)
		(end 298.3357 -102.606094)
		(width 0.13208)
		(layer "F.Cu")
		(net "NCSI_NIC5_TXD0")
	)
	(segment
		(start 297.131232 -103.814372)
		(end 298.3357 -102.609904)
		(width 0.13208)
		(layer "F.Cu")
		(net "NCSI_NIC5_TXD0")
	)
	(segment
		(start 291.595048 -103.814372)
		(end 296.106596 -103.814372)
		(width 0.13208)
		(layer "F.Cu")
		(net "NCSI_NIC5_TXD0")
	)
	(via
		(at 296.106596 -103.814372)
		(size 0.762)
		(drill 0.381)
		(layers "F.Cu" "B.Cu")
		(net "NCSI_NIC5_TXD0")
	)
	(segment
		(start 177.119534 -24.790146)
		(end 177.102262 -24.807418)
		(width 0.13208)
		(layer "F.Cu")
		(net "PU_CLKREQ6")
	)
	(segment
		(start 177.102262 -24.807418)
		(end 176.271936 -24.807418)
		(width 0.13208)
		(layer "F.Cu")
		(net "PU_CLKREQ6")
	)
	(segment
		(start 178.764946 -24.790146)
		(end 177.119534 -24.790146)
		(width 0.13208)
		(layer "F.Cu")
		(net "PU_CLKREQ6")
	)
	(via
		(at 177.102262 -24.807418)
		(size 0.508)
		(drill 0.254)
		(layers "F.Cu" "B.Cu")
		(net "PU_CLKREQ6")
	)
	(segment
		(start 364.232698 -28.55468)
		(end 364.068106 -28.390088)
		(width 0.13462)
		(layer "F.Cu")
		(net "P5E_PEX3_STN2_TX_C_DN<44>")
	)
	(segment
		(start 365.496348 -28.55468)
		(end 364.232698 -28.55468)
		(width 0.13462)
		(layer "F.Cu")
		(net "P5E_PEX3_STN2_TX_C_DN<44>")
	)
	(segment
		(start 364.068106 -28.390088)
		(end 363.564932 -28.390088)
		(width 0.13462)
		(layer "F.Cu")
		(net "P5E_PEX3_STN2_TX_C_DN<44>")
	)
	(segment
		(start 365.825786 -28.225242)
		(end 365.496348 -28.55468)
		(width 0.13462)
		(layer "F.Cu")
		(net "P5E_PEX3_STN2_TX_C_DN<44>")
	)
	(segment
		(start 213.571582 -24.942292)
		(end 213.571582 -24.910542)
		(width 0.13208)
		(layer "F.Cu")
		(net "DUALPORT_N_SSD7")
	)
	(segment
		(start 213.571582 -24.910542)
		(end 213.149688 -24.488648)
		(width 0.13208)
		(layer "F.Cu")
		(net "DUALPORT_N_SSD7")
	)
	(segment
		(start 213.149688 -24.488648)
		(end 210.920584 -24.488648)
		(width 0.13208)
		(layer "F.Cu")
		(net "DUALPORT_N_SSD7")
	)
	(segment
		(start 210.566508 -24.134572)
		(end 210.566508 -23.589996)
		(width 0.13208)
		(layer "F.Cu")
		(net "DUALPORT_N_SSD7")
	)
	(segment
		(start 210.566508 -23.589996)
		(end 209.364834 -23.589996)
		(width 0.13208)
		(layer "F.Cu")
		(net "DUALPORT_N_SSD7")
	)
	(segment
		(start 214.587582 -24.942292)
		(end 213.571582 -24.942292)
		(width 0.13208)
		(layer "F.Cu")
		(net "DUALPORT_N_SSD7")
	)
	(segment
		(start 210.920584 -24.488648)
		(end 210.566508 -24.134572)
		(width 0.13208)
		(layer "F.Cu")
		(net "DUALPORT_N_SSD7")
	)
	(via
		(at 210.566508 -23.589996)
		(size 0.508)
		(drill 0.254)
		(layers "F.Cu" "B.Cu")
		(net "DUALPORT_N_SSD7")
	)
	(segment
		(start 59.505596 -34.227262)
		(end 59.210448 -34.52241)
		(width 0.13462)
		(layer "F.Cu")
		(net "P5E_PEX0_STN2_RX_DP<39>")
	)
	(segment
		(start 62.664848 -34.390076)
		(end 62.182248 -34.390076)
		(width 0.13462)
		(layer "F.Cu")
		(net "P5E_PEX0_STN2_RX_DP<39>")
	)
	(segment
		(start 62.019434 -34.227262)
		(end 59.505596 -34.227262)
		(width 0.13462)
		(layer "F.Cu")
		(net "P5E_PEX0_STN2_RX_DP<39>")
	)
	(segment
		(start 62.182248 -34.390076)
		(end 62.019434 -34.227262)
		(width 0.13462)
		(layer "F.Cu")
		(net "P5E_PEX0_STN2_RX_DP<39>")
	)
	(segment
		(start 60.606178 -35.1028)
		(end 59.734958 -34.23158)
		(width 0.1651)
		(layer "In7.Cu")
		(net "P5E_PEX0_STN2_RX_DP<39>")
	)
	(segment
		(start 60.560966 -39.011352)
		(end 60.553346 -38.515798)
		(width 0.1651)
		(layer "In7.Cu")
		(net "P5E_PEX0_STN2_RX_DP<39>")
	)
	(segment
		(start 51.479704 -271.549368)
		(end 51.433984 -271.503648)
		(width 0.1143)
		(layer "In7.Cu")
		(net "P5E_PEX0_STN2_RX_DP<39>")
	)
	(segment
		(start 60.606178 -35.357562)
		(end 60.606178 -35.1028)
		(width 0.1651)
		(layer "In7.Cu")
		(net "P5E_PEX0_STN2_RX_DP<39>")
	)
	(segment
		(start 52.049934 -273.784314)
		(end 51.935634 -273.670014)
		(width 0.1143)
		(layer "In7.Cu")
		(net "P5E_PEX0_STN2_RX_DP<39>")
	)
	(segment
		(start 62.045596 -49.932336)
		(end 60.674758 -39.786052)
		(width 0.1651)
		(layer "In7.Cu")
		(net "P5E_PEX0_STN2_RX_DP<39>")
	)
	(segment
		(start 60.664344 -39.111174)
		(end 60.560966 -39.011352)
		(width 0.1651)
		(layer "In7.Cu")
		(net "P5E_PEX0_STN2_RX_DP<39>")
	)
	(segment
		(start 51.433984 -266.267438)
		(end 61.898784 -68.131182)
		(width 0.1651)
		(layer "In7.Cu")
		(net "P5E_PEX0_STN2_RX_DP<39>")
	)
	(segment
		(start 60.542424 -37.817552)
		(end 60.534804 -37.321998)
		(width 0.1651)
		(layer "In7.Cu")
		(net "P5E_PEX0_STN2_RX_DP<39>")
	)
	(segment
		(start 61.872876 -60.995052)
		(end 62.045596 -49.932336)
		(width 0.1651)
		(layer "In7.Cu")
		(net "P5E_PEX0_STN2_RX_DP<39>")
	)
	(segment
		(start 60.674758 -39.786052)
		(end 60.664344 -39.111174)
		(width 0.1651)
		(layer "In7.Cu")
		(net "P5E_PEX0_STN2_RX_DP<39>")
	)
	(segment
		(start 60.645802 -37.917628)
		(end 60.542424 -37.817552)
		(width 0.1651)
		(layer "In7.Cu")
		(net "P5E_PEX0_STN2_RX_DP<39>")
	)
	(segment
		(start 60.63488 -37.218874)
		(end 60.606178 -35.357562)
		(width 0.1651)
		(layer "In7.Cu")
		(net "P5E_PEX0_STN2_RX_DP<39>")
	)
	(segment
		(start 59.734958 -34.23158)
		(end 59.501278 -34.23158)
		(width 0.1651)
		(layer "In7.Cu")
		(net "P5E_PEX0_STN2_RX_DP<39>")
	)
	(segment
		(start 60.553346 -38.515798)
		(end 60.653422 -38.412674)
		(width 0.1651)
		(layer "In7.Cu")
		(net "P5E_PEX0_STN2_RX_DP<39>")
	)
	(segment
		(start 52.049934 -274.049744)
		(end 52.049934 -273.784314)
		(width 0.1143)
		(layer "In7.Cu")
		(net "P5E_PEX0_STN2_RX_DP<39>")
	)
	(segment
		(start 59.501278 -34.23158)
		(end 59.210448 -34.52241)
		(width 0.1651)
		(layer "In7.Cu")
		(net "P5E_PEX0_STN2_RX_DP<39>")
	)
	(segment
		(start 60.534804 -37.321998)
		(end 60.63488 -37.218874)
		(width 0.1651)
		(layer "In7.Cu")
		(net "P5E_PEX0_STN2_RX_DP<39>")
	)
	(segment
		(start 60.653422 -38.412674)
		(end 60.645802 -37.917628)
		(width 0.1651)
		(layer "In7.Cu")
		(net "P5E_PEX0_STN2_RX_DP<39>")
	)
	(segment
		(start 51.433984 -271.4752)
		(end 51.433984 -266.267438)
		(width 0.1651)
		(layer "In7.Cu")
		(net "P5E_PEX0_STN2_RX_DP<39>")
	)
	(segment
		(start 51.935634 -273.670014)
		(end 51.742086 -273.670014)
		(width 0.1143)
		(layer "In7.Cu")
		(net "P5E_PEX0_STN2_RX_DP<39>")
	)
	(segment
		(start 51.479704 -273.407632)
		(end 51.479704 -271.549368)
		(width 0.1143)
		(layer "In7.Cu")
		(net "P5E_PEX0_STN2_RX_DP<39>")
	)
	(segment
		(start 61.898784 -68.131182)
		(end 61.872876 -60.995052)
		(width 0.1651)
		(layer "In7.Cu")
		(net "P5E_PEX0_STN2_RX_DP<39>")
	)
	(segment
		(start 51.433984 -271.503648)
		(end 51.433984 -271.4752)
		(width 0.1143)
		(layer "In7.Cu")
		(net "P5E_PEX0_STN2_RX_DP<39>")
	)
	(segment
		(start 51.742086 -273.670014)
		(end 51.479704 -273.407632)
		(width 0.1143)
		(layer "In7.Cu")
		(net "P5E_PEX0_STN2_RX_DP<39>")
	)
	(segment
		(start 410.482288 -34.390076)
		(end 410.326332 -34.23412)
		(width 0.13462)
		(layer "F.Cu")
		(net "P5E_PEX3_STN2_RX_DP<39>")
	)
	(segment
		(start 410.326332 -34.23412)
		(end 407.798778 -34.23412)
		(width 0.13462)
		(layer "F.Cu")
		(net "P5E_PEX3_STN2_RX_DP<39>")
	)
	(segment
		(start 410.964888 -34.390076)
		(end 410.482288 -34.390076)
		(width 0.13462)
		(layer "F.Cu")
		(net "P5E_PEX3_STN2_RX_DP<39>")
	)
	(segment
		(start 407.798778 -34.23412)
		(end 407.510488 -34.52241)
		(width 0.13462)
		(layer "F.Cu")
		(net "P5E_PEX3_STN2_RX_DP<39>")
	)
	(segment
		(start 400.349974 -273.784314)
		(end 400.235674 -273.670014)
		(width 0.1143)
		(layer "In7.Cu")
		(net "P5E_PEX3_STN2_RX_DP<39>")
	)
	(segment
		(start 408.974798 -39.786052)
		(end 408.964384 -39.111174)
		(width 0.1651)
		(layer "In7.Cu")
		(net "P5E_PEX3_STN2_RX_DP<39>")
	)
	(segment
		(start 408.842464 -37.817552)
		(end 408.834844 -37.321998)
		(width 0.1651)
		(layer "In7.Cu")
		(net "P5E_PEX3_STN2_RX_DP<39>")
	)
	(segment
		(start 399.734024 -271.503648)
		(end 399.734024 -271.4752)
		(width 0.1143)
		(layer "In7.Cu")
		(net "P5E_PEX3_STN2_RX_DP<39>")
	)
	(segment
		(start 408.964384 -39.111174)
		(end 408.861006 -39.011352)
		(width 0.1651)
		(layer "In7.Cu")
		(net "P5E_PEX3_STN2_RX_DP<39>")
	)
	(segment
		(start 408.834844 -37.321998)
		(end 408.93492 -37.218874)
		(width 0.1651)
		(layer "In7.Cu")
		(net "P5E_PEX3_STN2_RX_DP<39>")
	)
	(segment
		(start 399.734024 -271.4752)
		(end 399.734024 -266.267438)
		(width 0.1651)
		(layer "In7.Cu")
		(net "P5E_PEX3_STN2_RX_DP<39>")
	)
	(segment
		(start 399.779744 -271.549368)
		(end 399.734024 -271.503648)
		(width 0.1143)
		(layer "In7.Cu")
		(net "P5E_PEX3_STN2_RX_DP<39>")
	)
	(segment
		(start 408.93492 -37.218874)
		(end 408.906218 -35.357562)
		(width 0.1651)
		(layer "In7.Cu")
		(net "P5E_PEX3_STN2_RX_DP<39>")
	)
	(segment
		(start 408.945842 -37.917628)
		(end 408.842464 -37.817552)
		(width 0.1651)
		(layer "In7.Cu")
		(net "P5E_PEX3_STN2_RX_DP<39>")
	)
	(segment
		(start 410.198824 -68.131182)
		(end 410.172916 -60.995052)
		(width 0.1651)
		(layer "In7.Cu")
		(net "P5E_PEX3_STN2_RX_DP<39>")
	)
	(segment
		(start 408.853386 -38.515798)
		(end 408.953462 -38.412674)
		(width 0.1651)
		(layer "In7.Cu")
		(net "P5E_PEX3_STN2_RX_DP<39>")
	)
	(segment
		(start 408.034998 -34.23158)
		(end 407.801318 -34.23158)
		(width 0.1651)
		(layer "In7.Cu")
		(net "P5E_PEX3_STN2_RX_DP<39>")
	)
	(segment
		(start 408.906218 -35.1028)
		(end 408.034998 -34.23158)
		(width 0.1651)
		(layer "In7.Cu")
		(net "P5E_PEX3_STN2_RX_DP<39>")
	)
	(segment
		(start 410.345636 -49.932336)
		(end 408.974798 -39.786052)
		(width 0.1651)
		(layer "In7.Cu")
		(net "P5E_PEX3_STN2_RX_DP<39>")
	)
	(segment
		(start 408.953462 -38.412674)
		(end 408.945842 -37.917628)
		(width 0.1651)
		(layer "In7.Cu")
		(net "P5E_PEX3_STN2_RX_DP<39>")
	)
	(segment
		(start 407.801318 -34.23158)
		(end 407.510488 -34.52241)
		(width 0.1651)
		(layer "In7.Cu")
		(net "P5E_PEX3_STN2_RX_DP<39>")
	)
	(segment
		(start 408.861006 -39.011352)
		(end 408.853386 -38.515798)
		(width 0.1651)
		(layer "In7.Cu")
		(net "P5E_PEX3_STN2_RX_DP<39>")
	)
	(segment
		(start 410.172916 -60.995052)
		(end 410.345636 -49.932336)
		(width 0.1651)
		(layer "In7.Cu")
		(net "P5E_PEX3_STN2_RX_DP<39>")
	)
	(segment
		(start 400.235674 -273.670014)
		(end 400.042126 -273.670014)
		(width 0.1143)
		(layer "In7.Cu")
		(net "P5E_PEX3_STN2_RX_DP<39>")
	)
	(segment
		(start 400.349974 -274.049744)
		(end 400.349974 -273.784314)
		(width 0.1143)
		(layer "In7.Cu")
		(net "P5E_PEX3_STN2_RX_DP<39>")
	)
	(segment
		(start 408.906218 -35.357562)
		(end 408.906218 -35.1028)
		(width 0.1651)
		(layer "In7.Cu")
		(net "P5E_PEX3_STN2_RX_DP<39>")
	)
	(segment
		(start 400.042126 -273.670014)
		(end 399.779744 -273.407632)
		(width 0.1143)
		(layer "In7.Cu")
		(net "P5E_PEX3_STN2_RX_DP<39>")
	)
	(segment
		(start 399.734024 -266.267438)
		(end 410.198824 -68.131182)
		(width 0.1651)
		(layer "In7.Cu")
		(net "P5E_PEX3_STN2_RX_DP<39>")
	)
	(segment
		(start 399.779744 -273.407632)
		(end 399.779744 -271.549368)
		(width 0.1143)
		(layer "In7.Cu")
		(net "P5E_PEX3_STN2_RX_DP<39>")
	)
	(segment
		(start 305.457606 -158.35503)
		(end 308.909466 -158.35503)
		(width 0.13208)
		(layer "F.Cu")
		(net "PRSNTB3_NIC5_N")
	)
	(segment
		(start 308.909466 -158.35503)
		(end 309.044848 -158.219648)
		(width 0.13208)
		(layer "F.Cu")
		(net "PRSNTB3_NIC5_N")
	)
	(segment
		(start 311.131966 -158.219648)
		(end 312.339482 -158.219648)
		(width 0.13208)
		(layer "F.Cu")
		(net "PRSNTB3_NIC5_N")
	)
	(segment
		(start 309.044848 -158.219648)
		(end 311.131966 -158.219648)
		(width 0.13208)
		(layer "F.Cu")
		(net "PRSNTB3_NIC5_N")
	)
	(segment
		(start 312.339482 -159.235648)
		(end 312.339482 -158.219648)
		(width 0.13208)
		(layer "F.Cu")
		(net "PRSNTB3_NIC5_N")
	)
	(via
		(at 311.131966 -158.219648)
		(size 0.762)
		(drill 0.381)
		(layers "F.Cu" "B.Cu")
		(net "PRSNTB3_NIC5_N")
	)
	(segment
		(start 187.571634 -24.942292)
		(end 187.571634 -24.910542)
		(width 0.13208)
		(layer "F.Cu")
		(net "DUALPORT_N_SSD6")
	)
	(segment
		(start 184.920636 -24.488648)
		(end 184.56656 -24.134572)
		(width 0.13208)
		(layer "F.Cu")
		(net "DUALPORT_N_SSD6")
	)
	(segment
		(start 188.587634 -24.942292)
		(end 187.571634 -24.942292)
		(width 0.13208)
		(layer "F.Cu")
		(net "DUALPORT_N_SSD6")
	)
	(segment
		(start 187.571634 -24.910542)
		(end 187.14974 -24.488648)
		(width 0.13208)
		(layer "F.Cu")
		(net "DUALPORT_N_SSD6")
	)
	(segment
		(start 184.56656 -24.134572)
		(end 184.56656 -23.589996)
		(width 0.13208)
		(layer "F.Cu")
		(net "DUALPORT_N_SSD6")
	)
	(segment
		(start 184.56656 -23.589996)
		(end 183.364886 -23.589996)
		(width 0.13208)
		(layer "F.Cu")
		(net "DUALPORT_N_SSD6")
	)
	(segment
		(start 187.14974 -24.488648)
		(end 184.920636 -24.488648)
		(width 0.13208)
		(layer "F.Cu")
		(net "DUALPORT_N_SSD6")
	)
	(via
		(at 184.56656 -23.589996)
		(size 0.508)
		(drill 0.254)
		(layers "F.Cu" "B.Cu")
		(net "DUALPORT_N_SSD6")
	)
	(segment
		(start 62.664848 -32.589978)
		(end 62.18555 -32.589978)
		(width 0.13462)
		(layer "F.Cu")
		(net "P5E_PEX0_STN2_RX_DP<38>")
	)
	(segment
		(start 62.018672 -32.4231)
		(end 61.36386 -32.4231)
		(width 0.13462)
		(layer "F.Cu")
		(net "P5E_PEX0_STN2_RX_DP<38>")
	)
	(segment
		(start 61.36386 -32.4231)
		(end 61.064648 -32.722312)
		(width 0.13462)
		(layer "F.Cu")
		(net "P5E_PEX0_STN2_RX_DP<38>")
	)
	(segment
		(start 62.18555 -32.589978)
		(end 62.018672 -32.4231)
		(width 0.13462)
		(layer "F.Cu")
		(net "P5E_PEX0_STN2_RX_DP<38>")
	)
	(segment
		(start 61.631322 -39.731442)
		(end 61.60135 -37.832538)
		(width 0.1651)
		(layer "In7.Cu")
		(net "P5E_PEX0_STN2_RX_DP<38>")
	)
	(segment
		(start 52.38369 -271.421352)
		(end 52.38369 -271.392904)
		(width 0.1143)
		(layer "In7.Cu")
		(net "P5E_PEX0_STN2_RX_DP<38>")
	)
	(segment
		(start 61.880496 -36.334192)
		(end 61.799216 -36.215574)
		(width 0.1651)
		(layer "In7.Cu")
		(net "P5E_PEX0_STN2_RX_DP<38>")
	)
	(segment
		(start 63.013336 -49.959514)
		(end 61.631322 -39.731442)
		(width 0.1651)
		(layer "In7.Cu")
		(net "P5E_PEX0_STN2_RX_DP<38>")
	)
	(segment
		(start 62.125606 -35.019996)
		(end 62.137036 -34.28238)
		(width 0.1651)
		(layer "In7.Cu")
		(net "P5E_PEX0_STN2_RX_DP<38>")
	)
	(segment
		(start 62.04458 -33.683702)
		(end 62.147958 -33.583626)
		(width 0.1651)
		(layer "In7.Cu")
		(net "P5E_PEX0_STN2_RX_DP<38>")
	)
	(segment
		(start 61.60135 -37.832538)
		(end 61.880496 -36.334192)
		(width 0.1651)
		(layer "In7.Cu")
		(net "P5E_PEX0_STN2_RX_DP<38>")
	)
	(segment
		(start 61.355478 -32.431482)
		(end 61.064648 -32.722312)
		(width 0.1651)
		(layer "In7.Cu")
		(net "P5E_PEX0_STN2_RX_DP<38>")
	)
	(segment
		(start 61.799216 -36.215574)
		(end 61.890148 -35.728402)
		(width 0.1651)
		(layer "In7.Cu")
		(net "P5E_PEX0_STN2_RX_DP<38>")
	)
	(segment
		(start 61.890148 -35.728402)
		(end 62.008766 -35.647122)
		(width 0.1651)
		(layer "In7.Cu")
		(net "P5E_PEX0_STN2_RX_DP<38>")
	)
	(segment
		(start 61.813186 -32.431482)
		(end 61.355478 -32.431482)
		(width 0.1651)
		(layer "In7.Cu")
		(net "P5E_PEX0_STN2_RX_DP<38>")
	)
	(segment
		(start 52.38369 -265.765788)
		(end 52.467256 -264.812272)
		(width 0.1651)
		(layer "In7.Cu")
		(net "P5E_PEX0_STN2_RX_DP<38>")
	)
	(segment
		(start 62.840616 -61.00953)
		(end 63.013336 -49.959514)
		(width 0.1651)
		(layer "In7.Cu")
		(net "P5E_PEX0_STN2_RX_DP<38>")
	)
	(segment
		(start 62.160404 -32.7787)
		(end 61.813186 -32.431482)
		(width 0.1651)
		(layer "In7.Cu")
		(net "P5E_PEX0_STN2_RX_DP<38>")
	)
	(segment
		(start 52.467256 -264.812272)
		(end 62.86754 -67.907408)
		(width 0.1651)
		(layer "In7.Cu")
		(net "P5E_PEX0_STN2_RX_DP<38>")
	)
	(segment
		(start 62.008766 -35.647122)
		(end 62.125606 -35.019996)
		(width 0.1651)
		(layer "In7.Cu")
		(net "P5E_PEX0_STN2_RX_DP<38>")
	)
	(segment
		(start 52.999894 -275.949918)
		(end 52.999894 -275.684488)
		(width 0.1143)
		(layer "In7.Cu")
		(net "P5E_PEX0_STN2_RX_DP<38>")
	)
	(segment
		(start 52.999894 -275.684488)
		(end 52.885594 -275.570188)
		(width 0.1143)
		(layer "In7.Cu")
		(net "P5E_PEX0_STN2_RX_DP<38>")
	)
	(segment
		(start 62.147958 -33.583626)
		(end 62.160404 -32.7787)
		(width 0.1651)
		(layer "In7.Cu")
		(net "P5E_PEX0_STN2_RX_DP<38>")
	)
	(segment
		(start 52.38369 -271.392904)
		(end 52.38369 -265.765788)
		(width 0.1651)
		(layer "In7.Cu")
		(net "P5E_PEX0_STN2_RX_DP<38>")
	)
	(segment
		(start 62.03696 -34.179256)
		(end 62.04458 -33.683702)
		(width 0.1651)
		(layer "In7.Cu")
		(net "P5E_PEX0_STN2_RX_DP<38>")
	)
	(segment
		(start 52.42941 -275.354796)
		(end 52.42941 -271.467072)
		(width 0.1143)
		(layer "In7.Cu")
		(net "P5E_PEX0_STN2_RX_DP<38>")
	)
	(segment
		(start 62.86754 -67.907408)
		(end 62.840616 -61.00953)
		(width 0.1651)
		(layer "In7.Cu")
		(net "P5E_PEX0_STN2_RX_DP<38>")
	)
	(segment
		(start 52.644802 -275.570188)
		(end 52.42941 -275.354796)
		(width 0.1143)
		(layer "In7.Cu")
		(net "P5E_PEX0_STN2_RX_DP<38>")
	)
	(segment
		(start 52.42941 -271.467072)
		(end 52.38369 -271.421352)
		(width 0.1143)
		(layer "In7.Cu")
		(net "P5E_PEX0_STN2_RX_DP<38>")
	)
	(segment
		(start 52.885594 -275.570188)
		(end 52.644802 -275.570188)
		(width 0.1143)
		(layer "In7.Cu")
		(net "P5E_PEX0_STN2_RX_DP<38>")
	)
	(segment
		(start 62.137036 -34.28238)
		(end 62.03696 -34.179256)
		(width 0.1651)
		(layer "In7.Cu")
		(net "P5E_PEX0_STN2_RX_DP<38>")
	)
	(segment
		(start 268.786102 -350.365314)
		(end 268.466062 -350.685354)
		(width 0.13462)
		(layer "F.Cu")
		(net "P5E_PEX2_STN7_TX_C_DN<112>")
	)
	(segment
		(start 268.466062 -351.316798)
		(end 268.760702 -351.611438)
		(width 0.13462)
		(layer "F.Cu")
		(net "P5E_PEX2_STN7_TX_C_DN<112>")
	)
	(segment
		(start 268.466062 -350.685354)
		(end 268.466062 -351.316798)
		(width 0.13462)
		(layer "F.Cu")
		(net "P5E_PEX2_STN7_TX_C_DN<112>")
	)
	(segment
		(start 287.4899 -401.690078)
		(end 287.4899 -401.308062)
		(width 0.1651)
		(layer "In7.Cu")
		(net "P5E_PEX2_STN7_TX_C_DN<112>")
	)
	(segment
		(start 287.4899 -401.308062)
		(end 287.6169 -401.181062)
		(width 0.1651)
		(layer "In7.Cu")
		(net "P5E_PEX2_STN7_TX_C_DN<112>")
	)
	(segment
		(start 279.998932 -387.194552)
		(end 277.636478 -375.086372)
		(width 0.1651)
		(layer "In7.Cu")
		(net "P5E_PEX2_STN7_TX_C_DN<112>")
	)
	(segment
		(start 280.830528 -389.210804)
		(end 279.998932 -387.194552)
		(width 0.1651)
		(layer "In7.Cu")
		(net "P5E_PEX2_STN7_TX_C_DN<112>")
	)
	(segment
		(start 288.615882 -400.729196)
		(end 288.615882 -394.757148)
		(width 0.1651)
		(layer "In7.Cu")
		(net "P5E_PEX2_STN7_TX_C_DN<112>")
	)
	(segment
		(start 268.469872 -351.902268)
		(end 268.760702 -351.611438)
		(width 0.1651)
		(layer "In7.Cu")
		(net "P5E_PEX2_STN7_TX_C_DN<112>")
	)
	(segment
		(start 277.636478 -375.086372)
		(end 268.469872 -358.321864)
		(width 0.1651)
		(layer "In7.Cu")
		(net "P5E_PEX2_STN7_TX_C_DN<112>")
	)
	(segment
		(start 288.615882 -394.757148)
		(end 288.102294 -393.989306)
		(width 0.1651)
		(layer "In7.Cu")
		(net "P5E_PEX2_STN7_TX_C_DN<112>")
	)
	(segment
		(start 288.164016 -401.181062)
		(end 288.615882 -400.729196)
		(width 0.1651)
		(layer "In7.Cu")
		(net "P5E_PEX2_STN7_TX_C_DN<112>")
	)
	(segment
		(start 283.683964 -391.76833)
		(end 280.830528 -389.210804)
		(width 0.1651)
		(layer "In7.Cu")
		(net "P5E_PEX2_STN7_TX_C_DN<112>")
	)
	(segment
		(start 287.6169 -401.181062)
		(end 288.164016 -401.181062)
		(width 0.1651)
		(layer "In7.Cu")
		(net "P5E_PEX2_STN7_TX_C_DN<112>")
	)
	(segment
		(start 268.469872 -358.321864)
		(end 268.469872 -351.902268)
		(width 0.1651)
		(layer "In7.Cu")
		(net "P5E_PEX2_STN7_TX_C_DN<112>")
	)
	(segment
		(start 288.102294 -393.989306)
		(end 283.683964 -391.76833)
		(width 0.1651)
		(layer "In7.Cu")
		(net "P5E_PEX2_STN7_TX_C_DN<112>")
	)
	(segment
		(start 416.064446 -32.589978)
		(end 415.564828 -32.589978)
		(width 0.13462)
		(layer "F.Cu")
		(net "P5E_PEX3_STN2_TX_C_DP<38>")
	)
	(segment
		(start 417.496498 -32.4104)
		(end 416.244024 -32.4104)
		(width 0.13462)
		(layer "F.Cu")
		(net "P5E_PEX3_STN2_TX_C_DP<38>")
	)
	(segment
		(start 417.825682 -32.739584)
		(end 417.496498 -32.4104)
		(width 0.13462)
		(layer "F.Cu")
		(net "P5E_PEX3_STN2_TX_C_DP<38>")
	)
	(segment
		(start 416.244024 -32.4104)
		(end 416.064446 -32.589978)
		(width 0.13462)
		(layer "F.Cu")
		(net "P5E_PEX3_STN2_TX_C_DP<38>")
	)
	(segment
		(start 297.241722 -102.798372)
		(end 298.800012 -101.240082)
		(width 0.13208)
		(layer "F.Cu")
		(net "NCSI_NIC5_TXD1")
	)
	(segment
		(start 298.800012 -101.240082)
		(end 300.857412 -101.240082)
		(width 0.13208)
		(layer "F.Cu")
		(net "NCSI_NIC5_TXD1")
	)
	(segment
		(start 293.769034 -102.798372)
		(end 297.241722 -102.798372)
		(width 0.13208)
		(layer "F.Cu")
		(net "NCSI_NIC5_TXD1")
	)
	(segment
		(start 291.595048 -102.798372)
		(end 293.769034 -102.798372)
		(width 0.13208)
		(layer "F.Cu")
		(net "NCSI_NIC5_TXD1")
	)
	(via
		(at 293.769034 -102.798372)
		(size 0.762)
		(drill 0.381)
		(layers "F.Cu" "B.Cu")
		(net "NCSI_NIC5_TXD1")
	)
	(segment
		(start 202.271884 -24.807418)
		(end 203.10221 -24.807418)
		(width 0.13208)
		(layer "F.Cu")
		(net "PU_CLKREQ7")
	)
	(segment
		(start 203.119482 -24.790146)
		(end 203.10221 -24.807418)
		(width 0.13208)
		(layer "F.Cu")
		(net "PU_CLKREQ7")
	)
	(segment
		(start 204.764894 -24.790146)
		(end 203.119482 -24.790146)
		(width 0.13208)
		(layer "F.Cu")
		(net "PU_CLKREQ7")
	)
	(via
		(at 203.10221 -24.807418)
		(size 0.508)
		(drill 0.254)
		(layers "F.Cu" "B.Cu")
		(net "PU_CLKREQ7")
	)
	(segment
		(start 271.215358 -305.399948)
		(end 271.329658 -305.285648)
		(width 0.1143)
		(layer "In5.Cu")
		(net "P5E_PEX2_STN7_RX_DN<116>")
	)
	(segment
		(start 256.548382 -313.56808)
		(end 255.392428 -315.751718)
		(width 0.1651)
		(layer "In5.Cu")
		(net "P5E_PEX2_STN7_RX_DN<116>")
	)
	(segment
		(start 256.91719 -313.025282)
		(end 256.645664 -313.538108)
		(width 0.1651)
		(layer "In5.Cu")
		(net "P5E_PEX2_STN7_RX_DN<116>")
	)
	(segment
		(start 271.329658 -305.134518)
		(end 271.215358 -305.020218)
		(width 0.1143)
		(layer "In5.Cu")
		(net "P5E_PEX2_STN7_RX_DN<116>")
	)
	(segment
		(start 261.102348 -306.963572)
		(end 261.102856 -307.107336)
		(width 0.1651)
		(layer "In5.Cu")
		(net "P5E_PEX2_STN7_RX_DN<116>")
	)
	(segment
		(start 283.54782 -385.03606)
		(end 284.239462 -386.707888)
		(width 0.1651)
		(layer "In5.Cu")
		(net "P5E_PEX2_STN7_RX_DN<116>")
	)
	(segment
		(start 256.645664 -313.538108)
		(end 256.548382 -313.56808)
		(width 0.1651)
		(layer "In5.Cu")
		(net "P5E_PEX2_STN7_RX_DN<116>")
	)
	(segment
		(start 258.235958 -310.380126)
		(end 258.00431 -310.817768)
		(width 0.1651)
		(layer "In5.Cu")
		(net "P5E_PEX2_STN7_RX_DN<116>")
	)
	(segment
		(start 271.215358 -305.020218)
		(end 267.911072 -305.020218)
		(width 0.1143)
		(layer "In5.Cu")
		(net "P5E_PEX2_STN7_RX_DN<116>")
	)
	(segment
		(start 261.732522 -306.328572)
		(end 261.102348 -306.963572)
		(width 0.1651)
		(layer "In5.Cu")
		(net "P5E_PEX2_STN7_RX_DN<116>")
	)
	(segment
		(start 285.915354 -388.3025)
		(end 296.4434 -393.8778)
		(width 0.1651)
		(layer "In5.Cu")
		(net "P5E_PEX2_STN7_RX_DN<116>")
	)
	(segment
		(start 258.834636 -309.249064)
		(end 258.56311 -309.762398)
		(width 0.1651)
		(layer "In5.Cu")
		(net "P5E_PEX2_STN7_RX_DN<116>")
	)
	(segment
		(start 258.046728 -310.954928)
		(end 257.814572 -311.392824)
		(width 0.1651)
		(layer "In5.Cu")
		(net "P5E_PEX2_STN7_RX_DN<116>")
	)
	(segment
		(start 267.836904 -305.065938)
		(end 265.215878 -305.065938)
		(width 0.1651)
		(layer "In5.Cu")
		(net "P5E_PEX2_STN7_RX_DN<116>")
	)
	(segment
		(start 296.289984 -409.108148)
		(end 296.289984 -409.490164)
		(width 0.1651)
		(layer "In5.Cu")
		(net "P5E_PEX2_STN7_RX_DN<116>")
	)
	(segment
		(start 257.211068 -312.461656)
		(end 257.118866 -312.490104)
		(width 0.1651)
		(layer "In5.Cu")
		(net "P5E_PEX2_STN7_RX_DN<116>")
	)
	(segment
		(start 267.911072 -305.020218)
		(end 267.865352 -305.065938)
		(width 0.1143)
		(layer "In5.Cu")
		(net "P5E_PEX2_STN7_RX_DN<116>")
	)
	(segment
		(start 260.610096 -307.459634)
		(end 259.849874 -308.225952)
		(width 0.1651)
		(layer "In5.Cu")
		(net "P5E_PEX2_STN7_RX_DN<116>")
	)
	(segment
		(start 270.024352 -357.900986)
		(end 270.311372 -358.607868)
		(width 0.1651)
		(layer "In5.Cu")
		(net "P5E_PEX2_STN7_RX_DN<116>")
	)
	(segment
		(start 258.235958 -310.379872)
		(end 258.235958 -310.380126)
		(width 0.1651)
		(layer "In5.Cu")
		(net "P5E_PEX2_STN7_RX_DN<116>")
	)
	(segment
		(start 281.684984 -370.31295)
		(end 282.583382 -372.08841)
		(width 0.1651)
		(layer "In5.Cu")
		(net "P5E_PEX2_STN7_RX_DN<116>")
	)
	(segment
		(start 269.372334 -340.485222)
		(end 270.024352 -342.330024)
		(width 0.1651)
		(layer "In5.Cu")
		(net "P5E_PEX2_STN7_RX_DN<116>")
	)
	(segment
		(start 267.865352 -305.065938)
		(end 267.836904 -305.065938)
		(width 0.1143)
		(layer "In5.Cu")
		(net "P5E_PEX2_STN7_RX_DN<116>")
	)
	(segment
		(start 259.850382 -308.369462)
		(end 259.501386 -308.721252)
		(width 0.1651)
		(layer "In5.Cu")
		(net "P5E_PEX2_STN7_RX_DN<116>")
	)
	(segment
		(start 258.56311 -309.762398)
		(end 258.605274 -309.899558)
		(width 0.1651)
		(layer "In5.Cu")
		(net "P5E_PEX2_STN7_RX_DN<116>")
	)
	(segment
		(start 296.4434 -393.8778)
		(end 297.0784 -394.2842)
		(width 0.1651)
		(layer "In5.Cu")
		(net "P5E_PEX2_STN7_RX_DN<116>")
	)
	(segment
		(start 256.887218 -312.928254)
		(end 256.91719 -313.025282)
		(width 0.1651)
		(layer "In5.Cu")
		(net "P5E_PEX2_STN7_RX_DN<116>")
	)
	(segment
		(start 257.118866 -312.490104)
		(end 257.11912 -312.490358)
		(width 0.1651)
		(layer "In5.Cu")
		(net "P5E_PEX2_STN7_RX_DN<116>")
	)
	(segment
		(start 255.392428 -315.751718)
		(end 253.76378 -319.521332)
		(width 0.1651)
		(layer "In5.Cu")
		(net "P5E_PEX2_STN7_RX_DN<116>")
	)
	(segment
		(start 258.00431 -310.817768)
		(end 258.046728 -310.954928)
		(width 0.1651)
		(layer "In5.Cu")
		(net "P5E_PEX2_STN7_RX_DN<116>")
	)
	(segment
		(start 284.239462 -386.707888)
		(end 285.915354 -388.3025)
		(width 0.1651)
		(layer "In5.Cu")
		(net "P5E_PEX2_STN7_RX_DN<116>")
	)
	(segment
		(start 257.445764 -311.872884)
		(end 257.474212 -311.965086)
		(width 0.1651)
		(layer "In5.Cu")
		(net "P5E_PEX2_STN7_RX_DN<116>")
	)
	(segment
		(start 283.19476 -378.81306)
		(end 283.54782 -385.03606)
		(width 0.1651)
		(layer "In5.Cu")
		(net "P5E_PEX2_STN7_RX_DN<116>")
	)
	(segment
		(start 297.0784 -394.2842)
		(end 297.415966 -394.9192)
		(width 0.1651)
		(layer "In5.Cu")
		(net "P5E_PEX2_STN7_RX_DN<116>")
	)
	(segment
		(start 258.605274 -309.899558)
		(end 258.373372 -310.337708)
		(width 0.1651)
		(layer "In5.Cu")
		(net "P5E_PEX2_STN7_RX_DN<116>")
	)
	(segment
		(start 271.329658 -305.285648)
		(end 271.329658 -305.134518)
		(width 0.1143)
		(layer "In5.Cu")
		(net "P5E_PEX2_STN7_RX_DN<116>")
	)
	(segment
		(start 253.76378 -322.475098)
		(end 255.279906 -326.116696)
		(width 0.1651)
		(layer "In5.Cu")
		(net "P5E_PEX2_STN7_RX_DN<116>")
	)
	(segment
		(start 270.311372 -358.607868)
		(end 281.684984 -370.31295)
		(width 0.1651)
		(layer "In5.Cu")
		(net "P5E_PEX2_STN7_RX_DN<116>")
	)
	(segment
		(start 257.677412 -311.434988)
		(end 257.445764 -311.872884)
		(width 0.1651)
		(layer "In5.Cu")
		(net "P5E_PEX2_STN7_RX_DN<116>")
	)
	(segment
		(start 257.11912 -312.490358)
		(end 256.887218 -312.928254)
		(width 0.1651)
		(layer "In5.Cu")
		(net "P5E_PEX2_STN7_RX_DN<116>")
	)
	(segment
		(start 253.76378 -319.521332)
		(end 253.76378 -322.475098)
		(width 0.1651)
		(layer "In5.Cu")
		(net "P5E_PEX2_STN7_RX_DN<116>")
	)
	(segment
		(start 296.9641 -408.981148)
		(end 296.416984 -408.981148)
		(width 0.1651)
		(layer "In5.Cu")
		(net "P5E_PEX2_STN7_RX_DN<116>")
	)
	(segment
		(start 282.583382 -372.08841)
		(end 283.19476 -378.81306)
		(width 0.1651)
		(layer "In5.Cu")
		(net "P5E_PEX2_STN7_RX_DN<116>")
	)
	(segment
		(start 297.415966 -408.529282)
		(end 296.9641 -408.981148)
		(width 0.1651)
		(layer "In5.Cu")
		(net "P5E_PEX2_STN7_RX_DN<116>")
	)
	(segment
		(start 261.102856 -307.107336)
		(end 260.75386 -307.459126)
		(width 0.1651)
		(layer "In5.Cu")
		(net "P5E_PEX2_STN7_RX_DN<116>")
	)
	(segment
		(start 260.75386 -307.459126)
		(end 260.610096 -307.459634)
		(width 0.1651)
		(layer "In5.Cu")
		(net "P5E_PEX2_STN7_RX_DN<116>")
	)
	(segment
		(start 255.279906 -326.116696)
		(end 269.372334 -340.485222)
		(width 0.1651)
		(layer "In5.Cu")
		(net "P5E_PEX2_STN7_RX_DN<116>")
	)
	(segment
		(start 259.849874 -308.225952)
		(end 259.850382 -308.369462)
		(width 0.1651)
		(layer "In5.Cu")
		(net "P5E_PEX2_STN7_RX_DN<116>")
	)
	(segment
		(start 270.949928 -305.399948)
		(end 271.215358 -305.399948)
		(width 0.1143)
		(layer "In5.Cu")
		(net "P5E_PEX2_STN7_RX_DN<116>")
	)
	(segment
		(start 265.215878 -305.065938)
		(end 261.732522 -306.328572)
		(width 0.1651)
		(layer "In5.Cu")
		(net "P5E_PEX2_STN7_RX_DN<116>")
	)
	(segment
		(start 297.415966 -394.9192)
		(end 297.415966 -408.529282)
		(width 0.1651)
		(layer "In5.Cu")
		(net "P5E_PEX2_STN7_RX_DN<116>")
	)
	(segment
		(start 259.501386 -308.721252)
		(end 259.357622 -308.722014)
		(width 0.1651)
		(layer "In5.Cu")
		(net "P5E_PEX2_STN7_RX_DN<116>")
	)
	(segment
		(start 257.814572 -311.392824)
		(end 257.677412 -311.434988)
		(width 0.1651)
		(layer "In5.Cu")
		(net "P5E_PEX2_STN7_RX_DN<116>")
	)
	(segment
		(start 296.416984 -408.981148)
		(end 296.289984 -409.108148)
		(width 0.1651)
		(layer "In5.Cu")
		(net "P5E_PEX2_STN7_RX_DN<116>")
	)
	(segment
		(start 259.357622 -308.722014)
		(end 258.834636 -309.249064)
		(width 0.1651)
		(layer "In5.Cu")
		(net "P5E_PEX2_STN7_RX_DN<116>")
	)
	(segment
		(start 258.373372 -310.337708)
		(end 258.235958 -310.379872)
		(width 0.1651)
		(layer "In5.Cu")
		(net "P5E_PEX2_STN7_RX_DN<116>")
	)
	(segment
		(start 270.024352 -342.330024)
		(end 270.024352 -357.900986)
		(width 0.1651)
		(layer "In5.Cu")
		(net "P5E_PEX2_STN7_RX_DN<116>")
	)
	(segment
		(start 257.474212 -311.965086)
		(end 257.211068 -312.461656)
		(width 0.1651)
		(layer "In5.Cu")
		(net "P5E_PEX2_STN7_RX_DN<116>")
	)
	(segment
		(start 390.232646 -28.55468)
		(end 390.068054 -28.390088)
		(width 0.13462)
		(layer "F.Cu")
		(net "P5E_PEX3_STN2_TX_C_DN<40>")
	)
	(segment
		(start 391.825734 -28.225242)
		(end 391.496296 -28.55468)
		(width 0.13462)
		(layer "F.Cu")
		(net "P5E_PEX3_STN2_TX_C_DN<40>")
	)
	(segment
		(start 390.068054 -28.390088)
		(end 389.56488 -28.390088)
		(width 0.13462)
		(layer "F.Cu")
		(net "P5E_PEX3_STN2_TX_C_DN<40>")
	)
	(segment
		(start 391.496296 -28.55468)
		(end 390.232646 -28.55468)
		(width 0.13462)
		(layer "F.Cu")
		(net "P5E_PEX3_STN2_TX_C_DN<40>")
	)
	(segment
		(start 311.108852 -137.24509)
		(end 311.938924 -137.24509)
		(width 0.13208)
		(layer "F.Cu")
		(net "PRSNTB0_NIC5_N")
	)
	(segment
		(start 311.938924 -137.24509)
		(end 312.339482 -137.645648)
		(width 0.13208)
		(layer "F.Cu")
		(net "PRSNTB0_NIC5_N")
	)
	(segment
		(start 312.339482 -138.661648)
		(end 312.339482 -137.645648)
		(width 0.13208)
		(layer "F.Cu")
		(net "PRSNTB0_NIC5_N")
	)
	(segment
		(start 305.457606 -137.24509)
		(end 311.108852 -137.24509)
		(width 0.13208)
		(layer "F.Cu")
		(net "PRSNTB0_NIC5_N")
	)
	(via
		(at 311.108852 -137.24509)
		(size 0.762)
		(drill 0.381)
		(layers "F.Cu" "B.Cu")
		(net "PRSNTB0_NIC5_N")
	)
	(segment
		(start 443.82563 -28.225242)
		(end 443.501272 -28.5496)
		(width 0.13462)
		(layer "F.Cu")
		(net "P5E_PEX3_STN2_TX_C_DN<32>")
	)
	(segment
		(start 443.501272 -28.5496)
		(end 442.227462 -28.5496)
		(width 0.13462)
		(layer "F.Cu")
		(net "P5E_PEX3_STN2_TX_C_DN<32>")
	)
	(segment
		(start 442.227462 -28.5496)
		(end 442.06795 -28.390088)
		(width 0.13462)
		(layer "F.Cu")
		(net "P5E_PEX3_STN2_TX_C_DN<32>")
	)
	(segment
		(start 442.06795 -28.390088)
		(end 441.564776 -28.390088)
		(width 0.13462)
		(layer "F.Cu")
		(net "P5E_PEX3_STN2_TX_C_DN<32>")
	)
	(segment
		(start 409.319476 -24.790146)
		(end 409.302204 -24.807418)
		(width 0.13208)
		(layer "F.Cu")
		(net "PU_CLKREQ14")
	)
	(segment
		(start 408.471878 -24.807418)
		(end 409.302204 -24.807418)
		(width 0.13208)
		(layer "F.Cu")
		(net "PU_CLKREQ14")
	)
	(segment
		(start 410.964888 -24.790146)
		(end 409.319476 -24.790146)
		(width 0.13208)
		(layer "F.Cu")
		(net "PU_CLKREQ14")
	)
	(via
		(at 409.302204 -24.807418)
		(size 0.508)
		(drill 0.254)
		(layers "F.Cu" "B.Cu")
		(net "PU_CLKREQ14")
	)
	(segment
		(start 271.575022 -357.46309)
		(end 271.869662 -357.75773)
		(width 0.13462)
		(layer "F.Cu")
		(net "P5E_PEX2_STN7_TX_C_DN<114>")
	)
	(segment
		(start 271.895062 -356.511606)
		(end 271.575022 -356.831646)
		(width 0.13462)
		(layer "F.Cu")
		(net "P5E_PEX2_STN7_TX_C_DN<114>")
	)
	(segment
		(start 271.575022 -356.831646)
		(end 271.575022 -357.46309)
		(width 0.13462)
		(layer "F.Cu")
		(net "P5E_PEX2_STN7_TX_C_DN<114>")
	)
	(segment
		(start 291.786818 -393.337288)
		(end 284.732476 -389.965946)
		(width 0.1651)
		(layer "In7.Cu")
		(net "P5E_PEX2_STN7_TX_C_DN<114>")
	)
	(segment
		(start 292.564058 -401.181062)
		(end 293.015924 -400.729196)
		(width 0.1651)
		(layer "In7.Cu")
		(net "P5E_PEX2_STN7_TX_C_DN<114>")
	)
	(segment
		(start 271.578832 -358.04856)
		(end 271.869662 -357.75773)
		(width 0.1651)
		(layer "In7.Cu")
		(net "P5E_PEX2_STN7_TX_C_DN<114>")
	)
	(segment
		(start 279.772364 -374.58523)
		(end 271.578832 -358.579928)
		(width 0.1651)
		(layer "In7.Cu")
		(net "P5E_PEX2_STN7_TX_C_DN<114>")
	)
	(segment
		(start 282.488894 -387.893814)
		(end 281.741372 -386.094986)
		(width 0.1651)
		(layer "In7.Cu")
		(net "P5E_PEX2_STN7_TX_C_DN<114>")
	)
	(segment
		(start 271.578832 -358.579928)
		(end 271.578832 -358.04856)
		(width 0.1651)
		(layer "In7.Cu")
		(net "P5E_PEX2_STN7_TX_C_DN<114>")
	)
	(segment
		(start 291.889942 -401.690078)
		(end 291.889942 -401.308062)
		(width 0.1651)
		(layer "In7.Cu")
		(net "P5E_PEX2_STN7_TX_C_DN<114>")
	)
	(segment
		(start 284.732476 -389.965946)
		(end 282.488894 -387.893814)
		(width 0.1651)
		(layer "In7.Cu")
		(net "P5E_PEX2_STN7_TX_C_DN<114>")
	)
	(segment
		(start 291.889942 -401.308062)
		(end 292.016942 -401.181062)
		(width 0.1651)
		(layer "In7.Cu")
		(net "P5E_PEX2_STN7_TX_C_DN<114>")
	)
	(segment
		(start 293.015924 -400.729196)
		(end 293.015924 -394.843)
		(width 0.1651)
		(layer "In7.Cu")
		(net "P5E_PEX2_STN7_TX_C_DN<114>")
	)
	(segment
		(start 292.016942 -401.181062)
		(end 292.564058 -401.181062)
		(width 0.1651)
		(layer "In7.Cu")
		(net "P5E_PEX2_STN7_TX_C_DN<114>")
	)
	(segment
		(start 293.015924 -394.843)
		(end 291.786818 -393.337288)
		(width 0.1651)
		(layer "In7.Cu")
		(net "P5E_PEX2_STN7_TX_C_DN<114>")
	)
	(segment
		(start 281.741372 -386.094986)
		(end 279.772364 -374.58523)
		(width 0.1651)
		(layer "In7.Cu")
		(net "P5E_PEX2_STN7_TX_C_DN<114>")
	)
	(segment
		(start 364.068106 -30.190186)
		(end 363.564932 -30.190186)
		(width 0.13462)
		(layer "F.Cu")
		(net "P5E_PEX3_STN2_TX_C_DN<45>")
	)
	(segment
		(start 368.146584 -30.353)
		(end 364.23092 -30.353)
		(width 0.13462)
		(layer "F.Cu")
		(net "P5E_PEX3_STN2_TX_C_DN<45>")
	)
	(segment
		(start 368.467894 -30.03169)
		(end 368.146584 -30.353)
		(width 0.13462)
		(layer "F.Cu")
		(net "P5E_PEX3_STN2_TX_C_DN<45>")
	)
	(segment
		(start 364.23092 -30.353)
		(end 364.068106 -30.190186)
		(width 0.13462)
		(layer "F.Cu")
		(net "P5E_PEX3_STN2_TX_C_DN<45>")
	)
	(segment
		(start 305.457606 -97.039938)
		(end 307.307488 -97.039938)
		(width 0.13208)
		(layer "F.Cu")
		(net "PWRGD_NIC5_PWR_GOOD")
	)
	(via
		(at 307.307488 -97.039938)
		(size 0.508)
		(drill 0.254)
		(layers "F.Cu" "B.Cu")
		(net "PWRGD_NIC5_PWR_GOOD")
	)
	(segment
		(start 303.554892 -96.79305)
		(end 303.954942 -96.393)
		(width 0.13208)
		(layer "B.Cu")
		(net "PWRGD_NIC5_PWR_GOOD")
	)
	(segment
		(start 302.703992 -97.663)
		(end 303.554892 -97.663)
		(width 0.13208)
		(layer "B.Cu")
		(net "PWRGD_NIC5_PWR_GOOD")
	)
	(segment
		(start 303.554892 -97.663)
		(end 303.554892 -96.79305)
		(width 0.13208)
		(layer "B.Cu")
		(net "PWRGD_NIC5_PWR_GOOD")
	)
	(segment
		(start 303.954942 -96.393)
		(end 306.66055 -96.393)
		(width 0.13208)
		(layer "B.Cu")
		(net "PWRGD_NIC5_PWR_GOOD")
	)
	(segment
		(start 306.66055 -96.393)
		(end 307.307488 -97.039938)
		(width 0.13208)
		(layer "B.Cu")
		(net "PWRGD_NIC5_PWR_GOOD")
	)
	(segment
		(start 436.964836 -24.790146)
		(end 435.319424 -24.790146)
		(width 0.13208)
		(layer "F.Cu")
		(net "PU_CLKREQ15")
	)
	(segment
		(start 434.471826 -24.807418)
		(end 435.302152 -24.807418)
		(width 0.13208)
		(layer "F.Cu")
		(net "PU_CLKREQ15")
	)
	(segment
		(start 435.319424 -24.790146)
		(end 435.302152 -24.807418)
		(width 0.13208)
		(layer "F.Cu")
		(net "PU_CLKREQ15")
	)
	(via
		(at 435.302152 -24.807418)
		(size 0.508)
		(drill 0.254)
		(layers "F.Cu" "B.Cu")
		(net "PU_CLKREQ15")
	)
	(segment
		(start 262.37692 -312.626756)
		(end 262.702802 -312.253884)
		(width 0.1651)
		(layer "In5.Cu")
		(net "P5E_PEX2_STN7_RX_DN<119>")
	)
	(segment
		(start 261.916926 -313.15279)
		(end 262.060182 -313.143138)
		(width 0.1651)
		(layer "In5.Cu")
		(net "P5E_PEX2_STN7_RX_DN<119>")
	)
	(segment
		(start 261.13105 -314.05195)
		(end 261.13105 -314.051696)
		(width 0.1651)
		(layer "In5.Cu")
		(net "P5E_PEX2_STN7_RX_DN<119>")
	)
	(segment
		(start 269.315184 -308.249828)
		(end 269.049754 -308.249828)
		(width 0.1143)
		(layer "In5.Cu")
		(net "P5E_PEX2_STN7_RX_DN<119>")
	)
	(segment
		(start 269.315184 -307.870098)
		(end 269.429484 -307.984398)
		(width 0.1143)
		(layer "In5.Cu")
		(net "P5E_PEX2_STN7_RX_DN<119>")
	)
	(segment
		(start 301.953422 -393.368022)
		(end 299.070014 -391.400284)
		(width 0.1651)
		(layer "In5.Cu")
		(net "P5E_PEX2_STN7_RX_DN<119>")
	)
	(segment
		(start 262.386572 -312.770012)
		(end 262.37692 -312.626756)
		(width 0.1651)
		(layer "In5.Cu")
		(net "P5E_PEX2_STN7_RX_DN<119>")
	)
	(segment
		(start 257.831336 -317.826136)
		(end 258.619498 -316.92469)
		(width 0.1651)
		(layer "In5.Cu")
		(net "P5E_PEX2_STN7_RX_DN<119>")
	)
	(segment
		(start 262.846312 -312.244232)
		(end 263.172448 -311.871106)
		(width 0.1651)
		(layer "In5.Cu")
		(net "P5E_PEX2_STN7_RX_DN<119>")
	)
	(segment
		(start 279.469088 -358.456738)
		(end 279.351232 -357.939086)
		(width 0.1651)
		(layer "In5.Cu")
		(net "P5E_PEX2_STN7_RX_DN<119>")
	)
	(segment
		(start 260.33476 -315.117226)
		(end 260.660896 -314.7441)
		(width 0.1651)
		(layer "In5.Cu")
		(net "P5E_PEX2_STN7_RX_DN<119>")
	)
	(segment
		(start 259.87502 -315.643006)
		(end 259.865368 -315.49975)
		(width 0.1651)
		(layer "In5.Cu")
		(net "P5E_PEX2_STN7_RX_DN<119>")
	)
	(segment
		(start 258.762754 -316.915038)
		(end 259.089144 -316.541912)
		(width 0.1651)
		(layer "In5.Cu")
		(net "P5E_PEX2_STN7_RX_DN<119>")
	)
	(segment
		(start 267.836904 -307.915818)
		(end 267.865352 -307.915818)
		(width 0.1143)
		(layer "In5.Cu")
		(net "P5E_PEX2_STN7_RX_DN<119>")
	)
	(segment
		(start 257.347466 -323.454268)
		(end 256.999994 -322.614036)
		(width 0.1651)
		(layer "In5.Cu")
		(net "P5E_PEX2_STN7_RX_DN<119>")
	)
	(segment
		(start 257.79984 -324.057772)
		(end 257.347466 -323.454014)
		(width 0.1651)
		(layer "In5.Cu")
		(net "P5E_PEX2_STN7_RX_DN<119>")
	)
	(segment
		(start 259.405374 -316.025784)
		(end 259.54863 -316.016132)
		(width 0.1651)
		(layer "In5.Cu")
		(net "P5E_PEX2_STN7_RX_DN<119>")
	)
	(segment
		(start 260.19125 -315.126878)
		(end 260.33476 -315.117226)
		(width 0.1651)
		(layer "In5.Cu")
		(net "P5E_PEX2_STN7_RX_DN<119>")
	)
	(segment
		(start 259.865368 -315.49975)
		(end 260.19125 -315.126878)
		(width 0.1651)
		(layer "In5.Cu")
		(net "P5E_PEX2_STN7_RX_DN<119>")
	)
	(segment
		(start 303.605946 -395.0208)
		(end 301.953422 -393.368022)
		(width 0.1651)
		(layer "In5.Cu")
		(net "P5E_PEX2_STN7_RX_DN<119>")
	)
	(segment
		(start 303.564036 -410.080968)
		(end 304.015902 -409.629102)
		(width 0.1651)
		(layer "In5.Cu")
		(net "P5E_PEX2_STN7_RX_DN<119>")
	)
	(segment
		(start 267.865352 -307.915818)
		(end 267.911072 -307.870098)
		(width 0.1143)
		(layer "In5.Cu")
		(net "P5E_PEX2_STN7_RX_DN<119>")
	)
	(segment
		(start 267.911072 -307.870098)
		(end 269.315184 -307.870098)
		(width 0.1143)
		(layer "In5.Cu")
		(net "P5E_PEX2_STN7_RX_DN<119>")
	)
	(segment
		(start 302.88992 -410.207968)
		(end 303.01692 -410.080968)
		(width 0.1651)
		(layer "In5.Cu")
		(net "P5E_PEX2_STN7_RX_DN<119>")
	)
	(segment
		(start 278.96058 -341.01786)
		(end 257.79984 -324.057772)
		(width 0.1651)
		(layer "In5.Cu")
		(net "P5E_PEX2_STN7_RX_DN<119>")
	)
	(segment
		(start 256.65176 -321.773296)
		(end 256.65176 -320.677286)
		(width 0.1651)
		(layer "In5.Cu")
		(net "P5E_PEX2_STN7_RX_DN<119>")
	)
	(segment
		(start 259.079492 -316.398656)
		(end 259.405374 -316.025784)
		(width 0.1651)
		(layer "In5.Cu")
		(net "P5E_PEX2_STN7_RX_DN<119>")
	)
	(segment
		(start 256.999994 -322.614036)
		(end 256.99974 -322.614036)
		(width 0.1651)
		(layer "In5.Cu")
		(net "P5E_PEX2_STN7_RX_DN<119>")
	)
	(segment
		(start 286.7406 -384.9878)
		(end 286.45231 -384.411474)
		(width 0.1651)
		(layer "In5.Cu")
		(net "P5E_PEX2_STN7_RX_DN<119>")
	)
	(segment
		(start 304.015902 -409.629102)
		(end 304.015902 -396.0114)
		(width 0.1651)
		(layer "In5.Cu")
		(net "P5E_PEX2_STN7_RX_DN<119>")
	)
	(segment
		(start 261.591044 -313.525662)
		(end 261.916926 -313.15279)
		(width 0.1651)
		(layer "In5.Cu")
		(net "P5E_PEX2_STN7_RX_DN<119>")
	)
	(segment
		(start 267.073126 -307.915818)
		(end 267.836904 -307.915818)
		(width 0.1651)
		(layer "In5.Cu")
		(net "P5E_PEX2_STN7_RX_DN<119>")
	)
	(segment
		(start 304.015902 -396.0114)
		(end 303.605946 -395.0208)
		(width 0.1651)
		(layer "In5.Cu")
		(net "P5E_PEX2_STN7_RX_DN<119>")
	)
	(segment
		(start 286.45231 -384.411474)
		(end 286.156654 -378.135388)
		(width 0.1651)
		(layer "In5.Cu")
		(net "P5E_PEX2_STN7_RX_DN<119>")
	)
	(segment
		(start 259.54863 -316.016132)
		(end 259.87502 -315.643006)
		(width 0.1651)
		(layer "In5.Cu")
		(net "P5E_PEX2_STN7_RX_DN<119>")
	)
	(segment
		(start 262.702802 -312.253884)
		(end 262.846312 -312.244232)
		(width 0.1651)
		(layer "In5.Cu")
		(net "P5E_PEX2_STN7_RX_DN<119>")
	)
	(segment
		(start 257.347466 -323.454014)
		(end 257.347466 -323.454268)
		(width 0.1651)
		(layer "In5.Cu")
		(net "P5E_PEX2_STN7_RX_DN<119>")
	)
	(segment
		(start 303.01692 -410.080968)
		(end 303.564036 -410.080968)
		(width 0.1651)
		(layer "In5.Cu")
		(net "P5E_PEX2_STN7_RX_DN<119>")
	)
	(segment
		(start 279.351232 -357.939086)
		(end 279.351232 -341.95512)
		(width 0.1651)
		(layer "In5.Cu")
		(net "P5E_PEX2_STN7_RX_DN<119>")
	)
	(segment
		(start 261.274306 -314.042044)
		(end 261.600696 -313.668918)
		(width 0.1651)
		(layer "In5.Cu")
		(net "P5E_PEX2_STN7_RX_DN<119>")
	)
	(segment
		(start 285.484316 -370.956586)
		(end 279.469088 -358.456738)
		(width 0.1651)
		(layer "In5.Cu")
		(net "P5E_PEX2_STN7_RX_DN<119>")
	)
	(segment
		(start 299.070014 -391.400284)
		(end 287.42259 -385.66979)
		(width 0.1651)
		(layer "In5.Cu")
		(net "P5E_PEX2_STN7_RX_DN<119>")
	)
	(segment
		(start 256.99974 -322.614036)
		(end 256.65176 -321.773296)
		(width 0.1651)
		(layer "In5.Cu")
		(net "P5E_PEX2_STN7_RX_DN<119>")
	)
	(segment
		(start 260.660896 -314.7441)
		(end 260.651244 -314.60059)
		(width 0.1651)
		(layer "In5.Cu")
		(net "P5E_PEX2_STN7_RX_DN<119>")
	)
	(segment
		(start 258.619498 -316.92469)
		(end 258.762754 -316.915038)
		(width 0.1651)
		(layer "In5.Cu")
		(net "P5E_PEX2_STN7_RX_DN<119>")
	)
	(segment
		(start 263.162796 -311.72785)
		(end 266.16787 -308.290722)
		(width 0.1651)
		(layer "In5.Cu")
		(net "P5E_PEX2_STN7_RX_DN<119>")
	)
	(segment
		(start 286.156654 -378.135388)
		(end 285.484316 -370.956586)
		(width 0.1651)
		(layer "In5.Cu")
		(net "P5E_PEX2_STN7_RX_DN<119>")
	)
	(segment
		(start 259.089144 -316.541912)
		(end 259.079492 -316.398656)
		(width 0.1651)
		(layer "In5.Cu")
		(net "P5E_PEX2_STN7_RX_DN<119>")
	)
	(segment
		(start 287.42259 -385.66979)
		(end 286.7406 -384.9878)
		(width 0.1651)
		(layer "In5.Cu")
		(net "P5E_PEX2_STN7_RX_DN<119>")
	)
	(segment
		(start 262.060182 -313.143138)
		(end 262.386572 -312.770012)
		(width 0.1651)
		(layer "In5.Cu")
		(net "P5E_PEX2_STN7_RX_DN<119>")
	)
	(segment
		(start 256.65176 -320.677286)
		(end 257.831336 -317.826136)
		(width 0.1651)
		(layer "In5.Cu")
		(net "P5E_PEX2_STN7_RX_DN<119>")
	)
	(segment
		(start 279.351232 -341.95512)
		(end 278.96058 -341.01786)
		(width 0.1651)
		(layer "In5.Cu")
		(net "P5E_PEX2_STN7_RX_DN<119>")
	)
	(segment
		(start 263.172448 -311.871106)
		(end 263.162796 -311.72785)
		(width 0.1651)
		(layer "In5.Cu")
		(net "P5E_PEX2_STN7_RX_DN<119>")
	)
	(segment
		(start 261.600696 -313.668918)
		(end 261.591044 -313.525662)
		(width 0.1651)
		(layer "In5.Cu")
		(net "P5E_PEX2_STN7_RX_DN<119>")
	)
	(segment
		(start 266.16787 -308.290722)
		(end 267.073126 -307.915818)
		(width 0.1651)
		(layer "In5.Cu")
		(net "P5E_PEX2_STN7_RX_DN<119>")
	)
	(segment
		(start 260.651244 -314.60059)
		(end 261.13105 -314.05195)
		(width 0.1651)
		(layer "In5.Cu")
		(net "P5E_PEX2_STN7_RX_DN<119>")
	)
	(segment
		(start 261.13105 -314.051696)
		(end 261.274306 -314.042044)
		(width 0.1651)
		(layer "In5.Cu")
		(net "P5E_PEX2_STN7_RX_DN<119>")
	)
	(segment
		(start 269.429484 -308.135528)
		(end 269.315184 -308.249828)
		(width 0.1143)
		(layer "In5.Cu")
		(net "P5E_PEX2_STN7_RX_DN<119>")
	)
	(segment
		(start 302.88992 -410.589984)
		(end 302.88992 -410.207968)
		(width 0.1651)
		(layer "In5.Cu")
		(net "P5E_PEX2_STN7_RX_DN<119>")
	)
	(segment
		(start 269.429484 -307.984398)
		(end 269.429484 -308.135528)
		(width 0.1143)
		(layer "In5.Cu")
		(net "P5E_PEX2_STN7_RX_DN<119>")
	)
	(segment
		(start 433.805584 -30.62732)
		(end 433.510436 -30.922468)
		(width 0.13462)
		(layer "F.Cu")
		(net "P5E_PEX3_STN2_RX_DP<33>")
	)
	(segment
		(start 436.319422 -30.62732)
		(end 433.805584 -30.62732)
		(width 0.13462)
		(layer "F.Cu")
		(net "P5E_PEX3_STN2_RX_DP<33>")
	)
	(segment
		(start 436.482236 -30.790134)
		(end 436.319422 -30.62732)
		(width 0.13462)
		(layer "F.Cu")
		(net "P5E_PEX3_STN2_RX_DP<33>")
	)
	(segment
		(start 436.964836 -30.790134)
		(end 436.482236 -30.790134)
		(width 0.13462)
		(layer "F.Cu")
		(net "P5E_PEX3_STN2_RX_DP<33>")
	)
	(segment
		(start 437.353964 -32.366966)
		(end 437.085994 -31.95066)
		(width 0.1651)
		(layer "In7.Cu")
		(net "P5E_PEX3_STN2_RX_DP<33>")
	)
	(segment
		(start 434.85689 -30.631638)
		(end 433.874418 -30.631638)
		(width 0.1651)
		(layer "In7.Cu")
		(net "P5E_PEX3_STN2_RX_DP<33>")
	)
	(segment
		(start 406.049988 -273.784314)
		(end 405.935688 -273.670014)
		(width 0.1143)
		(layer "In7.Cu")
		(net "P5E_PEX3_STN2_RX_DP<33>")
	)
	(segment
		(start 437.603138 -34.076386)
		(end 437.611266 -33.05302)
		(width 0.1651)
		(layer "In7.Cu")
		(net "P5E_PEX3_STN2_RX_DP<33>")
	)
	(segment
		(start 425.33951 -154.656282)
		(end 426.715428 -143.970756)
		(width 0.1651)
		(layer "In7.Cu")
		(net "P5E_PEX3_STN2_RX_DP<33>")
	)
	(segment
		(start 433.74945 -30.683454)
		(end 433.510436 -30.922468)
		(width 0.1651)
		(layer "In7.Cu")
		(net "P5E_PEX3_STN2_RX_DP<33>")
	)
	(segment
		(start 438.039256 -61.179456)
		(end 438.223406 -49.394364)
		(width 0.1651)
		(layer "In7.Cu")
		(net "P5E_PEX3_STN2_RX_DP<33>")
	)
	(segment
		(start 426.715428 -143.970756)
		(end 427.03115 -116.662708)
		(width 0.1651)
		(layer "In7.Cu")
		(net "P5E_PEX3_STN2_RX_DP<33>")
	)
	(segment
		(start 434.97119 -30.745938)
		(end 434.85689 -30.631638)
		(width 0.1651)
		(layer "In7.Cu")
		(net "P5E_PEX3_STN2_RX_DP<33>")
	)
	(segment
		(start 405.479758 -271.41932)
		(end 405.434038 -271.3736)
		(width 0.1143)
		(layer "In7.Cu")
		(net "P5E_PEX3_STN2_RX_DP<33>")
	)
	(segment
		(start 436.236872 -30.631638)
		(end 435.58079 -30.631638)
		(width 0.1651)
		(layer "In7.Cu")
		(net "P5E_PEX3_STN2_RX_DP<33>")
	)
	(segment
		(start 437.085994 -31.95066)
		(end 436.928006 -31.91637)
		(width 0.1651)
		(layer "In7.Cu")
		(net "P5E_PEX3_STN2_RX_DP<33>")
	)
	(segment
		(start 405.434038 -271.345152)
		(end 405.434038 -270.917416)
		(width 0.1651)
		(layer "In7.Cu")
		(net "P5E_PEX3_STN2_RX_DP<33>")
	)
	(segment
		(start 436.659528 -31.499556)
		(end 436.693818 -31.341822)
		(width 0.1651)
		(layer "In7.Cu")
		(net "P5E_PEX3_STN2_RX_DP<33>")
	)
	(segment
		(start 405.773382 -267.004546)
		(end 425.33951 -154.656282)
		(width 0.1651)
		(layer "In7.Cu")
		(net "P5E_PEX3_STN2_RX_DP<33>")
	)
	(segment
		(start 436.883556 -38.129464)
		(end 437.603138 -34.076386)
		(width 0.1651)
		(layer "In7.Cu")
		(net "P5E_PEX3_STN2_RX_DP<33>")
	)
	(segment
		(start 405.74214 -273.670014)
		(end 405.479758 -273.407632)
		(width 0.1143)
		(layer "In7.Cu")
		(net "P5E_PEX3_STN2_RX_DP<33>")
	)
	(segment
		(start 405.935688 -273.670014)
		(end 405.74214 -273.670014)
		(width 0.1143)
		(layer "In7.Cu")
		(net "P5E_PEX3_STN2_RX_DP<33>")
	)
	(segment
		(start 436.928006 -31.91637)
		(end 436.659528 -31.499556)
		(width 0.1651)
		(layer "In7.Cu")
		(net "P5E_PEX3_STN2_RX_DP<33>")
	)
	(segment
		(start 436.693818 -31.341822)
		(end 436.236872 -30.631638)
		(width 0.1651)
		(layer "In7.Cu")
		(net "P5E_PEX3_STN2_RX_DP<33>")
	)
	(segment
		(start 437.611266 -33.05302)
		(end 437.353964 -32.366966)
		(width 0.1651)
		(layer "In7.Cu")
		(net "P5E_PEX3_STN2_RX_DP<33>")
	)
	(segment
		(start 406.049988 -274.049744)
		(end 406.049988 -273.784314)
		(width 0.1143)
		(layer "In7.Cu")
		(net "P5E_PEX3_STN2_RX_DP<33>")
	)
	(segment
		(start 405.434038 -270.917416)
		(end 405.773382 -267.004546)
		(width 0.1651)
		(layer "In7.Cu")
		(net "P5E_PEX3_STN2_RX_DP<33>")
	)
	(segment
		(start 405.479758 -273.407632)
		(end 405.479758 -271.41932)
		(width 0.1143)
		(layer "In7.Cu")
		(net "P5E_PEX3_STN2_RX_DP<33>")
	)
	(segment
		(start 435.46649 -30.745938)
		(end 434.97119 -30.745938)
		(width 0.1651)
		(layer "In7.Cu")
		(net "P5E_PEX3_STN2_RX_DP<33>")
	)
	(segment
		(start 435.58079 -30.631638)
		(end 435.46649 -30.745938)
		(width 0.1651)
		(layer "In7.Cu")
		(net "P5E_PEX3_STN2_RX_DP<33>")
	)
	(segment
		(start 438.223406 -49.394364)
		(end 436.90794 -39.65829)
		(width 0.1651)
		(layer "In7.Cu")
		(net "P5E_PEX3_STN2_RX_DP<33>")
	)
	(segment
		(start 427.03115 -116.662708)
		(end 438.039256 -61.179456)
		(width 0.1651)
		(layer "In7.Cu")
		(net "P5E_PEX3_STN2_RX_DP<33>")
	)
	(segment
		(start 405.434038 -271.3736)
		(end 405.434038 -271.345152)
		(width 0.1143)
		(layer "In7.Cu")
		(net "P5E_PEX3_STN2_RX_DP<33>")
	)
	(segment
		(start 436.90794 -39.65829)
		(end 436.883556 -38.129464)
		(width 0.1651)
		(layer "In7.Cu")
		(net "P5E_PEX3_STN2_RX_DP<33>")
	)
	(segment
		(start 433.874418 -30.631638)
		(end 433.74945 -30.683454)
		(width 0.1651)
		(layer "In7.Cu")
		(net "P5E_PEX3_STN2_RX_DP<33>")
	)
	(segment
		(start 291.595048 -99.750372)
		(end 294.130222 -99.750372)
		(width 0.13208)
		(layer "F.Cu")
		(net "NIC5_SLOT_ID1")
	)
	(segment
		(start 294.419782 -100.039932)
		(end 300.857412 -100.039932)
		(width 0.13208)
		(layer "F.Cu")
		(net "NIC5_SLOT_ID1")
	)
	(segment
		(start 294.130222 -99.750372)
		(end 294.419782 -100.039932)
		(width 0.13208)
		(layer "F.Cu")
		(net "NIC5_SLOT_ID1")
	)
	(segment
		(start 291.595048 -100.766372)
		(end 291.595048 -99.750372)
		(width 0.13208)
		(layer "F.Cu")
		(net "NIC5_SLOT_ID1")
	)
	(via
		(at 294.419782 -100.039932)
		(size 0.762)
		(drill 0.381)
		(layers "F.Cu" "B.Cu")
		(net "NIC5_SLOT_ID1")
	)
	(segment
		(start 416.766502 -23.589996)
		(end 416.766502 -24.134572)
		(width 0.13208)
		(layer "F.Cu")
		(net "DUALPORT_N_SSD14")
	)
	(segment
		(start 417.120578 -24.488648)
		(end 419.349682 -24.488648)
		(width 0.13208)
		(layer "F.Cu")
		(net "DUALPORT_N_SSD14")
	)
	(segment
		(start 420.787576 -24.942292)
		(end 419.771576 -24.942292)
		(width 0.13208)
		(layer "F.Cu")
		(net "DUALPORT_N_SSD14")
	)
	(segment
		(start 415.564828 -23.589996)
		(end 416.766502 -23.589996)
		(width 0.13208)
		(layer "F.Cu")
		(net "DUALPORT_N_SSD14")
	)
	(segment
		(start 416.766502 -24.134572)
		(end 417.120578 -24.488648)
		(width 0.13208)
		(layer "F.Cu")
		(net "DUALPORT_N_SSD14")
	)
	(segment
		(start 419.771576 -24.910542)
		(end 419.771576 -24.942292)
		(width 0.13208)
		(layer "F.Cu")
		(net "DUALPORT_N_SSD14")
	)
	(segment
		(start 419.349682 -24.488648)
		(end 419.771576 -24.910542)
		(width 0.13208)
		(layer "F.Cu")
		(net "DUALPORT_N_SSD14")
	)
	(via
		(at 416.766502 -23.589996)
		(size 0.508)
		(drill 0.254)
		(layers "F.Cu" "B.Cu")
		(net "DUALPORT_N_SSD14")
	)
	(segment
		(start 271.575022 -344.539062)
		(end 271.575022 -345.170506)
		(width 0.13462)
		(layer "F.Cu")
		(net "P5E_PEX2_STN7_TX_C_DN<113>")
	)
	(segment
		(start 271.575022 -345.170506)
		(end 271.869662 -345.465146)
		(width 0.13462)
		(layer "F.Cu")
		(net "P5E_PEX2_STN7_TX_C_DN<113>")
	)
	(segment
		(start 271.895062 -344.219022)
		(end 271.575022 -344.539062)
		(width 0.13462)
		(layer "F.Cu")
		(net "P5E_PEX2_STN7_TX_C_DN<113>")
	)
	(segment
		(start 288.8488 -393.192)
		(end 284.04566 -390.713722)
		(width 0.1651)
		(layer "In7.Cu")
		(net "P5E_PEX2_STN7_TX_C_DN<113>")
	)
	(segment
		(start 280.868628 -386.660136)
		(end 278.7142 -374.8532)
		(width 0.1651)
		(layer "In7.Cu")
		(net "P5E_PEX2_STN7_TX_C_DN<113>")
	)
	(segment
		(start 270.024352 -358.3686)
		(end 270.024352 -347.881194)
		(width 0.1651)
		(layer "In7.Cu")
		(net "P5E_PEX2_STN7_TX_C_DN<113>")
	)
	(segment
		(start 270.024352 -347.881194)
		(end 271.578832 -346.326714)
		(width 0.1651)
		(layer "In7.Cu")
		(net "P5E_PEX2_STN7_TX_C_DN<113>")
	)
	(segment
		(start 289.689794 -402.408136)
		(end 289.816794 -402.281136)
		(width 0.1651)
		(layer "In7.Cu")
		(net "P5E_PEX2_STN7_TX_C_DN<113>")
	)
	(segment
		(start 289.816794 -402.281136)
		(end 290.36391 -402.281136)
		(width 0.1651)
		(layer "In7.Cu")
		(net "P5E_PEX2_STN7_TX_C_DN<113>")
	)
	(segment
		(start 290.815776 -401.82927)
		(end 290.815776 -395.859)
		(width 0.1651)
		(layer "In7.Cu")
		(net "P5E_PEX2_STN7_TX_C_DN<113>")
	)
	(segment
		(start 271.578832 -345.755976)
		(end 271.869662 -345.465146)
		(width 0.1651)
		(layer "In7.Cu")
		(net "P5E_PEX2_STN7_TX_C_DN<113>")
	)
	(segment
		(start 289.689794 -402.790152)
		(end 289.689794 -402.408136)
		(width 0.1651)
		(layer "In7.Cu")
		(net "P5E_PEX2_STN7_TX_C_DN<113>")
	)
	(segment
		(start 271.578832 -346.326714)
		(end 271.578832 -345.755976)
		(width 0.1651)
		(layer "In7.Cu")
		(net "P5E_PEX2_STN7_TX_C_DN<113>")
	)
	(segment
		(start 281.630628 -388.499858)
		(end 280.868628 -386.660136)
		(width 0.1651)
		(layer "In7.Cu")
		(net "P5E_PEX2_STN7_TX_C_DN<113>")
	)
	(segment
		(start 290.36391 -402.281136)
		(end 290.815776 -401.82927)
		(width 0.1651)
		(layer "In7.Cu")
		(net "P5E_PEX2_STN7_TX_C_DN<113>")
	)
	(segment
		(start 290.4998 -394.843)
		(end 288.8488 -393.192)
		(width 0.1651)
		(layer "In7.Cu")
		(net "P5E_PEX2_STN7_TX_C_DN<113>")
	)
	(segment
		(start 278.7142 -374.8532)
		(end 270.024352 -358.3686)
		(width 0.1651)
		(layer "In7.Cu")
		(net "P5E_PEX2_STN7_TX_C_DN<113>")
	)
	(segment
		(start 284.04566 -390.713722)
		(end 281.630628 -388.499858)
		(width 0.1651)
		(layer "In7.Cu")
		(net "P5E_PEX2_STN7_TX_C_DN<113>")
	)
	(segment
		(start 290.815776 -395.859)
		(end 290.4998 -394.843)
		(width 0.1651)
		(layer "In7.Cu")
		(net "P5E_PEX2_STN7_TX_C_DN<113>")
	)
	(segment
		(start 384.332226 -30.34538)
		(end 381.797052 -30.34538)
		(width 0.13462)
		(layer "F.Cu")
		(net "P5E_PEX3_STN2_RX_DN<41>")
	)
	(segment
		(start 384.96494 -30.190186)
		(end 384.48742 -30.190186)
		(width 0.13462)
		(layer "F.Cu")
		(net "P5E_PEX3_STN2_RX_DN<41>")
	)
	(segment
		(start 381.797052 -30.34538)
		(end 381.51054 -30.058868)
		(width 0.13462)
		(layer "F.Cu")
		(net "P5E_PEX3_STN2_RX_DN<41>")
	)
	(segment
		(start 384.48742 -30.190186)
		(end 384.332226 -30.34538)
		(width 0.13462)
		(layer "F.Cu")
		(net "P5E_PEX3_STN2_RX_DN<41>")
	)
	(segment
		(start 398.069562 -249.971052)
		(end 390.113266 -147.970494)
		(width 0.1651)
		(layer "In7.Cu")
		(net "P5E_PEX3_STN2_RX_DN<41>")
	)
	(segment
		(start 398.07007 -271.41932)
		(end 398.11579 -271.3736)
		(width 0.1143)
		(layer "In7.Cu")
		(net "P5E_PEX3_STN2_RX_DN<41>")
	)
	(segment
		(start 398.11579 -271.345152)
		(end 398.11579 -267.669264)
		(width 0.1651)
		(layer "In7.Cu")
		(net "P5E_PEX3_STN2_RX_DN<41>")
	)
	(segment
		(start 398.220946 -273.479514)
		(end 398.07007 -273.328638)
		(width 0.1143)
		(layer "In7.Cu")
		(net "P5E_PEX3_STN2_RX_DN<41>")
	)
	(segment
		(start 390.113266 -147.970494)
		(end 390.419336 -119.573802)
		(width 0.1651)
		(layer "In7.Cu")
		(net "P5E_PEX3_STN2_RX_DN<41>")
	)
	(segment
		(start 397.716756 -263.616948)
		(end 397.86433 -260.611112)
		(width 0.1651)
		(layer "In7.Cu")
		(net "P5E_PEX3_STN2_RX_DN<41>")
	)
	(segment
		(start 385.163314 -37.96284)
		(end 385.688078 -35.00755)
		(width 0.1651)
		(layer "In7.Cu")
		(net "P5E_PEX3_STN2_RX_DN<41>")
	)
	(segment
		(start 398.4498 -273.099784)
		(end 398.4498 -273.365214)
		(width 0.1143)
		(layer "In7.Cu")
		(net "P5E_PEX3_STN2_RX_DN<41>")
	)
	(segment
		(start 386.766054 -64.739774)
		(end 386.40639 -55.754524)
		(width 0.1651)
		(layer "In7.Cu")
		(net "P5E_PEX3_STN2_RX_DN<41>")
	)
	(segment
		(start 389.965692 -104.603296)
		(end 386.766054 -64.739774)
		(width 0.1651)
		(layer "In7.Cu")
		(net "P5E_PEX3_STN2_RX_DN<41>")
	)
	(segment
		(start 398.11579 -271.3736)
		(end 398.11579 -271.345152)
		(width 0.1143)
		(layer "In7.Cu")
		(net "P5E_PEX3_STN2_RX_DN<41>")
	)
	(segment
		(start 381.80137 -30.349698)
		(end 381.51054 -30.058868)
		(width 0.1651)
		(layer "In7.Cu")
		(net "P5E_PEX3_STN2_RX_DN<41>")
	)
	(segment
		(start 390.419336 -119.573802)
		(end 389.965692 -104.603296)
		(width 0.1651)
		(layer "In7.Cu")
		(net "P5E_PEX3_STN2_RX_DN<41>")
	)
	(segment
		(start 398.3355 -273.479514)
		(end 398.220946 -273.479514)
		(width 0.1143)
		(layer "In7.Cu")
		(net "P5E_PEX3_STN2_RX_DN<41>")
	)
	(segment
		(start 384.089148 -30.349698)
		(end 381.80137 -30.349698)
		(width 0.1651)
		(layer "In7.Cu")
		(net "P5E_PEX3_STN2_RX_DN<41>")
	)
	(segment
		(start 385.18973 -39.636954)
		(end 385.163314 -37.96284)
		(width 0.1651)
		(layer "In7.Cu")
		(net "P5E_PEX3_STN2_RX_DN<41>")
	)
	(segment
		(start 398.07007 -273.328638)
		(end 398.07007 -271.41932)
		(width 0.1143)
		(layer "In7.Cu")
		(net "P5E_PEX3_STN2_RX_DN<41>")
	)
	(segment
		(start 397.86433 -260.611112)
		(end 398.069562 -249.971052)
		(width 0.1651)
		(layer "In7.Cu")
		(net "P5E_PEX3_STN2_RX_DN<41>")
	)
	(segment
		(start 398.11579 -267.669264)
		(end 397.716756 -263.616948)
		(width 0.1651)
		(layer "In7.Cu")
		(net "P5E_PEX3_STN2_RX_DN<41>")
	)
	(segment
		(start 398.4498 -273.365214)
		(end 398.3355 -273.479514)
		(width 0.1143)
		(layer "In7.Cu")
		(net "P5E_PEX3_STN2_RX_DN<41>")
	)
	(segment
		(start 385.688078 -35.00755)
		(end 385.712462 -31.973012)
		(width 0.1651)
		(layer "In7.Cu")
		(net "P5E_PEX3_STN2_RX_DN<41>")
	)
	(segment
		(start 386.40639 -55.754524)
		(end 386.505958 -49.3776)
		(width 0.1651)
		(layer "In7.Cu")
		(net "P5E_PEX3_STN2_RX_DN<41>")
	)
	(segment
		(start 385.712462 -31.973012)
		(end 384.089148 -30.349698)
		(width 0.1651)
		(layer "In7.Cu")
		(net "P5E_PEX3_STN2_RX_DN<41>")
	)
	(segment
		(start 386.505958 -49.3776)
		(end 385.18973 -39.636954)
		(width 0.1651)
		(layer "In7.Cu")
		(net "P5E_PEX3_STN2_RX_DN<41>")
	)
	(segment
		(start 304.802032 -115.834922)
		(end 304.60696 -116.029994)
		(width 0.13208)
		(layer "F.Cu")
		(net "NIC5_AUX_PWR_EN_R")
	)
	(segment
		(start 304.14087 -116.22278)
		(end 303.886362 -116.477288)
		(width 0.13208)
		(layer "F.Cu")
		(net "NIC5_AUX_PWR_EN_R")
	)
	(segment
		(start 305.457606 -115.834922)
		(end 304.802032 -115.834922)
		(width 0.13208)
		(layer "F.Cu")
		(net "NIC5_AUX_PWR_EN_R")
	)
	(segment
		(start 304.60696 -116.029994)
		(end 304.14087 -116.22278)
		(width 0.13208)
		(layer "F.Cu")
		(net "NIC5_AUX_PWR_EN_R")
	)
	(via
		(at 303.886362 -116.477288)
		(size 0.508)
		(drill 0.254)
		(layers "F.Cu" "B.Cu")
		(net "NIC5_AUX_PWR_EN_R")
	)
	(segment
		(start 302.199294 -114.713512)
		(end 302.199294 -115.256564)
		(width 0.13208)
		(layer "B.Cu")
		(net "NIC5_AUX_PWR_EN_R")
	)
	(segment
		(start 303.886362 -116.477288)
		(end 303.886362 -117.66169)
		(width 0.13208)
		(layer "B.Cu")
		(net "NIC5_AUX_PWR_EN_R")
	)
	(segment
		(start 302.199294 -115.256564)
		(end 303.420018 -116.477288)
		(width 0.13208)
		(layer "B.Cu")
		(net "NIC5_AUX_PWR_EN_R")
	)
	(segment
		(start 303.420018 -116.477288)
		(end 303.886362 -116.477288)
		(width 0.13208)
		(layer "B.Cu")
		(net "NIC5_AUX_PWR_EN_R")
	)
	(segment
		(start 446.787524 -24.942292)
		(end 445.771524 -24.942292)
		(width 0.13208)
		(layer "F.Cu")
		(net "DUALPORT_N_SSD15")
	)
	(segment
		(start 443.120526 -24.488648)
		(end 445.34963 -24.488648)
		(width 0.13208)
		(layer "F.Cu")
		(net "DUALPORT_N_SSD15")
	)
	(segment
		(start 442.76645 -24.134572)
		(end 443.120526 -24.488648)
		(width 0.13208)
		(layer "F.Cu")
		(net "DUALPORT_N_SSD15")
	)
	(segment
		(start 445.34963 -24.488648)
		(end 445.771524 -24.910542)
		(width 0.13208)
		(layer "F.Cu")
		(net "DUALPORT_N_SSD15")
	)
	(segment
		(start 445.771524 -24.910542)
		(end 445.771524 -24.942292)
		(width 0.13208)
		(layer "F.Cu")
		(net "DUALPORT_N_SSD15")
	)
	(segment
		(start 442.76645 -23.589996)
		(end 442.76645 -24.134572)
		(width 0.13208)
		(layer "F.Cu")
		(net "DUALPORT_N_SSD15")
	)
	(segment
		(start 441.564776 -23.589996)
		(end 442.76645 -23.589996)
		(width 0.13208)
		(layer "F.Cu")
		(net "DUALPORT_N_SSD15")
	)
	(via
		(at 442.76645 -23.589996)
		(size 0.508)
		(drill 0.254)
		(layers "F.Cu" "B.Cu")
		(net "DUALPORT_N_SSD15")
	)
	(segment
		(start 73.908666 -124.39777)
		(end 82.07375 -124.39777)
		(width 0.13462)
		(layer "F.Cu")
		(net "P5E_PEX0_STN0_TX_C_DN<3>")
	)
	(segment
		(start 73.745852 -124.234956)
		(end 73.908666 -124.39777)
		(width 0.13462)
		(layer "F.Cu")
		(net "P5E_PEX0_STN0_TX_C_DN<3>")
	)
	(segment
		(start 73.257664 -124.234956)
		(end 73.745852 -124.234956)
		(width 0.13462)
		(layer "F.Cu")
		(net "P5E_PEX0_STN0_TX_C_DN<3>")
	)
	(segment
		(start 82.07375 -124.39777)
		(end 82.394806 -124.076714)
		(width 0.13462)
		(layer "F.Cu")
		(net "P5E_PEX0_STN0_TX_C_DN<3>")
	)
	(segment
		(start 416.241484 -33.9598)
		(end 416.071812 -33.790128)
		(width 0.13462)
		(layer "F.Cu")
		(net "P5E_PEX3_STN2_TX_C_DN<39>")
	)
	(segment
		(start 420.46779 -33.631886)
		(end 420.139876 -33.9598)
		(width 0.13462)
		(layer "F.Cu")
		(net "P5E_PEX3_STN2_TX_C_DN<39>")
	)
	(segment
		(start 420.139876 -33.9598)
		(end 416.241484 -33.9598)
		(width 0.13462)
		(layer "F.Cu")
		(net "P5E_PEX3_STN2_TX_C_DN<39>")
	)
	(segment
		(start 416.071812 -33.790128)
		(end 415.564828 -33.790128)
		(width 0.13462)
		(layer "F.Cu")
		(net "P5E_PEX3_STN2_TX_C_DN<39>")
	)
	(segment
		(start 306.937918 -104.840024)
		(end 307.891942 -103.886)
		(width 0.13208)
		(layer "F.Cu")
		(net "NCSI_NIC5_CRS_DV")
	)
	(segment
		(start 305.457606 -104.840024)
		(end 306.937918 -104.840024)
		(width 0.13208)
		(layer "F.Cu")
		(net "NCSI_NIC5_CRS_DV")
	)
	(via
		(at 307.891942 -103.886)
		(size 0.508)
		(drill 0.254)
		(layers "F.Cu" "B.Cu")
		(net "NCSI_NIC5_CRS_DV")
	)
	(segment
		(start 309.341774 -104.120696)
		(end 308.634638 -104.120696)
		(width 0.13208)
		(layer "B.Cu")
		(net "NCSI_NIC5_CRS_DV")
	)
	(segment
		(start 308.634638 -104.120696)
		(end 308.399942 -103.886)
		(width 0.13208)
		(layer "B.Cu")
		(net "NCSI_NIC5_CRS_DV")
	)
	(segment
		(start 308.399942 -103.886)
		(end 307.891942 -103.886)
		(width 0.13208)
		(layer "B.Cu")
		(net "NCSI_NIC5_CRS_DV")
	)
	(segment
		(start 178.764946 -25.390094)
		(end 177.552096 -25.390094)
		(width 0.13208)
		(layer "F.Cu")
		(net "PRSNT_SSD6_N")
	)
	(segment
		(start 177.002186 -26.266394)
		(end 176.220628 -26.266394)
		(width 0.13208)
		(layer "F.Cu")
		(net "PRSNT_SSD6_N")
	)
	(segment
		(start 177.552096 -25.390094)
		(end 177.002186 -25.940004)
		(width 0.13208)
		(layer "F.Cu")
		(net "PRSNT_SSD6_N")
	)
	(segment
		(start 177.002186 -25.940004)
		(end 177.002186 -26.266394)
		(width 0.13208)
		(layer "F.Cu")
		(net "PRSNT_SSD6_N")
	)
	(via
		(at 177.002186 -26.266394)
		(size 0.508)
		(drill 0.254)
		(layers "F.Cu" "B.Cu")
		(net "PRSNT_SSD6_N")
	)
	(segment
		(start 73.257664 -148.155152)
		(end 73.745852 -148.155152)
		(width 0.13462)
		(layer "F.Cu")
		(net "P5E_PEX0_STN0_TX_C_DN<11>")
	)
	(segment
		(start 73.908666 -148.317966)
		(end 82.07375 -148.317966)
		(width 0.13462)
		(layer "F.Cu")
		(net "P5E_PEX0_STN0_TX_C_DN<11>")
	)
	(segment
		(start 73.745852 -148.155152)
		(end 73.908666 -148.317966)
		(width 0.13462)
		(layer "F.Cu")
		(net "P5E_PEX0_STN0_TX_C_DN<11>")
	)
	(segment
		(start 82.07375 -148.317966)
		(end 82.394806 -147.99691)
		(width 0.13462)
		(layer "F.Cu")
		(net "P5E_PEX0_STN0_TX_C_DN<11>")
	)
	(segment
		(start 288.164016 -408.981148)
		(end 288.615882 -408.529282)
		(width 0.1651)
		(layer "In5.Cu")
		(net "P5E_PEX2_STN7_RX_DN<112>")
	)
	(segment
		(start 261.970266 -348.808548)
		(end 261.970266 -348.808294)
		(width 0.1651)
		(layer "In5.Cu")
		(net "P5E_PEX2_STN7_RX_DN<112>")
	)
	(segment
		(start 261.97052 -348.808548)
		(end 261.970266 -348.808548)
		(width 0.1651)
		(layer "In5.Cu")
		(net "P5E_PEX2_STN7_RX_DN<112>")
	)
	(segment
		(start 255.49733 -306.291234)
		(end 255.84785 -305.940714)
		(width 0.1651)
		(layer "In5.Cu")
		(net "P5E_PEX2_STN7_RX_DN<112>")
	)
	(segment
		(start 251.83846 -328.3458)
		(end 249.71756 -323.557392)
		(width 0.1651)
		(layer "In5.Cu")
		(net "P5E_PEX2_STN7_RX_DN<112>")
	)
	(segment
		(start 271.215358 -301.220124)
		(end 271.329658 -301.334424)
		(width 0.1143)
		(layer "In5.Cu")
		(net "P5E_PEX2_STN7_RX_DN<112>")
	)
	(segment
		(start 261.524496 -302.102774)
		(end 261.579614 -301.970186)
		(width 0.1651)
		(layer "In5.Cu")
		(net "P5E_PEX2_STN7_RX_DN<112>")
	)
	(segment
		(start 279.43302 -385.79044)
		(end 279.14092 -378.98832)
		(width 0.1651)
		(layer "In5.Cu")
		(net "P5E_PEX2_STN7_RX_DN<112>")
	)
	(segment
		(start 261.970266 -348.808294)
		(end 257.04546 -336.75574)
		(width 0.1651)
		(layer "In5.Cu")
		(net "P5E_PEX2_STN7_RX_DN<112>")
	)
	(segment
		(start 259.831078 -302.694594)
		(end 259.963666 -302.749458)
		(width 0.1651)
		(layer "In5.Cu")
		(net "P5E_PEX2_STN7_RX_DN<112>")
	)
	(segment
		(start 281.03068 -389.23468)
		(end 279.43302 -385.79044)
		(width 0.1651)
		(layer "In5.Cu")
		(net "P5E_PEX2_STN7_RX_DN<112>")
	)
	(segment
		(start 268.627352 -301.265844)
		(end 268.6558 -301.265844)
		(width 0.1143)
		(layer "In5.Cu")
		(net "P5E_PEX2_STN7_RX_DN<112>")
	)
	(segment
		(start 277.99792 -372.25986)
		(end 266.894818 -360.86034)
		(width 0.1651)
		(layer "In5.Cu")
		(net "P5E_PEX2_STN7_RX_DN<112>")
	)
	(segment
		(start 271.329658 -301.334424)
		(end 271.329658 -301.485554)
		(width 0.1143)
		(layer "In5.Cu")
		(net "P5E_PEX2_STN7_RX_DN<112>")
	)
	(segment
		(start 261.579614 -301.970186)
		(end 261.579868 -301.969932)
		(width 0.1651)
		(layer "In5.Cu")
		(net "P5E_PEX2_STN7_RX_DN<112>")
	)
	(segment
		(start 256.692146 -305.096418)
		(end 256.692146 -304.952654)
		(width 0.1651)
		(layer "In5.Cu")
		(net "P5E_PEX2_STN7_RX_DN<112>")
	)
	(segment
		(start 260.421628 -302.55972)
		(end 260.476492 -302.426878)
		(width 0.1651)
		(layer "In5.Cu")
		(net "P5E_PEX2_STN7_RX_DN<112>")
	)
	(segment
		(start 256.692146 -304.952654)
		(end 257.042158 -304.602642)
		(width 0.1651)
		(layer "In5.Cu")
		(net "P5E_PEX2_STN7_RX_DN<112>")
	)
	(segment
		(start 255.353566 -306.291234)
		(end 255.49733 -306.291234)
		(width 0.1651)
		(layer "In5.Cu")
		(net "P5E_PEX2_STN7_RX_DN<112>")
	)
	(segment
		(start 249.71756 -317.818516)
		(end 254.540258 -307.104542)
		(width 0.1651)
		(layer "In5.Cu")
		(net "P5E_PEX2_STN7_RX_DN<112>")
	)
	(segment
		(start 283.903674 -391.786364)
		(end 281.03068 -389.23468)
		(width 0.1651)
		(layer "In5.Cu")
		(net "P5E_PEX2_STN7_RX_DN<112>")
	)
	(segment
		(start 288.615882 -395.097)
		(end 288.0614 -394.2588)
		(width 0.1651)
		(layer "In5.Cu")
		(net "P5E_PEX2_STN7_RX_DN<112>")
	)
	(segment
		(start 268.70152 -301.220124)
		(end 271.215358 -301.220124)
		(width 0.1143)
		(layer "In5.Cu")
		(net "P5E_PEX2_STN7_RX_DN<112>")
	)
	(segment
		(start 271.215358 -301.599854)
		(end 270.949928 -301.599854)
		(width 0.1143)
		(layer "In5.Cu")
		(net "P5E_PEX2_STN7_RX_DN<112>")
	)
	(segment
		(start 257.042158 -304.602642)
		(end 257.185922 -304.602642)
		(width 0.1651)
		(layer "In5.Cu")
		(net "P5E_PEX2_STN7_RX_DN<112>")
	)
	(segment
		(start 256.197862 -305.446938)
		(end 256.341626 -305.446938)
		(width 0.1651)
		(layer "In5.Cu")
		(net "P5E_PEX2_STN7_RX_DN<112>")
	)
	(segment
		(start 266.894818 -360.86034)
		(end 261.97052 -348.808548)
		(width 0.1651)
		(layer "In5.Cu")
		(net "P5E_PEX2_STN7_RX_DN<112>")
	)
	(segment
		(start 260.476492 -302.426878)
		(end 260.476492 -302.427132)
		(width 0.1651)
		(layer "In5.Cu")
		(net "P5E_PEX2_STN7_RX_DN<112>")
	)
	(segment
		(start 260.933946 -302.237648)
		(end 261.066788 -302.292766)
		(width 0.1651)
		(layer "In5.Cu")
		(net "P5E_PEX2_STN7_RX_DN<112>")
	)
	(segment
		(start 287.6169 -408.981148)
		(end 288.164016 -408.981148)
		(width 0.1651)
		(layer "In5.Cu")
		(net "P5E_PEX2_STN7_RX_DN<112>")
	)
	(segment
		(start 255.84785 -305.79695)
		(end 256.197862 -305.446938)
		(width 0.1651)
		(layer "In5.Cu")
		(net "P5E_PEX2_STN7_RX_DN<112>")
	)
	(segment
		(start 256.341626 -305.446938)
		(end 256.692146 -305.096418)
		(width 0.1651)
		(layer "In5.Cu")
		(net "P5E_PEX2_STN7_RX_DN<112>")
	)
	(segment
		(start 260.476492 -302.427132)
		(end 260.933946 -302.237648)
		(width 0.1651)
		(layer "In5.Cu")
		(net "P5E_PEX2_STN7_RX_DN<112>")
	)
	(segment
		(start 257.04546 -336.75574)
		(end 251.83846 -328.3458)
		(width 0.1651)
		(layer "In5.Cu")
		(net "P5E_PEX2_STN7_RX_DN<112>")
	)
	(segment
		(start 288.615882 -408.529282)
		(end 288.615882 -395.097)
		(width 0.1651)
		(layer "In5.Cu")
		(net "P5E_PEX2_STN7_RX_DN<112>")
	)
	(segment
		(start 257.536442 -304.252122)
		(end 257.536442 -304.108358)
		(width 0.1651)
		(layer "In5.Cu")
		(net "P5E_PEX2_STN7_RX_DN<112>")
	)
	(segment
		(start 268.6558 -301.265844)
		(end 268.70152 -301.220124)
		(width 0.1143)
		(layer "In5.Cu")
		(net "P5E_PEX2_STN7_RX_DN<112>")
	)
	(segment
		(start 254.540258 -307.104542)
		(end 255.353566 -306.291234)
		(width 0.1651)
		(layer "In5.Cu")
		(net "P5E_PEX2_STN7_RX_DN<112>")
	)
	(segment
		(start 257.185922 -304.602642)
		(end 257.536442 -304.252122)
		(width 0.1651)
		(layer "In5.Cu")
		(net "P5E_PEX2_STN7_RX_DN<112>")
	)
	(segment
		(start 287.4899 -409.490164)
		(end 287.4899 -409.108148)
		(width 0.1651)
		(layer "In5.Cu")
		(net "P5E_PEX2_STN7_RX_DN<112>")
	)
	(segment
		(start 255.84785 -305.940714)
		(end 255.84785 -305.79695)
		(width 0.1651)
		(layer "In5.Cu")
		(net "P5E_PEX2_STN7_RX_DN<112>")
	)
	(segment
		(start 279.14092 -378.98832)
		(end 278.608282 -373.51462)
		(width 0.1651)
		(layer "In5.Cu")
		(net "P5E_PEX2_STN7_RX_DN<112>")
	)
	(segment
		(start 257.536442 -304.108358)
		(end 258.327652 -303.317148)
		(width 0.1651)
		(layer "In5.Cu")
		(net "P5E_PEX2_STN7_RX_DN<112>")
	)
	(segment
		(start 287.4899 -409.108148)
		(end 287.6169 -408.981148)
		(width 0.1651)
		(layer "In5.Cu")
		(net "P5E_PEX2_STN7_RX_DN<112>")
	)
	(segment
		(start 259.963666 -302.749458)
		(end 260.421628 -302.55972)
		(width 0.1651)
		(layer "In5.Cu")
		(net "P5E_PEX2_STN7_RX_DN<112>")
	)
	(segment
		(start 261.579868 -301.969932)
		(end 263.279128 -301.265844)
		(width 0.1651)
		(layer "In5.Cu")
		(net "P5E_PEX2_STN7_RX_DN<112>")
	)
	(segment
		(start 258.327652 -303.317148)
		(end 259.831078 -302.694594)
		(width 0.1651)
		(layer "In5.Cu")
		(net "P5E_PEX2_STN7_RX_DN<112>")
	)
	(segment
		(start 261.066788 -302.292766)
		(end 261.524496 -302.102774)
		(width 0.1651)
		(layer "In5.Cu")
		(net "P5E_PEX2_STN7_RX_DN<112>")
	)
	(segment
		(start 263.279128 -301.265844)
		(end 268.627352 -301.265844)
		(width 0.1651)
		(layer "In5.Cu")
		(net "P5E_PEX2_STN7_RX_DN<112>")
	)
	(segment
		(start 288.0614 -394.2588)
		(end 283.903674 -391.786364)
		(width 0.1651)
		(layer "In5.Cu")
		(net "P5E_PEX2_STN7_RX_DN<112>")
	)
	(segment
		(start 249.71756 -323.557392)
		(end 249.71756 -317.818516)
		(width 0.1651)
		(layer "In5.Cu")
		(net "P5E_PEX2_STN7_RX_DN<112>")
	)
	(segment
		(start 278.608282 -373.51462)
		(end 277.99792 -372.25986)
		(width 0.1651)
		(layer "In5.Cu")
		(net "P5E_PEX2_STN7_RX_DN<112>")
	)
	(segment
		(start 271.329658 -301.485554)
		(end 271.215358 -301.599854)
		(width 0.1143)
		(layer "In5.Cu")
		(net "P5E_PEX2_STN7_RX_DN<112>")
	)
	(segment
		(start 390.225534 -28.829)
		(end 390.064498 -28.990036)
		(width 0.13462)
		(layer "F.Cu")
		(net "P5E_PEX3_STN2_TX_C_DP<40>")
	)
	(segment
		(start 390.064498 -28.990036)
		(end 389.56488 -28.990036)
		(width 0.13462)
		(layer "F.Cu")
		(net "P5E_PEX3_STN2_TX_C_DP<40>")
	)
	(segment
		(start 391.825734 -29.139642)
		(end 391.515092 -28.829)
		(width 0.13462)
		(layer "F.Cu")
		(net "P5E_PEX3_STN2_TX_C_DP<40>")
	)
	(segment
		(start 391.515092 -28.829)
		(end 390.225534 -28.829)
		(width 0.13462)
		(layer "F.Cu")
		(net "P5E_PEX3_STN2_TX_C_DP<40>")
	)
	(segment
		(start 73.745852 -121.234962)
		(end 73.908666 -121.072148)
		(width 0.13462)
		(layer "F.Cu")
		(net "P5E_PEX0_STN0_TX_C_DP<1>")
	)
	(segment
		(start 73.257664 -121.234962)
		(end 73.745852 -121.234962)
		(width 0.13462)
		(layer "F.Cu")
		(net "P5E_PEX0_STN0_TX_C_DP<1>")
	)
	(segment
		(start 82.075782 -121.072148)
		(end 82.394806 -121.391172)
		(width 0.13462)
		(layer "F.Cu")
		(net "P5E_PEX0_STN0_TX_C_DP<1>")
	)
	(segment
		(start 73.908666 -121.072148)
		(end 82.075782 -121.072148)
		(width 0.13462)
		(layer "F.Cu")
		(net "P5E_PEX0_STN0_TX_C_DP<1>")
	)
	(segment
		(start 407.811478 -33.9598)
		(end 407.510488 -33.65881)
		(width 0.13462)
		(layer "F.Cu")
		(net "P5E_PEX3_STN2_RX_DN<39>")
	)
	(segment
		(start 410.487368 -33.790128)
		(end 410.317696 -33.9598)
		(width 0.13462)
		(layer "F.Cu")
		(net "P5E_PEX3_STN2_RX_DN<39>")
	)
	(segment
		(start 410.964888 -33.790128)
		(end 410.487368 -33.790128)
		(width 0.13462)
		(layer "F.Cu")
		(net "P5E_PEX3_STN2_RX_DN<39>")
	)
	(segment
		(start 410.317696 -33.9598)
		(end 407.811478 -33.9598)
		(width 0.13462)
		(layer "F.Cu")
		(net "P5E_PEX3_STN2_RX_DN<39>")
	)
	(segment
		(start 410.45511 -60.99683)
		(end 410.628084 -49.915572)
		(width 0.1651)
		(layer "In7.Cu")
		(net "P5E_PEX3_STN2_RX_DN<39>")
	)
	(segment
		(start 399.970244 -273.328638)
		(end 399.970244 -271.549368)
		(width 0.1143)
		(layer "In7.Cu")
		(net "P5E_PEX3_STN2_RX_DN<39>")
	)
	(segment
		(start 410.628084 -49.915572)
		(end 409.256484 -39.76497)
		(width 0.1651)
		(layer "In7.Cu")
		(net "P5E_PEX3_STN2_RX_DN<39>")
	)
	(segment
		(start 408.151838 -33.94964)
		(end 407.801318 -33.94964)
		(width 0.1651)
		(layer "In7.Cu")
		(net "P5E_PEX3_STN2_RX_DN<39>")
	)
	(segment
		(start 410.481018 -68.13804)
		(end 410.45511 -60.99683)
		(width 0.1651)
		(layer "In7.Cu")
		(net "P5E_PEX3_STN2_RX_DN<39>")
	)
	(segment
		(start 399.970244 -271.549368)
		(end 400.015964 -271.503648)
		(width 0.1143)
		(layer "In7.Cu")
		(net "P5E_PEX3_STN2_RX_DN<39>")
	)
	(segment
		(start 409.256484 -39.76497)
		(end 409.188158 -35.355276)
		(width 0.1651)
		(layer "In7.Cu")
		(net "P5E_PEX3_STN2_RX_DN<39>")
	)
	(segment
		(start 400.235674 -273.479514)
		(end 400.12112 -273.479514)
		(width 0.1143)
		(layer "In7.Cu")
		(net "P5E_PEX3_STN2_RX_DN<39>")
	)
	(segment
		(start 409.188158 -35.355276)
		(end 409.188158 -34.98596)
		(width 0.1651)
		(layer "In7.Cu")
		(net "P5E_PEX3_STN2_RX_DN<39>")
	)
	(segment
		(start 400.12112 -273.479514)
		(end 399.970244 -273.328638)
		(width 0.1143)
		(layer "In7.Cu")
		(net "P5E_PEX3_STN2_RX_DN<39>")
	)
	(segment
		(start 400.015964 -271.503648)
		(end 400.015964 -271.4752)
		(width 0.1143)
		(layer "In7.Cu")
		(net "P5E_PEX3_STN2_RX_DN<39>")
	)
	(segment
		(start 409.188158 -34.98596)
		(end 408.151838 -33.94964)
		(width 0.1651)
		(layer "In7.Cu")
		(net "P5E_PEX3_STN2_RX_DN<39>")
	)
	(segment
		(start 400.349974 -273.365214)
		(end 400.235674 -273.479514)
		(width 0.1143)
		(layer "In7.Cu")
		(net "P5E_PEX3_STN2_RX_DN<39>")
	)
	(segment
		(start 400.015964 -266.275058)
		(end 410.481018 -68.13804)
		(width 0.1651)
		(layer "In7.Cu")
		(net "P5E_PEX3_STN2_RX_DN<39>")
	)
	(segment
		(start 400.349974 -273.099784)
		(end 400.349974 -273.365214)
		(width 0.1143)
		(layer "In7.Cu")
		(net "P5E_PEX3_STN2_RX_DN<39>")
	)
	(segment
		(start 400.015964 -271.4752)
		(end 400.015964 -266.275058)
		(width 0.1651)
		(layer "In7.Cu")
		(net "P5E_PEX3_STN2_RX_DN<39>")
	)
	(segment
		(start 407.801318 -33.94964)
		(end 407.510488 -33.65881)
		(width 0.1651)
		(layer "In7.Cu")
		(net "P5E_PEX3_STN2_RX_DN<39>")
	)
	(segment
		(start 305.457606 -98.840036)
		(end 307.476906 -98.840036)
		(width 0.13208)
		(layer "F.Cu")
		(net "NIC5_DATA_IN")
	)
	(segment
		(start 307.476906 -98.840036)
		(end 308.145942 -98.171)
		(width 0.13208)
		(layer "F.Cu")
		(net "NIC5_DATA_IN")
	)
	(via
		(at 308.145942 -98.171)
		(size 0.508)
		(drill 0.254)
		(layers "F.Cu" "B.Cu")
		(net "NIC5_DATA_IN")
	)
	(segment
		(start 308.176422 -98.171)
		(end 308.145942 -98.171)
		(width 0.13208)
		(layer "B.Cu")
		(net "NIC5_DATA_IN")
	)
	(segment
		(start 309.341774 -97.005648)
		(end 308.176422 -98.171)
		(width 0.13208)
		(layer "B.Cu")
		(net "NIC5_DATA_IN")
	)
	(segment
		(start 65.498218 -148.317966)
		(end 65.49771 -148.318474)
		(width 0.13462)
		(layer "F.Cu")
		(net "P5E_PEX0_STN0_RX_DN<11>")
	)
	(segment
		(start 68.006722 -148.317966)
		(end 65.498218 -148.317966)
		(width 0.13462)
		(layer "F.Cu")
		(net "P5E_PEX0_STN0_RX_DN<11>")
	)
	(segment
		(start 68.169536 -148.155152)
		(end 68.006722 -148.317966)
		(width 0.13462)
		(layer "F.Cu")
		(net "P5E_PEX0_STN0_RX_DN<11>")
	)
	(segment
		(start 68.65747 -148.155152)
		(end 68.169536 -148.155152)
		(width 0.13462)
		(layer "F.Cu")
		(net "P5E_PEX0_STN0_RX_DN<11>")
	)
	(segment
		(start 65.49771 -148.318474)
		(end 65.20307 -148.023834)
		(width 0.13462)
		(layer "F.Cu")
		(net "P5E_PEX0_STN0_RX_DN<11>")
	)
	(segment
		(start 65.4939 -148.314664)
		(end 67.702176 -148.314664)
		(width 0.1651)
		(layer "In5.Cu")
		(net "P5E_PEX0_STN0_RX_DN<11>")
	)
	(segment
		(start 75.290172 -161.147506)
		(end 75.316842 -161.269172)
		(width 0.1651)
		(layer "In5.Cu")
		(net "P5E_PEX0_STN0_RX_DN<11>")
	)
	(segment
		(start 78.85811 -268.156182)
		(end 78.31582 -270.91513)
		(width 0.1651)
		(layer "In5.Cu")
		(net "P5E_PEX0_STN0_RX_DN<11>")
	)
	(segment
		(start 75.268836 -161.050224)
		(end 75.289918 -161.146236)
		(width 0.1651)
		(layer "In5.Cu")
		(net "P5E_PEX0_STN0_RX_DN<11>")
	)
	(segment
		(start 78.2701 -271.848072)
		(end 78.2701 -273.376136)
		(width 0.1143)
		(layer "In5.Cu")
		(net "P5E_PEX0_STN0_RX_DN<11>")
	)
	(segment
		(start 78.649576 -273.365214)
		(end 78.649576 -273.099784)
		(width 0.1143)
		(layer "In5.Cu")
		(net "P5E_PEX0_STN0_RX_DN<11>")
	)
	(segment
		(start 67.702176 -148.314664)
		(end 70.283832 -150.89632)
		(width 0.1651)
		(layer "In5.Cu")
		(net "P5E_PEX0_STN0_RX_DN<11>")
	)
	(segment
		(start 78.31582 -271.773904)
		(end 78.31582 -271.802352)
		(width 0.1143)
		(layer "In5.Cu")
		(net "P5E_PEX0_STN0_RX_DN<11>")
	)
	(segment
		(start 75.316842 -161.269172)
		(end 78.823058 -260.513576)
		(width 0.1651)
		(layer "In5.Cu")
		(net "P5E_PEX0_STN0_RX_DN<11>")
	)
	(segment
		(start 78.535276 -273.479514)
		(end 78.649576 -273.365214)
		(width 0.1143)
		(layer "In5.Cu")
		(net "P5E_PEX0_STN0_RX_DN<11>")
	)
	(segment
		(start 74.000868 -157.91053)
		(end 75.21956 -160.825434)
		(width 0.1651)
		(layer "In5.Cu")
		(net "P5E_PEX0_STN0_RX_DN<11>")
	)
	(segment
		(start 78.31582 -270.91513)
		(end 78.31582 -271.773904)
		(width 0.1651)
		(layer "In5.Cu")
		(net "P5E_PEX0_STN0_RX_DN<11>")
	)
	(segment
		(start 75.289918 -161.146236)
		(end 75.290172 -161.147506)
		(width 0.1651)
		(layer "In5.Cu")
		(net "P5E_PEX0_STN0_RX_DN<11>")
	)
	(segment
		(start 78.823058 -260.513576)
		(end 78.85811 -268.156182)
		(width 0.1651)
		(layer "In5.Cu")
		(net "P5E_PEX0_STN0_RX_DN<11>")
	)
	(segment
		(start 71.873618 -154.710638)
		(end 74.000868 -157.91053)
		(width 0.1651)
		(layer "In5.Cu")
		(net "P5E_PEX0_STN0_RX_DN<11>")
	)
	(segment
		(start 78.31582 -271.802352)
		(end 78.2701 -271.848072)
		(width 0.1143)
		(layer "In5.Cu")
		(net "P5E_PEX0_STN0_RX_DN<11>")
	)
	(segment
		(start 75.268328 -161.047684)
		(end 75.268836 -161.050224)
		(width 0.1651)
		(layer "In5.Cu")
		(net "P5E_PEX0_STN0_RX_DN<11>")
	)
	(segment
		(start 75.21956 -160.825434)
		(end 75.268328 -161.047684)
		(width 0.1651)
		(layer "In5.Cu")
		(net "P5E_PEX0_STN0_RX_DN<11>")
	)
	(segment
		(start 78.2701 -273.376136)
		(end 78.373478 -273.479514)
		(width 0.1143)
		(layer "In5.Cu")
		(net "P5E_PEX0_STN0_RX_DN<11>")
	)
	(segment
		(start 70.283832 -150.89632)
		(end 71.873618 -154.710638)
		(width 0.1651)
		(layer "In5.Cu")
		(net "P5E_PEX0_STN0_RX_DN<11>")
	)
	(segment
		(start 65.20307 -148.023834)
		(end 65.4939 -148.314664)
		(width 0.1651)
		(layer "In5.Cu")
		(net "P5E_PEX0_STN0_RX_DN<11>")
	)
	(segment
		(start 78.373478 -273.479514)
		(end 78.535276 -273.479514)
		(width 0.1143)
		(layer "In5.Cu")
		(net "P5E_PEX0_STN0_RX_DN<11>")
	)
	(segment
		(start 390.064498 -32.589978)
		(end 389.56488 -32.589978)
		(width 0.13462)
		(layer "F.Cu")
		(net "P5E_PEX3_STN2_TX_C_DP<42>")
	)
	(segment
		(start 390.236456 -32.41802)
		(end 390.064498 -32.589978)
		(width 0.13462)
		(layer "F.Cu")
		(net "P5E_PEX3_STN2_TX_C_DP<42>")
	)
	(segment
		(start 391.825734 -32.739584)
		(end 391.50417 -32.41802)
		(width 0.13462)
		(layer "F.Cu")
		(net "P5E_PEX3_STN2_TX_C_DP<42>")
	)
	(segment
		(start 391.50417 -32.41802)
		(end 390.236456 -32.41802)
		(width 0.13462)
		(layer "F.Cu")
		(net "P5E_PEX3_STN2_TX_C_DP<42>")
	)
	(segment
		(start 168.089072 -175.238156)
		(end 168.089072 -176.478438)
		(width 0.13208)
		(layer "F.Cu")
		(net "HP_NIC2_PWRGD_R")
	)
	(segment
		(start 168.144952 -175.182276)
		(end 168.089072 -175.238156)
		(width 0.13208)
		(layer "F.Cu")
		(net "HP_NIC2_PWRGD_R")
	)
	(segment
		(start 168.172638 -173.229524)
		(end 168.698672 -173.755558)
		(width 0.13208)
		(layer "F.Cu")
		(net "HP_NIC2_PWRGD_R")
	)
	(segment
		(start 168.698672 -173.755558)
		(end 168.698672 -174.315882)
		(width 0.13208)
		(layer "F.Cu")
		(net "HP_NIC2_PWRGD_R")
	)
	(segment
		(start 167.243252 -173.229524)
		(end 168.172638 -173.229524)
		(width 0.13208)
		(layer "F.Cu")
		(net "HP_NIC2_PWRGD_R")
	)
	(segment
		(start 168.698672 -174.315882)
		(end 168.144952 -174.869602)
		(width 0.13208)
		(layer "F.Cu")
		(net "HP_NIC2_PWRGD_R")
	)
	(segment
		(start 168.144952 -174.869602)
		(end 168.144952 -175.182276)
		(width 0.13208)
		(layer "F.Cu")
		(net "HP_NIC2_PWRGD_R")
	)
	(via
		(at 168.698672 -173.755558)
		(size 0.762)
		(drill 0.381)
		(layers "F.Cu" "B.Cu")
		(net "HP_NIC2_PWRGD_R")
	)
	(segment
		(start 305.457606 -97.64014)
		(end 306.500022 -97.64014)
		(width 0.13208)
		(layer "F.Cu")
		(net "NIC5_MAIN_PWR_EN_R")
	)
	(via
		(at 305.478942 -98.552)
		(size 0.6604)
		(drill 0.3302)
		(layers "F.Cu" "B.Cu")
		(net "NIC5_MAIN_PWR_EN_R")
	)
	(via
		(at 306.500022 -97.64014)
		(size 0.508)
		(drill 0.254)
		(layers "F.Cu" "B.Cu")
		(net "NIC5_MAIN_PWR_EN_R")
	)
	(segment
		(start 305.478942 -98.552)
		(end 304.354992 -98.552)
		(width 0.13208)
		(layer "B.Cu")
		(net "NIC5_MAIN_PWR_EN_R")
	)
	(segment
		(start 305.969162 -98.171)
		(end 305.859942 -98.171)
		(width 0.13208)
		(layer "B.Cu")
		(net "NIC5_MAIN_PWR_EN_R")
	)
	(segment
		(start 306.500022 -97.64014)
		(end 305.969162 -98.171)
		(width 0.13208)
		(layer "B.Cu")
		(net "NIC5_MAIN_PWR_EN_R")
	)
	(segment
		(start 305.859942 -98.171)
		(end 305.478942 -98.552)
		(width 0.13208)
		(layer "B.Cu")
		(net "NIC5_MAIN_PWR_EN_R")
	)
	(segment
		(start 68.006722 -121.072148)
		(end 65.498218 -121.072148)
		(width 0.13462)
		(layer "F.Cu")
		(net "P5E_PEX0_STN0_RX_DP<1>")
	)
	(segment
		(start 68.169536 -121.234962)
		(end 68.006722 -121.072148)
		(width 0.13462)
		(layer "F.Cu")
		(net "P5E_PEX0_STN0_RX_DP<1>")
	)
	(segment
		(start 68.65747 -121.234962)
		(end 68.169536 -121.234962)
		(width 0.13462)
		(layer "F.Cu")
		(net "P5E_PEX0_STN0_RX_DP<1>")
	)
	(segment
		(start 65.498218 -121.072148)
		(end 65.20307 -121.367296)
		(width 0.13462)
		(layer "F.Cu")
		(net "P5E_PEX0_STN0_RX_DP<1>")
	)
	(segment
		(start 76.434442 -127.310134)
		(end 76.110846 -126.934722)
		(width 0.1651)
		(layer "In5.Cu")
		(net "P5E_PEX0_STN0_RX_DP<1>")
	)
	(segment
		(start 85.920326 -286.733996)
		(end 87.300816 -285.886398)
		(width 0.1651)
		(layer "In5.Cu")
		(net "P5E_PEX0_STN0_RX_DP<1>")
	)
	(segment
		(start 76.874116 -127.819658)
		(end 76.88326 -127.694182)
		(width 0.1651)
		(layer "In5.Cu")
		(net "P5E_PEX0_STN0_RX_DP<1>")
	)
	(segment
		(start 75.796648 -126.434342)
		(end 75.671426 -126.425198)
		(width 0.1651)
		(layer "In5.Cu")
		(net "P5E_PEX0_STN0_RX_DP<1>")
	)
	(segment
		(start 68.685156 -121.54535)
		(end 68.53555 -121.606818)
		(width 0.1651)
		(layer "In5.Cu")
		(net "P5E_PEX0_STN0_RX_DP<1>")
	)
	(segment
		(start 74.89317 -125.386846)
		(end 72.69734 -123.215908)
		(width 0.1651)
		(layer "In5.Cu")
		(net "P5E_PEX0_STN0_RX_DP<1>")
	)
	(segment
		(start 67.559428 -121.076466)
		(end 65.4939 -121.076466)
		(width 0.1651)
		(layer "In5.Cu")
		(net "P5E_PEX0_STN0_RX_DP<1>")
	)
	(segment
		(start 68.016628 -121.266712)
		(end 68.016628 -121.266966)
		(width 0.1651)
		(layer "In5.Cu")
		(net "P5E_PEX0_STN0_RX_DP<1>")
	)
	(segment
		(start 75.35672 -125.924564)
		(end 74.89317 -125.386846)
		(width 0.1651)
		(layer "In5.Cu")
		(net "P5E_PEX0_STN0_RX_DP<1>")
	)
	(segment
		(start 88.083898 -146.3929)
		(end 85.67166 -135.332724)
		(width 0.1651)
		(layer "In5.Cu")
		(net "P5E_PEX0_STN0_RX_DP<1>")
	)
	(segment
		(start 87.300816 -285.886398)
		(end 95.852234 -277.634192)
		(width 0.1651)
		(layer "In5.Cu")
		(net "P5E_PEX0_STN0_RX_DP<1>")
	)
	(segment
		(start 69.810884 -122.014234)
		(end 69.661278 -122.075702)
		(width 0.1651)
		(layer "In5.Cu")
		(net "P5E_PEX0_STN0_RX_DP<1>")
	)
	(segment
		(start 68.016628 -121.266966)
		(end 67.559428 -121.076466)
		(width 0.1651)
		(layer "In5.Cu")
		(net "P5E_PEX0_STN0_RX_DP<1>")
	)
	(segment
		(start 89.639902 -239.260888)
		(end 88.185244 -232.123996)
		(width 0.1651)
		(layer "In5.Cu")
		(net "P5E_PEX0_STN0_RX_DP<1>")
	)
	(segment
		(start 68.078096 -121.416572)
		(end 68.016628 -121.266712)
		(width 0.1651)
		(layer "In5.Cu")
		(net "P5E_PEX0_STN0_RX_DP<1>")
	)
	(segment
		(start 83.950048 -286.733996)
		(end 85.920326 -286.733996)
		(width 0.1651)
		(layer "In5.Cu")
		(net "P5E_PEX0_STN0_RX_DP<1>")
	)
	(segment
		(start 71.45528 -122.822716)
		(end 71.393812 -122.67311)
		(width 0.1651)
		(layer "In5.Cu")
		(net "P5E_PEX0_STN0_RX_DP<1>")
	)
	(segment
		(start 83.87588 -286.779716)
		(end 83.9216 -286.733996)
		(width 0.1143)
		(layer "In5.Cu")
		(net "P5E_PEX0_STN0_RX_DP<1>")
	)
	(segment
		(start 70.787006 -122.544586)
		(end 70.329552 -122.354086)
		(width 0.1651)
		(layer "In5.Cu")
		(net "P5E_PEX0_STN0_RX_DP<1>")
	)
	(segment
		(start 77.197712 -128.19507)
		(end 76.874116 -127.819658)
		(width 0.1651)
		(layer "In5.Cu")
		(net "P5E_PEX0_STN0_RX_DP<1>")
	)
	(segment
		(start 65.4939 -121.076466)
		(end 65.20307 -121.367296)
		(width 0.1651)
		(layer "In5.Cu")
		(net "P5E_PEX0_STN0_RX_DP<1>")
	)
	(segment
		(start 98.415094 -269.313406)
		(end 89.639902 -239.260888)
		(width 0.1651)
		(layer "In5.Cu")
		(net "P5E_PEX0_STN0_RX_DP<1>")
	)
	(segment
		(start 69.203824 -121.885202)
		(end 69.142356 -121.735596)
		(width 0.1651)
		(layer "In5.Cu")
		(net "P5E_PEX0_STN0_RX_DP<1>")
	)
	(segment
		(start 69.661278 -122.075702)
		(end 69.203824 -121.885202)
		(width 0.1651)
		(layer "In5.Cu")
		(net "P5E_PEX0_STN0_RX_DP<1>")
	)
	(segment
		(start 81.765394 -287.349946)
		(end 81.879694 -287.235646)
		(width 0.1143)
		(layer "In5.Cu")
		(net "P5E_PEX0_STN0_RX_DP<1>")
	)
	(segment
		(start 88.848438 -168.536366)
		(end 88.340438 -149.910546)
		(width 0.1651)
		(layer "In5.Cu")
		(net "P5E_PEX0_STN0_RX_DP<1>")
	)
	(segment
		(start 88.340438 -149.910546)
		(end 88.083898 -146.3929)
		(width 0.1651)
		(layer "In5.Cu")
		(net "P5E_PEX0_STN0_RX_DP<1>")
	)
	(segment
		(start 95.852234 -277.634192)
		(end 98.267266 -273.294602)
		(width 0.1651)
		(layer "In5.Cu")
		(net "P5E_PEX0_STN0_RX_DP<1>")
	)
	(segment
		(start 83.9216 -286.733996)
		(end 83.950048 -286.733996)
		(width 0.1143)
		(layer "In5.Cu")
		(net "P5E_PEX0_STN0_RX_DP<1>")
	)
	(segment
		(start 82.543142 -132.942584)
		(end 80.382364 -131.751578)
		(width 0.1651)
		(layer "In5.Cu")
		(net "P5E_PEX0_STN0_RX_DP<1>")
	)
	(segment
		(start 76.110846 -126.934722)
		(end 76.11999 -126.809246)
		(width 0.1651)
		(layer "In5.Cu")
		(net "P5E_PEX0_STN0_RX_DP<1>")
	)
	(segment
		(start 70.329552 -122.354086)
		(end 70.268084 -122.20448)
		(width 0.1651)
		(layer "In5.Cu")
		(net "P5E_PEX0_STN0_RX_DP<1>")
	)
	(segment
		(start 80.382364 -131.751578)
		(end 77.323188 -128.204214)
		(width 0.1651)
		(layer "In5.Cu")
		(net "P5E_PEX0_STN0_RX_DP<1>")
	)
	(segment
		(start 69.142356 -121.735596)
		(end 68.685156 -121.54535)
		(width 0.1651)
		(layer "In5.Cu")
		(net "P5E_PEX0_STN0_RX_DP<1>")
	)
	(segment
		(start 75.347576 -126.049786)
		(end 75.35672 -125.924564)
		(width 0.1651)
		(layer "In5.Cu")
		(net "P5E_PEX0_STN0_RX_DP<1>")
	)
	(segment
		(start 71.393812 -122.67311)
		(end 70.936612 -122.482864)
		(width 0.1651)
		(layer "In5.Cu")
		(net "P5E_PEX0_STN0_RX_DP<1>")
	)
	(segment
		(start 76.559918 -127.319278)
		(end 76.434442 -127.310134)
		(width 0.1651)
		(layer "In5.Cu")
		(net "P5E_PEX0_STN0_RX_DP<1>")
	)
	(segment
		(start 81.879694 -287.235646)
		(end 81.879694 -286.994854)
		(width 0.1143)
		(layer "In5.Cu")
		(net "P5E_PEX0_STN0_RX_DP<1>")
	)
	(segment
		(start 76.11999 -126.809246)
		(end 75.796648 -126.434342)
		(width 0.1651)
		(layer "In5.Cu")
		(net "P5E_PEX0_STN0_RX_DP<1>")
	)
	(segment
		(start 70.268084 -122.20448)
		(end 69.810884 -122.014234)
		(width 0.1651)
		(layer "In5.Cu")
		(net "P5E_PEX0_STN0_RX_DP<1>")
	)
	(segment
		(start 81.499964 -287.349946)
		(end 81.765394 -287.349946)
		(width 0.1143)
		(layer "In5.Cu")
		(net "P5E_PEX0_STN0_RX_DP<1>")
	)
	(segment
		(start 70.936612 -122.482864)
		(end 70.787006 -122.544586)
		(width 0.1651)
		(layer "In5.Cu")
		(net "P5E_PEX0_STN0_RX_DP<1>")
	)
	(segment
		(start 82.972148 -133.37159)
		(end 82.543142 -132.942584)
		(width 0.1651)
		(layer "In5.Cu")
		(net "P5E_PEX0_STN0_RX_DP<1>")
	)
	(segment
		(start 77.323188 -128.204214)
		(end 77.197712 -128.19507)
		(width 0.1651)
		(layer "In5.Cu")
		(net "P5E_PEX0_STN0_RX_DP<1>")
	)
	(segment
		(start 85.67166 -135.332724)
		(end 85.212682 -134.61873)
		(width 0.1651)
		(layer "In5.Cu")
		(net "P5E_PEX0_STN0_RX_DP<1>")
	)
	(segment
		(start 82.094832 -286.779716)
		(end 83.87588 -286.779716)
		(width 0.1143)
		(layer "In5.Cu")
		(net "P5E_PEX0_STN0_RX_DP<1>")
	)
	(segment
		(start 81.879694 -286.994854)
		(end 82.094832 -286.779716)
		(width 0.1143)
		(layer "In5.Cu")
		(net "P5E_PEX0_STN0_RX_DP<1>")
	)
	(segment
		(start 98.267266 -273.294602)
		(end 98.415094 -269.313406)
		(width 0.1651)
		(layer "In5.Cu")
		(net "P5E_PEX0_STN0_RX_DP<1>")
	)
	(segment
		(start 75.671426 -126.425198)
		(end 75.347576 -126.049786)
		(width 0.1651)
		(layer "In5.Cu")
		(net "P5E_PEX0_STN0_RX_DP<1>")
	)
	(segment
		(start 85.212682 -134.61873)
		(end 82.972148 -133.37159)
		(width 0.1651)
		(layer "In5.Cu")
		(net "P5E_PEX0_STN0_RX_DP<1>")
	)
	(segment
		(start 68.53555 -121.606818)
		(end 68.078096 -121.416572)
		(width 0.1651)
		(layer "In5.Cu")
		(net "P5E_PEX0_STN0_RX_DP<1>")
	)
	(segment
		(start 88.185244 -232.123996)
		(end 88.848438 -168.536366)
		(width 0.1651)
		(layer "In5.Cu")
		(net "P5E_PEX0_STN0_RX_DP<1>")
	)
	(segment
		(start 71.912734 -123.013216)
		(end 71.45528 -122.822716)
		(width 0.1651)
		(layer "In5.Cu")
		(net "P5E_PEX0_STN0_RX_DP<1>")
	)
	(segment
		(start 76.88326 -127.694182)
		(end 76.559918 -127.319278)
		(width 0.1651)
		(layer "In5.Cu")
		(net "P5E_PEX0_STN0_RX_DP<1>")
	)
	(segment
		(start 72.69734 -123.215908)
		(end 72.06234 -122.951494)
		(width 0.1651)
		(layer "In5.Cu")
		(net "P5E_PEX0_STN0_RX_DP<1>")
	)
	(segment
		(start 72.06234 -122.951494)
		(end 71.912734 -123.013216)
		(width 0.1651)
		(layer "In5.Cu")
		(net "P5E_PEX0_STN0_RX_DP<1>")
	)
	(segment
		(start 298.489878 -410.207968)
		(end 298.616878 -410.080968)
		(width 0.1651)
		(layer "In5.Cu")
		(net "P5E_PEX2_STN7_RX_DN<117>")
	)
	(segment
		(start 257.532124 -314.486798)
		(end 257.53187 -314.486798)
		(width 0.1651)
		(layer "In5.Cu")
		(net "P5E_PEX2_STN7_RX_DN<117>")
	)
	(segment
		(start 258.873244 -312.511186)
		(end 259.014468 -312.484262)
		(width 0.1651)
		(layer "In5.Cu")
		(net "P5E_PEX2_STN7_RX_DN<117>")
	)
	(segment
		(start 257.005836 -315.465206)
		(end 257.284474 -315.05525)
		(width 0.1651)
		(layer "In5.Cu")
		(net "P5E_PEX2_STN7_RX_DN<117>")
	)
	(segment
		(start 258.20243 -313.498992)
		(end 258.343654 -313.472068)
		(width 0.1651)
		(layer "In5.Cu")
		(net "P5E_PEX2_STN7_RX_DN<117>")
	)
	(segment
		(start 286.488886 -387.47827)
		(end 285.060644 -386.127244)
		(width 0.1651)
		(layer "In5.Cu")
		(net "P5E_PEX2_STN7_RX_DN<117>")
	)
	(segment
		(start 260.5532 -310.03748)
		(end 261.24408 -309.337456)
		(width 0.1651)
		(layer "In5.Cu")
		(net "P5E_PEX2_STN7_RX_DN<117>")
	)
	(segment
		(start 269.429484 -306.084478)
		(end 269.429484 -306.235608)
		(width 0.1143)
		(layer "In5.Cu")
		(net "P5E_PEX2_STN7_RX_DN<117>")
	)
	(segment
		(start 254.72644 -322.241926)
		(end 254.72644 -319.87617)
		(width 0.1651)
		(layer "In5.Cu")
		(net "P5E_PEX2_STN7_RX_DN<117>")
	)
	(segment
		(start 259.014468 -312.484262)
		(end 259.292852 -312.074052)
		(width 0.1651)
		(layer "In5.Cu")
		(net "P5E_PEX2_STN7_RX_DN<117>")
	)
	(segment
		(start 273.133312 -342.331548)
		(end 272.839434 -341.470996)
		(width 0.1651)
		(layer "In5.Cu")
		(net "P5E_PEX2_STN7_RX_DN<117>")
	)
	(segment
		(start 257.53187 -314.486798)
		(end 257.67284 -314.459874)
		(width 0.1651)
		(layer "In5.Cu")
		(net "P5E_PEX2_STN7_RX_DN<117>")
	)
	(segment
		(start 297.38955 -393.27328)
		(end 286.488886 -387.47827)
		(width 0.1651)
		(layer "In5.Cu")
		(net "P5E_PEX2_STN7_RX_DN<117>")
	)
	(segment
		(start 282.650438 -369.874038)
		(end 282.649168 -369.87353)
		(width 0.1651)
		(layer "In5.Cu")
		(net "P5E_PEX2_STN7_RX_DN<117>")
	)
	(segment
		(start 258.343654 -313.472068)
		(end 258.622038 -313.061858)
		(width 0.1651)
		(layer "In5.Cu")
		(net "P5E_PEX2_STN7_RX_DN<117>")
	)
	(segment
		(start 298.616878 -410.080968)
		(end 299.163994 -410.080968)
		(width 0.1651)
		(layer "In5.Cu")
		(net "P5E_PEX2_STN7_RX_DN<117>")
	)
	(segment
		(start 254.72644 -319.87617)
		(end 256.131822 -316.549024)
		(width 0.1651)
		(layer "In5.Cu")
		(net "P5E_PEX2_STN7_RX_DN<117>")
	)
	(segment
		(start 258.622038 -313.061858)
		(end 258.595114 -312.920888)
		(width 0.1651)
		(layer "In5.Cu")
		(net "P5E_PEX2_STN7_RX_DN<117>")
	)
	(segment
		(start 261.735062 -308.840124)
		(end 263.497314 -307.054758)
		(width 0.1651)
		(layer "In5.Cu")
		(net "P5E_PEX2_STN7_RX_DN<117>")
	)
	(segment
		(start 282.6512 -369.8748)
		(end 282.650438 -369.874038)
		(width 0.1651)
		(layer "In5.Cu")
		(net "P5E_PEX2_STN7_RX_DN<117>")
	)
	(segment
		(start 267.866368 -305.970178)
		(end 269.315184 -305.970178)
		(width 0.1143)
		(layer "In5.Cu")
		(net "P5E_PEX2_STN7_RX_DN<117>")
	)
	(segment
		(start 265.982196 -306.015898)
		(end 267.7922 -306.015898)
		(width 0.1651)
		(layer "In5.Cu")
		(net "P5E_PEX2_STN7_RX_DN<117>")
	)
	(segment
		(start 299.61586 -409.629102)
		(end 299.61586 -395.351)
		(width 0.1651)
		(layer "In5.Cu")
		(net "P5E_PEX2_STN7_RX_DN<117>")
	)
	(segment
		(start 273.346672 -358.45242)
		(end 273.133312 -357.852218)
		(width 0.1651)
		(layer "In5.Cu")
		(net "P5E_PEX2_STN7_RX_DN<117>")
	)
	(segment
		(start 299.61586 -395.351)
		(end 299.1104 -394.410946)
		(width 0.1651)
		(layer "In5.Cu")
		(net "P5E_PEX2_STN7_RX_DN<117>")
	)
	(segment
		(start 259.936742 -310.945276)
		(end 260.5532 -310.03748)
		(width 0.1651)
		(layer "In5.Cu")
		(net "P5E_PEX2_STN7_RX_DN<117>")
	)
	(segment
		(start 256.131822 -316.549024)
		(end 256.847086 -315.495686)
		(width 0.1651)
		(layer "In5.Cu")
		(net "P5E_PEX2_STN7_RX_DN<117>")
	)
	(segment
		(start 259.544058 -311.52338)
		(end 259.685282 -311.496456)
		(width 0.1651)
		(layer "In5.Cu")
		(net "P5E_PEX2_STN7_RX_DN<117>")
	)
	(segment
		(start 269.315184 -306.349908)
		(end 269.049754 -306.349908)
		(width 0.1143)
		(layer "In5.Cu")
		(net "P5E_PEX2_STN7_RX_DN<117>")
	)
	(segment
		(start 257.253994 -314.8965)
		(end 257.532124 -314.486798)
		(width 0.1651)
		(layer "In5.Cu")
		(net "P5E_PEX2_STN7_RX_DN<117>")
	)
	(segment
		(start 285.060644 -386.127244)
		(end 284.535626 -384.871722)
		(width 0.1651)
		(layer "In5.Cu")
		(net "P5E_PEX2_STN7_RX_DN<117>")
	)
	(segment
		(start 259.265928 -311.933336)
		(end 259.544312 -311.52338)
		(width 0.1651)
		(layer "In5.Cu")
		(net "P5E_PEX2_STN7_RX_DN<117>")
	)
	(segment
		(start 258.873498 -312.51144)
		(end 258.873244 -312.511186)
		(width 0.1651)
		(layer "In5.Cu")
		(net "P5E_PEX2_STN7_RX_DN<117>")
	)
	(segment
		(start 282.649168 -369.87353)
		(end 273.346672 -358.45242)
		(width 0.1651)
		(layer "In5.Cu")
		(net "P5E_PEX2_STN7_RX_DN<117>")
	)
	(segment
		(start 256.265172 -325.345806)
		(end 255.66878 -324.473316)
		(width 0.1651)
		(layer "In5.Cu")
		(net "P5E_PEX2_STN7_RX_DN<117>")
	)
	(segment
		(start 257.67284 -314.459874)
		(end 257.951478 -314.049664)
		(width 0.1651)
		(layer "In5.Cu")
		(net "P5E_PEX2_STN7_RX_DN<117>")
	)
	(segment
		(start 267.7922 -306.015898)
		(end 267.820648 -306.015898)
		(width 0.1143)
		(layer "In5.Cu")
		(net "P5E_PEX2_STN7_RX_DN<117>")
	)
	(segment
		(start 257.9243 -313.908694)
		(end 257.924554 -313.908948)
		(width 0.1651)
		(layer "In5.Cu")
		(net "P5E_PEX2_STN7_RX_DN<117>")
	)
	(segment
		(start 258.595114 -312.920888)
		(end 258.595368 -312.921142)
		(width 0.1651)
		(layer "In5.Cu")
		(net "P5E_PEX2_STN7_RX_DN<117>")
	)
	(segment
		(start 273.133312 -357.852218)
		(end 273.133312 -342.331548)
		(width 0.1651)
		(layer "In5.Cu")
		(net "P5E_PEX2_STN7_RX_DN<117>")
	)
	(segment
		(start 269.315184 -305.970178)
		(end 269.429484 -306.084478)
		(width 0.1143)
		(layer "In5.Cu")
		(net "P5E_PEX2_STN7_RX_DN<117>")
	)
	(segment
		(start 259.544312 -311.52338)
		(end 259.544058 -311.52338)
		(width 0.1651)
		(layer "In5.Cu")
		(net "P5E_PEX2_STN7_RX_DN<117>")
	)
	(segment
		(start 263.497314 -307.054758)
		(end 265.982196 -306.015898)
		(width 0.1651)
		(layer "In5.Cu")
		(net "P5E_PEX2_STN7_RX_DN<117>")
	)
	(segment
		(start 261.387844 -309.336694)
		(end 261.735824 -308.983888)
		(width 0.1651)
		(layer "In5.Cu")
		(net "P5E_PEX2_STN7_RX_DN<117>")
	)
	(segment
		(start 272.839434 -341.470996)
		(end 272.835878 -341.46744)
		(width 0.1651)
		(layer "In5.Cu")
		(net "P5E_PEX2_STN7_RX_DN<117>")
	)
	(segment
		(start 283.515054 -371.60454)
		(end 282.6512 -369.8748)
		(width 0.1651)
		(layer "In5.Cu")
		(net "P5E_PEX2_STN7_RX_DN<117>")
	)
	(segment
		(start 261.735824 -308.983888)
		(end 261.735062 -308.840124)
		(width 0.1651)
		(layer "In5.Cu")
		(net "P5E_PEX2_STN7_RX_DN<117>")
	)
	(segment
		(start 267.820648 -306.015898)
		(end 267.866368 -305.970178)
		(width 0.1143)
		(layer "In5.Cu")
		(net "P5E_PEX2_STN7_RX_DN<117>")
	)
	(segment
		(start 259.685282 -311.496456)
		(end 259.963666 -311.0865)
		(width 0.1651)
		(layer "In5.Cu")
		(net "P5E_PEX2_STN7_RX_DN<117>")
	)
	(segment
		(start 257.924554 -313.908948)
		(end 258.202938 -313.499246)
		(width 0.1651)
		(layer "In5.Cu")
		(net "P5E_PEX2_STN7_RX_DN<117>")
	)
	(segment
		(start 259.963666 -311.0865)
		(end 259.936742 -310.945276)
		(width 0.1651)
		(layer "In5.Cu")
		(net "P5E_PEX2_STN7_RX_DN<117>")
	)
	(segment
		(start 257.951478 -314.049664)
		(end 257.9243 -313.908694)
		(width 0.1651)
		(layer "In5.Cu")
		(net "P5E_PEX2_STN7_RX_DN<117>")
	)
	(segment
		(start 284.535626 -384.871722)
		(end 284.176216 -378.796296)
		(width 0.1651)
		(layer "In5.Cu")
		(net "P5E_PEX2_STN7_RX_DN<117>")
	)
	(segment
		(start 259.292852 -312.074052)
		(end 259.265928 -311.933336)
		(width 0.1651)
		(layer "In5.Cu")
		(net "P5E_PEX2_STN7_RX_DN<117>")
	)
	(segment
		(start 272.835878 -341.46744)
		(end 256.265172 -325.345806)
		(width 0.1651)
		(layer "In5.Cu")
		(net "P5E_PEX2_STN7_RX_DN<117>")
	)
	(segment
		(start 261.24408 -309.337456)
		(end 261.387844 -309.336694)
		(width 0.1651)
		(layer "In5.Cu")
		(net "P5E_PEX2_STN7_RX_DN<117>")
	)
	(segment
		(start 256.847086 -315.495686)
		(end 257.005836 -315.465206)
		(width 0.1651)
		(layer "In5.Cu")
		(net "P5E_PEX2_STN7_RX_DN<117>")
	)
	(segment
		(start 258.202938 -313.499246)
		(end 258.20243 -313.498992)
		(width 0.1651)
		(layer "In5.Cu")
		(net "P5E_PEX2_STN7_RX_DN<117>")
	)
	(segment
		(start 269.429484 -306.235608)
		(end 269.315184 -306.349908)
		(width 0.1143)
		(layer "In5.Cu")
		(net "P5E_PEX2_STN7_RX_DN<117>")
	)
	(segment
		(start 299.1104 -394.410946)
		(end 297.38955 -393.27328)
		(width 0.1651)
		(layer "In5.Cu")
		(net "P5E_PEX2_STN7_RX_DN<117>")
	)
	(segment
		(start 298.489878 -410.589984)
		(end 298.489878 -410.207968)
		(width 0.1651)
		(layer "In5.Cu")
		(net "P5E_PEX2_STN7_RX_DN<117>")
	)
	(segment
		(start 255.66878 -324.473316)
		(end 254.72644 -322.241926)
		(width 0.1651)
		(layer "In5.Cu")
		(net "P5E_PEX2_STN7_RX_DN<117>")
	)
	(segment
		(start 284.176216 -378.796296)
		(end 283.515054 -371.60454)
		(width 0.1651)
		(layer "In5.Cu")
		(net "P5E_PEX2_STN7_RX_DN<117>")
	)
	(segment
		(start 258.595368 -312.921142)
		(end 258.873498 -312.51144)
		(width 0.1651)
		(layer "In5.Cu")
		(net "P5E_PEX2_STN7_RX_DN<117>")
	)
	(segment
		(start 299.163994 -410.080968)
		(end 299.61586 -409.629102)
		(width 0.1651)
		(layer "In5.Cu")
		(net "P5E_PEX2_STN7_RX_DN<117>")
	)
	(segment
		(start 257.284474 -315.05525)
		(end 257.253994 -314.8965)
		(width 0.1651)
		(layer "In5.Cu")
		(net "P5E_PEX2_STN7_RX_DN<117>")
	)
	(segment
		(start 436.31358 -34.22142)
		(end 433.811426 -34.22142)
		(width 0.13462)
		(layer "F.Cu")
		(net "P5E_PEX3_STN2_RX_DP<35>")
	)
	(segment
		(start 436.964836 -34.390076)
		(end 436.482236 -34.390076)
		(width 0.13462)
		(layer "F.Cu")
		(net "P5E_PEX3_STN2_RX_DP<35>")
	)
	(segment
		(start 436.482236 -34.390076)
		(end 436.31358 -34.22142)
		(width 0.13462)
		(layer "F.Cu")
		(net "P5E_PEX3_STN2_RX_DP<35>")
	)
	(segment
		(start 433.811426 -34.22142)
		(end 433.510436 -34.52241)
		(width 0.13462)
		(layer "F.Cu")
		(net "P5E_PEX3_STN2_RX_DP<35>")
	)
	(segment
		(start 403.533864 -270.499332)
		(end 403.860762 -266.721844)
		(width 0.1651)
		(layer "In7.Cu")
		(net "P5E_PEX3_STN2_RX_DP<35>")
	)
	(segment
		(start 424.805348 -143.663162)
		(end 425.12107 -116.47424)
		(width 0.1651)
		(layer "In7.Cu")
		(net "P5E_PEX3_STN2_RX_DP<35>")
	)
	(segment
		(start 434.880512 -34.833306)
		(end 434.27904 -34.23158)
		(width 0.1651)
		(layer "In7.Cu")
		(net "P5E_PEX3_STN2_RX_DP<35>")
	)
	(segment
		(start 434.810916 -36.165536)
		(end 434.803804 -35.669982)
		(width 0.1651)
		(layer "In7.Cu")
		(net "P5E_PEX3_STN2_RX_DP<35>")
	)
	(segment
		(start 403.533864 -271.3736)
		(end 403.533864 -271.345152)
		(width 0.1143)
		(layer "In7.Cu")
		(net "P5E_PEX3_STN2_RX_DP<35>")
	)
	(segment
		(start 403.860762 -266.721844)
		(end 423.42816 -154.366976)
		(width 0.1651)
		(layer "In7.Cu")
		(net "P5E_PEX3_STN2_RX_DP<35>")
	)
	(segment
		(start 436.28818 -49.507648)
		(end 434.950362 -39.604696)
		(width 0.1651)
		(layer "In7.Cu")
		(net "P5E_PEX3_STN2_RX_DP<35>")
	)
	(segment
		(start 403.533864 -271.345152)
		(end 403.533864 -270.499332)
		(width 0.1651)
		(layer "In7.Cu")
		(net "P5E_PEX3_STN2_RX_DP<35>")
	)
	(segment
		(start 434.950362 -39.604696)
		(end 434.918358 -37.421312)
		(width 0.1651)
		(layer "In7.Cu")
		(net "P5E_PEX3_STN2_RX_DP<35>")
	)
	(segment
		(start 434.803804 -35.669982)
		(end 434.891434 -35.579812)
		(width 0.1651)
		(layer "In7.Cu")
		(net "P5E_PEX3_STN2_RX_DP<35>")
	)
	(segment
		(start 403.579584 -271.41932)
		(end 403.533864 -271.3736)
		(width 0.1143)
		(layer "In7.Cu")
		(net "P5E_PEX3_STN2_RX_DP<35>")
	)
	(segment
		(start 404.035514 -273.670014)
		(end 403.841966 -273.670014)
		(width 0.1143)
		(layer "In7.Cu")
		(net "P5E_PEX3_STN2_RX_DP<35>")
	)
	(segment
		(start 404.149814 -274.049744)
		(end 404.149814 -273.784314)
		(width 0.1143)
		(layer "In7.Cu")
		(net "P5E_PEX3_STN2_RX_DP<35>")
	)
	(segment
		(start 403.579584 -273.407632)
		(end 403.579584 -271.41932)
		(width 0.1143)
		(layer "In7.Cu")
		(net "P5E_PEX3_STN2_RX_DP<35>")
	)
	(segment
		(start 434.90134 -36.252912)
		(end 434.810916 -36.165536)
		(width 0.1651)
		(layer "In7.Cu")
		(net "P5E_PEX3_STN2_RX_DP<35>")
	)
	(segment
		(start 404.149814 -273.784314)
		(end 404.035514 -273.670014)
		(width 0.1143)
		(layer "In7.Cu")
		(net "P5E_PEX3_STN2_RX_DP<35>")
	)
	(segment
		(start 433.712366 -34.32048)
		(end 433.510436 -34.52241)
		(width 0.1651)
		(layer "In7.Cu")
		(net "P5E_PEX3_STN2_RX_DP<35>")
	)
	(segment
		(start 433.926996 -34.23158)
		(end 433.712366 -34.32048)
		(width 0.1651)
		(layer "In7.Cu")
		(net "P5E_PEX3_STN2_RX_DP<35>")
	)
	(segment
		(start 403.841966 -273.670014)
		(end 403.579584 -273.407632)
		(width 0.1143)
		(layer "In7.Cu")
		(net "P5E_PEX3_STN2_RX_DP<35>")
	)
	(segment
		(start 434.820822 -36.838128)
		(end 434.908452 -36.747958)
		(width 0.1651)
		(layer "In7.Cu")
		(net "P5E_PEX3_STN2_RX_DP<35>")
	)
	(segment
		(start 434.27904 -34.23158)
		(end 433.926996 -34.23158)
		(width 0.1651)
		(layer "In7.Cu")
		(net "P5E_PEX3_STN2_RX_DP<35>")
	)
	(segment
		(start 434.891434 -35.579812)
		(end 434.880512 -34.833306)
		(width 0.1651)
		(layer "In7.Cu")
		(net "P5E_PEX3_STN2_RX_DP<35>")
	)
	(segment
		(start 436.107332 -61.097668)
		(end 436.28818 -49.507648)
		(width 0.1651)
		(layer "In7.Cu")
		(net "P5E_PEX3_STN2_RX_DP<35>")
	)
	(segment
		(start 434.918612 -37.421312)
		(end 434.828188 -37.333682)
		(width 0.1651)
		(layer "In7.Cu")
		(net "P5E_PEX3_STN2_RX_DP<35>")
	)
	(segment
		(start 434.828188 -37.333682)
		(end 434.820822 -36.838128)
		(width 0.1651)
		(layer "In7.Cu")
		(net "P5E_PEX3_STN2_RX_DP<35>")
	)
	(segment
		(start 425.12107 -116.47424)
		(end 436.107332 -61.097668)
		(width 0.1651)
		(layer "In7.Cu")
		(net "P5E_PEX3_STN2_RX_DP<35>")
	)
	(segment
		(start 434.908452 -36.747958)
		(end 434.90134 -36.252912)
		(width 0.1651)
		(layer "In7.Cu")
		(net "P5E_PEX3_STN2_RX_DP<35>")
	)
	(segment
		(start 423.42816 -154.366976)
		(end 424.805348 -143.663162)
		(width 0.1651)
		(layer "In7.Cu")
		(net "P5E_PEX3_STN2_RX_DP<35>")
	)
	(segment
		(start 434.918358 -37.421312)
		(end 434.918612 -37.421312)
		(width 0.1651)
		(layer "In7.Cu")
		(net "P5E_PEX3_STN2_RX_DP<35>")
	)
	(segment
		(start 164.91585 -168.490392)
		(end 165.343332 -168.917874)
		(width 0.13208)
		(layer "F.Cu")
		(net "RST_HP_NIC2_N")
	)
	(segment
		(start 163.558982 -166.55288)
		(end 164.302186 -166.55288)
		(width 0.13208)
		(layer "F.Cu")
		(net "RST_HP_NIC2_N")
	)
	(segment
		(start 164.302186 -166.55288)
		(end 164.91585 -167.166544)
		(width 0.13208)
		(layer "F.Cu")
		(net "RST_HP_NIC2_N")
	)
	(segment
		(start 164.91585 -167.166544)
		(end 164.91585 -168.490392)
		(width 0.13208)
		(layer "F.Cu")
		(net "RST_HP_NIC2_N")
	)
	(segment
		(start 165.343332 -169.710862)
		(end 165.343332 -170.77944)
		(width 0.13208)
		(layer "F.Cu")
		(net "RST_HP_NIC2_N")
	)
	(segment
		(start 165.343332 -168.917874)
		(end 165.343332 -169.710862)
		(width 0.13208)
		(layer "F.Cu")
		(net "RST_HP_NIC2_N")
	)
	(via
		(at 165.343332 -169.710862)
		(size 0.508)
		(drill 0.254)
		(layers "F.Cu" "B.Cu")
		(net "RST_HP_NIC2_N")
	)
	(segment
		(start 16.475202 -25.031954)
		(end 17.926558 -25.031954)
		(width 0.381)
		(layer "F.Cu")
		(net "P3V3_SSD0")
	)
	(segment
		(start 7.371842 -24.807418)
		(end 6.753352 -24.807418)
		(width 0.4572)
		(layer "F.Cu")
		(net "P3V3_SSD0")
	)
	(segment
		(start 18.56994 -25.031954)
		(end 17.926558 -25.031954)
		(width 0.4572)
		(layer "F.Cu")
		(net "P3V3_SSD0")
	)
	(segment
		(start 1.599692 -25.602692)
		(end 2.032 -26.035)
		(width 0.508)
		(layer "F.Cu")
		(net "P3V3_SSD0")
	)
	(segment
		(start 8.179054 -59.978036)
		(end 8.179054 -60.633356)
		(width 0.381)
		(layer "F.Cu")
		(net "P3V3_SSD0")
	)
	(segment
		(start 2.032 -26.035)
		(end 1.578356 -26.488644)
		(width 0.381)
		(layer "F.Cu")
		(net "P3V3_SSD0")
	)
	(segment
		(start 8.85063 -73.475088)
		(end 8.85063 -74.106024)
		(width 0.254)
		(layer "F.Cu")
		(net "P3V3_SSD0")
	)
	(segment
		(start 4.647692 -25.334214)
		(end 4.647692 -25.943814)
		(width 0.508)
		(layer "F.Cu")
		(net "P3V3_SSD0")
	)
	(segment
		(start 2.47523 -69.182234)
		(end 1.787144 -69.182234)
		(width 0.381)
		(layer "F.Cu")
		(net "P3V3_SSD0")
	)
	(segment
		(start 1.599692 -25.334214)
		(end 1.599692 -25.602692)
		(width 0.508)
		(layer "F.Cu")
		(net "P3V3_SSD0")
	)
	(segment
		(start 19.47164 -25.742392)
		(end 19.47164 -26.360882)
		(width 0.4572)
		(layer "F.Cu")
		(net "P3V3_SSD0")
	)
	(segment
		(start 1.578356 -27.367738)
		(end 1.578356 -26.670254)
		(width 0.381)
		(layer "F.Cu")
		(net "P3V3_SSD0")
	)
	(segment
		(start 1.578356 -26.488644)
		(end 1.578356 -26.670254)
		(width 0.381)
		(layer "F.Cu")
		(net "P3V3_SSD0")
	)
	(segment
		(start 16.233394 -24.790146)
		(end 16.475202 -25.031954)
		(width 0.381)
		(layer "F.Cu")
		(net "P3V3_SSD0")
	)
	(segment
		(start 2.14884 -28.37434)
		(end 2.14884 -27.938222)
		(width 0.381)
		(layer "F.Cu")
		(net "P3V3_SSD0")
	)
	(segment
		(start 2.231644 -21.717762)
		(end 2.231644 -22.45995)
		(width 0.508)
		(layer "F.Cu")
		(net "P3V3_SSD0")
	)
	(segment
		(start 15.264892 -24.790146)
		(end 16.233394 -24.790146)
		(width 0.381)
		(layer "F.Cu")
		(net "P3V3_SSD0")
	)
	(segment
		(start 2.14884 -27.938222)
		(end 1.578356 -27.367738)
		(width 0.381)
		(layer "F.Cu")
		(net "P3V3_SSD0")
	)
	(via
		(at 6.964934 -52.528724)
		(size 0.508)
		(drill 0.254)
		(layers "F.Cu" "B.Cu")
		(net "P3V3_SSD0")
	)
	(via
		(at 6.494018 -49.574704)
		(size 0.508)
		(drill 0.254)
		(layers "F.Cu" "B.Cu")
		(net "P3V3_SSD0")
	)
	(via
		(at 1.787144 -69.182234)
		(size 0.508)
		(drill 0.254)
		(layers "F.Cu" "B.Cu")
		(net "P3V3_SSD0")
	)
	(via
		(at 8.27659 -50.608992)
		(size 0.508)
		(drill 0.254)
		(layers "F.Cu" "B.Cu")
		(net "P3V3_SSD0")
	)
	(via
		(at 2.231644 -22.45995)
		(size 0.508)
		(drill 0.254)
		(layers "F.Cu" "B.Cu")
		(net "P3V3_SSD0")
	)
	(via
		(at 4.647692 -25.943814)
		(size 0.508)
		(drill 0.254)
		(layers "F.Cu" "B.Cu")
		(net "P3V3_SSD0")
	)
	(via
		(at 8.27659 -51.320192)
		(size 0.508)
		(drill 0.254)
		(layers "F.Cu" "B.Cu")
		(net "P3V3_SSD0")
	)
	(via
		(at 18.56994 -25.031954)
		(size 0.508)
		(drill 0.254)
		(layers "F.Cu" "B.Cu")
		(net "P3V3_SSD0")
	)
	(via
		(at 5.82549 -40.404542)
		(size 0.508)
		(drill 0.254)
		(layers "F.Cu" "B.Cu")
		(net "P3V3_SSD0")
	)
	(via
		(at 8.399018 -49.574704)
		(size 0.508)
		(drill 0.254)
		(layers "F.Cu" "B.Cu")
		(net "P3V3_SSD0")
	)
	(via
		(at 7.51459 -50.608992)
		(size 0.508)
		(drill 0.254)
		(layers "F.Cu" "B.Cu")
		(net "P3V3_SSD0")
	)
	(via
		(at 8.85063 -74.106024)
		(size 0.508)
		(drill 0.254)
		(layers "F.Cu" "B.Cu")
		(net "P3V3_SSD0")
	)
	(via
		(at 2.032 -26.035)
		(size 0.508)
		(drill 0.254)
		(layers "F.Cu" "B.Cu")
		(net "P3V3_SSD0")
	)
	(via
		(at 7.599934 -52.528724)
		(size 0.508)
		(drill 0.254)
		(layers "F.Cu" "B.Cu")
		(net "P3V3_SSD0")
	)
	(via
		(at 6.514592 -53.469286)
		(size 0.508)
		(drill 0.254)
		(layers "F.Cu" "B.Cu")
		(net "P3V3_SSD0")
	)
	(via
		(at 6.753352 -24.807418)
		(size 0.508)
		(drill 0.254)
		(layers "F.Cu" "B.Cu")
		(net "P3V3_SSD0")
	)
	(via
		(at 5.82549 -41.166542)
		(size 0.508)
		(drill 0.254)
		(layers "F.Cu" "B.Cu")
		(net "P3V3_SSD0")
	)
	(via
		(at 7.149592 -53.469286)
		(size 0.508)
		(drill 0.254)
		(layers "F.Cu" "B.Cu")
		(net "P3V3_SSD0")
	)
	(via
		(at 7.129018 -49.574704)
		(size 0.508)
		(drill 0.254)
		(layers "F.Cu" "B.Cu")
		(net "P3V3_SSD0")
	)
	(via
		(at 7.764018 -49.574704)
		(size 0.508)
		(drill 0.254)
		(layers "F.Cu" "B.Cu")
		(net "P3V3_SSD0")
	)
	(via
		(at 8.179054 -60.633356)
		(size 0.508)
		(drill 0.254)
		(layers "F.Cu" "B.Cu")
		(net "P3V3_SSD0")
	)
	(via
		(at 19.47164 -26.360882)
		(size 0.508)
		(drill 0.254)
		(layers "F.Cu" "B.Cu")
		(net "P3V3_SSD0")
	)
	(via
		(at 7.51459 -51.243992)
		(size 0.508)
		(drill 0.254)
		(layers "F.Cu" "B.Cu")
		(net "P3V3_SSD0")
	)
	(segment
		(start 73.908666 -122.597926)
		(end 79.425038 -122.597926)
		(width 0.13462)
		(layer "F.Cu")
		(net "P5E_PEX0_STN0_TX_C_DN<2>")
	)
	(segment
		(start 73.745852 -122.435112)
		(end 73.908666 -122.597926)
		(width 0.13462)
		(layer "F.Cu")
		(net "P5E_PEX0_STN0_TX_C_DN<2>")
	)
	(segment
		(start 73.257664 -122.435112)
		(end 73.745852 -122.435112)
		(width 0.13462)
		(layer "F.Cu")
		(net "P5E_PEX0_STN0_TX_C_DN<2>")
	)
	(segment
		(start 79.425038 -122.597926)
		(end 79.752698 -122.270266)
		(width 0.13462)
		(layer "F.Cu")
		(net "P5E_PEX0_STN0_TX_C_DN<2>")
	)
	(segment
		(start 274.409662 -351.316798)
		(end 274.115022 -351.611438)
		(width 0.13462)
		(layer "F.Cu")
		(net "P5E_PEX2_STN7_TX_C_DP<115>")
	)
	(segment
		(start 274.089622 -350.365314)
		(end 274.409662 -350.685354)
		(width 0.13462)
		(layer "F.Cu")
		(net "P5E_PEX2_STN7_TX_C_DP<115>")
	)
	(segment
		(start 274.409662 -350.685354)
		(end 274.409662 -351.316798)
		(width 0.13462)
		(layer "F.Cu")
		(net "P5E_PEX2_STN7_TX_C_DP<115>")
	)
	(segment
		(start 294.248586 -394.418566)
		(end 294.122856 -394.418566)
		(width 0.1651)
		(layer "In7.Cu")
		(net "P5E_PEX2_STN7_TX_C_DP<115>")
	)
	(segment
		(start 283.097478 -387.46176)
		(end 282.367482 -385.676902)
		(width 0.1651)
		(layer "In7.Cu")
		(net "P5E_PEX2_STN7_TX_C_DP<115>")
	)
	(segment
		(start 294.598598 -394.768578)
		(end 294.248586 -394.418566)
		(width 0.1651)
		(layer "In7.Cu")
		(net "P5E_PEX2_STN7_TX_C_DP<115>")
	)
	(segment
		(start 289.665664 -391.397998)
		(end 289.547808 -391.441432)
		(width 0.1651)
		(layer "In7.Cu")
		(net "P5E_PEX2_STN7_TX_C_DP<115>")
	)
	(segment
		(start 272.851372 -358.075484)
		(end 272.851372 -353.910646)
		(width 0.1651)
		(layer "In7.Cu")
		(net "P5E_PEX2_STN7_TX_C_DP<115>")
	)
	(segment
		(start 290.726368 -391.888472)
		(end 290.608512 -391.931906)
		(width 0.1651)
		(layer "In7.Cu")
		(net "P5E_PEX2_STN7_TX_C_DP<115>")
	)
	(segment
		(start 294.598852 -394.769086)
		(end 294.598598 -394.768578)
		(width 0.1651)
		(layer "In7.Cu")
		(net "P5E_PEX2_STN7_TX_C_DP<115>")
	)
	(segment
		(start 290.158678 -391.72388)
		(end 290.115244 -391.60577)
		(width 0.1651)
		(layer "In7.Cu")
		(net "P5E_PEX2_STN7_TX_C_DP<115>")
	)
	(segment
		(start 280.434034 -374.347486)
		(end 272.851372 -358.075484)
		(width 0.1651)
		(layer "In7.Cu")
		(net "P5E_PEX2_STN7_TX_C_DP<115>")
	)
	(segment
		(start 289.097974 -391.233406)
		(end 289.05454 -391.115296)
		(width 0.1651)
		(layer "In7.Cu")
		(net "P5E_PEX2_STN7_TX_C_DP<115>")
	)
	(segment
		(start 292.946074 -393.241784)
		(end 292.946074 -393.116054)
		(width 0.1651)
		(layer "In7.Cu")
		(net "P5E_PEX2_STN7_TX_C_DP<115>")
	)
	(segment
		(start 290.115244 -391.60577)
		(end 289.665664 -391.397998)
		(width 0.1651)
		(layer "In7.Cu")
		(net "P5E_PEX2_STN7_TX_C_DP<115>")
	)
	(segment
		(start 291.175948 -392.096244)
		(end 290.726368 -391.888472)
		(width 0.1651)
		(layer "In7.Cu")
		(net "P5E_PEX2_STN7_TX_C_DP<115>")
	)
	(segment
		(start 293.772336 -394.068046)
		(end 293.772336 -393.942316)
		(width 0.1651)
		(layer "In7.Cu")
		(net "P5E_PEX2_STN7_TX_C_DP<115>")
	)
	(segment
		(start 292.57117 -392.74115)
		(end 291.787326 -392.378946)
		(width 0.1651)
		(layer "In7.Cu")
		(net "P5E_PEX2_STN7_TX_C_DP<115>")
	)
	(segment
		(start 272.851372 -353.910646)
		(end 274.405852 -352.356166)
		(width 0.1651)
		(layer "In7.Cu")
		(net "P5E_PEX2_STN7_TX_C_DP<115>")
	)
	(segment
		(start 290.608512 -391.931906)
		(end 290.158678 -391.72388)
		(width 0.1651)
		(layer "In7.Cu")
		(net "P5E_PEX2_STN7_TX_C_DP<115>")
	)
	(segment
		(start 289.05454 -391.115296)
		(end 289.05454 -391.11555)
		(width 0.1651)
		(layer "In7.Cu")
		(net "P5E_PEX2_STN7_TX_C_DP<115>")
	)
	(segment
		(start 282.367482 -385.676902)
		(end 280.434034 -374.347486)
		(width 0.1651)
		(layer "In7.Cu")
		(net "P5E_PEX2_STN7_TX_C_DP<115>")
	)
	(segment
		(start 291.219382 -392.2141)
		(end 291.175948 -392.096244)
		(width 0.1651)
		(layer "In7.Cu")
		(net "P5E_PEX2_STN7_TX_C_DP<115>")
	)
	(segment
		(start 274.405852 -351.902268)
		(end 274.115022 -351.611438)
		(width 0.1651)
		(layer "In7.Cu")
		(net "P5E_PEX2_STN7_TX_C_DP<115>")
	)
	(segment
		(start 284.930088 -389.208772)
		(end 283.097478 -387.46176)
		(width 0.1651)
		(layer "In7.Cu")
		(net "P5E_PEX2_STN7_TX_C_DP<115>")
	)
	(segment
		(start 294.089836 -401.49018)
		(end 294.089836 -401.872196)
		(width 0.1651)
		(layer "In7.Cu")
		(net "P5E_PEX2_STN7_TX_C_DP<115>")
	)
	(segment
		(start 294.216836 -401.999196)
		(end 294.647112 -401.999196)
		(width 0.1651)
		(layer "In7.Cu")
		(net "P5E_PEX2_STN7_TX_C_DP<115>")
	)
	(segment
		(start 294.089836 -401.872196)
		(end 294.216836 -401.999196)
		(width 0.1651)
		(layer "In7.Cu")
		(net "P5E_PEX2_STN7_TX_C_DP<115>")
	)
	(segment
		(start 294.933878 -401.71243)
		(end 294.933878 -395.704822)
		(width 0.1651)
		(layer "In7.Cu")
		(net "P5E_PEX2_STN7_TX_C_DP<115>")
	)
	(segment
		(start 294.933878 -395.704822)
		(end 294.598852 -394.769086)
		(width 0.1651)
		(layer "In7.Cu")
		(net "P5E_PEX2_STN7_TX_C_DP<115>")
	)
	(segment
		(start 289.05454 -391.11555)
		(end 284.930088 -389.208772)
		(width 0.1651)
		(layer "In7.Cu")
		(net "P5E_PEX2_STN7_TX_C_DP<115>")
	)
	(segment
		(start 293.296594 -393.592304)
		(end 292.946074 -393.241784)
		(width 0.1651)
		(layer "In7.Cu")
		(net "P5E_PEX2_STN7_TX_C_DP<115>")
	)
	(segment
		(start 294.122856 -394.418566)
		(end 293.772336 -394.068046)
		(width 0.1651)
		(layer "In7.Cu")
		(net "P5E_PEX2_STN7_TX_C_DP<115>")
	)
	(segment
		(start 274.405852 -352.356166)
		(end 274.405852 -351.902268)
		(width 0.1651)
		(layer "In7.Cu")
		(net "P5E_PEX2_STN7_TX_C_DP<115>")
	)
	(segment
		(start 293.772336 -393.942316)
		(end 293.422324 -393.592304)
		(width 0.1651)
		(layer "In7.Cu")
		(net "P5E_PEX2_STN7_TX_C_DP<115>")
	)
	(segment
		(start 291.669216 -392.422126)
		(end 291.219382 -392.2141)
		(width 0.1651)
		(layer "In7.Cu")
		(net "P5E_PEX2_STN7_TX_C_DP<115>")
	)
	(segment
		(start 294.647112 -401.999196)
		(end 294.933878 -401.71243)
		(width 0.1651)
		(layer "In7.Cu")
		(net "P5E_PEX2_STN7_TX_C_DP<115>")
	)
	(segment
		(start 291.787326 -392.378946)
		(end 291.669216 -392.422126)
		(width 0.1651)
		(layer "In7.Cu")
		(net "P5E_PEX2_STN7_TX_C_DP<115>")
	)
	(segment
		(start 293.422324 -393.592304)
		(end 293.296594 -393.592304)
		(width 0.1651)
		(layer "In7.Cu")
		(net "P5E_PEX2_STN7_TX_C_DP<115>")
	)
	(segment
		(start 292.946074 -393.116054)
		(end 292.57117 -392.74115)
		(width 0.1651)
		(layer "In7.Cu")
		(net "P5E_PEX2_STN7_TX_C_DP<115>")
	)
	(segment
		(start 289.547808 -391.441432)
		(end 289.097974 -391.233406)
		(width 0.1651)
		(layer "In7.Cu")
		(net "P5E_PEX2_STN7_TX_C_DP<115>")
	)
	(segment
		(start 391.825734 -31.825184)
		(end 391.507218 -32.1437)
		(width 0.13462)
		(layer "F.Cu")
		(net "P5E_PEX3_STN2_TX_C_DN<42>")
	)
	(segment
		(start 390.068054 -31.99003)
		(end 389.56488 -31.99003)
		(width 0.13462)
		(layer "F.Cu")
		(net "P5E_PEX3_STN2_TX_C_DN<42>")
	)
	(segment
		(start 390.221724 -32.1437)
		(end 390.068054 -31.99003)
		(width 0.13462)
		(layer "F.Cu")
		(net "P5E_PEX3_STN2_TX_C_DN<42>")
	)
	(segment
		(start 391.507218 -32.1437)
		(end 390.221724 -32.1437)
		(width 0.13462)
		(layer "F.Cu")
		(net "P5E_PEX3_STN2_TX_C_DN<42>")
	)
	(segment
		(start 305.457606 -101.84003)
		(end 306.734972 -101.84003)
		(width 0.13208)
		(layer "F.Cu")
		(net "NCSI_NIC5_RXD0")
	)
	(segment
		(start 306.734972 -101.84003)
		(end 307.383942 -102.489)
		(width 0.13208)
		(layer "F.Cu")
		(net "NCSI_NIC5_RXD0")
	)
	(via
		(at 307.383942 -102.489)
		(size 0.508)
		(drill 0.254)
		(layers "F.Cu" "B.Cu")
		(net "NCSI_NIC5_RXD0")
	)
	(segment
		(start 309.341774 -103.104696)
		(end 307.999638 -103.104696)
		(width 0.13208)
		(layer "B.Cu")
		(net "NCSI_NIC5_RXD0")
	)
	(segment
		(start 307.999638 -103.104696)
		(end 307.383942 -102.489)
		(width 0.13208)
		(layer "B.Cu")
		(net "NCSI_NIC5_RXD0")
	)
	(via
		(at 442.755274 -20.406106)
		(size 0.508)
		(drill 0.254)
		(layers "F.Cu" "B.Cu")
		(net "P12V_SSD15")
	)
	(via
		(at 444.988696 -42.670222)
		(size 0.508)
		(drill 0.254)
		(layers "F.Cu" "B.Cu")
		(net "P12V_SSD15")
	)
	(via
		(at 443.185296 -41.241472)
		(size 0.508)
		(drill 0.254)
		(layers "F.Cu" "B.Cu")
		(net "P12V_SSD15")
	)
	(via
		(at 444.988696 -42.009822)
		(size 0.508)
		(drill 0.254)
		(layers "F.Cu" "B.Cu")
		(net "P12V_SSD15")
	)
	(via
		(at 442.755274 -21.066506)
		(size 0.508)
		(drill 0.254)
		(layers "F.Cu" "B.Cu")
		(net "P12V_SSD15")
	)
	(via
		(at 443.262004 -43.041316)
		(size 0.6604)
		(drill 0.3302)
		(layers "F.Cu" "B.Cu")
		(net "P12V_SSD15")
	)
	(via
		(at 444.691008 -20.90039)
		(size 0.6604)
		(drill 0.3302)
		(layers "F.Cu" "B.Cu")
		(net "P12V_SSD15")
	)
	(via
		(at 446.596008 -20.90039)
		(size 0.6604)
		(drill 0.3302)
		(layers "F.Cu" "B.Cu")
		(net "P12V_SSD15")
	)
	(via
		(at 444.988696 -41.349422)
		(size 0.508)
		(drill 0.254)
		(layers "F.Cu" "B.Cu")
		(net "P12V_SSD15")
	)
	(via
		(at 442.755274 -21.726906)
		(size 0.508)
		(drill 0.254)
		(layers "F.Cu" "B.Cu")
		(net "P12V_SSD15")
	)
	(via
		(at 442.755274 -19.085306)
		(size 0.508)
		(drill 0.254)
		(layers "F.Cu" "B.Cu")
		(net "P12V_SSD15")
	)
	(via
		(at 442.755274 -19.745706)
		(size 0.508)
		(drill 0.254)
		(layers "F.Cu" "B.Cu")
		(net "P12V_SSD15")
	)
	(via
		(at 441.357004 -43.041316)
		(size 0.6604)
		(drill 0.3302)
		(layers "F.Cu" "B.Cu")
		(net "P12V_SSD15")
	)
	(via
		(at 444.988696 -43.305222)
		(size 0.508)
		(drill 0.254)
		(layers "F.Cu" "B.Cu")
		(net "P12V_SSD15")
	)
	(via
		(at 442.524896 -41.241472)
		(size 0.508)
		(drill 0.254)
		(layers "F.Cu" "B.Cu")
		(net "P12V_SSD15")
	)
	(segment
		(start 67.352164 -143.192246)
		(end 68.006722 -143.192246)
		(width 0.13462)
		(layer "F.Cu")
		(net "P5E_PEX0_STN0_RX_DP<8>")
	)
	(segment
		(start 68.169536 -143.35506)
		(end 68.65747 -143.35506)
		(width 0.13462)
		(layer "F.Cu")
		(net "P5E_PEX0_STN0_RX_DP<8>")
	)
	(segment
		(start 67.05727 -143.48714)
		(end 67.352164 -143.192246)
		(width 0.13462)
		(layer "F.Cu")
		(net "P5E_PEX0_STN0_RX_DP<8>")
	)
	(segment
		(start 68.006722 -143.192246)
		(end 68.169536 -143.35506)
		(width 0.13462)
		(layer "F.Cu")
		(net "P5E_PEX0_STN0_RX_DP<8>")
	)
	(segment
		(start 70.27545 -145.970752)
		(end 70.30974 -145.812764)
		(width 0.1651)
		(layer "In5.Cu")
		(net "P5E_PEX0_STN0_RX_DP<8>")
	)
	(segment
		(start 72.527414 -149.430486)
		(end 72.259698 -149.013418)
		(width 0.1651)
		(layer "In5.Cu")
		(net "P5E_PEX0_STN0_RX_DP<8>")
	)
	(segment
		(start 70.701154 -146.42211)
		(end 70.543166 -146.38782)
		(width 0.1651)
		(layer "In5.Cu")
		(net "P5E_PEX0_STN0_RX_DP<8>")
	)
	(segment
		(start 76.406756 -154.825954)
		(end 75.063604 -153.018744)
		(width 0.1651)
		(layer "In5.Cu")
		(net "P5E_PEX0_STN0_RX_DP<8>")
	)
	(segment
		(start 81.879694 -273.679412)
		(end 82.13598 -273.423126)
		(width 0.1143)
		(layer "In5.Cu")
		(net "P5E_PEX0_STN0_RX_DP<8>")
	)
	(segment
		(start 70.543166 -146.38782)
		(end 70.27545 -145.970752)
		(width 0.1651)
		(layer "In5.Cu")
		(net "P5E_PEX0_STN0_RX_DP<8>")
	)
	(segment
		(start 77.991716 -160.6423)
		(end 77.898244 -160.044384)
		(width 0.1651)
		(layer "In5.Cu")
		(net "P5E_PEX0_STN0_RX_DP<8>")
	)
	(segment
		(start 67.51066 -143.19631)
		(end 67.3481 -143.19631)
		(width 0.1651)
		(layer "In5.Cu")
		(net "P5E_PEX0_STN0_RX_DP<8>")
	)
	(segment
		(start 71.36003 -147.448016)
		(end 71.202042 -147.413726)
		(width 0.1651)
		(layer "In5.Cu")
		(net "P5E_PEX0_STN0_RX_DP<8>")
	)
	(segment
		(start 81.603596 -265.22934)
		(end 77.991716 -160.6423)
		(width 0.1651)
		(layer "In5.Cu")
		(net "P5E_PEX0_STN0_RX_DP<8>")
	)
	(segment
		(start 68.79463 -144.054322)
		(end 68.636134 -144.086072)
		(width 0.1651)
		(layer "In5.Cu")
		(net "P5E_PEX0_STN0_RX_DP<8>")
	)
	(segment
		(start 82.09026 -269.322042)
		(end 81.603596 -265.22934)
		(width 0.1651)
		(layer "In5.Cu")
		(net "P5E_PEX0_STN0_RX_DP<8>")
	)
	(segment
		(start 81.879694 -274.885404)
		(end 81.879694 -273.679412)
		(width 0.1143)
		(layer "In5.Cu")
		(net "P5E_PEX0_STN0_RX_DP<8>")
	)
	(segment
		(start 71.627492 -147.864576)
		(end 71.36003 -147.448016)
		(width 0.1651)
		(layer "In5.Cu")
		(net "P5E_PEX0_STN0_RX_DP<8>")
	)
	(segment
		(start 82.09026 -273.205194)
		(end 82.09026 -269.322042)
		(width 0.1651)
		(layer "In5.Cu")
		(net "P5E_PEX0_STN0_RX_DP<8>")
	)
	(segment
		(start 71.202042 -147.413726)
		(end 70.934326 -146.996658)
		(width 0.1651)
		(layer "In5.Cu")
		(net "P5E_PEX0_STN0_RX_DP<8>")
	)
	(segment
		(start 72.65035 -149.457156)
		(end 72.527414 -149.430486)
		(width 0.1651)
		(layer "In5.Cu")
		(net "P5E_PEX0_STN0_RX_DP<8>")
	)
	(segment
		(start 73.570592 -151.590248)
		(end 73.011792 -150.020528)
		(width 0.1651)
		(layer "In5.Cu")
		(net "P5E_PEX0_STN0_RX_DP<8>")
	)
	(segment
		(start 72.286368 -148.890482)
		(end 72.018906 -148.473922)
		(width 0.1651)
		(layer "In5.Cu")
		(net "P5E_PEX0_STN0_RX_DP<8>")
	)
	(segment
		(start 70.934326 -146.996658)
		(end 70.968616 -146.83867)
		(width 0.1651)
		(layer "In5.Cu")
		(net "P5E_PEX0_STN0_RX_DP<8>")
	)
	(segment
		(start 82.13598 -273.423126)
		(end 82.13598 -273.279362)
		(width 0.1143)
		(layer "In5.Cu")
		(net "P5E_PEX0_STN0_RX_DP<8>")
	)
	(segment
		(start 72.259698 -149.013418)
		(end 72.286368 -148.890482)
		(width 0.1651)
		(layer "In5.Cu")
		(net "P5E_PEX0_STN0_RX_DP<8>")
	)
	(segment
		(start 82.13598 -273.279362)
		(end 82.09026 -273.233642)
		(width 0.1143)
		(layer "In5.Cu")
		(net "P5E_PEX0_STN0_RX_DP<8>")
	)
	(segment
		(start 72.018906 -148.473922)
		(end 71.860918 -148.439632)
		(width 0.1651)
		(layer "In5.Cu")
		(net "P5E_PEX0_STN0_RX_DP<8>")
	)
	(segment
		(start 68.636134 -144.086072)
		(end 68.224146 -143.810482)
		(width 0.1651)
		(layer "In5.Cu")
		(net "P5E_PEX0_STN0_RX_DP<8>")
	)
	(segment
		(start 71.860918 -148.439632)
		(end 71.593202 -148.022564)
		(width 0.1651)
		(layer "In5.Cu")
		(net "P5E_PEX0_STN0_RX_DP<8>")
	)
	(segment
		(start 81.765394 -274.999704)
		(end 81.879694 -274.885404)
		(width 0.1143)
		(layer "In5.Cu")
		(net "P5E_PEX0_STN0_RX_DP<8>")
	)
	(segment
		(start 77.898244 -160.044384)
		(end 76.406756 -154.825954)
		(width 0.1651)
		(layer "In5.Cu")
		(net "P5E_PEX0_STN0_RX_DP<8>")
	)
	(segment
		(start 67.3481 -143.19631)
		(end 67.05727 -143.48714)
		(width 0.1651)
		(layer "In5.Cu")
		(net "P5E_PEX0_STN0_RX_DP<8>")
	)
	(segment
		(start 73.011792 -150.020528)
		(end 72.65035 -149.457156)
		(width 0.1651)
		(layer "In5.Cu")
		(net "P5E_PEX0_STN0_RX_DP<8>")
	)
	(segment
		(start 68.224146 -143.810482)
		(end 68.19265 -143.651986)
		(width 0.1651)
		(layer "In5.Cu")
		(net "P5E_PEX0_STN0_RX_DP<8>")
	)
	(segment
		(start 68.19265 -143.651986)
		(end 67.51066 -143.19631)
		(width 0.1651)
		(layer "In5.Cu")
		(net "P5E_PEX0_STN0_RX_DP<8>")
	)
	(segment
		(start 82.09026 -273.233642)
		(end 82.09026 -273.205194)
		(width 0.1143)
		(layer "In5.Cu")
		(net "P5E_PEX0_STN0_RX_DP<8>")
	)
	(segment
		(start 70.30974 -145.812764)
		(end 69.470778 -144.506188)
		(width 0.1651)
		(layer "In5.Cu")
		(net "P5E_PEX0_STN0_RX_DP<8>")
	)
	(segment
		(start 71.593202 -148.022564)
		(end 71.627492 -147.864576)
		(width 0.1651)
		(layer "In5.Cu")
		(net "P5E_PEX0_STN0_RX_DP<8>")
	)
	(segment
		(start 70.968616 -146.83867)
		(end 70.701154 -146.42211)
		(width 0.1651)
		(layer "In5.Cu")
		(net "P5E_PEX0_STN0_RX_DP<8>")
	)
	(segment
		(start 75.063604 -153.018744)
		(end 73.570592 -151.590248)
		(width 0.1651)
		(layer "In5.Cu")
		(net "P5E_PEX0_STN0_RX_DP<8>")
	)
	(segment
		(start 81.499964 -274.999704)
		(end 81.765394 -274.999704)
		(width 0.1143)
		(layer "In5.Cu")
		(net "P5E_PEX0_STN0_RX_DP<8>")
	)
	(segment
		(start 69.470778 -144.506188)
		(end 68.79463 -144.054322)
		(width 0.1651)
		(layer "In5.Cu")
		(net "P5E_PEX0_STN0_RX_DP<8>")
	)
	(segment
		(start 277.792942 -344.539062)
		(end 277.792942 -345.170506)
		(width 0.13462)
		(layer "F.Cu")
		(net "P5E_PEX2_STN7_TX_C_DN<116>")
	)
	(segment
		(start 277.792942 -345.170506)
		(end 278.087582 -345.465146)
		(width 0.13462)
		(layer "F.Cu")
		(net "P5E_PEX2_STN7_TX_C_DN<116>")
	)
	(segment
		(start 278.112982 -344.219022)
		(end 277.792942 -344.539062)
		(width 0.13462)
		(layer "F.Cu")
		(net "P5E_PEX2_STN7_TX_C_DN<116>")
	)
	(segment
		(start 281.7622 -374.0404)
		(end 276.242272 -358.0384)
		(width 0.1651)
		(layer "In7.Cu")
		(net "P5E_PEX2_STN7_TX_C_DN<116>")
	)
	(segment
		(start 285.608014 -388.077202)
		(end 284.216348 -386.746242)
		(width 0.1651)
		(layer "In7.Cu")
		(net "P5E_PEX2_STN7_TX_C_DN<116>")
	)
	(segment
		(start 297.415966 -400.729196)
		(end 297.415966 -395.318996)
		(width 0.1651)
		(layer "In7.Cu")
		(net "P5E_PEX2_STN7_TX_C_DN<116>")
	)
	(segment
		(start 277.796752 -345.755976)
		(end 278.087582 -345.465146)
		(width 0.1651)
		(layer "In7.Cu")
		(net "P5E_PEX2_STN7_TX_C_DN<116>")
	)
	(segment
		(start 284.216348 -386.746242)
		(end 283.593286 -385.26593)
		(width 0.1651)
		(layer "In7.Cu")
		(net "P5E_PEX2_STN7_TX_C_DN<116>")
	)
	(segment
		(start 277.796752 -346.326714)
		(end 277.796752 -345.755976)
		(width 0.1651)
		(layer "In7.Cu")
		(net "P5E_PEX2_STN7_TX_C_DN<116>")
	)
	(segment
		(start 276.242272 -347.881194)
		(end 277.796752 -346.326714)
		(width 0.1651)
		(layer "In7.Cu")
		(net "P5E_PEX2_STN7_TX_C_DN<116>")
	)
	(segment
		(start 296.289984 -401.690078)
		(end 296.289984 -401.308062)
		(width 0.1651)
		(layer "In7.Cu")
		(net "P5E_PEX2_STN7_TX_C_DN<116>")
	)
	(segment
		(start 296.289984 -401.308062)
		(end 296.416984 -401.181062)
		(width 0.1651)
		(layer "In7.Cu")
		(net "P5E_PEX2_STN7_TX_C_DN<116>")
	)
	(segment
		(start 296.9641 -401.181062)
		(end 297.415966 -400.729196)
		(width 0.1651)
		(layer "In7.Cu")
		(net "P5E_PEX2_STN7_TX_C_DN<116>")
	)
	(segment
		(start 293.203376 -391.522458)
		(end 285.608014 -388.077202)
		(width 0.1651)
		(layer "In7.Cu")
		(net "P5E_PEX2_STN7_TX_C_DN<116>")
	)
	(segment
		(start 276.242272 -358.0384)
		(end 276.242272 -347.881194)
		(width 0.1651)
		(layer "In7.Cu")
		(net "P5E_PEX2_STN7_TX_C_DN<116>")
	)
	(segment
		(start 283.593286 -385.26593)
		(end 281.7622 -374.0404)
		(width 0.1651)
		(layer "In7.Cu")
		(net "P5E_PEX2_STN7_TX_C_DN<116>")
	)
	(segment
		(start 295.982136 -393.400534)
		(end 293.203376 -391.522458)
		(width 0.1651)
		(layer "In7.Cu")
		(net "P5E_PEX2_STN7_TX_C_DN<116>")
	)
	(segment
		(start 297.231562 -394.514578)
		(end 295.982136 -393.400534)
		(width 0.1651)
		(layer "In7.Cu")
		(net "P5E_PEX2_STN7_TX_C_DN<116>")
	)
	(segment
		(start 296.416984 -401.181062)
		(end 296.9641 -401.181062)
		(width 0.1651)
		(layer "In7.Cu")
		(net "P5E_PEX2_STN7_TX_C_DN<116>")
	)
	(segment
		(start 297.415966 -395.318996)
		(end 297.231562 -394.514578)
		(width 0.1651)
		(layer "In7.Cu")
		(net "P5E_PEX2_STN7_TX_C_DN<116>")
	)
	(segment
		(start 409.658058 -28.829)
		(end 409.364688 -29.12237)
		(width 0.13462)
		(layer "F.Cu")
		(net "P5E_PEX3_STN2_RX_DP<36>")
	)
	(segment
		(start 410.964888 -28.99029)
		(end 410.485844 -28.99029)
		(width 0.13462)
		(layer "F.Cu")
		(net "P5E_PEX3_STN2_RX_DP<36>")
	)
	(segment
		(start 410.485844 -28.99029)
		(end 410.324554 -28.829)
		(width 0.13462)
		(layer "F.Cu")
		(net "P5E_PEX3_STN2_RX_DP<36>")
	)
	(segment
		(start 410.964888 -28.990036)
		(end 410.964888 -28.99029)
		(width 0.13462)
		(layer "F.Cu")
		(net "P5E_PEX3_STN2_RX_DP<36>")
	)
	(segment
		(start 410.324554 -28.829)
		(end 409.658058 -28.829)
		(width 0.13462)
		(layer "F.Cu")
		(net "P5E_PEX3_STN2_RX_DP<36>")
	)
	(segment
		(start 410.683202 -29.671518)
		(end 411.033722 -30.022038)
		(width 0.1651)
		(layer "In7.Cu")
		(net "P5E_PEX3_STN2_RX_DP<36>")
	)
	(segment
		(start 411.033722 -30.022038)
		(end 411.177486 -30.022038)
		(width 0.1651)
		(layer "In7.Cu")
		(net "P5E_PEX3_STN2_RX_DP<36>")
	)
	(segment
		(start 413.301434 -48.804068)
		(end 413.10179 -68.365624)
		(width 0.1651)
		(layer "In7.Cu")
		(net "P5E_PEX3_STN2_RX_DP<36>")
	)
	(segment
		(start 409.364688 -29.12237)
		(end 409.609798 -28.87726)
		(width 0.1651)
		(layer "In7.Cu")
		(net "P5E_PEX3_STN2_RX_DP<36>")
	)
	(segment
		(start 402.58365 -266.487402)
		(end 402.58365 -271.392904)
		(width 0.1651)
		(layer "In7.Cu")
		(net "P5E_PEX3_STN2_RX_DP<36>")
	)
	(segment
		(start 412.764224 -31.608776)
		(end 415.34842 -37.742622)
		(width 0.1651)
		(layer "In7.Cu")
		(net "P5E_PEX3_STN2_RX_DP<36>")
	)
	(segment
		(start 402.62937 -271.467072)
		(end 402.62937 -275.354796)
		(width 0.1143)
		(layer "In7.Cu")
		(net "P5E_PEX3_STN2_RX_DP<36>")
	)
	(segment
		(start 415.325052 -39.138098)
		(end 413.301434 -48.804068)
		(width 0.1651)
		(layer "In7.Cu")
		(net "P5E_PEX3_STN2_RX_DP<36>")
	)
	(segment
		(start 411.527498 -30.37205)
		(end 411.527498 -30.515814)
		(width 0.1651)
		(layer "In7.Cu")
		(net "P5E_PEX3_STN2_RX_DP<36>")
	)
	(segment
		(start 402.844762 -275.570188)
		(end 403.085554 -275.570188)
		(width 0.1143)
		(layer "In7.Cu")
		(net "P5E_PEX3_STN2_RX_DP<36>")
	)
	(segment
		(start 411.527498 -30.515814)
		(end 411.878018 -30.866334)
		(width 0.1651)
		(layer "In7.Cu")
		(net "P5E_PEX3_STN2_RX_DP<36>")
	)
	(segment
		(start 403.085554 -275.570188)
		(end 403.199854 -275.684488)
		(width 0.1143)
		(layer "In7.Cu")
		(net "P5E_PEX3_STN2_RX_DP<36>")
	)
	(segment
		(start 409.609798 -28.87726)
		(end 409.720034 -28.83154)
		(width 0.1651)
		(layer "In7.Cu")
		(net "P5E_PEX3_STN2_RX_DP<36>")
	)
	(segment
		(start 411.878018 -30.866334)
		(end 412.021782 -30.866334)
		(width 0.1651)
		(layer "In7.Cu")
		(net "P5E_PEX3_STN2_RX_DP<36>")
	)
	(segment
		(start 411.177486 -30.022038)
		(end 411.527498 -30.37205)
		(width 0.1651)
		(layer "In7.Cu")
		(net "P5E_PEX3_STN2_RX_DP<36>")
	)
	(segment
		(start 402.71827 -264.952226)
		(end 402.58365 -266.487402)
		(width 0.1651)
		(layer "In7.Cu")
		(net "P5E_PEX3_STN2_RX_DP<36>")
	)
	(segment
		(start 413.10179 -68.365624)
		(end 402.71827 -264.952226)
		(width 0.1651)
		(layer "In7.Cu")
		(net "P5E_PEX3_STN2_RX_DP<36>")
	)
	(segment
		(start 409.720034 -28.83154)
		(end 409.986988 -28.83154)
		(width 0.1651)
		(layer "In7.Cu")
		(net "P5E_PEX3_STN2_RX_DP<36>")
	)
	(segment
		(start 412.021782 -30.866334)
		(end 412.764224 -31.608776)
		(width 0.1651)
		(layer "In7.Cu")
		(net "P5E_PEX3_STN2_RX_DP<36>")
	)
	(segment
		(start 415.34842 -37.742622)
		(end 415.325052 -39.138098)
		(width 0.1651)
		(layer "In7.Cu")
		(net "P5E_PEX3_STN2_RX_DP<36>")
	)
	(segment
		(start 403.199854 -275.684488)
		(end 403.199854 -275.949918)
		(width 0.1143)
		(layer "In7.Cu")
		(net "P5E_PEX3_STN2_RX_DP<36>")
	)
	(segment
		(start 402.58365 -271.421352)
		(end 402.62937 -271.467072)
		(width 0.1143)
		(layer "In7.Cu")
		(net "P5E_PEX3_STN2_RX_DP<36>")
	)
	(segment
		(start 409.986988 -28.83154)
		(end 410.683202 -29.527754)
		(width 0.1651)
		(layer "In7.Cu")
		(net "P5E_PEX3_STN2_RX_DP<36>")
	)
	(segment
		(start 402.58365 -271.392904)
		(end 402.58365 -271.421352)
		(width 0.1143)
		(layer "In7.Cu")
		(net "P5E_PEX3_STN2_RX_DP<36>")
	)
	(segment
		(start 410.683202 -29.527754)
		(end 410.683202 -29.671518)
		(width 0.1651)
		(layer "In7.Cu")
		(net "P5E_PEX3_STN2_RX_DP<36>")
	)
	(segment
		(start 402.62937 -275.354796)
		(end 402.844762 -275.570188)
		(width 0.1143)
		(layer "In7.Cu")
		(net "P5E_PEX3_STN2_RX_DP<36>")
	)
	(segment
		(start 293.623492 -96.702372)
		(end 291.595048 -96.702372)
		(width 0.13208)
		(layer "F.Cu")
		(net "RST_NIC5_PERST2_R_N")
	)
	(segment
		(start 299.569124 -96.702372)
		(end 293.623492 -96.702372)
		(width 0.13208)
		(layer "F.Cu")
		(net "RST_NIC5_PERST2_R_N")
	)
	(segment
		(start 299.90669 -97.039938)
		(end 299.569124 -96.702372)
		(width 0.13208)
		(layer "F.Cu")
		(net "RST_NIC5_PERST2_R_N")
	)
	(segment
		(start 300.857412 -97.039938)
		(end 299.90669 -97.039938)
		(width 0.13208)
		(layer "F.Cu")
		(net "RST_NIC5_PERST2_R_N")
	)
	(via
		(at 293.623492 -96.702372)
		(size 0.762)
		(drill 0.381)
		(layers "F.Cu" "B.Cu")
		(net "RST_NIC5_PERST2_R_N")
	)
	(via
		(at 416.755326 -19.745706)
		(size 0.508)
		(drill 0.254)
		(layers "F.Cu" "B.Cu")
		(net "P12V_SSD14")
	)
	(via
		(at 418.263578 -19.5326)
		(size 0.6604)
		(drill 0.3302)
		(layers "F.Cu" "B.Cu")
		(net "P12V_SSD14")
	)
	(via
		(at 415.357056 -43.041316)
		(size 0.6604)
		(drill 0.3302)
		(layers "F.Cu" "B.Cu")
		(net "P12V_SSD14")
	)
	(via
		(at 418.988748 -42.009822)
		(size 0.508)
		(drill 0.254)
		(layers "F.Cu" "B.Cu")
		(net "P12V_SSD14")
	)
	(via
		(at 418.988748 -41.349422)
		(size 0.508)
		(drill 0.254)
		(layers "F.Cu" "B.Cu")
		(net "P12V_SSD14")
	)
	(via
		(at 418.988748 -43.305222)
		(size 0.508)
		(drill 0.254)
		(layers "F.Cu" "B.Cu")
		(net "P12V_SSD14")
	)
	(via
		(at 418.988748 -42.670222)
		(size 0.508)
		(drill 0.254)
		(layers "F.Cu" "B.Cu")
		(net "P12V_SSD14")
	)
	(via
		(at 420.168578 -19.5326)
		(size 0.6604)
		(drill 0.3302)
		(layers "F.Cu" "B.Cu")
		(net "P12V_SSD14")
	)
	(via
		(at 416.755326 -19.085306)
		(size 0.508)
		(drill 0.254)
		(layers "F.Cu" "B.Cu")
		(net "P12V_SSD14")
	)
	(via
		(at 417.185348 -41.241472)
		(size 0.508)
		(drill 0.254)
		(layers "F.Cu" "B.Cu")
		(net "P12V_SSD14")
	)
	(via
		(at 416.755326 -20.406106)
		(size 0.508)
		(drill 0.254)
		(layers "F.Cu" "B.Cu")
		(net "P12V_SSD14")
	)
	(via
		(at 416.524948 -41.241472)
		(size 0.508)
		(drill 0.254)
		(layers "F.Cu" "B.Cu")
		(net "P12V_SSD14")
	)
	(via
		(at 416.755326 -21.066506)
		(size 0.508)
		(drill 0.254)
		(layers "F.Cu" "B.Cu")
		(net "P12V_SSD14")
	)
	(via
		(at 417.262056 -43.041316)
		(size 0.6604)
		(drill 0.3302)
		(layers "F.Cu" "B.Cu")
		(net "P12V_SSD14")
	)
	(via
		(at 416.755326 -21.726906)
		(size 0.508)
		(drill 0.254)
		(layers "F.Cu" "B.Cu")
		(net "P12V_SSD14")
	)
	(segment
		(start 73.90892 -153.717752)
		(end 79.425292 -153.717752)
		(width 0.13462)
		(layer "F.Cu")
		(net "P5E_PEX0_STN0_TX_C_DP<14>")
	)
	(segment
		(start 79.425292 -153.717752)
		(end 79.752698 -153.390346)
		(width 0.13462)
		(layer "F.Cu")
		(net "P5E_PEX0_STN0_TX_C_DP<14>")
	)
	(segment
		(start 73.257664 -153.554938)
		(end 73.746106 -153.554938)
		(width 0.13462)
		(layer "F.Cu")
		(net "P5E_PEX0_STN0_TX_C_DP<14>")
	)
	(segment
		(start 73.746106 -153.554938)
		(end 73.90892 -153.717752)
		(width 0.13462)
		(layer "F.Cu")
		(net "P5E_PEX0_STN0_TX_C_DP<14>")
	)
	(segment
		(start 262.632952 -310.736996)
		(end 262.958834 -310.363362)
		(width 0.1651)
		(layer "In5.Cu")
		(net "P5E_PEX2_STN7_RX_DN<118>")
	)
	(segment
		(start 301.815754 -408.529282)
		(end 301.815754 -394.8176)
		(width 0.1651)
		(layer "In5.Cu")
		(net "P5E_PEX2_STN7_RX_DN<118>")
	)
	(segment
		(start 262.174228 -311.263284)
		(end 262.164322 -311.119774)
		(width 0.1651)
		(layer "In5.Cu")
		(net "P5E_PEX2_STN7_RX_DN<118>")
	)
	(segment
		(start 298.0944 -392.0998)
		(end 287.0962 -386.715)
		(width 0.1651)
		(layer "In5.Cu")
		(net "P5E_PEX2_STN7_RX_DN<118>")
	)
	(segment
		(start 256.54889 -324.02653)
		(end 255.69418 -321.963288)
		(width 0.1651)
		(layer "In5.Cu")
		(net "P5E_PEX2_STN7_RX_DN<118>")
	)
	(segment
		(start 276.393402 -358.454198)
		(end 276.242272 -357.95204)
		(width 0.1651)
		(layer "In5.Cu")
		(net "P5E_PEX2_STN7_RX_DN<118>")
	)
	(segment
		(start 262.489696 -310.746648)
		(end 262.632952 -310.736996)
		(width 0.1651)
		(layer "In5.Cu")
		(net "P5E_PEX2_STN7_RX_DN<118>")
	)
	(segment
		(start 257.048508 -324.725284)
		(end 256.54889 -324.02653)
		(width 0.1651)
		(layer "In5.Cu")
		(net "P5E_PEX2_STN7_RX_DN<118>")
	)
	(segment
		(start 261.848346 -311.636664)
		(end 262.174228 -311.263284)
		(width 0.1651)
		(layer "In5.Cu")
		(net "P5E_PEX2_STN7_RX_DN<118>")
	)
	(segment
		(start 261.70509 -311.64657)
		(end 261.848346 -311.636664)
		(width 0.1651)
		(layer "In5.Cu")
		(net "P5E_PEX2_STN7_RX_DN<118>")
	)
	(segment
		(start 266.674346 -306.965858)
		(end 267.7922 -306.965858)
		(width 0.1651)
		(layer "In5.Cu")
		(net "P5E_PEX2_STN7_RX_DN<118>")
	)
	(segment
		(start 271.215358 -307.299868)
		(end 270.949928 -307.299868)
		(width 0.1143)
		(layer "In5.Cu")
		(net "P5E_PEX2_STN7_RX_DN<118>")
	)
	(segment
		(start 258.345178 -315.49975)
		(end 258.670552 -315.126624)
		(width 0.1651)
		(layer "In5.Cu")
		(net "P5E_PEX2_STN7_RX_DN<118>")
	)
	(segment
		(start 287.0962 -386.715)
		(end 285.850838 -385.496562)
		(width 0.1651)
		(layer "In5.Cu")
		(net "P5E_PEX2_STN7_RX_DN<118>")
	)
	(segment
		(start 262.958834 -310.363362)
		(end 262.948928 -310.220106)
		(width 0.1651)
		(layer "In5.Cu")
		(net "P5E_PEX2_STN7_RX_DN<118>")
	)
	(segment
		(start 285.213552 -378.679202)
		(end 284.553152 -371.41277)
		(width 0.1651)
		(layer "In5.Cu")
		(net "P5E_PEX2_STN7_RX_DN<118>")
	)
	(segment
		(start 257.032506 -317.004954)
		(end 257.885692 -316.026546)
		(width 0.1651)
		(layer "In5.Cu")
		(net "P5E_PEX2_STN7_RX_DN<118>")
	)
	(segment
		(start 300.689772 -409.108148)
		(end 300.816772 -408.981148)
		(width 0.1651)
		(layer "In5.Cu")
		(net "P5E_PEX2_STN7_RX_DN<118>")
	)
	(segment
		(start 258.813808 -315.116718)
		(end 259.13969 -314.743084)
		(width 0.1651)
		(layer "In5.Cu")
		(net "P5E_PEX2_STN7_RX_DN<118>")
	)
	(segment
		(start 259.13969 -314.743084)
		(end 259.129784 -314.599828)
		(width 0.1651)
		(layer "In5.Cu")
		(net "P5E_PEX2_STN7_RX_DN<118>")
	)
	(segment
		(start 257.885692 -316.026546)
		(end 258.029202 -316.01664)
		(width 0.1651)
		(layer "In5.Cu")
		(net "P5E_PEX2_STN7_RX_DN<118>")
	)
	(segment
		(start 265.20267 -307.635402)
		(end 266.674346 -306.965858)
		(width 0.1651)
		(layer "In5.Cu")
		(net "P5E_PEX2_STN7_RX_DN<118>")
	)
	(segment
		(start 255.69418 -321.963288)
		(end 255.69418 -320.326004)
		(width 0.1651)
		(layer "In5.Cu")
		(net "P5E_PEX2_STN7_RX_DN<118>")
	)
	(segment
		(start 262.164322 -311.119774)
		(end 262.489696 -310.746648)
		(width 0.1651)
		(layer "In5.Cu")
		(net "P5E_PEX2_STN7_RX_DN<118>")
	)
	(segment
		(start 267.820648 -306.965858)
		(end 267.866368 -306.920138)
		(width 0.1143)
		(layer "In5.Cu")
		(net "P5E_PEX2_STN7_RX_DN<118>")
	)
	(segment
		(start 283.627322 -369.393978)
		(end 276.393402 -358.454198)
		(width 0.1651)
		(layer "In5.Cu")
		(net "P5E_PEX2_STN7_RX_DN<118>")
	)
	(segment
		(start 271.215358 -306.920138)
		(end 271.329658 -307.034438)
		(width 0.1143)
		(layer "In5.Cu")
		(net "P5E_PEX2_STN7_RX_DN<118>")
	)
	(segment
		(start 300.689772 -409.490164)
		(end 300.689772 -409.108148)
		(width 0.1651)
		(layer "In5.Cu")
		(net "P5E_PEX2_STN7_RX_DN<118>")
	)
	(segment
		(start 285.494222 -384.627882)
		(end 285.213552 -378.679202)
		(width 0.1651)
		(layer "In5.Cu")
		(net "P5E_PEX2_STN7_RX_DN<118>")
	)
	(segment
		(start 301.363888 -408.981148)
		(end 301.815754 -408.529282)
		(width 0.1651)
		(layer "In5.Cu")
		(net "P5E_PEX2_STN7_RX_DN<118>")
	)
	(segment
		(start 260.920484 -312.546492)
		(end 261.06374 -312.536586)
		(width 0.1651)
		(layer "In5.Cu")
		(net "P5E_PEX2_STN7_RX_DN<118>")
	)
	(segment
		(start 276.242272 -357.95204)
		(end 276.242272 -342.059768)
		(width 0.1651)
		(layer "In5.Cu")
		(net "P5E_PEX2_STN7_RX_DN<118>")
	)
	(segment
		(start 255.69418 -320.326004)
		(end 257.032506 -317.004954)
		(width 0.1651)
		(layer "In5.Cu")
		(net "P5E_PEX2_STN7_RX_DN<118>")
	)
	(segment
		(start 262.948928 -310.220106)
		(end 265.20267 -307.635402)
		(width 0.1651)
		(layer "In5.Cu")
		(net "P5E_PEX2_STN7_RX_DN<118>")
	)
	(segment
		(start 259.129784 -314.599828)
		(end 260.920484 -312.546492)
		(width 0.1651)
		(layer "In5.Cu")
		(net "P5E_PEX2_STN7_RX_DN<118>")
	)
	(segment
		(start 258.029202 -316.01664)
		(end 258.35483 -315.64326)
		(width 0.1651)
		(layer "In5.Cu")
		(net "P5E_PEX2_STN7_RX_DN<118>")
	)
	(segment
		(start 300.816772 -408.981148)
		(end 301.363888 -408.981148)
		(width 0.1651)
		(layer "In5.Cu")
		(net "P5E_PEX2_STN7_RX_DN<118>")
	)
	(segment
		(start 301.815754 -394.8176)
		(end 301.244 -394.208)
		(width 0.1651)
		(layer "In5.Cu")
		(net "P5E_PEX2_STN7_RX_DN<118>")
	)
	(segment
		(start 267.7922 -306.965858)
		(end 267.820648 -306.965858)
		(width 0.1143)
		(layer "In5.Cu")
		(net "P5E_PEX2_STN7_RX_DN<118>")
	)
	(segment
		(start 258.670552 -315.126624)
		(end 258.813808 -315.116718)
		(width 0.1651)
		(layer "In5.Cu")
		(net "P5E_PEX2_STN7_RX_DN<118>")
	)
	(segment
		(start 267.866368 -306.920138)
		(end 271.215358 -306.920138)
		(width 0.1143)
		(layer "In5.Cu")
		(net "P5E_PEX2_STN7_RX_DN<118>")
	)
	(segment
		(start 285.850838 -385.496562)
		(end 285.494222 -384.627882)
		(width 0.1651)
		(layer "In5.Cu")
		(net "P5E_PEX2_STN7_RX_DN<118>")
	)
	(segment
		(start 301.244 -394.208)
		(end 298.0944 -392.0998)
		(width 0.1651)
		(layer "In5.Cu")
		(net "P5E_PEX2_STN7_RX_DN<118>")
	)
	(segment
		(start 261.06374 -312.536586)
		(end 261.389368 -312.163206)
		(width 0.1651)
		(layer "In5.Cu")
		(net "P5E_PEX2_STN7_RX_DN<118>")
	)
	(segment
		(start 271.329658 -307.034438)
		(end 271.329658 -307.185568)
		(width 0.1143)
		(layer "In5.Cu")
		(net "P5E_PEX2_STN7_RX_DN<118>")
	)
	(segment
		(start 258.35483 -315.64326)
		(end 258.345178 -315.49975)
		(width 0.1651)
		(layer "In5.Cu")
		(net "P5E_PEX2_STN7_RX_DN<118>")
	)
	(segment
		(start 276.242272 -342.059768)
		(end 275.692616 -341.136986)
		(width 0.1651)
		(layer "In5.Cu")
		(net "P5E_PEX2_STN7_RX_DN<118>")
	)
	(segment
		(start 271.329658 -307.185568)
		(end 271.215358 -307.299868)
		(width 0.1143)
		(layer "In5.Cu")
		(net "P5E_PEX2_STN7_RX_DN<118>")
	)
	(segment
		(start 261.379716 -312.019696)
		(end 261.70509 -311.64657)
		(width 0.1651)
		(layer "In5.Cu")
		(net "P5E_PEX2_STN7_RX_DN<118>")
	)
	(segment
		(start 261.389368 -312.163206)
		(end 261.379716 -312.019696)
		(width 0.1651)
		(layer "In5.Cu")
		(net "P5E_PEX2_STN7_RX_DN<118>")
	)
	(segment
		(start 275.692616 -341.136986)
		(end 257.048508 -324.725284)
		(width 0.1651)
		(layer "In5.Cu")
		(net "P5E_PEX2_STN7_RX_DN<118>")
	)
	(segment
		(start 284.553152 -371.41277)
		(end 283.627322 -369.393978)
		(width 0.1651)
		(layer "In5.Cu")
		(net "P5E_PEX2_STN7_RX_DN<118>")
	)
	(segment
		(start 390.223248 -30.34538)
		(end 390.068054 -30.190186)
		(width 0.13462)
		(layer "F.Cu")
		(net "P5E_PEX3_STN2_TX_C_DN<41>")
	)
	(segment
		(start 390.068054 -30.190186)
		(end 389.56488 -30.190186)
		(width 0.13462)
		(layer "F.Cu")
		(net "P5E_PEX3_STN2_TX_C_DN<41>")
	)
	(segment
		(start 394.467842 -30.03169)
		(end 394.154152 -30.34538)
		(width 0.13462)
		(layer "F.Cu")
		(net "P5E_PEX3_STN2_TX_C_DN<41>")
	)
	(segment
		(start 394.154152 -30.34538)
		(end 390.223248 -30.34538)
		(width 0.13462)
		(layer "F.Cu")
		(net "P5E_PEX3_STN2_TX_C_DN<41>")
	)
	(segment
		(start 305.457606 -100.039932)
		(end 306.458874 -100.039932)
		(width 0.13208)
		(layer "F.Cu")
		(net "NIC5_CLK")
	)
	(via
		(at 306.458874 -100.039932)
		(size 0.508)
		(drill 0.254)
		(layers "F.Cu" "B.Cu")
		(net "NIC5_CLK")
	)
	(segment
		(start 308.33949 -100.039932)
		(end 306.458874 -100.039932)
		(width 0.13208)
		(layer "B.Cu")
		(net "NIC5_CLK")
	)
	(segment
		(start 309.341774 -99.037648)
		(end 308.33949 -100.039932)
		(width 0.13208)
		(layer "B.Cu")
		(net "NIC5_CLK")
	)
	(via
		(at 392.9888 -43.305222)
		(size 0.508)
		(drill 0.254)
		(layers "F.Cu" "B.Cu")
		(net "P12V_SSD13")
	)
	(via
		(at 390.755378 -20.406106)
		(size 0.508)
		(drill 0.254)
		(layers "F.Cu" "B.Cu")
		(net "P12V_SSD13")
	)
	(via
		(at 390.525 -41.241472)
		(size 0.508)
		(drill 0.254)
		(layers "F.Cu" "B.Cu")
		(net "P12V_SSD13")
	)
	(via
		(at 390.755378 -21.726906)
		(size 0.508)
		(drill 0.254)
		(layers "F.Cu" "B.Cu")
		(net "P12V_SSD13")
	)
	(via
		(at 392.9888 -41.349422)
		(size 0.508)
		(drill 0.254)
		(layers "F.Cu" "B.Cu")
		(net "P12V_SSD13")
	)
	(via
		(at 392.9888 -42.009822)
		(size 0.508)
		(drill 0.254)
		(layers "F.Cu" "B.Cu")
		(net "P12V_SSD13")
	)
	(via
		(at 391.262108 -43.041316)
		(size 0.6604)
		(drill 0.3302)
		(layers "F.Cu" "B.Cu")
		(net "P12V_SSD13")
	)
	(via
		(at 390.755378 -21.066506)
		(size 0.508)
		(drill 0.254)
		(layers "F.Cu" "B.Cu")
		(net "P12V_SSD13")
	)
	(via
		(at 391.1854 -41.241472)
		(size 0.508)
		(drill 0.254)
		(layers "F.Cu" "B.Cu")
		(net "P12V_SSD13")
	)
	(via
		(at 394.339572 -19.532346)
		(size 0.6604)
		(drill 0.3302)
		(layers "F.Cu" "B.Cu")
		(net "P12V_SSD13")
	)
	(via
		(at 392.9888 -42.670222)
		(size 0.508)
		(drill 0.254)
		(layers "F.Cu" "B.Cu")
		(net "P12V_SSD13")
	)
	(via
		(at 392.434572 -19.532346)
		(size 0.6604)
		(drill 0.3302)
		(layers "F.Cu" "B.Cu")
		(net "P12V_SSD13")
	)
	(via
		(at 390.755378 -19.085306)
		(size 0.508)
		(drill 0.254)
		(layers "F.Cu" "B.Cu")
		(net "P12V_SSD13")
	)
	(via
		(at 390.755378 -19.745706)
		(size 0.508)
		(drill 0.254)
		(layers "F.Cu" "B.Cu")
		(net "P12V_SSD13")
	)
	(via
		(at 389.357108 -43.041316)
		(size 0.6604)
		(drill 0.3302)
		(layers "F.Cu" "B.Cu")
		(net "P12V_SSD13")
	)
	(segment
		(start 73.257664 -149.954996)
		(end 73.745852 -149.954996)
		(width 0.13462)
		(layer "F.Cu")
		(net "P5E_PEX0_STN0_TX_C_DP<12>")
	)
	(segment
		(start 73.908666 -150.11781)
		(end 79.425038 -150.11781)
		(width 0.13462)
		(layer "F.Cu")
		(net "P5E_PEX0_STN0_TX_C_DP<12>")
	)
	(segment
		(start 79.425038 -150.11781)
		(end 79.752698 -149.79015)
		(width 0.13462)
		(layer "F.Cu")
		(net "P5E_PEX0_STN0_TX_C_DP<12>")
	)
	(segment
		(start 73.745852 -149.954996)
		(end 73.908666 -150.11781)
		(width 0.13462)
		(layer "F.Cu")
		(net "P5E_PEX0_STN0_TX_C_DP<12>")
	)
	(segment
		(start 394.467842 -33.631886)
		(end 394.147548 -33.95218)
		(width 0.13462)
		(layer "F.Cu")
		(net "P5E_PEX3_STN2_TX_C_DN<43>")
	)
	(segment
		(start 390.233916 -33.95218)
		(end 390.071864 -33.790128)
		(width 0.13462)
		(layer "F.Cu")
		(net "P5E_PEX3_STN2_TX_C_DN<43>")
	)
	(segment
		(start 394.147548 -33.95218)
		(end 390.233916 -33.95218)
		(width 0.13462)
		(layer "F.Cu")
		(net "P5E_PEX3_STN2_TX_C_DN<43>")
	)
	(segment
		(start 390.071864 -33.790128)
		(end 389.56488 -33.790128)
		(width 0.13462)
		(layer "F.Cu")
		(net "P5E_PEX3_STN2_TX_C_DN<43>")
	)
	(segment
		(start 296.070782 -138.864848)
		(end 296.070782 -137.848848)
		(width 0.13208)
		(layer "F.Cu")
		(net "PRSNTB1_NIC5_N")
	)
	(segment
		(start 296.070782 -137.848848)
		(end 297.247056 -137.848848)
		(width 0.13208)
		(layer "F.Cu")
		(net "PRSNTB1_NIC5_N")
	)
	(segment
		(start 298.678854 -137.24509)
		(end 300.857412 -137.24509)
		(width 0.13208)
		(layer "F.Cu")
		(net "PRSNTB1_NIC5_N")
	)
	(segment
		(start 297.247056 -137.848848)
		(end 298.075096 -137.848848)
		(width 0.13208)
		(layer "F.Cu")
		(net "PRSNTB1_NIC5_N")
	)
	(segment
		(start 298.075096 -137.848848)
		(end 298.678854 -137.24509)
		(width 0.13208)
		(layer "F.Cu")
		(net "PRSNTB1_NIC5_N")
	)
	(via
		(at 297.247056 -137.848848)
		(size 0.762)
		(drill 0.381)
		(layers "F.Cu" "B.Cu")
		(net "PRSNTB1_NIC5_N")
	)
	(via
		(at 365.26216 -43.041316)
		(size 0.6604)
		(drill 0.3302)
		(layers "F.Cu" "B.Cu")
		(net "P12V_SSD12")
	)
	(via
		(at 365.185452 -41.241472)
		(size 0.508)
		(drill 0.254)
		(layers "F.Cu" "B.Cu")
		(net "P12V_SSD12")
	)
	(via
		(at 364.75543 -20.978622)
		(size 0.508)
		(drill 0.254)
		(layers "F.Cu" "B.Cu")
		(net "P12V_SSD12")
	)
	(via
		(at 368.339624 -19.532346)
		(size 0.6604)
		(drill 0.3302)
		(layers "F.Cu" "B.Cu")
		(net "P12V_SSD12")
	)
	(via
		(at 364.75543 -19.657822)
		(size 0.508)
		(drill 0.254)
		(layers "F.Cu" "B.Cu")
		(net "P12V_SSD12")
	)
	(via
		(at 364.75543 -18.997422)
		(size 0.508)
		(drill 0.254)
		(layers "F.Cu" "B.Cu")
		(net "P12V_SSD12")
	)
	(via
		(at 364.75543 -20.318222)
		(size 0.508)
		(drill 0.254)
		(layers "F.Cu" "B.Cu")
		(net "P12V_SSD12")
	)
	(via
		(at 366.988852 -43.305222)
		(size 0.508)
		(drill 0.254)
		(layers "F.Cu" "B.Cu")
		(net "P12V_SSD12")
	)
	(via
		(at 366.988852 -42.009822)
		(size 0.508)
		(drill 0.254)
		(layers "F.Cu" "B.Cu")
		(net "P12V_SSD12")
	)
	(via
		(at 364.75543 -21.639022)
		(size 0.508)
		(drill 0.254)
		(layers "F.Cu" "B.Cu")
		(net "P12V_SSD12")
	)
	(via
		(at 366.434624 -19.532346)
		(size 0.6604)
		(drill 0.3302)
		(layers "F.Cu" "B.Cu")
		(net "P12V_SSD12")
	)
	(via
		(at 366.988852 -41.349422)
		(size 0.508)
		(drill 0.254)
		(layers "F.Cu" "B.Cu")
		(net "P12V_SSD12")
	)
	(via
		(at 366.988852 -42.670222)
		(size 0.508)
		(drill 0.254)
		(layers "F.Cu" "B.Cu")
		(net "P12V_SSD12")
	)
	(via
		(at 363.35716 -43.041316)
		(size 0.6604)
		(drill 0.3302)
		(layers "F.Cu" "B.Cu")
		(net "P12V_SSD12")
	)
	(via
		(at 364.525052 -41.241472)
		(size 0.508)
		(drill 0.254)
		(layers "F.Cu" "B.Cu")
		(net "P12V_SSD12")
	)
	(segment
		(start 67.05727 -122.30354)
		(end 67.05727 -122.303794)
		(width 0.13462)
		(layer "F.Cu")
		(net "P5E_PEX0_STN0_RX_DN<2>")
	)
	(segment
		(start 67.05727 -122.303794)
		(end 67.351402 -122.597926)
		(width 0.13462)
		(layer "F.Cu")
		(net "P5E_PEX0_STN0_RX_DN<2>")
	)
	(segment
		(start 68.006722 -122.597926)
		(end 68.169536 -122.435112)
		(width 0.13462)
		(layer "F.Cu")
		(net "P5E_PEX0_STN0_RX_DN<2>")
	)
	(segment
		(start 67.351402 -122.597926)
		(end 68.006722 -122.597926)
		(width 0.13462)
		(layer "F.Cu")
		(net "P5E_PEX0_STN0_RX_DN<2>")
	)
	(segment
		(start 68.169536 -122.435112)
		(end 68.65747 -122.435112)
		(width 0.13462)
		(layer "F.Cu")
		(net "P5E_PEX0_STN0_RX_DN<2>")
	)
	(segment
		(start 67.05727 -122.30354)
		(end 67.3481 -122.59437)
		(width 0.1651)
		(layer "In5.Cu")
		(net "P5E_PEX0_STN0_RX_DN<2>")
	)
	(segment
		(start 83.924648 -286.065722)
		(end 83.8962 -286.065722)
		(width 0.1143)
		(layer "In5.Cu")
		(net "P5E_PEX0_STN0_RX_DN<2>")
	)
	(segment
		(start 86.94039 -285.298642)
		(end 85.51926 -286.034226)
		(width 0.1651)
		(layer "In5.Cu")
		(net "P5E_PEX0_STN0_RX_DN<2>")
	)
	(segment
		(start 79.648558 -134.04088)
		(end 83.943444 -138.329924)
		(width 0.1651)
		(layer "In5.Cu")
		(net "P5E_PEX0_STN0_RX_DN<2>")
	)
	(segment
		(start 80.28432 -286.399732)
		(end 80.54975 -286.399732)
		(width 0.1143)
		(layer "In5.Cu")
		(net "P5E_PEX0_STN0_RX_DN<2>")
	)
	(segment
		(start 97.566988 -273.153378)
		(end 95.23857 -277.258272)
		(width 0.1651)
		(layer "In5.Cu")
		(net "P5E_PEX0_STN0_RX_DN<2>")
	)
	(segment
		(start 80.17002 -286.15259)
		(end 80.17002 -286.285432)
		(width 0.1143)
		(layer "In5.Cu")
		(net "P5E_PEX0_STN0_RX_DN<2>")
	)
	(segment
		(start 80.302608 -286.020002)
		(end 80.17002 -286.15259)
		(width 0.1143)
		(layer "In5.Cu")
		(net "P5E_PEX0_STN0_RX_DN<2>")
	)
	(segment
		(start 74.604118 -126.48184)
		(end 79.648558 -134.04088)
		(width 0.1651)
		(layer "In5.Cu")
		(net "P5E_PEX0_STN0_RX_DN<2>")
	)
	(segment
		(start 83.85048 -286.020002)
		(end 80.302608 -286.020002)
		(width 0.1143)
		(layer "In5.Cu")
		(net "P5E_PEX0_STN0_RX_DN<2>")
	)
	(segment
		(start 89.083896 -239.882426)
		(end 97.73539 -269.474696)
		(width 0.1651)
		(layer "In5.Cu")
		(net "P5E_PEX0_STN0_RX_DN<2>")
	)
	(segment
		(start 97.73539 -269.474696)
		(end 97.566988 -273.153378)
		(width 0.1651)
		(layer "In5.Cu")
		(net "P5E_PEX0_STN0_RX_DN<2>")
	)
	(segment
		(start 72.688958 -124.55398)
		(end 74.604118 -126.48184)
		(width 0.1651)
		(layer "In5.Cu")
		(net "P5E_PEX0_STN0_RX_DN<2>")
	)
	(segment
		(start 85.51926 -286.034226)
		(end 85.487764 -286.065722)
		(width 0.1651)
		(layer "In5.Cu")
		(net "P5E_PEX0_STN0_RX_DN<2>")
	)
	(segment
		(start 86.735666 -143.552926)
		(end 87.64651 -149.960838)
		(width 0.1651)
		(layer "In5.Cu")
		(net "P5E_PEX0_STN0_RX_DN<2>")
	)
	(segment
		(start 80.17002 -286.285432)
		(end 80.28432 -286.399732)
		(width 0.1143)
		(layer "In5.Cu")
		(net "P5E_PEX0_STN0_RX_DN<2>")
	)
	(segment
		(start 83.8962 -286.065722)
		(end 83.85048 -286.020002)
		(width 0.1143)
		(layer "In5.Cu")
		(net "P5E_PEX0_STN0_RX_DN<2>")
	)
	(segment
		(start 67.974464 -122.59437)
		(end 72.688958 -124.55398)
		(width 0.1651)
		(layer "In5.Cu")
		(net "P5E_PEX0_STN0_RX_DN<2>")
	)
	(segment
		(start 85.487764 -286.065722)
		(end 83.924648 -286.065722)
		(width 0.1651)
		(layer "In5.Cu")
		(net "P5E_PEX0_STN0_RX_DN<2>")
	)
	(segment
		(start 87.436198 -232.139744)
		(end 89.083896 -239.882426)
		(width 0.1651)
		(layer "In5.Cu")
		(net "P5E_PEX0_STN0_RX_DN<2>")
	)
	(segment
		(start 67.3481 -122.59437)
		(end 67.974464 -122.59437)
		(width 0.1651)
		(layer "In5.Cu")
		(net "P5E_PEX0_STN0_RX_DN<2>")
	)
	(segment
		(start 95.23857 -277.258272)
		(end 86.94039 -285.298642)
		(width 0.1651)
		(layer "In5.Cu")
		(net "P5E_PEX0_STN0_RX_DN<2>")
	)
	(segment
		(start 83.943444 -138.329924)
		(end 86.735666 -143.552926)
		(width 0.1651)
		(layer "In5.Cu")
		(net "P5E_PEX0_STN0_RX_DN<2>")
	)
	(segment
		(start 88.142572 -168.455086)
		(end 87.436198 -232.139744)
		(width 0.1651)
		(layer "In5.Cu")
		(net "P5E_PEX0_STN0_RX_DN<2>")
	)
	(segment
		(start 87.64651 -149.960838)
		(end 88.142572 -168.455086)
		(width 0.1651)
		(layer "In5.Cu")
		(net "P5E_PEX0_STN0_RX_DN<2>")
	)
	(segment
		(start 384.324606 -28.5496)
		(end 383.65557 -28.5496)
		(width 0.13462)
		(layer "F.Cu")
		(net "P5E_PEX3_STN2_RX_DN<40>")
	)
	(segment
		(start 384.96494 -28.390088)
		(end 384.484118 -28.390088)
		(width 0.13462)
		(layer "F.Cu")
		(net "P5E_PEX3_STN2_RX_DN<40>")
	)
	(segment
		(start 384.484118 -28.390088)
		(end 384.324606 -28.5496)
		(width 0.13462)
		(layer "F.Cu")
		(net "P5E_PEX3_STN2_RX_DN<40>")
	)
	(segment
		(start 383.65557 -28.5496)
		(end 383.36474 -28.25877)
		(width 0.13462)
		(layer "F.Cu")
		(net "P5E_PEX3_STN2_RX_DN<40>")
	)
	(segment
		(start 387.370574 -55.191914)
		(end 387.768338 -65.131442)
		(width 0.1651)
		(layer "In7.Cu")
		(net "P5E_PEX3_STN2_RX_DN<40>")
	)
	(segment
		(start 399.02003 -271.467072)
		(end 399.02003 -275.275802)
		(width 0.1143)
		(layer "In7.Cu")
		(net "P5E_PEX3_STN2_RX_DN<40>")
	)
	(segment
		(start 399.030698 -250.008136)
		(end 398.74444 -264.860786)
		(width 0.1651)
		(layer "In7.Cu")
		(net "P5E_PEX3_STN2_RX_DN<40>")
	)
	(segment
		(start 387.469888 -48.829722)
		(end 387.370574 -55.191914)
		(width 0.1651)
		(layer "In7.Cu")
		(net "P5E_PEX3_STN2_RX_DN<40>")
	)
	(segment
		(start 399.400014 -275.265388)
		(end 399.400014 -274.999958)
		(width 0.1143)
		(layer "In7.Cu")
		(net "P5E_PEX3_STN2_RX_DN<40>")
	)
	(segment
		(start 390.912096 -104.30002)
		(end 391.374884 -119.564404)
		(width 0.1651)
		(layer "In7.Cu")
		(net "P5E_PEX3_STN2_RX_DN<40>")
	)
	(segment
		(start 387.002782 -31.448502)
		(end 389.631428 -37.688012)
		(width 0.1651)
		(layer "In7.Cu")
		(net "P5E_PEX3_STN2_RX_DN<40>")
	)
	(segment
		(start 384.10388 -28.5496)
		(end 387.002782 -31.448502)
		(width 0.1651)
		(layer "In7.Cu")
		(net "P5E_PEX3_STN2_RX_DN<40>")
	)
	(segment
		(start 389.616696 -38.576758)
		(end 387.469888 -48.829722)
		(width 0.1651)
		(layer "In7.Cu")
		(net "P5E_PEX3_STN2_RX_DN<40>")
	)
	(segment
		(start 387.768338 -65.131442)
		(end 390.912096 -104.30002)
		(width 0.1651)
		(layer "In7.Cu")
		(net "P5E_PEX3_STN2_RX_DN<40>")
	)
	(segment
		(start 383.36474 -28.25877)
		(end 383.65557 -28.5496)
		(width 0.1651)
		(layer "In7.Cu")
		(net "P5E_PEX3_STN2_RX_DN<40>")
	)
	(segment
		(start 399.06575 -271.392904)
		(end 399.06575 -271.421352)
		(width 0.1143)
		(layer "In7.Cu")
		(net "P5E_PEX3_STN2_RX_DN<40>")
	)
	(segment
		(start 383.65557 -28.5496)
		(end 384.10388 -28.5496)
		(width 0.1651)
		(layer "In7.Cu")
		(net "P5E_PEX3_STN2_RX_DN<40>")
	)
	(segment
		(start 398.74444 -264.860786)
		(end 399.06575 -268.123162)
		(width 0.1651)
		(layer "In7.Cu")
		(net "P5E_PEX3_STN2_RX_DN<40>")
	)
	(segment
		(start 399.06575 -268.123162)
		(end 399.06575 -271.392904)
		(width 0.1651)
		(layer "In7.Cu")
		(net "P5E_PEX3_STN2_RX_DN<40>")
	)
	(segment
		(start 399.123916 -275.379688)
		(end 399.285714 -275.379688)
		(width 0.1143)
		(layer "In7.Cu")
		(net "P5E_PEX3_STN2_RX_DN<40>")
	)
	(segment
		(start 391.069068 -147.93849)
		(end 399.030698 -250.008136)
		(width 0.1651)
		(layer "In7.Cu")
		(net "P5E_PEX3_STN2_RX_DN<40>")
	)
	(segment
		(start 399.02003 -275.275802)
		(end 399.123916 -275.379688)
		(width 0.1143)
		(layer "In7.Cu")
		(net "P5E_PEX3_STN2_RX_DN<40>")
	)
	(segment
		(start 389.631428 -37.688012)
		(end 389.616696 -38.576758)
		(width 0.1651)
		(layer "In7.Cu")
		(net "P5E_PEX3_STN2_RX_DN<40>")
	)
	(segment
		(start 399.285714 -275.379688)
		(end 399.400014 -275.265388)
		(width 0.1143)
		(layer "In7.Cu")
		(net "P5E_PEX3_STN2_RX_DN<40>")
	)
	(segment
		(start 391.374884 -119.564404)
		(end 391.069068 -147.93849)
		(width 0.1651)
		(layer "In7.Cu")
		(net "P5E_PEX3_STN2_RX_DN<40>")
	)
	(segment
		(start 399.06575 -271.421352)
		(end 399.02003 -271.467072)
		(width 0.1143)
		(layer "In7.Cu")
		(net "P5E_PEX3_STN2_RX_DN<40>")
	)
	(segment
		(start 296.277792 -116.550186)
		(end 297.66768 -116.550186)
		(width 0.13208)
		(layer "F.Cu")
		(net "PRSNTB2_NIC5_N")
	)
	(segment
		(start 299.3517 -115.834922)
		(end 300.857412 -115.834922)
		(width 0.13208)
		(layer "F.Cu")
		(net "PRSNTB2_NIC5_N")
	)
	(segment
		(start 297.770296 -116.44757)
		(end 298.739052 -116.44757)
		(width 0.13208)
		(layer "F.Cu")
		(net "PRSNTB2_NIC5_N")
	)
	(segment
		(start 298.739052 -116.44757)
		(end 299.3517 -115.834922)
		(width 0.13208)
		(layer "F.Cu")
		(net "PRSNTB2_NIC5_N")
	)
	(segment
		(start 297.66768 -116.550186)
		(end 297.770296 -116.44757)
		(width 0.13208)
		(layer "F.Cu")
		(net "PRSNTB2_NIC5_N")
	)
	(segment
		(start 296.277792 -117.566186)
		(end 296.277792 -116.550186)
		(width 0.13208)
		(layer "F.Cu")
		(net "PRSNTB2_NIC5_N")
	)
	(via
		(at 298.739052 -116.44757)
		(size 0.508)
		(drill 0.254)
		(layers "F.Cu" "B.Cu")
		(net "PRSNTB2_NIC5_N")
	)
	(via
		(at 326.655176 -19.085306)
		(size 0.508)
		(drill 0.254)
		(layers "F.Cu" "B.Cu")
		(net "P12V_SSD11")
	)
	(via
		(at 326.655176 -19.745706)
		(size 0.508)
		(drill 0.254)
		(layers "F.Cu" "B.Cu")
		(net "P12V_SSD11")
	)
	(via
		(at 326.424798 -41.241472)
		(size 0.508)
		(drill 0.254)
		(layers "F.Cu" "B.Cu")
		(net "P12V_SSD11")
	)
	(via
		(at 326.655176 -20.406106)
		(size 0.508)
		(drill 0.254)
		(layers "F.Cu" "B.Cu")
		(net "P12V_SSD11")
	)
	(via
		(at 326.655176 -21.066506)
		(size 0.508)
		(drill 0.254)
		(layers "F.Cu" "B.Cu")
		(net "P12V_SSD11")
	)
	(via
		(at 328.888598 -42.009822)
		(size 0.508)
		(drill 0.254)
		(layers "F.Cu" "B.Cu")
		(net "P12V_SSD11")
	)
	(via
		(at 328.888598 -43.305222)
		(size 0.508)
		(drill 0.254)
		(layers "F.Cu" "B.Cu")
		(net "P12V_SSD11")
	)
	(via
		(at 328.888598 -41.349422)
		(size 0.508)
		(drill 0.254)
		(layers "F.Cu" "B.Cu")
		(net "P12V_SSD11")
	)
	(via
		(at 325.256906 -43.041316)
		(size 0.6604)
		(drill 0.3302)
		(layers "F.Cu" "B.Cu")
		(net "P12V_SSD11")
	)
	(via
		(at 329.812142 -19.87423)
		(size 0.6604)
		(drill 0.3302)
		(layers "F.Cu" "B.Cu")
		(net "P12V_SSD11")
	)
	(via
		(at 327.161906 -43.041316)
		(size 0.6604)
		(drill 0.3302)
		(layers "F.Cu" "B.Cu")
		(net "P12V_SSD11")
	)
	(via
		(at 326.655176 -21.726906)
		(size 0.508)
		(drill 0.254)
		(layers "F.Cu" "B.Cu")
		(net "P12V_SSD11")
	)
	(via
		(at 328.888598 -42.670222)
		(size 0.508)
		(drill 0.254)
		(layers "F.Cu" "B.Cu")
		(net "P12V_SSD11")
	)
	(via
		(at 327.907142 -19.87423)
		(size 0.6604)
		(drill 0.3302)
		(layers "F.Cu" "B.Cu")
		(net "P12V_SSD11")
	)
	(via
		(at 327.085198 -41.241472)
		(size 0.508)
		(drill 0.254)
		(layers "F.Cu" "B.Cu")
		(net "P12V_SSD11")
	)
	(segment
		(start 73.745852 -130.6449)
		(end 73.908666 -130.482086)
		(width 0.13462)
		(layer "F.Cu")
		(net "P5E_PEX0_STN0_TX_C_DP<4>")
	)
	(segment
		(start 79.440278 -130.482086)
		(end 79.752698 -130.794506)
		(width 0.13462)
		(layer "F.Cu")
		(net "P5E_PEX0_STN0_TX_C_DP<4>")
	)
	(segment
		(start 73.908666 -130.482086)
		(end 79.440278 -130.482086)
		(width 0.13462)
		(layer "F.Cu")
		(net "P5E_PEX0_STN0_TX_C_DP<4>")
	)
	(segment
		(start 73.257664 -130.6449)
		(end 73.745852 -130.6449)
		(width 0.13462)
		(layer "F.Cu")
		(net "P5E_PEX0_STN0_TX_C_DP<4>")
	)
	(segment
		(start 267.871702 -350.365314)
		(end 268.191742 -350.685354)
		(width 0.13462)
		(layer "F.Cu")
		(net "P5E_PEX2_STN7_TX_C_DP<112>")
	)
	(segment
		(start 268.191742 -351.316798)
		(end 267.897102 -351.611438)
		(width 0.13462)
		(layer "F.Cu")
		(net "P5E_PEX2_STN7_TX_C_DP<112>")
	)
	(segment
		(start 268.191742 -350.685354)
		(end 268.191742 -351.316798)
		(width 0.13462)
		(layer "F.Cu")
		(net "P5E_PEX2_STN7_TX_C_DP<112>")
	)
	(segment
		(start 288.333942 -394.843)
		(end 288.333942 -400.612356)
		(width 0.1651)
		(layer "In7.Cu")
		(net "P5E_PEX2_STN7_TX_C_DP<112>")
	)
	(segment
		(start 282.138374 -390.881108)
		(end 282.26385 -390.87425)
		(width 0.1651)
		(layer "In7.Cu")
		(net "P5E_PEX2_STN7_TX_C_DP<112>")
	)
	(segment
		(start 282.632658 -391.204704)
		(end 282.639516 -391.330434)
		(width 0.1651)
		(layer "In7.Cu")
		(net "P5E_PEX2_STN7_TX_C_DP<112>")
	)
	(segment
		(start 287.347152 -394.02512)
		(end 287.466532 -393.98575)
		(width 0.1651)
		(layer "In7.Cu")
		(net "P5E_PEX2_STN7_TX_C_DP<112>")
	)
	(segment
		(start 284.816296 -392.752834)
		(end 285.259018 -392.975338)
		(width 0.1651)
		(layer "In7.Cu")
		(net "P5E_PEX2_STN7_TX_C_DP<112>")
	)
	(segment
		(start 267.897102 -351.611438)
		(end 268.187932 -351.902268)
		(width 0.1651)
		(layer "In7.Cu")
		(net "P5E_PEX2_STN7_TX_C_DP<112>")
	)
	(segment
		(start 288.333942 -400.612356)
		(end 288.047176 -400.899122)
		(width 0.1651)
		(layer "In7.Cu")
		(net "P5E_PEX2_STN7_TX_C_DP<112>")
	)
	(segment
		(start 281.762454 -390.42467)
		(end 281.769312 -390.5504)
		(width 0.1651)
		(layer "In7.Cu")
		(net "P5E_PEX2_STN7_TX_C_DP<112>")
	)
	(segment
		(start 268.187932 -358.394)
		(end 277.368 -375.1834)
		(width 0.1651)
		(layer "In7.Cu")
		(net "P5E_PEX2_STN7_TX_C_DP<112>")
	)
	(segment
		(start 288.047176 -400.899122)
		(end 287.6169 -400.899122)
		(width 0.1651)
		(layer "In7.Cu")
		(net "P5E_PEX2_STN7_TX_C_DP<112>")
	)
	(segment
		(start 283.52369 -392.003534)
		(end 284.776926 -392.633454)
		(width 0.1651)
		(layer "In7.Cu")
		(net "P5E_PEX2_STN7_TX_C_DP<112>")
	)
	(segment
		(start 287.909 -394.208)
		(end 288.333942 -394.843)
		(width 0.1651)
		(layer "In7.Cu")
		(net "P5E_PEX2_STN7_TX_C_DP<112>")
	)
	(segment
		(start 283.008578 -391.661142)
		(end 283.134054 -391.654284)
		(width 0.1651)
		(layer "In7.Cu")
		(net "P5E_PEX2_STN7_TX_C_DP<112>")
	)
	(segment
		(start 287.466532 -393.98575)
		(end 287.909 -394.208)
		(width 0.1651)
		(layer "In7.Cu")
		(net "P5E_PEX2_STN7_TX_C_DP<112>")
	)
	(segment
		(start 268.187932 -351.902268)
		(end 268.187932 -358.394)
		(width 0.1651)
		(layer "In7.Cu")
		(net "P5E_PEX2_STN7_TX_C_DP<112>")
	)
	(segment
		(start 285.86049 -393.277598)
		(end 286.303212 -393.500102)
		(width 0.1651)
		(layer "In7.Cu")
		(net "P5E_PEX2_STN7_TX_C_DP<112>")
	)
	(segment
		(start 284.776926 -392.633454)
		(end 284.816296 -392.752834)
		(width 0.1651)
		(layer "In7.Cu")
		(net "P5E_PEX2_STN7_TX_C_DP<112>")
	)
	(segment
		(start 287.4899 -400.772122)
		(end 287.4899 -400.390106)
		(width 0.1651)
		(layer "In7.Cu")
		(net "P5E_PEX2_STN7_TX_C_DP<112>")
	)
	(segment
		(start 285.378398 -392.935968)
		(end 285.820866 -393.158218)
		(width 0.1651)
		(layer "In7.Cu")
		(net "P5E_PEX2_STN7_TX_C_DP<112>")
	)
	(segment
		(start 286.90443 -393.802362)
		(end 287.347152 -394.02512)
		(width 0.1651)
		(layer "In7.Cu")
		(net "P5E_PEX2_STN7_TX_C_DP<112>")
	)
	(segment
		(start 281.769312 -390.5504)
		(end 282.138374 -390.881108)
		(width 0.1651)
		(layer "In7.Cu")
		(net "P5E_PEX2_STN7_TX_C_DP<112>")
	)
	(segment
		(start 285.259018 -392.975338)
		(end 285.378398 -392.935968)
		(width 0.1651)
		(layer "In7.Cu")
		(net "P5E_PEX2_STN7_TX_C_DP<112>")
	)
	(segment
		(start 286.422592 -393.460732)
		(end 286.86506 -393.682982)
		(width 0.1651)
		(layer "In7.Cu")
		(net "P5E_PEX2_STN7_TX_C_DP<112>")
	)
	(segment
		(start 277.368 -375.1834)
		(end 279.727406 -387.276086)
		(width 0.1651)
		(layer "In7.Cu")
		(net "P5E_PEX2_STN7_TX_C_DP<112>")
	)
	(segment
		(start 283.134054 -391.654284)
		(end 283.52369 -392.003534)
		(width 0.1651)
		(layer "In7.Cu")
		(net "P5E_PEX2_STN7_TX_C_DP<112>")
	)
	(segment
		(start 279.727406 -387.276086)
		(end 280.594308 -389.377936)
		(width 0.1651)
		(layer "In7.Cu")
		(net "P5E_PEX2_STN7_TX_C_DP<112>")
	)
	(segment
		(start 287.6169 -400.899122)
		(end 287.4899 -400.772122)
		(width 0.1651)
		(layer "In7.Cu")
		(net "P5E_PEX2_STN7_TX_C_DP<112>")
	)
	(segment
		(start 286.303212 -393.500102)
		(end 286.422592 -393.460732)
		(width 0.1651)
		(layer "In7.Cu")
		(net "P5E_PEX2_STN7_TX_C_DP<112>")
	)
	(segment
		(start 282.639516 -391.330434)
		(end 283.008578 -391.661142)
		(width 0.1651)
		(layer "In7.Cu")
		(net "P5E_PEX2_STN7_TX_C_DP<112>")
	)
	(segment
		(start 286.86506 -393.682982)
		(end 286.90443 -393.802362)
		(width 0.1651)
		(layer "In7.Cu")
		(net "P5E_PEX2_STN7_TX_C_DP<112>")
	)
	(segment
		(start 282.26385 -390.87425)
		(end 282.632658 -391.204704)
		(width 0.1651)
		(layer "In7.Cu")
		(net "P5E_PEX2_STN7_TX_C_DP<112>")
	)
	(segment
		(start 285.820866 -393.158218)
		(end 285.86049 -393.277598)
		(width 0.1651)
		(layer "In7.Cu")
		(net "P5E_PEX2_STN7_TX_C_DP<112>")
	)
	(segment
		(start 280.594308 -389.377936)
		(end 281.762454 -390.42467)
		(width 0.1651)
		(layer "In7.Cu")
		(net "P5E_PEX2_STN7_TX_C_DP<112>")
	)
	(segment
		(start 410.331412 -32.4358)
		(end 410.48559 -32.589978)
		(width 0.13462)
		(layer "F.Cu")
		(net "P5E_PEX3_STN2_RX_DP<38>")
	)
	(segment
		(start 409.364688 -32.722312)
		(end 409.6512 -32.4358)
		(width 0.13462)
		(layer "F.Cu")
		(net "P5E_PEX3_STN2_RX_DP<38>")
	)
	(segment
		(start 410.48559 -32.589978)
		(end 410.964888 -32.589978)
		(width 0.13462)
		(layer "F.Cu")
		(net "P5E_PEX3_STN2_RX_DP<38>")
	)
	(segment
		(start 409.6512 -32.4358)
		(end 410.331412 -32.4358)
		(width 0.13462)
		(layer "F.Cu")
		(net "P5E_PEX3_STN2_RX_DP<38>")
	)
	(segment
		(start 401.299934 -275.684488)
		(end 401.185634 -275.570188)
		(width 0.1143)
		(layer "In7.Cu")
		(net "P5E_PEX3_STN2_RX_DP<38>")
	)
	(segment
		(start 411.16758 -67.907408)
		(end 411.140656 -61.00953)
		(width 0.1651)
		(layer "In7.Cu")
		(net "P5E_PEX3_STN2_RX_DP<38>")
	)
	(segment
		(start 410.460444 -32.7787)
		(end 410.113226 -32.431482)
		(width 0.1651)
		(layer "In7.Cu")
		(net "P5E_PEX3_STN2_RX_DP<38>")
	)
	(segment
		(start 409.931362 -39.731442)
		(end 409.90139 -37.832538)
		(width 0.1651)
		(layer "In7.Cu")
		(net "P5E_PEX3_STN2_RX_DP<38>")
	)
	(segment
		(start 401.299934 -275.949918)
		(end 401.299934 -275.684488)
		(width 0.1143)
		(layer "In7.Cu")
		(net "P5E_PEX3_STN2_RX_DP<38>")
	)
	(segment
		(start 410.190188 -35.728402)
		(end 410.308806 -35.647122)
		(width 0.1651)
		(layer "In7.Cu")
		(net "P5E_PEX3_STN2_RX_DP<38>")
	)
	(segment
		(start 410.337 -34.179256)
		(end 410.34462 -33.683702)
		(width 0.1651)
		(layer "In7.Cu")
		(net "P5E_PEX3_STN2_RX_DP<38>")
	)
	(segment
		(start 400.68373 -271.421352)
		(end 400.68373 -271.392904)
		(width 0.1143)
		(layer "In7.Cu")
		(net "P5E_PEX3_STN2_RX_DP<38>")
	)
	(segment
		(start 410.34462 -33.683702)
		(end 410.447998 -33.583626)
		(width 0.1651)
		(layer "In7.Cu")
		(net "P5E_PEX3_STN2_RX_DP<38>")
	)
	(segment
		(start 400.767296 -264.812272)
		(end 411.16758 -67.907408)
		(width 0.1651)
		(layer "In7.Cu")
		(net "P5E_PEX3_STN2_RX_DP<38>")
	)
	(segment
		(start 400.72945 -275.354796)
		(end 400.72945 -271.467072)
		(width 0.1143)
		(layer "In7.Cu")
		(net "P5E_PEX3_STN2_RX_DP<38>")
	)
	(segment
		(start 410.180536 -36.334192)
		(end 410.099256 -36.215574)
		(width 0.1651)
		(layer "In7.Cu")
		(net "P5E_PEX3_STN2_RX_DP<38>")
	)
	(segment
		(start 410.437076 -34.28238)
		(end 410.337 -34.179256)
		(width 0.1651)
		(layer "In7.Cu")
		(net "P5E_PEX3_STN2_RX_DP<38>")
	)
	(segment
		(start 400.68373 -271.392904)
		(end 400.68373 -265.765788)
		(width 0.1651)
		(layer "In7.Cu")
		(net "P5E_PEX3_STN2_RX_DP<38>")
	)
	(segment
		(start 409.655518 -32.431482)
		(end 409.364688 -32.722312)
		(width 0.1651)
		(layer "In7.Cu")
		(net "P5E_PEX3_STN2_RX_DP<38>")
	)
	(segment
		(start 410.308806 -35.647122)
		(end 410.425646 -35.019996)
		(width 0.1651)
		(layer "In7.Cu")
		(net "P5E_PEX3_STN2_RX_DP<38>")
	)
	(segment
		(start 410.113226 -32.431482)
		(end 409.655518 -32.431482)
		(width 0.1651)
		(layer "In7.Cu")
		(net "P5E_PEX3_STN2_RX_DP<38>")
	)
	(segment
		(start 410.099256 -36.215574)
		(end 410.190188 -35.728402)
		(width 0.1651)
		(layer "In7.Cu")
		(net "P5E_PEX3_STN2_RX_DP<38>")
	)
	(segment
		(start 409.90139 -37.832538)
		(end 410.180536 -36.334192)
		(width 0.1651)
		(layer "In7.Cu")
		(net "P5E_PEX3_STN2_RX_DP<38>")
	)
	(segment
		(start 410.425646 -35.019996)
		(end 410.437076 -34.28238)
		(width 0.1651)
		(layer "In7.Cu")
		(net "P5E_PEX3_STN2_RX_DP<38>")
	)
	(segment
		(start 410.447998 -33.583626)
		(end 410.460444 -32.7787)
		(width 0.1651)
		(layer "In7.Cu")
		(net "P5E_PEX3_STN2_RX_DP<38>")
	)
	(segment
		(start 400.944842 -275.570188)
		(end 400.72945 -275.354796)
		(width 0.1143)
		(layer "In7.Cu")
		(net "P5E_PEX3_STN2_RX_DP<38>")
	)
	(segment
		(start 400.72945 -271.467072)
		(end 400.68373 -271.421352)
		(width 0.1143)
		(layer "In7.Cu")
		(net "P5E_PEX3_STN2_RX_DP<38>")
	)
	(segment
		(start 411.313376 -49.959514)
		(end 409.931362 -39.731442)
		(width 0.1651)
		(layer "In7.Cu")
		(net "P5E_PEX3_STN2_RX_DP<38>")
	)
	(segment
		(start 401.185634 -275.570188)
		(end 400.944842 -275.570188)
		(width 0.1143)
		(layer "In7.Cu")
		(net "P5E_PEX3_STN2_RX_DP<38>")
	)
	(segment
		(start 411.140656 -61.00953)
		(end 411.313376 -49.959514)
		(width 0.1651)
		(layer "In7.Cu")
		(net "P5E_PEX3_STN2_RX_DP<38>")
	)
	(segment
		(start 400.68373 -265.765788)
		(end 400.767296 -264.812272)
		(width 0.1651)
		(layer "In7.Cu")
		(net "P5E_PEX3_STN2_RX_DP<38>")
	)
	(segment
		(start 297.660314 -98.522536)
		(end 297.977814 -98.840036)
		(width 0.13208)
		(layer "F.Cu")
		(net "NIC5_RBT_ARB_IN")
	)
	(segment
		(start 291.595048 -98.734372)
		(end 293.685468 -98.734372)
		(width 0.13208)
		(layer "F.Cu")
		(net "NIC5_RBT_ARB_IN")
	)
	(segment
		(start 294.719756 -98.522536)
		(end 297.660314 -98.522536)
		(width 0.13208)
		(layer "F.Cu")
		(net "NIC5_RBT_ARB_IN")
	)
	(segment
		(start 293.685468 -98.734372)
		(end 293.897304 -98.522536)
		(width 0.13208)
		(layer "F.Cu")
		(net "NIC5_RBT_ARB_IN")
	)
	(segment
		(start 293.897304 -98.522536)
		(end 294.719756 -98.522536)
		(width 0.13208)
		(layer "F.Cu")
		(net "NIC5_RBT_ARB_IN")
	)
	(segment
		(start 297.977814 -98.840036)
		(end 300.857412 -98.840036)
		(width 0.13208)
		(layer "F.Cu")
		(net "NIC5_RBT_ARB_IN")
	)
	(via
		(at 294.719756 -98.522536)
		(size 0.762)
		(drill 0.381)
		(layers "F.Cu" "B.Cu")
		(net "NIC5_RBT_ARB_IN")
	)
	(via
		(at 304.154078 -20.558252)
		(size 0.6604)
		(drill 0.3302)
		(layers "F.Cu" "B.Cu")
		(net "P12V_SSD10")
	)
	(via
		(at 302.88865 -42.670222)
		(size 0.508)
		(drill 0.254)
		(layers "F.Cu" "B.Cu")
		(net "P12V_SSD10")
	)
	(via
		(at 299.256958 -43.041316)
		(size 0.6604)
		(drill 0.3302)
		(layers "F.Cu" "B.Cu")
		(net "P12V_SSD10")
	)
	(via
		(at 301.08525 -41.241472)
		(size 0.508)
		(drill 0.254)
		(layers "F.Cu" "B.Cu")
		(net "P12V_SSD10")
	)
	(via
		(at 302.249078 -20.558252)
		(size 0.6604)
		(drill 0.3302)
		(layers "F.Cu" "B.Cu")
		(net "P12V_SSD10")
	)
	(via
		(at 302.88865 -42.009822)
		(size 0.508)
		(drill 0.254)
		(layers "F.Cu" "B.Cu")
		(net "P12V_SSD10")
	)
	(via
		(at 300.655228 -19.657822)
		(size 0.508)
		(drill 0.254)
		(layers "F.Cu" "B.Cu")
		(net "P12V_SSD10")
	)
	(via
		(at 300.655228 -21.639022)
		(size 0.508)
		(drill 0.254)
		(layers "F.Cu" "B.Cu")
		(net "P12V_SSD10")
	)
	(via
		(at 302.88865 -43.305222)
		(size 0.508)
		(drill 0.254)
		(layers "F.Cu" "B.Cu")
		(net "P12V_SSD10")
	)
	(via
		(at 300.655228 -20.318222)
		(size 0.508)
		(drill 0.254)
		(layers "F.Cu" "B.Cu")
		(net "P12V_SSD10")
	)
	(via
		(at 301.161958 -43.041316)
		(size 0.6604)
		(drill 0.3302)
		(layers "F.Cu" "B.Cu")
		(net "P12V_SSD10")
	)
	(via
		(at 302.88865 -41.349422)
		(size 0.508)
		(drill 0.254)
		(layers "F.Cu" "B.Cu")
		(net "P12V_SSD10")
	)
	(via
		(at 300.655228 -20.978622)
		(size 0.508)
		(drill 0.254)
		(layers "F.Cu" "B.Cu")
		(net "P12V_SSD10")
	)
	(via
		(at 300.655228 -18.997422)
		(size 0.508)
		(drill 0.254)
		(layers "F.Cu" "B.Cu")
		(net "P12V_SSD10")
	)
	(via
		(at 300.42485 -41.241472)
		(size 0.508)
		(drill 0.254)
		(layers "F.Cu" "B.Cu")
		(net "P12V_SSD10")
	)
	(segment
		(start 435.202076 -26.266394)
		(end 434.420518 -26.266394)
		(width 0.13208)
		(layer "F.Cu")
		(net "PRSNT_SSD15_N")
	)
	(segment
		(start 435.751986 -25.390094)
		(end 435.202076 -25.940004)
		(width 0.13208)
		(layer "F.Cu")
		(net "PRSNT_SSD15_N")
	)
	(segment
		(start 436.964836 -25.390094)
		(end 435.751986 -25.390094)
		(width 0.13208)
		(layer "F.Cu")
		(net "PRSNT_SSD15_N")
	)
	(segment
		(start 435.202076 -25.940004)
		(end 435.202076 -26.266394)
		(width 0.13208)
		(layer "F.Cu")
		(net "PRSNT_SSD15_N")
	)
	(via
		(at 435.202076 -26.266394)
		(size 0.508)
		(drill 0.254)
		(layers "F.Cu" "B.Cu")
		(net "PRSNT_SSD15_N")
	)
	(segment
		(start 68.169536 -124.834904)
		(end 68.006722 -124.67209)
		(width 0.13462)
		(layer "F.Cu")
		(net "P5E_PEX0_STN0_RX_DP<3>")
	)
	(segment
		(start 68.65747 -124.834904)
		(end 68.169536 -124.834904)
		(width 0.13462)
		(layer "F.Cu")
		(net "P5E_PEX0_STN0_RX_DP<3>")
	)
	(segment
		(start 65.498218 -124.67209)
		(end 65.20307 -124.967238)
		(width 0.13462)
		(layer "F.Cu")
		(net "P5E_PEX0_STN0_RX_DP<3>")
	)
	(segment
		(start 68.006722 -124.67209)
		(end 65.498218 -124.67209)
		(width 0.13462)
		(layer "F.Cu")
		(net "P5E_PEX0_STN0_RX_DP<3>")
	)
	(segment
		(start 83.950048 -284.833822)
		(end 85.20049 -284.833822)
		(width 0.1651)
		(layer "In5.Cu")
		(net "P5E_PEX0_STN0_RX_DP<3>")
	)
	(segment
		(start 74.103992 -128.500632)
		(end 73.849484 -128.075182)
		(width 0.1651)
		(layer "In5.Cu")
		(net "P5E_PEX0_STN0_RX_DP<3>")
	)
	(segment
		(start 74.921618 -129.869692)
		(end 74.961242 -129.712974)
		(width 0.1651)
		(layer "In5.Cu")
		(net "P5E_PEX0_STN0_RX_DP<3>")
	)
	(segment
		(start 83.87588 -284.879542)
		(end 83.9216 -284.833822)
		(width 0.1143)
		(layer "In5.Cu")
		(net "P5E_PEX0_STN0_RX_DP<3>")
	)
	(segment
		(start 70.16496 -125.514354)
		(end 70.103238 -125.364748)
		(width 0.1651)
		(layer "In5.Cu")
		(net "P5E_PEX0_STN0_RX_DP<3>")
	)
	(segment
		(start 87.919814 -240.358422)
		(end 86.189312 -232.225596)
		(width 0.1651)
		(layer "In5.Cu")
		(net "P5E_PEX0_STN0_RX_DP<3>")
	)
	(segment
		(start 75.176126 -130.295142)
		(end 74.921618 -129.869692)
		(width 0.1651)
		(layer "In5.Cu")
		(net "P5E_PEX0_STN0_RX_DP<3>")
	)
	(segment
		(start 70.771766 -125.642624)
		(end 70.622414 -125.704346)
		(width 0.1651)
		(layer "In5.Cu")
		(net "P5E_PEX0_STN0_RX_DP<3>")
	)
	(segment
		(start 69.486018 -125.107954)
		(end 68.72351 -124.960634)
		(width 0.1651)
		(layer "In5.Cu")
		(net "P5E_PEX0_STN0_RX_DP<3>")
	)
	(segment
		(start 81.879694 -285.09468)
		(end 82.094832 -284.879542)
		(width 0.1143)
		(layer "In5.Cu")
		(net "P5E_PEX0_STN0_RX_DP<3>")
	)
	(segment
		(start 70.103238 -125.364748)
		(end 70.103238 -125.364494)
		(width 0.1651)
		(layer "In5.Cu")
		(net "P5E_PEX0_STN0_RX_DP<3>")
	)
	(segment
		(start 73.889108 -127.918464)
		(end 73.471532 -127.219456)
		(width 0.1651)
		(layer "In5.Cu")
		(net "P5E_PEX0_STN0_RX_DP<3>")
	)
	(segment
		(start 81.499964 -285.449772)
		(end 81.765394 -285.449772)
		(width 0.1143)
		(layer "In5.Cu")
		(net "P5E_PEX0_STN0_RX_DP<3>")
	)
	(segment
		(start 85.20049 -284.833822)
		(end 86.300564 -284.196028)
		(width 0.1651)
		(layer "In5.Cu")
		(net "P5E_PEX0_STN0_RX_DP<3>")
	)
	(segment
		(start 73.849484 -128.075182)
		(end 73.889108 -127.918464)
		(width 0.1651)
		(layer "In5.Cu")
		(net "P5E_PEX0_STN0_RX_DP<3>")
	)
	(segment
		(start 75.332844 -130.334512)
		(end 75.176126 -130.295142)
		(width 0.1651)
		(layer "In5.Cu")
		(net "P5E_PEX0_STN0_RX_DP<3>")
	)
	(segment
		(start 96.454468 -269.578836)
		(end 87.919814 -240.358422)
		(width 0.1651)
		(layer "In5.Cu")
		(net "P5E_PEX0_STN0_RX_DP<3>")
	)
	(segment
		(start 75.33259 -130.334512)
		(end 75.332844 -130.334512)
		(width 0.1651)
		(layer "In5.Cu")
		(net "P5E_PEX0_STN0_RX_DP<3>")
	)
	(segment
		(start 81.879694 -285.335472)
		(end 81.879694 -285.09468)
		(width 0.1143)
		(layer "In5.Cu")
		(net "P5E_PEX0_STN0_RX_DP<3>")
	)
	(segment
		(start 74.961242 -129.712974)
		(end 74.26071 -128.540256)
		(width 0.1651)
		(layer "In5.Cu")
		(net "P5E_PEX0_STN0_RX_DP<3>")
	)
	(segment
		(start 68.103242 -124.957078)
		(end 68.012564 -124.822966)
		(width 0.1651)
		(layer "In5.Cu")
		(net "P5E_PEX0_STN0_RX_DP<3>")
	)
	(segment
		(start 67.254628 -124.676408)
		(end 65.4939 -124.676408)
		(width 0.1651)
		(layer "In5.Cu")
		(net "P5E_PEX0_STN0_RX_DP<3>")
	)
	(segment
		(start 72.658732 -126.426722)
		(end 70.771766 -125.642624)
		(width 0.1651)
		(layer "In5.Cu")
		(net "P5E_PEX0_STN0_RX_DP<3>")
	)
	(segment
		(start 82.094832 -284.879542)
		(end 83.87588 -284.879542)
		(width 0.1143)
		(layer "In5.Cu")
		(net "P5E_PEX0_STN0_RX_DP<3>")
	)
	(segment
		(start 81.765394 -285.449772)
		(end 81.879694 -285.335472)
		(width 0.1143)
		(layer "In5.Cu")
		(net "P5E_PEX0_STN0_RX_DP<3>")
	)
	(segment
		(start 96.34474 -272.77822)
		(end 96.454468 -269.578836)
		(width 0.1651)
		(layer "In5.Cu")
		(net "P5E_PEX0_STN0_RX_DP<3>")
	)
	(segment
		(start 70.622414 -125.704346)
		(end 70.16496 -125.514354)
		(width 0.1651)
		(layer "In5.Cu")
		(net "P5E_PEX0_STN0_RX_DP<3>")
	)
	(segment
		(start 85.587078 -144.429226)
		(end 82.3722 -140.240512)
		(width 0.1651)
		(layer "In5.Cu")
		(net "P5E_PEX0_STN0_RX_DP<3>")
	)
	(segment
		(start 86.382098 -150.0505)
		(end 85.587078 -144.429226)
		(width 0.1651)
		(layer "In5.Cu")
		(net "P5E_PEX0_STN0_RX_DP<3>")
	)
	(segment
		(start 75.80122 -131.341876)
		(end 75.546966 -130.916426)
		(width 0.1651)
		(layer "In5.Cu")
		(net "P5E_PEX0_STN0_RX_DP<3>")
	)
	(segment
		(start 73.471532 -127.219456)
		(end 72.658732 -126.426722)
		(width 0.1651)
		(layer "In5.Cu")
		(net "P5E_PEX0_STN0_RX_DP<3>")
	)
	(segment
		(start 70.103238 -125.364494)
		(end 69.486018 -125.107954)
		(width 0.1651)
		(layer "In5.Cu")
		(net "P5E_PEX0_STN0_RX_DP<3>")
	)
	(segment
		(start 75.58659 -130.759454)
		(end 75.33259 -130.334512)
		(width 0.1651)
		(layer "In5.Cu")
		(net "P5E_PEX0_STN0_RX_DP<3>")
	)
	(segment
		(start 68.72351 -124.960634)
		(end 68.589652 -125.051058)
		(width 0.1651)
		(layer "In5.Cu")
		(net "P5E_PEX0_STN0_RX_DP<3>")
	)
	(segment
		(start 94.252796 -276.487382)
		(end 96.34474 -272.77822)
		(width 0.1651)
		(layer "In5.Cu")
		(net "P5E_PEX0_STN0_RX_DP<3>")
	)
	(segment
		(start 75.546966 -130.916426)
		(end 75.58659 -130.759454)
		(width 0.1651)
		(layer "In5.Cu")
		(net "P5E_PEX0_STN0_RX_DP<3>")
	)
	(segment
		(start 75.957938 -131.381246)
		(end 75.80122 -131.341876)
		(width 0.1651)
		(layer "In5.Cu")
		(net "P5E_PEX0_STN0_RX_DP<3>")
	)
	(segment
		(start 68.589652 -125.051058)
		(end 68.103242 -124.957078)
		(width 0.1651)
		(layer "In5.Cu")
		(net "P5E_PEX0_STN0_RX_DP<3>")
	)
	(segment
		(start 86.844378 -168.404286)
		(end 86.382098 -150.0505)
		(width 0.1651)
		(layer "In5.Cu")
		(net "P5E_PEX0_STN0_RX_DP<3>")
	)
	(segment
		(start 83.9216 -284.833822)
		(end 83.950048 -284.833822)
		(width 0.1143)
		(layer "In5.Cu")
		(net "P5E_PEX0_STN0_RX_DP<3>")
	)
	(segment
		(start 76.172314 -131.96316)
		(end 76.211938 -131.806188)
		(width 0.1651)
		(layer "In5.Cu")
		(net "P5E_PEX0_STN0_RX_DP<3>")
	)
	(segment
		(start 68.012564 -124.822966)
		(end 67.254628 -124.676408)
		(width 0.1651)
		(layer "In5.Cu")
		(net "P5E_PEX0_STN0_RX_DP<3>")
	)
	(segment
		(start 74.26071 -128.540256)
		(end 74.103992 -128.500632)
		(width 0.1651)
		(layer "In5.Cu")
		(net "P5E_PEX0_STN0_RX_DP<3>")
	)
	(segment
		(start 65.4939 -124.676408)
		(end 65.20307 -124.967238)
		(width 0.1651)
		(layer "In5.Cu")
		(net "P5E_PEX0_STN0_RX_DP<3>")
	)
	(segment
		(start 79.838042 -137.875264)
		(end 76.583286 -132.42798)
		(width 0.1651)
		(layer "In5.Cu")
		(net "P5E_PEX0_STN0_RX_DP<3>")
	)
	(segment
		(start 82.05089 -139.342368)
		(end 79.838042 -137.875264)
		(width 0.1651)
		(layer "In5.Cu")
		(net "P5E_PEX0_STN0_RX_DP<3>")
	)
	(segment
		(start 76.211938 -131.806188)
		(end 75.957938 -131.381246)
		(width 0.1651)
		(layer "In5.Cu")
		(net "P5E_PEX0_STN0_RX_DP<3>")
	)
	(segment
		(start 86.300564 -284.196028)
		(end 94.252796 -276.487382)
		(width 0.1651)
		(layer "In5.Cu")
		(net "P5E_PEX0_STN0_RX_DP<3>")
	)
	(segment
		(start 86.189312 -232.225596)
		(end 86.844378 -168.404286)
		(width 0.1651)
		(layer "In5.Cu")
		(net "P5E_PEX0_STN0_RX_DP<3>")
	)
	(segment
		(start 76.426568 -132.38861)
		(end 76.172314 -131.96316)
		(width 0.1651)
		(layer "In5.Cu")
		(net "P5E_PEX0_STN0_RX_DP<3>")
	)
	(segment
		(start 76.583286 -132.42798)
		(end 76.426568 -132.38861)
		(width 0.1651)
		(layer "In5.Cu")
		(net "P5E_PEX0_STN0_RX_DP<3>")
	)
	(segment
		(start 82.3722 -140.240512)
		(end 82.05089 -139.342368)
		(width 0.1651)
		(layer "In5.Cu")
		(net "P5E_PEX0_STN0_RX_DP<3>")
	)
	(segment
		(start 270.980662 -356.511606)
		(end 271.300702 -356.831646)
		(width 0.13462)
		(layer "F.Cu")
		(net "P5E_PEX2_STN7_TX_C_DP<114>")
	)
	(segment
		(start 271.300702 -357.46309)
		(end 271.006062 -357.75773)
		(width 0.13462)
		(layer "F.Cu")
		(net "P5E_PEX2_STN7_TX_C_DP<114>")
	)
	(segment
		(start 271.300702 -356.831646)
		(end 271.300702 -357.46309)
		(width 0.13462)
		(layer "F.Cu")
		(net "P5E_PEX2_STN7_TX_C_DP<114>")
	)
	(segment
		(start 284.572456 -390.202166)
		(end 287.382712 -391.545064)
		(width 0.1651)
		(layer "In7.Cu")
		(net "P5E_PEX2_STN7_TX_C_DP<114>")
	)
	(segment
		(start 271.296892 -358.648)
		(end 279.5016 -374.6754)
		(width 0.1651)
		(layer "In7.Cu")
		(net "P5E_PEX2_STN7_TX_C_DP<114>")
	)
	(segment
		(start 288.478976 -392.167618)
		(end 288.926016 -392.381486)
		(width 0.1651)
		(layer "In7.Cu")
		(net "P5E_PEX2_STN7_TX_C_DP<114>")
	)
	(segment
		(start 289.49142 -392.552936)
		(end 289.53333 -392.671554)
		(width 0.1651)
		(layer "In7.Cu")
		(net "P5E_PEX2_STN7_TX_C_DP<114>")
	)
	(segment
		(start 281.468576 -386.17398)
		(end 282.252166 -388.059168)
		(width 0.1651)
		(layer "In7.Cu")
		(net "P5E_PEX2_STN7_TX_C_DP<114>")
	)
	(segment
		(start 292.733984 -394.943584)
		(end 292.733984 -400.612356)
		(width 0.1651)
		(layer "In7.Cu")
		(net "P5E_PEX2_STN7_TX_C_DP<114>")
	)
	(segment
		(start 292.016942 -400.899122)
		(end 291.889942 -400.772122)
		(width 0.1651)
		(layer "In7.Cu")
		(net "P5E_PEX2_STN7_TX_C_DP<114>")
	)
	(segment
		(start 290.587684 -393.175236)
		(end 291.034724 -393.389104)
		(width 0.1651)
		(layer "In7.Cu")
		(net "P5E_PEX2_STN7_TX_C_DP<114>")
	)
	(segment
		(start 287.99028 -391.83564)
		(end 288.437066 -392.049)
		(width 0.1651)
		(layer "In7.Cu")
		(net "P5E_PEX2_STN7_TX_C_DP<114>")
	)
	(segment
		(start 287.382712 -391.545064)
		(end 287.424622 -391.663682)
		(width 0.1651)
		(layer "In7.Cu")
		(net "P5E_PEX2_STN7_TX_C_DP<114>")
	)
	(segment
		(start 289.044634 -392.339576)
		(end 289.49142 -392.552936)
		(width 0.1651)
		(layer "In7.Cu")
		(net "P5E_PEX2_STN7_TX_C_DP<114>")
	)
	(segment
		(start 292.733984 -400.612356)
		(end 292.447218 -400.899122)
		(width 0.1651)
		(layer "In7.Cu")
		(net "P5E_PEX2_STN7_TX_C_DP<114>")
	)
	(segment
		(start 291.608256 -393.564618)
		(end 291.921438 -393.948158)
		(width 0.1651)
		(layer "In7.Cu")
		(net "P5E_PEX2_STN7_TX_C_DP<114>")
	)
	(segment
		(start 289.53333 -392.671554)
		(end 289.98037 -392.885422)
		(width 0.1651)
		(layer "In7.Cu")
		(net "P5E_PEX2_STN7_TX_C_DP<114>")
	)
	(segment
		(start 291.153342 -393.347194)
		(end 291.608256 -393.564618)
		(width 0.1651)
		(layer "In7.Cu")
		(net "P5E_PEX2_STN7_TX_C_DP<114>")
	)
	(segment
		(start 288.926016 -392.381486)
		(end 289.044634 -392.339576)
		(width 0.1651)
		(layer "In7.Cu")
		(net "P5E_PEX2_STN7_TX_C_DP<114>")
	)
	(segment
		(start 288.437066 -392.049)
		(end 288.478976 -392.167618)
		(width 0.1651)
		(layer "In7.Cu")
		(net "P5E_PEX2_STN7_TX_C_DP<114>")
	)
	(segment
		(start 290.098988 -392.843512)
		(end 290.545774 -393.056872)
		(width 0.1651)
		(layer "In7.Cu")
		(net "P5E_PEX2_STN7_TX_C_DP<114>")
	)
	(segment
		(start 291.889942 -400.772122)
		(end 291.889942 -400.390106)
		(width 0.1651)
		(layer "In7.Cu")
		(net "P5E_PEX2_STN7_TX_C_DP<114>")
	)
	(segment
		(start 271.296892 -358.04856)
		(end 271.296892 -358.648)
		(width 0.1651)
		(layer "In7.Cu")
		(net "P5E_PEX2_STN7_TX_C_DP<114>")
	)
	(segment
		(start 291.034724 -393.389104)
		(end 291.153342 -393.347194)
		(width 0.1651)
		(layer "In7.Cu")
		(net "P5E_PEX2_STN7_TX_C_DP<114>")
	)
	(segment
		(start 287.424622 -391.663682)
		(end 287.871662 -391.87755)
		(width 0.1651)
		(layer "In7.Cu")
		(net "P5E_PEX2_STN7_TX_C_DP<114>")
	)
	(segment
		(start 282.252166 -388.059168)
		(end 284.572456 -390.202166)
		(width 0.1651)
		(layer "In7.Cu")
		(net "P5E_PEX2_STN7_TX_C_DP<114>")
	)
	(segment
		(start 279.5016 -374.6754)
		(end 281.468576 -386.17398)
		(width 0.1651)
		(layer "In7.Cu")
		(net "P5E_PEX2_STN7_TX_C_DP<114>")
	)
	(segment
		(start 287.871662 -391.87755)
		(end 287.99028 -391.83564)
		(width 0.1651)
		(layer "In7.Cu")
		(net "P5E_PEX2_STN7_TX_C_DP<114>")
	)
	(segment
		(start 290.545774 -393.056872)
		(end 290.587684 -393.175236)
		(width 0.1651)
		(layer "In7.Cu")
		(net "P5E_PEX2_STN7_TX_C_DP<114>")
	)
	(segment
		(start 292.347142 -394.469874)
		(end 292.733984 -394.943584)
		(width 0.1651)
		(layer "In7.Cu")
		(net "P5E_PEX2_STN7_TX_C_DP<114>")
	)
	(segment
		(start 271.006062 -357.75773)
		(end 271.296892 -358.04856)
		(width 0.1651)
		(layer "In7.Cu")
		(net "P5E_PEX2_STN7_TX_C_DP<114>")
	)
	(segment
		(start 291.921438 -393.948158)
		(end 291.908738 -394.07338)
		(width 0.1651)
		(layer "In7.Cu")
		(net "P5E_PEX2_STN7_TX_C_DP<114>")
	)
	(segment
		(start 289.98037 -392.885422)
		(end 290.098988 -392.843512)
		(width 0.1651)
		(layer "In7.Cu")
		(net "P5E_PEX2_STN7_TX_C_DP<114>")
	)
	(segment
		(start 292.222174 -394.457174)
		(end 292.347142 -394.469874)
		(width 0.1651)
		(layer "In7.Cu")
		(net "P5E_PEX2_STN7_TX_C_DP<114>")
	)
	(segment
		(start 292.447218 -400.899122)
		(end 292.016942 -400.899122)
		(width 0.1651)
		(layer "In7.Cu")
		(net "P5E_PEX2_STN7_TX_C_DP<114>")
	)
	(segment
		(start 291.908738 -394.07338)
		(end 292.222174 -394.457174)
		(width 0.1651)
		(layer "In7.Cu")
		(net "P5E_PEX2_STN7_TX_C_DP<114>")
	)
	(segment
		(start 355.804724 -30.353)
		(end 355.510592 -30.058868)
		(width 0.13462)
		(layer "F.Cu")
		(net "P5E_PEX3_STN2_RX_DN<45>")
	)
	(segment
		(start 358.964992 -30.190186)
		(end 358.487472 -30.190186)
		(width 0.13462)
		(layer "F.Cu")
		(net "P5E_PEX3_STN2_RX_DN<45>")
	)
	(segment
		(start 358.324658 -30.353)
		(end 355.804724 -30.353)
		(width 0.13462)
		(layer "F.Cu")
		(net "P5E_PEX3_STN2_RX_DN<45>")
	)
	(segment
		(start 358.487472 -30.190186)
		(end 358.324658 -30.353)
		(width 0.13462)
		(layer "F.Cu")
		(net "P5E_PEX3_STN2_RX_DN<45>")
	)
	(segment
		(start 370.836698 -119.552466)
		(end 365.647478 -102.432612)
		(width 0.1651)
		(layer "In7.Cu")
		(net "P5E_PEX3_STN2_RX_DN<45>")
	)
	(segment
		(start 393.353798 -263.502648)
		(end 393.43076 -255.646936)
		(width 0.1651)
		(layer "In7.Cu")
		(net "P5E_PEX3_STN2_RX_DN<45>")
	)
	(segment
		(start 359.68813 -35.00755)
		(end 359.712514 -31.973012)
		(width 0.1651)
		(layer "In7.Cu")
		(net "P5E_PEX3_STN2_RX_DN<45>")
	)
	(segment
		(start 394.31595 -271.3736)
		(end 394.31595 -271.345152)
		(width 0.1143)
		(layer "In7.Cu")
		(net "P5E_PEX3_STN2_RX_DN<45>")
	)
	(segment
		(start 393.43076 -255.646936)
		(end 391.830814 -238.16945)
		(width 0.1651)
		(layer "In7.Cu")
		(net "P5E_PEX3_STN2_RX_DN<45>")
	)
	(segment
		(start 394.27023 -273.328638)
		(end 394.27023 -271.41932)
		(width 0.1143)
		(layer "In7.Cu")
		(net "P5E_PEX3_STN2_RX_DN<45>")
	)
	(segment
		(start 360.458004 -85.311742)
		(end 360.648504 -61.48959)
		(width 0.1651)
		(layer "In7.Cu")
		(net "P5E_PEX3_STN2_RX_DN<45>")
	)
	(segment
		(start 360.381042 -57.362344)
		(end 360.49839 -49.868074)
		(width 0.1651)
		(layer "In7.Cu")
		(net "P5E_PEX3_STN2_RX_DN<45>")
	)
	(segment
		(start 355.801422 -30.349698)
		(end 355.510592 -30.058868)
		(width 0.1651)
		(layer "In7.Cu")
		(net "P5E_PEX3_STN2_RX_DN<45>")
	)
	(segment
		(start 359.199434 -40.256206)
		(end 359.163366 -37.96284)
		(width 0.1651)
		(layer "In7.Cu")
		(net "P5E_PEX3_STN2_RX_DN<45>")
	)
	(segment
		(start 394.421106 -273.479514)
		(end 394.27023 -273.328638)
		(width 0.1143)
		(layer "In7.Cu")
		(net "P5E_PEX3_STN2_RX_DN<45>")
	)
	(segment
		(start 394.53566 -273.479514)
		(end 394.421106 -273.479514)
		(width 0.1143)
		(layer "In7.Cu")
		(net "P5E_PEX3_STN2_RX_DN<45>")
	)
	(segment
		(start 360.648504 -60.132976)
		(end 360.381042 -57.362344)
		(width 0.1651)
		(layer "In7.Cu")
		(net "P5E_PEX3_STN2_RX_DN<45>")
	)
	(segment
		(start 365.647478 -102.432104)
		(end 365.63554 -102.392734)
		(width 0.1651)
		(layer "In7.Cu")
		(net "P5E_PEX3_STN2_RX_DN<45>")
	)
	(segment
		(start 391.830814 -238.16945)
		(end 374.118886 -144.505172)
		(width 0.1651)
		(layer "In7.Cu")
		(net "P5E_PEX3_STN2_RX_DN<45>")
	)
	(segment
		(start 394.31595 -271.345152)
		(end 394.31595 -270.28521)
		(width 0.1651)
		(layer "In7.Cu")
		(net "P5E_PEX3_STN2_RX_DN<45>")
	)
	(segment
		(start 359.712514 -31.973012)
		(end 358.0892 -30.349698)
		(width 0.1651)
		(layer "In7.Cu")
		(net "P5E_PEX3_STN2_RX_DN<45>")
	)
	(segment
		(start 374.118886 -144.505172)
		(end 370.836698 -119.552466)
		(width 0.1651)
		(layer "In7.Cu")
		(net "P5E_PEX3_STN2_RX_DN<45>")
	)
	(segment
		(start 394.31595 -270.28521)
		(end 393.353798 -263.502648)
		(width 0.1651)
		(layer "In7.Cu")
		(net "P5E_PEX3_STN2_RX_DN<45>")
	)
	(segment
		(start 394.27023 -271.41932)
		(end 394.31595 -271.3736)
		(width 0.1143)
		(layer "In7.Cu")
		(net "P5E_PEX3_STN2_RX_DN<45>")
	)
	(segment
		(start 394.64996 -273.099784)
		(end 394.64996 -273.365214)
		(width 0.1143)
		(layer "In7.Cu")
		(net "P5E_PEX3_STN2_RX_DN<45>")
	)
	(segment
		(start 360.648504 -61.48959)
		(end 360.648504 -60.132976)
		(width 0.1651)
		(layer "In7.Cu")
		(net "P5E_PEX3_STN2_RX_DN<45>")
	)
	(segment
		(start 359.163366 -37.96284)
		(end 359.68813 -35.00755)
		(width 0.1651)
		(layer "In7.Cu")
		(net "P5E_PEX3_STN2_RX_DN<45>")
	)
	(segment
		(start 358.0892 -30.349698)
		(end 355.801422 -30.349698)
		(width 0.1651)
		(layer "In7.Cu")
		(net "P5E_PEX3_STN2_RX_DN<45>")
	)
	(segment
		(start 365.635286 -102.391972)
		(end 360.458004 -85.311742)
		(width 0.1651)
		(layer "In7.Cu")
		(net "P5E_PEX3_STN2_RX_DN<45>")
	)
	(segment
		(start 365.63554 -102.392734)
		(end 365.635286 -102.391972)
		(width 0.1651)
		(layer "In7.Cu")
		(net "P5E_PEX3_STN2_RX_DN<45>")
	)
	(segment
		(start 365.647478 -102.432612)
		(end 365.647478 -102.432104)
		(width 0.1651)
		(layer "In7.Cu")
		(net "P5E_PEX3_STN2_RX_DN<45>")
	)
	(segment
		(start 394.64996 -273.365214)
		(end 394.53566 -273.479514)
		(width 0.1143)
		(layer "In7.Cu")
		(net "P5E_PEX3_STN2_RX_DN<45>")
	)
	(segment
		(start 360.49839 -49.868074)
		(end 359.199434 -40.256206)
		(width 0.1651)
		(layer "In7.Cu")
		(net "P5E_PEX3_STN2_RX_DN<45>")
	)
	(segment
		(start 422.619932 -356.511606)
		(end 422.3004 -356.831138)
		(width 0.13462)
		(layer "F.Cu")
		(net "P5E_PEX3_STN7_TX_C_DN<118>")
	)
	(segment
		(start 422.3004 -356.831138)
		(end 422.3004 -357.463598)
		(width 0.13462)
		(layer "F.Cu")
		(net "P5E_PEX3_STN7_TX_C_DN<118>")
	)
	(segment
		(start 422.3004 -357.463598)
		(end 422.594532 -357.75773)
		(width 0.13462)
		(layer "F.Cu")
		(net "P5E_PEX3_STN7_TX_C_DN<118>")
	)
	(segment
		(start 417.910772 -386.119878)
		(end 417.436046 -385.004056)
		(width 0.1651)
		(layer "In11.Cu")
		(net "P5E_PEX3_STN7_TX_C_DN<118>")
	)
	(segment
		(start 432.18862 -393.23264)
		(end 417.910772 -386.119878)
		(width 0.1651)
		(layer "In11.Cu")
		(net "P5E_PEX3_STN7_TX_C_DN<118>")
	)
	(segment
		(start 417.2712 -383.3368)
		(end 417.423092 -369.14963)
		(width 0.1651)
		(layer "In11.Cu")
		(net "P5E_PEX3_STN7_TX_C_DN<118>")
	)
	(segment
		(start 417.423092 -369.14963)
		(end 422.303702 -358.889554)
		(width 0.1651)
		(layer "In11.Cu")
		(net "P5E_PEX3_STN7_TX_C_DN<118>")
	)
	(segment
		(start 433.815744 -400.729196)
		(end 433.815744 -394.859764)
		(width 0.1651)
		(layer "In11.Cu")
		(net "P5E_PEX3_STN7_TX_C_DN<118>")
	)
	(segment
		(start 422.303702 -358.04856)
		(end 422.594532 -357.75773)
		(width 0.1651)
		(layer "In11.Cu")
		(net "P5E_PEX3_STN7_TX_C_DN<118>")
	)
	(segment
		(start 432.689762 -401.308062)
		(end 432.816762 -401.181062)
		(width 0.1651)
		(layer "In11.Cu")
		(net "P5E_PEX3_STN7_TX_C_DN<118>")
	)
	(segment
		(start 432.689762 -401.690078)
		(end 432.689762 -401.308062)
		(width 0.1651)
		(layer "In11.Cu")
		(net "P5E_PEX3_STN7_TX_C_DN<118>")
	)
	(segment
		(start 433.815744 -394.859764)
		(end 432.18862 -393.23264)
		(width 0.1651)
		(layer "In11.Cu")
		(net "P5E_PEX3_STN7_TX_C_DN<118>")
	)
	(segment
		(start 432.816762 -401.181062)
		(end 433.363878 -401.181062)
		(width 0.1651)
		(layer "In11.Cu")
		(net "P5E_PEX3_STN7_TX_C_DN<118>")
	)
	(segment
		(start 417.436046 -385.004056)
		(end 417.2712 -383.3368)
		(width 0.1651)
		(layer "In11.Cu")
		(net "P5E_PEX3_STN7_TX_C_DN<118>")
	)
	(segment
		(start 422.303702 -358.889554)
		(end 422.303702 -358.04856)
		(width 0.1651)
		(layer "In11.Cu")
		(net "P5E_PEX3_STN7_TX_C_DN<118>")
	)
	(segment
		(start 433.363878 -401.181062)
		(end 433.815744 -400.729196)
		(width 0.1651)
		(layer "In11.Cu")
		(net "P5E_PEX3_STN7_TX_C_DN<118>")
	)
	(segment
		(start 293.820088 -104.840024)
		(end 300.857412 -104.840024)
		(width 0.13208)
		(layer "F.Cu")
		(net "CLK_50M_NIC5_RBT_REF")
	)
	(segment
		(start 291.595048 -104.830372)
		(end 293.810436 -104.830372)
		(width 0.13208)
		(layer "F.Cu")
		(net "CLK_50M_NIC5_RBT_REF")
	)
	(segment
		(start 293.810436 -104.830372)
		(end 293.820088 -104.840024)
		(width 0.13208)
		(layer "F.Cu")
		(net "CLK_50M_NIC5_RBT_REF")
	)
	(via
		(at 293.810436 -104.830372)
		(size 0.762)
		(drill 0.381)
		(layers "F.Cu" "B.Cu")
		(net "CLK_50M_NIC5_RBT_REF")
	)
	(via
		(at 276.888702 -43.305222)
		(size 0.508)
		(drill 0.254)
		(layers "F.Cu" "B.Cu")
		(net "P12V_SSD9")
	)
	(via
		(at 276.888702 -42.670222)
		(size 0.508)
		(drill 0.254)
		(layers "F.Cu" "B.Cu")
		(net "P12V_SSD9")
	)
	(via
		(at 274.65528 -21.639022)
		(size 0.508)
		(drill 0.254)
		(layers "F.Cu" "B.Cu")
		(net "P12V_SSD9")
	)
	(via
		(at 274.65528 -20.318222)
		(size 0.508)
		(drill 0.254)
		(layers "F.Cu" "B.Cu")
		(net "P12V_SSD9")
	)
	(via
		(at 276.888702 -41.349422)
		(size 0.508)
		(drill 0.254)
		(layers "F.Cu" "B.Cu")
		(net "P12V_SSD9")
	)
	(via
		(at 275.821648 -20.045172)
		(size 0.6604)
		(drill 0.3302)
		(layers "F.Cu" "B.Cu")
		(net "P12V_SSD9")
	)
	(via
		(at 274.424902 -41.241472)
		(size 0.508)
		(drill 0.254)
		(layers "F.Cu" "B.Cu")
		(net "P12V_SSD9")
	)
	(via
		(at 274.65528 -20.978622)
		(size 0.508)
		(drill 0.254)
		(layers "F.Cu" "B.Cu")
		(net "P12V_SSD9")
	)
	(via
		(at 276.888702 -42.009822)
		(size 0.508)
		(drill 0.254)
		(layers "F.Cu" "B.Cu")
		(net "P12V_SSD9")
	)
	(via
		(at 275.16201 -43.041316)
		(size 0.6604)
		(drill 0.3302)
		(layers "F.Cu" "B.Cu")
		(net "P12V_SSD9")
	)
	(via
		(at 274.65528 -19.657822)
		(size 0.508)
		(drill 0.254)
		(layers "F.Cu" "B.Cu")
		(net "P12V_SSD9")
	)
	(via
		(at 274.65528 -18.997422)
		(size 0.508)
		(drill 0.254)
		(layers "F.Cu" "B.Cu")
		(net "P12V_SSD9")
	)
	(via
		(at 275.085302 -41.241472)
		(size 0.508)
		(drill 0.254)
		(layers "F.Cu" "B.Cu")
		(net "P12V_SSD9")
	)
	(via
		(at 277.726648 -20.045172)
		(size 0.6604)
		(drill 0.3302)
		(layers "F.Cu" "B.Cu")
		(net "P12V_SSD9")
	)
	(via
		(at 273.25701 -43.041316)
		(size 0.6604)
		(drill 0.3302)
		(layers "F.Cu" "B.Cu")
		(net "P12V_SSD9")
	)
	(segment
		(start 204.764894 -25.390094)
		(end 203.552044 -25.390094)
		(width 0.13208)
		(layer "F.Cu")
		(net "PRSNT_SSD7_N")
	)
	(segment
		(start 203.002134 -25.940004)
		(end 203.002134 -26.266394)
		(width 0.13208)
		(layer "F.Cu")
		(net "PRSNT_SSD7_N")
	)
	(segment
		(start 203.552044 -25.390094)
		(end 203.002134 -25.940004)
		(width 0.13208)
		(layer "F.Cu")
		(net "PRSNT_SSD7_N")
	)
	(segment
		(start 202.220576 -26.266394)
		(end 203.002134 -26.266394)
		(width 0.13208)
		(layer "F.Cu")
		(net "PRSNT_SSD7_N")
	)
	(via
		(at 203.002134 -26.266394)
		(size 0.508)
		(drill 0.254)
		(layers "F.Cu" "B.Cu")
		(net "PRSNT_SSD7_N")
	)
	(segment
		(start 73.257664 -144.554956)
		(end 73.745852 -144.554956)
		(width 0.13462)
		(layer "F.Cu")
		(net "P5E_PEX0_STN0_TX_C_DN<9>")
	)
	(segment
		(start 82.07375 -144.71777)
		(end 82.394806 -144.396714)
		(width 0.13462)
		(layer "F.Cu")
		(net "P5E_PEX0_STN0_TX_C_DN<9>")
	)
	(segment
		(start 73.745852 -144.554956)
		(end 73.908666 -144.71777)
		(width 0.13462)
		(layer "F.Cu")
		(net "P5E_PEX0_STN0_TX_C_DN<9>")
	)
	(segment
		(start 73.908666 -144.71777)
		(end 82.07375 -144.71777)
		(width 0.13462)
		(layer "F.Cu")
		(net "P5E_PEX0_STN0_TX_C_DN<9>")
	)
	(segment
		(start 443.82563 -32.739584)
		(end 443.496446 -32.4104)
		(width 0.13462)
		(layer "F.Cu")
		(net "P5E_PEX3_STN2_TX_C_DP<34>")
	)
	(segment
		(start 442.243972 -32.4104)
		(end 442.064394 -32.589978)
		(width 0.13462)
		(layer "F.Cu")
		(net "P5E_PEX3_STN2_TX_C_DP<34>")
	)
	(segment
		(start 443.496446 -32.4104)
		(end 442.243972 -32.4104)
		(width 0.13462)
		(layer "F.Cu")
		(net "P5E_PEX3_STN2_TX_C_DP<34>")
	)
	(segment
		(start 442.064394 -32.589978)
		(end 441.564776 -32.589978)
		(width 0.13462)
		(layer "F.Cu")
		(net "P5E_PEX3_STN2_TX_C_DP<34>")
	)
	(segment
		(start 412.378652 -350.365314)
		(end 412.6992 -350.685862)
		(width 0.13462)
		(layer "F.Cu")
		(net "P5E_PEX3_STN7_TX_C_DP<113>")
	)
	(segment
		(start 412.6992 -351.31629)
		(end 412.404052 -351.611438)
		(width 0.13462)
		(layer "F.Cu")
		(net "P5E_PEX3_STN7_TX_C_DP<113>")
	)
	(segment
		(start 412.6992 -350.685862)
		(end 412.6992 -351.31629)
		(width 0.13462)
		(layer "F.Cu")
		(net "P5E_PEX3_STN7_TX_C_DP<113>")
	)
	(segment
		(start 421.74795 -394.370814)
		(end 421.62984 -394.413994)
		(width 0.1651)
		(layer "In11.Cu")
		(net "P5E_PEX3_STN7_TX_C_DP<113>")
	)
	(segment
		(start 410.932122 -363.634782)
		(end 411.044136 -363.51845)
		(width 0.1651)
		(layer "In11.Cu")
		(net "P5E_PEX3_STN7_TX_C_DP<113>")
	)
	(segment
		(start 411.068266 -364.737396)
		(end 411.058614 -364.24235)
		(width 0.1651)
		(layer "In11.Cu")
		(net "P5E_PEX3_STN7_TX_C_DP<113>")
	)
	(segment
		(start 411.082236 -365.461804)
		(end 411.082744 -365.46155)
		(width 0.1651)
		(layer "In11.Cu")
		(net "P5E_PEX3_STN7_TX_C_DP<113>")
	)
	(segment
		(start 412.694882 -351.902268)
		(end 412.404052 -351.611438)
		(width 0.1651)
		(layer "In11.Cu")
		(net "P5E_PEX3_STN7_TX_C_DP<113>")
	)
	(segment
		(start 421.816784 -401.999196)
		(end 422.24706 -401.999196)
		(width 0.1651)
		(layer "In11.Cu")
		(net "P5E_PEX3_STN7_TX_C_DP<113>")
	)
	(segment
		(start 411.058614 -364.24235)
		(end 410.941774 -364.130336)
		(width 0.1651)
		(layer "In11.Cu")
		(net "P5E_PEX3_STN7_TX_C_DP<113>")
	)
	(segment
		(start 421.689784 -401.49018)
		(end 421.689784 -401.872196)
		(width 0.1651)
		(layer "In11.Cu")
		(net "P5E_PEX3_STN7_TX_C_DP<113>")
	)
	(segment
		(start 414.361884 -390.935464)
		(end 411.936692 -386.382768)
		(width 0.1651)
		(layer "In11.Cu")
		(net "P5E_PEX3_STN7_TX_C_DP<113>")
	)
	(segment
		(start 422.24706 -401.999196)
		(end 422.533826 -401.71243)
		(width 0.1651)
		(layer "In11.Cu")
		(net "P5E_PEX3_STN7_TX_C_DP<113>")
	)
	(segment
		(start 411.140402 -353.910646)
		(end 412.694882 -352.356166)
		(width 0.1651)
		(layer "In11.Cu")
		(net "P5E_PEX3_STN7_TX_C_DP<113>")
	)
	(segment
		(start 422.533826 -401.71243)
		(end 422.533826 -396.084806)
		(width 0.1651)
		(layer "In11.Cu")
		(net "P5E_PEX3_STN7_TX_C_DP<113>")
	)
	(segment
		(start 421.62984 -394.413994)
		(end 421.180514 -394.204952)
		(width 0.1651)
		(layer "In11.Cu")
		(net "P5E_PEX3_STN7_TX_C_DP<113>")
	)
	(segment
		(start 421.180514 -394.204952)
		(end 421.137588 -394.086842)
		(width 0.1651)
		(layer "In11.Cu")
		(net "P5E_PEX3_STN7_TX_C_DP<113>")
	)
	(segment
		(start 412.694882 -352.356166)
		(end 412.694882 -351.902268)
		(width 0.1651)
		(layer "In11.Cu")
		(net "P5E_PEX3_STN7_TX_C_DP<113>")
	)
	(segment
		(start 421.689784 -401.872196)
		(end 421.816784 -401.999196)
		(width 0.1651)
		(layer "In11.Cu")
		(net "P5E_PEX3_STN7_TX_C_DP<113>")
	)
	(segment
		(start 422.533826 -394.916406)
		(end 422.197022 -394.579602)
		(width 0.1651)
		(layer "In11.Cu")
		(net "P5E_PEX3_STN7_TX_C_DP<113>")
	)
	(segment
		(start 411.044136 -363.51845)
		(end 410.892752 -355.786436)
		(width 0.1651)
		(layer "In11.Cu")
		(net "P5E_PEX3_STN7_TX_C_DP<113>")
	)
	(segment
		(start 422.444926 -395.995906)
		(end 422.444926 -395.500606)
		(width 0.1651)
		(layer "In11.Cu")
		(net "P5E_PEX3_STN7_TX_C_DP<113>")
	)
	(segment
		(start 411.082744 -365.46155)
		(end 410.965904 -365.349282)
		(width 0.1651)
		(layer "In11.Cu")
		(net "P5E_PEX3_STN7_TX_C_DP<113>")
	)
	(segment
		(start 410.941774 -364.130336)
		(end 410.932122 -363.634782)
		(width 0.1651)
		(layer "In11.Cu")
		(net "P5E_PEX3_STN7_TX_C_DP<113>")
	)
	(segment
		(start 411.453838 -383.488438)
		(end 411.430724 -383.234946)
		(width 0.1651)
		(layer "In11.Cu")
		(net "P5E_PEX3_STN7_TX_C_DP<113>")
	)
	(segment
		(start 422.533826 -396.084806)
		(end 422.444926 -395.995906)
		(width 0.1651)
		(layer "In11.Cu")
		(net "P5E_PEX3_STN7_TX_C_DP<113>")
	)
	(segment
		(start 421.137588 -394.086842)
		(end 414.361884 -390.935464)
		(width 0.1651)
		(layer "In11.Cu")
		(net "P5E_PEX3_STN7_TX_C_DP<113>")
	)
	(segment
		(start 422.533826 -395.411706)
		(end 422.533826 -394.916406)
		(width 0.1651)
		(layer "In11.Cu")
		(net "P5E_PEX3_STN7_TX_C_DP<113>")
	)
	(segment
		(start 410.965904 -365.349282)
		(end 410.956252 -364.853982)
		(width 0.1651)
		(layer "In11.Cu")
		(net "P5E_PEX3_STN7_TX_C_DP<113>")
	)
	(segment
		(start 410.956252 -364.853982)
		(end 411.068266 -364.737396)
		(width 0.1651)
		(layer "In11.Cu")
		(net "P5E_PEX3_STN7_TX_C_DP<113>")
	)
	(segment
		(start 410.892752 -355.786436)
		(end 411.140402 -353.910646)
		(width 0.1651)
		(layer "In11.Cu")
		(net "P5E_PEX3_STN7_TX_C_DP<113>")
	)
	(segment
		(start 422.197022 -394.579602)
		(end 421.74795 -394.370814)
		(width 0.1651)
		(layer "In11.Cu")
		(net "P5E_PEX3_STN7_TX_C_DP<113>")
	)
	(segment
		(start 411.430724 -383.234946)
		(end 411.082236 -365.461804)
		(width 0.1651)
		(layer "In11.Cu")
		(net "P5E_PEX3_STN7_TX_C_DP<113>")
	)
	(segment
		(start 422.444926 -395.500606)
		(end 422.533826 -395.411706)
		(width 0.1651)
		(layer "In11.Cu")
		(net "P5E_PEX3_STN7_TX_C_DP<113>")
	)
	(segment
		(start 411.936692 -386.382768)
		(end 411.453838 -383.488438)
		(width 0.1651)
		(layer "In11.Cu")
		(net "P5E_PEX3_STN7_TX_C_DP<113>")
	)
	(segment
		(start 290.794948 -98.734372)
		(end 290.794948 -99.06254)
		(width 0.13208)
		(layer "F.Cu")
		(net "NIC5_RBT_ARB_OUT")
	)
	(segment
		(start 295.123108 -99.189794)
		(end 295.373298 -99.439984)
		(width 0.13208)
		(layer "F.Cu")
		(net "NIC5_RBT_ARB_OUT")
	)
	(segment
		(start 296.509186 -99.439984)
		(end 300.857412 -99.439984)
		(width 0.13208)
		(layer "F.Cu")
		(net "NIC5_RBT_ARB_OUT")
	)
	(segment
		(start 295.373298 -99.439984)
		(end 296.509186 -99.439984)
		(width 0.13208)
		(layer "F.Cu")
		(net "NIC5_RBT_ARB_OUT")
	)
	(segment
		(start 290.922202 -99.189794)
		(end 295.123108 -99.189794)
		(width 0.13208)
		(layer "F.Cu")
		(net "NIC5_RBT_ARB_OUT")
	)
	(segment
		(start 290.794948 -99.06254)
		(end 290.922202 -99.189794)
		(width 0.13208)
		(layer "F.Cu")
		(net "NIC5_RBT_ARB_OUT")
	)
	(via
		(at 296.509186 -99.439984)
		(size 0.762)
		(drill 0.381)
		(layers "F.Cu" "B.Cu")
		(net "NIC5_RBT_ARB_OUT")
	)
	(via
		(at 249.162062 -43.041316)
		(size 0.6604)
		(drill 0.3302)
		(layers "F.Cu" "B.Cu")
		(net "P12V_SSD8")
	)
	(via
		(at 247.257062 -43.041316)
		(size 0.6604)
		(drill 0.3302)
		(layers "F.Cu" "B.Cu")
		(net "P12V_SSD8")
	)
	(via
		(at 248.655332 -19.657822)
		(size 0.508)
		(drill 0.254)
		(layers "F.Cu" "B.Cu")
		(net "P12V_SSD8")
	)
	(via
		(at 248.655332 -20.978622)
		(size 0.508)
		(drill 0.254)
		(layers "F.Cu" "B.Cu")
		(net "P12V_SSD8")
	)
	(via
		(at 248.655332 -21.639022)
		(size 0.508)
		(drill 0.254)
		(layers "F.Cu" "B.Cu")
		(net "P12V_SSD8")
	)
	(via
		(at 248.655332 -18.997422)
		(size 0.508)
		(drill 0.254)
		(layers "F.Cu" "B.Cu")
		(net "P12V_SSD8")
	)
	(via
		(at 250.888754 -42.670222)
		(size 0.508)
		(drill 0.254)
		(layers "F.Cu" "B.Cu")
		(net "P12V_SSD8")
	)
	(via
		(at 248.655332 -20.318222)
		(size 0.508)
		(drill 0.254)
		(layers "F.Cu" "B.Cu")
		(net "P12V_SSD8")
	)
	(via
		(at 250.505722 -20.045426)
		(size 0.6604)
		(drill 0.3302)
		(layers "F.Cu" "B.Cu")
		(net "P12V_SSD8")
	)
	(via
		(at 252.410722 -20.045426)
		(size 0.6604)
		(drill 0.3302)
		(layers "F.Cu" "B.Cu")
		(net "P12V_SSD8")
	)
	(via
		(at 250.888754 -42.009822)
		(size 0.508)
		(drill 0.254)
		(layers "F.Cu" "B.Cu")
		(net "P12V_SSD8")
	)
	(via
		(at 249.085354 -41.241472)
		(size 0.508)
		(drill 0.254)
		(layers "F.Cu" "B.Cu")
		(net "P12V_SSD8")
	)
	(via
		(at 250.888754 -43.305222)
		(size 0.508)
		(drill 0.254)
		(layers "F.Cu" "B.Cu")
		(net "P12V_SSD8")
	)
	(via
		(at 250.888754 -41.349422)
		(size 0.508)
		(drill 0.254)
		(layers "F.Cu" "B.Cu")
		(net "P12V_SSD8")
	)
	(via
		(at 248.424954 -41.241472)
		(size 0.508)
		(drill 0.254)
		(layers "F.Cu" "B.Cu")
		(net "P12V_SSD8")
	)
	(segment
		(start 68.169536 -151.755094)
		(end 68.006722 -151.917908)
		(width 0.13462)
		(layer "F.Cu")
		(net "P5E_PEX0_STN0_RX_DN<13>")
	)
	(segment
		(start 65.498218 -151.917908)
		(end 65.49771 -151.918416)
		(width 0.13462)
		(layer "F.Cu")
		(net "P5E_PEX0_STN0_RX_DN<13>")
	)
	(segment
		(start 68.65747 -151.755094)
		(end 68.169536 -151.755094)
		(width 0.13462)
		(layer "F.Cu")
		(net "P5E_PEX0_STN0_RX_DN<13>")
	)
	(segment
		(start 68.006722 -151.917908)
		(end 65.498218 -151.917908)
		(width 0.13462)
		(layer "F.Cu")
		(net "P5E_PEX0_STN0_RX_DN<13>")
	)
	(segment
		(start 65.49771 -151.918416)
		(end 65.20307 -151.623776)
		(width 0.13462)
		(layer "F.Cu")
		(net "P5E_PEX0_STN0_RX_DN<13>")
	)
	(segment
		(start 76.4159 -271.773904)
		(end 76.4159 -271.802352)
		(width 0.1143)
		(layer "In5.Cu")
		(net "P5E_PEX0_STN0_RX_DN<13>")
	)
	(segment
		(start 76.473558 -273.479514)
		(end 76.635356 -273.479514)
		(width 0.1143)
		(layer "In5.Cu")
		(net "P5E_PEX0_STN0_RX_DN<13>")
	)
	(segment
		(start 76.635356 -273.479514)
		(end 76.749656 -273.365214)
		(width 0.1143)
		(layer "In5.Cu")
		(net "P5E_PEX0_STN0_RX_DN<13>")
	)
	(segment
		(start 67.814952 -151.914606)
		(end 68.8594 -152.959054)
		(width 0.1651)
		(layer "In5.Cu")
		(net "P5E_PEX0_STN0_RX_DN<13>")
	)
	(segment
		(start 76.37018 -273.376136)
		(end 76.473558 -273.479514)
		(width 0.1143)
		(layer "In5.Cu")
		(net "P5E_PEX0_STN0_RX_DN<13>")
	)
	(segment
		(start 76.37018 -271.848072)
		(end 76.37018 -273.376136)
		(width 0.1143)
		(layer "In5.Cu")
		(net "P5E_PEX0_STN0_RX_DN<13>")
	)
	(segment
		(start 76.857606 -260.64464)
		(end 76.93279 -267.869924)
		(width 0.1651)
		(layer "In5.Cu")
		(net "P5E_PEX0_STN0_RX_DN<13>")
	)
	(segment
		(start 76.4159 -271.802352)
		(end 76.37018 -271.848072)
		(width 0.1143)
		(layer "In5.Cu")
		(net "P5E_PEX0_STN0_RX_DN<13>")
	)
	(segment
		(start 72.265032 -158.80207)
		(end 72.275954 -158.828232)
		(width 0.1651)
		(layer "In5.Cu")
		(net "P5E_PEX0_STN0_RX_DN<13>")
	)
	(segment
		(start 68.8594 -152.959054)
		(end 69.731382 -155.050998)
		(width 0.1651)
		(layer "In5.Cu")
		(net "P5E_PEX0_STN0_RX_DN<13>")
	)
	(segment
		(start 69.731382 -155.050998)
		(end 72.265032 -158.80207)
		(width 0.1651)
		(layer "In5.Cu")
		(net "P5E_PEX0_STN0_RX_DN<13>")
	)
	(segment
		(start 76.4159 -270.540226)
		(end 76.4159 -271.773904)
		(width 0.1651)
		(layer "In5.Cu")
		(net "P5E_PEX0_STN0_RX_DN<13>")
	)
	(segment
		(start 65.4939 -151.914606)
		(end 67.814952 -151.914606)
		(width 0.1651)
		(layer "In5.Cu")
		(net "P5E_PEX0_STN0_RX_DN<13>")
	)
	(segment
		(start 65.20307 -151.623776)
		(end 65.4939 -151.914606)
		(width 0.1651)
		(layer "In5.Cu")
		(net "P5E_PEX0_STN0_RX_DN<13>")
	)
	(segment
		(start 73.301606 -161.295334)
		(end 76.857606 -260.64464)
		(width 0.1651)
		(layer "In5.Cu")
		(net "P5E_PEX0_STN0_RX_DN<13>")
	)
	(segment
		(start 76.749656 -273.365214)
		(end 76.749656 -273.099784)
		(width 0.1143)
		(layer "In5.Cu")
		(net "P5E_PEX0_STN0_RX_DN<13>")
	)
	(segment
		(start 72.275954 -158.828232)
		(end 72.2757 -158.828232)
		(width 0.1651)
		(layer "In5.Cu")
		(net "P5E_PEX0_STN0_RX_DN<13>")
	)
	(segment
		(start 72.2757 -158.828232)
		(end 73.301606 -161.295334)
		(width 0.1651)
		(layer "In5.Cu")
		(net "P5E_PEX0_STN0_RX_DN<13>")
	)
	(segment
		(start 76.93279 -267.869924)
		(end 76.4159 -270.540226)
		(width 0.1651)
		(layer "In5.Cu")
		(net "P5E_PEX0_STN0_RX_DN<13>")
	)
	(segment
		(start 358.48417 -31.99003)
		(end 358.3178 -32.1564)
		(width 0.13462)
		(layer "F.Cu")
		(net "P5E_PEX3_STN2_RX_DN<46>")
	)
	(segment
		(start 358.964992 -31.99003)
		(end 358.48417 -31.99003)
		(width 0.13462)
		(layer "F.Cu")
		(net "P5E_PEX3_STN2_RX_DN<46>")
	)
	(segment
		(start 358.3178 -32.1564)
		(end 357.66248 -32.1564)
		(width 0.13462)
		(layer "F.Cu")
		(net "P5E_PEX3_STN2_RX_DN<46>")
	)
	(segment
		(start 357.66248 -32.1564)
		(end 357.364792 -31.858712)
		(width 0.13462)
		(layer "F.Cu")
		(net "P5E_PEX3_STN2_RX_DN<46>")
	)
	(segment
		(start 359.686098 -61.72327)
		(end 359.494074 -85.450426)
		(width 0.1651)
		(layer "In7.Cu")
		(net "P5E_PEX3_STN2_RX_DN<46>")
	)
	(segment
		(start 393.423902 -275.379688)
		(end 393.5857 -275.379688)
		(width 0.1143)
		(layer "In7.Cu")
		(net "P5E_PEX3_STN2_RX_DN<46>")
	)
	(segment
		(start 358.74452 -32.663638)
		(end 358.707436 -35.04819)
		(width 0.1651)
		(layer "In7.Cu")
		(net "P5E_PEX3_STN2_RX_DN<46>")
	)
	(segment
		(start 358.707436 -35.04819)
		(end 358.183942 -37.856414)
		(width 0.1651)
		(layer "In7.Cu")
		(net "P5E_PEX3_STN2_RX_DN<46>")
	)
	(segment
		(start 357.655622 -32.149542)
		(end 358.23017 -32.149542)
		(width 0.1651)
		(layer "In7.Cu")
		(net "P5E_PEX3_STN2_RX_DN<46>")
	)
	(segment
		(start 392.39063 -263.518142)
		(end 393.365736 -270.38427)
		(width 0.1651)
		(layer "In7.Cu")
		(net "P5E_PEX3_STN2_RX_DN<46>")
	)
	(segment
		(start 393.320016 -275.275802)
		(end 393.423902 -275.379688)
		(width 0.1143)
		(layer "In7.Cu")
		(net "P5E_PEX3_STN2_RX_DN<46>")
	)
	(segment
		(start 393.5857 -275.379688)
		(end 393.7 -275.265388)
		(width 0.1143)
		(layer "In7.Cu")
		(net "P5E_PEX3_STN2_RX_DN<46>")
	)
	(segment
		(start 364.681262 -102.563168)
		(end 364.681516 -102.56393)
		(width 0.1651)
		(layer "In7.Cu")
		(net "P5E_PEX3_STN2_RX_DN<46>")
	)
	(segment
		(start 364.681516 -102.56393)
		(end 364.693454 -102.6033)
		(width 0.1651)
		(layer "In7.Cu")
		(net "P5E_PEX3_STN2_RX_DN<46>")
	)
	(segment
		(start 373.16791 -144.657572)
		(end 390.876282 -238.303054)
		(width 0.1651)
		(layer "In7.Cu")
		(net "P5E_PEX3_STN2_RX_DN<46>")
	)
	(segment
		(start 393.320016 -271.467072)
		(end 393.320016 -275.275802)
		(width 0.1143)
		(layer "In7.Cu")
		(net "P5E_PEX3_STN2_RX_DN<46>")
	)
	(segment
		(start 358.220264 -40.147748)
		(end 359.522014 -49.782222)
		(width 0.1651)
		(layer "In7.Cu")
		(net "P5E_PEX3_STN2_RX_DN<46>")
	)
	(segment
		(start 393.365736 -271.392904)
		(end 393.365736 -271.421352)
		(width 0.1143)
		(layer "In7.Cu")
		(net "P5E_PEX3_STN2_RX_DN<46>")
	)
	(segment
		(start 359.522014 -49.782222)
		(end 359.405936 -57.201562)
		(width 0.1651)
		(layer "In7.Cu")
		(net "P5E_PEX3_STN2_RX_DN<46>")
	)
	(segment
		(start 359.686098 -60.294012)
		(end 359.686098 -61.72327)
		(width 0.1651)
		(layer "In7.Cu")
		(net "P5E_PEX3_STN2_RX_DN<46>")
	)
	(segment
		(start 364.693454 -102.603808)
		(end 369.89258 -119.756174)
		(width 0.1651)
		(layer "In7.Cu")
		(net "P5E_PEX3_STN2_RX_DN<46>")
	)
	(segment
		(start 393.365736 -271.421352)
		(end 393.320016 -271.467072)
		(width 0.1143)
		(layer "In7.Cu")
		(net "P5E_PEX3_STN2_RX_DN<46>")
	)
	(segment
		(start 393.365736 -270.38427)
		(end 393.365736 -271.392904)
		(width 0.1651)
		(layer "In7.Cu")
		(net "P5E_PEX3_STN2_RX_DN<46>")
	)
	(segment
		(start 358.183942 -37.856414)
		(end 358.220264 -40.147748)
		(width 0.1651)
		(layer "In7.Cu")
		(net "P5E_PEX3_STN2_RX_DN<46>")
	)
	(segment
		(start 392.467592 -255.686052)
		(end 392.39063 -263.518142)
		(width 0.1651)
		(layer "In7.Cu")
		(net "P5E_PEX3_STN2_RX_DN<46>")
	)
	(segment
		(start 359.494074 -85.450426)
		(end 364.681262 -102.563168)
		(width 0.1651)
		(layer "In7.Cu")
		(net "P5E_PEX3_STN2_RX_DN<46>")
	)
	(segment
		(start 357.364792 -31.858712)
		(end 357.655622 -32.149542)
		(width 0.1651)
		(layer "In7.Cu")
		(net "P5E_PEX3_STN2_RX_DN<46>")
	)
	(segment
		(start 390.876282 -238.303054)
		(end 392.467592 -255.686052)
		(width 0.1651)
		(layer "In7.Cu")
		(net "P5E_PEX3_STN2_RX_DN<46>")
	)
	(segment
		(start 393.7 -275.265388)
		(end 393.7 -274.999958)
		(width 0.1143)
		(layer "In7.Cu")
		(net "P5E_PEX3_STN2_RX_DN<46>")
	)
	(segment
		(start 369.89258 -119.756174)
		(end 373.16791 -144.657572)
		(width 0.1651)
		(layer "In7.Cu")
		(net "P5E_PEX3_STN2_RX_DN<46>")
	)
	(segment
		(start 359.405936 -57.201562)
		(end 359.686098 -60.294012)
		(width 0.1651)
		(layer "In7.Cu")
		(net "P5E_PEX3_STN2_RX_DN<46>")
	)
	(segment
		(start 364.693454 -102.6033)
		(end 364.693454 -102.603808)
		(width 0.1651)
		(layer "In7.Cu")
		(net "P5E_PEX3_STN2_RX_DN<46>")
	)
	(segment
		(start 358.23017 -32.149542)
		(end 358.74452 -32.663638)
		(width 0.1651)
		(layer "In7.Cu")
		(net "P5E_PEX3_STN2_RX_DN<46>")
	)
	(segment
		(start 371.830346 -305.163728)
		(end 374.399556 -302.594518)
		(width 0.1651)
		(layer "In9.Cu")
		(net "P5E_PEX3_STN7_RX_DP<112>")
	)
	(segment
		(start 418.875464 -394.128752)
		(end 418.408612 -393.96289)
		(width 0.1651)
		(layer "In9.Cu")
		(net "P5E_PEX3_STN7_RX_DP<112>")
	)
	(segment
		(start 369.434872 -309.645558)
		(end 369.435126 -309.645304)
		(width 0.1651)
		(layer "In9.Cu")
		(net "P5E_PEX3_STN7_RX_DP<112>")
	)
	(segment
		(start 377.81611 -335.149444)
		(end 373.560594 -333.807054)
		(width 0.1651)
		(layer "In9.Cu")
		(net "P5E_PEX3_STN7_RX_DP<112>")
	)
	(segment
		(start 367.51514 -327.761854)
		(end 365.7854 -323.585332)
		(width 0.1651)
		(layer "In9.Cu")
		(net "P5E_PEX3_STN7_RX_DP<112>")
	)
	(segment
		(start 396.505684 -339.432392)
		(end 377.81611 -335.149444)
		(width 0.1651)
		(layer "In9.Cu")
		(net "P5E_PEX3_STN7_RX_DP<112>")
	)
	(segment
		(start 387.719316 -301.599854)
		(end 387.999986 -301.599854)
		(width 0.1143)
		(layer "In9.Cu")
		(net "P5E_PEX3_STN7_RX_DP<112>")
	)
	(segment
		(start 420.364666 -394.977112)
		(end 419.702742 -394.315188)
		(width 0.1651)
		(layer "In9.Cu")
		(net "P5E_PEX3_STN7_RX_DP<112>")
	)
	(segment
		(start 369.435126 -309.645304)
		(end 371.830346 -305.163728)
		(width 0.1651)
		(layer "In9.Cu")
		(net "P5E_PEX3_STN7_RX_DP<112>")
	)
	(segment
		(start 384.679952 -300.983904)
		(end 384.7084 -300.983904)
		(width 0.1143)
		(layer "In9.Cu")
		(net "P5E_PEX3_STN7_RX_DP<112>")
	)
	(segment
		(start 420.364666 -408.17292)
		(end 420.364666 -394.977112)
		(width 0.1651)
		(layer "In9.Cu")
		(net "P5E_PEX3_STN7_RX_DP<112>")
	)
	(segment
		(start 417.880292 -393.66698)
		(end 416.700462 -392.70559)
		(width 0.1651)
		(layer "In9.Cu")
		(net "P5E_PEX3_STN7_RX_DP<112>")
	)
	(segment
		(start 416.15868 -392.264138)
		(end 415.774886 -391.951464)
		(width 0.1651)
		(layer "In9.Cu")
		(net "P5E_PEX3_STN7_RX_DP<112>")
	)
	(segment
		(start 409.583636 -376.478292)
		(end 404.920958 -351.02165)
		(width 0.1651)
		(layer "In9.Cu")
		(net "P5E_PEX3_STN7_RX_DP<112>")
	)
	(segment
		(start 400.408902 -341.13978)
		(end 396.505684 -339.432392)
		(width 0.1651)
		(layer "In9.Cu")
		(net "P5E_PEX3_STN7_RX_DP<112>")
	)
	(segment
		(start 401.292314 -346.34932)
		(end 401.03679 -345.731846)
		(width 0.1651)
		(layer "In9.Cu")
		(net "P5E_PEX3_STN7_RX_DP<112>")
	)
	(segment
		(start 373.560594 -333.807054)
		(end 367.51514 -327.761854)
		(width 0.1651)
		(layer "In9.Cu")
		(net "P5E_PEX3_STN7_RX_DP<112>")
	)
	(segment
		(start 416.173412 -392.40714)
		(end 416.15868 -392.264138)
		(width 0.1651)
		(layer "In9.Cu")
		(net "P5E_PEX3_STN7_RX_DP<112>")
	)
	(segment
		(start 416.700462 -392.70559)
		(end 416.55746 -392.720322)
		(width 0.1651)
		(layer "In9.Cu")
		(net "P5E_PEX3_STN7_RX_DP<112>")
	)
	(segment
		(start 415.774886 -391.951464)
		(end 415.631884 -391.965942)
		(width 0.1651)
		(layer "In9.Cu")
		(net "P5E_PEX3_STN7_RX_DP<112>")
	)
	(segment
		(start 365.7854 -317.803276)
		(end 368.229388 -311.902094)
		(width 0.1651)
		(layer "In9.Cu")
		(net "P5E_PEX3_STN7_RX_DP<112>")
	)
	(segment
		(start 415.247582 -391.65276)
		(end 415.233104 -391.510012)
		(width 0.1651)
		(layer "In9.Cu")
		(net "P5E_PEX3_STN7_RX_DP<112>")
	)
	(segment
		(start 415.631884 -391.965942)
		(end 415.247582 -391.65276)
		(width 0.1651)
		(layer "In9.Cu")
		(net "P5E_PEX3_STN7_RX_DP<112>")
	)
	(segment
		(start 414.706308 -391.211816)
		(end 414.322006 -390.898634)
		(width 0.1651)
		(layer "In9.Cu")
		(net "P5E_PEX3_STN7_RX_DP<112>")
	)
	(segment
		(start 419.48989 -408.572208)
		(end 419.61689 -408.699208)
		(width 0.1651)
		(layer "In9.Cu")
		(net "P5E_PEX3_STN7_RX_DP<112>")
	)
	(segment
		(start 387.380988 -301.029624)
		(end 387.624828 -301.273464)
		(width 0.1143)
		(layer "In9.Cu")
		(net "P5E_PEX3_STN7_RX_DP<112>")
	)
	(segment
		(start 404.920958 -351.02165)
		(end 404.566882 -349.891858)
		(width 0.1651)
		(layer "In9.Cu")
		(net "P5E_PEX3_STN7_RX_DP<112>")
	)
	(segment
		(start 414.84931 -391.197338)
		(end 414.706308 -391.211816)
		(width 0.1651)
		(layer "In9.Cu")
		(net "P5E_PEX3_STN7_RX_DP<112>")
	)
	(segment
		(start 379.803406 -300.983904)
		(end 384.679952 -300.983904)
		(width 0.1651)
		(layer "In9.Cu")
		(net "P5E_PEX3_STN7_RX_DP<112>")
	)
	(segment
		(start 365.7854 -323.585332)
		(end 365.7854 -317.803276)
		(width 0.1651)
		(layer "In9.Cu")
		(net "P5E_PEX3_STN7_RX_DP<112>")
	)
	(segment
		(start 413.177482 -389.834882)
		(end 411.57271 -387.446012)
		(width 0.1651)
		(layer "In9.Cu")
		(net "P5E_PEX3_STN7_RX_DP<112>")
	)
	(segment
		(start 419.838378 -408.699208)
		(end 420.364666 -408.17292)
		(width 0.1651)
		(layer "In9.Cu")
		(net "P5E_PEX3_STN7_RX_DP<112>")
	)
	(segment
		(start 418.34689 -393.832842)
		(end 417.880292 -393.66698)
		(width 0.1651)
		(layer "In9.Cu")
		(net "P5E_PEX3_STN7_RX_DP<112>")
	)
	(segment
		(start 368.229388 -311.902094)
		(end 369.434872 -309.645558)
		(width 0.1651)
		(layer "In9.Cu")
		(net "P5E_PEX3_STN7_RX_DP<112>")
	)
	(segment
		(start 404.257002 -348.291658)
		(end 403.658578 -347.523562)
		(width 0.1651)
		(layer "In9.Cu")
		(net "P5E_PEX3_STN7_RX_DP<112>")
	)
	(segment
		(start 416.55746 -392.720322)
		(end 416.173412 -392.40714)
		(width 0.1651)
		(layer "In9.Cu")
		(net "P5E_PEX3_STN7_RX_DP<112>")
	)
	(segment
		(start 384.75412 -301.029624)
		(end 387.380988 -301.029624)
		(width 0.1143)
		(layer "In9.Cu")
		(net "P5E_PEX3_STN7_RX_DP<112>")
	)
	(segment
		(start 387.624828 -301.505366)
		(end 387.719316 -301.599854)
		(width 0.1143)
		(layer "In9.Cu")
		(net "P5E_PEX3_STN7_RX_DP<112>")
	)
	(segment
		(start 411.57271 -387.446012)
		(end 410.783024 -385.366768)
		(width 0.1651)
		(layer "In9.Cu")
		(net "P5E_PEX3_STN7_RX_DP<112>")
	)
	(segment
		(start 374.399556 -302.594518)
		(end 376.406664 -301.76216)
		(width 0.1651)
		(layer "In9.Cu")
		(net "P5E_PEX3_STN7_RX_DP<112>")
	)
	(segment
		(start 401.03679 -345.731846)
		(end 401.03679 -342.099138)
		(width 0.1651)
		(layer "In9.Cu")
		(net "P5E_PEX3_STN7_RX_DP<112>")
	)
	(segment
		(start 384.7084 -300.983904)
		(end 384.75412 -301.029624)
		(width 0.1143)
		(layer "In9.Cu")
		(net "P5E_PEX3_STN7_RX_DP<112>")
	)
	(segment
		(start 404.566882 -349.891858)
		(end 404.257002 -348.291658)
		(width 0.1651)
		(layer "In9.Cu")
		(net "P5E_PEX3_STN7_RX_DP<112>")
	)
	(segment
		(start 401.817332 -346.875354)
		(end 401.292314 -346.34932)
		(width 0.1651)
		(layer "In9.Cu")
		(net "P5E_PEX3_STN7_RX_DP<112>")
	)
	(segment
		(start 419.005258 -394.067284)
		(end 418.875464 -394.128752)
		(width 0.1651)
		(layer "In9.Cu")
		(net "P5E_PEX3_STN7_RX_DP<112>")
	)
	(segment
		(start 414.322006 -390.898634)
		(end 414.307528 -390.755632)
		(width 0.1651)
		(layer "In9.Cu")
		(net "P5E_PEX3_STN7_RX_DP<112>")
	)
	(segment
		(start 418.408612 -393.96289)
		(end 418.34689 -393.832842)
		(width 0.1651)
		(layer "In9.Cu")
		(net "P5E_PEX3_STN7_RX_DP<112>")
	)
	(segment
		(start 410.783024 -385.366768)
		(end 409.583636 -376.478292)
		(width 0.1651)
		(layer "In9.Cu")
		(net "P5E_PEX3_STN7_RX_DP<112>")
	)
	(segment
		(start 403.658578 -347.523562)
		(end 401.817332 -346.875354)
		(width 0.1651)
		(layer "In9.Cu")
		(net "P5E_PEX3_STN7_RX_DP<112>")
	)
	(segment
		(start 419.48989 -408.190192)
		(end 419.48989 -408.572208)
		(width 0.1651)
		(layer "In9.Cu")
		(net "P5E_PEX3_STN7_RX_DP<112>")
	)
	(segment
		(start 387.624828 -301.273464)
		(end 387.624828 -301.505366)
		(width 0.1143)
		(layer "In9.Cu")
		(net "P5E_PEX3_STN7_RX_DP<112>")
	)
	(segment
		(start 419.702742 -394.315188)
		(end 419.005258 -394.067284)
		(width 0.1651)
		(layer "In9.Cu")
		(net "P5E_PEX3_STN7_RX_DP<112>")
	)
	(segment
		(start 401.03679 -342.099138)
		(end 400.408902 -341.13978)
		(width 0.1651)
		(layer "In9.Cu")
		(net "P5E_PEX3_STN7_RX_DP<112>")
	)
	(segment
		(start 419.61689 -408.699208)
		(end 419.838378 -408.699208)
		(width 0.1651)
		(layer "In9.Cu")
		(net "P5E_PEX3_STN7_RX_DP<112>")
	)
	(segment
		(start 376.406664 -301.76216)
		(end 379.803406 -300.983904)
		(width 0.1651)
		(layer "In9.Cu")
		(net "P5E_PEX3_STN7_RX_DP<112>")
	)
	(segment
		(start 414.307528 -390.755632)
		(end 413.177482 -389.834882)
		(width 0.1651)
		(layer "In9.Cu")
		(net "P5E_PEX3_STN7_RX_DP<112>")
	)
	(segment
		(start 415.233104 -391.510012)
		(end 414.84931 -391.197338)
		(width 0.1651)
		(layer "In9.Cu")
		(net "P5E_PEX3_STN7_RX_DP<112>")
	)
	(segment
		(start 306.933854 -98.240088)
		(end 308.145942 -97.028)
		(width 0.13208)
		(layer "F.Cu")
		(net "NIC5_LD_N")
	)
	(segment
		(start 305.457606 -98.240088)
		(end 306.933854 -98.240088)
		(width 0.13208)
		(layer "F.Cu")
		(net "NIC5_LD_N")
	)
	(segment
		(start 308.145942 -97.028)
		(end 308.145942 -95.989648)
		(width 0.13208)
		(layer "F.Cu")
		(net "NIC5_LD_N")
	)
	(via
		(at 308.145942 -95.989648)
		(size 0.508)
		(drill 0.254)
		(layers "F.Cu" "B.Cu")
		(net "NIC5_LD_N")
	)
	(segment
		(start 308.145942 -95.989648)
		(end 309.341774 -95.989648)
		(width 0.13208)
		(layer "B.Cu")
		(net "NIC5_LD_N")
	)
	(via
		(at 210.555332 -21.639022)
		(size 0.508)
		(drill 0.254)
		(layers "F.Cu" "B.Cu")
		(net "P12V_SSD7")
	)
	(via
		(at 209.157062 -43.041316)
		(size 0.6604)
		(drill 0.3302)
		(layers "F.Cu" "B.Cu")
		(net "P12V_SSD7")
	)
	(via
		(at 212.788754 -42.670222)
		(size 0.508)
		(drill 0.254)
		(layers "F.Cu" "B.Cu")
		(net "P12V_SSD7")
	)
	(via
		(at 213.882986 -20.38731)
		(size 0.6604)
		(drill 0.3302)
		(layers "F.Cu" "B.Cu")
		(net "P12V_SSD7")
	)
	(via
		(at 210.555332 -19.657822)
		(size 0.508)
		(drill 0.254)
		(layers "F.Cu" "B.Cu")
		(net "P12V_SSD7")
	)
	(via
		(at 211.977986 -20.38731)
		(size 0.6604)
		(drill 0.3302)
		(layers "F.Cu" "B.Cu")
		(net "P12V_SSD7")
	)
	(via
		(at 211.062062 -43.041316)
		(size 0.6604)
		(drill 0.3302)
		(layers "F.Cu" "B.Cu")
		(net "P12V_SSD7")
	)
	(via
		(at 210.555332 -20.978622)
		(size 0.508)
		(drill 0.254)
		(layers "F.Cu" "B.Cu")
		(net "P12V_SSD7")
	)
	(via
		(at 212.788754 -43.305222)
		(size 0.508)
		(drill 0.254)
		(layers "F.Cu" "B.Cu")
		(net "P12V_SSD7")
	)
	(via
		(at 210.985354 -41.241472)
		(size 0.508)
		(drill 0.254)
		(layers "F.Cu" "B.Cu")
		(net "P12V_SSD7")
	)
	(via
		(at 210.324954 -41.241472)
		(size 0.508)
		(drill 0.254)
		(layers "F.Cu" "B.Cu")
		(net "P12V_SSD7")
	)
	(via
		(at 212.788754 -41.349422)
		(size 0.508)
		(drill 0.254)
		(layers "F.Cu" "B.Cu")
		(net "P12V_SSD7")
	)
	(via
		(at 210.555332 -20.318222)
		(size 0.508)
		(drill 0.254)
		(layers "F.Cu" "B.Cu")
		(net "P12V_SSD7")
	)
	(via
		(at 212.788754 -42.009822)
		(size 0.508)
		(drill 0.254)
		(layers "F.Cu" "B.Cu")
		(net "P12V_SSD7")
	)
	(via
		(at 210.555332 -18.997422)
		(size 0.508)
		(drill 0.254)
		(layers "F.Cu" "B.Cu")
		(net "P12V_SSD7")
	)
	(segment
		(start 409.202128 -25.940004)
		(end 409.202128 -26.266394)
		(width 0.13208)
		(layer "F.Cu")
		(net "PRSNT_SSD14_N")
	)
	(segment
		(start 409.752038 -25.390094)
		(end 409.202128 -25.940004)
		(width 0.13208)
		(layer "F.Cu")
		(net "PRSNT_SSD14_N")
	)
	(segment
		(start 410.964888 -25.390094)
		(end 409.752038 -25.390094)
		(width 0.13208)
		(layer "F.Cu")
		(net "PRSNT_SSD14_N")
	)
	(segment
		(start 409.202128 -26.266394)
		(end 408.42057 -26.266394)
		(width 0.13208)
		(layer "F.Cu")
		(net "PRSNT_SSD14_N")
	)
	(via
		(at 409.202128 -26.266394)
		(size 0.508)
		(drill 0.254)
		(layers "F.Cu" "B.Cu")
		(net "PRSNT_SSD14_N")
	)
	(segment
		(start 79.440024 -153.992072)
		(end 79.752698 -154.304746)
		(width 0.13462)
		(layer "F.Cu")
		(net "P5E_PEX0_STN0_TX_C_DN<14>")
	)
	(segment
		(start 73.257664 -154.15514)
		(end 73.745852 -154.15514)
		(width 0.13462)
		(layer "F.Cu")
		(net "P5E_PEX0_STN0_TX_C_DN<14>")
	)
	(segment
		(start 73.90892 -153.992072)
		(end 79.440024 -153.992072)
		(width 0.13462)
		(layer "F.Cu")
		(net "P5E_PEX0_STN0_TX_C_DN<14>")
	)
	(segment
		(start 73.745852 -154.15514)
		(end 73.90892 -153.992072)
		(width 0.13462)
		(layer "F.Cu")
		(net "P5E_PEX0_STN0_TX_C_DN<14>")
	)
	(segment
		(start 283.325062 -122.95505)
		(end 282.842462 -122.95505)
		(width 0.13462)
		(layer "F.Cu")
		(net "P5E_PEX2_STN1_RX_DP<26>")
	)
	(segment
		(start 286.296862 -122.822716)
		(end 286.000698 -123.11888)
		(width 0.13462)
		(layer "F.Cu")
		(net "P5E_PEX2_STN1_RX_DP<26>")
	)
	(segment
		(start 283.488892 -123.11888)
		(end 283.325062 -122.95505)
		(width 0.13462)
		(layer "F.Cu")
		(net "P5E_PEX2_STN1_RX_DP<26>")
	)
	(segment
		(start 286.000698 -123.11888)
		(end 283.488892 -123.11888)
		(width 0.13462)
		(layer "F.Cu")
		(net "P5E_PEX2_STN1_RX_DP<26>")
	)
	(segment
		(start 276.719284 -129.219198)
		(end 276.549104 -129.59461)
		(width 0.1651)
		(layer "In5.Cu")
		(net "P5E_PEX2_STN1_RX_DP<26>")
	)
	(segment
		(start 286.296862 -122.822716)
		(end 286.006032 -123.113546)
		(width 0.1651)
		(layer "In5.Cu")
		(net "P5E_PEX2_STN1_RX_DP<26>")
	)
	(segment
		(start 300.779688 -271.600168)
		(end 300.779688 -273.45513)
		(width 0.1143)
		(layer "In5.Cu")
		(net "P5E_PEX2_STN1_RX_DP<26>")
	)
	(segment
		(start 300.733968 -271.554448)
		(end 300.779688 -271.600168)
		(width 0.1143)
		(layer "In5.Cu")
		(net "P5E_PEX2_STN1_RX_DP<26>")
	)
	(segment
		(start 286.006032 -123.113546)
		(end 284.019244 -123.113546)
		(width 0.1651)
		(layer "In5.Cu")
		(net "P5E_PEX2_STN1_RX_DP<26>")
	)
	(segment
		(start 300.733968 -271.526)
		(end 300.733968 -271.554448)
		(width 0.1143)
		(layer "In5.Cu")
		(net "P5E_PEX2_STN1_RX_DP<26>")
	)
	(segment
		(start 301.349664 -273.784314)
		(end 301.349664 -274.049744)
		(width 0.1143)
		(layer "In5.Cu")
		(net "P5E_PEX2_STN1_RX_DP<26>")
	)
	(segment
		(start 279.599644 -125.839474)
		(end 278.893524 -126.46787)
		(width 0.1651)
		(layer "In5.Cu")
		(net "P5E_PEX2_STN1_RX_DP<26>")
	)
	(segment
		(start 274.8788 -139.268962)
		(end 273.858482 -142.790672)
		(width 0.1651)
		(layer "In5.Cu")
		(net "P5E_PEX2_STN1_RX_DP<26>")
	)
	(segment
		(start 271.026128 -147.406106)
		(end 271.675606 -157.418786)
		(width 0.1651)
		(layer "In5.Cu")
		(net "P5E_PEX2_STN1_RX_DP<26>")
	)
	(segment
		(start 284.019244 -123.113546)
		(end 279.599644 -125.839474)
		(width 0.1651)
		(layer "In5.Cu")
		(net "P5E_PEX2_STN1_RX_DP<26>")
	)
	(segment
		(start 300.779688 -273.45513)
		(end 300.994572 -273.670014)
		(width 0.1143)
		(layer "In5.Cu")
		(net "P5E_PEX2_STN1_RX_DP<26>")
	)
	(segment
		(start 273.858482 -142.790672)
		(end 271.355058 -146.151092)
		(width 0.1651)
		(layer "In5.Cu")
		(net "P5E_PEX2_STN1_RX_DP<26>")
	)
	(segment
		(start 276.549104 -129.59461)
		(end 274.8788 -139.268962)
		(width 0.1651)
		(layer "In5.Cu")
		(net "P5E_PEX2_STN1_RX_DP<26>")
	)
	(segment
		(start 271.675606 -157.418786)
		(end 272.491454 -161.945066)
		(width 0.1651)
		(layer "In5.Cu")
		(net "P5E_PEX2_STN1_RX_DP<26>")
	)
	(segment
		(start 272.491454 -161.945066)
		(end 300.733968 -267.93063)
		(width 0.1651)
		(layer "In5.Cu")
		(net "P5E_PEX2_STN1_RX_DP<26>")
	)
	(segment
		(start 300.733968 -267.93063)
		(end 300.733968 -271.526)
		(width 0.1651)
		(layer "In5.Cu")
		(net "P5E_PEX2_STN1_RX_DP<26>")
	)
	(segment
		(start 278.893524 -126.46787)
		(end 276.719284 -129.219198)
		(width 0.1651)
		(layer "In5.Cu")
		(net "P5E_PEX2_STN1_RX_DP<26>")
	)
	(segment
		(start 271.355058 -146.151092)
		(end 271.026128 -147.406106)
		(width 0.1651)
		(layer "In5.Cu")
		(net "P5E_PEX2_STN1_RX_DP<26>")
	)
	(segment
		(start 301.235364 -273.670014)
		(end 301.349664 -273.784314)
		(width 0.1143)
		(layer "In5.Cu")
		(net "P5E_PEX2_STN1_RX_DP<26>")
	)
	(segment
		(start 300.994572 -273.670014)
		(end 301.235364 -273.670014)
		(width 0.1143)
		(layer "In5.Cu")
		(net "P5E_PEX2_STN1_RX_DP<26>")
	)
	(segment
		(start 384.331464 -32.4358)
		(end 384.485642 -32.589978)
		(width 0.13462)
		(layer "F.Cu")
		(net "P5E_PEX3_STN2_RX_DP<42>")
	)
	(segment
		(start 384.485642 -32.589978)
		(end 384.96494 -32.589978)
		(width 0.13462)
		(layer "F.Cu")
		(net "P5E_PEX3_STN2_RX_DP<42>")
	)
	(segment
		(start 383.651252 -32.4358)
		(end 384.331464 -32.4358)
		(width 0.13462)
		(layer "F.Cu")
		(net "P5E_PEX3_STN2_RX_DP<42>")
	)
	(segment
		(start 383.36474 -32.722312)
		(end 383.651252 -32.4358)
		(width 0.13462)
		(layer "F.Cu")
		(net "P5E_PEX3_STN2_RX_DP<42>")
	)
	(segment
		(start 384.448812 -33.533842)
		(end 384.460496 -32.7787)
		(width 0.1651)
		(layer "In7.Cu")
		(net "P5E_PEX3_STN2_RX_DP<42>")
	)
	(segment
		(start 384.425698 -35.019996)
		(end 384.43789 -34.232596)
		(width 0.1651)
		(layer "In7.Cu")
		(net "P5E_PEX3_STN2_RX_DP<42>")
	)
	(segment
		(start 396.883636 -267.781786)
		(end 396.43939 -263.273032)
		(width 0.1651)
		(layer "In7.Cu")
		(net "P5E_PEX3_STN2_RX_DP<42>")
	)
	(segment
		(start 384.216402 -35.58794)
		(end 384.33502 -35.50666)
		(width 0.1651)
		(layer "In7.Cu")
		(net "P5E_PEX3_STN2_RX_DP<42>")
	)
	(segment
		(start 384.43789 -34.232596)
		(end 384.337814 -34.129472)
		(width 0.1651)
		(layer "In7.Cu")
		(net "P5E_PEX3_STN2_RX_DP<42>")
	)
	(segment
		(start 396.43939 -263.273032)
		(end 396.662656 -258.724654)
		(width 0.1651)
		(layer "In7.Cu")
		(net "P5E_PEX3_STN2_RX_DP<42>")
	)
	(segment
		(start 389.181594 -119.585994)
		(end 388.738872 -104.96804)
		(width 0.1651)
		(layer "In7.Cu")
		(net "P5E_PEX3_STN2_RX_DP<42>")
	)
	(segment
		(start 385.152646 -55.371238)
		(end 385.244848 -49.45253)
		(width 0.1651)
		(layer "In7.Cu")
		(net "P5E_PEX3_STN2_RX_DP<42>")
	)
	(segment
		(start 385.244848 -49.45253)
		(end 383.931414 -39.731442)
		(width 0.1651)
		(layer "In7.Cu")
		(net "P5E_PEX3_STN2_RX_DP<42>")
	)
	(segment
		(start 396.929356 -275.354796)
		(end 396.929356 -271.467072)
		(width 0.1143)
		(layer "In7.Cu")
		(net "P5E_PEX3_STN2_RX_DP<42>")
	)
	(segment
		(start 397.38554 -275.570188)
		(end 397.144748 -275.570188)
		(width 0.1143)
		(layer "In7.Cu")
		(net "P5E_PEX3_STN2_RX_DP<42>")
	)
	(segment
		(start 396.831312 -250.005342)
		(end 388.87527 -148.011896)
		(width 0.1651)
		(layer "In7.Cu")
		(net "P5E_PEX3_STN2_RX_DP<42>")
	)
	(segment
		(start 384.345434 -33.633918)
		(end 384.448812 -33.533842)
		(width 0.1651)
		(layer "In7.Cu")
		(net "P5E_PEX3_STN2_RX_DP<42>")
	)
	(segment
		(start 384.113278 -32.431482)
		(end 383.65557 -32.431482)
		(width 0.1651)
		(layer "In7.Cu")
		(net "P5E_PEX3_STN2_RX_DP<42>")
	)
	(segment
		(start 384.337814 -34.129472)
		(end 384.345434 -33.633918)
		(width 0.1651)
		(layer "In7.Cu")
		(net "P5E_PEX3_STN2_RX_DP<42>")
	)
	(segment
		(start 385.544822 -65.176654)
		(end 385.152646 -55.371238)
		(width 0.1651)
		(layer "In7.Cu")
		(net "P5E_PEX3_STN2_RX_DP<42>")
	)
	(segment
		(start 396.662656 -258.724654)
		(end 396.831312 -250.005342)
		(width 0.1651)
		(layer "In7.Cu")
		(net "P5E_PEX3_STN2_RX_DP<42>")
	)
	(segment
		(start 397.144748 -275.570188)
		(end 396.929356 -275.354796)
		(width 0.1143)
		(layer "In7.Cu")
		(net "P5E_PEX3_STN2_RX_DP<42>")
	)
	(segment
		(start 384.12547 -36.075112)
		(end 384.216402 -35.58794)
		(width 0.1651)
		(layer "In7.Cu")
		(net "P5E_PEX3_STN2_RX_DP<42>")
	)
	(segment
		(start 388.738872 -104.96804)
		(end 385.544822 -65.176654)
		(width 0.1651)
		(layer "In7.Cu")
		(net "P5E_PEX3_STN2_RX_DP<42>")
	)
	(segment
		(start 397.49984 -275.949918)
		(end 397.49984 -275.684488)
		(width 0.1143)
		(layer "In7.Cu")
		(net "P5E_PEX3_STN2_RX_DP<42>")
	)
	(segment
		(start 383.65557 -32.431482)
		(end 383.36474 -32.722312)
		(width 0.1651)
		(layer "In7.Cu")
		(net "P5E_PEX3_STN2_RX_DP<42>")
	)
	(segment
		(start 396.929356 -271.467072)
		(end 396.883636 -271.421352)
		(width 0.1143)
		(layer "In7.Cu")
		(net "P5E_PEX3_STN2_RX_DP<42>")
	)
	(segment
		(start 396.883636 -271.421352)
		(end 396.883636 -271.392904)
		(width 0.1143)
		(layer "In7.Cu")
		(net "P5E_PEX3_STN2_RX_DP<42>")
	)
	(segment
		(start 384.20675 -36.19373)
		(end 384.12547 -36.075112)
		(width 0.1651)
		(layer "In7.Cu")
		(net "P5E_PEX3_STN2_RX_DP<42>")
	)
	(segment
		(start 384.460496 -32.7787)
		(end 384.113278 -32.431482)
		(width 0.1651)
		(layer "In7.Cu")
		(net "P5E_PEX3_STN2_RX_DP<42>")
	)
	(segment
		(start 396.883636 -271.392904)
		(end 396.883636 -267.781786)
		(width 0.1651)
		(layer "In7.Cu")
		(net "P5E_PEX3_STN2_RX_DP<42>")
	)
	(segment
		(start 383.931414 -39.731442)
		(end 383.901442 -37.832538)
		(width 0.1651)
		(layer "In7.Cu")
		(net "P5E_PEX3_STN2_RX_DP<42>")
	)
	(segment
		(start 388.87527 -148.011896)
		(end 389.181594 -119.585994)
		(width 0.1651)
		(layer "In7.Cu")
		(net "P5E_PEX3_STN2_RX_DP<42>")
	)
	(segment
		(start 384.33502 -35.50666)
		(end 384.425698 -35.019996)
		(width 0.1651)
		(layer "In7.Cu")
		(net "P5E_PEX3_STN2_RX_DP<42>")
	)
	(segment
		(start 397.49984 -275.684488)
		(end 397.38554 -275.570188)
		(width 0.1143)
		(layer "In7.Cu")
		(net "P5E_PEX3_STN2_RX_DP<42>")
	)
	(segment
		(start 383.901442 -37.832538)
		(end 384.20675 -36.19373)
		(width 0.1651)
		(layer "In7.Cu")
		(net "P5E_PEX3_STN2_RX_DP<42>")
	)
	(segment
		(start 432.936904 -341.271352)
		(end 422.548558 -337.380326)
		(width 0.1651)
		(layer "In9.Cu")
		(net "P5E_PEX3_STN7_RX_DN<123>")
	)
	(segment
		(start 393.599416 -325.931276)
		(end 393.485116 -325.991474)
		(width 0.1651)
		(layer "In9.Cu")
		(net "P5E_PEX3_STN7_RX_DN<123>")
	)
	(segment
		(start 386.716016 -319.865248)
		(end 386.670296 -319.819528)
		(width 0.1143)
		(layer "In9.Cu")
		(net "P5E_PEX3_STN7_RX_DN<123>")
	)
	(segment
		(start 394.13307 -326.192896)
		(end 394.072872 -326.078088)
		(width 0.1651)
		(layer "In9.Cu")
		(net "P5E_PEX3_STN7_RX_DN<123>")
	)
	(segment
		(start 422.548558 -337.380326)
		(end 408.217624 -330.623926)
		(width 0.1651)
		(layer "In9.Cu")
		(net "P5E_PEX3_STN7_RX_DN<123>")
	)
	(segment
		(start 386.716016 -321.539108)
		(end 386.716016 -319.893696)
		(width 0.1651)
		(layer "In9.Cu")
		(net "P5E_PEX3_STN7_RX_DN<123>")
	)
	(segment
		(start 386.670296 -319.819528)
		(end 386.670296 -318.447674)
		(width 0.1143)
		(layer "In9.Cu")
		(net "P5E_PEX3_STN7_RX_DN<123>")
	)
	(segment
		(start 389.325104 -324.701154)
		(end 387.474714 -323.370956)
		(width 0.1651)
		(layer "In9.Cu")
		(net "P5E_PEX3_STN7_RX_DN<123>")
	)
	(segment
		(start 389.32612 -324.701408)
		(end 389.325104 -324.701154)
		(width 0.1651)
		(layer "In9.Cu")
		(net "P5E_PEX3_STN7_RX_DN<123>")
	)
	(segment
		(start 433.185062 -341.629492)
		(end 432.936904 -341.271352)
		(width 0.1651)
		(layer "In9.Cu")
		(net "P5E_PEX3_STN7_RX_DN<123>")
	)
	(segment
		(start 426.089826 -384.590036)
		(end 426.089826 -384.20802)
		(width 0.1651)
		(layer "In9.Cu")
		(net "P5E_PEX3_STN7_RX_DN<123>")
	)
	(segment
		(start 386.716016 -319.893696)
		(end 386.716016 -319.865248)
		(width 0.1143)
		(layer "In9.Cu")
		(net "P5E_PEX3_STN7_RX_DN<123>")
	)
	(segment
		(start 426.089826 -384.20802)
		(end 426.216826 -384.08102)
		(width 0.1651)
		(layer "In9.Cu")
		(net "P5E_PEX3_STN7_RX_DN<123>")
	)
	(segment
		(start 387.474714 -323.370956)
		(end 386.716016 -321.539108)
		(width 0.1651)
		(layer "In9.Cu")
		(net "P5E_PEX3_STN7_RX_DN<123>")
	)
	(segment
		(start 386.797804 -318.320166)
		(end 386.961126 -318.320166)
		(width 0.1143)
		(layer "In9.Cu")
		(net "P5E_PEX3_STN7_RX_DN<123>")
	)
	(segment
		(start 426.216826 -384.08102)
		(end 426.555662 -384.08102)
		(width 0.1651)
		(layer "In9.Cu")
		(net "P5E_PEX3_STN7_RX_DN<123>")
	)
	(segment
		(start 427.246796 -369.279678)
		(end 433.185062 -358.46258)
		(width 0.1651)
		(layer "In9.Cu")
		(net "P5E_PEX3_STN7_RX_DN<123>")
	)
	(segment
		(start 387.050026 -318.409066)
		(end 387.050026 -318.699896)
		(width 0.1143)
		(layer "In9.Cu")
		(net "P5E_PEX3_STN7_RX_DN<123>")
	)
	(segment
		(start 406.783794 -330.11745)
		(end 394.13307 -326.192642)
		(width 0.1651)
		(layer "In9.Cu")
		(net "P5E_PEX3_STN7_RX_DN<123>")
	)
	(segment
		(start 408.217624 -330.623926)
		(end 406.783794 -330.11745)
		(width 0.1651)
		(layer "In9.Cu")
		(net "P5E_PEX3_STN7_RX_DN<123>")
	)
	(segment
		(start 386.961126 -318.320166)
		(end 387.050026 -318.409066)
		(width 0.1143)
		(layer "In9.Cu")
		(net "P5E_PEX3_STN7_RX_DN<123>")
	)
	(segment
		(start 427.246796 -383.389886)
		(end 427.246796 -369.279678)
		(width 0.1651)
		(layer "In9.Cu")
		(net "P5E_PEX3_STN7_RX_DN<123>")
	)
	(segment
		(start 394.13307 -326.192642)
		(end 394.13307 -326.192896)
		(width 0.1651)
		(layer "In9.Cu")
		(net "P5E_PEX3_STN7_RX_DN<123>")
	)
	(segment
		(start 386.670296 -318.447674)
		(end 386.797804 -318.320166)
		(width 0.1143)
		(layer "In9.Cu")
		(net "P5E_PEX3_STN7_RX_DN<123>")
	)
	(segment
		(start 393.485116 -325.991474)
		(end 389.32612 -324.701408)
		(width 0.1651)
		(layer "In9.Cu")
		(net "P5E_PEX3_STN7_RX_DN<123>")
	)
	(segment
		(start 426.555662 -384.08102)
		(end 427.246796 -383.389886)
		(width 0.1651)
		(layer "In9.Cu")
		(net "P5E_PEX3_STN7_RX_DN<123>")
	)
	(segment
		(start 433.185062 -358.46258)
		(end 433.185062 -341.629492)
		(width 0.1651)
		(layer "In9.Cu")
		(net "P5E_PEX3_STN7_RX_DN<123>")
	)
	(segment
		(start 394.072872 -326.078088)
		(end 393.599416 -325.931276)
		(width 0.1651)
		(layer "In9.Cu")
		(net "P5E_PEX3_STN7_RX_DN<123>")
	)
	(segment
		(start 304.789586 -113.05159)
		(end 305.006248 -112.834928)
		(width 0.13208)
		(layer "F.Cu")
		(net "NIC5_BIF0_N")
	)
	(segment
		(start 303.011078 -110.530132)
		(end 303.441354 -110.960408)
		(width 0.13208)
		(layer "F.Cu")
		(net "NIC5_BIF0_N")
	)
	(segment
		(start 304.246026 -113.05159)
		(end 304.789586 -113.05159)
		(width 0.13208)
		(layer "F.Cu")
		(net "NIC5_BIF0_N")
	)
	(segment
		(start 305.006248 -112.834928)
		(end 305.457606 -112.834928)
		(width 0.13208)
		(layer "F.Cu")
		(net "NIC5_BIF0_N")
	)
	(segment
		(start 303.441354 -112.246918)
		(end 304.246026 -113.05159)
		(width 0.13208)
		(layer "F.Cu")
		(net "NIC5_BIF0_N")
	)
	(segment
		(start 303.441354 -110.960408)
		(end 303.441354 -112.246918)
		(width 0.13208)
		(layer "F.Cu")
		(net "NIC5_BIF0_N")
	)
	(via
		(at 303.011078 -110.530132)
		(size 0.508)
		(drill 0.254)
		(layers "F.Cu" "B.Cu")
		(net "NIC5_BIF0_N")
	)
	(segment
		(start 300.675802 -108.194856)
		(end 298.57319 -108.194856)
		(width 0.13208)
		(layer "B.Cu")
		(net "NIC5_BIF0_N")
	)
	(segment
		(start 294.200326 -108.462318)
		(end 295.183306 -108.462318)
		(width 0.13208)
		(layer "B.Cu")
		(net "NIC5_BIF0_N")
	)
	(segment
		(start 298.229528 -107.851194)
		(end 295.318942 -107.851194)
		(width 0.13208)
		(layer "B.Cu")
		(net "NIC5_BIF0_N")
	)
	(segment
		(start 303.011078 -110.530132)
		(end 300.675802 -108.194856)
		(width 0.13208)
		(layer "B.Cu")
		(net "NIC5_BIF0_N")
	)
	(segment
		(start 295.183306 -107.98683)
		(end 295.183306 -108.462318)
		(width 0.13208)
		(layer "B.Cu")
		(net "NIC5_BIF0_N")
	)
	(segment
		(start 295.318942 -107.851194)
		(end 295.183306 -107.98683)
		(width 0.13208)
		(layer "B.Cu")
		(net "NIC5_BIF0_N")
	)
	(segment
		(start 298.57319 -108.194856)
		(end 298.229528 -107.851194)
		(width 0.13208)
		(layer "B.Cu")
		(net "NIC5_BIF0_N")
	)
	(segment
		(start 294.197278 -108.465366)
		(end 294.200326 -108.462318)
		(width 0.13208)
		(layer "B.Cu")
		(net "NIC5_BIF0_N")
	)
	(via
		(at 184.555384 -21.639022)
		(size 0.508)
		(drill 0.254)
		(layers "F.Cu" "B.Cu")
		(net "P12V_SSD6")
	)
	(via
		(at 184.555384 -18.997422)
		(size 0.508)
		(drill 0.254)
		(layers "F.Cu" "B.Cu")
		(net "P12V_SSD6")
	)
	(via
		(at 183.157114 -43.041316)
		(size 0.6604)
		(drill 0.3302)
		(layers "F.Cu" "B.Cu")
		(net "P12V_SSD6")
	)
	(via
		(at 184.555384 -19.657822)
		(size 0.508)
		(drill 0.254)
		(layers "F.Cu" "B.Cu")
		(net "P12V_SSD6")
	)
	(via
		(at 186.788806 -41.349422)
		(size 0.508)
		(drill 0.254)
		(layers "F.Cu" "B.Cu")
		(net "P12V_SSD6")
	)
	(via
		(at 184.985406 -41.241472)
		(size 0.508)
		(drill 0.254)
		(layers "F.Cu" "B.Cu")
		(net "P12V_SSD6")
	)
	(via
		(at 186.788806 -42.670222)
		(size 0.508)
		(drill 0.254)
		(layers "F.Cu" "B.Cu")
		(net "P12V_SSD6")
	)
	(via
		(at 184.325006 -41.241472)
		(size 0.508)
		(drill 0.254)
		(layers "F.Cu" "B.Cu")
		(net "P12V_SSD6")
	)
	(via
		(at 187.284868 -20.643596)
		(size 0.6604)
		(drill 0.3302)
		(layers "F.Cu" "B.Cu")
		(net "P12V_SSD6")
	)
	(via
		(at 186.788806 -43.305222)
		(size 0.508)
		(drill 0.254)
		(layers "F.Cu" "B.Cu")
		(net "P12V_SSD6")
	)
	(via
		(at 184.555384 -20.978622)
		(size 0.508)
		(drill 0.254)
		(layers "F.Cu" "B.Cu")
		(net "P12V_SSD6")
	)
	(via
		(at 185.062114 -43.041316)
		(size 0.6604)
		(drill 0.3302)
		(layers "F.Cu" "B.Cu")
		(net "P12V_SSD6")
	)
	(via
		(at 186.788806 -42.009822)
		(size 0.508)
		(drill 0.254)
		(layers "F.Cu" "B.Cu")
		(net "P12V_SSD6")
	)
	(via
		(at 184.555384 -20.318222)
		(size 0.508)
		(drill 0.254)
		(layers "F.Cu" "B.Cu")
		(net "P12V_SSD6")
	)
	(via
		(at 185.379868 -20.643596)
		(size 0.6604)
		(drill 0.3302)
		(layers "F.Cu" "B.Cu")
		(net "P12V_SSD6")
	)
	(segment
		(start 65.498218 -132.282184)
		(end 65.20307 -132.577332)
		(width 0.13462)
		(layer "F.Cu")
		(net "P5E_PEX0_STN0_RX_DP<5>")
	)
	(segment
		(start 68.169536 -132.444998)
		(end 68.006722 -132.282184)
		(width 0.13462)
		(layer "F.Cu")
		(net "P5E_PEX0_STN0_RX_DP<5>")
	)
	(segment
		(start 68.006722 -132.282184)
		(end 65.498218 -132.282184)
		(width 0.13462)
		(layer "F.Cu")
		(net "P5E_PEX0_STN0_RX_DP<5>")
	)
	(segment
		(start 68.65747 -132.444998)
		(end 68.169536 -132.444998)
		(width 0.13462)
		(layer "F.Cu")
		(net "P5E_PEX0_STN0_RX_DP<5>")
	)
	(segment
		(start 81.879694 -283.435552)
		(end 81.879694 -283.19476)
		(width 0.1143)
		(layer "In5.Cu")
		(net "P5E_PEX0_STN0_RX_DP<5>")
	)
	(segment
		(start 92.746068 -275.243798)
		(end 94.448884 -272.229834)
		(width 0.1651)
		(layer "In5.Cu")
		(net "P5E_PEX0_STN0_RX_DP<5>")
	)
	(segment
		(start 69.278754 -133.42747)
		(end 69.2277 -133.274054)
		(width 0.1651)
		(layer "In5.Cu")
		(net "P5E_PEX0_STN0_RX_DP<5>")
	)
	(segment
		(start 75.477116 -136.72185)
		(end 75.317604 -136.747504)
		(width 0.1651)
		(layer "In5.Cu")
		(net "P5E_PEX0_STN0_RX_DP<5>")
	)
	(segment
		(start 79.620364 -151.399748)
		(end 79.620364 -151.39924)
		(width 0.1651)
		(layer "In5.Cu")
		(net "P5E_PEX0_STN0_RX_DP<5>")
	)
	(segment
		(start 69.721476 -133.649974)
		(end 69.278754 -133.42747)
		(width 0.1651)
		(layer "In5.Cu")
		(net "P5E_PEX0_STN0_RX_DP<5>")
	)
	(segment
		(start 78.23962 -142.071598)
		(end 77.63129 -139.23772)
		(width 0.1651)
		(layer "In5.Cu")
		(net "P5E_PEX0_STN0_RX_DP<5>")
	)
	(segment
		(start 94.448884 -272.229834)
		(end 94.5007 -270.270224)
		(width 0.1651)
		(layer "In5.Cu")
		(net "P5E_PEX0_STN0_RX_DP<5>")
	)
	(segment
		(start 65.4939 -132.286502)
		(end 65.20307 -132.577332)
		(width 0.1651)
		(layer "In5.Cu")
		(net "P5E_PEX0_STN0_RX_DP<5>")
	)
	(segment
		(start 72.05472 -134.693152)
		(end 71.90105 -134.743952)
		(width 0.1651)
		(layer "In5.Cu")
		(net "P5E_PEX0_STN0_RX_DP<5>")
	)
	(segment
		(start 86.875366 -244.204744)
		(end 84.250022 -233.359452)
		(width 0.1651)
		(layer "In5.Cu")
		(net "P5E_PEX0_STN0_RX_DP<5>")
	)
	(segment
		(start 72.991218 -135.291068)
		(end 72.548242 -135.068564)
		(width 0.1651)
		(layer "In5.Cu")
		(net "P5E_PEX0_STN0_RX_DP<5>")
	)
	(segment
		(start 68.13804 -132.726938)
		(end 68.137786 -132.727192)
		(width 0.1651)
		(layer "In5.Cu")
		(net "P5E_PEX0_STN0_RX_DP<5>")
	)
	(segment
		(start 69.874892 -133.599174)
		(end 69.721476 -133.649974)
		(width 0.1651)
		(layer "In5.Cu")
		(net "P5E_PEX0_STN0_RX_DP<5>")
	)
	(segment
		(start 81.001362 -160.728406)
		(end 79.620618 -151.400002)
		(width 0.1651)
		(layer "In5.Cu")
		(net "P5E_PEX0_STN0_RX_DP<5>")
	)
	(segment
		(start 72.548242 -135.068564)
		(end 72.497188 -134.915148)
		(width 0.1651)
		(layer "In5.Cu")
		(net "P5E_PEX0_STN0_RX_DP<5>")
	)
	(segment
		(start 83.917536 -282.933902)
		(end 84.56676 -282.933902)
		(width 0.1651)
		(layer "In5.Cu")
		(net "P5E_PEX0_STN0_RX_DP<5>")
	)
	(segment
		(start 77.63129 -139.23772)
		(end 77.36586 -138.618976)
		(width 0.1651)
		(layer "In5.Cu")
		(net "P5E_PEX0_STN0_RX_DP<5>")
	)
	(segment
		(start 84.56676 -282.933902)
		(end 85.396578 -282.388056)
		(width 0.1651)
		(layer "In5.Cu")
		(net "P5E_PEX0_STN0_RX_DP<5>")
	)
	(segment
		(start 68.18884 -132.880354)
		(end 68.13804 -132.726938)
		(width 0.1651)
		(layer "In5.Cu")
		(net "P5E_PEX0_STN0_RX_DP<5>")
	)
	(segment
		(start 67.259962 -132.286502)
		(end 65.4939 -132.286502)
		(width 0.1651)
		(layer "In5.Cu")
		(net "P5E_PEX0_STN0_RX_DP<5>")
	)
	(segment
		(start 83.213448 -222.619316)
		(end 81.001362 -160.728406)
		(width 0.1651)
		(layer "In5.Cu")
		(net "P5E_PEX0_STN0_RX_DP<5>")
	)
	(segment
		(start 71.407274 -134.368032)
		(end 70.964806 -134.146036)
		(width 0.1651)
		(layer "In5.Cu")
		(net "P5E_PEX0_STN0_RX_DP<5>")
	)
	(segment
		(start 70.964806 -134.146036)
		(end 70.81139 -134.19709)
		(width 0.1651)
		(layer "In5.Cu")
		(net "P5E_PEX0_STN0_RX_DP<5>")
	)
	(segment
		(start 83.843368 -282.979622)
		(end 83.889088 -282.933902)
		(width 0.1143)
		(layer "In5.Cu")
		(net "P5E_PEX0_STN0_RX_DP<5>")
	)
	(segment
		(start 68.137786 -132.727192)
		(end 67.259962 -132.286502)
		(width 0.1651)
		(layer "In5.Cu")
		(net "P5E_PEX0_STN0_RX_DP<5>")
	)
	(segment
		(start 74.890122 -136.29767)
		(end 74.066146 -135.702548)
		(width 0.1651)
		(layer "In5.Cu")
		(net "P5E_PEX0_STN0_RX_DP<5>")
	)
	(segment
		(start 83.889088 -282.933902)
		(end 83.917536 -282.933902)
		(width 0.1143)
		(layer "In5.Cu")
		(net "P5E_PEX0_STN0_RX_DP<5>")
	)
	(segment
		(start 85.396578 -282.388056)
		(end 92.746068 -275.243798)
		(width 0.1651)
		(layer "In5.Cu")
		(net "P5E_PEX0_STN0_RX_DP<5>")
	)
	(segment
		(start 68.785232 -133.052058)
		(end 68.631816 -133.102858)
		(width 0.1651)
		(layer "In5.Cu")
		(net "P5E_PEX0_STN0_RX_DP<5>")
	)
	(segment
		(start 71.458328 -134.521448)
		(end 71.407274 -134.368032)
		(width 0.1651)
		(layer "In5.Cu")
		(net "P5E_PEX0_STN0_RX_DP<5>")
	)
	(segment
		(start 94.5007 -270.270224)
		(end 86.875366 -244.204744)
		(width 0.1651)
		(layer "In5.Cu")
		(net "P5E_PEX0_STN0_RX_DP<5>")
	)
	(segment
		(start 81.879694 -283.19476)
		(end 82.094832 -282.979622)
		(width 0.1143)
		(layer "In5.Cu")
		(net "P5E_PEX0_STN0_RX_DP<5>")
	)
	(segment
		(start 82.094832 -282.979622)
		(end 83.843368 -282.979622)
		(width 0.1143)
		(layer "In5.Cu")
		(net "P5E_PEX0_STN0_RX_DP<5>")
	)
	(segment
		(start 76.698856 -137.604246)
		(end 75.477116 -136.72185)
		(width 0.1651)
		(layer "In5.Cu")
		(net "P5E_PEX0_STN0_RX_DP<5>")
	)
	(segment
		(start 70.81139 -134.19709)
		(end 70.368414 -133.974586)
		(width 0.1651)
		(layer "In5.Cu")
		(net "P5E_PEX0_STN0_RX_DP<5>")
	)
	(segment
		(start 74.915776 -136.457182)
		(end 74.890122 -136.29767)
		(width 0.1651)
		(layer "In5.Cu")
		(net "P5E_PEX0_STN0_RX_DP<5>")
	)
	(segment
		(start 70.31736 -133.82117)
		(end 69.874892 -133.599174)
		(width 0.1651)
		(layer "In5.Cu")
		(net "P5E_PEX0_STN0_RX_DP<5>")
	)
	(segment
		(start 73.144634 -135.240014)
		(end 72.991218 -135.291068)
		(width 0.1651)
		(layer "In5.Cu")
		(net "P5E_PEX0_STN0_RX_DP<5>")
	)
	(segment
		(start 70.368414 -133.974586)
		(end 70.31736 -133.82117)
		(width 0.1651)
		(layer "In5.Cu")
		(net "P5E_PEX0_STN0_RX_DP<5>")
	)
	(segment
		(start 71.90105 -134.743952)
		(end 71.458328 -134.521448)
		(width 0.1651)
		(layer "In5.Cu")
		(net "P5E_PEX0_STN0_RX_DP<5>")
	)
	(segment
		(start 69.2277 -133.274054)
		(end 68.785232 -133.052058)
		(width 0.1651)
		(layer "In5.Cu")
		(net "P5E_PEX0_STN0_RX_DP<5>")
	)
	(segment
		(start 81.499964 -283.549852)
		(end 81.765394 -283.549852)
		(width 0.1143)
		(layer "In5.Cu")
		(net "P5E_PEX0_STN0_RX_DP<5>")
	)
	(segment
		(start 81.765394 -283.549852)
		(end 81.879694 -283.435552)
		(width 0.1143)
		(layer "In5.Cu")
		(net "P5E_PEX0_STN0_RX_DP<5>")
	)
	(segment
		(start 77.36586 -138.618976)
		(end 76.698856 -137.604246)
		(width 0.1651)
		(layer "In5.Cu")
		(net "P5E_PEX0_STN0_RX_DP<5>")
	)
	(segment
		(start 75.317604 -136.747504)
		(end 74.915776 -136.457182)
		(width 0.1651)
		(layer "In5.Cu")
		(net "P5E_PEX0_STN0_RX_DP<5>")
	)
	(segment
		(start 84.250022 -233.359452)
		(end 83.213448 -222.619316)
		(width 0.1651)
		(layer "In5.Cu")
		(net "P5E_PEX0_STN0_RX_DP<5>")
	)
	(segment
		(start 79.620618 -151.400002)
		(end 79.620364 -151.399748)
		(width 0.1651)
		(layer "In5.Cu")
		(net "P5E_PEX0_STN0_RX_DP<5>")
	)
	(segment
		(start 79.620364 -151.39924)
		(end 78.23962 -142.071598)
		(width 0.1651)
		(layer "In5.Cu")
		(net "P5E_PEX0_STN0_RX_DP<5>")
	)
	(segment
		(start 74.066146 -135.702548)
		(end 73.144634 -135.240014)
		(width 0.1651)
		(layer "In5.Cu")
		(net "P5E_PEX0_STN0_RX_DP<5>")
	)
	(segment
		(start 72.497188 -134.915148)
		(end 72.05472 -134.693152)
		(width 0.1651)
		(layer "In5.Cu")
		(net "P5E_PEX0_STN0_RX_DP<5>")
	)
	(segment
		(start 68.631816 -133.102858)
		(end 68.18884 -132.880354)
		(width 0.1651)
		(layer "In5.Cu")
		(net "P5E_PEX0_STN0_RX_DP<5>")
	)
	(segment
		(start 277.583138 -123.111514)
		(end 277.739602 -122.95505)
		(width 0.13462)
		(layer "F.Cu")
		(net "P5E_PEX2_STN1_TX_C_DP<26>")
	)
	(segment
		(start 277.739602 -122.95505)
		(end 278.242268 -122.95505)
		(width 0.13462)
		(layer "F.Cu")
		(net "P5E_PEX2_STN1_TX_C_DP<26>")
	)
	(segment
		(start 269.105126 -122.79884)
		(end 269.4178 -123.111514)
		(width 0.13462)
		(layer "F.Cu")
		(net "P5E_PEX2_STN1_TX_C_DP<26>")
	)
	(segment
		(start 269.4178 -123.111514)
		(end 277.583138 -123.111514)
		(width 0.13462)
		(layer "F.Cu")
		(net "P5E_PEX2_STN1_TX_C_DP<26>")
	)
	(segment
		(start 409.660598 -28.55468)
		(end 409.364688 -28.25877)
		(width 0.13462)
		(layer "F.Cu")
		(net "P5E_PEX3_STN2_RX_DN<36>")
	)
	(segment
		(start 410.484066 -28.390088)
		(end 410.319474 -28.55468)
		(width 0.13462)
		(layer "F.Cu")
		(net "P5E_PEX3_STN2_RX_DN<36>")
	)
	(segment
		(start 410.319474 -28.55468)
		(end 409.660598 -28.55468)
		(width 0.13462)
		(layer "F.Cu")
		(net "P5E_PEX3_STN2_RX_DN<36>")
	)
	(segment
		(start 410.964888 -28.390088)
		(end 410.484066 -28.390088)
		(width 0.13462)
		(layer "F.Cu")
		(net "P5E_PEX3_STN2_RX_DN<36>")
	)
	(segment
		(start 402.86559 -266.499848)
		(end 402.86559 -271.392904)
		(width 0.1651)
		(layer "In7.Cu")
		(net "P5E_PEX3_STN2_RX_DN<36>")
	)
	(segment
		(start 413.58312 -48.834802)
		(end 413.38373 -68.374514)
		(width 0.1651)
		(layer "In7.Cu")
		(net "P5E_PEX3_STN2_RX_DN<36>")
	)
	(segment
		(start 409.663646 -28.5496)
		(end 410.103828 -28.5496)
		(width 0.1651)
		(layer "In7.Cu")
		(net "P5E_PEX3_STN2_RX_DN<36>")
	)
	(segment
		(start 415.631376 -37.688012)
		(end 415.606738 -39.169594)
		(width 0.1651)
		(layer "In7.Cu")
		(net "P5E_PEX3_STN2_RX_DN<36>")
	)
	(segment
		(start 415.606738 -39.169594)
		(end 413.58312 -48.834802)
		(width 0.1651)
		(layer "In7.Cu")
		(net "P5E_PEX3_STN2_RX_DN<36>")
	)
	(segment
		(start 409.364688 -28.25877)
		(end 409.657804 -28.551886)
		(width 0.1651)
		(layer "In7.Cu")
		(net "P5E_PEX3_STN2_RX_DN<36>")
	)
	(segment
		(start 413.00273 -31.448502)
		(end 415.631376 -37.688012)
		(width 0.1651)
		(layer "In7.Cu")
		(net "P5E_PEX3_STN2_RX_DN<36>")
	)
	(segment
		(start 403.199854 -275.265388)
		(end 403.199854 -274.999958)
		(width 0.1143)
		(layer "In7.Cu")
		(net "P5E_PEX3_STN2_RX_DN<36>")
	)
	(segment
		(start 402.86559 -271.392904)
		(end 402.86559 -271.421352)
		(width 0.1143)
		(layer "In7.Cu")
		(net "P5E_PEX3_STN2_RX_DN<36>")
	)
	(segment
		(start 402.86559 -271.421352)
		(end 402.81987 -271.467072)
		(width 0.1143)
		(layer "In7.Cu")
		(net "P5E_PEX3_STN2_RX_DN<36>")
	)
	(segment
		(start 413.38373 -68.374514)
		(end 402.999702 -264.972038)
		(width 0.1651)
		(layer "In7.Cu")
		(net "P5E_PEX3_STN2_RX_DN<36>")
	)
	(segment
		(start 402.81987 -275.275802)
		(end 402.923756 -275.379688)
		(width 0.1143)
		(layer "In7.Cu")
		(net "P5E_PEX3_STN2_RX_DN<36>")
	)
	(segment
		(start 402.999702 -264.972038)
		(end 402.86559 -266.499848)
		(width 0.1651)
		(layer "In7.Cu")
		(net "P5E_PEX3_STN2_RX_DN<36>")
	)
	(segment
		(start 402.923756 -275.379688)
		(end 403.085554 -275.379688)
		(width 0.1143)
		(layer "In7.Cu")
		(net "P5E_PEX3_STN2_RX_DN<36>")
	)
	(segment
		(start 409.657804 -28.551886)
		(end 409.663646 -28.5496)
		(width 0.1651)
		(layer "In7.Cu")
		(net "P5E_PEX3_STN2_RX_DN<36>")
	)
	(segment
		(start 410.103828 -28.5496)
		(end 413.00273 -31.448502)
		(width 0.1651)
		(layer "In7.Cu")
		(net "P5E_PEX3_STN2_RX_DN<36>")
	)
	(segment
		(start 402.81987 -271.467072)
		(end 402.81987 -275.275802)
		(width 0.1143)
		(layer "In7.Cu")
		(net "P5E_PEX3_STN2_RX_DN<36>")
	)
	(segment
		(start 403.085554 -275.379688)
		(end 403.199854 -275.265388)
		(width 0.1143)
		(layer "In7.Cu")
		(net "P5E_PEX3_STN2_RX_DN<36>")
	)
	(segment
		(start 434.46192 -356.832154)
		(end 434.46192 -357.462582)
		(width 0.13462)
		(layer "F.Cu")
		(net "P5E_PEX3_STN7_TX_C_DP<124>")
	)
	(segment
		(start 434.141372 -356.511606)
		(end 434.46192 -356.832154)
		(width 0.13462)
		(layer "F.Cu")
		(net "P5E_PEX3_STN7_TX_C_DP<124>")
	)
	(segment
		(start 434.46192 -357.462582)
		(end 434.166772 -357.75773)
		(width 0.13462)
		(layer "F.Cu")
		(net "P5E_PEX3_STN7_TX_C_DP<124>")
	)
	(segment
		(start 433.61864 -360.333036)
		(end 433.6542 -360.453686)
		(width 0.1651)
		(layer "In11.Cu")
		(net "P5E_PEX3_STN7_TX_C_DP<124>")
	)
	(segment
		(start 429.134016 -369.756182)
		(end 429.134016 -374.612408)
		(width 0.1651)
		(layer "In11.Cu")
		(net "P5E_PEX3_STN7_TX_C_DP<124>")
	)
	(segment
		(start 434.457602 -358.04856)
		(end 434.457602 -358.467152)
		(width 0.1651)
		(layer "In11.Cu")
		(net "P5E_PEX3_STN7_TX_C_DP<124>")
	)
	(segment
		(start 433.976272 -359.86212)
		(end 433.855622 -359.89768)
		(width 0.1651)
		(layer "In11.Cu")
		(net "P5E_PEX3_STN7_TX_C_DP<124>")
	)
	(segment
		(start 430.19472 -366.808766)
		(end 430.039526 -366.854486)
		(width 0.1651)
		(layer "In11.Cu")
		(net "P5E_PEX3_STN7_TX_C_DP<124>")
	)
	(segment
		(start 431.014378 -365.303054)
		(end 430.77765 -365.737902)
		(width 0.1651)
		(layer "In11.Cu")
		(net "P5E_PEX3_STN7_TX_C_DP<124>")
	)
	(segment
		(start 432.5366 -362.506514)
		(end 431.94351 -363.596174)
		(width 0.1651)
		(layer "In11.Cu")
		(net "P5E_PEX3_STN7_TX_C_DP<124>")
	)
	(segment
		(start 431.94351 -363.596174)
		(end 431.78857 -363.641894)
		(width 0.1651)
		(layer "In11.Cu")
		(net "P5E_PEX3_STN7_TX_C_DP<124>")
	)
	(segment
		(start 431.36058 -364.667038)
		(end 431.20564 -364.712758)
		(width 0.1651)
		(layer "In11.Cu")
		(net "P5E_PEX3_STN7_TX_C_DP<124>")
	)
	(segment
		(start 434.166772 -357.75773)
		(end 434.457602 -358.04856)
		(width 0.1651)
		(layer "In11.Cu")
		(net "P5E_PEX3_STN7_TX_C_DP<124>")
	)
	(segment
		(start 434.457602 -358.467152)
		(end 434.213 -359.427272)
		(width 0.1651)
		(layer "In11.Cu")
		(net "P5E_PEX3_STN7_TX_C_DP<124>")
	)
	(segment
		(start 433.05984 -361.35945)
		(end 433.0954 -361.4801)
		(width 0.1651)
		(layer "In11.Cu")
		(net "P5E_PEX3_STN7_TX_C_DP<124>")
	)
	(segment
		(start 429.611536 -367.87963)
		(end 429.134016 -369.756182)
		(width 0.1651)
		(layer "In11.Cu")
		(net "P5E_PEX3_STN7_TX_C_DP<124>")
	)
	(segment
		(start 430.968658 -365.14786)
		(end 431.014378 -365.303054)
		(width 0.1651)
		(layer "In11.Cu")
		(net "P5E_PEX3_STN7_TX_C_DP<124>")
	)
	(segment
		(start 432.50104 -362.385864)
		(end 432.5366 -362.506514)
		(width 0.1651)
		(layer "In11.Cu")
		(net "P5E_PEX3_STN7_TX_C_DP<124>")
	)
	(segment
		(start 431.597308 -364.23219)
		(end 431.36058 -364.667038)
		(width 0.1651)
		(layer "In11.Cu")
		(net "P5E_PEX3_STN7_TX_C_DP<124>")
	)
	(segment
		(start 432.738022 -361.950508)
		(end 432.50104 -362.385864)
		(width 0.1651)
		(layer "In11.Cu")
		(net "P5E_PEX3_STN7_TX_C_DP<124>")
	)
	(segment
		(start 431.78857 -363.641894)
		(end 431.551588 -364.076996)
		(width 0.1651)
		(layer "In11.Cu")
		(net "P5E_PEX3_STN7_TX_C_DP<124>")
	)
	(segment
		(start 429.802544 -367.289588)
		(end 429.848264 -367.444782)
		(width 0.1651)
		(layer "In11.Cu")
		(net "P5E_PEX3_STN7_TX_C_DP<124>")
	)
	(segment
		(start 429.134016 -374.612408)
		(end 428.84725 -374.899174)
		(width 0.1651)
		(layer "In11.Cu")
		(net "P5E_PEX3_STN7_TX_C_DP<124>")
	)
	(segment
		(start 430.039526 -366.854486)
		(end 429.802544 -367.289588)
		(width 0.1651)
		(layer "In11.Cu")
		(net "P5E_PEX3_STN7_TX_C_DP<124>")
	)
	(segment
		(start 428.289974 -374.772174)
		(end 428.289974 -374.390158)
		(width 0.1651)
		(layer "In11.Cu")
		(net "P5E_PEX3_STN7_TX_C_DP<124>")
	)
	(segment
		(start 430.62271 -365.783622)
		(end 430.385728 -366.218724)
		(width 0.1651)
		(layer "In11.Cu")
		(net "P5E_PEX3_STN7_TX_C_DP<124>")
	)
	(segment
		(start 431.20564 -364.712758)
		(end 430.968658 -365.14786)
		(width 0.1651)
		(layer "In11.Cu")
		(net "P5E_PEX3_STN7_TX_C_DP<124>")
	)
	(segment
		(start 433.855622 -359.89768)
		(end 433.61864 -360.333036)
		(width 0.1651)
		(layer "In11.Cu")
		(net "P5E_PEX3_STN7_TX_C_DP<124>")
	)
	(segment
		(start 433.296822 -360.924094)
		(end 433.05984 -361.35945)
		(width 0.1651)
		(layer "In11.Cu")
		(net "P5E_PEX3_STN7_TX_C_DP<124>")
	)
	(segment
		(start 429.848264 -367.444782)
		(end 429.611536 -367.87963)
		(width 0.1651)
		(layer "In11.Cu")
		(net "P5E_PEX3_STN7_TX_C_DP<124>")
	)
	(segment
		(start 430.77765 -365.737902)
		(end 430.62271 -365.783622)
		(width 0.1651)
		(layer "In11.Cu")
		(net "P5E_PEX3_STN7_TX_C_DP<124>")
	)
	(segment
		(start 433.0954 -361.4801)
		(end 432.858672 -361.914948)
		(width 0.1651)
		(layer "In11.Cu")
		(net "P5E_PEX3_STN7_TX_C_DP<124>")
	)
	(segment
		(start 433.6542 -360.453686)
		(end 433.417472 -360.888534)
		(width 0.1651)
		(layer "In11.Cu")
		(net "P5E_PEX3_STN7_TX_C_DP<124>")
	)
	(segment
		(start 431.551588 -364.076996)
		(end 431.597308 -364.23219)
		(width 0.1651)
		(layer "In11.Cu")
		(net "P5E_PEX3_STN7_TX_C_DP<124>")
	)
	(segment
		(start 428.84725 -374.899174)
		(end 428.416974 -374.899174)
		(width 0.1651)
		(layer "In11.Cu")
		(net "P5E_PEX3_STN7_TX_C_DP<124>")
	)
	(segment
		(start 430.385728 -366.218724)
		(end 430.431448 -366.373918)
		(width 0.1651)
		(layer "In11.Cu")
		(net "P5E_PEX3_STN7_TX_C_DP<124>")
	)
	(segment
		(start 432.858672 -361.914948)
		(end 432.738022 -361.950508)
		(width 0.1651)
		(layer "In11.Cu")
		(net "P5E_PEX3_STN7_TX_C_DP<124>")
	)
	(segment
		(start 428.416974 -374.899174)
		(end 428.289974 -374.772174)
		(width 0.1651)
		(layer "In11.Cu")
		(net "P5E_PEX3_STN7_TX_C_DP<124>")
	)
	(segment
		(start 430.431448 -366.373918)
		(end 430.19472 -366.808766)
		(width 0.1651)
		(layer "In11.Cu")
		(net "P5E_PEX3_STN7_TX_C_DP<124>")
	)
	(segment
		(start 434.213 -359.427272)
		(end 433.976272 -359.86212)
		(width 0.1651)
		(layer "In11.Cu")
		(net "P5E_PEX3_STN7_TX_C_DP<124>")
	)
	(segment
		(start 433.417472 -360.888534)
		(end 433.296822 -360.924094)
		(width 0.1651)
		(layer "In11.Cu")
		(net "P5E_PEX3_STN7_TX_C_DP<124>")
	)
	(segment
		(start 159.625284 -155.960064)
		(end 162.14217 -155.960064)
		(width 0.13208)
		(layer "F.Cu")
		(net "NIC2_DATA_OUT")
	)
	(segment
		(start 155.529026 -156.3624)
		(end 155.648152 -156.481526)
		(width 0.13208)
		(layer "F.Cu")
		(net "NIC2_DATA_OUT")
	)
	(segment
		(start 159.103822 -156.481526)
		(end 159.625284 -155.960064)
		(width 0.13208)
		(layer "F.Cu")
		(net "NIC2_DATA_OUT")
	)
	(segment
		(start 156.293312 -156.481526)
		(end 159.103822 -156.481526)
		(width 0.13208)
		(layer "F.Cu")
		(net "NIC2_DATA_OUT")
	)
	(segment
		(start 155.648152 -156.481526)
		(end 156.293312 -156.481526)
		(width 0.13208)
		(layer "F.Cu")
		(net "NIC2_DATA_OUT")
	)
	(segment
		(start 155.107894 -156.3624)
		(end 155.529026 -156.3624)
		(width 0.13208)
		(layer "F.Cu")
		(net "NIC2_DATA_OUT")
	)
	(via
		(at 156.293312 -156.481526)
		(size 0.762)
		(drill 0.381)
		(layers "F.Cu" "B.Cu")
		(net "NIC2_DATA_OUT")
	)
	(segment
		(start 304.209196 -113.43513)
		(end 305.457606 -113.43513)
		(width 0.13208)
		(layer "F.Cu")
		(net "NIC5_BIF1_N")
	)
	(segment
		(start 302.946308 -111.884206)
		(end 302.946308 -112.172242)
		(width 0.13208)
		(layer "F.Cu")
		(net "NIC5_BIF1_N")
	)
	(segment
		(start 302.946308 -112.172242)
		(end 304.209196 -113.43513)
		(width 0.13208)
		(layer "F.Cu")
		(net "NIC5_BIF1_N")
	)
	(via
		(at 302.946308 -111.884206)
		(size 0.508)
		(drill 0.254)
		(layers "F.Cu" "B.Cu")
		(net "NIC5_BIF1_N")
	)
	(segment
		(start 300.52772 -108.479336)
		(end 298.106846 -108.479336)
		(width 0.13208)
		(layer "B.Cu")
		(net "NIC5_BIF1_N")
	)
	(segment
		(start 298.106846 -108.479336)
		(end 297.62577 -108.960412)
		(width 0.13208)
		(layer "B.Cu")
		(net "NIC5_BIF1_N")
	)
	(segment
		(start 302.946308 -111.884206)
		(end 301.181516 -110.119414)
		(width 0.13208)
		(layer "B.Cu")
		(net "NIC5_BIF1_N")
	)
	(segment
		(start 295.175178 -109.198156)
		(end 295.175178 -109.481366)
		(width 0.13208)
		(layer "B.Cu")
		(net "NIC5_BIF1_N")
	)
	(segment
		(start 295.175178 -109.481366)
		(end 294.197278 -109.481366)
		(width 0.13208)
		(layer "B.Cu")
		(net "NIC5_BIF1_N")
	)
	(segment
		(start 295.412922 -108.960412)
		(end 295.175178 -109.198156)
		(width 0.13208)
		(layer "B.Cu")
		(net "NIC5_BIF1_N")
	)
	(segment
		(start 297.62577 -108.960412)
		(end 295.412922 -108.960412)
		(width 0.13208)
		(layer "B.Cu")
		(net "NIC5_BIF1_N")
	)
	(segment
		(start 301.181516 -110.119414)
		(end 301.181516 -109.133132)
		(width 0.13208)
		(layer "B.Cu")
		(net "NIC5_BIF1_N")
	)
	(segment
		(start 301.181516 -109.133132)
		(end 300.52772 -108.479336)
		(width 0.13208)
		(layer "B.Cu")
		(net "NIC5_BIF1_N")
	)
	(via
		(at 157.664658 -41.241472)
		(size 0.508)
		(drill 0.254)
		(layers "F.Cu" "B.Cu")
		(net "P12V_SSD5")
	)
	(via
		(at 158.555436 -20.318222)
		(size 0.508)
		(drill 0.254)
		(layers "F.Cu" "B.Cu")
		(net "P12V_SSD5")
	)
	(via
		(at 160.788858 -42.009822)
		(size 0.508)
		(drill 0.254)
		(layers "F.Cu" "B.Cu")
		(net "P12V_SSD5")
	)
	(via
		(at 158.555436 -19.657822)
		(size 0.508)
		(drill 0.254)
		(layers "F.Cu" "B.Cu")
		(net "P12V_SSD5")
	)
	(via
		(at 158.555436 -21.639022)
		(size 0.508)
		(drill 0.254)
		(layers "F.Cu" "B.Cu")
		(net "P12V_SSD5")
	)
	(via
		(at 158.325058 -41.241472)
		(size 0.508)
		(drill 0.254)
		(layers "F.Cu" "B.Cu")
		(net "P12V_SSD5")
	)
	(via
		(at 160.788858 -42.670222)
		(size 0.508)
		(drill 0.254)
		(layers "F.Cu" "B.Cu")
		(net "P12V_SSD5")
	)
	(via
		(at 160.788858 -43.305222)
		(size 0.508)
		(drill 0.254)
		(layers "F.Cu" "B.Cu")
		(net "P12V_SSD5")
	)
	(via
		(at 158.985458 -41.241472)
		(size 0.508)
		(drill 0.254)
		(layers "F.Cu" "B.Cu")
		(net "P12V_SSD5")
	)
	(via
		(at 157.157166 -43.041316)
		(size 0.6604)
		(drill 0.3302)
		(layers "F.Cu" "B.Cu")
		(net "P12V_SSD5")
	)
	(via
		(at 159.550862 -20.729194)
		(size 0.6604)
		(drill 0.3302)
		(layers "F.Cu" "B.Cu")
		(net "P12V_SSD5")
	)
	(via
		(at 161.455862 -20.729194)
		(size 0.6604)
		(drill 0.3302)
		(layers "F.Cu" "B.Cu")
		(net "P12V_SSD5")
	)
	(via
		(at 159.062166 -43.041316)
		(size 0.6604)
		(drill 0.3302)
		(layers "F.Cu" "B.Cu")
		(net "P12V_SSD5")
	)
	(via
		(at 158.555436 -20.978622)
		(size 0.508)
		(drill 0.254)
		(layers "F.Cu" "B.Cu")
		(net "P12V_SSD5")
	)
	(via
		(at 160.788858 -41.349422)
		(size 0.508)
		(drill 0.254)
		(layers "F.Cu" "B.Cu")
		(net "P12V_SSD5")
	)
	(via
		(at 158.555436 -18.997422)
		(size 0.508)
		(drill 0.254)
		(layers "F.Cu" "B.Cu")
		(net "P12V_SSD5")
	)
	(segment
		(start 73.745852 -119.435118)
		(end 73.90892 -119.27205)
		(width 0.13462)
		(layer "F.Cu")
		(net "P5E_PEX0_STN0_TX_C_DP<0>")
	)
	(segment
		(start 79.440024 -119.27205)
		(end 79.752698 -119.584724)
		(width 0.13462)
		(layer "F.Cu")
		(net "P5E_PEX0_STN0_TX_C_DP<0>")
	)
	(segment
		(start 73.257664 -119.435118)
		(end 73.745852 -119.435118)
		(width 0.13462)
		(layer "F.Cu")
		(net "P5E_PEX0_STN0_TX_C_DP<0>")
	)
	(segment
		(start 73.90892 -119.27205)
		(end 79.440024 -119.27205)
		(width 0.13462)
		(layer "F.Cu")
		(net "P5E_PEX0_STN0_TX_C_DP<0>")
	)
	(segment
		(start 277.583138 -130.721608)
		(end 277.739602 -130.565144)
		(width 0.13462)
		(layer "F.Cu")
		(net "P5E_PEX2_STN1_TX_C_DP<28>")
	)
	(segment
		(start 277.739602 -130.565144)
		(end 278.242268 -130.565144)
		(width 0.13462)
		(layer "F.Cu")
		(net "P5E_PEX2_STN1_TX_C_DP<28>")
	)
	(segment
		(start 269.105126 -130.408934)
		(end 269.4178 -130.721608)
		(width 0.13462)
		(layer "F.Cu")
		(net "P5E_PEX2_STN1_TX_C_DP<28>")
	)
	(segment
		(start 269.4178 -130.721608)
		(end 277.583138 -130.721608)
		(width 0.13462)
		(layer "F.Cu")
		(net "P5E_PEX2_STN1_TX_C_DP<28>")
	)
	(segment
		(start 257.588512 -317.675514)
		(end 265.99896 -308.055264)
		(width 0.1651)
		(layer "In5.Cu")
		(net "P5E_PEX2_STN7_RX_DP<119>")
	)
	(segment
		(start 265.99896 -308.055264)
		(end 267.016992 -307.633878)
		(width 0.1651)
		(layer "In5.Cu")
		(net "P5E_PEX2_STN7_RX_DP<119>")
	)
	(segment
		(start 267.865352 -307.633878)
		(end 267.911072 -307.679598)
		(width 0.1143)
		(layer "In5.Cu")
		(net "P5E_PEX2_STN7_RX_DP<119>")
	)
	(segment
		(start 303.733962 -396.067534)
		(end 303.366932 -395.180566)
		(width 0.1651)
		(layer "In5.Cu")
		(net "P5E_PEX2_STN7_RX_DP<119>")
	)
	(segment
		(start 267.836904 -307.633878)
		(end 267.865352 -307.633878)
		(width 0.1143)
		(layer "In5.Cu")
		(net "P5E_PEX2_STN7_RX_DP<119>")
	)
	(segment
		(start 303.447196 -409.799028)
		(end 303.733962 -409.512262)
		(width 0.1651)
		(layer "In5.Cu")
		(net "P5E_PEX2_STN7_RX_DP<119>")
	)
	(segment
		(start 286.508698 -385.154932)
		(end 286.173418 -384.484372)
		(width 0.1651)
		(layer "In5.Cu")
		(net "P5E_PEX2_STN7_RX_DP<119>")
	)
	(segment
		(start 278.727916 -341.192866)
		(end 257.59537 -324.255638)
		(width 0.1651)
		(layer "In5.Cu")
		(net "P5E_PEX2_STN7_RX_DP<119>")
	)
	(segment
		(start 285.875222 -378.1552)
		(end 285.208218 -371.033294)
		(width 0.1651)
		(layer "In5.Cu")
		(net "P5E_PEX2_STN7_RX_DP<119>")
	)
	(segment
		(start 302.88992 -409.672028)
		(end 303.01692 -409.799028)
		(width 0.1651)
		(layer "In5.Cu")
		(net "P5E_PEX2_STN7_RX_DP<119>")
	)
	(segment
		(start 302.88992 -409.290012)
		(end 302.88992 -409.672028)
		(width 0.1651)
		(layer "In5.Cu")
		(net "P5E_PEX2_STN7_RX_DP<119>")
	)
	(segment
		(start 267.911072 -307.679598)
		(end 269.394178 -307.679598)
		(width 0.1143)
		(layer "In5.Cu")
		(net "P5E_PEX2_STN7_RX_DP<119>")
	)
	(segment
		(start 286.173418 -384.484372)
		(end 285.875222 -378.1552)
		(width 0.1651)
		(layer "In5.Cu")
		(net "P5E_PEX2_STN7_RX_DP<119>")
	)
	(segment
		(start 269.619984 -307.905404)
		(end 269.619984 -308.135528)
		(width 0.1143)
		(layer "In5.Cu")
		(net "P5E_PEX2_STN7_RX_DP<119>")
	)
	(segment
		(start 301.772574 -393.586208)
		(end 298.92752 -391.644632)
		(width 0.1651)
		(layer "In5.Cu")
		(net "P5E_PEX2_STN7_RX_DP<119>")
	)
	(segment
		(start 269.394178 -307.679598)
		(end 269.619984 -307.905404)
		(width 0.1143)
		(layer "In5.Cu")
		(net "P5E_PEX2_STN7_RX_DP<119>")
	)
	(segment
		(start 269.619984 -308.135528)
		(end 269.734284 -308.249828)
		(width 0.1143)
		(layer "In5.Cu")
		(net "P5E_PEX2_STN7_RX_DP<119>")
	)
	(segment
		(start 257.59537 -324.255384)
		(end 257.100578 -323.594984)
		(width 0.1651)
		(layer "In5.Cu")
		(net "P5E_PEX2_STN7_RX_DP<119>")
	)
	(segment
		(start 257.59537 -324.255638)
		(end 257.59537 -324.255384)
		(width 0.1651)
		(layer "In5.Cu")
		(net "P5E_PEX2_STN7_RX_DP<119>")
	)
	(segment
		(start 279.201118 -358.55021)
		(end 279.069292 -357.970836)
		(width 0.1651)
		(layer "In5.Cu")
		(net "P5E_PEX2_STN7_RX_DP<119>")
	)
	(segment
		(start 257.100578 -323.594984)
		(end 256.36982 -321.82943)
		(width 0.1651)
		(layer "In5.Cu")
		(net "P5E_PEX2_STN7_RX_DP<119>")
	)
	(segment
		(start 279.069292 -342.011762)
		(end 278.727916 -341.192866)
		(width 0.1651)
		(layer "In5.Cu")
		(net "P5E_PEX2_STN7_RX_DP<119>")
	)
	(segment
		(start 269.734284 -308.249828)
		(end 269.999714 -308.249828)
		(width 0.1143)
		(layer "In5.Cu")
		(net "P5E_PEX2_STN7_RX_DP<119>")
	)
	(segment
		(start 256.36982 -320.621152)
		(end 257.588512 -317.675514)
		(width 0.1651)
		(layer "In5.Cu")
		(net "P5E_PEX2_STN7_RX_DP<119>")
	)
	(segment
		(start 303.01692 -409.799028)
		(end 303.447196 -409.799028)
		(width 0.1651)
		(layer "In5.Cu")
		(net "P5E_PEX2_STN7_RX_DP<119>")
	)
	(segment
		(start 303.733962 -409.512262)
		(end 303.733962 -396.067534)
		(width 0.1651)
		(layer "In5.Cu")
		(net "P5E_PEX2_STN7_RX_DP<119>")
	)
	(segment
		(start 287.25622 -385.9022)
		(end 286.508698 -385.154932)
		(width 0.1651)
		(layer "In5.Cu")
		(net "P5E_PEX2_STN7_RX_DP<119>")
	)
	(segment
		(start 303.366932 -395.180566)
		(end 301.772574 -393.586208)
		(width 0.1651)
		(layer "In5.Cu")
		(net "P5E_PEX2_STN7_RX_DP<119>")
	)
	(segment
		(start 256.36982 -321.82943)
		(end 256.36982 -320.621152)
		(width 0.1651)
		(layer "In5.Cu")
		(net "P5E_PEX2_STN7_RX_DP<119>")
	)
	(segment
		(start 285.208218 -371.033294)
		(end 279.201118 -358.55021)
		(width 0.1651)
		(layer "In5.Cu")
		(net "P5E_PEX2_STN7_RX_DP<119>")
	)
	(segment
		(start 279.069292 -357.970836)
		(end 279.069292 -342.011762)
		(width 0.1651)
		(layer "In5.Cu")
		(net "P5E_PEX2_STN7_RX_DP<119>")
	)
	(segment
		(start 267.016992 -307.633878)
		(end 267.836904 -307.633878)
		(width 0.1651)
		(layer "In5.Cu")
		(net "P5E_PEX2_STN7_RX_DP<119>")
	)
	(segment
		(start 298.92752 -391.644632)
		(end 287.25622 -385.9022)
		(width 0.1651)
		(layer "In5.Cu")
		(net "P5E_PEX2_STN7_RX_DP<119>")
	)
	(segment
		(start 420.155624 -34.23412)
		(end 416.223704 -34.23412)
		(width 0.13462)
		(layer "F.Cu")
		(net "P5E_PEX3_STN2_TX_C_DP<39>")
	)
	(segment
		(start 420.46779 -34.546286)
		(end 420.155624 -34.23412)
		(width 0.13462)
		(layer "F.Cu")
		(net "P5E_PEX3_STN2_TX_C_DP<39>")
	)
	(segment
		(start 416.067748 -34.390076)
		(end 415.564828 -34.390076)
		(width 0.13462)
		(layer "F.Cu")
		(net "P5E_PEX3_STN2_TX_C_DP<39>")
	)
	(segment
		(start 416.223704 -34.23412)
		(end 416.067748 -34.390076)
		(width 0.13462)
		(layer "F.Cu")
		(net "P5E_PEX3_STN2_TX_C_DP<39>")
	)
	(segment
		(start 376.956066 -327.680066)
		(end 376.956066 -327.679812)
		(width 0.1651)
		(layer "In9.Cu")
		(net "P5E_PEX3_STN7_RX_DP<119>")
	)
	(segment
		(start 419.09238 -341.266018)
		(end 419.22192 -341.203534)
		(width 0.1651)
		(layer "In9.Cu")
		(net "P5E_PEX3_STN7_RX_DP<119>")
	)
	(segment
		(start 383.892552 -307.633878)
		(end 382.854454 -307.633878)
		(width 0.1651)
		(layer "In9.Cu")
		(net "P5E_PEX3_STN7_RX_DP<119>")
	)
	(segment
		(start 418.086032 -370.236496)
		(end 417.58743 -383.681732)
		(width 0.1651)
		(layer "In9.Cu")
		(net "P5E_PEX3_STN7_RX_DP<119>")
	)
	(segment
		(start 435.01691 -409.799028)
		(end 434.88991 -409.672028)
		(width 0.1651)
		(layer "In9.Cu")
		(net "P5E_PEX3_STN7_RX_DP<119>")
	)
	(segment
		(start 385.724654 -308.15534)
		(end 385.724654 -307.923438)
		(width 0.1143)
		(layer "In9.Cu")
		(net "P5E_PEX3_STN7_RX_DP<119>")
	)
	(segment
		(start 417.952174 -340.760812)
		(end 418.561774 -340.97341)
		(width 0.1651)
		(layer "In9.Cu")
		(net "P5E_PEX3_STN7_RX_DP<119>")
	)
	(segment
		(start 383.921 -307.633878)
		(end 383.892552 -307.633878)
		(width 0.1143)
		(layer "In9.Cu")
		(net "P5E_PEX3_STN7_RX_DP<119>")
	)
	(segment
		(start 435.238906 -409.799028)
		(end 435.01691 -409.799028)
		(width 0.1651)
		(layer "In9.Cu")
		(net "P5E_PEX3_STN7_RX_DP<119>")
	)
	(segment
		(start 373.246904 -324.017894)
		(end 376.890026 -327.659238)
		(width 0.1651)
		(layer "In9.Cu")
		(net "P5E_PEX3_STN7_RX_DP<119>")
	)
	(segment
		(start 372.5418 -322.314062)
		(end 373.246904 -324.017894)
		(width 0.1651)
		(layer "In9.Cu")
		(net "P5E_PEX3_STN7_RX_DP<119>")
	)
	(segment
		(start 376.890026 -327.659238)
		(end 376.956066 -327.680066)
		(width 0.1651)
		(layer "In9.Cu")
		(net "P5E_PEX3_STN7_RX_DP<119>")
	)
	(segment
		(start 435.463442 -395.302232)
		(end 435.76494 -396.048992)
		(width 0.1651)
		(layer "In9.Cu")
		(net "P5E_PEX3_STN7_RX_DP<119>")
	)
	(segment
		(start 382.854454 -307.633878)
		(end 382.304544 -307.861716)
		(width 0.1651)
		(layer "In9.Cu")
		(net "P5E_PEX3_STN7_RX_DP<119>")
	)
	(segment
		(start 418.561774 -340.97341)
		(end 418.562028 -340.97341)
		(width 0.1651)
		(layer "In9.Cu")
		(net "P5E_PEX3_STN7_RX_DP<119>")
	)
	(segment
		(start 386.099812 -308.249828)
		(end 385.819142 -308.249828)
		(width 0.1143)
		(layer "In9.Cu")
		(net "P5E_PEX3_STN7_RX_DP<119>")
	)
	(segment
		(start 434.88991 -409.672028)
		(end 434.88991 -409.290012)
		(width 0.1651)
		(layer "In9.Cu")
		(net "P5E_PEX3_STN7_RX_DP<119>")
	)
	(segment
		(start 420.467282 -342.130126)
		(end 420.467282 -358.217978)
		(width 0.1651)
		(layer "In9.Cu")
		(net "P5E_PEX3_STN7_RX_DP<119>")
	)
	(segment
		(start 418.562028 -340.97341)
		(end 418.624512 -341.10295)
		(width 0.1651)
		(layer "In9.Cu")
		(net "P5E_PEX3_STN7_RX_DP<119>")
	)
	(segment
		(start 420.01313 -341.479378)
		(end 420.467282 -342.130126)
		(width 0.1651)
		(layer "In9.Cu")
		(net "P5E_PEX3_STN7_RX_DP<119>")
	)
	(segment
		(start 418.624512 -341.10295)
		(end 419.09238 -341.266018)
		(width 0.1651)
		(layer "In9.Cu")
		(net "P5E_PEX3_STN7_RX_DP<119>")
	)
	(segment
		(start 435.76494 -396.048992)
		(end 435.76494 -409.272994)
		(width 0.1651)
		(layer "In9.Cu")
		(net "P5E_PEX3_STN7_RX_DP<119>")
	)
	(segment
		(start 382.304544 -307.861716)
		(end 377.281948 -312.884312)
		(width 0.1651)
		(layer "In9.Cu")
		(net "P5E_PEX3_STN7_RX_DP<119>")
	)
	(segment
		(start 418.37991 -385.422394)
		(end 420.20109 -386.907024)
		(width 0.1651)
		(layer "In9.Cu")
		(net "P5E_PEX3_STN7_RX_DP<119>")
	)
	(segment
		(start 372.5418 -320.071242)
		(end 372.5418 -322.314062)
		(width 0.1651)
		(layer "In9.Cu")
		(net "P5E_PEX3_STN7_RX_DP<119>")
	)
	(segment
		(start 373.285512 -318.272414)
		(end 372.5418 -320.071242)
		(width 0.1651)
		(layer "In9.Cu")
		(net "P5E_PEX3_STN7_RX_DP<119>")
	)
	(segment
		(start 435.76494 -409.272994)
		(end 435.238906 -409.799028)
		(width 0.1651)
		(layer "In9.Cu")
		(net "P5E_PEX3_STN7_RX_DP<119>")
	)
	(segment
		(start 426.812456 -389.259572)
		(end 433.896008 -393.735052)
		(width 0.1651)
		(layer "In9.Cu")
		(net "P5E_PEX3_STN7_RX_DP<119>")
	)
	(segment
		(start 376.956066 -327.679812)
		(end 378.12472 -328.047858)
		(width 0.1651)
		(layer "In9.Cu")
		(net "P5E_PEX3_STN7_RX_DP<119>")
	)
	(segment
		(start 385.819142 -308.249828)
		(end 385.724654 -308.15534)
		(width 0.1143)
		(layer "In9.Cu")
		(net "P5E_PEX3_STN7_RX_DP<119>")
	)
	(segment
		(start 400.741896 -333.237078)
		(end 417.952174 -340.760812)
		(width 0.1651)
		(layer "In9.Cu")
		(net "P5E_PEX3_STN7_RX_DP<119>")
	)
	(segment
		(start 433.896008 -393.735052)
		(end 435.463442 -395.302232)
		(width 0.1651)
		(layer "In9.Cu")
		(net "P5E_PEX3_STN7_RX_DP<119>")
	)
	(segment
		(start 417.58743 -383.681732)
		(end 417.86429 -384.65506)
		(width 0.1651)
		(layer "In9.Cu")
		(net "P5E_PEX3_STN7_RX_DP<119>")
	)
	(segment
		(start 385.480814 -307.679598)
		(end 383.96672 -307.679598)
		(width 0.1143)
		(layer "In9.Cu")
		(net "P5E_PEX3_STN7_RX_DP<119>")
	)
	(segment
		(start 378.12472 -328.047858)
		(end 400.741896 -333.237078)
		(width 0.1651)
		(layer "In9.Cu")
		(net "P5E_PEX3_STN7_RX_DP<119>")
	)
	(segment
		(start 419.22192 -341.203534)
		(end 420.01313 -341.479378)
		(width 0.1651)
		(layer "In9.Cu")
		(net "P5E_PEX3_STN7_RX_DP<119>")
	)
	(segment
		(start 420.467282 -358.217978)
		(end 418.086032 -370.236496)
		(width 0.1651)
		(layer "In9.Cu")
		(net "P5E_PEX3_STN7_RX_DP<119>")
	)
	(segment
		(start 385.724654 -307.923438)
		(end 385.480814 -307.679598)
		(width 0.1143)
		(layer "In9.Cu")
		(net "P5E_PEX3_STN7_RX_DP<119>")
	)
	(segment
		(start 377.281948 -312.884312)
		(end 373.285512 -318.272414)
		(width 0.1651)
		(layer "In9.Cu")
		(net "P5E_PEX3_STN7_RX_DP<119>")
	)
	(segment
		(start 383.96672 -307.679598)
		(end 383.921 -307.633878)
		(width 0.1143)
		(layer "In9.Cu")
		(net "P5E_PEX3_STN7_RX_DP<119>")
	)
	(segment
		(start 420.20109 -386.907024)
		(end 426.812456 -389.259572)
		(width 0.1651)
		(layer "In9.Cu")
		(net "P5E_PEX3_STN7_RX_DP<119>")
	)
	(segment
		(start 417.86429 -384.65506)
		(end 418.37991 -385.422394)
		(width 0.1651)
		(layer "In9.Cu")
		(net "P5E_PEX3_STN7_RX_DP<119>")
	)
	(segment
		(start 155.723844 -151.465534)
		(end 155.537662 -151.279352)
		(width 0.13208)
		(layer "F.Cu")
		(net "NCSI_NIC2_RXD0")
	)
	(segment
		(start 162.14217 -153.560018)
		(end 159.834834 -153.560018)
		(width 0.13208)
		(layer "F.Cu")
		(net "NCSI_NIC2_RXD0")
	)
	(segment
		(start 157.74035 -151.465534)
		(end 156.282136 -151.465534)
		(width 0.13208)
		(layer "F.Cu")
		(net "NCSI_NIC2_RXD0")
	)
	(segment
		(start 155.537662 -151.279352)
		(end 155.099766 -151.279352)
		(width 0.13208)
		(layer "F.Cu")
		(net "NCSI_NIC2_RXD0")
	)
	(segment
		(start 156.282136 -151.465534)
		(end 155.723844 -151.465534)
		(width 0.13208)
		(layer "F.Cu")
		(net "NCSI_NIC2_RXD0")
	)
	(segment
		(start 159.834834 -153.560018)
		(end 157.74035 -151.465534)
		(width 0.13208)
		(layer "F.Cu")
		(net "NCSI_NIC2_RXD0")
	)
	(via
		(at 156.282136 -151.465534)
		(size 0.762)
		(drill 0.381)
		(layers "F.Cu" "B.Cu")
		(net "NCSI_NIC2_RXD0")
	)
	(via
		(at 136.139936 -20.216368)
		(size 0.6604)
		(drill 0.3302)
		(layers "F.Cu" "B.Cu")
		(net "P12V_SSD4")
	)
	(via
		(at 132.32511 -41.241472)
		(size 0.508)
		(drill 0.254)
		(layers "F.Cu" "B.Cu")
		(net "P12V_SSD4")
	)
	(via
		(at 134.234936 -20.216368)
		(size 0.6604)
		(drill 0.3302)
		(layers "F.Cu" "B.Cu")
		(net "P12V_SSD4")
	)
	(via
		(at 132.555488 -20.318222)
		(size 0.508)
		(drill 0.254)
		(layers "F.Cu" "B.Cu")
		(net "P12V_SSD4")
	)
	(via
		(at 134.78891 -43.305222)
		(size 0.508)
		(drill 0.254)
		(layers "F.Cu" "B.Cu")
		(net "P12V_SSD4")
	)
	(via
		(at 132.555488 -20.978622)
		(size 0.508)
		(drill 0.254)
		(layers "F.Cu" "B.Cu")
		(net "P12V_SSD4")
	)
	(via
		(at 132.555488 -18.997422)
		(size 0.508)
		(drill 0.254)
		(layers "F.Cu" "B.Cu")
		(net "P12V_SSD4")
	)
	(via
		(at 132.555488 -21.639022)
		(size 0.508)
		(drill 0.254)
		(layers "F.Cu" "B.Cu")
		(net "P12V_SSD4")
	)
	(via
		(at 134.78891 -42.670222)
		(size 0.508)
		(drill 0.254)
		(layers "F.Cu" "B.Cu")
		(net "P12V_SSD4")
	)
	(via
		(at 134.78891 -42.009822)
		(size 0.508)
		(drill 0.254)
		(layers "F.Cu" "B.Cu")
		(net "P12V_SSD4")
	)
	(via
		(at 131.157218 -43.041316)
		(size 0.6604)
		(drill 0.3302)
		(layers "F.Cu" "B.Cu")
		(net "P12V_SSD4")
	)
	(via
		(at 133.062218 -43.041316)
		(size 0.6604)
		(drill 0.3302)
		(layers "F.Cu" "B.Cu")
		(net "P12V_SSD4")
	)
	(via
		(at 132.555488 -19.657822)
		(size 0.508)
		(drill 0.254)
		(layers "F.Cu" "B.Cu")
		(net "P12V_SSD4")
	)
	(via
		(at 132.98551 -41.241472)
		(size 0.508)
		(drill 0.254)
		(layers "F.Cu" "B.Cu")
		(net "P12V_SSD4")
	)
	(via
		(at 134.78891 -41.349422)
		(size 0.508)
		(drill 0.254)
		(layers "F.Cu" "B.Cu")
		(net "P12V_SSD4")
	)
	(segment
		(start 73.257664 -146.955002)
		(end 73.745852 -146.955002)
		(width 0.13462)
		(layer "F.Cu")
		(net "P5E_PEX0_STN0_TX_C_DP<10>")
	)
	(segment
		(start 73.908666 -146.792188)
		(end 79.440278 -146.792188)
		(width 0.13462)
		(layer "F.Cu")
		(net "P5E_PEX0_STN0_TX_C_DP<10>")
	)
	(segment
		(start 73.745852 -146.955002)
		(end 73.908666 -146.792188)
		(width 0.13462)
		(layer "F.Cu")
		(net "P5E_PEX0_STN0_TX_C_DP<10>")
	)
	(segment
		(start 79.440278 -146.792188)
		(end 79.752698 -147.104608)
		(width 0.13462)
		(layer "F.Cu")
		(net "P5E_PEX0_STN0_TX_C_DP<10>")
	)
	(segment
		(start 284.442662 -132.232908)
		(end 284.154626 -132.520944)
		(width 0.13462)
		(layer "F.Cu")
		(net "P5E_PEX2_STN1_RX_DP<29>")
	)
	(segment
		(start 283.477462 -132.520944)
		(end 283.321506 -132.364988)
		(width 0.13462)
		(layer "F.Cu")
		(net "P5E_PEX2_STN1_RX_DP<29>")
	)
	(segment
		(start 284.154626 -132.520944)
		(end 283.477462 -132.520944)
		(width 0.13462)
		(layer "F.Cu")
		(net "P5E_PEX2_STN1_RX_DP<29>")
	)
	(segment
		(start 283.321506 -132.364988)
		(end 282.842462 -132.364988)
		(width 0.13462)
		(layer "F.Cu")
		(net "P5E_PEX2_STN1_RX_DP<29>")
	)
	(segment
		(start 283.878782 -132.523738)
		(end 283.56687 -132.653024)
		(width 0.1651)
		(layer "In5.Cu")
		(net "P5E_PEX2_STN1_RX_DP<29>")
	)
	(segment
		(start 303.629568 -271.644872)
		(end 303.629568 -275.35505)
		(width 0.1143)
		(layer "In5.Cu")
		(net "P5E_PEX2_STN1_RX_DP<29>")
	)
	(segment
		(start 274.41652 -146.854926)
		(end 273.923506 -147.76069)
		(width 0.1651)
		(layer "In5.Cu")
		(net "P5E_PEX2_STN1_RX_DP<29>")
	)
	(segment
		(start 280.869644 -140.713206)
		(end 280.025348 -142.75181)
		(width 0.1651)
		(layer "In5.Cu")
		(net "P5E_PEX2_STN1_RX_DP<29>")
	)
	(segment
		(start 275.240496 -160.904428)
		(end 303.583848 -267.498322)
		(width 0.1651)
		(layer "In5.Cu")
		(net "P5E_PEX2_STN1_RX_DP<29>")
	)
	(segment
		(start 304.085244 -275.569934)
		(end 304.199544 -275.684234)
		(width 0.1143)
		(layer "In5.Cu")
		(net "P5E_PEX2_STN1_RX_DP<29>")
	)
	(segment
		(start 303.583848 -267.498322)
		(end 303.583848 -271.570704)
		(width 0.1651)
		(layer "In5.Cu")
		(net "P5E_PEX2_STN1_RX_DP<29>")
	)
	(segment
		(start 282.043886 -134.100824)
		(end 280.869644 -136.936988)
		(width 0.1651)
		(layer "In5.Cu")
		(net "P5E_PEX2_STN1_RX_DP<29>")
	)
	(segment
		(start 304.199544 -275.684234)
		(end 304.199544 -275.949664)
		(width 0.1143)
		(layer "In5.Cu")
		(net "P5E_PEX2_STN1_RX_DP<29>")
	)
	(segment
		(start 303.583848 -271.570704)
		(end 303.583848 -271.599152)
		(width 0.1143)
		(layer "In5.Cu")
		(net "P5E_PEX2_STN1_RX_DP<29>")
	)
	(segment
		(start 280.025348 -142.75181)
		(end 278.122634 -144.47647)
		(width 0.1651)
		(layer "In5.Cu")
		(net "P5E_PEX2_STN1_RX_DP<29>")
	)
	(segment
		(start 280.869644 -136.936988)
		(end 280.869644 -140.713206)
		(width 0.1651)
		(layer "In5.Cu")
		(net "P5E_PEX2_STN1_RX_DP<29>")
	)
	(segment
		(start 275.065236 -146.226022)
		(end 274.637754 -146.58467)
		(width 0.1651)
		(layer "In5.Cu")
		(net "P5E_PEX2_STN1_RX_DP<29>")
	)
	(segment
		(start 303.583848 -271.599152)
		(end 303.629568 -271.644872)
		(width 0.1143)
		(layer "In5.Cu")
		(net "P5E_PEX2_STN1_RX_DP<29>")
	)
	(segment
		(start 278.122634 -144.47647)
		(end 277.71598 -145.0848)
		(width 0.1651)
		(layer "In5.Cu")
		(net "P5E_PEX2_STN1_RX_DP<29>")
	)
	(segment
		(start 277.71598 -145.0848)
		(end 277.286974 -145.513806)
		(width 0.1651)
		(layer "In5.Cu")
		(net "P5E_PEX2_STN1_RX_DP<29>")
	)
	(segment
		(start 274.510246 -156.780992)
		(end 275.240496 -160.904428)
		(width 0.1651)
		(layer "In5.Cu")
		(net "P5E_PEX2_STN1_RX_DP<29>")
	)
	(segment
		(start 303.629568 -275.35505)
		(end 303.844452 -275.569934)
		(width 0.1143)
		(layer "In5.Cu")
		(net "P5E_PEX2_STN1_RX_DP<29>")
	)
	(segment
		(start 274.637754 -146.58467)
		(end 274.41652 -146.854926)
		(width 0.1651)
		(layer "In5.Cu")
		(net "P5E_PEX2_STN1_RX_DP<29>")
	)
	(segment
		(start 284.151832 -132.523738)
		(end 283.878782 -132.523738)
		(width 0.1651)
		(layer "In5.Cu")
		(net "P5E_PEX2_STN1_RX_DP<29>")
	)
	(segment
		(start 303.844452 -275.569934)
		(end 304.085244 -275.569934)
		(width 0.1143)
		(layer "In5.Cu")
		(net "P5E_PEX2_STN1_RX_DP<29>")
	)
	(segment
		(start 283.460698 -132.759196)
		(end 282.043886 -134.100824)
		(width 0.1651)
		(layer "In5.Cu")
		(net "P5E_PEX2_STN1_RX_DP<29>")
	)
	(segment
		(start 283.56687 -132.653024)
		(end 283.460698 -132.759196)
		(width 0.1651)
		(layer "In5.Cu")
		(net "P5E_PEX2_STN1_RX_DP<29>")
	)
	(segment
		(start 273.923506 -147.76069)
		(end 274.510246 -156.780992)
		(width 0.1651)
		(layer "In5.Cu")
		(net "P5E_PEX2_STN1_RX_DP<29>")
	)
	(segment
		(start 277.286974 -145.513806)
		(end 275.065236 -146.226022)
		(width 0.1651)
		(layer "In5.Cu")
		(net "P5E_PEX2_STN1_RX_DP<29>")
	)
	(segment
		(start 284.442662 -132.232908)
		(end 284.151832 -132.523738)
		(width 0.1651)
		(layer "In5.Cu")
		(net "P5E_PEX2_STN1_RX_DP<29>")
	)
	(segment
		(start 383.667508 -32.16148)
		(end 384.312668 -32.16148)
		(width 0.13462)
		(layer "F.Cu")
		(net "P5E_PEX3_STN2_RX_DN<42>")
	)
	(segment
		(start 383.36474 -31.858712)
		(end 383.667508 -32.16148)
		(width 0.13462)
		(layer "F.Cu")
		(net "P5E_PEX3_STN2_RX_DN<42>")
	)
	(segment
		(start 384.312668 -32.16148)
		(end 384.484118 -31.99003)
		(width 0.13462)
		(layer "F.Cu")
		(net "P5E_PEX3_STN2_RX_DN<42>")
	)
	(segment
		(start 384.484118 -31.99003)
		(end 384.96494 -31.99003)
		(width 0.13462)
		(layer "F.Cu")
		(net "P5E_PEX3_STN2_RX_DN<42>")
	)
	(segment
		(start 397.38554 -275.379688)
		(end 397.223742 -275.379688)
		(width 0.1143)
		(layer "In7.Cu")
		(net "P5E_PEX3_STN2_RX_DN<42>")
	)
	(segment
		(start 385.527296 -49.435766)
		(end 384.2131 -39.71036)
		(width 0.1651)
		(layer "In7.Cu")
		(net "P5E_PEX3_STN2_RX_DN<42>")
	)
	(segment
		(start 396.944596 -258.734306)
		(end 397.113506 -249.99696)
		(width 0.1651)
		(layer "In7.Cu")
		(net "P5E_PEX3_STN2_RX_DN<42>")
	)
	(segment
		(start 397.113506 -249.99696)
		(end 389.157464 -148.002498)
		(width 0.1651)
		(layer "In7.Cu")
		(net "P5E_PEX3_STN2_RX_DN<42>")
	)
	(segment
		(start 384.2131 -39.71036)
		(end 384.18389 -37.856414)
		(width 0.1651)
		(layer "In7.Cu")
		(net "P5E_PEX3_STN2_RX_DN<42>")
	)
	(segment
		(start 397.49984 -274.999958)
		(end 397.49984 -275.265388)
		(width 0.1143)
		(layer "In7.Cu")
		(net "P5E_PEX3_STN2_RX_DN<42>")
	)
	(segment
		(start 389.463788 -119.5832)
		(end 389.020558 -104.952546)
		(width 0.1651)
		(layer "In7.Cu")
		(net "P5E_PEX3_STN2_RX_DN<42>")
	)
	(segment
		(start 397.119856 -271.467072)
		(end 397.165576 -271.421352)
		(width 0.1143)
		(layer "In7.Cu")
		(net "P5E_PEX3_STN2_RX_DN<42>")
	)
	(segment
		(start 397.49984 -275.265388)
		(end 397.38554 -275.379688)
		(width 0.1143)
		(layer "In7.Cu")
		(net "P5E_PEX3_STN2_RX_DN<42>")
	)
	(segment
		(start 397.165576 -267.767816)
		(end 396.722092 -263.266174)
		(width 0.1651)
		(layer "In7.Cu")
		(net "P5E_PEX3_STN2_RX_DN<42>")
	)
	(segment
		(start 384.744468 -32.663638)
		(end 384.230118 -32.149542)
		(width 0.1651)
		(layer "In7.Cu")
		(net "P5E_PEX3_STN2_RX_DN<42>")
	)
	(segment
		(start 397.165576 -271.392904)
		(end 397.165576 -267.767816)
		(width 0.1651)
		(layer "In7.Cu")
		(net "P5E_PEX3_STN2_RX_DN<42>")
	)
	(segment
		(start 385.826508 -65.159636)
		(end 385.43484 -55.367682)
		(width 0.1651)
		(layer "In7.Cu")
		(net "P5E_PEX3_STN2_RX_DN<42>")
	)
	(segment
		(start 396.722092 -263.266174)
		(end 396.944596 -258.734306)
		(width 0.1651)
		(layer "In7.Cu")
		(net "P5E_PEX3_STN2_RX_DN<42>")
	)
	(segment
		(start 389.157464 -148.002498)
		(end 389.463788 -119.5832)
		(width 0.1651)
		(layer "In7.Cu")
		(net "P5E_PEX3_STN2_RX_DN<42>")
	)
	(segment
		(start 389.020558 -104.952546)
		(end 385.826508 -65.159636)
		(width 0.1651)
		(layer "In7.Cu")
		(net "P5E_PEX3_STN2_RX_DN<42>")
	)
	(segment
		(start 397.119856 -275.275802)
		(end 397.119856 -271.467072)
		(width 0.1143)
		(layer "In7.Cu")
		(net "P5E_PEX3_STN2_RX_DN<42>")
	)
	(segment
		(start 385.43484 -55.367682)
		(end 385.527296 -49.435766)
		(width 0.1651)
		(layer "In7.Cu")
		(net "P5E_PEX3_STN2_RX_DN<42>")
	)
	(segment
		(start 384.707384 -35.04819)
		(end 384.744468 -32.663638)
		(width 0.1651)
		(layer "In7.Cu")
		(net "P5E_PEX3_STN2_RX_DN<42>")
	)
	(segment
		(start 397.223742 -275.379688)
		(end 397.119856 -275.275802)
		(width 0.1143)
		(layer "In7.Cu")
		(net "P5E_PEX3_STN2_RX_DN<42>")
	)
	(segment
		(start 397.165576 -271.421352)
		(end 397.165576 -271.392904)
		(width 0.1143)
		(layer "In7.Cu")
		(net "P5E_PEX3_STN2_RX_DN<42>")
	)
	(segment
		(start 383.65557 -32.149542)
		(end 383.36474 -31.858712)
		(width 0.1651)
		(layer "In7.Cu")
		(net "P5E_PEX3_STN2_RX_DN<42>")
	)
	(segment
		(start 384.18389 -37.856414)
		(end 384.707384 -35.04819)
		(width 0.1651)
		(layer "In7.Cu")
		(net "P5E_PEX3_STN2_RX_DN<42>")
	)
	(segment
		(start 384.230118 -32.149542)
		(end 383.65557 -32.149542)
		(width 0.1651)
		(layer "In7.Cu")
		(net "P5E_PEX3_STN2_RX_DN<42>")
	)
	(segment
		(start 432.75504 -341.504778)
		(end 422.43883 -337.640422)
		(width 0.1651)
		(layer "In9.Cu")
		(net "P5E_PEX3_STN7_RX_DP<123>")
	)
	(segment
		(start 386.434076 -319.893696)
		(end 386.434076 -319.865248)
		(width 0.1143)
		(layer "In9.Cu")
		(net "P5E_PEX3_STN7_RX_DP<123>")
	)
	(segment
		(start 429.213264 -365.111538)
		(end 429.178212 -364.990888)
		(width 0.1651)
		(layer "In9.Cu")
		(net "P5E_PEX3_STN7_RX_DP<123>")
	)
	(segment
		(start 426.438822 -383.79908)
		(end 426.964856 -383.273046)
		(width 0.1651)
		(layer "In9.Cu")
		(net "P5E_PEX3_STN7_RX_DP<123>")
	)
	(segment
		(start 386.479796 -318.36868)
		(end 386.71881 -318.129666)
		(width 0.1143)
		(layer "In9.Cu")
		(net "P5E_PEX3_STN7_RX_DP<123>")
	)
	(segment
		(start 428.0154 -367.293652)
		(end 427.980094 -367.173002)
		(width 0.1651)
		(layer "In9.Cu")
		(net "P5E_PEX3_STN7_RX_DP<123>")
	)
	(segment
		(start 387.244844 -323.553074)
		(end 386.434076 -321.595242)
		(width 0.1651)
		(layer "In9.Cu")
		(net "P5E_PEX3_STN7_RX_DP<123>")
	)
	(segment
		(start 422.43883 -337.640422)
		(end 408.110182 -330.885038)
		(width 0.1651)
		(layer "In9.Cu")
		(net "P5E_PEX3_STN7_RX_DP<123>")
	)
	(segment
		(start 429.77562 -364.087156)
		(end 429.740568 -363.966506)
		(width 0.1651)
		(layer "In9.Cu")
		(net "P5E_PEX3_STN7_RX_DP<123>")
	)
	(segment
		(start 426.089826 -383.290064)
		(end 426.089826 -383.67208)
		(width 0.1651)
		(layer "In9.Cu")
		(net "P5E_PEX3_STN7_RX_DP<123>")
	)
	(segment
		(start 432.903122 -341.71763)
		(end 432.75504 -341.504778)
		(width 0.1651)
		(layer "In9.Cu")
		(net "P5E_PEX3_STN7_RX_DP<123>")
	)
	(segment
		(start 408.110182 -330.885038)
		(end 406.695148 -330.385166)
		(width 0.1651)
		(layer "In9.Cu")
		(net "P5E_PEX3_STN7_RX_DP<123>")
	)
	(segment
		(start 427.980094 -367.173002)
		(end 428.218854 -366.738408)
		(width 0.1651)
		(layer "In9.Cu")
		(net "P5E_PEX3_STN7_RX_DP<123>")
	)
	(segment
		(start 426.964856 -369.207288)
		(end 428.0154 -367.293652)
		(width 0.1651)
		(layer "In9.Cu")
		(net "P5E_PEX3_STN7_RX_DP<123>")
	)
	(segment
		(start 429.416718 -364.556294)
		(end 429.537368 -364.521242)
		(width 0.1651)
		(layer "In9.Cu")
		(net "P5E_PEX3_STN7_RX_DP<123>")
	)
	(segment
		(start 406.695148 -330.385166)
		(end 389.19785 -324.956932)
		(width 0.1651)
		(layer "In9.Cu")
		(net "P5E_PEX3_STN7_RX_DP<123>")
	)
	(segment
		(start 429.537368 -364.521242)
		(end 429.77562 -364.087156)
		(width 0.1651)
		(layer "In9.Cu")
		(net "P5E_PEX3_STN7_RX_DP<123>")
	)
	(segment
		(start 429.979074 -363.532166)
		(end 430.099724 -363.49686)
		(width 0.1651)
		(layer "In9.Cu")
		(net "P5E_PEX3_STN7_RX_DP<123>")
	)
	(segment
		(start 428.218854 -366.738408)
		(end 428.339504 -366.703356)
		(width 0.1651)
		(layer "In9.Cu")
		(net "P5E_PEX3_STN7_RX_DP<123>")
	)
	(segment
		(start 426.089826 -383.67208)
		(end 426.216826 -383.79908)
		(width 0.1651)
		(layer "In9.Cu")
		(net "P5E_PEX3_STN7_RX_DP<123>")
	)
	(segment
		(start 426.964856 -383.273046)
		(end 426.964856 -369.207288)
		(width 0.1651)
		(layer "In9.Cu")
		(net "P5E_PEX3_STN7_RX_DP<123>")
	)
	(segment
		(start 429.740568 -363.966506)
		(end 429.979074 -363.532166)
		(width 0.1651)
		(layer "In9.Cu")
		(net "P5E_PEX3_STN7_RX_DP<123>")
	)
	(segment
		(start 426.216826 -383.79908)
		(end 426.438822 -383.79908)
		(width 0.1651)
		(layer "In9.Cu")
		(net "P5E_PEX3_STN7_RX_DP<123>")
	)
	(segment
		(start 386.71881 -318.129666)
		(end 386.961126 -318.129666)
		(width 0.1143)
		(layer "In9.Cu")
		(net "P5E_PEX3_STN7_RX_DP<123>")
	)
	(segment
		(start 429.21301 -365.111538)
		(end 429.213264 -365.111538)
		(width 0.1651)
		(layer "In9.Cu")
		(net "P5E_PEX3_STN7_RX_DP<123>")
	)
	(segment
		(start 428.339504 -366.703356)
		(end 428.33925 -366.703356)
		(width 0.1651)
		(layer "In9.Cu")
		(net "P5E_PEX3_STN7_RX_DP<123>")
	)
	(segment
		(start 386.479796 -319.819528)
		(end 386.479796 -318.36868)
		(width 0.1143)
		(layer "In9.Cu")
		(net "P5E_PEX3_STN7_RX_DP<123>")
	)
	(segment
		(start 428.33925 -366.703356)
		(end 429.21301 -365.111538)
		(width 0.1651)
		(layer "In9.Cu")
		(net "P5E_PEX3_STN7_RX_DP<123>")
	)
	(segment
		(start 386.434076 -321.595242)
		(end 386.434076 -319.893696)
		(width 0.1651)
		(layer "In9.Cu")
		(net "P5E_PEX3_STN7_RX_DP<123>")
	)
	(segment
		(start 389.19785 -324.956932)
		(end 387.244844 -323.553074)
		(width 0.1651)
		(layer "In9.Cu")
		(net "P5E_PEX3_STN7_RX_DP<123>")
	)
	(segment
		(start 387.050026 -318.040766)
		(end 387.050026 -317.749936)
		(width 0.1143)
		(layer "In9.Cu")
		(net "P5E_PEX3_STN7_RX_DP<123>")
	)
	(segment
		(start 386.961126 -318.129666)
		(end 387.050026 -318.040766)
		(width 0.1143)
		(layer "In9.Cu")
		(net "P5E_PEX3_STN7_RX_DP<123>")
	)
	(segment
		(start 432.903122 -358.39019)
		(end 432.903122 -341.71763)
		(width 0.1651)
		(layer "In9.Cu")
		(net "P5E_PEX3_STN7_RX_DP<123>")
	)
	(segment
		(start 429.178212 -364.990888)
		(end 429.416718 -364.556294)
		(width 0.1651)
		(layer "In9.Cu")
		(net "P5E_PEX3_STN7_RX_DP<123>")
	)
	(segment
		(start 386.434076 -319.865248)
		(end 386.479796 -319.819528)
		(width 0.1143)
		(layer "In9.Cu")
		(net "P5E_PEX3_STN7_RX_DP<123>")
	)
	(segment
		(start 430.099724 -363.49686)
		(end 432.903122 -358.39019)
		(width 0.1651)
		(layer "In9.Cu")
		(net "P5E_PEX3_STN7_RX_DP<123>")
	)
	(segment
		(start 159.031178 -154.759914)
		(end 158.243524 -153.97226)
		(width 0.13208)
		(layer "F.Cu")
		(net "NIC2_SLOT_ID0")
	)
	(segment
		(start 158.243524 -153.97226)
		(end 156.287724 -153.97226)
		(width 0.13208)
		(layer "F.Cu")
		(net "NIC2_SLOT_ID0")
	)
	(segment
		(start 155.099766 -154.327352)
		(end 155.099766 -153.322528)
		(width 0.13208)
		(layer "F.Cu")
		(net "NIC2_SLOT_ID0")
	)
	(segment
		(start 155.629864 -153.3144)
		(end 155.107894 -153.3144)
		(width 0.13208)
		(layer "F.Cu")
		(net "NIC2_SLOT_ID0")
	)
	(segment
		(start 156.287724 -153.97226)
		(end 155.629864 -153.3144)
		(width 0.13208)
		(layer "F.Cu")
		(net "NIC2_SLOT_ID0")
	)
	(segment
		(start 162.14217 -154.759914)
		(end 159.031178 -154.759914)
		(width 0.13208)
		(layer "F.Cu")
		(net "NIC2_SLOT_ID0")
	)
	(segment
		(start 155.099766 -153.322528)
		(end 155.107894 -153.3144)
		(width 0.13208)
		(layer "F.Cu")
		(net "NIC2_SLOT_ID0")
	)
	(via
		(at 156.287724 -153.97226)
		(size 0.762)
		(drill 0.381)
		(layers "F.Cu" "B.Cu")
		(net "NIC2_SLOT_ID0")
	)
	(segment
		(start 302.942244 -114.290094)
		(end 302.97755 -114.3254)
		(width 0.13208)
		(layer "F.Cu")
		(net "RST_NIC5_PERST0_R_N")
	)
	(segment
		(start 313.839606 -87.749126)
		(end 313.839606 -88.39581)
		(width 0.13208)
		(layer "F.Cu")
		(net "RST_NIC5_PERST0_R_N")
	)
	(segment
		(start 304.973736 -114.635026)
		(end 305.457606 -114.635026)
		(width 0.13208)
		(layer "F.Cu")
		(net "RST_NIC5_PERST0_R_N")
	)
	(segment
		(start 302.97755 -114.3254)
		(end 304.66411 -114.3254)
		(width 0.13208)
		(layer "F.Cu")
		(net "RST_NIC5_PERST0_R_N")
	)
	(segment
		(start 304.66411 -114.3254)
		(end 304.973736 -114.635026)
		(width 0.13208)
		(layer "F.Cu")
		(net "RST_NIC5_PERST0_R_N")
	)
	(via
		(at 302.942244 -114.290094)
		(size 0.508)
		(drill 0.254)
		(layers "F.Cu" "B.Cu")
		(net "RST_NIC5_PERST0_R_N")
	)
	(via
		(at 313.839606 -88.39581)
		(size 0.508)
		(drill 0.254)
		(layers "F.Cu" "B.Cu")
		(net "RST_NIC5_PERST0_R_N")
	)
	(segment
		(start 305.093878 -98.06559)
		(end 305.093878 -104.619806)
		(width 0.15494)
		(layer "In11.Cu")
		(net "RST_NIC5_PERST0_R_N")
	)
	(segment
		(start 313.839606 -88.39581)
		(end 313.352434 -88.882982)
		(width 0.15494)
		(layer "In11.Cu")
		(net "RST_NIC5_PERST0_R_N")
	)
	(segment
		(start 305.093878 -104.619806)
		(end 305.903884 -105.429812)
		(width 0.15494)
		(layer "In11.Cu")
		(net "RST_NIC5_PERST0_R_N")
	)
	(segment
		(start 304.489104 -113.56086)
		(end 303.671478 -113.56086)
		(width 0.15494)
		(layer "In11.Cu")
		(net "RST_NIC5_PERST0_R_N")
	)
	(segment
		(start 313.352434 -88.882982)
		(end 312.007758 -88.882982)
		(width 0.15494)
		(layer "In11.Cu")
		(net "RST_NIC5_PERST0_R_N")
	)
	(segment
		(start 303.671478 -113.56086)
		(end 302.942244 -114.290094)
		(width 0.15494)
		(layer "In11.Cu")
		(net "RST_NIC5_PERST0_R_N")
	)
	(segment
		(start 312.007758 -88.882982)
		(end 306.894484 -93.996256)
		(width 0.15494)
		(layer "In11.Cu")
		(net "RST_NIC5_PERST0_R_N")
	)
	(segment
		(start 305.903884 -112.14608)
		(end 304.489104 -113.56086)
		(width 0.15494)
		(layer "In11.Cu")
		(net "RST_NIC5_PERST0_R_N")
	)
	(segment
		(start 305.903884 -105.429812)
		(end 305.903884 -112.14608)
		(width 0.15494)
		(layer "In11.Cu")
		(net "RST_NIC5_PERST0_R_N")
	)
	(segment
		(start 306.894484 -96.264984)
		(end 305.093878 -98.06559)
		(width 0.15494)
		(layer "In11.Cu")
		(net "RST_NIC5_PERST0_R_N")
	)
	(segment
		(start 306.894484 -93.996256)
		(end 306.894484 -96.264984)
		(width 0.15494)
		(layer "In11.Cu")
		(net "RST_NIC5_PERST0_R_N")
	)
	(segment
		(start 68.65747 -130.044952)
		(end 68.169536 -130.044952)
		(width 0.13462)
		(layer "F.Cu")
		(net "P5E_PEX0_STN0_RX_DN<4>")
	)
	(segment
		(start 68.006722 -130.207766)
		(end 67.351402 -130.207766)
		(width 0.13462)
		(layer "F.Cu")
		(net "P5E_PEX0_STN0_RX_DN<4>")
	)
	(segment
		(start 67.351402 -130.207766)
		(end 67.05727 -129.913634)
		(width 0.13462)
		(layer "F.Cu")
		(net "P5E_PEX0_STN0_RX_DN<4>")
	)
	(segment
		(start 68.169536 -130.044952)
		(end 68.006722 -130.207766)
		(width 0.13462)
		(layer "F.Cu")
		(net "P5E_PEX0_STN0_RX_DN<4>")
	)
	(segment
		(start 93.717364 -276.06625)
		(end 95.67545 -272.573242)
		(width 0.1651)
		(layer "In5.Cu")
		(net "P5E_PEX0_STN0_RX_DN<4>")
	)
	(segment
		(start 85.470746 -232.2322)
		(end 86.072472 -168.331642)
		(width 0.1651)
		(layer "In5.Cu")
		(net "P5E_PEX0_STN0_RX_DN<4>")
	)
	(segment
		(start 95.67545 -272.573242)
		(end 95.775526 -269.73022)
		(width 0.1651)
		(layer "In5.Cu")
		(net "P5E_PEX0_STN0_RX_DN<4>")
	)
	(segment
		(start 83.85048 -284.120082)
		(end 83.8962 -284.165802)
		(width 0.1143)
		(layer "In5.Cu")
		(net "P5E_PEX0_STN0_RX_DN<4>")
	)
	(segment
		(start 87.346282 -240.890298)
		(end 85.470746 -232.2322)
		(width 0.1651)
		(layer "In5.Cu")
		(net "P5E_PEX0_STN0_RX_DN<4>")
	)
	(segment
		(start 86.072472 -168.331642)
		(end 85.705442 -151.490172)
		(width 0.1651)
		(layer "In5.Cu")
		(net "P5E_PEX0_STN0_RX_DN<4>")
	)
	(segment
		(start 80.28432 -284.499812)
		(end 80.17002 -284.385512)
		(width 0.1143)
		(layer "In5.Cu")
		(net "P5E_PEX0_STN0_RX_DN<4>")
	)
	(segment
		(start 79.331312 -139.993624)
		(end 78.569566 -138.063478)
		(width 0.1651)
		(layer "In5.Cu")
		(net "P5E_PEX0_STN0_RX_DN<4>")
	)
	(segment
		(start 86.131908 -283.398722)
		(end 93.717364 -276.06625)
		(width 0.1651)
		(layer "In5.Cu")
		(net "P5E_PEX0_STN0_RX_DN<4>")
	)
	(segment
		(start 80.17002 -284.385512)
		(end 80.17002 -284.25267)
		(width 0.1143)
		(layer "In5.Cu")
		(net "P5E_PEX0_STN0_RX_DN<4>")
	)
	(segment
		(start 67.3481 -130.204464)
		(end 67.05727 -129.913634)
		(width 0.1651)
		(layer "In5.Cu")
		(net "P5E_PEX0_STN0_RX_DN<4>")
	)
	(segment
		(start 95.775526 -269.73022)
		(end 87.346282 -240.890298)
		(width 0.1651)
		(layer "In5.Cu")
		(net "P5E_PEX0_STN0_RX_DN<4>")
	)
	(segment
		(start 80.17002 -284.25267)
		(end 80.302608 -284.120082)
		(width 0.1143)
		(layer "In5.Cu")
		(net "P5E_PEX0_STN0_RX_DN<4>")
	)
	(segment
		(start 85.038946 -284.165802)
		(end 86.131908 -283.398722)
		(width 0.1651)
		(layer "In5.Cu")
		(net "P5E_PEX0_STN0_RX_DN<4>")
	)
	(segment
		(start 81.98231 -148.287486)
		(end 81.98231 -148.28774)
		(width 0.1651)
		(layer "In5.Cu")
		(net "P5E_PEX0_STN0_RX_DN<4>")
	)
	(segment
		(start 80.821276 -148.009864)
		(end 80.478122 -147.649184)
		(width 0.1651)
		(layer "In5.Cu")
		(net "P5E_PEX0_STN0_RX_DN<4>")
	)
	(segment
		(start 75.756008 -135.076692)
		(end 75.756008 -135.076438)
		(width 0.1651)
		(layer "In5.Cu")
		(net "P5E_PEX0_STN0_RX_DN<4>")
	)
	(segment
		(start 80.54975 -284.499812)
		(end 80.28432 -284.499812)
		(width 0.1143)
		(layer "In5.Cu")
		(net "P5E_PEX0_STN0_RX_DN<4>")
	)
	(segment
		(start 85.34019 -150.649178)
		(end 83.19643 -149.578568)
		(width 0.1651)
		(layer "In5.Cu")
		(net "P5E_PEX0_STN0_RX_DN<4>")
	)
	(segment
		(start 78.569566 -138.063478)
		(end 77.758036 -136.865868)
		(width 0.1651)
		(layer "In5.Cu")
		(net "P5E_PEX0_STN0_RX_DN<4>")
	)
	(segment
		(start 75.756008 -135.076438)
		(end 73.961244 -133.472428)
		(width 0.1651)
		(layer "In5.Cu")
		(net "P5E_PEX0_STN0_RX_DN<4>")
	)
	(segment
		(start 67.776344 -130.204464)
		(end 67.3481 -130.204464)
		(width 0.1651)
		(layer "In5.Cu")
		(net "P5E_PEX0_STN0_RX_DN<4>")
	)
	(segment
		(start 83.19643 -149.578568)
		(end 82.068924 -148.308314)
		(width 0.1651)
		(layer "In5.Cu")
		(net "P5E_PEX0_STN0_RX_DN<4>")
	)
	(segment
		(start 83.924648 -284.165802)
		(end 85.038946 -284.165802)
		(width 0.1651)
		(layer "In5.Cu")
		(net "P5E_PEX0_STN0_RX_DN<4>")
	)
	(segment
		(start 73.961244 -133.472428)
		(end 67.776344 -130.204464)
		(width 0.1651)
		(layer "In5.Cu")
		(net "P5E_PEX0_STN0_RX_DN<4>")
	)
	(segment
		(start 81.98231 -148.28774)
		(end 80.821276 -148.009864)
		(width 0.1651)
		(layer "In5.Cu")
		(net "P5E_PEX0_STN0_RX_DN<4>")
	)
	(segment
		(start 77.758036 -136.865868)
		(end 75.756008 -135.076692)
		(width 0.1651)
		(layer "In5.Cu")
		(net "P5E_PEX0_STN0_RX_DN<4>")
	)
	(segment
		(start 80.302608 -284.120082)
		(end 83.85048 -284.120082)
		(width 0.1143)
		(layer "In5.Cu")
		(net "P5E_PEX0_STN0_RX_DN<4>")
	)
	(segment
		(start 83.8962 -284.165802)
		(end 83.924648 -284.165802)
		(width 0.1143)
		(layer "In5.Cu")
		(net "P5E_PEX0_STN0_RX_DN<4>")
	)
	(segment
		(start 80.478122 -147.649184)
		(end 79.331312 -139.993624)
		(width 0.1651)
		(layer "In5.Cu")
		(net "P5E_PEX0_STN0_RX_DN<4>")
	)
	(segment
		(start 85.705442 -151.490172)
		(end 85.34019 -150.649178)
		(width 0.1651)
		(layer "In5.Cu")
		(net "P5E_PEX0_STN0_RX_DN<4>")
	)
	(segment
		(start 82.068924 -148.308314)
		(end 81.98231 -148.287486)
		(width 0.1651)
		(layer "In5.Cu")
		(net "P5E_PEX0_STN0_RX_DN<4>")
	)
	(segment
		(start 130.810508 -351.316798)
		(end 130.810508 -350.685354)
		(width 0.13462)
		(layer "F.Cu")
		(net "P5E_PEX1_STN5_TX_C_DP<81>")
	)
	(segment
		(start 130.810508 -350.685354)
		(end 130.490468 -350.365314)
		(width 0.13462)
		(layer "F.Cu")
		(net "P5E_PEX1_STN5_TX_C_DP<81>")
	)
	(segment
		(start 130.515868 -351.611438)
		(end 130.810508 -351.316798)
		(width 0.13462)
		(layer "F.Cu")
		(net "P5E_PEX1_STN5_TX_C_DP<81>")
	)
	(segment
		(start 136.731502 -370.07546)
		(end 136.243568 -368.71148)
		(width 0.1651)
		(layer "In7.Cu")
		(net "P5E_PEX1_STN5_TX_C_DP<81>")
	)
	(segment
		(start 136.40943 -383.170938)
		(end 136.731502 -370.07546)
		(width 0.1651)
		(layer "In7.Cu")
		(net "P5E_PEX1_STN5_TX_C_DP<81>")
	)
	(segment
		(start 130.806698 -351.902268)
		(end 130.515868 -351.611438)
		(width 0.1651)
		(layer "In7.Cu")
		(net "P5E_PEX1_STN5_TX_C_DP<81>")
	)
	(segment
		(start 120.073166 -393.785852)
		(end 122.99188 -391.748264)
		(width 0.1651)
		(layer "In7.Cu")
		(net "P5E_PEX1_STN5_TX_C_DP<81>")
	)
	(segment
		(start 135.235696 -367.39957)
		(end 134.95528 -366.990884)
		(width 0.1651)
		(layer "In7.Cu")
		(net "P5E_PEX1_STN5_TX_C_DP<81>")
	)
	(segment
		(start 119.53875 -394.158724)
		(end 120.070118 -393.787884)
		(width 0.1651)
		(layer "In7.Cu")
		(net "P5E_PEX1_STN5_TX_C_DP<81>")
	)
	(segment
		(start 122.99188 -391.748264)
		(end 132.35813 -387.855714)
		(width 0.1651)
		(layer "In7.Cu")
		(net "P5E_PEX1_STN5_TX_C_DP<81>")
	)
	(segment
		(start 118.237 -405.898858)
		(end 118.469156 -405.898858)
		(width 0.1651)
		(layer "In7.Cu")
		(net "P5E_PEX1_STN5_TX_C_DP<81>")
	)
	(segment
		(start 134.978394 -366.867186)
		(end 134.97814 -366.867186)
		(width 0.1651)
		(layer "In7.Cu")
		(net "P5E_PEX1_STN5_TX_C_DP<81>")
	)
	(segment
		(start 118.11 -405.771858)
		(end 118.237 -405.898858)
		(width 0.1651)
		(layer "In7.Cu")
		(net "P5E_PEX1_STN5_TX_C_DP<81>")
	)
	(segment
		(start 129.52222 -358.914446)
		(end 129.252218 -358.159558)
		(width 0.1651)
		(layer "In7.Cu")
		(net "P5E_PEX1_STN5_TX_C_DP<81>")
	)
	(segment
		(start 135.359394 -367.422684)
		(end 135.235696 -367.39957)
		(width 0.1651)
		(layer "In7.Cu")
		(net "P5E_PEX1_STN5_TX_C_DP<81>")
	)
	(segment
		(start 136.40943 -386.107432)
		(end 136.40943 -383.170938)
		(width 0.1651)
		(layer "In7.Cu")
		(net "P5E_PEX1_STN5_TX_C_DP<81>")
	)
	(segment
		(start 118.887494 -396.280132)
		(end 119.0117 -395.671294)
		(width 0.1651)
		(layer "In7.Cu")
		(net "P5E_PEX1_STN5_TX_C_DP<81>")
	)
	(segment
		(start 136.034272 -386.536692)
		(end 136.320022 -386.29844)
		(width 0.1651)
		(layer "In7.Cu")
		(net "P5E_PEX1_STN5_TX_C_DP<81>")
	)
	(segment
		(start 118.469156 -405.898858)
		(end 118.887494 -405.48052)
		(width 0.1651)
		(layer "In7.Cu")
		(net "P5E_PEX1_STN5_TX_C_DP<81>")
	)
	(segment
		(start 119.0117 -395.671294)
		(end 119.53875 -394.158724)
		(width 0.1651)
		(layer "In7.Cu")
		(net "P5E_PEX1_STN5_TX_C_DP<81>")
	)
	(segment
		(start 132.35813 -387.855714)
		(end 136.034272 -386.536692)
		(width 0.1651)
		(layer "In7.Cu")
		(net "P5E_PEX1_STN5_TX_C_DP<81>")
	)
	(segment
		(start 134.95528 -366.990884)
		(end 134.978394 -366.867186)
		(width 0.1651)
		(layer "In7.Cu")
		(net "P5E_PEX1_STN5_TX_C_DP<81>")
	)
	(segment
		(start 130.806698 -352.420682)
		(end 130.806698 -351.902268)
		(width 0.1651)
		(layer "In7.Cu")
		(net "P5E_PEX1_STN5_TX_C_DP<81>")
	)
	(segment
		(start 129.252218 -353.975162)
		(end 130.806698 -352.420682)
		(width 0.1651)
		(layer "In7.Cu")
		(net "P5E_PEX1_STN5_TX_C_DP<81>")
	)
	(segment
		(start 118.887494 -405.48052)
		(end 118.887494 -396.280132)
		(width 0.1651)
		(layer "In7.Cu")
		(net "P5E_PEX1_STN5_TX_C_DP<81>")
	)
	(segment
		(start 120.070118 -393.787884)
		(end 120.073166 -393.785852)
		(width 0.1651)
		(layer "In7.Cu")
		(net "P5E_PEX1_STN5_TX_C_DP<81>")
	)
	(segment
		(start 136.243568 -368.71148)
		(end 135.359394 -367.422684)
		(width 0.1651)
		(layer "In7.Cu")
		(net "P5E_PEX1_STN5_TX_C_DP<81>")
	)
	(segment
		(start 129.252218 -358.159558)
		(end 129.252218 -353.975162)
		(width 0.1651)
		(layer "In7.Cu")
		(net "P5E_PEX1_STN5_TX_C_DP<81>")
	)
	(segment
		(start 134.97814 -366.867186)
		(end 129.52222 -358.914446)
		(width 0.1651)
		(layer "In7.Cu")
		(net "P5E_PEX1_STN5_TX_C_DP<81>")
	)
	(segment
		(start 118.11 -405.390096)
		(end 118.11 -405.771858)
		(width 0.1651)
		(layer "In7.Cu")
		(net "P5E_PEX1_STN5_TX_C_DP<81>")
	)
	(segment
		(start 136.320022 -386.29844)
		(end 136.40943 -386.107432)
		(width 0.1651)
		(layer "In7.Cu")
		(net "P5E_PEX1_STN5_TX_C_DP<81>")
	)
	(segment
		(start 283.488638 -121.5898)
		(end 283.323538 -121.7549)
		(width 0.13462)
		(layer "F.Cu")
		(net "P5E_PEX2_STN1_RX_DN<25>")
	)
	(segment
		(start 284.14599 -121.5898)
		(end 283.488638 -121.5898)
		(width 0.13462)
		(layer "F.Cu")
		(net "P5E_PEX2_STN1_RX_DN<25>")
	)
	(segment
		(start 284.442662 -121.886472)
		(end 284.14599 -121.5898)
		(width 0.13462)
		(layer "F.Cu")
		(net "P5E_PEX2_STN1_RX_DN<25>")
	)
	(segment
		(start 283.323538 -121.7549)
		(end 282.842462 -121.7549)
		(width 0.13462)
		(layer "F.Cu")
		(net "P5E_PEX2_STN1_RX_DN<25>")
	)
	(segment
		(start 277.422356 -126.978918)
		(end 277.113746 -127.366014)
		(width 0.1651)
		(layer "In5.Cu")
		(net "P5E_PEX2_STN1_RX_DN<25>")
	)
	(segment
		(start 277.892256 -126.57328)
		(end 277.583138 -126.960884)
		(width 0.1651)
		(layer "In5.Cu")
		(net "P5E_PEX2_STN1_RX_DN<25>")
	)
	(segment
		(start 280.694892 -123.899676)
		(end 280.533348 -123.892056)
		(width 0.1651)
		(layer "In5.Cu")
		(net "P5E_PEX2_STN1_RX_DN<25>")
	)
	(segment
		(start 276.12467 -128.605788)
		(end 275.96465 -128.970024)
		(width 0.1651)
		(layer "In5.Cu")
		(net "P5E_PEX2_STN1_RX_DN<25>")
	)
	(segment
		(start 300.39945 -275.265134)
		(end 300.39945 -274.999704)
		(width 0.1143)
		(layer "In5.Cu")
		(net "P5E_PEX2_STN1_RX_DN<25>")
	)
	(segment
		(start 282.799282 -122.069352)
		(end 282.339288 -122.25274)
		(width 0.1651)
		(layer "In5.Cu")
		(net "P5E_PEX2_STN1_RX_DN<25>")
	)
	(segment
		(start 281.061922 -123.566682)
		(end 280.694892 -123.899676)
		(width 0.1651)
		(layer "In5.Cu")
		(net "P5E_PEX2_STN1_RX_DN<25>")
	)
	(segment
		(start 300.065694 -271.570704)
		(end 300.065694 -271.599152)
		(width 0.1143)
		(layer "In5.Cu")
		(net "P5E_PEX2_STN1_RX_DN<25>")
	)
	(segment
		(start 276.66188 -127.93218)
		(end 276.12467 -128.605788)
		(width 0.1651)
		(layer "In5.Cu")
		(net "P5E_PEX2_STN1_RX_DN<25>")
	)
	(segment
		(start 280.166826 -124.224796)
		(end 280.158952 -124.38634)
		(width 0.1651)
		(layer "In5.Cu")
		(net "P5E_PEX2_STN1_RX_DN<25>")
	)
	(segment
		(start 282.947618 -122.133106)
		(end 282.799282 -122.069352)
		(width 0.1651)
		(layer "In5.Cu")
		(net "P5E_PEX2_STN1_RX_DN<25>")
	)
	(segment
		(start 278.727408 -125.531372)
		(end 278.182832 -126.025656)
		(width 0.1651)
		(layer "In5.Cu")
		(net "P5E_PEX2_STN1_RX_DN<25>")
	)
	(segment
		(start 277.873968 -126.412752)
		(end 277.892256 -126.57328)
		(width 0.1651)
		(layer "In5.Cu")
		(net "P5E_PEX2_STN1_RX_DN<25>")
	)
	(segment
		(start 274.396962 -137.99439)
		(end 273.42084 -141.405356)
		(width 0.1651)
		(layer "In5.Cu")
		(net "P5E_PEX2_STN1_RX_DN<25>")
	)
	(segment
		(start 277.13178 -127.526542)
		(end 276.822662 -127.914146)
		(width 0.1651)
		(layer "In5.Cu")
		(net "P5E_PEX2_STN1_RX_DN<25>")
	)
	(segment
		(start 270.334994 -147.294346)
		(end 270.944086 -157.221936)
		(width 0.1651)
		(layer "In5.Cu")
		(net "P5E_PEX2_STN1_RX_DN<25>")
	)
	(segment
		(start 281.972766 -122.58548)
		(end 281.964892 -122.747024)
		(width 0.1651)
		(layer "In5.Cu")
		(net "P5E_PEX2_STN1_RX_DN<25>")
	)
	(segment
		(start 279.255982 -125.205998)
		(end 278.888952 -125.538992)
		(width 0.1651)
		(layer "In5.Cu")
		(net "P5E_PEX2_STN1_RX_DN<25>")
	)
	(segment
		(start 279.791922 -124.719334)
		(end 279.630378 -124.711714)
		(width 0.1651)
		(layer "In5.Cu")
		(net "P5E_PEX2_STN1_RX_DN<25>")
	)
	(segment
		(start 270.944086 -157.221936)
		(end 271.880838 -162.364166)
		(width 0.1651)
		(layer "In5.Cu")
		(net "P5E_PEX2_STN1_RX_DN<25>")
	)
	(segment
		(start 281.597862 -123.080018)
		(end 281.436318 -123.072398)
		(width 0.1651)
		(layer "In5.Cu")
		(net "P5E_PEX2_STN1_RX_DN<25>")
	)
	(segment
		(start 283.471874 -121.800874)
		(end 283.40812 -121.949718)
		(width 0.1651)
		(layer "In5.Cu")
		(net "P5E_PEX2_STN1_RX_DN<25>")
	)
	(segment
		(start 273.499326 -141.54658)
		(end 273.363182 -142.023084)
		(width 0.1651)
		(layer "In5.Cu")
		(net "P5E_PEX2_STN1_RX_DN<25>")
	)
	(segment
		(start 273.22145 -142.10157)
		(end 273.031458 -142.766034)
		(width 0.1651)
		(layer "In5.Cu")
		(net "P5E_PEX2_STN1_RX_DN<25>")
	)
	(segment
		(start 300.123352 -275.379434)
		(end 300.28515 -275.379434)
		(width 0.1143)
		(layer "In5.Cu")
		(net "P5E_PEX2_STN1_RX_DN<25>")
	)
	(segment
		(start 270.745712 -145.714212)
		(end 270.334994 -147.294346)
		(width 0.1651)
		(layer "In5.Cu")
		(net "P5E_PEX2_STN1_RX_DN<25>")
	)
	(segment
		(start 281.964892 -122.747024)
		(end 281.597862 -123.080018)
		(width 0.1651)
		(layer "In5.Cu")
		(net "P5E_PEX2_STN1_RX_DN<25>")
	)
	(segment
		(start 275.96465 -128.970024)
		(end 274.396962 -137.99439)
		(width 0.1651)
		(layer "In5.Cu")
		(net "P5E_PEX2_STN1_RX_DN<25>")
	)
	(segment
		(start 276.822662 -127.914146)
		(end 276.66188 -127.93218)
		(width 0.1651)
		(layer "In5.Cu")
		(net "P5E_PEX2_STN1_RX_DN<25>")
	)
	(segment
		(start 277.583138 -126.960884)
		(end 277.422356 -126.978918)
		(width 0.1651)
		(layer "In5.Cu")
		(net "P5E_PEX2_STN1_RX_DN<25>")
	)
	(segment
		(start 273.363182 -142.023084)
		(end 273.22145 -142.10157)
		(width 0.1651)
		(layer "In5.Cu")
		(net "P5E_PEX2_STN1_RX_DN<25>")
	)
	(segment
		(start 283.986732 -121.595642)
		(end 283.471874 -121.800874)
		(width 0.1651)
		(layer "In5.Cu")
		(net "P5E_PEX2_STN1_RX_DN<25>")
	)
	(segment
		(start 278.888952 -125.538992)
		(end 278.727408 -125.531372)
		(width 0.1651)
		(layer "In5.Cu")
		(net "P5E_PEX2_STN1_RX_DN<25>")
	)
	(segment
		(start 273.031458 -142.766034)
		(end 270.745712 -145.714212)
		(width 0.1651)
		(layer "In5.Cu")
		(net "P5E_PEX2_STN1_RX_DN<25>")
	)
	(segment
		(start 279.263856 -125.044454)
		(end 279.255982 -125.205998)
		(width 0.1651)
		(layer "In5.Cu")
		(net "P5E_PEX2_STN1_RX_DN<25>")
	)
	(segment
		(start 280.533348 -123.892056)
		(end 280.166826 -124.224796)
		(width 0.1651)
		(layer "In5.Cu")
		(net "P5E_PEX2_STN1_RX_DN<25>")
	)
	(segment
		(start 300.019974 -275.276056)
		(end 300.123352 -275.379434)
		(width 0.1143)
		(layer "In5.Cu")
		(net "P5E_PEX2_STN1_RX_DN<25>")
	)
	(segment
		(start 284.442662 -121.886472)
		(end 284.151832 -121.595642)
		(width 0.1651)
		(layer "In5.Cu")
		(net "P5E_PEX2_STN1_RX_DN<25>")
	)
	(segment
		(start 279.630378 -124.711714)
		(end 279.263856 -125.044454)
		(width 0.1651)
		(layer "In5.Cu")
		(net "P5E_PEX2_STN1_RX_DN<25>")
	)
	(segment
		(start 300.019974 -271.644872)
		(end 300.019974 -275.276056)
		(width 0.1143)
		(layer "In5.Cu")
		(net "P5E_PEX2_STN1_RX_DN<25>")
	)
	(segment
		(start 281.069796 -123.405138)
		(end 281.061922 -123.566682)
		(width 0.1651)
		(layer "In5.Cu")
		(net "P5E_PEX2_STN1_RX_DN<25>")
	)
	(segment
		(start 280.158952 -124.38634)
		(end 279.791922 -124.719334)
		(width 0.1651)
		(layer "In5.Cu")
		(net "P5E_PEX2_STN1_RX_DN<25>")
	)
	(segment
		(start 300.065694 -271.599152)
		(end 300.019974 -271.644872)
		(width 0.1143)
		(layer "In5.Cu")
		(net "P5E_PEX2_STN1_RX_DN<25>")
	)
	(segment
		(start 300.28515 -275.379434)
		(end 300.39945 -275.265134)
		(width 0.1143)
		(layer "In5.Cu")
		(net "P5E_PEX2_STN1_RX_DN<25>")
	)
	(segment
		(start 283.40812 -121.949718)
		(end 282.947618 -122.133106)
		(width 0.1651)
		(layer "In5.Cu")
		(net "P5E_PEX2_STN1_RX_DN<25>")
	)
	(segment
		(start 281.436318 -123.072398)
		(end 281.069796 -123.405138)
		(width 0.1651)
		(layer "In5.Cu")
		(net "P5E_PEX2_STN1_RX_DN<25>")
	)
	(segment
		(start 284.151832 -121.595642)
		(end 283.986732 -121.595642)
		(width 0.1651)
		(layer "In5.Cu")
		(net "P5E_PEX2_STN1_RX_DN<25>")
	)
	(segment
		(start 300.065694 -268.037056)
		(end 300.065694 -271.570704)
		(width 0.1651)
		(layer "In5.Cu")
		(net "P5E_PEX2_STN1_RX_DN<25>")
	)
	(segment
		(start 282.339288 -122.25274)
		(end 281.972766 -122.58548)
		(width 0.1651)
		(layer "In5.Cu")
		(net "P5E_PEX2_STN1_RX_DN<25>")
	)
	(segment
		(start 271.880838 -162.364166)
		(end 300.065694 -268.037056)
		(width 0.1651)
		(layer "In5.Cu")
		(net "P5E_PEX2_STN1_RX_DN<25>")
	)
	(segment
		(start 278.182832 -126.025656)
		(end 277.873968 -126.412752)
		(width 0.1651)
		(layer "In5.Cu")
		(net "P5E_PEX2_STN1_RX_DN<25>")
	)
	(segment
		(start 273.42084 -141.405356)
		(end 273.499326 -141.54658)
		(width 0.1651)
		(layer "In5.Cu")
		(net "P5E_PEX2_STN1_RX_DN<25>")
	)
	(segment
		(start 277.113746 -127.366014)
		(end 277.13178 -127.526542)
		(width 0.1651)
		(layer "In5.Cu")
		(net "P5E_PEX2_STN1_RX_DN<25>")
	)
	(segment
		(start 277.792942 -356.831646)
		(end 277.792942 -357.46309)
		(width 0.13462)
		(layer "F.Cu")
		(net "P5E_PEX2_STN7_TX_C_DN<117>")
	)
	(segment
		(start 278.112982 -356.511606)
		(end 277.792942 -356.831646)
		(width 0.13462)
		(layer "F.Cu")
		(net "P5E_PEX2_STN7_TX_C_DN<117>")
	)
	(segment
		(start 277.792942 -357.46309)
		(end 278.087582 -357.75773)
		(width 0.13462)
		(layer "F.Cu")
		(net "P5E_PEX2_STN7_TX_C_DN<117>")
	)
	(segment
		(start 298.489878 -402.408136)
		(end 298.616878 -402.281136)
		(width 0.1651)
		(layer "In7.Cu")
		(net "P5E_PEX2_STN7_TX_C_DN<117>")
	)
	(segment
		(start 297.9928 -393.2682)
		(end 294.386 -390.8806)
		(width 0.1651)
		(layer "In7.Cu")
		(net "P5E_PEX2_STN7_TX_C_DN<117>")
	)
	(segment
		(start 277.796752 -358.519222)
		(end 277.796752 -358.04856)
		(width 0.1651)
		(layer "In7.Cu")
		(net "P5E_PEX2_STN7_TX_C_DN<117>")
	)
	(segment
		(start 282.773882 -373.79656)
		(end 277.796752 -358.519222)
		(width 0.1651)
		(layer "In7.Cu")
		(net "P5E_PEX2_STN7_TX_C_DN<117>")
	)
	(segment
		(start 299.61586 -395.4526)
		(end 299.2374 -394.5128)
		(width 0.1651)
		(layer "In7.Cu")
		(net "P5E_PEX2_STN7_TX_C_DN<117>")
	)
	(segment
		(start 277.796752 -358.04856)
		(end 278.087582 -357.75773)
		(width 0.1651)
		(layer "In7.Cu")
		(net "P5E_PEX2_STN7_TX_C_DN<117>")
	)
	(segment
		(start 294.386 -390.8806)
		(end 286.212534 -387.287516)
		(width 0.1651)
		(layer "In7.Cu")
		(net "P5E_PEX2_STN7_TX_C_DN<117>")
	)
	(segment
		(start 284.50921 -384.855212)
		(end 282.773882 -373.79656)
		(width 0.1651)
		(layer "In7.Cu")
		(net "P5E_PEX2_STN7_TX_C_DN<117>")
	)
	(segment
		(start 285.21914 -386.365242)
		(end 284.50921 -384.855212)
		(width 0.1651)
		(layer "In7.Cu")
		(net "P5E_PEX2_STN7_TX_C_DN<117>")
	)
	(segment
		(start 298.489878 -402.790152)
		(end 298.489878 -402.408136)
		(width 0.1651)
		(layer "In7.Cu")
		(net "P5E_PEX2_STN7_TX_C_DN<117>")
	)
	(segment
		(start 298.616878 -402.281136)
		(end 299.163994 -402.281136)
		(width 0.1651)
		(layer "In7.Cu")
		(net "P5E_PEX2_STN7_TX_C_DN<117>")
	)
	(segment
		(start 299.2374 -394.5128)
		(end 297.9928 -393.2682)
		(width 0.1651)
		(layer "In7.Cu")
		(net "P5E_PEX2_STN7_TX_C_DN<117>")
	)
	(segment
		(start 286.212534 -387.287516)
		(end 285.21914 -386.365242)
		(width 0.1651)
		(layer "In7.Cu")
		(net "P5E_PEX2_STN7_TX_C_DN<117>")
	)
	(segment
		(start 299.163994 -402.281136)
		(end 299.61586 -401.82927)
		(width 0.1651)
		(layer "In7.Cu")
		(net "P5E_PEX2_STN7_TX_C_DN<117>")
	)
	(segment
		(start 299.61586 -401.82927)
		(end 299.61586 -395.4526)
		(width 0.1651)
		(layer "In7.Cu")
		(net "P5E_PEX2_STN7_TX_C_DN<117>")
	)
	(segment
		(start 436.964836 -32.589978)
		(end 436.485538 -32.589978)
		(width 0.13462)
		(layer "F.Cu")
		(net "P5E_PEX3_STN2_RX_DP<34>")
	)
	(segment
		(start 436.485538 -32.589978)
		(end 436.32628 -32.43072)
		(width 0.13462)
		(layer "F.Cu")
		(net "P5E_PEX3_STN2_RX_DP<34>")
	)
	(segment
		(start 435.656228 -32.43072)
		(end 435.364636 -32.722312)
		(width 0.13462)
		(layer "F.Cu")
		(net "P5E_PEX3_STN2_RX_DP<34>")
	)
	(segment
		(start 436.32628 -32.43072)
		(end 435.656228 -32.43072)
		(width 0.13462)
		(layer "F.Cu")
		(net "P5E_PEX3_STN2_RX_DP<34>")
	)
	(segment
		(start 425.760134 -143.730472)
		(end 424.372786 -154.509978)
		(width 0.1651)
		(layer "In7.Cu")
		(net "P5E_PEX3_STN2_RX_DP<34>")
	)
	(segment
		(start 437.061356 -61.197744)
		(end 426.075094 -116.573554)
		(width 0.1651)
		(layer "In7.Cu")
		(net "P5E_PEX3_STN2_RX_DP<34>")
	)
	(segment
		(start 435.93131 -39.731442)
		(end 437.244744 -49.45253)
		(width 0.1651)
		(layer "In7.Cu")
		(net "P5E_PEX3_STN2_RX_DP<34>")
	)
	(segment
		(start 404.483824 -270.641064)
		(end 404.483824 -271.392904)
		(width 0.1651)
		(layer "In7.Cu")
		(net "P5E_PEX3_STN2_RX_DP<34>")
	)
	(segment
		(start 435.900576 -37.779198)
		(end 435.931056 -39.714678)
		(width 0.1651)
		(layer "In7.Cu")
		(net "P5E_PEX3_STN2_RX_DP<34>")
	)
	(segment
		(start 424.372786 -154.509978)
		(end 404.812754 -266.82319)
		(width 0.1651)
		(layer "In7.Cu")
		(net "P5E_PEX3_STN2_RX_DP<34>")
	)
	(segment
		(start 404.483824 -271.421352)
		(end 404.529544 -271.467072)
		(width 0.1143)
		(layer "In7.Cu")
		(net "P5E_PEX3_STN2_RX_DP<34>")
	)
	(segment
		(start 404.529544 -271.467072)
		(end 404.529544 -275.354796)
		(width 0.1143)
		(layer "In7.Cu")
		(net "P5E_PEX3_STN2_RX_DP<34>")
	)
	(segment
		(start 436.324502 -34.155888)
		(end 436.437024 -34.271966)
		(width 0.1651)
		(layer "In7.Cu")
		(net "P5E_PEX3_STN2_RX_DP<34>")
	)
	(segment
		(start 436.064152 -36.901374)
		(end 435.900576 -37.779198)
		(width 0.1651)
		(layer "In7.Cu")
		(net "P5E_PEX3_STN2_RX_DP<34>")
	)
	(segment
		(start 435.590188 -32.49676)
		(end 435.747668 -32.431482)
		(width 0.1651)
		(layer "In7.Cu")
		(net "P5E_PEX3_STN2_RX_DP<34>")
	)
	(segment
		(start 436.196994 -36.189412)
		(end 436.06339 -36.280852)
		(width 0.1651)
		(layer "In7.Cu")
		(net "P5E_PEX3_STN2_RX_DP<34>")
	)
	(segment
		(start 436.45836 -32.905954)
		(end 436.448454 -33.547812)
		(width 0.1651)
		(layer "In7.Cu")
		(net "P5E_PEX3_STN2_RX_DP<34>")
	)
	(segment
		(start 435.931056 -39.714678)
		(end 435.930802 -39.714678)
		(width 0.1651)
		(layer "In7.Cu")
		(net "P5E_PEX3_STN2_RX_DP<34>")
	)
	(segment
		(start 404.812754 -266.82319)
		(end 404.483824 -270.641064)
		(width 0.1651)
		(layer "In7.Cu")
		(net "P5E_PEX3_STN2_RX_DP<34>")
	)
	(segment
		(start 404.529544 -275.354796)
		(end 404.744936 -275.570188)
		(width 0.1143)
		(layer "In7.Cu")
		(net "P5E_PEX3_STN2_RX_DP<34>")
	)
	(segment
		(start 404.744936 -275.570188)
		(end 404.985728 -275.570188)
		(width 0.1143)
		(layer "In7.Cu")
		(net "P5E_PEX3_STN2_RX_DP<34>")
	)
	(segment
		(start 404.483824 -271.392904)
		(end 404.483824 -271.421352)
		(width 0.1143)
		(layer "In7.Cu")
		(net "P5E_PEX3_STN2_RX_DP<34>")
	)
	(segment
		(start 437.244744 -49.45253)
		(end 437.061356 -61.197744)
		(width 0.1651)
		(layer "In7.Cu")
		(net "P5E_PEX3_STN2_RX_DP<34>")
	)
	(segment
		(start 436.06339 -36.280852)
		(end 435.972712 -36.768024)
		(width 0.1651)
		(layer "In7.Cu")
		(net "P5E_PEX3_STN2_RX_DP<34>")
	)
	(segment
		(start 405.100028 -275.684488)
		(end 405.100028 -275.949918)
		(width 0.1143)
		(layer "In7.Cu")
		(net "P5E_PEX3_STN2_RX_DP<34>")
	)
	(segment
		(start 404.985728 -275.570188)
		(end 405.100028 -275.684488)
		(width 0.1143)
		(layer "In7.Cu")
		(net "P5E_PEX3_STN2_RX_DP<34>")
	)
	(segment
		(start 436.42661 -34.95675)
		(end 436.196994 -36.189412)
		(width 0.1651)
		(layer "In7.Cu")
		(net "P5E_PEX3_STN2_RX_DP<34>")
	)
	(segment
		(start 436.448454 -33.547812)
		(end 436.332122 -33.660334)
		(width 0.1651)
		(layer "In7.Cu")
		(net "P5E_PEX3_STN2_RX_DP<34>")
	)
	(segment
		(start 426.075094 -116.573554)
		(end 425.760134 -143.730472)
		(width 0.1651)
		(layer "In7.Cu")
		(net "P5E_PEX3_STN2_RX_DP<34>")
	)
	(segment
		(start 435.930802 -39.714678)
		(end 435.93131 -39.731442)
		(width 0.1651)
		(layer "In7.Cu")
		(net "P5E_PEX3_STN2_RX_DP<34>")
	)
	(segment
		(start 436.437024 -34.271966)
		(end 436.42661 -34.95675)
		(width 0.1651)
		(layer "In7.Cu")
		(net "P5E_PEX3_STN2_RX_DP<34>")
	)
	(segment
		(start 436.332122 -33.660334)
		(end 436.324502 -34.155888)
		(width 0.1651)
		(layer "In7.Cu")
		(net "P5E_PEX3_STN2_RX_DP<34>")
	)
	(segment
		(start 435.984142 -32.431482)
		(end 436.45836 -32.905954)
		(width 0.1651)
		(layer "In7.Cu")
		(net "P5E_PEX3_STN2_RX_DP<34>")
	)
	(segment
		(start 435.364636 -32.722312)
		(end 435.590188 -32.49676)
		(width 0.1651)
		(layer "In7.Cu")
		(net "P5E_PEX3_STN2_RX_DP<34>")
	)
	(segment
		(start 435.972712 -36.768024)
		(end 436.064152 -36.901374)
		(width 0.1651)
		(layer "In7.Cu")
		(net "P5E_PEX3_STN2_RX_DP<34>")
	)
	(segment
		(start 435.747668 -32.431482)
		(end 435.984142 -32.431482)
		(width 0.1651)
		(layer "In7.Cu")
		(net "P5E_PEX3_STN2_RX_DP<34>")
	)
	(segment
		(start 441.273692 -344.219022)
		(end 440.95416 -344.538554)
		(width 0.13462)
		(layer "F.Cu")
		(net "P5E_PEX3_STN7_TX_C_DN<126>")
	)
	(segment
		(start 440.95416 -345.171014)
		(end 441.248292 -345.465146)
		(width 0.13462)
		(layer "F.Cu")
		(net "P5E_PEX3_STN7_TX_C_DN<126>")
	)
	(segment
		(start 440.95416 -344.538554)
		(end 440.95416 -345.171014)
		(width 0.13462)
		(layer "F.Cu")
		(net "P5E_PEX3_STN7_TX_C_DN<126>")
	)
	(segment
		(start 432.816762 -375.181114)
		(end 433.363878 -375.181114)
		(width 0.1651)
		(layer "In11.Cu")
		(net "P5E_PEX3_STN7_TX_C_DN<126>")
	)
	(segment
		(start 433.815744 -369.555776)
		(end 434.213508 -368.06251)
		(width 0.1651)
		(layer "In11.Cu")
		(net "P5E_PEX3_STN7_TX_C_DN<126>")
	)
	(segment
		(start 438.943496 -359.813098)
		(end 439.402982 -358.088438)
		(width 0.1651)
		(layer "In11.Cu")
		(net "P5E_PEX3_STN7_TX_C_DN<126>")
	)
	(segment
		(start 434.213508 -368.06251)
		(end 438.943496 -359.813098)
		(width 0.1651)
		(layer "In11.Cu")
		(net "P5E_PEX3_STN7_TX_C_DN<126>")
	)
	(segment
		(start 440.957462 -346.326714)
		(end 440.957462 -345.755976)
		(width 0.1651)
		(layer "In11.Cu")
		(net "P5E_PEX3_STN7_TX_C_DN<126>")
	)
	(segment
		(start 439.402982 -358.088438)
		(end 439.402982 -347.881194)
		(width 0.1651)
		(layer "In11.Cu")
		(net "P5E_PEX3_STN7_TX_C_DN<126>")
	)
	(segment
		(start 433.363878 -375.181114)
		(end 433.815744 -374.729248)
		(width 0.1651)
		(layer "In11.Cu")
		(net "P5E_PEX3_STN7_TX_C_DN<126>")
	)
	(segment
		(start 440.957462 -345.755976)
		(end 441.248292 -345.465146)
		(width 0.1651)
		(layer "In11.Cu")
		(net "P5E_PEX3_STN7_TX_C_DN<126>")
	)
	(segment
		(start 432.689762 -375.69013)
		(end 432.689762 -375.308114)
		(width 0.1651)
		(layer "In11.Cu")
		(net "P5E_PEX3_STN7_TX_C_DN<126>")
	)
	(segment
		(start 432.689762 -375.308114)
		(end 432.816762 -375.181114)
		(width 0.1651)
		(layer "In11.Cu")
		(net "P5E_PEX3_STN7_TX_C_DN<126>")
	)
	(segment
		(start 433.815744 -374.729248)
		(end 433.815744 -369.555776)
		(width 0.1651)
		(layer "In11.Cu")
		(net "P5E_PEX3_STN7_TX_C_DN<126>")
	)
	(segment
		(start 439.402982 -347.881194)
		(end 440.957462 -346.326714)
		(width 0.1651)
		(layer "In11.Cu")
		(net "P5E_PEX3_STN7_TX_C_DN<126>")
	)
	(segment
		(start 157.162246 -142.080234)
		(end 157.277562 -141.964918)
		(width 0.13208)
		(layer "F.Cu")
		(net "NIC2_BIF1_N")
	)
	(segment
		(start 154.482546 -142.22095)
		(end 154.609546 -142.34795)
		(width 0.13208)
		(layer "F.Cu")
		(net "NIC2_BIF1_N")
	)
	(segment
		(start 153.504646 -141.87297)
		(end 154.482546 -141.87297)
		(width 0.13208)
		(layer "F.Cu")
		(net "NIC2_BIF1_N")
	)
	(segment
		(start 155.659328 -142.34795)
		(end 155.927044 -142.080234)
		(width 0.13208)
		(layer "F.Cu")
		(net "NIC2_BIF1_N")
	)
	(segment
		(start 154.609546 -142.34795)
		(end 155.659328 -142.34795)
		(width 0.13208)
		(layer "F.Cu")
		(net "NIC2_BIF1_N")
	)
	(segment
		(start 156.481272 -142.080234)
		(end 157.162246 -142.080234)
		(width 0.13208)
		(layer "F.Cu")
		(net "NIC2_BIF1_N")
	)
	(segment
		(start 157.277562 -141.964918)
		(end 162.14217 -141.964918)
		(width 0.13208)
		(layer "F.Cu")
		(net "NIC2_BIF1_N")
	)
	(segment
		(start 154.482546 -141.87297)
		(end 154.482546 -142.22095)
		(width 0.13208)
		(layer "F.Cu")
		(net "NIC2_BIF1_N")
	)
	(segment
		(start 155.927044 -142.080234)
		(end 156.481272 -142.080234)
		(width 0.13208)
		(layer "F.Cu")
		(net "NIC2_BIF1_N")
	)
	(via
		(at 156.481272 -142.080234)
		(size 0.762)
		(drill 0.381)
		(layers "F.Cu" "B.Cu")
		(net "NIC2_BIF1_N")
	)
	(segment
		(start 291.595048 -97.718372)
		(end 296.208958 -97.718372)
		(width 0.13208)
		(layer "F.Cu")
		(net "RST_NIC5_PERST3_R_N")
	)
	(segment
		(start 296.208958 -97.718372)
		(end 298.127166 -97.718372)
		(width 0.13208)
		(layer "F.Cu")
		(net "RST_NIC5_PERST3_R_N")
	)
	(segment
		(start 298.127166 -97.718372)
		(end 298.205398 -97.64014)
		(width 0.13208)
		(layer "F.Cu")
		(net "RST_NIC5_PERST3_R_N")
	)
	(segment
		(start 298.205398 -97.64014)
		(end 300.857412 -97.64014)
		(width 0.13208)
		(layer "F.Cu")
		(net "RST_NIC5_PERST3_R_N")
	)
	(via
		(at 296.208958 -97.718372)
		(size 0.762)
		(drill 0.381)
		(layers "F.Cu" "B.Cu")
		(net "RST_NIC5_PERST3_R_N")
	)
	(segment
		(start 68.65747 -153.554938)
		(end 68.169282 -153.554938)
		(width 0.13462)
		(layer "F.Cu")
		(net "P5E_PEX0_STN0_RX_DN<14>")
	)
	(segment
		(start 67.351402 -153.717752)
		(end 67.05727 -153.42362)
		(width 0.13462)
		(layer "F.Cu")
		(net "P5E_PEX0_STN0_RX_DN<14>")
	)
	(segment
		(start 68.169282 -153.554938)
		(end 68.006468 -153.717752)
		(width 0.13462)
		(layer "F.Cu")
		(net "P5E_PEX0_STN0_RX_DN<14>")
	)
	(segment
		(start 68.006468 -153.717752)
		(end 67.351402 -153.717752)
		(width 0.13462)
		(layer "F.Cu")
		(net "P5E_PEX0_STN0_RX_DN<14>")
	)
	(segment
		(start 68.277994 -154.211528)
		(end 68.515484 -154.733752)
		(width 0.1651)
		(layer "In5.Cu")
		(net "P5E_PEX0_STN0_RX_DN<14>")
	)
	(segment
		(start 75.46594 -270.457168)
		(end 75.46594 -271.773904)
		(width 0.1651)
		(layer "In5.Cu")
		(net "P5E_PEX0_STN0_RX_DN<14>")
	)
	(segment
		(start 75.799696 -275.265134)
		(end 75.799696 -274.999704)
		(width 0.1143)
		(layer "In5.Cu")
		(net "P5E_PEX0_STN0_RX_DN<14>")
	)
	(segment
		(start 68.7832 -160.386776)
		(end 68.898516 -162.064446)
		(width 0.1651)
		(layer "In5.Cu")
		(net "P5E_PEX0_STN0_RX_DN<14>")
	)
	(segment
		(start 68.898516 -162.064446)
		(end 69.314568 -164.671502)
		(width 0.1651)
		(layer "In5.Cu")
		(net "P5E_PEX0_STN0_RX_DN<14>")
	)
	(segment
		(start 75.523598 -275.379434)
		(end 75.685396 -275.379434)
		(width 0.1143)
		(layer "In5.Cu")
		(net "P5E_PEX0_STN0_RX_DN<14>")
	)
	(segment
		(start 75.46594 -271.802352)
		(end 75.42022 -271.848072)
		(width 0.1143)
		(layer "In5.Cu")
		(net "P5E_PEX0_STN0_RX_DN<14>")
	)
	(segment
		(start 68.782692 -158.632144)
		(end 68.7832 -158.632652)
		(width 0.1651)
		(layer "In5.Cu")
		(net "P5E_PEX0_STN0_RX_DN<14>")
	)
	(segment
		(start 68.515484 -154.733752)
		(end 68.782692 -158.632144)
		(width 0.1651)
		(layer "In5.Cu")
		(net "P5E_PEX0_STN0_RX_DN<14>")
	)
	(segment
		(start 69.314568 -164.671502)
		(end 75.745594 -258.322826)
		(width 0.1651)
		(layer "In5.Cu")
		(net "P5E_PEX0_STN0_RX_DN<14>")
	)
	(segment
		(start 75.685396 -275.379434)
		(end 75.799696 -275.265134)
		(width 0.1143)
		(layer "In5.Cu")
		(net "P5E_PEX0_STN0_RX_DN<14>")
	)
	(segment
		(start 75.42022 -271.848072)
		(end 75.42022 -275.276056)
		(width 0.1143)
		(layer "In5.Cu")
		(net "P5E_PEX0_STN0_RX_DN<14>")
	)
	(segment
		(start 75.960986 -267.81125)
		(end 75.46594 -270.457168)
		(width 0.1651)
		(layer "In5.Cu")
		(net "P5E_PEX0_STN0_RX_DN<14>")
	)
	(segment
		(start 75.46594 -271.773904)
		(end 75.46594 -271.802352)
		(width 0.1143)
		(layer "In5.Cu")
		(net "P5E_PEX0_STN0_RX_DN<14>")
	)
	(segment
		(start 67.05727 -153.42362)
		(end 67.34683 -153.71318)
		(width 0.1651)
		(layer "In5.Cu")
		(net "P5E_PEX0_STN0_RX_DN<14>")
	)
	(segment
		(start 68.7832 -158.632652)
		(end 68.7832 -160.386776)
		(width 0.1651)
		(layer "In5.Cu")
		(net "P5E_PEX0_STN0_RX_DN<14>")
	)
	(segment
		(start 67.34683 -153.71318)
		(end 67.779646 -153.71318)
		(width 0.1651)
		(layer "In5.Cu")
		(net "P5E_PEX0_STN0_RX_DN<14>")
	)
	(segment
		(start 75.42022 -275.276056)
		(end 75.523598 -275.379434)
		(width 0.1143)
		(layer "In5.Cu")
		(net "P5E_PEX0_STN0_RX_DN<14>")
	)
	(segment
		(start 75.745594 -258.322826)
		(end 75.960986 -267.81125)
		(width 0.1651)
		(layer "In5.Cu")
		(net "P5E_PEX0_STN0_RX_DN<14>")
	)
	(segment
		(start 67.779646 -153.71318)
		(end 68.277994 -154.211528)
		(width 0.1651)
		(layer "In5.Cu")
		(net "P5E_PEX0_STN0_RX_DN<14>")
	)
	(segment
		(start 283.323284 -109.044994)
		(end 282.842462 -109.044994)
		(width 0.13462)
		(layer "F.Cu")
		(net "P5E_PEX2_STN1_RX_DN<21>")
	)
	(segment
		(start 284.442662 -109.176312)
		(end 284.15615 -108.8898)
		(width 0.13462)
		(layer "F.Cu")
		(net "P5E_PEX2_STN1_RX_DN<21>")
	)
	(segment
		(start 284.15615 -108.8898)
		(end 283.478478 -108.8898)
		(width 0.13462)
		(layer "F.Cu")
		(net "P5E_PEX2_STN1_RX_DN<21>")
	)
	(segment
		(start 283.478478 -108.8898)
		(end 283.323284 -109.044994)
		(width 0.13462)
		(layer "F.Cu")
		(net "P5E_PEX2_STN1_RX_DN<21>")
	)
	(segment
		(start 280.91511 -110.66653)
		(end 280.484072 -110.911132)
		(width 0.1651)
		(layer "In5.Cu")
		(net "P5E_PEX2_STN1_RX_DN<21>")
	)
	(segment
		(start 270.620744 -127.82042)
		(end 270.680688 -127.970534)
		(width 0.1651)
		(layer "In5.Cu")
		(net "P5E_PEX2_STN1_RX_DN<21>")
	)
	(segment
		(start 271.10182 -126.700026)
		(end 271.161764 -126.85014)
		(width 0.1651)
		(layer "In5.Cu")
		(net "P5E_PEX2_STN1_RX_DN<21>")
	)
	(segment
		(start 269.372588 -130.726688)
		(end 268.752828 -132.169662)
		(width 0.1651)
		(layer "In5.Cu")
		(net "P5E_PEX2_STN1_RX_DN<21>")
	)
	(segment
		(start 270.81607 -127.365506)
		(end 270.620744 -127.82042)
		(width 0.1651)
		(layer "In5.Cu")
		(net "P5E_PEX2_STN1_RX_DN<21>")
	)
	(segment
		(start 270.139668 -128.940814)
		(end 270.199612 -129.090928)
		(width 0.1651)
		(layer "In5.Cu")
		(net "P5E_PEX2_STN1_RX_DN<21>")
	)
	(segment
		(start 267.55979 -139.737338)
		(end 265.575034 -150.684484)
		(width 0.1651)
		(layer "In5.Cu")
		(net "P5E_PEX2_STN1_RX_DN<21>")
	)
	(segment
		(start 268.752828 -132.169662)
		(end 268.752828 -136.432798)
		(width 0.1651)
		(layer "In5.Cu")
		(net "P5E_PEX2_STN1_RX_DN<21>")
	)
	(segment
		(start 283.819092 -108.885482)
		(end 283.820108 -108.886498)
		(width 0.1651)
		(layer "In5.Cu")
		(net "P5E_PEX2_STN1_RX_DN<21>")
	)
	(segment
		(start 279.85466 -111.268256)
		(end 279.423622 -111.512858)
		(width 0.1651)
		(layer "In5.Cu")
		(net "P5E_PEX2_STN1_RX_DN<21>")
	)
	(segment
		(start 270.199612 -129.090928)
		(end 270.004032 -129.54635)
		(width 0.1651)
		(layer "In5.Cu")
		(net "P5E_PEX2_STN1_RX_DN<21>")
	)
	(segment
		(start 281.758136 -110.188248)
		(end 281.602434 -110.145322)
		(width 0.1651)
		(layer "In5.Cu")
		(net "P5E_PEX2_STN1_RX_DN<21>")
	)
	(segment
		(start 265.575034 -150.684484)
		(end 266.059666 -158.511494)
		(width 0.1651)
		(layer "In5.Cu")
		(net "P5E_PEX2_STN1_RX_DN<21>")
	)
	(segment
		(start 267.11148 -164.60978)
		(end 296.265854 -269.144496)
		(width 0.1651)
		(layer "In5.Cu")
		(net "P5E_PEX2_STN1_RX_DN<21>")
	)
	(segment
		(start 269.853664 -129.606294)
		(end 269.658338 -130.061208)
		(width 0.1651)
		(layer "In5.Cu")
		(net "P5E_PEX2_STN1_RX_DN<21>")
	)
	(segment
		(start 274.871688 -113.984532)
		(end 274.211034 -115.159028)
		(width 0.1651)
		(layer "In5.Cu")
		(net "P5E_PEX2_STN1_RX_DN<21>")
	)
	(segment
		(start 296.220134 -275.276056)
		(end 296.323512 -275.379434)
		(width 0.1143)
		(layer "In5.Cu")
		(net "P5E_PEX2_STN1_RX_DN<21>")
	)
	(segment
		(start 274.211034 -115.159028)
		(end 272.102072 -124.370846)
		(width 0.1651)
		(layer "In5.Cu")
		(net "P5E_PEX2_STN1_RX_DN<21>")
	)
	(segment
		(start 270.966438 -127.305562)
		(end 270.81607 -127.365506)
		(width 0.1651)
		(layer "In5.Cu")
		(net "P5E_PEX2_STN1_RX_DN<21>")
	)
	(segment
		(start 266.059666 -158.511494)
		(end 267.11148 -164.60978)
		(width 0.1651)
		(layer "In5.Cu")
		(net "P5E_PEX2_STN1_RX_DN<21>")
	)
	(segment
		(start 283.249878 -109.34192)
		(end 282.818586 -109.586522)
		(width 0.1651)
		(layer "In5.Cu")
		(net "P5E_PEX2_STN1_RX_DN<21>")
	)
	(segment
		(start 269.522956 -130.666744)
		(end 269.372588 -130.726688)
		(width 0.1651)
		(layer "In5.Cu")
		(net "P5E_PEX2_STN1_RX_DN<21>")
	)
	(segment
		(start 270.485362 -128.425956)
		(end 270.334994 -128.4859)
		(width 0.1651)
		(layer "In5.Cu")
		(net "P5E_PEX2_STN1_RX_DN<21>")
	)
	(segment
		(start 282.2321 -109.787944)
		(end 282.189174 -109.943646)
		(width 0.1651)
		(layer "In5.Cu")
		(net "P5E_PEX2_STN1_RX_DN<21>")
	)
	(segment
		(start 283.292804 -109.186218)
		(end 283.249878 -109.34192)
		(width 0.1651)
		(layer "In5.Cu")
		(net "P5E_PEX2_STN1_RX_DN<21>")
	)
	(segment
		(start 270.004032 -129.54635)
		(end 269.853664 -129.606294)
		(width 0.1651)
		(layer "In5.Cu")
		(net "P5E_PEX2_STN1_RX_DN<21>")
	)
	(segment
		(start 296.220134 -271.644872)
		(end 296.220134 -275.276056)
		(width 0.1143)
		(layer "In5.Cu")
		(net "P5E_PEX2_STN1_RX_DN<21>")
	)
	(segment
		(start 296.265854 -271.599152)
		(end 296.220134 -271.644872)
		(width 0.1143)
		(layer "In5.Cu")
		(net "P5E_PEX2_STN1_RX_DN<21>")
	)
	(segment
		(start 283.820108 -108.886498)
		(end 283.820108 -108.887006)
		(width 0.1651)
		(layer "In5.Cu")
		(net "P5E_PEX2_STN1_RX_DN<21>")
	)
	(segment
		(start 280.32837 -110.868206)
		(end 279.897586 -111.112554)
		(width 0.1651)
		(layer "In5.Cu")
		(net "P5E_PEX2_STN1_RX_DN<21>")
	)
	(segment
		(start 271.161764 -126.85014)
		(end 270.966438 -127.305562)
		(width 0.1651)
		(layer "In5.Cu")
		(net "P5E_PEX2_STN1_RX_DN<21>")
	)
	(segment
		(start 282.662884 -109.543596)
		(end 282.2321 -109.787944)
		(width 0.1651)
		(layer "In5.Cu")
		(net "P5E_PEX2_STN1_RX_DN<21>")
	)
	(segment
		(start 279.267666 -111.469932)
		(end 274.923504 -113.93424)
		(width 0.1651)
		(layer "In5.Cu")
		(net "P5E_PEX2_STN1_RX_DN<21>")
	)
	(segment
		(start 296.265854 -271.570704)
		(end 296.265854 -271.599152)
		(width 0.1143)
		(layer "In5.Cu")
		(net "P5E_PEX2_STN1_RX_DN<21>")
	)
	(segment
		(start 279.897586 -111.112554)
		(end 279.85466 -111.268256)
		(width 0.1651)
		(layer "In5.Cu")
		(net "P5E_PEX2_STN1_RX_DN<21>")
	)
	(segment
		(start 268.752828 -136.432798)
		(end 267.55979 -139.737338)
		(width 0.1651)
		(layer "In5.Cu")
		(net "P5E_PEX2_STN1_RX_DN<21>")
	)
	(segment
		(start 272.102072 -124.370846)
		(end 271.10182 -126.700026)
		(width 0.1651)
		(layer "In5.Cu")
		(net "P5E_PEX2_STN1_RX_DN<21>")
	)
	(segment
		(start 284.151832 -108.885482)
		(end 283.819092 -108.885482)
		(width 0.1651)
		(layer "In5.Cu")
		(net "P5E_PEX2_STN1_RX_DN<21>")
	)
	(segment
		(start 296.48531 -275.379434)
		(end 296.59961 -275.265134)
		(width 0.1143)
		(layer "In5.Cu")
		(net "P5E_PEX2_STN1_RX_DN<21>")
	)
	(segment
		(start 269.658338 -130.061208)
		(end 269.718282 -130.211322)
		(width 0.1651)
		(layer "In5.Cu")
		(net "P5E_PEX2_STN1_RX_DN<21>")
	)
	(segment
		(start 270.680688 -127.970534)
		(end 270.485362 -128.425956)
		(width 0.1651)
		(layer "In5.Cu")
		(net "P5E_PEX2_STN1_RX_DN<21>")
	)
	(segment
		(start 280.958036 -110.510828)
		(end 280.91511 -110.66653)
		(width 0.1651)
		(layer "In5.Cu")
		(net "P5E_PEX2_STN1_RX_DN<21>")
	)
	(segment
		(start 296.59961 -275.265134)
		(end 296.59961 -274.999704)
		(width 0.1143)
		(layer "In5.Cu")
		(net "P5E_PEX2_STN1_RX_DN<21>")
	)
	(segment
		(start 279.423622 -111.512858)
		(end 279.267666 -111.469932)
		(width 0.1651)
		(layer "In5.Cu")
		(net "P5E_PEX2_STN1_RX_DN<21>")
	)
	(segment
		(start 269.718282 -130.211322)
		(end 269.522956 -130.666744)
		(width 0.1651)
		(layer "In5.Cu")
		(net "P5E_PEX2_STN1_RX_DN<21>")
	)
	(segment
		(start 270.334994 -128.4859)
		(end 270.139668 -128.940814)
		(width 0.1651)
		(layer "In5.Cu")
		(net "P5E_PEX2_STN1_RX_DN<21>")
	)
	(segment
		(start 280.484072 -110.911132)
		(end 280.32837 -110.868206)
		(width 0.1651)
		(layer "In5.Cu")
		(net "P5E_PEX2_STN1_RX_DN<21>")
	)
	(segment
		(start 281.602434 -110.145322)
		(end 280.958036 -110.510828)
		(width 0.1651)
		(layer "In5.Cu")
		(net "P5E_PEX2_STN1_RX_DN<21>")
	)
	(segment
		(start 284.442662 -109.176312)
		(end 284.151832 -108.885482)
		(width 0.1651)
		(layer "In5.Cu")
		(net "P5E_PEX2_STN1_RX_DN<21>")
	)
	(segment
		(start 282.818586 -109.586522)
		(end 282.662884 -109.543596)
		(width 0.1651)
		(layer "In5.Cu")
		(net "P5E_PEX2_STN1_RX_DN<21>")
	)
	(segment
		(start 274.923504 -113.93424)
		(end 274.871688 -113.984532)
		(width 0.1651)
		(layer "In5.Cu")
		(net "P5E_PEX2_STN1_RX_DN<21>")
	)
	(segment
		(start 282.189174 -109.943646)
		(end 281.758136 -110.188248)
		(width 0.1651)
		(layer "In5.Cu")
		(net "P5E_PEX2_STN1_RX_DN<21>")
	)
	(segment
		(start 296.323512 -275.379434)
		(end 296.48531 -275.379434)
		(width 0.1143)
		(layer "In5.Cu")
		(net "P5E_PEX2_STN1_RX_DN<21>")
	)
	(segment
		(start 296.265854 -269.144496)
		(end 296.265854 -271.570704)
		(width 0.1651)
		(layer "In5.Cu")
		(net "P5E_PEX2_STN1_RX_DN<21>")
	)
	(segment
		(start 283.820108 -108.887006)
		(end 283.292804 -109.186218)
		(width 0.1651)
		(layer "In5.Cu")
		(net "P5E_PEX2_STN1_RX_DN<21>")
	)
	(segment
		(start 294.14597 -392.980418)
		(end 294.146224 -392.980164)
		(width 0.1651)
		(layer "In5.Cu")
		(net "P5E_PEX2_STN7_RX_DP<116>")
	)
	(segment
		(start 295.27119 -393.705334)
		(end 295.709086 -393.93749)
		(width 0.1651)
		(layer "In5.Cu")
		(net "P5E_PEX2_STN7_RX_DP<116>")
	)
	(segment
		(start 269.127224 -340.63813)
		(end 269.742412 -342.378538)
		(width 0.1651)
		(layer "In5.Cu")
		(net "P5E_PEX2_STN7_RX_DP<116>")
	)
	(segment
		(start 283.268928 -385.099814)
		(end 284.001718 -386.870956)
		(width 0.1651)
		(layer "In5.Cu")
		(net "P5E_PEX2_STN7_RX_DP<116>")
	)
	(segment
		(start 271.520158 -305.055524)
		(end 271.294352 -304.829718)
		(width 0.1143)
		(layer "In5.Cu")
		(net "P5E_PEX2_STN7_RX_DP<116>")
	)
	(segment
		(start 296.864024 -394.482066)
		(end 297.134026 -394.989558)
		(width 0.1651)
		(layer "In5.Cu")
		(net "P5E_PEX2_STN7_RX_DP<116>")
	)
	(segment
		(start 255.13792 -315.629798)
		(end 253.48184 -319.462912)
		(width 0.1651)
		(layer "In5.Cu")
		(net "P5E_PEX2_STN7_RX_DP<116>")
	)
	(segment
		(start 267.911072 -304.829718)
		(end 267.865352 -304.783998)
		(width 0.1143)
		(layer "In5.Cu")
		(net "P5E_PEX2_STN7_RX_DP<116>")
	)
	(segment
		(start 295.223692 -393.550902)
		(end 295.27119 -393.705334)
		(width 0.1651)
		(layer "In5.Cu")
		(net "P5E_PEX2_STN7_RX_DP<116>")
	)
	(segment
		(start 269.742412 -357.956104)
		(end 270.07058 -358.765094)
		(width 0.1651)
		(layer "In5.Cu")
		(net "P5E_PEX2_STN7_RX_DP<116>")
	)
	(segment
		(start 282.913328 -378.833888)
		(end 283.268928 -385.099814)
		(width 0.1651)
		(layer "In5.Cu")
		(net "P5E_PEX2_STN7_RX_DP<116>")
	)
	(segment
		(start 294.78605 -393.319254)
		(end 295.223692 -393.550902)
		(width 0.1651)
		(layer "In5.Cu")
		(net "P5E_PEX2_STN7_RX_DP<116>")
	)
	(segment
		(start 294.146224 -392.980164)
		(end 294.193722 -393.134596)
		(width 0.1651)
		(layer "In5.Cu")
		(net "P5E_PEX2_STN7_RX_DP<116>")
	)
	(segment
		(start 296.416984 -408.699208)
		(end 296.289984 -408.572208)
		(width 0.1651)
		(layer "In5.Cu")
		(net "P5E_PEX2_STN7_RX_DP<116>")
	)
	(segment
		(start 285.748984 -388.53364)
		(end 294.14597 -392.980418)
		(width 0.1651)
		(layer "In5.Cu")
		(net "P5E_PEX2_STN7_RX_DP<116>")
	)
	(segment
		(start 271.899888 -305.399948)
		(end 271.634458 -305.399948)
		(width 0.1143)
		(layer "In5.Cu")
		(net "P5E_PEX2_STN7_RX_DP<116>")
	)
	(segment
		(start 296.30116 -394.12164)
		(end 296.864024 -394.482066)
		(width 0.1651)
		(layer "In5.Cu")
		(net "P5E_PEX2_STN7_RX_DP<116>")
	)
	(segment
		(start 267.865352 -304.783998)
		(end 267.836904 -304.783998)
		(width 0.1143)
		(layer "In5.Cu")
		(net "P5E_PEX2_STN7_RX_DP<116>")
	)
	(segment
		(start 265.166348 -304.783998)
		(end 261.57682 -306.084732)
		(width 0.1651)
		(layer "In5.Cu")
		(net "P5E_PEX2_STN7_RX_DP<116>")
	)
	(segment
		(start 270.07058 -358.765094)
		(end 281.452574 -370.478812)
		(width 0.1651)
		(layer "In5.Cu")
		(net "P5E_PEX2_STN7_RX_DP<116>")
	)
	(segment
		(start 297.134026 -408.412442)
		(end 296.84726 -408.699208)
		(width 0.1651)
		(layer "In5.Cu")
		(net "P5E_PEX2_STN7_RX_DP<116>")
	)
	(segment
		(start 297.134026 -394.989558)
		(end 297.134026 -408.412442)
		(width 0.1651)
		(layer "In5.Cu")
		(net "P5E_PEX2_STN7_RX_DP<116>")
	)
	(segment
		(start 253.48184 -319.462912)
		(end 253.48184 -322.531486)
		(width 0.1651)
		(layer "In5.Cu")
		(net "P5E_PEX2_STN7_RX_DP<116>")
	)
	(segment
		(start 295.709086 -393.93749)
		(end 295.863518 -393.889992)
		(width 0.1651)
		(layer "In5.Cu")
		(net "P5E_PEX2_STN7_RX_DP<116>")
	)
	(segment
		(start 261.57682 -306.084732)
		(end 258.60502 -309.080154)
		(width 0.1651)
		(layer "In5.Cu")
		(net "P5E_PEX2_STN7_RX_DP<116>")
	)
	(segment
		(start 271.634458 -305.399948)
		(end 271.520158 -305.285648)
		(width 0.1143)
		(layer "In5.Cu")
		(net "P5E_PEX2_STN7_RX_DP<116>")
	)
	(segment
		(start 253.48184 -322.531486)
		(end 255.040384 -326.275446)
		(width 0.1651)
		(layer "In5.Cu")
		(net "P5E_PEX2_STN7_RX_DP<116>")
	)
	(segment
		(start 282.307284 -372.167658)
		(end 282.913328 -378.833888)
		(width 0.1651)
		(layer "In5.Cu")
		(net "P5E_PEX2_STN7_RX_DP<116>")
	)
	(segment
		(start 271.520158 -305.285648)
		(end 271.520158 -305.055524)
		(width 0.1143)
		(layer "In5.Cu")
		(net "P5E_PEX2_STN7_RX_DP<116>")
	)
	(segment
		(start 281.452574 -370.478812)
		(end 282.307284 -372.167658)
		(width 0.1651)
		(layer "In5.Cu")
		(net "P5E_PEX2_STN7_RX_DP<116>")
	)
	(segment
		(start 295.863518 -393.889992)
		(end 296.30116 -394.12164)
		(width 0.1651)
		(layer "In5.Cu")
		(net "P5E_PEX2_STN7_RX_DP<116>")
	)
	(segment
		(start 258.60502 -309.080154)
		(end 255.13792 -315.629798)
		(width 0.1651)
		(layer "In5.Cu")
		(net "P5E_PEX2_STN7_RX_DP<116>")
	)
	(segment
		(start 296.289984 -408.572208)
		(end 296.289984 -408.190192)
		(width 0.1651)
		(layer "In5.Cu")
		(net "P5E_PEX2_STN7_RX_DP<116>")
	)
	(segment
		(start 255.040384 -326.275446)
		(end 269.127224 -340.63813)
		(width 0.1651)
		(layer "In5.Cu")
		(net "P5E_PEX2_STN7_RX_DP<116>")
	)
	(segment
		(start 271.294352 -304.829718)
		(end 267.911072 -304.829718)
		(width 0.1143)
		(layer "In5.Cu")
		(net "P5E_PEX2_STN7_RX_DP<116>")
	)
	(segment
		(start 284.001718 -386.870956)
		(end 285.748984 -388.53364)
		(width 0.1651)
		(layer "In5.Cu")
		(net "P5E_PEX2_STN7_RX_DP<116>")
	)
	(segment
		(start 294.631618 -393.366752)
		(end 294.78605 -393.319254)
		(width 0.1651)
		(layer "In5.Cu")
		(net "P5E_PEX2_STN7_RX_DP<116>")
	)
	(segment
		(start 267.836904 -304.783998)
		(end 265.166348 -304.783998)
		(width 0.1651)
		(layer "In5.Cu")
		(net "P5E_PEX2_STN7_RX_DP<116>")
	)
	(segment
		(start 294.193722 -393.134596)
		(end 294.631618 -393.366752)
		(width 0.1651)
		(layer "In5.Cu")
		(net "P5E_PEX2_STN7_RX_DP<116>")
	)
	(segment
		(start 296.84726 -408.699208)
		(end 296.416984 -408.699208)
		(width 0.1651)
		(layer "In5.Cu")
		(net "P5E_PEX2_STN7_RX_DP<116>")
	)
	(segment
		(start 269.742412 -342.378538)
		(end 269.742412 -357.956104)
		(width 0.1651)
		(layer "In5.Cu")
		(net "P5E_PEX2_STN7_RX_DP<116>")
	)
	(segment
		(start 357.656384 -32.43072)
		(end 357.364792 -32.722312)
		(width 0.13462)
		(layer "F.Cu")
		(net "P5E_PEX3_STN2_RX_DP<46>")
	)
	(segment
		(start 358.326436 -32.43072)
		(end 357.656384 -32.43072)
		(width 0.13462)
		(layer "F.Cu")
		(net "P5E_PEX3_STN2_RX_DP<46>")
	)
	(segment
		(start 358.964992 -32.589978)
		(end 358.485694 -32.589978)
		(width 0.13462)
		(layer "F.Cu")
		(net "P5E_PEX3_STN2_RX_DP<46>")
	)
	(segment
		(start 358.485694 -32.589978)
		(end 358.326436 -32.43072)
		(width 0.13462)
		(layer "F.Cu")
		(net "P5E_PEX3_STN2_RX_DP<46>")
	)
	(segment
		(start 358.460548 -32.7787)
		(end 358.44734 -33.636458)
		(width 0.1651)
		(layer "In7.Cu")
		(net "P5E_PEX3_STN2_RX_DP<46>")
	)
	(segment
		(start 358.42575 -35.019996)
		(end 358.32288 -35.572446)
		(width 0.1651)
		(layer "In7.Cu")
		(net "P5E_PEX3_STN2_RX_DP<46>")
	)
	(segment
		(start 393.083796 -270.404336)
		(end 393.083796 -271.392904)
		(width 0.1651)
		(layer "In7.Cu")
		(net "P5E_PEX3_STN2_RX_DP<46>")
	)
	(segment
		(start 393.129516 -275.354796)
		(end 393.344908 -275.570188)
		(width 0.1143)
		(layer "In7.Cu")
		(net "P5E_PEX3_STN2_RX_DP<46>")
	)
	(segment
		(start 359.404158 -60.306966)
		(end 359.404158 -61.722)
		(width 0.1651)
		(layer "In7.Cu")
		(net "P5E_PEX3_STN2_RX_DP<46>")
	)
	(segment
		(start 359.404158 -61.722)
		(end 359.211626 -85.491066)
		(width 0.1651)
		(layer "In7.Cu")
		(net "P5E_PEX3_STN2_RX_DP<46>")
	)
	(segment
		(start 358.19461 -36.259516)
		(end 357.901494 -37.832538)
		(width 0.1651)
		(layer "In7.Cu")
		(net "P5E_PEX3_STN2_RX_DP<46>")
	)
	(segment
		(start 393.083796 -271.392904)
		(end 393.083796 -271.421352)
		(width 0.1143)
		(layer "In7.Cu")
		(net "P5E_PEX3_STN2_RX_DP<46>")
	)
	(segment
		(start 393.083796 -271.421352)
		(end 393.129516 -271.467072)
		(width 0.1143)
		(layer "In7.Cu")
		(net "P5E_PEX3_STN2_RX_DP<46>")
	)
	(segment
		(start 357.901494 -37.832538)
		(end 357.938578 -40.16883)
		(width 0.1651)
		(layer "In7.Cu")
		(net "P5E_PEX3_STN2_RX_DP<46>")
	)
	(segment
		(start 369.615974 -119.815864)
		(end 372.889272 -144.702276)
		(width 0.1651)
		(layer "In7.Cu")
		(net "P5E_PEX3_STN2_RX_DP<46>")
	)
	(segment
		(start 358.204008 -35.653726)
		(end 358.11333 -36.140898)
		(width 0.1651)
		(layer "In7.Cu")
		(net "P5E_PEX3_STN2_RX_DP<46>")
	)
	(segment
		(start 358.336342 -34.231834)
		(end 358.436164 -34.334958)
		(width 0.1651)
		(layer "In7.Cu")
		(net "P5E_PEX3_STN2_RX_DP<46>")
	)
	(segment
		(start 390.99363 -242.68049)
		(end 392.185398 -255.697482)
		(width 0.1651)
		(layer "In7.Cu")
		(net "P5E_PEX3_STN2_RX_DP<46>")
	)
	(segment
		(start 393.129516 -271.467072)
		(end 393.129516 -275.354796)
		(width 0.1143)
		(layer "In7.Cu")
		(net "P5E_PEX3_STN2_RX_DP<46>")
	)
	(segment
		(start 364.411514 -102.645718)
		(end 364.423452 -102.685088)
		(width 0.1651)
		(layer "In7.Cu")
		(net "P5E_PEX3_STN2_RX_DP<46>")
	)
	(segment
		(start 393.7 -275.684488)
		(end 393.7 -275.949918)
		(width 0.1143)
		(layer "In7.Cu")
		(net "P5E_PEX3_STN2_RX_DP<46>")
	)
	(segment
		(start 359.123742 -57.21223)
		(end 359.404158 -60.306966)
		(width 0.1651)
		(layer "In7.Cu")
		(net "P5E_PEX3_STN2_RX_DP<46>")
	)
	(segment
		(start 393.344908 -275.570188)
		(end 393.5857 -275.570188)
		(width 0.1143)
		(layer "In7.Cu")
		(net "P5E_PEX3_STN2_RX_DP<46>")
	)
	(segment
		(start 359.239566 -49.798986)
		(end 359.123742 -57.21223)
		(width 0.1651)
		(layer "In7.Cu")
		(net "P5E_PEX3_STN2_RX_DP<46>")
	)
	(segment
		(start 357.938578 -40.16883)
		(end 359.239566 -49.798986)
		(width 0.1651)
		(layer "In7.Cu")
		(net "P5E_PEX3_STN2_RX_DP<46>")
	)
	(segment
		(start 358.11333 -36.140898)
		(end 358.19461 -36.259516)
		(width 0.1651)
		(layer "In7.Cu")
		(net "P5E_PEX3_STN2_RX_DP<46>")
	)
	(segment
		(start 392.185398 -255.697482)
		(end 392.108436 -263.536684)
		(width 0.1651)
		(layer "In7.Cu")
		(net "P5E_PEX3_STN2_RX_DP<46>")
	)
	(segment
		(start 364.423452 -102.685088)
		(end 364.423706 -102.68585)
		(width 0.1651)
		(layer "In7.Cu")
		(net "P5E_PEX3_STN2_RX_DP<46>")
	)
	(segment
		(start 393.5857 -275.570188)
		(end 393.7 -275.684488)
		(width 0.1143)
		(layer "In7.Cu")
		(net "P5E_PEX3_STN2_RX_DP<46>")
	)
	(segment
		(start 364.423706 -102.68585)
		(end 369.615974 -119.815864)
		(width 0.1651)
		(layer "In7.Cu")
		(net "P5E_PEX3_STN2_RX_DP<46>")
	)
	(segment
		(start 357.364792 -32.722312)
		(end 357.655622 -32.431482)
		(width 0.1651)
		(layer "In7.Cu")
		(net "P5E_PEX3_STN2_RX_DP<46>")
	)
	(segment
		(start 358.11333 -32.431482)
		(end 358.460548 -32.7787)
		(width 0.1651)
		(layer "In7.Cu")
		(net "P5E_PEX3_STN2_RX_DP<46>")
	)
	(segment
		(start 359.211626 -85.491066)
		(end 364.411514 -102.64521)
		(width 0.1651)
		(layer "In7.Cu")
		(net "P5E_PEX3_STN2_RX_DP<46>")
	)
	(segment
		(start 392.108436 -263.536684)
		(end 393.083796 -270.404336)
		(width 0.1651)
		(layer "In7.Cu")
		(net "P5E_PEX3_STN2_RX_DP<46>")
	)
	(segment
		(start 358.44734 -33.636458)
		(end 358.343962 -33.73628)
		(width 0.1651)
		(layer "In7.Cu")
		(net "P5E_PEX3_STN2_RX_DP<46>")
	)
	(segment
		(start 358.436164 -34.334958)
		(end 358.42575 -35.019996)
		(width 0.1651)
		(layer "In7.Cu")
		(net "P5E_PEX3_STN2_RX_DP<46>")
	)
	(segment
		(start 357.655622 -32.431482)
		(end 358.11333 -32.431482)
		(width 0.1651)
		(layer "In7.Cu")
		(net "P5E_PEX3_STN2_RX_DP<46>")
	)
	(segment
		(start 358.32288 -35.572446)
		(end 358.204008 -35.653726)
		(width 0.1651)
		(layer "In7.Cu")
		(net "P5E_PEX3_STN2_RX_DP<46>")
	)
	(segment
		(start 390.993376 -242.68049)
		(end 390.99363 -242.68049)
		(width 0.1651)
		(layer "In7.Cu")
		(net "P5E_PEX3_STN2_RX_DP<46>")
	)
	(segment
		(start 358.343962 -33.73628)
		(end 358.336342 -34.231834)
		(width 0.1651)
		(layer "In7.Cu")
		(net "P5E_PEX3_STN2_RX_DP<46>")
	)
	(segment
		(start 364.411514 -102.64521)
		(end 364.411514 -102.645718)
		(width 0.1651)
		(layer "In7.Cu")
		(net "P5E_PEX3_STN2_RX_DP<46>")
	)
	(segment
		(start 390.596628 -238.34217)
		(end 390.993376 -242.68049)
		(width 0.1651)
		(layer "In7.Cu")
		(net "P5E_PEX3_STN2_RX_DP<46>")
	)
	(segment
		(start 372.889272 -144.702276)
		(end 390.596628 -238.34217)
		(width 0.1651)
		(layer "In7.Cu")
		(net "P5E_PEX3_STN2_RX_DP<46>")
	)
	(segment
		(start 421.705532 -344.219022)
		(end 422.02608 -344.53957)
		(width 0.13462)
		(layer "F.Cu")
		(net "P5E_PEX3_STN7_TX_C_DP<117>")
	)
	(segment
		(start 422.02608 -344.53957)
		(end 422.02608 -345.169998)
		(width 0.13462)
		(layer "F.Cu")
		(net "P5E_PEX3_STN7_TX_C_DP<117>")
	)
	(segment
		(start 422.02608 -345.169998)
		(end 421.730932 -345.465146)
		(width 0.13462)
		(layer "F.Cu")
		(net "P5E_PEX3_STN7_TX_C_DP<117>")
	)
	(segment
		(start 428.15256 -392.777726)
		(end 428.15256 -392.77798)
		(width 0.1651)
		(layer "In11.Cu")
		(net "P5E_PEX3_STN7_TX_C_DP<117>")
	)
	(segment
		(start 416.9664 -387.207506)
		(end 416.140646 -385.36499)
		(width 0.1651)
		(layer "In11.Cu")
		(net "P5E_PEX3_STN7_TX_C_DP<117>")
	)
	(segment
		(start 428.755302 -393.077954)
		(end 428.636176 -393.118086)
		(width 0.1651)
		(layer "In11.Cu")
		(net "P5E_PEX3_STN7_TX_C_DP<117>")
	)
	(segment
		(start 426.083476 -391.86104)
		(end 426.037756 -391.724642)
		(width 0.1651)
		(layer "In11.Cu")
		(net "P5E_PEX3_STN7_TX_C_DP<117>")
	)
	(segment
		(start 431.33391 -401.71243)
		(end 431.33391 -394.80109)
		(width 0.1651)
		(layer "In11.Cu")
		(net "P5E_PEX3_STN7_TX_C_DP<117>")
	)
	(segment
		(start 430.489868 -401.49018)
		(end 430.489868 -401.872196)
		(width 0.1651)
		(layer "In11.Cu")
		(net "P5E_PEX3_STN7_TX_C_DP<117>")
	)
	(segment
		(start 415.908744 -383.38252)
		(end 416.169094 -368.842544)
		(width 0.1651)
		(layer "In11.Cu")
		(net "P5E_PEX3_STN7_TX_C_DP<117>")
	)
	(segment
		(start 427.106588 -392.257026)
		(end 426.663358 -392.0363)
		(width 0.1651)
		(layer "In11.Cu")
		(net "P5E_PEX3_STN7_TX_C_DP<117>")
	)
	(segment
		(start 429.198532 -393.29868)
		(end 428.755302 -393.077954)
		(width 0.1651)
		(layer "In11.Cu")
		(net "P5E_PEX3_STN7_TX_C_DP<117>")
	)
	(segment
		(start 430.489868 -401.872196)
		(end 430.616868 -401.999196)
		(width 0.1651)
		(layer "In11.Cu")
		(net "P5E_PEX3_STN7_TX_C_DP<117>")
	)
	(segment
		(start 426.527214 -392.08202)
		(end 426.083476 -391.86104)
		(width 0.1651)
		(layer "In11.Cu")
		(net "P5E_PEX3_STN7_TX_C_DP<117>")
	)
	(segment
		(start 427.70933 -392.557254)
		(end 427.590204 -392.597386)
		(width 0.1651)
		(layer "In11.Cu")
		(net "P5E_PEX3_STN7_TX_C_DP<117>")
	)
	(segment
		(start 426.037756 -391.724642)
		(end 426.037756 -391.724896)
		(width 0.1651)
		(layer "In11.Cu")
		(net "P5E_PEX3_STN7_TX_C_DP<117>")
	)
	(segment
		(start 420.467282 -347.764354)
		(end 422.021762 -346.209874)
		(width 0.1651)
		(layer "In11.Cu")
		(net "P5E_PEX3_STN7_TX_C_DP<117>")
	)
	(segment
		(start 422.021762 -345.755976)
		(end 421.730932 -345.465146)
		(width 0.1651)
		(layer "In11.Cu")
		(net "P5E_PEX3_STN7_TX_C_DP<117>")
	)
	(segment
		(start 416.140646 -385.36499)
		(end 415.908744 -383.38252)
		(width 0.1651)
		(layer "In11.Cu")
		(net "P5E_PEX3_STN7_TX_C_DP<117>")
	)
	(segment
		(start 426.037756 -391.724896)
		(end 416.9664 -387.207506)
		(width 0.1651)
		(layer "In11.Cu")
		(net "P5E_PEX3_STN7_TX_C_DP<117>")
	)
	(segment
		(start 428.636176 -393.118086)
		(end 428.192438 -392.896852)
		(width 0.1651)
		(layer "In11.Cu")
		(net "P5E_PEX3_STN7_TX_C_DP<117>")
	)
	(segment
		(start 416.169094 -368.842544)
		(end 420.467282 -358.619044)
		(width 0.1651)
		(layer "In11.Cu")
		(net "P5E_PEX3_STN7_TX_C_DP<117>")
	)
	(segment
		(start 427.590204 -392.597386)
		(end 427.146466 -392.376152)
		(width 0.1651)
		(layer "In11.Cu")
		(net "P5E_PEX3_STN7_TX_C_DP<117>")
	)
	(segment
		(start 431.33391 -394.80109)
		(end 430.459642 -393.926822)
		(width 0.1651)
		(layer "In11.Cu")
		(net "P5E_PEX3_STN7_TX_C_DP<117>")
	)
	(segment
		(start 427.146466 -392.376152)
		(end 427.106588 -392.257026)
		(width 0.1651)
		(layer "In11.Cu")
		(net "P5E_PEX3_STN7_TX_C_DP<117>")
	)
	(segment
		(start 428.192438 -392.896852)
		(end 428.15256 -392.777726)
		(width 0.1651)
		(layer "In11.Cu")
		(net "P5E_PEX3_STN7_TX_C_DP<117>")
	)
	(segment
		(start 429.801274 -393.598908)
		(end 429.681894 -393.63904)
		(width 0.1651)
		(layer "In11.Cu")
		(net "P5E_PEX3_STN7_TX_C_DP<117>")
	)
	(segment
		(start 430.616868 -401.999196)
		(end 431.047144 -401.999196)
		(width 0.1651)
		(layer "In11.Cu")
		(net "P5E_PEX3_STN7_TX_C_DP<117>")
	)
	(segment
		(start 426.663358 -392.0363)
		(end 426.527214 -392.08202)
		(width 0.1651)
		(layer "In11.Cu")
		(net "P5E_PEX3_STN7_TX_C_DP<117>")
	)
	(segment
		(start 422.021762 -346.209874)
		(end 422.021762 -345.755976)
		(width 0.1651)
		(layer "In11.Cu")
		(net "P5E_PEX3_STN7_TX_C_DP<117>")
	)
	(segment
		(start 420.467282 -358.619044)
		(end 420.467282 -347.764354)
		(width 0.1651)
		(layer "In11.Cu")
		(net "P5E_PEX3_STN7_TX_C_DP<117>")
	)
	(segment
		(start 429.23841 -393.417806)
		(end 429.198532 -393.29868)
		(width 0.1651)
		(layer "In11.Cu")
		(net "P5E_PEX3_STN7_TX_C_DP<117>")
	)
	(segment
		(start 430.459642 -393.926822)
		(end 429.801274 -393.598908)
		(width 0.1651)
		(layer "In11.Cu")
		(net "P5E_PEX3_STN7_TX_C_DP<117>")
	)
	(segment
		(start 431.047144 -401.999196)
		(end 431.33391 -401.71243)
		(width 0.1651)
		(layer "In11.Cu")
		(net "P5E_PEX3_STN7_TX_C_DP<117>")
	)
	(segment
		(start 429.681894 -393.63904)
		(end 429.23841 -393.417806)
		(width 0.1651)
		(layer "In11.Cu")
		(net "P5E_PEX3_STN7_TX_C_DP<117>")
	)
	(segment
		(start 428.15256 -392.77798)
		(end 427.70933 -392.557254)
		(width 0.1651)
		(layer "In11.Cu")
		(net "P5E_PEX3_STN7_TX_C_DP<117>")
	)
	(segment
		(start 170.37558 -140.867892)
		(end 171.344844 -140.867892)
		(width 0.13208)
		(layer "F.Cu")
		(net "RST_SMB_NIC2_MUX_ISO_R_N")
	)
	(segment
		(start 166.742364 -141.36497)
		(end 168.309036 -141.36497)
		(width 0.13208)
		(layer "F.Cu")
		(net "RST_SMB_NIC2_MUX_ISO_R_N")
	)
	(segment
		(start 168.806114 -140.867892)
		(end 170.37558 -140.867892)
		(width 0.13208)
		(layer "F.Cu")
		(net "RST_SMB_NIC2_MUX_ISO_R_N")
	)
	(segment
		(start 168.309036 -141.36497)
		(end 168.806114 -140.867892)
		(width 0.13208)
		(layer "F.Cu")
		(net "RST_SMB_NIC2_MUX_ISO_R_N")
	)
	(segment
		(start 171.344844 -140.867892)
		(end 171.912534 -140.300202)
		(width 0.13208)
		(layer "F.Cu")
		(net "RST_SMB_NIC2_MUX_ISO_R_N")
	)
	(segment
		(start 173.087792 -140.300202)
		(end 173.764194 -139.6238)
		(width 0.13208)
		(layer "F.Cu")
		(net "RST_SMB_NIC2_MUX_ISO_R_N")
	)
	(segment
		(start 171.912534 -140.300202)
		(end 173.087792 -140.300202)
		(width 0.13208)
		(layer "F.Cu")
		(net "RST_SMB_NIC2_MUX_ISO_R_N")
	)
	(via
		(at 170.37558 -140.867892)
		(size 0.762)
		(drill 0.381)
		(layers "F.Cu" "B.Cu")
		(net "RST_SMB_NIC2_MUX_ISO_R_N")
	)
	(segment
		(start 307.73878 -100.640134)
		(end 308.168294 -101.069648)
		(width 0.13208)
		(layer "F.Cu")
		(net "NIC5_SLOT_ID0")
	)
	(segment
		(start 305.457606 -100.640134)
		(end 307.73878 -100.640134)
		(width 0.13208)
		(layer "F.Cu")
		(net "NIC5_SLOT_ID0")
	)
	(via
		(at 308.168294 -101.069648)
		(size 0.508)
		(drill 0.254)
		(layers "F.Cu" "B.Cu")
		(net "NIC5_SLOT_ID0")
	)
	(segment
		(start 309.341774 -101.069648)
		(end 308.168294 -101.069648)
		(width 0.13208)
		(layer "B.Cu")
		(net "NIC5_SLOT_ID0")
	)
	(segment
		(start 309.341774 -100.056696)
		(end 309.341774 -101.069648)
		(width 0.13208)
		(layer "B.Cu")
		(net "NIC5_SLOT_ID0")
	)
	(segment
		(start 73.745852 -143.35506)
		(end 73.908666 -143.192246)
		(width 0.13462)
		(layer "F.Cu")
		(net "P5E_PEX0_STN0_TX_C_DP<8>")
	)
	(segment
		(start 79.440278 -143.192246)
		(end 79.752698 -143.504666)
		(width 0.13462)
		(layer "F.Cu")
		(net "P5E_PEX0_STN0_TX_C_DP<8>")
	)
	(segment
		(start 73.257664 -143.35506)
		(end 73.745852 -143.35506)
		(width 0.13462)
		(layer "F.Cu")
		(net "P5E_PEX0_STN0_TX_C_DP<8>")
	)
	(segment
		(start 73.908666 -143.192246)
		(end 79.440278 -143.192246)
		(width 0.13462)
		(layer "F.Cu")
		(net "P5E_PEX0_STN0_TX_C_DP<8>")
	)
	(segment
		(start 286.01543 -134.61492)
		(end 283.470096 -134.61492)
		(width 0.13462)
		(layer "F.Cu")
		(net "P5E_PEX2_STN1_RX_DN<30>")
	)
	(segment
		(start 283.470096 -134.61492)
		(end 283.319982 -134.765034)
		(width 0.13462)
		(layer "F.Cu")
		(net "P5E_PEX2_STN1_RX_DN<30>")
	)
	(segment
		(start 283.319982 -134.765034)
		(end 282.842462 -134.765034)
		(width 0.13462)
		(layer "F.Cu")
		(net "P5E_PEX2_STN1_RX_DN<30>")
	)
	(segment
		(start 286.296862 -134.896352)
		(end 286.01543 -134.61492)
		(width 0.13462)
		(layer "F.Cu")
		(net "P5E_PEX2_STN1_RX_DN<30>")
	)
	(segment
		(start 286.296862 -134.896352)
		(end 286.003746 -134.603236)
		(width 0.1651)
		(layer "In5.Cu")
		(net "P5E_PEX2_STN1_RX_DN<30>")
	)
	(segment
		(start 282.221178 -141.209776)
		(end 281.902662 -141.979142)
		(width 0.1651)
		(layer "In5.Cu")
		(net "P5E_PEX2_STN1_RX_DN<30>")
	)
	(segment
		(start 305.149504 -273.365214)
		(end 305.149504 -273.099784)
		(width 0.1143)
		(layer "In5.Cu")
		(net "P5E_PEX2_STN1_RX_DN<30>")
	)
	(segment
		(start 275.638768 -153.586688)
		(end 275.555964 -153.681176)
		(width 0.1651)
		(layer "In5.Cu")
		(net "P5E_PEX2_STN1_RX_DN<30>")
	)
	(segment
		(start 304.873406 -273.479514)
		(end 305.035204 -273.479514)
		(width 0.1143)
		(layer "In5.Cu")
		(net "P5E_PEX2_STN1_RX_DN<30>")
	)
	(segment
		(start 304.815748 -271.554448)
		(end 304.770028 -271.600168)
		(width 0.1143)
		(layer "In5.Cu")
		(net "P5E_PEX2_STN1_RX_DN<30>")
	)
	(segment
		(start 282.335478 -138.885676)
		(end 282.335478 -139.380976)
		(width 0.1651)
		(layer "In5.Cu")
		(net "P5E_PEX2_STN1_RX_DN<30>")
	)
	(segment
		(start 276.700488 -147.17014)
		(end 276.206204 -147.17014)
		(width 0.1651)
		(layer "In5.Cu")
		(net "P5E_PEX2_STN1_RX_DN<30>")
	)
	(segment
		(start 281.7749 -142.586202)
		(end 281.625294 -142.648178)
		(width 0.1651)
		(layer "In5.Cu")
		(net "P5E_PEX2_STN1_RX_DN<30>")
	)
	(segment
		(start 275.430488 -151.792686)
		(end 275.540724 -151.889206)
		(width 0.1651)
		(layer "In5.Cu")
		(net "P5E_PEX2_STN1_RX_DN<30>")
	)
	(segment
		(start 282.221178 -138.771376)
		(end 282.335478 -138.885676)
		(width 0.1651)
		(layer "In5.Cu")
		(net "P5E_PEX2_STN1_RX_DN<30>")
	)
	(segment
		(start 275.51126 -153.009346)
		(end 275.606002 -153.09215)
		(width 0.1651)
		(layer "In5.Cu")
		(net "P5E_PEX2_STN1_RX_DN<30>")
	)
	(segment
		(start 304.770028 -273.376136)
		(end 304.873406 -273.479514)
		(width 0.1143)
		(layer "In5.Cu")
		(net "P5E_PEX2_STN1_RX_DN<30>")
	)
	(segment
		(start 275.397722 -151.298656)
		(end 275.430488 -151.792686)
		(width 0.1651)
		(layer "In5.Cu")
		(net "P5E_PEX2_STN1_RX_DN<30>")
	)
	(segment
		(start 278.96312 -145.454624)
		(end 278.6507 -145.920968)
		(width 0.1651)
		(layer "In5.Cu")
		(net "P5E_PEX2_STN1_RX_DN<30>")
	)
	(segment
		(start 286.003746 -134.603236)
		(end 285.99765 -134.605522)
		(width 0.1651)
		(layer "In5.Cu")
		(net "P5E_PEX2_STN1_RX_DN<30>")
	)
	(segment
		(start 283.33573 -134.937754)
		(end 283.223208 -135.044688)
		(width 0.1651)
		(layer "In5.Cu")
		(net "P5E_PEX2_STN1_RX_DN<30>")
	)
	(segment
		(start 282.221178 -139.990576)
		(end 282.335478 -140.104876)
		(width 0.1651)
		(layer "In5.Cu")
		(net "P5E_PEX2_STN1_RX_DN<30>")
	)
	(segment
		(start 275.907246 -147.257262)
		(end 275.764752 -147.328636)
		(width 0.1651)
		(layer "In5.Cu")
		(net "P5E_PEX2_STN1_RX_DN<30>")
	)
	(segment
		(start 275.633434 -154.847036)
		(end 275.756878 -156.713936)
		(width 0.1651)
		(layer "In5.Cu")
		(net "P5E_PEX2_STN1_RX_DN<30>")
	)
	(segment
		(start 281.625294 -142.648432)
		(end 281.342592 -143.33093)
		(width 0.1651)
		(layer "In5.Cu")
		(net "P5E_PEX2_STN1_RX_DN<30>")
	)
	(segment
		(start 277.897082 -146.674586)
		(end 276.700488 -147.17014)
		(width 0.1651)
		(layer "In5.Cu")
		(net "P5E_PEX2_STN1_RX_DN<30>")
	)
	(segment
		(start 281.342592 -143.33093)
		(end 280.387044 -144.286478)
		(width 0.1651)
		(layer "In5.Cu")
		(net "P5E_PEX2_STN1_RX_DN<30>")
	)
	(segment
		(start 275.504148 -151.17699)
		(end 275.397722 -151.298656)
		(width 0.1651)
		(layer "In5.Cu")
		(net "P5E_PEX2_STN1_RX_DN<30>")
	)
	(segment
		(start 282.221178 -140.714476)
		(end 282.221178 -141.209776)
		(width 0.1651)
		(layer "In5.Cu")
		(net "P5E_PEX2_STN1_RX_DN<30>")
	)
	(segment
		(start 283.223208 -135.044688)
		(end 283.011626 -135.492236)
		(width 0.1651)
		(layer "In5.Cu")
		(net "P5E_PEX2_STN1_RX_DN<30>")
	)
	(segment
		(start 284.137608 -134.605522)
		(end 283.33573 -134.937754)
		(width 0.1651)
		(layer "In5.Cu")
		(net "P5E_PEX2_STN1_RX_DN<30>")
	)
	(segment
		(start 304.815748 -267.233654)
		(end 304.815748 -271.526)
		(width 0.1651)
		(layer "In5.Cu")
		(net "P5E_PEX2_STN1_RX_DN<30>")
	)
	(segment
		(start 282.221178 -139.495276)
		(end 282.221178 -139.990576)
		(width 0.1651)
		(layer "In5.Cu")
		(net "P5E_PEX2_STN1_RX_DN<30>")
	)
	(segment
		(start 283.065982 -135.644382)
		(end 282.853892 -136.092438)
		(width 0.1651)
		(layer "In5.Cu")
		(net "P5E_PEX2_STN1_RX_DN<30>")
	)
	(segment
		(start 275.764752 -147.328636)
		(end 275.438108 -147.574)
		(width 0.1651)
		(layer "In5.Cu")
		(net "P5E_PEX2_STN1_RX_DN<30>")
	)
	(segment
		(start 275.471382 -150.682452)
		(end 275.504148 -151.17699)
		(width 0.1651)
		(layer "In5.Cu")
		(net "P5E_PEX2_STN1_RX_DN<30>")
	)
	(segment
		(start 285.242508 -134.719822)
		(end 284.747208 -134.719822)
		(width 0.1651)
		(layer "In5.Cu")
		(net "P5E_PEX2_STN1_RX_DN<30>")
	)
	(segment
		(start 282.701746 -136.147048)
		(end 282.701746 -136.147302)
		(width 0.1651)
		(layer "In5.Cu")
		(net "P5E_PEX2_STN1_RX_DN<30>")
	)
	(segment
		(start 275.185378 -148.099526)
		(end 275.349716 -150.576026)
		(width 0.1651)
		(layer "In5.Cu")
		(net "P5E_PEX2_STN1_RX_DN<30>")
	)
	(segment
		(start 282.701746 -136.147302)
		(end 282.221178 -137.163302)
		(width 0.1651)
		(layer "In5.Cu")
		(net "P5E_PEX2_STN1_RX_DN<30>")
	)
	(segment
		(start 281.625294 -142.648178)
		(end 281.625294 -142.648432)
		(width 0.1651)
		(layer "In5.Cu")
		(net "P5E_PEX2_STN1_RX_DN<30>")
	)
	(segment
		(start 284.632908 -134.605522)
		(end 284.137608 -134.605522)
		(width 0.1651)
		(layer "In5.Cu")
		(net "P5E_PEX2_STN1_RX_DN<30>")
	)
	(segment
		(start 282.853892 -136.092438)
		(end 282.701746 -136.147048)
		(width 0.1651)
		(layer "In5.Cu")
		(net "P5E_PEX2_STN1_RX_DN<30>")
	)
	(segment
		(start 285.99765 -134.605522)
		(end 285.356808 -134.605522)
		(width 0.1651)
		(layer "In5.Cu")
		(net "P5E_PEX2_STN1_RX_DN<30>")
	)
	(segment
		(start 275.756878 -156.713936)
		(end 276.468078 -160.706816)
		(width 0.1651)
		(layer "In5.Cu")
		(net "P5E_PEX2_STN1_RX_DN<30>")
	)
	(segment
		(start 275.668994 -154.245564)
		(end 275.703538 -154.767026)
		(width 0.1651)
		(layer "In5.Cu")
		(net "P5E_PEX2_STN1_RX_DN<30>")
	)
	(segment
		(start 275.606002 -153.09215)
		(end 275.638768 -153.586688)
		(width 0.1651)
		(layer "In5.Cu")
		(net "P5E_PEX2_STN1_RX_DN<30>")
	)
	(segment
		(start 304.815748 -271.526)
		(end 304.815748 -271.554448)
		(width 0.1143)
		(layer "In5.Cu")
		(net "P5E_PEX2_STN1_RX_DN<30>")
	)
	(segment
		(start 283.011626 -135.492236)
		(end 283.065982 -135.644382)
		(width 0.1651)
		(layer "In5.Cu")
		(net "P5E_PEX2_STN1_RX_DN<30>")
	)
	(segment
		(start 284.747208 -134.719822)
		(end 284.632908 -134.605522)
		(width 0.1651)
		(layer "In5.Cu")
		(net "P5E_PEX2_STN1_RX_DN<30>")
	)
	(segment
		(start 275.438108 -147.574)
		(end 275.185378 -148.099526)
		(width 0.1651)
		(layer "In5.Cu")
		(net "P5E_PEX2_STN1_RX_DN<30>")
	)
	(segment
		(start 281.964384 -142.128494)
		(end 281.7749 -142.586202)
		(width 0.1651)
		(layer "In5.Cu")
		(net "P5E_PEX2_STN1_RX_DN<30>")
	)
	(segment
		(start 282.335478 -140.104876)
		(end 282.335478 -140.600176)
		(width 0.1651)
		(layer "In5.Cu")
		(net "P5E_PEX2_STN1_RX_DN<30>")
	)
	(segment
		(start 275.575014 -152.40508)
		(end 275.478494 -152.515316)
		(width 0.1651)
		(layer "In5.Cu")
		(net "P5E_PEX2_STN1_RX_DN<30>")
	)
	(segment
		(start 275.555964 -153.681176)
		(end 275.588476 -154.175206)
		(width 0.1651)
		(layer "In5.Cu")
		(net "P5E_PEX2_STN1_RX_DN<30>")
	)
	(segment
		(start 280.387044 -144.286478)
		(end 278.96312 -145.454624)
		(width 0.1651)
		(layer "In5.Cu")
		(net "P5E_PEX2_STN1_RX_DN<30>")
	)
	(segment
		(start 281.902662 -141.979142)
		(end 281.964384 -142.128494)
		(width 0.1651)
		(layer "In5.Cu")
		(net "P5E_PEX2_STN1_RX_DN<30>")
	)
	(segment
		(start 275.703538 -154.767026)
		(end 275.633434 -154.847036)
		(width 0.1651)
		(layer "In5.Cu")
		(net "P5E_PEX2_STN1_RX_DN<30>")
	)
	(segment
		(start 275.540724 -151.889206)
		(end 275.575014 -152.40508)
		(width 0.1651)
		(layer "In5.Cu")
		(net "P5E_PEX2_STN1_RX_DN<30>")
	)
	(segment
		(start 282.335478 -139.380976)
		(end 282.221178 -139.495276)
		(width 0.1651)
		(layer "In5.Cu")
		(net "P5E_PEX2_STN1_RX_DN<30>")
	)
	(segment
		(start 282.221178 -137.163302)
		(end 282.221178 -138.771376)
		(width 0.1651)
		(layer "In5.Cu")
		(net "P5E_PEX2_STN1_RX_DN<30>")
	)
	(segment
		(start 275.588476 -154.175206)
		(end 275.668994 -154.245564)
		(width 0.1651)
		(layer "In5.Cu")
		(net "P5E_PEX2_STN1_RX_DN<30>")
	)
	(segment
		(start 285.356808 -134.605522)
		(end 285.242508 -134.719822)
		(width 0.1651)
		(layer "In5.Cu")
		(net "P5E_PEX2_STN1_RX_DN<30>")
	)
	(segment
		(start 275.478494 -152.515316)
		(end 275.51126 -153.009346)
		(width 0.1651)
		(layer "In5.Cu")
		(net "P5E_PEX2_STN1_RX_DN<30>")
	)
	(segment
		(start 275.349716 -150.576026)
		(end 275.349462 -150.576026)
		(width 0.1651)
		(layer "In5.Cu")
		(net "P5E_PEX2_STN1_RX_DN<30>")
	)
	(segment
		(start 276.206204 -147.17014)
		(end 275.907246 -147.257262)
		(width 0.1651)
		(layer "In5.Cu")
		(net "P5E_PEX2_STN1_RX_DN<30>")
	)
	(segment
		(start 304.770028 -271.600168)
		(end 304.770028 -273.376136)
		(width 0.1143)
		(layer "In5.Cu")
		(net "P5E_PEX2_STN1_RX_DN<30>")
	)
	(segment
		(start 305.035204 -273.479514)
		(end 305.149504 -273.365214)
		(width 0.1143)
		(layer "In5.Cu")
		(net "P5E_PEX2_STN1_RX_DN<30>")
	)
	(segment
		(start 282.335478 -140.600176)
		(end 282.221178 -140.714476)
		(width 0.1651)
		(layer "In5.Cu")
		(net "P5E_PEX2_STN1_RX_DN<30>")
	)
	(segment
		(start 278.6507 -145.920968)
		(end 277.897082 -146.674586)
		(width 0.1651)
		(layer "In5.Cu")
		(net "P5E_PEX2_STN1_RX_DN<30>")
	)
	(segment
		(start 275.349462 -150.576026)
		(end 275.471382 -150.682452)
		(width 0.1651)
		(layer "In5.Cu")
		(net "P5E_PEX2_STN1_RX_DN<30>")
	)
	(segment
		(start 276.468078 -160.706816)
		(end 304.815748 -267.233654)
		(width 0.1651)
		(layer "In5.Cu")
		(net "P5E_PEX2_STN1_RX_DN<30>")
	)
	(segment
		(start 384.48234 -34.390076)
		(end 384.313684 -34.22142)
		(width 0.13462)
		(layer "F.Cu")
		(net "P5E_PEX3_STN2_RX_DP<43>")
	)
	(segment
		(start 384.313684 -34.22142)
		(end 381.81153 -34.22142)
		(width 0.13462)
		(layer "F.Cu")
		(net "P5E_PEX3_STN2_RX_DP<43>")
	)
	(segment
		(start 384.96494 -34.390076)
		(end 384.48234 -34.390076)
		(width 0.13462)
		(layer "F.Cu")
		(net "P5E_PEX3_STN2_RX_DP<43>")
	)
	(segment
		(start 381.81153 -34.22142)
		(end 381.51054 -34.52241)
		(width 0.13462)
		(layer "F.Cu")
		(net "P5E_PEX3_STN2_RX_DP<43>")
	)
	(segment
		(start 395.47546 -263.230106)
		(end 395.47546 -262.82015)
		(width 0.1651)
		(layer "In7.Cu")
		(net "P5E_PEX3_STN2_RX_DP<43>")
	)
	(segment
		(start 396.54988 -273.784314)
		(end 396.43558 -273.670014)
		(width 0.1143)
		(layer "In7.Cu")
		(net "P5E_PEX3_STN2_RX_DP<43>")
	)
	(segment
		(start 382.946656 -37.978334)
		(end 382.94691 -37.978334)
		(width 0.1651)
		(layer "In7.Cu")
		(net "P5E_PEX3_STN2_RX_DP<43>")
	)
	(segment
		(start 384.195066 -55.483252)
		(end 384.288538 -49.509426)
		(width 0.1651)
		(layer "In7.Cu")
		(net "P5E_PEX3_STN2_RX_DP<43>")
	)
	(segment
		(start 384.288538 -49.509426)
		(end 382.97485 -39.786052)
		(width 0.1651)
		(layer "In7.Cu")
		(net "P5E_PEX3_STN2_RX_DP<43>")
	)
	(segment
		(start 395.752828 -248.479818)
		(end 387.353556 -141.679676)
		(width 0.1651)
		(layer "In7.Cu")
		(net "P5E_PEX3_STN2_RX_DP<43>")
	)
	(segment
		(start 388.092696 -131.969002)
		(end 388.226046 -119.595392)
		(width 0.1651)
		(layer "In7.Cu")
		(net "P5E_PEX3_STN2_RX_DP<43>")
	)
	(segment
		(start 396.242032 -273.670014)
		(end 395.97965 -273.407632)
		(width 0.1143)
		(layer "In7.Cu")
		(net "P5E_PEX3_STN2_RX_DP<43>")
	)
	(segment
		(start 382.90627 -35.357562)
		(end 382.90627 -35.1028)
		(width 0.1651)
		(layer "In7.Cu")
		(net "P5E_PEX3_STN2_RX_DP<43>")
	)
	(segment
		(start 382.856486 -37.890704)
		(end 382.848612 -37.395404)
		(width 0.1651)
		(layer "In7.Cu")
		(net "P5E_PEX3_STN2_RX_DP<43>")
	)
	(segment
		(start 382.94691 -37.978334)
		(end 382.856486 -37.890704)
		(width 0.1651)
		(layer "In7.Cu")
		(net "P5E_PEX3_STN2_RX_DP<43>")
	)
	(segment
		(start 395.47546 -262.82015)
		(end 395.752828 -248.479818)
		(width 0.1651)
		(layer "In7.Cu")
		(net "P5E_PEX3_STN2_RX_DP<43>")
	)
	(segment
		(start 395.97965 -271.41932)
		(end 395.93393 -271.3736)
		(width 0.1143)
		(layer "In7.Cu")
		(net "P5E_PEX3_STN2_RX_DP<43>")
	)
	(segment
		(start 382.918208 -36.13658)
		(end 382.90627 -35.357562)
		(width 0.1651)
		(layer "In7.Cu")
		(net "P5E_PEX3_STN2_RX_DP<43>")
	)
	(segment
		(start 382.97485 -39.786052)
		(end 382.946656 -37.978334)
		(width 0.1651)
		(layer "In7.Cu")
		(net "P5E_PEX3_STN2_RX_DP<43>")
	)
	(segment
		(start 381.80137 -34.23158)
		(end 381.51054 -34.52241)
		(width 0.1651)
		(layer "In7.Cu")
		(net "P5E_PEX3_STN2_RX_DP<43>")
	)
	(segment
		(start 396.54988 -274.049744)
		(end 396.54988 -273.784314)
		(width 0.1143)
		(layer "In7.Cu")
		(net "P5E_PEX3_STN2_RX_DP<43>")
	)
	(segment
		(start 382.830578 -36.227004)
		(end 382.918208 -36.13658)
		(width 0.1651)
		(layer "In7.Cu")
		(net "P5E_PEX3_STN2_RX_DP<43>")
	)
	(segment
		(start 382.848612 -37.395404)
		(end 382.936242 -37.30498)
		(width 0.1651)
		(layer "In7.Cu")
		(net "P5E_PEX3_STN2_RX_DP<43>")
	)
	(segment
		(start 382.90627 -35.1028)
		(end 382.03505 -34.23158)
		(width 0.1651)
		(layer "In7.Cu")
		(net "P5E_PEX3_STN2_RX_DP<43>")
	)
	(segment
		(start 395.93393 -267.885926)
		(end 395.47546 -263.230106)
		(width 0.1651)
		(layer "In7.Cu")
		(net "P5E_PEX3_STN2_RX_DP<43>")
	)
	(segment
		(start 382.928876 -36.809934)
		(end 382.838452 -36.722558)
		(width 0.1651)
		(layer "In7.Cu")
		(net "P5E_PEX3_STN2_RX_DP<43>")
	)
	(segment
		(start 384.586734 -65.267332)
		(end 384.195066 -55.483252)
		(width 0.1651)
		(layer "In7.Cu")
		(net "P5E_PEX3_STN2_RX_DP<43>")
	)
	(segment
		(start 387.387592 -138.494516)
		(end 388.092696 -131.969002)
		(width 0.1651)
		(layer "In7.Cu")
		(net "P5E_PEX3_STN2_RX_DP<43>")
	)
	(segment
		(start 382.936242 -37.30498)
		(end 382.928622 -36.809934)
		(width 0.1651)
		(layer "In7.Cu")
		(net "P5E_PEX3_STN2_RX_DP<43>")
	)
	(segment
		(start 382.928622 -36.809934)
		(end 382.928876 -36.809934)
		(width 0.1651)
		(layer "In7.Cu")
		(net "P5E_PEX3_STN2_RX_DP<43>")
	)
	(segment
		(start 395.93393 -271.3736)
		(end 395.93393 -271.345152)
		(width 0.1143)
		(layer "In7.Cu")
		(net "P5E_PEX3_STN2_RX_DP<43>")
	)
	(segment
		(start 382.03505 -34.23158)
		(end 381.80137 -34.23158)
		(width 0.1651)
		(layer "In7.Cu")
		(net "P5E_PEX3_STN2_RX_DP<43>")
	)
	(segment
		(start 382.838452 -36.722558)
		(end 382.830578 -36.227004)
		(width 0.1651)
		(layer "In7.Cu")
		(net "P5E_PEX3_STN2_RX_DP<43>")
	)
	(segment
		(start 396.43558 -273.670014)
		(end 396.242032 -273.670014)
		(width 0.1143)
		(layer "In7.Cu")
		(net "P5E_PEX3_STN2_RX_DP<43>")
	)
	(segment
		(start 388.226046 -119.595392)
		(end 387.788912 -105.153714)
		(width 0.1651)
		(layer "In7.Cu")
		(net "P5E_PEX3_STN2_RX_DP<43>")
	)
	(segment
		(start 387.353556 -141.679676)
		(end 387.387592 -138.494516)
		(width 0.1651)
		(layer "In7.Cu")
		(net "P5E_PEX3_STN2_RX_DP<43>")
	)
	(segment
		(start 395.97965 -273.407632)
		(end 395.97965 -271.41932)
		(width 0.1143)
		(layer "In7.Cu")
		(net "P5E_PEX3_STN2_RX_DP<43>")
	)
	(segment
		(start 395.93393 -271.345152)
		(end 395.93393 -267.885926)
		(width 0.1651)
		(layer "In7.Cu")
		(net "P5E_PEX3_STN2_RX_DP<43>")
	)
	(segment
		(start 387.788912 -105.153714)
		(end 384.586734 -65.267332)
		(width 0.1651)
		(layer "In7.Cu")
		(net "P5E_PEX3_STN2_RX_DP<43>")
	)
	(segment
		(start 391.453116 -323.141086)
		(end 389.715502 -322.591176)
		(width 0.1651)
		(layer "In9.Cu")
		(net "P5E_PEX3_STN7_RX_DN<125>")
	)
	(segment
		(start 407.844244 -328.329798)
		(end 392.100054 -323.346064)
		(width 0.1651)
		(layer "In9.Cu")
		(net "P5E_PEX3_STN7_RX_DN<125>")
	)
	(segment
		(start 391.567924 -323.08165)
		(end 391.453116 -323.141086)
		(width 0.1651)
		(layer "In9.Cu")
		(net "P5E_PEX3_STN7_RX_DN<125>")
	)
	(segment
		(start 439.167524 -341.290656)
		(end 420.537894 -334.313784)
		(width 0.1651)
		(layer "In9.Cu")
		(net "P5E_PEX3_STN7_RX_DN<125>")
	)
	(segment
		(start 431.646838 -383.389886)
		(end 431.646838 -368.700558)
		(width 0.1651)
		(layer "In9.Cu")
		(net "P5E_PEX3_STN7_RX_DN<125>")
	)
	(segment
		(start 392.100054 -323.346064)
		(end 392.040364 -323.231002)
		(width 0.1651)
		(layer "In9.Cu")
		(net "P5E_PEX3_STN7_RX_DN<125>")
	)
	(segment
		(start 388.615936 -321.02679)
		(end 388.615936 -319.893696)
		(width 0.1651)
		(layer "In9.Cu")
		(net "P5E_PEX3_STN7_RX_DN<125>")
	)
	(segment
		(start 430.489868 -384.20802)
		(end 430.616868 -384.08102)
		(width 0.1651)
		(layer "In9.Cu")
		(net "P5E_PEX3_STN7_RX_DN<125>")
	)
	(segment
		(start 430.489868 -384.590036)
		(end 430.489868 -384.20802)
		(width 0.1651)
		(layer "In9.Cu")
		(net "P5E_PEX3_STN7_RX_DN<125>")
	)
	(segment
		(start 439.402982 -358.351836)
		(end 439.402982 -341.630508)
		(width 0.1651)
		(layer "In9.Cu")
		(net "P5E_PEX3_STN7_RX_DN<125>")
	)
	(segment
		(start 388.949946 -318.409066)
		(end 388.949946 -318.699896)
		(width 0.1143)
		(layer "In9.Cu")
		(net "P5E_PEX3_STN7_RX_DN<125>")
	)
	(segment
		(start 388.570216 -319.819528)
		(end 388.570216 -318.447674)
		(width 0.1143)
		(layer "In9.Cu")
		(net "P5E_PEX3_STN7_RX_DN<125>")
	)
	(segment
		(start 388.615936 -319.893696)
		(end 388.615936 -319.865248)
		(width 0.1143)
		(layer "In9.Cu")
		(net "P5E_PEX3_STN7_RX_DN<125>")
	)
	(segment
		(start 388.570216 -318.447674)
		(end 388.697724 -318.320166)
		(width 0.1143)
		(layer "In9.Cu")
		(net "P5E_PEX3_STN7_RX_DN<125>")
	)
	(segment
		(start 389.072374 -322.128896)
		(end 388.615936 -321.02679)
		(width 0.1651)
		(layer "In9.Cu")
		(net "P5E_PEX3_STN7_RX_DN<125>")
	)
	(segment
		(start 439.402982 -341.630508)
		(end 439.167524 -341.290656)
		(width 0.1651)
		(layer "In9.Cu")
		(net "P5E_PEX3_STN7_RX_DN<125>")
	)
	(segment
		(start 388.615936 -319.865248)
		(end 388.570216 -319.819528)
		(width 0.1143)
		(layer "In9.Cu")
		(net "P5E_PEX3_STN7_RX_DN<125>")
	)
	(segment
		(start 388.697724 -318.320166)
		(end 388.861046 -318.320166)
		(width 0.1143)
		(layer "In9.Cu")
		(net "P5E_PEX3_STN7_RX_DN<125>")
	)
	(segment
		(start 430.955704 -384.08102)
		(end 431.646838 -383.389886)
		(width 0.1651)
		(layer "In9.Cu")
		(net "P5E_PEX3_STN7_RX_DN<125>")
	)
	(segment
		(start 389.715502 -322.591176)
		(end 389.072374 -322.128896)
		(width 0.1651)
		(layer "In9.Cu")
		(net "P5E_PEX3_STN7_RX_DN<125>")
	)
	(segment
		(start 431.646838 -368.700558)
		(end 439.402982 -358.351836)
		(width 0.1651)
		(layer "In9.Cu")
		(net "P5E_PEX3_STN7_RX_DN<125>")
	)
	(segment
		(start 392.040364 -323.231002)
		(end 391.567924 -323.08165)
		(width 0.1651)
		(layer "In9.Cu")
		(net "P5E_PEX3_STN7_RX_DN<125>")
	)
	(segment
		(start 420.537894 -334.313784)
		(end 407.844244 -328.329798)
		(width 0.1651)
		(layer "In9.Cu")
		(net "P5E_PEX3_STN7_RX_DN<125>")
	)
	(segment
		(start 430.616868 -384.08102)
		(end 430.955704 -384.08102)
		(width 0.1651)
		(layer "In9.Cu")
		(net "P5E_PEX3_STN7_RX_DN<125>")
	)
	(segment
		(start 388.861046 -318.320166)
		(end 388.949946 -318.409066)
		(width 0.1143)
		(layer "In9.Cu")
		(net "P5E_PEX3_STN7_RX_DN<125>")
	)
	(segment
		(start 298.179236 -115.283742)
		(end 298.881546 -114.581432)
		(width 0.13208)
		(layer "F.Cu")
		(net "RST_SMB_NIC5_MUX_ISO_R_N")
	)
	(segment
		(start 299.4279 -114.035078)
		(end 300.857412 -114.035078)
		(width 0.13208)
		(layer "F.Cu")
		(net "RST_SMB_NIC5_MUX_ISO_R_N")
	)
	(segment
		(start 296.277792 -115.283742)
		(end 298.179236 -115.283742)
		(width 0.13208)
		(layer "F.Cu")
		(net "RST_SMB_NIC5_MUX_ISO_R_N")
	)
	(segment
		(start 298.881546 -114.581432)
		(end 299.4279 -114.035078)
		(width 0.13208)
		(layer "F.Cu")
		(net "RST_SMB_NIC5_MUX_ISO_R_N")
	)
	(via
		(at 298.881546 -114.581432)
		(size 0.508)
		(drill 0.254)
		(layers "F.Cu" "B.Cu")
		(net "RST_SMB_NIC5_MUX_ISO_R_N")
	)
	(via
		(at 21.151088 -40.091868)
		(size 0.6604)
		(drill 0.3302)
		(layers "F.Cu" "B.Cu")
		(net "P12V_SSD0")
	)
	(via
		(at 16.96212 -43.041316)
		(size 0.6604)
		(drill 0.3302)
		(layers "F.Cu" "B.Cu")
		(net "P12V_SSD0")
	)
	(via
		(at 15.05712 -43.041316)
		(size 0.6604)
		(drill 0.3302)
		(layers "F.Cu" "B.Cu")
		(net "P12V_SSD0")
	)
	(via
		(at 18.688812 -43.305222)
		(size 0.508)
		(drill 0.254)
		(layers "F.Cu" "B.Cu")
		(net "P12V_SSD0")
	)
	(via
		(at 16.885412 -41.241472)
		(size 0.508)
		(drill 0.254)
		(layers "F.Cu" "B.Cu")
		(net "P12V_SSD0")
	)
	(via
		(at 18.688812 -42.670222)
		(size 0.508)
		(drill 0.254)
		(layers "F.Cu" "B.Cu")
		(net "P12V_SSD0")
	)
	(via
		(at 16.225012 -41.241472)
		(size 0.508)
		(drill 0.254)
		(layers "F.Cu" "B.Cu")
		(net "P12V_SSD0")
	)
	(via
		(at 8.2169 -15.128748)
		(size 0.508)
		(drill 0.254)
		(layers "F.Cu" "B.Cu")
		(net "P12V_SSD0")
	)
	(via
		(at 18.688812 -42.009822)
		(size 0.508)
		(drill 0.254)
		(layers "F.Cu" "B.Cu")
		(net "P12V_SSD0")
	)
	(via
		(at 17.946624 -29.91485)
		(size 0.6604)
		(drill 0.3302)
		(layers "F.Cu" "B.Cu")
		(net "P12V_SSD0")
	)
	(via
		(at 8.2169 -17.160748)
		(size 0.508)
		(drill 0.254)
		(layers "F.Cu" "B.Cu")
		(net "P12V_SSD0")
	)
	(via
		(at 16.45539 -20.318222)
		(size 0.508)
		(drill 0.254)
		(layers "F.Cu" "B.Cu")
		(net "P12V_SSD0")
	)
	(via
		(at 8.2169 -16.144748)
		(size 0.508)
		(drill 0.254)
		(layers "F.Cu" "B.Cu")
		(net "P12V_SSD0")
	)
	(via
		(at 18.688812 -41.349422)
		(size 0.508)
		(drill 0.254)
		(layers "F.Cu" "B.Cu")
		(net "P12V_SSD0")
	)
	(via
		(at 17.680178 -34.381694)
		(size 0.6604)
		(drill 0.3302)
		(layers "F.Cu" "B.Cu")
		(net "P12V_SSD0")
	)
	(via
		(at 16.45539 -18.997422)
		(size 0.508)
		(drill 0.254)
		(layers "F.Cu" "B.Cu")
		(net "P12V_SSD0")
	)
	(via
		(at 16.45539 -19.657822)
		(size 0.508)
		(drill 0.254)
		(layers "F.Cu" "B.Cu")
		(net "P12V_SSD0")
	)
	(via
		(at 16.45539 -21.639022)
		(size 0.508)
		(drill 0.254)
		(layers "F.Cu" "B.Cu")
		(net "P12V_SSD0")
	)
	(via
		(at 7.224268 -14.05636)
		(size 0.508)
		(drill 0.254)
		(layers "F.Cu" "B.Cu")
		(net "P12V_SSD0")
	)
	(via
		(at 16.45539 -20.978622)
		(size 0.508)
		(drill 0.254)
		(layers "F.Cu" "B.Cu")
		(net "P12V_SSD0")
	)
	(segment
		(start 73.745852 -152.355042)
		(end 73.908666 -152.192228)
		(width 0.13462)
		(layer "F.Cu")
		(net "P5E_PEX0_STN0_TX_C_DP<13>")
	)
	(segment
		(start 73.257664 -152.355042)
		(end 73.745852 -152.355042)
		(width 0.13462)
		(layer "F.Cu")
		(net "P5E_PEX0_STN0_TX_C_DP<13>")
	)
	(segment
		(start 82.075782 -152.192228)
		(end 82.394806 -152.511252)
		(width 0.13462)
		(layer "F.Cu")
		(net "P5E_PEX0_STN0_TX_C_DP<13>")
	)
	(segment
		(start 73.908666 -152.192228)
		(end 82.075782 -152.192228)
		(width 0.13462)
		(layer "F.Cu")
		(net "P5E_PEX0_STN0_TX_C_DP<13>")
	)
	(segment
		(start 283.323284 -101.84511)
		(end 282.842462 -101.84511)
		(width 0.13462)
		(layer "F.Cu")
		(net "P5E_PEX2_STN1_RX_DN<17>")
	)
	(segment
		(start 284.442662 -101.976428)
		(end 284.142434 -101.6762)
		(width 0.13462)
		(layer "F.Cu")
		(net "P5E_PEX2_STN1_RX_DN<17>")
	)
	(segment
		(start 283.492194 -101.6762)
		(end 283.323284 -101.84511)
		(width 0.13462)
		(layer "F.Cu")
		(net "P5E_PEX2_STN1_RX_DN<17>")
	)
	(segment
		(start 284.142434 -101.6762)
		(end 283.492194 -101.6762)
		(width 0.13462)
		(layer "F.Cu")
		(net "P5E_PEX2_STN1_RX_DN<17>")
	)
	(segment
		(start 292.42004 -271.644872)
		(end 292.42004 -275.276056)
		(width 0.1143)
		(layer "In5.Cu")
		(net "P5E_PEX2_STN1_RX_DN<17>")
	)
	(segment
		(start 280.113232 -103.899716)
		(end 279.682702 -104.145334)
		(width 0.1651)
		(layer "In5.Cu")
		(net "P5E_PEX2_STN1_RX_DN<17>")
	)
	(segment
		(start 277.863808 -105.051606)
		(end 277.09749 -105.488994)
		(width 0.1651)
		(layer "In5.Cu")
		(net "P5E_PEX2_STN1_RX_DN<17>")
	)
	(segment
		(start 282.859734 -102.332536)
		(end 282.703778 -102.289864)
		(width 0.1651)
		(layer "In5.Cu")
		(net "P5E_PEX2_STN1_RX_DN<17>")
	)
	(segment
		(start 292.46576 -269.900654)
		(end 292.46576 -271.570704)
		(width 0.1651)
		(layer "In5.Cu")
		(net "P5E_PEX2_STN1_RX_DN<17>")
	)
	(segment
		(start 278.019764 -105.094278)
		(end 277.863808 -105.051606)
		(width 0.1651)
		(layer "In5.Cu")
		(net "P5E_PEX2_STN1_RX_DN<17>")
	)
	(segment
		(start 262.941054 -126.612142)
		(end 261.517892 -150.180294)
		(width 0.1651)
		(layer "In5.Cu")
		(net "P5E_PEX2_STN1_RX_DN<17>")
	)
	(segment
		(start 275.257006 -107.408472)
		(end 275.260308 -107.570016)
		(width 0.1651)
		(layer "In5.Cu")
		(net "P5E_PEX2_STN1_RX_DN<17>")
	)
	(segment
		(start 292.799516 -275.265134)
		(end 292.799516 -274.999704)
		(width 0.1143)
		(layer "In5.Cu")
		(net "P5E_PEX2_STN1_RX_DN<17>")
	)
	(segment
		(start 292.523418 -275.379434)
		(end 292.685216 -275.379434)
		(width 0.1143)
		(layer "In5.Cu")
		(net "P5E_PEX2_STN1_RX_DN<17>")
	)
	(segment
		(start 274.917408 -107.927902)
		(end 274.755864 -107.931204)
		(width 0.1651)
		(layer "In5.Cu")
		(net "P5E_PEX2_STN1_RX_DN<17>")
	)
	(segment
		(start 282.703778 -102.289864)
		(end 282.273756 -102.535228)
		(width 0.1651)
		(layer "In5.Cu")
		(net "P5E_PEX2_STN1_RX_DN<17>")
	)
	(segment
		(start 261.517892 -150.180294)
		(end 262.085582 -158.838138)
		(width 0.1651)
		(layer "In5.Cu")
		(net "P5E_PEX2_STN1_RX_DN<17>")
	)
	(segment
		(start 262.085582 -158.838138)
		(end 263.275064 -165.351968)
		(width 0.1651)
		(layer "In5.Cu")
		(net "P5E_PEX2_STN1_RX_DN<17>")
	)
	(segment
		(start 278.492712 -104.692704)
		(end 278.45004 -104.84866)
		(width 0.1651)
		(layer "In5.Cu")
		(net "P5E_PEX2_STN1_RX_DN<17>")
	)
	(segment
		(start 265.766804 -117.307614)
		(end 264.431526 -119.95023)
		(width 0.1651)
		(layer "In5.Cu")
		(net "P5E_PEX2_STN1_RX_DN<17>")
	)
	(segment
		(start 279.526746 -104.102662)
		(end 278.492712 -104.692704)
		(width 0.1651)
		(layer "In5.Cu")
		(net "P5E_PEX2_STN1_RX_DN<17>")
	)
	(segment
		(start 292.42004 -275.276056)
		(end 292.523418 -275.379434)
		(width 0.1143)
		(layer "In5.Cu")
		(net "P5E_PEX2_STN1_RX_DN<17>")
	)
	(segment
		(start 274.07362 -108.808012)
		(end 273.912076 -108.811314)
		(width 0.1651)
		(layer "In5.Cu")
		(net "P5E_PEX2_STN1_RX_DN<17>")
	)
	(segment
		(start 282.273756 -102.535228)
		(end 282.231084 -102.691184)
		(width 0.1651)
		(layer "In5.Cu")
		(net "P5E_PEX2_STN1_RX_DN<17>")
	)
	(segment
		(start 263.275064 -165.351968)
		(end 292.46576 -269.900654)
		(width 0.1651)
		(layer "In5.Cu")
		(net "P5E_PEX2_STN1_RX_DN<17>")
	)
	(segment
		(start 276.101048 -106.528362)
		(end 276.10435 -106.689906)
		(width 0.1651)
		(layer "In5.Cu")
		(net "P5E_PEX2_STN1_RX_DN<17>")
	)
	(segment
		(start 274.41652 -108.450126)
		(end 274.07362 -108.808012)
		(width 0.1651)
		(layer "In5.Cu")
		(net "P5E_PEX2_STN1_RX_DN<17>")
	)
	(segment
		(start 277.09749 -105.488994)
		(end 276.101048 -106.528362)
		(width 0.1651)
		(layer "In5.Cu")
		(net "P5E_PEX2_STN1_RX_DN<17>")
	)
	(segment
		(start 274.413218 -108.288582)
		(end 274.41652 -108.450126)
		(width 0.1651)
		(layer "In5.Cu")
		(net "P5E_PEX2_STN1_RX_DN<17>")
	)
	(segment
		(start 275.599652 -107.051094)
		(end 275.257006 -107.408472)
		(width 0.1651)
		(layer "In5.Cu")
		(net "P5E_PEX2_STN1_RX_DN<17>")
	)
	(segment
		(start 283.290264 -102.086918)
		(end 282.859734 -102.332536)
		(width 0.1651)
		(layer "In5.Cu")
		(net "P5E_PEX2_STN1_RX_DN<17>")
	)
	(segment
		(start 283.332936 -101.930962)
		(end 283.290264 -102.086918)
		(width 0.1651)
		(layer "In5.Cu")
		(net "P5E_PEX2_STN1_RX_DN<17>")
	)
	(segment
		(start 280.585926 -103.498396)
		(end 280.155904 -103.74376)
		(width 0.1651)
		(layer "In5.Cu")
		(net "P5E_PEX2_STN1_RX_DN<17>")
	)
	(segment
		(start 278.45004 -104.84866)
		(end 278.019764 -105.094278)
		(width 0.1651)
		(layer "In5.Cu")
		(net "P5E_PEX2_STN1_RX_DN<17>")
	)
	(segment
		(start 279.682702 -104.145334)
		(end 279.526746 -104.102662)
		(width 0.1651)
		(layer "In5.Cu")
		(net "P5E_PEX2_STN1_RX_DN<17>")
	)
	(segment
		(start 292.46576 -271.570704)
		(end 292.46576 -271.599152)
		(width 0.1143)
		(layer "In5.Cu")
		(net "P5E_PEX2_STN1_RX_DN<17>")
	)
	(segment
		(start 280.741628 -103.541068)
		(end 280.585926 -103.498396)
		(width 0.1651)
		(layer "In5.Cu")
		(net "P5E_PEX2_STN1_RX_DN<17>")
	)
	(segment
		(start 281.644852 -102.89413)
		(end 281.21483 -103.139494)
		(width 0.1651)
		(layer "In5.Cu")
		(net "P5E_PEX2_STN1_RX_DN<17>")
	)
	(segment
		(start 281.21483 -103.139494)
		(end 281.172158 -103.29545)
		(width 0.1651)
		(layer "In5.Cu")
		(net "P5E_PEX2_STN1_RX_DN<17>")
	)
	(segment
		(start 282.231084 -102.691184)
		(end 281.800554 -102.936802)
		(width 0.1651)
		(layer "In5.Cu")
		(net "P5E_PEX2_STN1_RX_DN<17>")
	)
	(segment
		(start 281.172158 -103.29545)
		(end 280.741628 -103.541068)
		(width 0.1651)
		(layer "In5.Cu")
		(net "P5E_PEX2_STN1_RX_DN<17>")
	)
	(segment
		(start 280.155904 -103.74376)
		(end 280.113232 -103.899716)
		(width 0.1651)
		(layer "In5.Cu")
		(net "P5E_PEX2_STN1_RX_DN<17>")
	)
	(segment
		(start 275.260308 -107.570016)
		(end 274.917408 -107.927902)
		(width 0.1651)
		(layer "In5.Cu")
		(net "P5E_PEX2_STN1_RX_DN<17>")
	)
	(segment
		(start 264.431526 -119.95023)
		(end 262.941054 -126.612142)
		(width 0.1651)
		(layer "In5.Cu")
		(net "P5E_PEX2_STN1_RX_DN<17>")
	)
	(segment
		(start 275.76145 -107.047792)
		(end 275.599652 -107.051094)
		(width 0.1651)
		(layer "In5.Cu")
		(net "P5E_PEX2_STN1_RX_DN<17>")
	)
	(segment
		(start 274.755864 -107.931204)
		(end 274.413218 -108.288582)
		(width 0.1651)
		(layer "In5.Cu")
		(net "P5E_PEX2_STN1_RX_DN<17>")
	)
	(segment
		(start 273.912076 -108.811314)
		(end 265.766804 -117.307614)
		(width 0.1651)
		(layer "In5.Cu")
		(net "P5E_PEX2_STN1_RX_DN<17>")
	)
	(segment
		(start 281.800554 -102.936802)
		(end 281.644852 -102.89413)
		(width 0.1651)
		(layer "In5.Cu")
		(net "P5E_PEX2_STN1_RX_DN<17>")
	)
	(segment
		(start 292.685216 -275.379434)
		(end 292.799516 -275.265134)
		(width 0.1143)
		(layer "In5.Cu")
		(net "P5E_PEX2_STN1_RX_DN<17>")
	)
	(segment
		(start 283.762958 -101.685598)
		(end 283.332936 -101.930962)
		(width 0.1651)
		(layer "In5.Cu")
		(net "P5E_PEX2_STN1_RX_DN<17>")
	)
	(segment
		(start 284.151832 -101.685598)
		(end 283.762958 -101.685598)
		(width 0.1651)
		(layer "In5.Cu")
		(net "P5E_PEX2_STN1_RX_DN<17>")
	)
	(segment
		(start 284.442662 -101.976428)
		(end 284.151832 -101.685598)
		(width 0.1651)
		(layer "In5.Cu")
		(net "P5E_PEX2_STN1_RX_DN<17>")
	)
	(segment
		(start 276.10435 -106.689906)
		(end 275.76145 -107.047792)
		(width 0.1651)
		(layer "In5.Cu")
		(net "P5E_PEX2_STN1_RX_DN<17>")
	)
	(segment
		(start 292.46576 -271.599152)
		(end 292.42004 -271.644872)
		(width 0.1143)
		(layer "In5.Cu")
		(net "P5E_PEX2_STN1_RX_DN<17>")
	)
	(segment
		(start 368.467894 -33.631886)
		(end 368.13998 -33.9598)
		(width 0.13462)
		(layer "F.Cu")
		(net "P5E_PEX3_STN2_TX_C_DN<47>")
	)
	(segment
		(start 364.241588 -33.9598)
		(end 364.071916 -33.790128)
		(width 0.13462)
		(layer "F.Cu")
		(net "P5E_PEX3_STN2_TX_C_DN<47>")
	)
	(segment
		(start 368.13998 -33.9598)
		(end 364.241588 -33.9598)
		(width 0.13462)
		(layer "F.Cu")
		(net "P5E_PEX3_STN2_TX_C_DN<47>")
	)
	(segment
		(start 364.071916 -33.790128)
		(end 363.564932 -33.790128)
		(width 0.13462)
		(layer "F.Cu")
		(net "P5E_PEX3_STN2_TX_C_DN<47>")
	)
	(segment
		(start 419.19144 -351.317306)
		(end 419.485572 -351.611438)
		(width 0.13462)
		(layer "F.Cu")
		(net "P5E_PEX3_STN7_TX_C_DN<116>")
	)
	(segment
		(start 419.19144 -350.684846)
		(end 419.19144 -351.317306)
		(width 0.13462)
		(layer "F.Cu")
		(net "P5E_PEX3_STN7_TX_C_DN<116>")
	)
	(segment
		(start 419.510972 -350.365314)
		(end 419.19144 -350.684846)
		(width 0.13462)
		(layer "F.Cu")
		(net "P5E_PEX3_STN7_TX_C_DN<116>")
	)
	(segment
		(start 429.00346 -394.11148)
		(end 416.564572 -387.949186)
		(width 0.1651)
		(layer "In11.Cu")
		(net "P5E_PEX3_STN7_TX_C_DN<116>")
	)
	(segment
		(start 428.96409 -401.181062)
		(end 429.415956 -400.729196)
		(width 0.1651)
		(layer "In11.Cu")
		(net "P5E_PEX3_STN7_TX_C_DN<116>")
	)
	(segment
		(start 415.441892 -368.962432)
		(end 417.640262 -358.88168)
		(width 0.1651)
		(layer "In11.Cu")
		(net "P5E_PEX3_STN7_TX_C_DN<116>")
	)
	(segment
		(start 428.416974 -401.181062)
		(end 428.96409 -401.181062)
		(width 0.1651)
		(layer "In11.Cu")
		(net "P5E_PEX3_STN7_TX_C_DN<116>")
	)
	(segment
		(start 417.640262 -358.88168)
		(end 417.640262 -354.027486)
		(width 0.1651)
		(layer "In11.Cu")
		(net "P5E_PEX3_STN7_TX_C_DN<116>")
	)
	(segment
		(start 428.289974 -401.308062)
		(end 428.416974 -401.181062)
		(width 0.1651)
		(layer "In11.Cu")
		(net "P5E_PEX3_STN7_TX_C_DN<116>")
	)
	(segment
		(start 419.194742 -352.473006)
		(end 419.194742 -351.902268)
		(width 0.1651)
		(layer "In11.Cu")
		(net "P5E_PEX3_STN7_TX_C_DN<116>")
	)
	(segment
		(start 429.415956 -394.523976)
		(end 429.00346 -394.11148)
		(width 0.1651)
		(layer "In11.Cu")
		(net "P5E_PEX3_STN7_TX_C_DN<116>")
	)
	(segment
		(start 415.3662 -385.4704)
		(end 415.1376 -383.3368)
		(width 0.1651)
		(layer "In11.Cu")
		(net "P5E_PEX3_STN7_TX_C_DN<116>")
	)
	(segment
		(start 415.1376 -383.3368)
		(end 415.441892 -368.962432)
		(width 0.1651)
		(layer "In11.Cu")
		(net "P5E_PEX3_STN7_TX_C_DN<116>")
	)
	(segment
		(start 416.564572 -387.949186)
		(end 415.3662 -385.4704)
		(width 0.1651)
		(layer "In11.Cu")
		(net "P5E_PEX3_STN7_TX_C_DN<116>")
	)
	(segment
		(start 429.415956 -400.729196)
		(end 429.415956 -394.523976)
		(width 0.1651)
		(layer "In11.Cu")
		(net "P5E_PEX3_STN7_TX_C_DN<116>")
	)
	(segment
		(start 428.289974 -401.690078)
		(end 428.289974 -401.308062)
		(width 0.1651)
		(layer "In11.Cu")
		(net "P5E_PEX3_STN7_TX_C_DN<116>")
	)
	(segment
		(start 419.194742 -351.902268)
		(end 419.485572 -351.611438)
		(width 0.1651)
		(layer "In11.Cu")
		(net "P5E_PEX3_STN7_TX_C_DN<116>")
	)
	(segment
		(start 417.640262 -354.027486)
		(end 419.194742 -352.473006)
		(width 0.1651)
		(layer "In11.Cu")
		(net "P5E_PEX3_STN7_TX_C_DN<116>")
	)
	(segment
		(start 168.947338 -156.282136)
		(end 169.20972 -156.544518)
		(width 0.13208)
		(layer "F.Cu")
		(net "NIC2_RBT_ARB_OUT")
	)
	(segment
		(start 166.742364 -155.960064)
		(end 167.508174 -155.960064)
		(width 0.13208)
		(layer "F.Cu")
		(net "NIC2_RBT_ARB_OUT")
	)
	(segment
		(start 167.508174 -155.960064)
		(end 167.830246 -156.282136)
		(width 0.13208)
		(layer "F.Cu")
		(net "NIC2_RBT_ARB_OUT")
	)
	(segment
		(start 167.830246 -156.282136)
		(end 168.947338 -156.282136)
		(width 0.13208)
		(layer "F.Cu")
		(net "NIC2_RBT_ARB_OUT")
	)
	(via
		(at 169.20972 -156.544518)
		(size 0.508)
		(drill 0.254)
		(layers "F.Cu" "B.Cu")
		(net "NIC2_RBT_ARB_OUT")
	)
	(segment
		(start 166.954708 -156.282136)
		(end 168.947338 -156.282136)
		(width 0.13208)
		(layer "B.Cu")
		(net "NIC2_RBT_ARB_OUT")
	)
	(segment
		(start 166.645844 -156.591)
		(end 166.954708 -156.282136)
		(width 0.13208)
		(layer "B.Cu")
		(net "NIC2_RBT_ARB_OUT")
	)
	(segment
		(start 165.255194 -157.0736)
		(end 165.255194 -156.718)
		(width 0.13208)
		(layer "B.Cu")
		(net "NIC2_RBT_ARB_OUT")
	)
	(segment
		(start 168.947338 -156.282136)
		(end 169.20972 -156.544518)
		(width 0.13208)
		(layer "B.Cu")
		(net "NIC2_RBT_ARB_OUT")
	)
	(segment
		(start 165.255194 -156.718)
		(end 165.382194 -156.591)
		(width 0.13208)
		(layer "B.Cu")
		(net "NIC2_RBT_ARB_OUT")
	)
	(segment
		(start 165.382194 -156.591)
		(end 166.645844 -156.591)
		(width 0.13208)
		(layer "B.Cu")
		(net "NIC2_RBT_ARB_OUT")
	)
	(segment
		(start 305.457606 -101.240082)
		(end 306.875942 -101.240082)
		(width 0.13208)
		(layer "F.Cu")
		(net "NCSI_NIC5_RXD1")
	)
	(via
		(at 306.875942 -101.240082)
		(size 0.508)
		(drill 0.254)
		(layers "F.Cu" "B.Cu")
		(net "NCSI_NIC5_RXD1")
	)
	(segment
		(start 307.278278 -101.240082)
		(end 306.875942 -101.240082)
		(width 0.13208)
		(layer "B.Cu")
		(net "NCSI_NIC5_RXD1")
	)
	(segment
		(start 309.341774 -102.088696)
		(end 308.126892 -102.088696)
		(width 0.13208)
		(layer "B.Cu")
		(net "NCSI_NIC5_RXD1")
	)
	(segment
		(start 308.126892 -102.088696)
		(end 307.278278 -101.240082)
		(width 0.13208)
		(layer "B.Cu")
		(net "NCSI_NIC5_RXD1")
	)
	(segment
		(start 73.745852 -132.444998)
		(end 73.908666 -132.282184)
		(width 0.13462)
		(layer "F.Cu")
		(net "P5E_PEX0_STN0_TX_C_DP<5>")
	)
	(segment
		(start 82.075782 -132.282184)
		(end 82.394806 -132.601208)
		(width 0.13462)
		(layer "F.Cu")
		(net "P5E_PEX0_STN0_TX_C_DP<5>")
	)
	(segment
		(start 73.908666 -132.282184)
		(end 82.075782 -132.282184)
		(width 0.13462)
		(layer "F.Cu")
		(net "P5E_PEX0_STN0_TX_C_DP<5>")
	)
	(segment
		(start 73.257664 -132.444998)
		(end 73.745852 -132.444998)
		(width 0.13462)
		(layer "F.Cu")
		(net "P5E_PEX0_STN0_TX_C_DP<5>")
	)
	(segment
		(start 277.735538 -100.045012)
		(end 278.242268 -100.045012)
		(width 0.13462)
		(layer "F.Cu")
		(net "P5E_PEX2_STN1_TX_C_DN<16>")
	)
	(segment
		(start 277.563326 -99.8728)
		(end 277.735538 -100.045012)
		(width 0.13462)
		(layer "F.Cu")
		(net "P5E_PEX2_STN1_TX_C_DN<16>")
	)
	(segment
		(start 272.077688 -99.8728)
		(end 277.563326 -99.8728)
		(width 0.13462)
		(layer "F.Cu")
		(net "P5E_PEX2_STN1_TX_C_DN<16>")
	)
	(segment
		(start 271.747234 -100.203254)
		(end 272.077688 -99.8728)
		(width 0.13462)
		(layer "F.Cu")
		(net "P5E_PEX2_STN1_TX_C_DN<16>")
	)
	(segment
		(start 410.964888 -30.790134)
		(end 410.482288 -30.790134)
		(width 0.13462)
		(layer "F.Cu")
		(net "P5E_PEX3_STN2_RX_DP<37>")
	)
	(segment
		(start 410.324554 -30.6324)
		(end 407.800556 -30.6324)
		(width 0.13462)
		(layer "F.Cu")
		(net "P5E_PEX3_STN2_RX_DP<37>")
	)
	(segment
		(start 410.482288 -30.790134)
		(end 410.324554 -30.6324)
		(width 0.13462)
		(layer "F.Cu")
		(net "P5E_PEX3_STN2_RX_DP<37>")
	)
	(segment
		(start 407.800556 -30.6324)
		(end 407.510488 -30.922468)
		(width 0.13462)
		(layer "F.Cu")
		(net "P5E_PEX3_STN2_RX_DP<37>")
	)
	(segment
		(start 410.935678 -31.738824)
		(end 410.585158 -31.388304)
		(width 0.1651)
		(layer "In7.Cu")
		(net "P5E_PEX3_STN2_RX_DP<37>")
	)
	(segment
		(start 402.249894 -273.784314)
		(end 402.135594 -273.670014)
		(width 0.1143)
		(layer "In7.Cu")
		(net "P5E_PEX3_STN2_RX_DP<37>")
	)
	(segment
		(start 410.585158 -31.24454)
		(end 409.972256 -30.631638)
		(width 0.1651)
		(layer "In7.Cu")
		(net "P5E_PEX3_STN2_RX_DP<37>")
	)
	(segment
		(start 401.679664 -273.407632)
		(end 401.679664 -271.41932)
		(width 0.1143)
		(layer "In7.Cu")
		(net "P5E_PEX3_STN2_RX_DP<37>")
	)
	(segment
		(start 401.633944 -271.3736)
		(end 401.633944 -271.345152)
		(width 0.1143)
		(layer "In7.Cu")
		(net "P5E_PEX3_STN2_RX_DP<37>")
	)
	(segment
		(start 409.375356 -30.733238)
		(end 408.880056 -30.733238)
		(width 0.1651)
		(layer "In7.Cu")
		(net "P5E_PEX3_STN2_RX_DP<37>")
	)
	(segment
		(start 410.585158 -31.388304)
		(end 410.585158 -31.24454)
		(width 0.1651)
		(layer "In7.Cu")
		(net "P5E_PEX3_STN2_RX_DP<37>")
	)
	(segment
		(start 410.880814 -37.940234)
		(end 411.406086 -34.981642)
		(width 0.1651)
		(layer "In7.Cu")
		(net "P5E_PEX3_STN2_RX_DP<37>")
	)
	(segment
		(start 401.765008 -264.886186)
		(end 412.138622 -68.490084)
		(width 0.1651)
		(layer "In7.Cu")
		(net "P5E_PEX3_STN2_RX_DP<37>")
	)
	(segment
		(start 411.079442 -31.738824)
		(end 410.935678 -31.738824)
		(width 0.1651)
		(layer "In7.Cu")
		(net "P5E_PEX3_STN2_RX_DP<37>")
	)
	(segment
		(start 410.95295 -39.991792)
		(end 410.902658 -39.321486)
		(width 0.1651)
		(layer "In7.Cu")
		(net "P5E_PEX3_STN2_RX_DP<37>")
	)
	(segment
		(start 409.972256 -30.631638)
		(end 409.476956 -30.631638)
		(width 0.1651)
		(layer "In7.Cu")
		(net "P5E_PEX3_STN2_RX_DP<37>")
	)
	(segment
		(start 402.135594 -273.670014)
		(end 401.942046 -273.670014)
		(width 0.1143)
		(layer "In7.Cu")
		(net "P5E_PEX3_STN2_RX_DP<37>")
	)
	(segment
		(start 401.942046 -273.670014)
		(end 401.679664 -273.407632)
		(width 0.1143)
		(layer "In7.Cu")
		(net "P5E_PEX3_STN2_RX_DP<37>")
	)
	(segment
		(start 408.880056 -30.733238)
		(end 408.778456 -30.631638)
		(width 0.1651)
		(layer "In7.Cu")
		(net "P5E_PEX3_STN2_RX_DP<37>")
	)
	(segment
		(start 407.801318 -30.631638)
		(end 407.510488 -30.922468)
		(width 0.1651)
		(layer "In7.Cu")
		(net "P5E_PEX3_STN2_RX_DP<37>")
	)
	(segment
		(start 412.322772 -50.12817)
		(end 410.95295 -39.991792)
		(width 0.1651)
		(layer "In7.Cu")
		(net "P5E_PEX3_STN2_RX_DP<37>")
	)
	(segment
		(start 402.249894 -274.049744)
		(end 402.249894 -273.784314)
		(width 0.1143)
		(layer "In7.Cu")
		(net "P5E_PEX3_STN2_RX_DP<37>")
	)
	(segment
		(start 401.679664 -271.41932)
		(end 401.633944 -271.3736)
		(width 0.1143)
		(layer "In7.Cu")
		(net "P5E_PEX3_STN2_RX_DP<37>")
	)
	(segment
		(start 411.406086 -34.981642)
		(end 411.429454 -32.088836)
		(width 0.1651)
		(layer "In7.Cu")
		(net "P5E_PEX3_STN2_RX_DP<37>")
	)
	(segment
		(start 410.902658 -39.321486)
		(end 410.880814 -37.940234)
		(width 0.1651)
		(layer "In7.Cu")
		(net "P5E_PEX3_STN2_RX_DP<37>")
	)
	(segment
		(start 401.633944 -266.379706)
		(end 401.765008 -264.886186)
		(width 0.1651)
		(layer "In7.Cu")
		(net "P5E_PEX3_STN2_RX_DP<37>")
	)
	(segment
		(start 408.778456 -30.631638)
		(end 407.801318 -30.631638)
		(width 0.1651)
		(layer "In7.Cu")
		(net "P5E_PEX3_STN2_RX_DP<37>")
	)
	(segment
		(start 412.138622 -68.490084)
		(end 412.322772 -50.12817)
		(width 0.1651)
		(layer "In7.Cu")
		(net "P5E_PEX3_STN2_RX_DP<37>")
	)
	(segment
		(start 411.429454 -32.088836)
		(end 411.079442 -31.738824)
		(width 0.1651)
		(layer "In7.Cu")
		(net "P5E_PEX3_STN2_RX_DP<37>")
	)
	(segment
		(start 409.476956 -30.631638)
		(end 409.375356 -30.733238)
		(width 0.1651)
		(layer "In7.Cu")
		(net "P5E_PEX3_STN2_RX_DP<37>")
	)
	(segment
		(start 401.633944 -271.345152)
		(end 401.633944 -266.379706)
		(width 0.1651)
		(layer "In7.Cu")
		(net "P5E_PEX3_STN2_RX_DP<37>")
	)
	(segment
		(start 420.64686 -382.289812)
		(end 420.64686 -369.593368)
		(width 0.1651)
		(layer "In9.Cu")
		(net "P5E_PEX3_STN7_RX_DN<120>")
	)
	(segment
		(start 390.19988 -328.122788)
		(end 390.056624 -328.19721)
		(width 0.1651)
		(layer "In9.Cu")
		(net "P5E_PEX3_STN7_RX_DN<120>")
	)
	(segment
		(start 383.189988 -308.865778)
		(end 383.867152 -308.865778)
		(width 0.1651)
		(layer "In9.Cu")
		(net "P5E_PEX3_STN7_RX_DN<120>")
	)
	(segment
		(start 419.48989 -383.490216)
		(end 419.48989 -383.107946)
		(width 0.1651)
		(layer "In9.Cu")
		(net "P5E_PEX3_STN7_RX_DN<120>")
	)
	(segment
		(start 382.140968 -311.89041)
		(end 382.25984 -311.780428)
		(width 0.1651)
		(layer "In9.Cu")
		(net "P5E_PEX3_STN7_RX_DN<120>")
	)
	(segment
		(start 382.27889 -311.285382)
		(end 382.168908 -311.166764)
		(width 0.1651)
		(layer "In9.Cu")
		(net "P5E_PEX3_STN7_RX_DN<120>")
	)
	(segment
		(start 391.909554 -328.783696)
		(end 391.909554 -328.78395)
		(width 0.1651)
		(layer "In9.Cu")
		(net "P5E_PEX3_STN7_RX_DN<120>")
	)
	(segment
		(start 387.338316 -309.199788)
		(end 387.050026 -309.199788)
		(width 0.1143)
		(layer "In9.Cu")
		(net "P5E_PEX3_STN7_RX_DN<120>")
	)
	(segment
		(start 383.94132 -308.820058)
		(end 387.301994 -308.820058)
		(width 0.1143)
		(layer "In9.Cu")
		(net "P5E_PEX3_STN7_RX_DN<120>")
	)
	(segment
		(start 385.636262 -325.887842)
		(end 384.123692 -323.818504)
		(width 0.1651)
		(layer "In9.Cu")
		(net "P5E_PEX3_STN7_RX_DN<120>")
	)
	(segment
		(start 382.451356 -316.496192)
		(end 382.542796 -316.362842)
		(width 0.1651)
		(layer "In9.Cu")
		(net "P5E_PEX3_STN7_RX_DN<120>")
	)
	(segment
		(start 419.955726 -382.980946)
		(end 420.64686 -382.289812)
		(width 0.1651)
		(layer "In9.Cu")
		(net "P5E_PEX3_STN7_RX_DN<120>")
	)
	(segment
		(start 408.97683 -334.187038)
		(end 391.909554 -328.783696)
		(width 0.1651)
		(layer "In9.Cu")
		(net "P5E_PEX3_STN7_RX_DN<120>")
	)
	(segment
		(start 422.973754 -340.786974)
		(end 408.97683 -334.187038)
		(width 0.1651)
		(layer "In9.Cu")
		(net "P5E_PEX3_STN7_RX_DN<120>")
	)
	(segment
		(start 383.867152 -308.865778)
		(end 383.8956 -308.865778)
		(width 0.1143)
		(layer "In9.Cu")
		(net "P5E_PEX3_STN7_RX_DN<120>")
	)
	(segment
		(start 389.037576 -327.754742)
		(end 388.894066 -327.829164)
		(width 0.1651)
		(layer "In9.Cu")
		(net "P5E_PEX3_STN7_RX_DN<120>")
	)
	(segment
		(start 420.64686 -369.593368)
		(end 423.858182 -357.884222)
		(width 0.1651)
		(layer "In9.Cu")
		(net "P5E_PEX3_STN7_RX_DN<120>")
	)
	(segment
		(start 383.402586 -321.599814)
		(end 382.451356 -316.496192)
		(width 0.1651)
		(layer "In9.Cu")
		(net "P5E_PEX3_STN7_RX_DN<120>")
	)
	(segment
		(start 382.168908 -311.166764)
		(end 382.209294 -310.114442)
		(width 0.1651)
		(layer "In9.Cu")
		(net "P5E_PEX3_STN7_RX_DN<120>")
	)
	(segment
		(start 390.746996 -328.415904)
		(end 390.67232 -328.27214)
		(width 0.1651)
		(layer "In9.Cu")
		(net "P5E_PEX3_STN7_RX_DN<120>")
	)
	(segment
		(start 382.542796 -316.362842)
		(end 382.451864 -315.87567)
		(width 0.1651)
		(layer "In9.Cu")
		(net "P5E_PEX3_STN7_RX_DN<120>")
	)
	(segment
		(start 384.123692 -323.818504)
		(end 383.402586 -321.599814)
		(width 0.1651)
		(layer "In9.Cu")
		(net "P5E_PEX3_STN7_RX_DN<120>")
	)
	(segment
		(start 382.318514 -315.78423)
		(end 382.047242 -314.329064)
		(width 0.1651)
		(layer "In9.Cu")
		(net "P5E_PEX3_STN7_RX_DN<120>")
	)
	(segment
		(start 391.219182 -328.565256)
		(end 390.746996 -328.41565)
		(width 0.1651)
		(layer "In9.Cu")
		(net "P5E_PEX3_STN7_RX_DN<120>")
	)
	(segment
		(start 419.61689 -382.980946)
		(end 419.955726 -382.980946)
		(width 0.1651)
		(layer "In9.Cu")
		(net "P5E_PEX3_STN7_RX_DN<120>")
	)
	(segment
		(start 390.746996 -328.41565)
		(end 390.746996 -328.415904)
		(width 0.1651)
		(layer "In9.Cu")
		(net "P5E_PEX3_STN7_RX_DN<120>")
	)
	(segment
		(start 382.494028 -309.561992)
		(end 383.068576 -308.98719)
		(width 0.1651)
		(layer "In9.Cu")
		(net "P5E_PEX3_STN7_RX_DN<120>")
	)
	(segment
		(start 387.434328 -308.952392)
		(end 387.434328 -309.103776)
		(width 0.1143)
		(layer "In9.Cu")
		(net "P5E_PEX3_STN7_RX_DN<120>")
	)
	(segment
		(start 383.8956 -308.865778)
		(end 383.94132 -308.820058)
		(width 0.1143)
		(layer "In9.Cu")
		(net "P5E_PEX3_STN7_RX_DN<120>")
	)
	(segment
		(start 419.48989 -383.107946)
		(end 419.61689 -382.980946)
		(width 0.1651)
		(layer "In9.Cu")
		(net "P5E_PEX3_STN7_RX_DN<120>")
	)
	(segment
		(start 389.584438 -328.047604)
		(end 389.584438 -328.047858)
		(width 0.1651)
		(layer "In9.Cu")
		(net "P5E_PEX3_STN7_RX_DN<120>")
	)
	(segment
		(start 391.834878 -328.640186)
		(end 391.362438 -328.490834)
		(width 0.1651)
		(layer "In9.Cu")
		(net "P5E_PEX3_STN7_RX_DN<120>")
	)
	(segment
		(start 389.584438 -328.047858)
		(end 389.510016 -327.904094)
		(width 0.1651)
		(layer "In9.Cu")
		(net "P5E_PEX3_STN7_RX_DN<120>")
	)
	(segment
		(start 382.047242 -314.329064)
		(end 382.140968 -311.89041)
		(width 0.1651)
		(layer "In9.Cu")
		(net "P5E_PEX3_STN7_RX_DN<120>")
	)
	(segment
		(start 423.858182 -342.065864)
		(end 422.973754 -340.786974)
		(width 0.1651)
		(layer "In9.Cu")
		(net "P5E_PEX3_STN7_RX_DN<120>")
	)
	(segment
		(start 382.451864 -315.87567)
		(end 382.318514 -315.78423)
		(width 0.1651)
		(layer "In9.Cu")
		(net "P5E_PEX3_STN7_RX_DN<120>")
	)
	(segment
		(start 389.510016 -327.904094)
		(end 389.037576 -327.754742)
		(width 0.1651)
		(layer "In9.Cu")
		(net "P5E_PEX3_STN7_RX_DN<120>")
	)
	(segment
		(start 423.858182 -357.884222)
		(end 423.858182 -342.065864)
		(width 0.1651)
		(layer "In9.Cu")
		(net "P5E_PEX3_STN7_RX_DN<120>")
	)
	(segment
		(start 390.056624 -328.19721)
		(end 389.584438 -328.047604)
		(width 0.1651)
		(layer "In9.Cu")
		(net "P5E_PEX3_STN7_RX_DN<120>")
	)
	(segment
		(start 387.301994 -308.820058)
		(end 387.434328 -308.952392)
		(width 0.1143)
		(layer "In9.Cu")
		(net "P5E_PEX3_STN7_RX_DN<120>")
	)
	(segment
		(start 388.894066 -327.829164)
		(end 387.900672 -327.514712)
		(width 0.1651)
		(layer "In9.Cu")
		(net "P5E_PEX3_STN7_RX_DN<120>")
	)
	(segment
		(start 382.25984 -311.780428)
		(end 382.27889 -311.285382)
		(width 0.1651)
		(layer "In9.Cu")
		(net "P5E_PEX3_STN7_RX_DN<120>")
	)
	(segment
		(start 383.068576 -308.98719)
		(end 383.189988 -308.865778)
		(width 0.1651)
		(layer "In9.Cu")
		(net "P5E_PEX3_STN7_RX_DN<120>")
	)
	(segment
		(start 387.900672 -327.514712)
		(end 385.636262 -325.887842)
		(width 0.1651)
		(layer "In9.Cu")
		(net "P5E_PEX3_STN7_RX_DN<120>")
	)
	(segment
		(start 382.209294 -310.114442)
		(end 382.494028 -309.561992)
		(width 0.1651)
		(layer "In9.Cu")
		(net "P5E_PEX3_STN7_RX_DN<120>")
	)
	(segment
		(start 391.362438 -328.490834)
		(end 391.219182 -328.565256)
		(width 0.1651)
		(layer "In9.Cu")
		(net "P5E_PEX3_STN7_RX_DN<120>")
	)
	(segment
		(start 390.67232 -328.27214)
		(end 390.19988 -328.122788)
		(width 0.1651)
		(layer "In9.Cu")
		(net "P5E_PEX3_STN7_RX_DN<120>")
	)
	(segment
		(start 387.434328 -309.103776)
		(end 387.338316 -309.199788)
		(width 0.1143)
		(layer "In9.Cu")
		(net "P5E_PEX3_STN7_RX_DN<120>")
	)
	(segment
		(start 391.909554 -328.78395)
		(end 391.834878 -328.640186)
		(width 0.1651)
		(layer "In9.Cu")
		(net "P5E_PEX3_STN7_RX_DN<120>")
	)
	(segment
		(start 162.14217 -150.560024)
		(end 159.034226 -150.560024)
		(width 0.13208)
		(layer "F.Cu")
		(net "NCSI_NIC2_CRS_DV")
	)
	(segment
		(start 159.034226 -150.560024)
		(end 158.686754 -150.212552)
		(width 0.13208)
		(layer "F.Cu")
		(net "NCSI_NIC2_CRS_DV")
	)
	(segment
		(start 158.686754 -150.212552)
		(end 156.490924 -150.212552)
		(width 0.13208)
		(layer "F.Cu")
		(net "NCSI_NIC2_CRS_DV")
	)
	(segment
		(start 156.440124 -150.263352)
		(end 155.099766 -150.263352)
		(width 0.13208)
		(layer "F.Cu")
		(net "NCSI_NIC2_CRS_DV")
	)
	(segment
		(start 156.490924 -150.212552)
		(end 156.440124 -150.263352)
		(width 0.13208)
		(layer "F.Cu")
		(net "NCSI_NIC2_CRS_DV")
	)
	(via
		(at 156.490924 -150.212552)
		(size 0.762)
		(drill 0.381)
		(layers "F.Cu" "B.Cu")
		(net "NCSI_NIC2_CRS_DV")
	)
	(segment
		(start 73.257664 -151.755094)
		(end 73.745852 -151.755094)
		(width 0.13462)
		(layer "F.Cu")
		(net "P5E_PEX0_STN0_TX_C_DN<13>")
	)
	(segment
		(start 73.908666 -151.917908)
		(end 82.07375 -151.917908)
		(width 0.13462)
		(layer "F.Cu")
		(net "P5E_PEX0_STN0_TX_C_DN<13>")
	)
	(segment
		(start 73.745852 -151.755094)
		(end 73.908666 -151.917908)
		(width 0.13462)
		(layer "F.Cu")
		(net "P5E_PEX0_STN0_TX_C_DN<13>")
	)
	(segment
		(start 82.07375 -151.917908)
		(end 82.394806 -151.596852)
		(width 0.13462)
		(layer "F.Cu")
		(net "P5E_PEX0_STN0_TX_C_DN<13>")
	)
	(segment
		(start 277.583138 -119.511572)
		(end 277.739602 -119.355108)
		(width 0.13462)
		(layer "F.Cu")
		(net "P5E_PEX2_STN1_TX_C_DP<24>")
	)
	(segment
		(start 269.105126 -119.198898)
		(end 269.4178 -119.511572)
		(width 0.13462)
		(layer "F.Cu")
		(net "P5E_PEX2_STN1_TX_C_DP<24>")
	)
	(segment
		(start 277.739602 -119.355108)
		(end 278.242268 -119.355108)
		(width 0.13462)
		(layer "F.Cu")
		(net "P5E_PEX2_STN1_TX_C_DP<24>")
	)
	(segment
		(start 269.4178 -119.511572)
		(end 277.583138 -119.511572)
		(width 0.13462)
		(layer "F.Cu")
		(net "P5E_PEX2_STN1_TX_C_DP<24>")
	)
	(segment
		(start 299.198538 -393.178538)
		(end 299.040042 -393.210034)
		(width 0.1651)
		(layer "In5.Cu")
		(net "P5E_PEX2_STN7_RX_DP<118>")
	)
	(segment
		(start 271.520158 -307.185568)
		(end 271.634458 -307.299868)
		(width 0.1143)
		(layer "In5.Cu")
		(net "P5E_PEX2_STN7_RX_DP<118>")
	)
	(segment
		(start 301.533814 -394.92936)
		(end 301.060358 -394.424408)
		(width 0.1651)
		(layer "In5.Cu")
		(net "P5E_PEX2_STN7_RX_DP<118>")
	)
	(segment
		(start 267.7922 -306.683918)
		(end 267.820648 -306.683918)
		(width 0.1143)
		(layer "In5.Cu")
		(net "P5E_PEX2_STN7_RX_DP<118>")
	)
	(segment
		(start 285.611824 -385.657598)
		(end 285.214822 -384.689858)
		(width 0.1651)
		(layer "In5.Cu")
		(net "P5E_PEX2_STN7_RX_DP<118>")
	)
	(segment
		(start 299.040042 -393.210034)
		(end 298.628054 -392.93419)
		(width 0.1651)
		(layer "In5.Cu")
		(net "P5E_PEX2_STN7_RX_DP<118>")
	)
	(segment
		(start 299.641514 -393.61237)
		(end 299.610018 -393.453874)
		(width 0.1651)
		(layer "In5.Cu")
		(net "P5E_PEX2_STN7_RX_DP<118>")
	)
	(segment
		(start 275.466048 -341.313516)
		(end 256.837688 -324.915784)
		(width 0.1651)
		(layer "In5.Cu")
		(net "P5E_PEX2_STN7_RX_DP<118>")
	)
	(segment
		(start 275.467572 -341.315802)
		(end 275.466048 -341.313516)
		(width 0.1651)
		(layer "In5.Cu")
		(net "P5E_PEX2_STN7_RX_DP<118>")
	)
	(segment
		(start 298.596812 -392.775694)
		(end 297.953176 -392.34491)
		(width 0.1651)
		(layer "In5.Cu")
		(net "P5E_PEX2_STN7_RX_DP<118>")
	)
	(segment
		(start 271.294352 -306.729638)
		(end 271.520158 -306.955444)
		(width 0.1143)
		(layer "In5.Cu")
		(net "P5E_PEX2_STN7_RX_DP<118>")
	)
	(segment
		(start 301.533814 -408.412442)
		(end 301.533814 -394.92936)
		(width 0.1651)
		(layer "In5.Cu")
		(net "P5E_PEX2_STN7_RX_DP<118>")
	)
	(segment
		(start 301.247048 -408.699208)
		(end 301.533814 -408.412442)
		(width 0.1651)
		(layer "In5.Cu")
		(net "P5E_PEX2_STN7_RX_DP<118>")
	)
	(segment
		(start 286.931354 -386.948426)
		(end 285.611824 -385.657598)
		(width 0.1651)
		(layer "In5.Cu")
		(net "P5E_PEX2_STN7_RX_DP<118>")
	)
	(segment
		(start 275.960332 -342.138)
		(end 275.467572 -341.315802)
		(width 0.1651)
		(layer "In5.Cu")
		(net "P5E_PEX2_STN7_RX_DP<118>")
	)
	(segment
		(start 299.610018 -393.453874)
		(end 299.198538 -393.178538)
		(width 0.1651)
		(layer "In5.Cu")
		(net "P5E_PEX2_STN7_RX_DP<118>")
	)
	(segment
		(start 256.788666 -316.855348)
		(end 265.030204 -307.403754)
		(width 0.1651)
		(layer "In5.Cu")
		(net "P5E_PEX2_STN7_RX_DP<118>")
	)
	(segment
		(start 300.211998 -393.856718)
		(end 300.053248 -393.88796)
		(width 0.1651)
		(layer "In5.Cu")
		(net "P5E_PEX2_STN7_RX_DP<118>")
	)
	(segment
		(start 266.613132 -306.683918)
		(end 267.7922 -306.683918)
		(width 0.1651)
		(layer "In5.Cu")
		(net "P5E_PEX2_STN7_RX_DP<118>")
	)
	(segment
		(start 265.030204 -307.403754)
		(end 266.613132 -306.683918)
		(width 0.1651)
		(layer "In5.Cu")
		(net "P5E_PEX2_STN7_RX_DP<118>")
	)
	(segment
		(start 271.634458 -307.299868)
		(end 271.899888 -307.299868)
		(width 0.1143)
		(layer "In5.Cu")
		(net "P5E_PEX2_STN7_RX_DP<118>")
	)
	(segment
		(start 283.379926 -369.531392)
		(end 276.135338 -358.575102)
		(width 0.1651)
		(layer "In5.Cu")
		(net "P5E_PEX2_STN7_RX_DP<118>")
	)
	(segment
		(start 255.41224 -322.019422)
		(end 255.41224 -320.27114)
		(width 0.1651)
		(layer "In5.Cu")
		(net "P5E_PEX2_STN7_RX_DP<118>")
	)
	(segment
		(start 300.053248 -393.88796)
		(end 299.641514 -393.61237)
		(width 0.1651)
		(layer "In5.Cu")
		(net "P5E_PEX2_STN7_RX_DP<118>")
	)
	(segment
		(start 284.93212 -378.698506)
		(end 284.276546 -371.48643)
		(width 0.1651)
		(layer "In5.Cu")
		(net "P5E_PEX2_STN7_RX_DP<118>")
	)
	(segment
		(start 267.866368 -306.729638)
		(end 271.294352 -306.729638)
		(width 0.1143)
		(layer "In5.Cu")
		(net "P5E_PEX2_STN7_RX_DP<118>")
	)
	(segment
		(start 300.816772 -408.699208)
		(end 301.247048 -408.699208)
		(width 0.1651)
		(layer "In5.Cu")
		(net "P5E_PEX2_STN7_RX_DP<118>")
	)
	(segment
		(start 267.820648 -306.683918)
		(end 267.866368 -306.729638)
		(width 0.1143)
		(layer "In5.Cu")
		(net "P5E_PEX2_STN7_RX_DP<118>")
	)
	(segment
		(start 256.300478 -324.164452)
		(end 255.41224 -322.019422)
		(width 0.1651)
		(layer "In5.Cu")
		(net "P5E_PEX2_STN7_RX_DP<118>")
	)
	(segment
		(start 276.135338 -358.575102)
		(end 275.960332 -357.993696)
		(width 0.1651)
		(layer "In5.Cu")
		(net "P5E_PEX2_STN7_RX_DP<118>")
	)
	(segment
		(start 255.41224 -320.27114)
		(end 256.788666 -316.855348)
		(width 0.1651)
		(layer "In5.Cu")
		(net "P5E_PEX2_STN7_RX_DP<118>")
	)
	(segment
		(start 284.276546 -371.48643)
		(end 283.379926 -369.531392)
		(width 0.1651)
		(layer "In5.Cu")
		(net "P5E_PEX2_STN7_RX_DP<118>")
	)
	(segment
		(start 300.689772 -408.572208)
		(end 300.816772 -408.699208)
		(width 0.1651)
		(layer "In5.Cu")
		(net "P5E_PEX2_STN7_RX_DP<118>")
	)
	(segment
		(start 301.060358 -394.424408)
		(end 300.211998 -393.856718)
		(width 0.1651)
		(layer "In5.Cu")
		(net "P5E_PEX2_STN7_RX_DP<118>")
	)
	(segment
		(start 300.689772 -408.190192)
		(end 300.689772 -408.572208)
		(width 0.1651)
		(layer "In5.Cu")
		(net "P5E_PEX2_STN7_RX_DP<118>")
	)
	(segment
		(start 275.960332 -357.993696)
		(end 275.960332 -342.138)
		(width 0.1651)
		(layer "In5.Cu")
		(net "P5E_PEX2_STN7_RX_DP<118>")
	)
	(segment
		(start 298.628054 -392.93419)
		(end 298.596812 -392.775694)
		(width 0.1651)
		(layer "In5.Cu")
		(net "P5E_PEX2_STN7_RX_DP<118>")
	)
	(segment
		(start 285.214822 -384.689858)
		(end 284.93212 -378.698506)
		(width 0.1651)
		(layer "In5.Cu")
		(net "P5E_PEX2_STN7_RX_DP<118>")
	)
	(segment
		(start 256.837688 -324.915784)
		(end 256.300478 -324.164452)
		(width 0.1651)
		(layer "In5.Cu")
		(net "P5E_PEX2_STN7_RX_DP<118>")
	)
	(segment
		(start 271.520158 -306.955444)
		(end 271.520158 -307.185568)
		(width 0.1143)
		(layer "In5.Cu")
		(net "P5E_PEX2_STN7_RX_DP<118>")
	)
	(segment
		(start 297.953176 -392.34491)
		(end 286.931354 -386.948426)
		(width 0.1651)
		(layer "In5.Cu")
		(net "P5E_PEX2_STN7_RX_DP<118>")
	)
	(segment
		(start 442.23051 -28.82392)
		(end 442.064394 -28.990036)
		(width 0.13462)
		(layer "F.Cu")
		(net "P5E_PEX3_STN2_TX_C_DP<32>")
	)
	(segment
		(start 443.82563 -29.139642)
		(end 443.509908 -28.82392)
		(width 0.13462)
		(layer "F.Cu")
		(net "P5E_PEX3_STN2_TX_C_DP<32>")
	)
	(segment
		(start 443.509908 -28.82392)
		(end 442.23051 -28.82392)
		(width 0.13462)
		(layer "F.Cu")
		(net "P5E_PEX3_STN2_TX_C_DP<32>")
	)
	(segment
		(start 442.064394 -28.990036)
		(end 441.564776 -28.990036)
		(width 0.13462)
		(layer "F.Cu")
		(net "P5E_PEX3_STN2_TX_C_DP<32>")
	)
	(segment
		(start 409.59024 -345.169998)
		(end 409.295092 -345.465146)
		(width 0.13462)
		(layer "F.Cu")
		(net "P5E_PEX3_STN7_TX_C_DP<112>")
	)
	(segment
		(start 409.269692 -344.219022)
		(end 409.59024 -344.53957)
		(width 0.13462)
		(layer "F.Cu")
		(net "P5E_PEX3_STN7_TX_C_DP<112>")
	)
	(segment
		(start 409.59024 -344.53957)
		(end 409.59024 -345.169998)
		(width 0.13462)
		(layer "F.Cu")
		(net "P5E_PEX3_STN7_TX_C_DP<112>")
	)
	(segment
		(start 409.133548 -368.632486)
		(end 409.133294 -368.632486)
		(width 0.1651)
		(layer "In11.Cu")
		(net "P5E_PEX3_STN7_TX_C_DP<112>")
	)
	(segment
		(start 420.333932 -400.612356)
		(end 420.047166 -400.899122)
		(width 0.1651)
		(layer "In11.Cu")
		(net "P5E_PEX3_STN7_TX_C_DP<112>")
	)
	(segment
		(start 409.133294 -368.632486)
		(end 410.311092 -383.557272)
		(width 0.1651)
		(layer "In11.Cu")
		(net "P5E_PEX3_STN7_TX_C_DP<112>")
	)
	(segment
		(start 407.691336 -350.359472)
		(end 408.98826 -366.79632)
		(width 0.1651)
		(layer "In11.Cu")
		(net "P5E_PEX3_STN7_TX_C_DP<112>")
	)
	(segment
		(start 409.041346 -367.467642)
		(end 409.080208 -367.961164)
		(width 0.1651)
		(layer "In11.Cu")
		(net "P5E_PEX3_STN7_TX_C_DP<112>")
	)
	(segment
		(start 420.05123 -394.64361)
		(end 420.333932 -394.926312)
		(width 0.1651)
		(layer "In11.Cu")
		(net "P5E_PEX3_STN7_TX_C_DP<112>")
	)
	(segment
		(start 410.791152 -386.462524)
		(end 413.644588 -391.664952)
		(width 0.1651)
		(layer "In11.Cu")
		(net "P5E_PEX3_STN7_TX_C_DP<112>")
	)
	(segment
		(start 417.114482 -393.278106)
		(end 417.163758 -393.41298)
		(width 0.1651)
		(layer "In11.Cu")
		(net "P5E_PEX3_STN7_TX_C_DP<112>")
	)
	(segment
		(start 417.747958 -393.572746)
		(end 418.19703 -393.781534)
		(width 0.1651)
		(layer "In11.Cu")
		(net "P5E_PEX3_STN7_TX_C_DP<112>")
	)
	(segment
		(start 410.311092 -383.557272)
		(end 410.791152 -386.462524)
		(width 0.1651)
		(layer "In11.Cu")
		(net "P5E_PEX3_STN7_TX_C_DP<112>")
	)
	(segment
		(start 418.246306 -393.916408)
		(end 418.695632 -394.12545)
		(width 0.1651)
		(layer "In11.Cu")
		(net "P5E_PEX3_STN7_TX_C_DP<112>")
	)
	(segment
		(start 409.037536 -368.550952)
		(end 409.133548 -368.632486)
		(width 0.1651)
		(layer "In11.Cu")
		(net "P5E_PEX3_STN7_TX_C_DP<112>")
	)
	(segment
		(start 408.031442 -347.764354)
		(end 407.691336 -350.359472)
		(width 0.1651)
		(layer "In11.Cu")
		(net "P5E_PEX3_STN7_TX_C_DP<112>")
	)
	(segment
		(start 408.998674 -368.056922)
		(end 409.037536 -368.550952)
		(width 0.1651)
		(layer "In11.Cu")
		(net "P5E_PEX3_STN7_TX_C_DP<112>")
	)
	(segment
		(start 420.333932 -394.926312)
		(end 420.333932 -400.612356)
		(width 0.1651)
		(layer "In11.Cu")
		(net "P5E_PEX3_STN7_TX_C_DP<112>")
	)
	(segment
		(start 408.945588 -367.385854)
		(end 409.041346 -367.467642)
		(width 0.1651)
		(layer "In11.Cu")
		(net "P5E_PEX3_STN7_TX_C_DP<112>")
	)
	(segment
		(start 420.047166 -400.899122)
		(end 419.61689 -400.899122)
		(width 0.1651)
		(layer "In11.Cu")
		(net "P5E_PEX3_STN7_TX_C_DP<112>")
	)
	(segment
		(start 408.906472 -366.891824)
		(end 408.945588 -367.385854)
		(width 0.1651)
		(layer "In11.Cu")
		(net "P5E_PEX3_STN7_TX_C_DP<112>")
	)
	(segment
		(start 409.585922 -345.755976)
		(end 409.585922 -346.209874)
		(width 0.1651)
		(layer "In11.Cu")
		(net "P5E_PEX3_STN7_TX_C_DP<112>")
	)
	(segment
		(start 409.585922 -346.209874)
		(end 408.031442 -347.764354)
		(width 0.1651)
		(layer "In11.Cu")
		(net "P5E_PEX3_STN7_TX_C_DP<112>")
	)
	(segment
		(start 418.83076 -394.076174)
		(end 420.05123 -394.64361)
		(width 0.1651)
		(layer "In11.Cu")
		(net "P5E_PEX3_STN7_TX_C_DP<112>")
	)
	(segment
		(start 413.644588 -391.664952)
		(end 417.114482 -393.278106)
		(width 0.1651)
		(layer "In11.Cu")
		(net "P5E_PEX3_STN7_TX_C_DP<112>")
	)
	(segment
		(start 417.163758 -393.41298)
		(end 417.613084 -393.622022)
		(width 0.1651)
		(layer "In11.Cu")
		(net "P5E_PEX3_STN7_TX_C_DP<112>")
	)
	(segment
		(start 418.695632 -394.12545)
		(end 418.83076 -394.076174)
		(width 0.1651)
		(layer "In11.Cu")
		(net "P5E_PEX3_STN7_TX_C_DP<112>")
	)
	(segment
		(start 409.295092 -345.465146)
		(end 409.585922 -345.755976)
		(width 0.1651)
		(layer "In11.Cu")
		(net "P5E_PEX3_STN7_TX_C_DP<112>")
	)
	(segment
		(start 419.48989 -400.772122)
		(end 419.48989 -400.390106)
		(width 0.1651)
		(layer "In11.Cu")
		(net "P5E_PEX3_STN7_TX_C_DP<112>")
	)
	(segment
		(start 417.613084 -393.622022)
		(end 417.747958 -393.572746)
		(width 0.1651)
		(layer "In11.Cu")
		(net "P5E_PEX3_STN7_TX_C_DP<112>")
	)
	(segment
		(start 418.19703 -393.781534)
		(end 418.246306 -393.916408)
		(width 0.1651)
		(layer "In11.Cu")
		(net "P5E_PEX3_STN7_TX_C_DP<112>")
	)
	(segment
		(start 419.61689 -400.899122)
		(end 419.48989 -400.772122)
		(width 0.1651)
		(layer "In11.Cu")
		(net "P5E_PEX3_STN7_TX_C_DP<112>")
	)
	(segment
		(start 408.98826 -366.79632)
		(end 408.906472 -366.891824)
		(width 0.1651)
		(layer "In11.Cu")
		(net "P5E_PEX3_STN7_TX_C_DP<112>")
	)
	(segment
		(start 409.080208 -367.961164)
		(end 408.998674 -368.056922)
		(width 0.1651)
		(layer "In11.Cu")
		(net "P5E_PEX3_STN7_TX_C_DP<112>")
	)
	(segment
		(start 73.745852 -131.84505)
		(end 73.908666 -132.007864)
		(width 0.13462)
		(layer "F.Cu")
		(net "P5E_PEX0_STN0_TX_C_DN<5>")
	)
	(segment
		(start 73.257664 -131.84505)
		(end 73.745852 -131.84505)
		(width 0.13462)
		(layer "F.Cu")
		(net "P5E_PEX0_STN0_TX_C_DN<5>")
	)
	(segment
		(start 73.908666 -132.007864)
		(end 82.07375 -132.007864)
		(width 0.13462)
		(layer "F.Cu")
		(net "P5E_PEX0_STN0_TX_C_DN<5>")
	)
	(segment
		(start 82.07375 -132.007864)
		(end 82.394806 -131.686808)
		(width 0.13462)
		(layer "F.Cu")
		(net "P5E_PEX0_STN0_TX_C_DN<5>")
	)
	(segment
		(start 277.566374 -130.995928)
		(end 277.735538 -131.165092)
		(width 0.13462)
		(layer "F.Cu")
		(net "P5E_PEX2_STN1_TX_C_DN<28>")
	)
	(segment
		(start 269.105126 -131.323334)
		(end 269.432532 -130.995928)
		(width 0.13462)
		(layer "F.Cu")
		(net "P5E_PEX2_STN1_TX_C_DN<28>")
	)
	(segment
		(start 277.735538 -131.165092)
		(end 278.242268 -131.165092)
		(width 0.13462)
		(layer "F.Cu")
		(net "P5E_PEX2_STN1_TX_C_DN<28>")
	)
	(segment
		(start 269.432532 -130.995928)
		(end 277.566374 -130.995928)
		(width 0.13462)
		(layer "F.Cu")
		(net "P5E_PEX2_STN1_TX_C_DN<28>")
	)
	(segment
		(start 409.667456 -32.16148)
		(end 410.312616 -32.16148)
		(width 0.13462)
		(layer "F.Cu")
		(net "P5E_PEX3_STN2_RX_DN<38>")
	)
	(segment
		(start 410.312616 -32.16148)
		(end 410.484066 -31.99003)
		(width 0.13462)
		(layer "F.Cu")
		(net "P5E_PEX3_STN2_RX_DN<38>")
	)
	(segment
		(start 410.484066 -31.99003)
		(end 410.964888 -31.99003)
		(width 0.13462)
		(layer "F.Cu")
		(net "P5E_PEX3_STN2_RX_DN<38>")
	)
	(segment
		(start 409.364688 -31.858712)
		(end 409.667456 -32.16148)
		(width 0.13462)
		(layer "F.Cu")
		(net "P5E_PEX3_STN2_RX_DN<38>")
	)
	(segment
		(start 410.213048 -39.71036)
		(end 410.183838 -37.856414)
		(width 0.1651)
		(layer "In7.Cu")
		(net "P5E_PEX3_STN2_RX_DN<38>")
	)
	(segment
		(start 410.744416 -32.663638)
		(end 410.230066 -32.149542)
		(width 0.1651)
		(layer "In7.Cu")
		(net "P5E_PEX3_STN2_RX_DN<38>")
	)
	(segment
		(start 410.230066 -32.149542)
		(end 409.655518 -32.149542)
		(width 0.1651)
		(layer "In7.Cu")
		(net "P5E_PEX3_STN2_RX_DN<38>")
	)
	(segment
		(start 411.595824 -49.94275)
		(end 410.213048 -39.71036)
		(width 0.1651)
		(layer "In7.Cu")
		(net "P5E_PEX3_STN2_RX_DN<38>")
	)
	(segment
		(start 400.96567 -271.392904)
		(end 400.96567 -265.778234)
		(width 0.1651)
		(layer "In7.Cu")
		(net "P5E_PEX3_STN2_RX_DN<38>")
	)
	(segment
		(start 401.048728 -264.832084)
		(end 411.449774 -67.914266)
		(width 0.1651)
		(layer "In7.Cu")
		(net "P5E_PEX3_STN2_RX_DN<38>")
	)
	(segment
		(start 400.91995 -271.467072)
		(end 400.96567 -271.421352)
		(width 0.1143)
		(layer "In7.Cu")
		(net "P5E_PEX3_STN2_RX_DN<38>")
	)
	(segment
		(start 410.707332 -35.04819)
		(end 410.744416 -32.663638)
		(width 0.1651)
		(layer "In7.Cu")
		(net "P5E_PEX3_STN2_RX_DN<38>")
	)
	(segment
		(start 411.449774 -67.914266)
		(end 411.42285 -61.011308)
		(width 0.1651)
		(layer "In7.Cu")
		(net "P5E_PEX3_STN2_RX_DN<38>")
	)
	(segment
		(start 409.655518 -32.149542)
		(end 409.364688 -31.858712)
		(width 0.1651)
		(layer "In7.Cu")
		(net "P5E_PEX3_STN2_RX_DN<38>")
	)
	(segment
		(start 401.299934 -274.999958)
		(end 401.299934 -275.265388)
		(width 0.1143)
		(layer "In7.Cu")
		(net "P5E_PEX3_STN2_RX_DN<38>")
	)
	(segment
		(start 401.299934 -275.265388)
		(end 401.185634 -275.379688)
		(width 0.1143)
		(layer "In7.Cu")
		(net "P5E_PEX3_STN2_RX_DN<38>")
	)
	(segment
		(start 400.96567 -265.778234)
		(end 401.048728 -264.832084)
		(width 0.1651)
		(layer "In7.Cu")
		(net "P5E_PEX3_STN2_RX_DN<38>")
	)
	(segment
		(start 401.185634 -275.379688)
		(end 401.023836 -275.379688)
		(width 0.1143)
		(layer "In7.Cu")
		(net "P5E_PEX3_STN2_RX_DN<38>")
	)
	(segment
		(start 410.183838 -37.856414)
		(end 410.707332 -35.04819)
		(width 0.1651)
		(layer "In7.Cu")
		(net "P5E_PEX3_STN2_RX_DN<38>")
	)
	(segment
		(start 400.91995 -275.275802)
		(end 400.91995 -271.467072)
		(width 0.1143)
		(layer "In7.Cu")
		(net "P5E_PEX3_STN2_RX_DN<38>")
	)
	(segment
		(start 411.42285 -61.011308)
		(end 411.595824 -49.94275)
		(width 0.1651)
		(layer "In7.Cu")
		(net "P5E_PEX3_STN2_RX_DN<38>")
	)
	(segment
		(start 400.96567 -271.421352)
		(end 400.96567 -271.392904)
		(width 0.1143)
		(layer "In7.Cu")
		(net "P5E_PEX3_STN2_RX_DN<38>")
	)
	(segment
		(start 401.023836 -275.379688)
		(end 400.91995 -275.275802)
		(width 0.1143)
		(layer "In7.Cu")
		(net "P5E_PEX3_STN2_RX_DN<38>")
	)
	(segment
		(start 390.394444 -321.658996)
		(end 389.75919 -321.202812)
		(width 0.1651)
		(layer "In9.Cu")
		(net "P5E_PEX3_STN7_RX_DN<126>")
	)
	(segment
		(start 392.70432 -322.29425)
		(end 392.589512 -322.353686)
		(width 0.1651)
		(layer "In9.Cu")
		(net "P5E_PEX3_STN7_RX_DN<126>")
	)
	(segment
		(start 434.23586 -368.536728)
		(end 442.12002 -358.78516)
		(width 0.1651)
		(layer "In9.Cu")
		(net "P5E_PEX3_STN7_RX_DN<126>")
	)
	(segment
		(start 392.589512 -322.353686)
		(end 390.394444 -321.658996)
		(width 0.1651)
		(layer "In9.Cu")
		(net "P5E_PEX3_STN7_RX_DN<126>")
	)
	(segment
		(start 442.542168 -341.526622)
		(end 442.324236 -341.232744)
		(width 0.1651)
		(layer "In9.Cu")
		(net "P5E_PEX3_STN7_RX_DN<126>")
	)
	(segment
		(start 432.816762 -382.980946)
		(end 433.155598 -382.980946)
		(width 0.1651)
		(layer "In9.Cu")
		(net "P5E_PEX3_STN7_RX_DN<126>")
	)
	(segment
		(start 389.81126 -316.419992)
		(end 389.90016 -316.508892)
		(width 0.1143)
		(layer "In9.Cu")
		(net "P5E_PEX3_STN7_RX_DN<126>")
	)
	(segment
		(start 389.56615 -319.865248)
		(end 389.52043 -319.819528)
		(width 0.1143)
		(layer "In9.Cu")
		(net "P5E_PEX3_STN7_RX_DN<126>")
	)
	(segment
		(start 407.429716 -327.051416)
		(end 393.236196 -322.55841)
		(width 0.1651)
		(layer "In9.Cu")
		(net "P5E_PEX3_STN7_RX_DN<126>")
	)
	(segment
		(start 389.75919 -321.202812)
		(end 389.56615 -320.736976)
		(width 0.1651)
		(layer "In9.Cu")
		(net "P5E_PEX3_STN7_RX_DN<126>")
	)
	(segment
		(start 389.52043 -316.585092)
		(end 389.68553 -316.419992)
		(width 0.1143)
		(layer "In9.Cu")
		(net "P5E_PEX3_STN7_RX_DN<126>")
	)
	(segment
		(start 442.12002 -358.78516)
		(end 442.54674 -357.90124)
		(width 0.1651)
		(layer "In9.Cu")
		(net "P5E_PEX3_STN7_RX_DN<126>")
	)
	(segment
		(start 432.689762 -383.107946)
		(end 432.816762 -382.980946)
		(width 0.1651)
		(layer "In9.Cu")
		(net "P5E_PEX3_STN7_RX_DN<126>")
	)
	(segment
		(start 433.155598 -382.980946)
		(end 433.846732 -382.289812)
		(width 0.1651)
		(layer "In9.Cu")
		(net "P5E_PEX3_STN7_RX_DN<126>")
	)
	(segment
		(start 393.236196 -322.558664)
		(end 393.17676 -322.443602)
		(width 0.1651)
		(layer "In9.Cu")
		(net "P5E_PEX3_STN7_RX_DN<126>")
	)
	(segment
		(start 389.90016 -316.508892)
		(end 389.90016 -316.799468)
		(width 0.1143)
		(layer "In9.Cu")
		(net "P5E_PEX3_STN7_RX_DN<126>")
	)
	(segment
		(start 389.68553 -316.419992)
		(end 389.81126 -316.419992)
		(width 0.1143)
		(layer "In9.Cu")
		(net "P5E_PEX3_STN7_RX_DN<126>")
	)
	(segment
		(start 442.54674 -357.90124)
		(end 442.542168 -341.526622)
		(width 0.1651)
		(layer "In9.Cu")
		(net "P5E_PEX3_STN7_RX_DN<126>")
	)
	(segment
		(start 432.689762 -383.490216)
		(end 432.689762 -383.107946)
		(width 0.1651)
		(layer "In9.Cu")
		(net "P5E_PEX3_STN7_RX_DN<126>")
	)
	(segment
		(start 439.861198 -340.480904)
		(end 420.677594 -333.296514)
		(width 0.1651)
		(layer "In9.Cu")
		(net "P5E_PEX3_STN7_RX_DN<126>")
	)
	(segment
		(start 433.846732 -382.289812)
		(end 433.846732 -369.59667)
		(width 0.1651)
		(layer "In9.Cu")
		(net "P5E_PEX3_STN7_RX_DN<126>")
	)
	(segment
		(start 389.56615 -320.736976)
		(end 389.56615 -319.893696)
		(width 0.1651)
		(layer "In9.Cu")
		(net "P5E_PEX3_STN7_RX_DN<126>")
	)
	(segment
		(start 389.90016 -316.799468)
		(end 389.899906 -316.799722)
		(width 0.1143)
		(layer "In9.Cu")
		(net "P5E_PEX3_STN7_RX_DN<126>")
	)
	(segment
		(start 393.17676 -322.443602)
		(end 392.70432 -322.29425)
		(width 0.1651)
		(layer "In9.Cu")
		(net "P5E_PEX3_STN7_RX_DN<126>")
	)
	(segment
		(start 389.56615 -319.893696)
		(end 389.56615 -319.865248)
		(width 0.1143)
		(layer "In9.Cu")
		(net "P5E_PEX3_STN7_RX_DN<126>")
	)
	(segment
		(start 433.846732 -369.59667)
		(end 434.23586 -368.536728)
		(width 0.1651)
		(layer "In9.Cu")
		(net "P5E_PEX3_STN7_RX_DN<126>")
	)
	(segment
		(start 393.236196 -322.55841)
		(end 393.236196 -322.558664)
		(width 0.1651)
		(layer "In9.Cu")
		(net "P5E_PEX3_STN7_RX_DN<126>")
	)
	(segment
		(start 420.677594 -333.296514)
		(end 407.429716 -327.051416)
		(width 0.1651)
		(layer "In9.Cu")
		(net "P5E_PEX3_STN7_RX_DN<126>")
	)
	(segment
		(start 389.52043 -319.819528)
		(end 389.52043 -316.585092)
		(width 0.1143)
		(layer "In9.Cu")
		(net "P5E_PEX3_STN7_RX_DN<126>")
	)
	(segment
		(start 442.324236 -341.232744)
		(end 439.861198 -340.480904)
		(width 0.1651)
		(layer "In9.Cu")
		(net "P5E_PEX3_STN7_RX_DN<126>")
	)
	(segment
		(start 155.84297 -155.226004)
		(end 156.49829 -155.226004)
		(width 0.13208)
		(layer "F.Cu")
		(net "NIC2_CLK")
	)
	(segment
		(start 158.472886 -155.360116)
		(end 162.14217 -155.360116)
		(width 0.13208)
		(layer "F.Cu")
		(net "NIC2_CLK")
	)
	(segment
		(start 155.107894 -155.3464)
		(end 155.722574 -155.3464)
		(width 0.13208)
		(layer "F.Cu")
		(net "NIC2_CLK")
	)
	(segment
		(start 158.338774 -155.226004)
		(end 158.472886 -155.360116)
		(width 0.13208)
		(layer "F.Cu")
		(net "NIC2_CLK")
	)
	(segment
		(start 156.49829 -155.226004)
		(end 158.338774 -155.226004)
		(width 0.13208)
		(layer "F.Cu")
		(net "NIC2_CLK")
	)
	(segment
		(start 155.722574 -155.3464)
		(end 155.84297 -155.226004)
		(width 0.13208)
		(layer "F.Cu")
		(net "NIC2_CLK")
	)
	(via
		(at 156.49829 -155.226004)
		(size 0.762)
		(drill 0.381)
		(layers "F.Cu" "B.Cu")
		(net "NIC2_CLK")
	)
	(segment
		(start 82.075782 -155.79217)
		(end 82.394806 -156.111194)
		(width 0.13462)
		(layer "F.Cu")
		(net "P5E_PEX0_STN0_TX_C_DP<15>")
	)
	(segment
		(start 73.908666 -155.79217)
		(end 82.075782 -155.79217)
		(width 0.13462)
		(layer "F.Cu")
		(net "P5E_PEX0_STN0_TX_C_DP<15>")
	)
	(segment
		(start 73.745852 -155.954984)
		(end 73.908666 -155.79217)
		(width 0.13462)
		(layer "F.Cu")
		(net "P5E_PEX0_STN0_TX_C_DP<15>")
	)
	(segment
		(start 73.257664 -155.954984)
		(end 73.745852 -155.954984)
		(width 0.13462)
		(layer "F.Cu")
		(net "P5E_PEX0_STN0_TX_C_DP<15>")
	)
	(segment
		(start 286.003746 -123.3932)
		(end 283.48178 -123.3932)
		(width 0.13462)
		(layer "F.Cu")
		(net "P5E_PEX2_STN1_RX_DN<26>")
	)
	(segment
		(start 283.48178 -123.3932)
		(end 283.319982 -123.554998)
		(width 0.13462)
		(layer "F.Cu")
		(net "P5E_PEX2_STN1_RX_DN<26>")
	)
	(segment
		(start 286.296862 -123.686316)
		(end 286.003746 -123.3932)
		(width 0.13462)
		(layer "F.Cu")
		(net "P5E_PEX2_STN1_RX_DN<26>")
	)
	(segment
		(start 283.319982 -123.554998)
		(end 282.842462 -123.554998)
		(width 0.13462)
		(layer "F.Cu")
		(net "P5E_PEX2_STN1_RX_DN<26>")
	)
	(segment
		(start 276.493986 -132.245354)
		(end 276.361652 -132.338572)
		(width 0.1651)
		(layer "In5.Cu")
		(net "P5E_PEX2_STN1_RX_DN<26>")
	)
	(segment
		(start 280.584656 -125.56363)
		(end 279.768808 -126.066804)
		(width 0.1651)
		(layer "In5.Cu")
		(net "P5E_PEX2_STN1_RX_DN<26>")
	)
	(segment
		(start 278.025098 -128.022096)
		(end 277.718012 -128.410462)
		(width 0.1651)
		(layer "In5.Cu")
		(net "P5E_PEX2_STN1_RX_DN<26>")
	)
	(segment
		(start 300.970188 -271.600168)
		(end 300.970188 -273.376136)
		(width 0.1143)
		(layer "In5.Cu")
		(net "P5E_PEX2_STN1_RX_DN<26>")
	)
	(segment
		(start 301.015908 -271.526)
		(end 301.015908 -271.554448)
		(width 0.1143)
		(layer "In5.Cu")
		(net "P5E_PEX2_STN1_RX_DN<26>")
	)
	(segment
		(start 283.276548 -123.902978)
		(end 283.239464 -124.060204)
		(width 0.1651)
		(layer "In5.Cu")
		(net "P5E_PEX2_STN1_RX_DN<26>")
	)
	(segment
		(start 276.820884 -129.678176)
		(end 276.69236 -130.423158)
		(width 0.1651)
		(layer "In5.Cu")
		(net "P5E_PEX2_STN1_RX_DN<26>")
	)
	(segment
		(start 282.20162 -124.700284)
		(end 281.779726 -124.960634)
		(width 0.1651)
		(layer "In5.Cu")
		(net "P5E_PEX2_STN1_RX_DN<26>")
	)
	(segment
		(start 271.956022 -157.384496)
		(end 272.767044 -161.883598)
		(width 0.1651)
		(layer "In5.Cu")
		(net "P5E_PEX2_STN1_RX_DN<26>")
	)
	(segment
		(start 272.767044 -161.883598)
		(end 301.015908 -267.893546)
		(width 0.1651)
		(layer "In5.Cu")
		(net "P5E_PEX2_STN1_RX_DN<26>")
	)
	(segment
		(start 284.099254 -123.395486)
		(end 283.276548 -123.902978)
		(width 0.1651)
		(layer "In5.Cu")
		(net "P5E_PEX2_STN1_RX_DN<26>")
	)
	(segment
		(start 276.785578 -130.555238)
		(end 276.70125 -131.04368)
		(width 0.1651)
		(layer "In5.Cu")
		(net "P5E_PEX2_STN1_RX_DN<26>")
	)
	(segment
		(start 271.310608 -147.433538)
		(end 271.956022 -157.384496)
		(width 0.1651)
		(layer "In5.Cu")
		(net "P5E_PEX2_STN1_RX_DN<26>")
	)
	(segment
		(start 282.238958 -124.543058)
		(end 282.20162 -124.700284)
		(width 0.1651)
		(layer "In5.Cu")
		(net "P5E_PEX2_STN1_RX_DN<26>")
	)
	(segment
		(start 276.56917 -131.136898)
		(end 276.485096 -131.624832)
		(width 0.1651)
		(layer "In5.Cu")
		(net "P5E_PEX2_STN1_RX_DN<26>")
	)
	(segment
		(start 278.47417 -127.453644)
		(end 278.47417 -127.453898)
		(width 0.1651)
		(layer "In5.Cu")
		(net "P5E_PEX2_STN1_RX_DN<26>")
	)
	(segment
		(start 301.349664 -273.365214)
		(end 301.349664 -273.099784)
		(width 0.1143)
		(layer "In5.Cu")
		(net "P5E_PEX2_STN1_RX_DN<26>")
	)
	(segment
		(start 276.69236 -130.423158)
		(end 276.785578 -130.555238)
		(width 0.1651)
		(layer "In5.Cu")
		(net "P5E_PEX2_STN1_RX_DN<26>")
	)
	(segment
		(start 277.429468 -128.959864)
		(end 277.26894 -128.97866)
		(width 0.1651)
		(layer "In5.Cu")
		(net "P5E_PEX2_STN1_RX_DN<26>")
	)
	(segment
		(start 283.239464 -124.060204)
		(end 282.81757 -124.320554)
		(width 0.1651)
		(layer "In5.Cu")
		(net "P5E_PEX2_STN1_RX_DN<26>")
	)
	(segment
		(start 286.006032 -123.395486)
		(end 285.318454 -123.395486)
		(width 0.1651)
		(layer "In5.Cu")
		(net "P5E_PEX2_STN1_RX_DN<26>")
	)
	(segment
		(start 276.961854 -129.367026)
		(end 276.820884 -129.678176)
		(width 0.1651)
		(layer "In5.Cu")
		(net "P5E_PEX2_STN1_RX_DN<26>")
	)
	(segment
		(start 278.492966 -127.614426)
		(end 278.185626 -128.0033)
		(width 0.1651)
		(layer "In5.Cu")
		(net "P5E_PEX2_STN1_RX_DN<26>")
	)
	(segment
		(start 286.296862 -123.686316)
		(end 286.006032 -123.395486)
		(width 0.1651)
		(layer "In5.Cu")
		(net "P5E_PEX2_STN1_RX_DN<26>")
	)
	(segment
		(start 282.660344 -124.283216)
		(end 282.238958 -124.543058)
		(width 0.1651)
		(layer "In5.Cu")
		(net "P5E_PEX2_STN1_RX_DN<26>")
	)
	(segment
		(start 276.578314 -131.756912)
		(end 276.493986 -132.245354)
		(width 0.1651)
		(layer "In5.Cu")
		(net "P5E_PEX2_STN1_RX_DN<26>")
	)
	(segment
		(start 278.185626 -128.0033)
		(end 278.025098 -128.022096)
		(width 0.1651)
		(layer "In5.Cu")
		(net "P5E_PEX2_STN1_RX_DN<26>")
	)
	(segment
		(start 282.81757 -124.320554)
		(end 282.660344 -124.283216)
		(width 0.1651)
		(layer "In5.Cu")
		(net "P5E_PEX2_STN1_RX_DN<26>")
	)
	(segment
		(start 284.594554 -123.395486)
		(end 284.099254 -123.395486)
		(width 0.1651)
		(layer "In5.Cu")
		(net "P5E_PEX2_STN1_RX_DN<26>")
	)
	(segment
		(start 276.568916 -131.136898)
		(end 276.56917 -131.136898)
		(width 0.1651)
		(layer "In5.Cu")
		(net "P5E_PEX2_STN1_RX_DN<26>")
	)
	(segment
		(start 280.741882 -125.600714)
		(end 280.584656 -125.56363)
		(width 0.1651)
		(layer "In5.Cu")
		(net "P5E_PEX2_STN1_RX_DN<26>")
	)
	(segment
		(start 285.318454 -123.395486)
		(end 285.204154 -123.509786)
		(width 0.1651)
		(layer "In5.Cu")
		(net "P5E_PEX2_STN1_RX_DN<26>")
	)
	(segment
		(start 277.718012 -128.410462)
		(end 277.736808 -128.57099)
		(width 0.1651)
		(layer "In5.Cu")
		(net "P5E_PEX2_STN1_RX_DN<26>")
	)
	(segment
		(start 275.154136 -139.332462)
		(end 274.115276 -142.91818)
		(width 0.1651)
		(layer "In5.Cu")
		(net "P5E_PEX2_STN1_RX_DN<26>")
	)
	(segment
		(start 279.768808 -126.066804)
		(end 279.099518 -126.66218)
		(width 0.1651)
		(layer "In5.Cu")
		(net "P5E_PEX2_STN1_RX_DN<26>")
	)
	(segment
		(start 278.47417 -127.453898)
		(end 278.492966 -127.614426)
		(width 0.1651)
		(layer "In5.Cu")
		(net "P5E_PEX2_STN1_RX_DN<26>")
	)
	(segment
		(start 281.779726 -124.960634)
		(end 281.6225 -124.923296)
		(width 0.1651)
		(layer "In5.Cu")
		(net "P5E_PEX2_STN1_RX_DN<26>")
	)
	(segment
		(start 281.6225 -124.923296)
		(end 281.201114 -125.183138)
		(width 0.1651)
		(layer "In5.Cu")
		(net "P5E_PEX2_STN1_RX_DN<26>")
	)
	(segment
		(start 281.163776 -125.340618)
		(end 280.741882 -125.600714)
		(width 0.1651)
		(layer "In5.Cu")
		(net "P5E_PEX2_STN1_RX_DN<26>")
	)
	(segment
		(start 301.015908 -271.554448)
		(end 300.970188 -271.600168)
		(width 0.1143)
		(layer "In5.Cu")
		(net "P5E_PEX2_STN1_RX_DN<26>")
	)
	(segment
		(start 284.708854 -123.509786)
		(end 284.594554 -123.395486)
		(width 0.1651)
		(layer "In5.Cu")
		(net "P5E_PEX2_STN1_RX_DN<26>")
	)
	(segment
		(start 276.70125 -131.04368)
		(end 276.568916 -131.136898)
		(width 0.1651)
		(layer "In5.Cu")
		(net "P5E_PEX2_STN1_RX_DN<26>")
	)
	(segment
		(start 279.099518 -126.66218)
		(end 278.47417 -127.453644)
		(width 0.1651)
		(layer "In5.Cu")
		(net "P5E_PEX2_STN1_RX_DN<26>")
	)
	(segment
		(start 301.235364 -273.479514)
		(end 301.349664 -273.365214)
		(width 0.1143)
		(layer "In5.Cu")
		(net "P5E_PEX2_STN1_RX_DN<26>")
	)
	(segment
		(start 274.115276 -142.91818)
		(end 271.614138 -146.275806)
		(width 0.1651)
		(layer "In5.Cu")
		(net "P5E_PEX2_STN1_RX_DN<26>")
	)
	(segment
		(start 301.015908 -267.893546)
		(end 301.015908 -271.526)
		(width 0.1651)
		(layer "In5.Cu")
		(net "P5E_PEX2_STN1_RX_DN<26>")
	)
	(segment
		(start 277.736808 -128.57099)
		(end 277.429468 -128.959864)
		(width 0.1651)
		(layer "In5.Cu")
		(net "P5E_PEX2_STN1_RX_DN<26>")
	)
	(segment
		(start 277.26894 -128.97866)
		(end 276.961854 -129.367026)
		(width 0.1651)
		(layer "In5.Cu")
		(net "P5E_PEX2_STN1_RX_DN<26>")
	)
	(segment
		(start 281.201114 -125.183138)
		(end 281.163776 -125.340618)
		(width 0.1651)
		(layer "In5.Cu")
		(net "P5E_PEX2_STN1_RX_DN<26>")
	)
	(segment
		(start 276.361652 -132.338572)
		(end 275.154136 -139.332462)
		(width 0.1651)
		(layer "In5.Cu")
		(net "P5E_PEX2_STN1_RX_DN<26>")
	)
	(segment
		(start 276.485096 -131.624832)
		(end 276.578314 -131.756912)
		(width 0.1651)
		(layer "In5.Cu")
		(net "P5E_PEX2_STN1_RX_DN<26>")
	)
	(segment
		(start 285.204154 -123.509786)
		(end 284.708854 -123.509786)
		(width 0.1651)
		(layer "In5.Cu")
		(net "P5E_PEX2_STN1_RX_DN<26>")
	)
	(segment
		(start 271.614138 -146.275806)
		(end 271.310608 -147.433538)
		(width 0.1651)
		(layer "In5.Cu")
		(net "P5E_PEX2_STN1_RX_DN<26>")
	)
	(segment
		(start 300.970188 -273.376136)
		(end 301.073566 -273.479514)
		(width 0.1143)
		(layer "In5.Cu")
		(net "P5E_PEX2_STN1_RX_DN<26>")
	)
	(segment
		(start 301.073566 -273.479514)
		(end 301.235364 -273.479514)
		(width 0.1143)
		(layer "In5.Cu")
		(net "P5E_PEX2_STN1_RX_DN<26>")
	)
	(segment
		(start 442.230764 -30.353)
		(end 442.06795 -30.190186)
		(width 0.13462)
		(layer "F.Cu")
		(net "P5E_PEX3_STN2_TX_C_DN<33>")
	)
	(segment
		(start 446.467738 -30.03169)
		(end 446.146428 -30.353)
		(width 0.13462)
		(layer "F.Cu")
		(net "P5E_PEX3_STN2_TX_C_DN<33>")
	)
	(segment
		(start 442.06795 -30.190186)
		(end 441.564776 -30.190186)
		(width 0.13462)
		(layer "F.Cu")
		(net "P5E_PEX3_STN2_TX_C_DN<33>")
	)
	(segment
		(start 446.146428 -30.353)
		(end 442.230764 -30.353)
		(width 0.13462)
		(layer "F.Cu")
		(net "P5E_PEX3_STN2_TX_C_DN<33>")
	)
	(segment
		(start 387.719316 -307.299868)
		(end 387.999986 -307.299868)
		(width 0.1143)
		(layer "In9.Cu")
		(net "P5E_PEX3_STN7_RX_DP<118>")
	)
	(segment
		(start 417.358322 -358.21874)
		(end 417.358322 -341.956898)
		(width 0.1651)
		(layer "In9.Cu")
		(net "P5E_PEX3_STN7_RX_DP<118>")
	)
	(segment
		(start 387.380988 -306.729638)
		(end 387.624828 -306.973478)
		(width 0.1143)
		(layer "In9.Cu")
		(net "P5E_PEX3_STN7_RX_DP<118>")
	)
	(segment
		(start 431.913792 -393.752578)
		(end 431.4952 -393.488164)
		(width 0.1651)
		(layer "In9.Cu")
		(net "P5E_PEX3_STN7_RX_DP<118>")
	)
	(segment
		(start 414.919668 -340.59876)
		(end 414.465516 -340.400132)
		(width 0.1651)
		(layer "In9.Cu")
		(net "P5E_PEX3_STN7_RX_DP<118>")
	)
	(segment
		(start 372.428262 -324.552056)
		(end 371.5766 -322.494148)
		(width 0.1651)
		(layer "In9.Cu")
		(net "P5E_PEX3_STN7_RX_DP<118>")
	)
	(segment
		(start 371.5766 -319.783968)
		(end 372.522496 -317.497206)
		(width 0.1651)
		(layer "In9.Cu")
		(net "P5E_PEX3_STN7_RX_DP<118>")
	)
	(segment
		(start 430.936146 -393.254992)
		(end 430.904396 -393.114784)
		(width 0.1651)
		(layer "In9.Cu")
		(net "P5E_PEX3_STN7_RX_DP<118>")
	)
	(segment
		(start 416.599878 -383.815844)
		(end 417.358322 -358.21874)
		(width 0.1651)
		(layer "In9.Cu")
		(net "P5E_PEX3_STN7_RX_DP<118>")
	)
	(segment
		(start 387.624828 -307.20538)
		(end 387.719316 -307.299868)
		(width 0.1143)
		(layer "In9.Cu")
		(net "P5E_PEX3_STN7_RX_DP<118>")
	)
	(segment
		(start 417.358322 -341.956898)
		(end 417.005008 -341.399622)
		(width 0.1651)
		(layer "In9.Cu")
		(net "P5E_PEX3_STN7_RX_DP<118>")
	)
	(segment
		(start 432.816762 -408.699208)
		(end 433.038758 -408.699208)
		(width 0.1651)
		(layer "In9.Cu")
		(net "P5E_PEX3_STN7_RX_DP<118>")
	)
	(segment
		(start 431.4952 -393.488164)
		(end 431.354992 -393.51966)
		(width 0.1651)
		(layer "In9.Cu")
		(net "P5E_PEX3_STN7_RX_DP<118>")
	)
	(segment
		(start 416.14725 -341.024718)
		(end 416.013646 -341.077042)
		(width 0.1651)
		(layer "In9.Cu")
		(net "P5E_PEX3_STN7_RX_DP<118>")
	)
	(segment
		(start 432.689762 -408.572208)
		(end 432.816762 -408.699208)
		(width 0.1651)
		(layer "In9.Cu")
		(net "P5E_PEX3_STN7_RX_DP<118>")
	)
	(segment
		(start 416.950652 -385.031488)
		(end 416.599878 -383.815844)
		(width 0.1651)
		(layer "In9.Cu")
		(net "P5E_PEX3_STN7_RX_DP<118>")
	)
	(segment
		(start 433.564792 -408.173174)
		(end 433.564792 -395.247368)
		(width 0.1651)
		(layer "In9.Cu")
		(net "P5E_PEX3_STN7_RX_DP<118>")
	)
	(segment
		(start 383.921 -306.683918)
		(end 383.96672 -306.729638)
		(width 0.1143)
		(layer "In9.Cu")
		(net "P5E_PEX3_STN7_RX_DP<118>")
	)
	(segment
		(start 383.892552 -306.683918)
		(end 383.921 -306.683918)
		(width 0.1143)
		(layer "In9.Cu")
		(net "P5E_PEX3_STN7_RX_DP<118>")
	)
	(segment
		(start 387.624828 -306.973478)
		(end 387.624828 -307.20538)
		(width 0.1143)
		(layer "In9.Cu")
		(net "P5E_PEX3_STN7_RX_DP<118>")
	)
	(segment
		(start 376.38863 -328.5109)
		(end 372.428262 -324.552056)
		(width 0.1651)
		(layer "In9.Cu")
		(net "P5E_PEX3_STN7_RX_DP<118>")
	)
	(segment
		(start 433.038758 -408.699208)
		(end 433.564792 -408.173174)
		(width 0.1651)
		(layer "In9.Cu")
		(net "P5E_PEX3_STN7_RX_DP<118>")
	)
	(segment
		(start 419.827964 -387.837172)
		(end 417.63569 -386.051044)
		(width 0.1651)
		(layer "In9.Cu")
		(net "P5E_PEX3_STN7_RX_DP<118>")
	)
	(segment
		(start 415.506916 -340.74481)
		(end 415.053272 -340.546436)
		(width 0.1651)
		(layer "In9.Cu")
		(net "P5E_PEX3_STN7_RX_DP<118>")
	)
	(segment
		(start 432.689762 -408.190192)
		(end 432.689762 -408.572208)
		(width 0.1651)
		(layer "In9.Cu")
		(net "P5E_PEX3_STN7_RX_DP<118>")
	)
	(segment
		(start 417.63569 -386.051044)
		(end 416.950652 -385.031488)
		(width 0.1651)
		(layer "In9.Cu")
		(net "P5E_PEX3_STN7_RX_DP<118>")
	)
	(segment
		(start 433.564792 -395.247368)
		(end 433.183284 -394.55471)
		(width 0.1651)
		(layer "In9.Cu")
		(net "P5E_PEX3_STN7_RX_DP<118>")
	)
	(segment
		(start 381.533908 -307.133498)
		(end 382.618996 -306.683918)
		(width 0.1651)
		(layer "In9.Cu")
		(net "P5E_PEX3_STN7_RX_DP<118>")
	)
	(segment
		(start 415.559494 -340.878414)
		(end 415.50717 -340.744556)
		(width 0.1651)
		(layer "In9.Cu")
		(net "P5E_PEX3_STN7_RX_DP<118>")
	)
	(segment
		(start 433.183284 -394.55471)
		(end 432.504342 -394.125958)
		(width 0.1651)
		(layer "In9.Cu")
		(net "P5E_PEX3_STN7_RX_DP<118>")
	)
	(segment
		(start 383.96672 -306.729638)
		(end 387.380988 -306.729638)
		(width 0.1143)
		(layer "In9.Cu")
		(net "P5E_PEX3_STN7_RX_DP<118>")
	)
	(segment
		(start 376.397774 -312.27395)
		(end 376.397774 -312.269632)
		(width 0.1651)
		(layer "In9.Cu")
		(net "P5E_PEX3_STN7_RX_DP<118>")
	)
	(segment
		(start 432.504342 -394.125958)
		(end 432.364388 -394.157454)
		(width 0.1651)
		(layer "In9.Cu")
		(net "P5E_PEX3_STN7_RX_DP<118>")
	)
	(segment
		(start 376.397774 -312.269632)
		(end 381.533908 -307.133498)
		(width 0.1651)
		(layer "In9.Cu")
		(net "P5E_PEX3_STN7_RX_DP<118>")
	)
	(segment
		(start 426.06214 -390.055608)
		(end 419.827964 -387.837172)
		(width 0.1651)
		(layer "In9.Cu")
		(net "P5E_PEX3_STN7_RX_DP<118>")
	)
	(segment
		(start 371.5766 -322.494148)
		(end 371.5766 -319.783968)
		(width 0.1651)
		(layer "In9.Cu")
		(net "P5E_PEX3_STN7_RX_DP<118>")
	)
	(segment
		(start 431.354992 -393.51966)
		(end 430.936146 -393.254992)
		(width 0.1651)
		(layer "In9.Cu")
		(net "P5E_PEX3_STN7_RX_DP<118>")
	)
	(segment
		(start 431.945288 -393.892786)
		(end 431.913792 -393.752578)
		(width 0.1651)
		(layer "In9.Cu")
		(net "P5E_PEX3_STN7_RX_DP<118>")
	)
	(segment
		(start 377.999498 -329.018138)
		(end 376.38863 -328.5109)
		(width 0.1651)
		(layer "In9.Cu")
		(net "P5E_PEX3_STN7_RX_DP<118>")
	)
	(segment
		(start 372.522496 -317.497206)
		(end 376.397774 -312.27395)
		(width 0.1651)
		(layer "In9.Cu")
		(net "P5E_PEX3_STN7_RX_DP<118>")
	)
	(segment
		(start 415.053272 -340.546436)
		(end 415.053526 -340.546182)
		(width 0.1651)
		(layer "In9.Cu")
		(net "P5E_PEX3_STN7_RX_DP<118>")
	)
	(segment
		(start 414.465516 -340.400132)
		(end 414.413192 -340.266274)
		(width 0.1651)
		(layer "In9.Cu")
		(net "P5E_PEX3_STN7_RX_DP<118>")
	)
	(segment
		(start 430.904396 -393.114784)
		(end 426.06214 -390.055608)
		(width 0.1651)
		(layer "In9.Cu")
		(net "P5E_PEX3_STN7_RX_DP<118>")
	)
	(segment
		(start 414.413192 -340.266274)
		(end 414.412938 -340.266528)
		(width 0.1651)
		(layer "In9.Cu")
		(net "P5E_PEX3_STN7_RX_DP<118>")
	)
	(segment
		(start 400.48434 -334.177132)
		(end 377.999498 -329.018138)
		(width 0.1651)
		(layer "In9.Cu")
		(net "P5E_PEX3_STN7_RX_DP<118>")
	)
	(segment
		(start 382.618996 -306.683918)
		(end 383.892552 -306.683918)
		(width 0.1651)
		(layer "In9.Cu")
		(net "P5E_PEX3_STN7_RX_DP<118>")
	)
	(segment
		(start 415.053526 -340.546182)
		(end 414.919668 -340.59876)
		(width 0.1651)
		(layer "In9.Cu")
		(net "P5E_PEX3_STN7_RX_DP<118>")
	)
	(segment
		(start 432.364388 -394.157454)
		(end 431.945288 -393.892786)
		(width 0.1651)
		(layer "In9.Cu")
		(net "P5E_PEX3_STN7_RX_DP<118>")
	)
	(segment
		(start 415.50717 -340.744556)
		(end 415.506916 -340.74481)
		(width 0.1651)
		(layer "In9.Cu")
		(net "P5E_PEX3_STN7_RX_DP<118>")
	)
	(segment
		(start 416.013646 -341.077042)
		(end 415.559494 -340.878414)
		(width 0.1651)
		(layer "In9.Cu")
		(net "P5E_PEX3_STN7_RX_DP<118>")
	)
	(segment
		(start 414.412938 -340.266528)
		(end 400.48434 -334.177132)
		(width 0.1651)
		(layer "In9.Cu")
		(net "P5E_PEX3_STN7_RX_DP<118>")
	)
	(segment
		(start 417.005008 -341.399622)
		(end 416.14725 -341.024718)
		(width 0.1651)
		(layer "In9.Cu")
		(net "P5E_PEX3_STN7_RX_DP<118>")
	)
	(segment
		(start 167.778684 -156.687012)
		(end 167.778684 -157.0736)
		(width 0.13208)
		(layer "F.Cu")
		(net "NIC2_RBT_ARB_IN")
	)
	(segment
		(start 167.651684 -156.560012)
		(end 167.778684 -156.687012)
		(width 0.13208)
		(layer "F.Cu")
		(net "NIC2_RBT_ARB_IN")
	)
	(segment
		(start 166.742364 -156.560012)
		(end 167.651684 -156.560012)
		(width 0.13208)
		(layer "F.Cu")
		(net "NIC2_RBT_ARB_IN")
	)
	(via
		(at 167.778684 -157.0736)
		(size 0.508)
		(drill 0.254)
		(layers "F.Cu" "B.Cu")
		(net "NIC2_RBT_ARB_IN")
	)
	(segment
		(start 166.055294 -157.0736)
		(end 167.778684 -157.0736)
		(width 0.13208)
		(layer "B.Cu")
		(net "NIC2_RBT_ARB_IN")
	)
	(segment
		(start 68.006722 -146.792188)
		(end 67.352418 -146.792188)
		(width 0.13462)
		(layer "F.Cu")
		(net "P5E_PEX0_STN0_RX_DP<10>")
	)
	(segment
		(start 67.352418 -146.792188)
		(end 67.05727 -147.087336)
		(width 0.13462)
		(layer "F.Cu")
		(net "P5E_PEX0_STN0_RX_DP<10>")
	)
	(segment
		(start 68.169536 -146.955002)
		(end 68.006722 -146.792188)
		(width 0.13462)
		(layer "F.Cu")
		(net "P5E_PEX0_STN0_RX_DP<10>")
	)
	(segment
		(start 68.65747 -146.955002)
		(end 68.169536 -146.955002)
		(width 0.13462)
		(layer "F.Cu")
		(net "P5E_PEX0_STN0_RX_DP<10>")
	)
	(segment
		(start 69.928486 -149.313138)
		(end 70.05193 -149.337268)
		(width 0.1651)
		(layer "In5.Cu")
		(net "P5E_PEX0_STN0_RX_DP<10>")
	)
	(segment
		(start 71.01205 -150.765256)
		(end 71.939404 -153.04135)
		(width 0.1651)
		(layer "In5.Cu")
		(net "P5E_PEX0_STN0_RX_DP<10>")
	)
	(segment
		(start 69.399912 -148.367496)
		(end 69.676264 -148.778468)
		(width 0.1651)
		(layer "In5.Cu")
		(net "P5E_PEX0_STN0_RX_DP<10>")
	)
	(segment
		(start 67.3481 -146.796506)
		(end 67.828922 -146.796506)
		(width 0.1651)
		(layer "In5.Cu")
		(net "P5E_PEX0_STN0_RX_DP<10>")
	)
	(segment
		(start 75.449176 -158.81731)
		(end 75.449176 -158.817564)
		(width 0.1651)
		(layer "In5.Cu")
		(net "P5E_PEX0_STN0_RX_DP<10>")
	)
	(segment
		(start 75.997308 -161.050732)
		(end 79.510128 -260.49986)
		(width 0.1651)
		(layer "In5.Cu")
		(net "P5E_PEX0_STN0_RX_DP<10>")
	)
	(segment
		(start 78.98384 -271.013428)
		(end 78.98384 -271.773904)
		(width 0.1651)
		(layer "In5.Cu")
		(net "P5E_PEX0_STN0_RX_DP<10>")
	)
	(segment
		(start 79.545434 -268.155928)
		(end 78.98384 -271.013428)
		(width 0.1651)
		(layer "In5.Cu")
		(net "P5E_PEX0_STN0_RX_DP<10>")
	)
	(segment
		(start 70.05193 -149.337268)
		(end 71.01205 -150.765256)
		(width 0.1651)
		(layer "In5.Cu")
		(net "P5E_PEX0_STN0_RX_DP<10>")
	)
	(segment
		(start 74.901044 -156.583888)
		(end 75.449176 -158.81731)
		(width 0.1651)
		(layer "In5.Cu")
		(net "P5E_PEX0_STN0_RX_DP<10>")
	)
	(segment
		(start 75.449176 -158.817564)
		(end 75.997308 -161.050732)
		(width 0.1651)
		(layer "In5.Cu")
		(net "P5E_PEX0_STN0_RX_DP<10>")
	)
	(segment
		(start 68.655184 -147.622768)
		(end 69.399912 -148.367496)
		(width 0.1651)
		(layer "In5.Cu")
		(net "P5E_PEX0_STN0_RX_DP<10>")
	)
	(segment
		(start 69.65188 -148.901658)
		(end 69.928486 -149.313138)
		(width 0.1651)
		(layer "In5.Cu")
		(net "P5E_PEX0_STN0_RX_DP<10>")
	)
	(segment
		(start 78.98384 -271.802352)
		(end 79.02956 -271.848072)
		(width 0.1143)
		(layer "In5.Cu")
		(net "P5E_PEX0_STN0_RX_DP<10>")
	)
	(segment
		(start 71.939404 -153.04135)
		(end 73.666858 -155.363164)
		(width 0.1651)
		(layer "In5.Cu")
		(net "P5E_PEX0_STN0_RX_DP<10>")
	)
	(segment
		(start 79.599536 -275.684488)
		(end 79.599536 -275.949918)
		(width 0.1143)
		(layer "In5.Cu")
		(net "P5E_PEX0_STN0_RX_DP<10>")
	)
	(segment
		(start 68.178934 -147.272248)
		(end 68.529454 -147.622768)
		(width 0.1651)
		(layer "In5.Cu")
		(net "P5E_PEX0_STN0_RX_DP<10>")
	)
	(segment
		(start 67.05727 -147.087336)
		(end 67.3481 -146.796506)
		(width 0.1651)
		(layer "In5.Cu")
		(net "P5E_PEX0_STN0_RX_DP<10>")
	)
	(segment
		(start 79.244444 -275.570188)
		(end 79.485236 -275.570188)
		(width 0.1143)
		(layer "In5.Cu")
		(net "P5E_PEX0_STN0_RX_DP<10>")
	)
	(segment
		(start 73.666858 -155.363164)
		(end 74.616564 -156.139388)
		(width 0.1651)
		(layer "In5.Cu")
		(net "P5E_PEX0_STN0_RX_DP<10>")
	)
	(segment
		(start 74.616564 -156.139388)
		(end 74.901044 -156.583888)
		(width 0.1651)
		(layer "In5.Cu")
		(net "P5E_PEX0_STN0_RX_DP<10>")
	)
	(segment
		(start 67.828922 -146.796506)
		(end 68.178934 -147.146518)
		(width 0.1651)
		(layer "In5.Cu")
		(net "P5E_PEX0_STN0_RX_DP<10>")
	)
	(segment
		(start 78.98384 -271.773904)
		(end 78.98384 -271.802352)
		(width 0.1143)
		(layer "In5.Cu")
		(net "P5E_PEX0_STN0_RX_DP<10>")
	)
	(segment
		(start 79.02956 -271.848072)
		(end 79.02956 -275.355304)
		(width 0.1143)
		(layer "In5.Cu")
		(net "P5E_PEX0_STN0_RX_DP<10>")
	)
	(segment
		(start 68.529454 -147.622768)
		(end 68.655184 -147.622768)
		(width 0.1651)
		(layer "In5.Cu")
		(net "P5E_PEX0_STN0_RX_DP<10>")
	)
	(segment
		(start 68.178934 -147.146518)
		(end 68.178934 -147.272248)
		(width 0.1651)
		(layer "In5.Cu")
		(net "P5E_PEX0_STN0_RX_DP<10>")
	)
	(segment
		(start 79.02956 -275.355304)
		(end 79.244444 -275.570188)
		(width 0.1143)
		(layer "In5.Cu")
		(net "P5E_PEX0_STN0_RX_DP<10>")
	)
	(segment
		(start 69.676264 -148.778468)
		(end 69.65188 -148.901658)
		(width 0.1651)
		(layer "In5.Cu")
		(net "P5E_PEX0_STN0_RX_DP<10>")
	)
	(segment
		(start 79.485236 -275.570188)
		(end 79.599536 -275.684488)
		(width 0.1143)
		(layer "In5.Cu")
		(net "P5E_PEX0_STN0_RX_DP<10>")
	)
	(segment
		(start 79.510128 -260.49986)
		(end 79.545434 -268.155928)
		(width 0.1651)
		(layer "In5.Cu")
		(net "P5E_PEX0_STN0_RX_DP<10>")
	)
	(segment
		(start 286.296862 -110.11281)
		(end 286.016192 -110.39348)
		(width 0.13462)
		(layer "F.Cu")
		(net "P5E_PEX2_STN1_RX_DP<22>")
	)
	(segment
		(start 286.016192 -110.39348)
		(end 283.473398 -110.39348)
		(width 0.13462)
		(layer "F.Cu")
		(net "P5E_PEX2_STN1_RX_DP<22>")
	)
	(segment
		(start 283.325062 -110.245144)
		(end 282.842462 -110.245144)
		(width 0.13462)
		(layer "F.Cu")
		(net "P5E_PEX2_STN1_RX_DP<22>")
	)
	(segment
		(start 283.473398 -110.39348)
		(end 283.325062 -110.245144)
		(width 0.13462)
		(layer "F.Cu")
		(net "P5E_PEX2_STN1_RX_DP<22>")
	)
	(segment
		(start 269.271242 -140.590016)
		(end 267.384022 -144.791938)
		(width 0.1651)
		(layer "In5.Cu")
		(net "P5E_PEX2_STN1_RX_DP<22>")
	)
	(segment
		(start 275.447252 -114.534442)
		(end 275.116544 -114.922554)
		(width 0.1651)
		(layer "In5.Cu")
		(net "P5E_PEX2_STN1_RX_DP<22>")
	)
	(segment
		(start 286.296862 -110.11281)
		(end 286.006032 -110.40364)
		(width 0.1651)
		(layer "In5.Cu")
		(net "P5E_PEX2_STN1_RX_DP<22>")
	)
	(segment
		(start 267.384022 -144.791938)
		(end 266.28217 -150.991316)
		(width 0.1651)
		(layer "In5.Cu")
		(net "P5E_PEX2_STN1_RX_DP<22>")
	)
	(segment
		(start 276.071584 -114.24666)
		(end 275.447252 -114.534442)
		(width 0.1651)
		(layer "In5.Cu")
		(net "P5E_PEX2_STN1_RX_DP<22>")
	)
	(segment
		(start 266.28217 -150.991316)
		(end 266.281916 -150.991316)
		(width 0.1651)
		(layer "In5.Cu")
		(net "P5E_PEX2_STN1_RX_DP<22>")
	)
	(segment
		(start 271.208754 -136.92378)
		(end 269.271242 -140.590016)
		(width 0.1651)
		(layer "In5.Cu")
		(net "P5E_PEX2_STN1_RX_DP<22>")
	)
	(segment
		(start 296.933874 -271.526)
		(end 296.933874 -271.554448)
		(width 0.1143)
		(layer "In5.Cu")
		(net "P5E_PEX2_STN1_RX_DP<22>")
	)
	(segment
		(start 266.734798 -158.40456)
		(end 267.824712 -164.482018)
		(width 0.1651)
		(layer "In5.Cu")
		(net "P5E_PEX2_STN1_RX_DP<22>")
	)
	(segment
		(start 276.68855 -114.177826)
		(end 276.523196 -114.24666)
		(width 0.1651)
		(layer "In5.Cu")
		(net "P5E_PEX2_STN1_RX_DP<22>")
	)
	(segment
		(start 266.276074 -151.024336)
		(end 266.734798 -158.40456)
		(width 0.1651)
		(layer "In5.Cu")
		(net "P5E_PEX2_STN1_RX_DP<22>")
	)
	(segment
		(start 286.006032 -110.40364)
		(end 283.98724 -110.40364)
		(width 0.1651)
		(layer "In5.Cu")
		(net "P5E_PEX2_STN1_RX_DP<22>")
	)
	(segment
		(start 296.979594 -273.45513)
		(end 297.194478 -273.670014)
		(width 0.1143)
		(layer "In5.Cu")
		(net "P5E_PEX2_STN1_RX_DP<22>")
	)
	(segment
		(start 267.824712 -164.482018)
		(end 296.933874 -268.825472)
		(width 0.1651)
		(layer "In5.Cu")
		(net "P5E_PEX2_STN1_RX_DP<22>")
	)
	(segment
		(start 276.523196 -114.24666)
		(end 276.071584 -114.24666)
		(width 0.1651)
		(layer "In5.Cu")
		(net "P5E_PEX2_STN1_RX_DP<22>")
	)
	(segment
		(start 266.281916 -150.991316)
		(end 266.276074 -151.024336)
		(width 0.1651)
		(layer "In5.Cu")
		(net "P5E_PEX2_STN1_RX_DP<22>")
	)
	(segment
		(start 296.933874 -268.825472)
		(end 296.933874 -271.526)
		(width 0.1651)
		(layer "In5.Cu")
		(net "P5E_PEX2_STN1_RX_DP<22>")
	)
	(segment
		(start 296.979594 -271.600168)
		(end 296.979594 -273.45513)
		(width 0.1143)
		(layer "In5.Cu")
		(net "P5E_PEX2_STN1_RX_DP<22>")
	)
	(segment
		(start 275.116544 -114.922554)
		(end 274.801076 -115.598956)
		(width 0.1651)
		(layer "In5.Cu")
		(net "P5E_PEX2_STN1_RX_DP<22>")
	)
	(segment
		(start 283.98724 -110.40364)
		(end 279.784556 -112.114584)
		(width 0.1651)
		(layer "In5.Cu")
		(net "P5E_PEX2_STN1_RX_DP<22>")
	)
	(segment
		(start 279.784556 -112.114584)
		(end 276.68855 -114.177826)
		(width 0.1651)
		(layer "In5.Cu")
		(net "P5E_PEX2_STN1_RX_DP<22>")
	)
	(segment
		(start 274.801076 -115.598956)
		(end 271.208754 -136.92378)
		(width 0.1651)
		(layer "In5.Cu")
		(net "P5E_PEX2_STN1_RX_DP<22>")
	)
	(segment
		(start 296.933874 -271.554448)
		(end 296.979594 -271.600168)
		(width 0.1143)
		(layer "In5.Cu")
		(net "P5E_PEX2_STN1_RX_DP<22>")
	)
	(segment
		(start 297.43527 -273.670014)
		(end 297.54957 -273.784314)
		(width 0.1143)
		(layer "In5.Cu")
		(net "P5E_PEX2_STN1_RX_DP<22>")
	)
	(segment
		(start 297.194478 -273.670014)
		(end 297.43527 -273.670014)
		(width 0.1143)
		(layer "In5.Cu")
		(net "P5E_PEX2_STN1_RX_DP<22>")
	)
	(segment
		(start 297.54957 -273.784314)
		(end 297.54957 -274.049744)
		(width 0.1143)
		(layer "In5.Cu")
		(net "P5E_PEX2_STN1_RX_DP<22>")
	)
	(segment
		(start 267.820648 -305.733958)
		(end 267.866368 -305.779678)
		(width 0.1143)
		(layer "In5.Cu")
		(net "P5E_PEX2_STN7_RX_DP<117>")
	)
	(segment
		(start 298.489878 -409.672028)
		(end 298.616878 -409.799028)
		(width 0.1651)
		(layer "In5.Cu")
		(net "P5E_PEX2_STN7_RX_DP<117>")
	)
	(segment
		(start 298.616878 -409.799028)
		(end 299.047154 -409.799028)
		(width 0.1651)
		(layer "In5.Cu")
		(net "P5E_PEX2_STN7_RX_DP<117>")
	)
	(segment
		(start 269.394178 -305.779678)
		(end 269.619984 -306.005484)
		(width 0.1143)
		(layer "In5.Cu")
		(net "P5E_PEX2_STN7_RX_DP<117>")
	)
	(segment
		(start 254.4445 -319.81902)
		(end 255.882902 -316.413642)
		(width 0.1651)
		(layer "In5.Cu")
		(net "P5E_PEX2_STN7_RX_DP<117>")
	)
	(segment
		(start 272.594324 -341.625936)
		(end 256.048256 -325.528178)
		(width 0.1651)
		(layer "In5.Cu")
		(net "P5E_PEX2_STN7_RX_DP<117>")
	)
	(segment
		(start 263.336278 -306.816252)
		(end 265.925554 -305.733958)
		(width 0.1651)
		(layer "In5.Cu")
		(net "P5E_PEX2_STN7_RX_DP<117>")
	)
	(segment
		(start 255.882902 -316.413642)
		(end 260.334252 -309.857902)
		(width 0.1651)
		(layer "In5.Cu")
		(net "P5E_PEX2_STN7_RX_DP<117>")
	)
	(segment
		(start 255.420114 -324.609206)
		(end 254.4445 -322.299076)
		(width 0.1651)
		(layer "In5.Cu")
		(net "P5E_PEX2_STN7_RX_DP<117>")
	)
	(segment
		(start 297.245278 -393.516104)
		(end 286.32277 -387.70941)
		(width 0.1651)
		(layer "In5.Cu")
		(net "P5E_PEX2_STN7_RX_DP<117>")
	)
	(segment
		(start 299.33392 -395.42212)
		(end 298.895516 -394.607288)
		(width 0.1651)
		(layer "In5.Cu")
		(net "P5E_PEX2_STN7_RX_DP<117>")
	)
	(segment
		(start 299.047154 -409.799028)
		(end 299.33392 -409.512262)
		(width 0.1651)
		(layer "In5.Cu")
		(net "P5E_PEX2_STN7_RX_DP<117>")
	)
	(segment
		(start 299.33392 -409.512262)
		(end 299.33392 -395.42212)
		(width 0.1651)
		(layer "In5.Cu")
		(net "P5E_PEX2_STN7_RX_DP<117>")
	)
	(segment
		(start 269.734284 -306.349908)
		(end 269.999714 -306.349908)
		(width 0.1143)
		(layer "In5.Cu")
		(net "P5E_PEX2_STN7_RX_DP<117>")
	)
	(segment
		(start 260.334252 -309.857902)
		(end 263.336278 -306.816252)
		(width 0.1651)
		(layer "In5.Cu")
		(net "P5E_PEX2_STN7_RX_DP<117>")
	)
	(segment
		(start 272.851372 -342.378538)
		(end 272.594324 -341.625936)
		(width 0.1651)
		(layer "In5.Cu")
		(net "P5E_PEX2_STN7_RX_DP<117>")
	)
	(segment
		(start 267.866368 -305.779678)
		(end 269.394178 -305.779678)
		(width 0.1143)
		(layer "In5.Cu")
		(net "P5E_PEX2_STN7_RX_DP<117>")
	)
	(segment
		(start 269.619984 -306.005484)
		(end 269.619984 -306.235608)
		(width 0.1143)
		(layer "In5.Cu")
		(net "P5E_PEX2_STN7_RX_DP<117>")
	)
	(segment
		(start 284.256988 -384.936238)
		(end 283.89453 -378.812806)
		(width 0.1651)
		(layer "In5.Cu")
		(net "P5E_PEX2_STN7_RX_DP<117>")
	)
	(segment
		(start 272.851372 -357.900986)
		(end 272.851372 -342.378538)
		(width 0.1651)
		(layer "In5.Cu")
		(net "P5E_PEX2_STN7_RX_DP<117>")
	)
	(segment
		(start 298.895516 -394.607288)
		(end 297.245278 -393.516104)
		(width 0.1651)
		(layer "In5.Cu")
		(net "P5E_PEX2_STN7_RX_DP<117>")
	)
	(segment
		(start 298.489878 -409.290012)
		(end 298.489878 -409.672028)
		(width 0.1651)
		(layer "In5.Cu")
		(net "P5E_PEX2_STN7_RX_DP<117>")
	)
	(segment
		(start 273.097244 -358.592628)
		(end 272.851372 -357.900986)
		(width 0.1651)
		(layer "In5.Cu")
		(net "P5E_PEX2_STN7_RX_DP<117>")
	)
	(segment
		(start 282.413456 -370.030756)
		(end 273.097244 -358.592628)
		(width 0.1651)
		(layer "In5.Cu")
		(net "P5E_PEX2_STN7_RX_DP<117>")
	)
	(segment
		(start 267.7922 -305.733958)
		(end 267.820648 -305.733958)
		(width 0.1143)
		(layer "In5.Cu")
		(net "P5E_PEX2_STN7_RX_DP<117>")
	)
	(segment
		(start 256.048256 -325.528178)
		(end 255.420114 -324.609206)
		(width 0.1651)
		(layer "In5.Cu")
		(net "P5E_PEX2_STN7_RX_DP<117>")
	)
	(segment
		(start 284.823408 -386.291328)
		(end 284.256988 -384.936238)
		(width 0.1651)
		(layer "In5.Cu")
		(net "P5E_PEX2_STN7_RX_DP<117>")
	)
	(segment
		(start 283.89453 -378.812806)
		(end 283.238956 -371.68328)
		(width 0.1651)
		(layer "In5.Cu")
		(net "P5E_PEX2_STN7_RX_DP<117>")
	)
	(segment
		(start 269.619984 -306.235608)
		(end 269.734284 -306.349908)
		(width 0.1143)
		(layer "In5.Cu")
		(net "P5E_PEX2_STN7_RX_DP<117>")
	)
	(segment
		(start 265.925554 -305.733958)
		(end 267.7922 -305.733958)
		(width 0.1651)
		(layer "In5.Cu")
		(net "P5E_PEX2_STN7_RX_DP<117>")
	)
	(segment
		(start 283.238956 -371.68328)
		(end 282.413456 -370.030756)
		(width 0.1651)
		(layer "In5.Cu")
		(net "P5E_PEX2_STN7_RX_DP<117>")
	)
	(segment
		(start 254.4445 -322.299076)
		(end 254.4445 -319.81902)
		(width 0.1651)
		(layer "In5.Cu")
		(net "P5E_PEX2_STN7_RX_DP<117>")
	)
	(segment
		(start 286.32277 -387.70941)
		(end 284.823408 -386.291328)
		(width 0.1651)
		(layer "In5.Cu")
		(net "P5E_PEX2_STN7_RX_DP<117>")
	)
	(segment
		(start 416.235896 -30.6197)
		(end 416.065462 -30.790134)
		(width 0.13462)
		(layer "F.Cu")
		(net "P5E_PEX3_STN2_TX_C_DP<37>")
	)
	(segment
		(start 420.1414 -30.6197)
		(end 416.235896 -30.6197)
		(width 0.13462)
		(layer "F.Cu")
		(net "P5E_PEX3_STN2_TX_C_DP<37>")
	)
	(segment
		(start 420.46779 -30.94609)
		(end 420.1414 -30.6197)
		(width 0.13462)
		(layer "F.Cu")
		(net "P5E_PEX3_STN2_TX_C_DP<37>")
	)
	(segment
		(start 416.065462 -30.790134)
		(end 415.564828 -30.790134)
		(width 0.13462)
		(layer "F.Cu")
		(net "P5E_PEX3_STN2_TX_C_DP<37>")
	)
	(segment
		(start 425.40936 -351.317306)
		(end 425.703492 -351.611438)
		(width 0.13462)
		(layer "F.Cu")
		(net "P5E_PEX3_STN7_TX_C_DN<119>")
	)
	(segment
		(start 425.40936 -350.684846)
		(end 425.40936 -351.317306)
		(width 0.13462)
		(layer "F.Cu")
		(net "P5E_PEX3_STN7_TX_C_DN<119>")
	)
	(segment
		(start 425.728892 -350.365314)
		(end 425.40936 -350.684846)
		(width 0.13462)
		(layer "F.Cu")
		(net "P5E_PEX3_STN7_TX_C_DN<119>")
	)
	(segment
		(start 418.4142 -384.7846)
		(end 418.2872 -383.3622)
		(width 0.1651)
		(layer "In11.Cu")
		(net "P5E_PEX3_STN7_TX_C_DN<119>")
	)
	(segment
		(start 436.015892 -395.198092)
		(end 433.50688 -392.68908)
		(width 0.1651)
		(layer "In11.Cu")
		(net "P5E_PEX3_STN7_TX_C_DN<119>")
	)
	(segment
		(start 423.858182 -359.072942)
		(end 423.858182 -354.027486)
		(width 0.1651)
		(layer "In11.Cu")
		(net "P5E_PEX3_STN7_TX_C_DN<119>")
	)
	(segment
		(start 433.486306 -392.68908)
		(end 418.592 -385.2418)
		(width 0.1651)
		(layer "In11.Cu")
		(net "P5E_PEX3_STN7_TX_C_DN<119>")
	)
	(segment
		(start 434.88991 -402.790152)
		(end 434.88991 -402.408136)
		(width 0.1651)
		(layer "In11.Cu")
		(net "P5E_PEX3_STN7_TX_C_DN<119>")
	)
	(segment
		(start 433.50688 -392.68908)
		(end 433.486306 -392.68908)
		(width 0.1651)
		(layer "In11.Cu")
		(net "P5E_PEX3_STN7_TX_C_DN<119>")
	)
	(segment
		(start 435.564026 -402.281136)
		(end 436.015892 -401.82927)
		(width 0.1651)
		(layer "In11.Cu")
		(net "P5E_PEX3_STN7_TX_C_DN<119>")
	)
	(segment
		(start 423.858182 -354.027486)
		(end 425.412662 -352.473006)
		(width 0.1651)
		(layer "In11.Cu")
		(net "P5E_PEX3_STN7_TX_C_DN<119>")
	)
	(segment
		(start 418.2872 -383.3622)
		(end 418.438076 -369.309904)
		(width 0.1651)
		(layer "In11.Cu")
		(net "P5E_PEX3_STN7_TX_C_DN<119>")
	)
	(segment
		(start 425.412662 -351.902268)
		(end 425.703492 -351.611438)
		(width 0.1651)
		(layer "In11.Cu")
		(net "P5E_PEX3_STN7_TX_C_DN<119>")
	)
	(segment
		(start 434.88991 -402.408136)
		(end 435.01691 -402.281136)
		(width 0.1651)
		(layer "In11.Cu")
		(net "P5E_PEX3_STN7_TX_C_DN<119>")
	)
	(segment
		(start 436.015892 -401.82927)
		(end 436.015892 -395.198092)
		(width 0.1651)
		(layer "In11.Cu")
		(net "P5E_PEX3_STN7_TX_C_DN<119>")
	)
	(segment
		(start 418.438076 -369.309904)
		(end 423.858182 -359.072942)
		(width 0.1651)
		(layer "In11.Cu")
		(net "P5E_PEX3_STN7_TX_C_DN<119>")
	)
	(segment
		(start 418.592 -385.2418)
		(end 418.4142 -384.7846)
		(width 0.1651)
		(layer "In11.Cu")
		(net "P5E_PEX3_STN7_TX_C_DN<119>")
	)
	(segment
		(start 435.01691 -402.281136)
		(end 435.564026 -402.281136)
		(width 0.1651)
		(layer "In11.Cu")
		(net "P5E_PEX3_STN7_TX_C_DN<119>")
	)
	(segment
		(start 425.412662 -352.473006)
		(end 425.412662 -351.902268)
		(width 0.1651)
		(layer "In11.Cu")
		(net "P5E_PEX3_STN7_TX_C_DN<119>")
	)
	(segment
		(start 158.69031 -97.045018)
		(end 158.554928 -97.1804)
		(width 0.13208)
		(layer "F.Cu")
		(net "PRSNTB3_NIC2_N")
	)
	(segment
		(start 158.554928 -97.1804)
		(end 156.46781 -97.1804)
		(width 0.13208)
		(layer "F.Cu")
		(net "PRSNTB3_NIC2_N")
	)
	(segment
		(start 162.14217 -97.045018)
		(end 158.69031 -97.045018)
		(width 0.13208)
		(layer "F.Cu")
		(net "PRSNTB3_NIC2_N")
	)
	(segment
		(start 156.46781 -97.1804)
		(end 155.260294 -97.1804)
		(width 0.13208)
		(layer "F.Cu")
		(net "PRSNTB3_NIC2_N")
	)
	(segment
		(start 155.260294 -96.1644)
		(end 155.260294 -97.1804)
		(width 0.13208)
		(layer "F.Cu")
		(net "PRSNTB3_NIC2_N")
	)
	(via
		(at 156.46781 -97.1804)
		(size 0.762)
		(drill 0.381)
		(layers "F.Cu" "B.Cu")
		(net "PRSNTB3_NIC2_N")
	)
	(segment
		(start 79.425038 -133.807962)
		(end 79.752698 -133.480302)
		(width 0.13462)
		(layer "F.Cu")
		(net "P5E_PEX0_STN0_TX_C_DN<6>")
	)
	(segment
		(start 73.257664 -133.645148)
		(end 73.745852 -133.645148)
		(width 0.13462)
		(layer "F.Cu")
		(net "P5E_PEX0_STN0_TX_C_DN<6>")
	)
	(segment
		(start 73.908666 -133.807962)
		(end 79.425038 -133.807962)
		(width 0.13462)
		(layer "F.Cu")
		(net "P5E_PEX0_STN0_TX_C_DN<6>")
	)
	(segment
		(start 73.745852 -133.645148)
		(end 73.908666 -133.807962)
		(width 0.13462)
		(layer "F.Cu")
		(net "P5E_PEX0_STN0_TX_C_DN<6>")
	)
	(segment
		(start 277.739602 -134.165086)
		(end 278.242268 -134.165086)
		(width 0.13462)
		(layer "F.Cu")
		(net "P5E_PEX2_STN1_TX_C_DP<30>")
	)
	(segment
		(start 277.583138 -134.32155)
		(end 277.739602 -134.165086)
		(width 0.13462)
		(layer "F.Cu")
		(net "P5E_PEX2_STN1_TX_C_DP<30>")
	)
	(segment
		(start 269.105126 -134.008876)
		(end 269.4178 -134.32155)
		(width 0.13462)
		(layer "F.Cu")
		(net "P5E_PEX2_STN1_TX_C_DP<30>")
	)
	(segment
		(start 269.4178 -134.32155)
		(end 277.583138 -134.32155)
		(width 0.13462)
		(layer "F.Cu")
		(net "P5E_PEX2_STN1_TX_C_DP<30>")
	)
	(segment
		(start 264.114534 -302.883824)
		(end 267.7922 -302.883824)
		(width 0.1651)
		(layer "In5.Cu")
		(net "P5E_PEX2_STN7_RX_DP<114>")
	)
	(segment
		(start 267.820648 -302.883824)
		(end 267.866368 -302.929544)
		(width 0.1143)
		(layer "In5.Cu")
		(net "P5E_PEX2_STN7_RX_DP<114>")
	)
	(segment
		(start 290.91509 -393.674346)
		(end 290.476432 -393.44346)
		(width 0.1651)
		(layer "In5.Cu")
		(net "P5E_PEX2_STN7_RX_DP<114>")
	)
	(segment
		(start 251.52096 -318.502284)
		(end 256.170684 -308.057296)
		(width 0.1651)
		(layer "In5.Cu")
		(net "P5E_PEX2_STN7_RX_DP<114>")
	)
	(segment
		(start 289.39744 -392.875516)
		(end 289.349688 -392.721084)
		(width 0.1651)
		(layer "In5.Cu")
		(net "P5E_PEX2_STN7_RX_DP<114>")
	)
	(segment
		(start 279.688798 -371.48897)
		(end 268.415262 -360.004868)
		(width 0.1651)
		(layer "In5.Cu")
		(net "P5E_PEX2_STN7_RX_DP<114>")
	)
	(segment
		(start 281.281632 -385.481068)
		(end 280.916888 -378.928376)
		(width 0.1651)
		(layer "In5.Cu")
		(net "P5E_PEX2_STN7_RX_DP<114>")
	)
	(segment
		(start 258.74091 -336.123788)
		(end 253.265432 -327.194418)
		(width 0.1651)
		(layer "In5.Cu")
		(net "P5E_PEX2_STN7_RX_DP<114>")
	)
	(segment
		(start 292.032436 -394.13307)
		(end 291.069522 -393.62634)
		(width 0.1651)
		(layer "In5.Cu")
		(net "P5E_PEX2_STN7_RX_DP<114>")
	)
	(segment
		(start 267.7922 -302.883824)
		(end 267.820648 -302.883824)
		(width 0.1143)
		(layer "In5.Cu")
		(net "P5E_PEX2_STN7_RX_DP<114>")
	)
	(segment
		(start 289.99053 -393.058396)
		(end 289.836098 -393.106402)
		(width 0.1651)
		(layer "In5.Cu")
		(net "P5E_PEX2_STN7_RX_DP<114>")
	)
	(segment
		(start 268.415262 -360.004868)
		(end 258.74091 -336.123788)
		(width 0.1651)
		(layer "In5.Cu")
		(net "P5E_PEX2_STN7_RX_DP<114>")
	)
	(segment
		(start 291.889942 -408.190192)
		(end 291.889942 -408.572208)
		(width 0.1651)
		(layer "In5.Cu")
		(net "P5E_PEX2_STN7_RX_DP<114>")
	)
	(segment
		(start 290.476432 -393.44346)
		(end 290.42868 -393.289028)
		(width 0.1651)
		(layer "In5.Cu")
		(net "P5E_PEX2_STN7_RX_DP<114>")
	)
	(segment
		(start 292.447218 -408.699208)
		(end 292.733984 -408.412442)
		(width 0.1651)
		(layer "In5.Cu")
		(net "P5E_PEX2_STN7_RX_DP<114>")
	)
	(segment
		(start 271.634458 -303.499774)
		(end 271.899888 -303.499774)
		(width 0.1143)
		(layer "In5.Cu")
		(net "P5E_PEX2_STN7_RX_DP<114>")
	)
	(segment
		(start 290.42868 -393.289028)
		(end 289.99053 -393.058396)
		(width 0.1651)
		(layer "In5.Cu")
		(net "P5E_PEX2_STN7_RX_DP<114>")
	)
	(segment
		(start 282.334208 -388.031482)
		(end 281.281632 -385.481068)
		(width 0.1651)
		(layer "In5.Cu")
		(net "P5E_PEX2_STN7_RX_DP<114>")
	)
	(segment
		(start 256.170684 -308.057296)
		(end 259.385054 -304.84318)
		(width 0.1651)
		(layer "In5.Cu")
		(net "P5E_PEX2_STN7_RX_DP<114>")
	)
	(segment
		(start 267.866368 -302.929544)
		(end 271.294352 -302.929544)
		(width 0.1143)
		(layer "In5.Cu")
		(net "P5E_PEX2_STN7_RX_DP<114>")
	)
	(segment
		(start 289.349688 -392.721084)
		(end 284.82163 -390.33831)
		(width 0.1651)
		(layer "In5.Cu")
		(net "P5E_PEX2_STN7_RX_DP<114>")
	)
	(segment
		(start 292.733984 -408.412442)
		(end 292.733984 -394.833094)
		(width 0.1651)
		(layer "In5.Cu")
		(net "P5E_PEX2_STN7_RX_DP<114>")
	)
	(segment
		(start 271.294352 -302.929544)
		(end 271.520158 -303.15535)
		(width 0.1143)
		(layer "In5.Cu")
		(net "P5E_PEX2_STN7_RX_DP<114>")
	)
	(segment
		(start 271.520158 -303.15535)
		(end 271.520158 -303.385474)
		(width 0.1143)
		(layer "In5.Cu")
		(net "P5E_PEX2_STN7_RX_DP<114>")
	)
	(segment
		(start 271.520158 -303.385474)
		(end 271.634458 -303.499774)
		(width 0.1143)
		(layer "In5.Cu")
		(net "P5E_PEX2_STN7_RX_DP<114>")
	)
	(segment
		(start 292.733984 -394.833094)
		(end 292.032436 -394.13307)
		(width 0.1651)
		(layer "In5.Cu")
		(net "P5E_PEX2_STN7_RX_DP<114>")
	)
	(segment
		(start 291.889942 -408.572208)
		(end 292.016942 -408.699208)
		(width 0.1651)
		(layer "In5.Cu")
		(net "P5E_PEX2_STN7_RX_DP<114>")
	)
	(segment
		(start 284.82163 -390.33831)
		(end 282.334208 -388.031482)
		(width 0.1651)
		(layer "In5.Cu")
		(net "P5E_PEX2_STN7_RX_DP<114>")
	)
	(segment
		(start 280.916888 -378.928376)
		(end 280.336498 -372.852188)
		(width 0.1651)
		(layer "In5.Cu")
		(net "P5E_PEX2_STN7_RX_DP<114>")
	)
	(segment
		(start 251.52096 -323.013832)
		(end 251.52096 -318.502284)
		(width 0.1651)
		(layer "In5.Cu")
		(net "P5E_PEX2_STN7_RX_DP<114>")
	)
	(segment
		(start 280.336498 -372.852188)
		(end 279.688798 -371.48897)
		(width 0.1651)
		(layer "In5.Cu")
		(net "P5E_PEX2_STN7_RX_DP<114>")
	)
	(segment
		(start 291.069522 -393.62634)
		(end 290.91509 -393.674346)
		(width 0.1651)
		(layer "In5.Cu")
		(net "P5E_PEX2_STN7_RX_DP<114>")
	)
	(segment
		(start 289.836098 -393.106402)
		(end 289.39744 -392.875516)
		(width 0.1651)
		(layer "In5.Cu")
		(net "P5E_PEX2_STN7_RX_DP<114>")
	)
	(segment
		(start 259.385054 -304.84318)
		(end 264.114534 -302.883824)
		(width 0.1651)
		(layer "In5.Cu")
		(net "P5E_PEX2_STN7_RX_DP<114>")
	)
	(segment
		(start 253.265432 -327.194418)
		(end 251.52096 -323.013832)
		(width 0.1651)
		(layer "In5.Cu")
		(net "P5E_PEX2_STN7_RX_DP<114>")
	)
	(segment
		(start 292.016942 -408.699208)
		(end 292.447218 -408.699208)
		(width 0.1651)
		(layer "In5.Cu")
		(net "P5E_PEX2_STN7_RX_DP<114>")
	)
	(segment
		(start 358.482392 -30.790134)
		(end 358.319578 -30.62732)
		(width 0.13462)
		(layer "F.Cu")
		(net "P5E_PEX3_STN2_RX_DP<45>")
	)
	(segment
		(start 358.319578 -30.62732)
		(end 355.80574 -30.62732)
		(width 0.13462)
		(layer "F.Cu")
		(net "P5E_PEX3_STN2_RX_DP<45>")
	)
	(segment
		(start 355.80574 -30.62732)
		(end 355.510592 -30.922468)
		(width 0.13462)
		(layer "F.Cu")
		(net "P5E_PEX3_STN2_RX_DP<45>")
	)
	(segment
		(start 358.964992 -30.790134)
		(end 358.482392 -30.790134)
		(width 0.13462)
		(layer "F.Cu")
		(net "P5E_PEX3_STN2_RX_DP<45>")
	)
	(segment
		(start 360.366564 -61.48832)
		(end 360.366564 -60.146692)
		(width 0.1651)
		(layer "In7.Cu")
		(net "P5E_PEX3_STN2_RX_DP<45>")
	)
	(segment
		(start 358.917748 -40.277288)
		(end 358.880918 -37.940234)
		(width 0.1651)
		(layer "In7.Cu")
		(net "P5E_PEX3_STN2_RX_DP<45>")
	)
	(segment
		(start 357.97236 -30.631638)
		(end 357.47706 -30.631638)
		(width 0.1651)
		(layer "In7.Cu")
		(net "P5E_PEX3_STN2_RX_DP<45>")
	)
	(segment
		(start 358.880918 -37.940234)
		(end 359.40619 -34.981642)
		(width 0.1651)
		(layer "In7.Cu")
		(net "P5E_PEX3_STN2_RX_DP<45>")
	)
	(segment
		(start 394.03401 -271.3736)
		(end 394.03401 -271.345152)
		(width 0.1143)
		(layer "In7.Cu")
		(net "P5E_PEX3_STN2_RX_DP<45>")
	)
	(segment
		(start 356.77856 -30.631638)
		(end 355.801422 -30.631638)
		(width 0.1651)
		(layer "In7.Cu")
		(net "P5E_PEX3_STN2_RX_DP<45>")
	)
	(segment
		(start 358.490266 -31.149544)
		(end 357.97236 -30.631638)
		(width 0.1651)
		(layer "In7.Cu")
		(net "P5E_PEX3_STN2_RX_DP<45>")
	)
	(segment
		(start 365.377476 -102.513892)
		(end 365.365538 -102.474522)
		(width 0.1651)
		(layer "In7.Cu")
		(net "P5E_PEX3_STN2_RX_DP<45>")
	)
	(segment
		(start 394.64996 -273.784314)
		(end 394.53566 -273.670014)
		(width 0.1143)
		(layer "In7.Cu")
		(net "P5E_PEX3_STN2_RX_DP<45>")
	)
	(segment
		(start 358.490266 -31.293054)
		(end 358.490266 -31.149544)
		(width 0.1651)
		(layer "In7.Cu")
		(net "P5E_PEX3_STN2_RX_DP<45>")
	)
	(segment
		(start 394.64996 -274.049744)
		(end 394.64996 -273.784314)
		(width 0.1143)
		(layer "In7.Cu")
		(net "P5E_PEX3_STN2_RX_DP<45>")
	)
	(segment
		(start 393.148566 -255.658366)
		(end 391.55116 -238.208566)
		(width 0.1651)
		(layer "In7.Cu")
		(net "P5E_PEX3_STN2_RX_DP<45>")
	)
	(segment
		(start 357.47706 -30.631638)
		(end 357.37546 -30.733238)
		(width 0.1651)
		(layer "In7.Cu")
		(net "P5E_PEX3_STN2_RX_DP<45>")
	)
	(segment
		(start 394.07973 -273.407632)
		(end 394.07973 -271.41932)
		(width 0.1143)
		(layer "In7.Cu")
		(net "P5E_PEX3_STN2_RX_DP<45>")
	)
	(segment
		(start 359.40619 -34.981642)
		(end 359.429558 -32.088836)
		(width 0.1651)
		(layer "In7.Cu")
		(net "P5E_PEX3_STN2_RX_DP<45>")
	)
	(segment
		(start 358.984296 -31.643574)
		(end 358.840786 -31.643574)
		(width 0.1651)
		(layer "In7.Cu")
		(net "P5E_PEX3_STN2_RX_DP<45>")
	)
	(segment
		(start 360.175556 -85.352382)
		(end 360.366564 -61.48832)
		(width 0.1651)
		(layer "In7.Cu")
		(net "P5E_PEX3_STN2_RX_DP<45>")
	)
	(segment
		(start 394.07973 -271.41932)
		(end 394.03401 -271.3736)
		(width 0.1143)
		(layer "In7.Cu")
		(net "P5E_PEX3_STN2_RX_DP<45>")
	)
	(segment
		(start 360.098848 -57.373774)
		(end 360.215942 -49.884838)
		(width 0.1651)
		(layer "In7.Cu")
		(net "P5E_PEX3_STN2_RX_DP<45>")
	)
	(segment
		(start 365.365538 -102.474522)
		(end 365.365538 -102.474014)
		(width 0.1651)
		(layer "In7.Cu")
		(net "P5E_PEX3_STN2_RX_DP<45>")
	)
	(segment
		(start 365.365538 -102.474014)
		(end 360.175556 -85.352382)
		(width 0.1651)
		(layer "In7.Cu")
		(net "P5E_PEX3_STN2_RX_DP<45>")
	)
	(segment
		(start 394.342112 -273.670014)
		(end 394.07973 -273.407632)
		(width 0.1143)
		(layer "In7.Cu")
		(net "P5E_PEX3_STN2_RX_DP<45>")
	)
	(segment
		(start 394.03401 -271.345152)
		(end 394.03401 -270.305276)
		(width 0.1651)
		(layer "In7.Cu")
		(net "P5E_PEX3_STN2_RX_DP<45>")
	)
	(segment
		(start 360.215942 -49.884838)
		(end 358.917748 -40.277288)
		(width 0.1651)
		(layer "In7.Cu")
		(net "P5E_PEX3_STN2_RX_DP<45>")
	)
	(segment
		(start 394.03401 -270.305276)
		(end 393.071604 -263.52119)
		(width 0.1651)
		(layer "In7.Cu")
		(net "P5E_PEX3_STN2_RX_DP<45>")
	)
	(segment
		(start 365.37773 -102.514654)
		(end 365.377476 -102.513892)
		(width 0.1651)
		(layer "In7.Cu")
		(net "P5E_PEX3_STN2_RX_DP<45>")
	)
	(segment
		(start 360.366564 -60.146692)
		(end 360.098848 -57.373774)
		(width 0.1651)
		(layer "In7.Cu")
		(net "P5E_PEX3_STN2_RX_DP<45>")
	)
	(segment
		(start 373.840248 -144.549876)
		(end 370.560092 -119.612156)
		(width 0.1651)
		(layer "In7.Cu")
		(net "P5E_PEX3_STN2_RX_DP<45>")
	)
	(segment
		(start 359.429558 -32.088836)
		(end 358.984296 -31.643574)
		(width 0.1651)
		(layer "In7.Cu")
		(net "P5E_PEX3_STN2_RX_DP<45>")
	)
	(segment
		(start 394.53566 -273.670014)
		(end 394.342112 -273.670014)
		(width 0.1143)
		(layer "In7.Cu")
		(net "P5E_PEX3_STN2_RX_DP<45>")
	)
	(segment
		(start 355.801422 -30.631638)
		(end 355.510592 -30.922468)
		(width 0.1651)
		(layer "In7.Cu")
		(net "P5E_PEX3_STN2_RX_DP<45>")
	)
	(segment
		(start 393.071604 -263.52119)
		(end 393.148566 -255.658366)
		(width 0.1651)
		(layer "In7.Cu")
		(net "P5E_PEX3_STN2_RX_DP<45>")
	)
	(segment
		(start 357.37546 -30.733238)
		(end 356.88016 -30.733238)
		(width 0.1651)
		(layer "In7.Cu")
		(net "P5E_PEX3_STN2_RX_DP<45>")
	)
	(segment
		(start 391.55116 -238.208566)
		(end 373.840248 -144.549876)
		(width 0.1651)
		(layer "In7.Cu")
		(net "P5E_PEX3_STN2_RX_DP<45>")
	)
	(segment
		(start 358.840786 -31.643574)
		(end 358.490266 -31.293054)
		(width 0.1651)
		(layer "In7.Cu")
		(net "P5E_PEX3_STN2_RX_DP<45>")
	)
	(segment
		(start 356.88016 -30.733238)
		(end 356.77856 -30.631638)
		(width 0.1651)
		(layer "In7.Cu")
		(net "P5E_PEX3_STN2_RX_DP<45>")
	)
	(segment
		(start 370.560092 -119.612156)
		(end 365.37773 -102.514654)
		(width 0.1651)
		(layer "In7.Cu")
		(net "P5E_PEX3_STN2_RX_DP<45>")
	)
	(segment
		(start 436.294022 -341.57793)
		(end 436.09133 -341.285068)
		(width 0.1651)
		(layer "In9.Cu")
		(net "P5E_PEX3_STN7_RX_DN<124>")
	)
	(segment
		(start 387.62051 -319.819528)
		(end 387.62051 -316.585092)
		(width 0.1143)
		(layer "In9.Cu")
		(net "P5E_PEX3_STN7_RX_DN<124>")
	)
	(segment
		(start 428.289974 -383.107946)
		(end 428.416974 -382.980946)
		(width 0.1651)
		(layer "In9.Cu")
		(net "P5E_PEX3_STN7_RX_DN<124>")
	)
	(segment
		(start 387.91134 -316.419992)
		(end 388.00024 -316.508892)
		(width 0.1143)
		(layer "In9.Cu")
		(net "P5E_PEX3_STN7_RX_DN<124>")
	)
	(segment
		(start 387.78561 -316.419992)
		(end 387.91134 -316.419992)
		(width 0.1143)
		(layer "In9.Cu")
		(net "P5E_PEX3_STN7_RX_DN<124>")
	)
	(segment
		(start 389.490966 -323.622162)
		(end 388.291324 -322.759832)
		(width 0.1651)
		(layer "In9.Cu")
		(net "P5E_PEX3_STN7_RX_DN<124>")
	)
	(segment
		(start 392.45667 -324.560946)
		(end 389.490966 -323.622162)
		(width 0.1651)
		(layer "In9.Cu")
		(net "P5E_PEX3_STN7_RX_DN<124>")
	)
	(segment
		(start 429.446944 -382.289812)
		(end 429.446944 -368.81054)
		(width 0.1651)
		(layer "In9.Cu")
		(net "P5E_PEX3_STN7_RX_DN<124>")
	)
	(segment
		(start 428.75581 -382.980946)
		(end 429.446944 -382.289812)
		(width 0.1651)
		(layer "In9.Cu")
		(net "P5E_PEX3_STN7_RX_DN<124>")
	)
	(segment
		(start 393.098528 -324.764146)
		(end 393.040616 -324.652386)
		(width 0.1651)
		(layer "In9.Cu")
		(net "P5E_PEX3_STN7_RX_DN<124>")
	)
	(segment
		(start 387.66623 -321.250564)
		(end 387.66623 -319.893696)
		(width 0.1651)
		(layer "In9.Cu")
		(net "P5E_PEX3_STN7_RX_DN<124>")
	)
	(segment
		(start 436.294022 -358.504236)
		(end 436.294022 -341.57793)
		(width 0.1651)
		(layer "In9.Cu")
		(net "P5E_PEX3_STN7_RX_DN<124>")
	)
	(segment
		(start 387.66623 -319.893696)
		(end 387.66623 -319.865248)
		(width 0.1143)
		(layer "In9.Cu")
		(net "P5E_PEX3_STN7_RX_DN<124>")
	)
	(segment
		(start 388.291324 -322.759832)
		(end 387.66623 -321.250564)
		(width 0.1651)
		(layer "In9.Cu")
		(net "P5E_PEX3_STN7_RX_DN<124>")
	)
	(segment
		(start 387.62051 -316.585092)
		(end 387.78561 -316.419992)
		(width 0.1143)
		(layer "In9.Cu")
		(net "P5E_PEX3_STN7_RX_DN<124>")
	)
	(segment
		(start 429.446944 -368.81054)
		(end 436.294022 -358.504236)
		(width 0.1651)
		(layer "In9.Cu")
		(net "P5E_PEX3_STN7_RX_DN<124>")
	)
	(segment
		(start 421.459406 -335.805526)
		(end 408.126438 -329.521058)
		(width 0.1651)
		(layer "In9.Cu")
		(net "P5E_PEX3_STN7_RX_DN<124>")
	)
	(segment
		(start 428.289974 -383.490216)
		(end 428.289974 -383.107946)
		(width 0.1651)
		(layer "In9.Cu")
		(net "P5E_PEX3_STN7_RX_DN<124>")
	)
	(segment
		(start 393.040616 -324.652386)
		(end 392.568176 -324.503034)
		(width 0.1651)
		(layer "In9.Cu")
		(net "P5E_PEX3_STN7_RX_DN<124>")
	)
	(segment
		(start 436.09133 -341.285068)
		(end 421.459406 -335.805526)
		(width 0.1651)
		(layer "In9.Cu")
		(net "P5E_PEX3_STN7_RX_DN<124>")
	)
	(segment
		(start 388.00024 -316.799468)
		(end 387.999986 -316.799722)
		(width 0.1143)
		(layer "In9.Cu")
		(net "P5E_PEX3_STN7_RX_DN<124>")
	)
	(segment
		(start 428.416974 -382.980946)
		(end 428.75581 -382.980946)
		(width 0.1651)
		(layer "In9.Cu")
		(net "P5E_PEX3_STN7_RX_DN<124>")
	)
	(segment
		(start 387.66623 -319.865248)
		(end 387.62051 -319.819528)
		(width 0.1143)
		(layer "In9.Cu")
		(net "P5E_PEX3_STN7_RX_DN<124>")
	)
	(segment
		(start 408.126438 -329.521058)
		(end 393.098528 -324.764146)
		(width 0.1651)
		(layer "In9.Cu")
		(net "P5E_PEX3_STN7_RX_DN<124>")
	)
	(segment
		(start 388.00024 -316.508892)
		(end 388.00024 -316.799468)
		(width 0.1143)
		(layer "In9.Cu")
		(net "P5E_PEX3_STN7_RX_DN<124>")
	)
	(segment
		(start 392.568176 -324.503034)
		(end 392.45667 -324.560946)
		(width 0.1651)
		(layer "In9.Cu")
		(net "P5E_PEX3_STN7_RX_DN<124>")
	)
	(segment
		(start 155.657042 -159.4104)
		(end 155.107894 -159.4104)
		(width 0.13208)
		(layer "F.Cu")
		(net "NIC2_MAIN_PWR_EN_R")
	)
	(segment
		(start 160.723834 -157.759908)
		(end 158.238698 -160.245044)
		(width 0.13208)
		(layer "F.Cu")
		(net "NIC2_MAIN_PWR_EN_R")
	)
	(segment
		(start 162.14217 -157.759908)
		(end 160.723834 -157.759908)
		(width 0.13208)
		(layer "F.Cu")
		(net "NIC2_MAIN_PWR_EN_R")
	)
	(segment
		(start 156.491686 -160.245044)
		(end 155.657042 -159.4104)
		(width 0.13208)
		(layer "F.Cu")
		(net "NIC2_MAIN_PWR_EN_R")
	)
	(segment
		(start 158.238698 -160.245044)
		(end 156.491686 -160.245044)
		(width 0.13208)
		(layer "F.Cu")
		(net "NIC2_MAIN_PWR_EN_R")
	)
	(via
		(at 156.491686 -160.245044)
		(size 0.762)
		(drill 0.381)
		(layers "F.Cu" "B.Cu")
		(net "NIC2_MAIN_PWR_EN_R")
	)
	(segment
		(start 65.498218 -144.71777)
		(end 65.49771 -144.718278)
		(width 0.13462)
		(layer "F.Cu")
		(net "P5E_PEX0_STN0_RX_DN<9>")
	)
	(segment
		(start 65.49771 -144.718278)
		(end 65.20307 -144.423638)
		(width 0.13462)
		(layer "F.Cu")
		(net "P5E_PEX0_STN0_RX_DN<9>")
	)
	(segment
		(start 68.006722 -144.71777)
		(end 65.498218 -144.71777)
		(width 0.13462)
		(layer "F.Cu")
		(net "P5E_PEX0_STN0_RX_DN<9>")
	)
	(segment
		(start 68.65747 -144.554956)
		(end 68.169536 -144.554956)
		(width 0.13462)
		(layer "F.Cu")
		(net "P5E_PEX0_STN0_RX_DN<9>")
	)
	(segment
		(start 68.169536 -144.554956)
		(end 68.006722 -144.71777)
		(width 0.13462)
		(layer "F.Cu")
		(net "P5E_PEX0_STN0_RX_DN<9>")
	)
	(segment
		(start 77.124814 -160.116012)
		(end 77.124814 -160.115758)
		(width 0.1651)
		(layer "In5.Cu")
		(net "P5E_PEX0_STN0_RX_DN<9>")
	)
	(segment
		(start 80.273398 -273.479514)
		(end 80.435196 -273.479514)
		(width 0.1143)
		(layer "In5.Cu")
		(net "P5E_PEX0_STN0_RX_DN<9>")
	)
	(segment
		(start 80.21574 -271.225518)
		(end 80.21574 -271.773904)
		(width 0.1651)
		(layer "In5.Cu")
		(net "P5E_PEX0_STN0_RX_DN<9>")
	)
	(segment
		(start 65.20307 -144.423638)
		(end 65.4939 -144.714468)
		(width 0.1651)
		(layer "In5.Cu")
		(net "P5E_PEX0_STN0_RX_DN<9>")
	)
	(segment
		(start 73.081642 -152.48255)
		(end 75.838558 -155.292806)
		(width 0.1651)
		(layer "In5.Cu")
		(net "P5E_PEX0_STN0_RX_DN<9>")
	)
	(segment
		(start 80.79994 -268.288008)
		(end 80.21574 -271.225518)
		(width 0.1651)
		(layer "In5.Cu")
		(net "P5E_PEX0_STN0_RX_DN<9>")
	)
	(segment
		(start 70.39356 -147.418806)
		(end 72.335898 -150.41118)
		(width 0.1651)
		(layer "In5.Cu")
		(net "P5E_PEX0_STN0_RX_DN<9>")
	)
	(segment
		(start 80.435196 -273.479514)
		(end 80.549496 -273.365214)
		(width 0.1143)
		(layer "In5.Cu")
		(net "P5E_PEX0_STN0_RX_DN<9>")
	)
	(segment
		(start 67.224148 -144.714468)
		(end 68.078604 -145.071846)
		(width 0.1651)
		(layer "In5.Cu")
		(net "P5E_PEX0_STN0_RX_DN<9>")
	)
	(segment
		(start 80.17002 -271.848072)
		(end 80.17002 -273.376136)
		(width 0.1143)
		(layer "In5.Cu")
		(net "P5E_PEX0_STN0_RX_DN<9>")
	)
	(segment
		(start 77.124814 -160.115758)
		(end 77.21727 -160.462976)
		(width 0.1651)
		(layer "In5.Cu")
		(net "P5E_PEX0_STN0_RX_DN<9>")
	)
	(segment
		(start 80.21574 -271.802352)
		(end 80.17002 -271.848072)
		(width 0.1143)
		(layer "In5.Cu")
		(net "P5E_PEX0_STN0_RX_DN<9>")
	)
	(segment
		(start 80.21574 -271.773904)
		(end 80.21574 -271.802352)
		(width 0.1143)
		(layer "In5.Cu")
		(net "P5E_PEX0_STN0_RX_DN<9>")
	)
	(segment
		(start 80.549496 -273.365214)
		(end 80.549496 -273.099784)
		(width 0.1143)
		(layer "In5.Cu")
		(net "P5E_PEX0_STN0_RX_DN<9>")
	)
	(segment
		(start 80.17002 -273.376136)
		(end 80.273398 -273.479514)
		(width 0.1143)
		(layer "In5.Cu")
		(net "P5E_PEX0_STN0_RX_DN<9>")
	)
	(segment
		(start 80.79994 -261.973314)
		(end 80.79994 -268.288008)
		(width 0.1651)
		(layer "In5.Cu")
		(net "P5E_PEX0_STN0_RX_DN<9>")
	)
	(segment
		(start 68.078604 -145.071846)
		(end 70.39356 -147.418806)
		(width 0.1651)
		(layer "In5.Cu")
		(net "P5E_PEX0_STN0_RX_DN<9>")
	)
	(segment
		(start 77.21727 -160.462976)
		(end 80.79994 -261.973314)
		(width 0.1651)
		(layer "In5.Cu")
		(net "P5E_PEX0_STN0_RX_DN<9>")
	)
	(segment
		(start 72.335898 -150.41118)
		(end 73.081642 -152.48255)
		(width 0.1651)
		(layer "In5.Cu")
		(net "P5E_PEX0_STN0_RX_DN<9>")
	)
	(segment
		(start 75.838558 -155.292806)
		(end 77.124814 -160.116012)
		(width 0.1651)
		(layer "In5.Cu")
		(net "P5E_PEX0_STN0_RX_DN<9>")
	)
	(segment
		(start 65.4939 -144.714468)
		(end 67.224148 -144.714468)
		(width 0.1651)
		(layer "In5.Cu")
		(net "P5E_PEX0_STN0_RX_DN<9>")
	)
	(segment
		(start 277.735538 -103.644954)
		(end 278.242268 -103.644954)
		(width 0.13462)
		(layer "F.Cu")
		(net "P5E_PEX2_STN1_TX_C_DN<18>")
	)
	(segment
		(start 277.570184 -103.4796)
		(end 277.735538 -103.644954)
		(width 0.13462)
		(layer "F.Cu")
		(net "P5E_PEX2_STN1_TX_C_DN<18>")
	)
	(segment
		(start 271.747234 -103.803196)
		(end 272.07083 -103.4796)
		(width 0.13462)
		(layer "F.Cu")
		(net "P5E_PEX2_STN1_TX_C_DN<18>")
	)
	(segment
		(start 272.07083 -103.4796)
		(end 277.570184 -103.4796)
		(width 0.13462)
		(layer "F.Cu")
		(net "P5E_PEX2_STN1_TX_C_DN<18>")
	)
	(segment
		(start 280.627582 -351.316798)
		(end 280.332942 -351.611438)
		(width 0.13462)
		(layer "F.Cu")
		(net "P5E_PEX2_STN7_TX_C_DP<118>")
	)
	(segment
		(start 280.627582 -350.685354)
		(end 280.627582 -351.316798)
		(width 0.13462)
		(layer "F.Cu")
		(net "P5E_PEX2_STN7_TX_C_DP<118>")
	)
	(segment
		(start 280.307542 -350.365314)
		(end 280.627582 -350.685354)
		(width 0.13462)
		(layer "F.Cu")
		(net "P5E_PEX2_STN7_TX_C_DP<118>")
	)
	(segment
		(start 286.56661 -386.692902)
		(end 285.773876 -385.818126)
		(width 0.1651)
		(layer "In7.Cu")
		(net "P5E_PEX2_STN7_TX_C_DP<118>")
	)
	(segment
		(start 300.689772 -400.390106)
		(end 300.689772 -400.772122)
		(width 0.1651)
		(layer "In7.Cu")
		(net "P5E_PEX2_STN7_TX_C_DP<118>")
	)
	(segment
		(start 300.525434 -393.9413)
		(end 300.047152 -393.625578)
		(width 0.1651)
		(layer "In7.Cu")
		(net "P5E_PEX2_STN7_TX_C_DP<118>")
	)
	(segment
		(start 297.534584 -391.966704)
		(end 297.121326 -391.693908)
		(width 0.1651)
		(layer "In7.Cu")
		(net "P5E_PEX2_STN7_TX_C_DP<118>")
	)
	(segment
		(start 299.48505 -393.254484)
		(end 299.071792 -392.981688)
		(width 0.1651)
		(layer "In7.Cu")
		(net "P5E_PEX2_STN7_TX_C_DP<118>")
	)
	(segment
		(start 283.467302 -373.66956)
		(end 279.069292 -358.434132)
		(width 0.1651)
		(layer "In7.Cu")
		(net "P5E_PEX2_STN7_TX_C_DP<118>")
	)
	(segment
		(start 296.584624 -391.446004)
		(end 296.559224 -391.322814)
		(width 0.1651)
		(layer "In7.Cu")
		(net "P5E_PEX2_STN7_TX_C_DP<118>")
	)
	(segment
		(start 280.623772 -352.356166)
		(end 280.623772 -351.902268)
		(width 0.1651)
		(layer "In7.Cu")
		(net "P5E_PEX2_STN7_TX_C_DP<118>")
	)
	(segment
		(start 301.533814 -395.190218)
		(end 301.35957 -394.771372)
		(width 0.1651)
		(layer "In7.Cu")
		(net "P5E_PEX2_STN7_TX_C_DP<118>")
	)
	(segment
		(start 298.53509 -392.733784)
		(end 298.509944 -392.610594)
		(width 0.1651)
		(layer "In7.Cu")
		(net "P5E_PEX2_STN7_TX_C_DP<118>")
	)
	(segment
		(start 297.973496 -392.363198)
		(end 297.559984 -392.089894)
		(width 0.1651)
		(layer "In7.Cu")
		(net "P5E_PEX2_STN7_TX_C_DP<118>")
	)
	(segment
		(start 300.047152 -393.625578)
		(end 299.923962 -393.650724)
		(width 0.1651)
		(layer "In7.Cu")
		(net "P5E_PEX2_STN7_TX_C_DP<118>")
	)
	(segment
		(start 297.559984 -392.089894)
		(end 297.534584 -391.966704)
		(width 0.1651)
		(layer "In7.Cu")
		(net "P5E_PEX2_STN7_TX_C_DP<118>")
	)
	(segment
		(start 299.071792 -392.981688)
		(end 298.948602 -393.006834)
		(width 0.1651)
		(layer "In7.Cu")
		(net "P5E_PEX2_STN7_TX_C_DP<118>")
	)
	(segment
		(start 301.533814 -400.612356)
		(end 301.533814 -395.190218)
		(width 0.1651)
		(layer "In7.Cu")
		(net "P5E_PEX2_STN7_TX_C_DP<118>")
	)
	(segment
		(start 285.773876 -385.818126)
		(end 285.17342 -384.644138)
		(width 0.1651)
		(layer "In7.Cu")
		(net "P5E_PEX2_STN7_TX_C_DP<118>")
	)
	(segment
		(start 299.923962 -393.650724)
		(end 299.51045 -393.377674)
		(width 0.1651)
		(layer "In7.Cu")
		(net "P5E_PEX2_STN7_TX_C_DP<118>")
	)
	(segment
		(start 297.121326 -391.693908)
		(end 296.998136 -391.719308)
		(width 0.1651)
		(layer "In7.Cu")
		(net "P5E_PEX2_STN7_TX_C_DP<118>")
	)
	(segment
		(start 298.948602 -393.006834)
		(end 298.53509 -392.733784)
		(width 0.1651)
		(layer "In7.Cu")
		(net "P5E_PEX2_STN7_TX_C_DP<118>")
	)
	(segment
		(start 300.816772 -400.899122)
		(end 301.247048 -400.899122)
		(width 0.1651)
		(layer "In7.Cu")
		(net "P5E_PEX2_STN7_TX_C_DP<118>")
	)
	(segment
		(start 301.35957 -394.771372)
		(end 300.525434 -393.9413)
		(width 0.1651)
		(layer "In7.Cu")
		(net "P5E_PEX2_STN7_TX_C_DP<118>")
	)
	(segment
		(start 298.096686 -392.337798)
		(end 297.973496 -392.363198)
		(width 0.1651)
		(layer "In7.Cu")
		(net "P5E_PEX2_STN7_TX_C_DP<118>")
	)
	(segment
		(start 279.069292 -353.910646)
		(end 280.623772 -352.356166)
		(width 0.1651)
		(layer "In7.Cu")
		(net "P5E_PEX2_STN7_TX_C_DP<118>")
	)
	(segment
		(start 295.419272 -390.570466)
		(end 286.56661 -386.692902)
		(width 0.1651)
		(layer "In7.Cu")
		(net "P5E_PEX2_STN7_TX_C_DP<118>")
	)
	(segment
		(start 300.689772 -400.772122)
		(end 300.816772 -400.899122)
		(width 0.1651)
		(layer "In7.Cu")
		(net "P5E_PEX2_STN7_TX_C_DP<118>")
	)
	(segment
		(start 296.998136 -391.719308)
		(end 296.584624 -391.446004)
		(width 0.1651)
		(layer "In7.Cu")
		(net "P5E_PEX2_STN7_TX_C_DP<118>")
	)
	(segment
		(start 285.17342 -384.644138)
		(end 283.467302 -373.66956)
		(width 0.1651)
		(layer "In7.Cu")
		(net "P5E_PEX2_STN7_TX_C_DP<118>")
	)
	(segment
		(start 296.559224 -391.322814)
		(end 295.419272 -390.570466)
		(width 0.1651)
		(layer "In7.Cu")
		(net "P5E_PEX2_STN7_TX_C_DP<118>")
	)
	(segment
		(start 299.51045 -393.377674)
		(end 299.48505 -393.254484)
		(width 0.1651)
		(layer "In7.Cu")
		(net "P5E_PEX2_STN7_TX_C_DP<118>")
	)
	(segment
		(start 280.623772 -351.902268)
		(end 280.332942 -351.611438)
		(width 0.1651)
		(layer "In7.Cu")
		(net "P5E_PEX2_STN7_TX_C_DP<118>")
	)
	(segment
		(start 279.069292 -358.434132)
		(end 279.069292 -353.910646)
		(width 0.1651)
		(layer "In7.Cu")
		(net "P5E_PEX2_STN7_TX_C_DP<118>")
	)
	(segment
		(start 301.247048 -400.899122)
		(end 301.533814 -400.612356)
		(width 0.1651)
		(layer "In7.Cu")
		(net "P5E_PEX2_STN7_TX_C_DP<118>")
	)
	(segment
		(start 298.509944 -392.610594)
		(end 298.096686 -392.337798)
		(width 0.1651)
		(layer "In7.Cu")
		(net "P5E_PEX2_STN7_TX_C_DP<118>")
	)
	(segment
		(start 436.330344 -33.9471)
		(end 433.798726 -33.9471)
		(width 0.13462)
		(layer "F.Cu")
		(net "P5E_PEX3_STN2_RX_DN<35>")
	)
	(segment
		(start 433.798726 -33.9471)
		(end 433.510436 -33.65881)
		(width 0.13462)
		(layer "F.Cu")
		(net "P5E_PEX3_STN2_RX_DN<35>")
	)
	(segment
		(start 436.487316 -33.790128)
		(end 436.330344 -33.9471)
		(width 0.13462)
		(layer "F.Cu")
		(net "P5E_PEX3_STN2_RX_DN<35>")
	)
	(segment
		(start 436.964836 -33.790128)
		(end 436.487316 -33.790128)
		(width 0.13462)
		(layer "F.Cu")
		(net "P5E_PEX3_STN2_RX_DN<35>")
	)
	(segment
		(start 435.232048 -39.583614)
		(end 435.160928 -34.714688)
		(width 0.1651)
		(layer "In7.Cu")
		(net "P5E_PEX3_STN2_RX_DN<35>")
	)
	(segment
		(start 403.770084 -273.328638)
		(end 403.770084 -271.41932)
		(width 0.1143)
		(layer "In7.Cu")
		(net "P5E_PEX3_STN2_RX_DN<35>")
	)
	(segment
		(start 404.149814 -273.099784)
		(end 404.149814 -273.365214)
		(width 0.1143)
		(layer "In7.Cu")
		(net "P5E_PEX3_STN2_RX_DN<35>")
	)
	(segment
		(start 425.402756 -116.50345)
		(end 436.389018 -61.12764)
		(width 0.1651)
		(layer "In7.Cu")
		(net "P5E_PEX3_STN2_RX_DN<35>")
	)
	(segment
		(start 403.815804 -271.3736)
		(end 403.815804 -271.345152)
		(width 0.1143)
		(layer "In7.Cu")
		(net "P5E_PEX3_STN2_RX_DN<35>")
	)
	(segment
		(start 434.39588 -33.94964)
		(end 433.801266 -33.94964)
		(width 0.1651)
		(layer "In7.Cu")
		(net "P5E_PEX3_STN2_RX_DN<35>")
	)
	(segment
		(start 404.149814 -273.365214)
		(end 404.035514 -273.479514)
		(width 0.1143)
		(layer "In7.Cu")
		(net "P5E_PEX3_STN2_RX_DN<35>")
	)
	(segment
		(start 404.14067 -266.758166)
		(end 423.707052 -154.40914)
		(width 0.1651)
		(layer "In7.Cu")
		(net "P5E_PEX3_STN2_RX_DN<35>")
	)
	(segment
		(start 404.035514 -273.479514)
		(end 403.92096 -273.479514)
		(width 0.1143)
		(layer "In7.Cu")
		(net "P5E_PEX3_STN2_RX_DN<35>")
	)
	(segment
		(start 436.570628 -49.490884)
		(end 435.232048 -39.583614)
		(width 0.1651)
		(layer "In7.Cu")
		(net "P5E_PEX3_STN2_RX_DN<35>")
	)
	(segment
		(start 403.815804 -270.511524)
		(end 404.14067 -266.758166)
		(width 0.1651)
		(layer "In7.Cu")
		(net "P5E_PEX3_STN2_RX_DN<35>")
	)
	(segment
		(start 435.160928 -34.714688)
		(end 434.39588 -33.94964)
		(width 0.1651)
		(layer "In7.Cu")
		(net "P5E_PEX3_STN2_RX_DN<35>")
	)
	(segment
		(start 403.92096 -273.479514)
		(end 403.770084 -273.328638)
		(width 0.1143)
		(layer "In7.Cu")
		(net "P5E_PEX3_STN2_RX_DN<35>")
	)
	(segment
		(start 403.815804 -271.345152)
		(end 403.815804 -270.511524)
		(width 0.1651)
		(layer "In7.Cu")
		(net "P5E_PEX3_STN2_RX_DN<35>")
	)
	(segment
		(start 403.770084 -271.41932)
		(end 403.815804 -271.3736)
		(width 0.1143)
		(layer "In7.Cu")
		(net "P5E_PEX3_STN2_RX_DN<35>")
	)
	(segment
		(start 433.801266 -33.94964)
		(end 433.510436 -33.65881)
		(width 0.1651)
		(layer "In7.Cu")
		(net "P5E_PEX3_STN2_RX_DN<35>")
	)
	(segment
		(start 423.707052 -154.40914)
		(end 425.087288 -143.682974)
		(width 0.1651)
		(layer "In7.Cu")
		(net "P5E_PEX3_STN2_RX_DN<35>")
	)
	(segment
		(start 436.389018 -61.12764)
		(end 436.570628 -49.490884)
		(width 0.1651)
		(layer "In7.Cu")
		(net "P5E_PEX3_STN2_RX_DN<35>")
	)
	(segment
		(start 425.087288 -143.682974)
		(end 425.402756 -116.50345)
		(width 0.1651)
		(layer "In7.Cu")
		(net "P5E_PEX3_STN2_RX_DN<35>")
	)
	(segment
		(start 437.57088 -350.685862)
		(end 437.57088 -351.31629)
		(width 0.13462)
		(layer "F.Cu")
		(net "P5E_PEX3_STN7_TX_C_DP<125>")
	)
	(segment
		(start 437.57088 -351.31629)
		(end 437.275732 -351.611438)
		(width 0.13462)
		(layer "F.Cu")
		(net "P5E_PEX3_STN7_TX_C_DP<125>")
	)
	(segment
		(start 437.250332 -350.365314)
		(end 437.57088 -350.685862)
		(width 0.13462)
		(layer "F.Cu")
		(net "P5E_PEX3_STN7_TX_C_DP<125>")
	)
	(segment
		(start 432.905154 -365.200692)
		(end 433.116736 -364.752636)
		(width 0.1651)
		(layer "In11.Cu")
		(net "P5E_PEX3_STN7_TX_C_DP<125>")
	)
	(segment
		(start 436.012082 -358.046274)
		(end 436.012082 -353.910646)
		(width 0.1651)
		(layer "In11.Cu")
		(net "P5E_PEX3_STN7_TX_C_DP<125>")
	)
	(segment
		(start 436.012082 -353.910646)
		(end 437.566562 -352.356166)
		(width 0.1651)
		(layer "In11.Cu")
		(net "P5E_PEX3_STN7_TX_C_DP<125>")
	)
	(segment
		(start 432.947572 -365.319056)
		(end 432.905154 -365.200692)
		(width 0.1651)
		(layer "In11.Cu")
		(net "P5E_PEX3_STN7_TX_C_DP<125>")
	)
	(segment
		(start 432.119024 -366.866424)
		(end 432.237388 -366.823752)
		(width 0.1651)
		(layer "In11.Cu")
		(net "P5E_PEX3_STN7_TX_C_DP<125>")
	)
	(segment
		(start 433.733956 -363.65307)
		(end 435.679088 -359.530904)
		(width 0.1651)
		(layer "In11.Cu")
		(net "P5E_PEX3_STN7_TX_C_DP<125>")
	)
	(segment
		(start 432.406298 -366.257586)
		(end 432.61788 -365.80953)
		(width 0.1651)
		(layer "In11.Cu")
		(net "P5E_PEX3_STN7_TX_C_DP<125>")
	)
	(segment
		(start 433.116736 -364.752636)
		(end 433.2351 -364.709964)
		(width 0.1651)
		(layer "In11.Cu")
		(net "P5E_PEX3_STN7_TX_C_DP<125>")
	)
	(segment
		(start 437.566562 -352.356166)
		(end 437.566562 -351.902268)
		(width 0.1651)
		(layer "In11.Cu")
		(net "P5E_PEX3_STN7_TX_C_DP<125>")
	)
	(segment
		(start 435.679088 -359.530904)
		(end 436.012082 -358.046274)
		(width 0.1651)
		(layer "In11.Cu")
		(net "P5E_PEX3_STN7_TX_C_DP<125>")
	)
	(segment
		(start 433.2351 -364.709964)
		(end 433.446428 -364.262162)
		(width 0.1651)
		(layer "In11.Cu")
		(net "P5E_PEX3_STN7_TX_C_DP<125>")
	)
	(segment
		(start 430.616868 -375.999248)
		(end 431.047144 -375.999248)
		(width 0.1651)
		(layer "In11.Cu")
		(net "P5E_PEX3_STN7_TX_C_DP<125>")
	)
	(segment
		(start 431.33391 -369.686332)
		(end 431.738532 -367.880646)
		(width 0.1651)
		(layer "In11.Cu")
		(net "P5E_PEX3_STN7_TX_C_DP<125>")
	)
	(segment
		(start 431.33391 -375.712482)
		(end 431.33391 -369.686332)
		(width 0.1651)
		(layer "In11.Cu")
		(net "P5E_PEX3_STN7_TX_C_DP<125>")
	)
	(segment
		(start 432.237388 -366.823752)
		(end 432.448716 -366.37595)
		(width 0.1651)
		(layer "In11.Cu")
		(net "P5E_PEX3_STN7_TX_C_DP<125>")
	)
	(segment
		(start 431.047144 -375.999248)
		(end 431.33391 -375.712482)
		(width 0.1651)
		(layer "In11.Cu")
		(net "P5E_PEX3_STN7_TX_C_DP<125>")
	)
	(segment
		(start 430.489868 -375.490232)
		(end 430.489868 -375.872248)
		(width 0.1651)
		(layer "In11.Cu")
		(net "P5E_PEX3_STN7_TX_C_DP<125>")
	)
	(segment
		(start 433.40401 -364.143798)
		(end 433.615592 -363.695742)
		(width 0.1651)
		(layer "In11.Cu")
		(net "P5E_PEX3_STN7_TX_C_DP<125>")
	)
	(segment
		(start 432.448716 -366.37595)
		(end 432.406298 -366.257586)
		(width 0.1651)
		(layer "In11.Cu")
		(net "P5E_PEX3_STN7_TX_C_DP<125>")
	)
	(segment
		(start 437.566562 -351.902268)
		(end 437.275732 -351.611438)
		(width 0.1651)
		(layer "In11.Cu")
		(net "P5E_PEX3_STN7_TX_C_DP<125>")
	)
	(segment
		(start 432.736244 -365.766858)
		(end 432.947572 -365.319056)
		(width 0.1651)
		(layer "In11.Cu")
		(net "P5E_PEX3_STN7_TX_C_DP<125>")
	)
	(segment
		(start 431.907442 -367.31448)
		(end 432.119024 -366.866424)
		(width 0.1651)
		(layer "In11.Cu")
		(net "P5E_PEX3_STN7_TX_C_DP<125>")
	)
	(segment
		(start 430.489868 -375.872248)
		(end 430.616868 -375.999248)
		(width 0.1651)
		(layer "In11.Cu")
		(net "P5E_PEX3_STN7_TX_C_DP<125>")
	)
	(segment
		(start 433.615592 -363.695742)
		(end 433.733956 -363.65307)
		(width 0.1651)
		(layer "In11.Cu")
		(net "P5E_PEX3_STN7_TX_C_DP<125>")
	)
	(segment
		(start 431.738532 -367.880646)
		(end 431.94986 -367.432844)
		(width 0.1651)
		(layer "In11.Cu")
		(net "P5E_PEX3_STN7_TX_C_DP<125>")
	)
	(segment
		(start 431.94986 -367.432844)
		(end 431.907442 -367.31448)
		(width 0.1651)
		(layer "In11.Cu")
		(net "P5E_PEX3_STN7_TX_C_DP<125>")
	)
	(segment
		(start 432.61788 -365.80953)
		(end 432.736244 -365.766858)
		(width 0.1651)
		(layer "In11.Cu")
		(net "P5E_PEX3_STN7_TX_C_DP<125>")
	)
	(segment
		(start 433.446428 -364.262162)
		(end 433.40401 -364.143798)
		(width 0.1651)
		(layer "In11.Cu")
		(net "P5E_PEX3_STN7_TX_C_DP<125>")
	)
	(segment
		(start 156.42971 -143.401796)
		(end 156.481272 -143.350234)
		(width 0.13208)
		(layer "F.Cu")
		(net "NIC2_BIF0_N")
	)
	(segment
		(start 154.487626 -142.88897)
		(end 154.490674 -142.892018)
		(width 0.13208)
		(layer "F.Cu")
		(net "NIC2_BIF0_N")
	)
	(segment
		(start 154.708352 -143.401796)
		(end 156.42971 -143.401796)
		(width 0.13208)
		(layer "F.Cu")
		(net "NIC2_BIF0_N")
	)
	(segment
		(start 158.606998 -142.56512)
		(end 162.14217 -142.56512)
		(width 0.13208)
		(layer "F.Cu")
		(net "NIC2_BIF0_N")
	)
	(segment
		(start 154.490674 -142.892018)
		(end 154.490674 -143.184118)
		(width 0.13208)
		(layer "F.Cu")
		(net "NIC2_BIF0_N")
	)
	(segment
		(start 157.821884 -143.350234)
		(end 158.606998 -142.56512)
		(width 0.13208)
		(layer "F.Cu")
		(net "NIC2_BIF0_N")
	)
	(segment
		(start 156.481272 -143.350234)
		(end 157.821884 -143.350234)
		(width 0.13208)
		(layer "F.Cu")
		(net "NIC2_BIF0_N")
	)
	(segment
		(start 153.504646 -142.88897)
		(end 154.487626 -142.88897)
		(width 0.13208)
		(layer "F.Cu")
		(net "NIC2_BIF0_N")
	)
	(segment
		(start 154.490674 -143.184118)
		(end 154.708352 -143.401796)
		(width 0.13208)
		(layer "F.Cu")
		(net "NIC2_BIF0_N")
	)
	(via
		(at 156.481272 -143.350234)
		(size 0.762)
		(drill 0.381)
		(layers "F.Cu" "B.Cu")
		(net "NIC2_BIF0_N")
	)
	(segment
		(start 68.169536 -154.15514)
		(end 68.006468 -153.992072)
		(width 0.13462)
		(layer "F.Cu")
		(net "P5E_PEX0_STN0_RX_DP<14>")
	)
	(segment
		(start 68.65747 -154.15514)
		(end 68.169536 -154.15514)
		(width 0.13462)
		(layer "F.Cu")
		(net "P5E_PEX0_STN0_RX_DP<14>")
	)
	(segment
		(start 67.352418 -153.992072)
		(end 67.05727 -154.28722)
		(width 0.13462)
		(layer "F.Cu")
		(net "P5E_PEX0_STN0_RX_DP<14>")
	)
	(segment
		(start 68.006468 -153.992072)
		(end 67.352418 -153.992072)
		(width 0.13462)
		(layer "F.Cu")
		(net "P5E_PEX0_STN0_RX_DP<14>")
	)
	(segment
		(start 68.404486 -157.236414)
		(end 68.500498 -158.641796)
		(width 0.1651)
		(layer "In5.Cu")
		(net "P5E_PEX0_STN0_RX_DP<14>")
	)
	(segment
		(start 68.282312 -157.130242)
		(end 68.404486 -157.236414)
		(width 0.1651)
		(layer "In5.Cu")
		(net "P5E_PEX0_STN0_RX_DP<14>")
	)
	(segment
		(start 68.50126 -158.642304)
		(end 68.50126 -160.396682)
		(width 0.1651)
		(layer "In5.Cu")
		(net "P5E_PEX0_STN0_RX_DP<14>")
	)
	(segment
		(start 75.444604 -275.569934)
		(end 75.685396 -275.569934)
		(width 0.1143)
		(layer "In5.Cu")
		(net "P5E_PEX0_STN0_RX_DP<14>")
	)
	(segment
		(start 68.6181 -162.09645)
		(end 69.034152 -164.703506)
		(width 0.1651)
		(layer "In5.Cu")
		(net "P5E_PEX0_STN0_RX_DP<14>")
	)
	(segment
		(start 67.227958 -154.116532)
		(end 67.521074 -153.99512)
		(width 0.1651)
		(layer "In5.Cu")
		(net "P5E_PEX0_STN0_RX_DP<14>")
	)
	(segment
		(start 68.32092 -156.020008)
		(end 68.354702 -156.514038)
		(width 0.1651)
		(layer "In5.Cu")
		(net "P5E_PEX0_STN0_RX_DP<14>")
	)
	(segment
		(start 75.184 -271.802352)
		(end 75.22972 -271.848072)
		(width 0.1143)
		(layer "In5.Cu")
		(net "P5E_PEX0_STN0_RX_DP<14>")
	)
	(segment
		(start 68.237608 -154.803856)
		(end 68.27139 -155.297632)
		(width 0.1651)
		(layer "In5.Cu")
		(net "P5E_PEX0_STN0_RX_DP<14>")
	)
	(segment
		(start 75.685396 -275.569934)
		(end 75.799696 -275.684234)
		(width 0.1143)
		(layer "In5.Cu")
		(net "P5E_PEX0_STN0_RX_DP<14>")
	)
	(segment
		(start 75.799696 -275.684234)
		(end 75.799696 -275.949664)
		(width 0.1143)
		(layer "In5.Cu")
		(net "P5E_PEX0_STN0_RX_DP<14>")
	)
	(segment
		(start 69.034152 -164.703506)
		(end 75.463654 -258.33578)
		(width 0.1651)
		(layer "In5.Cu")
		(net "P5E_PEX0_STN0_RX_DP<14>")
	)
	(segment
		(start 67.05727 -154.28722)
		(end 67.227958 -154.116532)
		(width 0.1651)
		(layer "In5.Cu")
		(net "P5E_PEX0_STN0_RX_DP<14>")
	)
	(segment
		(start 75.184 -271.773904)
		(end 75.184 -271.802352)
		(width 0.1143)
		(layer "In5.Cu")
		(net "P5E_PEX0_STN0_RX_DP<14>")
	)
	(segment
		(start 75.184 -270.431006)
		(end 75.184 -271.773904)
		(width 0.1651)
		(layer "In5.Cu")
		(net "P5E_PEX0_STN0_RX_DP<14>")
	)
	(segment
		(start 68.24853 -156.635958)
		(end 68.282312 -157.130242)
		(width 0.1651)
		(layer "In5.Cu")
		(net "P5E_PEX0_STN0_RX_DP<14>")
	)
	(segment
		(start 68.500498 -158.641796)
		(end 68.50126 -158.642304)
		(width 0.1651)
		(layer "In5.Cu")
		(net "P5E_PEX0_STN0_RX_DP<14>")
	)
	(segment
		(start 68.354702 -156.514038)
		(end 68.24853 -156.635958)
		(width 0.1651)
		(layer "In5.Cu")
		(net "P5E_PEX0_STN0_RX_DP<14>")
	)
	(segment
		(start 68.50126 -160.396682)
		(end 68.6181 -162.09645)
		(width 0.1651)
		(layer "In5.Cu")
		(net "P5E_PEX0_STN0_RX_DP<14>")
	)
	(segment
		(start 68.042536 -154.37485)
		(end 68.237608 -154.803856)
		(width 0.1651)
		(layer "In5.Cu")
		(net "P5E_PEX0_STN0_RX_DP<14>")
	)
	(segment
		(start 75.678284 -267.788136)
		(end 75.184 -270.431006)
		(width 0.1651)
		(layer "In5.Cu")
		(net "P5E_PEX0_STN0_RX_DP<14>")
	)
	(segment
		(start 68.27139 -155.297632)
		(end 68.165218 -155.419552)
		(width 0.1651)
		(layer "In5.Cu")
		(net "P5E_PEX0_STN0_RX_DP<14>")
	)
	(segment
		(start 75.22972 -275.35505)
		(end 75.444604 -275.569934)
		(width 0.1143)
		(layer "In5.Cu")
		(net "P5E_PEX0_STN0_RX_DP<14>")
	)
	(segment
		(start 75.463654 -258.33578)
		(end 75.678284 -267.788136)
		(width 0.1651)
		(layer "In5.Cu")
		(net "P5E_PEX0_STN0_RX_DP<14>")
	)
	(segment
		(start 67.521074 -153.99512)
		(end 67.662806 -153.99512)
		(width 0.1651)
		(layer "In5.Cu")
		(net "P5E_PEX0_STN0_RX_DP<14>")
	)
	(segment
		(start 68.199 -155.913836)
		(end 68.32092 -156.020008)
		(width 0.1651)
		(layer "In5.Cu")
		(net "P5E_PEX0_STN0_RX_DP<14>")
	)
	(segment
		(start 67.662806 -153.99512)
		(end 68.042536 -154.37485)
		(width 0.1651)
		(layer "In5.Cu")
		(net "P5E_PEX0_STN0_RX_DP<14>")
	)
	(segment
		(start 68.165218 -155.419552)
		(end 68.199 -155.913836)
		(width 0.1651)
		(layer "In5.Cu")
		(net "P5E_PEX0_STN0_RX_DP<14>")
	)
	(segment
		(start 75.22972 -271.848072)
		(end 75.22972 -275.35505)
		(width 0.1143)
		(layer "In5.Cu")
		(net "P5E_PEX0_STN0_RX_DP<14>")
	)
	(segment
		(start 283.485336 -105.283)
		(end 283.323284 -105.445052)
		(width 0.13462)
		(layer "F.Cu")
		(net "P5E_PEX2_STN1_RX_DN<19>")
	)
	(segment
		(start 284.442662 -105.57637)
		(end 284.149292 -105.283)
		(width 0.13462)
		(layer "F.Cu")
		(net "P5E_PEX2_STN1_RX_DN<19>")
	)
	(segment
		(start 283.323284 -105.445052)
		(end 282.842462 -105.445052)
		(width 0.13462)
		(layer "F.Cu")
		(net "P5E_PEX2_STN1_RX_DN<19>")
	)
	(segment
		(start 284.149292 -105.283)
		(end 283.485336 -105.283)
		(width 0.13462)
		(layer "F.Cu")
		(net "P5E_PEX2_STN1_RX_DN<19>")
	)
	(segment
		(start 281.093672 -106.68)
		(end 281.047444 -106.83494)
		(width 0.1651)
		(layer "In5.Cu")
		(net "P5E_PEX2_STN1_RX_DN<19>")
	)
	(segment
		(start 282.601924 -105.865168)
		(end 282.166314 -106.100372)
		(width 0.1651)
		(layer "In5.Cu")
		(net "P5E_PEX2_STN1_RX_DN<19>")
	)
	(segment
		(start 274.379182 -111.761016)
		(end 274.217638 -111.758222)
		(width 0.1651)
		(layer "In5.Cu")
		(net "P5E_PEX2_STN1_RX_DN<19>")
	)
	(segment
		(start 269.935452 -119.317008)
		(end 268.567662 -120.982232)
		(width 0.1651)
		(layer "In5.Cu")
		(net "P5E_PEX2_STN1_RX_DN<19>")
	)
	(segment
		(start 275.613876 -110.406434)
		(end 275.611336 -110.567978)
		(width 0.1651)
		(layer "In5.Cu")
		(net "P5E_PEX2_STN1_RX_DN<19>")
	)
	(segment
		(start 273.089878 -112.850168)
		(end 269.935452 -119.317008)
		(width 0.1651)
		(layer "In5.Cu")
		(net "P5E_PEX2_STN1_RX_DN<19>")
	)
	(segment
		(start 294.585136 -275.379688)
		(end 294.699436 -275.265388)
		(width 0.1143)
		(layer "In5.Cu")
		(net "P5E_PEX2_STN1_RX_DN<19>")
	)
	(segment
		(start 274.217638 -111.758222)
		(end 273.089878 -112.850168)
		(width 0.1651)
		(layer "In5.Cu")
		(net "P5E_PEX2_STN1_RX_DN<19>")
	)
	(segment
		(start 275.96973 -110.06201)
		(end 275.613876 -110.406434)
		(width 0.1651)
		(layer "In5.Cu")
		(net "P5E_PEX2_STN1_RX_DN<19>")
	)
	(segment
		(start 294.36568 -269.489682)
		(end 294.36568 -271.570958)
		(width 0.1651)
		(layer "In5.Cu")
		(net "P5E_PEX2_STN1_RX_DN<19>")
	)
	(segment
		(start 280.02103 -107.259628)
		(end 279.974802 -107.414568)
		(width 0.1651)
		(layer "In5.Cu")
		(net "P5E_PEX2_STN1_RX_DN<19>")
	)
	(segment
		(start 275.093684 -110.910116)
		(end 274.73783 -111.25454)
		(width 0.1651)
		(layer "In5.Cu")
		(net "P5E_PEX2_STN1_RX_DN<19>")
	)
	(segment
		(start 294.36568 -271.570958)
		(end 294.36568 -271.599406)
		(width 0.1143)
		(layer "In5.Cu")
		(net "P5E_PEX2_STN1_RX_DN<19>")
	)
	(segment
		(start 265.22553 -165.120574)
		(end 294.36568 -269.489682)
		(width 0.1651)
		(layer "In5.Cu")
		(net "P5E_PEX2_STN1_RX_DN<19>")
	)
	(segment
		(start 276.489922 -109.558074)
		(end 276.487382 -109.719618)
		(width 0.1651)
		(layer "In5.Cu")
		(net "P5E_PEX2_STN1_RX_DN<19>")
	)
	(segment
		(start 282.120086 -106.255312)
		(end 281.683968 -106.491024)
		(width 0.1651)
		(layer "In5.Cu")
		(net "P5E_PEX2_STN1_RX_DN<19>")
	)
	(segment
		(start 282.75661 -105.911396)
		(end 282.601924 -105.865168)
		(width 0.1651)
		(layer "In5.Cu")
		(net "P5E_PEX2_STN1_RX_DN<19>")
	)
	(segment
		(start 275.255228 -110.91291)
		(end 275.093684 -110.910116)
		(width 0.1651)
		(layer "In5.Cu")
		(net "P5E_PEX2_STN1_RX_DN<19>")
	)
	(segment
		(start 281.529282 -106.444796)
		(end 281.093672 -106.68)
		(width 0.1651)
		(layer "In5.Cu")
		(net "P5E_PEX2_STN1_RX_DN<19>")
	)
	(segment
		(start 263.603232 -150.483824)
		(end 264.129012 -158.735014)
		(width 0.1651)
		(layer "In5.Cu")
		(net "P5E_PEX2_STN1_RX_DN<19>")
	)
	(segment
		(start 264.403586 -138.436096)
		(end 263.603232 -150.483824)
		(width 0.1651)
		(layer "In5.Cu")
		(net "P5E_PEX2_STN1_RX_DN<19>")
	)
	(segment
		(start 268.567662 -120.982232)
		(end 266.531852 -122.078242)
		(width 0.1651)
		(layer "In5.Cu")
		(net "P5E_PEX2_STN1_RX_DN<19>")
	)
	(segment
		(start 294.699436 -275.265388)
		(end 294.699436 -274.999958)
		(width 0.1143)
		(layer "In5.Cu")
		(net "P5E_PEX2_STN1_RX_DN<19>")
	)
	(segment
		(start 283.192728 -105.675684)
		(end 282.75661 -105.911396)
		(width 0.1651)
		(layer "In5.Cu")
		(net "P5E_PEX2_STN1_RX_DN<19>")
	)
	(segment
		(start 284.151832 -105.28554)
		(end 283.674566 -105.28554)
		(width 0.1651)
		(layer "In5.Cu")
		(net "P5E_PEX2_STN1_RX_DN<19>")
	)
	(segment
		(start 280.611326 -107.070652)
		(end 280.45664 -107.024424)
		(width 0.1651)
		(layer "In5.Cu")
		(net "P5E_PEX2_STN1_RX_DN<19>")
	)
	(segment
		(start 276.131274 -110.06455)
		(end 275.96973 -110.06201)
		(width 0.1651)
		(layer "In5.Cu")
		(net "P5E_PEX2_STN1_RX_DN<19>")
	)
	(segment
		(start 280.45664 -107.024424)
		(end 280.02103 -107.259628)
		(width 0.1651)
		(layer "In5.Cu")
		(net "P5E_PEX2_STN1_RX_DN<19>")
	)
	(segment
		(start 294.423338 -275.379688)
		(end 294.585136 -275.379688)
		(width 0.1143)
		(layer "In5.Cu")
		(net "P5E_PEX2_STN1_RX_DN<19>")
	)
	(segment
		(start 275.611336 -110.567978)
		(end 275.255228 -110.91291)
		(width 0.1651)
		(layer "In5.Cu")
		(net "P5E_PEX2_STN1_RX_DN<19>")
	)
	(segment
		(start 277.402798 -108.674408)
		(end 276.489922 -109.558074)
		(width 0.1651)
		(layer "In5.Cu")
		(net "P5E_PEX2_STN1_RX_DN<19>")
	)
	(segment
		(start 279.538684 -107.65028)
		(end 279.383744 -107.604052)
		(width 0.1651)
		(layer "In5.Cu")
		(net "P5E_PEX2_STN1_RX_DN<19>")
	)
	(segment
		(start 279.974802 -107.414568)
		(end 279.538684 -107.65028)
		(width 0.1651)
		(layer "In5.Cu")
		(net "P5E_PEX2_STN1_RX_DN<19>")
	)
	(segment
		(start 281.047444 -106.83494)
		(end 280.611326 -107.070652)
		(width 0.1651)
		(layer "In5.Cu")
		(net "P5E_PEX2_STN1_RX_DN<19>")
	)
	(segment
		(start 264.129012 -158.735014)
		(end 265.22553 -165.120574)
		(width 0.1651)
		(layer "In5.Cu")
		(net "P5E_PEX2_STN1_RX_DN<19>")
	)
	(segment
		(start 284.442662 -105.57637)
		(end 284.151832 -105.28554)
		(width 0.1651)
		(layer "In5.Cu")
		(net "P5E_PEX2_STN1_RX_DN<19>")
	)
	(segment
		(start 265.204194 -126.387352)
		(end 264.404094 -138.435842)
		(width 0.1651)
		(layer "In5.Cu")
		(net "P5E_PEX2_STN1_RX_DN<19>")
	)
	(segment
		(start 294.36568 -271.599406)
		(end 294.31996 -271.645126)
		(width 0.1143)
		(layer "In5.Cu")
		(net "P5E_PEX2_STN1_RX_DN<19>")
	)
	(segment
		(start 274.73783 -111.25454)
		(end 274.73529 -111.416084)
		(width 0.1651)
		(layer "In5.Cu")
		(net "P5E_PEX2_STN1_RX_DN<19>")
	)
	(segment
		(start 279.383744 -107.604052)
		(end 278.948134 -107.839256)
		(width 0.1651)
		(layer "In5.Cu")
		(net "P5E_PEX2_STN1_RX_DN<19>")
	)
	(segment
		(start 276.487382 -109.719618)
		(end 276.131274 -110.06455)
		(width 0.1651)
		(layer "In5.Cu")
		(net "P5E_PEX2_STN1_RX_DN<19>")
	)
	(segment
		(start 281.683968 -106.491024)
		(end 281.529282 -106.444796)
		(width 0.1651)
		(layer "In5.Cu")
		(net "P5E_PEX2_STN1_RX_DN<19>")
	)
	(segment
		(start 264.404094 -138.435842)
		(end 264.403586 -138.436096)
		(width 0.1651)
		(layer "In5.Cu")
		(net "P5E_PEX2_STN1_RX_DN<19>")
	)
	(segment
		(start 294.31996 -271.645126)
		(end 294.31996 -275.27631)
		(width 0.1143)
		(layer "In5.Cu")
		(net "P5E_PEX2_STN1_RX_DN<19>")
	)
	(segment
		(start 274.73529 -111.416084)
		(end 274.379182 -111.761016)
		(width 0.1651)
		(layer "In5.Cu")
		(net "P5E_PEX2_STN1_RX_DN<19>")
	)
	(segment
		(start 278.311102 -108.18368)
		(end 277.402798 -108.674408)
		(width 0.1651)
		(layer "In5.Cu")
		(net "P5E_PEX2_STN1_RX_DN<19>")
	)
	(segment
		(start 265.867134 -122.886724)
		(end 265.204194 -126.387352)
		(width 0.1651)
		(layer "In5.Cu")
		(net "P5E_PEX2_STN1_RX_DN<19>")
	)
	(segment
		(start 278.901906 -107.994196)
		(end 278.465788 -108.229908)
		(width 0.1651)
		(layer "In5.Cu")
		(net "P5E_PEX2_STN1_RX_DN<19>")
	)
	(segment
		(start 278.948134 -107.839256)
		(end 278.901906 -107.994196)
		(width 0.1651)
		(layer "In5.Cu")
		(net "P5E_PEX2_STN1_RX_DN<19>")
	)
	(segment
		(start 278.465788 -108.229908)
		(end 278.311102 -108.18368)
		(width 0.1651)
		(layer "In5.Cu")
		(net "P5E_PEX2_STN1_RX_DN<19>")
	)
	(segment
		(start 282.166314 -106.100372)
		(end 282.120086 -106.255312)
		(width 0.1651)
		(layer "In5.Cu")
		(net "P5E_PEX2_STN1_RX_DN<19>")
	)
	(segment
		(start 283.674566 -105.28554)
		(end 283.238956 -105.520744)
		(width 0.1651)
		(layer "In5.Cu")
		(net "P5E_PEX2_STN1_RX_DN<19>")
	)
	(segment
		(start 266.531852 -122.078242)
		(end 265.867134 -122.886724)
		(width 0.1651)
		(layer "In5.Cu")
		(net "P5E_PEX2_STN1_RX_DN<19>")
	)
	(segment
		(start 283.238956 -105.520744)
		(end 283.192728 -105.675684)
		(width 0.1651)
		(layer "In5.Cu")
		(net "P5E_PEX2_STN1_RX_DN<19>")
	)
	(segment
		(start 294.31996 -275.27631)
		(end 294.423338 -275.379688)
		(width 0.1143)
		(layer "In5.Cu")
		(net "P5E_PEX2_STN1_RX_DN<19>")
	)
	(segment
		(start 277.198582 -356.511606)
		(end 277.518622 -356.831646)
		(width 0.13462)
		(layer "F.Cu")
		(net "P5E_PEX2_STN7_TX_C_DP<117>")
	)
	(segment
		(start 277.518622 -357.46309)
		(end 277.223982 -357.75773)
		(width 0.13462)
		(layer "F.Cu")
		(net "P5E_PEX2_STN7_TX_C_DP<117>")
	)
	(segment
		(start 277.518622 -356.831646)
		(end 277.518622 -357.46309)
		(width 0.13462)
		(layer "F.Cu")
		(net "P5E_PEX2_STN7_TX_C_DP<117>")
	)
	(segment
		(start 297.277282 -393.239498)
		(end 296.864024 -392.965686)
		(width 0.1651)
		(layer "In7.Cu")
		(net "P5E_PEX2_STN7_TX_C_DP<117>")
	)
	(segment
		(start 292.99027 -390.575038)
		(end 286.055562 -387.52653)
		(width 0.1651)
		(layer "In7.Cu")
		(net "P5E_PEX2_STN7_TX_C_DP<117>")
	)
	(segment
		(start 297.400472 -393.214352)
		(end 297.277282 -393.239498)
		(width 0.1651)
		(layer "In7.Cu")
		(net "P5E_PEX2_STN7_TX_C_DP<117>")
	)
	(segment
		(start 277.514812 -358.56418)
		(end 277.514812 -358.04856)
		(width 0.1651)
		(layer "In7.Cu")
		(net "P5E_PEX2_STN7_TX_C_DP<117>")
	)
	(segment
		(start 295.328594 -391.949432)
		(end 294.915336 -391.675874)
		(width 0.1651)
		(layer "In7.Cu")
		(net "P5E_PEX2_STN7_TX_C_DP<117>")
	)
	(segment
		(start 293.606728 -390.84631)
		(end 293.489634 -390.891776)
		(width 0.1651)
		(layer "In7.Cu")
		(net "P5E_PEX2_STN7_TX_C_DP<117>")
	)
	(segment
		(start 296.839132 -392.842496)
		(end 296.839132 -392.84275)
		(width 0.1651)
		(layer "In7.Cu")
		(net "P5E_PEX2_STN7_TX_C_DP<117>")
	)
	(segment
		(start 299.047154 -401.999196)
		(end 299.33392 -401.71243)
		(width 0.1651)
		(layer "In7.Cu")
		(net "P5E_PEX2_STN7_TX_C_DP<117>")
	)
	(segment
		(start 296.864024 -392.965686)
		(end 296.839132 -392.842496)
		(width 0.1651)
		(layer "In7.Cu")
		(net "P5E_PEX2_STN7_TX_C_DP<117>")
	)
	(segment
		(start 296.425874 -392.569192)
		(end 296.302938 -392.594338)
		(width 0.1651)
		(layer "In7.Cu")
		(net "P5E_PEX2_STN7_TX_C_DP<117>")
	)
	(segment
		(start 294.250364 -391.129012)
		(end 294.25011 -391.129012)
		(width 0.1651)
		(layer "In7.Cu")
		(net "P5E_PEX2_STN7_TX_C_DP<117>")
	)
	(segment
		(start 298.489878 -401.872196)
		(end 298.616878 -401.999196)
		(width 0.1651)
		(layer "In7.Cu")
		(net "P5E_PEX2_STN7_TX_C_DP<117>")
	)
	(segment
		(start 298.99737 -394.67155)
		(end 298.647358 -394.321538)
		(width 0.1651)
		(layer "In7.Cu")
		(net "P5E_PEX2_STN7_TX_C_DP<117>")
	)
	(segment
		(start 295.864788 -392.19759)
		(end 295.451784 -391.924286)
		(width 0.1651)
		(layer "In7.Cu")
		(net "P5E_PEX2_STN7_TX_C_DP<117>")
	)
	(segment
		(start 296.839132 -392.84275)
		(end 296.425874 -392.569192)
		(width 0.1651)
		(layer "In7.Cu")
		(net "P5E_PEX2_STN7_TX_C_DP<117>")
	)
	(segment
		(start 298.521628 -394.321538)
		(end 298.171108 -393.971018)
		(width 0.1651)
		(layer "In7.Cu")
		(net "P5E_PEX2_STN7_TX_C_DP<117>")
	)
	(segment
		(start 298.616878 -401.999196)
		(end 299.047154 -401.999196)
		(width 0.1651)
		(layer "In7.Cu")
		(net "P5E_PEX2_STN7_TX_C_DP<117>")
	)
	(segment
		(start 294.25011 -391.129012)
		(end 293.606728 -390.84631)
		(width 0.1651)
		(layer "In7.Cu")
		(net "P5E_PEX2_STN7_TX_C_DP<117>")
	)
	(segment
		(start 294.915336 -391.675874)
		(end 294.890444 -391.552684)
		(width 0.1651)
		(layer "In7.Cu")
		(net "P5E_PEX2_STN7_TX_C_DP<117>")
	)
	(segment
		(start 299.33392 -395.507464)
		(end 298.99737 -394.67155)
		(width 0.1651)
		(layer "In7.Cu")
		(net "P5E_PEX2_STN7_TX_C_DP<117>")
	)
	(segment
		(start 298.647358 -394.321538)
		(end 298.521628 -394.321538)
		(width 0.1651)
		(layer "In7.Cu")
		(net "P5E_PEX2_STN7_TX_C_DP<117>")
	)
	(segment
		(start 294.890444 -391.552684)
		(end 294.250364 -391.129012)
		(width 0.1651)
		(layer "In7.Cu")
		(net "P5E_PEX2_STN7_TX_C_DP<117>")
	)
	(segment
		(start 293.489634 -390.891776)
		(end 293.035736 -390.692132)
		(width 0.1651)
		(layer "In7.Cu")
		(net "P5E_PEX2_STN7_TX_C_DP<117>")
	)
	(segment
		(start 286.055562 -387.52653)
		(end 284.987238 -386.53466)
		(width 0.1651)
		(layer "In7.Cu")
		(net "P5E_PEX2_STN7_TX_C_DP<117>")
	)
	(segment
		(start 282.4988 -373.8626)
		(end 277.514812 -358.56418)
		(width 0.1651)
		(layer "In7.Cu")
		(net "P5E_PEX2_STN7_TX_C_DP<117>")
	)
	(segment
		(start 296.302938 -392.594338)
		(end 295.88968 -392.32078)
		(width 0.1651)
		(layer "In7.Cu")
		(net "P5E_PEX2_STN7_TX_C_DP<117>")
	)
	(segment
		(start 295.88968 -392.32078)
		(end 295.864788 -392.19759)
		(width 0.1651)
		(layer "In7.Cu")
		(net "P5E_PEX2_STN7_TX_C_DP<117>")
	)
	(segment
		(start 284.987238 -386.53466)
		(end 284.236922 -384.938778)
		(width 0.1651)
		(layer "In7.Cu")
		(net "P5E_PEX2_STN7_TX_C_DP<117>")
	)
	(segment
		(start 284.236922 -384.938778)
		(end 282.4988 -373.8626)
		(width 0.1651)
		(layer "In7.Cu")
		(net "P5E_PEX2_STN7_TX_C_DP<117>")
	)
	(segment
		(start 298.489878 -401.49018)
		(end 298.489878 -401.872196)
		(width 0.1651)
		(layer "In7.Cu")
		(net "P5E_PEX2_STN7_TX_C_DP<117>")
	)
	(segment
		(start 295.451784 -391.924286)
		(end 295.328594 -391.949432)
		(width 0.1651)
		(layer "In7.Cu")
		(net "P5E_PEX2_STN7_TX_C_DP<117>")
	)
	(segment
		(start 298.171108 -393.971018)
		(end 298.171108 -393.845288)
		(width 0.1651)
		(layer "In7.Cu")
		(net "P5E_PEX2_STN7_TX_C_DP<117>")
	)
	(segment
		(start 299.33392 -401.71243)
		(end 299.33392 -395.507464)
		(width 0.1651)
		(layer "In7.Cu")
		(net "P5E_PEX2_STN7_TX_C_DP<117>")
	)
	(segment
		(start 297.813476 -393.487656)
		(end 297.400472 -393.214352)
		(width 0.1651)
		(layer "In7.Cu")
		(net "P5E_PEX2_STN7_TX_C_DP<117>")
	)
	(segment
		(start 277.514812 -358.04856)
		(end 277.223982 -357.75773)
		(width 0.1651)
		(layer "In7.Cu")
		(net "P5E_PEX2_STN7_TX_C_DP<117>")
	)
	(segment
		(start 293.035736 -390.692132)
		(end 292.99027 -390.575038)
		(width 0.1651)
		(layer "In7.Cu")
		(net "P5E_PEX2_STN7_TX_C_DP<117>")
	)
	(segment
		(start 298.171108 -393.845288)
		(end 297.813476 -393.487656)
		(width 0.1651)
		(layer "In7.Cu")
		(net "P5E_PEX2_STN7_TX_C_DP<117>")
	)
	(segment
		(start 368.467894 -30.94609)
		(end 368.149124 -30.62732)
		(width 0.13462)
		(layer "F.Cu")
		(net "P5E_PEX3_STN2_TX_C_DP<45>")
	)
	(segment
		(start 364.065566 -30.790134)
		(end 363.564932 -30.790134)
		(width 0.13462)
		(layer "F.Cu")
		(net "P5E_PEX3_STN2_TX_C_DP<45>")
	)
	(segment
		(start 364.22838 -30.62732)
		(end 364.065566 -30.790134)
		(width 0.13462)
		(layer "F.Cu")
		(net "P5E_PEX3_STN2_TX_C_DP<45>")
	)
	(segment
		(start 368.149124 -30.62732)
		(end 364.22838 -30.62732)
		(width 0.13462)
		(layer "F.Cu")
		(net "P5E_PEX3_STN2_TX_C_DP<45>")
	)
	(segment
		(start 387.38429 -321.306698)
		(end 387.38429 -319.893696)
		(width 0.1651)
		(layer "In9.Cu")
		(net "P5E_PEX3_STN7_RX_DP<124>")
	)
	(segment
		(start 431.022252 -365.929926)
		(end 431.021998 -365.929926)
		(width 0.1651)
		(layer "In9.Cu")
		(net "P5E_PEX3_STN7_RX_DP<124>")
	)
	(segment
		(start 388.061454 -322.94195)
		(end 387.38429 -321.306698)
		(width 0.1651)
		(layer "In9.Cu")
		(net "P5E_PEX3_STN7_RX_DP<124>")
	)
	(segment
		(start 430.252378 -366.928146)
		(end 430.375568 -366.903254)
		(width 0.1651)
		(layer "In9.Cu")
		(net "P5E_PEX3_STN7_RX_DP<124>")
	)
	(segment
		(start 387.38429 -319.865248)
		(end 387.43001 -319.819528)
		(width 0.1143)
		(layer "In9.Cu")
		(net "P5E_PEX3_STN7_RX_DP<124>")
	)
	(segment
		(start 428.289974 -382.18999)
		(end 428.289974 -382.572006)
		(width 0.1651)
		(layer "In9.Cu")
		(net "P5E_PEX3_STN7_RX_DP<124>")
	)
	(segment
		(start 431.296318 -365.51743)
		(end 431.271426 -365.39424)
		(width 0.1651)
		(layer "In9.Cu")
		(net "P5E_PEX3_STN7_RX_DP<124>")
	)
	(segment
		(start 387.91134 -316.229492)
		(end 388.00024 -316.140592)
		(width 0.1143)
		(layer "In9.Cu")
		(net "P5E_PEX3_STN7_RX_DP<124>")
	)
	(segment
		(start 436.012082 -341.666068)
		(end 435.90972 -341.51824)
		(width 0.1651)
		(layer "In9.Cu")
		(net "P5E_PEX3_STN7_RX_DP<124>")
	)
	(segment
		(start 408.023314 -329.784202)
		(end 389.36295 -323.877432)
		(width 0.1651)
		(layer "In9.Cu")
		(net "P5E_PEX3_STN7_RX_DP<124>")
	)
	(segment
		(start 430.899062 -365.954818)
		(end 431.022252 -365.929926)
		(width 0.1651)
		(layer "In9.Cu")
		(net "P5E_PEX3_STN7_RX_DP<124>")
	)
	(segment
		(start 429.165004 -368.725196)
		(end 430.002696 -367.464086)
		(width 0.1651)
		(layer "In9.Cu")
		(net "P5E_PEX3_STN7_RX_DP<124>")
	)
	(segment
		(start 428.416974 -382.699006)
		(end 428.63897 -382.699006)
		(width 0.1651)
		(layer "In9.Cu")
		(net "P5E_PEX3_STN7_RX_DP<124>")
	)
	(segment
		(start 431.668682 -364.956598)
		(end 431.942748 -364.544102)
		(width 0.1651)
		(layer "In9.Cu")
		(net "P5E_PEX3_STN7_RX_DP<124>")
	)
	(segment
		(start 431.271426 -365.39424)
		(end 431.545746 -364.98149)
		(width 0.1651)
		(layer "In9.Cu")
		(net "P5E_PEX3_STN7_RX_DP<124>")
	)
	(segment
		(start 431.545746 -364.98149)
		(end 431.668936 -364.956598)
		(width 0.1651)
		(layer "In9.Cu")
		(net "P5E_PEX3_STN7_RX_DP<124>")
	)
	(segment
		(start 432.19243 -364.008162)
		(end 432.31562 -363.98327)
		(width 0.1651)
		(layer "In9.Cu")
		(net "P5E_PEX3_STN7_RX_DP<124>")
	)
	(segment
		(start 436.012082 -358.418892)
		(end 436.012082 -341.666068)
		(width 0.1651)
		(layer "In9.Cu")
		(net "P5E_PEX3_STN7_RX_DP<124>")
	)
	(segment
		(start 431.296064 -365.517176)
		(end 431.296318 -365.51743)
		(width 0.1651)
		(layer "In9.Cu")
		(net "P5E_PEX3_STN7_RX_DP<124>")
	)
	(segment
		(start 429.165004 -382.172972)
		(end 429.165004 -368.725196)
		(width 0.1651)
		(layer "In9.Cu")
		(net "P5E_PEX3_STN7_RX_DP<124>")
	)
	(segment
		(start 432.31562 -363.98327)
		(end 432.315366 -363.983016)
		(width 0.1651)
		(layer "In9.Cu")
		(net "P5E_PEX3_STN7_RX_DP<124>")
	)
	(segment
		(start 431.943002 -364.544102)
		(end 431.91811 -364.420912)
		(width 0.1651)
		(layer "In9.Cu")
		(net "P5E_PEX3_STN7_RX_DP<124>")
	)
	(segment
		(start 428.63897 -382.699006)
		(end 429.165004 -382.172972)
		(width 0.1651)
		(layer "In9.Cu")
		(net "P5E_PEX3_STN7_RX_DP<124>")
	)
	(segment
		(start 387.43001 -316.506098)
		(end 387.706616 -316.229492)
		(width 0.1143)
		(layer "In9.Cu")
		(net "P5E_PEX3_STN7_RX_DP<124>")
	)
	(segment
		(start 387.706616 -316.229492)
		(end 387.91134 -316.229492)
		(width 0.1143)
		(layer "In9.Cu")
		(net "P5E_PEX3_STN7_RX_DP<124>")
	)
	(segment
		(start 421.349678 -336.065622)
		(end 408.023314 -329.784202)
		(width 0.1651)
		(layer "In9.Cu")
		(net "P5E_PEX3_STN7_RX_DP<124>")
	)
	(segment
		(start 430.375314 -366.903254)
		(end 430.64938 -366.490758)
		(width 0.1651)
		(layer "In9.Cu")
		(net "P5E_PEX3_STN7_RX_DP<124>")
	)
	(segment
		(start 389.36295 -323.877432)
		(end 388.061454 -322.94195)
		(width 0.1651)
		(layer "In9.Cu")
		(net "P5E_PEX3_STN7_RX_DP<124>")
	)
	(segment
		(start 430.002696 -367.464086)
		(end 429.977804 -367.340896)
		(width 0.1651)
		(layer "In9.Cu")
		(net "P5E_PEX3_STN7_RX_DP<124>")
	)
	(segment
		(start 431.91811 -364.420912)
		(end 432.19243 -364.008162)
		(width 0.1651)
		(layer "In9.Cu")
		(net "P5E_PEX3_STN7_RX_DP<124>")
	)
	(segment
		(start 430.624742 -366.367568)
		(end 430.899062 -365.954818)
		(width 0.1651)
		(layer "In9.Cu")
		(net "P5E_PEX3_STN7_RX_DP<124>")
	)
	(segment
		(start 388.00024 -315.850016)
		(end 387.999986 -315.849762)
		(width 0.1143)
		(layer "In9.Cu")
		(net "P5E_PEX3_STN7_RX_DP<124>")
	)
	(segment
		(start 431.942748 -364.544102)
		(end 431.943002 -364.544102)
		(width 0.1651)
		(layer "In9.Cu")
		(net "P5E_PEX3_STN7_RX_DP<124>")
	)
	(segment
		(start 429.977804 -367.340896)
		(end 430.252378 -366.928146)
		(width 0.1651)
		(layer "In9.Cu")
		(net "P5E_PEX3_STN7_RX_DP<124>")
	)
	(segment
		(start 387.43001 -319.819528)
		(end 387.43001 -316.506098)
		(width 0.1143)
		(layer "In9.Cu")
		(net "P5E_PEX3_STN7_RX_DP<124>")
	)
	(segment
		(start 431.668936 -364.956598)
		(end 431.668682 -364.956598)
		(width 0.1651)
		(layer "In9.Cu")
		(net "P5E_PEX3_STN7_RX_DP<124>")
	)
	(segment
		(start 388.00024 -316.140592)
		(end 388.00024 -315.850016)
		(width 0.1143)
		(layer "In9.Cu")
		(net "P5E_PEX3_STN7_RX_DP<124>")
	)
	(segment
		(start 431.021998 -365.929926)
		(end 431.296064 -365.517176)
		(width 0.1651)
		(layer "In9.Cu")
		(net "P5E_PEX3_STN7_RX_DP<124>")
	)
	(segment
		(start 430.64938 -366.490758)
		(end 430.649634 -366.490758)
		(width 0.1651)
		(layer "In9.Cu")
		(net "P5E_PEX3_STN7_RX_DP<124>")
	)
	(segment
		(start 432.315366 -363.983016)
		(end 436.012082 -358.418892)
		(width 0.1651)
		(layer "In9.Cu")
		(net "P5E_PEX3_STN7_RX_DP<124>")
	)
	(segment
		(start 387.38429 -319.893696)
		(end 387.38429 -319.865248)
		(width 0.1143)
		(layer "In9.Cu")
		(net "P5E_PEX3_STN7_RX_DP<124>")
	)
	(segment
		(start 430.375568 -366.903254)
		(end 430.375314 -366.903254)
		(width 0.1651)
		(layer "In9.Cu")
		(net "P5E_PEX3_STN7_RX_DP<124>")
	)
	(segment
		(start 435.90972 -341.51824)
		(end 421.349678 -336.065622)
		(width 0.1651)
		(layer "In9.Cu")
		(net "P5E_PEX3_STN7_RX_DP<124>")
	)
	(segment
		(start 430.649634 -366.490758)
		(end 430.624742 -366.367568)
		(width 0.1651)
		(layer "In9.Cu")
		(net "P5E_PEX3_STN7_RX_DP<124>")
	)
	(segment
		(start 428.289974 -382.572006)
		(end 428.416974 -382.699006)
		(width 0.1651)
		(layer "In9.Cu")
		(net "P5E_PEX3_STN7_RX_DP<124>")
	)
	(segment
		(start 68.169536 -146.355054)
		(end 68.006722 -146.517868)
		(width 0.13462)
		(layer "F.Cu")
		(net "P5E_PEX0_STN0_RX_DN<10>")
	)
	(segment
		(start 68.65747 -146.355054)
		(end 68.169536 -146.355054)
		(width 0.13462)
		(layer "F.Cu")
		(net "P5E_PEX0_STN0_RX_DN<10>")
	)
	(segment
		(start 68.006722 -146.517868)
		(end 67.351402 -146.517868)
		(width 0.13462)
		(layer "F.Cu")
		(net "P5E_PEX0_STN0_RX_DN<10>")
	)
	(segment
		(start 67.351402 -146.517868)
		(end 67.05727 -146.223736)
		(width 0.13462)
		(layer "F.Cu")
		(net "P5E_PEX0_STN0_RX_DN<10>")
	)
	(segment
		(start 79.323438 -275.379688)
		(end 79.485236 -275.379688)
		(width 0.1143)
		(layer "In5.Cu")
		(net "P5E_PEX0_STN0_RX_DN<10>")
	)
	(segment
		(start 72.187308 -152.90165)
		(end 73.872344 -155.166822)
		(width 0.1651)
		(layer "In5.Cu")
		(net "P5E_PEX0_STN0_RX_DN<10>")
	)
	(segment
		(start 79.26578 -271.773904)
		(end 79.26578 -271.802352)
		(width 0.1143)
		(layer "In5.Cu")
		(net "P5E_PEX0_STN0_RX_DN<10>")
	)
	(segment
		(start 79.485236 -275.379688)
		(end 79.599536 -275.265388)
		(width 0.1143)
		(layer "In5.Cu")
		(net "P5E_PEX0_STN0_RX_DN<10>")
	)
	(segment
		(start 75.163934 -156.471112)
		(end 76.278232 -161.011616)
		(width 0.1651)
		(layer "In5.Cu")
		(net "P5E_PEX0_STN0_RX_DN<10>")
	)
	(segment
		(start 67.3481 -146.514566)
		(end 67.945762 -146.514566)
		(width 0.1651)
		(layer "In5.Cu")
		(net "P5E_PEX0_STN0_RX_DN<10>")
	)
	(segment
		(start 79.26578 -271.041114)
		(end 79.26578 -271.773904)
		(width 0.1651)
		(layer "In5.Cu")
		(net "P5E_PEX0_STN0_RX_DN<10>")
	)
	(segment
		(start 73.872344 -155.166822)
		(end 74.829924 -155.949396)
		(width 0.1651)
		(layer "In5.Cu")
		(net "P5E_PEX0_STN0_RX_DN<10>")
	)
	(segment
		(start 79.26578 -271.802352)
		(end 79.22006 -271.848072)
		(width 0.1143)
		(layer "In5.Cu")
		(net "P5E_PEX0_STN0_RX_DN<10>")
	)
	(segment
		(start 69.618606 -148.18741)
		(end 71.26224 -150.631906)
		(width 0.1651)
		(layer "In5.Cu")
		(net "P5E_PEX0_STN0_RX_DN<10>")
	)
	(segment
		(start 71.26224 -150.631906)
		(end 72.187308 -152.90165)
		(width 0.1651)
		(layer "In5.Cu")
		(net "P5E_PEX0_STN0_RX_DN<10>")
	)
	(segment
		(start 67.05727 -146.223736)
		(end 67.3481 -146.514566)
		(width 0.1651)
		(layer "In5.Cu")
		(net "P5E_PEX0_STN0_RX_DN<10>")
	)
	(segment
		(start 79.599536 -275.265388)
		(end 79.599536 -274.999958)
		(width 0.1143)
		(layer "In5.Cu")
		(net "P5E_PEX0_STN0_RX_DN<10>")
	)
	(segment
		(start 79.792068 -260.494272)
		(end 79.827628 -268.182852)
		(width 0.1651)
		(layer "In5.Cu")
		(net "P5E_PEX0_STN0_RX_DN<10>")
	)
	(segment
		(start 74.829924 -155.949396)
		(end 75.163934 -156.471112)
		(width 0.1651)
		(layer "In5.Cu")
		(net "P5E_PEX0_STN0_RX_DN<10>")
	)
	(segment
		(start 79.22006 -271.848072)
		(end 79.22006 -275.27631)
		(width 0.1143)
		(layer "In5.Cu")
		(net "P5E_PEX0_STN0_RX_DN<10>")
	)
	(segment
		(start 79.22006 -275.27631)
		(end 79.323438 -275.379688)
		(width 0.1143)
		(layer "In5.Cu")
		(net "P5E_PEX0_STN0_RX_DN<10>")
	)
	(segment
		(start 79.827628 -268.182852)
		(end 79.26578 -271.041114)
		(width 0.1651)
		(layer "In5.Cu")
		(net "P5E_PEX0_STN0_RX_DN<10>")
	)
	(segment
		(start 67.945762 -146.514566)
		(end 69.618606 -148.18741)
		(width 0.1651)
		(layer "In5.Cu")
		(net "P5E_PEX0_STN0_RX_DN<10>")
	)
	(segment
		(start 76.278232 -161.011616)
		(end 79.792068 -260.494272)
		(width 0.1651)
		(layer "In5.Cu")
		(net "P5E_PEX0_STN0_RX_DN<10>")
	)
	(segment
		(start 283.500576 -134.3406)
		(end 283.325062 -134.165086)
		(width 0.13462)
		(layer "F.Cu")
		(net "P5E_PEX2_STN1_RX_DP<30>")
	)
	(segment
		(start 283.325062 -134.165086)
		(end 282.842462 -134.165086)
		(width 0.13462)
		(layer "F.Cu")
		(net "P5E_PEX2_STN1_RX_DP<30>")
	)
	(segment
		(start 285.989014 -134.3406)
		(end 283.500576 -134.3406)
		(width 0.13462)
		(layer "F.Cu")
		(net "P5E_PEX2_STN1_RX_DP<30>")
	)
	(segment
		(start 286.296862 -134.032752)
		(end 285.989014 -134.3406)
		(width 0.13462)
		(layer "F.Cu")
		(net "P5E_PEX2_STN1_RX_DP<30>")
	)
	(segment
		(start 304.533808 -271.398238)
		(end 304.533808 -271.526)
		(width 0.1651)
		(layer "In5.Cu")
		(net "P5E_PEX2_STN1_RX_DP<30>")
	)
	(segment
		(start 304.794412 -273.670014)
		(end 305.035204 -273.670014)
		(width 0.1143)
		(layer "In5.Cu")
		(net "P5E_PEX2_STN1_RX_DP<30>")
	)
	(segment
		(start 281.966162 -137.042906)
		(end 281.939238 -137.06983)
		(width 0.1651)
		(layer "In5.Cu")
		(net "P5E_PEX2_STN1_RX_DP<30>")
	)
	(segment
		(start 284.081474 -134.323582)
		(end 283.179266 -134.697216)
		(width 0.1651)
		(layer "In5.Cu")
		(net "P5E_PEX2_STN1_RX_DP<30>")
	)
	(segment
		(start 281.103578 -143.171164)
		(end 280.19756 -144.077182)
		(width 0.1651)
		(layer "In5.Cu")
		(net "P5E_PEX2_STN1_RX_DP<30>")
	)
	(segment
		(start 304.533808 -271.526)
		(end 304.533808 -271.554448)
		(width 0.1143)
		(layer "In5.Cu")
		(net "P5E_PEX2_STN1_RX_DP<30>")
	)
	(segment
		(start 274.89912 -148.044154)
		(end 275.476462 -156.747972)
		(width 0.1651)
		(layer "In5.Cu")
		(net "P5E_PEX2_STN1_RX_DP<30>")
	)
	(segment
		(start 278.751792 -145.262854)
		(end 278.431752 -145.741136)
		(width 0.1651)
		(layer "In5.Cu")
		(net "P5E_PEX2_STN1_RX_DP<30>")
	)
	(segment
		(start 305.035204 -273.670014)
		(end 305.149504 -273.784314)
		(width 0.1143)
		(layer "In5.Cu")
		(net "P5E_PEX2_STN1_RX_DP<30>")
	)
	(segment
		(start 275.476462 -156.747972)
		(end 276.192488 -160.767776)
		(width 0.1651)
		(layer "In5.Cu")
		(net "P5E_PEX2_STN1_RX_DP<30>")
	)
	(segment
		(start 283.179266 -134.697216)
		(end 282.990798 -134.87654)
		(width 0.1651)
		(layer "In5.Cu")
		(net "P5E_PEX2_STN1_RX_DP<30>")
	)
	(segment
		(start 304.533808 -271.554448)
		(end 304.579528 -271.600168)
		(width 0.1143)
		(layer "In5.Cu")
		(net "P5E_PEX2_STN1_RX_DP<30>")
	)
	(segment
		(start 304.5333 -271.39773)
		(end 304.533808 -271.398238)
		(width 0.1651)
		(layer "In5.Cu")
		(net "P5E_PEX2_STN1_RX_DP<30>")
	)
	(segment
		(start 275.615654 -147.087844)
		(end 275.213572 -147.389596)
		(width 0.1651)
		(layer "In5.Cu")
		(net "P5E_PEX2_STN1_RX_DP<30>")
	)
	(segment
		(start 281.939238 -141.153642)
		(end 281.103578 -143.171164)
		(width 0.1651)
		(layer "In5.Cu")
		(net "P5E_PEX2_STN1_RX_DP<30>")
	)
	(segment
		(start 286.006032 -134.323582)
		(end 284.081474 -134.323582)
		(width 0.1651)
		(layer "In5.Cu")
		(net "P5E_PEX2_STN1_RX_DP<30>")
	)
	(segment
		(start 304.579528 -271.600168)
		(end 304.579528 -273.45513)
		(width 0.1143)
		(layer "In5.Cu")
		(net "P5E_PEX2_STN1_RX_DP<30>")
	)
	(segment
		(start 276.192488 -160.767776)
		(end 304.533808 -267.270738)
		(width 0.1651)
		(layer "In5.Cu")
		(net "P5E_PEX2_STN1_RX_DP<30>")
	)
	(segment
		(start 276.644354 -146.8882)
		(end 276.165818 -146.8882)
		(width 0.1651)
		(layer "In5.Cu")
		(net "P5E_PEX2_STN1_RX_DP<30>")
	)
	(segment
		(start 275.803868 -146.99361)
		(end 275.615654 -147.087844)
		(width 0.1651)
		(layer "In5.Cu")
		(net "P5E_PEX2_STN1_RX_DP<30>")
	)
	(segment
		(start 305.149504 -273.784314)
		(end 305.149504 -274.049744)
		(width 0.1143)
		(layer "In5.Cu")
		(net "P5E_PEX2_STN1_RX_DP<30>")
	)
	(segment
		(start 277.737316 -146.435572)
		(end 276.644354 -146.8882)
		(width 0.1651)
		(layer "In5.Cu")
		(net "P5E_PEX2_STN1_RX_DP<30>")
	)
	(segment
		(start 304.579528 -273.45513)
		(end 304.794412 -273.670014)
		(width 0.1143)
		(layer "In5.Cu")
		(net "P5E_PEX2_STN1_RX_DP<30>")
	)
	(segment
		(start 304.533808 -267.270738)
		(end 304.533808 -271.396714)
		(width 0.1651)
		(layer "In5.Cu")
		(net "P5E_PEX2_STN1_RX_DP<30>")
	)
	(segment
		(start 275.213572 -147.389596)
		(end 274.89912 -148.044154)
		(width 0.1651)
		(layer "In5.Cu")
		(net "P5E_PEX2_STN1_RX_DP<30>")
	)
	(segment
		(start 278.431752 -145.741136)
		(end 277.737316 -146.435572)
		(width 0.1651)
		(layer "In5.Cu")
		(net "P5E_PEX2_STN1_RX_DP<30>")
	)
	(segment
		(start 276.165818 -146.8882)
		(end 275.803868 -146.99361)
		(width 0.1651)
		(layer "In5.Cu")
		(net "P5E_PEX2_STN1_RX_DP<30>")
	)
	(segment
		(start 286.296862 -134.032752)
		(end 286.006032 -134.323582)
		(width 0.1651)
		(layer "In5.Cu")
		(net "P5E_PEX2_STN1_RX_DP<30>")
	)
	(segment
		(start 304.5333 -271.397222)
		(end 304.5333 -271.39773)
		(width 0.1651)
		(layer "In5.Cu")
		(net "P5E_PEX2_STN1_RX_DP<30>")
	)
	(segment
		(start 282.990798 -134.87654)
		(end 281.966162 -137.042906)
		(width 0.1651)
		(layer "In5.Cu")
		(net "P5E_PEX2_STN1_RX_DP<30>")
	)
	(segment
		(start 280.19756 -144.077182)
		(end 278.751792 -145.262854)
		(width 0.1651)
		(layer "In5.Cu")
		(net "P5E_PEX2_STN1_RX_DP<30>")
	)
	(segment
		(start 281.939238 -137.06983)
		(end 281.939238 -141.153642)
		(width 0.1651)
		(layer "In5.Cu")
		(net "P5E_PEX2_STN1_RX_DP<30>")
	)
	(segment
		(start 304.533808 -271.396714)
		(end 304.5333 -271.397222)
		(width 0.1651)
		(layer "In5.Cu")
		(net "P5E_PEX2_STN1_RX_DP<30>")
	)
	(segment
		(start 358.964992 -28.390088)
		(end 358.48417 -28.390088)
		(width 0.13462)
		(layer "F.Cu")
		(net "P5E_PEX3_STN2_RX_DN<44>")
	)
	(segment
		(start 358.48417 -28.390088)
		(end 358.332278 -28.54198)
		(width 0.13462)
		(layer "F.Cu")
		(net "P5E_PEX3_STN2_RX_DN<44>")
	)
	(segment
		(start 358.332278 -28.54198)
		(end 357.648002 -28.54198)
		(width 0.13462)
		(layer "F.Cu")
		(net "P5E_PEX3_STN2_RX_DN<44>")
	)
	(segment
		(start 357.648002 -28.54198)
		(end 357.364792 -28.25877)
		(width 0.13462)
		(layer "F.Cu")
		(net "P5E_PEX3_STN2_RX_DN<44>")
	)
	(segment
		(start 371.776752 -119.34952)
		(end 375.065798 -144.353534)
		(width 0.1651)
		(layer "In7.Cu")
		(net "P5E_PEX3_STN2_RX_DN<44>")
	)
	(segment
		(start 394.312902 -263.459722)
		(end 395.265656 -269.50162)
		(width 0.1651)
		(layer "In7.Cu")
		(net "P5E_PEX3_STN2_RX_DN<44>")
	)
	(segment
		(start 392.781282 -238.036354)
		(end 394.389864 -255.60782)
		(width 0.1651)
		(layer "In7.Cu")
		(net "P5E_PEX3_STN2_RX_DN<44>")
	)
	(segment
		(start 357.66375 -28.5496)
		(end 358.103932 -28.5496)
		(width 0.1651)
		(layer "In7.Cu")
		(net "P5E_PEX3_STN2_RX_DN<44>")
	)
	(segment
		(start 395.323822 -275.379688)
		(end 395.48562 -275.379688)
		(width 0.1143)
		(layer "In7.Cu")
		(net "P5E_PEX3_STN2_RX_DN<44>")
	)
	(segment
		(start 361.337352 -57.32399)
		(end 361.606846 -60.059824)
		(width 0.1651)
		(layer "In7.Cu")
		(net "P5E_PEX3_STN2_RX_DN<44>")
	)
	(segment
		(start 395.265656 -271.392904)
		(end 395.265656 -271.421352)
		(width 0.1143)
		(layer "In7.Cu")
		(net "P5E_PEX3_STN2_RX_DN<44>")
	)
	(segment
		(start 363.606842 -39.16934)
		(end 361.460796 -49.41951)
		(width 0.1651)
		(layer "In7.Cu")
		(net "P5E_PEX3_STN2_RX_DN<44>")
	)
	(segment
		(start 357.657908 -28.551886)
		(end 357.66375 -28.5496)
		(width 0.1651)
		(layer "In7.Cu")
		(net "P5E_PEX3_STN2_RX_DN<44>")
	)
	(segment
		(start 359.01503 -29.460698)
		(end 359.67924 -30.4546)
		(width 0.1651)
		(layer "In7.Cu")
		(net "P5E_PEX3_STN2_RX_DN<44>")
	)
	(segment
		(start 395.219936 -275.275802)
		(end 395.323822 -275.379688)
		(width 0.1143)
		(layer "In7.Cu")
		(net "P5E_PEX3_STN2_RX_DN<44>")
	)
	(segment
		(start 395.48562 -275.379688)
		(end 395.59992 -275.265388)
		(width 0.1143)
		(layer "In7.Cu")
		(net "P5E_PEX3_STN2_RX_DN<44>")
	)
	(segment
		(start 358.103932 -28.5496)
		(end 359.01503 -29.460698)
		(width 0.1651)
		(layer "In7.Cu")
		(net "P5E_PEX3_STN2_RX_DN<44>")
	)
	(segment
		(start 375.065798 -144.353534)
		(end 392.781282 -238.036354)
		(width 0.1651)
		(layer "In7.Cu")
		(net "P5E_PEX3_STN2_RX_DN<44>")
	)
	(segment
		(start 361.41787 -85.173566)
		(end 371.776752 -119.34952)
		(width 0.1651)
		(layer "In7.Cu")
		(net "P5E_PEX3_STN2_RX_DN<44>")
	)
	(segment
		(start 395.265656 -271.421352)
		(end 395.219936 -271.467072)
		(width 0.1143)
		(layer "In7.Cu")
		(net "P5E_PEX3_STN2_RX_DN<44>")
	)
	(segment
		(start 395.59992 -275.265388)
		(end 395.59992 -274.999958)
		(width 0.1143)
		(layer "In7.Cu")
		(net "P5E_PEX3_STN2_RX_DN<44>")
	)
	(segment
		(start 361.606846 -60.059824)
		(end 361.606846 -61.851032)
		(width 0.1651)
		(layer "In7.Cu")
		(net "P5E_PEX3_STN2_RX_DN<44>")
	)
	(segment
		(start 394.389864 -255.60782)
		(end 394.312902 -263.459722)
		(width 0.1651)
		(layer "In7.Cu")
		(net "P5E_PEX3_STN2_RX_DN<44>")
	)
	(segment
		(start 359.67924 -30.4546)
		(end 361.242864 -32.018224)
		(width 0.1651)
		(layer "In7.Cu")
		(net "P5E_PEX3_STN2_RX_DN<44>")
	)
	(segment
		(start 361.460796 -49.41951)
		(end 361.337352 -57.32399)
		(width 0.1651)
		(layer "In7.Cu")
		(net "P5E_PEX3_STN2_RX_DN<44>")
	)
	(segment
		(start 395.265656 -269.50162)
		(end 395.265656 -271.392904)
		(width 0.1651)
		(layer "In7.Cu")
		(net "P5E_PEX3_STN2_RX_DN<44>")
	)
	(segment
		(start 361.242864 -32.018224)
		(end 363.63148 -37.688012)
		(width 0.1651)
		(layer "In7.Cu")
		(net "P5E_PEX3_STN2_RX_DN<44>")
	)
	(segment
		(start 363.63148 -37.688012)
		(end 363.606842 -39.16934)
		(width 0.1651)
		(layer "In7.Cu")
		(net "P5E_PEX3_STN2_RX_DN<44>")
	)
	(segment
		(start 357.364792 -28.25877)
		(end 357.657908 -28.551886)
		(width 0.1651)
		(layer "In7.Cu")
		(net "P5E_PEX3_STN2_RX_DN<44>")
	)
	(segment
		(start 395.219936 -271.467072)
		(end 395.219936 -275.275802)
		(width 0.1143)
		(layer "In7.Cu")
		(net "P5E_PEX3_STN2_RX_DN<44>")
	)
	(segment
		(start 361.606846 -61.851032)
		(end 361.41787 -85.173566)
		(width 0.1651)
		(layer "In7.Cu")
		(net "P5E_PEX3_STN2_RX_DN<44>")
	)
	(segment
		(start 437.8452 -351.317306)
		(end 438.139332 -351.611438)
		(width 0.13462)
		(layer "F.Cu")
		(net "P5E_PEX3_STN7_TX_C_DN<125>")
	)
	(segment
		(start 437.8452 -350.684846)
		(end 437.8452 -351.317306)
		(width 0.13462)
		(layer "F.Cu")
		(net "P5E_PEX3_STN7_TX_C_DN<125>")
	)
	(segment
		(start 438.164732 -350.365314)
		(end 437.8452 -350.684846)
		(width 0.13462)
		(layer "F.Cu")
		(net "P5E_PEX3_STN7_TX_C_DN<125>")
	)
	(segment
		(start 436.294022 -358.077516)
		(end 436.294022 -354.027486)
		(width 0.1651)
		(layer "In11.Cu")
		(net "P5E_PEX3_STN7_TX_C_DN<125>")
	)
	(segment
		(start 430.489868 -376.408188)
		(end 430.616868 -376.281188)
		(width 0.1651)
		(layer "In11.Cu")
		(net "P5E_PEX3_STN7_TX_C_DN<125>")
	)
	(segment
		(start 435.947566 -359.623106)
		(end 436.294022 -358.077516)
		(width 0.1651)
		(layer "In11.Cu")
		(net "P5E_PEX3_STN7_TX_C_DN<125>")
	)
	(segment
		(start 436.294022 -354.027486)
		(end 437.848502 -352.473006)
		(width 0.1651)
		(layer "In11.Cu")
		(net "P5E_PEX3_STN7_TX_C_DN<125>")
	)
	(segment
		(start 431.163984 -376.281188)
		(end 431.61585 -375.829322)
		(width 0.1651)
		(layer "In11.Cu")
		(net "P5E_PEX3_STN7_TX_C_DN<125>")
	)
	(segment
		(start 431.61585 -369.717574)
		(end 432.00701 -367.972848)
		(width 0.1651)
		(layer "In11.Cu")
		(net "P5E_PEX3_STN7_TX_C_DN<125>")
	)
	(segment
		(start 432.00701 -367.972848)
		(end 435.947566 -359.623106)
		(width 0.1651)
		(layer "In11.Cu")
		(net "P5E_PEX3_STN7_TX_C_DN<125>")
	)
	(segment
		(start 431.61585 -375.829322)
		(end 431.61585 -369.717574)
		(width 0.1651)
		(layer "In11.Cu")
		(net "P5E_PEX3_STN7_TX_C_DN<125>")
	)
	(segment
		(start 437.848502 -352.473006)
		(end 437.848502 -351.902268)
		(width 0.1651)
		(layer "In11.Cu")
		(net "P5E_PEX3_STN7_TX_C_DN<125>")
	)
	(segment
		(start 430.616868 -376.281188)
		(end 431.163984 -376.281188)
		(width 0.1651)
		(layer "In11.Cu")
		(net "P5E_PEX3_STN7_TX_C_DN<125>")
	)
	(segment
		(start 437.848502 -351.902268)
		(end 438.139332 -351.611438)
		(width 0.1651)
		(layer "In11.Cu")
		(net "P5E_PEX3_STN7_TX_C_DN<125>")
	)
	(segment
		(start 430.489868 -376.790204)
		(end 430.489868 -376.408188)
		(width 0.1651)
		(layer "In11.Cu")
		(net "P5E_PEX3_STN7_TX_C_DN<125>")
	)
	(segment
		(start 73.908666 -122.872246)
		(end 79.440278 -122.872246)
		(width 0.13462)
		(layer "F.Cu")
		(net "P5E_PEX0_STN0_TX_C_DP<2>")
	)
	(segment
		(start 73.257664 -123.03506)
		(end 73.745852 -123.03506)
		(width 0.13462)
		(layer "F.Cu")
		(net "P5E_PEX0_STN0_TX_C_DP<2>")
	)
	(segment
		(start 79.440278 -122.872246)
		(end 79.752698 -123.184666)
		(width 0.13462)
		(layer "F.Cu")
		(net "P5E_PEX0_STN0_TX_C_DP<2>")
	)
	(segment
		(start 73.745852 -123.03506)
		(end 73.908666 -122.872246)
		(width 0.13462)
		(layer "F.Cu")
		(net "P5E_PEX0_STN0_TX_C_DP<2>")
	)
	(segment
		(start 277.558246 -110.6678)
		(end 277.735538 -110.845092)
		(width 0.13462)
		(layer "F.Cu")
		(net "P5E_PEX2_STN1_TX_C_DN<22>")
	)
	(segment
		(start 272.082768 -110.6678)
		(end 277.558246 -110.6678)
		(width 0.13462)
		(layer "F.Cu")
		(net "P5E_PEX2_STN1_TX_C_DN<22>")
	)
	(segment
		(start 271.747234 -111.003334)
		(end 272.082768 -110.6678)
		(width 0.13462)
		(layer "F.Cu")
		(net "P5E_PEX2_STN1_TX_C_DN<22>")
	)
	(segment
		(start 277.735538 -110.845092)
		(end 278.242268 -110.845092)
		(width 0.13462)
		(layer "F.Cu")
		(net "P5E_PEX2_STN1_TX_C_DN<22>")
	)
	(segment
		(start 364.067852 -34.390076)
		(end 363.564932 -34.390076)
		(width 0.13462)
		(layer "F.Cu")
		(net "P5E_PEX3_STN2_TX_C_DP<47>")
	)
	(segment
		(start 368.467894 -34.546286)
		(end 368.155728 -34.23412)
		(width 0.13462)
		(layer "F.Cu")
		(net "P5E_PEX3_STN2_TX_C_DP<47>")
	)
	(segment
		(start 364.223808 -34.23412)
		(end 364.067852 -34.390076)
		(width 0.13462)
		(layer "F.Cu")
		(net "P5E_PEX3_STN2_TX_C_DP<47>")
	)
	(segment
		(start 368.155728 -34.23412)
		(end 364.223808 -34.23412)
		(width 0.13462)
		(layer "F.Cu")
		(net "P5E_PEX3_STN2_TX_C_DP<47>")
	)
	(segment
		(start 380.546102 -301.933864)
		(end 383.892552 -301.933864)
		(width 0.1651)
		(layer "In9.Cu")
		(net "P5E_PEX3_STN7_RX_DP<113>")
	)
	(segment
		(start 420.260526 -393.430252)
		(end 418.207698 -392.700002)
		(width 0.1651)
		(layer "In9.Cu")
		(net "P5E_PEX3_STN7_RX_DP<113>")
	)
	(segment
		(start 375.086626 -303.379886)
		(end 376.49531 -302.79594)
		(width 0.1651)
		(layer "In9.Cu")
		(net "P5E_PEX3_STN7_RX_DP<113>")
	)
	(segment
		(start 372.77421 -305.69281)
		(end 375.086626 -303.379886)
		(width 0.1651)
		(layer "In9.Cu")
		(net "P5E_PEX3_STN7_RX_DP<113>")
	)
	(segment
		(start 385.724654 -302.455326)
		(end 385.819142 -302.549814)
		(width 0.1143)
		(layer "In9.Cu")
		(net "P5E_PEX3_STN7_RX_DP<113>")
	)
	(segment
		(start 412.474156 -387.051296)
		(end 411.764734 -385.184142)
		(width 0.1651)
		(layer "In9.Cu")
		(net "P5E_PEX3_STN7_RX_DP<113>")
	)
	(segment
		(start 420.260526 -393.429998)
		(end 420.260526 -393.430252)
		(width 0.1651)
		(layer "In9.Cu")
		(net "P5E_PEX3_STN7_RX_DP<113>")
	)
	(segment
		(start 366.752124 -323.40677)
		(end 366.752124 -318.252602)
		(width 0.1651)
		(layer "In9.Cu")
		(net "P5E_PEX3_STN7_RX_DP<113>")
	)
	(segment
		(start 385.724654 -302.223424)
		(end 385.724654 -302.455326)
		(width 0.1143)
		(layer "In9.Cu")
		(net "P5E_PEX3_STN7_RX_DP<113>")
	)
	(segment
		(start 405.968708 -349.38335)
		(end 404.107904 -342.043004)
		(width 0.1651)
		(layer "In9.Cu")
		(net "P5E_PEX3_STN7_RX_DP<113>")
	)
	(segment
		(start 411.764734 -385.184142)
		(end 410.639006 -376.841766)
		(width 0.1651)
		(layer "In9.Cu")
		(net "P5E_PEX3_STN7_RX_DP<113>")
	)
	(segment
		(start 385.819142 -302.549814)
		(end 386.099812 -302.549814)
		(width 0.1143)
		(layer "In9.Cu")
		(net "P5E_PEX3_STN7_RX_DP<113>")
	)
	(segment
		(start 378.997972 -302.424592)
		(end 380.546102 -301.933864)
		(width 0.1651)
		(layer "In9.Cu")
		(net "P5E_PEX3_STN7_RX_DP<113>")
	)
	(segment
		(start 418.207698 -392.700002)
		(end 413.923226 -389.208518)
		(width 0.1651)
		(layer "In9.Cu")
		(net "P5E_PEX3_STN7_RX_DP<113>")
	)
	(segment
		(start 374.029224 -332.921356)
		(end 368.33429 -327.226676)
		(width 0.1651)
		(layer "In9.Cu")
		(net "P5E_PEX3_STN7_RX_DP<113>")
	)
	(segment
		(start 422.57218 -395.55801)
		(end 422.163494 -394.571474)
		(width 0.1651)
		(layer "In9.Cu")
		(net "P5E_PEX3_STN7_RX_DP<113>")
	)
	(segment
		(start 385.480814 -301.979584)
		(end 385.724654 -302.223424)
		(width 0.1143)
		(layer "In9.Cu")
		(net "P5E_PEX3_STN7_RX_DP<113>")
	)
	(segment
		(start 413.923226 -389.208518)
		(end 412.474156 -387.051296)
		(width 0.1651)
		(layer "In9.Cu")
		(net "P5E_PEX3_STN7_RX_DP<113>")
	)
	(segment
		(start 420.7891 -393.726162)
		(end 420.322248 -393.560046)
		(width 0.1651)
		(layer "In9.Cu")
		(net "P5E_PEX3_STN7_RX_DP<113>")
	)
	(segment
		(start 410.639006 -376.841766)
		(end 406.078436 -351.9424)
		(width 0.1651)
		(layer "In9.Cu")
		(net "P5E_PEX3_STN7_RX_DP<113>")
	)
	(segment
		(start 366.752124 -318.252602)
		(end 369.128294 -312.514996)
		(width 0.1651)
		(layer "In9.Cu")
		(net "P5E_PEX3_STN7_RX_DP<113>")
	)
	(segment
		(start 421.689784 -409.672028)
		(end 421.816784 -409.799028)
		(width 0.1651)
		(layer "In9.Cu")
		(net "P5E_PEX3_STN7_RX_DP<113>")
	)
	(segment
		(start 421.689784 -409.290012)
		(end 421.689784 -409.672028)
		(width 0.1651)
		(layer "In9.Cu")
		(net "P5E_PEX3_STN7_RX_DP<113>")
	)
	(segment
		(start 383.921 -301.933864)
		(end 383.96672 -301.979584)
		(width 0.1143)
		(layer "In9.Cu")
		(net "P5E_PEX3_STN7_RX_DP<113>")
	)
	(segment
		(start 421.442642 -393.850622)
		(end 420.918894 -393.66444)
		(width 0.1651)
		(layer "In9.Cu")
		(net "P5E_PEX3_STN7_RX_DP<113>")
	)
	(segment
		(start 383.892552 -301.933864)
		(end 383.921 -301.933864)
		(width 0.1143)
		(layer "In9.Cu")
		(net "P5E_PEX3_STN7_RX_DP<113>")
	)
	(segment
		(start 406.078436 -351.9424)
		(end 405.968708 -349.38335)
		(width 0.1651)
		(layer "In9.Cu")
		(net "P5E_PEX3_STN7_RX_DP<113>")
	)
	(segment
		(start 383.96672 -301.979584)
		(end 385.480814 -301.979584)
		(width 0.1143)
		(layer "In9.Cu")
		(net "P5E_PEX3_STN7_RX_DP<113>")
	)
	(segment
		(start 368.33429 -327.226676)
		(end 366.752124 -323.40677)
		(width 0.1651)
		(layer "In9.Cu")
		(net "P5E_PEX3_STN7_RX_DP<113>")
	)
	(segment
		(start 396.955772 -338.533232)
		(end 378.122942 -334.212438)
		(width 0.1651)
		(layer "In9.Cu")
		(net "P5E_PEX3_STN7_RX_DP<113>")
	)
	(segment
		(start 403.592792 -341.435944)
		(end 396.955772 -338.533232)
		(width 0.1651)
		(layer "In9.Cu")
		(net "P5E_PEX3_STN7_RX_DP<113>")
	)
	(segment
		(start 421.816784 -409.799028)
		(end 422.038272 -409.799028)
		(width 0.1651)
		(layer "In9.Cu")
		(net "P5E_PEX3_STN7_RX_DP<113>")
	)
	(segment
		(start 378.122942 -334.212438)
		(end 374.029224 -332.921356)
		(width 0.1651)
		(layer "In9.Cu")
		(net "P5E_PEX3_STN7_RX_DP<113>")
	)
	(segment
		(start 404.107904 -342.043004)
		(end 403.592792 -341.435944)
		(width 0.1651)
		(layer "In9.Cu")
		(net "P5E_PEX3_STN7_RX_DP<113>")
	)
	(segment
		(start 369.128294 -312.514996)
		(end 372.77421 -305.69281)
		(width 0.1651)
		(layer "In9.Cu")
		(net "P5E_PEX3_STN7_RX_DP<113>")
	)
	(segment
		(start 422.163494 -394.571474)
		(end 421.442642 -393.850622)
		(width 0.1651)
		(layer "In9.Cu")
		(net "P5E_PEX3_STN7_RX_DP<113>")
	)
	(segment
		(start 376.49531 -302.79594)
		(end 378.997972 -302.424592)
		(width 0.1651)
		(layer "In9.Cu")
		(net "P5E_PEX3_STN7_RX_DP<113>")
	)
	(segment
		(start 420.918894 -393.66444)
		(end 420.7891 -393.726162)
		(width 0.1651)
		(layer "In9.Cu")
		(net "P5E_PEX3_STN7_RX_DP<113>")
	)
	(segment
		(start 422.038272 -409.799028)
		(end 422.57218 -409.26512)
		(width 0.1651)
		(layer "In9.Cu")
		(net "P5E_PEX3_STN7_RX_DP<113>")
	)
	(segment
		(start 422.57218 -409.26512)
		(end 422.57218 -395.55801)
		(width 0.1651)
		(layer "In9.Cu")
		(net "P5E_PEX3_STN7_RX_DP<113>")
	)
	(segment
		(start 420.322248 -393.560046)
		(end 420.260526 -393.429998)
		(width 0.1651)
		(layer "In9.Cu")
		(net "P5E_PEX3_STN7_RX_DP<113>")
	)
	(segment
		(start 67.352164 -134.082282)
		(end 68.006722 -134.082282)
		(width 0.13462)
		(layer "F.Cu")
		(net "P5E_PEX0_STN0_RX_DP<6>")
	)
	(segment
		(start 68.169536 -134.245096)
		(end 68.65747 -134.245096)
		(width 0.13462)
		(layer "F.Cu")
		(net "P5E_PEX0_STN0_RX_DP<6>")
	)
	(segment
		(start 67.05727 -134.377176)
		(end 67.352164 -134.082282)
		(width 0.13462)
		(layer "F.Cu")
		(net "P5E_PEX0_STN0_RX_DP<6>")
	)
	(segment
		(start 68.006722 -134.082282)
		(end 68.169536 -134.245096)
		(width 0.13462)
		(layer "F.Cu")
		(net "P5E_PEX0_STN0_RX_DP<6>")
	)
	(segment
		(start 84.25053 -281.983942)
		(end 84.815172 -281.606244)
		(width 0.1651)
		(layer "In5.Cu")
		(net "P5E_PEX0_STN0_RX_DP<6>")
	)
	(segment
		(start 76.467208 -139.025376)
		(end 76.130658 -138.625326)
		(width 0.1651)
		(layer "In5.Cu")
		(net "P5E_PEX0_STN0_RX_DP<6>")
	)
	(segment
		(start 68.58635 -134.575296)
		(end 67.675506 -134.086346)
		(width 0.1651)
		(layer "In5.Cu")
		(net "P5E_PEX0_STN0_RX_DP<6>")
	)
	(segment
		(start 80.223614 -282.029662)
		(end 83.85048 -282.029662)
		(width 0.1143)
		(layer "In5.Cu")
		(net "P5E_PEX0_STN0_RX_DP<6>")
	)
	(segment
		(start 70.73519 -135.728964)
		(end 70.298818 -135.494776)
		(width 0.1651)
		(layer "In5.Cu")
		(net "P5E_PEX0_STN0_RX_DP<6>")
	)
	(segment
		(start 83.8962 -281.983942)
		(end 83.924648 -281.983942)
		(width 0.1143)
		(layer "In5.Cu")
		(net "P5E_PEX0_STN0_RX_DP<6>")
	)
	(segment
		(start 84.815172 -281.606244)
		(end 85.255862 -281.074368)
		(width 0.1651)
		(layer "In5.Cu")
		(net "P5E_PEX0_STN0_RX_DP<6>")
	)
	(segment
		(start 72.109076 -136.46658)
		(end 71.373238 -136.07161)
		(width 0.1651)
		(layer "In5.Cu")
		(net "P5E_PEX0_STN0_RX_DP<6>")
	)
	(segment
		(start 69.224398 -134.917942)
		(end 69.069712 -134.964678)
		(width 0.1651)
		(layer "In5.Cu")
		(net "P5E_PEX0_STN0_RX_DP<6>")
	)
	(segment
		(start 71.373238 -136.07161)
		(end 71.218298 -136.118092)
		(width 0.1651)
		(layer "In5.Cu")
		(net "P5E_PEX0_STN0_RX_DP<6>")
	)
	(segment
		(start 72.155558 -136.621266)
		(end 72.109076 -136.46658)
		(width 0.1651)
		(layer "In5.Cu")
		(net "P5E_PEX0_STN0_RX_DP<6>")
	)
	(segment
		(start 73.183496 -137.04316)
		(end 72.747124 -136.808972)
		(width 0.1651)
		(layer "In5.Cu")
		(net "P5E_PEX0_STN0_RX_DP<6>")
	)
	(segment
		(start 72.592184 -136.855708)
		(end 72.155558 -136.621266)
		(width 0.1651)
		(layer "In5.Cu")
		(net "P5E_PEX0_STN0_RX_DP<6>")
	)
	(segment
		(start 67.675506 -134.086346)
		(end 67.3481 -134.086346)
		(width 0.1651)
		(layer "In5.Cu")
		(net "P5E_PEX0_STN0_RX_DP<6>")
	)
	(segment
		(start 72.747124 -136.808972)
		(end 72.592184 -136.855708)
		(width 0.1651)
		(layer "In5.Cu")
		(net "P5E_PEX0_STN0_RX_DP<6>")
	)
	(segment
		(start 74.895964 -137.96264)
		(end 74.741024 -138.009122)
		(width 0.1651)
		(layer "In5.Cu")
		(net "P5E_PEX0_STN0_RX_DP<6>")
	)
	(segment
		(start 76.60386 -139.813284)
		(end 76.467208 -139.025376)
		(width 0.1651)
		(layer "In5.Cu")
		(net "P5E_PEX0_STN0_RX_DP<6>")
	)
	(segment
		(start 85.551264 -277.085552)
		(end 85.551264 -276.721316)
		(width 0.1651)
		(layer "In5.Cu")
		(net "P5E_PEX0_STN0_RX_DP<6>")
	)
	(segment
		(start 69.707252 -135.306816)
		(end 69.66077 -135.15213)
		(width 0.1651)
		(layer "In5.Cu")
		(net "P5E_PEX0_STN0_RX_DP<6>")
	)
	(segment
		(start 67.3481 -134.086346)
		(end 67.05727 -134.377176)
		(width 0.1651)
		(layer "In5.Cu")
		(net "P5E_PEX0_STN0_RX_DP<6>")
	)
	(segment
		(start 76.60386 -140.932662)
		(end 76.60386 -139.813284)
		(width 0.1651)
		(layer "In5.Cu")
		(net "P5E_PEX0_STN0_RX_DP<6>")
	)
	(segment
		(start 85.255862 -281.074368)
		(end 85.464396 -280.582116)
		(width 0.1651)
		(layer "In5.Cu")
		(net "P5E_PEX0_STN0_RX_DP<6>")
	)
	(segment
		(start 79.97952 -282.485592)
		(end 79.97952 -282.273756)
		(width 0.1143)
		(layer "In5.Cu")
		(net "P5E_PEX0_STN0_RX_DP<6>")
	)
	(segment
		(start 73.821544 -137.385806)
		(end 73.666604 -137.432288)
		(width 0.1651)
		(layer "In5.Cu")
		(net "P5E_PEX0_STN0_RX_DP<6>")
	)
	(segment
		(start 79.97952 -282.273756)
		(end 80.223614 -282.029662)
		(width 0.1143)
		(layer "In5.Cu")
		(net "P5E_PEX0_STN0_RX_DP<6>")
	)
	(segment
		(start 73.229978 -137.197846)
		(end 73.183496 -137.04316)
		(width 0.1651)
		(layer "In5.Cu")
		(net "P5E_PEX0_STN0_RX_DP<6>")
	)
	(segment
		(start 84.428584 -270.821404)
		(end 83.512152 -264.723118)
		(width 0.1651)
		(layer "In5.Cu")
		(net "P5E_PEX0_STN0_RX_DP<6>")
	)
	(segment
		(start 83.512152 -264.723118)
		(end 79.956152 -160.27273)
		(width 0.1651)
		(layer "In5.Cu")
		(net "P5E_PEX0_STN0_RX_DP<6>")
	)
	(segment
		(start 69.66077 -135.15213)
		(end 69.224398 -134.917942)
		(width 0.1651)
		(layer "In5.Cu")
		(net "P5E_PEX0_STN0_RX_DP<6>")
	)
	(segment
		(start 74.304398 -137.77468)
		(end 74.257916 -137.619994)
		(width 0.1651)
		(layer "In5.Cu")
		(net "P5E_PEX0_STN0_RX_DP<6>")
	)
	(segment
		(start 71.218298 -136.118092)
		(end 70.781672 -135.88365)
		(width 0.1651)
		(layer "In5.Cu")
		(net "P5E_PEX0_STN0_RX_DP<6>")
	)
	(segment
		(start 85.464396 -280.582116)
		(end 85.551264 -277.085552)
		(width 0.1651)
		(layer "In5.Cu")
		(net "P5E_PEX0_STN0_RX_DP<6>")
	)
	(segment
		(start 70.781672 -135.88365)
		(end 70.73519 -135.728964)
		(width 0.1651)
		(layer "In5.Cu")
		(net "P5E_PEX0_STN0_RX_DP<6>")
	)
	(segment
		(start 69.069712 -134.964678)
		(end 68.633086 -134.729982)
		(width 0.1651)
		(layer "In5.Cu")
		(net "P5E_PEX0_STN0_RX_DP<6>")
	)
	(segment
		(start 79.86522 -282.599892)
		(end 79.97952 -282.485592)
		(width 0.1143)
		(layer "In5.Cu")
		(net "P5E_PEX0_STN0_RX_DP<6>")
	)
	(segment
		(start 74.257916 -137.619994)
		(end 73.821544 -137.385806)
		(width 0.1651)
		(layer "In5.Cu")
		(net "P5E_PEX0_STN0_RX_DP<6>")
	)
	(segment
		(start 79.956152 -160.27273)
		(end 76.60386 -140.932662)
		(width 0.1651)
		(layer "In5.Cu")
		(net "P5E_PEX0_STN0_RX_DP<6>")
	)
	(segment
		(start 70.143878 -135.541258)
		(end 69.707252 -135.306816)
		(width 0.1651)
		(layer "In5.Cu")
		(net "P5E_PEX0_STN0_RX_DP<6>")
	)
	(segment
		(start 74.741024 -138.009122)
		(end 74.304398 -137.77468)
		(width 0.1651)
		(layer "In5.Cu")
		(net "P5E_PEX0_STN0_RX_DP<6>")
	)
	(segment
		(start 85.551264 -276.721316)
		(end 84.428584 -270.821404)
		(width 0.1651)
		(layer "In5.Cu")
		(net "P5E_PEX0_STN0_RX_DP<6>")
	)
	(segment
		(start 73.666604 -137.432288)
		(end 73.229978 -137.197846)
		(width 0.1651)
		(layer "In5.Cu")
		(net "P5E_PEX0_STN0_RX_DP<6>")
	)
	(segment
		(start 79.59979 -282.599892)
		(end 79.86522 -282.599892)
		(width 0.1143)
		(layer "In5.Cu")
		(net "P5E_PEX0_STN0_RX_DP<6>")
	)
	(segment
		(start 83.924648 -281.983942)
		(end 84.25053 -281.983942)
		(width 0.1651)
		(layer "In5.Cu")
		(net "P5E_PEX0_STN0_RX_DP<6>")
	)
	(segment
		(start 70.298818 -135.494776)
		(end 70.143878 -135.541258)
		(width 0.1651)
		(layer "In5.Cu")
		(net "P5E_PEX0_STN0_RX_DP<6>")
	)
	(segment
		(start 76.130658 -138.625326)
		(end 74.896218 -137.96264)
		(width 0.1651)
		(layer "In5.Cu")
		(net "P5E_PEX0_STN0_RX_DP<6>")
	)
	(segment
		(start 74.896218 -137.96264)
		(end 74.895964 -137.96264)
		(width 0.1651)
		(layer "In5.Cu")
		(net "P5E_PEX0_STN0_RX_DP<6>")
	)
	(segment
		(start 83.85048 -282.029662)
		(end 83.8962 -281.983942)
		(width 0.1143)
		(layer "In5.Cu")
		(net "P5E_PEX0_STN0_RX_DP<6>")
	)
	(segment
		(start 68.633086 -134.729982)
		(end 68.58635 -134.575296)
		(width 0.1651)
		(layer "In5.Cu")
		(net "P5E_PEX0_STN0_RX_DP<6>")
	)
	(segment
		(start 133.624828 -345.465146)
		(end 133.919468 -345.170506)
		(width 0.13462)
		(layer "F.Cu")
		(net "P5E_PEX1_STN5_TX_C_DP<82>")
	)
	(segment
		(start 133.919468 -345.170506)
		(end 133.919468 -344.539062)
		(width 0.13462)
		(layer "F.Cu")
		(net "P5E_PEX1_STN5_TX_C_DP<82>")
	)
	(segment
		(start 133.919468 -344.539062)
		(end 133.599428 -344.219022)
		(width 0.13462)
		(layer "F.Cu")
		(net "P5E_PEX1_STN5_TX_C_DP<82>")
	)
	(segment
		(start 135.806688 -365.929926)
		(end 136.040368 -366.36706)
		(width 0.1651)
		(layer "In7.Cu")
		(net "P5E_PEX1_STN5_TX_C_DP<82>")
	)
	(segment
		(start 135.609838 -365.372904)
		(end 135.843264 -365.80953)
		(width 0.1651)
		(layer "In7.Cu")
		(net "P5E_PEX1_STN5_TX_C_DP<82>")
	)
	(segment
		(start 135.292338 -364.779052)
		(end 135.255762 -364.899194)
		(width 0.1651)
		(layer "In7.Cu")
		(net "P5E_PEX1_STN5_TX_C_DP<82>")
	)
	(segment
		(start 137.490708 -383.186178)
		(end 137.490708 -386.4229)
		(width 0.1651)
		(layer "In7.Cu")
		(net "P5E_PEX1_STN5_TX_C_DP<82>")
	)
	(segment
		(start 137.532364 -368.969544)
		(end 137.817098 -369.90782)
		(width 0.1651)
		(layer "In7.Cu")
		(net "P5E_PEX1_STN5_TX_C_DP<82>")
	)
	(segment
		(start 132.361178 -359.295446)
		(end 134.741412 -363.748574)
		(width 0.1651)
		(layer "In7.Cu")
		(net "P5E_PEX1_STN5_TX_C_DP<82>")
	)
	(segment
		(start 120.437148 -404.798784)
		(end 120.310148 -404.671784)
		(width 0.1651)
		(layer "In7.Cu")
		(net "P5E_PEX1_STN5_TX_C_DP<82>")
	)
	(segment
		(start 135.843264 -365.80953)
		(end 135.806688 -365.929926)
		(width 0.1651)
		(layer "In7.Cu")
		(net "P5E_PEX1_STN5_TX_C_DP<82>")
	)
	(segment
		(start 120.310148 -404.671784)
		(end 120.310148 -404.290022)
		(width 0.1651)
		(layer "In7.Cu")
		(net "P5E_PEX1_STN5_TX_C_DP<82>")
	)
	(segment
		(start 133.624828 -345.465146)
		(end 133.915658 -345.755976)
		(width 0.1651)
		(layer "In7.Cu")
		(net "P5E_PEX1_STN5_TX_C_DP<82>")
	)
	(segment
		(start 135.452104 -387.892036)
		(end 133.1976 -388.62)
		(width 0.1651)
		(layer "In7.Cu")
		(net "P5E_PEX1_STN5_TX_C_DP<82>")
	)
	(segment
		(start 134.741412 -363.748574)
		(end 134.704836 -363.868716)
		(width 0.1651)
		(layer "In7.Cu")
		(net "P5E_PEX1_STN5_TX_C_DP<82>")
	)
	(segment
		(start 136.628378 -387.356858)
		(end 135.452104 -387.892036)
		(width 0.1651)
		(layer "In7.Cu")
		(net "P5E_PEX1_STN5_TX_C_DP<82>")
	)
	(segment
		(start 134.93877 -364.30585)
		(end 135.058912 -364.342426)
		(width 0.1651)
		(layer "In7.Cu")
		(net "P5E_PEX1_STN5_TX_C_DP<82>")
	)
	(segment
		(start 121.087642 -404.380446)
		(end 120.669304 -404.798784)
		(width 0.1651)
		(layer "In7.Cu")
		(net "P5E_PEX1_STN5_TX_C_DP<82>")
	)
	(segment
		(start 121.087642 -395.3002)
		(end 121.087642 -404.380446)
		(width 0.1651)
		(layer "In7.Cu")
		(net "P5E_PEX1_STN5_TX_C_DP<82>")
	)
	(segment
		(start 137.289286 -386.806694)
		(end 136.628378 -387.356858)
		(width 0.1651)
		(layer "In7.Cu")
		(net "P5E_PEX1_STN5_TX_C_DP<82>")
	)
	(segment
		(start 120.669304 -404.798784)
		(end 120.437148 -404.798784)
		(width 0.1651)
		(layer "In7.Cu")
		(net "P5E_PEX1_STN5_TX_C_DP<82>")
	)
	(segment
		(start 133.915658 -345.755976)
		(end 133.915658 -346.360242)
		(width 0.1651)
		(layer "In7.Cu")
		(net "P5E_PEX1_STN5_TX_C_DP<82>")
	)
	(segment
		(start 137.490708 -386.4229)
		(end 137.289286 -386.806694)
		(width 0.1651)
		(layer "In7.Cu")
		(net "P5E_PEX1_STN5_TX_C_DP<82>")
	)
	(segment
		(start 135.058912 -364.342426)
		(end 135.292338 -364.779052)
		(width 0.1651)
		(layer "In7.Cu")
		(net "P5E_PEX1_STN5_TX_C_DP<82>")
	)
	(segment
		(start 133.1976 -388.62)
		(end 124.1552 -392.43)
		(width 0.1651)
		(layer "In7.Cu")
		(net "P5E_PEX1_STN5_TX_C_DP<82>")
	)
	(segment
		(start 132.361178 -347.914722)
		(end 132.361178 -359.295446)
		(width 0.1651)
		(layer "In7.Cu")
		(net "P5E_PEX1_STN5_TX_C_DP<82>")
	)
	(segment
		(start 135.255762 -364.899194)
		(end 135.489696 -365.336328)
		(width 0.1651)
		(layer "In7.Cu")
		(net "P5E_PEX1_STN5_TX_C_DP<82>")
	)
	(segment
		(start 136.160764 -366.403382)
		(end 137.532364 -368.969544)
		(width 0.1651)
		(layer "In7.Cu")
		(net "P5E_PEX1_STN5_TX_C_DP<82>")
	)
	(segment
		(start 133.915658 -346.360242)
		(end 132.361178 -347.914722)
		(width 0.1651)
		(layer "In7.Cu")
		(net "P5E_PEX1_STN5_TX_C_DP<82>")
	)
	(segment
		(start 137.817098 -369.90782)
		(end 137.490708 -383.186178)
		(width 0.1651)
		(layer "In7.Cu")
		(net "P5E_PEX1_STN5_TX_C_DP<82>")
	)
	(segment
		(start 135.489696 -365.336328)
		(end 135.609838 -365.372904)
		(width 0.1651)
		(layer "In7.Cu")
		(net "P5E_PEX1_STN5_TX_C_DP<82>")
	)
	(segment
		(start 134.704836 -363.868716)
		(end 134.93877 -364.30585)
		(width 0.1651)
		(layer "In7.Cu")
		(net "P5E_PEX1_STN5_TX_C_DP<82>")
	)
	(segment
		(start 136.040368 -366.36706)
		(end 136.160764 -366.403382)
		(width 0.1651)
		(layer "In7.Cu")
		(net "P5E_PEX1_STN5_TX_C_DP<82>")
	)
	(segment
		(start 124.1552 -392.43)
		(end 121.087642 -395.3002)
		(width 0.1651)
		(layer "In7.Cu")
		(net "P5E_PEX1_STN5_TX_C_DP<82>")
	)
	(segment
		(start 277.591012 -112.19688)
		(end 277.742904 -112.044988)
		(width 0.13462)
		(layer "F.Cu")
		(net "P5E_PEX2_STN1_TX_C_DN<23>")
	)
	(segment
		(start 269.406624 -112.19688)
		(end 277.591012 -112.19688)
		(width 0.13462)
		(layer "F.Cu")
		(net "P5E_PEX2_STN1_TX_C_DN<23>")
	)
	(segment
		(start 277.742904 -112.044988)
		(end 278.242268 -112.044988)
		(width 0.13462)
		(layer "F.Cu")
		(net "P5E_PEX2_STN1_TX_C_DN<23>")
	)
	(segment
		(start 269.105126 -111.895382)
		(end 269.406624 -112.19688)
		(width 0.13462)
		(layer "F.Cu")
		(net "P5E_PEX2_STN1_TX_C_DN<23>")
	)
	(segment
		(start 446.467738 -33.631886)
		(end 446.147444 -33.95218)
		(width 0.13462)
		(layer "F.Cu")
		(net "P5E_PEX3_STN2_TX_C_DN<35>")
	)
	(segment
		(start 446.147444 -33.95218)
		(end 442.233812 -33.95218)
		(width 0.13462)
		(layer "F.Cu")
		(net "P5E_PEX3_STN2_TX_C_DN<35>")
	)
	(segment
		(start 442.233812 -33.95218)
		(end 442.07176 -33.790128)
		(width 0.13462)
		(layer "F.Cu")
		(net "P5E_PEX3_STN2_TX_C_DN<35>")
	)
	(segment
		(start 442.07176 -33.790128)
		(end 441.564776 -33.790128)
		(width 0.13462)
		(layer "F.Cu")
		(net "P5E_PEX3_STN2_TX_C_DN<35>")
	)
	(segment
		(start 439.121042 -358.257856)
		(end 439.121042 -341.718646)
		(width 0.1651)
		(layer "In9.Cu")
		(net "P5E_PEX3_STN7_RX_DP<125>")
	)
	(segment
		(start 432.655472 -366.736376)
		(end 432.952652 -366.339882)
		(width 0.1651)
		(layer "In9.Cu")
		(net "P5E_PEX3_STN7_RX_DP<125>")
	)
	(segment
		(start 388.861046 -318.129666)
		(end 388.949946 -318.040766)
		(width 0.1143)
		(layer "In9.Cu")
		(net "P5E_PEX3_STN7_RX_DP<125>")
	)
	(segment
		(start 433.077112 -366.322102)
		(end 433.076858 -366.322102)
		(width 0.1651)
		(layer "In9.Cu")
		(net "P5E_PEX3_STN7_RX_DP<125>")
	)
	(segment
		(start 420.428166 -334.57388)
		(end 407.74112 -328.592942)
		(width 0.1651)
		(layer "In9.Cu")
		(net "P5E_PEX3_STN7_RX_DP<125>")
	)
	(segment
		(start 430.489868 -383.290064)
		(end 430.489868 -383.67208)
		(width 0.1651)
		(layer "In9.Cu")
		(net "P5E_PEX3_STN7_RX_DP<125>")
	)
	(segment
		(start 430.838864 -383.79908)
		(end 431.364898 -383.273046)
		(width 0.1651)
		(layer "In9.Cu")
		(net "P5E_PEX3_STN7_RX_DP<125>")
	)
	(segment
		(start 430.489868 -383.67208)
		(end 430.616868 -383.79908)
		(width 0.1651)
		(layer "In9.Cu")
		(net "P5E_PEX3_STN7_RX_DP<125>")
	)
	(segment
		(start 430.616868 -383.79908)
		(end 430.838864 -383.79908)
		(width 0.1651)
		(layer "In9.Cu")
		(net "P5E_PEX3_STN7_RX_DP<125>")
	)
	(segment
		(start 431.954432 -367.671604)
		(end 432.251866 -367.274856)
		(width 0.1651)
		(layer "In9.Cu")
		(net "P5E_PEX3_STN7_RX_DP<125>")
	)
	(segment
		(start 388.379716 -319.819528)
		(end 388.379716 -318.36868)
		(width 0.1143)
		(layer "In9.Cu")
		(net "P5E_PEX3_STN7_RX_DP<125>")
	)
	(segment
		(start 432.376326 -367.257076)
		(end 432.376072 -367.257076)
		(width 0.1651)
		(layer "In9.Cu")
		(net "P5E_PEX3_STN7_RX_DP<125>")
	)
	(segment
		(start 432.952652 -366.339882)
		(end 433.077112 -366.322102)
		(width 0.1651)
		(layer "In9.Cu")
		(net "P5E_PEX3_STN7_RX_DP<125>")
	)
	(segment
		(start 433.356258 -365.801402)
		(end 433.653438 -365.404908)
		(width 0.1651)
		(layer "In9.Cu")
		(net "P5E_PEX3_STN7_RX_DP<125>")
	)
	(segment
		(start 388.333996 -321.082924)
		(end 388.333996 -319.893696)
		(width 0.1651)
		(layer "In9.Cu")
		(net "P5E_PEX3_STN7_RX_DP<125>")
	)
	(segment
		(start 407.74112 -328.592942)
		(end 389.587486 -322.846446)
		(width 0.1651)
		(layer "In9.Cu")
		(net "P5E_PEX3_STN7_RX_DP<125>")
	)
	(segment
		(start 388.61873 -318.129666)
		(end 388.861046 -318.129666)
		(width 0.1143)
		(layer "In9.Cu")
		(net "P5E_PEX3_STN7_RX_DP<125>")
	)
	(segment
		(start 388.949946 -318.040766)
		(end 388.949946 -317.749936)
		(width 0.1143)
		(layer "In9.Cu")
		(net "P5E_PEX3_STN7_RX_DP<125>")
	)
	(segment
		(start 432.673252 -366.860836)
		(end 432.655472 -366.736376)
		(width 0.1651)
		(layer "In9.Cu")
		(net "P5E_PEX3_STN7_RX_DP<125>")
	)
	(segment
		(start 431.364898 -368.606578)
		(end 431.972212 -367.796064)
		(width 0.1651)
		(layer "In9.Cu")
		(net "P5E_PEX3_STN7_RX_DP<125>")
	)
	(segment
		(start 439.121042 -341.718646)
		(end 438.985914 -341.523828)
		(width 0.1651)
		(layer "In9.Cu")
		(net "P5E_PEX3_STN7_RX_DP<125>")
	)
	(segment
		(start 433.374038 -365.925862)
		(end 433.356258 -365.801402)
		(width 0.1651)
		(layer "In9.Cu")
		(net "P5E_PEX3_STN7_RX_DP<125>")
	)
	(segment
		(start 388.842504 -322.311014)
		(end 388.333996 -321.082924)
		(width 0.1651)
		(layer "In9.Cu")
		(net "P5E_PEX3_STN7_RX_DP<125>")
	)
	(segment
		(start 388.379716 -318.36868)
		(end 388.61873 -318.129666)
		(width 0.1143)
		(layer "In9.Cu")
		(net "P5E_PEX3_STN7_RX_DP<125>")
	)
	(segment
		(start 432.376072 -367.257076)
		(end 432.672998 -366.860836)
		(width 0.1651)
		(layer "In9.Cu")
		(net "P5E_PEX3_STN7_RX_DP<125>")
	)
	(segment
		(start 432.251866 -367.274856)
		(end 432.376326 -367.257076)
		(width 0.1651)
		(layer "In9.Cu")
		(net "P5E_PEX3_STN7_RX_DP<125>")
	)
	(segment
		(start 433.373784 -365.925862)
		(end 433.374038 -365.925862)
		(width 0.1651)
		(layer "In9.Cu")
		(net "P5E_PEX3_STN7_RX_DP<125>")
	)
	(segment
		(start 433.076858 -366.322102)
		(end 433.373784 -365.925862)
		(width 0.1651)
		(layer "In9.Cu")
		(net "P5E_PEX3_STN7_RX_DP<125>")
	)
	(segment
		(start 388.333996 -319.865248)
		(end 388.379716 -319.819528)
		(width 0.1143)
		(layer "In9.Cu")
		(net "P5E_PEX3_STN7_RX_DP<125>")
	)
	(segment
		(start 431.972466 -367.796064)
		(end 431.954432 -367.671604)
		(width 0.1651)
		(layer "In9.Cu")
		(net "P5E_PEX3_STN7_RX_DP<125>")
	)
	(segment
		(start 433.777644 -365.387128)
		(end 439.121042 -358.257856)
		(width 0.1651)
		(layer "In9.Cu")
		(net "P5E_PEX3_STN7_RX_DP<125>")
	)
	(segment
		(start 431.364898 -383.273046)
		(end 431.364898 -368.606578)
		(width 0.1651)
		(layer "In9.Cu")
		(net "P5E_PEX3_STN7_RX_DP<125>")
	)
	(segment
		(start 433.653438 -365.404908)
		(end 433.777898 -365.387128)
		(width 0.1651)
		(layer "In9.Cu")
		(net "P5E_PEX3_STN7_RX_DP<125>")
	)
	(segment
		(start 389.587486 -322.846446)
		(end 388.842504 -322.311014)
		(width 0.1651)
		(layer "In9.Cu")
		(net "P5E_PEX3_STN7_RX_DP<125>")
	)
	(segment
		(start 388.333996 -319.893696)
		(end 388.333996 -319.865248)
		(width 0.1143)
		(layer "In9.Cu")
		(net "P5E_PEX3_STN7_RX_DP<125>")
	)
	(segment
		(start 431.972212 -367.796064)
		(end 431.972466 -367.796064)
		(width 0.1651)
		(layer "In9.Cu")
		(net "P5E_PEX3_STN7_RX_DP<125>")
	)
	(segment
		(start 438.985914 -341.523828)
		(end 420.428166 -334.57388)
		(width 0.1651)
		(layer "In9.Cu")
		(net "P5E_PEX3_STN7_RX_DP<125>")
	)
	(segment
		(start 432.672998 -366.860836)
		(end 432.673252 -366.860836)
		(width 0.1651)
		(layer "In9.Cu")
		(net "P5E_PEX3_STN7_RX_DP<125>")
	)
	(segment
		(start 433.777898 -365.387128)
		(end 433.777644 -365.387128)
		(width 0.1651)
		(layer "In9.Cu")
		(net "P5E_PEX3_STN7_RX_DP<125>")
	)
	(segment
		(start 156.490924 -118.154958)
		(end 155.660852 -118.154958)
		(width 0.13208)
		(layer "F.Cu")
		(net "PRSNTB0_NIC2_N")
	)
	(segment
		(start 162.14217 -118.154958)
		(end 156.490924 -118.154958)
		(width 0.13208)
		(layer "F.Cu")
		(net "PRSNTB0_NIC2_N")
	)
	(segment
		(start 155.260294 -116.7384)
		(end 155.260294 -117.7544)
		(width 0.13208)
		(layer "F.Cu")
		(net "PRSNTB0_NIC2_N")
	)
	(segment
		(start 155.660852 -118.154958)
		(end 155.260294 -117.7544)
		(width 0.13208)
		(layer "F.Cu")
		(net "PRSNTB0_NIC2_N")
	)
	(via
		(at 156.490924 -118.154958)
		(size 0.762)
		(drill 0.381)
		(layers "F.Cu" "B.Cu")
		(net "PRSNTB0_NIC2_N")
	)
	(segment
		(start 68.169536 -120.635014)
		(end 68.006722 -120.797828)
		(width 0.13462)
		(layer "F.Cu")
		(net "P5E_PEX0_STN0_RX_DN<1>")
	)
	(segment
		(start 65.49771 -120.798336)
		(end 65.20307 -120.503696)
		(width 0.13462)
		(layer "F.Cu")
		(net "P5E_PEX0_STN0_RX_DN<1>")
	)
	(segment
		(start 68.006722 -120.797828)
		(end 65.498218 -120.797828)
		(width 0.13462)
		(layer "F.Cu")
		(net "P5E_PEX0_STN0_RX_DN<1>")
	)
	(segment
		(start 65.498218 -120.797828)
		(end 65.49771 -120.798336)
		(width 0.13462)
		(layer "F.Cu")
		(net "P5E_PEX0_STN0_RX_DN<1>")
	)
	(segment
		(start 68.65747 -120.635014)
		(end 68.169536 -120.635014)
		(width 0.13462)
		(layer "F.Cu")
		(net "P5E_PEX0_STN0_RX_DN<1>")
	)
	(segment
		(start 82.070194 -287.073848)
		(end 82.173826 -286.970216)
		(width 0.1143)
		(layer "In5.Cu")
		(net "P5E_PEX0_STN0_RX_DN<1>")
	)
	(segment
		(start 83.950048 -287.015936)
		(end 86.000082 -287.015936)
		(width 0.1651)
		(layer "In5.Cu")
		(net "P5E_PEX0_STN0_RX_DN<1>")
	)
	(segment
		(start 98.546666 -273.37258)
		(end 98.698558 -269.2781)
		(width 0.1651)
		(layer "In5.Cu")
		(net "P5E_PEX0_STN0_RX_DN<1>")
	)
	(segment
		(start 82.173826 -286.970216)
		(end 83.87588 -286.970216)
		(width 0.1143)
		(layer "In5.Cu")
		(net "P5E_PEX0_STN0_RX_DN<1>")
	)
	(segment
		(start 82.184494 -287.349946)
		(end 82.070194 -287.235646)
		(width 0.1143)
		(layer "In5.Cu")
		(net "P5E_PEX0_STN0_RX_DN<1>")
	)
	(segment
		(start 83.9216 -287.015936)
		(end 83.950048 -287.015936)
		(width 0.1143)
		(layer "In5.Cu")
		(net "P5E_PEX0_STN0_RX_DN<1>")
	)
	(segment
		(start 82.714338 -132.715)
		(end 80.562958 -131.52882)
		(width 0.1651)
		(layer "In5.Cu")
		(net "P5E_PEX0_STN0_RX_DN<1>")
	)
	(segment
		(start 65.4939 -120.794526)
		(end 65.20307 -120.503696)
		(width 0.1651)
		(layer "In5.Cu")
		(net "P5E_PEX0_STN0_RX_DN<1>")
	)
	(segment
		(start 86.0679 -286.97428)
		(end 87.474552 -286.11068)
		(width 0.1651)
		(layer "In5.Cu")
		(net "P5E_PEX0_STN0_RX_DN<1>")
	)
	(segment
		(start 72.856598 -122.97664)
		(end 67.615816 -120.794526)
		(width 0.1651)
		(layer "In5.Cu")
		(net "P5E_PEX0_STN0_RX_DN<1>")
	)
	(segment
		(start 88.363806 -146.35226)
		(end 85.936328 -135.222996)
		(width 0.1651)
		(layer "In5.Cu")
		(net "P5E_PEX0_STN0_RX_DN<1>")
	)
	(segment
		(start 75.099418 -125.19406)
		(end 72.856598 -122.97664)
		(width 0.1651)
		(layer "In5.Cu")
		(net "P5E_PEX0_STN0_RX_DN<1>")
	)
	(segment
		(start 87.474552 -286.11068)
		(end 96.078294 -277.807928)
		(width 0.1651)
		(layer "In5.Cu")
		(net "P5E_PEX0_STN0_RX_DN<1>")
	)
	(segment
		(start 85.936328 -135.222996)
		(end 85.411818 -134.40664)
		(width 0.1651)
		(layer "In5.Cu")
		(net "P5E_PEX0_STN0_RX_DN<1>")
	)
	(segment
		(start 96.078294 -277.807928)
		(end 98.546666 -273.37258)
		(width 0.1651)
		(layer "In5.Cu")
		(net "P5E_PEX0_STN0_RX_DN<1>")
	)
	(segment
		(start 80.562958 -131.52882)
		(end 75.099418 -125.19406)
		(width 0.1651)
		(layer "In5.Cu")
		(net "P5E_PEX0_STN0_RX_DN<1>")
	)
	(segment
		(start 88.467692 -232.097072)
		(end 89.130632 -168.53408)
		(width 0.1651)
		(layer "In5.Cu")
		(net "P5E_PEX0_STN0_RX_DN<1>")
	)
	(segment
		(start 67.615816 -120.794526)
		(end 65.4939 -120.794526)
		(width 0.1651)
		(layer "In5.Cu")
		(net "P5E_PEX0_STN0_RX_DN<1>")
	)
	(segment
		(start 88.622124 -149.896322)
		(end 88.363806 -146.35226)
		(width 0.1651)
		(layer "In5.Cu")
		(net "P5E_PEX0_STN0_RX_DN<1>")
	)
	(segment
		(start 89.130632 -168.53408)
		(end 88.622124 -149.896322)
		(width 0.1651)
		(layer "In5.Cu")
		(net "P5E_PEX0_STN0_RX_DN<1>")
	)
	(segment
		(start 86.000082 -287.015936)
		(end 86.0679 -286.974534)
		(width 0.1651)
		(layer "In5.Cu")
		(net "P5E_PEX0_STN0_RX_DN<1>")
	)
	(segment
		(start 82.070194 -287.235646)
		(end 82.070194 -287.073848)
		(width 0.1143)
		(layer "In5.Cu")
		(net "P5E_PEX0_STN0_RX_DN<1>")
	)
	(segment
		(start 98.698558 -269.2781)
		(end 89.913968 -239.19307)
		(width 0.1651)
		(layer "In5.Cu")
		(net "P5E_PEX0_STN0_RX_DN<1>")
	)
	(segment
		(start 89.913968 -239.19307)
		(end 88.467692 -232.097072)
		(width 0.1651)
		(layer "In5.Cu")
		(net "P5E_PEX0_STN0_RX_DN<1>")
	)
	(segment
		(start 82.449924 -287.349946)
		(end 82.184494 -287.349946)
		(width 0.1143)
		(layer "In5.Cu")
		(net "P5E_PEX0_STN0_RX_DN<1>")
	)
	(segment
		(start 83.143598 -133.14426)
		(end 82.714338 -132.715)
		(width 0.1651)
		(layer "In5.Cu")
		(net "P5E_PEX0_STN0_RX_DN<1>")
	)
	(segment
		(start 86.0679 -286.974534)
		(end 86.0679 -286.97428)
		(width 0.1651)
		(layer "In5.Cu")
		(net "P5E_PEX0_STN0_RX_DN<1>")
	)
	(segment
		(start 83.87588 -286.970216)
		(end 83.9216 -287.015936)
		(width 0.1143)
		(layer "In5.Cu")
		(net "P5E_PEX0_STN0_RX_DN<1>")
	)
	(segment
		(start 85.411818 -134.40664)
		(end 83.143598 -133.14426)
		(width 0.1651)
		(layer "In5.Cu")
		(net "P5E_PEX0_STN0_RX_DN<1>")
	)
	(segment
		(start 131.084828 -350.685354)
		(end 131.404868 -350.365314)
		(width 0.13462)
		(layer "F.Cu")
		(net "P5E_PEX1_STN5_TX_C_DN<81>")
	)
	(segment
		(start 131.084828 -351.316798)
		(end 131.084828 -350.685354)
		(width 0.13462)
		(layer "F.Cu")
		(net "P5E_PEX1_STN5_TX_C_DN<81>")
	)
	(segment
		(start 131.379468 -351.611438)
		(end 131.084828 -351.316798)
		(width 0.13462)
		(layer "F.Cu")
		(net "P5E_PEX1_STN5_TX_C_DN<81>")
	)
	(segment
		(start 118.11 -406.308052)
		(end 118.237254 -406.180798)
		(width 0.1651)
		(layer "In7.Cu")
		(net "P5E_PEX1_STN5_TX_C_DN<81>")
	)
	(segment
		(start 131.088638 -352.537522)
		(end 131.088638 -351.902268)
		(width 0.1651)
		(layer "In7.Cu")
		(net "P5E_PEX1_STN5_TX_C_DN<81>")
	)
	(segment
		(start 136.176766 -386.785358)
		(end 136.548876 -386.474716)
		(width 0.1651)
		(layer "In7.Cu")
		(net "P5E_PEX1_STN5_TX_C_DN<81>")
	)
	(segment
		(start 131.088638 -351.902268)
		(end 131.379468 -351.611438)
		(width 0.1651)
		(layer "In7.Cu")
		(net "P5E_PEX1_STN5_TX_C_DN<81>")
	)
	(segment
		(start 118.237254 -406.180798)
		(end 118.585996 -406.180798)
		(width 0.1651)
		(layer "In7.Cu")
		(net "P5E_PEX1_STN5_TX_C_DN<81>")
	)
	(segment
		(start 119.169434 -405.59736)
		(end 119.169434 -396.308834)
		(width 0.1651)
		(layer "In7.Cu")
		(net "P5E_PEX1_STN5_TX_C_DN<81>")
	)
	(segment
		(start 136.69137 -383.174494)
		(end 137.014712 -370.029994)
		(width 0.1651)
		(layer "In7.Cu")
		(net "P5E_PEX1_STN5_TX_C_DN<81>")
	)
	(segment
		(start 123.128278 -391.99693)
		(end 132.459984 -388.118858)
		(width 0.1651)
		(layer "In7.Cu")
		(net "P5E_PEX1_STN5_TX_C_DN<81>")
	)
	(segment
		(start 132.459984 -388.118858)
		(end 136.176766 -386.785358)
		(width 0.1651)
		(layer "In7.Cu")
		(net "P5E_PEX1_STN5_TX_C_DN<81>")
	)
	(segment
		(start 119.77497 -394.337794)
		(end 120.231408 -394.019278)
		(width 0.1651)
		(layer "In7.Cu")
		(net "P5E_PEX1_STN5_TX_C_DN<81>")
	)
	(segment
		(start 120.23217 -394.01877)
		(end 123.128278 -391.99693)
		(width 0.1651)
		(layer "In7.Cu")
		(net "P5E_PEX1_STN5_TX_C_DN<81>")
	)
	(segment
		(start 129.775458 -358.78516)
		(end 129.534158 -358.110536)
		(width 0.1651)
		(layer "In7.Cu")
		(net "P5E_PEX1_STN5_TX_C_DN<81>")
	)
	(segment
		(start 136.496806 -368.582194)
		(end 129.775458 -358.78516)
		(width 0.1651)
		(layer "In7.Cu")
		(net "P5E_PEX1_STN5_TX_C_DN<81>")
	)
	(segment
		(start 118.585996 -406.180798)
		(end 119.169434 -405.59736)
		(width 0.1651)
		(layer "In7.Cu")
		(net "P5E_PEX1_STN5_TX_C_DN<81>")
	)
	(segment
		(start 136.548876 -386.474716)
		(end 136.69137 -386.17017)
		(width 0.1651)
		(layer "In7.Cu")
		(net "P5E_PEX1_STN5_TX_C_DN<81>")
	)
	(segment
		(start 119.169434 -396.308834)
		(end 119.284242 -395.746224)
		(width 0.1651)
		(layer "In7.Cu")
		(net "P5E_PEX1_STN5_TX_C_DN<81>")
	)
	(segment
		(start 119.284242 -395.746224)
		(end 119.77497 -394.337794)
		(width 0.1651)
		(layer "In7.Cu")
		(net "P5E_PEX1_STN5_TX_C_DN<81>")
	)
	(segment
		(start 129.534158 -358.110536)
		(end 129.534158 -354.092002)
		(width 0.1651)
		(layer "In7.Cu")
		(net "P5E_PEX1_STN5_TX_C_DN<81>")
	)
	(segment
		(start 137.014712 -370.029994)
		(end 136.496806 -368.582194)
		(width 0.1651)
		(layer "In7.Cu")
		(net "P5E_PEX1_STN5_TX_C_DN<81>")
	)
	(segment
		(start 118.11 -406.690068)
		(end 118.11 -406.308052)
		(width 0.1651)
		(layer "In7.Cu")
		(net "P5E_PEX1_STN5_TX_C_DN<81>")
	)
	(segment
		(start 120.231408 -394.019278)
		(end 120.23217 -394.01877)
		(width 0.1651)
		(layer "In7.Cu")
		(net "P5E_PEX1_STN5_TX_C_DN<81>")
	)
	(segment
		(start 136.69137 -386.17017)
		(end 136.69137 -383.174494)
		(width 0.1651)
		(layer "In7.Cu")
		(net "P5E_PEX1_STN5_TX_C_DN<81>")
	)
	(segment
		(start 129.534158 -354.092002)
		(end 131.088638 -352.537522)
		(width 0.1651)
		(layer "In7.Cu")
		(net "P5E_PEX1_STN5_TX_C_DN<81>")
	)
	(segment
		(start 277.570692 -132.5372)
		(end 277.742904 -132.364988)
		(width 0.13462)
		(layer "F.Cu")
		(net "P5E_PEX2_STN1_TX_C_DN<29>")
	)
	(segment
		(start 277.742904 -132.364988)
		(end 278.242268 -132.364988)
		(width 0.13462)
		(layer "F.Cu")
		(net "P5E_PEX2_STN1_TX_C_DN<29>")
	)
	(segment
		(start 272.069052 -132.5372)
		(end 277.570692 -132.5372)
		(width 0.13462)
		(layer "F.Cu")
		(net "P5E_PEX2_STN1_TX_C_DN<29>")
	)
	(segment
		(start 271.747234 -132.215382)
		(end 272.069052 -132.5372)
		(width 0.13462)
		(layer "F.Cu")
		(net "P5E_PEX2_STN1_TX_C_DN<29>")
	)
	(segment
		(start 417.825682 -31.825184)
		(end 417.514786 -32.13608)
		(width 0.13462)
		(layer "F.Cu")
		(net "P5E_PEX3_STN2_TX_C_DN<38>")
	)
	(segment
		(start 416.214052 -32.13608)
		(end 416.068002 -31.99003)
		(width 0.13462)
		(layer "F.Cu")
		(net "P5E_PEX3_STN2_TX_C_DN<38>")
	)
	(segment
		(start 417.514786 -32.13608)
		(end 416.214052 -32.13608)
		(width 0.13462)
		(layer "F.Cu")
		(net "P5E_PEX3_STN2_TX_C_DN<38>")
	)
	(segment
		(start 416.068002 -31.99003)
		(end 415.564828 -31.99003)
		(width 0.13462)
		(layer "F.Cu")
		(net "P5E_PEX3_STN2_TX_C_DN<38>")
	)
	(segment
		(start 427.923452 -356.511606)
		(end 428.244 -356.832154)
		(width 0.13462)
		(layer "F.Cu")
		(net "P5E_PEX3_STN7_TX_C_DN<121>")
	)
	(segment
		(start 428.244 -356.832154)
		(end 428.244 -357.462582)
		(width 0.13462)
		(layer "F.Cu")
		(net "P5E_PEX3_STN7_TX_C_DN<121>")
	)
	(segment
		(start 428.244 -357.462582)
		(end 427.948852 -357.75773)
		(width 0.13462)
		(layer "F.Cu")
		(net "P5E_PEX3_STN7_TX_C_DN<121>")
	)
	(segment
		(start 423.992548 -366.211612)
		(end 423.955972 -366.072674)
		(width 0.1651)
		(layer "In11.Cu")
		(net "P5E_PEX3_STN7_TX_C_DN<121>")
	)
	(segment
		(start 421.689784 -375.490232)
		(end 421.689784 -375.872248)
		(width 0.1651)
		(layer "In11.Cu")
		(net "P5E_PEX3_STN7_TX_C_DN<121>")
	)
	(segment
		(start 424.205654 -365.64443)
		(end 424.344592 -365.607854)
		(width 0.1651)
		(layer "In11.Cu")
		(net "P5E_PEX3_STN7_TX_C_DN<121>")
	)
	(segment
		(start 423.955972 -366.072674)
		(end 424.205654 -365.64443)
		(width 0.1651)
		(layer "In11.Cu")
		(net "P5E_PEX3_STN7_TX_C_DN<121>")
	)
	(segment
		(start 425.408598 -363.581442)
		(end 425.547536 -363.544866)
		(width 0.1651)
		(layer "In11.Cu")
		(net "P5E_PEX3_STN7_TX_C_DN<121>")
	)
	(segment
		(start 423.391076 -367.243106)
		(end 423.3545 -367.104168)
		(width 0.1651)
		(layer "In11.Cu")
		(net "P5E_PEX3_STN7_TX_C_DN<121>")
	)
	(segment
		(start 424.59402 -365.180118)
		(end 424.557444 -365.04118)
		(width 0.1651)
		(layer "In11.Cu")
		(net "P5E_PEX3_STN7_TX_C_DN<121>")
	)
	(segment
		(start 423.3545 -367.104168)
		(end 423.604182 -366.675924)
		(width 0.1651)
		(layer "In11.Cu")
		(net "P5E_PEX3_STN7_TX_C_DN<121>")
	)
	(segment
		(start 421.816784 -375.999248)
		(end 422.24706 -375.999248)
		(width 0.1651)
		(layer "In11.Cu")
		(net "P5E_PEX3_STN7_TX_C_DN<121>")
	)
	(segment
		(start 425.547282 -363.544612)
		(end 427.965362 -359.3973)
		(width 0.1651)
		(layer "In11.Cu")
		(net "P5E_PEX3_STN7_TX_C_DN<121>")
	)
	(segment
		(start 424.557444 -365.04118)
		(end 424.807126 -364.612936)
		(width 0.1651)
		(layer "In11.Cu")
		(net "P5E_PEX3_STN7_TX_C_DN<121>")
	)
	(segment
		(start 422.654476 -368.895122)
		(end 422.783762 -368.41684)
		(width 0.1651)
		(layer "In11.Cu")
		(net "P5E_PEX3_STN7_TX_C_DN<121>")
	)
	(segment
		(start 422.24706 -375.999248)
		(end 422.533826 -375.712482)
		(width 0.1651)
		(layer "In11.Cu")
		(net "P5E_PEX3_STN7_TX_C_DN<121>")
	)
	(segment
		(start 425.547536 -363.544866)
		(end 425.547282 -363.544612)
		(width 0.1651)
		(layer "In11.Cu")
		(net "P5E_PEX3_STN7_TX_C_DN<121>")
	)
	(segment
		(start 423.604182 -366.675924)
		(end 423.74312 -366.639348)
		(width 0.1651)
		(layer "In11.Cu")
		(net "P5E_PEX3_STN7_TX_C_DN<121>")
	)
	(segment
		(start 424.807126 -364.612936)
		(end 424.946064 -364.57636)
		(width 0.1651)
		(layer "In11.Cu")
		(net "P5E_PEX3_STN7_TX_C_DN<121>")
	)
	(segment
		(start 421.689784 -375.872248)
		(end 421.816784 -375.999248)
		(width 0.1651)
		(layer "In11.Cu")
		(net "P5E_PEX3_STN7_TX_C_DN<121>")
	)
	(segment
		(start 425.158916 -364.009686)
		(end 425.408598 -363.581442)
		(width 0.1651)
		(layer "In11.Cu")
		(net "P5E_PEX3_STN7_TX_C_DN<121>")
	)
	(segment
		(start 422.783762 -368.41684)
		(end 422.892982 -368.354102)
		(width 0.1651)
		(layer "In11.Cu")
		(net "P5E_PEX3_STN7_TX_C_DN<121>")
	)
	(segment
		(start 422.533826 -369.68303)
		(end 422.717214 -369.004088)
		(width 0.1651)
		(layer "In11.Cu")
		(net "P5E_PEX3_STN7_TX_C_DN<121>")
	)
	(segment
		(start 425.195492 -364.148624)
		(end 425.158916 -364.009686)
		(width 0.1651)
		(layer "In11.Cu")
		(net "P5E_PEX3_STN7_TX_C_DN<121>")
	)
	(segment
		(start 422.892982 -368.354102)
		(end 423.022014 -367.876074)
		(width 0.1651)
		(layer "In11.Cu")
		(net "P5E_PEX3_STN7_TX_C_DN<121>")
	)
	(segment
		(start 424.344592 -365.607854)
		(end 424.59402 -365.180118)
		(width 0.1651)
		(layer "In11.Cu")
		(net "P5E_PEX3_STN7_TX_C_DN<121>")
	)
	(segment
		(start 425.195238 -364.14837)
		(end 425.195492 -364.148624)
		(width 0.1651)
		(layer "In11.Cu")
		(net "P5E_PEX3_STN7_TX_C_DN<121>")
	)
	(segment
		(start 423.74312 -366.639348)
		(end 423.992548 -366.211612)
		(width 0.1651)
		(layer "In11.Cu")
		(net "P5E_PEX3_STN7_TX_C_DN<121>")
	)
	(segment
		(start 422.533826 -375.712482)
		(end 422.533826 -369.68303)
		(width 0.1651)
		(layer "In11.Cu")
		(net "P5E_PEX3_STN7_TX_C_DN<121>")
	)
	(segment
		(start 422.717214 -369.004088)
		(end 422.654476 -368.895122)
		(width 0.1651)
		(layer "In11.Cu")
		(net "P5E_PEX3_STN7_TX_C_DN<121>")
	)
	(segment
		(start 423.022014 -367.876074)
		(end 423.391076 -367.243106)
		(width 0.1651)
		(layer "In11.Cu")
		(net "P5E_PEX3_STN7_TX_C_DN<121>")
	)
	(segment
		(start 424.946064 -364.57636)
		(end 424.94581 -364.57636)
		(width 0.1651)
		(layer "In11.Cu")
		(net "P5E_PEX3_STN7_TX_C_DN<121>")
	)
	(segment
		(start 428.239682 -358.04856)
		(end 427.948852 -357.75773)
		(width 0.1651)
		(layer "In11.Cu")
		(net "P5E_PEX3_STN7_TX_C_DN<121>")
	)
	(segment
		(start 424.94581 -364.57636)
		(end 425.195238 -364.14837)
		(width 0.1651)
		(layer "In11.Cu")
		(net "P5E_PEX3_STN7_TX_C_DN<121>")
	)
	(segment
		(start 427.965362 -359.3973)
		(end 428.239682 -358.383332)
		(width 0.1651)
		(layer "In11.Cu")
		(net "P5E_PEX3_STN7_TX_C_DN<121>")
	)
	(segment
		(start 428.239682 -358.383332)
		(end 428.239682 -358.04856)
		(width 0.1651)
		(layer "In11.Cu")
		(net "P5E_PEX3_STN7_TX_C_DN<121>")
	)
	(segment
		(start 170.455844 -158.8516)
		(end 171.681394 -158.8516)
		(width 0.13208)
		(layer "F.Cu")
		(net "RST_NIC2_PERST2_R_N")
	)
	(segment
		(start 170.049444 -158.8516)
		(end 170.455844 -158.8516)
		(width 0.13208)
		(layer "F.Cu")
		(net "RST_NIC2_PERST2_R_N")
	)
	(segment
		(start 166.742364 -158.36011)
		(end 169.557954 -158.36011)
		(width 0.13208)
		(layer "F.Cu")
		(net "RST_NIC2_PERST2_R_N")
	)
	(segment
		(start 169.557954 -158.36011)
		(end 170.049444 -158.8516)
		(width 0.13208)
		(layer "F.Cu")
		(net "RST_NIC2_PERST2_R_N")
	)
	(via
		(at 170.455844 -158.8516)
		(size 0.762)
		(drill 0.381)
		(layers "F.Cu" "B.Cu")
		(net "RST_NIC2_PERST2_R_N")
	)
	(segment
		(start 82.07375 -155.51785)
		(end 82.394806 -155.196794)
		(width 0.13462)
		(layer "F.Cu")
		(net "P5E_PEX0_STN0_TX_C_DN<15>")
	)
	(segment
		(start 73.257664 -155.355036)
		(end 73.745852 -155.355036)
		(width 0.13462)
		(layer "F.Cu")
		(net "P5E_PEX0_STN0_TX_C_DN<15>")
	)
	(segment
		(start 73.908666 -155.51785)
		(end 82.07375 -155.51785)
		(width 0.13462)
		(layer "F.Cu")
		(net "P5E_PEX0_STN0_TX_C_DN<15>")
	)
	(segment
		(start 73.745852 -155.355036)
		(end 73.908666 -155.51785)
		(width 0.13462)
		(layer "F.Cu")
		(net "P5E_PEX0_STN0_TX_C_DN<15>")
	)
	(segment
		(start 272.070576 -106.81208)
		(end 277.57247 -106.81208)
		(width 0.13462)
		(layer "F.Cu")
		(net "P5E_PEX2_STN1_TX_C_DP<20>")
	)
	(segment
		(start 271.747234 -106.488738)
		(end 272.070576 -106.81208)
		(width 0.13462)
		(layer "F.Cu")
		(net "P5E_PEX2_STN1_TX_C_DP<20>")
	)
	(segment
		(start 277.739602 -106.644948)
		(end 278.242268 -106.644948)
		(width 0.13462)
		(layer "F.Cu")
		(net "P5E_PEX2_STN1_TX_C_DP<20>")
	)
	(segment
		(start 277.57247 -106.81208)
		(end 277.739602 -106.644948)
		(width 0.13462)
		(layer "F.Cu")
		(net "P5E_PEX2_STN1_TX_C_DP<20>")
	)
	(segment
		(start 446.147952 -34.2265)
		(end 442.231272 -34.2265)
		(width 0.13462)
		(layer "F.Cu")
		(net "P5E_PEX3_STN2_TX_C_DP<35>")
	)
	(segment
		(start 446.467738 -34.546286)
		(end 446.147952 -34.2265)
		(width 0.13462)
		(layer "F.Cu")
		(net "P5E_PEX3_STN2_TX_C_DP<35>")
	)
	(segment
		(start 442.067696 -34.390076)
		(end 441.564776 -34.390076)
		(width 0.13462)
		(layer "F.Cu")
		(net "P5E_PEX3_STN2_TX_C_DP<35>")
	)
	(segment
		(start 442.231272 -34.2265)
		(end 442.067696 -34.390076)
		(width 0.13462)
		(layer "F.Cu")
		(net "P5E_PEX3_STN2_TX_C_DP<35>")
	)
	(segment
		(start 375.999756 -304.043334)
		(end 376.635518 -303.779682)
		(width 0.1651)
		(layer "In9.Cu")
		(net "P5E_PEX3_STN7_RX_DP<114>")
	)
	(segment
		(start 424.23842 -408.699208)
		(end 424.772328 -408.1653)
		(width 0.1651)
		(layer "In9.Cu")
		(net "P5E_PEX3_STN7_RX_DP<114>")
	)
	(segment
		(start 374.497854 -332.035658)
		(end 369.153186 -326.691244)
		(width 0.1651)
		(layer "In9.Cu")
		(net "P5E_PEX3_STN7_RX_DP<114>")
	)
	(segment
		(start 404.193248 -340.59876)
		(end 397.408654 -337.631786)
		(width 0.1651)
		(layer "In9.Cu")
		(net "P5E_PEX3_STN7_RX_DP<114>")
	)
	(segment
		(start 419.615366 -392.075416)
		(end 419.553644 -391.945368)
		(width 0.1651)
		(layer "In9.Cu")
		(net "P5E_PEX3_STN7_RX_DP<114>")
	)
	(segment
		(start 420.740332 -392.47572)
		(end 420.67861 -392.345672)
		(width 0.1651)
		(layer "In9.Cu")
		(net "P5E_PEX3_STN7_RX_DP<114>")
	)
	(segment
		(start 367.718848 -323.228208)
		(end 367.718848 -318.531748)
		(width 0.1651)
		(layer "In9.Cu")
		(net "P5E_PEX3_STN7_RX_DP<114>")
	)
	(segment
		(start 406.914604 -349.076264)
		(end 405.009858 -341.561674)
		(width 0.1651)
		(layer "In9.Cu")
		(net "P5E_PEX3_STN7_RX_DP<114>")
	)
	(segment
		(start 383.921 -302.883824)
		(end 383.96672 -302.929544)
		(width 0.1143)
		(layer "In9.Cu")
		(net "P5E_PEX3_STN7_RX_DP<114>")
	)
	(segment
		(start 387.624828 -303.173384)
		(end 387.624828 -303.405286)
		(width 0.1143)
		(layer "In9.Cu")
		(net "P5E_PEX3_STN7_RX_DP<114>")
	)
	(segment
		(start 422.33215 -393.04214)
		(end 421.865298 -392.876024)
		(width 0.1651)
		(layer "In9.Cu")
		(net "P5E_PEX3_STN7_RX_DP<114>")
	)
	(segment
		(start 369.153186 -326.691244)
		(end 367.718848 -323.228208)
		(width 0.1651)
		(layer "In9.Cu")
		(net "P5E_PEX3_STN7_RX_DP<114>")
	)
	(segment
		(start 387.380988 -302.929544)
		(end 387.624828 -303.173384)
		(width 0.1143)
		(layer "In9.Cu")
		(net "P5E_PEX3_STN7_RX_DP<114>")
	)
	(segment
		(start 383.892552 -302.883824)
		(end 383.921 -302.883824)
		(width 0.1143)
		(layer "In9.Cu")
		(net "P5E_PEX3_STN7_RX_DP<114>")
	)
	(segment
		(start 419.553644 -391.945368)
		(end 418.20973 -391.46734)
		(width 0.1651)
		(layer "In9.Cu")
		(net "P5E_PEX3_STN7_RX_DP<114>")
	)
	(segment
		(start 420.67861 -392.345672)
		(end 420.212012 -392.17981)
		(width 0.1651)
		(layer "In9.Cu")
		(net "P5E_PEX3_STN7_RX_DP<114>")
	)
	(segment
		(start 397.408654 -337.631786)
		(end 378.492004 -333.291688)
		(width 0.1651)
		(layer "In9.Cu")
		(net "P5E_PEX3_STN7_RX_DP<114>")
	)
	(segment
		(start 423.889932 -408.190192)
		(end 423.889932 -408.572208)
		(width 0.1651)
		(layer "In9.Cu")
		(net "P5E_PEX3_STN7_RX_DP<114>")
	)
	(segment
		(start 418.20973 -391.46734)
		(end 414.669986 -388.583424)
		(width 0.1651)
		(layer "In9.Cu")
		(net "P5E_PEX3_STN7_RX_DP<114>")
	)
	(segment
		(start 423.465498 -393.666218)
		(end 422.954958 -393.155678)
		(width 0.1651)
		(layer "In9.Cu")
		(net "P5E_PEX3_STN7_RX_DP<114>")
	)
	(segment
		(start 373.711978 -306.331112)
		(end 375.999756 -304.043334)
		(width 0.1651)
		(layer "In9.Cu")
		(net "P5E_PEX3_STN7_RX_DP<114>")
	)
	(segment
		(start 423.959782 -394.160502)
		(end 423.816018 -394.160502)
		(width 0.1651)
		(layer "In9.Cu")
		(net "P5E_PEX3_STN7_RX_DP<114>")
	)
	(segment
		(start 378.992892 -303.429924)
		(end 380.715266 -302.883824)
		(width 0.1651)
		(layer "In9.Cu")
		(net "P5E_PEX3_STN7_RX_DP<114>")
	)
	(segment
		(start 420.082218 -392.241532)
		(end 419.615366 -392.075416)
		(width 0.1651)
		(layer "In9.Cu")
		(net "P5E_PEX3_STN7_RX_DP<114>")
	)
	(segment
		(start 367.718848 -318.531748)
		(end 369.532916 -314.151518)
		(width 0.1651)
		(layer "In9.Cu")
		(net "P5E_PEX3_STN7_RX_DP<114>")
	)
	(segment
		(start 421.336978 -392.580114)
		(end 421.207184 -392.641836)
		(width 0.1651)
		(layer "In9.Cu")
		(net "P5E_PEX3_STN7_RX_DP<114>")
	)
	(segment
		(start 387.624828 -303.405286)
		(end 387.719316 -303.499774)
		(width 0.1143)
		(layer "In9.Cu")
		(net "P5E_PEX3_STN7_RX_DP<114>")
	)
	(segment
		(start 380.715266 -302.883824)
		(end 383.892552 -302.883824)
		(width 0.1651)
		(layer "In9.Cu")
		(net "P5E_PEX3_STN7_RX_DP<114>")
	)
	(segment
		(start 407.02865 -351.73158)
		(end 406.914604 -349.076264)
		(width 0.1651)
		(layer "In9.Cu")
		(net "P5E_PEX3_STN7_RX_DP<114>")
	)
	(segment
		(start 383.96672 -302.929544)
		(end 387.380988 -302.929544)
		(width 0.1143)
		(layer "In9.Cu")
		(net "P5E_PEX3_STN7_RX_DP<114>")
	)
	(segment
		(start 423.465498 -393.809982)
		(end 423.465498 -393.666218)
		(width 0.1651)
		(layer "In9.Cu")
		(net "P5E_PEX3_STN7_RX_DP<114>")
	)
	(segment
		(start 420.212012 -392.17981)
		(end 420.082218 -392.241532)
		(width 0.1651)
		(layer "In9.Cu")
		(net "P5E_PEX3_STN7_RX_DP<114>")
	)
	(segment
		(start 378.48032 -333.291688)
		(end 374.497854 -332.035658)
		(width 0.1651)
		(layer "In9.Cu")
		(net "P5E_PEX3_STN7_RX_DP<114>")
	)
	(segment
		(start 422.461944 -392.980418)
		(end 422.33215 -393.04214)
		(width 0.1651)
		(layer "In9.Cu")
		(net "P5E_PEX3_STN7_RX_DP<114>")
	)
	(segment
		(start 421.207184 -392.641836)
		(end 420.740332 -392.47572)
		(width 0.1651)
		(layer "In9.Cu")
		(net "P5E_PEX3_STN7_RX_DP<114>")
	)
	(segment
		(start 421.865298 -392.876024)
		(end 421.803576 -392.745976)
		(width 0.1651)
		(layer "In9.Cu")
		(net "P5E_PEX3_STN7_RX_DP<114>")
	)
	(segment
		(start 376.635518 -303.779682)
		(end 378.992892 -303.429924)
		(width 0.1651)
		(layer "In9.Cu")
		(net "P5E_PEX3_STN7_RX_DP<114>")
	)
	(segment
		(start 424.772328 -408.1653)
		(end 424.772328 -395.2748)
		(width 0.1651)
		(layer "In9.Cu")
		(net "P5E_PEX3_STN7_RX_DP<114>")
	)
	(segment
		(start 411.694376 -377.20524)
		(end 407.02865 -351.73158)
		(width 0.1651)
		(layer "In9.Cu")
		(net "P5E_PEX3_STN7_RX_DP<114>")
	)
	(segment
		(start 424.772328 -395.2748)
		(end 424.558968 -394.759688)
		(width 0.1651)
		(layer "In9.Cu")
		(net "P5E_PEX3_STN7_RX_DP<114>")
	)
	(segment
		(start 424.016932 -408.699208)
		(end 424.23842 -408.699208)
		(width 0.1651)
		(layer "In9.Cu")
		(net "P5E_PEX3_STN7_RX_DP<114>")
	)
	(segment
		(start 423.816018 -394.160502)
		(end 423.465498 -393.809982)
		(width 0.1651)
		(layer "In9.Cu")
		(net "P5E_PEX3_STN7_RX_DP<114>")
	)
	(segment
		(start 412.746444 -385.001516)
		(end 411.694376 -377.20524)
		(width 0.1651)
		(layer "In9.Cu")
		(net "P5E_PEX3_STN7_RX_DP<114>")
	)
	(segment
		(start 413.374078 -386.65404)
		(end 412.746444 -385.001516)
		(width 0.1651)
		(layer "In9.Cu")
		(net "P5E_PEX3_STN7_RX_DP<114>")
	)
	(segment
		(start 421.803576 -392.745976)
		(end 421.336978 -392.580114)
		(width 0.1651)
		(layer "In9.Cu")
		(net "P5E_PEX3_STN7_RX_DP<114>")
	)
	(segment
		(start 378.492004 -333.291688)
		(end 378.48032 -333.291688)
		(width 0.1651)
		(layer "In9.Cu")
		(net "P5E_PEX3_STN7_RX_DP<114>")
	)
	(segment
		(start 422.954958 -393.155678)
		(end 422.461944 -392.980418)
		(width 0.1651)
		(layer "In9.Cu")
		(net "P5E_PEX3_STN7_RX_DP<114>")
	)
	(segment
		(start 423.889932 -408.572208)
		(end 424.016932 -408.699208)
		(width 0.1651)
		(layer "In9.Cu")
		(net "P5E_PEX3_STN7_RX_DP<114>")
	)
	(segment
		(start 405.009858 -341.561674)
		(end 404.193248 -340.59876)
		(width 0.1651)
		(layer "In9.Cu")
		(net "P5E_PEX3_STN7_RX_DP<114>")
	)
	(segment
		(start 369.532916 -314.151518)
		(end 373.711978 -306.331112)
		(width 0.1651)
		(layer "In9.Cu")
		(net "P5E_PEX3_STN7_RX_DP<114>")
	)
	(segment
		(start 387.719316 -303.499774)
		(end 387.999986 -303.499774)
		(width 0.1143)
		(layer "In9.Cu")
		(net "P5E_PEX3_STN7_RX_DP<114>")
	)
	(segment
		(start 424.558968 -394.759688)
		(end 423.959782 -394.160502)
		(width 0.1651)
		(layer "In9.Cu")
		(net "P5E_PEX3_STN7_RX_DP<114>")
	)
	(segment
		(start 414.669986 -388.583424)
		(end 413.374078 -386.65404)
		(width 0.1651)
		(layer "In9.Cu")
		(net "P5E_PEX3_STN7_RX_DP<114>")
	)
	(segment
		(start 82.075782 -135.882126)
		(end 82.394806 -136.20115)
		(width 0.13462)
		(layer "F.Cu")
		(net "P5E_PEX0_STN0_TX_C_DP<7>")
	)
	(segment
		(start 73.908666 -135.882126)
		(end 82.075782 -135.882126)
		(width 0.13462)
		(layer "F.Cu")
		(net "P5E_PEX0_STN0_TX_C_DP<7>")
	)
	(segment
		(start 73.745852 -136.04494)
		(end 73.908666 -135.882126)
		(width 0.13462)
		(layer "F.Cu")
		(net "P5E_PEX0_STN0_TX_C_DP<7>")
	)
	(segment
		(start 73.257664 -136.04494)
		(end 73.745852 -136.04494)
		(width 0.13462)
		(layer "F.Cu")
		(net "P5E_PEX0_STN0_TX_C_DP<7>")
	)
	(segment
		(start 271.747234 -121.919746)
		(end 272.07718 -121.5898)
		(width 0.13462)
		(layer "F.Cu")
		(net "P5E_PEX2_STN1_TX_C_DP<25>")
	)
	(segment
		(start 277.574248 -121.5898)
		(end 277.739348 -121.7549)
		(width 0.13462)
		(layer "F.Cu")
		(net "P5E_PEX2_STN1_TX_C_DP<25>")
	)
	(segment
		(start 277.739348 -121.7549)
		(end 278.242268 -121.7549)
		(width 0.13462)
		(layer "F.Cu")
		(net "P5E_PEX2_STN1_TX_C_DP<25>")
	)
	(segment
		(start 272.07718 -121.5898)
		(end 277.574248 -121.5898)
		(width 0.13462)
		(layer "F.Cu")
		(net "P5E_PEX2_STN1_TX_C_DP<25>")
	)
	(segment
		(start 442.06795 -31.99003)
		(end 441.564776 -31.99003)
		(width 0.13462)
		(layer "F.Cu")
		(net "P5E_PEX3_STN2_TX_C_DN<34>")
	)
	(segment
		(start 443.82563 -31.825184)
		(end 443.514734 -32.13608)
		(width 0.13462)
		(layer "F.Cu")
		(net "P5E_PEX3_STN2_TX_C_DN<34>")
	)
	(segment
		(start 443.514734 -32.13608)
		(end 442.214 -32.13608)
		(width 0.13462)
		(layer "F.Cu")
		(net "P5E_PEX3_STN2_TX_C_DN<34>")
	)
	(segment
		(start 442.214 -32.13608)
		(end 442.06795 -31.99003)
		(width 0.13462)
		(layer "F.Cu")
		(net "P5E_PEX3_STN2_TX_C_DN<34>")
	)
	(segment
		(start 416.402012 -356.511606)
		(end 416.08248 -356.831138)
		(width 0.13462)
		(layer "F.Cu")
		(net "P5E_PEX3_STN7_TX_C_DN<115>")
	)
	(segment
		(start 416.08248 -357.463598)
		(end 416.376612 -357.75773)
		(width 0.13462)
		(layer "F.Cu")
		(net "P5E_PEX3_STN7_TX_C_DN<115>")
	)
	(segment
		(start 416.08248 -356.831138)
		(end 416.08248 -357.463598)
		(width 0.13462)
		(layer "F.Cu")
		(net "P5E_PEX3_STN7_TX_C_DN<115>")
	)
	(segment
		(start 415.913824 -388.970774)
		(end 414.274 -385.699)
		(width 0.1651)
		(layer "In11.Cu")
		(net "P5E_PEX3_STN7_TX_C_DN<115>")
	)
	(segment
		(start 426.763942 -402.281136)
		(end 427.215808 -401.82927)
		(width 0.1651)
		(layer "In11.Cu")
		(net "P5E_PEX3_STN7_TX_C_DN<115>")
	)
	(segment
		(start 427.215808 -395.288008)
		(end 425.478194 -393.550394)
		(width 0.1651)
		(layer "In11.Cu")
		(net "P5E_PEX3_STN7_TX_C_DN<115>")
	)
	(segment
		(start 425.478194 -393.550394)
		(end 415.913824 -388.970774)
		(width 0.1651)
		(layer "In11.Cu")
		(net "P5E_PEX3_STN7_TX_C_DN<115>")
	)
	(segment
		(start 426.216826 -402.281136)
		(end 426.763942 -402.281136)
		(width 0.1651)
		(layer "In11.Cu")
		(net "P5E_PEX3_STN7_TX_C_DN<115>")
	)
	(segment
		(start 426.089826 -402.408136)
		(end 426.216826 -402.281136)
		(width 0.1651)
		(layer "In11.Cu")
		(net "P5E_PEX3_STN7_TX_C_DN<115>")
	)
	(segment
		(start 413.99968 -383.504694)
		(end 414.438338 -368.904012)
		(width 0.1651)
		(layer "In11.Cu")
		(net "P5E_PEX3_STN7_TX_C_DN<115>")
	)
	(segment
		(start 426.089826 -402.790152)
		(end 426.089826 -402.408136)
		(width 0.1651)
		(layer "In11.Cu")
		(net "P5E_PEX3_STN7_TX_C_DN<115>")
	)
	(segment
		(start 414.438338 -368.904012)
		(end 416.085782 -358.899714)
		(width 0.1651)
		(layer "In11.Cu")
		(net "P5E_PEX3_STN7_TX_C_DN<115>")
	)
	(segment
		(start 416.085782 -358.04856)
		(end 416.376612 -357.75773)
		(width 0.1651)
		(layer "In11.Cu")
		(net "P5E_PEX3_STN7_TX_C_DN<115>")
	)
	(segment
		(start 427.215808 -401.82927)
		(end 427.215808 -395.288008)
		(width 0.1651)
		(layer "In11.Cu")
		(net "P5E_PEX3_STN7_TX_C_DN<115>")
	)
	(segment
		(start 416.085782 -358.899714)
		(end 416.085782 -358.04856)
		(width 0.1651)
		(layer "In11.Cu")
		(net "P5E_PEX3_STN7_TX_C_DN<115>")
	)
	(segment
		(start 414.274 -385.699)
		(end 413.99968 -383.504694)
		(width 0.1651)
		(layer "In11.Cu")
		(net "P5E_PEX3_STN7_TX_C_DN<115>")
	)
	(segment
		(start 166.742364 -150.560024)
		(end 168.361868 -150.560024)
		(width 0.13208)
		(layer "F.Cu")
		(net "CLK_50M_NIC2_RBT_REF")
	)
	(segment
		(start 168.361868 -150.560024)
		(end 169.058844 -151.257)
		(width 0.13208)
		(layer "F.Cu")
		(net "CLK_50M_NIC2_RBT_REF")
	)
	(via
		(at 169.058844 -151.257)
		(size 0.508)
		(drill 0.254)
		(layers "F.Cu" "B.Cu")
		(net "CLK_50M_NIC2_RBT_REF")
	)
	(segment
		(start 166.055294 -150.9776)
		(end 166.544244 -150.9776)
		(width 0.13208)
		(layer "B.Cu")
		(net "CLK_50M_NIC2_RBT_REF")
	)
	(segment
		(start 168.361868 -150.560024)
		(end 169.058844 -151.257)
		(width 0.13208)
		(layer "B.Cu")
		(net "CLK_50M_NIC2_RBT_REF")
	)
	(segment
		(start 166.96182 -150.560024)
		(end 168.361868 -150.560024)
		(width 0.13208)
		(layer "B.Cu")
		(net "CLK_50M_NIC2_RBT_REF")
	)
	(segment
		(start 166.544244 -150.9776)
		(end 166.96182 -150.560024)
		(width 0.13208)
		(layer "B.Cu")
		(net "CLK_50M_NIC2_RBT_REF")
	)
	(segment
		(start 423.920666 -87.479632)
		(end 423.920666 -86.247986)
		(width 0.13208)
		(layer "F.Cu")
		(net "RST_HP_NIC7_N")
	)
	(segment
		(start 425.33443 -87.599012)
		(end 424.040046 -87.599012)
		(width 0.13208)
		(layer "F.Cu")
		(net "RST_HP_NIC7_N")
	)
	(segment
		(start 424.040046 -87.599012)
		(end 423.920666 -87.479632)
		(width 0.13208)
		(layer "F.Cu")
		(net "RST_HP_NIC7_N")
	)
	(segment
		(start 423.920666 -85.751924)
		(end 424.246294 -85.426296)
		(width 0.13208)
		(layer "F.Cu")
		(net "RST_HP_NIC7_N")
	)
	(segment
		(start 423.920666 -86.247986)
		(end 423.920666 -85.751924)
		(width 0.13208)
		(layer "F.Cu")
		(net "RST_HP_NIC7_N")
	)
	(segment
		(start 424.246294 -85.426296)
		(end 427.199552 -85.426296)
		(width 0.13208)
		(layer "F.Cu")
		(net "RST_HP_NIC7_N")
	)
	(via
		(at 423.920666 -86.247986)
		(size 0.508)
		(drill 0.254)
		(layers "F.Cu" "B.Cu")
		(net "RST_HP_NIC7_N")
	)
	(segment
		(start 68.006722 -132.007864)
		(end 65.498218 -132.007864)
		(width 0.13462)
		(layer "F.Cu")
		(net "P5E_PEX0_STN0_RX_DN<5>")
	)
	(segment
		(start 65.498218 -132.007864)
		(end 65.49771 -132.008372)
		(width 0.13462)
		(layer "F.Cu")
		(net "P5E_PEX0_STN0_RX_DN<5>")
	)
	(segment
		(start 68.169536 -131.84505)
		(end 68.006722 -132.007864)
		(width 0.13462)
		(layer "F.Cu")
		(net "P5E_PEX0_STN0_RX_DN<5>")
	)
	(segment
		(start 65.49771 -132.008372)
		(end 65.20307 -131.713732)
		(width 0.13462)
		(layer "F.Cu")
		(net "P5E_PEX0_STN0_RX_DN<5>")
	)
	(segment
		(start 68.65747 -131.84505)
		(end 68.169536 -131.84505)
		(width 0.13462)
		(layer "F.Cu")
		(net "P5E_PEX0_STN0_RX_DN<5>")
	)
	(segment
		(start 84.528914 -233.312462)
		(end 83.495134 -222.600774)
		(width 0.1651)
		(layer "In5.Cu")
		(net "P5E_PEX0_STN0_RX_DN<5>")
	)
	(segment
		(start 82.173826 -283.170122)
		(end 83.843368 -283.170122)
		(width 0.1143)
		(layer "In5.Cu")
		(net "P5E_PEX0_STN0_RX_DN<5>")
	)
	(segment
		(start 77.615288 -138.484864)
		(end 76.934568 -137.449306)
		(width 0.1651)
		(layer "In5.Cu")
		(net "P5E_PEX0_STN0_RX_DN<5>")
	)
	(segment
		(start 83.495134 -222.600774)
		(end 81.282794 -160.702752)
		(width 0.1651)
		(layer "In5.Cu")
		(net "P5E_PEX0_STN0_RX_DN<5>")
	)
	(segment
		(start 76.90612 -137.405872)
		(end 74.212958 -135.46074)
		(width 0.1651)
		(layer "In5.Cu")
		(net "P5E_PEX0_STN0_RX_DN<5>")
	)
	(segment
		(start 77.901292 -139.151868)
		(end 77.615288 -138.484864)
		(width 0.1651)
		(layer "In5.Cu")
		(net "P5E_PEX0_STN0_RX_DN<5>")
	)
	(segment
		(start 94.78391 -270.233394)
		(end 87.147908 -244.131846)
		(width 0.1651)
		(layer "In5.Cu")
		(net "P5E_PEX0_STN0_RX_DN<5>")
	)
	(segment
		(start 81.282794 -160.702752)
		(end 79.89951 -151.3586)
		(width 0.1651)
		(layer "In5.Cu")
		(net "P5E_PEX0_STN0_RX_DN<5>")
	)
	(segment
		(start 83.917536 -283.215842)
		(end 84.651342 -283.215842)
		(width 0.1651)
		(layer "In5.Cu")
		(net "P5E_PEX0_STN0_RX_DN<5>")
	)
	(segment
		(start 92.97162 -275.417788)
		(end 94.729046 -272.307558)
		(width 0.1651)
		(layer "In5.Cu")
		(net "P5E_PEX0_STN0_RX_DN<5>")
	)
	(segment
		(start 76.934568 -137.449306)
		(end 76.934568 -137.449052)
		(width 0.1651)
		(layer "In5.Cu")
		(net "P5E_PEX0_STN0_RX_DN<5>")
	)
	(segment
		(start 82.184494 -283.549852)
		(end 82.070194 -283.435552)
		(width 0.1143)
		(layer "In5.Cu")
		(net "P5E_PEX0_STN0_RX_DN<5>")
	)
	(segment
		(start 67.327018 -132.004562)
		(end 65.4939 -132.004562)
		(width 0.1651)
		(layer "In5.Cu")
		(net "P5E_PEX0_STN0_RX_DN<5>")
	)
	(segment
		(start 84.651342 -283.215842)
		(end 85.574124 -282.609036)
		(width 0.1651)
		(layer "In5.Cu")
		(net "P5E_PEX0_STN0_RX_DN<5>")
	)
	(segment
		(start 74.212958 -135.46074)
		(end 67.327018 -132.004562)
		(width 0.1651)
		(layer "In5.Cu")
		(net "P5E_PEX0_STN0_RX_DN<5>")
	)
	(segment
		(start 79.899764 -151.3586)
		(end 78.517242 -142.021306)
		(width 0.1651)
		(layer "In5.Cu")
		(net "P5E_PEX0_STN0_RX_DN<5>")
	)
	(segment
		(start 82.070194 -283.435552)
		(end 82.070194 -283.273754)
		(width 0.1143)
		(layer "In5.Cu")
		(net "P5E_PEX0_STN0_RX_DN<5>")
	)
	(segment
		(start 65.4939 -132.004562)
		(end 65.20307 -131.713732)
		(width 0.1651)
		(layer "In5.Cu")
		(net "P5E_PEX0_STN0_RX_DN<5>")
	)
	(segment
		(start 83.843368 -283.170122)
		(end 83.889088 -283.215842)
		(width 0.1143)
		(layer "In5.Cu")
		(net "P5E_PEX0_STN0_RX_DN<5>")
	)
	(segment
		(start 78.517242 -142.021306)
		(end 77.901292 -139.151868)
		(width 0.1651)
		(layer "In5.Cu")
		(net "P5E_PEX0_STN0_RX_DN<5>")
	)
	(segment
		(start 76.934568 -137.449052)
		(end 76.90612 -137.405872)
		(width 0.1651)
		(layer "In5.Cu")
		(net "P5E_PEX0_STN0_RX_DN<5>")
	)
	(segment
		(start 87.147908 -244.131846)
		(end 84.528914 -233.312462)
		(width 0.1651)
		(layer "In5.Cu")
		(net "P5E_PEX0_STN0_RX_DN<5>")
	)
	(segment
		(start 79.89951 -151.3586)
		(end 79.899764 -151.3586)
		(width 0.1651)
		(layer "In5.Cu")
		(net "P5E_PEX0_STN0_RX_DN<5>")
	)
	(segment
		(start 82.449924 -283.549852)
		(end 82.184494 -283.549852)
		(width 0.1143)
		(layer "In5.Cu")
		(net "P5E_PEX0_STN0_RX_DN<5>")
	)
	(segment
		(start 83.889088 -283.215842)
		(end 83.917536 -283.215842)
		(width 0.1143)
		(layer "In5.Cu")
		(net "P5E_PEX0_STN0_RX_DN<5>")
	)
	(segment
		(start 82.070194 -283.273754)
		(end 82.173826 -283.170122)
		(width 0.1143)
		(layer "In5.Cu")
		(net "P5E_PEX0_STN0_RX_DN<5>")
	)
	(segment
		(start 85.574124 -282.609036)
		(end 92.97162 -275.417788)
		(width 0.1651)
		(layer "In5.Cu")
		(net "P5E_PEX0_STN0_RX_DN<5>")
	)
	(segment
		(start 94.729046 -272.307558)
		(end 94.78391 -270.233394)
		(width 0.1651)
		(layer "In5.Cu")
		(net "P5E_PEX0_STN0_RX_DN<5>")
	)
	(segment
		(start 134.193788 -344.539062)
		(end 134.513828 -344.219022)
		(width 0.13462)
		(layer "F.Cu")
		(net "P5E_PEX1_STN5_TX_C_DN<82>")
	)
	(segment
		(start 134.488428 -345.465146)
		(end 134.193788 -345.170506)
		(width 0.13462)
		(layer "F.Cu")
		(net "P5E_PEX1_STN5_TX_C_DN<82>")
	)
	(segment
		(start 134.193788 -345.170506)
		(end 134.193788 -344.539062)
		(width 0.13462)
		(layer "F.Cu")
		(net "P5E_PEX1_STN5_TX_C_DN<82>")
	)
	(segment
		(start 134.197598 -346.477082)
		(end 134.197598 -345.755976)
		(width 0.1651)
		(layer "In7.Cu")
		(net "P5E_PEX1_STN5_TX_C_DN<82>")
	)
	(segment
		(start 120.437402 -405.080724)
		(end 120.786144 -405.080724)
		(width 0.1651)
		(layer "In7.Cu")
		(net "P5E_PEX1_STN5_TX_C_DN<82>")
	)
	(segment
		(start 120.786144 -405.080724)
		(end 121.369582 -404.497286)
		(width 0.1651)
		(layer "In7.Cu")
		(net "P5E_PEX1_STN5_TX_C_DN<82>")
	)
	(segment
		(start 136.779508 -387.597904)
		(end 137.512806 -386.987542)
		(width 0.1651)
		(layer "In7.Cu")
		(net "P5E_PEX1_STN5_TX_C_DN<82>")
	)
	(segment
		(start 137.772648 -383.189734)
		(end 138.100308 -369.869212)
		(width 0.1651)
		(layer "In7.Cu")
		(net "P5E_PEX1_STN5_TX_C_DN<82>")
	)
	(segment
		(start 134.197598 -345.755976)
		(end 134.488428 -345.465146)
		(width 0.1651)
		(layer "In7.Cu")
		(net "P5E_PEX1_STN5_TX_C_DN<82>")
	)
	(segment
		(start 137.512806 -386.987542)
		(end 137.772648 -386.492496)
		(width 0.1651)
		(layer "In7.Cu")
		(net "P5E_PEX1_STN5_TX_C_DN<82>")
	)
	(segment
		(start 137.772648 -386.492496)
		(end 137.772648 -383.189734)
		(width 0.1651)
		(layer "In7.Cu")
		(net "P5E_PEX1_STN5_TX_C_DN<82>")
	)
	(segment
		(start 132.643118 -359.22458)
		(end 132.643118 -348.031562)
		(width 0.1651)
		(layer "In7.Cu")
		(net "P5E_PEX1_STN5_TX_C_DN<82>")
	)
	(segment
		(start 138.100308 -369.869212)
		(end 137.794238 -368.861086)
		(width 0.1651)
		(layer "In7.Cu")
		(net "P5E_PEX1_STN5_TX_C_DN<82>")
	)
	(segment
		(start 133.295898 -388.884668)
		(end 135.554212 -388.155434)
		(width 0.1651)
		(layer "In7.Cu")
		(net "P5E_PEX1_STN5_TX_C_DN<82>")
	)
	(segment
		(start 121.369582 -395.422628)
		(end 124.31141 -392.670284)
		(width 0.1651)
		(layer "In7.Cu")
		(net "P5E_PEX1_STN5_TX_C_DN<82>")
	)
	(segment
		(start 121.369582 -404.497286)
		(end 121.369582 -395.422628)
		(width 0.1651)
		(layer "In7.Cu")
		(net "P5E_PEX1_STN5_TX_C_DN<82>")
	)
	(segment
		(start 135.554212 -388.155434)
		(end 136.779508 -387.597904)
		(width 0.1651)
		(layer "In7.Cu")
		(net "P5E_PEX1_STN5_TX_C_DN<82>")
	)
	(segment
		(start 120.310148 -405.207978)
		(end 120.437402 -405.080724)
		(width 0.1651)
		(layer "In7.Cu")
		(net "P5E_PEX1_STN5_TX_C_DN<82>")
	)
	(segment
		(start 132.643118 -348.031562)
		(end 134.197598 -346.477082)
		(width 0.1651)
		(layer "In7.Cu")
		(net "P5E_PEX1_STN5_TX_C_DN<82>")
	)
	(segment
		(start 124.31141 -392.670284)
		(end 133.295898 -388.884668)
		(width 0.1651)
		(layer "In7.Cu")
		(net "P5E_PEX1_STN5_TX_C_DN<82>")
	)
	(segment
		(start 120.310148 -405.589994)
		(end 120.310148 -405.207978)
		(width 0.1651)
		(layer "In7.Cu")
		(net "P5E_PEX1_STN5_TX_C_DN<82>")
	)
	(segment
		(start 137.794238 -368.861086)
		(end 132.643118 -359.22458)
		(width 0.1651)
		(layer "In7.Cu")
		(net "P5E_PEX1_STN5_TX_C_DN<82>")
	)
	(segment
		(start 269.105126 -109.20984)
		(end 269.425166 -108.8898)
		(width 0.13462)
		(layer "F.Cu")
		(net "P5E_PEX2_STN1_TX_C_DP<21>")
	)
	(segment
		(start 277.739348 -109.044994)
		(end 278.242268 -109.044994)
		(width 0.13462)
		(layer "F.Cu")
		(net "P5E_PEX2_STN1_TX_C_DP<21>")
	)
	(segment
		(start 269.425166 -108.8898)
		(end 277.584154 -108.8898)
		(width 0.13462)
		(layer "F.Cu")
		(net "P5E_PEX2_STN1_TX_C_DP<21>")
	)
	(segment
		(start 277.584154 -108.8898)
		(end 277.739348 -109.044994)
		(width 0.13462)
		(layer "F.Cu")
		(net "P5E_PEX2_STN1_TX_C_DP<21>")
	)
	(segment
		(start 325.233284 -350.685354)
		(end 325.233284 -351.316798)
		(width 0.13462)
		(layer "F.Cu")
		(net "P5E_PEX2_STN5_TX_C_DP<86>")
	)
	(segment
		(start 325.233284 -351.316798)
		(end 324.938644 -351.611438)
		(width 0.13462)
		(layer "F.Cu")
		(net "P5E_PEX2_STN5_TX_C_DP<86>")
	)
	(segment
		(start 324.913244 -350.365314)
		(end 325.233284 -350.685354)
		(width 0.13462)
		(layer "F.Cu")
		(net "P5E_PEX2_STN5_TX_C_DP<86>")
	)
	(segment
		(start 325.229474 -352.356166)
		(end 325.229474 -351.902268)
		(width 0.1651)
		(layer "In7.Cu")
		(net "P5E_PEX2_STN5_TX_C_DP<86>")
	)
	(segment
		(start 336.91322 -389.60806)
		(end 330.88072 -387.11632)
		(width 0.1651)
		(layer "In7.Cu")
		(net "P5E_PEX2_STN5_TX_C_DP<86>")
	)
	(segment
		(start 340.313518 -391.641838)
		(end 339.88248 -391.396982)
		(width 0.1651)
		(layer "In7.Cu")
		(net "P5E_PEX2_STN5_TX_C_DP<86>")
	)
	(segment
		(start 342.466676 -392.762486)
		(end 342.345518 -392.796014)
		(width 0.1651)
		(layer "In7.Cu")
		(net "P5E_PEX2_STN5_TX_C_DP<86>")
	)
	(segment
		(start 329.155298 -384.451352)
		(end 323.674994 -358.902)
		(width 0.1651)
		(layer "In7.Cu")
		(net "P5E_PEX2_STN5_TX_C_DP<86>")
	)
	(segment
		(start 330.88072 -387.11632)
		(end 329.77582 -385.99618)
		(width 0.1651)
		(layer "In7.Cu")
		(net "P5E_PEX2_STN5_TX_C_DP<86>")
	)
	(segment
		(start 323.674994 -358.902)
		(end 323.674994 -353.910646)
		(width 0.1651)
		(layer "In7.Cu")
		(net "P5E_PEX2_STN5_TX_C_DP<86>")
	)
	(segment
		(start 342.345518 -392.796014)
		(end 341.91448 -392.551158)
		(width 0.1651)
		(layer "In7.Cu")
		(net "P5E_PEX2_STN5_TX_C_DP<86>")
	)
	(segment
		(start 345.53398 -394.88364)
		(end 345.06916 -394.24102)
		(width 0.1651)
		(layer "In7.Cu")
		(net "P5E_PEX2_STN5_TX_C_DP<86>")
	)
	(segment
		(start 342.897206 -393.007088)
		(end 342.466676 -392.762486)
		(width 0.1651)
		(layer "In7.Cu")
		(net "P5E_PEX2_STN5_TX_C_DP<86>")
	)
	(segment
		(start 344.689938 -404.672038)
		(end 344.816938 -404.799038)
		(width 0.1651)
		(layer "In7.Cu")
		(net "P5E_PEX2_STN5_TX_C_DP<86>")
	)
	(segment
		(start 341.91448 -392.551158)
		(end 341.881206 -392.43)
		(width 0.1651)
		(layer "In7.Cu")
		(net "P5E_PEX2_STN5_TX_C_DP<86>")
	)
	(segment
		(start 341.329518 -392.218926)
		(end 340.89848 -391.97407)
		(width 0.1651)
		(layer "In7.Cu")
		(net "P5E_PEX2_STN5_TX_C_DP<86>")
	)
	(segment
		(start 343.482676 -393.339828)
		(end 343.361518 -393.373356)
		(width 0.1651)
		(layer "In7.Cu")
		(net "P5E_PEX2_STN5_TX_C_DP<86>")
	)
	(segment
		(start 340.89848 -391.97407)
		(end 340.865206 -391.852912)
		(width 0.1651)
		(layer "In7.Cu")
		(net "P5E_PEX2_STN5_TX_C_DP<86>")
	)
	(segment
		(start 323.674994 -353.910646)
		(end 325.229474 -352.356166)
		(width 0.1651)
		(layer "In7.Cu")
		(net "P5E_PEX2_STN5_TX_C_DP<86>")
	)
	(segment
		(start 344.816938 -404.799038)
		(end 345.247214 -404.799038)
		(width 0.1651)
		(layer "In7.Cu")
		(net "P5E_PEX2_STN5_TX_C_DP<86>")
	)
	(segment
		(start 343.361518 -393.373356)
		(end 342.93048 -393.128246)
		(width 0.1651)
		(layer "In7.Cu")
		(net "P5E_PEX2_STN5_TX_C_DP<86>")
	)
	(segment
		(start 344.689938 -404.290022)
		(end 344.689938 -404.672038)
		(width 0.1651)
		(layer "In7.Cu")
		(net "P5E_PEX2_STN5_TX_C_DP<86>")
	)
	(segment
		(start 342.93048 -393.128246)
		(end 342.897206 -393.007088)
		(width 0.1651)
		(layer "In7.Cu")
		(net "P5E_PEX2_STN5_TX_C_DP<86>")
	)
	(segment
		(start 340.434676 -391.60831)
		(end 340.313518 -391.641838)
		(width 0.1651)
		(layer "In7.Cu")
		(net "P5E_PEX2_STN5_TX_C_DP<86>")
	)
	(segment
		(start 341.450676 -392.185398)
		(end 341.329518 -392.218926)
		(width 0.1651)
		(layer "In7.Cu")
		(net "P5E_PEX2_STN5_TX_C_DP<86>")
	)
	(segment
		(start 340.865206 -391.852912)
		(end 340.434676 -391.60831)
		(width 0.1651)
		(layer "In7.Cu")
		(net "P5E_PEX2_STN5_TX_C_DP<86>")
	)
	(segment
		(start 341.881206 -392.43)
		(end 341.450676 -392.185398)
		(width 0.1651)
		(layer "In7.Cu")
		(net "P5E_PEX2_STN5_TX_C_DP<86>")
	)
	(segment
		(start 339.849206 -391.275824)
		(end 336.91322 -389.60806)
		(width 0.1651)
		(layer "In7.Cu")
		(net "P5E_PEX2_STN5_TX_C_DP<86>")
	)
	(segment
		(start 329.77582 -385.99618)
		(end 329.155298 -384.451352)
		(width 0.1651)
		(layer "In7.Cu")
		(net "P5E_PEX2_STN5_TX_C_DP<86>")
	)
	(segment
		(start 345.247214 -404.799038)
		(end 345.53398 -404.512272)
		(width 0.1651)
		(layer "In7.Cu")
		(net "P5E_PEX2_STN5_TX_C_DP<86>")
	)
	(segment
		(start 339.88248 -391.396982)
		(end 339.849206 -391.275824)
		(width 0.1651)
		(layer "In7.Cu")
		(net "P5E_PEX2_STN5_TX_C_DP<86>")
	)
	(segment
		(start 345.53398 -404.512272)
		(end 345.53398 -394.88364)
		(width 0.1651)
		(layer "In7.Cu")
		(net "P5E_PEX2_STN5_TX_C_DP<86>")
	)
	(segment
		(start 345.06916 -394.24102)
		(end 343.482676 -393.339828)
		(width 0.1651)
		(layer "In7.Cu")
		(net "P5E_PEX2_STN5_TX_C_DP<86>")
	)
	(segment
		(start 325.229474 -351.902268)
		(end 324.938644 -351.611438)
		(width 0.1651)
		(layer "In7.Cu")
		(net "P5E_PEX2_STN5_TX_C_DP<86>")
	)
	(segment
		(start 436.487316 -30.190186)
		(end 436.324502 -30.353)
		(width 0.13462)
		(layer "F.Cu")
		(net "P5E_PEX3_STN2_RX_DN<33>")
	)
	(segment
		(start 436.964836 -30.190186)
		(end 436.487316 -30.190186)
		(width 0.13462)
		(layer "F.Cu")
		(net "P5E_PEX3_STN2_RX_DN<33>")
	)
	(segment
		(start 433.804568 -30.353)
		(end 433.510436 -30.058868)
		(width 0.13462)
		(layer "F.Cu")
		(net "P5E_PEX3_STN2_RX_DN<33>")
	)
	(segment
		(start 436.324502 -30.353)
		(end 433.804568 -30.353)
		(width 0.13462)
		(layer "F.Cu")
		(net "P5E_PEX3_STN2_RX_DN<33>")
	)
	(segment
		(start 437.166004 -38.15207)
		(end 437.885078 -34.102294)
		(width 0.1651)
		(layer "In7.Cu")
		(net "P5E_PEX3_STN2_RX_DN<33>")
	)
	(segment
		(start 405.715978 -271.345152)
		(end 405.715978 -270.929862)
		(width 0.1651)
		(layer "In7.Cu")
		(net "P5E_PEX3_STN2_RX_DN<33>")
	)
	(segment
		(start 405.670258 -271.41932)
		(end 405.715978 -271.3736)
		(width 0.1143)
		(layer "In7.Cu")
		(net "P5E_PEX3_STN2_RX_DN<33>")
	)
	(segment
		(start 406.05329 -267.040868)
		(end 425.618402 -154.698446)
		(width 0.1651)
		(layer "In7.Cu")
		(net "P5E_PEX3_STN2_RX_DN<33>")
	)
	(segment
		(start 405.715978 -271.3736)
		(end 405.715978 -271.345152)
		(width 0.1143)
		(layer "In7.Cu")
		(net "P5E_PEX3_STN2_RX_DN<33>")
	)
	(segment
		(start 438.320942 -61.209428)
		(end 438.505854 -49.3776)
		(width 0.1651)
		(layer "In7.Cu")
		(net "P5E_PEX3_STN2_RX_DN<33>")
	)
	(segment
		(start 427.312836 -116.691918)
		(end 438.320942 -61.209428)
		(width 0.1651)
		(layer "In7.Cu")
		(net "P5E_PEX3_STN2_RX_DN<33>")
	)
	(segment
		(start 405.935688 -273.479514)
		(end 405.821134 -273.479514)
		(width 0.1143)
		(layer "In7.Cu")
		(net "P5E_PEX3_STN2_RX_DN<33>")
	)
	(segment
		(start 437.893714 -33.002982)
		(end 437.607456 -32.239712)
		(width 0.1651)
		(layer "In7.Cu")
		(net "P5E_PEX3_STN2_RX_DN<33>")
	)
	(segment
		(start 437.189626 -39.636954)
		(end 437.166004 -38.15207)
		(width 0.1651)
		(layer "In7.Cu")
		(net "P5E_PEX3_STN2_RX_DN<33>")
	)
	(segment
		(start 437.607456 -32.239712)
		(end 436.390796 -30.349698)
		(width 0.1651)
		(layer "In7.Cu")
		(net "P5E_PEX3_STN2_RX_DN<33>")
	)
	(segment
		(start 406.049988 -273.099784)
		(end 406.049988 -273.365214)
		(width 0.1143)
		(layer "In7.Cu")
		(net "P5E_PEX3_STN2_RX_DN<33>")
	)
	(segment
		(start 406.049988 -273.365214)
		(end 405.935688 -273.479514)
		(width 0.1143)
		(layer "In7.Cu")
		(net "P5E_PEX3_STN2_RX_DN<33>")
	)
	(segment
		(start 405.715978 -270.929862)
		(end 406.05329 -267.040868)
		(width 0.1651)
		(layer "In7.Cu")
		(net "P5E_PEX3_STN2_RX_DN<33>")
	)
	(segment
		(start 436.390796 -30.349698)
		(end 433.801266 -30.349698)
		(width 0.1651)
		(layer "In7.Cu")
		(net "P5E_PEX3_STN2_RX_DN<33>")
	)
	(segment
		(start 405.670258 -273.328638)
		(end 405.670258 -271.41932)
		(width 0.1143)
		(layer "In7.Cu")
		(net "P5E_PEX3_STN2_RX_DN<33>")
	)
	(segment
		(start 438.505854 -49.3776)
		(end 437.189626 -39.636954)
		(width 0.1651)
		(layer "In7.Cu")
		(net "P5E_PEX3_STN2_RX_DN<33>")
	)
	(segment
		(start 437.885078 -34.102294)
		(end 437.893714 -33.002982)
		(width 0.1651)
		(layer "In7.Cu")
		(net "P5E_PEX3_STN2_RX_DN<33>")
	)
	(segment
		(start 425.618402 -154.698446)
		(end 426.997368 -143.990568)
		(width 0.1651)
		(layer "In7.Cu")
		(net "P5E_PEX3_STN2_RX_DN<33>")
	)
	(segment
		(start 426.997368 -143.990568)
		(end 427.312836 -116.691918)
		(width 0.1651)
		(layer "In7.Cu")
		(net "P5E_PEX3_STN2_RX_DN<33>")
	)
	(segment
		(start 433.801266 -30.349698)
		(end 433.510436 -30.058868)
		(width 0.1651)
		(layer "In7.Cu")
		(net "P5E_PEX3_STN2_RX_DN<33>")
	)
	(segment
		(start 405.821134 -273.479514)
		(end 405.670258 -273.328638)
		(width 0.1143)
		(layer "In7.Cu")
		(net "P5E_PEX3_STN2_RX_DN<33>")
	)
	(segment
		(start 412.97352 -351.317306)
		(end 413.267652 -351.611438)
		(width 0.13462)
		(layer "F.Cu")
		(net "P5E_PEX3_STN7_TX_C_DN<113>")
	)
	(segment
		(start 413.293052 -350.365314)
		(end 412.97352 -350.684846)
		(width 0.13462)
		(layer "F.Cu")
		(net "P5E_PEX3_STN7_TX_C_DN<113>")
	)
	(segment
		(start 412.97352 -350.684846)
		(end 412.97352 -351.317306)
		(width 0.13462)
		(layer "F.Cu")
		(net "P5E_PEX3_STN7_TX_C_DN<113>")
	)
	(segment
		(start 414.566354 -390.719564)
		(end 412.207202 -386.29082)
		(width 0.1651)
		(layer "In11.Cu")
		(net "P5E_PEX3_STN7_TX_C_DN<113>")
	)
	(segment
		(start 411.733746 -383.452624)
		(end 411.712664 -383.219452)
		(width 0.1651)
		(layer "In11.Cu")
		(net "P5E_PEX3_STN7_TX_C_DN<113>")
	)
	(segment
		(start 422.815766 -401.82927)
		(end 422.815766 -394.799566)
		(width 0.1651)
		(layer "In11.Cu")
		(net "P5E_PEX3_STN7_TX_C_DN<113>")
	)
	(segment
		(start 411.1752 -355.8032)
		(end 411.422342 -354.027486)
		(width 0.1651)
		(layer "In11.Cu")
		(net "P5E_PEX3_STN7_TX_C_DN<113>")
	)
	(segment
		(start 422.3639 -402.281136)
		(end 422.815766 -401.82927)
		(width 0.1651)
		(layer "In11.Cu")
		(net "P5E_PEX3_STN7_TX_C_DN<113>")
	)
	(segment
		(start 411.422342 -354.027486)
		(end 412.976822 -352.473006)
		(width 0.1651)
		(layer "In11.Cu")
		(net "P5E_PEX3_STN7_TX_C_DN<113>")
	)
	(segment
		(start 421.689784 -402.790152)
		(end 421.689784 -402.408136)
		(width 0.1651)
		(layer "In11.Cu")
		(net "P5E_PEX3_STN7_TX_C_DN<113>")
	)
	(segment
		(start 412.976822 -352.473006)
		(end 412.976822 -351.902268)
		(width 0.1651)
		(layer "In11.Cu")
		(net "P5E_PEX3_STN7_TX_C_DN<113>")
	)
	(segment
		(start 412.976822 -351.902268)
		(end 413.267652 -351.611438)
		(width 0.1651)
		(layer "In11.Cu")
		(net "P5E_PEX3_STN7_TX_C_DN<113>")
	)
	(segment
		(start 412.207202 -386.29082)
		(end 411.733746 -383.452624)
		(width 0.1651)
		(layer "In11.Cu")
		(net "P5E_PEX3_STN7_TX_C_DN<113>")
	)
	(segment
		(start 411.712664 -383.219452)
		(end 411.1752 -355.8032)
		(width 0.1651)
		(layer "In11.Cu")
		(net "P5E_PEX3_STN7_TX_C_DN<113>")
	)
	(segment
		(start 422.815766 -394.799566)
		(end 422.361106 -394.344906)
		(width 0.1651)
		(layer "In11.Cu")
		(net "P5E_PEX3_STN7_TX_C_DN<113>")
	)
	(segment
		(start 421.816784 -402.281136)
		(end 422.3639 -402.281136)
		(width 0.1651)
		(layer "In11.Cu")
		(net "P5E_PEX3_STN7_TX_C_DN<113>")
	)
	(segment
		(start 421.689784 -402.408136)
		(end 421.816784 -402.281136)
		(width 0.1651)
		(layer "In11.Cu")
		(net "P5E_PEX3_STN7_TX_C_DN<113>")
	)
	(segment
		(start 422.361106 -394.344906)
		(end 414.566354 -390.719564)
		(width 0.1651)
		(layer "In11.Cu")
		(net "P5E_PEX3_STN7_TX_C_DN<113>")
	)
	(segment
		(start 166.742364 -153.560018)
		(end 168.931844 -153.560018)
		(width 0.13208)
		(layer "F.Cu")
		(net "NCSI_NIC2_TXD0")
	)
	(via
		(at 168.931844 -153.560018)
		(size 0.508)
		(drill 0.254)
		(layers "F.Cu" "B.Cu")
		(net "NCSI_NIC2_TXD0")
	)
	(segment
		(start 168.017698 -151.9936)
		(end 168.931844 -152.907746)
		(width 0.13208)
		(layer "B.Cu")
		(net "NCSI_NIC2_TXD0")
	)
	(segment
		(start 168.931844 -152.907746)
		(end 168.931844 -153.560018)
		(width 0.13208)
		(layer "B.Cu")
		(net "NCSI_NIC2_TXD0")
	)
	(segment
		(start 166.055294 -151.9936)
		(end 168.017698 -151.9936)
		(width 0.13208)
		(layer "B.Cu")
		(net "NCSI_NIC2_TXD0")
	)
	(segment
		(start 427.604428 -81.749646)
		(end 427.614842 -81.76006)
		(width 0.13208)
		(layer "F.Cu")
		(net "HP_NIC7_PWRGD_R")
	)
	(segment
		(start 428.713646 -83.526376)
		(end 427.614842 -82.427572)
		(width 0.13208)
		(layer "F.Cu")
		(net "HP_NIC7_PWRGD_R")
	)
	(segment
		(start 426.357542 -81.749646)
		(end 427.604428 -81.749646)
		(width 0.13208)
		(layer "F.Cu")
		(net "HP_NIC7_PWRGD_R")
	)
	(segment
		(start 429.649636 -83.526376)
		(end 428.713646 -83.526376)
		(width 0.13208)
		(layer "F.Cu")
		(net "HP_NIC7_PWRGD_R")
	)
	(segment
		(start 427.614842 -82.427572)
		(end 427.614842 -81.76006)
		(width 0.13208)
		(layer "F.Cu")
		(net "HP_NIC7_PWRGD_R")
	)
	(via
		(at 427.614842 -82.427572)
		(size 0.508)
		(drill 0.254)
		(layers "F.Cu" "B.Cu")
		(net "HP_NIC7_PWRGD_R")
	)
	(segment
		(start 442.533278 -24.790146)
		(end 442.775086 -25.031954)
		(width 0.381)
		(layer "F.Cu")
		(net "P3V3_SSD15")
	)
	(segment
		(start 432.26863 -30.971236)
		(end 432.26863 -32.512762)
		(width 0.381)
		(layer "F.Cu")
		(net "P3V3_SSD15")
	)
	(segment
		(start 450.96938 -20.467574)
		(end 450.356478 -20.467574)
		(width 0.508)
		(layer "F.Cu")
		(net "P3V3_SSD15")
	)
	(segment
		(start 451.860412 -14.799818)
		(end 451.860412 -16.439388)
		(width 0.381)
		(layer "F.Cu")
		(net "P3V3_SSD15")
	)
	(segment
		(start 445.771524 -25.742392)
		(end 445.771524 -26.360882)
		(width 0.4572)
		(layer "F.Cu")
		(net "P3V3_SSD15")
	)
	(segment
		(start 434.478938 -59.978036)
		(end 434.478938 -60.633356)
		(width 0.381)
		(layer "F.Cu")
		(net "P3V3_SSD15")
	)
	(segment
		(start 431.994056 -32.787336)
		(end 431.994056 -34.248852)
		(width 0.381)
		(layer "F.Cu")
		(net "P3V3_SSD15")
	)
	(segment
		(start 451.924928 -14.735302)
		(end 451.860412 -14.799818)
		(width 0.381)
		(layer "F.Cu")
		(net "P3V3_SSD15")
	)
	(segment
		(start 448.18554 -27.492198)
		(end 448.053968 -27.492198)
		(width 0.381)
		(layer "F.Cu")
		(net "P3V3_SSD15")
	)
	(segment
		(start 432.26863 -32.512762)
		(end 431.994056 -32.787336)
		(width 0.381)
		(layer "F.Cu")
		(net "P3V3_SSD15")
	)
	(segment
		(start 441.564776 -24.790146)
		(end 442.533278 -24.790146)
		(width 0.381)
		(layer "F.Cu")
		(net "P3V3_SSD15")
	)
	(segment
		(start 448.053968 -27.492198)
		(end 447.533014 -26.971244)
		(width 0.381)
		(layer "F.Cu")
		(net "P3V3_SSD15")
	)
	(segment
		(start 419.146736 -37.47516)
		(end 418.441124 -37.47516)
		(width 0.4572)
		(layer "F.Cu")
		(net "P3V3_SSD15")
	)
	(segment
		(start 442.775086 -25.031954)
		(end 444.226442 -25.031954)
		(width 0.381)
		(layer "F.Cu")
		(net "P3V3_SSD15")
	)
	(segment
		(start 433.671726 -24.807418)
		(end 433.053236 -24.807418)
		(width 0.4572)
		(layer "F.Cu")
		(net "P3V3_SSD15")
	)
	(segment
		(start 431.694082 -30.396688)
		(end 432.26863 -30.971236)
		(width 0.381)
		(layer "F.Cu")
		(net "P3V3_SSD15")
	)
	(segment
		(start 450.356478 -17.419574)
		(end 450.966078 -17.419574)
		(width 0.508)
		(layer "F.Cu")
		(net "P3V3_SSD15")
	)
	(segment
		(start 451.924928 -14.100302)
		(end 451.924928 -14.735302)
		(width 0.381)
		(layer "F.Cu")
		(net "P3V3_SSD15")
	)
	(segment
		(start 444.226442 -25.031954)
		(end 444.869824 -25.031954)
		(width 0.4572)
		(layer "F.Cu")
		(net "P3V3_SSD15")
	)
	(via
		(at 434.576474 -51.320192)
		(size 0.508)
		(drill 0.254)
		(layers "F.Cu" "B.Cu")
		(net "P3V3_SSD15")
	)
	(via
		(at 432.793902 -49.574704)
		(size 0.508)
		(drill 0.254)
		(layers "F.Cu" "B.Cu")
		(net "P3V3_SSD15")
	)
	(via
		(at 451.924928 -14.100302)
		(size 0.508)
		(drill 0.254)
		(layers "F.Cu" "B.Cu")
		(net "P3V3_SSD15")
	)
	(via
		(at 433.899818 -52.528724)
		(size 0.508)
		(drill 0.254)
		(layers "F.Cu" "B.Cu")
		(net "P3V3_SSD15")
	)
	(via
		(at 433.814474 -51.243992)
		(size 0.508)
		(drill 0.254)
		(layers "F.Cu" "B.Cu")
		(net "P3V3_SSD15")
	)
	(via
		(at 430.610518 -29.614876)
		(size 0.508)
		(drill 0.254)
		(layers "F.Cu" "B.Cu")
		(net "P3V3_SSD15")
	)
	(via
		(at 450.966078 -17.419574)
		(size 0.508)
		(drill 0.254)
		(layers "F.Cu" "B.Cu")
		(net "P3V3_SSD15")
	)
	(via
		(at 447.533014 -26.971244)
		(size 0.508)
		(drill 0.254)
		(layers "F.Cu" "B.Cu")
		(net "P3V3_SSD15")
	)
	(via
		(at 430.610518 -30.376876)
		(size 0.508)
		(drill 0.254)
		(layers "F.Cu" "B.Cu")
		(net "P3V3_SSD15")
	)
	(via
		(at 434.478938 -60.633356)
		(size 0.508)
		(drill 0.254)
		(layers "F.Cu" "B.Cu")
		(net "P3V3_SSD15")
	)
	(via
		(at 434.698902 -49.574704)
		(size 0.508)
		(drill 0.254)
		(layers "F.Cu" "B.Cu")
		(net "P3V3_SSD15")
	)
	(via
		(at 433.814474 -50.608992)
		(size 0.508)
		(drill 0.254)
		(layers "F.Cu" "B.Cu")
		(net "P3V3_SSD15")
	)
	(via
		(at 433.264818 -52.528724)
		(size 0.508)
		(drill 0.254)
		(layers "F.Cu" "B.Cu")
		(net "P3V3_SSD15")
	)
	(via
		(at 445.771524 -26.360882)
		(size 0.508)
		(drill 0.254)
		(layers "F.Cu" "B.Cu")
		(net "P3V3_SSD15")
	)
	(via
		(at 432.793902 -50.478182)
		(size 0.6604)
		(drill 0.3302)
		(layers "F.Cu" "B.Cu")
		(net "P3V3_SSD15")
	)
	(via
		(at 432.814476 -53.469286)
		(size 0.508)
		(drill 0.254)
		(layers "F.Cu" "B.Cu")
		(net "P3V3_SSD15")
	)
	(via
		(at 434.063902 -49.574704)
		(size 0.508)
		(drill 0.254)
		(layers "F.Cu" "B.Cu")
		(net "P3V3_SSD15")
	)
	(via
		(at 444.869824 -25.031954)
		(size 0.508)
		(drill 0.254)
		(layers "F.Cu" "B.Cu")
		(net "P3V3_SSD15")
	)
	(via
		(at 433.449476 -53.469286)
		(size 0.508)
		(drill 0.254)
		(layers "F.Cu" "B.Cu")
		(net "P3V3_SSD15")
	)
	(via
		(at 434.576474 -50.608992)
		(size 0.508)
		(drill 0.254)
		(layers "F.Cu" "B.Cu")
		(net "P3V3_SSD15")
	)
	(via
		(at 418.441124 -37.47516)
		(size 0.508)
		(drill 0.254)
		(layers "F.Cu" "B.Cu")
		(net "P3V3_SSD15")
	)
	(via
		(at 433.428902 -49.574704)
		(size 0.508)
		(drill 0.254)
		(layers "F.Cu" "B.Cu")
		(net "P3V3_SSD15")
	)
	(via
		(at 450.96938 -20.467574)
		(size 0.508)
		(drill 0.254)
		(layers "F.Cu" "B.Cu")
		(net "P3V3_SSD15")
	)
	(via
		(at 433.053236 -24.807418)
		(size 0.508)
		(drill 0.254)
		(layers "F.Cu" "B.Cu")
		(net "P3V3_SSD15")
	)
	(segment
		(start 428.06366 -37.872924)
		(end 421.353996 -37.872924)
		(width 0.508)
		(layer "In9.Cu")
		(net "P3V3_SSD15")
	)
	(segment
		(start 421.353996 -37.872924)
		(end 420.904162 -38.322758)
		(width 0.508)
		(layer "In9.Cu")
		(net "P3V3_SSD15")
	)
	(segment
		(start 419.288722 -38.322758)
		(end 418.441124 -37.47516)
		(width 0.508)
		(layer "In9.Cu")
		(net "P3V3_SSD15")
	)
	(segment
		(start 420.904162 -38.322758)
		(end 419.288722 -38.322758)
		(width 0.508)
		(layer "In9.Cu")
		(net "P3V3_SSD15")
	)
	(segment
		(start 68.006722 -133.807962)
		(end 68.169536 -133.645148)
		(width 0.13462)
		(layer "F.Cu")
		(net "P5E_PEX0_STN0_RX_DN<6>")
	)
	(segment
		(start 67.05727 -133.513576)
		(end 67.05727 -133.51383)
		(width 0.13462)
		(layer "F.Cu")
		(net "P5E_PEX0_STN0_RX_DN<6>")
	)
	(segment
		(start 67.05727 -133.51383)
		(end 67.351402 -133.807962)
		(width 0.13462)
		(layer "F.Cu")
		(net "P5E_PEX0_STN0_RX_DN<6>")
	)
	(segment
		(start 67.351402 -133.807962)
		(end 68.006722 -133.807962)
		(width 0.13462)
		(layer "F.Cu")
		(net "P5E_PEX0_STN0_RX_DN<6>")
	)
	(segment
		(start 68.169536 -133.645148)
		(end 68.65747 -133.645148)
		(width 0.13462)
		(layer "F.Cu")
		(net "P5E_PEX0_STN0_RX_DN<6>")
	)
	(segment
		(start 76.73213 -138.902186)
		(end 76.31176 -138.402314)
		(width 0.1651)
		(layer "In5.Cu")
		(net "P5E_PEX0_STN0_RX_DN<6>")
	)
	(segment
		(start 76.8858 -139.7889)
		(end 76.73213 -138.902186)
		(width 0.1651)
		(layer "In5.Cu")
		(net "P5E_PEX0_STN0_RX_DN<6>")
	)
	(segment
		(start 67.746626 -133.804406)
		(end 67.3481 -133.804406)
		(width 0.1651)
		(layer "In5.Cu")
		(net "P5E_PEX0_STN0_RX_DN<6>")
	)
	(segment
		(start 67.3481 -133.804406)
		(end 67.05727 -133.513576)
		(width 0.1651)
		(layer "In5.Cu")
		(net "P5E_PEX0_STN0_RX_DN<6>")
	)
	(segment
		(start 85.499448 -281.22245)
		(end 85.745066 -280.642822)
		(width 0.1651)
		(layer "In5.Cu")
		(net "P5E_PEX0_STN0_RX_DN<6>")
	)
	(segment
		(start 85.00618 -281.817826)
		(end 85.499448 -281.22245)
		(width 0.1651)
		(layer "In5.Cu")
		(net "P5E_PEX0_STN0_RX_DN<6>")
	)
	(segment
		(start 80.23733 -160.243774)
		(end 76.8858 -140.908278)
		(width 0.1651)
		(layer "In5.Cu")
		(net "P5E_PEX0_STN0_RX_DN<6>")
	)
	(segment
		(start 83.793584 -264.69721)
		(end 80.23733 -160.243774)
		(width 0.1651)
		(layer "In5.Cu")
		(net "P5E_PEX0_STN0_RX_DN<6>")
	)
	(segment
		(start 80.17002 -282.35275)
		(end 80.302608 -282.220162)
		(width 0.1143)
		(layer "In5.Cu")
		(net "P5E_PEX0_STN0_RX_DN<6>")
	)
	(segment
		(start 83.8962 -282.265882)
		(end 83.924648 -282.265882)
		(width 0.1143)
		(layer "In5.Cu")
		(net "P5E_PEX0_STN0_RX_DN<6>")
	)
	(segment
		(start 84.336128 -282.265882)
		(end 85.00618 -281.817826)
		(width 0.1651)
		(layer "In5.Cu")
		(net "P5E_PEX0_STN0_RX_DN<6>")
	)
	(segment
		(start 80.28432 -282.599892)
		(end 80.17002 -282.485592)
		(width 0.1143)
		(layer "In5.Cu")
		(net "P5E_PEX0_STN0_RX_DN<6>")
	)
	(segment
		(start 83.85048 -282.220162)
		(end 83.8962 -282.265882)
		(width 0.1143)
		(layer "In5.Cu")
		(net "P5E_PEX0_STN0_RX_DN<6>")
	)
	(segment
		(start 80.54975 -282.599892)
		(end 80.28432 -282.599892)
		(width 0.1143)
		(layer "In5.Cu")
		(net "P5E_PEX0_STN0_RX_DN<6>")
	)
	(segment
		(start 80.17002 -282.485592)
		(end 80.17002 -282.35275)
		(width 0.1143)
		(layer "In5.Cu")
		(net "P5E_PEX0_STN0_RX_DN<6>")
	)
	(segment
		(start 85.833204 -277.089108)
		(end 85.833204 -276.694646)
		(width 0.1651)
		(layer "In5.Cu")
		(net "P5E_PEX0_STN0_RX_DN<6>")
	)
	(segment
		(start 76.8858 -140.908278)
		(end 76.8858 -139.7889)
		(width 0.1651)
		(layer "In5.Cu")
		(net "P5E_PEX0_STN0_RX_DN<6>")
	)
	(segment
		(start 85.745066 -280.642822)
		(end 85.833204 -277.089108)
		(width 0.1651)
		(layer "In5.Cu")
		(net "P5E_PEX0_STN0_RX_DN<6>")
	)
	(segment
		(start 84.706714 -270.77416)
		(end 83.793584 -264.69721)
		(width 0.1651)
		(layer "In5.Cu")
		(net "P5E_PEX0_STN0_RX_DN<6>")
	)
	(segment
		(start 76.31176 -138.402314)
		(end 67.746626 -133.804406)
		(width 0.1651)
		(layer "In5.Cu")
		(net "P5E_PEX0_STN0_RX_DN<6>")
	)
	(segment
		(start 85.833204 -276.694646)
		(end 84.706714 -270.77416)
		(width 0.1651)
		(layer "In5.Cu")
		(net "P5E_PEX0_STN0_RX_DN<6>")
	)
	(segment
		(start 80.302608 -282.220162)
		(end 83.85048 -282.220162)
		(width 0.1143)
		(layer "In5.Cu")
		(net "P5E_PEX0_STN0_RX_DN<6>")
	)
	(segment
		(start 83.924648 -282.265882)
		(end 84.336128 -282.265882)
		(width 0.1651)
		(layer "In5.Cu")
		(net "P5E_PEX0_STN0_RX_DN<6>")
	)
	(segment
		(start 283.321506 -101.244908)
		(end 283.478478 -101.40188)
		(width 0.13462)
		(layer "F.Cu")
		(net "P5E_PEX2_STN1_RX_DP<17>")
	)
	(segment
		(start 284.15361 -101.40188)
		(end 284.442662 -101.112828)
		(width 0.13462)
		(layer "F.Cu")
		(net "P5E_PEX2_STN1_RX_DP<17>")
	)
	(segment
		(start 282.842462 -101.244908)
		(end 283.321506 -101.244908)
		(width 0.13462)
		(layer "F.Cu")
		(net "P5E_PEX2_STN1_RX_DP<17>")
	)
	(segment
		(start 283.478478 -101.40188)
		(end 284.15361 -101.40188)
		(width 0.13462)
		(layer "F.Cu")
		(net "P5E_PEX2_STN1_RX_DP<17>")
	)
	(segment
		(start 292.22954 -271.644872)
		(end 292.22954 -275.35505)
		(width 0.1143)
		(layer "In5.Cu")
		(net "P5E_PEX2_STN1_RX_DP<17>")
	)
	(segment
		(start 283.660088 -101.403658)
		(end 283.623004 -101.440742)
		(width 0.1651)
		(layer "In5.Cu")
		(net "P5E_PEX2_STN1_RX_DP<17>")
	)
	(segment
		(start 292.18382 -271.570704)
		(end 292.18382 -271.599152)
		(width 0.1143)
		(layer "In5.Cu")
		(net "P5E_PEX2_STN1_RX_DP<17>")
	)
	(segment
		(start 276.921976 -105.264204)
		(end 265.53414 -117.142768)
		(width 0.1651)
		(layer "In5.Cu")
		(net "P5E_PEX2_STN1_RX_DP<17>")
	)
	(segment
		(start 292.685216 -275.569934)
		(end 292.799516 -275.684234)
		(width 0.1143)
		(layer "In5.Cu")
		(net "P5E_PEX2_STN1_RX_DP<17>")
	)
	(segment
		(start 261.23519 -150.181056)
		(end 261.805166 -158.872936)
		(width 0.1651)
		(layer "In5.Cu")
		(net "P5E_PEX2_STN1_RX_DP<17>")
	)
	(segment
		(start 284.151832 -101.403658)
		(end 283.660088 -101.403658)
		(width 0.1651)
		(layer "In5.Cu")
		(net "P5E_PEX2_STN1_RX_DP<17>")
	)
	(segment
		(start 262.999982 -165.415214)
		(end 292.18382 -269.939516)
		(width 0.1651)
		(layer "In5.Cu")
		(net "P5E_PEX2_STN1_RX_DP<17>")
	)
	(segment
		(start 284.442662 -101.112828)
		(end 284.151832 -101.403658)
		(width 0.1651)
		(layer "In5.Cu")
		(net "P5E_PEX2_STN1_RX_DP<17>")
	)
	(segment
		(start 262.660892 -126.572518)
		(end 261.23519 -150.181056)
		(width 0.1651)
		(layer "In5.Cu")
		(net "P5E_PEX2_STN1_RX_DP<17>")
	)
	(segment
		(start 265.53414 -117.142768)
		(end 264.16381 -119.854218)
		(width 0.1651)
		(layer "In5.Cu")
		(net "P5E_PEX2_STN1_RX_DP<17>")
	)
	(segment
		(start 264.16381 -119.854218)
		(end 262.660892 -126.572518)
		(width 0.1651)
		(layer "In5.Cu")
		(net "P5E_PEX2_STN1_RX_DP<17>")
	)
	(segment
		(start 292.799516 -275.684234)
		(end 292.799516 -275.949664)
		(width 0.1143)
		(layer "In5.Cu")
		(net "P5E_PEX2_STN1_RX_DP<17>")
	)
	(segment
		(start 261.805166 -158.872936)
		(end 262.999982 -165.415214)
		(width 0.1651)
		(layer "In5.Cu")
		(net "P5E_PEX2_STN1_RX_DP<17>")
	)
	(segment
		(start 292.18382 -269.939516)
		(end 292.18382 -271.570704)
		(width 0.1651)
		(layer "In5.Cu")
		(net "P5E_PEX2_STN1_RX_DP<17>")
	)
	(segment
		(start 292.22954 -275.35505)
		(end 292.444424 -275.569934)
		(width 0.1143)
		(layer "In5.Cu")
		(net "P5E_PEX2_STN1_RX_DP<17>")
	)
	(segment
		(start 283.623004 -101.440742)
		(end 276.921976 -105.264204)
		(width 0.1651)
		(layer "In5.Cu")
		(net "P5E_PEX2_STN1_RX_DP<17>")
	)
	(segment
		(start 292.444424 -275.569934)
		(end 292.685216 -275.569934)
		(width 0.1143)
		(layer "In5.Cu")
		(net "P5E_PEX2_STN1_RX_DP<17>")
	)
	(segment
		(start 292.18382 -271.599152)
		(end 292.22954 -271.644872)
		(width 0.1143)
		(layer "In5.Cu")
		(net "P5E_PEX2_STN1_RX_DP<17>")
	)
	(segment
		(start 442.06541 -30.790134)
		(end 441.564776 -30.790134)
		(width 0.13462)
		(layer "F.Cu")
		(net "P5E_PEX3_STN2_TX_C_DP<33>")
	)
	(segment
		(start 446.467738 -30.94609)
		(end 446.148968 -30.62732)
		(width 0.13462)
		(layer "F.Cu")
		(net "P5E_PEX3_STN2_TX_C_DP<33>")
	)
	(segment
		(start 442.228224 -30.62732)
		(end 442.06541 -30.790134)
		(width 0.13462)
		(layer "F.Cu")
		(net "P5E_PEX3_STN2_TX_C_DP<33>")
	)
	(segment
		(start 446.148968 -30.62732)
		(end 442.228224 -30.62732)
		(width 0.13462)
		(layer "F.Cu")
		(net "P5E_PEX3_STN2_TX_C_DP<33>")
	)
	(segment
		(start 381.376682 -304.783998)
		(end 383.892552 -304.783998)
		(width 0.1651)
		(layer "In9.Cu")
		(net "P5E_PEX3_STN7_RX_DP<116>")
	)
	(segment
		(start 416.164522 -387.33476)
		(end 415.175446 -385.862322)
		(width 0.1651)
		(layer "In9.Cu")
		(net "P5E_PEX3_STN7_RX_DP<116>")
	)
	(segment
		(start 429.165004 -395.288262)
		(end 428.595028 -394.254482)
		(width 0.1651)
		(layer "In9.Cu")
		(net "P5E_PEX3_STN7_RX_DP<116>")
	)
	(segment
		(start 408.030172 -340.004146)
		(end 408.030172 -340.0044)
		(width 0.1651)
		(layer "In9.Cu")
		(net "P5E_PEX3_STN7_RX_DP<116>")
	)
	(segment
		(start 428.289974 -408.190192)
		(end 428.289974 -408.572208)
		(width 0.1651)
		(layer "In9.Cu")
		(net "P5E_PEX3_STN7_RX_DP<116>")
	)
	(segment
		(start 411.140402 -358.371648)
		(end 411.140402 -341.997792)
		(width 0.1651)
		(layer "In9.Cu")
		(net "P5E_PEX3_STN7_RX_DP<116>")
	)
	(segment
		(start 387.719316 -305.399948)
		(end 387.999986 -305.399948)
		(width 0.1143)
		(layer "In9.Cu")
		(net "P5E_PEX3_STN7_RX_DP<116>")
	)
	(segment
		(start 410.585412 -341.121746)
		(end 409.76423 -340.762844)
		(width 0.1651)
		(layer "In9.Cu")
		(net "P5E_PEX3_STN7_RX_DP<116>")
	)
	(segment
		(start 418.870892 -389.53948)
		(end 416.164522 -387.33476)
		(width 0.1651)
		(layer "In9.Cu")
		(net "P5E_PEX3_STN7_RX_DP<116>")
	)
	(segment
		(start 374.831356 -308.949344)
		(end 377.952 -305.8287)
		(width 0.1651)
		(layer "In9.Cu")
		(net "P5E_PEX3_STN7_RX_DP<116>")
	)
	(segment
		(start 370.874798 -316.352936)
		(end 374.831356 -308.949344)
		(width 0.1651)
		(layer "In9.Cu")
		(net "P5E_PEX3_STN7_RX_DP<116>")
	)
	(segment
		(start 387.380988 -304.829718)
		(end 387.624828 -305.073558)
		(width 0.1143)
		(layer "In9.Cu")
		(net "P5E_PEX3_STN7_RX_DP<116>")
	)
	(segment
		(start 428.595028 -394.254482)
		(end 427.992794 -393.87399)
		(width 0.1651)
		(layer "In9.Cu")
		(net "P5E_PEX3_STN7_RX_DP<116>")
	)
	(segment
		(start 428.289974 -408.572208)
		(end 428.416974 -408.699208)
		(width 0.1651)
		(layer "In9.Cu")
		(net "P5E_PEX3_STN7_RX_DP<116>")
	)
	(segment
		(start 409.12415 -340.482682)
		(end 408.670506 -340.284308)
		(width 0.1651)
		(layer "In9.Cu")
		(net "P5E_PEX3_STN7_RX_DP<116>")
	)
	(segment
		(start 383.96672 -304.829718)
		(end 387.380988 -304.829718)
		(width 0.1143)
		(layer "In9.Cu")
		(net "P5E_PEX3_STN7_RX_DP<116>")
	)
	(segment
		(start 428.63897 -408.699208)
		(end 429.165004 -408.173174)
		(width 0.1651)
		(layer "In9.Cu")
		(net "P5E_PEX3_STN7_RX_DP<116>")
	)
	(segment
		(start 370.790978 -325.62038)
		(end 369.652296 -322.871084)
		(width 0.1651)
		(layer "In9.Cu")
		(net "P5E_PEX3_STN7_RX_DP<116>")
	)
	(segment
		(start 379.433836 -305.533552)
		(end 381.376682 -304.783998)
		(width 0.1651)
		(layer "In9.Cu")
		(net "P5E_PEX3_STN7_RX_DP<116>")
	)
	(segment
		(start 377.952 -305.8287)
		(end 379.433836 -305.533552)
		(width 0.1651)
		(layer "In9.Cu")
		(net "P5E_PEX3_STN7_RX_DP<116>")
	)
	(segment
		(start 428.416974 -408.699208)
		(end 428.63897 -408.699208)
		(width 0.1651)
		(layer "In9.Cu")
		(net "P5E_PEX3_STN7_RX_DP<116>")
	)
	(segment
		(start 383.921 -304.783998)
		(end 383.96672 -304.829718)
		(width 0.1143)
		(layer "In9.Cu")
		(net "P5E_PEX3_STN7_RX_DP<116>")
	)
	(segment
		(start 409.630626 -340.815168)
		(end 409.176474 -340.616286)
		(width 0.1651)
		(layer "In9.Cu")
		(net "P5E_PEX3_STN7_RX_DP<116>")
	)
	(segment
		(start 387.624828 -305.30546)
		(end 387.719316 -305.399948)
		(width 0.1143)
		(layer "In9.Cu")
		(net "P5E_PEX3_STN7_RX_DP<116>")
	)
	(segment
		(start 408.536648 -340.336632)
		(end 408.082496 -340.138004)
		(width 0.1651)
		(layer "In9.Cu")
		(net "P5E_PEX3_STN7_RX_DP<116>")
	)
	(segment
		(start 424.050206 -391.382758)
		(end 418.870892 -389.53948)
		(width 0.1651)
		(layer "In9.Cu")
		(net "P5E_PEX3_STN7_RX_DP<116>")
	)
	(segment
		(start 408.670506 -340.284308)
		(end 408.536648 -340.336632)
		(width 0.1651)
		(layer "In9.Cu")
		(net "P5E_PEX3_STN7_RX_DP<116>")
	)
	(segment
		(start 409.176474 -340.616286)
		(end 409.12415 -340.482682)
		(width 0.1651)
		(layer "In9.Cu")
		(net "P5E_PEX3_STN7_RX_DP<116>")
	)
	(segment
		(start 409.76423 -340.762844)
		(end 409.630626 -340.815168)
		(width 0.1651)
		(layer "In9.Cu")
		(net "P5E_PEX3_STN7_RX_DP<116>")
	)
	(segment
		(start 427.40199 -393.50061)
		(end 426.983398 -393.236196)
		(width 0.1651)
		(layer "In9.Cu")
		(net "P5E_PEX3_STN7_RX_DP<116>")
	)
	(segment
		(start 411.140402 -341.997792)
		(end 410.585412 -341.121746)
		(width 0.1651)
		(layer "In9.Cu")
		(net "P5E_PEX3_STN7_RX_DP<116>")
	)
	(segment
		(start 415.175446 -385.862322)
		(end 414.67151 -384.534664)
		(width 0.1651)
		(layer "In9.Cu")
		(net "P5E_PEX3_STN7_RX_DP<116>")
	)
	(segment
		(start 377.176284 -330.81341)
		(end 375.435114 -330.264262)
		(width 0.1651)
		(layer "In9.Cu")
		(net "P5E_PEX3_STN7_RX_DP<116>")
	)
	(segment
		(start 387.624828 -305.073558)
		(end 387.624828 -305.30546)
		(width 0.1143)
		(layer "In9.Cu")
		(net "P5E_PEX3_STN7_RX_DP<116>")
	)
	(segment
		(start 375.435114 -330.264262)
		(end 370.790978 -325.62038)
		(width 0.1651)
		(layer "In9.Cu")
		(net "P5E_PEX3_STN7_RX_DP<116>")
	)
	(segment
		(start 426.983398 -393.236196)
		(end 426.84319 -393.267692)
		(width 0.1651)
		(layer "In9.Cu")
		(net "P5E_PEX3_STN7_RX_DP<116>")
	)
	(segment
		(start 426.424344 -393.003024)
		(end 426.392594 -392.862816)
		(width 0.1651)
		(layer "In9.Cu")
		(net "P5E_PEX3_STN7_RX_DP<116>")
	)
	(segment
		(start 369.652296 -319.305178)
		(end 370.874798 -316.352936)
		(width 0.1651)
		(layer "In9.Cu")
		(net "P5E_PEX3_STN7_RX_DP<116>")
	)
	(segment
		(start 426.392594 -392.862816)
		(end 424.050206 -391.382758)
		(width 0.1651)
		(layer "In9.Cu")
		(net "P5E_PEX3_STN7_RX_DP<116>")
	)
	(segment
		(start 408.030172 -340.0044)
		(end 397.869664 -335.560924)
		(width 0.1651)
		(layer "In9.Cu")
		(net "P5E_PEX3_STN7_RX_DP<116>")
	)
	(segment
		(start 369.652296 -322.871084)
		(end 369.652296 -319.305178)
		(width 0.1651)
		(layer "In9.Cu")
		(net "P5E_PEX3_STN7_RX_DP<116>")
	)
	(segment
		(start 383.892552 -304.783998)
		(end 383.921 -304.783998)
		(width 0.1143)
		(layer "In9.Cu")
		(net "P5E_PEX3_STN7_RX_DP<116>")
	)
	(segment
		(start 427.992794 -393.87399)
		(end 427.852586 -393.905486)
		(width 0.1651)
		(layer "In9.Cu")
		(net "P5E_PEX3_STN7_RX_DP<116>")
	)
	(segment
		(start 427.433486 -393.640818)
		(end 427.40199 -393.50061)
		(width 0.1651)
		(layer "In9.Cu")
		(net "P5E_PEX3_STN7_RX_DP<116>")
	)
	(segment
		(start 426.84319 -393.267692)
		(end 426.424344 -393.003024)
		(width 0.1651)
		(layer "In9.Cu")
		(net "P5E_PEX3_STN7_RX_DP<116>")
	)
	(segment
		(start 427.852586 -393.905486)
		(end 427.433486 -393.640818)
		(width 0.1651)
		(layer "In9.Cu")
		(net "P5E_PEX3_STN7_RX_DP<116>")
	)
	(segment
		(start 429.165004 -408.173174)
		(end 429.165004 -395.288262)
		(width 0.1651)
		(layer "In9.Cu")
		(net "P5E_PEX3_STN7_RX_DP<116>")
	)
	(segment
		(start 397.869664 -335.560924)
		(end 377.176284 -330.81341)
		(width 0.1651)
		(layer "In9.Cu")
		(net "P5E_PEX3_STN7_RX_DP<116>")
	)
	(segment
		(start 414.67151 -384.534664)
		(end 411.140402 -358.371648)
		(width 0.1651)
		(layer "In9.Cu")
		(net "P5E_PEX3_STN7_RX_DP<116>")
	)
	(segment
		(start 408.082496 -340.138004)
		(end 408.030172 -340.004146)
		(width 0.1651)
		(layer "In9.Cu")
		(net "P5E_PEX3_STN7_RX_DP<116>")
	)
	(segment
		(start 166.742364 -154.159966)
		(end 167.788844 -154.159966)
		(width 0.13208)
		(layer "F.Cu")
		(net "NCSI_NIC2_TXD1")
	)
	(via
		(at 167.788844 -154.159966)
		(size 0.508)
		(drill 0.254)
		(layers "F.Cu" "B.Cu")
		(net "NCSI_NIC2_TXD1")
	)
	(segment
		(start 166.638478 -153.0096)
		(end 167.788844 -154.159966)
		(width 0.13208)
		(layer "B.Cu")
		(net "NCSI_NIC2_TXD1")
	)
	(segment
		(start 166.055294 -153.0096)
		(end 166.638478 -153.0096)
		(width 0.13208)
		(layer "B.Cu")
		(net "NCSI_NIC2_TXD1")
	)
	(segment
		(start 422.185592 -27.492198)
		(end 422.05402 -27.492198)
		(width 0.381)
		(layer "F.Cu")
		(net "P3V3_SSD14")
	)
	(segment
		(start 416.53333 -24.790146)
		(end 416.775138 -25.031954)
		(width 0.381)
		(layer "F.Cu")
		(net "P3V3_SSD14")
	)
	(segment
		(start 406.268682 -32.512762)
		(end 406.268682 -30.971236)
		(width 0.381)
		(layer "F.Cu")
		(net "P3V3_SSD14")
	)
	(segment
		(start 393.146788 -37.47516)
		(end 392.441176 -37.47516)
		(width 0.4572)
		(layer "F.Cu")
		(net "P3V3_SSD14")
	)
	(segment
		(start 424.969432 -20.467574)
		(end 424.35653 -20.467574)
		(width 0.508)
		(layer "F.Cu")
		(net "P3V3_SSD14")
	)
	(segment
		(start 408.47899 -59.978036)
		(end 408.47899 -60.633356)
		(width 0.381)
		(layer "F.Cu")
		(net "P3V3_SSD14")
	)
	(segment
		(start 405.994108 -32.787336)
		(end 406.268682 -32.512762)
		(width 0.381)
		(layer "F.Cu")
		(net "P3V3_SSD14")
	)
	(segment
		(start 425.92498 -14.735302)
		(end 425.860464 -14.799818)
		(width 0.381)
		(layer "F.Cu")
		(net "P3V3_SSD14")
	)
	(segment
		(start 405.994108 -34.248852)
		(end 405.994108 -32.787336)
		(width 0.381)
		(layer "F.Cu")
		(net "P3V3_SSD14")
	)
	(segment
		(start 418.226494 -25.031954)
		(end 418.869876 -25.031954)
		(width 0.4572)
		(layer "F.Cu")
		(net "P3V3_SSD14")
	)
	(segment
		(start 422.05402 -27.492198)
		(end 421.533066 -26.971244)
		(width 0.381)
		(layer "F.Cu")
		(net "P3V3_SSD14")
	)
	(segment
		(start 419.771576 -25.742392)
		(end 419.771576 -26.360882)
		(width 0.4572)
		(layer "F.Cu")
		(net "P3V3_SSD14")
	)
	(segment
		(start 416.775138 -25.031954)
		(end 418.226494 -25.031954)
		(width 0.381)
		(layer "F.Cu")
		(net "P3V3_SSD14")
	)
	(segment
		(start 415.564828 -24.790146)
		(end 416.53333 -24.790146)
		(width 0.381)
		(layer "F.Cu")
		(net "P3V3_SSD14")
	)
	(segment
		(start 425.860464 -14.799818)
		(end 425.860464 -16.439388)
		(width 0.381)
		(layer "F.Cu")
		(net "P3V3_SSD14")
	)
	(segment
		(start 407.671778 -24.807418)
		(end 407.053288 -24.807418)
		(width 0.4572)
		(layer "F.Cu")
		(net "P3V3_SSD14")
	)
	(segment
		(start 425.92498 -14.100302)
		(end 425.92498 -14.735302)
		(width 0.381)
		(layer "F.Cu")
		(net "P3V3_SSD14")
	)
	(segment
		(start 406.268682 -30.971236)
		(end 405.694134 -30.396688)
		(width 0.381)
		(layer "F.Cu")
		(net "P3V3_SSD14")
	)
	(segment
		(start 424.35653 -17.419574)
		(end 424.96613 -17.419574)
		(width 0.508)
		(layer "F.Cu")
		(net "P3V3_SSD14")
	)
	(via
		(at 407.449528 -53.469286)
		(size 0.508)
		(drill 0.254)
		(layers "F.Cu" "B.Cu")
		(net "P3V3_SSD14")
	)
	(via
		(at 404.61057 -30.376876)
		(size 0.508)
		(drill 0.254)
		(layers "F.Cu" "B.Cu")
		(net "P3V3_SSD14")
	)
	(via
		(at 424.969432 -20.467574)
		(size 0.508)
		(drill 0.254)
		(layers "F.Cu" "B.Cu")
		(net "P3V3_SSD14")
	)
	(via
		(at 421.533066 -26.971244)
		(size 0.508)
		(drill 0.254)
		(layers "F.Cu" "B.Cu")
		(net "P3V3_SSD14")
	)
	(via
		(at 407.428954 -49.574704)
		(size 0.508)
		(drill 0.254)
		(layers "F.Cu" "B.Cu")
		(net "P3V3_SSD14")
	)
	(via
		(at 406.793954 -50.478182)
		(size 0.6604)
		(drill 0.3302)
		(layers "F.Cu" "B.Cu")
		(net "P3V3_SSD14")
	)
	(via
		(at 424.96613 -17.419574)
		(size 0.508)
		(drill 0.254)
		(layers "F.Cu" "B.Cu")
		(net "P3V3_SSD14")
	)
	(via
		(at 408.063954 -49.574704)
		(size 0.508)
		(drill 0.254)
		(layers "F.Cu" "B.Cu")
		(net "P3V3_SSD14")
	)
	(via
		(at 407.053288 -24.807418)
		(size 0.508)
		(drill 0.254)
		(layers "F.Cu" "B.Cu")
		(net "P3V3_SSD14")
	)
	(via
		(at 407.89987 -52.528724)
		(size 0.508)
		(drill 0.254)
		(layers "F.Cu" "B.Cu")
		(net "P3V3_SSD14")
	)
	(via
		(at 407.26487 -52.528724)
		(size 0.508)
		(drill 0.254)
		(layers "F.Cu" "B.Cu")
		(net "P3V3_SSD14")
	)
	(via
		(at 408.47899 -60.633356)
		(size 0.508)
		(drill 0.254)
		(layers "F.Cu" "B.Cu")
		(net "P3V3_SSD14")
	)
	(via
		(at 407.814526 -51.243992)
		(size 0.508)
		(drill 0.254)
		(layers "F.Cu" "B.Cu")
		(net "P3V3_SSD14")
	)
	(via
		(at 407.814526 -50.608992)
		(size 0.508)
		(drill 0.254)
		(layers "F.Cu" "B.Cu")
		(net "P3V3_SSD14")
	)
	(via
		(at 404.61057 -29.614876)
		(size 0.508)
		(drill 0.254)
		(layers "F.Cu" "B.Cu")
		(net "P3V3_SSD14")
	)
	(via
		(at 408.576526 -50.608992)
		(size 0.508)
		(drill 0.254)
		(layers "F.Cu" "B.Cu")
		(net "P3V3_SSD14")
	)
	(via
		(at 392.441176 -37.47516)
		(size 0.508)
		(drill 0.254)
		(layers "F.Cu" "B.Cu")
		(net "P3V3_SSD14")
	)
	(via
		(at 408.698954 -49.574704)
		(size 0.508)
		(drill 0.254)
		(layers "F.Cu" "B.Cu")
		(net "P3V3_SSD14")
	)
	(via
		(at 408.576526 -51.320192)
		(size 0.508)
		(drill 0.254)
		(layers "F.Cu" "B.Cu")
		(net "P3V3_SSD14")
	)
	(via
		(at 419.771576 -26.360882)
		(size 0.508)
		(drill 0.254)
		(layers "F.Cu" "B.Cu")
		(net "P3V3_SSD14")
	)
	(via
		(at 425.92498 -14.100302)
		(size 0.508)
		(drill 0.254)
		(layers "F.Cu" "B.Cu")
		(net "P3V3_SSD14")
	)
	(via
		(at 406.814528 -53.469286)
		(size 0.508)
		(drill 0.254)
		(layers "F.Cu" "B.Cu")
		(net "P3V3_SSD14")
	)
	(via
		(at 406.793954 -49.574704)
		(size 0.508)
		(drill 0.254)
		(layers "F.Cu" "B.Cu")
		(net "P3V3_SSD14")
	)
	(via
		(at 418.869876 -25.031954)
		(size 0.508)
		(drill 0.254)
		(layers "F.Cu" "B.Cu")
		(net "P3V3_SSD14")
	)
	(segment
		(start 395.354048 -37.872924)
		(end 394.904214 -38.322758)
		(width 0.508)
		(layer "In9.Cu")
		(net "P3V3_SSD14")
	)
	(segment
		(start 393.288774 -38.322758)
		(end 392.441176 -37.47516)
		(width 0.508)
		(layer "In9.Cu")
		(net "P3V3_SSD14")
	)
	(segment
		(start 402.063712 -37.872924)
		(end 395.354048 -37.872924)
		(width 0.508)
		(layer "In9.Cu")
		(net "P3V3_SSD14")
	)
	(segment
		(start 394.904214 -38.322758)
		(end 393.288774 -38.322758)
		(width 0.508)
		(layer "In9.Cu")
		(net "P3V3_SSD14")
	)
	(segment
		(start 68.006722 -135.882126)
		(end 65.498218 -135.882126)
		(width 0.13462)
		(layer "F.Cu")
		(net "P5E_PEX0_STN0_RX_DP<7>")
	)
	(segment
		(start 65.498218 -135.882126)
		(end 65.20307 -136.177274)
		(width 0.13462)
		(layer "F.Cu")
		(net "P5E_PEX0_STN0_RX_DP<7>")
	)
	(segment
		(start 68.169536 -136.04494)
		(end 68.006722 -135.882126)
		(width 0.13462)
		(layer "F.Cu")
		(net "P5E_PEX0_STN0_RX_DP<7>")
	)
	(segment
		(start 68.65747 -136.04494)
		(end 68.169536 -136.04494)
		(width 0.13462)
		(layer "F.Cu")
		(net "P5E_PEX0_STN0_RX_DP<7>")
	)
	(segment
		(start 74.596244 -141.568678)
		(end 74.740262 -141.814042)
		(width 0.1651)
		(layer "In5.Cu")
		(net "P5E_PEX0_STN0_RX_DP<7>")
	)
	(segment
		(start 70.467982 -137.250424)
		(end 70.927214 -137.437114)
		(width 0.1651)
		(layer "In5.Cu")
		(net "P5E_PEX0_STN0_RX_DP<7>")
	)
	(segment
		(start 81.879694 -281.29484)
		(end 81.879694 -281.535632)
		(width 0.1143)
		(layer "In5.Cu")
		(net "P5E_PEX0_STN0_RX_DP<7>")
	)
	(segment
		(start 65.20307 -136.177274)
		(end 65.4939 -135.886444)
		(width 0.1651)
		(layer "In5.Cu")
		(net "P5E_PEX0_STN0_RX_DP<7>")
	)
	(segment
		(start 75.6793 -146.451574)
		(end 75.816206 -146.53768)
		(width 0.1651)
		(layer "In5.Cu")
		(net "P5E_PEX0_STN0_RX_DP<7>")
	)
	(segment
		(start 75.816206 -146.53768)
		(end 78.998572 -160.511744)
		(width 0.1651)
		(layer "In5.Cu")
		(net "P5E_PEX0_STN0_RX_DP<7>")
	)
	(segment
		(start 71.806562 -137.671302)
		(end 73.04405 -138.926062)
		(width 0.1651)
		(layer "In5.Cu")
		(net "P5E_PEX0_STN0_RX_DP<7>")
	)
	(segment
		(start 73.04405 -138.926062)
		(end 73.405492 -139.540996)
		(width 0.1651)
		(layer "In5.Cu")
		(net "P5E_PEX0_STN0_RX_DP<7>")
	)
	(segment
		(start 83.950048 -281.033982)
		(end 83.9216 -281.033982)
		(width 0.1143)
		(layer "In5.Cu")
		(net "P5E_PEX0_STN0_RX_DP<7>")
	)
	(segment
		(start 82.552794 -264.857484)
		(end 83.206336 -269.468854)
		(width 0.1651)
		(layer "In5.Cu")
		(net "P5E_PEX0_STN0_RX_DP<7>")
	)
	(segment
		(start 69.797422 -136.977628)
		(end 69.94652 -136.91489)
		(width 0.1651)
		(layer "In5.Cu")
		(net "P5E_PEX0_STN0_RX_DP<7>")
	)
	(segment
		(start 73.405492 -139.926568)
		(end 73.72477 -140.697204)
		(width 0.1651)
		(layer "In5.Cu")
		(net "P5E_PEX0_STN0_RX_DP<7>")
	)
	(segment
		(start 73.72477 -140.697204)
		(end 74.596244 -141.568678)
		(width 0.1651)
		(layer "In5.Cu")
		(net "P5E_PEX0_STN0_RX_DP<7>")
	)
	(segment
		(start 75.545442 -145.348706)
		(end 75.65517 -145.83156)
		(width 0.1651)
		(layer "In5.Cu")
		(net "P5E_PEX0_STN0_RX_DP<7>")
	)
	(segment
		(start 75.027536 -143.590518)
		(end 75.137518 -144.073626)
		(width 0.1651)
		(layer "In5.Cu")
		(net "P5E_PEX0_STN0_RX_DP<7>")
	)
	(segment
		(start 82.094832 -281.079702)
		(end 81.879694 -281.29484)
		(width 0.1143)
		(layer "In5.Cu")
		(net "P5E_PEX0_STN0_RX_DP<7>")
	)
	(segment
		(start 83.87588 -281.079702)
		(end 82.094832 -281.079702)
		(width 0.1143)
		(layer "In5.Cu")
		(net "P5E_PEX0_STN0_RX_DP<7>")
	)
	(segment
		(start 75.384406 -144.642586)
		(end 75.298554 -144.779492)
		(width 0.1651)
		(layer "In5.Cu")
		(net "P5E_PEX0_STN0_RX_DP<7>")
	)
	(segment
		(start 81.765394 -281.649932)
		(end 81.499964 -281.649932)
		(width 0.1143)
		(layer "In5.Cu")
		(net "P5E_PEX0_STN0_RX_DP<7>")
	)
	(segment
		(start 69.94652 -136.91489)
		(end 70.405244 -137.101326)
		(width 0.1651)
		(layer "In5.Cu")
		(net "P5E_PEX0_STN0_RX_DP<7>")
	)
	(segment
		(start 67.418204 -135.886444)
		(end 68.146168 -136.182608)
		(width 0.1651)
		(layer "In5.Cu")
		(net "P5E_PEX0_STN0_RX_DP<7>")
	)
	(segment
		(start 69.338444 -136.791192)
		(end 69.797422 -136.977628)
		(width 0.1651)
		(layer "In5.Cu")
		(net "P5E_PEX0_STN0_RX_DP<7>")
	)
	(segment
		(start 68.20916 -136.331706)
		(end 68.668138 -136.518396)
		(width 0.1651)
		(layer "In5.Cu")
		(net "P5E_PEX0_STN0_RX_DP<7>")
	)
	(segment
		(start 75.113642 -143.453612)
		(end 75.027536 -143.590518)
		(width 0.1651)
		(layer "In5.Cu")
		(net "P5E_PEX0_STN0_RX_DP<7>")
	)
	(segment
		(start 68.816982 -136.455404)
		(end 69.275706 -136.64184)
		(width 0.1651)
		(layer "In5.Cu")
		(net "P5E_PEX0_STN0_RX_DP<7>")
	)
	(segment
		(start 68.668138 -136.518396)
		(end 68.816982 -136.455404)
		(width 0.1651)
		(layer "In5.Cu")
		(net "P5E_PEX0_STN0_RX_DP<7>")
	)
	(segment
		(start 84.47786 -276.331172)
		(end 84.391246 -280.407364)
		(width 0.1651)
		(layer "In5.Cu")
		(net "P5E_PEX0_STN0_RX_DP<7>")
	)
	(segment
		(start 70.405244 -137.101326)
		(end 70.467982 -137.250424)
		(width 0.1651)
		(layer "In5.Cu")
		(net "P5E_PEX0_STN0_RX_DP<7>")
	)
	(segment
		(start 78.998826 -160.51276)
		(end 82.552794 -264.857484)
		(width 0.1651)
		(layer "In5.Cu")
		(net "P5E_PEX0_STN0_RX_DP<7>")
	)
	(segment
		(start 70.927214 -137.437114)
		(end 71.076058 -137.374376)
		(width 0.1651)
		(layer "In5.Cu")
		(net "P5E_PEX0_STN0_RX_DP<7>")
	)
	(segment
		(start 78.998572 -160.511744)
		(end 78.998826 -160.51276)
		(width 0.1651)
		(layer "In5.Cu")
		(net "P5E_PEX0_STN0_RX_DP<7>")
	)
	(segment
		(start 69.275706 -136.64184)
		(end 69.338444 -136.791192)
		(width 0.1651)
		(layer "In5.Cu")
		(net "P5E_PEX0_STN0_RX_DP<7>")
	)
	(segment
		(start 73.405492 -139.540996)
		(end 73.405492 -139.926568)
		(width 0.1651)
		(layer "In5.Cu")
		(net "P5E_PEX0_STN0_RX_DP<7>")
	)
	(segment
		(start 75.274678 -144.159732)
		(end 75.384406 -144.642586)
		(width 0.1651)
		(layer "In5.Cu")
		(net "P5E_PEX0_STN0_RX_DP<7>")
	)
	(segment
		(start 75.408536 -145.2626)
		(end 75.545442 -145.348706)
		(width 0.1651)
		(layer "In5.Cu")
		(net "P5E_PEX0_STN0_RX_DP<7>")
	)
	(segment
		(start 83.9216 -281.033982)
		(end 83.87588 -281.079702)
		(width 0.1143)
		(layer "In5.Cu")
		(net "P5E_PEX0_STN0_RX_DP<7>")
	)
	(segment
		(start 75.137518 -144.073626)
		(end 75.274678 -144.159732)
		(width 0.1651)
		(layer "In5.Cu")
		(net "P5E_PEX0_STN0_RX_DP<7>")
	)
	(segment
		(start 71.076058 -137.374376)
		(end 71.806562 -137.671302)
		(width 0.1651)
		(layer "In5.Cu")
		(net "P5E_PEX0_STN0_RX_DP<7>")
	)
	(segment
		(start 75.298554 -144.779492)
		(end 75.408536 -145.2626)
		(width 0.1651)
		(layer "In5.Cu")
		(net "P5E_PEX0_STN0_RX_DP<7>")
	)
	(segment
		(start 84.071968 -281.033982)
		(end 83.950048 -281.033982)
		(width 0.1651)
		(layer "In5.Cu")
		(net "P5E_PEX0_STN0_RX_DP<7>")
	)
	(segment
		(start 83.206336 -269.468854)
		(end 84.47786 -276.331172)
		(width 0.1651)
		(layer "In5.Cu")
		(net "P5E_PEX0_STN0_RX_DP<7>")
	)
	(segment
		(start 65.4939 -135.886444)
		(end 67.418204 -135.886444)
		(width 0.1651)
		(layer "In5.Cu")
		(net "P5E_PEX0_STN0_RX_DP<7>")
	)
	(segment
		(start 81.879694 -281.535632)
		(end 81.765394 -281.649932)
		(width 0.1143)
		(layer "In5.Cu")
		(net "P5E_PEX0_STN0_RX_DP<7>")
	)
	(segment
		(start 84.391246 -280.407364)
		(end 84.160614 -280.94559)
		(width 0.1651)
		(layer "In5.Cu")
		(net "P5E_PEX0_STN0_RX_DP<7>")
	)
	(segment
		(start 75.65517 -145.83156)
		(end 75.569318 -145.968466)
		(width 0.1651)
		(layer "In5.Cu")
		(net "P5E_PEX0_STN0_RX_DP<7>")
	)
	(segment
		(start 75.569318 -145.968466)
		(end 75.6793 -146.451574)
		(width 0.1651)
		(layer "In5.Cu")
		(net "P5E_PEX0_STN0_RX_DP<7>")
	)
	(segment
		(start 74.740262 -141.814042)
		(end 75.113642 -143.453612)
		(width 0.1651)
		(layer "In5.Cu")
		(net "P5E_PEX0_STN0_RX_DP<7>")
	)
	(segment
		(start 84.160614 -280.94559)
		(end 84.071968 -281.033982)
		(width 0.1651)
		(layer "In5.Cu")
		(net "P5E_PEX0_STN0_RX_DP<7>")
	)
	(segment
		(start 68.146168 -136.182608)
		(end 68.20916 -136.331706)
		(width 0.1651)
		(layer "In5.Cu")
		(net "P5E_PEX0_STN0_RX_DP<7>")
	)
	(segment
		(start 283.475176 -136.1186)
		(end 283.321506 -135.96493)
		(width 0.13462)
		(layer "F.Cu")
		(net "P5E_PEX2_STN1_RX_DP<31>")
	)
	(segment
		(start 283.321506 -135.96493)
		(end 282.842462 -135.96493)
		(width 0.13462)
		(layer "F.Cu")
		(net "P5E_PEX2_STN1_RX_DP<31>")
	)
	(segment
		(start 284.156912 -136.1186)
		(end 283.475176 -136.1186)
		(width 0.13462)
		(layer "F.Cu")
		(net "P5E_PEX2_STN1_RX_DP<31>")
	)
	(segment
		(start 284.442662 -135.83285)
		(end 284.156912 -136.1186)
		(width 0.13462)
		(layer "F.Cu")
		(net "P5E_PEX2_STN1_RX_DP<31>")
	)
	(segment
		(start 284.151832 -136.12368)
		(end 283.774896 -136.12368)
		(width 0.1651)
		(layer "In5.Cu")
		(net "P5E_PEX2_STN1_RX_DP<31>")
	)
	(segment
		(start 306.099464 -275.684488)
		(end 306.099464 -275.949918)
		(width 0.1143)
		(layer "In5.Cu")
		(net "P5E_PEX2_STN1_RX_DP<31>")
	)
	(segment
		(start 305.483768 -271.599406)
		(end 305.529488 -271.645126)
		(width 0.1143)
		(layer "In5.Cu")
		(net "P5E_PEX2_STN1_RX_DP<31>")
	)
	(segment
		(start 305.483768 -271.570958)
		(end 305.483768 -271.599406)
		(width 0.1143)
		(layer "In5.Cu")
		(net "P5E_PEX2_STN1_RX_DP<31>")
	)
	(segment
		(start 305.483768 -267.07973)
		(end 305.483768 -271.570958)
		(width 0.1651)
		(layer "In5.Cu")
		(net "P5E_PEX2_STN1_RX_DP<31>")
	)
	(segment
		(start 283.087572 -141.23035)
		(end 281.865832 -144.215612)
		(width 0.1651)
		(layer "In5.Cu")
		(net "P5E_PEX2_STN1_RX_DP<31>")
	)
	(segment
		(start 305.985164 -275.570188)
		(end 306.099464 -275.684488)
		(width 0.1143)
		(layer "In5.Cu")
		(net "P5E_PEX2_STN1_RX_DP<31>")
	)
	(segment
		(start 284.442662 -135.83285)
		(end 284.151832 -136.12368)
		(width 0.1651)
		(layer "In5.Cu")
		(net "P5E_PEX2_STN1_RX_DP<31>")
	)
	(segment
		(start 305.744372 -275.570188)
		(end 305.985164 -275.570188)
		(width 0.1143)
		(layer "In5.Cu")
		(net "P5E_PEX2_STN1_RX_DP<31>")
	)
	(segment
		(start 277.111714 -159.491172)
		(end 277.1521 -160.413446)
		(width 0.1651)
		(layer "In5.Cu")
		(net "P5E_PEX2_STN1_RX_DP<31>")
	)
	(segment
		(start 277.638002 -153.01214)
		(end 277.637494 -153.01214)
		(width 0.1651)
		(layer "In5.Cu")
		(net "P5E_PEX2_STN1_RX_DP<31>")
	)
	(segment
		(start 283.212286 -136.68629)
		(end 283.087572 -136.987534)
		(width 0.1651)
		(layer "In5.Cu")
		(net "P5E_PEX2_STN1_RX_DP<31>")
	)
	(segment
		(start 278.494744 -147.156424)
		(end 278.030686 -148.199094)
		(width 0.1651)
		(layer "In5.Cu")
		(net "P5E_PEX2_STN1_RX_DP<31>")
	)
	(segment
		(start 281.865832 -144.215612)
		(end 279.463754 -146.579844)
		(width 0.1651)
		(layer "In5.Cu")
		(net "P5E_PEX2_STN1_RX_DP<31>")
	)
	(segment
		(start 305.529488 -271.645126)
		(end 305.529488 -275.355304)
		(width 0.1143)
		(layer "In5.Cu")
		(net "P5E_PEX2_STN1_RX_DP<31>")
	)
	(segment
		(start 283.774896 -136.12368)
		(end 283.212286 -136.68629)
		(width 0.1651)
		(layer "In5.Cu")
		(net "P5E_PEX2_STN1_RX_DP<31>")
	)
	(segment
		(start 279.463754 -146.579844)
		(end 278.807418 -146.848576)
		(width 0.1651)
		(layer "In5.Cu")
		(net "P5E_PEX2_STN1_RX_DP<31>")
	)
	(segment
		(start 278.030432 -148.200872)
		(end 277.638002 -153.01214)
		(width 0.1651)
		(layer "In5.Cu")
		(net "P5E_PEX2_STN1_RX_DP<31>")
	)
	(segment
		(start 283.087572 -136.987534)
		(end 283.087572 -141.23035)
		(width 0.1651)
		(layer "In5.Cu")
		(net "P5E_PEX2_STN1_RX_DP<31>")
	)
	(segment
		(start 278.030686 -148.199094)
		(end 278.030432 -148.200872)
		(width 0.1651)
		(layer "In5.Cu")
		(net "P5E_PEX2_STN1_RX_DP<31>")
	)
	(segment
		(start 278.807418 -146.848576)
		(end 278.494744 -147.156424)
		(width 0.1651)
		(layer "In5.Cu")
		(net "P5E_PEX2_STN1_RX_DP<31>")
	)
	(segment
		(start 305.529488 -275.355304)
		(end 305.744372 -275.570188)
		(width 0.1143)
		(layer "In5.Cu")
		(net "P5E_PEX2_STN1_RX_DP<31>")
	)
	(segment
		(start 277.110952 -159.473646)
		(end 277.11146 -159.491172)
		(width 0.1651)
		(layer "In5.Cu")
		(net "P5E_PEX2_STN1_RX_DP<31>")
	)
	(segment
		(start 305.420522 -266.597638)
		(end 305.483768 -267.07973)
		(width 0.1651)
		(layer "In5.Cu")
		(net "P5E_PEX2_STN1_RX_DP<31>")
	)
	(segment
		(start 277.1521 -160.413446)
		(end 305.420522 -266.597638)
		(width 0.1651)
		(layer "In5.Cu")
		(net "P5E_PEX2_STN1_RX_DP<31>")
	)
	(segment
		(start 277.637494 -153.01214)
		(end 277.110952 -159.473646)
		(width 0.1651)
		(layer "In5.Cu")
		(net "P5E_PEX2_STN1_RX_DP<31>")
	)
	(segment
		(start 277.11146 -159.491172)
		(end 277.111714 -159.491172)
		(width 0.1651)
		(layer "In5.Cu")
		(net "P5E_PEX2_STN1_RX_DP<31>")
	)
	(segment
		(start 436.964836 -31.99003)
		(end 436.484014 -31.99003)
		(width 0.13462)
		(layer "F.Cu")
		(net "P5E_PEX3_STN2_RX_DN<34>")
	)
	(segment
		(start 436.317644 -32.1564)
		(end 435.662324 -32.1564)
		(width 0.13462)
		(layer "F.Cu")
		(net "P5E_PEX3_STN2_RX_DN<34>")
	)
	(segment
		(start 436.484014 -31.99003)
		(end 436.317644 -32.1564)
		(width 0.13462)
		(layer "F.Cu")
		(net "P5E_PEX3_STN2_RX_DN<34>")
	)
	(segment
		(start 435.662324 -32.1564)
		(end 435.364636 -31.858712)
		(width 0.13462)
		(layer "F.Cu")
		(net "P5E_PEX3_STN2_RX_DN<34>")
	)
	(segment
		(start 405.100028 -275.265388)
		(end 404.985728 -275.379688)
		(width 0.1143)
		(layer "In7.Cu")
		(net "P5E_PEX3_STN2_RX_DN<34>")
	)
	(segment
		(start 404.765764 -271.421352)
		(end 404.765764 -271.392904)
		(width 0.1143)
		(layer "In7.Cu")
		(net "P5E_PEX3_STN2_RX_DN<34>")
	)
	(segment
		(start 436.742332 -32.790892)
		(end 436.100982 -32.149542)
		(width 0.1651)
		(layer "In7.Cu")
		(net "P5E_PEX3_STN2_RX_DN<34>")
	)
	(segment
		(start 405.092662 -266.859512)
		(end 424.651678 -154.552142)
		(width 0.1651)
		(layer "In7.Cu")
		(net "P5E_PEX3_STN2_RX_DN<34>")
	)
	(segment
		(start 436.212996 -39.71036)
		(end 436.183024 -37.803074)
		(width 0.1651)
		(layer "In7.Cu")
		(net "P5E_PEX3_STN2_RX_DN<34>")
	)
	(segment
		(start 424.651678 -154.552142)
		(end 426.042074 -143.750284)
		(width 0.1651)
		(layer "In7.Cu")
		(net "P5E_PEX3_STN2_RX_DN<34>")
	)
	(segment
		(start 436.708296 -34.984944)
		(end 436.742332 -32.790892)
		(width 0.1651)
		(layer "In7.Cu")
		(net "P5E_PEX3_STN2_RX_DN<34>")
	)
	(segment
		(start 404.82393 -275.379688)
		(end 404.720044 -275.275802)
		(width 0.1143)
		(layer "In7.Cu")
		(net "P5E_PEX3_STN2_RX_DN<34>")
	)
	(segment
		(start 435.655466 -32.149542)
		(end 435.364636 -31.858712)
		(width 0.1651)
		(layer "In7.Cu")
		(net "P5E_PEX3_STN2_RX_DN<34>")
	)
	(segment
		(start 437.343042 -61.227716)
		(end 437.527192 -49.435766)
		(width 0.1651)
		(layer "In7.Cu")
		(net "P5E_PEX3_STN2_RX_DN<34>")
	)
	(segment
		(start 426.35678 -116.602764)
		(end 437.343042 -61.227716)
		(width 0.1651)
		(layer "In7.Cu")
		(net "P5E_PEX3_STN2_RX_DN<34>")
	)
	(segment
		(start 404.985728 -275.379688)
		(end 404.82393 -275.379688)
		(width 0.1143)
		(layer "In7.Cu")
		(net "P5E_PEX3_STN2_RX_DN<34>")
	)
	(segment
		(start 404.720044 -271.467072)
		(end 404.765764 -271.421352)
		(width 0.1143)
		(layer "In7.Cu")
		(net "P5E_PEX3_STN2_RX_DN<34>")
	)
	(segment
		(start 426.042074 -143.750284)
		(end 426.35678 -116.602764)
		(width 0.1651)
		(layer "In7.Cu")
		(net "P5E_PEX3_STN2_RX_DN<34>")
	)
	(segment
		(start 404.765764 -271.392904)
		(end 404.765764 -270.653256)
		(width 0.1651)
		(layer "In7.Cu")
		(net "P5E_PEX3_STN2_RX_DN<34>")
	)
	(segment
		(start 436.183024 -37.803074)
		(end 436.708296 -34.984944)
		(width 0.1651)
		(layer "In7.Cu")
		(net "P5E_PEX3_STN2_RX_DN<34>")
	)
	(segment
		(start 436.100982 -32.149542)
		(end 435.655466 -32.149542)
		(width 0.1651)
		(layer "In7.Cu")
		(net "P5E_PEX3_STN2_RX_DN<34>")
	)
	(segment
		(start 405.100028 -274.999958)
		(end 405.100028 -275.265388)
		(width 0.1143)
		(layer "In7.Cu")
		(net "P5E_PEX3_STN2_RX_DN<34>")
	)
	(segment
		(start 404.765764 -270.653256)
		(end 405.092662 -266.859512)
		(width 0.1651)
		(layer "In7.Cu")
		(net "P5E_PEX3_STN2_RX_DN<34>")
	)
	(segment
		(start 437.527192 -49.435766)
		(end 436.212996 -39.71036)
		(width 0.1651)
		(layer "In7.Cu")
		(net "P5E_PEX3_STN2_RX_DN<34>")
	)
	(segment
		(start 404.720044 -275.275802)
		(end 404.720044 -271.467072)
		(width 0.1143)
		(layer "In7.Cu")
		(net "P5E_PEX3_STN2_RX_DN<34>")
	)
	(segment
		(start 415.487612 -344.219022)
		(end 415.80816 -344.53957)
		(width 0.13462)
		(layer "F.Cu")
		(net "P5E_PEX3_STN7_TX_C_DP<114>")
	)
	(segment
		(start 415.80816 -345.169998)
		(end 415.513012 -345.465146)
		(width 0.13462)
		(layer "F.Cu")
		(net "P5E_PEX3_STN7_TX_C_DP<114>")
	)
	(segment
		(start 415.80816 -344.53957)
		(end 415.80816 -345.169998)
		(width 0.13462)
		(layer "F.Cu")
		(net "P5E_PEX3_STN7_TX_C_DP<114>")
	)
	(segment
		(start 414.249362 -347.764354)
		(end 415.803842 -346.209874)
		(width 0.1651)
		(layer "In11.Cu")
		(net "P5E_PEX3_STN7_TX_C_DP<114>")
	)
	(segment
		(start 413.312356 -366.57026)
		(end 413.371792 -366.07877)
		(width 0.1651)
		(layer "In11.Cu")
		(net "P5E_PEX3_STN7_TX_C_DP<114>")
	)
	(segment
		(start 413.371792 -366.07877)
		(end 413.27197 -365.951516)
		(width 0.1651)
		(layer "In11.Cu")
		(net "P5E_PEX3_STN7_TX_C_DP<114>")
	)
	(segment
		(start 422.836594 -393.68476)
		(end 422.71823 -393.727178)
		(width 0.1651)
		(layer "In11.Cu")
		(net "P5E_PEX3_STN7_TX_C_DP<114>")
	)
	(segment
		(start 413.225234 -367.28908)
		(end 413.125412 -367.16208)
		(width 0.1651)
		(layer "In11.Cu")
		(net "P5E_PEX3_STN7_TX_C_DP<114>")
	)
	(segment
		(start 412.62427 -383.585466)
		(end 413.042354 -368.801904)
		(width 0.1651)
		(layer "In11.Cu")
		(net "P5E_PEX3_STN7_TX_C_DP<114>")
	)
	(segment
		(start 414.249362 -358.8258)
		(end 414.249362 -347.764354)
		(width 0.1651)
		(layer "In11.Cu")
		(net "P5E_PEX3_STN7_TX_C_DP<114>")
	)
	(segment
		(start 421.213026 -393.017502)
		(end 421.170608 -392.899138)
		(width 0.1651)
		(layer "In11.Cu")
		(net "P5E_PEX3_STN7_TX_C_DP<114>")
	)
	(segment
		(start 423.889932 -400.772122)
		(end 424.016932 -400.899122)
		(width 0.1651)
		(layer "In11.Cu")
		(net "P5E_PEX3_STN7_TX_C_DP<114>")
	)
	(segment
		(start 424.447208 -400.899122)
		(end 424.733974 -400.612356)
		(width 0.1651)
		(layer "In11.Cu")
		(net "P5E_PEX3_STN7_TX_C_DP<114>")
	)
	(segment
		(start 424.016932 -400.899122)
		(end 424.447208 -400.899122)
		(width 0.1651)
		(layer "In11.Cu")
		(net "P5E_PEX3_STN7_TX_C_DP<114>")
	)
	(segment
		(start 424.733974 -394.881354)
		(end 424.161966 -394.309346)
		(width 0.1651)
		(layer "In11.Cu")
		(net "P5E_PEX3_STN7_TX_C_DP<114>")
	)
	(segment
		(start 415.803842 -345.755976)
		(end 415.513012 -345.465146)
		(width 0.1651)
		(layer "In11.Cu")
		(net "P5E_PEX3_STN7_TX_C_DP<114>")
	)
	(segment
		(start 413.331406 -365.459518)
		(end 413.458914 -365.359696)
		(width 0.1651)
		(layer "In11.Cu")
		(net "P5E_PEX3_STN7_TX_C_DP<114>")
	)
	(segment
		(start 415.803842 -346.209874)
		(end 415.803842 -345.755976)
		(width 0.1651)
		(layer "In11.Cu")
		(net "P5E_PEX3_STN7_TX_C_DP<114>")
	)
	(segment
		(start 424.161966 -394.309346)
		(end 422.836594 -393.68476)
		(width 0.1651)
		(layer "In11.Cu")
		(net "P5E_PEX3_STN7_TX_C_DP<114>")
	)
	(segment
		(start 422.71823 -393.727178)
		(end 422.270174 -393.515596)
		(width 0.1651)
		(layer "In11.Cu")
		(net "P5E_PEX3_STN7_TX_C_DP<114>")
	)
	(segment
		(start 421.170608 -392.899138)
		(end 414.994344 -389.987536)
		(width 0.1651)
		(layer "In11.Cu")
		(net "P5E_PEX3_STN7_TX_C_DP<114>")
	)
	(segment
		(start 422.227502 -393.397486)
		(end 421.7797 -393.186412)
		(width 0.1651)
		(layer "In11.Cu")
		(net "P5E_PEX3_STN7_TX_C_DP<114>")
	)
	(segment
		(start 413.042354 -368.801904)
		(end 413.225234 -367.28908)
		(width 0.1651)
		(layer "In11.Cu")
		(net "P5E_PEX3_STN7_TX_C_DP<114>")
	)
	(segment
		(start 423.889932 -400.390106)
		(end 423.889932 -400.772122)
		(width 0.1651)
		(layer "In11.Cu")
		(net "P5E_PEX3_STN7_TX_C_DP<114>")
	)
	(segment
		(start 412.985458 -386.090922)
		(end 412.62427 -383.585466)
		(width 0.1651)
		(layer "In11.Cu")
		(net "P5E_PEX3_STN7_TX_C_DP<114>")
	)
	(segment
		(start 413.185102 -366.670082)
		(end 413.312356 -366.57026)
		(width 0.1651)
		(layer "In11.Cu")
		(net "P5E_PEX3_STN7_TX_C_DP<114>")
	)
	(segment
		(start 422.270174 -393.515596)
		(end 422.227502 -393.397486)
		(width 0.1651)
		(layer "In11.Cu")
		(net "P5E_PEX3_STN7_TX_C_DP<114>")
	)
	(segment
		(start 424.733974 -400.612356)
		(end 424.733974 -394.881354)
		(width 0.1651)
		(layer "In11.Cu")
		(net "P5E_PEX3_STN7_TX_C_DP<114>")
	)
	(segment
		(start 413.458914 -365.359696)
		(end 414.249362 -358.8258)
		(width 0.1651)
		(layer "In11.Cu")
		(net "P5E_PEX3_STN7_TX_C_DP<114>")
	)
	(segment
		(start 414.994344 -389.987536)
		(end 412.985458 -386.090922)
		(width 0.1651)
		(layer "In11.Cu")
		(net "P5E_PEX3_STN7_TX_C_DP<114>")
	)
	(segment
		(start 413.27197 -365.951516)
		(end 413.331406 -365.459518)
		(width 0.1651)
		(layer "In11.Cu")
		(net "P5E_PEX3_STN7_TX_C_DP<114>")
	)
	(segment
		(start 413.125412 -367.16208)
		(end 413.185102 -366.670082)
		(width 0.1651)
		(layer "In11.Cu")
		(net "P5E_PEX3_STN7_TX_C_DP<114>")
	)
	(segment
		(start 421.661336 -393.22883)
		(end 421.213026 -393.017502)
		(width 0.1651)
		(layer "In11.Cu")
		(net "P5E_PEX3_STN7_TX_C_DP<114>")
	)
	(segment
		(start 421.7797 -393.186412)
		(end 421.661336 -393.22883)
		(width 0.1651)
		(layer "In11.Cu")
		(net "P5E_PEX3_STN7_TX_C_DP<114>")
	)
	(segment
		(start 167.755062 -154.958288)
		(end 169.225976 -154.958288)
		(width 0.13208)
		(layer "F.Cu")
		(net "NCSI_NIC2_TX_EN")
	)
	(segment
		(start 166.742364 -154.759914)
		(end 167.556688 -154.759914)
		(width 0.13208)
		(layer "F.Cu")
		(net "NCSI_NIC2_TX_EN")
	)
	(segment
		(start 167.556688 -154.759914)
		(end 167.755062 -154.958288)
		(width 0.13208)
		(layer "F.Cu")
		(net "NCSI_NIC2_TX_EN")
	)
	(via
		(at 169.225976 -154.958288)
		(size 0.508)
		(drill 0.254)
		(layers "F.Cu" "B.Cu")
		(net "NCSI_NIC2_TX_EN")
	)
	(segment
		(start 166.620444 -154.0256)
		(end 167.553132 -154.958288)
		(width 0.13208)
		(layer "B.Cu")
		(net "NCSI_NIC2_TX_EN")
	)
	(segment
		(start 166.055294 -154.0256)
		(end 166.620444 -154.0256)
		(width 0.13208)
		(layer "B.Cu")
		(net "NCSI_NIC2_TX_EN")
	)
	(segment
		(start 167.553132 -154.958288)
		(end 169.225976 -154.958288)
		(width 0.13208)
		(layer "B.Cu")
		(net "NCSI_NIC2_TX_EN")
	)
	(segment
		(start 68.006722 -148.592286)
		(end 65.498218 -148.592286)
		(width 0.13462)
		(layer "F.Cu")
		(net "P5E_PEX0_STN0_RX_DP<11>")
	)
	(segment
		(start 68.65747 -148.7551)
		(end 68.169536 -148.7551)
		(width 0.13462)
		(layer "F.Cu")
		(net "P5E_PEX0_STN0_RX_DP<11>")
	)
	(segment
		(start 68.169536 -148.7551)
		(end 68.006722 -148.592286)
		(width 0.13462)
		(layer "F.Cu")
		(net "P5E_PEX0_STN0_RX_DP<11>")
	)
	(segment
		(start 65.498218 -148.592286)
		(end 65.20307 -148.887434)
		(width 0.13462)
		(layer "F.Cu")
		(net "P5E_PEX0_STN0_RX_DP<11>")
	)
	(segment
		(start 78.294484 -273.670014)
		(end 78.535276 -273.670014)
		(width 0.1143)
		(layer "In5.Cu")
		(net "P5E_PEX0_STN0_RX_DP<11>")
	)
	(segment
		(start 69.102732 -150.23973)
		(end 69.453252 -150.59025)
		(width 0.1651)
		(layer "In5.Cu")
		(net "P5E_PEX0_STN0_RX_DP<11>")
	)
	(segment
		(start 75.014582 -161.207196)
		(end 75.035918 -161.304478)
		(width 0.1651)
		(layer "In5.Cu")
		(net "P5E_PEX0_STN0_RX_DP<11>")
	)
	(segment
		(start 65.4939 -148.596604)
		(end 67.585336 -148.596604)
		(width 0.1651)
		(layer "In5.Cu")
		(net "P5E_PEX0_STN0_RX_DP<11>")
	)
	(segment
		(start 74.992992 -161.110676)
		(end 75.014328 -161.206942)
		(width 0.1651)
		(layer "In5.Cu")
		(net "P5E_PEX0_STN0_RX_DP<11>")
	)
	(segment
		(start 68.75272 -149.763988)
		(end 69.102732 -150.114)
		(width 0.1651)
		(layer "In5.Cu")
		(net "P5E_PEX0_STN0_RX_DP<11>")
	)
	(segment
		(start 69.453252 -150.59025)
		(end 69.578982 -150.59025)
		(width 0.1651)
		(layer "In5.Cu")
		(net "P5E_PEX0_STN0_RX_DP<11>")
	)
	(segment
		(start 74.992738 -161.107882)
		(end 74.992738 -161.108136)
		(width 0.1651)
		(layer "In5.Cu")
		(net "P5E_PEX0_STN0_RX_DP<11>")
	)
	(segment
		(start 71.623682 -154.844242)
		(end 73.750932 -158.044388)
		(width 0.1651)
		(layer "In5.Cu")
		(net "P5E_PEX0_STN0_RX_DP<11>")
	)
	(segment
		(start 78.03388 -270.887444)
		(end 78.03388 -271.773904)
		(width 0.1651)
		(layer "In5.Cu")
		(net "P5E_PEX0_STN0_RX_DP<11>")
	)
	(segment
		(start 69.102732 -150.114)
		(end 69.102732 -150.23973)
		(width 0.1651)
		(layer "In5.Cu")
		(net "P5E_PEX0_STN0_RX_DP<11>")
	)
	(segment
		(start 78.0796 -271.848072)
		(end 78.0796 -273.45513)
		(width 0.1143)
		(layer "In5.Cu")
		(net "P5E_PEX0_STN0_RX_DP<11>")
	)
	(segment
		(start 69.578982 -150.59025)
		(end 70.045072 -151.05634)
		(width 0.1651)
		(layer "In5.Cu")
		(net "P5E_PEX0_STN0_RX_DP<11>")
	)
	(segment
		(start 70.045072 -151.05634)
		(end 71.623682 -154.844242)
		(width 0.1651)
		(layer "In5.Cu")
		(net "P5E_PEX0_STN0_RX_DP<11>")
	)
	(segment
		(start 74.992484 -161.108136)
		(end 74.992992 -161.110676)
		(width 0.1651)
		(layer "In5.Cu")
		(net "P5E_PEX0_STN0_RX_DP<11>")
	)
	(segment
		(start 78.575916 -268.129258)
		(end 78.03388 -270.887444)
		(width 0.1651)
		(layer "In5.Cu")
		(net "P5E_PEX0_STN0_RX_DP<11>")
	)
	(segment
		(start 75.035918 -161.304478)
		(end 78.541118 -260.519164)
		(width 0.1651)
		(layer "In5.Cu")
		(net "P5E_PEX0_STN0_RX_DP<11>")
	)
	(segment
		(start 74.949558 -160.910778)
		(end 74.992738 -161.107882)
		(width 0.1651)
		(layer "In5.Cu")
		(net "P5E_PEX0_STN0_RX_DP<11>")
	)
	(segment
		(start 73.750932 -158.044388)
		(end 74.949558 -160.910778)
		(width 0.1651)
		(layer "In5.Cu")
		(net "P5E_PEX0_STN0_RX_DP<11>")
	)
	(segment
		(start 78.541118 -260.519164)
		(end 78.575916 -268.129258)
		(width 0.1651)
		(layer "In5.Cu")
		(net "P5E_PEX0_STN0_RX_DP<11>")
	)
	(segment
		(start 75.014328 -161.206942)
		(end 75.014582 -161.207196)
		(width 0.1651)
		(layer "In5.Cu")
		(net "P5E_PEX0_STN0_RX_DP<11>")
	)
	(segment
		(start 67.585336 -148.596604)
		(end 68.27647 -149.287738)
		(width 0.1651)
		(layer "In5.Cu")
		(net "P5E_PEX0_STN0_RX_DP<11>")
	)
	(segment
		(start 74.992738 -161.108136)
		(end 74.992484 -161.108136)
		(width 0.1651)
		(layer "In5.Cu")
		(net "P5E_PEX0_STN0_RX_DP<11>")
	)
	(segment
		(start 78.03388 -271.802352)
		(end 78.0796 -271.848072)
		(width 0.1143)
		(layer "In5.Cu")
		(net "P5E_PEX0_STN0_RX_DP<11>")
	)
	(segment
		(start 68.27647 -149.413468)
		(end 68.62699 -149.763988)
		(width 0.1651)
		(layer "In5.Cu")
		(net "P5E_PEX0_STN0_RX_DP<11>")
	)
	(segment
		(start 78.649576 -273.784314)
		(end 78.649576 -274.049744)
		(width 0.1143)
		(layer "In5.Cu")
		(net "P5E_PEX0_STN0_RX_DP<11>")
	)
	(segment
		(start 68.62699 -149.763988)
		(end 68.75272 -149.763988)
		(width 0.1651)
		(layer "In5.Cu")
		(net "P5E_PEX0_STN0_RX_DP<11>")
	)
	(segment
		(start 78.03388 -271.773904)
		(end 78.03388 -271.802352)
		(width 0.1143)
		(layer "In5.Cu")
		(net "P5E_PEX0_STN0_RX_DP<11>")
	)
	(segment
		(start 68.27647 -149.287738)
		(end 68.27647 -149.413468)
		(width 0.1651)
		(layer "In5.Cu")
		(net "P5E_PEX0_STN0_RX_DP<11>")
	)
	(segment
		(start 65.20307 -148.887434)
		(end 65.4939 -148.596604)
		(width 0.1651)
		(layer "In5.Cu")
		(net "P5E_PEX0_STN0_RX_DP<11>")
	)
	(segment
		(start 78.0796 -273.45513)
		(end 78.294484 -273.670014)
		(width 0.1143)
		(layer "In5.Cu")
		(net "P5E_PEX0_STN0_RX_DP<11>")
	)
	(segment
		(start 78.535276 -273.670014)
		(end 78.649576 -273.784314)
		(width 0.1143)
		(layer "In5.Cu")
		(net "P5E_PEX0_STN0_RX_DP<11>")
	)
	(segment
		(start 286.296862 -110.97641)
		(end 285.988252 -110.6678)
		(width 0.13462)
		(layer "F.Cu")
		(net "P5E_PEX2_STN1_RX_DN<22>")
	)
	(segment
		(start 283.319982 -110.845092)
		(end 282.842462 -110.845092)
		(width 0.13462)
		(layer "F.Cu")
		(net "P5E_PEX2_STN1_RX_DN<22>")
	)
	(segment
		(start 283.497274 -110.6678)
		(end 283.319982 -110.845092)
		(width 0.13462)
		(layer "F.Cu")
		(net "P5E_PEX2_STN1_RX_DN<22>")
	)
	(segment
		(start 285.988252 -110.6678)
		(end 283.497274 -110.6678)
		(width 0.13462)
		(layer "F.Cu")
		(net "P5E_PEX2_STN1_RX_DN<22>")
	)
	(segment
		(start 268.100048 -164.419026)
		(end 297.215814 -268.786864)
		(width 0.1651)
		(layer "In5.Cu")
		(net "P5E_PEX2_STN1_RX_DN<22>")
	)
	(segment
		(start 282.454604 -111.332264)
		(end 282.391866 -111.481362)
		(width 0.1651)
		(layer "In5.Cu")
		(net "P5E_PEX2_STN1_RX_DN<22>")
	)
	(segment
		(start 297.215814 -271.526)
		(end 297.215814 -271.554448)
		(width 0.1143)
		(layer "In5.Cu")
		(net "P5E_PEX2_STN1_RX_DN<22>")
	)
	(segment
		(start 285.147512 -110.79988)
		(end 284.652212 -110.79988)
		(width 0.1651)
		(layer "In5.Cu")
		(net "P5E_PEX2_STN1_RX_DN<22>")
	)
	(segment
		(start 286.296862 -110.97641)
		(end 286.006032 -110.68558)
		(width 0.1651)
		(layer "In5.Cu")
		(net "P5E_PEX2_STN1_RX_DN<22>")
	)
	(segment
		(start 274.145502 -121.87682)
		(end 274.013676 -121.970546)
		(width 0.1651)
		(layer "In5.Cu")
		(net "P5E_PEX2_STN1_RX_DN<22>")
	)
	(segment
		(start 274.336764 -120.053862)
		(end 274.43049 -120.185688)
		(width 0.1651)
		(layer "In5.Cu")
		(net "P5E_PEX2_STN1_RX_DN<22>")
	)
	(segment
		(start 271.479264 -137.015474)
		(end 269.524988 -140.713968)
		(width 0.1651)
		(layer "In5.Cu")
		(net "P5E_PEX2_STN1_RX_DN<22>")
	)
	(segment
		(start 285.261812 -110.68558)
		(end 285.147512 -110.79988)
		(width 0.1651)
		(layer "In5.Cu")
		(net "P5E_PEX2_STN1_RX_DN<22>")
	)
	(segment
		(start 286.006032 -110.68558)
		(end 285.261812 -110.68558)
		(width 0.1651)
		(layer "In5.Cu")
		(net "P5E_PEX2_STN1_RX_DN<22>")
	)
	(segment
		(start 281.32532 -111.792258)
		(end 281.262582 -111.941356)
		(width 0.1651)
		(layer "In5.Cu")
		(net "P5E_PEX2_STN1_RX_DN<22>")
	)
	(segment
		(start 276.133814 -114.5286)
		(end 275.62175 -114.76482)
		(width 0.1651)
		(layer "In5.Cu")
		(net "P5E_PEX2_STN1_RX_DN<22>")
	)
	(segment
		(start 283.52115 -111.021368)
		(end 283.062172 -111.208312)
		(width 0.1651)
		(layer "In5.Cu")
		(net "P5E_PEX2_STN1_RX_DN<22>")
	)
	(segment
		(start 269.524988 -140.713968)
		(end 267.655802 -144.875758)
		(width 0.1651)
		(layer "In5.Cu")
		(net "P5E_PEX2_STN1_RX_DN<22>")
	)
	(segment
		(start 274.348194 -120.674384)
		(end 274.216114 -120.76811)
		(width 0.1651)
		(layer "In5.Cu")
		(net "P5E_PEX2_STN1_RX_DN<22>")
	)
	(segment
		(start 278.819864 -113.233962)
		(end 278.407368 -113.50879)
		(width 0.1651)
		(layer "In5.Cu")
		(net "P5E_PEX2_STN1_RX_DN<22>")
	)
	(segment
		(start 267.015214 -158.370778)
		(end 268.100048 -164.419026)
		(width 0.1651)
		(layer "In5.Cu")
		(net "P5E_PEX2_STN1_RX_DN<22>")
	)
	(segment
		(start 278.407368 -113.50879)
		(end 278.248872 -113.47704)
		(width 0.1651)
		(layer "In5.Cu")
		(net "P5E_PEX2_STN1_RX_DN<22>")
	)
	(segment
		(start 297.215814 -271.554448)
		(end 297.170094 -271.600168)
		(width 0.1143)
		(layer "In5.Cu")
		(net "P5E_PEX2_STN1_RX_DN<22>")
	)
	(segment
		(start 274.013676 -121.970546)
		(end 271.479264 -137.015474)
		(width 0.1651)
		(layer "In5.Cu")
		(net "P5E_PEX2_STN1_RX_DN<22>")
	)
	(segment
		(start 280.65476 -112.065308)
		(end 279.917398 -112.365282)
		(width 0.1651)
		(layer "In5.Cu")
		(net "P5E_PEX2_STN1_RX_DN<22>")
	)
	(segment
		(start 277.805134 -113.91011)
		(end 277.392638 -114.184938)
		(width 0.1651)
		(layer "In5.Cu")
		(net "P5E_PEX2_STN1_RX_DN<22>")
	)
	(segment
		(start 283.584142 -110.87227)
		(end 283.52115 -111.021368)
		(width 0.1651)
		(layer "In5.Cu")
		(net "P5E_PEX2_STN1_RX_DN<22>")
	)
	(segment
		(start 297.170094 -271.600168)
		(end 297.170094 -273.376136)
		(width 0.1143)
		(layer "In5.Cu")
		(net "P5E_PEX2_STN1_RX_DN<22>")
	)
	(segment
		(start 274.43049 -120.185688)
		(end 274.348194 -120.674384)
		(width 0.1651)
		(layer "In5.Cu")
		(net "P5E_PEX2_STN1_RX_DN<22>")
	)
	(segment
		(start 276.579584 -114.5286)
		(end 276.133814 -114.5286)
		(width 0.1651)
		(layer "In5.Cu")
		(net "P5E_PEX2_STN1_RX_DN<22>")
	)
	(segment
		(start 275.62175 -114.76482)
		(end 275.356066 -115.076478)
		(width 0.1651)
		(layer "In5.Cu")
		(net "P5E_PEX2_STN1_RX_DN<22>")
	)
	(segment
		(start 281.784044 -111.605568)
		(end 281.32532 -111.792258)
		(width 0.1651)
		(layer "In5.Cu")
		(net "P5E_PEX2_STN1_RX_DN<22>")
	)
	(segment
		(start 282.913328 -111.145574)
		(end 282.454604 -111.332264)
		(width 0.1651)
		(layer "In5.Cu")
		(net "P5E_PEX2_STN1_RX_DN<22>")
	)
	(segment
		(start 277.392638 -114.184938)
		(end 277.234142 -114.153188)
		(width 0.1651)
		(layer "In5.Cu")
		(net "P5E_PEX2_STN1_RX_DN<22>")
	)
	(segment
		(start 278.248872 -113.47704)
		(end 277.836884 -113.751614)
		(width 0.1651)
		(layer "In5.Cu")
		(net "P5E_PEX2_STN1_RX_DN<22>")
	)
	(segment
		(start 277.836884 -113.751614)
		(end 277.805134 -113.91011)
		(width 0.1651)
		(layer "In5.Cu")
		(net "P5E_PEX2_STN1_RX_DN<22>")
	)
	(segment
		(start 280.803604 -112.128046)
		(end 280.65476 -112.065308)
		(width 0.1651)
		(layer "In5.Cu")
		(net "P5E_PEX2_STN1_RX_DN<22>")
	)
	(segment
		(start 282.391866 -111.481362)
		(end 281.932888 -111.668306)
		(width 0.1651)
		(layer "In5.Cu")
		(net "P5E_PEX2_STN1_RX_DN<22>")
	)
	(segment
		(start 266.559792 -151.040592)
		(end 267.015214 -158.370778)
		(width 0.1651)
		(layer "In5.Cu")
		(net "P5E_PEX2_STN1_RX_DN<22>")
	)
	(segment
		(start 297.54957 -273.365214)
		(end 297.54957 -273.099784)
		(width 0.1143)
		(layer "In5.Cu")
		(net "P5E_PEX2_STN1_RX_DN<22>")
	)
	(segment
		(start 275.072856 -115.683538)
		(end 274.336764 -120.053862)
		(width 0.1651)
		(layer "In5.Cu")
		(net "P5E_PEX2_STN1_RX_DN<22>")
	)
	(segment
		(start 275.356066 -115.076478)
		(end 275.072856 -115.683538)
		(width 0.1651)
		(layer "In5.Cu")
		(net "P5E_PEX2_STN1_RX_DN<22>")
	)
	(segment
		(start 284.537912 -110.68558)
		(end 284.042612 -110.68558)
		(width 0.1651)
		(layer "In5.Cu")
		(net "P5E_PEX2_STN1_RX_DN<22>")
	)
	(segment
		(start 283.062172 -111.208312)
		(end 282.913328 -111.145574)
		(width 0.1651)
		(layer "In5.Cu")
		(net "P5E_PEX2_STN1_RX_DN<22>")
	)
	(segment
		(start 297.170094 -273.376136)
		(end 297.273472 -273.479514)
		(width 0.1143)
		(layer "In5.Cu")
		(net "P5E_PEX2_STN1_RX_DN<22>")
	)
	(segment
		(start 297.43527 -273.479514)
		(end 297.54957 -273.365214)
		(width 0.1143)
		(layer "In5.Cu")
		(net "P5E_PEX2_STN1_RX_DN<22>")
	)
	(segment
		(start 284.652212 -110.79988)
		(end 284.537912 -110.68558)
		(width 0.1651)
		(layer "In5.Cu")
		(net "P5E_PEX2_STN1_RX_DN<22>")
	)
	(segment
		(start 297.273472 -273.479514)
		(end 297.43527 -273.479514)
		(width 0.1143)
		(layer "In5.Cu")
		(net "P5E_PEX2_STN1_RX_DN<22>")
	)
	(segment
		(start 276.822154 -114.427762)
		(end 276.579584 -114.5286)
		(width 0.1651)
		(layer "In5.Cu")
		(net "P5E_PEX2_STN1_RX_DN<22>")
	)
	(segment
		(start 274.216114 -120.76811)
		(end 274.134072 -121.256298)
		(width 0.1651)
		(layer "In5.Cu")
		(net "P5E_PEX2_STN1_RX_DN<22>")
	)
	(segment
		(start 267.655802 -144.875758)
		(end 266.559792 -151.040592)
		(width 0.1651)
		(layer "In5.Cu")
		(net "P5E_PEX2_STN1_RX_DN<22>")
	)
	(segment
		(start 278.851614 -113.075466)
		(end 278.819864 -113.233962)
		(width 0.1651)
		(layer "In5.Cu")
		(net "P5E_PEX2_STN1_RX_DN<22>")
	)
	(segment
		(start 281.262582 -111.941356)
		(end 280.803604 -112.128046)
		(width 0.1651)
		(layer "In5.Cu")
		(net "P5E_PEX2_STN1_RX_DN<22>")
	)
	(segment
		(start 277.234142 -114.153188)
		(end 276.822154 -114.427762)
		(width 0.1651)
		(layer "In5.Cu")
		(net "P5E_PEX2_STN1_RX_DN<22>")
	)
	(segment
		(start 274.227798 -121.388124)
		(end 274.145502 -121.87682)
		(width 0.1651)
		(layer "In5.Cu")
		(net "P5E_PEX2_STN1_RX_DN<22>")
	)
	(segment
		(start 297.215814 -268.786864)
		(end 297.215814 -271.526)
		(width 0.1651)
		(layer "In5.Cu")
		(net "P5E_PEX2_STN1_RX_DN<22>")
	)
	(segment
		(start 279.917398 -112.365282)
		(end 278.851614 -113.075466)
		(width 0.1651)
		(layer "In5.Cu")
		(net "P5E_PEX2_STN1_RX_DN<22>")
	)
	(segment
		(start 281.932888 -111.668306)
		(end 281.784044 -111.605568)
		(width 0.1651)
		(layer "In5.Cu")
		(net "P5E_PEX2_STN1_RX_DN<22>")
	)
	(segment
		(start 284.042612 -110.68558)
		(end 283.584142 -110.87227)
		(width 0.1651)
		(layer "In5.Cu")
		(net "P5E_PEX2_STN1_RX_DN<22>")
	)
	(segment
		(start 274.134072 -121.256298)
		(end 274.227798 -121.388124)
		(width 0.1651)
		(layer "In5.Cu")
		(net "P5E_PEX2_STN1_RX_DN<22>")
	)
	(segment
		(start 436.964836 -28.990036)
		(end 436.964836 -28.99029)
		(width 0.13462)
		(layer "F.Cu")
		(net "P5E_PEX3_STN2_RX_DP<32>")
	)
	(segment
		(start 436.485792 -28.99029)
		(end 436.319422 -28.82392)
		(width 0.13462)
		(layer "F.Cu")
		(net "P5E_PEX3_STN2_RX_DP<32>")
	)
	(segment
		(start 436.319422 -28.82392)
		(end 435.663086 -28.82392)
		(width 0.13462)
		(layer "F.Cu")
		(net "P5E_PEX3_STN2_RX_DP<32>")
	)
	(segment
		(start 435.663086 -28.82392)
		(end 435.364636 -29.12237)
		(width 0.13462)
		(layer "F.Cu")
		(net "P5E_PEX3_STN2_RX_DP<32>")
	)
	(segment
		(start 436.964836 -28.99029)
		(end 436.485792 -28.99029)
		(width 0.13462)
		(layer "F.Cu")
		(net "P5E_PEX3_STN2_RX_DP<32>")
	)
	(segment
		(start 406.999948 -275.684488)
		(end 406.999948 -275.949918)
		(width 0.1143)
		(layer "In7.Cu")
		(net "P5E_PEX3_STN2_RX_DP<32>")
	)
	(segment
		(start 435.364636 -29.12237)
		(end 435.522624 -28.964382)
		(width 0.1651)
		(layer "In7.Cu")
		(net "P5E_PEX3_STN2_RX_DP<32>")
	)
	(segment
		(start 438.613296 -31.250636)
		(end 441.27293 -37.563552)
		(width 0.1651)
		(layer "In7.Cu")
		(net "P5E_PEX3_STN2_RX_DP<32>")
	)
	(segment
		(start 426.284136 -154.799284)
		(end 406.79624 -266.698222)
		(width 0.1651)
		(layer "In7.Cu")
		(net "P5E_PEX3_STN2_RX_DP<32>")
	)
	(segment
		(start 406.885648 -275.570188)
		(end 406.999948 -275.684488)
		(width 0.1143)
		(layer "In7.Cu")
		(net "P5E_PEX3_STN2_RX_DP<32>")
	)
	(segment
		(start 438.99328 -61.28004)
		(end 427.985428 -116.762022)
		(width 0.1651)
		(layer "In7.Cu")
		(net "P5E_PEX3_STN2_RX_DP<32>")
	)
	(segment
		(start 437.05653 -29.69387)
		(end 437.406542 -30.043882)
		(width 0.1651)
		(layer "In7.Cu")
		(net "P5E_PEX3_STN2_RX_DP<32>")
	)
	(segment
		(start 427.670214 -144.038066)
		(end 426.284136 -154.799284)
		(width 0.1651)
		(layer "In7.Cu")
		(net "P5E_PEX3_STN2_RX_DP<32>")
	)
	(segment
		(start 406.644856 -275.570188)
		(end 406.885648 -275.570188)
		(width 0.1143)
		(layer "In7.Cu")
		(net "P5E_PEX3_STN2_RX_DP<32>")
	)
	(segment
		(start 435.843426 -28.83154)
		(end 436.1942 -28.83154)
		(width 0.1651)
		(layer "In7.Cu")
		(net "P5E_PEX3_STN2_RX_DP<32>")
	)
	(segment
		(start 437.406542 -30.169612)
		(end 437.757062 -30.520132)
		(width 0.1651)
		(layer "In7.Cu")
		(net "P5E_PEX3_STN2_RX_DP<32>")
	)
	(segment
		(start 435.522624 -28.964382)
		(end 435.843426 -28.83154)
		(width 0.1651)
		(layer "In7.Cu")
		(net "P5E_PEX3_STN2_RX_DP<32>")
	)
	(segment
		(start 436.1942 -28.83154)
		(end 436.544212 -29.181552)
		(width 0.1651)
		(layer "In7.Cu")
		(net "P5E_PEX3_STN2_RX_DP<32>")
	)
	(segment
		(start 406.429464 -275.354796)
		(end 406.644856 -275.570188)
		(width 0.1143)
		(layer "In7.Cu")
		(net "P5E_PEX3_STN2_RX_DP<32>")
	)
	(segment
		(start 437.406542 -30.043882)
		(end 437.406542 -30.169612)
		(width 0.1651)
		(layer "In7.Cu")
		(net "P5E_PEX3_STN2_RX_DP<32>")
	)
	(segment
		(start 406.383744 -271.421352)
		(end 406.429464 -271.467072)
		(width 0.1143)
		(layer "In7.Cu")
		(net "P5E_PEX3_STN2_RX_DP<32>")
	)
	(segment
		(start 437.882792 -30.520132)
		(end 438.613296 -31.250636)
		(width 0.1651)
		(layer "In7.Cu")
		(net "P5E_PEX3_STN2_RX_DP<32>")
	)
	(segment
		(start 406.429464 -271.467072)
		(end 406.429464 -275.354796)
		(width 0.1143)
		(layer "In7.Cu")
		(net "P5E_PEX3_STN2_RX_DP<32>")
	)
	(segment
		(start 436.894732 -29.69387)
		(end 437.05653 -29.69387)
		(width 0.1651)
		(layer "In7.Cu")
		(net "P5E_PEX3_STN2_RX_DP<32>")
	)
	(segment
		(start 427.985428 -116.762022)
		(end 427.670214 -144.038066)
		(width 0.1651)
		(layer "In7.Cu")
		(net "P5E_PEX3_STN2_RX_DP<32>")
	)
	(segment
		(start 436.544212 -29.181552)
		(end 436.544212 -29.34335)
		(width 0.1651)
		(layer "In7.Cu")
		(net "P5E_PEX3_STN2_RX_DP<32>")
	)
	(segment
		(start 436.544212 -29.34335)
		(end 436.894732 -29.69387)
		(width 0.1651)
		(layer "In7.Cu")
		(net "P5E_PEX3_STN2_RX_DP<32>")
	)
	(segment
		(start 406.563322 -269.382494)
		(end 406.383744 -270.159734)
		(width 0.1651)
		(layer "In7.Cu")
		(net "P5E_PEX3_STN2_RX_DP<32>")
	)
	(segment
		(start 439.178954 -49.388014)
		(end 438.99328 -61.28004)
		(width 0.1651)
		(layer "In7.Cu")
		(net "P5E_PEX3_STN2_RX_DP<32>")
	)
	(segment
		(start 441.369196 -38.063424)
		(end 441.160916 -39.920926)
		(width 0.1651)
		(layer "In7.Cu")
		(net "P5E_PEX3_STN2_RX_DP<32>")
	)
	(segment
		(start 406.79624 -266.698222)
		(end 406.563322 -269.382494)
		(width 0.1651)
		(layer "In7.Cu")
		(net "P5E_PEX3_STN2_RX_DP<32>")
	)
	(segment
		(start 441.27293 -37.563552)
		(end 441.369196 -38.063424)
		(width 0.1651)
		(layer "In7.Cu")
		(net "P5E_PEX3_STN2_RX_DP<32>")
	)
	(segment
		(start 441.160916 -39.920926)
		(end 439.178954 -49.388014)
		(width 0.1651)
		(layer "In7.Cu")
		(net "P5E_PEX3_STN2_RX_DP<32>")
	)
	(segment
		(start 406.383744 -271.392904)
		(end 406.383744 -271.421352)
		(width 0.1143)
		(layer "In7.Cu")
		(net "P5E_PEX3_STN2_RX_DP<32>")
	)
	(segment
		(start 437.757062 -30.520132)
		(end 437.882792 -30.520132)
		(width 0.1651)
		(layer "In7.Cu")
		(net "P5E_PEX3_STN2_RX_DP<32>")
	)
	(segment
		(start 406.383744 -270.159734)
		(end 406.383744 -271.392904)
		(width 0.1651)
		(layer "In7.Cu")
		(net "P5E_PEX3_STN2_RX_DP<32>")
	)
	(segment
		(start 440.67984 -356.832154)
		(end 440.67984 -357.462582)
		(width 0.13462)
		(layer "F.Cu")
		(net "P5E_PEX3_STN7_TX_C_DP<127>")
	)
	(segment
		(start 440.359292 -356.511606)
		(end 440.67984 -356.832154)
		(width 0.13462)
		(layer "F.Cu")
		(net "P5E_PEX3_STN7_TX_C_DP<127>")
	)
	(segment
		(start 440.67984 -357.462582)
		(end 440.384692 -357.75773)
		(width 0.13462)
		(layer "F.Cu")
		(net "P5E_PEX3_STN7_TX_C_DP<127>")
	)
	(segment
		(start 437.147462 -365.618522)
		(end 437.266842 -365.578644)
		(width 0.1651)
		(layer "In11.Cu")
		(net "P5E_PEX3_STN7_TX_C_DP<127>")
	)
	(segment
		(start 435.733952 -369.233704)
		(end 435.991762 -368.138202)
		(width 0.1651)
		(layer "In11.Cu")
		(net "P5E_PEX3_STN7_TX_C_DP<127>")
	)
	(segment
		(start 435.447186 -375.999248)
		(end 435.733952 -375.712482)
		(width 0.1651)
		(layer "In11.Cu")
		(net "P5E_PEX3_STN7_TX_C_DP<127>")
	)
	(segment
		(start 436.445406 -367.227358)
		(end 436.405528 -367.108232)
		(width 0.1651)
		(layer "In11.Cu")
		(net "P5E_PEX3_STN7_TX_C_DP<127>")
	)
	(segment
		(start 436.926482 -366.06226)
		(end 437.147462 -365.618522)
		(width 0.1651)
		(layer "In11.Cu")
		(net "P5E_PEX3_STN7_TX_C_DP<127>")
	)
	(segment
		(start 437.266842 -365.578644)
		(end 437.266588 -365.578644)
		(width 0.1651)
		(layer "In11.Cu")
		(net "P5E_PEX3_STN7_TX_C_DP<127>")
	)
	(segment
		(start 435.733952 -375.712482)
		(end 435.733952 -369.233704)
		(width 0.1651)
		(layer "In11.Cu")
		(net "P5E_PEX3_STN7_TX_C_DP<127>")
	)
	(segment
		(start 436.626508 -366.664748)
		(end 436.745634 -366.624616)
		(width 0.1651)
		(layer "In11.Cu")
		(net "P5E_PEX3_STN7_TX_C_DP<127>")
	)
	(segment
		(start 436.745634 -366.624616)
		(end 436.96636 -366.181386)
		(width 0.1651)
		(layer "In11.Cu")
		(net "P5E_PEX3_STN7_TX_C_DP<127>")
	)
	(segment
		(start 436.405528 -367.108232)
		(end 436.626508 -366.664748)
		(width 0.1651)
		(layer "In11.Cu")
		(net "P5E_PEX3_STN7_TX_C_DP<127>")
	)
	(segment
		(start 435.991762 -368.138202)
		(end 436.445406 -367.227358)
		(width 0.1651)
		(layer "In11.Cu")
		(net "P5E_PEX3_STN7_TX_C_DP<127>")
	)
	(segment
		(start 437.668416 -364.57255)
		(end 437.787796 -364.532672)
		(width 0.1651)
		(layer "In11.Cu")
		(net "P5E_PEX3_STN7_TX_C_DP<127>")
	)
	(segment
		(start 435.01691 -375.999248)
		(end 435.447186 -375.999248)
		(width 0.1651)
		(layer "In11.Cu")
		(net "P5E_PEX3_STN7_TX_C_DP<127>")
	)
	(segment
		(start 440.675522 -358.04856)
		(end 440.384692 -357.75773)
		(width 0.1651)
		(layer "In11.Cu")
		(net "P5E_PEX3_STN7_TX_C_DP<127>")
	)
	(segment
		(start 440.675522 -358.291384)
		(end 440.675522 -358.04856)
		(width 0.1651)
		(layer "In11.Cu")
		(net "P5E_PEX3_STN7_TX_C_DP<127>")
	)
	(segment
		(start 434.88991 -375.872248)
		(end 435.01691 -375.999248)
		(width 0.1651)
		(layer "In11.Cu")
		(net "P5E_PEX3_STN7_TX_C_DP<127>")
	)
	(segment
		(start 434.88991 -375.490232)
		(end 434.88991 -375.872248)
		(width 0.1651)
		(layer "In11.Cu")
		(net "P5E_PEX3_STN7_TX_C_DP<127>")
	)
	(segment
		(start 440.477656 -359.132632)
		(end 440.675522 -358.291384)
		(width 0.1651)
		(layer "In11.Cu")
		(net "P5E_PEX3_STN7_TX_C_DP<127>")
	)
	(segment
		(start 436.96636 -366.181386)
		(end 436.926482 -366.06226)
		(width 0.1651)
		(layer "In11.Cu")
		(net "P5E_PEX3_STN7_TX_C_DP<127>")
	)
	(segment
		(start 437.266588 -365.578644)
		(end 437.487314 -365.135414)
		(width 0.1651)
		(layer "In11.Cu")
		(net "P5E_PEX3_STN7_TX_C_DP<127>")
	)
	(segment
		(start 437.487314 -365.135414)
		(end 437.447436 -365.016288)
		(width 0.1651)
		(layer "In11.Cu")
		(net "P5E_PEX3_STN7_TX_C_DP<127>")
	)
	(segment
		(start 437.787796 -364.532672)
		(end 440.477656 -359.132632)
		(width 0.1651)
		(layer "In11.Cu")
		(net "P5E_PEX3_STN7_TX_C_DP<127>")
	)
	(segment
		(start 437.447436 -365.016288)
		(end 437.668416 -364.57255)
		(width 0.1651)
		(layer "In11.Cu")
		(net "P5E_PEX3_STN7_TX_C_DP<127>")
	)
	(segment
		(start 171.579794 -138.6332)
		(end 171.579794 -139.6492)
		(width 0.13208)
		(layer "F.Cu")
		(net "PRSNTB2_NIC2_N")
	)
	(segment
		(start 171.06392 -139.565126)
		(end 171.147994 -139.6492)
		(width 0.13208)
		(layer "F.Cu")
		(net "PRSNTB2_NIC2_N")
	)
	(segment
		(start 170.369992 -139.565126)
		(end 171.06392 -139.565126)
		(width 0.13208)
		(layer "F.Cu")
		(net "PRSNTB2_NIC2_N")
	)
	(segment
		(start 171.147994 -139.6492)
		(end 171.579794 -139.6492)
		(width 0.13208)
		(layer "F.Cu")
		(net "PRSNTB2_NIC2_N")
	)
	(segment
		(start 166.742364 -139.565126)
		(end 170.369992 -139.565126)
		(width 0.13208)
		(layer "F.Cu")
		(net "PRSNTB2_NIC2_N")
	)
	(via
		(at 170.369992 -139.565126)
		(size 0.762)
		(drill 0.381)
		(layers "F.Cu" "B.Cu")
		(net "PRSNTB2_NIC2_N")
	)
	(segment
		(start 79.440278 -150.39213)
		(end 79.752698 -150.70455)
		(width 0.13462)
		(layer "F.Cu")
		(net "P5E_PEX0_STN0_TX_C_DN<12>")
	)
	(segment
		(start 73.257664 -150.554944)
		(end 73.745852 -150.554944)
		(width 0.13462)
		(layer "F.Cu")
		(net "P5E_PEX0_STN0_TX_C_DN<12>")
	)
	(segment
		(start 73.908666 -150.39213)
		(end 79.440278 -150.39213)
		(width 0.13462)
		(layer "F.Cu")
		(net "P5E_PEX0_STN0_TX_C_DN<12>")
	)
	(segment
		(start 73.745852 -150.554944)
		(end 73.908666 -150.39213)
		(width 0.13462)
		(layer "F.Cu")
		(net "P5E_PEX0_STN0_TX_C_DN<12>")
	)
	(segment
		(start 161.432748 -321.998594)
		(end 160.043622 -323.38772)
		(width 0.1651)
		(layer "In15.Cu")
		(net "P5E_PEX1_STN6_RX_DN<108>")
	)
	(segment
		(start 162.116008 -319.8368)
		(end 162.116008 -319.865248)
		(width 0.1143)
		(layer "In15.Cu")
		(net "P5E_PEX1_STN6_RX_DN<108>")
	)
	(segment
		(start 123.617482 -339.451442)
		(end 117.557296 -341.395812)
		(width 0.1651)
		(layer "In15.Cu")
		(net "P5E_PEX1_STN6_RX_DN<108>")
	)
	(segment
		(start 162.361118 -318.320166)
		(end 162.197288 -318.320166)
		(width 0.1143)
		(layer "In15.Cu")
		(net "P5E_PEX1_STN6_RX_DN<108>")
	)
	(segment
		(start 116.93906 -358.477058)
		(end 112.681004 -365.127286)
		(width 0.1651)
		(layer "In15.Cu")
		(net "P5E_PEX1_STN6_RX_DN<108>")
	)
	(segment
		(start 117.098318 -357.93299)
		(end 116.93906 -358.477058)
		(width 0.1651)
		(layer "In15.Cu")
		(net "P5E_PEX1_STN6_RX_DN<108>")
	)
	(segment
		(start 143.460724 -331.23251)
		(end 123.617482 -339.451442)
		(width 0.1651)
		(layer "In15.Cu")
		(net "P5E_PEX1_STN6_RX_DN<108>")
	)
	(segment
		(start 123.666758 -399.197068)
		(end 123.67514 -399.20545)
		(width 0.1651)
		(layer "In15.Cu")
		(net "P5E_PEX1_STN6_RX_DN<108>")
	)
	(segment
		(start 110.7948 -384.894582)
		(end 111.140494 -386.138928)
		(width 0.1651)
		(layer "In15.Cu")
		(net "P5E_PEX1_STN6_RX_DN<108>")
	)
	(segment
		(start 162.197288 -318.320166)
		(end 162.070288 -318.447166)
		(width 0.1143)
		(layer "In15.Cu")
		(net "P5E_PEX1_STN6_RX_DN<108>")
	)
	(segment
		(start 117.327934 -341.74557)
		(end 117.098318 -342.095582)
		(width 0.1651)
		(layer "In15.Cu")
		(net "P5E_PEX1_STN6_RX_DN<108>")
	)
	(segment
		(start 117.098318 -342.095582)
		(end 117.098318 -357.93299)
		(width 0.1651)
		(layer "In15.Cu")
		(net "P5E_PEX1_STN6_RX_DN<108>")
	)
	(segment
		(start 162.070288 -319.79108)
		(end 162.116008 -319.8368)
		(width 0.1143)
		(layer "In15.Cu")
		(net "P5E_PEX1_STN6_RX_DN<108>")
	)
	(segment
		(start 115.058698 -390.152636)
		(end 120.843802 -392.549634)
		(width 0.1651)
		(layer "In15.Cu")
		(net "P5E_PEX1_STN6_RX_DN<108>")
	)
	(segment
		(start 160.043622 -323.38772)
		(end 143.460724 -331.23251)
		(width 0.1651)
		(layer "In15.Cu")
		(net "P5E_PEX1_STN6_RX_DN<108>")
	)
	(segment
		(start 123.67514 -399.20545)
		(end 123.67514 -401.581366)
		(width 0.1651)
		(layer "In15.Cu")
		(net "P5E_PEX1_STN6_RX_DN<108>")
	)
	(segment
		(start 122.97537 -402.281136)
		(end 122.637042 -402.281136)
		(width 0.1651)
		(layer "In15.Cu")
		(net "P5E_PEX1_STN6_RX_DN<108>")
	)
	(segment
		(start 162.116008 -320.347594)
		(end 161.432748 -321.998594)
		(width 0.1651)
		(layer "In15.Cu")
		(net "P5E_PEX1_STN6_RX_DN<108>")
	)
	(segment
		(start 162.070288 -318.447166)
		(end 162.070288 -319.79108)
		(width 0.1143)
		(layer "In15.Cu")
		(net "P5E_PEX1_STN6_RX_DN<108>")
	)
	(segment
		(start 110.903004 -368.667792)
		(end 110.7948 -384.894582)
		(width 0.1651)
		(layer "In15.Cu")
		(net "P5E_PEX1_STN6_RX_DN<108>")
	)
	(segment
		(start 162.450018 -318.409066)
		(end 162.361118 -318.320166)
		(width 0.1143)
		(layer "In15.Cu")
		(net "P5E_PEX1_STN6_RX_DN<108>")
	)
	(segment
		(start 112.681004 -365.127286)
		(end 110.903004 -368.667792)
		(width 0.1651)
		(layer "In15.Cu")
		(net "P5E_PEX1_STN6_RX_DN<108>")
	)
	(segment
		(start 122.637042 -402.281136)
		(end 122.510042 -402.408136)
		(width 0.1651)
		(layer "In15.Cu")
		(net "P5E_PEX1_STN6_RX_DN<108>")
	)
	(segment
		(start 122.510042 -402.408136)
		(end 122.510042 -402.790152)
		(width 0.1651)
		(layer "In15.Cu")
		(net "P5E_PEX1_STN6_RX_DN<108>")
	)
	(segment
		(start 117.557296 -341.395812)
		(end 117.328188 -341.745316)
		(width 0.1651)
		(layer "In15.Cu")
		(net "P5E_PEX1_STN6_RX_DN<108>")
	)
	(segment
		(start 162.116008 -319.865248)
		(end 162.116008 -320.347594)
		(width 0.1651)
		(layer "In15.Cu")
		(net "P5E_PEX1_STN6_RX_DN<108>")
	)
	(segment
		(start 123.67514 -401.581366)
		(end 122.97537 -402.281136)
		(width 0.1651)
		(layer "In15.Cu")
		(net "P5E_PEX1_STN6_RX_DN<108>")
	)
	(segment
		(start 123.666758 -395.37259)
		(end 123.666758 -399.197068)
		(width 0.1651)
		(layer "In15.Cu")
		(net "P5E_PEX1_STN6_RX_DN<108>")
	)
	(segment
		(start 112.357154 -387.949694)
		(end 115.058698 -390.152636)
		(width 0.1651)
		(layer "In15.Cu")
		(net "P5E_PEX1_STN6_RX_DN<108>")
	)
	(segment
		(start 111.140494 -386.138928)
		(end 112.357154 -387.949694)
		(width 0.1651)
		(layer "In15.Cu")
		(net "P5E_PEX1_STN6_RX_DN<108>")
	)
	(segment
		(start 117.328188 -341.745316)
		(end 117.327934 -341.74557)
		(width 0.1651)
		(layer "In15.Cu")
		(net "P5E_PEX1_STN6_RX_DN<108>")
	)
	(segment
		(start 162.450018 -318.699896)
		(end 162.450018 -318.409066)
		(width 0.1143)
		(layer "In15.Cu")
		(net "P5E_PEX1_STN6_RX_DN<108>")
	)
	(segment
		(start 120.843802 -392.549634)
		(end 123.666758 -395.37259)
		(width 0.1651)
		(layer "In15.Cu")
		(net "P5E_PEX1_STN6_RX_DN<108>")
	)
	(segment
		(start 286.296862 -130.43281)
		(end 286.016192 -130.71348)
		(width 0.13462)
		(layer "F.Cu")
		(net "P5E_PEX2_STN1_RX_DP<28>")
	)
	(segment
		(start 283.473398 -130.71348)
		(end 283.325062 -130.565144)
		(width 0.13462)
		(layer "F.Cu")
		(net "P5E_PEX2_STN1_RX_DP<28>")
	)
	(segment
		(start 283.325062 -130.565144)
		(end 282.842462 -130.565144)
		(width 0.13462)
		(layer "F.Cu")
		(net "P5E_PEX2_STN1_RX_DP<28>")
	)
	(segment
		(start 286.016192 -130.71348)
		(end 283.473398 -130.71348)
		(width 0.13462)
		(layer "F.Cu")
		(net "P5E_PEX2_STN1_RX_DP<28>")
	)
	(segment
		(start 273.558 -156.926026)
		(end 274.31619 -161.20364)
		(width 0.1651)
		(layer "In5.Cu")
		(net "P5E_PEX2_STN1_RX_DP<28>")
	)
	(segment
		(start 279.914604 -140.292328)
		(end 279.736296 -140.723366)
		(width 0.1651)
		(layer "In5.Cu")
		(net "P5E_PEX2_STN1_RX_DP<28>")
	)
	(segment
		(start 303.135284 -273.670014)
		(end 303.249584 -273.784314)
		(width 0.1143)
		(layer "In5.Cu")
		(net "P5E_PEX2_STN1_RX_DP<28>")
	)
	(segment
		(start 302.894492 -273.670014)
		(end 303.135284 -273.670014)
		(width 0.1143)
		(layer "In5.Cu")
		(net "P5E_PEX2_STN1_RX_DP<28>")
	)
	(segment
		(start 283.282898 -130.72364)
		(end 281.268678 -133.177026)
		(width 0.1651)
		(layer "In5.Cu")
		(net "P5E_PEX2_STN1_RX_DP<28>")
	)
	(segment
		(start 279.736296 -140.723366)
		(end 278.865584 -141.594078)
		(width 0.1651)
		(layer "In5.Cu")
		(net "P5E_PEX2_STN1_RX_DP<28>")
	)
	(segment
		(start 302.633888 -267.64234)
		(end 302.633888 -271.526)
		(width 0.1651)
		(layer "In5.Cu")
		(net "P5E_PEX2_STN1_RX_DP<28>")
	)
	(segment
		(start 274.87118 -144.635982)
		(end 273.154394 -146.953732)
		(width 0.1651)
		(layer "In5.Cu")
		(net "P5E_PEX2_STN1_RX_DP<28>")
	)
	(segment
		(start 278.865584 -141.594078)
		(end 275.992082 -143.514318)
		(width 0.1651)
		(layer "In5.Cu")
		(net "P5E_PEX2_STN1_RX_DP<28>")
	)
	(segment
		(start 286.296862 -130.43281)
		(end 286.006032 -130.72364)
		(width 0.1651)
		(layer "In5.Cu")
		(net "P5E_PEX2_STN1_RX_DP<28>")
	)
	(segment
		(start 279.914604 -136.446514)
		(end 279.914604 -140.292328)
		(width 0.1651)
		(layer "In5.Cu")
		(net "P5E_PEX2_STN1_RX_DP<28>")
	)
	(segment
		(start 273.154394 -146.953732)
		(end 272.959576 -147.65528)
		(width 0.1651)
		(layer "In5.Cu")
		(net "P5E_PEX2_STN1_RX_DP<28>")
	)
	(segment
		(start 274.31619 -161.20364)
		(end 302.633888 -267.64234)
		(width 0.1651)
		(layer "In5.Cu")
		(net "P5E_PEX2_STN1_RX_DP<28>")
	)
	(segment
		(start 302.679608 -271.600168)
		(end 302.679608 -273.45513)
		(width 0.1143)
		(layer "In5.Cu")
		(net "P5E_PEX2_STN1_RX_DP<28>")
	)
	(segment
		(start 302.633888 -271.526)
		(end 302.633888 -271.554448)
		(width 0.1143)
		(layer "In5.Cu")
		(net "P5E_PEX2_STN1_RX_DP<28>")
	)
	(segment
		(start 302.679608 -273.45513)
		(end 302.894492 -273.670014)
		(width 0.1143)
		(layer "In5.Cu")
		(net "P5E_PEX2_STN1_RX_DP<28>")
	)
	(segment
		(start 280.364438 -135.360156)
		(end 280.364184 -135.36041)
		(width 0.1651)
		(layer "In5.Cu")
		(net "P5E_PEX2_STN1_RX_DP<28>")
	)
	(segment
		(start 272.959576 -147.65528)
		(end 273.558 -156.926026)
		(width 0.1651)
		(layer "In5.Cu")
		(net "P5E_PEX2_STN1_RX_DP<28>")
	)
	(segment
		(start 303.249584 -273.784314)
		(end 303.249584 -274.049744)
		(width 0.1143)
		(layer "In5.Cu")
		(net "P5E_PEX2_STN1_RX_DP<28>")
	)
	(segment
		(start 286.006032 -130.72364)
		(end 283.282898 -130.72364)
		(width 0.1651)
		(layer "In5.Cu")
		(net "P5E_PEX2_STN1_RX_DP<28>")
	)
	(segment
		(start 281.268678 -133.177026)
		(end 280.364438 -135.360156)
		(width 0.1651)
		(layer "In5.Cu")
		(net "P5E_PEX2_STN1_RX_DP<28>")
	)
	(segment
		(start 302.633888 -271.554448)
		(end 302.679608 -271.600168)
		(width 0.1143)
		(layer "In5.Cu")
		(net "P5E_PEX2_STN1_RX_DP<28>")
	)
	(segment
		(start 275.992082 -143.514318)
		(end 274.87118 -144.635982)
		(width 0.1651)
		(layer "In5.Cu")
		(net "P5E_PEX2_STN1_RX_DP<28>")
	)
	(segment
		(start 280.364184 -135.36041)
		(end 279.914604 -136.446514)
		(width 0.1651)
		(layer "In5.Cu")
		(net "P5E_PEX2_STN1_RX_DP<28>")
	)
	(segment
		(start 435.655466 -28.5496)
		(end 435.364636 -28.25877)
		(width 0.13462)
		(layer "F.Cu")
		(net "P5E_PEX3_STN2_RX_DN<32>")
	)
	(segment
		(start 436.324502 -28.5496)
		(end 435.655466 -28.5496)
		(width 0.13462)
		(layer "F.Cu")
		(net "P5E_PEX3_STN2_RX_DN<32>")
	)
	(segment
		(start 436.964836 -28.390088)
		(end 436.484014 -28.390088)
		(width 0.13462)
		(layer "F.Cu")
		(net "P5E_PEX3_STN2_RX_DN<32>")
	)
	(segment
		(start 436.484014 -28.390088)
		(end 436.324502 -28.5496)
		(width 0.13462)
		(layer "F.Cu")
		(net "P5E_PEX3_STN2_RX_DN<32>")
	)
	(segment
		(start 439.274966 -61.310012)
		(end 439.46064 -49.41951)
		(width 0.1651)
		(layer "In7.Cu")
		(net "P5E_PEX3_STN2_RX_DN<32>")
	)
	(segment
		(start 435.655466 -28.5496)
		(end 435.364636 -28.25877)
		(width 0.1651)
		(layer "In7.Cu")
		(net "P5E_PEX3_STN2_RX_DN<32>")
	)
	(segment
		(start 406.72385 -275.379688)
		(end 406.619964 -275.275802)
		(width 0.1143)
		(layer "In7.Cu")
		(net "P5E_PEX3_STN2_RX_DN<32>")
	)
	(segment
		(start 439.46064 -49.41951)
		(end 441.439808 -39.96563)
		(width 0.1651)
		(layer "In7.Cu")
		(net "P5E_PEX3_STN2_RX_DN<32>")
	)
	(segment
		(start 441.654438 -38.052248)
		(end 441.544202 -37.481256)
		(width 0.1651)
		(layer "In7.Cu")
		(net "P5E_PEX3_STN2_RX_DN<32>")
	)
	(segment
		(start 438.851802 -31.090362)
		(end 436.31104 -28.5496)
		(width 0.1651)
		(layer "In7.Cu")
		(net "P5E_PEX3_STN2_RX_DN<32>")
	)
	(segment
		(start 441.439808 -39.96563)
		(end 441.654438 -38.052248)
		(width 0.1651)
		(layer "In7.Cu")
		(net "P5E_PEX3_STN2_RX_DN<32>")
	)
	(segment
		(start 407.076402 -266.734544)
		(end 426.563028 -154.841448)
		(width 0.1651)
		(layer "In7.Cu")
		(net "P5E_PEX3_STN2_RX_DN<32>")
	)
	(segment
		(start 406.885648 -275.379688)
		(end 406.72385 -275.379688)
		(width 0.1143)
		(layer "In7.Cu")
		(net "P5E_PEX3_STN2_RX_DN<32>")
	)
	(segment
		(start 441.544202 -37.481256)
		(end 438.851802 -31.090362)
		(width 0.1651)
		(layer "In7.Cu")
		(net "P5E_PEX3_STN2_RX_DN<32>")
	)
	(segment
		(start 406.999948 -274.999958)
		(end 406.999948 -275.265388)
		(width 0.1143)
		(layer "In7.Cu")
		(net "P5E_PEX3_STN2_RX_DN<32>")
	)
	(segment
		(start 406.619964 -271.467072)
		(end 406.665684 -271.421352)
		(width 0.1143)
		(layer "In7.Cu")
		(net "P5E_PEX3_STN2_RX_DN<32>")
	)
	(segment
		(start 428.267114 -116.791232)
		(end 439.274966 -61.310012)
		(width 0.1651)
		(layer "In7.Cu")
		(net "P5E_PEX3_STN2_RX_DN<32>")
	)
	(segment
		(start 436.31104 -28.5496)
		(end 435.655466 -28.5496)
		(width 0.1651)
		(layer "In7.Cu")
		(net "P5E_PEX3_STN2_RX_DN<32>")
	)
	(segment
		(start 406.665684 -271.421352)
		(end 406.665684 -271.392904)
		(width 0.1143)
		(layer "In7.Cu")
		(net "P5E_PEX3_STN2_RX_DN<32>")
	)
	(segment
		(start 426.563028 -154.841448)
		(end 427.952154 -144.057878)
		(width 0.1651)
		(layer "In7.Cu")
		(net "P5E_PEX3_STN2_RX_DN<32>")
	)
	(segment
		(start 407.076148 -266.734544)
		(end 407.076402 -266.734544)
		(width 0.1651)
		(layer "In7.Cu")
		(net "P5E_PEX3_STN2_RX_DN<32>")
	)
	(segment
		(start 427.952154 -144.057878)
		(end 428.267114 -116.791232)
		(width 0.1651)
		(layer "In7.Cu")
		(net "P5E_PEX3_STN2_RX_DN<32>")
	)
	(segment
		(start 406.665684 -270.191992)
		(end 406.842722 -269.42669)
		(width 0.1651)
		(layer "In7.Cu")
		(net "P5E_PEX3_STN2_RX_DN<32>")
	)
	(segment
		(start 406.999948 -275.265388)
		(end 406.885648 -275.379688)
		(width 0.1143)
		(layer "In7.Cu")
		(net "P5E_PEX3_STN2_RX_DN<32>")
	)
	(segment
		(start 406.665684 -271.392904)
		(end 406.665684 -270.191992)
		(width 0.1651)
		(layer "In7.Cu")
		(net "P5E_PEX3_STN2_RX_DN<32>")
	)
	(segment
		(start 406.842722 -269.42669)
		(end 407.076148 -266.734544)
		(width 0.1651)
		(layer "In7.Cu")
		(net "P5E_PEX3_STN2_RX_DN<32>")
	)
	(segment
		(start 406.619964 -275.275802)
		(end 406.619964 -271.467072)
		(width 0.1143)
		(layer "In7.Cu")
		(net "P5E_PEX3_STN2_RX_DN<32>")
	)
	(segment
		(start 431.62728 -351.317306)
		(end 431.921412 -351.611438)
		(width 0.13462)
		(layer "F.Cu")
		(net "P5E_PEX3_STN7_TX_C_DP<122>")
	)
	(segment
		(start 431.946812 -350.365314)
		(end 431.62728 -350.684846)
		(width 0.13462)
		(layer "F.Cu")
		(net "P5E_PEX3_STN7_TX_C_DP<122>")
	)
	(segment
		(start 431.62728 -350.684846)
		(end 431.62728 -351.317306)
		(width 0.13462)
		(layer "F.Cu")
		(net "P5E_PEX3_STN7_TX_C_DP<122>")
	)
	(segment
		(start 425.420282 -368.088418)
		(end 429.644556 -359.884726)
		(width 0.1651)
		(layer "In11.Cu")
		(net "P5E_PEX3_STN7_TX_C_DP<122>")
	)
	(segment
		(start 425.015914 -374.729248)
		(end 425.015914 -369.757452)
		(width 0.1651)
		(layer "In11.Cu")
		(net "P5E_PEX3_STN7_TX_C_DP<122>")
	)
	(segment
		(start 431.630582 -352.473006)
		(end 431.630582 -351.902268)
		(width 0.1651)
		(layer "In11.Cu")
		(net "P5E_PEX3_STN7_TX_C_DP<122>")
	)
	(segment
		(start 425.015914 -369.757452)
		(end 425.420282 -368.088418)
		(width 0.1651)
		(layer "In11.Cu")
		(net "P5E_PEX3_STN7_TX_C_DP<122>")
	)
	(segment
		(start 430.076102 -354.027486)
		(end 431.630582 -352.473006)
		(width 0.1651)
		(layer "In11.Cu")
		(net "P5E_PEX3_STN7_TX_C_DP<122>")
	)
	(segment
		(start 424.016932 -375.181114)
		(end 424.564048 -375.181114)
		(width 0.1651)
		(layer "In11.Cu")
		(net "P5E_PEX3_STN7_TX_C_DP<122>")
	)
	(segment
		(start 423.889932 -375.308114)
		(end 424.016932 -375.181114)
		(width 0.1651)
		(layer "In11.Cu")
		(net "P5E_PEX3_STN7_TX_C_DP<122>")
	)
	(segment
		(start 429.644556 -359.884726)
		(end 430.076102 -358.103932)
		(width 0.1651)
		(layer "In11.Cu")
		(net "P5E_PEX3_STN7_TX_C_DP<122>")
	)
	(segment
		(start 430.076102 -358.103932)
		(end 430.076102 -354.027486)
		(width 0.1651)
		(layer "In11.Cu")
		(net "P5E_PEX3_STN7_TX_C_DP<122>")
	)
	(segment
		(start 431.630582 -351.902268)
		(end 431.921412 -351.611438)
		(width 0.1651)
		(layer "In11.Cu")
		(net "P5E_PEX3_STN7_TX_C_DP<122>")
	)
	(segment
		(start 424.564048 -375.181114)
		(end 425.015914 -374.729248)
		(width 0.1651)
		(layer "In11.Cu")
		(net "P5E_PEX3_STN7_TX_C_DP<122>")
	)
	(segment
		(start 423.889932 -375.69013)
		(end 423.889932 -375.308114)
		(width 0.1651)
		(layer "In11.Cu")
		(net "P5E_PEX3_STN7_TX_C_DP<122>")
	)
	(segment
		(start 162.637216 -139.565126)
		(end 163.173156 -139.029186)
		(width 0.13208)
		(layer "F.Cu")
		(net "NIC2_AUX_PWR_EN_R")
	)
	(segment
		(start 162.14217 -139.565126)
		(end 162.637216 -139.565126)
		(width 0.13208)
		(layer "F.Cu")
		(net "NIC2_AUX_PWR_EN_R")
	)
	(segment
		(start 163.173156 -139.029186)
		(end 163.173156 -138.564112)
		(width 0.13208)
		(layer "F.Cu")
		(net "NIC2_AUX_PWR_EN_R")
	)
	(via
		(at 163.173156 -138.564112)
		(size 0.508)
		(drill 0.254)
		(layers "F.Cu" "B.Cu")
		(net "NIC2_AUX_PWR_EN_R")
	)
	(segment
		(start 164.565838 -138.421618)
		(end 164.565838 -137.795)
		(width 0.13208)
		(layer "B.Cu")
		(net "NIC2_AUX_PWR_EN_R")
	)
	(segment
		(start 163.590732 -138.564112)
		(end 163.733226 -138.421618)
		(width 0.13208)
		(layer "B.Cu")
		(net "NIC2_AUX_PWR_EN_R")
	)
	(segment
		(start 163.173156 -138.564112)
		(end 163.590732 -138.564112)
		(width 0.13208)
		(layer "B.Cu")
		(net "NIC2_AUX_PWR_EN_R")
	)
	(segment
		(start 164.565838 -137.795)
		(end 164.692838 -137.668)
		(width 0.13208)
		(layer "B.Cu")
		(net "NIC2_AUX_PWR_EN_R")
	)
	(segment
		(start 170.064684 -138.54684)
		(end 170.064684 -140.181076)
		(width 0.13208)
		(layer "B.Cu")
		(net "NIC2_AUX_PWR_EN_R")
	)
	(segment
		(start 163.733226 -138.421618)
		(end 164.565838 -138.421618)
		(width 0.13208)
		(layer "B.Cu")
		(net "NIC2_AUX_PWR_EN_R")
	)
	(segment
		(start 169.185844 -137.668)
		(end 170.064684 -138.54684)
		(width 0.13208)
		(layer "B.Cu")
		(net "NIC2_AUX_PWR_EN_R")
	)
	(segment
		(start 164.692838 -137.668)
		(end 169.185844 -137.668)
		(width 0.13208)
		(layer "B.Cu")
		(net "NIC2_AUX_PWR_EN_R")
	)
	(segment
		(start 68.006722 -155.79217)
		(end 65.498218 -155.79217)
		(width 0.13462)
		(layer "F.Cu")
		(net "P5E_PEX0_STN0_RX_DP<15>")
	)
	(segment
		(start 68.65747 -155.954984)
		(end 68.169536 -155.954984)
		(width 0.13462)
		(layer "F.Cu")
		(net "P5E_PEX0_STN0_RX_DP<15>")
	)
	(segment
		(start 68.169536 -155.954984)
		(end 68.006722 -155.79217)
		(width 0.13462)
		(layer "F.Cu")
		(net "P5E_PEX0_STN0_RX_DP<15>")
	)
	(segment
		(start 65.498218 -155.79217)
		(end 65.20307 -156.087318)
		(width 0.13462)
		(layer "F.Cu")
		(net "P5E_PEX0_STN0_RX_DP<15>")
	)
	(segment
		(start 74.23404 -271.773904)
		(end 74.23404 -271.802352)
		(width 0.1143)
		(layer "In5.Cu")
		(net "P5E_PEX0_STN0_RX_DP<15>")
	)
	(segment
		(start 66.990976 -158.351474)
		(end 66.893694 -158.48076)
		(width 0.1651)
		(layer "In5.Cu")
		(net "P5E_PEX0_STN0_RX_DP<15>")
	)
	(segment
		(start 66.72326 -157.273498)
		(end 66.792602 -157.764226)
		(width 0.1651)
		(layer "In5.Cu")
		(net "P5E_PEX0_STN0_RX_DP<15>")
	)
	(segment
		(start 74.27976 -271.848072)
		(end 74.27976 -273.45513)
		(width 0.1143)
		(layer "In5.Cu")
		(net "P5E_PEX0_STN0_RX_DP<15>")
	)
	(segment
		(start 66.921888 -157.861254)
		(end 66.990976 -158.351474)
		(width 0.1651)
		(layer "In5.Cu")
		(net "P5E_PEX0_STN0_RX_DP<15>")
	)
	(segment
		(start 65.610486 -155.796488)
		(end 66.226182 -155.796488)
		(width 0.1651)
		(layer "In5.Cu")
		(net "P5E_PEX0_STN0_RX_DP<15>")
	)
	(segment
		(start 66.792602 -157.764226)
		(end 66.921888 -157.861254)
		(width 0.1651)
		(layer "In5.Cu")
		(net "P5E_PEX0_STN0_RX_DP<15>")
	)
	(segment
		(start 65.20307 -156.087318)
		(end 65.411604 -155.878784)
		(width 0.1651)
		(layer "In5.Cu")
		(net "P5E_PEX0_STN0_RX_DP<15>")
	)
	(segment
		(start 67.092068 -159.06877)
		(end 67.630548 -162.8902)
		(width 0.1651)
		(layer "In5.Cu")
		(net "P5E_PEX0_STN0_RX_DP<15>")
	)
	(segment
		(start 74.537316 -261.285482)
		(end 74.70648 -267.744956)
		(width 0.1651)
		(layer "In5.Cu")
		(net "P5E_PEX0_STN0_RX_DP<15>")
	)
	(segment
		(start 74.23404 -271.802352)
		(end 74.27976 -271.848072)
		(width 0.1143)
		(layer "In5.Cu")
		(net "P5E_PEX0_STN0_RX_DP<15>")
	)
	(segment
		(start 66.820542 -157.144212)
		(end 66.72326 -157.273498)
		(width 0.1651)
		(layer "In5.Cu")
		(net "P5E_PEX0_STN0_RX_DP<15>")
	)
	(segment
		(start 66.226182 -155.796488)
		(end 66.697098 -156.267404)
		(width 0.1651)
		(layer "In5.Cu")
		(net "P5E_PEX0_STN0_RX_DP<15>")
	)
	(segment
		(start 74.23404 -270.204692)
		(end 74.23404 -271.773904)
		(width 0.1651)
		(layer "In5.Cu")
		(net "P5E_PEX0_STN0_RX_DP<15>")
	)
	(segment
		(start 65.411604 -155.878784)
		(end 65.610486 -155.796488)
		(width 0.1651)
		(layer "In5.Cu")
		(net "P5E_PEX0_STN0_RX_DP<15>")
	)
	(segment
		(start 74.494644 -273.670014)
		(end 74.735436 -273.670014)
		(width 0.1143)
		(layer "In5.Cu")
		(net "P5E_PEX0_STN0_RX_DP<15>")
	)
	(segment
		(start 66.893694 -158.48076)
		(end 66.962782 -158.971488)
		(width 0.1651)
		(layer "In5.Cu")
		(net "P5E_PEX0_STN0_RX_DP<15>")
	)
	(segment
		(start 74.849736 -273.784314)
		(end 74.849736 -274.049744)
		(width 0.1143)
		(layer "In5.Cu")
		(net "P5E_PEX0_STN0_RX_DP<15>")
	)
	(segment
		(start 66.962782 -158.971488)
		(end 67.092068 -159.06877)
		(width 0.1651)
		(layer "In5.Cu")
		(net "P5E_PEX0_STN0_RX_DP<15>")
	)
	(segment
		(start 66.697098 -156.267404)
		(end 66.820542 -157.144212)
		(width 0.1651)
		(layer "In5.Cu")
		(net "P5E_PEX0_STN0_RX_DP<15>")
	)
	(segment
		(start 74.70648 -267.744956)
		(end 74.23404 -270.204692)
		(width 0.1651)
		(layer "In5.Cu")
		(net "P5E_PEX0_STN0_RX_DP<15>")
	)
	(segment
		(start 74.735436 -273.670014)
		(end 74.849736 -273.784314)
		(width 0.1143)
		(layer "In5.Cu")
		(net "P5E_PEX0_STN0_RX_DP<15>")
	)
	(segment
		(start 67.630548 -162.8902)
		(end 74.537316 -261.285482)
		(width 0.1651)
		(layer "In5.Cu")
		(net "P5E_PEX0_STN0_RX_DP<15>")
	)
	(segment
		(start 74.27976 -273.45513)
		(end 74.494644 -273.670014)
		(width 0.1143)
		(layer "In5.Cu")
		(net "P5E_PEX0_STN0_RX_DP<15>")
	)
	(segment
		(start 118.943628 -351.611438)
		(end 118.648988 -351.316798)
		(width 0.13462)
		(layer "F.Cu")
		(net "P5E_PEX1_STN6_TX_C_DN<100>")
	)
	(segment
		(start 118.648988 -350.685354)
		(end 118.969028 -350.365314)
		(width 0.13462)
		(layer "F.Cu")
		(net "P5E_PEX1_STN6_TX_C_DN<100>")
	)
	(segment
		(start 118.648988 -351.316798)
		(end 118.648988 -350.685354)
		(width 0.13462)
		(layer "F.Cu")
		(net "P5E_PEX1_STN6_TX_C_DN<100>")
	)
	(segment
		(start 118.652798 -352.537522)
		(end 118.652798 -351.902268)
		(width 0.1651)
		(layer "In7.Cu")
		(net "P5E_PEX1_STN6_TX_C_DN<100>")
	)
	(segment
		(start 117.098318 -358.799638)
		(end 117.098318 -354.092002)
		(width 0.1651)
		(layer "In7.Cu")
		(net "P5E_PEX1_STN6_TX_C_DN<100>")
	)
	(segment
		(start 118.652798 -351.902268)
		(end 118.943628 -351.611438)
		(width 0.1651)
		(layer "In7.Cu")
		(net "P5E_PEX1_STN6_TX_C_DN<100>")
	)
	(segment
		(start 122.637296 -384.080766)
		(end 122.986038 -384.080766)
		(width 0.1651)
		(layer "In7.Cu")
		(net "P5E_PEX1_STN6_TX_C_DN<100>")
	)
	(segment
		(start 123.569476 -368.48415)
		(end 117.098318 -358.799638)
		(width 0.1651)
		(layer "In7.Cu")
		(net "P5E_PEX1_STN6_TX_C_DN<100>")
	)
	(segment
		(start 117.098318 -354.092002)
		(end 118.652798 -352.537522)
		(width 0.1651)
		(layer "In7.Cu")
		(net "P5E_PEX1_STN6_TX_C_DN<100>")
	)
	(segment
		(start 123.569476 -383.497328)
		(end 123.569476 -368.48415)
		(width 0.1651)
		(layer "In7.Cu")
		(net "P5E_PEX1_STN6_TX_C_DN<100>")
	)
	(segment
		(start 122.986038 -384.080766)
		(end 123.569476 -383.497328)
		(width 0.1651)
		(layer "In7.Cu")
		(net "P5E_PEX1_STN6_TX_C_DN<100>")
	)
	(segment
		(start 122.510042 -384.20802)
		(end 122.637296 -384.080766)
		(width 0.1651)
		(layer "In7.Cu")
		(net "P5E_PEX1_STN6_TX_C_DN<100>")
	)
	(segment
		(start 122.510042 -384.590036)
		(end 122.510042 -384.20802)
		(width 0.1651)
		(layer "In7.Cu")
		(net "P5E_PEX1_STN6_TX_C_DN<100>")
	)
	(segment
		(start 277.742904 -124.755148)
		(end 278.242268 -124.755148)
		(width 0.13462)
		(layer "F.Cu")
		(net "P5E_PEX2_STN1_TX_C_DN<27>")
	)
	(segment
		(start 271.747234 -124.605542)
		(end 272.063972 -124.92228)
		(width 0.13462)
		(layer "F.Cu")
		(net "P5E_PEX2_STN1_TX_C_DN<27>")
	)
	(segment
		(start 272.063972 -124.92228)
		(end 277.575772 -124.92228)
		(width 0.13462)
		(layer "F.Cu")
		(net "P5E_PEX2_STN1_TX_C_DN<27>")
	)
	(segment
		(start 277.575772 -124.92228)
		(end 277.742904 -124.755148)
		(width 0.13462)
		(layer "F.Cu")
		(net "P5E_PEX2_STN1_TX_C_DN<27>")
	)
	(segment
		(start 319.609724 -350.365314)
		(end 319.289684 -350.685354)
		(width 0.13462)
		(layer "F.Cu")
		(net "P5E_PEX2_STN5_TX_C_DN<83>")
	)
	(segment
		(start 319.289684 -351.316798)
		(end 319.584324 -351.611438)
		(width 0.13462)
		(layer "F.Cu")
		(net "P5E_PEX2_STN5_TX_C_DN<83>")
	)
	(segment
		(start 319.289684 -350.685354)
		(end 319.289684 -351.316798)
		(width 0.13462)
		(layer "F.Cu")
		(net "P5E_PEX2_STN5_TX_C_DN<83>")
	)
	(segment
		(start 329.46848 -389.65632)
		(end 327.7235 -387.92404)
		(width 0.1651)
		(layer "In7.Cu")
		(net "P5E_PEX2_STN5_TX_C_DN<83>")
	)
	(segment
		(start 338.090002 -406.308052)
		(end 338.217002 -406.181052)
		(width 0.1651)
		(layer "In7.Cu")
		(net "P5E_PEX2_STN5_TX_C_DN<83>")
	)
	(segment
		(start 338.95284 -395.2748)
		(end 336.10042 -392.4173)
		(width 0.1651)
		(layer "In7.Cu")
		(net "P5E_PEX2_STN5_TX_C_DN<83>")
	)
	(segment
		(start 319.293494 -352.473006)
		(end 319.293494 -351.902268)
		(width 0.1651)
		(layer "In7.Cu")
		(net "P5E_PEX2_STN5_TX_C_DN<83>")
	)
	(segment
		(start 317.739014 -354.027486)
		(end 319.293494 -352.473006)
		(width 0.1651)
		(layer "In7.Cu")
		(net "P5E_PEX2_STN5_TX_C_DN<83>")
	)
	(segment
		(start 319.293494 -351.902268)
		(end 319.584324 -351.611438)
		(width 0.1651)
		(layer "In7.Cu")
		(net "P5E_PEX2_STN5_TX_C_DN<83>")
	)
	(segment
		(start 326.66178 -385.34594)
		(end 317.739014 -358.902)
		(width 0.1651)
		(layer "In7.Cu")
		(net "P5E_PEX2_STN5_TX_C_DN<83>")
	)
	(segment
		(start 327.7235 -387.92404)
		(end 326.66178 -385.34594)
		(width 0.1651)
		(layer "In7.Cu")
		(net "P5E_PEX2_STN5_TX_C_DN<83>")
	)
	(segment
		(start 336.10042 -392.4173)
		(end 329.46848 -389.65632)
		(width 0.1651)
		(layer "In7.Cu")
		(net "P5E_PEX2_STN5_TX_C_DN<83>")
	)
	(segment
		(start 317.739014 -358.902)
		(end 317.739014 -354.027486)
		(width 0.1651)
		(layer "In7.Cu")
		(net "P5E_PEX2_STN5_TX_C_DN<83>")
	)
	(segment
		(start 338.090002 -406.690068)
		(end 338.090002 -406.308052)
		(width 0.1651)
		(layer "In7.Cu")
		(net "P5E_PEX2_STN5_TX_C_DN<83>")
	)
	(segment
		(start 338.764118 -406.181052)
		(end 339.215984 -405.729186)
		(width 0.1651)
		(layer "In7.Cu")
		(net "P5E_PEX2_STN5_TX_C_DN<83>")
	)
	(segment
		(start 339.215984 -405.729186)
		(end 339.215984 -395.90472)
		(width 0.1651)
		(layer "In7.Cu")
		(net "P5E_PEX2_STN5_TX_C_DN<83>")
	)
	(segment
		(start 338.217002 -406.181052)
		(end 338.764118 -406.181052)
		(width 0.1651)
		(layer "In7.Cu")
		(net "P5E_PEX2_STN5_TX_C_DN<83>")
	)
	(segment
		(start 339.215984 -395.90472)
		(end 338.95284 -395.2748)
		(width 0.1651)
		(layer "In7.Cu")
		(net "P5E_PEX2_STN5_TX_C_DN<83>")
	)
	(segment
		(start 358.318816 -34.2265)
		(end 355.806502 -34.2265)
		(width 0.13462)
		(layer "F.Cu")
		(net "P5E_PEX3_STN2_RX_DP<47>")
	)
	(segment
		(start 358.964992 -34.390076)
		(end 358.482392 -34.390076)
		(width 0.13462)
		(layer "F.Cu")
		(net "P5E_PEX3_STN2_RX_DP<47>")
	)
	(segment
		(start 358.482392 -34.390076)
		(end 358.318816 -34.2265)
		(width 0.13462)
		(layer "F.Cu")
		(net "P5E_PEX3_STN2_RX_DP<47>")
	)
	(segment
		(start 355.806502 -34.2265)
		(end 355.510592 -34.52241)
		(width 0.13462)
		(layer "F.Cu")
		(net "P5E_PEX3_STN2_RX_DP<47>")
	)
	(segment
		(start 392.749786 -273.784314)
		(end 392.635486 -273.670014)
		(width 0.1143)
		(layer "In7.Cu")
		(net "P5E_PEX3_STN2_RX_DP<47>")
	)
	(segment
		(start 380.782322 -191.58585)
		(end 380.782068 -191.58585)
		(width 0.1651)
		(layer "In7.Cu")
		(net "P5E_PEX3_STN2_RX_DP<47>")
	)
	(segment
		(start 392.133836 -270.490188)
		(end 392.133582 -270.489934)
		(width 0.1651)
		(layer "In7.Cu")
		(net "P5E_PEX3_STN2_RX_DP<47>")
	)
	(segment
		(start 368.664236 -119.974106)
		(end 363.466634 -102.82682)
		(width 0.1651)
		(layer "In7.Cu")
		(net "P5E_PEX3_STN2_RX_DP<47>")
	)
	(segment
		(start 392.179556 -271.41932)
		(end 392.133836 -271.3736)
		(width 0.1143)
		(layer "In7.Cu")
		(net "P5E_PEX3_STN2_RX_DP<47>")
	)
	(segment
		(start 356.957376 -38.66515)
		(end 356.949756 -38.170104)
		(width 0.1651)
		(layer "In7.Cu")
		(net "P5E_PEX3_STN2_RX_DP<47>")
	)
	(segment
		(start 358.167686 -57.253632)
		(end 358.283002 -49.871376)
		(width 0.1651)
		(layer "In7.Cu")
		(net "P5E_PEX3_STN2_RX_DP<47>")
	)
	(segment
		(start 358.439466 -62.60719)
		(end 358.439466 -60.256166)
		(width 0.1651)
		(layer "In7.Cu")
		(net "P5E_PEX3_STN2_RX_DP<47>")
	)
	(segment
		(start 356.949756 -38.170104)
		(end 356.846378 -38.070028)
		(width 0.1651)
		(layer "In7.Cu")
		(net "P5E_PEX3_STN2_RX_DP<47>")
	)
	(segment
		(start 356.968552 -39.36365)
		(end 356.865174 -39.263574)
		(width 0.1651)
		(layer "In7.Cu")
		(net "P5E_PEX3_STN2_RX_DP<47>")
	)
	(segment
		(start 356.857554 -38.768274)
		(end 356.957376 -38.66515)
		(width 0.1651)
		(layer "In7.Cu")
		(net "P5E_PEX3_STN2_RX_DP<47>")
	)
	(segment
		(start 392.179556 -273.407632)
		(end 392.179556 -271.41932)
		(width 0.1143)
		(layer "In7.Cu")
		(net "P5E_PEX3_STN2_RX_DP<47>")
	)
	(segment
		(start 391.569956 -267.071856)
		(end 391.153396 -263.595612)
		(width 0.1651)
		(layer "In7.Cu")
		(net "P5E_PEX3_STN2_RX_DP<47>")
	)
	(segment
		(start 392.749786 -274.049744)
		(end 392.749786 -273.784314)
		(width 0.1143)
		(layer "In7.Cu")
		(net "P5E_PEX3_STN2_RX_DP<47>")
	)
	(segment
		(start 363.466634 -102.82682)
		(end 363.46638 -102.826058)
		(width 0.1651)
		(layer "In7.Cu")
		(net "P5E_PEX3_STN2_RX_DP<47>")
	)
	(segment
		(start 356.982014 -40.241982)
		(end 356.968552 -39.36365)
		(width 0.1651)
		(layer "In7.Cu")
		(net "P5E_PEX3_STN2_RX_DP<47>")
	)
	(segment
		(start 356.906322 -35.357562)
		(end 356.906322 -35.1028)
		(width 0.1651)
		(layer "In7.Cu")
		(net "P5E_PEX3_STN2_RX_DP<47>")
	)
	(segment
		(start 358.283002 -49.871376)
		(end 356.982014 -40.241982)
		(width 0.1651)
		(layer "In7.Cu")
		(net "P5E_PEX3_STN2_RX_DP<47>")
	)
	(segment
		(start 356.035102 -34.23158)
		(end 355.801422 -34.23158)
		(width 0.1651)
		(layer "In7.Cu")
		(net "P5E_PEX3_STN2_RX_DP<47>")
	)
	(segment
		(start 371.916198 -144.698974)
		(end 368.664236 -119.974106)
		(width 0.1651)
		(layer "In7.Cu")
		(net "P5E_PEX3_STN2_RX_DP<47>")
	)
	(segment
		(start 391.218928 -255.62306)
		(end 389.6487 -238.473234)
		(width 0.1651)
		(layer "In7.Cu")
		(net "P5E_PEX3_STN2_RX_DP<47>")
	)
	(segment
		(start 385.21513 -215.029288)
		(end 380.782322 -191.58585)
		(width 0.1651)
		(layer "In7.Cu")
		(net "P5E_PEX3_STN2_RX_DP<47>")
	)
	(segment
		(start 358.439466 -60.256166)
		(end 358.167686 -57.253632)
		(width 0.1651)
		(layer "In7.Cu")
		(net "P5E_PEX3_STN2_RX_DP<47>")
	)
	(segment
		(start 392.133836 -271.3736)
		(end 392.133836 -271.345152)
		(width 0.1143)
		(layer "In7.Cu")
		(net "P5E_PEX3_STN2_RX_DP<47>")
	)
	(segment
		(start 391.153396 -263.595612)
		(end 391.153396 -262.326374)
		(width 0.1651)
		(layer "In7.Cu")
		(net "P5E_PEX3_STN2_RX_DP<47>")
	)
	(segment
		(start 356.938834 -37.47135)
		(end 356.906322 -35.357562)
		(width 0.1651)
		(layer "In7.Cu")
		(net "P5E_PEX3_STN2_RX_DP<47>")
	)
	(segment
		(start 380.782068 -191.58585)
		(end 371.916198 -144.698974)
		(width 0.1651)
		(layer "In7.Cu")
		(net "P5E_PEX3_STN2_RX_DP<47>")
	)
	(segment
		(start 392.635486 -273.670014)
		(end 392.441938 -273.670014)
		(width 0.1143)
		(layer "In7.Cu")
		(net "P5E_PEX3_STN2_RX_DP<47>")
	)
	(segment
		(start 363.46638 -102.826058)
		(end 358.249474 -85.615018)
		(width 0.1651)
		(layer "In7.Cu")
		(net "P5E_PEX3_STN2_RX_DP<47>")
	)
	(segment
		(start 356.846378 -38.070028)
		(end 356.838758 -37.574474)
		(width 0.1651)
		(layer "In7.Cu")
		(net "P5E_PEX3_STN2_RX_DP<47>")
	)
	(segment
		(start 389.6487 -238.473234)
		(end 385.215384 -215.029288)
		(width 0.1651)
		(layer "In7.Cu")
		(net "P5E_PEX3_STN2_RX_DP<47>")
	)
	(segment
		(start 358.249474 -85.615018)
		(end 358.439466 -62.60719)
		(width 0.1651)
		(layer "In7.Cu")
		(net "P5E_PEX3_STN2_RX_DP<47>")
	)
	(segment
		(start 391.153396 -262.326374)
		(end 391.218928 -255.62306)
		(width 0.1651)
		(layer "In7.Cu")
		(net "P5E_PEX3_STN2_RX_DP<47>")
	)
	(segment
		(start 356.865174 -39.263574)
		(end 356.857554 -38.768274)
		(width 0.1651)
		(layer "In7.Cu")
		(net "P5E_PEX3_STN2_RX_DP<47>")
	)
	(segment
		(start 392.441938 -273.670014)
		(end 392.179556 -273.407632)
		(width 0.1143)
		(layer "In7.Cu")
		(net "P5E_PEX3_STN2_RX_DP<47>")
	)
	(segment
		(start 385.215384 -215.029288)
		(end 385.21513 -215.029288)
		(width 0.1651)
		(layer "In7.Cu")
		(net "P5E_PEX3_STN2_RX_DP<47>")
	)
	(segment
		(start 356.906322 -35.1028)
		(end 356.035102 -34.23158)
		(width 0.1651)
		(layer "In7.Cu")
		(net "P5E_PEX3_STN2_RX_DP<47>")
	)
	(segment
		(start 392.133836 -271.345152)
		(end 392.133836 -270.490188)
		(width 0.1651)
		(layer "In7.Cu")
		(net "P5E_PEX3_STN2_RX_DP<47>")
	)
	(segment
		(start 391.939272 -268.869414)
		(end 391.569956 -267.071856)
		(width 0.1651)
		(layer "In7.Cu")
		(net "P5E_PEX3_STN2_RX_DP<47>")
	)
	(segment
		(start 356.838758 -37.574474)
		(end 356.938834 -37.47135)
		(width 0.1651)
		(layer "In7.Cu")
		(net "P5E_PEX3_STN2_RX_DP<47>")
	)
	(segment
		(start 392.133582 -270.489934)
		(end 391.939272 -268.869414)
		(width 0.1651)
		(layer "In7.Cu")
		(net "P5E_PEX3_STN2_RX_DP<47>")
	)
	(segment
		(start 355.801422 -34.23158)
		(end 355.510592 -34.52241)
		(width 0.1651)
		(layer "In7.Cu")
		(net "P5E_PEX3_STN2_RX_DP<47>")
	)
	(segment
		(start 434.46192 -344.53957)
		(end 434.46192 -345.169998)
		(width 0.13462)
		(layer "F.Cu")
		(net "P5E_PEX3_STN7_TX_C_DP<123>")
	)
	(segment
		(start 434.46192 -345.169998)
		(end 434.166772 -345.465146)
		(width 0.13462)
		(layer "F.Cu")
		(net "P5E_PEX3_STN7_TX_C_DP<123>")
	)
	(segment
		(start 434.141372 -344.219022)
		(end 434.46192 -344.53957)
		(width 0.13462)
		(layer "F.Cu")
		(net "P5E_PEX3_STN7_TX_C_DP<123>")
	)
	(segment
		(start 432.517804 -359.57383)
		(end 432.903122 -358.192324)
		(width 0.1651)
		(layer "In11.Cu")
		(net "P5E_PEX3_STN7_TX_C_DP<123>")
	)
	(segment
		(start 429.393096 -364.568994)
		(end 429.649636 -364.145068)
		(width 0.1651)
		(layer "In11.Cu")
		(net "P5E_PEX3_STN7_TX_C_DP<123>")
	)
	(segment
		(start 431.865532 -360.455972)
		(end 432.122072 -360.031792)
		(width 0.1651)
		(layer "In11.Cu")
		(net "P5E_PEX3_STN7_TX_C_DP<123>")
	)
	(segment
		(start 428.213774 -366.691164)
		(end 428.183548 -366.56899)
		(width 0.1651)
		(layer "In11.Cu")
		(net "P5E_PEX3_STN7_TX_C_DP<123>")
	)
	(segment
		(start 427.835314 -367.145062)
		(end 427.957488 -367.114836)
		(width 0.1651)
		(layer "In11.Cu")
		(net "P5E_PEX3_STN7_TX_C_DP<123>")
	)
	(segment
		(start 432.261518 -359.997502)
		(end 432.517804 -359.57383)
		(width 0.1651)
		(layer "In11.Cu")
		(net "P5E_PEX3_STN7_TX_C_DP<123>")
	)
	(segment
		(start 427.352714 -368.114834)
		(end 427.609 -367.691162)
		(width 0.1651)
		(layer "In11.Cu")
		(net "P5E_PEX3_STN7_TX_C_DP<123>")
	)
	(segment
		(start 427.609 -367.691162)
		(end 427.578774 -367.568988)
		(width 0.1651)
		(layer "In11.Cu")
		(net "P5E_PEX3_STN7_TX_C_DP<123>")
	)
	(segment
		(start 426.933868 -369.618006)
		(end 427.352714 -368.114834)
		(width 0.1651)
		(layer "In11.Cu")
		(net "P5E_PEX3_STN7_TX_C_DP<123>")
	)
	(segment
		(start 428.788322 -365.568992)
		(end 429.044862 -365.145066)
		(width 0.1651)
		(layer "In11.Cu")
		(net "P5E_PEX3_STN7_TX_C_DP<123>")
	)
	(segment
		(start 428.440088 -366.145064)
		(end 428.562262 -366.114838)
		(width 0.1651)
		(layer "In11.Cu")
		(net "P5E_PEX3_STN7_TX_C_DP<123>")
	)
	(segment
		(start 426.089826 -375.872248)
		(end 426.216826 -375.999248)
		(width 0.1651)
		(layer "In11.Cu")
		(net "P5E_PEX3_STN7_TX_C_DP<123>")
	)
	(segment
		(start 429.77181 -364.114842)
		(end 431.899822 -360.595418)
		(width 0.1651)
		(layer "In11.Cu")
		(net "P5E_PEX3_STN7_TX_C_DP<123>")
	)
	(segment
		(start 429.649636 -364.145068)
		(end 429.77181 -364.114842)
		(width 0.1651)
		(layer "In11.Cu")
		(net "P5E_PEX3_STN7_TX_C_DP<123>")
	)
	(segment
		(start 432.903122 -347.764354)
		(end 434.457602 -346.209874)
		(width 0.1651)
		(layer "In11.Cu")
		(net "P5E_PEX3_STN7_TX_C_DP<123>")
	)
	(segment
		(start 428.562262 -366.114838)
		(end 428.818548 -365.691166)
		(width 0.1651)
		(layer "In11.Cu")
		(net "P5E_PEX3_STN7_TX_C_DP<123>")
	)
	(segment
		(start 426.933868 -375.712482)
		(end 426.933868 -369.618006)
		(width 0.1651)
		(layer "In11.Cu")
		(net "P5E_PEX3_STN7_TX_C_DP<123>")
	)
	(segment
		(start 428.183548 -366.56899)
		(end 428.440088 -366.145064)
		(width 0.1651)
		(layer "In11.Cu")
		(net "P5E_PEX3_STN7_TX_C_DP<123>")
	)
	(segment
		(start 431.899822 -360.595418)
		(end 431.865532 -360.455972)
		(width 0.1651)
		(layer "In11.Cu")
		(net "P5E_PEX3_STN7_TX_C_DP<123>")
	)
	(segment
		(start 432.122072 -360.031792)
		(end 432.261518 -359.997502)
		(width 0.1651)
		(layer "In11.Cu")
		(net "P5E_PEX3_STN7_TX_C_DP<123>")
	)
	(segment
		(start 434.457602 -346.209874)
		(end 434.457602 -345.755976)
		(width 0.1651)
		(layer "In11.Cu")
		(net "P5E_PEX3_STN7_TX_C_DP<123>")
	)
	(segment
		(start 426.216826 -375.999248)
		(end 426.647102 -375.999248)
		(width 0.1651)
		(layer "In11.Cu")
		(net "P5E_PEX3_STN7_TX_C_DP<123>")
	)
	(segment
		(start 427.957488 -367.114836)
		(end 428.213774 -366.691164)
		(width 0.1651)
		(layer "In11.Cu")
		(net "P5E_PEX3_STN7_TX_C_DP<123>")
	)
	(segment
		(start 429.423322 -364.691168)
		(end 429.393096 -364.568994)
		(width 0.1651)
		(layer "In11.Cu")
		(net "P5E_PEX3_STN7_TX_C_DP<123>")
	)
	(segment
		(start 428.818548 -365.691166)
		(end 428.788322 -365.568992)
		(width 0.1651)
		(layer "In11.Cu")
		(net "P5E_PEX3_STN7_TX_C_DP<123>")
	)
	(segment
		(start 434.457602 -345.755976)
		(end 434.166772 -345.465146)
		(width 0.1651)
		(layer "In11.Cu")
		(net "P5E_PEX3_STN7_TX_C_DP<123>")
	)
	(segment
		(start 427.578774 -367.568988)
		(end 427.835314 -367.145062)
		(width 0.1651)
		(layer "In11.Cu")
		(net "P5E_PEX3_STN7_TX_C_DP<123>")
	)
	(segment
		(start 432.903122 -358.192324)
		(end 432.903122 -347.764354)
		(width 0.1651)
		(layer "In11.Cu")
		(net "P5E_PEX3_STN7_TX_C_DP<123>")
	)
	(segment
		(start 426.647102 -375.999248)
		(end 426.933868 -375.712482)
		(width 0.1651)
		(layer "In11.Cu")
		(net "P5E_PEX3_STN7_TX_C_DP<123>")
	)
	(segment
		(start 426.089826 -375.490232)
		(end 426.089826 -375.872248)
		(width 0.1651)
		(layer "In11.Cu")
		(net "P5E_PEX3_STN7_TX_C_DP<123>")
	)
	(segment
		(start 429.167036 -365.11484)
		(end 429.423322 -364.691168)
		(width 0.1651)
		(layer "In11.Cu")
		(net "P5E_PEX3_STN7_TX_C_DP<123>")
	)
	(segment
		(start 429.044862 -365.145066)
		(end 429.167036 -365.11484)
		(width 0.1651)
		(layer "In11.Cu")
		(net "P5E_PEX3_STN7_TX_C_DP<123>")
	)
	(segment
		(start 170.35272 -117.5512)
		(end 171.528994 -117.5512)
		(width 0.13208)
		(layer "F.Cu")
		(net "PRSNTB1_NIC2_N")
	)
	(segment
		(start 169.52468 -117.5512)
		(end 170.35272 -117.5512)
		(width 0.13208)
		(layer "F.Cu")
		(net "PRSNTB1_NIC2_N")
	)
	(segment
		(start 166.742364 -118.154958)
		(end 168.920922 -118.154958)
		(width 0.13208)
		(layer "F.Cu")
		(net "PRSNTB1_NIC2_N")
	)
	(segment
		(start 171.528994 -116.5352)
		(end 171.528994 -117.5512)
		(width 0.13208)
		(layer "F.Cu")
		(net "PRSNTB1_NIC2_N")
	)
	(segment
		(start 168.920922 -118.154958)
		(end 169.52468 -117.5512)
		(width 0.13208)
		(layer "F.Cu")
		(net "PRSNTB1_NIC2_N")
	)
	(via
		(at 170.35272 -117.5512)
		(size 0.762)
		(drill 0.381)
		(layers "F.Cu" "B.Cu")
		(net "PRSNTB1_NIC2_N")
	)
	(segment
		(start 68.169536 -145.154904)
		(end 68.006722 -144.99209)
		(width 0.13462)
		(layer "F.Cu")
		(net "P5E_PEX0_STN0_RX_DP<9>")
	)
	(segment
		(start 68.65747 -145.154904)
		(end 68.169536 -145.154904)
		(width 0.13462)
		(layer "F.Cu")
		(net "P5E_PEX0_STN0_RX_DP<9>")
	)
	(segment
		(start 65.498218 -144.99209)
		(end 65.20307 -145.287238)
		(width 0.13462)
		(layer "F.Cu")
		(net "P5E_PEX0_STN0_RX_DP<9>")
	)
	(segment
		(start 68.006722 -144.99209)
		(end 65.498218 -144.99209)
		(width 0.13462)
		(layer "F.Cu")
		(net "P5E_PEX0_STN0_RX_DP<9>")
	)
	(segment
		(start 80.435196 -273.670014)
		(end 80.549496 -273.784314)
		(width 0.1143)
		(layer "In5.Cu")
		(net "P5E_PEX0_STN0_RX_DP<9>")
	)
	(segment
		(start 80.518 -268.260068)
		(end 79.9338 -271.197578)
		(width 0.1651)
		(layer "In5.Cu")
		(net "P5E_PEX0_STN0_RX_DP<9>")
	)
	(segment
		(start 79.97952 -273.45513)
		(end 80.194404 -273.670014)
		(width 0.1143)
		(layer "In5.Cu")
		(net "P5E_PEX0_STN0_RX_DP<9>")
	)
	(segment
		(start 69.22643 -146.637248)
		(end 69.225668 -146.762978)
		(width 0.1651)
		(layer "In5.Cu")
		(net "P5E_PEX0_STN0_RX_DP<9>")
	)
	(segment
		(start 75.585066 -155.437332)
		(end 76.9366 -160.504886)
		(width 0.1651)
		(layer "In5.Cu")
		(net "P5E_PEX0_STN0_RX_DP<9>")
	)
	(segment
		(start 80.518 -261.978394)
		(end 80.518 -268.260068)
		(width 0.1651)
		(layer "In5.Cu")
		(net "P5E_PEX0_STN0_RX_DP<9>")
	)
	(segment
		(start 65.20307 -145.287238)
		(end 65.4939 -144.996408)
		(width 0.1651)
		(layer "In5.Cu")
		(net "P5E_PEX0_STN0_RX_DP<9>")
	)
	(segment
		(start 68.405756 -145.805398)
		(end 68.404994 -145.931128)
		(width 0.1651)
		(layer "In5.Cu")
		(net "P5E_PEX0_STN0_RX_DP<9>")
	)
	(segment
		(start 70.17258 -147.596352)
		(end 72.081644 -150.537418)
		(width 0.1651)
		(layer "In5.Cu")
		(net "P5E_PEX0_STN0_RX_DP<9>")
	)
	(segment
		(start 67.167506 -144.996408)
		(end 67.917568 -145.310352)
		(width 0.1651)
		(layer "In5.Cu")
		(net "P5E_PEX0_STN0_RX_DP<9>")
	)
	(segment
		(start 68.752974 -146.283934)
		(end 68.878704 -146.284696)
		(width 0.1651)
		(layer "In5.Cu")
		(net "P5E_PEX0_STN0_RX_DP<9>")
	)
	(segment
		(start 69.699378 -147.116546)
		(end 70.17258 -147.596352)
		(width 0.1651)
		(layer "In5.Cu")
		(net "P5E_PEX0_STN0_RX_DP<9>")
	)
	(segment
		(start 69.573648 -147.115784)
		(end 69.699378 -147.116546)
		(width 0.1651)
		(layer "In5.Cu")
		(net "P5E_PEX0_STN0_RX_DP<9>")
	)
	(segment
		(start 79.9338 -271.802352)
		(end 79.97952 -271.848072)
		(width 0.1143)
		(layer "In5.Cu")
		(net "P5E_PEX0_STN0_RX_DP<9>")
	)
	(segment
		(start 67.917568 -145.310352)
		(end 68.405756 -145.805398)
		(width 0.1651)
		(layer "In5.Cu")
		(net "P5E_PEX0_STN0_RX_DP<9>")
	)
	(segment
		(start 79.97952 -271.848072)
		(end 79.97952 -273.45513)
		(width 0.1143)
		(layer "In5.Cu")
		(net "P5E_PEX0_STN0_RX_DP<9>")
	)
	(segment
		(start 68.404994 -145.931128)
		(end 68.752974 -146.283934)
		(width 0.1651)
		(layer "In5.Cu")
		(net "P5E_PEX0_STN0_RX_DP<9>")
	)
	(segment
		(start 69.225668 -146.762978)
		(end 69.573648 -147.115784)
		(width 0.1651)
		(layer "In5.Cu")
		(net "P5E_PEX0_STN0_RX_DP<9>")
	)
	(segment
		(start 72.83704 -152.63622)
		(end 75.585066 -155.437332)
		(width 0.1651)
		(layer "In5.Cu")
		(net "P5E_PEX0_STN0_RX_DP<9>")
	)
	(segment
		(start 80.549496 -273.784314)
		(end 80.549496 -274.049744)
		(width 0.1143)
		(layer "In5.Cu")
		(net "P5E_PEX0_STN0_RX_DP<9>")
	)
	(segment
		(start 65.4939 -144.996408)
		(end 67.167506 -144.996408)
		(width 0.1651)
		(layer "In5.Cu")
		(net "P5E_PEX0_STN0_RX_DP<9>")
	)
	(segment
		(start 79.9338 -271.197578)
		(end 79.9338 -271.773904)
		(width 0.1651)
		(layer "In5.Cu")
		(net "P5E_PEX0_STN0_RX_DP<9>")
	)
	(segment
		(start 72.081644 -150.537418)
		(end 72.83704 -152.63622)
		(width 0.1651)
		(layer "In5.Cu")
		(net "P5E_PEX0_STN0_RX_DP<9>")
	)
	(segment
		(start 68.878704 -146.284696)
		(end 69.22643 -146.637248)
		(width 0.1651)
		(layer "In5.Cu")
		(net "P5E_PEX0_STN0_RX_DP<9>")
	)
	(segment
		(start 79.9338 -271.773904)
		(end 79.9338 -271.802352)
		(width 0.1143)
		(layer "In5.Cu")
		(net "P5E_PEX0_STN0_RX_DP<9>")
	)
	(segment
		(start 76.9366 -160.504886)
		(end 80.518 -261.978394)
		(width 0.1651)
		(layer "In5.Cu")
		(net "P5E_PEX0_STN0_RX_DP<9>")
	)
	(segment
		(start 80.194404 -273.670014)
		(end 80.435196 -273.670014)
		(width 0.1143)
		(layer "In5.Cu")
		(net "P5E_PEX0_STN0_RX_DP<9>")
	)
	(segment
		(start 112.431068 -345.170506)
		(end 112.431068 -344.539062)
		(width 0.13462)
		(layer "F.Cu")
		(net "P5E_PEX1_STN6_TX_C_DN<111>")
	)
	(segment
		(start 112.725708 -345.465146)
		(end 112.431068 -345.170506)
		(width 0.13462)
		(layer "F.Cu")
		(net "P5E_PEX1_STN6_TX_C_DN<111>")
	)
	(segment
		(start 112.431068 -344.539062)
		(end 112.751108 -344.219022)
		(width 0.13462)
		(layer "F.Cu")
		(net "P5E_PEX1_STN6_TX_C_DN<111>")
	)
	(segment
		(start 116.037106 -408.981148)
		(end 116.375434 -408.981148)
		(width 0.1651)
		(layer "In13.Cu")
		(net "P5E_PEX1_STN6_TX_C_DN<111>")
	)
	(segment
		(start 112.434878 -346.401136)
		(end 112.434878 -345.755976)
		(width 0.1651)
		(layer "In13.Cu")
		(net "P5E_PEX1_STN6_TX_C_DN<111>")
	)
	(segment
		(start 112.434878 -345.755976)
		(end 112.725708 -345.465146)
		(width 0.1651)
		(layer "In13.Cu")
		(net "P5E_PEX1_STN6_TX_C_DN<111>")
	)
	(segment
		(start 116.500656 -394.177774)
		(end 114.247422 -393.24407)
		(width 0.1651)
		(layer "In13.Cu")
		(net "P5E_PEX1_STN6_TX_C_DN<111>")
	)
	(segment
		(start 108.398056 -387.369558)
		(end 107.493816 -384.111246)
		(width 0.1651)
		(layer "In13.Cu")
		(net "P5E_PEX1_STN6_TX_C_DN<111>")
	)
	(segment
		(start 107.620054 -365.190024)
		(end 110.761018 -348.07525)
		(width 0.1651)
		(layer "In13.Cu")
		(net "P5E_PEX1_STN6_TX_C_DN<111>")
	)
	(segment
		(start 114.247422 -393.24407)
		(end 110.040674 -389.813292)
		(width 0.1651)
		(layer "In13.Cu")
		(net "P5E_PEX1_STN6_TX_C_DN<111>")
	)
	(segment
		(start 115.910106 -409.108148)
		(end 116.037106 -408.981148)
		(width 0.1651)
		(layer "In13.Cu")
		(net "P5E_PEX1_STN6_TX_C_DN<111>")
	)
	(segment
		(start 117.066822 -408.28976)
		(end 117.066822 -394.74394)
		(width 0.1651)
		(layer "In13.Cu")
		(net "P5E_PEX1_STN6_TX_C_DN<111>")
	)
	(segment
		(start 110.761018 -348.07525)
		(end 112.434878 -346.401136)
		(width 0.1651)
		(layer "In13.Cu")
		(net "P5E_PEX1_STN6_TX_C_DN<111>")
	)
	(segment
		(start 117.066822 -394.74394)
		(end 116.500656 -394.177774)
		(width 0.1651)
		(layer "In13.Cu")
		(net "P5E_PEX1_STN6_TX_C_DN<111>")
	)
	(segment
		(start 115.910106 -409.490164)
		(end 115.910106 -409.108148)
		(width 0.1651)
		(layer "In13.Cu")
		(net "P5E_PEX1_STN6_TX_C_DN<111>")
	)
	(segment
		(start 107.493816 -384.111246)
		(end 107.620054 -365.190024)
		(width 0.1651)
		(layer "In13.Cu")
		(net "P5E_PEX1_STN6_TX_C_DN<111>")
	)
	(segment
		(start 116.375434 -408.981148)
		(end 117.066822 -408.28976)
		(width 0.1651)
		(layer "In13.Cu")
		(net "P5E_PEX1_STN6_TX_C_DN<111>")
	)
	(segment
		(start 110.040674 -389.813292)
		(end 108.398056 -387.369558)
		(width 0.1651)
		(layer "In13.Cu")
		(net "P5E_PEX1_STN6_TX_C_DN<111>")
	)
	(segment
		(start 283.492194 -99.8728)
		(end 283.319982 -100.045012)
		(width 0.13462)
		(layer "F.Cu")
		(net "P5E_PEX2_STN1_RX_DN<16>")
	)
	(segment
		(start 285.993332 -99.8728)
		(end 283.492194 -99.8728)
		(width 0.13462)
		(layer "F.Cu")
		(net "P5E_PEX2_STN1_RX_DN<16>")
	)
	(segment
		(start 286.296862 -100.17633)
		(end 285.993332 -99.8728)
		(width 0.13462)
		(layer "F.Cu")
		(net "P5E_PEX2_STN1_RX_DN<16>")
	)
	(segment
		(start 283.319982 -100.045012)
		(end 282.842462 -100.045012)
		(width 0.13462)
		(layer "F.Cu")
		(net "P5E_PEX2_STN1_RX_DN<16>")
	)
	(segment
		(start 271.398238 -107.989878)
		(end 268.962632 -109.605572)
		(width 0.1651)
		(layer "In5.Cu")
		(net "P5E_PEX2_STN1_RX_DN<16>")
	)
	(segment
		(start 291.573458 -273.47926)
		(end 291.735256 -273.47926)
		(width 0.1143)
		(layer "In5.Cu")
		(net "P5E_PEX2_STN1_RX_DN<16>")
	)
	(segment
		(start 268.962632 -109.605572)
		(end 268.285722 -110.21695)
		(width 0.1651)
		(layer "In5.Cu")
		(net "P5E_PEX2_STN1_RX_DN<16>")
	)
	(segment
		(start 291.849556 -273.36496)
		(end 291.849556 -273.09953)
		(width 0.1143)
		(layer "In5.Cu")
		(net "P5E_PEX2_STN1_RX_DN<16>")
	)
	(segment
		(start 282.997148 -100.466144)
		(end 282.946094 -100.61956)
		(width 0.1651)
		(layer "In5.Cu")
		(net "P5E_PEX2_STN1_RX_DN<16>")
	)
	(segment
		(start 266.655804 -110.87989)
		(end 266.269216 -111.275876)
		(width 0.1651)
		(layer "In5.Cu")
		(net "P5E_PEX2_STN1_RX_DN<16>")
	)
	(segment
		(start 282.502864 -100.841302)
		(end 282.349448 -100.790248)
		(width 0.1651)
		(layer "In5.Cu")
		(net "P5E_PEX2_STN1_RX_DN<16>")
	)
	(segment
		(start 281.258772 -101.335586)
		(end 280.815796 -101.55682)
		(width 0.1651)
		(layer "In5.Cu")
		(net "P5E_PEX2_STN1_RX_DN<16>")
	)
	(segment
		(start 291.47008 -271.599914)
		(end 291.47008 -273.375882)
		(width 0.1143)
		(layer "In5.Cu")
		(net "P5E_PEX2_STN1_RX_DN<16>")
	)
	(segment
		(start 274.222464 -105.893108)
		(end 274.061936 -105.87482)
		(width 0.1651)
		(layer "In5.Cu")
		(net "P5E_PEX2_STN1_RX_DN<16>")
	)
	(segment
		(start 291.5158 -271.525746)
		(end 291.5158 -271.554194)
		(width 0.1143)
		(layer "In5.Cu")
		(net "P5E_PEX2_STN1_RX_DN<16>")
	)
	(segment
		(start 275.565362 -104.826562)
		(end 275.17725 -105.134664)
		(width 0.1651)
		(layer "In5.Cu")
		(net "P5E_PEX2_STN1_RX_DN<16>")
	)
	(segment
		(start 291.5158 -270.066262)
		(end 291.5158 -271.525746)
		(width 0.1651)
		(layer "In5.Cu")
		(net "P5E_PEX2_STN1_RX_DN<16>")
	)
	(segment
		(start 286.006032 -99.8855)
		(end 284.15869 -99.8855)
		(width 0.1651)
		(layer "In5.Cu")
		(net "P5E_PEX2_STN1_RX_DN<16>")
	)
	(segment
		(start 275.971508 -104.357932)
		(end 275.583904 -104.66578)
		(width 0.1651)
		(layer "In5.Cu")
		(net "P5E_PEX2_STN1_RX_DN<16>")
	)
	(segment
		(start 279.07742 -102.426262)
		(end 278.634444 -102.647496)
		(width 0.1651)
		(layer "In5.Cu")
		(net "P5E_PEX2_STN1_RX_DN<16>")
	)
	(segment
		(start 286.296862 -100.17633)
		(end 286.006032 -99.8855)
		(width 0.1651)
		(layer "In5.Cu")
		(net "P5E_PEX2_STN1_RX_DN<16>")
	)
	(segment
		(start 275.17725 -105.134664)
		(end 275.016722 -105.116376)
		(width 0.1651)
		(layer "In5.Cu")
		(net "P5E_PEX2_STN1_RX_DN<16>")
	)
	(segment
		(start 281.906472 -101.011482)
		(end 281.855418 -101.164898)
		(width 0.1651)
		(layer "In5.Cu")
		(net "P5E_PEX2_STN1_RX_DN<16>")
	)
	(segment
		(start 280.815796 -101.55682)
		(end 280.764742 -101.710236)
		(width 0.1651)
		(layer "In5.Cu")
		(net "P5E_PEX2_STN1_RX_DN<16>")
	)
	(segment
		(start 262.419084 -166.005764)
		(end 291.5158 -270.066262)
		(width 0.1651)
		(layer "In5.Cu")
		(net "P5E_PEX2_STN1_RX_DN<16>")
	)
	(segment
		(start 266.269216 -111.275876)
		(end 263.492488 -119.720106)
		(width 0.1651)
		(layer "In5.Cu")
		(net "P5E_PEX2_STN1_RX_DN<16>")
	)
	(segment
		(start 275.016722 -105.116376)
		(end 274.628864 -105.424224)
		(width 0.1651)
		(layer "In5.Cu")
		(net "P5E_PEX2_STN1_RX_DN<16>")
	)
	(segment
		(start 281.412188 -101.38664)
		(end 281.258772 -101.335586)
		(width 0.1651)
		(layer "In5.Cu")
		(net "P5E_PEX2_STN1_RX_DN<16>")
	)
	(segment
		(start 277.986744 -102.9716)
		(end 277.259288 -103.335074)
		(width 0.1651)
		(layer "In5.Cu")
		(net "P5E_PEX2_STN1_RX_DN<16>")
	)
	(segment
		(start 276.132036 -104.37622)
		(end 275.971508 -104.357932)
		(width 0.1651)
		(layer "In5.Cu")
		(net "P5E_PEX2_STN1_RX_DN<16>")
	)
	(segment
		(start 281.855418 -101.164898)
		(end 281.412188 -101.38664)
		(width 0.1651)
		(layer "In5.Cu")
		(net "P5E_PEX2_STN1_RX_DN<16>")
	)
	(segment
		(start 274.628864 -105.424224)
		(end 274.610576 -105.584752)
		(width 0.1651)
		(layer "In5.Cu")
		(net "P5E_PEX2_STN1_RX_DN<16>")
	)
	(segment
		(start 284.15869 -99.8855)
		(end 282.997148 -100.466144)
		(width 0.1651)
		(layer "In5.Cu")
		(net "P5E_PEX2_STN1_RX_DN<16>")
	)
	(segment
		(start 261.168896 -159.535368)
		(end 262.419084 -166.005764)
		(width 0.1651)
		(layer "In5.Cu")
		(net "P5E_PEX2_STN1_RX_DN<16>")
	)
	(segment
		(start 274.061936 -105.87482)
		(end 271.398238 -107.989878)
		(width 0.1651)
		(layer "In5.Cu")
		(net "P5E_PEX2_STN1_RX_DN<16>")
	)
	(segment
		(start 263.492488 -119.720106)
		(end 261.878064 -126.400306)
		(width 0.1651)
		(layer "In5.Cu")
		(net "P5E_PEX2_STN1_RX_DN<16>")
	)
	(segment
		(start 276.53869 -103.907336)
		(end 276.520148 -104.068118)
		(width 0.1651)
		(layer "In5.Cu")
		(net "P5E_PEX2_STN1_RX_DN<16>")
	)
	(segment
		(start 291.47008 -273.375882)
		(end 291.573458 -273.47926)
		(width 0.1143)
		(layer "In5.Cu")
		(net "P5E_PEX2_STN1_RX_DN<16>")
	)
	(segment
		(start 280.764742 -101.710236)
		(end 280.321512 -101.931978)
		(width 0.1651)
		(layer "In5.Cu")
		(net "P5E_PEX2_STN1_RX_DN<16>")
	)
	(segment
		(start 279.674066 -102.255574)
		(end 279.230836 -102.477316)
		(width 0.1651)
		(layer "In5.Cu")
		(net "P5E_PEX2_STN1_RX_DN<16>")
	)
	(segment
		(start 261.878064 -126.400306)
		(end 260.496812 -149.9362)
		(width 0.1651)
		(layer "In5.Cu")
		(net "P5E_PEX2_STN1_RX_DN<16>")
	)
	(segment
		(start 291.735256 -273.47926)
		(end 291.849556 -273.36496)
		(width 0.1143)
		(layer "In5.Cu")
		(net "P5E_PEX2_STN1_RX_DN<16>")
	)
	(segment
		(start 280.168096 -101.880924)
		(end 279.72512 -102.102158)
		(width 0.1651)
		(layer "In5.Cu")
		(net "P5E_PEX2_STN1_RX_DN<16>")
	)
	(segment
		(start 275.583904 -104.66578)
		(end 275.565362 -104.826562)
		(width 0.1651)
		(layer "In5.Cu")
		(net "P5E_PEX2_STN1_RX_DN<16>")
	)
	(segment
		(start 268.285722 -110.21695)
		(end 266.655804 -110.87989)
		(width 0.1651)
		(layer "In5.Cu")
		(net "P5E_PEX2_STN1_RX_DN<16>")
	)
	(segment
		(start 274.610576 -105.584752)
		(end 274.222464 -105.893108)
		(width 0.1651)
		(layer "In5.Cu")
		(net "P5E_PEX2_STN1_RX_DN<16>")
	)
	(segment
		(start 260.496812 -149.9362)
		(end 261.168896 -159.535368)
		(width 0.1651)
		(layer "In5.Cu")
		(net "P5E_PEX2_STN1_RX_DN<16>")
	)
	(segment
		(start 282.349448 -100.790248)
		(end 281.906472 -101.011482)
		(width 0.1651)
		(layer "In5.Cu")
		(net "P5E_PEX2_STN1_RX_DN<16>")
	)
	(segment
		(start 278.634444 -102.647496)
		(end 278.58339 -102.800912)
		(width 0.1651)
		(layer "In5.Cu")
		(net "P5E_PEX2_STN1_RX_DN<16>")
	)
	(segment
		(start 282.946094 -100.61956)
		(end 282.502864 -100.841302)
		(width 0.1651)
		(layer "In5.Cu")
		(net "P5E_PEX2_STN1_RX_DN<16>")
	)
	(segment
		(start 279.230836 -102.477316)
		(end 279.07742 -102.426262)
		(width 0.1651)
		(layer "In5.Cu")
		(net "P5E_PEX2_STN1_RX_DN<16>")
	)
	(segment
		(start 276.520148 -104.068118)
		(end 276.132036 -104.37622)
		(width 0.1651)
		(layer "In5.Cu")
		(net "P5E_PEX2_STN1_RX_DN<16>")
	)
	(segment
		(start 278.14016 -103.022654)
		(end 277.986744 -102.9716)
		(width 0.1651)
		(layer "In5.Cu")
		(net "P5E_PEX2_STN1_RX_DN<16>")
	)
	(segment
		(start 279.72512 -102.102158)
		(end 279.674066 -102.255574)
		(width 0.1651)
		(layer "In5.Cu")
		(net "P5E_PEX2_STN1_RX_DN<16>")
	)
	(segment
		(start 277.259288 -103.335074)
		(end 276.53869 -103.907336)
		(width 0.1651)
		(layer "In5.Cu")
		(net "P5E_PEX2_STN1_RX_DN<16>")
	)
	(segment
		(start 291.5158 -271.554194)
		(end 291.47008 -271.599914)
		(width 0.1143)
		(layer "In5.Cu")
		(net "P5E_PEX2_STN1_RX_DN<16>")
	)
	(segment
		(start 280.321512 -101.931978)
		(end 280.168096 -101.880924)
		(width 0.1651)
		(layer "In5.Cu")
		(net "P5E_PEX2_STN1_RX_DN<16>")
	)
	(segment
		(start 278.58339 -102.800912)
		(end 278.14016 -103.022654)
		(width 0.1651)
		(layer "In5.Cu")
		(net "P5E_PEX2_STN1_RX_DN<16>")
	)
	(segment
		(start 293.13378 -319.8876)
		(end 293.1795 -319.84188)
		(width 0.1143)
		(layer "In9.Cu")
		(net "P5E_PEX2_STN5_RX_DP<83>")
	)
	(segment
		(start 339.930994 -394.061188)
		(end 340.346792 -393.79144)
		(width 0.1651)
		(layer "In9.Cu")
		(net "P5E_PEX2_STN5_RX_DP<83>")
	)
	(segment
		(start 340.911434 -393.425172)
		(end 341.327232 -393.155424)
		(width 0.1651)
		(layer "In9.Cu")
		(net "P5E_PEX2_STN5_RX_DP<83>")
	)
	(segment
		(start 294.118538 -321.974718)
		(end 293.13378 -320.50101)
		(width 0.1651)
		(layer "In9.Cu")
		(net "P5E_PEX2_STN5_RX_DP<83>")
	)
	(segment
		(start 352.581464 -388.264146)
		(end 353.185222 -387.82752)
		(width 0.1651)
		(layer "In9.Cu")
		(net "P5E_PEX2_STN5_RX_DP<83>")
	)
	(segment
		(start 293.1795 -319.84188)
		(end 293.1795 -318.355218)
		(width 0.1143)
		(layer "In9.Cu")
		(net "P5E_PEX2_STN5_RX_DP<83>")
	)
	(segment
		(start 338.090002 -397.59001)
		(end 338.090002 -397.97228)
		(width 0.1651)
		(layer "In9.Cu")
		(net "P5E_PEX2_STN5_RX_DP<83>")
	)
	(segment
		(start 341.891874 -392.789156)
		(end 342.307672 -392.519408)
		(width 0.1651)
		(layer "In9.Cu")
		(net "P5E_PEX2_STN5_RX_DP<83>")
	)
	(segment
		(start 338.217002 -398.09928)
		(end 338.647278 -398.09928)
		(width 0.1651)
		(layer "In9.Cu")
		(net "P5E_PEX2_STN5_RX_DP<83>")
	)
	(segment
		(start 342.430608 -392.54557)
		(end 343.67597 -391.73785)
		(width 0.1651)
		(layer "In9.Cu")
		(net "P5E_PEX2_STN5_RX_DP<83>")
	)
	(segment
		(start 354.401628 -386.103114)
		(end 354.68306 -370.769642)
		(width 0.1651)
		(layer "In9.Cu")
		(net "P5E_PEX2_STN5_RX_DP<83>")
	)
	(segment
		(start 353.120198 -366.948212)
		(end 347.523054 -362.146596)
		(width 0.1651)
		(layer "In9.Cu")
		(net "P5E_PEX2_STN5_RX_DP<83>")
	)
	(segment
		(start 341.327232 -393.155424)
		(end 341.450168 -393.181586)
		(width 0.1651)
		(layer "In9.Cu")
		(net "P5E_PEX2_STN5_RX_DP<83>")
	)
	(segment
		(start 353.185222 -387.82752)
		(end 354.073714 -386.7531)
		(width 0.1651)
		(layer "In9.Cu")
		(net "P5E_PEX2_STN5_RX_DP<83>")
	)
	(segment
		(start 347.523054 -362.146596)
		(end 342.757252 -359.056432)
		(width 0.1651)
		(layer "In9.Cu")
		(net "P5E_PEX2_STN5_RX_DP<83>")
	)
	(segment
		(start 340.885018 -393.548108)
		(end 340.911434 -393.425172)
		(width 0.1651)
		(layer "In9.Cu")
		(net "P5E_PEX2_STN5_RX_DP<83>")
	)
	(segment
		(start 354.68306 -370.769642)
		(end 354.207826 -368.865404)
		(width 0.1651)
		(layer "In9.Cu")
		(net "P5E_PEX2_STN5_RX_DP<83>")
	)
	(segment
		(start 338.934044 -397.812514)
		(end 338.934044 -395.213332)
		(width 0.1651)
		(layer "In9.Cu")
		(net "P5E_PEX2_STN5_RX_DP<83>")
	)
	(segment
		(start 341.801958 -340.6394)
		(end 297.13555 -324.301866)
		(width 0.1651)
		(layer "In9.Cu")
		(net "P5E_PEX2_STN5_RX_DP<83>")
	)
	(segment
		(start 338.934044 -395.213332)
		(end 339.146388 -394.676122)
		(width 0.1651)
		(layer "In9.Cu")
		(net "P5E_PEX2_STN5_RX_DP<83>")
	)
	(segment
		(start 341.865458 -392.912092)
		(end 341.891874 -392.789156)
		(width 0.1651)
		(layer "In9.Cu")
		(net "P5E_PEX2_STN5_RX_DP<83>")
	)
	(segment
		(start 339.146388 -394.676122)
		(end 339.904832 -394.184124)
		(width 0.1651)
		(layer "In9.Cu")
		(net "P5E_PEX2_STN5_RX_DP<83>")
	)
	(segment
		(start 339.904832 -394.184124)
		(end 339.930994 -394.061188)
		(width 0.1651)
		(layer "In9.Cu")
		(net "P5E_PEX2_STN5_RX_DP<83>")
	)
	(segment
		(start 342.757252 -359.056432)
		(end 342.328754 -358.627934)
		(width 0.1651)
		(layer "In9.Cu")
		(net "P5E_PEX2_STN5_RX_DP<83>")
	)
	(segment
		(start 293.66083 -318.129666)
		(end 293.74973 -318.040766)
		(width 0.1143)
		(layer "In9.Cu")
		(net "P5E_PEX2_STN5_RX_DP<83>")
	)
	(segment
		(start 354.073714 -386.7531)
		(end 354.401628 -386.103114)
		(width 0.1651)
		(layer "In9.Cu")
		(net "P5E_PEX2_STN5_RX_DP<83>")
	)
	(segment
		(start 293.74973 -318.040766)
		(end 293.74973 -317.749936)
		(width 0.1143)
		(layer "In9.Cu")
		(net "P5E_PEX2_STN5_RX_DP<83>")
	)
	(segment
		(start 343.67597 -391.73785)
		(end 352.581464 -388.264146)
		(width 0.1651)
		(layer "In9.Cu")
		(net "P5E_PEX2_STN5_RX_DP<83>")
	)
	(segment
		(start 342.328754 -342.203786)
		(end 341.801958 -340.6394)
		(width 0.1651)
		(layer "In9.Cu")
		(net "P5E_PEX2_STN5_RX_DP<83>")
	)
	(segment
		(start 338.090002 -397.97228)
		(end 338.217002 -398.09928)
		(width 0.1651)
		(layer "In9.Cu")
		(net "P5E_PEX2_STN5_RX_DP<83>")
	)
	(segment
		(start 340.346792 -393.79144)
		(end 340.469728 -393.817602)
		(width 0.1651)
		(layer "In9.Cu")
		(net "P5E_PEX2_STN5_RX_DP<83>")
	)
	(segment
		(start 295.229026 -323.085206)
		(end 294.118538 -321.974718)
		(width 0.1651)
		(layer "In9.Cu")
		(net "P5E_PEX2_STN5_RX_DP<83>")
	)
	(segment
		(start 340.469728 -393.817602)
		(end 340.885018 -393.548108)
		(width 0.1651)
		(layer "In9.Cu")
		(net "P5E_PEX2_STN5_RX_DP<83>")
	)
	(segment
		(start 341.450168 -393.181586)
		(end 341.865458 -392.912092)
		(width 0.1651)
		(layer "In9.Cu")
		(net "P5E_PEX2_STN5_RX_DP<83>")
	)
	(segment
		(start 338.647278 -398.09928)
		(end 338.934044 -397.812514)
		(width 0.1651)
		(layer "In9.Cu")
		(net "P5E_PEX2_STN5_RX_DP<83>")
	)
	(segment
		(start 293.405052 -318.129666)
		(end 293.66083 -318.129666)
		(width 0.1143)
		(layer "In9.Cu")
		(net "P5E_PEX2_STN5_RX_DP<83>")
	)
	(segment
		(start 342.328754 -358.627934)
		(end 342.328754 -342.203786)
		(width 0.1651)
		(layer "In9.Cu")
		(net "P5E_PEX2_STN5_RX_DP<83>")
	)
	(segment
		(start 293.13378 -320.50101)
		(end 293.13378 -319.916048)
		(width 0.1651)
		(layer "In9.Cu")
		(net "P5E_PEX2_STN5_RX_DP<83>")
	)
	(segment
		(start 342.307672 -392.519408)
		(end 342.430608 -392.54557)
		(width 0.1651)
		(layer "In9.Cu")
		(net "P5E_PEX2_STN5_RX_DP<83>")
	)
	(segment
		(start 297.13555 -324.301866)
		(end 295.229026 -323.085206)
		(width 0.1651)
		(layer "In9.Cu")
		(net "P5E_PEX2_STN5_RX_DP<83>")
	)
	(segment
		(start 293.13378 -319.916048)
		(end 293.13378 -319.8876)
		(width 0.1143)
		(layer "In9.Cu")
		(net "P5E_PEX2_STN5_RX_DP<83>")
	)
	(segment
		(start 293.1795 -318.355218)
		(end 293.405052 -318.129666)
		(width 0.1143)
		(layer "In9.Cu")
		(net "P5E_PEX2_STN5_RX_DP<83>")
	)
	(segment
		(start 354.207826 -368.865404)
		(end 353.120198 -366.948212)
		(width 0.1651)
		(layer "In9.Cu")
		(net "P5E_PEX2_STN5_RX_DP<83>")
	)
	(segment
		(start 410.964888 -30.190186)
		(end 410.487368 -30.190186)
		(width 0.13462)
		(layer "F.Cu")
		(net "P5E_PEX3_STN2_RX_DN<37>")
	)
	(segment
		(start 410.319474 -30.35808)
		(end 407.8097 -30.35808)
		(width 0.13462)
		(layer "F.Cu")
		(net "P5E_PEX3_STN2_RX_DN<37>")
	)
	(segment
		(start 410.487368 -30.190186)
		(end 410.319474 -30.35808)
		(width 0.13462)
		(layer "F.Cu")
		(net "P5E_PEX3_STN2_RX_DN<37>")
	)
	(segment
		(start 407.8097 -30.35808)
		(end 407.510488 -30.058868)
		(width 0.13462)
		(layer "F.Cu")
		(net "P5E_PEX3_STN2_RX_DN<37>")
	)
	(segment
		(start 411.688026 -35.00755)
		(end 411.71241 -31.973012)
		(width 0.1651)
		(layer "In7.Cu")
		(net "P5E_PEX3_STN2_RX_DN<37>")
	)
	(segment
		(start 411.163262 -37.96284)
		(end 411.688026 -35.00755)
		(width 0.1651)
		(layer "In7.Cu")
		(net "P5E_PEX3_STN2_RX_DN<37>")
	)
	(segment
		(start 401.915884 -271.3736)
		(end 401.915884 -271.345152)
		(width 0.1143)
		(layer "In7.Cu")
		(net "P5E_PEX3_STN2_RX_DN<37>")
	)
	(segment
		(start 401.870164 -271.41932)
		(end 401.915884 -271.3736)
		(width 0.1143)
		(layer "In7.Cu")
		(net "P5E_PEX3_STN2_RX_DN<37>")
	)
	(segment
		(start 402.04644 -264.905998)
		(end 412.420562 -68.498974)
		(width 0.1651)
		(layer "In7.Cu")
		(net "P5E_PEX3_STN2_RX_DN<37>")
	)
	(segment
		(start 402.249894 -273.099784)
		(end 402.249894 -273.365214)
		(width 0.1143)
		(layer "In7.Cu")
		(net "P5E_PEX3_STN2_RX_DN<37>")
	)
	(segment
		(start 401.915884 -271.345152)
		(end 401.915884 -266.392152)
		(width 0.1651)
		(layer "In7.Cu")
		(net "P5E_PEX3_STN2_RX_DN<37>")
	)
	(segment
		(start 411.71241 -31.973012)
		(end 410.089096 -30.349698)
		(width 0.1651)
		(layer "In7.Cu")
		(net "P5E_PEX3_STN2_RX_DN<37>")
	)
	(segment
		(start 407.801318 -30.349698)
		(end 407.510488 -30.058868)
		(width 0.1651)
		(layer "In7.Cu")
		(net "P5E_PEX3_STN2_RX_DN<37>")
	)
	(segment
		(start 401.915884 -266.392152)
		(end 402.04644 -264.905998)
		(width 0.1651)
		(layer "In7.Cu")
		(net "P5E_PEX3_STN2_RX_DN<37>")
	)
	(segment
		(start 410.089096 -30.349698)
		(end 407.801318 -30.349698)
		(width 0.1651)
		(layer "In7.Cu")
		(net "P5E_PEX3_STN2_RX_DN<37>")
	)
	(segment
		(start 402.249894 -273.365214)
		(end 402.135594 -273.479514)
		(width 0.1143)
		(layer "In7.Cu")
		(net "P5E_PEX3_STN2_RX_DN<37>")
	)
	(segment
		(start 411.23362 -39.962328)
		(end 411.184598 -39.308786)
		(width 0.1651)
		(layer "In7.Cu")
		(net "P5E_PEX3_STN2_RX_DN<37>")
	)
	(segment
		(start 412.604966 -50.110644)
		(end 411.23362 -39.962328)
		(width 0.1651)
		(layer "In7.Cu")
		(net "P5E_PEX3_STN2_RX_DN<37>")
	)
	(segment
		(start 411.184598 -39.308786)
		(end 411.163262 -37.96284)
		(width 0.1651)
		(layer "In7.Cu")
		(net "P5E_PEX3_STN2_RX_DN<37>")
	)
	(segment
		(start 412.420562 -68.498974)
		(end 412.604966 -50.110644)
		(width 0.1651)
		(layer "In7.Cu")
		(net "P5E_PEX3_STN2_RX_DN<37>")
	)
	(segment
		(start 402.135594 -273.479514)
		(end 402.02104 -273.479514)
		(width 0.1143)
		(layer "In7.Cu")
		(net "P5E_PEX3_STN2_RX_DN<37>")
	)
	(segment
		(start 401.870164 -273.328638)
		(end 401.870164 -271.41932)
		(width 0.1143)
		(layer "In7.Cu")
		(net "P5E_PEX3_STN2_RX_DN<37>")
	)
	(segment
		(start 402.02104 -273.479514)
		(end 401.870164 -273.328638)
		(width 0.1143)
		(layer "In7.Cu")
		(net "P5E_PEX3_STN2_RX_DN<37>")
	)
	(segment
		(start 422.02608 -357.462582)
		(end 421.730932 -357.75773)
		(width 0.13462)
		(layer "F.Cu")
		(net "P5E_PEX3_STN7_TX_C_DP<118>")
	)
	(segment
		(start 421.705532 -356.511606)
		(end 422.02608 -356.832154)
		(width 0.13462)
		(layer "F.Cu")
		(net "P5E_PEX3_STN7_TX_C_DP<118>")
	)
	(segment
		(start 422.02608 -356.832154)
		(end 422.02608 -357.462582)
		(width 0.13462)
		(layer "F.Cu")
		(net "P5E_PEX3_STN7_TX_C_DP<118>")
	)
	(segment
		(start 422.021762 -358.8258)
		(end 422.021762 -358.04856)
		(width 0.1651)
		(layer "In11.Cu")
		(net "P5E_PEX3_STN7_TX_C_DP<118>")
	)
	(segment
		(start 427.031912 -391.092182)
		(end 426.986446 -390.956038)
		(width 0.1651)
		(layer "In11.Cu")
		(net "P5E_PEX3_STN7_TX_C_DP<118>")
	)
	(segment
		(start 426.986446 -390.956038)
		(end 417.691824 -386.326126)
		(width 0.1651)
		(layer "In11.Cu")
		(net "P5E_PEX3_STN7_TX_C_DP<118>")
	)
	(segment
		(start 430.19218 -392.55319)
		(end 429.74895 -392.332464)
		(width 0.1651)
		(layer "In11.Cu")
		(net "P5E_PEX3_STN7_TX_C_DP<118>")
	)
	(segment
		(start 429.123602 -392.020806)
		(end 428.680372 -391.80008)
		(width 0.1651)
		(layer "In11.Cu")
		(net "P5E_PEX3_STN7_TX_C_DP<118>")
	)
	(segment
		(start 432.689762 -400.772122)
		(end 432.816762 -400.899122)
		(width 0.1651)
		(layer "In11.Cu")
		(net "P5E_PEX3_STN7_TX_C_DP<118>")
	)
	(segment
		(start 428.544228 -391.8458)
		(end 428.10049 -391.624566)
		(width 0.1651)
		(layer "In11.Cu")
		(net "P5E_PEX3_STN7_TX_C_DP<118>")
	)
	(segment
		(start 427.47565 -391.313416)
		(end 427.031912 -391.092182)
		(width 0.1651)
		(layer "In11.Cu")
		(net "P5E_PEX3_STN7_TX_C_DP<118>")
	)
	(segment
		(start 432.021742 -393.464542)
		(end 430.817782 -392.864848)
		(width 0.1651)
		(layer "In11.Cu")
		(net "P5E_PEX3_STN7_TX_C_DP<118>")
	)
	(segment
		(start 429.612806 -392.378184)
		(end 429.169068 -392.15695)
		(width 0.1651)
		(layer "In11.Cu")
		(net "P5E_PEX3_STN7_TX_C_DP<118>")
	)
	(segment
		(start 429.74895 -392.332464)
		(end 429.612806 -392.378184)
		(width 0.1651)
		(layer "In11.Cu")
		(net "P5E_PEX3_STN7_TX_C_DP<118>")
	)
	(segment
		(start 430.817782 -392.864848)
		(end 430.681384 -392.910314)
		(width 0.1651)
		(layer "In11.Cu")
		(net "P5E_PEX3_STN7_TX_C_DP<118>")
	)
	(segment
		(start 428.680372 -391.80008)
		(end 428.544228 -391.8458)
		(width 0.1651)
		(layer "In11.Cu")
		(net "P5E_PEX3_STN7_TX_C_DP<118>")
	)
	(segment
		(start 432.816762 -400.899122)
		(end 433.247038 -400.899122)
		(width 0.1651)
		(layer "In11.Cu")
		(net "P5E_PEX3_STN7_TX_C_DP<118>")
	)
	(segment
		(start 416.989006 -383.349246)
		(end 417.14166 -369.084606)
		(width 0.1651)
		(layer "In11.Cu")
		(net "P5E_PEX3_STN7_TX_C_DP<118>")
	)
	(segment
		(start 422.021762 -358.04856)
		(end 421.730932 -357.75773)
		(width 0.1651)
		(layer "In11.Cu")
		(net "P5E_PEX3_STN7_TX_C_DP<118>")
	)
	(segment
		(start 433.533804 -400.612356)
		(end 433.533804 -394.976604)
		(width 0.1651)
		(layer "In11.Cu")
		(net "P5E_PEX3_STN7_TX_C_DP<118>")
	)
	(segment
		(start 432.689762 -400.390106)
		(end 432.689762 -400.772122)
		(width 0.1651)
		(layer "In11.Cu")
		(net "P5E_PEX3_STN7_TX_C_DP<118>")
	)
	(segment
		(start 417.691824 -386.326126)
		(end 417.15944 -385.074922)
		(width 0.1651)
		(layer "In11.Cu")
		(net "P5E_PEX3_STN7_TX_C_DP<118>")
	)
	(segment
		(start 430.681384 -392.910314)
		(end 430.2379 -392.689334)
		(width 0.1651)
		(layer "In11.Cu")
		(net "P5E_PEX3_STN7_TX_C_DP<118>")
	)
	(segment
		(start 429.169068 -392.15695)
		(end 429.123602 -392.020806)
		(width 0.1651)
		(layer "In11.Cu")
		(net "P5E_PEX3_STN7_TX_C_DP<118>")
	)
	(segment
		(start 417.15944 -385.074922)
		(end 416.989006 -383.349246)
		(width 0.1651)
		(layer "In11.Cu")
		(net "P5E_PEX3_STN7_TX_C_DP<118>")
	)
	(segment
		(start 427.611794 -391.267696)
		(end 427.47565 -391.313416)
		(width 0.1651)
		(layer "In11.Cu")
		(net "P5E_PEX3_STN7_TX_C_DP<118>")
	)
	(segment
		(start 433.533804 -394.976604)
		(end 432.021742 -393.464542)
		(width 0.1651)
		(layer "In11.Cu")
		(net "P5E_PEX3_STN7_TX_C_DP<118>")
	)
	(segment
		(start 433.247038 -400.899122)
		(end 433.533804 -400.612356)
		(width 0.1651)
		(layer "In11.Cu")
		(net "P5E_PEX3_STN7_TX_C_DP<118>")
	)
	(segment
		(start 430.2379 -392.689334)
		(end 430.19218 -392.55319)
		(width 0.1651)
		(layer "In11.Cu")
		(net "P5E_PEX3_STN7_TX_C_DP<118>")
	)
	(segment
		(start 428.10049 -391.624566)
		(end 428.055024 -391.488422)
		(width 0.1651)
		(layer "In11.Cu")
		(net "P5E_PEX3_STN7_TX_C_DP<118>")
	)
	(segment
		(start 428.055024 -391.488422)
		(end 427.611794 -391.267696)
		(width 0.1651)
		(layer "In11.Cu")
		(net "P5E_PEX3_STN7_TX_C_DP<118>")
	)
	(segment
		(start 417.14166 -369.084606)
		(end 422.021762 -358.8258)
		(width 0.1651)
		(layer "In11.Cu")
		(net "P5E_PEX3_STN7_TX_C_DP<118>")
	)
	(segment
		(start 167.611806 -155.360116)
		(end 167.850058 -155.598368)
		(width 0.13208)
		(layer "F.Cu")
		(net "NIC2_SLOT_ID1")
	)
	(segment
		(start 166.742364 -155.360116)
		(end 167.611806 -155.360116)
		(width 0.13208)
		(layer "F.Cu")
		(net "NIC2_SLOT_ID1")
	)
	(via
		(at 167.850058 -155.598368)
		(size 0.508)
		(drill 0.254)
		(layers "F.Cu" "B.Cu")
		(net "NIC2_SLOT_ID1")
	)
	(segment
		(start 167.019986 -155.598368)
		(end 167.850058 -155.598368)
		(width 0.13208)
		(layer "B.Cu")
		(net "NIC2_SLOT_ID1")
	)
	(segment
		(start 166.463218 -155.0416)
		(end 167.019986 -155.598368)
		(width 0.13208)
		(layer "B.Cu")
		(net "NIC2_SLOT_ID1")
	)
	(segment
		(start 166.055294 -156.0576)
		(end 166.055294 -155.0416)
		(width 0.13208)
		(layer "B.Cu")
		(net "NIC2_SLOT_ID1")
	)
	(segment
		(start 166.055294 -155.0416)
		(end 166.463218 -155.0416)
		(width 0.13208)
		(layer "B.Cu")
		(net "NIC2_SLOT_ID1")
	)
	(segment
		(start 68.65747 -150.554944)
		(end 68.169536 -150.554944)
		(width 0.13462)
		(layer "F.Cu")
		(net "P5E_PEX0_STN0_RX_DP<12>")
	)
	(segment
		(start 68.169536 -150.554944)
		(end 68.006722 -150.39213)
		(width 0.13462)
		(layer "F.Cu")
		(net "P5E_PEX0_STN0_RX_DP<12>")
	)
	(segment
		(start 68.006722 -150.39213)
		(end 67.352418 -150.39213)
		(width 0.13462)
		(layer "F.Cu")
		(net "P5E_PEX0_STN0_RX_DP<12>")
	)
	(segment
		(start 67.352418 -150.39213)
		(end 67.05727 -150.687278)
		(width 0.13462)
		(layer "F.Cu")
		(net "P5E_PEX0_STN0_RX_DP<12>")
	)
	(segment
		(start 67.05727 -150.687278)
		(end 67.3481 -150.396448)
		(width 0.1651)
		(layer "In5.Cu")
		(net "P5E_PEX0_STN0_RX_DP<12>")
	)
	(segment
		(start 67.3481 -150.396448)
		(end 67.822826 -150.396448)
		(width 0.1651)
		(layer "In5.Cu")
		(net "P5E_PEX0_STN0_RX_DP<12>")
	)
	(segment
		(start 77.08392 -271.773904)
		(end 77.08392 -271.802352)
		(width 0.1143)
		(layer "In5.Cu")
		(net "P5E_PEX0_STN0_RX_DP<12>")
	)
	(segment
		(start 77.344524 -275.570188)
		(end 77.585316 -275.570188)
		(width 0.1143)
		(layer "In5.Cu")
		(net "P5E_PEX0_STN0_RX_DP<12>")
	)
	(segment
		(start 77.585316 -275.570188)
		(end 77.699616 -275.684488)
		(width 0.1143)
		(layer "In5.Cu")
		(net "P5E_PEX0_STN0_RX_DP<12>")
	)
	(segment
		(start 70.618096 -155.10637)
		(end 72.882506 -158.4706)
		(width 0.1651)
		(layer "In5.Cu")
		(net "P5E_PEX0_STN0_RX_DP<12>")
	)
	(segment
		(start 77.12964 -271.848072)
		(end 77.12964 -275.355304)
		(width 0.1143)
		(layer "In5.Cu")
		(net "P5E_PEX0_STN0_RX_DP<12>")
	)
	(segment
		(start 69.820028 -153.438352)
		(end 70.012306 -153.895298)
		(width 0.1651)
		(layer "In5.Cu")
		(net "P5E_PEX0_STN0_RX_DP<12>")
	)
	(segment
		(start 70.128892 -153.942796)
		(end 70.618096 -155.10637)
		(width 0.1651)
		(layer "In5.Cu")
		(net "P5E_PEX0_STN0_RX_DP<12>")
	)
	(segment
		(start 77.08392 -270.75892)
		(end 77.08392 -271.773904)
		(width 0.1651)
		(layer "In5.Cu")
		(net "P5E_PEX0_STN0_RX_DP<12>")
	)
	(segment
		(start 69.210936 -151.760174)
		(end 69.414644 -152.244806)
		(width 0.1651)
		(layer "In5.Cu")
		(net "P5E_PEX0_STN0_RX_DP<12>")
	)
	(segment
		(start 69.559424 -152.818084)
		(end 69.675756 -152.865582)
		(width 0.1651)
		(layer "In5.Cu")
		(net "P5E_PEX0_STN0_RX_DP<12>")
	)
	(segment
		(start 77.550772 -260.77418)
		(end 77.613256 -268.035278)
		(width 0.1651)
		(layer "In5.Cu")
		(net "P5E_PEX0_STN0_RX_DP<12>")
	)
	(segment
		(start 67.822826 -150.396448)
		(end 69.210936 -151.760174)
		(width 0.1651)
		(layer "In5.Cu")
		(net "P5E_PEX0_STN0_RX_DP<12>")
	)
	(segment
		(start 77.699616 -275.684488)
		(end 77.699616 -275.949918)
		(width 0.1143)
		(layer "In5.Cu")
		(net "P5E_PEX0_STN0_RX_DP<12>")
	)
	(segment
		(start 74.022204 -161.211514)
		(end 77.550772 -260.77418)
		(width 0.1651)
		(layer "In5.Cu")
		(net "P5E_PEX0_STN0_RX_DP<12>")
	)
	(segment
		(start 72.882506 -158.4706)
		(end 74.022204 -161.211514)
		(width 0.1651)
		(layer "In5.Cu")
		(net "P5E_PEX0_STN0_RX_DP<12>")
	)
	(segment
		(start 77.12964 -275.355304)
		(end 77.344524 -275.570188)
		(width 0.1143)
		(layer "In5.Cu")
		(net "P5E_PEX0_STN0_RX_DP<12>")
	)
	(segment
		(start 77.613256 -268.035278)
		(end 77.08392 -270.75892)
		(width 0.1651)
		(layer "In5.Cu")
		(net "P5E_PEX0_STN0_RX_DP<12>")
	)
	(segment
		(start 69.675756 -152.865582)
		(end 69.867526 -153.32202)
		(width 0.1651)
		(layer "In5.Cu")
		(net "P5E_PEX0_STN0_RX_DP<12>")
	)
	(segment
		(start 69.367146 -152.361392)
		(end 69.559424 -152.818084)
		(width 0.1651)
		(layer "In5.Cu")
		(net "P5E_PEX0_STN0_RX_DP<12>")
	)
	(segment
		(start 69.867526 -153.32202)
		(end 69.820028 -153.438352)
		(width 0.1651)
		(layer "In5.Cu")
		(net "P5E_PEX0_STN0_RX_DP<12>")
	)
	(segment
		(start 77.08392 -271.802352)
		(end 77.12964 -271.848072)
		(width 0.1143)
		(layer "In5.Cu")
		(net "P5E_PEX0_STN0_RX_DP<12>")
	)
	(segment
		(start 69.414644 -152.244806)
		(end 69.367146 -152.361392)
		(width 0.1651)
		(layer "In5.Cu")
		(net "P5E_PEX0_STN0_RX_DP<12>")
	)
	(segment
		(start 70.012306 -153.895298)
		(end 70.128892 -153.942796)
		(width 0.1651)
		(layer "In5.Cu")
		(net "P5E_PEX0_STN0_RX_DP<12>")
	)
	(segment
		(start 115.265708 -345.170506)
		(end 115.265708 -344.539062)
		(width 0.13462)
		(layer "F.Cu")
		(net "P5E_PEX1_STN6_TX_C_DP<102>")
	)
	(segment
		(start 114.971068 -345.465146)
		(end 115.265708 -345.170506)
		(width 0.13462)
		(layer "F.Cu")
		(net "P5E_PEX1_STN6_TX_C_DP<102>")
	)
	(segment
		(start 115.265708 -344.539062)
		(end 114.945668 -344.219022)
		(width 0.13462)
		(layer "F.Cu")
		(net "P5E_PEX1_STN6_TX_C_DP<102>")
	)
	(segment
		(start 116.531898 -364.686342)
		(end 113.919 -359.5624)
		(width 0.1651)
		(layer "In7.Cu")
		(net "P5E_PEX1_STN6_TX_C_DP<102>")
	)
	(segment
		(start 113.707418 -358.768904)
		(end 113.707418 -347.886782)
		(width 0.1651)
		(layer "In7.Cu")
		(net "P5E_PEX1_STN6_TX_C_DP<102>")
	)
	(segment
		(start 118.11 -383.671826)
		(end 118.237 -383.798826)
		(width 0.1651)
		(layer "In7.Cu")
		(net "P5E_PEX1_STN6_TX_C_DP<102>")
	)
	(segment
		(start 116.531644 -364.686342)
		(end 116.531898 -364.686342)
		(width 0.1651)
		(layer "In7.Cu")
		(net "P5E_PEX1_STN6_TX_C_DP<102>")
	)
	(segment
		(start 117.845078 -366.956086)
		(end 117.740938 -366.9284)
		(width 0.1651)
		(layer "In7.Cu")
		(net "P5E_PEX1_STN6_TX_C_DP<102>")
	)
	(segment
		(start 118.887494 -383.380488)
		(end 118.887494 -368.7572)
		(width 0.1651)
		(layer "In7.Cu")
		(net "P5E_PEX1_STN6_TX_C_DP<102>")
	)
	(segment
		(start 116.5352 -364.6932)
		(end 116.531644 -364.686342)
		(width 0.1651)
		(layer "In7.Cu")
		(net "P5E_PEX1_STN6_TX_C_DP<102>")
	)
	(segment
		(start 118.237 -383.798826)
		(end 118.469156 -383.798826)
		(width 0.1651)
		(layer "In7.Cu")
		(net "P5E_PEX1_STN6_TX_C_DP<102>")
	)
	(segment
		(start 113.707418 -347.886782)
		(end 115.2652 -346.329)
		(width 0.1651)
		(layer "In7.Cu")
		(net "P5E_PEX1_STN6_TX_C_DP<102>")
	)
	(segment
		(start 115.2652 -346.329)
		(end 115.2652 -345.759278)
		(width 0.1651)
		(layer "In7.Cu")
		(net "P5E_PEX1_STN6_TX_C_DP<102>")
	)
	(segment
		(start 117.520466 -366.395254)
		(end 116.5352 -364.6932)
		(width 0.1651)
		(layer "In7.Cu")
		(net "P5E_PEX1_STN6_TX_C_DP<102>")
	)
	(segment
		(start 115.2652 -345.759278)
		(end 114.971068 -345.465146)
		(width 0.1651)
		(layer "In7.Cu")
		(net "P5E_PEX1_STN6_TX_C_DP<102>")
	)
	(segment
		(start 118.887494 -368.7572)
		(end 117.845078 -366.956086)
		(width 0.1651)
		(layer "In7.Cu")
		(net "P5E_PEX1_STN6_TX_C_DP<102>")
	)
	(segment
		(start 118.469156 -383.798826)
		(end 118.887494 -383.380488)
		(width 0.1651)
		(layer "In7.Cu")
		(net "P5E_PEX1_STN6_TX_C_DP<102>")
	)
	(segment
		(start 117.492526 -366.499394)
		(end 117.520466 -366.395254)
		(width 0.1651)
		(layer "In7.Cu")
		(net "P5E_PEX1_STN6_TX_C_DP<102>")
	)
	(segment
		(start 113.919 -359.5624)
		(end 113.707418 -358.768904)
		(width 0.1651)
		(layer "In7.Cu")
		(net "P5E_PEX1_STN6_TX_C_DP<102>")
	)
	(segment
		(start 118.11 -383.290064)
		(end 118.11 -383.671826)
		(width 0.1651)
		(layer "In7.Cu")
		(net "P5E_PEX1_STN6_TX_C_DP<102>")
	)
	(segment
		(start 117.740938 -366.9284)
		(end 117.492526 -366.499394)
		(width 0.1651)
		(layer "In7.Cu")
		(net "P5E_PEX1_STN6_TX_C_DP<102>")
	)
	(segment
		(start 277.735538 -134.765034)
		(end 278.242268 -134.765034)
		(width 0.13462)
		(layer "F.Cu")
		(net "P5E_PEX2_STN1_TX_C_DN<30>")
	)
	(segment
		(start 269.432532 -134.59587)
		(end 277.566374 -134.59587)
		(width 0.13462)
		(layer "F.Cu")
		(net "P5E_PEX2_STN1_TX_C_DN<30>")
	)
	(segment
		(start 269.105126 -134.923276)
		(end 269.432532 -134.59587)
		(width 0.13462)
		(layer "F.Cu")
		(net "P5E_PEX2_STN1_TX_C_DN<30>")
	)
	(segment
		(start 277.566374 -134.59587)
		(end 277.735538 -134.765034)
		(width 0.13462)
		(layer "F.Cu")
		(net "P5E_PEX2_STN1_TX_C_DN<30>")
	)
	(segment
		(start 291.23386 -319.8876)
		(end 291.27958 -319.84188)
		(width 0.1143)
		(layer "In9.Cu")
		(net "P5E_PEX2_STN5_RX_DP<81>")
	)
	(segment
		(start 291.23386 -321.131692)
		(end 291.23386 -319.916048)
		(width 0.1651)
		(layer "In9.Cu")
		(net "P5E_PEX2_STN5_RX_DP<81>")
	)
	(segment
		(start 335.546954 -340.634828)
		(end 296.68724 -326.308466)
		(width 0.1651)
		(layer "In9.Cu")
		(net "P5E_PEX2_STN5_RX_DP<81>")
	)
	(segment
		(start 333.81696 -398.09928)
		(end 334.247236 -398.09928)
		(width 0.1651)
		(layer "In9.Cu")
		(net "P5E_PEX2_STN5_RX_DP<81>")
	)
	(segment
		(start 351.924874 -386.30098)
		(end 352.005646 -386.183124)
		(width 0.1651)
		(layer "In9.Cu")
		(net "P5E_PEX2_STN5_RX_DP<81>")
	)
	(segment
		(start 342.749886 -389.852662)
		(end 351.646998 -386.526278)
		(width 0.1651)
		(layer "In9.Cu")
		(net "P5E_PEX2_STN5_RX_DP<81>")
	)
	(segment
		(start 338.79409 -391.764266)
		(end 338.930742 -391.808208)
		(width 0.1651)
		(layer "In9.Cu")
		(net "P5E_PEX2_STN5_RX_DP<81>")
	)
	(segment
		(start 336.110834 -341.870792)
		(end 335.546954 -340.634828)
		(width 0.1651)
		(layer "In9.Cu")
		(net "P5E_PEX2_STN5_RX_DP<81>")
	)
	(segment
		(start 334.534002 -395.333728)
		(end 334.931512 -394.460984)
		(width 0.1651)
		(layer "In9.Cu")
		(net "P5E_PEX2_STN5_RX_DP<81>")
	)
	(segment
		(start 291.72281 -318.129666)
		(end 291.84981 -318.002666)
		(width 0.1143)
		(layer "In9.Cu")
		(net "P5E_PEX2_STN5_RX_DP<81>")
	)
	(segment
		(start 338.308696 -392.126978)
		(end 338.352892 -391.990072)
		(width 0.1651)
		(layer "In9.Cu")
		(net "P5E_PEX2_STN5_RX_DP<81>")
	)
	(segment
		(start 334.931512 -394.460984)
		(end 336.170016 -393.222226)
		(width 0.1651)
		(layer "In9.Cu")
		(net "P5E_PEX2_STN5_RX_DP<81>")
	)
	(segment
		(start 293.91356 -324.53326)
		(end 292.688264 -323.307964)
		(width 0.1651)
		(layer "In9.Cu")
		(net "P5E_PEX2_STN5_RX_DP<81>")
	)
	(segment
		(start 334.534002 -397.812514)
		(end 334.534002 -395.333728)
		(width 0.1651)
		(layer "In9.Cu")
		(net "P5E_PEX2_STN5_RX_DP<81>")
	)
	(segment
		(start 352.005646 -386.183124)
		(end 352.174048 -385.658614)
		(width 0.1651)
		(layer "In9.Cu")
		(net "P5E_PEX2_STN5_RX_DP<81>")
	)
	(segment
		(start 337.731354 -392.308334)
		(end 337.868006 -392.35253)
		(width 0.1651)
		(layer "In9.Cu")
		(net "P5E_PEX2_STN5_RX_DP<81>")
	)
	(segment
		(start 338.352892 -391.990072)
		(end 338.79409 -391.764266)
		(width 0.1651)
		(layer "In9.Cu")
		(net "P5E_PEX2_STN5_RX_DP<81>")
	)
	(segment
		(start 291.23386 -319.916048)
		(end 291.23386 -319.8876)
		(width 0.1143)
		(layer "In9.Cu")
		(net "P5E_PEX2_STN5_RX_DP<81>")
	)
	(segment
		(start 339.984334 -360.561382)
		(end 336.53476 -359.024174)
		(width 0.1651)
		(layer "In9.Cu")
		(net "P5E_PEX2_STN5_RX_DP<81>")
	)
	(segment
		(start 337.290156 -392.534394)
		(end 337.731354 -392.308334)
		(width 0.1651)
		(layer "In9.Cu")
		(net "P5E_PEX2_STN5_RX_DP<81>")
	)
	(segment
		(start 338.930742 -391.808208)
		(end 342.749886 -389.852662)
		(width 0.1651)
		(layer "In9.Cu")
		(net "P5E_PEX2_STN5_RX_DP<81>")
	)
	(segment
		(start 337.246214 -392.6713)
		(end 337.290156 -392.534394)
		(width 0.1651)
		(layer "In9.Cu")
		(net "P5E_PEX2_STN5_RX_DP<81>")
	)
	(segment
		(start 292.688264 -323.307964)
		(end 291.23386 -321.131692)
		(width 0.1651)
		(layer "In9.Cu")
		(net "P5E_PEX2_STN5_RX_DP<81>")
	)
	(segment
		(start 352.174048 -385.658614)
		(end 352.461576 -370.007896)
		(width 0.1651)
		(layer "In9.Cu")
		(net "P5E_PEX2_STN5_RX_DP<81>")
	)
	(segment
		(start 346.192348 -364.052358)
		(end 339.984334 -360.561382)
		(width 0.1651)
		(layer "In9.Cu")
		(net "P5E_PEX2_STN5_RX_DP<81>")
	)
	(segment
		(start 352.461576 -370.007896)
		(end 351.736406 -368.599212)
		(width 0.1651)
		(layer "In9.Cu")
		(net "P5E_PEX2_STN5_RX_DP<81>")
	)
	(segment
		(start 351.646998 -386.526278)
		(end 351.924874 -386.30098)
		(width 0.1651)
		(layer "In9.Cu")
		(net "P5E_PEX2_STN5_RX_DP<81>")
	)
	(segment
		(start 291.27958 -318.355218)
		(end 291.505132 -318.129666)
		(width 0.1143)
		(layer "In9.Cu")
		(net "P5E_PEX2_STN5_RX_DP<81>")
	)
	(segment
		(start 337.868006 -392.35253)
		(end 338.308696 -392.126978)
		(width 0.1651)
		(layer "In9.Cu")
		(net "P5E_PEX2_STN5_RX_DP<81>")
	)
	(segment
		(start 333.68996 -397.97228)
		(end 333.81696 -398.09928)
		(width 0.1651)
		(layer "In9.Cu")
		(net "P5E_PEX2_STN5_RX_DP<81>")
	)
	(segment
		(start 296.68724 -326.308466)
		(end 293.91356 -324.53326)
		(width 0.1651)
		(layer "In9.Cu")
		(net "P5E_PEX2_STN5_RX_DP<81>")
	)
	(segment
		(start 351.736406 -368.599212)
		(end 346.192348 -364.052358)
		(width 0.1651)
		(layer "In9.Cu")
		(net "P5E_PEX2_STN5_RX_DP<81>")
	)
	(segment
		(start 336.53476 -359.024174)
		(end 336.110834 -358.599994)
		(width 0.1651)
		(layer "In9.Cu")
		(net "P5E_PEX2_STN5_RX_DP<81>")
	)
	(segment
		(start 291.84981 -318.002666)
		(end 291.84981 -317.749936)
		(width 0.1143)
		(layer "In9.Cu")
		(net "P5E_PEX2_STN5_RX_DP<81>")
	)
	(segment
		(start 291.505132 -318.129666)
		(end 291.72281 -318.129666)
		(width 0.1143)
		(layer "In9.Cu")
		(net "P5E_PEX2_STN5_RX_DP<81>")
	)
	(segment
		(start 291.27958 -319.84188)
		(end 291.27958 -318.355218)
		(width 0.1143)
		(layer "In9.Cu")
		(net "P5E_PEX2_STN5_RX_DP<81>")
	)
	(segment
		(start 333.68996 -397.59001)
		(end 333.68996 -397.97228)
		(width 0.1651)
		(layer "In9.Cu")
		(net "P5E_PEX2_STN5_RX_DP<81>")
	)
	(segment
		(start 336.170016 -393.222226)
		(end 337.246214 -392.6713)
		(width 0.1651)
		(layer "In9.Cu")
		(net "P5E_PEX2_STN5_RX_DP<81>")
	)
	(segment
		(start 336.110834 -358.599994)
		(end 336.110834 -341.870792)
		(width 0.1651)
		(layer "In9.Cu")
		(net "P5E_PEX2_STN5_RX_DP<81>")
	)
	(segment
		(start 334.247236 -398.09928)
		(end 334.534002 -397.812514)
		(width 0.1651)
		(layer "In9.Cu")
		(net "P5E_PEX2_STN5_RX_DP<81>")
	)
	(segment
		(start 364.068106 -31.99003)
		(end 363.564932 -31.99003)
		(width 0.13462)
		(layer "F.Cu")
		(net "P5E_PEX3_STN2_TX_C_DN<46>")
	)
	(segment
		(start 364.234476 -32.1564)
		(end 364.068106 -31.99003)
		(width 0.13462)
		(layer "F.Cu")
		(net "P5E_PEX3_STN2_TX_C_DN<46>")
	)
	(segment
		(start 365.49457 -32.1564)
		(end 364.234476 -32.1564)
		(width 0.13462)
		(layer "F.Cu")
		(net "P5E_PEX3_STN2_TX_C_DN<46>")
	)
	(segment
		(start 365.825786 -31.825184)
		(end 365.49457 -32.1564)
		(width 0.13462)
		(layer "F.Cu")
		(net "P5E_PEX3_STN2_TX_C_DN<46>")
	)
	(segment
		(start 383.4384 -314.11672)
		(end 383.371344 -316.318392)
		(width 0.1651)
		(layer "In9.Cu")
		(net "P5E_PEX3_STN7_RX_DN<121>")
	)
	(segment
		(start 424.374564 -364.330234)
		(end 424.288966 -364.369096)
		(width 0.1651)
		(layer "In9.Cu")
		(net "P5E_PEX3_STN7_RX_DN<121>")
	)
	(segment
		(start 426.25264 -359.334054)
		(end 426.252894 -359.334054)
		(width 0.1651)
		(layer "In9.Cu")
		(net "P5E_PEX3_STN7_RX_DN<121>")
	)
	(segment
		(start 421.689784 -383.67208)
		(end 421.689784 -383.290064)
		(width 0.1651)
		(layer "In9.Cu")
		(net "P5E_PEX3_STN7_RX_DN<121>")
	)
	(segment
		(start 426.15358 -341.372952)
		(end 426.685202 -342.142064)
		(width 0.1651)
		(layer "In9.Cu")
		(net "P5E_PEX3_STN7_RX_DN<121>")
	)
	(segment
		(start 425.931076 -359.86466)
		(end 425.997878 -360.011726)
		(width 0.1651)
		(layer "In9.Cu")
		(net "P5E_PEX3_STN7_RX_DN<121>")
	)
	(segment
		(start 384.739134 -323.480938)
		(end 385.728718 -324.835012)
		(width 0.1651)
		(layer "In9.Cu")
		(net "P5E_PEX3_STN7_RX_DN<121>")
	)
	(segment
		(start 422.809162 -368.206274)
		(end 422.868598 -368.337084)
		(width 0.1651)
		(layer "In9.Cu")
		(net "P5E_PEX3_STN7_RX_DN<121>")
	)
	(segment
		(start 423.954702 -365.447834)
		(end 423.843196 -365.49838)
		(width 0.1651)
		(layer "In9.Cu")
		(net "P5E_PEX3_STN7_RX_DN<121>")
	)
	(segment
		(start 385.364482 -310.529478)
		(end 384.744722 -310.529478)
		(width 0.1143)
		(layer "In9.Cu")
		(net "P5E_PEX3_STN7_RX_DN<121>")
	)
	(segment
		(start 422.564814 -369.145312)
		(end 422.564814 -383.273046)
		(width 0.1651)
		(layer "In9.Cu")
		(net "P5E_PEX3_STN7_RX_DN<121>")
	)
	(segment
		(start 384.462528 -310.74741)
		(end 383.664714 -311.545224)
		(width 0.1651)
		(layer "In9.Cu")
		(net "P5E_PEX3_STN7_RX_DN<121>")
	)
	(segment
		(start 383.664714 -311.545224)
		(end 383.4384 -312.091578)
		(width 0.1651)
		(layer "In9.Cu")
		(net "P5E_PEX3_STN7_RX_DN<121>")
	)
	(segment
		(start 422.03878 -383.79908)
		(end 421.816784 -383.79908)
		(width 0.1651)
		(layer "In9.Cu")
		(net "P5E_PEX3_STN7_RX_DN<121>")
	)
	(segment
		(start 383.55143 -318.659002)
		(end 384.06197 -321.398138)
		(width 0.1651)
		(layer "In9.Cu")
		(net "P5E_PEX3_STN7_RX_DN<121>")
	)
	(segment
		(start 383.4384 -312.091578)
		(end 383.4384 -314.11672)
		(width 0.1651)
		(layer "In9.Cu")
		(net "P5E_PEX3_STN7_RX_DN<121>")
	)
	(segment
		(start 423.843196 -365.49838)
		(end 423.658284 -365.990632)
		(width 0.1651)
		(layer "In9.Cu")
		(net "P5E_PEX3_STN7_RX_DN<121>")
	)
	(segment
		(start 423.534586 -366.565434)
		(end 423.403522 -366.62487)
		(width 0.1651)
		(layer "In9.Cu")
		(net "P5E_PEX3_STN7_RX_DN<121>")
	)
	(segment
		(start 426.252894 -359.334054)
		(end 426.105574 -359.400856)
		(width 0.1651)
		(layer "In9.Cu")
		(net "P5E_PEX3_STN7_RX_DN<121>")
	)
	(segment
		(start 422.564814 -383.273046)
		(end 422.03878 -383.79908)
		(width 0.1651)
		(layer "In9.Cu")
		(net "P5E_PEX3_STN7_RX_DN<121>")
	)
	(segment
		(start 424.288966 -364.369096)
		(end 424.090084 -364.898686)
		(width 0.1651)
		(layer "In9.Cu")
		(net "P5E_PEX3_STN7_RX_DN<121>")
	)
	(segment
		(start 384.744722 -310.529478)
		(end 384.546602 -310.727598)
		(width 0.1143)
		(layer "In9.Cu")
		(net "P5E_PEX3_STN7_RX_DN<121>")
	)
	(segment
		(start 423.288714 -367.219484)
		(end 423.11447 -367.683034)
		(width 0.1651)
		(layer "In9.Cu")
		(net "P5E_PEX3_STN7_RX_DN<121>")
	)
	(segment
		(start 383.371344 -316.318392)
		(end 383.55143 -318.659002)
		(width 0.1651)
		(layer "In9.Cu")
		(net "P5E_PEX3_STN7_RX_DN<121>")
	)
	(segment
		(start 426.105574 -359.400856)
		(end 425.931076 -359.86466)
		(width 0.1651)
		(layer "In9.Cu")
		(net "P5E_PEX3_STN7_RX_DN<121>")
	)
	(segment
		(start 385.529582 -310.238648)
		(end 385.529582 -310.364378)
		(width 0.1143)
		(layer "In9.Cu")
		(net "P5E_PEX3_STN7_RX_DN<121>")
	)
	(segment
		(start 388.546086 -326.859392)
		(end 408.328368 -333.121508)
		(width 0.1651)
		(layer "In9.Cu")
		(net "P5E_PEX3_STN7_RX_DN<121>")
	)
	(segment
		(start 424.128692 -364.984284)
		(end 423.954702 -365.447834)
		(width 0.1651)
		(layer "In9.Cu")
		(net "P5E_PEX3_STN7_RX_DN<121>")
	)
	(segment
		(start 408.328368 -333.121508)
		(end 424.517566 -340.760558)
		(width 0.1651)
		(layer "In9.Cu")
		(net "P5E_PEX3_STN7_RX_DN<121>")
	)
	(segment
		(start 423.70883 -366.101884)
		(end 423.534586 -366.565434)
		(width 0.1651)
		(layer "In9.Cu")
		(net "P5E_PEX3_STN7_RX_DN<121>")
	)
	(segment
		(start 423.11447 -367.683034)
		(end 422.983406 -367.742216)
		(width 0.1651)
		(layer "In9.Cu")
		(net "P5E_PEX3_STN7_RX_DN<121>")
	)
	(segment
		(start 422.868598 -368.337084)
		(end 422.564814 -369.145312)
		(width 0.1651)
		(layer "In9.Cu")
		(net "P5E_PEX3_STN7_RX_DN<121>")
	)
	(segment
		(start 384.482594 -310.727344)
		(end 384.462528 -310.74741)
		(width 0.1143)
		(layer "In9.Cu")
		(net "P5E_PEX3_STN7_RX_DN<121>")
	)
	(segment
		(start 384.546602 -310.727598)
		(end 384.482594 -310.727344)
		(width 0.1143)
		(layer "In9.Cu")
		(net "P5E_PEX3_STN7_RX_DN<121>")
	)
	(segment
		(start 384.06197 -321.398138)
		(end 384.739134 -323.480938)
		(width 0.1651)
		(layer "In9.Cu")
		(net "P5E_PEX3_STN7_RX_DN<121>")
	)
	(segment
		(start 385.440682 -310.149748)
		(end 385.529582 -310.238648)
		(width 0.1143)
		(layer "In9.Cu")
		(net "P5E_PEX3_STN7_RX_DN<121>")
	)
	(segment
		(start 424.517566 -340.760558)
		(end 426.15358 -341.372952)
		(width 0.1651)
		(layer "In9.Cu")
		(net "P5E_PEX3_STN7_RX_DN<121>")
	)
	(segment
		(start 425.997878 -360.011726)
		(end 424.374564 -364.330234)
		(width 0.1651)
		(layer "In9.Cu")
		(net "P5E_PEX3_STN7_RX_DN<121>")
	)
	(segment
		(start 423.658284 -365.990632)
		(end 423.70883 -366.101884)
		(width 0.1651)
		(layer "In9.Cu")
		(net "P5E_PEX3_STN7_RX_DN<121>")
	)
	(segment
		(start 423.229278 -367.088674)
		(end 423.288714 -367.219484)
		(width 0.1651)
		(layer "In9.Cu")
		(net "P5E_PEX3_STN7_RX_DN<121>")
	)
	(segment
		(start 426.685202 -342.142064)
		(end 426.685202 -358.183688)
		(width 0.1651)
		(layer "In9.Cu")
		(net "P5E_PEX3_STN7_RX_DN<121>")
	)
	(segment
		(start 426.685202 -358.183688)
		(end 426.25264 -359.334054)
		(width 0.1651)
		(layer "In9.Cu")
		(net "P5E_PEX3_STN7_RX_DN<121>")
	)
	(segment
		(start 423.403522 -366.62487)
		(end 423.229278 -367.088674)
		(width 0.1651)
		(layer "In9.Cu")
		(net "P5E_PEX3_STN7_RX_DN<121>")
	)
	(segment
		(start 385.728718 -324.835012)
		(end 388.546086 -326.859392)
		(width 0.1651)
		(layer "In9.Cu")
		(net "P5E_PEX3_STN7_RX_DN<121>")
	)
	(segment
		(start 385.529582 -310.364378)
		(end 385.364482 -310.529478)
		(width 0.1143)
		(layer "In9.Cu")
		(net "P5E_PEX3_STN7_RX_DN<121>")
	)
	(segment
		(start 421.816784 -383.79908)
		(end 421.689784 -383.67208)
		(width 0.1651)
		(layer "In9.Cu")
		(net "P5E_PEX3_STN7_RX_DN<121>")
	)
	(segment
		(start 424.090084 -364.898686)
		(end 424.128692 -364.984284)
		(width 0.1651)
		(layer "In9.Cu")
		(net "P5E_PEX3_STN7_RX_DN<121>")
	)
	(segment
		(start 385.149852 -310.149748)
		(end 385.440682 -310.149748)
		(width 0.1143)
		(layer "In9.Cu")
		(net "P5E_PEX3_STN7_RX_DN<121>")
	)
	(segment
		(start 422.983406 -367.742216)
		(end 422.809162 -368.206274)
		(width 0.1651)
		(layer "In9.Cu")
		(net "P5E_PEX3_STN7_RX_DN<121>")
	)
	(segment
		(start 158.077408 -152.719278)
		(end 159.518096 -154.159966)
		(width 0.13208)
		(layer "F.Cu")
		(net "NCSI_NIC2_RXD1")
	)
	(segment
		(start 159.518096 -154.159966)
		(end 162.14217 -154.159966)
		(width 0.13208)
		(layer "F.Cu")
		(net "NCSI_NIC2_RXD1")
	)
	(segment
		(start 156.072586 -152.295352)
		(end 156.496512 -152.719278)
		(width 0.13208)
		(layer "F.Cu")
		(net "NCSI_NIC2_RXD1")
	)
	(segment
		(start 155.099766 -152.295352)
		(end 156.072586 -152.295352)
		(width 0.13208)
		(layer "F.Cu")
		(net "NCSI_NIC2_RXD1")
	)
	(segment
		(start 156.496512 -152.719278)
		(end 158.077408 -152.719278)
		(width 0.13208)
		(layer "F.Cu")
		(net "NCSI_NIC2_RXD1")
	)
	(via
		(at 156.496512 -152.719278)
		(size 0.762)
		(drill 0.381)
		(layers "F.Cu" "B.Cu")
		(net "NCSI_NIC2_RXD1")
	)
	(segment
		(start 65.498218 -152.192228)
		(end 65.20307 -152.487376)
		(width 0.13462)
		(layer "F.Cu")
		(net "P5E_PEX0_STN0_RX_DP<13>")
	)
	(segment
		(start 68.65747 -152.355042)
		(end 68.169536 -152.355042)
		(width 0.13462)
		(layer "F.Cu")
		(net "P5E_PEX0_STN0_RX_DP<13>")
	)
	(segment
		(start 68.006722 -152.192228)
		(end 65.498218 -152.192228)
		(width 0.13462)
		(layer "F.Cu")
		(net "P5E_PEX0_STN0_RX_DP<13>")
	)
	(segment
		(start 68.169536 -152.355042)
		(end 68.006722 -152.192228)
		(width 0.13462)
		(layer "F.Cu")
		(net "P5E_PEX0_STN0_RX_DP<13>")
	)
	(segment
		(start 76.749656 -273.784314)
		(end 76.749656 -274.049744)
		(width 0.1143)
		(layer "In5.Cu")
		(net "P5E_PEX0_STN0_RX_DP<13>")
	)
	(segment
		(start 68.62064 -153.119074)
		(end 69.4817 -155.185618)
		(width 0.1651)
		(layer "In5.Cu")
		(net "P5E_PEX0_STN0_RX_DP<13>")
	)
	(segment
		(start 65.4939 -152.196546)
		(end 67.698112 -152.196546)
		(width 0.1651)
		(layer "In5.Cu")
		(net "P5E_PEX0_STN0_RX_DP<13>")
	)
	(segment
		(start 70.501764 -156.854398)
		(end 70.779132 -157.265116)
		(width 0.1651)
		(layer "In5.Cu")
		(net "P5E_PEX0_STN0_RX_DP<13>")
	)
	(segment
		(start 76.17968 -271.848072)
		(end 76.17968 -273.45513)
		(width 0.1143)
		(layer "In5.Cu")
		(net "P5E_PEX0_STN0_RX_DP<13>")
	)
	(segment
		(start 76.13396 -271.773904)
		(end 76.13396 -271.802352)
		(width 0.1143)
		(layer "In5.Cu")
		(net "P5E_PEX0_STN0_RX_DP<13>")
	)
	(segment
		(start 70.52564 -156.730954)
		(end 70.501764 -156.854398)
		(width 0.1651)
		(layer "In5.Cu")
		(net "P5E_PEX0_STN0_RX_DP<13>")
	)
	(segment
		(start 65.20307 -152.487376)
		(end 65.4939 -152.196546)
		(width 0.1651)
		(layer "In5.Cu")
		(net "P5E_PEX0_STN0_RX_DP<13>")
	)
	(segment
		(start 76.650342 -267.84427)
		(end 76.13396 -270.513048)
		(width 0.1651)
		(layer "In5.Cu")
		(net "P5E_PEX0_STN0_RX_DP<13>")
	)
	(segment
		(start 71.433436 -158.233364)
		(end 71.556626 -158.25724)
		(width 0.1651)
		(layer "In5.Cu")
		(net "P5E_PEX0_STN0_RX_DP<13>")
	)
	(segment
		(start 70.779132 -157.265116)
		(end 70.902576 -157.288992)
		(width 0.1651)
		(layer "In5.Cu")
		(net "P5E_PEX0_STN0_RX_DP<13>")
	)
	(segment
		(start 76.13396 -270.513048)
		(end 76.13396 -271.773904)
		(width 0.1651)
		(layer "In5.Cu")
		(net "P5E_PEX0_STN0_RX_DP<13>")
	)
	(segment
		(start 73.021444 -161.356548)
		(end 76.575666 -260.651244)
		(width 0.1651)
		(layer "In5.Cu")
		(net "P5E_PEX0_STN0_RX_DP<13>")
	)
	(segment
		(start 67.698112 -152.196546)
		(end 68.62064 -153.119074)
		(width 0.1651)
		(layer "In5.Cu")
		(net "P5E_PEX0_STN0_RX_DP<13>")
	)
	(segment
		(start 76.13396 -271.802352)
		(end 76.17968 -271.848072)
		(width 0.1143)
		(layer "In5.Cu")
		(net "P5E_PEX0_STN0_RX_DP<13>")
	)
	(segment
		(start 70.902576 -157.288992)
		(end 71.17969 -157.699202)
		(width 0.1651)
		(layer "In5.Cu")
		(net "P5E_PEX0_STN0_RX_DP<13>")
	)
	(segment
		(start 71.556626 -158.25724)
		(end 72.01535 -158.936436)
		(width 0.1651)
		(layer "In5.Cu")
		(net "P5E_PEX0_STN0_RX_DP<13>")
	)
	(segment
		(start 76.575666 -260.651244)
		(end 76.650342 -267.84427)
		(width 0.1651)
		(layer "In5.Cu")
		(net "P5E_PEX0_STN0_RX_DP<13>")
	)
	(segment
		(start 72.01535 -158.936436)
		(end 73.021444 -161.356548)
		(width 0.1651)
		(layer "In5.Cu")
		(net "P5E_PEX0_STN0_RX_DP<13>")
	)
	(segment
		(start 76.635356 -273.670014)
		(end 76.749656 -273.784314)
		(width 0.1143)
		(layer "In5.Cu")
		(net "P5E_PEX0_STN0_RX_DP<13>")
	)
	(segment
		(start 71.155814 -157.822646)
		(end 71.433436 -158.233364)
		(width 0.1651)
		(layer "In5.Cu")
		(net "P5E_PEX0_STN0_RX_DP<13>")
	)
	(segment
		(start 76.394564 -273.670014)
		(end 76.635356 -273.670014)
		(width 0.1143)
		(layer "In5.Cu")
		(net "P5E_PEX0_STN0_RX_DP<13>")
	)
	(segment
		(start 69.4817 -155.185618)
		(end 70.52564 -156.730954)
		(width 0.1651)
		(layer "In5.Cu")
		(net "P5E_PEX0_STN0_RX_DP<13>")
	)
	(segment
		(start 71.17969 -157.699202)
		(end 71.155814 -157.822646)
		(width 0.1651)
		(layer "In5.Cu")
		(net "P5E_PEX0_STN0_RX_DP<13>")
	)
	(segment
		(start 76.17968 -273.45513)
		(end 76.394564 -273.670014)
		(width 0.1143)
		(layer "In5.Cu")
		(net "P5E_PEX0_STN0_RX_DP<13>")
	)
	(segment
		(start 122.052588 -357.75773)
		(end 121.757948 -357.46309)
		(width 0.13462)
		(layer "F.Cu")
		(net "P5E_PEX1_STN6_TX_C_DN<98>")
	)
	(segment
		(start 121.757948 -357.46309)
		(end 121.757948 -356.831646)
		(width 0.13462)
		(layer "F.Cu")
		(net "P5E_PEX1_STN6_TX_C_DN<98>")
	)
	(segment
		(start 121.757948 -356.831646)
		(end 122.077988 -356.511606)
		(width 0.13462)
		(layer "F.Cu")
		(net "P5E_PEX1_STN6_TX_C_DN<98>")
	)
	(segment
		(start 126.910084 -384.20802)
		(end 126.910084 -384.590036)
		(width 0.1651)
		(layer "In7.Cu")
		(net "P5E_PEX1_STN6_TX_C_DN<98>")
	)
	(segment
		(start 127.037338 -384.080766)
		(end 126.910084 -384.20802)
		(width 0.1651)
		(layer "In7.Cu")
		(net "P5E_PEX1_STN6_TX_C_DN<98>")
	)
	(segment
		(start 127.38608 -384.080766)
		(end 127.037338 -384.080766)
		(width 0.1651)
		(layer "In7.Cu")
		(net "P5E_PEX1_STN6_TX_C_DN<98>")
	)
	(segment
		(start 127.719074 -368.54257)
		(end 127.969518 -369.368324)
		(width 0.1651)
		(layer "In7.Cu")
		(net "P5E_PEX1_STN6_TX_C_DN<98>")
	)
	(segment
		(start 122.052588 -357.75773)
		(end 121.761758 -358.04856)
		(width 0.1651)
		(layer "In7.Cu")
		(net "P5E_PEX1_STN6_TX_C_DN<98>")
	)
	(segment
		(start 121.761758 -359.626916)
		(end 127.719074 -368.54257)
		(width 0.1651)
		(layer "In7.Cu")
		(net "P5E_PEX1_STN6_TX_C_DN<98>")
	)
	(segment
		(start 127.969518 -383.497328)
		(end 127.38608 -384.080766)
		(width 0.1651)
		(layer "In7.Cu")
		(net "P5E_PEX1_STN6_TX_C_DN<98>")
	)
	(segment
		(start 127.969518 -369.368324)
		(end 127.969518 -383.497328)
		(width 0.1651)
		(layer "In7.Cu")
		(net "P5E_PEX1_STN6_TX_C_DN<98>")
	)
	(segment
		(start 121.761758 -358.04856)
		(end 121.761758 -359.626916)
		(width 0.1651)
		(layer "In7.Cu")
		(net "P5E_PEX1_STN6_TX_C_DN<98>")
	)
	(segment
		(start 269.432532 -119.785892)
		(end 277.566374 -119.785892)
		(width 0.13462)
		(layer "F.Cu")
		(net "P5E_PEX2_STN1_TX_C_DN<24>")
	)
	(segment
		(start 269.105126 -120.113298)
		(end 269.432532 -119.785892)
		(width 0.13462)
		(layer "F.Cu")
		(net "P5E_PEX2_STN1_TX_C_DN<24>")
	)
	(segment
		(start 277.566374 -119.785892)
		(end 277.735538 -119.955056)
		(width 0.13462)
		(layer "F.Cu")
		(net "P5E_PEX2_STN1_TX_C_DN<24>")
	)
	(segment
		(start 277.735538 -119.955056)
		(end 278.242268 -119.955056)
		(width 0.13462)
		(layer "F.Cu")
		(net "P5E_PEX2_STN1_TX_C_DN<24>")
	)
	(segment
		(start 383.66319 -28.82392)
		(end 383.36474 -29.12237)
		(width 0.13462)
		(layer "F.Cu")
		(net "P5E_PEX3_STN2_RX_DP<40>")
	)
	(segment
		(start 384.485896 -28.99029)
		(end 384.319526 -28.82392)
		(width 0.13462)
		(layer "F.Cu")
		(net "P5E_PEX3_STN2_RX_DP<40>")
	)
	(segment
		(start 384.96494 -28.990036)
		(end 384.96494 -28.99029)
		(width 0.13462)
		(layer "F.Cu")
		(net "P5E_PEX3_STN2_RX_DP<40>")
	)
	(segment
		(start 384.319526 -28.82392)
		(end 383.66319 -28.82392)
		(width 0.13462)
		(layer "F.Cu")
		(net "P5E_PEX3_STN2_RX_DP<40>")
	)
	(segment
		(start 384.96494 -28.99029)
		(end 384.485896 -28.99029)
		(width 0.13462)
		(layer "F.Cu")
		(net "P5E_PEX3_STN2_RX_DP<40>")
	)
	(segment
		(start 385.898644 -30.886908)
		(end 386.042408 -30.886908)
		(width 0.1651)
		(layer "In7.Cu")
		(net "P5E_PEX3_STN2_RX_DP<40>")
	)
	(segment
		(start 386.042408 -30.886908)
		(end 386.764276 -31.608776)
		(width 0.1651)
		(layer "In7.Cu")
		(net "P5E_PEX3_STN2_RX_DP<40>")
	)
	(segment
		(start 389.348472 -37.742622)
		(end 389.33501 -38.545262)
		(width 0.1651)
		(layer "In7.Cu")
		(net "P5E_PEX3_STN2_RX_DP<40>")
	)
	(segment
		(start 389.33501 -38.545262)
		(end 387.188202 -48.798226)
		(width 0.1651)
		(layer "In7.Cu")
		(net "P5E_PEX3_STN2_RX_DP<40>")
	)
	(segment
		(start 398.78381 -268.137132)
		(end 398.78381 -271.392904)
		(width 0.1651)
		(layer "In7.Cu")
		(net "P5E_PEX3_STN2_RX_DP<40>")
	)
	(segment
		(start 383.623058 -28.864052)
		(end 383.701544 -28.83154)
		(width 0.1651)
		(layer "In7.Cu")
		(net "P5E_PEX3_STN2_RX_DP<40>")
	)
	(segment
		(start 399.400014 -275.684488)
		(end 399.400014 -275.949918)
		(width 0.1143)
		(layer "In7.Cu")
		(net "P5E_PEX3_STN2_RX_DP<40>")
	)
	(segment
		(start 398.78381 -271.392904)
		(end 398.78381 -271.421352)
		(width 0.1143)
		(layer "In7.Cu")
		(net "P5E_PEX3_STN2_RX_DP<40>")
	)
	(segment
		(start 385.198112 -30.042612)
		(end 385.548124 -30.392624)
		(width 0.1651)
		(layer "In7.Cu")
		(net "P5E_PEX3_STN2_RX_DP<40>")
	)
	(segment
		(start 384.703828 -29.692092)
		(end 385.054348 -30.042612)
		(width 0.1651)
		(layer "In7.Cu")
		(net "P5E_PEX3_STN2_RX_DP<40>")
	)
	(segment
		(start 391.09269 -119.567198)
		(end 390.786874 -147.947888)
		(width 0.1651)
		(layer "In7.Cu")
		(net "P5E_PEX3_STN2_RX_DP<40>")
	)
	(segment
		(start 385.548124 -30.392624)
		(end 385.548124 -30.536388)
		(width 0.1651)
		(layer "In7.Cu")
		(net "P5E_PEX3_STN2_RX_DP<40>")
	)
	(segment
		(start 387.486652 -65.14846)
		(end 390.63041 -104.315514)
		(width 0.1651)
		(layer "In7.Cu")
		(net "P5E_PEX3_STN2_RX_DP<40>")
	)
	(segment
		(start 398.78381 -271.421352)
		(end 398.82953 -271.467072)
		(width 0.1143)
		(layer "In7.Cu")
		(net "P5E_PEX3_STN2_RX_DP<40>")
	)
	(segment
		(start 398.82953 -271.467072)
		(end 398.82953 -275.354796)
		(width 0.1143)
		(layer "In7.Cu")
		(net "P5E_PEX3_STN2_RX_DP<40>")
	)
	(segment
		(start 385.548124 -30.536388)
		(end 385.898644 -30.886908)
		(width 0.1651)
		(layer "In7.Cu")
		(net "P5E_PEX3_STN2_RX_DP<40>")
	)
	(segment
		(start 390.63041 -104.315514)
		(end 391.09269 -119.567198)
		(width 0.1651)
		(layer "In7.Cu")
		(net "P5E_PEX3_STN2_RX_DP<40>")
	)
	(segment
		(start 385.054348 -30.042612)
		(end 385.198112 -30.042612)
		(width 0.1651)
		(layer "In7.Cu")
		(net "P5E_PEX3_STN2_RX_DP<40>")
	)
	(segment
		(start 383.36474 -29.12237)
		(end 383.623058 -28.864052)
		(width 0.1651)
		(layer "In7.Cu")
		(net "P5E_PEX3_STN2_RX_DP<40>")
	)
	(segment
		(start 399.044922 -275.570188)
		(end 399.285714 -275.570188)
		(width 0.1143)
		(layer "In7.Cu")
		(net "P5E_PEX3_STN2_RX_DP<40>")
	)
	(segment
		(start 383.701544 -28.83154)
		(end 383.98704 -28.83154)
		(width 0.1651)
		(layer "In7.Cu")
		(net "P5E_PEX3_STN2_RX_DP<40>")
	)
	(segment
		(start 398.82953 -275.354796)
		(end 399.044922 -275.570188)
		(width 0.1143)
		(layer "In7.Cu")
		(net "P5E_PEX3_STN2_RX_DP<40>")
	)
	(segment
		(start 384.703828 -29.548328)
		(end 384.703828 -29.692092)
		(width 0.1651)
		(layer "In7.Cu")
		(net "P5E_PEX3_STN2_RX_DP<40>")
	)
	(segment
		(start 390.786874 -147.947888)
		(end 398.748504 -250.016518)
		(width 0.1651)
		(layer "In7.Cu")
		(net "P5E_PEX3_STN2_RX_DP<40>")
	)
	(segment
		(start 398.748504 -250.016518)
		(end 398.461992 -264.871962)
		(width 0.1651)
		(layer "In7.Cu")
		(net "P5E_PEX3_STN2_RX_DP<40>")
	)
	(segment
		(start 387.08838 -55.19547)
		(end 387.486652 -65.14846)
		(width 0.1651)
		(layer "In7.Cu")
		(net "P5E_PEX3_STN2_RX_DP<40>")
	)
	(segment
		(start 399.285714 -275.570188)
		(end 399.400014 -275.684488)
		(width 0.1143)
		(layer "In7.Cu")
		(net "P5E_PEX3_STN2_RX_DP<40>")
	)
	(segment
		(start 383.98704 -28.83154)
		(end 384.703828 -29.548328)
		(width 0.1651)
		(layer "In7.Cu")
		(net "P5E_PEX3_STN2_RX_DP<40>")
	)
	(segment
		(start 386.764276 -31.608776)
		(end 389.348472 -37.742622)
		(width 0.1651)
		(layer "In7.Cu")
		(net "P5E_PEX3_STN2_RX_DP<40>")
	)
	(segment
		(start 387.188202 -48.798226)
		(end 387.08838 -55.19547)
		(width 0.1651)
		(layer "In7.Cu")
		(net "P5E_PEX3_STN2_RX_DP<40>")
	)
	(segment
		(start 398.461992 -264.871962)
		(end 398.78381 -268.137132)
		(width 0.1651)
		(layer "In7.Cu")
		(net "P5E_PEX3_STN2_RX_DP<40>")
	)
	(segment
		(start 440.95416 -356.831138)
		(end 440.95416 -357.463598)
		(width 0.13462)
		(layer "F.Cu")
		(net "P5E_PEX3_STN7_TX_C_DN<127>")
	)
	(segment
		(start 440.95416 -357.463598)
		(end 441.248292 -357.75773)
		(width 0.13462)
		(layer "F.Cu")
		(net "P5E_PEX3_STN7_TX_C_DN<127>")
	)
	(segment
		(start 441.273692 -356.511606)
		(end 440.95416 -356.831138)
		(width 0.13462)
		(layer "F.Cu")
		(net "P5E_PEX3_STN7_TX_C_DN<127>")
	)
	(segment
		(start 440.74461 -359.229152)
		(end 440.957462 -358.32415)
		(width 0.1651)
		(layer "In11.Cu")
		(net "P5E_PEX3_STN7_TX_C_DN<127>")
	)
	(segment
		(start 436.015892 -375.829322)
		(end 436.015892 -369.26647)
		(width 0.1651)
		(layer "In11.Cu")
		(net "P5E_PEX3_STN7_TX_C_DN<127>")
	)
	(segment
		(start 436.258716 -368.234722)
		(end 440.74461 -359.229152)
		(width 0.1651)
		(layer "In11.Cu")
		(net "P5E_PEX3_STN7_TX_C_DN<127>")
	)
	(segment
		(start 435.564026 -376.281188)
		(end 436.015892 -375.829322)
		(width 0.1651)
		(layer "In11.Cu")
		(net "P5E_PEX3_STN7_TX_C_DN<127>")
	)
	(segment
		(start 434.88991 -376.408188)
		(end 435.01691 -376.281188)
		(width 0.1651)
		(layer "In11.Cu")
		(net "P5E_PEX3_STN7_TX_C_DN<127>")
	)
	(segment
		(start 440.957462 -358.32415)
		(end 440.957462 -358.04856)
		(width 0.1651)
		(layer "In11.Cu")
		(net "P5E_PEX3_STN7_TX_C_DN<127>")
	)
	(segment
		(start 440.957462 -358.04856)
		(end 441.248292 -357.75773)
		(width 0.1651)
		(layer "In11.Cu")
		(net "P5E_PEX3_STN7_TX_C_DN<127>")
	)
	(segment
		(start 436.015892 -369.26647)
		(end 436.258716 -368.234722)
		(width 0.1651)
		(layer "In11.Cu")
		(net "P5E_PEX3_STN7_TX_C_DN<127>")
	)
	(segment
		(start 434.88991 -376.790204)
		(end 434.88991 -376.408188)
		(width 0.1651)
		(layer "In11.Cu")
		(net "P5E_PEX3_STN7_TX_C_DN<127>")
	)
	(segment
		(start 435.01691 -376.281188)
		(end 435.564026 -376.281188)
		(width 0.1651)
		(layer "In11.Cu")
		(net "P5E_PEX3_STN7_TX_C_DN<127>")
	)
	(segment
		(start 162.14217 -157.15996)
		(end 160.452816 -157.15996)
		(width 0.13208)
		(layer "F.Cu")
		(net "NIC2_LD_N")
	)
	(segment
		(start 160.452816 -157.15996)
		(end 158.621476 -158.9913)
		(width 0.13208)
		(layer "F.Cu")
		(net "NIC2_LD_N")
	)
	(segment
		(start 158.621476 -158.9913)
		(end 156.28747 -158.9913)
		(width 0.13208)
		(layer "F.Cu")
		(net "NIC2_LD_N")
	)
	(segment
		(start 155.69057 -158.3944)
		(end 155.107894 -158.3944)
		(width 0.13208)
		(layer "F.Cu")
		(net "NIC2_LD_N")
	)
	(segment
		(start 156.28747 -158.9913)
		(end 155.69057 -158.3944)
		(width 0.13208)
		(layer "F.Cu")
		(net "NIC2_LD_N")
	)
	(via
		(at 156.28747 -158.9913)
		(size 0.762)
		(drill 0.381)
		(layers "F.Cu" "B.Cu")
		(net "NIC2_LD_N")
	)
	(segment
		(start 68.65747 -135.444992)
		(end 68.169536 -135.444992)
		(width 0.13462)
		(layer "F.Cu")
		(net "P5E_PEX0_STN0_RX_DN<7>")
	)
	(segment
		(start 65.498218 -135.607806)
		(end 65.49771 -135.608314)
		(width 0.13462)
		(layer "F.Cu")
		(net "P5E_PEX0_STN0_RX_DN<7>")
	)
	(segment
		(start 65.49771 -135.608314)
		(end 65.20307 -135.313674)
		(width 0.13462)
		(layer "F.Cu")
		(net "P5E_PEX0_STN0_RX_DN<7>")
	)
	(segment
		(start 68.006722 -135.607806)
		(end 65.498218 -135.607806)
		(width 0.13462)
		(layer "F.Cu")
		(net "P5E_PEX0_STN0_RX_DN<7>")
	)
	(segment
		(start 68.169536 -135.444992)
		(end 68.006722 -135.607806)
		(width 0.13462)
		(layer "F.Cu")
		(net "P5E_PEX0_STN0_RX_DN<7>")
	)
	(segment
		(start 79.27975 -160.476184)
		(end 79.27975 -160.455102)
		(width 0.1651)
		(layer "In5.Cu")
		(net "P5E_PEX0_STN0_RX_DN<7>")
	)
	(segment
		(start 84.67217 -280.46807)
		(end 84.760562 -276.308312)
		(width 0.1651)
		(layer "In5.Cu")
		(net "P5E_PEX0_STN0_RX_DN<7>")
	)
	(segment
		(start 79.27975 -160.455102)
		(end 79.273654 -160.449006)
		(width 0.1651)
		(layer "In5.Cu")
		(net "P5E_PEX0_STN0_RX_DN<7>")
	)
	(segment
		(start 73.687432 -139.464288)
		(end 73.269602 -138.752834)
		(width 0.1651)
		(layer "In5.Cu")
		(net "P5E_PEX0_STN0_RX_DN<7>")
	)
	(segment
		(start 82.184494 -281.649932)
		(end 82.070194 -281.535632)
		(width 0.1143)
		(layer "In5.Cu")
		(net "P5E_PEX0_STN0_RX_DN<7>")
	)
	(segment
		(start 83.87588 -281.270202)
		(end 83.9216 -281.315922)
		(width 0.1143)
		(layer "In5.Cu")
		(net "P5E_PEX0_STN0_RX_DN<7>")
	)
	(segment
		(start 83.950048 -281.315922)
		(end 84.1883 -281.315922)
		(width 0.1651)
		(layer "In5.Cu")
		(net "P5E_PEX0_STN0_RX_DN<7>")
	)
	(segment
		(start 83.48472 -269.423388)
		(end 82.834226 -264.832846)
		(width 0.1651)
		(layer "In5.Cu")
		(net "P5E_PEX0_STN0_RX_DN<7>")
	)
	(segment
		(start 82.449924 -281.649932)
		(end 82.184494 -281.649932)
		(width 0.1143)
		(layer "In5.Cu")
		(net "P5E_PEX0_STN0_RX_DN<7>")
	)
	(segment
		(start 83.9216 -281.315922)
		(end 83.950048 -281.315922)
		(width 0.1143)
		(layer "In5.Cu")
		(net "P5E_PEX0_STN0_RX_DN<7>")
	)
	(segment
		(start 82.173826 -281.270202)
		(end 83.87588 -281.270202)
		(width 0.1143)
		(layer "In5.Cu")
		(net "P5E_PEX0_STN0_RX_DN<7>")
	)
	(segment
		(start 79.273654 -160.449006)
		(end 75.005692 -141.708886)
		(width 0.1651)
		(layer "In5.Cu")
		(net "P5E_PEX0_STN0_RX_DN<7>")
	)
	(segment
		(start 71.966582 -137.43178)
		(end 67.473576 -135.604504)
		(width 0.1651)
		(layer "In5.Cu")
		(net "P5E_PEX0_STN0_RX_DN<7>")
	)
	(segment
		(start 82.070194 -281.373834)
		(end 82.173826 -281.270202)
		(width 0.1143)
		(layer "In5.Cu")
		(net "P5E_PEX0_STN0_RX_DN<7>")
	)
	(segment
		(start 82.070194 -281.535632)
		(end 82.070194 -281.373834)
		(width 0.1143)
		(layer "In5.Cu")
		(net "P5E_PEX0_STN0_RX_DN<7>")
	)
	(segment
		(start 73.269602 -138.752834)
		(end 71.966582 -137.43178)
		(width 0.1651)
		(layer "In5.Cu")
		(net "P5E_PEX0_STN0_RX_DN<7>")
	)
	(segment
		(start 73.963784 -140.537438)
		(end 73.687432 -139.870434)
		(width 0.1651)
		(layer "In5.Cu")
		(net "P5E_PEX0_STN0_RX_DN<7>")
	)
	(segment
		(start 84.760562 -276.308312)
		(end 83.48472 -269.423388)
		(width 0.1651)
		(layer "In5.Cu")
		(net "P5E_PEX0_STN0_RX_DN<7>")
	)
	(segment
		(start 67.473576 -135.604504)
		(end 65.4939 -135.604504)
		(width 0.1651)
		(layer "In5.Cu")
		(net "P5E_PEX0_STN0_RX_DN<7>")
	)
	(segment
		(start 82.834226 -264.832846)
		(end 79.27975 -160.476184)
		(width 0.1651)
		(layer "In5.Cu")
		(net "P5E_PEX0_STN0_RX_DN<7>")
	)
	(segment
		(start 84.1883 -281.315922)
		(end 84.398358 -281.107134)
		(width 0.1651)
		(layer "In5.Cu")
		(net "P5E_PEX0_STN0_RX_DN<7>")
	)
	(segment
		(start 75.005438 -141.708378)
		(end 75.005438 -141.708632)
		(width 0.1651)
		(layer "In5.Cu")
		(net "P5E_PEX0_STN0_RX_DN<7>")
	)
	(segment
		(start 74.821034 -141.394688)
		(end 73.963784 -140.537438)
		(width 0.1651)
		(layer "In5.Cu")
		(net "P5E_PEX0_STN0_RX_DN<7>")
	)
	(segment
		(start 73.687432 -139.870434)
		(end 73.687432 -139.464288)
		(width 0.1651)
		(layer "In5.Cu")
		(net "P5E_PEX0_STN0_RX_DN<7>")
	)
	(segment
		(start 75.005692 -141.708886)
		(end 75.005438 -141.708378)
		(width 0.1651)
		(layer "In5.Cu")
		(net "P5E_PEX0_STN0_RX_DN<7>")
	)
	(segment
		(start 84.398358 -281.107134)
		(end 84.67217 -280.46807)
		(width 0.1651)
		(layer "In5.Cu")
		(net "P5E_PEX0_STN0_RX_DN<7>")
	)
	(segment
		(start 75.005438 -141.708632)
		(end 74.821034 -141.394688)
		(width 0.1651)
		(layer "In5.Cu")
		(net "P5E_PEX0_STN0_RX_DN<7>")
	)
	(segment
		(start 65.4939 -135.604504)
		(end 65.20307 -135.313674)
		(width 0.1651)
		(layer "In5.Cu")
		(net "P5E_PEX0_STN0_RX_DN<7>")
	)
	(segment
		(start 118.013734 -367.14938)
		(end 117.188742 -368.495326)
		(width 0.1651)
		(layer "In5.Cu")
		(net "P5E_PEX1_STN6_RX_DP<103>")
	)
	(segment
		(start 116.469922 -374.899174)
		(end 116.037106 -374.899174)
		(width 0.1651)
		(layer "In5.Cu")
		(net "P5E_PEX1_STN6_RX_DP<103>")
	)
	(segment
		(start 167.200072 -316.115192)
		(end 167.085772 -316.229492)
		(width 0.1143)
		(layer "In5.Cu")
		(net "P5E_PEX1_STN6_RX_DP<103>")
	)
	(segment
		(start 117.976142 -366.992154)
		(end 118.013734 -367.14938)
		(width 0.1651)
		(layer "In5.Cu")
		(net "P5E_PEX1_STN6_RX_DP<103>")
	)
	(segment
		(start 166.629842 -319.79108)
		(end 166.406322 -320.0146)
		(width 0.1143)
		(layer "In5.Cu")
		(net "P5E_PEX1_STN6_RX_DP<103>")
	)
	(segment
		(start 165.8874 -319.96888)
		(end 165.858952 -319.96888)
		(width 0.1143)
		(layer "In5.Cu")
		(net "P5E_PEX1_STN6_RX_DP<103>")
	)
	(segment
		(start 166.629842 -316.455298)
		(end 166.629842 -319.79108)
		(width 0.1143)
		(layer "In5.Cu")
		(net "P5E_PEX1_STN6_RX_DP<103>")
	)
	(segment
		(start 118.392448 -366.531906)
		(end 118.235222 -366.569498)
		(width 0.1651)
		(layer "In5.Cu")
		(net "P5E_PEX1_STN6_RX_DP<103>")
	)
	(segment
		(start 123.034298 -358.18191)
		(end 122.627898 -359.622344)
		(width 0.1651)
		(layer "In5.Cu")
		(net "P5E_PEX1_STN6_RX_DP<103>")
	)
	(segment
		(start 118.235222 -366.569498)
		(end 117.976142 -366.992154)
		(width 0.1651)
		(layer "In5.Cu")
		(net "P5E_PEX1_STN6_RX_DP<103>")
	)
	(segment
		(start 165.585394 -319.96888)
		(end 164.541454 -320.825622)
		(width 0.1651)
		(layer "In5.Cu")
		(net "P5E_PEX1_STN6_RX_DP<103>")
	)
	(segment
		(start 118.911116 -365.520732)
		(end 118.622572 -365.991394)
		(width 0.1651)
		(layer "In5.Cu")
		(net "P5E_PEX1_STN6_RX_DP<103>")
	)
	(segment
		(start 167.200072 -315.849762)
		(end 167.200072 -316.115192)
		(width 0.1143)
		(layer "In5.Cu")
		(net "P5E_PEX1_STN6_RX_DP<103>")
	)
	(segment
		(start 164.541454 -320.825622)
		(end 154.399234 -326.830182)
		(width 0.1651)
		(layer "In5.Cu")
		(net "P5E_PEX1_STN6_RX_DP<103>")
	)
	(segment
		(start 154.399234 -326.830182)
		(end 147.059904 -331.487272)
		(width 0.1651)
		(layer "In5.Cu")
		(net "P5E_PEX1_STN6_RX_DP<103>")
	)
	(segment
		(start 166.406322 -320.0146)
		(end 165.93312 -320.0146)
		(width 0.1143)
		(layer "In5.Cu")
		(net "P5E_PEX1_STN6_RX_DP<103>")
	)
	(segment
		(start 165.93312 -320.0146)
		(end 165.8874 -319.96888)
		(width 0.1143)
		(layer "In5.Cu")
		(net "P5E_PEX1_STN6_RX_DP<103>")
	)
	(segment
		(start 122.627898 -359.622344)
		(end 119.02948 -365.492284)
		(width 0.1651)
		(layer "In5.Cu")
		(net "P5E_PEX1_STN6_RX_DP<103>")
	)
	(segment
		(start 167.085772 -316.229492)
		(end 166.855648 -316.229492)
		(width 0.1143)
		(layer "In5.Cu")
		(net "P5E_PEX1_STN6_RX_DP<103>")
	)
	(segment
		(start 147.059904 -331.487272)
		(end 144.120108 -332.341474)
		(width 0.1651)
		(layer "In5.Cu")
		(net "P5E_PEX1_STN6_RX_DP<103>")
	)
	(segment
		(start 118.622572 -365.991394)
		(end 118.65102 -366.109758)
		(width 0.1651)
		(layer "In5.Cu")
		(net "P5E_PEX1_STN6_RX_DP<103>")
	)
	(segment
		(start 116.6876 -374.681496)
		(end 116.469922 -374.899174)
		(width 0.1651)
		(layer "In5.Cu")
		(net "P5E_PEX1_STN6_RX_DP<103>")
	)
	(segment
		(start 144.120108 -332.341474)
		(end 123.66625 -341.143844)
		(width 0.1651)
		(layer "In5.Cu")
		(net "P5E_PEX1_STN6_RX_DP<103>")
	)
	(segment
		(start 123.66625 -341.143844)
		(end 123.034298 -342.001856)
		(width 0.1651)
		(layer "In5.Cu")
		(net "P5E_PEX1_STN6_RX_DP<103>")
	)
	(segment
		(start 117.188742 -368.495326)
		(end 116.6876 -370.272056)
		(width 0.1651)
		(layer "In5.Cu")
		(net "P5E_PEX1_STN6_RX_DP<103>")
	)
	(segment
		(start 123.034298 -342.001856)
		(end 123.034298 -358.18191)
		(width 0.1651)
		(layer "In5.Cu")
		(net "P5E_PEX1_STN6_RX_DP<103>")
	)
	(segment
		(start 165.858952 -319.96888)
		(end 165.585394 -319.96888)
		(width 0.1651)
		(layer "In5.Cu")
		(net "P5E_PEX1_STN6_RX_DP<103>")
	)
	(segment
		(start 116.6876 -370.272056)
		(end 116.6876 -374.681496)
		(width 0.1651)
		(layer "In5.Cu")
		(net "P5E_PEX1_STN6_RX_DP<103>")
	)
	(segment
		(start 119.02948 -365.492284)
		(end 118.911116 -365.520732)
		(width 0.1651)
		(layer "In5.Cu")
		(net "P5E_PEX1_STN6_RX_DP<103>")
	)
	(segment
		(start 166.855648 -316.229492)
		(end 166.629842 -316.455298)
		(width 0.1143)
		(layer "In5.Cu")
		(net "P5E_PEX1_STN6_RX_DP<103>")
	)
	(segment
		(start 115.910106 -374.772174)
		(end 115.910106 -374.390158)
		(width 0.1651)
		(layer "In5.Cu")
		(net "P5E_PEX1_STN6_RX_DP<103>")
	)
	(segment
		(start 116.037106 -374.899174)
		(end 115.910106 -374.772174)
		(width 0.1651)
		(layer "In5.Cu")
		(net "P5E_PEX1_STN6_RX_DP<103>")
	)
	(segment
		(start 118.65102 -366.109758)
		(end 118.392448 -366.531906)
		(width 0.1651)
		(layer "In5.Cu")
		(net "P5E_PEX1_STN6_RX_DP<103>")
	)
	(segment
		(start 286.009334 -103.2002)
		(end 283.480256 -103.2002)
		(width 0.13462)
		(layer "F.Cu")
		(net "P5E_PEX2_STN1_RX_DP<18>")
	)
	(segment
		(start 283.325062 -103.045006)
		(end 282.842462 -103.045006)
		(width 0.13462)
		(layer "F.Cu")
		(net "P5E_PEX2_STN1_RX_DP<18>")
	)
	(segment
		(start 286.296862 -102.912672)
		(end 286.009334 -103.2002)
		(width 0.13462)
		(layer "F.Cu")
		(net "P5E_PEX2_STN1_RX_DP<18>")
	)
	(segment
		(start 283.480256 -103.2002)
		(end 283.325062 -103.045006)
		(width 0.13462)
		(layer "F.Cu")
		(net "P5E_PEX2_STN1_RX_DP<18>")
	)
	(segment
		(start 262.581644 -154.568144)
		(end 262.861552 -158.791148)
		(width 0.1651)
		(layer "In5.Cu")
		(net "P5E_PEX2_STN1_RX_DP<18>")
	)
	(segment
		(start 266.037822 -118.307358)
		(end 265.043412 -120.379236)
		(width 0.1651)
		(layer "In5.Cu")
		(net "P5E_PEX2_STN1_RX_DP<18>")
	)
	(segment
		(start 293.1795 -271.600168)
		(end 293.1795 -273.45513)
		(width 0.1143)
		(layer "In5.Cu")
		(net "P5E_PEX2_STN1_RX_DP<18>")
	)
	(segment
		(start 286.296862 -102.912672)
		(end 286.006032 -103.203502)
		(width 0.1651)
		(layer "In5.Cu")
		(net "P5E_PEX2_STN1_RX_DP<18>")
	)
	(segment
		(start 293.749476 -273.784314)
		(end 293.749476 -274.049744)
		(width 0.1143)
		(layer "In5.Cu")
		(net "P5E_PEX2_STN1_RX_DP<18>")
	)
	(segment
		(start 293.394384 -273.670014)
		(end 293.635176 -273.670014)
		(width 0.1143)
		(layer "In5.Cu")
		(net "P5E_PEX2_STN1_RX_DP<18>")
	)
	(segment
		(start 293.13378 -269.772892)
		(end 293.13378 -271.526)
		(width 0.1651)
		(layer "In5.Cu")
		(net "P5E_PEX2_STN1_RX_DP<18>")
	)
	(segment
		(start 263.905746 -126.602744)
		(end 262.301736 -150.34133)
		(width 0.1651)
		(layer "In5.Cu")
		(net "P5E_PEX2_STN1_RX_DP<18>")
	)
	(segment
		(start 293.635176 -273.670014)
		(end 293.749476 -273.784314)
		(width 0.1143)
		(layer "In5.Cu")
		(net "P5E_PEX2_STN1_RX_DP<18>")
	)
	(segment
		(start 265.043412 -120.379236)
		(end 263.905746 -126.602744)
		(width 0.1651)
		(layer "In5.Cu")
		(net "P5E_PEX2_STN1_RX_DP<18>")
	)
	(segment
		(start 286.006032 -103.203502)
		(end 284.13075 -103.203502)
		(width 0.1651)
		(layer "In5.Cu")
		(net "P5E_PEX2_STN1_RX_DP<18>")
	)
	(segment
		(start 293.13378 -271.526)
		(end 293.13378 -271.554448)
		(width 0.1143)
		(layer "In5.Cu")
		(net "P5E_PEX2_STN1_RX_DP<18>")
	)
	(segment
		(start 276.93112 -106.897932)
		(end 266.037822 -118.307358)
		(width 0.1651)
		(layer "In5.Cu")
		(net "P5E_PEX2_STN1_RX_DP<18>")
	)
	(segment
		(start 262.861552 -158.791148)
		(end 263.988042 -165.304216)
		(width 0.1651)
		(layer "In5.Cu")
		(net "P5E_PEX2_STN1_RX_DP<18>")
	)
	(segment
		(start 284.13075 -103.203502)
		(end 276.93112 -106.897932)
		(width 0.1651)
		(layer "In5.Cu")
		(net "P5E_PEX2_STN1_RX_DP<18>")
	)
	(segment
		(start 293.1795 -273.45513)
		(end 293.394384 -273.670014)
		(width 0.1143)
		(layer "In5.Cu")
		(net "P5E_PEX2_STN1_RX_DP<18>")
	)
	(segment
		(start 262.301736 -150.34133)
		(end 262.581644 -154.568144)
		(width 0.1651)
		(layer "In5.Cu")
		(net "P5E_PEX2_STN1_RX_DP<18>")
	)
	(segment
		(start 263.988042 -165.304216)
		(end 293.13378 -269.772892)
		(width 0.1651)
		(layer "In5.Cu")
		(net "P5E_PEX2_STN1_RX_DP<18>")
	)
	(segment
		(start 293.13378 -271.554448)
		(end 293.1795 -271.600168)
		(width 0.1143)
		(layer "In5.Cu")
		(net "P5E_PEX2_STN1_RX_DP<18>")
	)
	(segment
		(start 417.825682 -28.225242)
		(end 417.508944 -28.54198)
		(width 0.13462)
		(layer "F.Cu")
		(net "P5E_PEX3_STN2_TX_C_DN<36>")
	)
	(segment
		(start 416.068002 -28.390088)
		(end 415.564828 -28.390088)
		(width 0.13462)
		(layer "F.Cu")
		(net "P5E_PEX3_STN2_TX_C_DN<36>")
	)
	(segment
		(start 416.219894 -28.54198)
		(end 416.068002 -28.390088)
		(width 0.13462)
		(layer "F.Cu")
		(net "P5E_PEX3_STN2_TX_C_DN<36>")
	)
	(segment
		(start 417.508944 -28.54198)
		(end 416.219894 -28.54198)
		(width 0.13462)
		(layer "F.Cu")
		(net "P5E_PEX3_STN2_TX_C_DN<36>")
	)
	(segment
		(start 419.968426 -387.587744)
		(end 417.84651 -385.858766)
		(width 0.1651)
		(layer "In9.Cu")
		(net "P5E_PEX3_STN7_RX_DN<118>")
	)
	(segment
		(start 379.37567 -309.83428)
		(end 379.37567 -309.690516)
		(width 0.1651)
		(layer "In9.Cu")
		(net "P5E_PEX3_STN7_RX_DN<118>")
	)
	(segment
		(start 432.689762 -409.490164)
		(end 432.689762 -409.108148)
		(width 0.1651)
		(layer "In9.Cu")
		(net "P5E_PEX3_STN7_RX_DN<118>")
	)
	(segment
		(start 379.02515 -310.1848)
		(end 379.37567 -309.83428)
		(width 0.1651)
		(layer "In9.Cu")
		(net "P5E_PEX3_STN7_RX_DN<118>")
	)
	(segment
		(start 376.539252 -328.262488)
		(end 372.667276 -324.39229)
		(width 0.1651)
		(layer "In9.Cu")
		(net "P5E_PEX3_STN7_RX_DN<118>")
	)
	(segment
		(start 379.37567 -309.690516)
		(end 379.725682 -309.340504)
		(width 0.1651)
		(layer "In9.Cu")
		(net "P5E_PEX3_STN7_RX_DN<118>")
	)
	(segment
		(start 380.219966 -308.84622)
		(end 380.569978 -308.496208)
		(width 0.1651)
		(layer "In9.Cu")
		(net "P5E_PEX3_STN7_RX_DN<118>")
	)
	(segment
		(start 432.689762 -409.108148)
		(end 432.816762 -408.981148)
		(width 0.1651)
		(layer "In9.Cu")
		(net "P5E_PEX3_STN7_RX_DN<118>")
	)
	(segment
		(start 373.90578 -316.106048)
		(end 374.200674 -315.708284)
		(width 0.1651)
		(layer "In9.Cu")
		(net "P5E_PEX3_STN7_RX_DN<118>")
	)
	(segment
		(start 371.85854 -322.438014)
		(end 371.85854 -319.840102)
		(width 0.1651)
		(layer "In9.Cu")
		(net "P5E_PEX3_STN7_RX_DN<118>")
	)
	(segment
		(start 374.200674 -315.708284)
		(end 374.342914 -315.687202)
		(width 0.1651)
		(layer "In9.Cu")
		(net "P5E_PEX3_STN7_RX_DN<118>")
	)
	(segment
		(start 417.640262 -358.223058)
		(end 417.640262 -341.874856)
		(width 0.1651)
		(layer "In9.Cu")
		(net "P5E_PEX3_STN7_RX_DN<118>")
	)
	(segment
		(start 381.064008 -308.145688)
		(end 381.064008 -308.002178)
		(width 0.1651)
		(layer "In9.Cu")
		(net "P5E_PEX3_STN7_RX_DN<118>")
	)
	(segment
		(start 387.301994 -306.920138)
		(end 387.434328 -307.052472)
		(width 0.1143)
		(layer "In9.Cu")
		(net "P5E_PEX3_STN7_RX_DN<118>")
	)
	(segment
		(start 378.073666 -328.745596)
		(end 376.539252 -328.262488)
		(width 0.1651)
		(layer "In9.Cu")
		(net "P5E_PEX3_STN7_RX_DN<118>")
	)
	(segment
		(start 373.926862 -316.248034)
		(end 373.90578 -316.106048)
		(width 0.1651)
		(layer "In9.Cu")
		(net "P5E_PEX3_STN7_RX_DN<118>")
	)
	(segment
		(start 378.881386 -310.1848)
		(end 379.02515 -310.1848)
		(width 0.1651)
		(layer "In9.Cu")
		(net "P5E_PEX3_STN7_RX_DN<118>")
	)
	(segment
		(start 382.67513 -306.965858)
		(end 383.892552 -306.965858)
		(width 0.1651)
		(layer "In9.Cu")
		(net "P5E_PEX3_STN7_RX_DN<118>")
	)
	(segment
		(start 400.572986 -333.908146)
		(end 378.073666 -328.745596)
		(width 0.1651)
		(layer "In9.Cu")
		(net "P5E_PEX3_STN7_RX_DN<118>")
	)
	(segment
		(start 373.63146 -316.646306)
		(end 373.926862 -316.248034)
		(width 0.1651)
		(layer "In9.Cu")
		(net "P5E_PEX3_STN7_RX_DN<118>")
	)
	(segment
		(start 379.869446 -309.340504)
		(end 380.219966 -308.989984)
		(width 0.1651)
		(layer "In9.Cu")
		(net "P5E_PEX3_STN7_RX_DN<118>")
	)
	(segment
		(start 375.765822 -313.769502)
		(end 376.061224 -313.371484)
		(width 0.1651)
		(layer "In9.Cu")
		(net "P5E_PEX3_STN7_RX_DN<118>")
	)
	(segment
		(start 375.34977 -314.330334)
		(end 375.328688 -314.188348)
		(width 0.1651)
		(layer "In9.Cu")
		(net "P5E_PEX3_STN7_RX_DN<118>")
	)
	(segment
		(start 376.040142 -313.229244)
		(end 376.624088 -312.442098)
		(width 0.1651)
		(layer "In9.Cu")
		(net "P5E_PEX3_STN7_RX_DN<118>")
	)
	(segment
		(start 432.816762 -408.981148)
		(end 433.155598 -408.981148)
		(width 0.1651)
		(layer "In9.Cu")
		(net "P5E_PEX3_STN7_RX_DN<118>")
	)
	(segment
		(start 417.209478 -384.910838)
		(end 416.883088 -383.78003)
		(width 0.1651)
		(layer "In9.Cu")
		(net "P5E_PEX3_STN7_RX_DN<118>")
	)
	(segment
		(start 387.434328 -307.052472)
		(end 387.434328 -307.203856)
		(width 0.1143)
		(layer "In9.Cu")
		(net "P5E_PEX3_STN7_RX_DN<118>")
	)
	(segment
		(start 374.912128 -314.749434)
		(end 375.054368 -314.728352)
		(width 0.1651)
		(layer "In9.Cu")
		(net "P5E_PEX3_STN7_RX_DN<118>")
	)
	(segment
		(start 375.623582 -313.790584)
		(end 375.765822 -313.769502)
		(width 0.1651)
		(layer "In9.Cu")
		(net "P5E_PEX3_STN7_RX_DN<118>")
	)
	(segment
		(start 383.921 -306.965858)
		(end 383.96672 -306.920138)
		(width 0.1143)
		(layer "In9.Cu")
		(net "P5E_PEX3_STN7_RX_DN<118>")
	)
	(segment
		(start 387.434328 -307.203856)
		(end 387.338316 -307.299868)
		(width 0.1143)
		(layer "In9.Cu")
		(net "P5E_PEX3_STN7_RX_DN<118>")
	)
	(segment
		(start 372.667276 -324.39229)
		(end 371.85854 -322.438014)
		(width 0.1651)
		(layer "In9.Cu")
		(net "P5E_PEX3_STN7_RX_DN<118>")
	)
	(segment
		(start 375.054368 -314.728352)
		(end 375.34977 -314.330334)
		(width 0.1651)
		(layer "In9.Cu")
		(net "P5E_PEX3_STN7_RX_DN<118>")
	)
	(segment
		(start 417.197032 -341.175848)
		(end 400.572986 -333.908146)
		(width 0.1651)
		(layer "In9.Cu")
		(net "P5E_PEX3_STN7_RX_DN<118>")
	)
	(segment
		(start 376.061224 -313.371484)
		(end 376.040142 -313.229244)
		(width 0.1651)
		(layer "In9.Cu")
		(net "P5E_PEX3_STN7_RX_DN<118>")
	)
	(segment
		(start 433.846732 -395.174724)
		(end 433.395374 -394.355066)
		(width 0.1651)
		(layer "In9.Cu")
		(net "P5E_PEX3_STN7_RX_DN<118>")
	)
	(segment
		(start 426.186346 -389.800338)
		(end 419.968426 -387.587744)
		(width 0.1651)
		(layer "In9.Cu")
		(net "P5E_PEX3_STN7_RX_DN<118>")
	)
	(segment
		(start 375.328688 -314.188348)
		(end 375.623582 -313.790584)
		(width 0.1651)
		(layer "In9.Cu")
		(net "P5E_PEX3_STN7_RX_DN<118>")
	)
	(segment
		(start 417.84651 -385.858766)
		(end 417.209478 -384.910838)
		(width 0.1651)
		(layer "In9.Cu")
		(net "P5E_PEX3_STN7_RX_DN<118>")
	)
	(segment
		(start 381.693674 -307.372512)
		(end 382.67513 -306.965858)
		(width 0.1651)
		(layer "In9.Cu")
		(net "P5E_PEX3_STN7_RX_DN<118>")
	)
	(segment
		(start 381.064008 -308.002178)
		(end 381.693674 -307.372512)
		(width 0.1651)
		(layer "In9.Cu")
		(net "P5E_PEX3_STN7_RX_DN<118>")
	)
	(segment
		(start 374.617234 -315.147198)
		(end 374.912128 -314.749434)
		(width 0.1651)
		(layer "In9.Cu")
		(net "P5E_PEX3_STN7_RX_DN<118>")
	)
	(segment
		(start 383.892552 -306.965858)
		(end 383.921 -306.965858)
		(width 0.1143)
		(layer "In9.Cu")
		(net "P5E_PEX3_STN7_RX_DN<118>")
	)
	(segment
		(start 374.342914 -315.687202)
		(end 374.638316 -315.289184)
		(width 0.1651)
		(layer "In9.Cu")
		(net "P5E_PEX3_STN7_RX_DN<118>")
	)
	(segment
		(start 383.96672 -306.920138)
		(end 387.301994 -306.920138)
		(width 0.1143)
		(layer "In9.Cu")
		(net "P5E_PEX3_STN7_RX_DN<118>")
	)
	(segment
		(start 380.569978 -308.496208)
		(end 380.713488 -308.496208)
		(width 0.1651)
		(layer "In9.Cu")
		(net "P5E_PEX3_STN7_RX_DN<118>")
	)
	(segment
		(start 433.846732 -408.290014)
		(end 433.846732 -395.174724)
		(width 0.1651)
		(layer "In9.Cu")
		(net "P5E_PEX3_STN7_RX_DN<118>")
	)
	(segment
		(start 374.638316 -315.289184)
		(end 374.617234 -315.147198)
		(width 0.1651)
		(layer "In9.Cu")
		(net "P5E_PEX3_STN7_RX_DN<118>")
	)
	(segment
		(start 416.883088 -383.78003)
		(end 417.640262 -358.223058)
		(width 0.1651)
		(layer "In9.Cu")
		(net "P5E_PEX3_STN7_RX_DN<118>")
	)
	(segment
		(start 372.769892 -317.637414)
		(end 373.489728 -316.667134)
		(width 0.1651)
		(layer "In9.Cu")
		(net "P5E_PEX3_STN7_RX_DN<118>")
	)
	(segment
		(start 376.624088 -312.442098)
		(end 378.881386 -310.1848)
		(width 0.1651)
		(layer "In9.Cu")
		(net "P5E_PEX3_STN7_RX_DN<118>")
	)
	(segment
		(start 380.219966 -308.989984)
		(end 380.219966 -308.84622)
		(width 0.1651)
		(layer "In9.Cu")
		(net "P5E_PEX3_STN7_RX_DN<118>")
	)
	(segment
		(start 379.725682 -309.340504)
		(end 379.869446 -309.340504)
		(width 0.1651)
		(layer "In9.Cu")
		(net "P5E_PEX3_STN7_RX_DN<118>")
	)
	(segment
		(start 371.85854 -319.840102)
		(end 372.769892 -317.637414)
		(width 0.1651)
		(layer "In9.Cu")
		(net "P5E_PEX3_STN7_RX_DN<118>")
	)
	(segment
		(start 373.489728 -316.667134)
		(end 373.63146 -316.646306)
		(width 0.1651)
		(layer "In9.Cu")
		(net "P5E_PEX3_STN7_RX_DN<118>")
	)
	(segment
		(start 433.395374 -394.355066)
		(end 426.186346 -389.800338)
		(width 0.1651)
		(layer "In9.Cu")
		(net "P5E_PEX3_STN7_RX_DN<118>")
	)
	(segment
		(start 433.155598 -408.981148)
		(end 433.846732 -408.290014)
		(width 0.1651)
		(layer "In9.Cu")
		(net "P5E_PEX3_STN7_RX_DN<118>")
	)
	(segment
		(start 380.713488 -308.496208)
		(end 381.064008 -308.145688)
		(width 0.1651)
		(layer "In9.Cu")
		(net "P5E_PEX3_STN7_RX_DN<118>")
	)
	(segment
		(start 387.338316 -307.299868)
		(end 387.050026 -307.299868)
		(width 0.1143)
		(layer "In9.Cu")
		(net "P5E_PEX3_STN7_RX_DN<118>")
	)
	(segment
		(start 417.640262 -341.874856)
		(end 417.197032 -341.175848)
		(width 0.1651)
		(layer "In9.Cu")
		(net "P5E_PEX3_STN7_RX_DN<118>")
	)
	(segment
		(start 156.500068 -157.73273)
		(end 156.497528 -157.73527)
		(width 0.13208)
		(layer "F.Cu")
		(net "NIC2_DATA_IN")
	)
	(segment
		(start 156.497528 -157.73527)
		(end 156.140658 -157.3784)
		(width 0.13208)
		(layer "F.Cu")
		(net "NIC2_DATA_IN")
	)
	(segment
		(start 160.078928 -156.560012)
		(end 158.90621 -157.73273)
		(width 0.13208)
		(layer "F.Cu")
		(net "NIC2_DATA_IN")
	)
	(segment
		(start 158.90621 -157.73273)
		(end 156.500068 -157.73273)
		(width 0.13208)
		(layer "F.Cu")
		(net "NIC2_DATA_IN")
	)
	(segment
		(start 162.14217 -156.560012)
		(end 160.078928 -156.560012)
		(width 0.13208)
		(layer "F.Cu")
		(net "NIC2_DATA_IN")
	)
	(segment
		(start 156.140658 -157.3784)
		(end 155.107894 -157.3784)
		(width 0.13208)
		(layer "F.Cu")
		(net "NIC2_DATA_IN")
	)
	(via
		(at 156.497528 -157.73527)
		(size 0.762)
		(drill 0.381)
		(layers "F.Cu" "B.Cu")
		(net "NIC2_DATA_IN")
	)
	(segment
		(start 73.908666 -135.607806)
		(end 82.07375 -135.607806)
		(width 0.13462)
		(layer "F.Cu")
		(net "P5E_PEX0_STN0_TX_C_DN<7>")
	)
	(segment
		(start 73.745852 -135.444992)
		(end 73.908666 -135.607806)
		(width 0.13462)
		(layer "F.Cu")
		(net "P5E_PEX0_STN0_TX_C_DN<7>")
	)
	(segment
		(start 73.257664 -135.444992)
		(end 73.745852 -135.444992)
		(width 0.13462)
		(layer "F.Cu")
		(net "P5E_PEX0_STN0_TX_C_DN<7>")
	)
	(segment
		(start 82.07375 -135.607806)
		(end 82.394806 -135.28675)
		(width 0.13462)
		(layer "F.Cu")
		(net "P5E_PEX0_STN0_TX_C_DN<7>")
	)
	(segment
		(start 118.374668 -344.539062)
		(end 118.054628 -344.219022)
		(width 0.13462)
		(layer "F.Cu")
		(net "P5E_PEX1_STN6_TX_C_DP<109>")
	)
	(segment
		(start 118.374668 -345.170506)
		(end 118.374668 -344.539062)
		(width 0.13462)
		(layer "F.Cu")
		(net "P5E_PEX1_STN6_TX_C_DP<109>")
	)
	(segment
		(start 118.080028 -345.465146)
		(end 118.374668 -345.170506)
		(width 0.13462)
		(layer "F.Cu")
		(net "P5E_PEX1_STN6_TX_C_DP<109>")
	)
	(segment
		(start 118.370858 -345.755976)
		(end 118.370858 -346.31503)
		(width 0.1651)
		(layer "In13.Cu")
		(net "P5E_PEX1_STN6_TX_C_DP<109>")
	)
	(segment
		(start 118.716806 -393.038076)
		(end 119.431562 -393.333986)
		(width 0.1651)
		(layer "In13.Cu")
		(net "P5E_PEX1_STN6_TX_C_DP<109>")
	)
	(segment
		(start 116.558822 -358.668828)
		(end 109.891322 -365.41075)
		(width 0.1651)
		(layer "In13.Cu")
		(net "P5E_PEX1_STN6_TX_C_DP<109>")
	)
	(segment
		(start 111.341154 -388.736332)
		(end 112.89411 -390.002522)
		(width 0.1651)
		(layer "In13.Cu")
		(net "P5E_PEX1_STN6_TX_C_DP<109>")
	)
	(segment
		(start 121.184924 -408.17292)
		(end 120.658636 -408.699208)
		(width 0.1651)
		(layer "In13.Cu")
		(net "P5E_PEX1_STN6_TX_C_DP<109>")
	)
	(segment
		(start 117.520974 -392.638788)
		(end 117.637306 -392.590782)
		(width 0.1651)
		(layer "In13.Cu")
		(net "P5E_PEX1_STN6_TX_C_DP<109>")
	)
	(segment
		(start 116.816378 -358.042718)
		(end 116.558822 -358.668828)
		(width 0.1651)
		(layer "In13.Cu")
		(net "P5E_PEX1_STN6_TX_C_DP<109>")
	)
	(segment
		(start 109.955838 -386.674106)
		(end 111.31804 -388.701534)
		(width 0.1651)
		(layer "In13.Cu")
		(net "P5E_PEX1_STN6_TX_C_DP<109>")
	)
	(segment
		(start 116.816378 -347.86951)
		(end 116.816378 -358.042718)
		(width 0.1651)
		(layer "In13.Cu")
		(net "P5E_PEX1_STN6_TX_C_DP<109>")
	)
	(segment
		(start 119.431562 -393.333986)
		(end 119.93499 -393.837414)
		(width 0.1651)
		(layer "In13.Cu")
		(net "P5E_PEX1_STN6_TX_C_DP<109>")
	)
	(segment
		(start 112.89411 -390.002776)
		(end 114.447066 -391.268966)
		(width 0.1651)
		(layer "In13.Cu")
		(net "P5E_PEX1_STN6_TX_C_DP<109>")
	)
	(segment
		(start 118.600728 -393.086082)
		(end 118.716806 -393.038076)
		(width 0.1651)
		(layer "In13.Cu")
		(net "P5E_PEX1_STN6_TX_C_DP<109>")
	)
	(segment
		(start 117.015006 -392.332718)
		(end 117.063266 -392.44905)
		(width 0.1651)
		(layer "In13.Cu")
		(net "P5E_PEX1_STN6_TX_C_DP<109>")
	)
	(segment
		(start 112.89411 -390.002522)
		(end 112.89411 -390.002776)
		(width 0.1651)
		(layer "In13.Cu")
		(net "P5E_PEX1_STN6_TX_C_DP<109>")
	)
	(segment
		(start 118.142766 -392.896344)
		(end 118.600728 -393.086082)
		(width 0.1651)
		(layer "In13.Cu")
		(net "P5E_PEX1_STN6_TX_C_DP<109>")
	)
	(segment
		(start 121.184924 -395.087348)
		(end 121.184924 -408.17292)
		(width 0.1651)
		(layer "In13.Cu")
		(net "P5E_PEX1_STN6_TX_C_DP<109>")
	)
	(segment
		(start 119.93499 -393.837414)
		(end 119.93499 -393.963144)
		(width 0.1651)
		(layer "In13.Cu")
		(net "P5E_PEX1_STN6_TX_C_DP<109>")
	)
	(segment
		(start 114.447066 -391.268966)
		(end 117.015006 -392.332718)
		(width 0.1651)
		(layer "In13.Cu")
		(net "P5E_PEX1_STN6_TX_C_DP<109>")
	)
	(segment
		(start 118.080028 -345.465146)
		(end 118.370858 -345.755976)
		(width 0.1651)
		(layer "In13.Cu")
		(net "P5E_PEX1_STN6_TX_C_DP<109>")
	)
	(segment
		(start 117.063266 -392.44905)
		(end 117.520974 -392.638788)
		(width 0.1651)
		(layer "In13.Cu")
		(net "P5E_PEX1_STN6_TX_C_DP<109>")
	)
	(segment
		(start 120.310148 -408.572208)
		(end 120.310148 -408.190192)
		(width 0.1651)
		(layer "In13.Cu")
		(net "P5E_PEX1_STN6_TX_C_DP<109>")
	)
	(segment
		(start 120.285256 -394.31341)
		(end 120.410986 -394.31341)
		(width 0.1651)
		(layer "In13.Cu")
		(net "P5E_PEX1_STN6_TX_C_DP<109>")
	)
	(segment
		(start 109.296454 -366.595406)
		(end 109.181392 -383.886202)
		(width 0.1651)
		(layer "In13.Cu")
		(net "P5E_PEX1_STN6_TX_C_DP<109>")
	)
	(segment
		(start 120.437148 -408.699208)
		(end 120.310148 -408.572208)
		(width 0.1651)
		(layer "In13.Cu")
		(net "P5E_PEX1_STN6_TX_C_DP<109>")
	)
	(segment
		(start 120.410986 -394.31341)
		(end 121.184924 -395.087348)
		(width 0.1651)
		(layer "In13.Cu")
		(net "P5E_PEX1_STN6_TX_C_DP<109>")
	)
	(segment
		(start 109.181392 -383.886202)
		(end 109.955838 -386.674106)
		(width 0.1651)
		(layer "In13.Cu")
		(net "P5E_PEX1_STN6_TX_C_DP<109>")
	)
	(segment
		(start 111.31804 -388.701534)
		(end 111.317786 -388.701788)
		(width 0.1651)
		(layer "In13.Cu")
		(net "P5E_PEX1_STN6_TX_C_DP<109>")
	)
	(segment
		(start 119.93499 -393.963144)
		(end 120.285256 -394.31341)
		(width 0.1651)
		(layer "In13.Cu")
		(net "P5E_PEX1_STN6_TX_C_DP<109>")
	)
	(segment
		(start 118.370858 -346.31503)
		(end 116.816378 -347.86951)
		(width 0.1651)
		(layer "In13.Cu")
		(net "P5E_PEX1_STN6_TX_C_DP<109>")
	)
	(segment
		(start 117.637306 -392.590782)
		(end 118.09476 -392.780266)
		(width 0.1651)
		(layer "In13.Cu")
		(net "P5E_PEX1_STN6_TX_C_DP<109>")
	)
	(segment
		(start 120.658636 -408.699208)
		(end 120.437148 -408.699208)
		(width 0.1651)
		(layer "In13.Cu")
		(net "P5E_PEX1_STN6_TX_C_DP<109>")
	)
	(segment
		(start 111.317786 -388.701788)
		(end 111.341154 -388.736332)
		(width 0.1651)
		(layer "In13.Cu")
		(net "P5E_PEX1_STN6_TX_C_DP<109>")
	)
	(segment
		(start 109.891322 -365.41075)
		(end 109.296454 -366.595406)
		(width 0.1651)
		(layer "In13.Cu")
		(net "P5E_PEX1_STN6_TX_C_DP<109>")
	)
	(segment
		(start 118.09476 -392.780266)
		(end 118.142766 -392.896344)
		(width 0.1651)
		(layer "In13.Cu")
		(net "P5E_PEX1_STN6_TX_C_DP<109>")
	)
	(segment
		(start 277.57247 -108.61548)
		(end 277.742904 -108.445046)
		(width 0.13462)
		(layer "F.Cu")
		(net "P5E_PEX2_STN1_TX_C_DN<21>")
	)
	(segment
		(start 269.105126 -108.29544)
		(end 269.425166 -108.61548)
		(width 0.13462)
		(layer "F.Cu")
		(net "P5E_PEX2_STN1_TX_C_DN<21>")
	)
	(segment
		(start 277.742904 -108.445046)
		(end 278.242268 -108.445046)
		(width 0.13462)
		(layer "F.Cu")
		(net "P5E_PEX2_STN1_TX_C_DN<21>")
	)
	(segment
		(start 269.425166 -108.61548)
		(end 277.57247 -108.61548)
		(width 0.13462)
		(layer "F.Cu")
		(net "P5E_PEX2_STN1_TX_C_DN<21>")
	)
	(segment
		(start 358.964992 -33.790128)
		(end 358.487472 -33.790128)
		(width 0.13462)
		(layer "F.Cu")
		(net "P5E_PEX3_STN2_RX_DN<47>")
	)
	(segment
		(start 358.487472 -33.790128)
		(end 358.32542 -33.95218)
		(width 0.13462)
		(layer "F.Cu")
		(net "P5E_PEX3_STN2_RX_DN<47>")
	)
	(segment
		(start 355.803962 -33.95218)
		(end 355.510592 -33.65881)
		(width 0.13462)
		(layer "F.Cu")
		(net "P5E_PEX3_STN2_RX_DN<47>")
	)
	(segment
		(start 358.32542 -33.95218)
		(end 355.803962 -33.95218)
		(width 0.13462)
		(layer "F.Cu")
		(net "P5E_PEX3_STN2_RX_DN<47>")
	)
	(segment
		(start 357.188262 -35.355276)
		(end 357.188262 -34.98596)
		(width 0.1651)
		(layer "In7.Cu")
		(net "P5E_PEX3_STN2_RX_DN<47>")
	)
	(segment
		(start 392.749786 -273.365214)
		(end 392.635486 -273.479514)
		(width 0.1143)
		(layer "In7.Cu")
		(net "P5E_PEX3_STN2_RX_DN<47>")
	)
	(segment
		(start 358.56545 -49.854612)
		(end 357.2637 -40.2209)
		(width 0.1651)
		(layer "In7.Cu")
		(net "P5E_PEX3_STN2_RX_DN<47>")
	)
	(segment
		(start 392.21791 -268.824202)
		(end 391.848594 -267.026644)
		(width 0.1651)
		(layer "In7.Cu")
		(net "P5E_PEX3_STN2_RX_DN<47>")
	)
	(segment
		(start 358.531922 -85.574378)
		(end 358.721406 -62.60846)
		(width 0.1651)
		(layer "In7.Cu")
		(net "P5E_PEX3_STN2_RX_DN<47>")
	)
	(segment
		(start 368.940842 -119.914416)
		(end 363.736636 -102.745032)
		(width 0.1651)
		(layer "In7.Cu")
		(net "P5E_PEX3_STN2_RX_DN<47>")
	)
	(segment
		(start 392.370056 -273.328638)
		(end 392.370056 -271.41932)
		(width 0.1143)
		(layer "In7.Cu")
		(net "P5E_PEX3_STN2_RX_DN<47>")
	)
	(segment
		(start 392.520932 -273.479514)
		(end 392.370056 -273.328638)
		(width 0.1143)
		(layer "In7.Cu")
		(net "P5E_PEX3_STN2_RX_DN<47>")
	)
	(segment
		(start 392.415776 -271.345152)
		(end 392.415776 -270.472916)
		(width 0.1651)
		(layer "In7.Cu")
		(net "P5E_PEX3_STN2_RX_DN<47>")
	)
	(segment
		(start 358.721406 -60.243212)
		(end 358.44988 -57.243218)
		(width 0.1651)
		(layer "In7.Cu")
		(net "P5E_PEX3_STN2_RX_DN<47>")
	)
	(segment
		(start 392.749786 -273.099784)
		(end 392.749786 -273.365214)
		(width 0.1143)
		(layer "In7.Cu")
		(net "P5E_PEX3_STN2_RX_DN<47>")
	)
	(segment
		(start 358.44988 -57.243218)
		(end 358.56545 -49.854612)
		(width 0.1651)
		(layer "In7.Cu")
		(net "P5E_PEX3_STN2_RX_DN<47>")
	)
	(segment
		(start 389.928354 -238.434118)
		(end 372.194836 -144.65427)
		(width 0.1651)
		(layer "In7.Cu")
		(net "P5E_PEX3_STN2_RX_DN<47>")
	)
	(segment
		(start 392.635486 -273.479514)
		(end 392.520932 -273.479514)
		(width 0.1143)
		(layer "In7.Cu")
		(net "P5E_PEX3_STN2_RX_DN<47>")
	)
	(segment
		(start 363.736382 -102.744524)
		(end 358.531922 -85.574378)
		(width 0.1651)
		(layer "In7.Cu")
		(net "P5E_PEX3_STN2_RX_DN<47>")
	)
	(segment
		(start 372.194836 -144.65427)
		(end 368.940842 -119.914416)
		(width 0.1651)
		(layer "In7.Cu")
		(net "P5E_PEX3_STN2_RX_DN<47>")
	)
	(segment
		(start 392.415776 -270.472916)
		(end 392.21791 -268.824202)
		(width 0.1651)
		(layer "In7.Cu")
		(net "P5E_PEX3_STN2_RX_DN<47>")
	)
	(segment
		(start 358.721406 -62.60846)
		(end 358.721406 -60.243212)
		(width 0.1651)
		(layer "In7.Cu")
		(net "P5E_PEX3_STN2_RX_DN<47>")
	)
	(segment
		(start 392.370056 -271.41932)
		(end 392.415776 -271.3736)
		(width 0.1143)
		(layer "In7.Cu")
		(net "P5E_PEX3_STN2_RX_DN<47>")
	)
	(segment
		(start 391.848594 -267.026644)
		(end 391.435336 -263.578594)
		(width 0.1651)
		(layer "In7.Cu")
		(net "P5E_PEX3_STN2_RX_DN<47>")
	)
	(segment
		(start 391.435336 -263.578594)
		(end 391.435336 -262.327898)
		(width 0.1651)
		(layer "In7.Cu")
		(net "P5E_PEX3_STN2_RX_DN<47>")
	)
	(segment
		(start 391.435336 -262.327898)
		(end 391.501122 -255.61163)
		(width 0.1651)
		(layer "In7.Cu")
		(net "P5E_PEX3_STN2_RX_DN<47>")
	)
	(segment
		(start 391.501122 -255.61163)
		(end 389.928354 -238.434118)
		(width 0.1651)
		(layer "In7.Cu")
		(net "P5E_PEX3_STN2_RX_DN<47>")
	)
	(segment
		(start 363.736636 -102.745032)
		(end 363.736382 -102.744524)
		(width 0.1651)
		(layer "In7.Cu")
		(net "P5E_PEX3_STN2_RX_DN<47>")
	)
	(segment
		(start 355.801422 -33.94964)
		(end 355.510592 -33.65881)
		(width 0.1651)
		(layer "In7.Cu")
		(net "P5E_PEX3_STN2_RX_DN<47>")
	)
	(segment
		(start 356.151942 -33.94964)
		(end 355.801422 -33.94964)
		(width 0.1651)
		(layer "In7.Cu")
		(net "P5E_PEX3_STN2_RX_DN<47>")
	)
	(segment
		(start 357.188262 -34.98596)
		(end 356.151942 -33.94964)
		(width 0.1651)
		(layer "In7.Cu")
		(net "P5E_PEX3_STN2_RX_DN<47>")
	)
	(segment
		(start 392.415776 -271.3736)
		(end 392.415776 -271.345152)
		(width 0.1143)
		(layer "In7.Cu")
		(net "P5E_PEX3_STN2_RX_DN<47>")
	)
	(segment
		(start 357.2637 -40.2209)
		(end 357.188262 -35.355276)
		(width 0.1651)
		(layer "In7.Cu")
		(net "P5E_PEX3_STN2_RX_DN<47>")
	)
	(segment
		(start 381.764032 -314.349638)
		(end 383.12852 -321.669664)
		(width 0.1651)
		(layer "In9.Cu")
		(net "P5E_PEX3_STN7_RX_DP<120>")
	)
	(segment
		(start 422.784778 -341.009986)
		(end 423.576242 -342.154002)
		(width 0.1651)
		(layer "In9.Cu")
		(net "P5E_PEX3_STN7_RX_DP<120>")
	)
	(segment
		(start 415.829242 -337.730084)
		(end 422.784778 -341.009986)
		(width 0.1651)
		(layer "In9.Cu")
		(net "P5E_PEX3_STN7_RX_DP<120>")
	)
	(segment
		(start 383.869438 -323.948552)
		(end 385.435094 -326.090534)
		(width 0.1651)
		(layer "In9.Cu")
		(net "P5E_PEX3_STN7_RX_DP<120>")
	)
	(segment
		(start 387.624828 -308.873398)
		(end 387.380988 -308.629558)
		(width 0.1143)
		(layer "In9.Cu")
		(net "P5E_PEX3_STN7_RX_DP<120>")
	)
	(segment
		(start 381.929894 -310.041036)
		(end 381.764032 -314.349638)
		(width 0.1651)
		(layer "In9.Cu")
		(net "P5E_PEX3_STN7_RX_DP<120>")
	)
	(segment
		(start 415.828988 -337.72983)
		(end 415.829242 -337.730084)
		(width 0.1651)
		(layer "In9.Cu")
		(net "P5E_PEX3_STN7_RX_DP<120>")
	)
	(segment
		(start 420.997634 -367.248694)
		(end 420.856918 -367.328704)
		(width 0.1651)
		(layer "In9.Cu")
		(net "P5E_PEX3_STN7_RX_DP<120>")
	)
	(segment
		(start 419.61689 -382.699006)
		(end 419.48989 -382.572006)
		(width 0.1651)
		(layer "In9.Cu")
		(net "P5E_PEX3_STN7_RX_DP<120>")
	)
	(segment
		(start 420.856918 -367.328704)
		(end 420.725854 -367.806478)
		(width 0.1651)
		(layer "In9.Cu")
		(net "P5E_PEX3_STN7_RX_DP<120>")
	)
	(segment
		(start 420.36492 -382.172972)
		(end 419.838886 -382.699006)
		(width 0.1651)
		(layer "In9.Cu")
		(net "P5E_PEX3_STN7_RX_DP<120>")
	)
	(segment
		(start 419.48989 -382.572006)
		(end 419.48989 -382.18999)
		(width 0.1651)
		(layer "In9.Cu")
		(net "P5E_PEX3_STN7_RX_DP<120>")
	)
	(segment
		(start 387.719316 -309.199788)
		(end 387.624828 -309.1053)
		(width 0.1143)
		(layer "In9.Cu")
		(net "P5E_PEX3_STN7_RX_DP<120>")
	)
	(segment
		(start 421.128444 -366.771174)
		(end 420.99738 -367.248694)
		(width 0.1651)
		(layer "In9.Cu")
		(net "P5E_PEX3_STN7_RX_DP<120>")
	)
	(segment
		(start 421.320214 -366.072674)
		(end 421.179498 -366.152684)
		(width 0.1651)
		(layer "In9.Cu")
		(net "P5E_PEX3_STN7_RX_DP<120>")
	)
	(segment
		(start 387.624828 -309.1053)
		(end 387.624828 -308.873398)
		(width 0.1143)
		(layer "In9.Cu")
		(net "P5E_PEX3_STN7_RX_DP<120>")
	)
	(segment
		(start 387.999986 -309.199788)
		(end 387.719316 -309.199788)
		(width 0.1143)
		(layer "In9.Cu")
		(net "P5E_PEX3_STN7_RX_DP<120>")
	)
	(segment
		(start 423.576242 -342.154002)
		(end 423.576242 -357.846122)
		(width 0.1651)
		(layer "In9.Cu")
		(net "P5E_PEX3_STN7_RX_DP<120>")
	)
	(segment
		(start 420.36492 -369.555268)
		(end 420.36492 -382.172972)
		(width 0.1651)
		(layer "In9.Cu")
		(net "P5E_PEX3_STN7_RX_DP<120>")
	)
	(segment
		(start 383.867152 -308.583838)
		(end 383.073148 -308.583838)
		(width 0.1651)
		(layer "In9.Cu")
		(net "P5E_PEX3_STN7_RX_DP<120>")
	)
	(segment
		(start 383.12852 -321.669664)
		(end 383.869438 -323.948552)
		(width 0.1651)
		(layer "In9.Cu")
		(net "P5E_PEX3_STN7_RX_DP<120>")
	)
	(segment
		(start 408.873706 -334.450182)
		(end 415.828988 -337.72983)
		(width 0.1651)
		(layer "In9.Cu")
		(net "P5E_PEX3_STN7_RX_DP<120>")
	)
	(segment
		(start 385.435094 -326.090534)
		(end 387.772656 -327.769982)
		(width 0.1651)
		(layer "In9.Cu")
		(net "P5E_PEX3_STN7_RX_DP<120>")
	)
	(segment
		(start 420.805864 -367.94694)
		(end 420.36492 -369.555268)
		(width 0.1651)
		(layer "In9.Cu")
		(net "P5E_PEX3_STN7_RX_DP<120>")
	)
	(segment
		(start 383.94132 -308.629558)
		(end 383.8956 -308.583838)
		(width 0.1143)
		(layer "In9.Cu")
		(net "P5E_PEX3_STN7_RX_DP<120>")
	)
	(segment
		(start 423.576242 -357.846122)
		(end 421.64254 -364.896654)
		(width 0.1651)
		(layer "In9.Cu")
		(net "P5E_PEX3_STN7_RX_DP<120>")
	)
	(segment
		(start 421.385492 -365.480346)
		(end 421.45077 -365.595154)
		(width 0.1651)
		(layer "In9.Cu")
		(net "P5E_PEX3_STN7_RX_DP<120>")
	)
	(segment
		(start 421.64254 -364.896654)
		(end 421.527732 -364.962186)
		(width 0.1651)
		(layer "In9.Cu")
		(net "P5E_PEX3_STN7_RX_DP<120>")
	)
	(segment
		(start 419.838886 -382.699006)
		(end 419.61689 -382.699006)
		(width 0.1651)
		(layer "In9.Cu")
		(net "P5E_PEX3_STN7_RX_DP<120>")
	)
	(segment
		(start 387.380988 -308.629558)
		(end 383.94132 -308.629558)
		(width 0.1143)
		(layer "In9.Cu")
		(net "P5E_PEX3_STN7_RX_DP<120>")
	)
	(segment
		(start 421.45077 -365.595154)
		(end 421.320214 -366.072674)
		(width 0.1651)
		(layer "In9.Cu")
		(net "P5E_PEX3_STN7_RX_DP<120>")
	)
	(segment
		(start 421.527732 -364.962186)
		(end 421.385492 -365.480346)
		(width 0.1651)
		(layer "In9.Cu")
		(net "P5E_PEX3_STN7_RX_DP<120>")
	)
	(segment
		(start 383.073148 -308.583838)
		(end 382.263396 -309.39359)
		(width 0.1651)
		(layer "In9.Cu")
		(net "P5E_PEX3_STN7_RX_DP<120>")
	)
	(segment
		(start 420.99738 -367.248694)
		(end 420.997634 -367.248694)
		(width 0.1651)
		(layer "In9.Cu")
		(net "P5E_PEX3_STN7_RX_DP<120>")
	)
	(segment
		(start 383.8956 -308.583838)
		(end 383.867152 -308.583838)
		(width 0.1143)
		(layer "In9.Cu")
		(net "P5E_PEX3_STN7_RX_DP<120>")
	)
	(segment
		(start 420.725854 -367.806478)
		(end 420.805864 -367.94694)
		(width 0.1651)
		(layer "In9.Cu")
		(net "P5E_PEX3_STN7_RX_DP<120>")
	)
	(segment
		(start 421.048434 -366.630712)
		(end 421.128444 -366.771174)
		(width 0.1651)
		(layer "In9.Cu")
		(net "P5E_PEX3_STN7_RX_DP<120>")
	)
	(segment
		(start 387.772656 -327.769982)
		(end 408.873706 -334.450182)
		(width 0.1651)
		(layer "In9.Cu")
		(net "P5E_PEX3_STN7_RX_DP<120>")
	)
	(segment
		(start 382.263396 -309.39359)
		(end 381.929894 -310.041036)
		(width 0.1651)
		(layer "In9.Cu")
		(net "P5E_PEX3_STN7_RX_DP<120>")
	)
	(segment
		(start 421.179498 -366.152684)
		(end 421.048434 -366.630712)
		(width 0.1651)
		(layer "In9.Cu")
		(net "P5E_PEX3_STN7_RX_DP<120>")
	)
	(segment
		(start 68.169536 -119.435118)
		(end 68.006468 -119.27205)
		(width 0.13462)
		(layer "F.Cu")
		(net "P5E_PEX0_STN0_RX_DP<0>")
	)
	(segment
		(start 67.352418 -119.27205)
		(end 67.05727 -119.567198)
		(width 0.13462)
		(layer "F.Cu")
		(net "P5E_PEX0_STN0_RX_DP<0>")
	)
	(segment
		(start 68.65747 -119.435118)
		(end 68.169536 -119.435118)
		(width 0.13462)
		(layer "F.Cu")
		(net "P5E_PEX0_STN0_RX_DP<0>")
	)
	(segment
		(start 68.006468 -119.27205)
		(end 67.352418 -119.27205)
		(width 0.13462)
		(layer "F.Cu")
		(net "P5E_PEX0_STN0_RX_DP<0>")
	)
	(segment
		(start 77.912722 -125.620018)
		(end 77.935836 -125.780038)
		(width 0.1651)
		(layer "In5.Cu")
		(net "P5E_PEX0_STN0_RX_DP<0>")
	)
	(segment
		(start 69.410834 -119.931942)
		(end 69.411088 -119.931942)
		(width 0.1651)
		(layer "In5.Cu")
		(net "P5E_PEX0_STN0_RX_DP<0>")
	)
	(segment
		(start 77.355954 -125.347476)
		(end 77.51572 -125.324108)
		(width 0.1651)
		(layer "In5.Cu")
		(net "P5E_PEX0_STN0_RX_DP<0>")
	)
	(segment
		(start 69.473064 -120.081548)
		(end 69.931026 -120.271032)
		(width 0.1651)
		(layer "In5.Cu")
		(net "P5E_PEX0_STN0_RX_DP<0>")
	)
	(segment
		(start 76.958444 -125.051058)
		(end 77.355954 -125.347476)
		(width 0.1651)
		(layer "In5.Cu")
		(net "P5E_PEX0_STN0_RX_DP<0>")
	)
	(segment
		(start 67.826636 -119.276368)
		(end 68.284344 -119.465852)
		(width 0.1651)
		(layer "In5.Cu")
		(net "P5E_PEX0_STN0_RX_DP<0>")
	)
	(segment
		(start 76.378308 -124.618496)
		(end 76.538328 -124.595128)
		(width 0.1651)
		(layer "In5.Cu")
		(net "P5E_PEX0_STN0_RX_DP<0>")
	)
	(segment
		(start 79.97952 -287.97377)
		(end 79.97952 -288.185606)
		(width 0.1143)
		(layer "In5.Cu")
		(net "P5E_PEX0_STN0_RX_DP<0>")
	)
	(segment
		(start 85.188552 -131.045458)
		(end 85.914484 -131.999482)
		(width 0.1651)
		(layer "In5.Cu")
		(net "P5E_PEX0_STN0_RX_DP<0>")
	)
	(segment
		(start 88.976708 -145.627852)
		(end 89.371678 -149.84476)
		(width 0.1651)
		(layer "In5.Cu")
		(net "P5E_PEX0_STN0_RX_DP<0>")
	)
	(segment
		(start 69.411088 -119.931942)
		(end 69.473064 -120.081548)
		(width 0.1651)
		(layer "In5.Cu")
		(net "P5E_PEX0_STN0_RX_DP<0>")
	)
	(segment
		(start 83.924648 -287.683956)
		(end 83.8962 -287.683956)
		(width 0.1143)
		(layer "In5.Cu")
		(net "P5E_PEX0_STN0_RX_DP<0>")
	)
	(segment
		(start 67.05727 -119.567198)
		(end 67.3481 -119.276368)
		(width 0.1651)
		(layer "In5.Cu")
		(net "P5E_PEX0_STN0_RX_DP<0>")
	)
	(segment
		(start 80.223614 -287.729676)
		(end 79.97952 -287.97377)
		(width 0.1143)
		(layer "In5.Cu")
		(net "P5E_PEX0_STN0_RX_DP<0>")
	)
	(segment
		(start 68.284344 -119.465852)
		(end 68.284344 -119.465598)
		(width 0.1651)
		(layer "In5.Cu")
		(net "P5E_PEX0_STN0_RX_DP<0>")
	)
	(segment
		(start 68.34632 -119.615204)
		(end 68.804282 -119.804688)
		(width 0.1651)
		(layer "In5.Cu")
		(net "P5E_PEX0_STN0_RX_DP<0>")
	)
	(segment
		(start 76.93533 -124.891038)
		(end 76.958444 -125.051058)
		(width 0.1651)
		(layer "In5.Cu")
		(net "P5E_PEX0_STN0_RX_DP<0>")
	)
	(segment
		(start 78.333346 -126.076456)
		(end 78.493112 -126.053088)
		(width 0.1651)
		(layer "In5.Cu")
		(net "P5E_PEX0_STN0_RX_DP<0>")
	)
	(segment
		(start 76.538328 -124.595128)
		(end 76.93533 -124.891038)
		(width 0.1651)
		(layer "In5.Cu")
		(net "P5E_PEX0_STN0_RX_DP<0>")
	)
	(segment
		(start 68.284344 -119.465598)
		(end 68.34632 -119.615204)
		(width 0.1651)
		(layer "In5.Cu")
		(net "P5E_PEX0_STN0_RX_DP<0>")
	)
	(segment
		(start 87.559388 -286.969708)
		(end 86.42731 -287.683956)
		(width 0.1651)
		(layer "In5.Cu")
		(net "P5E_PEX0_STN0_RX_DP<0>")
	)
	(segment
		(start 83.8962 -287.683956)
		(end 83.85048 -287.729676)
		(width 0.1143)
		(layer "In5.Cu")
		(net "P5E_PEX0_STN0_RX_DP<0>")
	)
	(segment
		(start 89.823798 -168.526206)
		(end 89.157302 -231.903016)
		(width 0.1651)
		(layer "In5.Cu")
		(net "P5E_PEX0_STN0_RX_DP<0>")
	)
	(segment
		(start 69.931026 -120.271032)
		(end 70.080378 -120.209056)
		(width 0.1651)
		(layer "In5.Cu")
		(net "P5E_PEX0_STN0_RX_DP<0>")
	)
	(segment
		(start 70.599808 -120.547892)
		(end 71.05777 -120.737376)
		(width 0.1651)
		(layer "In5.Cu")
		(net "P5E_PEX0_STN0_RX_DP<0>")
	)
	(segment
		(start 70.537832 -120.398286)
		(end 70.599808 -120.547892)
		(width 0.1651)
		(layer "In5.Cu")
		(net "P5E_PEX0_STN0_RX_DP<0>")
	)
	(segment
		(start 68.804282 -119.804688)
		(end 68.953634 -119.742712)
		(width 0.1651)
		(layer "In5.Cu")
		(net "P5E_PEX0_STN0_RX_DP<0>")
	)
	(segment
		(start 71.207122 -120.6754)
		(end 72.509126 -121.214388)
		(width 0.1651)
		(layer "In5.Cu")
		(net "P5E_PEX0_STN0_RX_DP<0>")
	)
	(segment
		(start 77.935836 -125.780038)
		(end 78.333346 -126.076456)
		(width 0.1651)
		(layer "In5.Cu")
		(net "P5E_PEX0_STN0_RX_DP<0>")
	)
	(segment
		(start 67.3481 -119.276368)
		(end 67.826636 -119.276368)
		(width 0.1651)
		(layer "In5.Cu")
		(net "P5E_PEX0_STN0_RX_DP<0>")
	)
	(segment
		(start 70.537578 -120.398286)
		(end 70.537832 -120.398286)
		(width 0.1651)
		(layer "In5.Cu")
		(net "P5E_PEX0_STN0_RX_DP<0>")
	)
	(segment
		(start 70.080378 -120.209056)
		(end 70.537578 -120.398286)
		(width 0.1651)
		(layer "In5.Cu")
		(net "P5E_PEX0_STN0_RX_DP<0>")
	)
	(segment
		(start 89.371678 -149.84476)
		(end 89.823798 -168.526206)
		(width 0.1651)
		(layer "In5.Cu")
		(net "P5E_PEX0_STN0_RX_DP<0>")
	)
	(segment
		(start 99.209352 -273.645376)
		(end 96.615504 -278.22525)
		(width 0.1651)
		(layer "In5.Cu")
		(net "P5E_PEX0_STN0_RX_DP<0>")
	)
	(segment
		(start 89.157302 -231.903016)
		(end 90.69324 -239.28705)
		(width 0.1651)
		(layer "In5.Cu")
		(net "P5E_PEX0_STN0_RX_DP<0>")
	)
	(segment
		(start 74.007726 -122.708162)
		(end 75.957938 -124.162312)
		(width 0.1651)
		(layer "In5.Cu")
		(net "P5E_PEX0_STN0_RX_DP<0>")
	)
	(segment
		(start 79.97952 -288.185606)
		(end 79.86522 -288.299906)
		(width 0.1143)
		(layer "In5.Cu")
		(net "P5E_PEX0_STN0_RX_DP<0>")
	)
	(segment
		(start 78.493112 -126.053088)
		(end 85.188552 -131.045458)
		(width 0.1651)
		(layer "In5.Cu")
		(net "P5E_PEX0_STN0_RX_DP<0>")
	)
	(segment
		(start 86.42731 -287.683956)
		(end 83.924648 -287.683956)
		(width 0.1651)
		(layer "In5.Cu")
		(net "P5E_PEX0_STN0_RX_DP<0>")
	)
	(segment
		(start 99.390708 -269.159482)
		(end 99.209352 -273.645376)
		(width 0.1651)
		(layer "In5.Cu")
		(net "P5E_PEX0_STN0_RX_DP<0>")
	)
	(segment
		(start 72.509126 -121.214388)
		(end 74.007726 -122.708162)
		(width 0.1651)
		(layer "In5.Cu")
		(net "P5E_PEX0_STN0_RX_DP<0>")
	)
	(segment
		(start 96.615504 -278.22525)
		(end 87.559388 -286.969708)
		(width 0.1651)
		(layer "In5.Cu")
		(net "P5E_PEX0_STN0_RX_DP<0>")
	)
	(segment
		(start 68.953634 -119.742712)
		(end 69.410834 -119.931942)
		(width 0.1651)
		(layer "In5.Cu")
		(net "P5E_PEX0_STN0_RX_DP<0>")
	)
	(segment
		(start 75.957938 -124.162312)
		(end 75.981052 -124.322332)
		(width 0.1651)
		(layer "In5.Cu")
		(net "P5E_PEX0_STN0_RX_DP<0>")
	)
	(segment
		(start 85.914484 -131.999482)
		(end 88.976708 -145.627852)
		(width 0.1651)
		(layer "In5.Cu")
		(net "P5E_PEX0_STN0_RX_DP<0>")
	)
	(segment
		(start 90.69324 -239.28705)
		(end 99.390708 -269.159482)
		(width 0.1651)
		(layer "In5.Cu")
		(net "P5E_PEX0_STN0_RX_DP<0>")
	)
	(segment
		(start 83.85048 -287.729676)
		(end 80.223614 -287.729676)
		(width 0.1143)
		(layer "In5.Cu")
		(net "P5E_PEX0_STN0_RX_DP<0>")
	)
	(segment
		(start 77.51572 -125.324108)
		(end 77.912722 -125.620018)
		(width 0.1651)
		(layer "In5.Cu")
		(net "P5E_PEX0_STN0_RX_DP<0>")
	)
	(segment
		(start 71.05777 -120.737376)
		(end 71.207122 -120.6754)
		(width 0.1651)
		(layer "In5.Cu")
		(net "P5E_PEX0_STN0_RX_DP<0>")
	)
	(segment
		(start 79.86522 -288.299906)
		(end 79.59979 -288.299906)
		(width 0.1143)
		(layer "In5.Cu")
		(net "P5E_PEX0_STN0_RX_DP<0>")
	)
	(segment
		(start 75.981052 -124.322332)
		(end 76.378308 -124.618496)
		(width 0.1651)
		(layer "In5.Cu")
		(net "P5E_PEX0_STN0_RX_DP<0>")
	)
	(segment
		(start 118.648988 -356.831646)
		(end 118.969028 -356.511606)
		(width 0.13462)
		(layer "F.Cu")
		(net "P5E_PEX1_STN6_TX_C_DN<108>")
	)
	(segment
		(start 118.648988 -357.46309)
		(end 118.648988 -356.831646)
		(width 0.13462)
		(layer "F.Cu")
		(net "P5E_PEX1_STN6_TX_C_DN<108>")
	)
	(segment
		(start 118.943628 -357.75773)
		(end 118.648988 -357.46309)
		(width 0.13462)
		(layer "F.Cu")
		(net "P5E_PEX1_STN6_TX_C_DN<108>")
	)
	(segment
		(start 122.521472 -394.119608)
		(end 122.871992 -394.470128)
		(width 0.1651)
		(layer "In13.Cu")
		(net "P5E_PEX1_STN6_TX_C_DN<108>")
	)
	(segment
		(start 122.413776 -394.119608)
		(end 122.521472 -394.119608)
		(width 0.1651)
		(layer "In13.Cu")
		(net "P5E_PEX1_STN6_TX_C_DN<108>")
	)
	(segment
		(start 123.666758 -395.37259)
		(end 123.666758 -409.38958)
		(width 0.1651)
		(layer "In13.Cu")
		(net "P5E_PEX1_STN6_TX_C_DN<108>")
	)
	(segment
		(start 118.652798 -358.622092)
		(end 118.511828 -358.952546)
		(width 0.1651)
		(layer "In13.Cu")
		(net "P5E_PEX1_STN6_TX_C_DN<108>")
	)
	(segment
		(start 122.637042 -410.080968)
		(end 122.510042 -410.207968)
		(width 0.1651)
		(layer "In13.Cu")
		(net "P5E_PEX1_STN6_TX_C_DN<108>")
	)
	(segment
		(start 112.357154 -387.949694)
		(end 115.058698 -390.152636)
		(width 0.1651)
		(layer "In13.Cu")
		(net "P5E_PEX1_STN6_TX_C_DN<108>")
	)
	(segment
		(start 122.97537 -410.080968)
		(end 122.637042 -410.080968)
		(width 0.1651)
		(layer "In13.Cu")
		(net "P5E_PEX1_STN6_TX_C_DN<108>")
	)
	(segment
		(start 123.666758 -409.38958)
		(end 122.97537 -410.080968)
		(width 0.1651)
		(layer "In13.Cu")
		(net "P5E_PEX1_STN6_TX_C_DN<108>")
	)
	(segment
		(start 111.140494 -386.138928)
		(end 112.357154 -387.949694)
		(width 0.1651)
		(layer "In13.Cu")
		(net "P5E_PEX1_STN6_TX_C_DN<108>")
	)
	(segment
		(start 110.55985 -367.050066)
		(end 110.449106 -383.649474)
		(width 0.1651)
		(layer "In13.Cu")
		(net "P5E_PEX1_STN6_TX_C_DN<108>")
	)
	(segment
		(start 122.871992 -394.470128)
		(end 122.871992 -394.577824)
		(width 0.1651)
		(layer "In13.Cu")
		(net "P5E_PEX1_STN6_TX_C_DN<108>")
	)
	(segment
		(start 120.822212 -392.528044)
		(end 122.413776 -394.119608)
		(width 0.1651)
		(layer "In13.Cu")
		(net "P5E_PEX1_STN6_TX_C_DN<108>")
	)
	(segment
		(start 122.871992 -394.577824)
		(end 123.666758 -395.37259)
		(width 0.1651)
		(layer "In13.Cu")
		(net "P5E_PEX1_STN6_TX_C_DN<108>")
	)
	(segment
		(start 111.02594 -366.12195)
		(end 110.55985 -367.050066)
		(width 0.1651)
		(layer "In13.Cu")
		(net "P5E_PEX1_STN6_TX_C_DN<108>")
	)
	(segment
		(start 120.791732 -392.527536)
		(end 120.79224 -392.528044)
		(width 0.1651)
		(layer "In13.Cu")
		(net "P5E_PEX1_STN6_TX_C_DN<108>")
	)
	(segment
		(start 110.449106 -383.649474)
		(end 111.140494 -386.138928)
		(width 0.1651)
		(layer "In13.Cu")
		(net "P5E_PEX1_STN6_TX_C_DN<108>")
	)
	(segment
		(start 118.652798 -358.04856)
		(end 118.652798 -358.622092)
		(width 0.1651)
		(layer "In13.Cu")
		(net "P5E_PEX1_STN6_TX_C_DN<108>")
	)
	(segment
		(start 118.943628 -357.75773)
		(end 118.652798 -358.04856)
		(width 0.1651)
		(layer "In13.Cu")
		(net "P5E_PEX1_STN6_TX_C_DN<108>")
	)
	(segment
		(start 122.510042 -410.207968)
		(end 122.510042 -410.589984)
		(width 0.1651)
		(layer "In13.Cu")
		(net "P5E_PEX1_STN6_TX_C_DN<108>")
	)
	(segment
		(start 118.511828 -358.952546)
		(end 111.02594 -366.12195)
		(width 0.1651)
		(layer "In13.Cu")
		(net "P5E_PEX1_STN6_TX_C_DN<108>")
	)
	(segment
		(start 120.79224 -392.528044)
		(end 120.822212 -392.528044)
		(width 0.1651)
		(layer "In13.Cu")
		(net "P5E_PEX1_STN6_TX_C_DN<108>")
	)
	(segment
		(start 115.058698 -390.152636)
		(end 120.791732 -392.527536)
		(width 0.1651)
		(layer "In13.Cu")
		(net "P5E_PEX1_STN6_TX_C_DN<108>")
	)
	(segment
		(start 286.296862 -119.222774)
		(end 286.007556 -119.51208)
		(width 0.13462)
		(layer "F.Cu")
		(net "P5E_PEX2_STN1_RX_DP<24>")
	)
	(segment
		(start 286.007556 -119.51208)
		(end 283.482034 -119.51208)
		(width 0.13462)
		(layer "F.Cu")
		(net "P5E_PEX2_STN1_RX_DP<24>")
	)
	(segment
		(start 283.325062 -119.355108)
		(end 282.842462 -119.355108)
		(width 0.13462)
		(layer "F.Cu")
		(net "P5E_PEX2_STN1_RX_DP<24>")
	)
	(segment
		(start 283.482034 -119.51208)
		(end 283.325062 -119.355108)
		(width 0.13462)
		(layer "F.Cu")
		(net "P5E_PEX2_STN1_RX_DP<24>")
	)
	(segment
		(start 298.879514 -271.600168)
		(end 298.879514 -273.45513)
		(width 0.1143)
		(layer "In5.Cu")
		(net "P5E_PEX2_STN1_RX_DP<24>")
	)
	(segment
		(start 282.212034 -120.150382)
		(end 276.596348 -125.476508)
		(width 0.1651)
		(layer "In5.Cu")
		(net "P5E_PEX2_STN1_RX_DP<24>")
	)
	(segment
		(start 284.256988 -119.513604)
		(end 282.212034 -120.150382)
		(width 0.1651)
		(layer "In5.Cu")
		(net "P5E_PEX2_STN1_RX_DP<24>")
	)
	(segment
		(start 276.596348 -125.476508)
		(end 274.97405 -127.992124)
		(width 0.1651)
		(layer "In5.Cu")
		(net "P5E_PEX2_STN1_RX_DP<24>")
	)
	(segment
		(start 271.498568 -140.622274)
		(end 269.44701 -145.16735)
		(width 0.1651)
		(layer "In5.Cu")
		(net "P5E_PEX2_STN1_RX_DP<24>")
	)
	(segment
		(start 299.44949 -273.784314)
		(end 299.44949 -274.049744)
		(width 0.1143)
		(layer "In5.Cu")
		(net "P5E_PEX2_STN1_RX_DP<24>")
	)
	(segment
		(start 274.621498 -128.909064)
		(end 273.202908 -137.613898)
		(width 0.1651)
		(layer "In5.Cu")
		(net "P5E_PEX2_STN1_RX_DP<24>")
	)
	(segment
		(start 273.202908 -137.613898)
		(end 271.498568 -140.622274)
		(width 0.1651)
		(layer "In5.Cu")
		(net "P5E_PEX2_STN1_RX_DP<24>")
	)
	(segment
		(start 286.006032 -119.513604)
		(end 284.256988 -119.513604)
		(width 0.1651)
		(layer "In5.Cu")
		(net "P5E_PEX2_STN1_RX_DP<24>")
	)
	(segment
		(start 298.879514 -273.45513)
		(end 299.094398 -273.670014)
		(width 0.1143)
		(layer "In5.Cu")
		(net "P5E_PEX2_STN1_RX_DP<24>")
	)
	(segment
		(start 286.296862 -119.222774)
		(end 286.006032 -119.513604)
		(width 0.1651)
		(layer "In5.Cu")
		(net "P5E_PEX2_STN1_RX_DP<24>")
	)
	(segment
		(start 269.44701 -145.16735)
		(end 268.266926 -151.562054)
		(width 0.1651)
		(layer "In5.Cu")
		(net "P5E_PEX2_STN1_RX_DP<24>")
	)
	(segment
		(start 298.833794 -271.526)
		(end 298.833794 -271.554448)
		(width 0.1143)
		(layer "In5.Cu")
		(net "P5E_PEX2_STN1_RX_DP<24>")
	)
	(segment
		(start 299.094398 -273.670014)
		(end 299.33519 -273.670014)
		(width 0.1143)
		(layer "In5.Cu")
		(net "P5E_PEX2_STN1_RX_DP<24>")
	)
	(segment
		(start 268.70279 -158.20644)
		(end 269.706598 -163.938458)
		(width 0.1651)
		(layer "In5.Cu")
		(net "P5E_PEX2_STN1_RX_DP<24>")
	)
	(segment
		(start 268.266926 -151.562054)
		(end 268.70279 -158.20644)
		(width 0.1651)
		(layer "In5.Cu")
		(net "P5E_PEX2_STN1_RX_DP<24>")
	)
	(segment
		(start 269.706598 -163.938458)
		(end 298.833794 -268.419834)
		(width 0.1651)
		(layer "In5.Cu")
		(net "P5E_PEX2_STN1_RX_DP<24>")
	)
	(segment
		(start 298.833794 -268.419834)
		(end 298.833794 -271.526)
		(width 0.1651)
		(layer "In5.Cu")
		(net "P5E_PEX2_STN1_RX_DP<24>")
	)
	(segment
		(start 298.833794 -271.554448)
		(end 298.879514 -271.600168)
		(width 0.1143)
		(layer "In5.Cu")
		(net "P5E_PEX2_STN1_RX_DP<24>")
	)
	(segment
		(start 299.33519 -273.670014)
		(end 299.44949 -273.784314)
		(width 0.1143)
		(layer "In5.Cu")
		(net "P5E_PEX2_STN1_RX_DP<24>")
	)
	(segment
		(start 274.97405 -127.992124)
		(end 274.621498 -128.909064)
		(width 0.1651)
		(layer "In5.Cu")
		(net "P5E_PEX2_STN1_RX_DP<24>")
	)
	(segment
		(start 336.017108 -397.281146)
		(end 336.564224 -397.281146)
		(width 0.1651)
		(layer "In9.Cu")
		(net "P5E_PEX2_STN5_RX_DN<82>")
	)
	(segment
		(start 297.241722 -325.17461)
		(end 294.740584 -323.577204)
		(width 0.1651)
		(layer "In9.Cu")
		(net "P5E_PEX2_STN5_RX_DN<82>")
	)
	(segment
		(start 352.864674 -367.893854)
		(end 346.905834 -362.869988)
		(width 0.1651)
		(layer "In9.Cu")
		(net "P5E_PEX2_STN5_RX_DN<82>")
	)
	(segment
		(start 353.392486 -386.462016)
		(end 353.63658 -385.777994)
		(width 0.1651)
		(layer "In9.Cu")
		(net "P5E_PEX2_STN5_RX_DN<82>")
	)
	(segment
		(start 353.91598 -370.589048)
		(end 353.51466 -369.0239)
		(width 0.1651)
		(layer "In9.Cu")
		(net "P5E_PEX2_STN5_RX_DN<82>")
	)
	(segment
		(start 292.42004 -316.534038)
		(end 292.534086 -316.419992)
		(width 0.1143)
		(layer "In9.Cu")
		(net "P5E_PEX2_STN5_RX_DN<82>")
	)
	(segment
		(start 298.37634 -325.49592)
		(end 297.911012 -325.325232)
		(width 0.1651)
		(layer "In9.Cu")
		(net "P5E_PEX2_STN5_RX_DN<82>")
	)
	(segment
		(start 339.8139 -358.81056)
		(end 339.501734 -358.498394)
		(width 0.1651)
		(layer "In9.Cu")
		(net "P5E_PEX2_STN5_RX_DN<82>")
	)
	(segment
		(start 337.01609 -395.676628)
		(end 339.42401 -393.300712)
		(width 0.1651)
		(layer "In9.Cu")
		(net "P5E_PEX2_STN5_RX_DN<82>")
	)
	(segment
		(start 339.42401 -393.300712)
		(end 343.0016 -391.241788)
		(width 0.1651)
		(layer "In9.Cu")
		(net "P5E_PEX2_STN5_RX_DN<82>")
	)
	(segment
		(start 294.740584 -323.577204)
		(end 293.644066 -322.480686)
		(width 0.1651)
		(layer "In9.Cu")
		(net "P5E_PEX2_STN5_RX_DN<82>")
	)
	(segment
		(start 353.51466 -369.0239)
		(end 352.864674 -367.893854)
		(width 0.1651)
		(layer "In9.Cu")
		(net "P5E_PEX2_STN5_RX_DN<82>")
	)
	(segment
		(start 343.0016 -391.241788)
		(end 352.224594 -387.64337)
		(width 0.1651)
		(layer "In9.Cu")
		(net "P5E_PEX2_STN5_RX_DN<82>")
	)
	(segment
		(start 352.224594 -387.64337)
		(end 352.708464 -387.331204)
		(width 0.1651)
		(layer "In9.Cu")
		(net "P5E_PEX2_STN5_RX_DN<82>")
	)
	(segment
		(start 292.46576 -319.916048)
		(end 292.46576 -319.8876)
		(width 0.1143)
		(layer "In9.Cu")
		(net "P5E_PEX2_STN5_RX_DN<82>")
	)
	(segment
		(start 292.534086 -316.419992)
		(end 292.71087 -316.419992)
		(width 0.1143)
		(layer "In9.Cu")
		(net "P5E_PEX2_STN5_RX_DN<82>")
	)
	(segment
		(start 292.71087 -316.419992)
		(end 292.79977 -316.508892)
		(width 0.1143)
		(layer "In9.Cu")
		(net "P5E_PEX2_STN5_RX_DN<82>")
	)
	(segment
		(start 339.501734 -358.498394)
		(end 339.501734 -341.83828)
		(width 0.1651)
		(layer "In9.Cu")
		(net "P5E_PEX2_STN5_RX_DN<82>")
	)
	(segment
		(start 338.864448 -340.429342)
		(end 338.749132 -340.390988)
		(width 0.1651)
		(layer "In9.Cu")
		(net "P5E_PEX2_STN5_RX_DN<82>")
	)
	(segment
		(start 338.749132 -340.390988)
		(end 298.429172 -325.609966)
		(width 0.1651)
		(layer "In9.Cu")
		(net "P5E_PEX2_STN5_RX_DN<82>")
	)
	(segment
		(start 298.429172 -325.609966)
		(end 298.37634 -325.49592)
		(width 0.1651)
		(layer "In9.Cu")
		(net "P5E_PEX2_STN5_RX_DN<82>")
	)
	(segment
		(start 335.890108 -397.790162)
		(end 335.890108 -397.408146)
		(width 0.1651)
		(layer "In9.Cu")
		(net "P5E_PEX2_STN5_RX_DN<82>")
	)
	(segment
		(start 293.644066 -322.480686)
		(end 292.46576 -320.717418)
		(width 0.1651)
		(layer "In9.Cu")
		(net "P5E_PEX2_STN5_RX_DN<82>")
	)
	(segment
		(start 337.01609 -396.82928)
		(end 337.01609 -395.676628)
		(width 0.1651)
		(layer "In9.Cu")
		(net "P5E_PEX2_STN5_RX_DN<82>")
	)
	(segment
		(start 352.708464 -387.331204)
		(end 353.392486 -386.462016)
		(width 0.1651)
		(layer "In9.Cu")
		(net "P5E_PEX2_STN5_RX_DN<82>")
	)
	(segment
		(start 297.796966 -325.378064)
		(end 297.241722 -325.17461)
		(width 0.1651)
		(layer "In9.Cu")
		(net "P5E_PEX2_STN5_RX_DN<82>")
	)
	(segment
		(start 336.564224 -397.281146)
		(end 337.01609 -396.82928)
		(width 0.1651)
		(layer "In9.Cu")
		(net "P5E_PEX2_STN5_RX_DN<82>")
	)
	(segment
		(start 297.911012 -325.325232)
		(end 297.796966 -325.378064)
		(width 0.1651)
		(layer "In9.Cu")
		(net "P5E_PEX2_STN5_RX_DN<82>")
	)
	(segment
		(start 339.501734 -341.83828)
		(end 338.864448 -340.429342)
		(width 0.1651)
		(layer "In9.Cu")
		(net "P5E_PEX2_STN5_RX_DN<82>")
	)
	(segment
		(start 335.890108 -397.408146)
		(end 336.017108 -397.281146)
		(width 0.1651)
		(layer "In9.Cu")
		(net "P5E_PEX2_STN5_RX_DN<82>")
	)
	(segment
		(start 292.46576 -320.717418)
		(end 292.46576 -319.916048)
		(width 0.1651)
		(layer "In9.Cu")
		(net "P5E_PEX2_STN5_RX_DN<82>")
	)
	(segment
		(start 346.905834 -362.869988)
		(end 339.8139 -358.81056)
		(width 0.1651)
		(layer "In9.Cu")
		(net "P5E_PEX2_STN5_RX_DN<82>")
	)
	(segment
		(start 292.46576 -319.8876)
		(end 292.42004 -319.84188)
		(width 0.1143)
		(layer "In9.Cu")
		(net "P5E_PEX2_STN5_RX_DN<82>")
	)
	(segment
		(start 292.79977 -316.508892)
		(end 292.79977 -316.799722)
		(width 0.1143)
		(layer "In9.Cu")
		(net "P5E_PEX2_STN5_RX_DN<82>")
	)
	(segment
		(start 292.42004 -319.84188)
		(end 292.42004 -316.534038)
		(width 0.1143)
		(layer "In9.Cu")
		(net "P5E_PEX2_STN5_RX_DN<82>")
	)
	(segment
		(start 353.63658 -385.777994)
		(end 353.91598 -370.589048)
		(width 0.1651)
		(layer "In9.Cu")
		(net "P5E_PEX2_STN5_RX_DN<82>")
	)
	(segment
		(start 381.813308 -30.6197)
		(end 381.51054 -30.922468)
		(width 0.13462)
		(layer "F.Cu")
		(net "P5E_PEX3_STN2_RX_DP<41>")
	)
	(segment
		(start 384.96494 -30.790134)
		(end 384.48234 -30.790134)
		(width 0.13462)
		(layer "F.Cu")
		(net "P5E_PEX3_STN2_RX_DP<41>")
	)
	(segment
		(start 384.311906 -30.6197)
		(end 381.813308 -30.6197)
		(width 0.13462)
		(layer "F.Cu")
		(net "P5E_PEX3_STN2_RX_DP<41>")
	)
	(segment
		(start 384.48234 -30.790134)
		(end 384.311906 -30.6197)
		(width 0.13462)
		(layer "F.Cu")
		(net "P5E_PEX3_STN2_RX_DP<41>")
	)
	(segment
		(start 384.59791 -31.38297)
		(end 384.94843 -31.73349)
		(width 0.1651)
		(layer "In7.Cu")
		(net "P5E_PEX3_STN2_RX_DP<41>")
	)
	(segment
		(start 398.3355 -273.670014)
		(end 398.4498 -273.784314)
		(width 0.1143)
		(layer "In7.Cu")
		(net "P5E_PEX3_STN2_RX_DP<41>")
	)
	(segment
		(start 384.908044 -39.658036)
		(end 386.22351 -49.394364)
		(width 0.1651)
		(layer "In7.Cu")
		(net "P5E_PEX3_STN2_RX_DP<41>")
	)
	(segment
		(start 385.429506 -32.088836)
		(end 385.406138 -34.981642)
		(width 0.1651)
		(layer "In7.Cu")
		(net "P5E_PEX3_STN2_RX_DP<41>")
	)
	(segment
		(start 397.83385 -271.3736)
		(end 397.87957 -271.41932)
		(width 0.1143)
		(layer "In7.Cu")
		(net "P5E_PEX3_STN2_RX_DP<41>")
	)
	(segment
		(start 386.22351 -49.394364)
		(end 386.124196 -55.75808)
		(width 0.1651)
		(layer "In7.Cu")
		(net "P5E_PEX3_STN2_RX_DP<41>")
	)
	(segment
		(start 398.141952 -273.670014)
		(end 398.3355 -273.670014)
		(width 0.1143)
		(layer "In7.Cu")
		(net "P5E_PEX3_STN2_RX_DP<41>")
	)
	(segment
		(start 384.880866 -37.940234)
		(end 384.90779 -39.641272)
		(width 0.1651)
		(layer "In7.Cu")
		(net "P5E_PEX3_STN2_RX_DP<41>")
	)
	(segment
		(start 382.77419 -30.631638)
		(end 382.87579 -30.733238)
		(width 0.1651)
		(layer "In7.Cu")
		(net "P5E_PEX3_STN2_RX_DP<41>")
	)
	(segment
		(start 389.684006 -104.61879)
		(end 390.137142 -119.576596)
		(width 0.1651)
		(layer "In7.Cu")
		(net "P5E_PEX3_STN2_RX_DP<41>")
	)
	(segment
		(start 383.972308 -30.631638)
		(end 384.59791 -31.25724)
		(width 0.1651)
		(layer "In7.Cu")
		(net "P5E_PEX3_STN2_RX_DP<41>")
	)
	(segment
		(start 398.4498 -273.784314)
		(end 398.4498 -274.049744)
		(width 0.1143)
		(layer "In7.Cu")
		(net "P5E_PEX3_STN2_RX_DP<41>")
	)
	(segment
		(start 384.907536 -39.641272)
		(end 384.908044 -39.658036)
		(width 0.1651)
		(layer "In7.Cu")
		(net "P5E_PEX3_STN2_RX_DP<41>")
	)
	(segment
		(start 397.87957 -273.407632)
		(end 398.141952 -273.670014)
		(width 0.1143)
		(layer "In7.Cu")
		(net "P5E_PEX3_STN2_RX_DP<41>")
	)
	(segment
		(start 384.90779 -39.641272)
		(end 384.907536 -39.641272)
		(width 0.1651)
		(layer "In7.Cu")
		(net "P5E_PEX3_STN2_RX_DP<41>")
	)
	(segment
		(start 397.434054 -263.623806)
		(end 397.83385 -267.683234)
		(width 0.1651)
		(layer "In7.Cu")
		(net "P5E_PEX3_STN2_RX_DP<41>")
	)
	(segment
		(start 397.83385 -271.345152)
		(end 397.83385 -271.3736)
		(width 0.1143)
		(layer "In7.Cu")
		(net "P5E_PEX3_STN2_RX_DP<41>")
	)
	(segment
		(start 383.47269 -30.631638)
		(end 383.972308 -30.631638)
		(width 0.1651)
		(layer "In7.Cu")
		(net "P5E_PEX3_STN2_RX_DP<41>")
	)
	(segment
		(start 382.87579 -30.733238)
		(end 383.37109 -30.733238)
		(width 0.1651)
		(layer "In7.Cu")
		(net "P5E_PEX3_STN2_RX_DP<41>")
	)
	(segment
		(start 384.94843 -31.73349)
		(end 385.07416 -31.73349)
		(width 0.1651)
		(layer "In7.Cu")
		(net "P5E_PEX3_STN2_RX_DP<41>")
	)
	(segment
		(start 386.124196 -55.75808)
		(end 386.484368 -64.756792)
		(width 0.1651)
		(layer "In7.Cu")
		(net "P5E_PEX3_STN2_RX_DP<41>")
	)
	(segment
		(start 397.83385 -267.683234)
		(end 397.83385 -271.345152)
		(width 0.1651)
		(layer "In7.Cu")
		(net "P5E_PEX3_STN2_RX_DP<41>")
	)
	(segment
		(start 386.484368 -64.756792)
		(end 389.684006 -104.61879)
		(width 0.1651)
		(layer "In7.Cu")
		(net "P5E_PEX3_STN2_RX_DP<41>")
	)
	(segment
		(start 389.831072 -147.979892)
		(end 397.787368 -249.979434)
		(width 0.1651)
		(layer "In7.Cu")
		(net "P5E_PEX3_STN2_RX_DP<41>")
	)
	(segment
		(start 384.59791 -31.25724)
		(end 384.59791 -31.38297)
		(width 0.1651)
		(layer "In7.Cu")
		(net "P5E_PEX3_STN2_RX_DP<41>")
	)
	(segment
		(start 381.80137 -30.631638)
		(end 382.77419 -30.631638)
		(width 0.1651)
		(layer "In7.Cu")
		(net "P5E_PEX3_STN2_RX_DP<41>")
	)
	(segment
		(start 397.58239 -260.60146)
		(end 397.434054 -263.623806)
		(width 0.1651)
		(layer "In7.Cu")
		(net "P5E_PEX3_STN2_RX_DP<41>")
	)
	(segment
		(start 383.37109 -30.733238)
		(end 383.47269 -30.631638)
		(width 0.1651)
		(layer "In7.Cu")
		(net "P5E_PEX3_STN2_RX_DP<41>")
	)
	(segment
		(start 385.406138 -34.981642)
		(end 384.880866 -37.940234)
		(width 0.1651)
		(layer "In7.Cu")
		(net "P5E_PEX3_STN2_RX_DP<41>")
	)
	(segment
		(start 385.07416 -31.73349)
		(end 385.429506 -32.088836)
		(width 0.1651)
		(layer "In7.Cu")
		(net "P5E_PEX3_STN2_RX_DP<41>")
	)
	(segment
		(start 390.137142 -119.576596)
		(end 389.831072 -147.979892)
		(width 0.1651)
		(layer "In7.Cu")
		(net "P5E_PEX3_STN2_RX_DP<41>")
	)
	(segment
		(start 381.51054 -30.922468)
		(end 381.80137 -30.631638)
		(width 0.1651)
		(layer "In7.Cu")
		(net "P5E_PEX3_STN2_RX_DP<41>")
	)
	(segment
		(start 397.787368 -249.979434)
		(end 397.58239 -260.60146)
		(width 0.1651)
		(layer "In7.Cu")
		(net "P5E_PEX3_STN2_RX_DP<41>")
	)
	(segment
		(start 397.87957 -271.41932)
		(end 397.87957 -273.407632)
		(width 0.1143)
		(layer "In7.Cu")
		(net "P5E_PEX3_STN2_RX_DP<41>")
	)
	(segment
		(start 418.91712 -351.31629)
		(end 418.621972 -351.611438)
		(width 0.13462)
		(layer "F.Cu")
		(net "P5E_PEX3_STN7_TX_C_DP<116>")
	)
	(segment
		(start 418.596572 -350.365314)
		(end 418.91712 -350.685862)
		(width 0.13462)
		(layer "F.Cu")
		(net "P5E_PEX3_STN7_TX_C_DP<116>")
	)
	(segment
		(start 418.91712 -350.685862)
		(end 418.91712 -351.31629)
		(width 0.13462)
		(layer "F.Cu")
		(net "P5E_PEX3_STN7_TX_C_DP<116>")
	)
	(segment
		(start 417.358322 -353.910646)
		(end 418.912802 -352.356166)
		(width 0.1651)
		(layer "In11.Cu")
		(net "P5E_PEX3_STN7_TX_C_DP<116>")
	)
	(segment
		(start 426.28312 -393.078462)
		(end 425.839382 -392.858752)
		(width 0.1651)
		(layer "In11.Cu")
		(net "P5E_PEX3_STN7_TX_C_DP<116>")
	)
	(segment
		(start 418.912802 -351.902268)
		(end 418.621972 -351.611438)
		(width 0.1651)
		(layer "In11.Cu")
		(net "P5E_PEX3_STN7_TX_C_DP<116>")
	)
	(segment
		(start 428.289974 -400.772122)
		(end 428.416974 -400.899122)
		(width 0.1651)
		(layer "In11.Cu")
		(net "P5E_PEX3_STN7_TX_C_DP<116>")
	)
	(segment
		(start 428.836836 -394.343636)
		(end 427.979078 -393.918694)
		(width 0.1651)
		(layer "In11.Cu")
		(net "P5E_PEX3_STN7_TX_C_DP<116>")
	)
	(segment
		(start 424.769534 -392.328654)
		(end 424.63339 -392.374628)
		(width 0.1651)
		(layer "In11.Cu")
		(net "P5E_PEX3_STN7_TX_C_DP<116>")
	)
	(segment
		(start 428.416974 -400.899122)
		(end 428.84725 -400.899122)
		(width 0.1651)
		(layer "In11.Cu")
		(net "P5E_PEX3_STN7_TX_C_DP<116>")
	)
	(segment
		(start 418.912802 -352.356166)
		(end 418.912802 -351.902268)
		(width 0.1651)
		(layer "In11.Cu")
		(net "P5E_PEX3_STN7_TX_C_DP<116>")
	)
	(segment
		(start 424.143424 -392.018266)
		(end 424.143424 -392.01852)
		(width 0.1651)
		(layer "In11.Cu")
		(net "P5E_PEX3_STN7_TX_C_DP<116>")
	)
	(segment
		(start 427.842934 -393.964668)
		(end 427.398942 -393.744704)
		(width 0.1651)
		(layer "In11.Cu")
		(net "P5E_PEX3_STN7_TX_C_DP<116>")
	)
	(segment
		(start 426.90923 -393.38885)
		(end 426.773086 -393.434824)
		(width 0.1651)
		(layer "In11.Cu")
		(net "P5E_PEX3_STN7_TX_C_DP<116>")
	)
	(segment
		(start 426.773086 -393.434824)
		(end 426.329094 -393.214606)
		(width 0.1651)
		(layer "In11.Cu")
		(net "P5E_PEX3_STN7_TX_C_DP<116>")
	)
	(segment
		(start 415.16046 -368.929158)
		(end 417.358322 -358.8512)
		(width 0.1651)
		(layer "In11.Cu")
		(net "P5E_PEX3_STN7_TX_C_DP<116>")
	)
	(segment
		(start 429.134016 -400.612356)
		(end 429.134016 -394.640816)
		(width 0.1651)
		(layer "In11.Cu")
		(net "P5E_PEX3_STN7_TX_C_DP<116>")
	)
	(segment
		(start 425.703238 -392.904726)
		(end 425.259246 -392.684508)
		(width 0.1651)
		(layer "In11.Cu")
		(net "P5E_PEX3_STN7_TX_C_DP<116>")
	)
	(segment
		(start 429.134016 -394.640816)
		(end 428.836836 -394.343636)
		(width 0.1651)
		(layer "In11.Cu")
		(net "P5E_PEX3_STN7_TX_C_DP<116>")
	)
	(segment
		(start 427.352968 -393.60856)
		(end 426.90923 -393.38885)
		(width 0.1651)
		(layer "In11.Cu")
		(net "P5E_PEX3_STN7_TX_C_DP<116>")
	)
	(segment
		(start 424.189398 -392.15441)
		(end 424.143424 -392.018266)
		(width 0.1651)
		(layer "In11.Cu")
		(net "P5E_PEX3_STN7_TX_C_DP<116>")
	)
	(segment
		(start 425.213272 -392.548364)
		(end 424.769534 -392.328654)
		(width 0.1651)
		(layer "In11.Cu")
		(net "P5E_PEX3_STN7_TX_C_DP<116>")
	)
	(segment
		(start 424.63339 -392.374628)
		(end 424.189398 -392.15441)
		(width 0.1651)
		(layer "In11.Cu")
		(net "P5E_PEX3_STN7_TX_C_DP<116>")
	)
	(segment
		(start 425.259246 -392.684508)
		(end 425.213272 -392.548364)
		(width 0.1651)
		(layer "In11.Cu")
		(net "P5E_PEX3_STN7_TX_C_DP<116>")
	)
	(segment
		(start 416.352736 -388.15899)
		(end 415.090864 -385.54914)
		(width 0.1651)
		(layer "In11.Cu")
		(net "P5E_PEX3_STN7_TX_C_DP<116>")
	)
	(segment
		(start 427.398942 -393.744704)
		(end 427.352968 -393.60856)
		(width 0.1651)
		(layer "In11.Cu")
		(net "P5E_PEX3_STN7_TX_C_DP<116>")
	)
	(segment
		(start 427.979078 -393.918694)
		(end 427.842934 -393.964668)
		(width 0.1651)
		(layer "In11.Cu")
		(net "P5E_PEX3_STN7_TX_C_DP<116>")
	)
	(segment
		(start 414.855152 -383.348992)
		(end 415.16046 -368.929158)
		(width 0.1651)
		(layer "In11.Cu")
		(net "P5E_PEX3_STN7_TX_C_DP<116>")
	)
	(segment
		(start 417.358322 -358.8512)
		(end 417.358322 -353.910646)
		(width 0.1651)
		(layer "In11.Cu")
		(net "P5E_PEX3_STN7_TX_C_DP<116>")
	)
	(segment
		(start 426.329094 -393.214606)
		(end 426.28312 -393.078462)
		(width 0.1651)
		(layer "In11.Cu")
		(net "P5E_PEX3_STN7_TX_C_DP<116>")
	)
	(segment
		(start 415.090864 -385.54914)
		(end 414.855152 -383.348992)
		(width 0.1651)
		(layer "In11.Cu")
		(net "P5E_PEX3_STN7_TX_C_DP<116>")
	)
	(segment
		(start 424.143424 -392.01852)
		(end 416.352736 -388.15899)
		(width 0.1651)
		(layer "In11.Cu")
		(net "P5E_PEX3_STN7_TX_C_DP<116>")
	)
	(segment
		(start 428.289974 -400.390106)
		(end 428.289974 -400.772122)
		(width 0.1651)
		(layer "In11.Cu")
		(net "P5E_PEX3_STN7_TX_C_DP<116>")
	)
	(segment
		(start 425.839382 -392.858752)
		(end 425.703238 -392.904726)
		(width 0.1651)
		(layer "In11.Cu")
		(net "P5E_PEX3_STN7_TX_C_DP<116>")
	)
	(segment
		(start 428.84725 -400.899122)
		(end 429.134016 -400.612356)
		(width 0.1651)
		(layer "In11.Cu")
		(net "P5E_PEX3_STN7_TX_C_DP<116>")
	)
	(segment
		(start 421.557704 -98.840036)
		(end 423.577004 -98.840036)
		(width 0.13208)
		(layer "F.Cu")
		(net "NIC7_DATA_IN")
	)
	(segment
		(start 423.577004 -98.840036)
		(end 424.24604 -98.171)
		(width 0.13208)
		(layer "F.Cu")
		(net "NIC7_DATA_IN")
	)
	(via
		(at 424.24604 -98.171)
		(size 0.508)
		(drill 0.254)
		(layers "F.Cu" "B.Cu")
		(net "NIC7_DATA_IN")
	)
	(segment
		(start 425.441872 -97.005648)
		(end 424.27652 -98.171)
		(width 0.13208)
		(layer "B.Cu")
		(net "NIC7_DATA_IN")
	)
	(segment
		(start 424.27652 -98.171)
		(end 424.24604 -98.171)
		(width 0.13208)
		(layer "B.Cu")
		(net "NIC7_DATA_IN")
	)
	(segment
		(start 73.908666 -124.67209)
		(end 82.075782 -124.67209)
		(width 0.13462)
		(layer "F.Cu")
		(net "P5E_PEX0_STN0_TX_C_DP<3>")
	)
	(segment
		(start 73.257664 -124.834904)
		(end 73.745852 -124.834904)
		(width 0.13462)
		(layer "F.Cu")
		(net "P5E_PEX0_STN0_TX_C_DP<3>")
	)
	(segment
		(start 82.075782 -124.67209)
		(end 82.394806 -124.991114)
		(width 0.13462)
		(layer "F.Cu")
		(net "P5E_PEX0_STN0_TX_C_DP<3>")
	)
	(segment
		(start 73.745852 -124.834904)
		(end 73.908666 -124.67209)
		(width 0.13462)
		(layer "F.Cu")
		(net "P5E_PEX0_STN0_TX_C_DP<3>")
	)
	(segment
		(start 124.866908 -350.685354)
		(end 125.186948 -350.365314)
		(width 0.13462)
		(layer "F.Cu")
		(net "P5E_PEX1_STN6_TX_C_DN<97>")
	)
	(segment
		(start 125.161548 -351.611438)
		(end 124.866908 -351.316798)
		(width 0.13462)
		(layer "F.Cu")
		(net "P5E_PEX1_STN6_TX_C_DN<97>")
	)
	(segment
		(start 124.866908 -351.316798)
		(end 124.866908 -350.685354)
		(width 0.13462)
		(layer "F.Cu")
		(net "P5E_PEX1_STN6_TX_C_DN<97>")
	)
	(segment
		(start 123.316238 -354.092002)
		(end 124.870718 -352.537522)
		(width 0.1651)
		(layer "In7.Cu")
		(net "P5E_PEX1_STN6_TX_C_DN<97>")
	)
	(segment
		(start 130.169412 -368.984276)
		(end 129.869692 -368.14633)
		(width 0.1651)
		(layer "In7.Cu")
		(net "P5E_PEX1_STN6_TX_C_DN<97>")
	)
	(segment
		(start 124.870718 -352.537522)
		(end 124.870718 -351.902268)
		(width 0.1651)
		(layer "In7.Cu")
		(net "P5E_PEX1_STN6_TX_C_DN<97>")
	)
	(segment
		(start 129.237232 -382.980946)
		(end 129.585974 -382.980946)
		(width 0.1651)
		(layer "In7.Cu")
		(net "P5E_PEX1_STN6_TX_C_DN<97>")
	)
	(segment
		(start 129.109978 -383.1082)
		(end 129.237232 -382.980946)
		(width 0.1651)
		(layer "In7.Cu")
		(net "P5E_PEX1_STN6_TX_C_DN<97>")
	)
	(segment
		(start 123.316238 -358.272842)
		(end 123.316238 -354.092002)
		(width 0.1651)
		(layer "In7.Cu")
		(net "P5E_PEX1_STN6_TX_C_DN<97>")
	)
	(segment
		(start 130.169412 -382.397508)
		(end 130.169412 -368.984276)
		(width 0.1651)
		(layer "In7.Cu")
		(net "P5E_PEX1_STN6_TX_C_DN<97>")
	)
	(segment
		(start 129.585974 -382.980946)
		(end 130.169412 -382.397508)
		(width 0.1651)
		(layer "In7.Cu")
		(net "P5E_PEX1_STN6_TX_C_DN<97>")
	)
	(segment
		(start 124.870718 -351.902268)
		(end 125.161548 -351.611438)
		(width 0.1651)
		(layer "In7.Cu")
		(net "P5E_PEX1_STN6_TX_C_DN<97>")
	)
	(segment
		(start 129.109978 -383.490216)
		(end 129.109978 -383.1082)
		(width 0.1651)
		(layer "In7.Cu")
		(net "P5E_PEX1_STN6_TX_C_DN<97>")
	)
	(segment
		(start 129.869692 -368.14633)
		(end 123.498102 -358.859074)
		(width 0.1651)
		(layer "In7.Cu")
		(net "P5E_PEX1_STN6_TX_C_DN<97>")
	)
	(segment
		(start 123.498102 -358.859074)
		(end 123.316238 -358.272842)
		(width 0.1651)
		(layer "In7.Cu")
		(net "P5E_PEX1_STN6_TX_C_DN<97>")
	)
	(segment
		(start 269.432532 -123.385834)
		(end 277.566374 -123.385834)
		(width 0.13462)
		(layer "F.Cu")
		(net "P5E_PEX2_STN1_TX_C_DN<26>")
	)
	(segment
		(start 277.566374 -123.385834)
		(end 277.735538 -123.554998)
		(width 0.13462)
		(layer "F.Cu")
		(net "P5E_PEX2_STN1_TX_C_DN<26>")
	)
	(segment
		(start 269.105126 -123.71324)
		(end 269.432532 -123.385834)
		(width 0.13462)
		(layer "F.Cu")
		(net "P5E_PEX2_STN1_TX_C_DN<26>")
	)
	(segment
		(start 277.735538 -123.554998)
		(end 278.242268 -123.554998)
		(width 0.13462)
		(layer "F.Cu")
		(net "P5E_PEX2_STN1_TX_C_DN<26>")
	)
	(segment
		(start 365.825786 -32.739584)
		(end 365.516922 -32.43072)
		(width 0.13462)
		(layer "F.Cu")
		(net "P5E_PEX3_STN2_TX_C_DP<46>")
	)
	(segment
		(start 364.223808 -32.43072)
		(end 364.06455 -32.589978)
		(width 0.13462)
		(layer "F.Cu")
		(net "P5E_PEX3_STN2_TX_C_DP<46>")
	)
	(segment
		(start 365.516922 -32.43072)
		(end 364.223808 -32.43072)
		(width 0.13462)
		(layer "F.Cu")
		(net "P5E_PEX3_STN2_TX_C_DP<46>")
	)
	(segment
		(start 364.06455 -32.589978)
		(end 363.564932 -32.589978)
		(width 0.13462)
		(layer "F.Cu")
		(net "P5E_PEX3_STN2_TX_C_DP<46>")
	)
	(segment
		(start 440.67984 -345.169998)
		(end 440.384692 -345.465146)
		(width 0.13462)
		(layer "F.Cu")
		(net "P5E_PEX3_STN7_TX_C_DP<126>")
	)
	(segment
		(start 440.359292 -344.219022)
		(end 440.67984 -344.53957)
		(width 0.13462)
		(layer "F.Cu")
		(net "P5E_PEX3_STN7_TX_C_DP<126>")
	)
	(segment
		(start 440.67984 -344.53957)
		(end 440.67984 -345.169998)
		(width 0.13462)
		(layer "F.Cu")
		(net "P5E_PEX3_STN7_TX_C_DP<126>")
	)
	(segment
		(start 437.316626 -361.904788)
		(end 437.438038 -361.872022)
		(width 0.1651)
		(layer "In11.Cu")
		(net "P5E_PEX3_STN7_TX_C_DP<126>")
	)
	(segment
		(start 434.777896 -366.511078)
		(end 434.74513 -366.389666)
		(width 0.1651)
		(layer "In11.Cu")
		(net "P5E_PEX3_STN7_TX_C_DP<126>")
	)
	(segment
		(start 435.359302 -365.497364)
		(end 435.326536 -365.375952)
		(width 0.1651)
		(layer "In11.Cu")
		(net "P5E_PEX3_STN7_TX_C_DP<126>")
	)
	(segment
		(start 432.689762 -374.772174)
		(end 432.816762 -374.899174)
		(width 0.1651)
		(layer "In11.Cu")
		(net "P5E_PEX3_STN7_TX_C_DP<126>")
	)
	(segment
		(start 437.069992 -362.33481)
		(end 437.316626 -361.904788)
		(width 0.1651)
		(layer "In11.Cu")
		(net "P5E_PEX3_STN7_TX_C_DP<126>")
	)
	(segment
		(start 433.533804 -374.612408)
		(end 433.533804 -369.518692)
		(width 0.1651)
		(layer "In11.Cu")
		(net "P5E_PEX3_STN7_TX_C_DP<126>")
	)
	(segment
		(start 434.777642 -366.511078)
		(end 434.777896 -366.511078)
		(width 0.1651)
		(layer "In11.Cu")
		(net "P5E_PEX3_STN7_TX_C_DP<126>")
	)
	(segment
		(start 436.521606 -363.469936)
		(end 436.48884 -363.348524)
		(width 0.1651)
		(layer "In11.Cu")
		(net "P5E_PEX3_STN7_TX_C_DP<126>")
	)
	(segment
		(start 433.950364 -367.954306)
		(end 434.19649 -367.524792)
		(width 0.1651)
		(layer "In11.Cu")
		(net "P5E_PEX3_STN7_TX_C_DP<126>")
	)
	(segment
		(start 434.53177 -366.940592)
		(end 434.531516 -366.940338)
		(width 0.1651)
		(layer "In11.Cu")
		(net "P5E_PEX3_STN7_TX_C_DP<126>")
	)
	(segment
		(start 434.991764 -365.959644)
		(end 435.113176 -365.926878)
		(width 0.1651)
		(layer "In11.Cu")
		(net "P5E_PEX3_STN7_TX_C_DP<126>")
	)
	(segment
		(start 437.684164 -361.442254)
		(end 437.651144 -361.320842)
		(width 0.1651)
		(layer "In11.Cu")
		(net "P5E_PEX3_STN7_TX_C_DP<126>")
	)
	(segment
		(start 434.163724 -367.40338)
		(end 434.410358 -366.973358)
		(width 0.1651)
		(layer "In11.Cu")
		(net "P5E_PEX3_STN7_TX_C_DP<126>")
	)
	(segment
		(start 432.689762 -374.390158)
		(end 432.689762 -374.772174)
		(width 0.1651)
		(layer "In11.Cu")
		(net "P5E_PEX3_STN7_TX_C_DP<126>")
	)
	(segment
		(start 432.816762 -374.899174)
		(end 433.247038 -374.899174)
		(width 0.1651)
		(layer "In11.Cu")
		(net "P5E_PEX3_STN7_TX_C_DP<126>")
	)
	(segment
		(start 439.121042 -358.051354)
		(end 439.121042 -347.764354)
		(width 0.1651)
		(layer "In11.Cu")
		(net "P5E_PEX3_STN7_TX_C_DP<126>")
	)
	(segment
		(start 438.01919 -360.858054)
		(end 438.680352 -359.704894)
		(width 0.1651)
		(layer "In11.Cu")
		(net "P5E_PEX3_STN7_TX_C_DP<126>")
	)
	(segment
		(start 435.694328 -364.913164)
		(end 435.694074 -364.91291)
		(width 0.1651)
		(layer "In11.Cu")
		(net "P5E_PEX3_STN7_TX_C_DP<126>")
	)
	(segment
		(start 433.247038 -374.899174)
		(end 433.533804 -374.612408)
		(width 0.1651)
		(layer "In11.Cu")
		(net "P5E_PEX3_STN7_TX_C_DP<126>")
	)
	(segment
		(start 435.907688 -364.362238)
		(end 436.154322 -363.932216)
		(width 0.1651)
		(layer "In11.Cu")
		(net "P5E_PEX3_STN7_TX_C_DP<126>")
	)
	(segment
		(start 436.856378 -362.885736)
		(end 437.102504 -362.456222)
		(width 0.1651)
		(layer "In11.Cu")
		(net "P5E_PEX3_STN7_TX_C_DP<126>")
	)
	(segment
		(start 434.531516 -366.940338)
		(end 434.777642 -366.511078)
		(width 0.1651)
		(layer "In11.Cu")
		(net "P5E_PEX3_STN7_TX_C_DP<126>")
	)
	(segment
		(start 436.521352 -363.469936)
		(end 436.521606 -363.469936)
		(width 0.1651)
		(layer "In11.Cu")
		(net "P5E_PEX3_STN7_TX_C_DP<126>")
	)
	(segment
		(start 437.102758 -362.456222)
		(end 437.069992 -362.33481)
		(width 0.1651)
		(layer "In11.Cu")
		(net "P5E_PEX3_STN7_TX_C_DP<126>")
	)
	(segment
		(start 435.113176 -365.926878)
		(end 435.112922 -365.926624)
		(width 0.1651)
		(layer "In11.Cu")
		(net "P5E_PEX3_STN7_TX_C_DP<126>")
	)
	(segment
		(start 434.410358 -366.973358)
		(end 434.53177 -366.940592)
		(width 0.1651)
		(layer "In11.Cu")
		(net "P5E_PEX3_STN7_TX_C_DP<126>")
	)
	(segment
		(start 437.651144 -361.320842)
		(end 437.897778 -360.891074)
		(width 0.1651)
		(layer "In11.Cu")
		(net "P5E_PEX3_STN7_TX_C_DP<126>")
	)
	(segment
		(start 434.19649 -367.524792)
		(end 434.163724 -367.40338)
		(width 0.1651)
		(layer "In11.Cu")
		(net "P5E_PEX3_STN7_TX_C_DP<126>")
	)
	(segment
		(start 435.112922 -365.926624)
		(end 435.359048 -365.497364)
		(width 0.1651)
		(layer "In11.Cu")
		(net "P5E_PEX3_STN7_TX_C_DP<126>")
	)
	(segment
		(start 436.735474 -362.918502)
		(end 436.856632 -362.885736)
		(width 0.1651)
		(layer "In11.Cu")
		(net "P5E_PEX3_STN7_TX_C_DP<126>")
	)
	(segment
		(start 435.57317 -364.94593)
		(end 435.694328 -364.913164)
		(width 0.1651)
		(layer "In11.Cu")
		(net "P5E_PEX3_STN7_TX_C_DP<126>")
	)
	(segment
		(start 436.154322 -363.932216)
		(end 436.27548 -363.89945)
		(width 0.1651)
		(layer "In11.Cu")
		(net "P5E_PEX3_STN7_TX_C_DP<126>")
	)
	(segment
		(start 436.48884 -363.348524)
		(end 436.735474 -362.918502)
		(width 0.1651)
		(layer "In11.Cu")
		(net "P5E_PEX3_STN7_TX_C_DP<126>")
	)
	(segment
		(start 436.27548 -363.89945)
		(end 436.275226 -363.89945)
		(width 0.1651)
		(layer "In11.Cu")
		(net "P5E_PEX3_STN7_TX_C_DP<126>")
	)
	(segment
		(start 435.9402 -364.48365)
		(end 435.940454 -364.48365)
		(width 0.1651)
		(layer "In11.Cu")
		(net "P5E_PEX3_STN7_TX_C_DP<126>")
	)
	(segment
		(start 436.856632 -362.885736)
		(end 436.856378 -362.885736)
		(width 0.1651)
		(layer "In11.Cu")
		(net "P5E_PEX3_STN7_TX_C_DP<126>")
	)
	(segment
		(start 435.326536 -365.375952)
		(end 435.57317 -364.94593)
		(width 0.1651)
		(layer "In11.Cu")
		(net "P5E_PEX3_STN7_TX_C_DP<126>")
	)
	(segment
		(start 437.102504 -362.456222)
		(end 437.102758 -362.456222)
		(width 0.1651)
		(layer "In11.Cu")
		(net "P5E_PEX3_STN7_TX_C_DP<126>")
	)
	(segment
		(start 435.940454 -364.48365)
		(end 435.907688 -364.362238)
		(width 0.1651)
		(layer "In11.Cu")
		(net "P5E_PEX3_STN7_TX_C_DP<126>")
	)
	(segment
		(start 438.680352 -359.704894)
		(end 439.121042 -358.051354)
		(width 0.1651)
		(layer "In11.Cu")
		(net "P5E_PEX3_STN7_TX_C_DP<126>")
	)
	(segment
		(start 436.275226 -363.89945)
		(end 436.521352 -363.469936)
		(width 0.1651)
		(layer "In11.Cu")
		(net "P5E_PEX3_STN7_TX_C_DP<126>")
	)
	(segment
		(start 435.694074 -364.91291)
		(end 435.9402 -364.48365)
		(width 0.1651)
		(layer "In11.Cu")
		(net "P5E_PEX3_STN7_TX_C_DP<126>")
	)
	(segment
		(start 439.121042 -347.764354)
		(end 440.675522 -346.209874)
		(width 0.1651)
		(layer "In11.Cu")
		(net "P5E_PEX3_STN7_TX_C_DP<126>")
	)
	(segment
		(start 437.438038 -361.872022)
		(end 437.437784 -361.871768)
		(width 0.1651)
		(layer "In11.Cu")
		(net "P5E_PEX3_STN7_TX_C_DP<126>")
	)
	(segment
		(start 440.675522 -345.755976)
		(end 440.384692 -345.465146)
		(width 0.1651)
		(layer "In11.Cu")
		(net "P5E_PEX3_STN7_TX_C_DP<126>")
	)
	(segment
		(start 435.359048 -365.497364)
		(end 435.359302 -365.497364)
		(width 0.1651)
		(layer "In11.Cu")
		(net "P5E_PEX3_STN7_TX_C_DP<126>")
	)
	(segment
		(start 437.437784 -361.871768)
		(end 437.684164 -361.442254)
		(width 0.1651)
		(layer "In11.Cu")
		(net "P5E_PEX3_STN7_TX_C_DP<126>")
	)
	(segment
		(start 440.675522 -346.209874)
		(end 440.675522 -345.755976)
		(width 0.1651)
		(layer "In11.Cu")
		(net "P5E_PEX3_STN7_TX_C_DP<126>")
	)
	(segment
		(start 433.533804 -369.518692)
		(end 433.950364 -367.954306)
		(width 0.1651)
		(layer "In11.Cu")
		(net "P5E_PEX3_STN7_TX_C_DP<126>")
	)
	(segment
		(start 434.74513 -366.389666)
		(end 434.991764 -365.959644)
		(width 0.1651)
		(layer "In11.Cu")
		(net "P5E_PEX3_STN7_TX_C_DP<126>")
	)
	(segment
		(start 437.897778 -360.891074)
		(end 438.01919 -360.858054)
		(width 0.1651)
		(layer "In11.Cu")
		(net "P5E_PEX3_STN7_TX_C_DP<126>")
	)
	(segment
		(start 162.77971 -140.765022)
		(end 164.824156 -142.809468)
		(width 0.13208)
		(layer "F.Cu")
		(net "RST_NIC2_PERST0_R_N")
	)
	(segment
		(start 164.824156 -146.172174)
		(end 165.391846 -146.739864)
		(width 0.13208)
		(layer "F.Cu")
		(net "RST_NIC2_PERST0_R_N")
	)
	(segment
		(start 164.824156 -142.809468)
		(end 164.824156 -146.172174)
		(width 0.13208)
		(layer "F.Cu")
		(net "RST_NIC2_PERST0_R_N")
	)
	(segment
		(start 167.148256 -165.902894)
		(end 167.148256 -165.130226)
		(width 0.13208)
		(layer "F.Cu")
		(net "RST_NIC2_PERST0_R_N")
	)
	(segment
		(start 162.14217 -140.765022)
		(end 162.77971 -140.765022)
		(width 0.13208)
		(layer "F.Cu")
		(net "RST_NIC2_PERST0_R_N")
	)
	(via
		(at 167.148256 -165.130226)
		(size 0.508)
		(drill 0.254)
		(layers "F.Cu" "B.Cu")
		(net "RST_NIC2_PERST0_R_N")
	)
	(via
		(at 165.391846 -146.739864)
		(size 0.508)
		(drill 0.254)
		(layers "F.Cu" "B.Cu")
		(net "RST_NIC2_PERST0_R_N")
	)
	(segment
		(start 165.391846 -146.739864)
		(end 166.560246 -147.908264)
		(width 0.15494)
		(layer "In7.Cu")
		(net "RST_NIC2_PERST0_R_N")
	)
	(segment
		(start 166.560246 -164.559996)
		(end 167.130476 -165.130226)
		(width 0.15494)
		(layer "In7.Cu")
		(net "RST_NIC2_PERST0_R_N")
	)
	(segment
		(start 166.560246 -147.908264)
		(end 166.560246 -164.559996)
		(width 0.15494)
		(layer "In7.Cu")
		(net "RST_NIC2_PERST0_R_N")
	)
	(segment
		(start 167.130476 -165.130226)
		(end 167.148256 -165.130226)
		(width 0.15494)
		(layer "In7.Cu")
		(net "RST_NIC2_PERST0_R_N")
	)
	(segment
		(start 419.98646 -116.477288)
		(end 420.43731 -116.026438)
		(width 0.13208)
		(layer "F.Cu")
		(net "NIC7_AUX_PWR_EN_R")
	)
	(segment
		(start 421.097202 -115.834922)
		(end 421.557704 -115.834922)
		(width 0.13208)
		(layer "F.Cu")
		(net "NIC7_AUX_PWR_EN_R")
	)
	(segment
		(start 420.905686 -116.026438)
		(end 421.097202 -115.834922)
		(width 0.13208)
		(layer "F.Cu")
		(net "NIC7_AUX_PWR_EN_R")
	)
	(segment
		(start 420.43731 -116.026438)
		(end 420.905686 -116.026438)
		(width 0.13208)
		(layer "F.Cu")
		(net "NIC7_AUX_PWR_EN_R")
	)
	(via
		(at 419.98646 -116.477288)
		(size 0.508)
		(drill 0.254)
		(layers "F.Cu" "B.Cu")
		(net "NIC7_AUX_PWR_EN_R")
	)
	(segment
		(start 419.543992 -116.477288)
		(end 419.98646 -116.477288)
		(width 0.13208)
		(layer "B.Cu")
		(net "NIC7_AUX_PWR_EN_R")
	)
	(segment
		(start 418.299392 -114.713512)
		(end 418.299392 -115.232688)
		(width 0.13208)
		(layer "B.Cu")
		(net "NIC7_AUX_PWR_EN_R")
	)
	(segment
		(start 419.98646 -116.477288)
		(end 419.98646 -117.66169)
		(width 0.13208)
		(layer "B.Cu")
		(net "NIC7_AUX_PWR_EN_R")
	)
	(segment
		(start 418.299392 -115.232688)
		(end 419.543992 -116.477288)
		(width 0.13208)
		(layer "B.Cu")
		(net "NIC7_AUX_PWR_EN_R")
	)
	(segment
		(start 68.169282 -118.834916)
		(end 68.006468 -118.99773)
		(width 0.13462)
		(layer "F.Cu")
		(net "P5E_PEX0_STN0_RX_DN<0>")
	)
	(segment
		(start 67.351402 -118.99773)
		(end 67.05727 -118.703598)
		(width 0.13462)
		(layer "F.Cu")
		(net "P5E_PEX0_STN0_RX_DN<0>")
	)
	(segment
		(start 68.006468 -118.99773)
		(end 67.351402 -118.99773)
		(width 0.13462)
		(layer "F.Cu")
		(net "P5E_PEX0_STN0_RX_DN<0>")
	)
	(segment
		(start 68.65747 -118.834916)
		(end 68.169282 -118.834916)
		(width 0.13462)
		(layer "F.Cu")
		(net "P5E_PEX0_STN0_RX_DN<0>")
	)
	(segment
		(start 72.668638 -120.97512)
		(end 67.883024 -118.994428)
		(width 0.1651)
		(layer "In5.Cu")
		(net "P5E_PEX0_STN0_RX_DN<0>")
	)
	(segment
		(start 86.176104 -131.877562)
		(end 85.388958 -130.84302)
		(width 0.1651)
		(layer "In5.Cu")
		(net "P5E_PEX0_STN0_RX_DN<0>")
	)
	(segment
		(start 90.105992 -168.524174)
		(end 89.653364 -149.82825)
		(width 0.1651)
		(layer "In5.Cu")
		(net "P5E_PEX0_STN0_RX_DN<0>")
	)
	(segment
		(start 80.17002 -288.052764)
		(end 80.302608 -287.920176)
		(width 0.1143)
		(layer "In5.Cu")
		(net "P5E_PEX0_STN0_RX_DN<0>")
	)
	(segment
		(start 99.488498 -273.725132)
		(end 99.674426 -269.124938)
		(width 0.1651)
		(layer "In5.Cu")
		(net "P5E_PEX0_STN0_RX_DN<0>")
	)
	(segment
		(start 86.508844 -287.965896)
		(end 87.734394 -287.19272)
		(width 0.1651)
		(layer "In5.Cu")
		(net "P5E_PEX0_STN0_RX_DN<0>")
	)
	(segment
		(start 87.734394 -287.19272)
		(end 96.840802 -278.399748)
		(width 0.1651)
		(layer "In5.Cu")
		(net "P5E_PEX0_STN0_RX_DN<0>")
	)
	(segment
		(start 85.388958 -130.84302)
		(end 74.192638 -122.49404)
		(width 0.1651)
		(layer "In5.Cu")
		(net "P5E_PEX0_STN0_RX_DN<0>")
	)
	(segment
		(start 90.967052 -239.218724)
		(end 89.43975 -231.87533)
		(width 0.1651)
		(layer "In5.Cu")
		(net "P5E_PEX0_STN0_RX_DN<0>")
	)
	(segment
		(start 80.17002 -288.185606)
		(end 80.17002 -288.052764)
		(width 0.1143)
		(layer "In5.Cu")
		(net "P5E_PEX0_STN0_RX_DN<0>")
	)
	(segment
		(start 83.924648 -287.965896)
		(end 86.508844 -287.965896)
		(width 0.1651)
		(layer "In5.Cu")
		(net "P5E_PEX0_STN0_RX_DN<0>")
	)
	(segment
		(start 89.653364 -149.82825)
		(end 89.255854 -145.583656)
		(width 0.1651)
		(layer "In5.Cu")
		(net "P5E_PEX0_STN0_RX_DN<0>")
	)
	(segment
		(start 80.28432 -288.299906)
		(end 80.17002 -288.185606)
		(width 0.1143)
		(layer "In5.Cu")
		(net "P5E_PEX0_STN0_RX_DN<0>")
	)
	(segment
		(start 83.85048 -287.920176)
		(end 83.8962 -287.965896)
		(width 0.1143)
		(layer "In5.Cu")
		(net "P5E_PEX0_STN0_RX_DN<0>")
	)
	(segment
		(start 67.3481 -118.994428)
		(end 67.05727 -118.703598)
		(width 0.1651)
		(layer "In5.Cu")
		(net "P5E_PEX0_STN0_RX_DN<0>")
	)
	(segment
		(start 96.840802 -278.399748)
		(end 99.488498 -273.725132)
		(width 0.1651)
		(layer "In5.Cu")
		(net "P5E_PEX0_STN0_RX_DN<0>")
	)
	(segment
		(start 67.883024 -118.994428)
		(end 67.3481 -118.994428)
		(width 0.1651)
		(layer "In5.Cu")
		(net "P5E_PEX0_STN0_RX_DN<0>")
	)
	(segment
		(start 89.255854 -145.583656)
		(end 86.176104 -131.877562)
		(width 0.1651)
		(layer "In5.Cu")
		(net "P5E_PEX0_STN0_RX_DN<0>")
	)
	(segment
		(start 80.54975 -288.299906)
		(end 80.28432 -288.299906)
		(width 0.1143)
		(layer "In5.Cu")
		(net "P5E_PEX0_STN0_RX_DN<0>")
	)
	(segment
		(start 89.43975 -231.87533)
		(end 90.105992 -168.524174)
		(width 0.1651)
		(layer "In5.Cu")
		(net "P5E_PEX0_STN0_RX_DN<0>")
	)
	(segment
		(start 83.8962 -287.965896)
		(end 83.924648 -287.965896)
		(width 0.1143)
		(layer "In5.Cu")
		(net "P5E_PEX0_STN0_RX_DN<0>")
	)
	(segment
		(start 99.674426 -269.124938)
		(end 90.967052 -239.218724)
		(width 0.1651)
		(layer "In5.Cu")
		(net "P5E_PEX0_STN0_RX_DN<0>")
	)
	(segment
		(start 80.302608 -287.920176)
		(end 83.85048 -287.920176)
		(width 0.1143)
		(layer "In5.Cu")
		(net "P5E_PEX0_STN0_RX_DN<0>")
	)
	(segment
		(start 74.192638 -122.49404)
		(end 72.668638 -120.97512)
		(width 0.1651)
		(layer "In5.Cu")
		(net "P5E_PEX0_STN0_RX_DN<0>")
	)
	(segment
		(start 283.492194 -106.81208)
		(end 283.325062 -106.644948)
		(width 0.13462)
		(layer "F.Cu")
		(net "P5E_PEX2_STN1_RX_DP<20>")
	)
	(segment
		(start 283.325062 -106.644948)
		(end 282.842462 -106.644948)
		(width 0.13462)
		(layer "F.Cu")
		(net "P5E_PEX2_STN1_RX_DP<20>")
	)
	(segment
		(start 286.296862 -106.512614)
		(end 285.997396 -106.81208)
		(width 0.13462)
		(layer "F.Cu")
		(net "P5E_PEX2_STN1_RX_DP<20>")
	)
	(segment
		(start 285.997396 -106.81208)
		(end 283.492194 -106.81208)
		(width 0.13462)
		(layer "F.Cu")
		(net "P5E_PEX2_STN1_RX_DP<20>")
	)
	(segment
		(start 295.033954 -271.554448)
		(end 295.079674 -271.600168)
		(width 0.1143)
		(layer "In5.Cu")
		(net "P5E_PEX2_STN1_RX_DP<20>")
	)
	(segment
		(start 295.64965 -273.784314)
		(end 295.64965 -274.049744)
		(width 0.1143)
		(layer "In5.Cu")
		(net "P5E_PEX2_STN1_RX_DP<20>")
	)
	(segment
		(start 273.882866 -113.218722)
		(end 273.045174 -114.696748)
		(width 0.1651)
		(layer "In5.Cu")
		(net "P5E_PEX2_STN1_RX_DP<20>")
	)
	(segment
		(start 265.936984 -129.472436)
		(end 264.296652 -150.509986)
		(width 0.1651)
		(layer "In5.Cu")
		(net "P5E_PEX2_STN1_RX_DP<20>")
	)
	(segment
		(start 270.63319 -122.95759)
		(end 268.865604 -123.639326)
		(width 0.1651)
		(layer "In5.Cu")
		(net "P5E_PEX2_STN1_RX_DP<20>")
	)
	(segment
		(start 283.789374 -106.803444)
		(end 276.512782 -110.677452)
		(width 0.1651)
		(layer "In5.Cu")
		(net "P5E_PEX2_STN1_RX_DP<20>")
	)
	(segment
		(start 286.006032 -106.803444)
		(end 283.789374 -106.803444)
		(width 0.1651)
		(layer "In5.Cu")
		(net "P5E_PEX2_STN1_RX_DP<20>")
	)
	(segment
		(start 268.816836 -123.736608)
		(end 265.936984 -129.472436)
		(width 0.1651)
		(layer "In5.Cu")
		(net "P5E_PEX2_STN1_RX_DP<20>")
	)
	(segment
		(start 295.294558 -273.670014)
		(end 295.53535 -273.670014)
		(width 0.1143)
		(layer "In5.Cu")
		(net "P5E_PEX2_STN1_RX_DP<20>")
	)
	(segment
		(start 268.865604 -123.639326)
		(end 268.816582 -123.736608)
		(width 0.1651)
		(layer "In5.Cu")
		(net "P5E_PEX2_STN1_RX_DP<20>")
	)
	(segment
		(start 276.512782 -110.677452)
		(end 273.882866 -113.218722)
		(width 0.1651)
		(layer "In5.Cu")
		(net "P5E_PEX2_STN1_RX_DP<20>")
	)
	(segment
		(start 265.843004 -164.725858)
		(end 295.033954 -269.350998)
		(width 0.1651)
		(layer "In5.Cu")
		(net "P5E_PEX2_STN1_RX_DP<20>")
	)
	(segment
		(start 264.296652 -150.509986)
		(end 264.557256 -154.632406)
		(width 0.1651)
		(layer "In5.Cu")
		(net "P5E_PEX2_STN1_RX_DP<20>")
	)
	(segment
		(start 295.079674 -271.600168)
		(end 295.079674 -273.45513)
		(width 0.1143)
		(layer "In5.Cu")
		(net "P5E_PEX2_STN1_RX_DP<20>")
	)
	(segment
		(start 295.079674 -273.45513)
		(end 295.294558 -273.670014)
		(width 0.1143)
		(layer "In5.Cu")
		(net "P5E_PEX2_STN1_RX_DP<20>")
	)
	(segment
		(start 268.816582 -123.736608)
		(end 268.816836 -123.736608)
		(width 0.1651)
		(layer "In5.Cu")
		(net "P5E_PEX2_STN1_RX_DP<20>")
	)
	(segment
		(start 286.296862 -106.512614)
		(end 286.006032 -106.803444)
		(width 0.1651)
		(layer "In5.Cu")
		(net "P5E_PEX2_STN1_RX_DP<20>")
	)
	(segment
		(start 264.817606 -158.750254)
		(end 265.843004 -164.725858)
		(width 0.1651)
		(layer "In5.Cu")
		(net "P5E_PEX2_STN1_RX_DP<20>")
	)
	(segment
		(start 295.53535 -273.670014)
		(end 295.64965 -273.784314)
		(width 0.1143)
		(layer "In5.Cu")
		(net "P5E_PEX2_STN1_RX_DP<20>")
	)
	(segment
		(start 295.033954 -269.350998)
		(end 295.033954 -271.526)
		(width 0.1651)
		(layer "In5.Cu")
		(net "P5E_PEX2_STN1_RX_DP<20>")
	)
	(segment
		(start 273.045174 -114.696748)
		(end 271.2974 -122.198384)
		(width 0.1651)
		(layer "In5.Cu")
		(net "P5E_PEX2_STN1_RX_DP<20>")
	)
	(segment
		(start 264.557256 -154.632406)
		(end 264.817606 -158.750254)
		(width 0.1651)
		(layer "In5.Cu")
		(net "P5E_PEX2_STN1_RX_DP<20>")
	)
	(segment
		(start 295.033954 -271.526)
		(end 295.033954 -271.554448)
		(width 0.1143)
		(layer "In5.Cu")
		(net "P5E_PEX2_STN1_RX_DP<20>")
	)
	(segment
		(start 271.2974 -122.198384)
		(end 270.63319 -122.95759)
		(width 0.1651)
		(layer "In5.Cu")
		(net "P5E_PEX2_STN1_RX_DP<20>")
	)
	(segment
		(start 390.065514 -30.790134)
		(end 389.56488 -30.790134)
		(width 0.13462)
		(layer "F.Cu")
		(net "P5E_PEX3_STN2_TX_C_DP<41>")
	)
	(segment
		(start 394.141452 -30.6197)
		(end 390.235948 -30.6197)
		(width 0.13462)
		(layer "F.Cu")
		(net "P5E_PEX3_STN2_TX_C_DP<41>")
	)
	(segment
		(start 390.235948 -30.6197)
		(end 390.065514 -30.790134)
		(width 0.13462)
		(layer "F.Cu")
		(net "P5E_PEX3_STN2_TX_C_DP<41>")
	)
	(segment
		(start 394.467842 -30.94609)
		(end 394.141452 -30.6197)
		(width 0.13462)
		(layer "F.Cu")
		(net "P5E_PEX3_STN2_TX_C_DP<41>")
	)
	(segment
		(start 422.3004 -344.538554)
		(end 422.3004 -345.171014)
		(width 0.13462)
		(layer "F.Cu")
		(net "P5E_PEX3_STN7_TX_C_DN<117>")
	)
	(segment
		(start 422.3004 -345.171014)
		(end 422.594532 -345.465146)
		(width 0.13462)
		(layer "F.Cu")
		(net "P5E_PEX3_STN7_TX_C_DN<117>")
	)
	(segment
		(start 422.619932 -344.219022)
		(end 422.3004 -344.538554)
		(width 0.13462)
		(layer "F.Cu")
		(net "P5E_PEX3_STN7_TX_C_DN<117>")
	)
	(segment
		(start 416.415728 -385.289298)
		(end 416.191192 -383.36855)
		(width 0.1651)
		(layer "In11.Cu")
		(net "P5E_PEX3_STN7_TX_C_DN<117>")
	)
	(segment
		(start 430.616868 -402.281136)
		(end 431.163984 -402.281136)
		(width 0.1651)
		(layer "In11.Cu")
		(net "P5E_PEX3_STN7_TX_C_DN<117>")
	)
	(segment
		(start 431.163984 -402.281136)
		(end 431.61585 -401.82927)
		(width 0.1651)
		(layer "In11.Cu")
		(net "P5E_PEX3_STN7_TX_C_DN<117>")
	)
	(segment
		(start 417.182554 -386.999988)
		(end 416.415728 -385.289298)
		(width 0.1651)
		(layer "In11.Cu")
		(net "P5E_PEX3_STN7_TX_C_DN<117>")
	)
	(segment
		(start 431.61585 -401.82927)
		(end 431.61585 -394.68425)
		(width 0.1651)
		(layer "In11.Cu")
		(net "P5E_PEX3_STN7_TX_C_DN<117>")
	)
	(segment
		(start 431.61585 -394.68425)
		(end 430.62652 -393.69492)
		(width 0.1651)
		(layer "In11.Cu")
		(net "P5E_PEX3_STN7_TX_C_DN<117>")
	)
	(segment
		(start 416.450272 -368.90198)
		(end 420.749222 -358.67594)
		(width 0.1651)
		(layer "In11.Cu")
		(net "P5E_PEX3_STN7_TX_C_DN<117>")
	)
	(segment
		(start 416.191192 -383.36855)
		(end 416.450272 -368.90198)
		(width 0.1651)
		(layer "In11.Cu")
		(net "P5E_PEX3_STN7_TX_C_DN<117>")
	)
	(segment
		(start 420.749222 -347.881194)
		(end 422.303702 -346.326714)
		(width 0.1651)
		(layer "In11.Cu")
		(net "P5E_PEX3_STN7_TX_C_DN<117>")
	)
	(segment
		(start 422.303702 -345.755976)
		(end 422.594532 -345.465146)
		(width 0.1651)
		(layer "In11.Cu")
		(net "P5E_PEX3_STN7_TX_C_DN<117>")
	)
	(segment
		(start 430.62652 -393.69492)
		(end 417.182554 -386.999988)
		(width 0.1651)
		(layer "In11.Cu")
		(net "P5E_PEX3_STN7_TX_C_DN<117>")
	)
	(segment
		(start 420.749222 -358.67594)
		(end 420.749222 -347.881194)
		(width 0.1651)
		(layer "In11.Cu")
		(net "P5E_PEX3_STN7_TX_C_DN<117>")
	)
	(segment
		(start 430.489868 -402.408136)
		(end 430.616868 -402.281136)
		(width 0.1651)
		(layer "In11.Cu")
		(net "P5E_PEX3_STN7_TX_C_DN<117>")
	)
	(segment
		(start 430.489868 -402.790152)
		(end 430.489868 -402.408136)
		(width 0.1651)
		(layer "In11.Cu")
		(net "P5E_PEX3_STN7_TX_C_DN<117>")
	)
	(segment
		(start 422.303702 -346.326714)
		(end 422.303702 -345.755976)
		(width 0.1651)
		(layer "In11.Cu")
		(net "P5E_PEX3_STN7_TX_C_DN<117>")
	)
	(segment
		(start 156.49702 -140.379196)
		(end 157.482794 -141.36497)
		(width 0.13208)
		(layer "F.Cu")
		(net "NIC2_BIF2_N")
	)
	(segment
		(start 154.65552 -140.379196)
		(end 156.49702 -140.379196)
		(width 0.13208)
		(layer "F.Cu")
		(net "NIC2_BIF2_N")
	)
	(segment
		(start 154.482546 -140.55217)
		(end 154.65552 -140.379196)
		(width 0.13208)
		(layer "F.Cu")
		(net "NIC2_BIF2_N")
	)
	(segment
		(start 157.482794 -141.36497)
		(end 162.14217 -141.36497)
		(width 0.13208)
		(layer "F.Cu")
		(net "NIC2_BIF2_N")
	)
	(segment
		(start 153.504646 -140.85697)
		(end 154.482546 -140.85697)
		(width 0.13208)
		(layer "F.Cu")
		(net "NIC2_BIF2_N")
	)
	(segment
		(start 154.482546 -140.85697)
		(end 154.482546 -140.55217)
		(width 0.13208)
		(layer "F.Cu")
		(net "NIC2_BIF2_N")
	)
	(via
		(at 156.49702 -140.379196)
		(size 0.762)
		(drill 0.381)
		(layers "F.Cu" "B.Cu")
		(net "NIC2_BIF2_N")
	)
	(segment
		(start 421.557704 -97.039938)
		(end 423.407586 -97.039938)
		(width 0.13208)
		(layer "F.Cu")
		(net "PWRGD_NIC7_PWR_GOOD")
	)
	(via
		(at 423.407586 -97.039938)
		(size 0.508)
		(drill 0.254)
		(layers "F.Cu" "B.Cu")
		(net "PWRGD_NIC7_PWR_GOOD")
	)
	(segment
		(start 420.05504 -96.393)
		(end 422.760648 -96.393)
		(width 0.13208)
		(layer "B.Cu")
		(net "PWRGD_NIC7_PWR_GOOD")
	)
	(segment
		(start 419.65499 -97.663)
		(end 419.65499 -96.79305)
		(width 0.13208)
		(layer "B.Cu")
		(net "PWRGD_NIC7_PWR_GOOD")
	)
	(segment
		(start 419.65499 -96.79305)
		(end 420.05504 -96.393)
		(width 0.13208)
		(layer "B.Cu")
		(net "PWRGD_NIC7_PWR_GOOD")
	)
	(segment
		(start 422.760648 -96.393)
		(end 423.407586 -97.039938)
		(width 0.13208)
		(layer "B.Cu")
		(net "PWRGD_NIC7_PWR_GOOD")
	)
	(segment
		(start 418.80409 -97.663)
		(end 419.65499 -97.663)
		(width 0.13208)
		(layer "B.Cu")
		(net "PWRGD_NIC7_PWR_GOOD")
	)
	(segment
		(start 68.169536 -155.355036)
		(end 68.006722 -155.51785)
		(width 0.13462)
		(layer "F.Cu")
		(net "P5E_PEX0_STN0_RX_DN<15>")
	)
	(segment
		(start 68.006722 -155.51785)
		(end 65.498218 -155.51785)
		(width 0.13462)
		(layer "F.Cu")
		(net "P5E_PEX0_STN0_RX_DN<15>")
	)
	(segment
		(start 68.65747 -155.355036)
		(end 68.169536 -155.355036)
		(width 0.13462)
		(layer "F.Cu")
		(net "P5E_PEX0_STN0_RX_DN<15>")
	)
	(segment
		(start 65.498218 -155.51785)
		(end 65.49771 -155.518358)
		(width 0.13462)
		(layer "F.Cu")
		(net "P5E_PEX0_STN0_RX_DN<15>")
	)
	(segment
		(start 65.49771 -155.518358)
		(end 65.20307 -155.223718)
		(width 0.13462)
		(layer "F.Cu")
		(net "P5E_PEX0_STN0_RX_DN<15>")
	)
	(segment
		(start 74.47026 -271.848072)
		(end 74.47026 -273.376136)
		(width 0.1143)
		(layer "In5.Cu")
		(net "P5E_PEX0_STN0_RX_DN<15>")
	)
	(segment
		(start 66.96329 -156.134562)
		(end 67.911218 -162.860736)
		(width 0.1651)
		(layer "In5.Cu")
		(net "P5E_PEX0_STN0_RX_DN<15>")
	)
	(segment
		(start 74.849736 -273.365214)
		(end 74.849736 -273.099784)
		(width 0.1143)
		(layer "In5.Cu")
		(net "P5E_PEX0_STN0_RX_DN<15>")
	)
	(segment
		(start 65.20307 -155.223718)
		(end 65.4939 -155.514548)
		(width 0.1651)
		(layer "In5.Cu")
		(net "P5E_PEX0_STN0_RX_DN<15>")
	)
	(segment
		(start 74.735436 -273.479514)
		(end 74.849736 -273.365214)
		(width 0.1143)
		(layer "In5.Cu")
		(net "P5E_PEX0_STN0_RX_DN<15>")
	)
	(segment
		(start 74.47026 -273.376136)
		(end 74.573638 -273.479514)
		(width 0.1143)
		(layer "In5.Cu")
		(net "P5E_PEX0_STN0_RX_DN<15>")
	)
	(segment
		(start 74.51598 -271.773904)
		(end 74.51598 -271.802352)
		(width 0.1143)
		(layer "In5.Cu")
		(net "P5E_PEX0_STN0_RX_DN<15>")
	)
	(segment
		(start 67.911218 -162.860736)
		(end 67.911218 -162.860482)
		(width 0.1651)
		(layer "In5.Cu")
		(net "P5E_PEX0_STN0_RX_DN<15>")
	)
	(segment
		(start 67.911218 -162.860482)
		(end 74.819256 -261.27202)
		(width 0.1651)
		(layer "In5.Cu")
		(net "P5E_PEX0_STN0_RX_DN<15>")
	)
	(segment
		(start 74.573638 -273.479514)
		(end 74.735436 -273.479514)
		(width 0.1143)
		(layer "In5.Cu")
		(net "P5E_PEX0_STN0_RX_DN<15>")
	)
	(segment
		(start 74.989182 -267.76807)
		(end 74.51598 -270.231616)
		(width 0.1651)
		(layer "In5.Cu")
		(net "P5E_PEX0_STN0_RX_DN<15>")
	)
	(segment
		(start 66.343022 -155.514548)
		(end 66.96329 -156.134562)
		(width 0.1651)
		(layer "In5.Cu")
		(net "P5E_PEX0_STN0_RX_DN<15>")
	)
	(segment
		(start 74.51598 -271.802352)
		(end 74.47026 -271.848072)
		(width 0.1143)
		(layer "In5.Cu")
		(net "P5E_PEX0_STN0_RX_DN<15>")
	)
	(segment
		(start 74.819256 -261.27202)
		(end 74.989182 -267.76807)
		(width 0.1651)
		(layer "In5.Cu")
		(net "P5E_PEX0_STN0_RX_DN<15>")
	)
	(segment
		(start 65.4939 -155.514548)
		(end 66.343022 -155.514548)
		(width 0.1651)
		(layer "In5.Cu")
		(net "P5E_PEX0_STN0_RX_DN<15>")
	)
	(segment
		(start 74.51598 -270.231616)
		(end 74.51598 -271.773904)
		(width 0.1651)
		(layer "In5.Cu")
		(net "P5E_PEX0_STN0_RX_DN<15>")
	)
	(segment
		(start 129.236978 -374.899174)
		(end 129.109978 -374.772174)
		(width 0.1651)
		(layer "In5.Cu")
		(net "P5E_PEX1_STN6_RX_DP<97>")
	)
	(segment
		(start 132.315204 -366.704118)
		(end 132.306314 -366.862106)
		(width 0.1651)
		(layer "In5.Cu")
		(net "P5E_PEX1_STN6_RX_DP<97>")
	)
	(segment
		(start 131.94665 -367.183416)
		(end 131.788916 -367.174526)
		(width 0.1651)
		(layer "In5.Cu")
		(net "P5E_PEX1_STN6_RX_DP<97>")
	)
	(segment
		(start 132.675376 -366.3823)
		(end 132.315204 -366.704118)
		(width 0.1651)
		(layer "In5.Cu")
		(net "P5E_PEX1_STN6_RX_DP<97>")
	)
	(segment
		(start 129.887472 -374.681496)
		(end 129.669794 -374.899174)
		(width 0.1651)
		(layer "In5.Cu")
		(net "P5E_PEX1_STN6_RX_DP<97>")
	)
	(segment
		(start 172.329856 -316.455298)
		(end 172.329856 -319.89268)
		(width 0.1143)
		(layer "In5.Cu")
		(net "P5E_PEX1_STN6_RX_DP<97>")
	)
	(segment
		(start 132.83311 -366.39119)
		(end 132.675376 -366.3823)
		(width 0.1651)
		(layer "In5.Cu")
		(net "P5E_PEX1_STN6_RX_DP<97>")
	)
	(segment
		(start 131.788916 -367.174526)
		(end 131.428744 -367.496344)
		(width 0.1651)
		(layer "In5.Cu")
		(net "P5E_PEX1_STN6_RX_DP<97>")
	)
	(segment
		(start 141.688058 -357.909368)
		(end 141.262862 -358.859074)
		(width 0.1651)
		(layer "In5.Cu")
		(net "P5E_PEX1_STN6_RX_DP<97>")
	)
	(segment
		(start 172.900086 -316.115192)
		(end 172.785786 -316.229492)
		(width 0.1143)
		(layer "In5.Cu")
		(net "P5E_PEX1_STN6_RX_DP<97>")
	)
	(segment
		(start 133.71957 -365.598964)
		(end 133.561836 -365.590074)
		(width 0.1651)
		(layer "In5.Cu")
		(net "P5E_PEX1_STN6_RX_DP<97>")
	)
	(segment
		(start 172.785786 -316.229492)
		(end 172.555662 -316.229492)
		(width 0.1143)
		(layer "In5.Cu")
		(net "P5E_PEX1_STN6_RX_DP<97>")
	)
	(segment
		(start 130.229864 -368.717322)
		(end 129.887472 -369.304316)
		(width 0.1651)
		(layer "In5.Cu")
		(net "P5E_PEX1_STN6_RX_DP<97>")
	)
	(segment
		(start 129.109978 -374.772174)
		(end 129.109978 -374.390158)
		(width 0.1651)
		(layer "In5.Cu")
		(net "P5E_PEX1_STN6_RX_DP<97>")
	)
	(segment
		(start 131.419854 -367.654078)
		(end 130.229864 -368.717322)
		(width 0.1651)
		(layer "In5.Cu")
		(net "P5E_PEX1_STN6_RX_DP<97>")
	)
	(segment
		(start 133.201664 -365.911892)
		(end 133.192774 -366.06988)
		(width 0.1651)
		(layer "In5.Cu")
		(net "P5E_PEX1_STN6_RX_DP<97>")
	)
	(segment
		(start 170.733212 -323.950076)
		(end 157.859984 -331.558646)
		(width 0.1651)
		(layer "In5.Cu")
		(net "P5E_PEX1_STN6_RX_DP<97>")
	)
	(segment
		(start 172.329856 -319.89268)
		(end 172.284136 -319.9384)
		(width 0.1143)
		(layer "In5.Cu")
		(net "P5E_PEX1_STN6_RX_DP<97>")
	)
	(segment
		(start 141.262862 -358.859074)
		(end 133.71957 -365.598964)
		(width 0.1651)
		(layer "In5.Cu")
		(net "P5E_PEX1_STN6_RX_DP<97>")
	)
	(segment
		(start 172.900086 -315.849762)
		(end 172.900086 -316.115192)
		(width 0.1143)
		(layer "In5.Cu")
		(net "P5E_PEX1_STN6_RX_DP<97>")
	)
	(segment
		(start 141.688058 -353.9744)
		(end 141.688058 -357.909368)
		(width 0.1651)
		(layer "In5.Cu")
		(net "P5E_PEX1_STN6_RX_DP<97>")
	)
	(segment
		(start 129.887472 -369.304316)
		(end 129.887472 -374.681496)
		(width 0.1651)
		(layer "In5.Cu")
		(net "P5E_PEX1_STN6_RX_DP<97>")
	)
	(segment
		(start 172.284136 -321.629532)
		(end 170.733212 -323.950076)
		(width 0.1651)
		(layer "In5.Cu")
		(net "P5E_PEX1_STN6_RX_DP<97>")
	)
	(segment
		(start 157.859984 -331.558646)
		(end 153.777696 -336.121756)
		(width 0.1651)
		(layer "In5.Cu")
		(net "P5E_PEX1_STN6_RX_DP<97>")
	)
	(segment
		(start 143.91513 -352.8822)
		(end 142.780258 -352.8822)
		(width 0.1651)
		(layer "In5.Cu")
		(net "P5E_PEX1_STN6_RX_DP<97>")
	)
	(segment
		(start 172.555662 -316.229492)
		(end 172.329856 -316.455298)
		(width 0.1143)
		(layer "In5.Cu")
		(net "P5E_PEX1_STN6_RX_DP<97>")
	)
	(segment
		(start 172.284136 -319.9384)
		(end 172.284136 -319.966848)
		(width 0.1143)
		(layer "In5.Cu")
		(net "P5E_PEX1_STN6_RX_DP<97>")
	)
	(segment
		(start 133.561836 -365.590074)
		(end 133.201664 -365.911892)
		(width 0.1651)
		(layer "In5.Cu")
		(net "P5E_PEX1_STN6_RX_DP<97>")
	)
	(segment
		(start 129.669794 -374.899174)
		(end 129.236978 -374.899174)
		(width 0.1651)
		(layer "In5.Cu")
		(net "P5E_PEX1_STN6_RX_DP<97>")
	)
	(segment
		(start 132.306314 -366.862106)
		(end 131.94665 -367.183416)
		(width 0.1651)
		(layer "In5.Cu")
		(net "P5E_PEX1_STN6_RX_DP<97>")
	)
	(segment
		(start 142.780258 -352.8822)
		(end 141.688058 -353.9744)
		(width 0.1651)
		(layer "In5.Cu")
		(net "P5E_PEX1_STN6_RX_DP<97>")
	)
	(segment
		(start 144.360138 -352.623882)
		(end 143.91513 -352.8822)
		(width 0.1651)
		(layer "In5.Cu")
		(net "P5E_PEX1_STN6_RX_DP<97>")
	)
	(segment
		(start 153.777696 -336.121756)
		(end 144.360138 -352.623882)
		(width 0.1651)
		(layer "In5.Cu")
		(net "P5E_PEX1_STN6_RX_DP<97>")
	)
	(segment
		(start 172.284136 -319.966848)
		(end 172.284136 -321.629532)
		(width 0.1651)
		(layer "In5.Cu")
		(net "P5E_PEX1_STN6_RX_DP<97>")
	)
	(segment
		(start 131.428744 -367.496344)
		(end 131.419854 -367.654078)
		(width 0.1651)
		(layer "In5.Cu")
		(net "P5E_PEX1_STN6_RX_DP<97>")
	)
	(segment
		(start 133.192774 -366.06988)
		(end 132.83311 -366.39119)
		(width 0.1651)
		(layer "In5.Cu")
		(net "P5E_PEX1_STN6_RX_DP<97>")
	)
	(segment
		(start 277.739602 -110.245144)
		(end 278.242268 -110.245144)
		(width 0.13462)
		(layer "F.Cu")
		(net "P5E_PEX2_STN1_TX_C_DP<22>")
	)
	(segment
		(start 272.05178 -110.39348)
		(end 277.591266 -110.39348)
		(width 0.13462)
		(layer "F.Cu")
		(net "P5E_PEX2_STN1_TX_C_DP<22>")
	)
	(segment
		(start 271.747234 -110.088934)
		(end 272.05178 -110.39348)
		(width 0.13462)
		(layer "F.Cu")
		(net "P5E_PEX2_STN1_TX_C_DP<22>")
	)
	(segment
		(start 277.591266 -110.39348)
		(end 277.739602 -110.245144)
		(width 0.13462)
		(layer "F.Cu")
		(net "P5E_PEX2_STN1_TX_C_DP<22>")
	)
	(segment
		(start 318.720724 -351.611438)
		(end 319.015364 -351.316798)
		(width 0.13462)
		(layer "F.Cu")
		(net "P5E_PEX2_STN5_TX_C_DP<83>")
	)
	(segment
		(start 319.015364 -350.685354)
		(end 318.695324 -350.365314)
		(width 0.13462)
		(layer "F.Cu")
		(net "P5E_PEX2_STN5_TX_C_DP<83>")
	)
	(segment
		(start 319.015364 -351.316798)
		(end 319.015364 -350.685354)
		(width 0.13462)
		(layer "F.Cu")
		(net "P5E_PEX2_STN5_TX_C_DP<83>")
	)
	(segment
		(start 338.090002 -405.772112)
		(end 338.217002 -405.899112)
		(width 0.1651)
		(layer "In7.Cu")
		(net "P5E_PEX2_STN5_TX_C_DP<83>")
	)
	(segment
		(start 326.397366 -385.445)
		(end 317.457074 -358.948482)
		(width 0.1651)
		(layer "In7.Cu")
		(net "P5E_PEX2_STN5_TX_C_DP<83>")
	)
	(segment
		(start 338.647278 -405.899112)
		(end 338.934044 -405.612346)
		(width 0.1651)
		(layer "In7.Cu")
		(net "P5E_PEX2_STN5_TX_C_DP<83>")
	)
	(segment
		(start 337.194906 -394.038836)
		(end 336.84464 -393.688062)
		(width 0.1651)
		(layer "In7.Cu")
		(net "P5E_PEX2_STN5_TX_C_DP<83>")
	)
	(segment
		(start 338.934044 -405.612346)
		(end 338.934044 -395.961362)
		(width 0.1651)
		(layer "In7.Cu")
		(net "P5E_PEX2_STN5_TX_C_DP<83>")
	)
	(segment
		(start 317.457074 -358.948482)
		(end 317.457074 -353.910646)
		(width 0.1651)
		(layer "In7.Cu")
		(net "P5E_PEX2_STN5_TX_C_DP<83>")
	)
	(segment
		(start 317.457074 -353.910646)
		(end 319.011554 -352.356166)
		(width 0.1651)
		(layer "In7.Cu")
		(net "P5E_PEX2_STN5_TX_C_DP<83>")
	)
	(segment
		(start 337.670394 -394.515086)
		(end 337.670394 -394.389356)
		(width 0.1651)
		(layer "In7.Cu")
		(net "P5E_PEX2_STN5_TX_C_DP<83>")
	)
	(segment
		(start 319.011554 -351.902268)
		(end 318.720724 -351.611438)
		(width 0.1651)
		(layer "In7.Cu")
		(net "P5E_PEX2_STN5_TX_C_DP<83>")
	)
	(segment
		(start 338.020406 -394.86586)
		(end 337.670394 -394.515086)
		(width 0.1651)
		(layer "In7.Cu")
		(net "P5E_PEX2_STN5_TX_C_DP<83>")
	)
	(segment
		(start 338.934044 -395.961362)
		(end 338.71408 -395.43482)
		(width 0.1651)
		(layer "In7.Cu")
		(net "P5E_PEX2_STN5_TX_C_DP<83>")
	)
	(segment
		(start 319.011554 -352.356166)
		(end 319.011554 -351.902268)
		(width 0.1651)
		(layer "In7.Cu")
		(net "P5E_PEX2_STN5_TX_C_DP<83>")
	)
	(segment
		(start 335.940146 -392.656314)
		(end 329.308968 -389.895334)
		(width 0.1651)
		(layer "In7.Cu")
		(net "P5E_PEX2_STN5_TX_C_DP<83>")
	)
	(segment
		(start 336.84464 -393.688062)
		(end 336.84464 -393.562332)
		(width 0.1651)
		(layer "In7.Cu")
		(net "P5E_PEX2_STN5_TX_C_DP<83>")
	)
	(segment
		(start 336.84464 -393.562332)
		(end 335.940146 -392.656314)
		(width 0.1651)
		(layer "In7.Cu")
		(net "P5E_PEX2_STN5_TX_C_DP<83>")
	)
	(segment
		(start 329.308968 -389.895334)
		(end 327.484486 -388.08406)
		(width 0.1651)
		(layer "In7.Cu")
		(net "P5E_PEX2_STN5_TX_C_DP<83>")
	)
	(segment
		(start 338.146136 -394.866114)
		(end 338.020406 -394.86586)
		(width 0.1651)
		(layer "In7.Cu")
		(net "P5E_PEX2_STN5_TX_C_DP<83>")
	)
	(segment
		(start 338.217002 -405.899112)
		(end 338.647278 -405.899112)
		(width 0.1651)
		(layer "In7.Cu")
		(net "P5E_PEX2_STN5_TX_C_DP<83>")
	)
	(segment
		(start 327.484486 -388.08406)
		(end 326.397366 -385.445)
		(width 0.1651)
		(layer "In7.Cu")
		(net "P5E_PEX2_STN5_TX_C_DP<83>")
	)
	(segment
		(start 337.320636 -394.03909)
		(end 337.194906 -394.038836)
		(width 0.1651)
		(layer "In7.Cu")
		(net "P5E_PEX2_STN5_TX_C_DP<83>")
	)
	(segment
		(start 338.71408 -395.43482)
		(end 338.146136 -394.866114)
		(width 0.1651)
		(layer "In7.Cu")
		(net "P5E_PEX2_STN5_TX_C_DP<83>")
	)
	(segment
		(start 337.670394 -394.389356)
		(end 337.320636 -394.03909)
		(width 0.1651)
		(layer "In7.Cu")
		(net "P5E_PEX2_STN5_TX_C_DP<83>")
	)
	(segment
		(start 338.090002 -405.390096)
		(end 338.090002 -405.772112)
		(width 0.1651)
		(layer "In7.Cu")
		(net "P5E_PEX2_STN5_TX_C_DP<83>")
	)
	(segment
		(start 364.06455 -28.990036)
		(end 363.564932 -28.990036)
		(width 0.13462)
		(layer "F.Cu")
		(net "P5E_PEX3_STN2_TX_C_DP<44>")
	)
	(segment
		(start 365.825786 -29.139642)
		(end 365.515144 -28.829)
		(width 0.13462)
		(layer "F.Cu")
		(net "P5E_PEX3_STN2_TX_C_DP<44>")
	)
	(segment
		(start 364.225586 -28.829)
		(end 364.06455 -28.990036)
		(width 0.13462)
		(layer "F.Cu")
		(net "P5E_PEX3_STN2_TX_C_DP<44>")
	)
	(segment
		(start 365.515144 -28.829)
		(end 364.225586 -28.829)
		(width 0.13462)
		(layer "F.Cu")
		(net "P5E_PEX3_STN2_TX_C_DP<44>")
	)
	(segment
		(start 409.86456 -344.538554)
		(end 409.86456 -345.171014)
		(width 0.13462)
		(layer "F.Cu")
		(net "P5E_PEX3_STN7_TX_C_DN<112>")
	)
	(segment
		(start 409.86456 -345.171014)
		(end 410.158692 -345.465146)
		(width 0.13462)
		(layer "F.Cu")
		(net "P5E_PEX3_STN7_TX_C_DN<112>")
	)
	(segment
		(start 410.184092 -344.219022)
		(end 409.86456 -344.538554)
		(width 0.13462)
		(layer "F.Cu")
		(net "P5E_PEX3_STN7_TX_C_DN<112>")
	)
	(segment
		(start 411.061662 -386.369052)
		(end 413.847534 -391.448036)
		(width 0.1651)
		(layer "In11.Cu")
		(net "P5E_PEX3_STN7_TX_C_DN<112>")
	)
	(segment
		(start 409.867862 -345.755976)
		(end 409.867862 -346.326714)
		(width 0.1651)
		(layer "In11.Cu")
		(net "P5E_PEX3_STN7_TX_C_DN<112>")
	)
	(segment
		(start 407.9748 -350.366838)
		(end 410.591254 -383.523236)
		(width 0.1651)
		(layer "In11.Cu")
		(net "P5E_PEX3_STN7_TX_C_DN<112>")
	)
	(segment
		(start 420.615872 -394.809472)
		(end 420.615872 -400.729196)
		(width 0.1651)
		(layer "In11.Cu")
		(net "P5E_PEX3_STN7_TX_C_DN<112>")
	)
	(segment
		(start 420.615872 -400.729196)
		(end 420.164006 -401.181062)
		(width 0.1651)
		(layer "In11.Cu")
		(net "P5E_PEX3_STN7_TX_C_DN<112>")
	)
	(segment
		(start 409.867862 -346.326714)
		(end 408.29865 -347.895926)
		(width 0.1651)
		(layer "In11.Cu")
		(net "P5E_PEX3_STN7_TX_C_DN<112>")
	)
	(segment
		(start 420.215314 -394.408914)
		(end 420.615872 -394.809472)
		(width 0.1651)
		(layer "In11.Cu")
		(net "P5E_PEX3_STN7_TX_C_DN<112>")
	)
	(segment
		(start 410.591254 -383.523236)
		(end 411.061662 -386.369052)
		(width 0.1651)
		(layer "In11.Cu")
		(net "P5E_PEX3_STN7_TX_C_DN<112>")
	)
	(segment
		(start 408.29865 -347.895926)
		(end 407.9748 -350.366838)
		(width 0.1651)
		(layer "In11.Cu")
		(net "P5E_PEX3_STN7_TX_C_DN<112>")
	)
	(segment
		(start 410.158692 -345.465146)
		(end 409.867862 -345.755976)
		(width 0.1651)
		(layer "In11.Cu")
		(net "P5E_PEX3_STN7_TX_C_DN<112>")
	)
	(segment
		(start 413.847534 -391.448036)
		(end 420.215314 -394.408914)
		(width 0.1651)
		(layer "In11.Cu")
		(net "P5E_PEX3_STN7_TX_C_DN<112>")
	)
	(segment
		(start 420.164006 -401.181062)
		(end 419.61689 -401.181062)
		(width 0.1651)
		(layer "In11.Cu")
		(net "P5E_PEX3_STN7_TX_C_DN<112>")
	)
	(segment
		(start 419.48989 -401.308062)
		(end 419.48989 -401.690078)
		(width 0.1651)
		(layer "In11.Cu")
		(net "P5E_PEX3_STN7_TX_C_DN<112>")
	)
	(segment
		(start 419.61689 -401.181062)
		(end 419.48989 -401.308062)
		(width 0.1651)
		(layer "In11.Cu")
		(net "P5E_PEX3_STN7_TX_C_DN<112>")
	)
	(segment
		(start 170.455844 -157.353)
		(end 171.198794 -157.353)
		(width 0.13208)
		(layer "F.Cu")
		(net "RST_NIC2_PERST3_R_N")
	)
	(segment
		(start 171.198794 -157.353)
		(end 171.681394 -157.8356)
		(width 0.13208)
		(layer "F.Cu")
		(net "RST_NIC2_PERST3_R_N")
	)
	(segment
		(start 168.143936 -157.759908)
		(end 168.550844 -157.353)
		(width 0.13208)
		(layer "F.Cu")
		(net "RST_NIC2_PERST3_R_N")
	)
	(segment
		(start 166.742364 -157.759908)
		(end 168.143936 -157.759908)
		(width 0.13208)
		(layer "F.Cu")
		(net "RST_NIC2_PERST3_R_N")
	)
	(segment
		(start 168.550844 -157.353)
		(end 170.455844 -157.353)
		(width 0.13208)
		(layer "F.Cu")
		(net "RST_NIC2_PERST3_R_N")
	)
	(via
		(at 170.455844 -157.353)
		(size 0.762)
		(drill 0.381)
		(layers "F.Cu" "B.Cu")
		(net "RST_NIC2_PERST3_R_N")
	)
	(segment
		(start 414.305496 -97.64014)
		(end 416.95751 -97.64014)
		(width 0.13208)
		(layer "F.Cu")
		(net "RST_NIC7_PERST3_R_N")
	)
	(segment
		(start 414.227264 -97.718372)
		(end 414.305496 -97.64014)
		(width 0.13208)
		(layer "F.Cu")
		(net "RST_NIC7_PERST3_R_N")
	)
	(segment
		(start 412.309056 -97.718372)
		(end 414.227264 -97.718372)
		(width 0.13208)
		(layer "F.Cu")
		(net "RST_NIC7_PERST3_R_N")
	)
	(segment
		(start 407.695146 -97.718372)
		(end 412.309056 -97.718372)
		(width 0.13208)
		(layer "F.Cu")
		(net "RST_NIC7_PERST3_R_N")
	)
	(via
		(at 412.309056 -97.718372)
		(size 0.762)
		(drill 0.381)
		(layers "F.Cu" "B.Cu")
		(net "RST_NIC7_PERST3_R_N")
	)
	(segment
		(start 73.908666 -144.99209)
		(end 82.075782 -144.99209)
		(width 0.13462)
		(layer "F.Cu")
		(net "P5E_PEX0_STN0_TX_C_DP<9>")
	)
	(segment
		(start 73.257664 -145.154904)
		(end 73.745852 -145.154904)
		(width 0.13462)
		(layer "F.Cu")
		(net "P5E_PEX0_STN0_TX_C_DP<9>")
	)
	(segment
		(start 73.745852 -145.154904)
		(end 73.908666 -144.99209)
		(width 0.13462)
		(layer "F.Cu")
		(net "P5E_PEX0_STN0_TX_C_DP<9>")
	)
	(segment
		(start 82.075782 -144.99209)
		(end 82.394806 -145.311114)
		(width 0.13462)
		(layer "F.Cu")
		(net "P5E_PEX0_STN0_TX_C_DP<9>")
	)
	(segment
		(start 145.456402 -336.260694)
		(end 156.026104 -329.555856)
		(width 0.1651)
		(layer "In5.Cu")
		(net "P5E_PEX1_STN6_RX_DN<100>")
	)
	(segment
		(start 122.637042 -376.281188)
		(end 123.186698 -376.281188)
		(width 0.1651)
		(layer "In5.Cu")
		(net "P5E_PEX1_STN6_RX_DN<100>")
	)
	(segment
		(start 169.715942 -319.916048)
		(end 169.715942 -319.8876)
		(width 0.1143)
		(layer "In5.Cu")
		(net "P5E_PEX1_STN6_RX_DN<100>")
	)
	(segment
		(start 123.569476 -375.89841)
		(end 123.569476 -369.82146)
		(width 0.1651)
		(layer "In5.Cu")
		(net "P5E_PEX1_STN6_RX_DN<100>")
	)
	(segment
		(start 169.715942 -320.76644)
		(end 169.715942 -319.916048)
		(width 0.1651)
		(layer "In5.Cu")
		(net "P5E_PEX1_STN6_RX_DN<100>")
	)
	(segment
		(start 122.510042 -376.408188)
		(end 122.637042 -376.281188)
		(width 0.1651)
		(layer "In5.Cu")
		(net "P5E_PEX1_STN6_RX_DN<100>")
	)
	(segment
		(start 169.784522 -318.320166)
		(end 169.935652 -318.320166)
		(width 0.1143)
		(layer "In5.Cu")
		(net "P5E_PEX1_STN6_RX_DN<100>")
	)
	(segment
		(start 168.470326 -322.200524)
		(end 169.715942 -320.76644)
		(width 0.1651)
		(layer "In5.Cu")
		(net "P5E_PEX1_STN6_RX_DN<100>")
	)
	(segment
		(start 132.643118 -342.08847)
		(end 132.990844 -341.622126)
		(width 0.1651)
		(layer "In5.Cu")
		(net "P5E_PEX1_STN6_RX_DN<100>")
	)
	(segment
		(start 123.186698 -376.281188)
		(end 123.569476 -375.89841)
		(width 0.1651)
		(layer "In5.Cu")
		(net "P5E_PEX1_STN6_RX_DN<100>")
	)
	(segment
		(start 124.12726 -368.32286)
		(end 132.294884 -358.864662)
		(width 0.1651)
		(layer "In5.Cu")
		(net "P5E_PEX1_STN6_RX_DN<100>")
	)
	(segment
		(start 133.208522 -341.404448)
		(end 145.456402 -336.260694)
		(width 0.1651)
		(layer "In5.Cu")
		(net "P5E_PEX1_STN6_RX_DN<100>")
	)
	(segment
		(start 169.670222 -319.84188)
		(end 169.670222 -318.434466)
		(width 0.1143)
		(layer "In5.Cu")
		(net "P5E_PEX1_STN6_RX_DN<100>")
	)
	(segment
		(start 132.990844 -341.622126)
		(end 133.208522 -341.404448)
		(width 0.1651)
		(layer "In5.Cu")
		(net "P5E_PEX1_STN6_RX_DN<100>")
	)
	(segment
		(start 169.715942 -319.8876)
		(end 169.670222 -319.84188)
		(width 0.1143)
		(layer "In5.Cu")
		(net "P5E_PEX1_STN6_RX_DN<100>")
	)
	(segment
		(start 123.569476 -369.82146)
		(end 124.12726 -368.32286)
		(width 0.1651)
		(layer "In5.Cu")
		(net "P5E_PEX1_STN6_RX_DN<100>")
	)
	(segment
		(start 169.935652 -318.320166)
		(end 170.049952 -318.434466)
		(width 0.1143)
		(layer "In5.Cu")
		(net "P5E_PEX1_STN6_RX_DN<100>")
	)
	(segment
		(start 169.670222 -318.434466)
		(end 169.784522 -318.320166)
		(width 0.1143)
		(layer "In5.Cu")
		(net "P5E_PEX1_STN6_RX_DN<100>")
	)
	(segment
		(start 132.294884 -358.864662)
		(end 132.643118 -357.928672)
		(width 0.1651)
		(layer "In5.Cu")
		(net "P5E_PEX1_STN6_RX_DN<100>")
	)
	(segment
		(start 156.026104 -329.555856)
		(end 168.470326 -322.200524)
		(width 0.1651)
		(layer "In5.Cu")
		(net "P5E_PEX1_STN6_RX_DN<100>")
	)
	(segment
		(start 132.643118 -357.928672)
		(end 132.643118 -342.08847)
		(width 0.1651)
		(layer "In5.Cu")
		(net "P5E_PEX1_STN6_RX_DN<100>")
	)
	(segment
		(start 170.049952 -318.434466)
		(end 170.049952 -318.699896)
		(width 0.1143)
		(layer "In5.Cu")
		(net "P5E_PEX1_STN6_RX_DN<100>")
	)
	(segment
		(start 122.510042 -376.790204)
		(end 122.510042 -376.408188)
		(width 0.1651)
		(layer "In5.Cu")
		(net "P5E_PEX1_STN6_RX_DN<100>")
	)
	(segment
		(start 283.492194 -108.61548)
		(end 283.32176 -108.445046)
		(width 0.13462)
		(layer "F.Cu")
		(net "P5E_PEX2_STN1_RX_DP<21>")
	)
	(segment
		(start 283.32176 -108.445046)
		(end 282.842462 -108.445046)
		(width 0.13462)
		(layer "F.Cu")
		(net "P5E_PEX2_STN1_RX_DP<21>")
	)
	(segment
		(start 284.139894 -108.61548)
		(end 283.492194 -108.61548)
		(width 0.13462)
		(layer "F.Cu")
		(net "P5E_PEX2_STN1_RX_DP<21>")
	)
	(segment
		(start 284.442662 -108.312712)
		(end 284.139894 -108.61548)
		(width 0.13462)
		(layer "F.Cu")
		(net "P5E_PEX2_STN1_RX_DP<21>")
	)
	(segment
		(start 274.752816 -113.706656)
		(end 274.645882 -113.810542)
		(width 0.1651)
		(layer "In5.Cu")
		(net "P5E_PEX2_STN1_RX_DP<21>")
	)
	(segment
		(start 296.48531 -275.569934)
		(end 296.59961 -275.684234)
		(width 0.1143)
		(layer "In5.Cu")
		(net "P5E_PEX2_STN1_RX_DP<21>")
	)
	(segment
		(start 296.59961 -275.684234)
		(end 296.59961 -275.949664)
		(width 0.1143)
		(layer "In5.Cu")
		(net "P5E_PEX2_STN1_RX_DP<21>")
	)
	(segment
		(start 284.151832 -108.603542)
		(end 283.71927 -108.603542)
		(width 0.1651)
		(layer "In5.Cu")
		(net "P5E_PEX2_STN1_RX_DP<21>")
	)
	(segment
		(start 266.83589 -164.671756)
		(end 295.983914 -269.183104)
		(width 0.1651)
		(layer "In5.Cu")
		(net "P5E_PEX2_STN1_RX_DP<21>")
	)
	(segment
		(start 295.983914 -271.570704)
		(end 295.983914 -271.599152)
		(width 0.1143)
		(layer "In5.Cu")
		(net "P5E_PEX2_STN1_RX_DP<21>")
	)
	(segment
		(start 284.442662 -108.312712)
		(end 284.151832 -108.603542)
		(width 0.1651)
		(layer "In5.Cu")
		(net "P5E_PEX2_STN1_RX_DP<21>")
	)
	(segment
		(start 265.291316 -150.66772)
		(end 265.293348 -150.701756)
		(width 0.1651)
		(layer "In5.Cu")
		(net "P5E_PEX2_STN1_RX_DP<21>")
	)
	(segment
		(start 268.470888 -132.111496)
		(end 268.470888 -136.383268)
		(width 0.1651)
		(layer "In5.Cu")
		(net "P5E_PEX2_STN1_RX_DP<21>")
	)
	(segment
		(start 273.945096 -115.056158)
		(end 271.832832 -124.282962)
		(width 0.1651)
		(layer "In5.Cu")
		(net "P5E_PEX2_STN1_RX_DP<21>")
	)
	(segment
		(start 265.293602 -150.701756)
		(end 265.778996 -158.54426)
		(width 0.1651)
		(layer "In5.Cu")
		(net "P5E_PEX2_STN1_RX_DP<21>")
	)
	(segment
		(start 283.71927 -108.603542)
		(end 283.68117 -108.641642)
		(width 0.1651)
		(layer "In5.Cu")
		(net "P5E_PEX2_STN1_RX_DP<21>")
	)
	(segment
		(start 295.983914 -271.599152)
		(end 296.029634 -271.644872)
		(width 0.1143)
		(layer "In5.Cu")
		(net "P5E_PEX2_STN1_RX_DP<21>")
	)
	(segment
		(start 267.286486 -139.663932)
		(end 265.291316 -150.66772)
		(width 0.1651)
		(layer "In5.Cu")
		(net "P5E_PEX2_STN1_RX_DP<21>")
	)
	(segment
		(start 265.778996 -158.54426)
		(end 266.83589 -164.671756)
		(width 0.1651)
		(layer "In5.Cu")
		(net "P5E_PEX2_STN1_RX_DP<21>")
	)
	(segment
		(start 296.029634 -275.35505)
		(end 296.244518 -275.569934)
		(width 0.1143)
		(layer "In5.Cu")
		(net "P5E_PEX2_STN1_RX_DP<21>")
	)
	(segment
		(start 296.029634 -271.644872)
		(end 296.029634 -275.35505)
		(width 0.1143)
		(layer "In5.Cu")
		(net "P5E_PEX2_STN1_RX_DP<21>")
	)
	(segment
		(start 265.293348 -150.701756)
		(end 265.293602 -150.701756)
		(width 0.1651)
		(layer "In5.Cu")
		(net "P5E_PEX2_STN1_RX_DP<21>")
	)
	(segment
		(start 283.68117 -108.641642)
		(end 274.752816 -113.706656)
		(width 0.1651)
		(layer "In5.Cu")
		(net "P5E_PEX2_STN1_RX_DP<21>")
	)
	(segment
		(start 296.244518 -275.569934)
		(end 296.48531 -275.569934)
		(width 0.1143)
		(layer "In5.Cu")
		(net "P5E_PEX2_STN1_RX_DP<21>")
	)
	(segment
		(start 295.983914 -269.183104)
		(end 295.983914 -271.570704)
		(width 0.1651)
		(layer "In5.Cu")
		(net "P5E_PEX2_STN1_RX_DP<21>")
	)
	(segment
		(start 274.645882 -113.810542)
		(end 273.945096 -115.056158)
		(width 0.1651)
		(layer "In5.Cu")
		(net "P5E_PEX2_STN1_RX_DP<21>")
	)
	(segment
		(start 268.470888 -136.383268)
		(end 267.286486 -139.663932)
		(width 0.1651)
		(layer "In5.Cu")
		(net "P5E_PEX2_STN1_RX_DP<21>")
	)
	(segment
		(start 271.832832 -124.282962)
		(end 268.470888 -132.111496)
		(width 0.1651)
		(layer "In5.Cu")
		(net "P5E_PEX2_STN1_RX_DP<21>")
	)
	(segment
		(start 321.804284 -344.219022)
		(end 322.124324 -344.539062)
		(width 0.13462)
		(layer "F.Cu")
		(net "P5E_PEX2_STN5_TX_C_DP<84>")
	)
	(segment
		(start 322.124324 -345.170506)
		(end 321.829684 -345.465146)
		(width 0.13462)
		(layer "F.Cu")
		(net "P5E_PEX2_STN5_TX_C_DP<84>")
	)
	(segment
		(start 322.124324 -344.539062)
		(end 322.124324 -345.170506)
		(width 0.13462)
		(layer "F.Cu")
		(net "P5E_PEX2_STN5_TX_C_DP<84>")
	)
	(segment
		(start 341.134192 -395.17574)
		(end 340.621366 -394.440918)
		(width 0.1651)
		(layer "In7.Cu")
		(net "P5E_PEX2_STN5_TX_C_DP<84>")
	)
	(segment
		(start 320.566034 -347.764354)
		(end 322.120514 -346.209874)
		(width 0.1651)
		(layer "In7.Cu")
		(net "P5E_PEX2_STN5_TX_C_DP<84>")
	)
	(segment
		(start 339.328252 -393.683236)
		(end 339.303614 -393.560046)
		(width 0.1651)
		(layer "In7.Cu")
		(net "P5E_PEX2_STN5_TX_C_DP<84>")
	)
	(segment
		(start 339.74024 -393.958826)
		(end 339.328252 -393.683236)
		(width 0.1651)
		(layer "In7.Cu")
		(net "P5E_PEX2_STN5_TX_C_DP<84>")
	)
	(segment
		(start 336.657442 -391.790682)
		(end 335.388204 -391.26287)
		(width 0.1651)
		(layer "In7.Cu")
		(net "P5E_PEX2_STN5_TX_C_DP<84>")
	)
	(segment
		(start 339.86343 -393.934188)
		(end 339.74024 -393.958826)
		(width 0.1651)
		(layer "In7.Cu")
		(net "P5E_PEX2_STN5_TX_C_DP<84>")
	)
	(segment
		(start 340.29015 -404.672038)
		(end 340.41715 -404.799038)
		(width 0.1651)
		(layer "In7.Cu")
		(net "P5E_PEX2_STN5_TX_C_DP<84>")
	)
	(segment
		(start 337.361022 -392.26109)
		(end 336.657442 -391.790682)
		(width 0.1651)
		(layer "In7.Cu")
		(net "P5E_PEX2_STN5_TX_C_DP<84>")
	)
	(segment
		(start 327.186036 -384.792982)
		(end 320.566034 -358.88676)
		(width 0.1651)
		(layer "In7.Cu")
		(net "P5E_PEX2_STN5_TX_C_DP<84>")
	)
	(segment
		(start 340.847426 -404.799038)
		(end 341.134192 -404.512272)
		(width 0.1651)
		(layer "In7.Cu")
		(net "P5E_PEX2_STN5_TX_C_DP<84>")
	)
	(segment
		(start 340.29015 -404.290022)
		(end 340.29015 -404.672038)
		(width 0.1651)
		(layer "In7.Cu")
		(net "P5E_PEX2_STN5_TX_C_DP<84>")
	)
	(segment
		(start 329.86472 -388.965694)
		(end 328.251566 -387.35)
		(width 0.1651)
		(layer "In7.Cu")
		(net "P5E_PEX2_STN5_TX_C_DP<84>")
	)
	(segment
		(start 335.388204 -391.26287)
		(end 335.271872 -391.310876)
		(width 0.1651)
		(layer "In7.Cu")
		(net "P5E_PEX2_STN5_TX_C_DP<84>")
	)
	(segment
		(start 320.566034 -358.88676)
		(end 320.566034 -347.764354)
		(width 0.1651)
		(layer "In7.Cu")
		(net "P5E_PEX2_STN5_TX_C_DP<84>")
	)
	(segment
		(start 338.356702 -393.033758)
		(end 338.332318 -392.910568)
		(width 0.1651)
		(layer "In7.Cu")
		(net "P5E_PEX2_STN5_TX_C_DP<84>")
	)
	(segment
		(start 328.251566 -387.35)
		(end 327.186036 -384.792982)
		(width 0.1651)
		(layer "In7.Cu")
		(net "P5E_PEX2_STN5_TX_C_DP<84>")
	)
	(segment
		(start 337.797394 -392.65987)
		(end 337.385406 -392.38428)
		(width 0.1651)
		(layer "In7.Cu")
		(net "P5E_PEX2_STN5_TX_C_DP<84>")
	)
	(segment
		(start 340.621366 -394.440918)
		(end 339.86343 -393.934188)
		(width 0.1651)
		(layer "In7.Cu")
		(net "P5E_PEX2_STN5_TX_C_DP<84>")
	)
	(segment
		(start 338.332318 -392.910568)
		(end 337.920584 -392.635486)
		(width 0.1651)
		(layer "In7.Cu")
		(net "P5E_PEX2_STN5_TX_C_DP<84>")
	)
	(segment
		(start 322.120514 -346.209874)
		(end 322.120514 -345.755976)
		(width 0.1651)
		(layer "In7.Cu")
		(net "P5E_PEX2_STN5_TX_C_DP<84>")
	)
	(segment
		(start 322.120514 -345.755976)
		(end 321.829684 -345.465146)
		(width 0.1651)
		(layer "In7.Cu")
		(net "P5E_PEX2_STN5_TX_C_DP<84>")
	)
	(segment
		(start 337.385406 -392.38428)
		(end 337.361022 -392.26109)
		(width 0.1651)
		(layer "In7.Cu")
		(net "P5E_PEX2_STN5_TX_C_DP<84>")
	)
	(segment
		(start 341.134192 -404.512272)
		(end 341.134192 -395.17574)
		(width 0.1651)
		(layer "In7.Cu")
		(net "P5E_PEX2_STN5_TX_C_DP<84>")
	)
	(segment
		(start 334.814418 -391.120376)
		(end 334.766412 -391.004044)
		(width 0.1651)
		(layer "In7.Cu")
		(net "P5E_PEX2_STN5_TX_C_DP<84>")
	)
	(segment
		(start 339.303614 -393.560046)
		(end 338.89188 -393.284964)
		(width 0.1651)
		(layer "In7.Cu")
		(net "P5E_PEX2_STN5_TX_C_DP<84>")
	)
	(segment
		(start 338.76869 -393.309348)
		(end 338.356702 -393.033758)
		(width 0.1651)
		(layer "In7.Cu")
		(net "P5E_PEX2_STN5_TX_C_DP<84>")
	)
	(segment
		(start 335.271872 -391.310876)
		(end 334.814418 -391.120376)
		(width 0.1651)
		(layer "In7.Cu")
		(net "P5E_PEX2_STN5_TX_C_DP<84>")
	)
	(segment
		(start 334.766412 -391.004044)
		(end 329.86472 -388.965694)
		(width 0.1651)
		(layer "In7.Cu")
		(net "P5E_PEX2_STN5_TX_C_DP<84>")
	)
	(segment
		(start 338.89188 -393.284964)
		(end 338.76869 -393.309348)
		(width 0.1651)
		(layer "In7.Cu")
		(net "P5E_PEX2_STN5_TX_C_DP<84>")
	)
	(segment
		(start 340.41715 -404.799038)
		(end 340.847426 -404.799038)
		(width 0.1651)
		(layer "In7.Cu")
		(net "P5E_PEX2_STN5_TX_C_DP<84>")
	)
	(segment
		(start 337.920584 -392.635486)
		(end 337.797394 -392.65987)
		(width 0.1651)
		(layer "In7.Cu")
		(net "P5E_PEX2_STN5_TX_C_DP<84>")
	)
	(segment
		(start 417.50234 -28.8163)
		(end 416.238182 -28.8163)
		(width 0.13462)
		(layer "F.Cu")
		(net "P5E_PEX3_STN2_TX_C_DP<36>")
	)
	(segment
		(start 416.064446 -28.990036)
		(end 415.564828 -28.990036)
		(width 0.13462)
		(layer "F.Cu")
		(net "P5E_PEX3_STN2_TX_C_DP<36>")
	)
	(segment
		(start 417.825682 -29.139642)
		(end 417.50234 -28.8163)
		(width 0.13462)
		(layer "F.Cu")
		(net "P5E_PEX3_STN2_TX_C_DP<36>")
	)
	(segment
		(start 416.238182 -28.8163)
		(end 416.064446 -28.990036)
		(width 0.13462)
		(layer "F.Cu")
		(net "P5E_PEX3_STN2_TX_C_DP<36>")
	)
	(segment
		(start 428.244 -344.53957)
		(end 428.244 -345.169998)
		(width 0.13462)
		(layer "F.Cu")
		(net "P5E_PEX3_STN7_TX_C_DP<120>")
	)
	(segment
		(start 427.923452 -344.219022)
		(end 428.244 -344.53957)
		(width 0.13462)
		(layer "F.Cu")
		(net "P5E_PEX3_STN7_TX_C_DP<120>")
	)
	(segment
		(start 428.244 -345.169998)
		(end 427.948852 -345.465146)
		(width 0.13462)
		(layer "F.Cu")
		(net "P5E_PEX3_STN7_TX_C_DP<120>")
	)
	(segment
		(start 423.43324 -363.80166)
		(end 423.164 -364.217712)
		(width 0.1651)
		(layer "In11.Cu")
		(net "P5E_PEX3_STN7_TX_C_DP<120>")
	)
	(segment
		(start 421.894508 -366.180116)
		(end 421.920924 -366.303052)
		(width 0.1651)
		(layer "In11.Cu")
		(net "P5E_PEX3_STN7_TX_C_DP<120>")
	)
	(segment
		(start 423.164 -364.217712)
		(end 423.190162 -364.340648)
		(width 0.1651)
		(layer "In11.Cu")
		(net "P5E_PEX3_STN7_TX_C_DP<120>")
	)
	(segment
		(start 421.651938 -366.71885)
		(end 421.529002 -366.745266)
		(width 0.1651)
		(layer "In11.Cu")
		(net "P5E_PEX3_STN7_TX_C_DP<120>")
	)
	(segment
		(start 423.556176 -363.775244)
		(end 423.43324 -363.80166)
		(width 0.1651)
		(layer "In11.Cu")
		(net "P5E_PEX3_STN7_TX_C_DP<120>")
	)
	(segment
		(start 420.333932 -369.913154)
		(end 420.333932 -374.612408)
		(width 0.1651)
		(layer "In11.Cu")
		(net "P5E_PEX3_STN7_TX_C_DP<120>")
	)
	(segment
		(start 428.239682 -346.209874)
		(end 426.685202 -347.764354)
		(width 0.1651)
		(layer "In11.Cu")
		(net "P5E_PEX3_STN7_TX_C_DP<120>")
	)
	(segment
		(start 423.824908 -363.359446)
		(end 423.556176 -363.775244)
		(width 0.1651)
		(layer "In11.Cu")
		(net "P5E_PEX3_STN7_TX_C_DP<120>")
	)
	(segment
		(start 426.200062 -359.68686)
		(end 424.190668 -362.794042)
		(width 0.1651)
		(layer "In11.Cu")
		(net "P5E_PEX3_STN7_TX_C_DP<120>")
	)
	(segment
		(start 423.798746 -363.23651)
		(end 423.824908 -363.359446)
		(width 0.1651)
		(layer "In11.Cu")
		(net "P5E_PEX3_STN7_TX_C_DP<120>")
	)
	(segment
		(start 422.163748 -365.764064)
		(end 421.894508 -366.180116)
		(width 0.1651)
		(layer "In11.Cu")
		(net "P5E_PEX3_STN7_TX_C_DP<120>")
	)
	(segment
		(start 427.948852 -345.465146)
		(end 428.239682 -345.755976)
		(width 0.1651)
		(layer "In11.Cu")
		(net "P5E_PEX3_STN7_TX_C_DP<120>")
	)
	(segment
		(start 420.961566 -367.786412)
		(end 420.333932 -369.913154)
		(width 0.1651)
		(layer "In11.Cu")
		(net "P5E_PEX3_STN7_TX_C_DP<120>")
	)
	(segment
		(start 422.92143 -364.756446)
		(end 422.798494 -364.782862)
		(width 0.1651)
		(layer "In11.Cu")
		(net "P5E_PEX3_STN7_TX_C_DP<120>")
	)
	(segment
		(start 428.239682 -345.755976)
		(end 428.239682 -346.209874)
		(width 0.1651)
		(layer "In11.Cu")
		(net "P5E_PEX3_STN7_TX_C_DP<120>")
	)
	(segment
		(start 423.190162 -364.340648)
		(end 422.92143 -364.756446)
		(width 0.1651)
		(layer "In11.Cu")
		(net "P5E_PEX3_STN7_TX_C_DP<120>")
	)
	(segment
		(start 422.286684 -365.737648)
		(end 422.163748 -365.764064)
		(width 0.1651)
		(layer "In11.Cu")
		(net "P5E_PEX3_STN7_TX_C_DP<120>")
	)
	(segment
		(start 424.190668 -362.794042)
		(end 424.067732 -362.820458)
		(width 0.1651)
		(layer "In11.Cu")
		(net "P5E_PEX3_STN7_TX_C_DP<120>")
	)
	(segment
		(start 421.920924 -366.303052)
		(end 421.651938 -366.71885)
		(width 0.1651)
		(layer "In11.Cu")
		(net "P5E_PEX3_STN7_TX_C_DP<120>")
	)
	(segment
		(start 419.48989 -374.772174)
		(end 419.48989 -374.390158)
		(width 0.1651)
		(layer "In11.Cu")
		(net "P5E_PEX3_STN7_TX_C_DP<120>")
	)
	(segment
		(start 424.067732 -362.820458)
		(end 423.798746 -363.23651)
		(width 0.1651)
		(layer "In11.Cu")
		(net "P5E_PEX3_STN7_TX_C_DP<120>")
	)
	(segment
		(start 422.798494 -364.782862)
		(end 422.529254 -365.198914)
		(width 0.1651)
		(layer "In11.Cu")
		(net "P5E_PEX3_STN7_TX_C_DP<120>")
	)
	(segment
		(start 426.685202 -358.04348)
		(end 426.200062 -359.68686)
		(width 0.1651)
		(layer "In11.Cu")
		(net "P5E_PEX3_STN7_TX_C_DP<120>")
	)
	(segment
		(start 419.61689 -374.899174)
		(end 419.48989 -374.772174)
		(width 0.1651)
		(layer "In11.Cu")
		(net "P5E_PEX3_STN7_TX_C_DP<120>")
	)
	(segment
		(start 426.685202 -347.764354)
		(end 426.685202 -358.04348)
		(width 0.1651)
		(layer "In11.Cu")
		(net "P5E_PEX3_STN7_TX_C_DP<120>")
	)
	(segment
		(start 421.529002 -366.745266)
		(end 421.259762 -367.161318)
		(width 0.1651)
		(layer "In11.Cu")
		(net "P5E_PEX3_STN7_TX_C_DP<120>")
	)
	(segment
		(start 420.333932 -374.612408)
		(end 420.047166 -374.899174)
		(width 0.1651)
		(layer "In11.Cu")
		(net "P5E_PEX3_STN7_TX_C_DP<120>")
	)
	(segment
		(start 422.529254 -365.198914)
		(end 422.555416 -365.32185)
		(width 0.1651)
		(layer "In11.Cu")
		(net "P5E_PEX3_STN7_TX_C_DP<120>")
	)
	(segment
		(start 422.555416 -365.32185)
		(end 422.286684 -365.737648)
		(width 0.1651)
		(layer "In11.Cu")
		(net "P5E_PEX3_STN7_TX_C_DP<120>")
	)
	(segment
		(start 421.286178 -367.284254)
		(end 420.961566 -367.786412)
		(width 0.1651)
		(layer "In11.Cu")
		(net "P5E_PEX3_STN7_TX_C_DP<120>")
	)
	(segment
		(start 420.047166 -374.899174)
		(end 419.61689 -374.899174)
		(width 0.1651)
		(layer "In11.Cu")
		(net "P5E_PEX3_STN7_TX_C_DP<120>")
	)
	(segment
		(start 421.259762 -367.161318)
		(end 421.286178 -367.284254)
		(width 0.1651)
		(layer "In11.Cu")
		(net "P5E_PEX3_STN7_TX_C_DP<120>")
	)
	(segment
		(start 155.107894 -163.061396)
		(end 155.107894 -162.044126)
		(width 0.13208)
		(layer "F.Cu")
		(net "PWRGD_NIC2_PWR_GOOD")
	)
	(segment
		(start 156.918406 -161.501074)
		(end 157.910276 -161.501074)
		(width 0.13208)
		(layer "F.Cu")
		(net "PWRGD_NIC2_PWR_GOOD")
	)
	(segment
		(start 155.107894 -162.044126)
		(end 156.370274 -162.044126)
		(width 0.13208)
		(layer "F.Cu")
		(net "PWRGD_NIC2_PWR_GOOD")
	)
	(segment
		(start 157.910276 -161.501074)
		(end 161.05124 -158.36011)
		(width 0.13208)
		(layer "F.Cu")
		(net "PWRGD_NIC2_PWR_GOOD")
	)
	(segment
		(start 156.372814 -162.046666)
		(end 156.918406 -161.501074)
		(width 0.13208)
		(layer "F.Cu")
		(net "PWRGD_NIC2_PWR_GOOD")
	)
	(segment
		(start 156.370274 -162.044126)
		(end 156.372814 -162.046666)
		(width 0.13208)
		(layer "F.Cu")
		(net "PWRGD_NIC2_PWR_GOOD")
	)
	(segment
		(start 161.05124 -158.36011)
		(end 162.14217 -158.36011)
		(width 0.13208)
		(layer "F.Cu")
		(net "PWRGD_NIC2_PWR_GOOD")
	)
	(via
		(at 156.372814 -162.046666)
		(size 0.762)
		(drill 0.381)
		(layers "F.Cu" "B.Cu")
		(net "PWRGD_NIC2_PWR_GOOD")
	)
	(segment
		(start 422.83507 -101.84003)
		(end 423.48404 -102.489)
		(width 0.13208)
		(layer "F.Cu")
		(net "NCSI_NIC7_RXD0")
	)
	(segment
		(start 421.557704 -101.84003)
		(end 422.83507 -101.84003)
		(width 0.13208)
		(layer "F.Cu")
		(net "NCSI_NIC7_RXD0")
	)
	(via
		(at 423.48404 -102.489)
		(size 0.508)
		(drill 0.254)
		(layers "F.Cu" "B.Cu")
		(net "NCSI_NIC7_RXD0")
	)
	(segment
		(start 424.099736 -103.104696)
		(end 423.48404 -102.489)
		(width 0.13208)
		(layer "B.Cu")
		(net "NCSI_NIC7_RXD0")
	)
	(segment
		(start 425.441872 -103.104696)
		(end 424.099736 -103.104696)
		(width 0.13208)
		(layer "B.Cu")
		(net "NCSI_NIC7_RXD0")
	)
	(segment
		(start 73.908666 -146.517868)
		(end 79.425038 -146.517868)
		(width 0.13462)
		(layer "F.Cu")
		(net "P5E_PEX0_STN0_TX_C_DN<10>")
	)
	(segment
		(start 79.425038 -146.517868)
		(end 79.752698 -146.190208)
		(width 0.13462)
		(layer "F.Cu")
		(net "P5E_PEX0_STN0_TX_C_DN<10>")
	)
	(segment
		(start 73.745852 -146.355054)
		(end 73.908666 -146.517868)
		(width 0.13462)
		(layer "F.Cu")
		(net "P5E_PEX0_STN0_TX_C_DN<10>")
	)
	(segment
		(start 73.257664 -146.355054)
		(end 73.745852 -146.355054)
		(width 0.13462)
		(layer "F.Cu")
		(net "P5E_PEX0_STN0_TX_C_DN<10>")
	)
	(segment
		(start 117.144038 -338.478876)
		(end 113.137442 -339.231478)
		(width 0.1651)
		(layer "In15.Cu")
		(net "P5E_PEX1_STN6_RX_DN<111>")
	)
	(segment
		(start 108.003594 -363.347254)
		(end 107.855512 -385.415282)
		(width 0.1651)
		(layer "In15.Cu")
		(net "P5E_PEX1_STN6_RX_DN<111>")
	)
	(segment
		(start 122.99315 -336.60207)
		(end 117.144038 -338.478876)
		(width 0.1651)
		(layer "In15.Cu")
		(net "P5E_PEX1_STN6_RX_DN<111>")
	)
	(segment
		(start 117.066822 -394.74394)
		(end 117.066822 -400.489674)
		(width 0.1651)
		(layer "In15.Cu")
		(net "P5E_PEX1_STN6_RX_DN<111>")
	)
	(segment
		(start 116.500656 -394.177774)
		(end 117.066822 -394.74394)
		(width 0.1651)
		(layer "In15.Cu")
		(net "P5E_PEX1_STN6_RX_DN<111>")
	)
	(segment
		(start 110.26394 -341.117174)
		(end 109.884464 -341.978742)
		(width 0.1651)
		(layer "In15.Cu")
		(net "P5E_PEX1_STN6_RX_DN<111>")
	)
	(segment
		(start 159.347154 -316.419992)
		(end 159.220154 -316.546992)
		(width 0.1143)
		(layer "In15.Cu")
		(net "P5E_PEX1_STN6_RX_DN<111>")
	)
	(segment
		(start 159.265874 -319.8368)
		(end 159.265874 -319.865248)
		(width 0.1143)
		(layer "In15.Cu")
		(net "P5E_PEX1_STN6_RX_DN<111>")
	)
	(segment
		(start 116.037106 -401.181062)
		(end 115.910106 -401.308062)
		(width 0.1651)
		(layer "In15.Cu")
		(net "P5E_PEX1_STN6_RX_DN<111>")
	)
	(segment
		(start 159.599884 -316.799722)
		(end 159.599884 -316.508892)
		(width 0.1143)
		(layer "In15.Cu")
		(net "P5E_PEX1_STN6_RX_DN<111>")
	)
	(segment
		(start 159.510984 -316.419992)
		(end 159.347154 -316.419992)
		(width 0.1143)
		(layer "In15.Cu")
		(net "P5E_PEX1_STN6_RX_DN<111>")
	)
	(segment
		(start 114.247422 -393.24407)
		(end 116.500656 -394.177774)
		(width 0.1651)
		(layer "In15.Cu")
		(net "P5E_PEX1_STN6_RX_DN<111>")
	)
	(segment
		(start 111.453168 -339.9282)
		(end 110.26394 -341.117174)
		(width 0.1651)
		(layer "In15.Cu")
		(net "P5E_PEX1_STN6_RX_DN<111>")
	)
	(segment
		(start 159.265874 -319.865248)
		(end 159.265874 -320.147442)
		(width 0.1651)
		(layer "In15.Cu")
		(net "P5E_PEX1_STN6_RX_DN<111>")
	)
	(segment
		(start 114.246914 -393.243816)
		(end 114.247422 -393.24407)
		(width 0.1651)
		(layer "In15.Cu")
		(net "P5E_PEX1_STN6_RX_DN<111>")
	)
	(segment
		(start 109.884464 -341.978742)
		(end 109.121956 -345.24061)
		(width 0.1651)
		(layer "In15.Cu")
		(net "P5E_PEX1_STN6_RX_DN<111>")
	)
	(segment
		(start 109.121956 -345.24061)
		(end 108.003594 -363.347254)
		(width 0.1651)
		(layer "In15.Cu")
		(net "P5E_PEX1_STN6_RX_DN<111>")
	)
	(segment
		(start 159.220154 -319.79108)
		(end 159.265874 -319.8368)
		(width 0.1143)
		(layer "In15.Cu")
		(net "P5E_PEX1_STN6_RX_DN<111>")
	)
	(segment
		(start 159.220154 -316.546992)
		(end 159.220154 -319.79108)
		(width 0.1143)
		(layer "In15.Cu")
		(net "P5E_PEX1_STN6_RX_DN<111>")
	)
	(segment
		(start 107.855512 -385.415282)
		(end 108.398056 -387.369558)
		(width 0.1651)
		(layer "In15.Cu")
		(net "P5E_PEX1_STN6_RX_DN<111>")
	)
	(segment
		(start 113.137442 -339.231478)
		(end 111.453168 -339.9282)
		(width 0.1651)
		(layer "In15.Cu")
		(net "P5E_PEX1_STN6_RX_DN<111>")
	)
	(segment
		(start 115.910106 -401.308062)
		(end 115.910106 -401.690078)
		(width 0.1651)
		(layer "In15.Cu")
		(net "P5E_PEX1_STN6_RX_DN<111>")
	)
	(segment
		(start 142.240508 -328.630026)
		(end 122.99315 -336.60207)
		(width 0.1651)
		(layer "In15.Cu")
		(net "P5E_PEX1_STN6_RX_DN<111>")
	)
	(segment
		(start 108.398056 -387.369558)
		(end 110.040674 -389.813292)
		(width 0.1651)
		(layer "In15.Cu")
		(net "P5E_PEX1_STN6_RX_DN<111>")
	)
	(segment
		(start 159.599884 -316.508892)
		(end 159.510984 -316.419992)
		(width 0.1143)
		(layer "In15.Cu")
		(net "P5E_PEX1_STN6_RX_DN<111>")
	)
	(segment
		(start 117.066822 -400.489674)
		(end 116.375434 -401.181062)
		(width 0.1651)
		(layer "In15.Cu")
		(net "P5E_PEX1_STN6_RX_DN<111>")
	)
	(segment
		(start 110.040674 -389.813292)
		(end 114.246914 -393.243816)
		(width 0.1651)
		(layer "In15.Cu")
		(net "P5E_PEX1_STN6_RX_DN<111>")
	)
	(segment
		(start 116.375434 -401.181062)
		(end 116.037106 -401.181062)
		(width 0.1651)
		(layer "In15.Cu")
		(net "P5E_PEX1_STN6_RX_DN<111>")
	)
	(segment
		(start 159.265874 -320.147442)
		(end 158.45282 -320.960496)
		(width 0.1651)
		(layer "In15.Cu")
		(net "P5E_PEX1_STN6_RX_DN<111>")
	)
	(segment
		(start 158.45282 -320.960496)
		(end 142.240508 -328.630026)
		(width 0.1651)
		(layer "In15.Cu")
		(net "P5E_PEX1_STN6_RX_DN<111>")
	)
	(segment
		(start 277.739602 -99.445064)
		(end 278.242268 -99.445064)
		(width 0.13462)
		(layer "F.Cu")
		(net "P5E_PEX2_STN1_TX_C_DP<16>")
	)
	(segment
		(start 271.747234 -99.288854)
		(end 272.05686 -99.59848)
		(width 0.13462)
		(layer "F.Cu")
		(net "P5E_PEX2_STN1_TX_C_DP<16>")
	)
	(segment
		(start 277.586186 -99.59848)
		(end 277.739602 -99.445064)
		(width 0.13462)
		(layer "F.Cu")
		(net "P5E_PEX2_STN1_TX_C_DP<16>")
	)
	(segment
		(start 272.05686 -99.59848)
		(end 277.586186 -99.59848)
		(width 0.13462)
		(layer "F.Cu")
		(net "P5E_PEX2_STN1_TX_C_DP<16>")
	)
	(segment
		(start 390.231376 -34.2265)
		(end 390.0678 -34.390076)
		(width 0.13462)
		(layer "F.Cu")
		(net "P5E_PEX3_STN2_TX_C_DP<43>")
	)
	(segment
		(start 394.467842 -34.546286)
		(end 394.148056 -34.2265)
		(width 0.13462)
		(layer "F.Cu")
		(net "P5E_PEX3_STN2_TX_C_DP<43>")
	)
	(segment
		(start 394.148056 -34.2265)
		(end 390.231376 -34.2265)
		(width 0.13462)
		(layer "F.Cu")
		(net "P5E_PEX3_STN2_TX_C_DP<43>")
	)
	(segment
		(start 390.0678 -34.390076)
		(end 389.56488 -34.390076)
		(width 0.13462)
		(layer "F.Cu")
		(net "P5E_PEX3_STN2_TX_C_DP<43>")
	)
	(segment
		(start 371.60962 -325.086218)
		(end 370.61902 -322.692522)
		(width 0.1651)
		(layer "In9.Cu")
		(net "P5E_PEX3_STN7_RX_DP<117>")
	)
	(segment
		(start 399.76552 -335.004156)
		(end 377.675394 -329.936094)
		(width 0.1651)
		(layer "In9.Cu")
		(net "P5E_PEX3_STN7_RX_DP<117>")
	)
	(segment
		(start 430.616868 -409.799028)
		(end 430.838864 -409.799028)
		(width 0.1651)
		(layer "In9.Cu")
		(net "P5E_PEX3_STN7_RX_DP<117>")
	)
	(segment
		(start 382.39192 -305.733958)
		(end 383.892552 -305.733958)
		(width 0.1651)
		(layer "In9.Cu")
		(net "P5E_PEX3_STN7_RX_DP<117>")
	)
	(segment
		(start 431.364898 -395.684248)
		(end 431.052224 -395.117066)
		(width 0.1651)
		(layer "In9.Cu")
		(net "P5E_PEX3_STN7_RX_DP<117>")
	)
	(segment
		(start 376.291094 -309.96001)
		(end 379.264164 -306.98694)
		(width 0.1651)
		(layer "In9.Cu")
		(net "P5E_PEX3_STN7_RX_DP<117>")
	)
	(segment
		(start 429.773842 -393.75969)
		(end 424.837098 -390.640824)
		(width 0.1651)
		(layer "In9.Cu")
		(net "P5E_PEX3_STN7_RX_DP<117>")
	)
	(segment
		(start 414.249362 -341.991442)
		(end 413.850836 -341.363046)
		(width 0.1651)
		(layer "In9.Cu")
		(net "P5E_PEX3_STN7_RX_DP<117>")
	)
	(segment
		(start 380.916434 -306.103528)
		(end 382.39192 -305.733958)
		(width 0.1651)
		(layer "In9.Cu")
		(net "P5E_PEX3_STN7_RX_DP<117>")
	)
	(segment
		(start 371.65661 -316.982856)
		(end 376.291094 -309.96001)
		(width 0.1651)
		(layer "In9.Cu")
		(net "P5E_PEX3_STN7_RX_DP<117>")
	)
	(segment
		(start 413.397446 -340.962996)
		(end 412.603442 -340.616032)
		(width 0.1651)
		(layer "In9.Cu")
		(net "P5E_PEX3_STN7_RX_DP<117>")
	)
	(segment
		(start 383.921 -305.733958)
		(end 383.96672 -305.779678)
		(width 0.1143)
		(layer "In9.Cu")
		(net "P5E_PEX3_STN7_RX_DP<117>")
	)
	(segment
		(start 413.850836 -341.363046)
		(end 413.397446 -340.962996)
		(width 0.1651)
		(layer "In9.Cu")
		(net "P5E_PEX3_STN7_RX_DP<117>")
	)
	(segment
		(start 385.724654 -306.023518)
		(end 385.724654 -306.25542)
		(width 0.1143)
		(layer "In9.Cu")
		(net "P5E_PEX3_STN7_RX_DP<117>")
	)
	(segment
		(start 383.892552 -305.733958)
		(end 383.921 -305.733958)
		(width 0.1143)
		(layer "In9.Cu")
		(net "P5E_PEX3_STN7_RX_DP<117>")
	)
	(segment
		(start 385.480814 -305.779678)
		(end 385.724654 -306.023518)
		(width 0.1143)
		(layer "In9.Cu")
		(net "P5E_PEX3_STN7_RX_DP<117>")
	)
	(segment
		(start 424.837098 -390.640824)
		(end 419.353238 -388.689342)
		(width 0.1651)
		(layer "In9.Cu")
		(net "P5E_PEX3_STN7_RX_DP<117>")
	)
	(segment
		(start 414.249362 -359.138474)
		(end 414.249362 -341.991442)
		(width 0.1651)
		(layer "In9.Cu")
		(net "P5E_PEX3_STN7_RX_DP<117>")
	)
	(segment
		(start 379.264164 -306.98694)
		(end 380.916434 -306.103528)
		(width 0.1651)
		(layer "In9.Cu")
		(net "P5E_PEX3_STN7_RX_DP<117>")
	)
	(segment
		(start 415.60115 -383.967228)
		(end 415.4805 -374.65127)
		(width 0.1651)
		(layer "In9.Cu")
		(net "P5E_PEX3_STN7_RX_DP<117>")
	)
	(segment
		(start 375.903744 -329.378564)
		(end 371.60962 -325.086218)
		(width 0.1651)
		(layer "In9.Cu")
		(net "P5E_PEX3_STN7_RX_DP<117>")
	)
	(segment
		(start 383.96672 -305.779678)
		(end 385.480814 -305.779678)
		(width 0.1143)
		(layer "In9.Cu")
		(net "P5E_PEX3_STN7_RX_DP<117>")
	)
	(segment
		(start 412.015686 -340.469728)
		(end 411.963108 -340.33587)
		(width 0.1651)
		(layer "In9.Cu")
		(net "P5E_PEX3_STN7_RX_DP<117>")
	)
	(segment
		(start 385.724654 -306.25542)
		(end 385.819142 -306.349908)
		(width 0.1143)
		(layer "In9.Cu")
		(net "P5E_PEX3_STN7_RX_DP<117>")
	)
	(segment
		(start 370.61902 -319.491106)
		(end 371.65661 -316.982856)
		(width 0.1651)
		(layer "In9.Cu")
		(net "P5E_PEX3_STN7_RX_DP<117>")
	)
	(segment
		(start 430.489868 -409.290012)
		(end 430.489868 -409.672028)
		(width 0.1651)
		(layer "In9.Cu")
		(net "P5E_PEX3_STN7_RX_DP<117>")
	)
	(segment
		(start 412.603442 -340.616032)
		(end 412.469584 -340.668356)
		(width 0.1651)
		(layer "In9.Cu")
		(net "P5E_PEX3_STN7_RX_DP<117>")
	)
	(segment
		(start 412.469584 -340.668356)
		(end 412.015686 -340.469728)
		(width 0.1651)
		(layer "In9.Cu")
		(net "P5E_PEX3_STN7_RX_DP<117>")
	)
	(segment
		(start 411.963108 -340.33587)
		(end 399.76552 -335.004156)
		(width 0.1651)
		(layer "In9.Cu")
		(net "P5E_PEX3_STN7_RX_DP<117>")
	)
	(segment
		(start 431.052224 -395.117066)
		(end 429.773842 -393.75969)
		(width 0.1651)
		(layer "In9.Cu")
		(net "P5E_PEX3_STN7_RX_DP<117>")
	)
	(segment
		(start 430.838864 -409.799028)
		(end 431.364898 -409.272994)
		(width 0.1651)
		(layer "In9.Cu")
		(net "P5E_PEX3_STN7_RX_DP<117>")
	)
	(segment
		(start 416.896296 -386.687314)
		(end 416.07613 -385.466336)
		(width 0.1651)
		(layer "In9.Cu")
		(net "P5E_PEX3_STN7_RX_DP<117>")
	)
	(segment
		(start 377.675394 -329.936094)
		(end 375.903744 -329.378564)
		(width 0.1651)
		(layer "In9.Cu")
		(net "P5E_PEX3_STN7_RX_DP<117>")
	)
	(segment
		(start 416.07613 -385.466336)
		(end 415.60115 -383.967228)
		(width 0.1651)
		(layer "In9.Cu")
		(net "P5E_PEX3_STN7_RX_DP<117>")
	)
	(segment
		(start 430.489868 -409.672028)
		(end 430.616868 -409.799028)
		(width 0.1651)
		(layer "In9.Cu")
		(net "P5E_PEX3_STN7_RX_DP<117>")
	)
	(segment
		(start 370.61902 -322.692522)
		(end 370.61902 -319.491106)
		(width 0.1651)
		(layer "In9.Cu")
		(net "P5E_PEX3_STN7_RX_DP<117>")
	)
	(segment
		(start 415.4805 -374.65127)
		(end 414.249362 -359.138474)
		(width 0.1651)
		(layer "In9.Cu")
		(net "P5E_PEX3_STN7_RX_DP<117>")
	)
	(segment
		(start 385.819142 -306.349908)
		(end 386.099812 -306.349908)
		(width 0.1143)
		(layer "In9.Cu")
		(net "P5E_PEX3_STN7_RX_DP<117>")
	)
	(segment
		(start 419.353238 -388.689342)
		(end 416.896296 -386.687314)
		(width 0.1651)
		(layer "In9.Cu")
		(net "P5E_PEX3_STN7_RX_DP<117>")
	)
	(segment
		(start 431.364898 -409.272994)
		(end 431.364898 -395.684248)
		(width 0.1651)
		(layer "In9.Cu")
		(net "P5E_PEX3_STN7_RX_DP<117>")
	)
	(segment
		(start 168.049448 -140.165074)
		(end 168.08704 -140.127482)
		(width 0.13208)
		(layer "F.Cu")
		(net "RST_NIC2_PERST1_R_N")
	)
	(segment
		(start 166.742364 -140.165074)
		(end 168.049448 -140.165074)
		(width 0.13208)
		(layer "F.Cu")
		(net "RST_NIC2_PERST1_R_N")
	)
	(segment
		(start 168.164256 -165.17112)
		(end 168.164256 -165.902894)
		(width 0.13208)
		(layer "F.Cu")
		(net "RST_NIC2_PERST1_R_N")
	)
	(segment
		(start 167.191182 -164.198046)
		(end 168.164256 -165.17112)
		(width 0.13208)
		(layer "F.Cu")
		(net "RST_NIC2_PERST1_R_N")
	)
	(via
		(at 168.08704 -140.127482)
		(size 0.508)
		(drill 0.254)
		(layers "F.Cu" "B.Cu")
		(net "RST_NIC2_PERST1_R_N")
	)
	(via
		(at 167.191182 -164.198046)
		(size 0.508)
		(drill 0.254)
		(layers "F.Cu" "B.Cu")
		(net "RST_NIC2_PERST1_R_N")
	)
	(segment
		(start 168.08704 -140.127482)
		(end 169.37355 -141.413992)
		(width 0.15494)
		(layer "In7.Cu")
		(net "RST_NIC2_PERST1_R_N")
	)
	(segment
		(start 169.37355 -148.289264)
		(end 167.191182 -150.471632)
		(width 0.15494)
		(layer "In7.Cu")
		(net "RST_NIC2_PERST1_R_N")
	)
	(segment
		(start 169.37355 -141.413992)
		(end 169.37355 -148.289264)
		(width 0.15494)
		(layer "In7.Cu")
		(net "RST_NIC2_PERST1_R_N")
	)
	(segment
		(start 167.191182 -150.471632)
		(end 167.191182 -164.198046)
		(width 0.15494)
		(layer "In7.Cu")
		(net "RST_NIC2_PERST1_R_N")
	)
	(segment
		(start 419.042342 -114.290094)
		(end 419.077648 -114.3254)
		(width 0.13208)
		(layer "F.Cu")
		(net "RST_NIC7_PERST0_R_N")
	)
	(segment
		(start 429.939704 -87.749126)
		(end 429.939704 -88.39581)
		(width 0.13208)
		(layer "F.Cu")
		(net "RST_NIC7_PERST0_R_N")
	)
	(segment
		(start 420.764208 -114.3254)
		(end 421.073834 -114.635026)
		(width 0.13208)
		(layer "F.Cu")
		(net "RST_NIC7_PERST0_R_N")
	)
	(segment
		(start 421.073834 -114.635026)
		(end 421.557704 -114.635026)
		(width 0.13208)
		(layer "F.Cu")
		(net "RST_NIC7_PERST0_R_N")
	)
	(segment
		(start 419.077648 -114.3254)
		(end 420.764208 -114.3254)
		(width 0.13208)
		(layer "F.Cu")
		(net "RST_NIC7_PERST0_R_N")
	)
	(via
		(at 429.939704 -88.39581)
		(size 0.508)
		(drill 0.254)
		(layers "F.Cu" "B.Cu")
		(net "RST_NIC7_PERST0_R_N")
	)
	(via
		(at 419.042342 -114.290094)
		(size 0.508)
		(drill 0.254)
		(layers "F.Cu" "B.Cu")
		(net "RST_NIC7_PERST0_R_N")
	)
	(segment
		(start 422.994582 -96.264984)
		(end 422.994582 -94.1832)
		(width 0.15494)
		(layer "In11.Cu")
		(net "RST_NIC7_PERST0_R_N")
	)
	(segment
		(start 428.208186 -88.969596)
		(end 429.365918 -88.969596)
		(width 0.15494)
		(layer "In11.Cu")
		(net "RST_NIC7_PERST0_R_N")
	)
	(segment
		(start 422.003982 -112.14608)
		(end 422.003982 -105.429812)
		(width 0.15494)
		(layer "In11.Cu")
		(net "RST_NIC7_PERST0_R_N")
	)
	(segment
		(start 429.365918 -88.969596)
		(end 429.939704 -88.39581)
		(width 0.15494)
		(layer "In11.Cu")
		(net "RST_NIC7_PERST0_R_N")
	)
	(segment
		(start 421.193976 -98.06559)
		(end 422.994582 -96.264984)
		(width 0.15494)
		(layer "In11.Cu")
		(net "RST_NIC7_PERST0_R_N")
	)
	(segment
		(start 419.771576 -113.56086)
		(end 420.589202 -113.56086)
		(width 0.15494)
		(layer "In11.Cu")
		(net "RST_NIC7_PERST0_R_N")
	)
	(segment
		(start 422.994582 -94.1832)
		(end 428.208186 -88.969596)
		(width 0.15494)
		(layer "In11.Cu")
		(net "RST_NIC7_PERST0_R_N")
	)
	(segment
		(start 420.589202 -113.56086)
		(end 422.003982 -112.14608)
		(width 0.15494)
		(layer "In11.Cu")
		(net "RST_NIC7_PERST0_R_N")
	)
	(segment
		(start 419.042342 -114.290094)
		(end 419.771576 -113.56086)
		(width 0.15494)
		(layer "In11.Cu")
		(net "RST_NIC7_PERST0_R_N")
	)
	(segment
		(start 422.003982 -105.429812)
		(end 421.193976 -104.619806)
		(width 0.15494)
		(layer "In11.Cu")
		(net "RST_NIC7_PERST0_R_N")
	)
	(segment
		(start 421.193976 -104.619806)
		(end 421.193976 -98.06559)
		(width 0.15494)
		(layer "In11.Cu")
		(net "RST_NIC7_PERST0_R_N")
	)
	(segment
		(start 68.006722 -142.917926)
		(end 68.169536 -142.755112)
		(width 0.13462)
		(layer "F.Cu")
		(net "P5E_PEX0_STN0_RX_DN<8>")
	)
	(segment
		(start 67.05727 -142.623794)
		(end 67.351402 -142.917926)
		(width 0.13462)
		(layer "F.Cu")
		(net "P5E_PEX0_STN0_RX_DN<8>")
	)
	(segment
		(start 68.169536 -142.755112)
		(end 68.65747 -142.755112)
		(width 0.13462)
		(layer "F.Cu")
		(net "P5E_PEX0_STN0_RX_DN<8>")
	)
	(segment
		(start 67.351402 -142.917926)
		(end 68.006722 -142.917926)
		(width 0.13462)
		(layer "F.Cu")
		(net "P5E_PEX0_STN0_RX_DN<8>")
	)
	(segment
		(start 67.05727 -142.62354)
		(end 67.05727 -142.623794)
		(width 0.13462)
		(layer "F.Cu")
		(net "P5E_PEX0_STN0_RX_DN<8>")
	)
	(segment
		(start 76.663804 -154.698954)
		(end 75.275948 -152.831292)
		(width 0.1651)
		(layer "In5.Cu")
		(net "P5E_PEX0_STN0_RX_DN<8>")
	)
	(segment
		(start 82.32648 -273.279362)
		(end 82.3722 -273.233642)
		(width 0.1143)
		(layer "In5.Cu")
		(net "P5E_PEX0_STN0_RX_DN<8>")
	)
	(segment
		(start 82.3722 -273.233642)
		(end 82.3722 -273.205194)
		(width 0.1143)
		(layer "In5.Cu")
		(net "P5E_PEX0_STN0_RX_DN<8>")
	)
	(segment
		(start 82.070194 -273.758406)
		(end 82.32648 -273.50212)
		(width 0.1143)
		(layer "In5.Cu")
		(net "P5E_PEX0_STN0_RX_DN<8>")
	)
	(segment
		(start 82.32648 -273.50212)
		(end 82.32648 -273.279362)
		(width 0.1143)
		(layer "In5.Cu")
		(net "P5E_PEX0_STN0_RX_DN<8>")
	)
	(segment
		(start 82.184494 -274.999704)
		(end 82.070194 -274.885404)
		(width 0.1143)
		(layer "In5.Cu")
		(net "P5E_PEX0_STN0_RX_DN<8>")
	)
	(segment
		(start 69.676518 -144.304258)
		(end 67.596258 -142.91437)
		(width 0.1651)
		(layer "In5.Cu")
		(net "P5E_PEX0_STN0_RX_DN<8>")
	)
	(segment
		(start 82.070194 -274.885404)
		(end 82.070194 -273.758406)
		(width 0.1143)
		(layer "In5.Cu")
		(net "P5E_PEX0_STN0_RX_DN<8>")
	)
	(segment
		(start 82.3722 -273.205194)
		(end 82.3722 -269.305278)
		(width 0.1651)
		(layer "In5.Cu")
		(net "P5E_PEX0_STN0_RX_DN<8>")
	)
	(segment
		(start 73.266808 -149.895306)
		(end 69.676518 -144.304258)
		(width 0.1651)
		(layer "In5.Cu")
		(net "P5E_PEX0_STN0_RX_DN<8>")
	)
	(segment
		(start 67.3481 -142.91437)
		(end 67.05727 -142.62354)
		(width 0.1651)
		(layer "In5.Cu")
		(net "P5E_PEX0_STN0_RX_DN<8>")
	)
	(segment
		(start 81.885028 -265.20775)
		(end 78.272894 -160.610042)
		(width 0.1651)
		(layer "In5.Cu")
		(net "P5E_PEX0_STN0_RX_DN<8>")
	)
	(segment
		(start 67.596258 -142.91437)
		(end 67.3481 -142.91437)
		(width 0.1651)
		(layer "In5.Cu")
		(net "P5E_PEX0_STN0_RX_DN<8>")
	)
	(segment
		(start 82.3722 -269.305278)
		(end 81.885028 -265.20775)
		(width 0.1651)
		(layer "In5.Cu")
		(net "P5E_PEX0_STN0_RX_DN<8>")
	)
	(segment
		(start 75.275948 -152.831292)
		(end 73.813924 -151.432514)
		(width 0.1651)
		(layer "In5.Cu")
		(net "P5E_PEX0_STN0_RX_DN<8>")
	)
	(segment
		(start 78.272894 -160.610042)
		(end 78.174088 -159.983424)
		(width 0.1651)
		(layer "In5.Cu")
		(net "P5E_PEX0_STN0_RX_DN<8>")
	)
	(segment
		(start 73.813924 -151.432514)
		(end 73.266808 -149.895306)
		(width 0.1651)
		(layer "In5.Cu")
		(net "P5E_PEX0_STN0_RX_DN<8>")
	)
	(segment
		(start 78.174088 -159.983424)
		(end 76.663804 -154.698954)
		(width 0.1651)
		(layer "In5.Cu")
		(net "P5E_PEX0_STN0_RX_DN<8>")
	)
	(segment
		(start 82.449924 -274.999704)
		(end 82.184494 -274.999704)
		(width 0.1143)
		(layer "In5.Cu")
		(net "P5E_PEX0_STN0_RX_DN<8>")
	)
	(segment
		(start 284.442662 -112.776508)
		(end 284.157674 -112.49152)
		(width 0.13462)
		(layer "F.Cu")
		(net "P5E_PEX2_STN1_RX_DN<23>")
	)
	(segment
		(start 283.323538 -112.644936)
		(end 282.842462 -112.644936)
		(width 0.13462)
		(layer "F.Cu")
		(net "P5E_PEX2_STN1_RX_DN<23>")
	)
	(segment
		(start 283.476954 -112.49152)
		(end 283.323538 -112.644936)
		(width 0.13462)
		(layer "F.Cu")
		(net "P5E_PEX2_STN1_RX_DN<23>")
	)
	(segment
		(start 284.157674 -112.49152)
		(end 283.476954 -112.49152)
		(width 0.13462)
		(layer "F.Cu")
		(net "P5E_PEX2_STN1_RX_DN<23>")
	)
	(segment
		(start 276.077172 -119.935498)
		(end 276.132544 -120.087136)
		(width 0.1651)
		(layer "In5.Cu")
		(net "P5E_PEX2_STN1_RX_DN<23>")
	)
	(segment
		(start 284.442662 -112.776508)
		(end 284.151832 -112.485678)
		(width 0.1651)
		(layer "In5.Cu")
		(net "P5E_PEX2_STN1_RX_DN<23>")
	)
	(segment
		(start 275.51761 -121.77141)
		(end 275.410168 -122.25528)
		(width 0.1651)
		(layer "In5.Cu")
		(net "P5E_PEX2_STN1_RX_DN<23>")
	)
	(segment
		(start 274.881086 -124.635768)
		(end 274.744688 -124.722382)
		(width 0.1651)
		(layer "In5.Cu")
		(net "P5E_PEX2_STN1_RX_DN<23>")
	)
	(segment
		(start 267.562584 -151.225504)
		(end 268.023848 -158.30169)
		(width 0.1651)
		(layer "In5.Cu")
		(net "P5E_PEX2_STN1_RX_DN<23>")
	)
	(segment
		(start 268.677136 -145.148046)
		(end 267.562584 -151.225504)
		(width 0.1651)
		(layer "In5.Cu")
		(net "P5E_PEX2_STN1_RX_DN<23>")
	)
	(segment
		(start 270.445738 -141.115288)
		(end 268.677136 -145.148046)
		(width 0.1651)
		(layer "In5.Cu")
		(net "P5E_PEX2_STN1_RX_DN<23>")
	)
	(segment
		(start 274.988528 -124.151898)
		(end 274.881086 -124.635768)
		(width 0.1651)
		(layer "In5.Cu")
		(net "P5E_PEX2_STN1_RX_DN<23>")
	)
	(segment
		(start 298.165774 -268.570202)
		(end 298.165774 -271.570958)
		(width 0.1651)
		(layer "In5.Cu")
		(net "P5E_PEX2_STN1_RX_DN<23>")
	)
	(segment
		(start 273.922744 -128.4224)
		(end 272.4531 -137.487406)
		(width 0.1651)
		(layer "In5.Cu")
		(net "P5E_PEX2_STN1_RX_DN<23>")
	)
	(segment
		(start 275.1455 -123.445524)
		(end 275.009102 -123.532138)
		(width 0.1651)
		(layer "In5.Cu")
		(net "P5E_PEX2_STN1_RX_DN<23>")
	)
	(segment
		(start 274.616672 -125.826012)
		(end 274.480274 -125.912626)
		(width 0.1651)
		(layer "In5.Cu")
		(net "P5E_PEX2_STN1_RX_DN<23>")
	)
	(segment
		(start 283.063696 -112.67313)
		(end 283.000958 -112.822482)
		(width 0.1651)
		(layer "In5.Cu")
		(net "P5E_PEX2_STN1_RX_DN<23>")
	)
	(segment
		(start 298.38523 -275.379688)
		(end 298.49953 -275.265388)
		(width 0.1143)
		(layer "In5.Cu")
		(net "P5E_PEX2_STN1_RX_DN<23>")
	)
	(segment
		(start 274.480274 -125.912626)
		(end 273.922744 -128.4224)
		(width 0.1651)
		(layer "In5.Cu")
		(net "P5E_PEX2_STN1_RX_DN<23>")
	)
	(segment
		(start 298.49953 -275.265388)
		(end 298.49953 -274.999958)
		(width 0.1143)
		(layer "In5.Cu")
		(net "P5E_PEX2_STN1_RX_DN<23>")
	)
	(segment
		(start 281.264868 -113.408968)
		(end 279.374092 -114.182144)
		(width 0.1651)
		(layer "In5.Cu")
		(net "P5E_PEX2_STN1_RX_DN<23>")
	)
	(segment
		(start 275.562314 -121.04243)
		(end 275.430742 -121.635012)
		(width 0.1651)
		(layer "In5.Cu")
		(net "P5E_PEX2_STN1_RX_DN<23>")
	)
	(segment
		(start 276.132544 -120.087136)
		(end 275.923502 -120.536716)
		(width 0.1651)
		(layer "In5.Cu")
		(net "P5E_PEX2_STN1_RX_DN<23>")
	)
	(segment
		(start 281.413712 -113.471452)
		(end 281.264868 -113.408968)
		(width 0.1651)
		(layer "In5.Cu")
		(net "P5E_PEX2_STN1_RX_DN<23>")
	)
	(segment
		(start 277.39467 -117.103398)
		(end 276.591522 -118.829836)
		(width 0.1651)
		(layer "In5.Cu")
		(net "P5E_PEX2_STN1_RX_DN<23>")
	)
	(segment
		(start 283.521912 -112.485678)
		(end 283.063696 -112.67313)
		(width 0.1651)
		(layer "In5.Cu")
		(net "P5E_PEX2_STN1_RX_DN<23>")
	)
	(segment
		(start 274.6375 -125.205744)
		(end 274.724114 -125.342142)
		(width 0.1651)
		(layer "In5.Cu")
		(net "P5E_PEX2_STN1_RX_DN<23>")
	)
	(segment
		(start 282.39339 -112.94745)
		(end 281.935174 -113.134902)
		(width 0.1651)
		(layer "In5.Cu")
		(net "P5E_PEX2_STN1_RX_DN<23>")
	)
	(segment
		(start 278.052276 -116.158772)
		(end 277.39467 -117.103398)
		(width 0.1651)
		(layer "In5.Cu")
		(net "P5E_PEX2_STN1_RX_DN<23>")
	)
	(segment
		(start 269.005812 -164.031168)
		(end 298.165774 -268.570202)
		(width 0.1651)
		(layer "In5.Cu")
		(net "P5E_PEX2_STN1_RX_DN<23>")
	)
	(segment
		(start 282.542488 -113.009934)
		(end 282.39339 -112.94745)
		(width 0.1651)
		(layer "In5.Cu")
		(net "P5E_PEX2_STN1_RX_DN<23>")
	)
	(segment
		(start 276.591522 -118.829836)
		(end 276.646894 -118.981728)
		(width 0.1651)
		(layer "In5.Cu")
		(net "P5E_PEX2_STN1_RX_DN<23>")
	)
	(segment
		(start 275.410168 -122.25528)
		(end 275.273516 -122.341894)
		(width 0.1651)
		(layer "In5.Cu")
		(net "P5E_PEX2_STN1_RX_DN<23>")
	)
	(segment
		(start 275.430742 -121.635012)
		(end 275.51761 -121.77141)
		(width 0.1651)
		(layer "In5.Cu")
		(net "P5E_PEX2_STN1_RX_DN<23>")
	)
	(segment
		(start 298.223432 -275.379688)
		(end 298.38523 -275.379688)
		(width 0.1143)
		(layer "In5.Cu")
		(net "P5E_PEX2_STN1_RX_DN<23>")
	)
	(segment
		(start 268.023848 -158.30169)
		(end 269.005812 -164.031168)
		(width 0.1651)
		(layer "In5.Cu")
		(net "P5E_PEX2_STN1_RX_DN<23>")
	)
	(segment
		(start 275.77161 -120.592088)
		(end 275.562314 -121.04243)
		(width 0.1651)
		(layer "In5.Cu")
		(net "P5E_PEX2_STN1_RX_DN<23>")
	)
	(segment
		(start 276.28596 -119.486426)
		(end 276.077172 -119.935498)
		(width 0.1651)
		(layer "In5.Cu")
		(net "P5E_PEX2_STN1_RX_DN<23>")
	)
	(segment
		(start 275.273516 -122.341894)
		(end 275.166328 -122.825256)
		(width 0.1651)
		(layer "In5.Cu")
		(net "P5E_PEX2_STN1_RX_DN<23>")
	)
	(segment
		(start 274.724114 -125.342142)
		(end 274.616672 -125.826012)
		(width 0.1651)
		(layer "In5.Cu")
		(net "P5E_PEX2_STN1_RX_DN<23>")
	)
	(segment
		(start 274.901914 -124.0155)
		(end 274.988528 -124.151898)
		(width 0.1651)
		(layer "In5.Cu")
		(net "P5E_PEX2_STN1_RX_DN<23>")
	)
	(segment
		(start 283.000958 -112.822482)
		(end 282.542488 -113.009934)
		(width 0.1651)
		(layer "In5.Cu")
		(net "P5E_PEX2_STN1_RX_DN<23>")
	)
	(segment
		(start 298.165774 -271.570958)
		(end 298.165774 -271.599406)
		(width 0.1143)
		(layer "In5.Cu")
		(net "P5E_PEX2_STN1_RX_DN<23>")
	)
	(segment
		(start 275.009102 -123.532138)
		(end 274.901914 -124.0155)
		(width 0.1651)
		(layer "In5.Cu")
		(net "P5E_PEX2_STN1_RX_DN<23>")
	)
	(segment
		(start 276.437852 -119.431054)
		(end 276.28596 -119.486426)
		(width 0.1651)
		(layer "In5.Cu")
		(net "P5E_PEX2_STN1_RX_DN<23>")
	)
	(segment
		(start 276.646894 -118.981728)
		(end 276.437852 -119.431054)
		(width 0.1651)
		(layer "In5.Cu")
		(net "P5E_PEX2_STN1_RX_DN<23>")
	)
	(segment
		(start 278.650954 -114.872008)
		(end 278.052276 -116.158772)
		(width 0.1651)
		(layer "In5.Cu")
		(net "P5E_PEX2_STN1_RX_DN<23>")
	)
	(segment
		(start 275.923502 -120.536716)
		(end 275.77161 -120.592088)
		(width 0.1651)
		(layer "In5.Cu")
		(net "P5E_PEX2_STN1_RX_DN<23>")
	)
	(segment
		(start 275.252942 -122.961654)
		(end 275.1455 -123.445524)
		(width 0.1651)
		(layer "In5.Cu")
		(net "P5E_PEX2_STN1_RX_DN<23>")
	)
	(segment
		(start 281.935174 -113.134902)
		(end 281.872436 -113.284)
		(width 0.1651)
		(layer "In5.Cu")
		(net "P5E_PEX2_STN1_RX_DN<23>")
	)
	(segment
		(start 284.151832 -112.485678)
		(end 283.521912 -112.485678)
		(width 0.1651)
		(layer "In5.Cu")
		(net "P5E_PEX2_STN1_RX_DN<23>")
	)
	(segment
		(start 298.120054 -275.27631)
		(end 298.223432 -275.379688)
		(width 0.1143)
		(layer "In5.Cu")
		(net "P5E_PEX2_STN1_RX_DN<23>")
	)
	(segment
		(start 281.872436 -113.284)
		(end 281.413712 -113.471452)
		(width 0.1651)
		(layer "In5.Cu")
		(net "P5E_PEX2_STN1_RX_DN<23>")
	)
	(segment
		(start 274.744688 -124.722382)
		(end 274.6375 -125.205744)
		(width 0.1651)
		(layer "In5.Cu")
		(net "P5E_PEX2_STN1_RX_DN<23>")
	)
	(segment
		(start 272.4531 -137.487406)
		(end 270.445738 -141.115288)
		(width 0.1651)
		(layer "In5.Cu")
		(net "P5E_PEX2_STN1_RX_DN<23>")
	)
	(segment
		(start 298.120054 -271.645126)
		(end 298.120054 -275.27631)
		(width 0.1143)
		(layer "In5.Cu")
		(net "P5E_PEX2_STN1_RX_DN<23>")
	)
	(segment
		(start 275.166328 -122.825256)
		(end 275.252942 -122.961654)
		(width 0.1651)
		(layer "In5.Cu")
		(net "P5E_PEX2_STN1_RX_DN<23>")
	)
	(segment
		(start 298.165774 -271.599406)
		(end 298.120054 -271.645126)
		(width 0.1143)
		(layer "In5.Cu")
		(net "P5E_PEX2_STN1_RX_DN<23>")
	)
	(segment
		(start 279.374092 -114.182144)
		(end 278.650954 -114.872008)
		(width 0.1651)
		(layer "In5.Cu")
		(net "P5E_PEX2_STN1_RX_DN<23>")
	)
	(segment
		(start 316.180724 -345.170506)
		(end 316.475364 -345.465146)
		(width 0.13462)
		(layer "F.Cu")
		(net "P5E_PEX2_STN5_TX_C_DN<81>")
	)
	(segment
		(start 316.180724 -344.539062)
		(end 316.180724 -345.170506)
		(width 0.13462)
		(layer "F.Cu")
		(net "P5E_PEX2_STN5_TX_C_DN<81>")
	)
	(segment
		(start 316.500764 -344.219022)
		(end 316.180724 -344.539062)
		(width 0.13462)
		(layer "F.Cu")
		(net "P5E_PEX2_STN5_TX_C_DN<81>")
	)
	(segment
		(start 333.68996 -406.308052)
		(end 333.81696 -406.181052)
		(width 0.1651)
		(layer "In7.Cu")
		(net "P5E_PEX2_STN5_TX_C_DN<81>")
	)
	(segment
		(start 316.184534 -345.755976)
		(end 316.475364 -345.465146)
		(width 0.1651)
		(layer "In7.Cu")
		(net "P5E_PEX2_STN5_TX_C_DN<81>")
	)
	(segment
		(start 314.630054 -358.82834)
		(end 314.630054 -347.881194)
		(width 0.1651)
		(layer "In7.Cu")
		(net "P5E_PEX2_STN5_TX_C_DN<81>")
	)
	(segment
		(start 332.973934 -393.43203)
		(end 328.783442 -391.721848)
		(width 0.1651)
		(layer "In7.Cu")
		(net "P5E_PEX2_STN5_TX_C_DN<81>")
	)
	(segment
		(start 334.364076 -406.181052)
		(end 334.815942 -405.729186)
		(width 0.1651)
		(layer "In7.Cu")
		(net "P5E_PEX2_STN5_TX_C_DN<81>")
	)
	(segment
		(start 334.41767 -394.840714)
		(end 332.973934 -393.43203)
		(width 0.1651)
		(layer "In7.Cu")
		(net "P5E_PEX2_STN5_TX_C_DN<81>")
	)
	(segment
		(start 333.81696 -406.181052)
		(end 334.364076 -406.181052)
		(width 0.1651)
		(layer "In7.Cu")
		(net "P5E_PEX2_STN5_TX_C_DN<81>")
	)
	(segment
		(start 334.815942 -395.845792)
		(end 334.41767 -394.840714)
		(width 0.1651)
		(layer "In7.Cu")
		(net "P5E_PEX2_STN5_TX_C_DN<81>")
	)
	(segment
		(start 324.738238 -385.99491)
		(end 314.630054 -358.82834)
		(width 0.1651)
		(layer "In7.Cu")
		(net "P5E_PEX2_STN5_TX_C_DN<81>")
	)
	(segment
		(start 333.68996 -406.690068)
		(end 333.68996 -406.308052)
		(width 0.1651)
		(layer "In7.Cu")
		(net "P5E_PEX2_STN5_TX_C_DN<81>")
	)
	(segment
		(start 316.184534 -346.326714)
		(end 316.184534 -345.755976)
		(width 0.1651)
		(layer "In7.Cu")
		(net "P5E_PEX2_STN5_TX_C_DN<81>")
	)
	(segment
		(start 334.815942 -405.729186)
		(end 334.815942 -395.845792)
		(width 0.1651)
		(layer "In7.Cu")
		(net "P5E_PEX2_STN5_TX_C_DN<81>")
	)
	(segment
		(start 314.630054 -347.881194)
		(end 316.184534 -346.326714)
		(width 0.1651)
		(layer "In7.Cu")
		(net "P5E_PEX2_STN5_TX_C_DN<81>")
	)
	(segment
		(start 328.783442 -391.721848)
		(end 325.951342 -388.90575)
		(width 0.1651)
		(layer "In7.Cu")
		(net "P5E_PEX2_STN5_TX_C_DN<81>")
	)
	(segment
		(start 325.951342 -388.90575)
		(end 324.738238 -385.99491)
		(width 0.1651)
		(layer "In7.Cu")
		(net "P5E_PEX2_STN5_TX_C_DN<81>")
	)
	(segment
		(start 374.492012 -313.382914)
		(end 374.351296 -313.411616)
		(width 0.1651)
		(layer "In9.Cu")
		(net "P5E_PEX3_STN7_RX_DN<117>")
	)
	(segment
		(start 377.745498 -308.90464)
		(end 377.395486 -309.254652)
		(width 0.1651)
		(layer "In9.Cu")
		(net "P5E_PEX3_STN7_RX_DN<117>")
	)
	(segment
		(start 419.4937 -388.439914)
		(end 424.961304 -390.385554)
		(width 0.1651)
		(layer "In9.Cu")
		(net "P5E_PEX3_STN7_RX_DN<117>")
	)
	(segment
		(start 431.646838 -409.389834)
		(end 430.955704 -410.080968)
		(width 0.1651)
		(layer "In9.Cu")
		(net "P5E_PEX3_STN7_RX_DN<117>")
	)
	(segment
		(start 370.90096 -322.636388)
		(end 371.848634 -324.926452)
		(width 0.1651)
		(layer "In9.Cu")
		(net "P5E_PEX3_STN7_RX_DN<117>")
	)
	(segment
		(start 374.351296 -313.411616)
		(end 374.0785 -313.824874)
		(width 0.1651)
		(layer "In9.Cu")
		(net "P5E_PEX3_STN7_RX_DN<117>")
	)
	(segment
		(start 375.422668 -311.972706)
		(end 375.149618 -312.386472)
		(width 0.1651)
		(layer "In9.Cu")
		(net "P5E_PEX3_STN7_RX_DN<117>")
	)
	(segment
		(start 430.489868 -410.207968)
		(end 430.489868 -410.589984)
		(width 0.1651)
		(layer "In9.Cu")
		(net "P5E_PEX3_STN7_RX_DN<117>")
	)
	(segment
		(start 376.054366 -329.130406)
		(end 376.05462 -329.130406)
		(width 0.1651)
		(layer "In9.Cu")
		(net "P5E_PEX3_STN7_RX_DN<117>")
	)
	(segment
		(start 383.96672 -305.970178)
		(end 383.921 -306.015898)
		(width 0.1143)
		(layer "In9.Cu")
		(net "P5E_PEX3_STN7_RX_DN<117>")
	)
	(segment
		(start 375.149618 -312.386472)
		(end 375.008902 -312.415174)
		(width 0.1651)
		(layer "In9.Cu")
		(net "P5E_PEX3_STN7_RX_DN<117>")
	)
	(segment
		(start 375.008902 -312.415174)
		(end 374.736106 -312.828432)
		(width 0.1651)
		(layer "In9.Cu")
		(net "P5E_PEX3_STN7_RX_DN<117>")
	)
	(segment
		(start 383.892552 -306.015898)
		(end 382.426718 -306.015898)
		(width 0.1651)
		(layer "In9.Cu")
		(net "P5E_PEX3_STN7_RX_DN<117>")
	)
	(segment
		(start 370.90096 -319.54724)
		(end 370.90096 -322.636388)
		(width 0.1651)
		(layer "In9.Cu")
		(net "P5E_PEX3_STN7_RX_DN<117>")
	)
	(segment
		(start 378.239782 -308.55412)
		(end 377.889262 -308.90464)
		(width 0.1651)
		(layer "In9.Cu")
		(net "P5E_PEX3_STN7_RX_DN<117>")
	)
	(segment
		(start 429.95469 -393.540234)
		(end 431.282094 -394.94968)
		(width 0.1651)
		(layer "In9.Cu")
		(net "P5E_PEX3_STN7_RX_DN<117>")
	)
	(segment
		(start 399.854166 -334.73517)
		(end 413.551116 -340.722204)
		(width 0.1651)
		(layer "In9.Cu")
		(net "P5E_PEX3_STN7_RX_DN<117>")
	)
	(segment
		(start 375.393712 -311.83199)
		(end 375.422668 -311.972706)
		(width 0.1651)
		(layer "In9.Cu")
		(net "P5E_PEX3_STN7_RX_DN<117>")
	)
	(segment
		(start 376.080274 -310.976264)
		(end 375.807224 -311.389776)
		(width 0.1651)
		(layer "In9.Cu")
		(net "P5E_PEX3_STN7_RX_DN<117>")
	)
	(segment
		(start 374.0785 -313.824874)
		(end 374.107456 -313.96559)
		(width 0.1651)
		(layer "In9.Cu")
		(net "P5E_PEX3_STN7_RX_DN<117>")
	)
	(segment
		(start 379.084078 -307.56606)
		(end 379.084078 -307.709824)
		(width 0.1651)
		(layer "In9.Cu")
		(net "P5E_PEX3_STN7_RX_DN<117>")
	)
	(segment
		(start 373.834406 -314.379356)
		(end 373.69369 -314.408058)
		(width 0.1651)
		(layer "In9.Cu")
		(net "P5E_PEX3_STN7_RX_DN<117>")
	)
	(segment
		(start 414.067498 -341.178134)
		(end 414.531302 -341.9094)
		(width 0.1651)
		(layer "In9.Cu")
		(net "P5E_PEX3_STN7_RX_DN<117>")
	)
	(segment
		(start 374.107456 -313.96559)
		(end 373.834406 -314.379356)
		(width 0.1651)
		(layer "In9.Cu")
		(net "P5E_PEX3_STN7_RX_DN<117>")
	)
	(segment
		(start 378.589794 -308.060344)
		(end 378.239782 -308.410356)
		(width 0.1651)
		(layer "In9.Cu")
		(net "P5E_PEX3_STN7_RX_DN<117>")
	)
	(segment
		(start 378.733558 -308.060344)
		(end 378.589794 -308.060344)
		(width 0.1651)
		(layer "In9.Cu")
		(net "P5E_PEX3_STN7_RX_DN<117>")
	)
	(segment
		(start 376.05462 -329.130152)
		(end 377.749308 -329.663552)
		(width 0.1651)
		(layer "In9.Cu")
		(net "P5E_PEX3_STN7_RX_DN<117>")
	)
	(segment
		(start 431.282094 -394.94968)
		(end 431.646838 -395.611604)
		(width 0.1651)
		(layer "In9.Cu")
		(net "P5E_PEX3_STN7_RX_DN<117>")
	)
	(segment
		(start 413.551116 -340.722204)
		(end 414.067498 -341.178134)
		(width 0.1651)
		(layer "In9.Cu")
		(net "P5E_PEX3_STN7_RX_DN<117>")
	)
	(segment
		(start 415.76244 -374.638316)
		(end 415.882582 -383.921762)
		(width 0.1651)
		(layer "In9.Cu")
		(net "P5E_PEX3_STN7_RX_DN<117>")
	)
	(segment
		(start 377.889262 -308.90464)
		(end 377.745498 -308.90464)
		(width 0.1651)
		(layer "In9.Cu")
		(net "P5E_PEX3_STN7_RX_DN<117>")
	)
	(segment
		(start 371.9068 -317.115698)
		(end 370.90096 -319.54724)
		(width 0.1651)
		(layer "In9.Cu")
		(net "P5E_PEX3_STN7_RX_DN<117>")
	)
	(segment
		(start 377.044966 -309.748936)
		(end 376.901202 -309.748936)
		(width 0.1651)
		(layer "In9.Cu")
		(net "P5E_PEX3_STN7_RX_DN<117>")
	)
	(segment
		(start 385.149852 -306.349908)
		(end 385.438142 -306.349908)
		(width 0.1143)
		(layer "In9.Cu")
		(net "P5E_PEX3_STN7_RX_DN<117>")
	)
	(segment
		(start 414.531302 -341.9094)
		(end 414.531302 -359.127298)
		(width 0.1651)
		(layer "In9.Cu")
		(net "P5E_PEX3_STN7_RX_DN<117>")
	)
	(segment
		(start 377.749308 -329.663552)
		(end 399.854166 -334.73517)
		(width 0.1651)
		(layer "In9.Cu")
		(net "P5E_PEX3_STN7_RX_DN<117>")
	)
	(segment
		(start 375.666508 -311.418732)
		(end 375.393712 -311.83199)
		(width 0.1651)
		(layer "In9.Cu")
		(net "P5E_PEX3_STN7_RX_DN<117>")
	)
	(segment
		(start 382.426718 -306.015898)
		(end 381.018796 -306.368704)
		(width 0.1651)
		(layer "In9.Cu")
		(net "P5E_PEX3_STN7_RX_DN<117>")
	)
	(segment
		(start 378.239782 -308.410356)
		(end 378.239782 -308.55412)
		(width 0.1651)
		(layer "In9.Cu")
		(net "P5E_PEX3_STN7_RX_DN<117>")
	)
	(segment
		(start 385.40182 -305.970178)
		(end 383.96672 -305.970178)
		(width 0.1143)
		(layer "In9.Cu")
		(net "P5E_PEX3_STN7_RX_DN<117>")
	)
	(segment
		(start 430.616868 -410.080968)
		(end 430.489868 -410.207968)
		(width 0.1651)
		(layer "In9.Cu")
		(net "P5E_PEX3_STN7_RX_DN<117>")
	)
	(segment
		(start 430.955704 -410.080968)
		(end 430.616868 -410.080968)
		(width 0.1651)
		(layer "In9.Cu")
		(net "P5E_PEX3_STN7_RX_DN<117>")
	)
	(segment
		(start 376.051572 -310.835294)
		(end 376.080274 -310.976264)
		(width 0.1651)
		(layer "In9.Cu")
		(net "P5E_PEX3_STN7_RX_DN<117>")
	)
	(segment
		(start 379.084078 -307.709824)
		(end 378.733558 -308.060344)
		(width 0.1651)
		(layer "In9.Cu")
		(net "P5E_PEX3_STN7_RX_DN<117>")
	)
	(segment
		(start 376.510804 -310.139334)
		(end 376.051572 -310.835294)
		(width 0.1651)
		(layer "In9.Cu")
		(net "P5E_PEX3_STN7_RX_DN<117>")
	)
	(segment
		(start 381.018796 -306.368704)
		(end 379.43409 -307.216048)
		(width 0.1651)
		(layer "In9.Cu")
		(net "P5E_PEX3_STN7_RX_DN<117>")
	)
	(segment
		(start 385.534154 -306.102512)
		(end 385.40182 -305.970178)
		(width 0.1143)
		(layer "In9.Cu")
		(net "P5E_PEX3_STN7_RX_DN<117>")
	)
	(segment
		(start 373.69369 -314.408058)
		(end 371.9068 -317.115698)
		(width 0.1651)
		(layer "In9.Cu")
		(net "P5E_PEX3_STN7_RX_DN<117>")
	)
	(segment
		(start 376.901202 -309.748936)
		(end 376.510804 -310.139334)
		(width 0.1651)
		(layer "In9.Cu")
		(net "P5E_PEX3_STN7_RX_DN<117>")
	)
	(segment
		(start 415.882582 -383.921762)
		(end 416.332924 -385.342638)
		(width 0.1651)
		(layer "In9.Cu")
		(net "P5E_PEX3_STN7_RX_DN<117>")
	)
	(segment
		(start 417.107116 -386.495036)
		(end 419.4937 -388.439914)
		(width 0.1651)
		(layer "In9.Cu")
		(net "P5E_PEX3_STN7_RX_DN<117>")
	)
	(segment
		(start 416.332924 -385.342638)
		(end 417.107116 -386.495036)
		(width 0.1651)
		(layer "In9.Cu")
		(net "P5E_PEX3_STN7_RX_DN<117>")
	)
	(segment
		(start 383.921 -306.015898)
		(end 383.892552 -306.015898)
		(width 0.1143)
		(layer "In9.Cu")
		(net "P5E_PEX3_STN7_RX_DN<117>")
	)
	(segment
		(start 375.807224 -311.389776)
		(end 375.666508 -311.418732)
		(width 0.1651)
		(layer "In9.Cu")
		(net "P5E_PEX3_STN7_RX_DN<117>")
	)
	(segment
		(start 374.765062 -312.969148)
		(end 374.492012 -313.382914)
		(width 0.1651)
		(layer "In9.Cu")
		(net "P5E_PEX3_STN7_RX_DN<117>")
	)
	(segment
		(start 374.736106 -312.828432)
		(end 374.765062 -312.969148)
		(width 0.1651)
		(layer "In9.Cu")
		(net "P5E_PEX3_STN7_RX_DN<117>")
	)
	(segment
		(start 385.534154 -306.253896)
		(end 385.534154 -306.102512)
		(width 0.1143)
		(layer "In9.Cu")
		(net "P5E_PEX3_STN7_RX_DN<117>")
	)
	(segment
		(start 385.438142 -306.349908)
		(end 385.534154 -306.253896)
		(width 0.1143)
		(layer "In9.Cu")
		(net "P5E_PEX3_STN7_RX_DN<117>")
	)
	(segment
		(start 414.531302 -359.127298)
		(end 415.76244 -374.638316)
		(width 0.1651)
		(layer "In9.Cu")
		(net "P5E_PEX3_STN7_RX_DN<117>")
	)
	(segment
		(start 431.646838 -395.611604)
		(end 431.646838 -409.389834)
		(width 0.1651)
		(layer "In9.Cu")
		(net "P5E_PEX3_STN7_RX_DN<117>")
	)
	(segment
		(start 377.395486 -309.398416)
		(end 377.044966 -309.748936)
		(width 0.1651)
		(layer "In9.Cu")
		(net "P5E_PEX3_STN7_RX_DN<117>")
	)
	(segment
		(start 377.395486 -309.254652)
		(end 377.395486 -309.398416)
		(width 0.1651)
		(layer "In9.Cu")
		(net "P5E_PEX3_STN7_RX_DN<117>")
	)
	(segment
		(start 371.848634 -324.926452)
		(end 376.054366 -329.130406)
		(width 0.1651)
		(layer "In9.Cu")
		(net "P5E_PEX3_STN7_RX_DN<117>")
	)
	(segment
		(start 424.961304 -390.385554)
		(end 429.95469 -393.540234)
		(width 0.1651)
		(layer "In9.Cu")
		(net "P5E_PEX3_STN7_RX_DN<117>")
	)
	(segment
		(start 376.05462 -329.130406)
		(end 376.05462 -329.130152)
		(width 0.1651)
		(layer "In9.Cu")
		(net "P5E_PEX3_STN7_RX_DN<117>")
	)
	(segment
		(start 379.43409 -307.216048)
		(end 379.084078 -307.56606)
		(width 0.1651)
		(layer "In9.Cu")
		(net "P5E_PEX3_STN7_RX_DN<117>")
	)
	(segment
		(start 68.169536 -124.234956)
		(end 68.006722 -124.39777)
		(width 0.13462)
		(layer "F.Cu")
		(net "P5E_PEX0_STN0_RX_DN<3>")
	)
	(segment
		(start 65.498218 -124.39777)
		(end 65.49771 -124.398278)
		(width 0.13462)
		(layer "F.Cu")
		(net "P5E_PEX0_STN0_RX_DN<3>")
	)
	(segment
		(start 65.49771 -124.398278)
		(end 65.20307 -124.103638)
		(width 0.13462)
		(layer "F.Cu")
		(net "P5E_PEX0_STN0_RX_DN<3>")
	)
	(segment
		(start 68.006722 -124.39777)
		(end 65.498218 -124.39777)
		(width 0.13462)
		(layer "F.Cu")
		(net "P5E_PEX0_STN0_RX_DN<3>")
	)
	(segment
		(start 68.65747 -124.234956)
		(end 68.169536 -124.234956)
		(width 0.13462)
		(layer "F.Cu")
		(net "P5E_PEX0_STN0_RX_DN<3>")
	)
	(segment
		(start 82.070194 -285.173674)
		(end 82.173826 -285.070042)
		(width 0.1143)
		(layer "In5.Cu")
		(net "P5E_PEX0_STN0_RX_DN<3>")
	)
	(segment
		(start 88.193626 -240.289334)
		(end 86.47176 -232.197402)
		(width 0.1651)
		(layer "In5.Cu")
		(net "P5E_PEX0_STN0_RX_DN<3>")
	)
	(segment
		(start 67.281806 -124.394468)
		(end 65.4939 -124.394468)
		(width 0.1651)
		(layer "In5.Cu")
		(net "P5E_PEX0_STN0_RX_DN<3>")
	)
	(segment
		(start 82.622898 -140.10386)
		(end 82.285078 -139.15898)
		(width 0.1651)
		(layer "In5.Cu")
		(net "P5E_PEX0_STN0_RX_DN<3>")
	)
	(segment
		(start 73.694798 -127.04318)
		(end 72.816212 -126.186438)
		(width 0.1651)
		(layer "In5.Cu")
		(net "P5E_PEX0_STN0_RX_DN<3>")
	)
	(segment
		(start 72.816212 -126.186438)
		(end 69.567806 -124.836428)
		(width 0.1651)
		(layer "In5.Cu")
		(net "P5E_PEX0_STN0_RX_DN<3>")
	)
	(segment
		(start 82.070194 -285.335472)
		(end 82.070194 -285.173674)
		(width 0.1143)
		(layer "In5.Cu")
		(net "P5E_PEX0_STN0_RX_DN<3>")
	)
	(segment
		(start 83.9216 -285.115762)
		(end 83.950048 -285.115762)
		(width 0.1143)
		(layer "In5.Cu")
		(net "P5E_PEX0_STN0_RX_DN<3>")
	)
	(segment
		(start 82.184494 -285.449772)
		(end 82.070194 -285.335472)
		(width 0.1143)
		(layer "In5.Cu")
		(net "P5E_PEX0_STN0_RX_DN<3>")
	)
	(segment
		(start 83.87588 -285.070042)
		(end 83.9216 -285.115762)
		(width 0.1143)
		(layer "In5.Cu")
		(net "P5E_PEX0_STN0_RX_DN<3>")
	)
	(segment
		(start 96.737932 -269.543276)
		(end 88.193626 -240.289334)
		(width 0.1651)
		(layer "In5.Cu")
		(net "P5E_PEX0_STN0_RX_DN<3>")
	)
	(segment
		(start 80.047338 -137.67562)
		(end 73.694798 -127.04318)
		(width 0.1651)
		(layer "In5.Cu")
		(net "P5E_PEX0_STN0_RX_DN<3>")
	)
	(segment
		(start 83.950048 -285.115762)
		(end 85.276436 -285.115762)
		(width 0.1651)
		(layer "In5.Cu")
		(net "P5E_PEX0_STN0_RX_DN<3>")
	)
	(segment
		(start 82.173826 -285.070042)
		(end 83.87588 -285.070042)
		(width 0.1143)
		(layer "In5.Cu")
		(net "P5E_PEX0_STN0_RX_DN<3>")
	)
	(segment
		(start 86.663784 -150.027132)
		(end 86.263988 -147.200366)
		(width 0.1651)
		(layer "In5.Cu")
		(net "P5E_PEX0_STN0_RX_DN<3>")
	)
	(segment
		(start 69.567806 -124.836428)
		(end 67.281806 -124.394468)
		(width 0.1651)
		(layer "In5.Cu")
		(net "P5E_PEX0_STN0_RX_DN<3>")
	)
	(segment
		(start 86.263988 -147.200366)
		(end 86.264242 -147.200366)
		(width 0.1651)
		(layer "In5.Cu")
		(net "P5E_PEX0_STN0_RX_DN<3>")
	)
	(segment
		(start 85.276436 -285.115762)
		(end 86.472014 -284.422596)
		(width 0.1651)
		(layer "In5.Cu")
		(net "P5E_PEX0_STN0_RX_DN<3>")
	)
	(segment
		(start 82.449924 -285.449772)
		(end 82.184494 -285.449772)
		(width 0.1143)
		(layer "In5.Cu")
		(net "P5E_PEX0_STN0_RX_DN<3>")
	)
	(segment
		(start 86.47176 -232.197402)
		(end 87.126572 -168.402254)
		(width 0.1651)
		(layer "In5.Cu")
		(net "P5E_PEX0_STN0_RX_DN<3>")
	)
	(segment
		(start 94.478602 -276.661626)
		(end 96.624394 -272.856706)
		(width 0.1651)
		(layer "In5.Cu")
		(net "P5E_PEX0_STN0_RX_DN<3>")
	)
	(segment
		(start 82.285078 -139.15898)
		(end 80.047338 -137.67562)
		(width 0.1651)
		(layer "In5.Cu")
		(net "P5E_PEX0_STN0_RX_DN<3>")
	)
	(segment
		(start 65.4939 -124.394468)
		(end 65.20307 -124.103638)
		(width 0.1651)
		(layer "In5.Cu")
		(net "P5E_PEX0_STN0_RX_DN<3>")
	)
	(segment
		(start 86.472014 -284.422596)
		(end 94.478602 -276.661626)
		(width 0.1651)
		(layer "In5.Cu")
		(net "P5E_PEX0_STN0_RX_DN<3>")
	)
	(segment
		(start 87.126572 -168.402254)
		(end 86.663784 -150.027132)
		(width 0.1651)
		(layer "In5.Cu")
		(net "P5E_PEX0_STN0_RX_DN<3>")
	)
	(segment
		(start 86.264242 -147.200366)
		(end 85.856064 -144.316196)
		(width 0.1651)
		(layer "In5.Cu")
		(net "P5E_PEX0_STN0_RX_DN<3>")
	)
	(segment
		(start 96.624394 -272.856706)
		(end 96.737932 -269.543276)
		(width 0.1651)
		(layer "In5.Cu")
		(net "P5E_PEX0_STN0_RX_DN<3>")
	)
	(segment
		(start 85.856064 -144.316196)
		(end 82.622898 -140.10386)
		(width 0.1651)
		(layer "In5.Cu")
		(net "P5E_PEX0_STN0_RX_DN<3>")
	)
	(segment
		(start 283.319982 -107.244896)
		(end 282.842462 -107.244896)
		(width 0.13462)
		(layer "F.Cu")
		(net "P5E_PEX2_STN1_RX_DN<20>")
	)
	(segment
		(start 286.296862 -107.376214)
		(end 286.007048 -107.0864)
		(width 0.13462)
		(layer "F.Cu")
		(net "P5E_PEX2_STN1_RX_DN<20>")
	)
	(segment
		(start 283.478478 -107.0864)
		(end 283.319982 -107.244896)
		(width 0.13462)
		(layer "F.Cu")
		(net "P5E_PEX2_STN1_RX_DN<20>")
	)
	(segment
		(start 286.007048 -107.0864)
		(end 283.478478 -107.0864)
		(width 0.13462)
		(layer "F.Cu")
		(net "P5E_PEX2_STN1_RX_DN<20>")
	)
	(segment
		(start 295.373552 -273.479514)
		(end 295.53535 -273.479514)
		(width 0.1143)
		(layer "In5.Cu")
		(net "P5E_PEX2_STN1_RX_DN<20>")
	)
	(segment
		(start 279.55494 -109.37748)
		(end 279.117806 -109.610144)
		(width 0.1651)
		(layer "In5.Cu")
		(net "P5E_PEX2_STN1_RX_DN<20>")
	)
	(segment
		(start 281.223212 -108.618782)
		(end 280.785824 -108.8517)
		(width 0.1651)
		(layer "In5.Cu")
		(net "P5E_PEX2_STN1_RX_DN<20>")
	)
	(segment
		(start 264.579354 -150.512018)
		(end 265.098276 -158.717488)
		(width 0.1651)
		(layer "In5.Cu")
		(net "P5E_PEX2_STN1_RX_DN<20>")
	)
	(segment
		(start 280.14676 -109.191806)
		(end 279.709372 -109.424724)
		(width 0.1651)
		(layer "In5.Cu")
		(net "P5E_PEX2_STN1_RX_DN<20>")
	)
	(segment
		(start 275.964904 -111.757968)
		(end 275.80336 -111.755174)
		(width 0.1651)
		(layer "In5.Cu")
		(net "P5E_PEX2_STN1_RX_DN<20>")
	)
	(segment
		(start 277.99411 -110.337854)
		(end 277.556722 -110.570772)
		(width 0.1651)
		(layer "In5.Cu")
		(net "P5E_PEX2_STN1_RX_DN<20>")
	)
	(segment
		(start 295.315894 -271.554448)
		(end 295.270174 -271.600168)
		(width 0.1143)
		(layer "In5.Cu")
		(net "P5E_PEX2_STN1_RX_DN<20>")
	)
	(segment
		(start 279.709372 -109.424724)
		(end 279.55494 -109.37748)
		(width 0.1651)
		(layer "In5.Cu")
		(net "P5E_PEX2_STN1_RX_DN<20>")
	)
	(segment
		(start 280.631138 -108.804456)
		(end 280.194004 -109.03712)
		(width 0.1651)
		(layer "In5.Cu")
		(net "P5E_PEX2_STN1_RX_DN<20>")
	)
	(segment
		(start 283.859986 -107.085384)
		(end 283.422852 -107.318048)
		(width 0.1651)
		(layer "In5.Cu")
		(net "P5E_PEX2_STN1_RX_DN<20>")
	)
	(segment
		(start 276.680168 -110.90783)
		(end 276.32406 -111.252)
		(width 0.1651)
		(layer "In5.Cu")
		(net "P5E_PEX2_STN1_RX_DN<20>")
	)
	(segment
		(start 295.270174 -273.376136)
		(end 295.373552 -273.479514)
		(width 0.1143)
		(layer "In5.Cu")
		(net "P5E_PEX2_STN1_RX_DN<20>")
	)
	(segment
		(start 266.118594 -164.663882)
		(end 295.315894 -269.31239)
		(width 0.1651)
		(layer "In5.Cu")
		(net "P5E_PEX2_STN1_RX_DN<20>")
	)
	(segment
		(start 281.70759 -108.231432)
		(end 281.270456 -108.464096)
		(width 0.1651)
		(layer "In5.Cu")
		(net "P5E_PEX2_STN1_RX_DN<20>")
	)
	(segment
		(start 275.088096 -112.605312)
		(end 274.926552 -112.602518)
		(width 0.1651)
		(layer "In5.Cu")
		(net "P5E_PEX2_STN1_RX_DN<20>")
	)
	(segment
		(start 283.375608 -107.472734)
		(end 282.93822 -107.705652)
		(width 0.1651)
		(layer "In5.Cu")
		(net "P5E_PEX2_STN1_RX_DN<20>")
	)
	(segment
		(start 277.402036 -110.523528)
		(end 276.680168 -110.90783)
		(width 0.1651)
		(layer "In5.Cu")
		(net "P5E_PEX2_STN1_RX_DN<20>")
	)
	(segment
		(start 295.270174 -271.600168)
		(end 295.270174 -273.376136)
		(width 0.1143)
		(layer "In5.Cu")
		(net "P5E_PEX2_STN1_RX_DN<20>")
	)
	(segment
		(start 274.926552 -112.602518)
		(end 274.108164 -113.39322)
		(width 0.1651)
		(layer "In5.Cu")
		(net "P5E_PEX2_STN1_RX_DN<20>")
	)
	(segment
		(start 286.006032 -107.085384)
		(end 283.859986 -107.085384)
		(width 0.1651)
		(layer "In5.Cu")
		(net "P5E_PEX2_STN1_RX_DN<20>")
	)
	(segment
		(start 271.556226 -122.331226)
		(end 270.799814 -123.195842)
		(width 0.1651)
		(layer "In5.Cu")
		(net "P5E_PEX2_STN1_RX_DN<20>")
	)
	(segment
		(start 286.296862 -107.376214)
		(end 286.006032 -107.085384)
		(width 0.1651)
		(layer "In5.Cu")
		(net "P5E_PEX2_STN1_RX_DN<20>")
	)
	(segment
		(start 278.041354 -110.183168)
		(end 277.99411 -110.337854)
		(width 0.1651)
		(layer "In5.Cu")
		(net "P5E_PEX2_STN1_RX_DN<20>")
	)
	(segment
		(start 295.315894 -271.526)
		(end 295.315894 -271.554448)
		(width 0.1143)
		(layer "In5.Cu")
		(net "P5E_PEX2_STN1_RX_DN<20>")
	)
	(segment
		(start 281.270456 -108.464096)
		(end 281.223212 -108.618782)
		(width 0.1651)
		(layer "In5.Cu")
		(net "P5E_PEX2_STN1_RX_DN<20>")
	)
	(segment
		(start 279.070562 -109.764576)
		(end 278.633174 -109.997748)
		(width 0.1651)
		(layer "In5.Cu")
		(net "P5E_PEX2_STN1_RX_DN<20>")
	)
	(segment
		(start 295.315894 -269.31239)
		(end 295.315894 -271.526)
		(width 0.1651)
		(layer "In5.Cu")
		(net "P5E_PEX2_STN1_RX_DN<20>")
	)
	(segment
		(start 278.633174 -109.997748)
		(end 278.478488 -109.950504)
		(width 0.1651)
		(layer "In5.Cu")
		(net "P5E_PEX2_STN1_RX_DN<20>")
	)
	(segment
		(start 282.783788 -107.658408)
		(end 282.346654 -107.891072)
		(width 0.1651)
		(layer "In5.Cu")
		(net "P5E_PEX2_STN1_RX_DN<20>")
	)
	(segment
		(start 282.346654 -107.891072)
		(end 282.29941 -108.045758)
		(width 0.1651)
		(layer "In5.Cu")
		(net "P5E_PEX2_STN1_RX_DN<20>")
	)
	(segment
		(start 274.108164 -113.39322)
		(end 273.310604 -114.80038)
		(width 0.1651)
		(layer "In5.Cu")
		(net "P5E_PEX2_STN1_RX_DN<20>")
	)
	(segment
		(start 276.321266 -111.413544)
		(end 275.964904 -111.757968)
		(width 0.1651)
		(layer "In5.Cu")
		(net "P5E_PEX2_STN1_RX_DN<20>")
	)
	(segment
		(start 282.93822 -107.705652)
		(end 282.783788 -107.658408)
		(width 0.1651)
		(layer "In5.Cu")
		(net "P5E_PEX2_STN1_RX_DN<20>")
	)
	(segment
		(start 280.785824 -108.8517)
		(end 280.631138 -108.804456)
		(width 0.1651)
		(layer "In5.Cu")
		(net "P5E_PEX2_STN1_RX_DN<20>")
	)
	(segment
		(start 277.556722 -110.570772)
		(end 277.402036 -110.523528)
		(width 0.1651)
		(layer "In5.Cu")
		(net "P5E_PEX2_STN1_RX_DN<20>")
	)
	(segment
		(start 269.068804 -123.863354)
		(end 266.213844 -129.549398)
		(width 0.1651)
		(layer "In5.Cu")
		(net "P5E_PEX2_STN1_RX_DN<20>")
	)
	(segment
		(start 281.862022 -108.278676)
		(end 281.70759 -108.231432)
		(width 0.1651)
		(layer "In5.Cu")
		(net "P5E_PEX2_STN1_RX_DN<20>")
	)
	(segment
		(start 280.194004 -109.03712)
		(end 280.14676 -109.191806)
		(width 0.1651)
		(layer "In5.Cu")
		(net "P5E_PEX2_STN1_RX_DN<20>")
	)
	(segment
		(start 278.478488 -109.950504)
		(end 278.041354 -110.183168)
		(width 0.1651)
		(layer "In5.Cu")
		(net "P5E_PEX2_STN1_RX_DN<20>")
	)
	(segment
		(start 275.444458 -112.260888)
		(end 275.088096 -112.605312)
		(width 0.1651)
		(layer "In5.Cu")
		(net "P5E_PEX2_STN1_RX_DN<20>")
	)
	(segment
		(start 279.117806 -109.610144)
		(end 279.070562 -109.764576)
		(width 0.1651)
		(layer "In5.Cu")
		(net "P5E_PEX2_STN1_RX_DN<20>")
	)
	(segment
		(start 283.422852 -107.318048)
		(end 283.375608 -107.472734)
		(width 0.1651)
		(layer "In5.Cu")
		(net "P5E_PEX2_STN1_RX_DN<20>")
	)
	(segment
		(start 275.447252 -112.099344)
		(end 275.444458 -112.260888)
		(width 0.1651)
		(layer "In5.Cu")
		(net "P5E_PEX2_STN1_RX_DN<20>")
	)
	(segment
		(start 270.799814 -123.195842)
		(end 269.068804 -123.863354)
		(width 0.1651)
		(layer "In5.Cu")
		(net "P5E_PEX2_STN1_RX_DN<20>")
	)
	(segment
		(start 295.53535 -273.479514)
		(end 295.64965 -273.365214)
		(width 0.1143)
		(layer "In5.Cu")
		(net "P5E_PEX2_STN1_RX_DN<20>")
	)
	(segment
		(start 265.098276 -158.717488)
		(end 266.118594 -164.663882)
		(width 0.1651)
		(layer "In5.Cu")
		(net "P5E_PEX2_STN1_RX_DN<20>")
	)
	(segment
		(start 276.32406 -111.252)
		(end 276.321266 -111.413544)
		(width 0.1651)
		(layer "In5.Cu")
		(net "P5E_PEX2_STN1_RX_DN<20>")
	)
	(segment
		(start 275.80336 -111.755174)
		(end 275.447252 -112.099344)
		(width 0.1651)
		(layer "In5.Cu")
		(net "P5E_PEX2_STN1_RX_DN<20>")
	)
	(segment
		(start 282.29941 -108.045758)
		(end 281.862022 -108.278676)
		(width 0.1651)
		(layer "In5.Cu")
		(net "P5E_PEX2_STN1_RX_DN<20>")
	)
	(segment
		(start 273.310604 -114.80038)
		(end 271.556226 -122.331226)
		(width 0.1651)
		(layer "In5.Cu")
		(net "P5E_PEX2_STN1_RX_DN<20>")
	)
	(segment
		(start 266.213844 -129.549398)
		(end 264.579354 -150.512018)
		(width 0.1651)
		(layer "In5.Cu")
		(net "P5E_PEX2_STN1_RX_DN<20>")
	)
	(segment
		(start 295.64965 -273.365214)
		(end 295.64965 -273.099784)
		(width 0.1143)
		(layer "In5.Cu")
		(net "P5E_PEX2_STN1_RX_DN<20>")
	)
	(segment
		(start 442.264546 -357.836724)
		(end 442.260228 -341.61984)
		(width 0.1651)
		(layer "In9.Cu")
		(net "P5E_PEX3_STN7_RX_DP<126>")
	)
	(segment
		(start 433.038758 -382.699006)
		(end 433.564792 -382.172972)
		(width 0.1651)
		(layer "In9.Cu")
		(net "P5E_PEX3_STN7_RX_DP<126>")
	)
	(segment
		(start 420.567866 -333.55661)
		(end 407.326592 -327.31456)
		(width 0.1651)
		(layer "In9.Cu")
		(net "P5E_PEX3_STN7_RX_DP<126>")
	)
	(segment
		(start 441.880244 -358.633268)
		(end 442.264546 -357.836724)
		(width 0.1651)
		(layer "In9.Cu")
		(net "P5E_PEX3_STN7_RX_DP<126>")
	)
	(segment
		(start 437.478424 -363.932216)
		(end 437.790082 -363.546644)
		(width 0.1651)
		(layer "In9.Cu")
		(net "P5E_PEX3_STN7_RX_DP<126>")
	)
	(segment
		(start 389.28421 -319.865248)
		(end 389.32993 -319.819528)
		(width 0.1143)
		(layer "In9.Cu")
		(net "P5E_PEX3_STN7_RX_DP<126>")
	)
	(segment
		(start 432.689762 -382.572006)
		(end 432.816762 -382.699006)
		(width 0.1651)
		(layer "In9.Cu")
		(net "P5E_PEX3_STN7_RX_DP<126>")
	)
	(segment
		(start 390.266428 -321.914266)
		(end 389.52932 -321.385184)
		(width 0.1651)
		(layer "In9.Cu")
		(net "P5E_PEX3_STN7_RX_DP<126>")
	)
	(segment
		(start 389.32993 -319.819528)
		(end 389.32993 -316.506098)
		(width 0.1143)
		(layer "In9.Cu")
		(net "P5E_PEX3_STN7_RX_DP<126>")
	)
	(segment
		(start 436.442866 -365.358426)
		(end 436.75427 -364.973362)
		(width 0.1651)
		(layer "In9.Cu")
		(net "P5E_PEX3_STN7_RX_DP<126>")
	)
	(segment
		(start 436.75427 -364.973362)
		(end 436.740554 -364.844838)
		(width 0.1651)
		(layer "In9.Cu")
		(net "P5E_PEX3_STN7_RX_DP<126>")
	)
	(segment
		(start 389.90016 -315.850016)
		(end 389.899906 -315.849762)
		(width 0.1143)
		(layer "In9.Cu")
		(net "P5E_PEX3_STN7_RX_DP<126>")
	)
	(segment
		(start 433.564792 -369.546378)
		(end 433.987194 -368.395758)
		(width 0.1651)
		(layer "In9.Cu")
		(net "P5E_PEX3_STN7_RX_DP<126>")
	)
	(segment
		(start 442.15304 -341.475568)
		(end 439.77052 -340.748112)
		(width 0.1651)
		(layer "In9.Cu")
		(net "P5E_PEX3_STN7_RX_DP<126>")
	)
	(segment
		(start 435.264814 -366.670082)
		(end 435.576472 -366.284764)
		(width 0.1651)
		(layer "In9.Cu")
		(net "P5E_PEX3_STN7_RX_DP<126>")
	)
	(segment
		(start 389.52932 -321.385184)
		(end 389.28421 -320.79311)
		(width 0.1651)
		(layer "In9.Cu")
		(net "P5E_PEX3_STN7_RX_DP<126>")
	)
	(segment
		(start 437.918606 -363.533182)
		(end 441.880244 -358.633268)
		(width 0.1651)
		(layer "In9.Cu")
		(net "P5E_PEX3_STN7_RX_DP<126>")
	)
	(segment
		(start 436.740554 -364.844838)
		(end 437.052212 -364.459266)
		(width 0.1651)
		(layer "In9.Cu")
		(net "P5E_PEX3_STN7_RX_DP<126>")
	)
	(segment
		(start 389.28421 -320.79311)
		(end 389.28421 -319.893696)
		(width 0.1651)
		(layer "In9.Cu")
		(net "P5E_PEX3_STN7_RX_DP<126>")
	)
	(segment
		(start 433.564792 -382.172972)
		(end 433.564792 -369.546378)
		(width 0.1651)
		(layer "In9.Cu")
		(net "P5E_PEX3_STN7_RX_DP<126>")
	)
	(segment
		(start 437.180736 -364.445804)
		(end 437.49214 -364.06074)
		(width 0.1651)
		(layer "In9.Cu")
		(net "P5E_PEX3_STN7_RX_DP<126>")
	)
	(segment
		(start 389.32993 -316.506098)
		(end 389.606536 -316.229492)
		(width 0.1143)
		(layer "In9.Cu")
		(net "P5E_PEX3_STN7_RX_DP<126>")
	)
	(segment
		(start 435.576472 -366.284764)
		(end 435.704996 -366.271048)
		(width 0.1651)
		(layer "In9.Cu")
		(net "P5E_PEX3_STN7_RX_DP<126>")
	)
	(segment
		(start 433.987194 -368.395758)
		(end 435.278276 -366.79886)
		(width 0.1651)
		(layer "In9.Cu")
		(net "P5E_PEX3_STN7_RX_DP<126>")
	)
	(segment
		(start 435.278276 -366.79886)
		(end 435.264814 -366.670082)
		(width 0.1651)
		(layer "In9.Cu")
		(net "P5E_PEX3_STN7_RX_DP<126>")
	)
	(segment
		(start 436.314342 -365.371888)
		(end 436.442866 -365.358426)
		(width 0.1651)
		(layer "In9.Cu")
		(net "P5E_PEX3_STN7_RX_DP<126>")
	)
	(segment
		(start 432.816762 -382.699006)
		(end 433.038758 -382.699006)
		(width 0.1651)
		(layer "In9.Cu")
		(net "P5E_PEX3_STN7_RX_DP<126>")
	)
	(segment
		(start 432.689762 -382.18999)
		(end 432.689762 -382.572006)
		(width 0.1651)
		(layer "In9.Cu")
		(net "P5E_PEX3_STN7_RX_DP<126>")
	)
	(segment
		(start 407.326592 -327.31456)
		(end 390.266428 -321.914266)
		(width 0.1651)
		(layer "In9.Cu")
		(net "P5E_PEX3_STN7_RX_DP<126>")
	)
	(segment
		(start 439.77052 -340.748112)
		(end 420.567866 -333.55661)
		(width 0.1651)
		(layer "In9.Cu")
		(net "P5E_PEX3_STN7_RX_DP<126>")
	)
	(segment
		(start 435.704996 -366.271048)
		(end 436.0164 -365.885984)
		(width 0.1651)
		(layer "In9.Cu")
		(net "P5E_PEX3_STN7_RX_DP<126>")
	)
	(segment
		(start 389.81126 -316.229492)
		(end 389.90016 -316.140592)
		(width 0.1143)
		(layer "In9.Cu")
		(net "P5E_PEX3_STN7_RX_DP<126>")
	)
	(segment
		(start 389.28421 -319.893696)
		(end 389.28421 -319.865248)
		(width 0.1143)
		(layer "In9.Cu")
		(net "P5E_PEX3_STN7_RX_DP<126>")
	)
	(segment
		(start 436.002684 -365.75746)
		(end 436.314342 -365.371888)
		(width 0.1651)
		(layer "In9.Cu")
		(net "P5E_PEX3_STN7_RX_DP<126>")
	)
	(segment
		(start 389.606536 -316.229492)
		(end 389.81126 -316.229492)
		(width 0.1143)
		(layer "In9.Cu")
		(net "P5E_PEX3_STN7_RX_DP<126>")
	)
	(segment
		(start 437.790082 -363.546644)
		(end 437.918606 -363.533182)
		(width 0.1651)
		(layer "In9.Cu")
		(net "P5E_PEX3_STN7_RX_DP<126>")
	)
	(segment
		(start 442.260228 -341.61984)
		(end 442.15304 -341.475568)
		(width 0.1651)
		(layer "In9.Cu")
		(net "P5E_PEX3_STN7_RX_DP<126>")
	)
	(segment
		(start 389.90016 -316.140592)
		(end 389.90016 -315.850016)
		(width 0.1143)
		(layer "In9.Cu")
		(net "P5E_PEX3_STN7_RX_DP<126>")
	)
	(segment
		(start 437.052212 -364.459266)
		(end 437.180736 -364.445804)
		(width 0.1651)
		(layer "In9.Cu")
		(net "P5E_PEX3_STN7_RX_DP<126>")
	)
	(segment
		(start 437.49214 -364.06074)
		(end 437.478424 -363.932216)
		(width 0.1651)
		(layer "In9.Cu")
		(net "P5E_PEX3_STN7_RX_DP<126>")
	)
	(segment
		(start 436.0164 -365.885984)
		(end 436.002684 -365.75746)
		(width 0.1651)
		(layer "In9.Cu")
		(net "P5E_PEX3_STN7_RX_DP<126>")
	)
	(segment
		(start 409.785566 -98.734372)
		(end 409.997402 -98.522536)
		(width 0.13208)
		(layer "F.Cu")
		(net "NIC7_RBT_ARB_IN")
	)
	(segment
		(start 413.760412 -98.522536)
		(end 414.077912 -98.840036)
		(width 0.13208)
		(layer "F.Cu")
		(net "NIC7_RBT_ARB_IN")
	)
	(segment
		(start 414.077912 -98.840036)
		(end 416.95751 -98.840036)
		(width 0.13208)
		(layer "F.Cu")
		(net "NIC7_RBT_ARB_IN")
	)
	(segment
		(start 407.695146 -98.734372)
		(end 409.785566 -98.734372)
		(width 0.13208)
		(layer "F.Cu")
		(net "NIC7_RBT_ARB_IN")
	)
	(segment
		(start 410.819854 -98.522536)
		(end 413.760412 -98.522536)
		(width 0.13208)
		(layer "F.Cu")
		(net "NIC7_RBT_ARB_IN")
	)
	(segment
		(start 409.997402 -98.522536)
		(end 410.819854 -98.522536)
		(width 0.13208)
		(layer "F.Cu")
		(net "NIC7_RBT_ARB_IN")
	)
	(via
		(at 410.819854 -98.522536)
		(size 0.762)
		(drill 0.381)
		(layers "F.Cu" "B.Cu")
		(net "NIC7_RBT_ARB_IN")
	)
	(segment
		(start 68.169536 -123.03506)
		(end 68.65747 -123.03506)
		(width 0.13462)
		(layer "F.Cu")
		(net "P5E_PEX0_STN0_RX_DP<2>")
	)
	(segment
		(start 67.05727 -123.16714)
		(end 67.352164 -122.872246)
		(width 0.13462)
		(layer "F.Cu")
		(net "P5E_PEX0_STN0_RX_DP<2>")
	)
	(segment
		(start 68.006722 -122.872246)
		(end 68.169536 -123.03506)
		(width 0.13462)
		(layer "F.Cu")
		(net "P5E_PEX0_STN0_RX_DP<2>")
	)
	(segment
		(start 67.352164 -122.872246)
		(end 68.006722 -122.872246)
		(width 0.13462)
		(layer "F.Cu")
		(net "P5E_PEX0_STN0_RX_DP<2>")
	)
	(segment
		(start 86.77402 -285.067248)
		(end 85.38972 -285.783782)
		(width 0.1651)
		(layer "In5.Cu")
		(net "P5E_PEX0_STN0_RX_DP<2>")
	)
	(segment
		(start 77.134212 -130.987546)
		(end 77.409548 -131.399788)
		(width 0.1651)
		(layer "In5.Cu")
		(net "P5E_PEX0_STN0_RX_DP<2>")
	)
	(segment
		(start 69.56298 -123.68403)
		(end 70.020688 -123.874276)
		(width 0.1651)
		(layer "In5.Cu")
		(net "P5E_PEX0_STN0_RX_DP<2>")
	)
	(segment
		(start 70.62724 -124.002546)
		(end 70.688962 -124.152152)
		(width 0.1651)
		(layer "In5.Cu")
		(net "P5E_PEX0_STN0_RX_DP<2>")
	)
	(segment
		(start 69.044058 -123.344432)
		(end 69.501258 -123.534424)
		(width 0.1651)
		(layer "In5.Cu")
		(net "P5E_PEX0_STN0_RX_DP<2>")
	)
	(segment
		(start 76.214478 -129.40284)
		(end 76.214224 -129.40284)
		(width 0.1651)
		(layer "In5.Cu")
		(net "P5E_PEX0_STN0_RX_DP<2>")
	)
	(segment
		(start 67.918076 -122.87631)
		(end 68.375276 -123.066302)
		(width 0.1651)
		(layer "In5.Cu")
		(net "P5E_PEX0_STN0_RX_DP<2>")
	)
	(segment
		(start 72.528684 -124.79274)
		(end 74.384662 -126.661164)
		(width 0.1651)
		(layer "In5.Cu")
		(net "P5E_PEX0_STN0_RX_DP<2>")
	)
	(segment
		(start 97.28835 -273.073114)
		(end 95.013018 -277.083774)
		(width 0.1651)
		(layer "In5.Cu")
		(net "P5E_PEX0_STN0_RX_DP<2>")
	)
	(segment
		(start 71.296022 -124.280676)
		(end 72.528684 -124.79274)
		(width 0.1651)
		(layer "In5.Cu")
		(net "P5E_PEX0_STN0_RX_DP<2>")
	)
	(segment
		(start 74.384662 -126.661164)
		(end 75.812396 -128.800606)
		(width 0.1651)
		(layer "In5.Cu")
		(net "P5E_PEX0_STN0_RX_DP<2>")
	)
	(segment
		(start 76.489052 -129.814574)
		(end 76.457302 -129.973324)
		(width 0.1651)
		(layer "In5.Cu")
		(net "P5E_PEX0_STN0_RX_DP<2>")
	)
	(segment
		(start 79.42961 -134.220712)
		(end 83.714336 -138.49985)
		(width 0.1651)
		(layer "In5.Cu")
		(net "P5E_PEX0_STN0_RX_DP<2>")
	)
	(segment
		(start 76.055982 -129.371344)
		(end 76.214478 -129.40284)
		(width 0.1651)
		(layer "In5.Cu")
		(net "P5E_PEX0_STN0_RX_DP<2>")
	)
	(segment
		(start 79.86522 -286.399732)
		(end 79.59979 -286.399732)
		(width 0.1143)
		(layer "In5.Cu")
		(net "P5E_PEX0_STN0_RX_DP<2>")
	)
	(segment
		(start 68.894706 -123.406154)
		(end 69.044058 -123.344432)
		(width 0.1651)
		(layer "In5.Cu")
		(net "P5E_PEX0_STN0_RX_DP<2>")
	)
	(segment
		(start 79.97952 -286.073596)
		(end 79.97952 -286.285432)
		(width 0.1143)
		(layer "In5.Cu")
		(net "P5E_PEX0_STN0_RX_DP<2>")
	)
	(segment
		(start 95.013018 -277.083774)
		(end 86.77402 -285.067248)
		(width 0.1651)
		(layer "In5.Cu")
		(net "P5E_PEX0_STN0_RX_DP<2>")
	)
	(segment
		(start 70.17004 -123.812554)
		(end 70.62724 -124.002546)
		(width 0.1651)
		(layer "In5.Cu")
		(net "P5E_PEX0_STN0_RX_DP<2>")
	)
	(segment
		(start 77.568044 -131.431284)
		(end 79.42961 -134.220712)
		(width 0.1651)
		(layer "In5.Cu")
		(net "P5E_PEX0_STN0_RX_DP<2>")
	)
	(segment
		(start 76.891134 -130.417062)
		(end 77.165962 -130.828796)
		(width 0.1651)
		(layer "In5.Cu")
		(net "P5E_PEX0_STN0_RX_DP<2>")
	)
	(segment
		(start 79.97952 -286.285432)
		(end 79.86522 -286.399732)
		(width 0.1143)
		(layer "In5.Cu")
		(net "P5E_PEX0_STN0_RX_DP<2>")
	)
	(segment
		(start 75.812396 -128.800606)
		(end 75.780646 -128.959102)
		(width 0.1651)
		(layer "In5.Cu")
		(net "P5E_PEX0_STN0_RX_DP<2>")
	)
	(segment
		(start 68.436998 -123.215908)
		(end 68.894706 -123.406154)
		(width 0.1651)
		(layer "In5.Cu")
		(net "P5E_PEX0_STN0_RX_DP<2>")
	)
	(segment
		(start 77.409548 -131.399788)
		(end 77.568044 -131.431284)
		(width 0.1651)
		(layer "In5.Cu")
		(net "P5E_PEX0_STN0_RX_DP<2>")
	)
	(segment
		(start 80.223614 -285.829502)
		(end 79.97952 -286.073596)
		(width 0.1143)
		(layer "In5.Cu")
		(net "P5E_PEX0_STN0_RX_DP<2>")
	)
	(segment
		(start 70.688962 -124.152152)
		(end 71.14667 -124.342144)
		(width 0.1651)
		(layer "In5.Cu")
		(net "P5E_PEX0_STN0_RX_DP<2>")
	)
	(segment
		(start 76.732638 -130.385566)
		(end 76.891134 -130.417062)
		(width 0.1651)
		(layer "In5.Cu")
		(net "P5E_PEX0_STN0_RX_DP<2>")
	)
	(segment
		(start 83.924648 -285.783782)
		(end 83.8962 -285.783782)
		(width 0.1143)
		(layer "In5.Cu")
		(net "P5E_PEX0_STN0_RX_DP<2>")
	)
	(segment
		(start 77.165962 -130.828796)
		(end 77.134212 -130.987546)
		(width 0.1651)
		(layer "In5.Cu")
		(net "P5E_PEX0_STN0_RX_DP<2>")
	)
	(segment
		(start 85.38972 -285.783782)
		(end 83.924648 -285.783782)
		(width 0.1651)
		(layer "In5.Cu")
		(net "P5E_PEX0_STN0_RX_DP<2>")
	)
	(segment
		(start 68.375276 -123.066302)
		(end 68.436998 -123.215908)
		(width 0.1651)
		(layer "In5.Cu")
		(net "P5E_PEX0_STN0_RX_DP<2>")
	)
	(segment
		(start 97.451418 -269.508732)
		(end 97.28835 -273.073114)
		(width 0.1651)
		(layer "In5.Cu")
		(net "P5E_PEX0_STN0_RX_DP<2>")
	)
	(segment
		(start 71.14667 -124.342144)
		(end 71.296022 -124.280676)
		(width 0.1651)
		(layer "In5.Cu")
		(net "P5E_PEX0_STN0_RX_DP<2>")
	)
	(segment
		(start 83.8962 -285.783782)
		(end 83.85048 -285.829502)
		(width 0.1143)
		(layer "In5.Cu")
		(net "P5E_PEX0_STN0_RX_DP<2>")
	)
	(segment
		(start 88.810338 -239.951514)
		(end 97.451418 -269.508732)
		(width 0.1651)
		(layer "In5.Cu")
		(net "P5E_PEX0_STN0_RX_DP<2>")
	)
	(segment
		(start 76.457302 -129.973324)
		(end 76.732638 -130.385566)
		(width 0.1651)
		(layer "In5.Cu")
		(net "P5E_PEX0_STN0_RX_DP<2>")
	)
	(segment
		(start 70.020688 -123.874276)
		(end 70.17004 -123.812554)
		(width 0.1651)
		(layer "In5.Cu")
		(net "P5E_PEX0_STN0_RX_DP<2>")
	)
	(segment
		(start 87.15375 -232.167938)
		(end 88.810338 -239.951514)
		(width 0.1651)
		(layer "In5.Cu")
		(net "P5E_PEX0_STN0_RX_DP<2>")
	)
	(segment
		(start 67.3481 -122.87631)
		(end 67.918076 -122.87631)
		(width 0.1651)
		(layer "In5.Cu")
		(net "P5E_PEX0_STN0_RX_DP<2>")
	)
	(segment
		(start 83.714336 -138.49985)
		(end 86.463378 -143.64208)
		(width 0.1651)
		(layer "In5.Cu")
		(net "P5E_PEX0_STN0_RX_DP<2>")
	)
	(segment
		(start 69.501258 -123.534424)
		(end 69.56298 -123.68403)
		(width 0.1651)
		(layer "In5.Cu")
		(net "P5E_PEX0_STN0_RX_DP<2>")
	)
	(segment
		(start 83.85048 -285.829502)
		(end 80.223614 -285.829502)
		(width 0.1143)
		(layer "In5.Cu")
		(net "P5E_PEX0_STN0_RX_DP<2>")
	)
	(segment
		(start 75.780646 -128.959102)
		(end 76.055982 -129.371344)
		(width 0.1651)
		(layer "In5.Cu")
		(net "P5E_PEX0_STN0_RX_DP<2>")
	)
	(segment
		(start 87.860378 -168.457372)
		(end 87.15375 -232.167938)
		(width 0.1651)
		(layer "In5.Cu")
		(net "P5E_PEX0_STN0_RX_DP<2>")
	)
	(segment
		(start 86.463378 -143.64208)
		(end 87.365078 -149.98446)
		(width 0.1651)
		(layer "In5.Cu")
		(net "P5E_PEX0_STN0_RX_DP<2>")
	)
	(segment
		(start 87.365078 -149.98446)
		(end 87.860378 -168.457372)
		(width 0.1651)
		(layer "In5.Cu")
		(net "P5E_PEX0_STN0_RX_DP<2>")
	)
	(segment
		(start 76.214224 -129.40284)
		(end 76.489052 -129.814574)
		(width 0.1651)
		(layer "In5.Cu")
		(net "P5E_PEX0_STN0_RX_DP<2>")
	)
	(segment
		(start 67.05727 -123.16714)
		(end 67.3481 -122.87631)
		(width 0.1651)
		(layer "In5.Cu")
		(net "P5E_PEX0_STN0_RX_DP<2>")
	)
	(segment
		(start 167.230298 -136.565132)
		(end 167.393366 -136.402064)
		(width 0.13462)
		(layer "F.Cu")
		(net "P5E_PEX1_STN1_RX_DN<31>")
	)
	(segment
		(start 168.048178 -136.402064)
		(end 168.342564 -136.69645)
		(width 0.13462)
		(layer "F.Cu")
		(net "P5E_PEX1_STN1_RX_DN<31>")
	)
	(segment
		(start 166.742364 -136.565132)
		(end 167.230298 -136.565132)
		(width 0.13462)
		(layer "F.Cu")
		(net "P5E_PEX1_STN1_RX_DN<31>")
	)
	(segment
		(start 167.393366 -136.402064)
		(end 168.048178 -136.402064)
		(width 0.13462)
		(layer "F.Cu")
		(net "P5E_PEX1_STN1_RX_DN<31>")
	)
	(segment
		(start 189.598046 -266.542774)
		(end 189.663578 -267.043154)
		(width 0.1651)
		(layer "In5.Cu")
		(net "P5E_PEX1_STN1_RX_DN<31>")
	)
	(segment
		(start 166.005256 -144.37614)
		(end 165.65245 -144.723358)
		(width 0.1651)
		(layer "In5.Cu")
		(net "P5E_PEX1_STN1_RX_DN<31>")
	)
	(segment
		(start 166.803324 -142.425674)
		(end 166.615872 -142.88389)
		(width 0.1651)
		(layer "In5.Cu")
		(net "P5E_PEX1_STN1_RX_DN<31>")
	)
	(segment
		(start 162.865816 -147.088606)
		(end 162.630866 -147.32)
		(width 0.1651)
		(layer "In5.Cu")
		(net "P5E_PEX1_STN1_RX_DN<31>")
	)
	(segment
		(start 165.297866 -145.232628)
		(end 165.136068 -145.231358)
		(width 0.1651)
		(layer "In5.Cu")
		(net "P5E_PEX1_STN1_RX_DN<31>")
	)
	(segment
		(start 166.952676 -142.36319)
		(end 166.803324 -142.425674)
		(width 0.1651)
		(layer "In5.Cu")
		(net "P5E_PEX1_STN1_RX_DN<31>")
	)
	(segment
		(start 189.99962 -275.265388)
		(end 189.99962 -274.999958)
		(width 0.1143)
		(layer "In5.Cu")
		(net "P5E_PEX1_STN1_RX_DN<31>")
	)
	(segment
		(start 164.783262 -145.578576)
		(end 164.781738 -145.740374)
		(width 0.1651)
		(layer "In5.Cu")
		(net "P5E_PEX1_STN1_RX_DN<31>")
	)
	(segment
		(start 189.665864 -271.599406)
		(end 189.620144 -271.645126)
		(width 0.1143)
		(layer "In5.Cu")
		(net "P5E_PEX1_STN1_RX_DN<31>")
	)
	(segment
		(start 161.898838 -152.062942)
		(end 161.869374 -152.424892)
		(width 0.1651)
		(layer "In5.Cu")
		(net "P5E_PEX1_STN1_RX_DN<31>")
	)
	(segment
		(start 167.267128 -138.38555)
		(end 167.267128 -139.46505)
		(width 0.1651)
		(layer "In5.Cu")
		(net "P5E_PEX1_STN1_RX_DN<31>")
	)
	(segment
		(start 167.381428 -140.07465)
		(end 167.267128 -140.18895)
		(width 0.1651)
		(layer "In5.Cu")
		(net "P5E_PEX1_STN1_RX_DN<31>")
	)
	(segment
		(start 161.42716 -160.725866)
		(end 189.598046 -266.542774)
		(width 0.1651)
		(layer "In5.Cu")
		(net "P5E_PEX1_STN1_RX_DN<31>")
	)
	(segment
		(start 161.99485 -152.57272)
		(end 161.965386 -152.934924)
		(width 0.1651)
		(layer "In5.Cu")
		(net "P5E_PEX1_STN1_RX_DN<31>")
	)
	(segment
		(start 189.663578 -267.043154)
		(end 189.665864 -267.04544)
		(width 0.1651)
		(layer "In5.Cu")
		(net "P5E_PEX1_STN1_RX_DN<31>")
	)
	(segment
		(start 167.351456 -136.846056)
		(end 167.267128 -137.049764)
		(width 0.1651)
		(layer "In5.Cu")
		(net "P5E_PEX1_STN1_RX_DN<31>")
	)
	(segment
		(start 162.630866 -147.32)
		(end 162.207956 -148.271484)
		(width 0.1651)
		(layer "In5.Cu")
		(net "P5E_PEX1_STN1_RX_DN<31>")
	)
	(segment
		(start 189.620144 -271.645126)
		(end 189.620144 -275.27631)
		(width 0.1143)
		(layer "In5.Cu")
		(net "P5E_PEX1_STN1_RX_DN<31>")
	)
	(segment
		(start 167.267128 -137.66165)
		(end 167.381428 -137.77595)
		(width 0.1651)
		(layer "In5.Cu")
		(net "P5E_PEX1_STN1_RX_DN<31>")
	)
	(segment
		(start 167.140128 -141.904466)
		(end 166.952676 -142.36319)
		(width 0.1651)
		(layer "In5.Cu")
		(net "P5E_PEX1_STN1_RX_DN<31>")
	)
	(segment
		(start 163.522152 -146.819874)
		(end 162.865816 -147.088606)
		(width 0.1651)
		(layer "In5.Cu")
		(net "P5E_PEX1_STN1_RX_DN<31>")
	)
	(segment
		(start 189.723522 -275.379688)
		(end 189.88532 -275.379688)
		(width 0.1143)
		(layer "In5.Cu")
		(net "P5E_PEX1_STN1_RX_DN<31>")
	)
	(segment
		(start 167.267128 -137.049764)
		(end 167.267128 -137.66165)
		(width 0.1651)
		(layer "In5.Cu")
		(net "P5E_PEX1_STN1_RX_DN<31>")
	)
	(segment
		(start 161.817304 -153.060654)
		(end 161.344864 -158.854394)
		(width 0.1651)
		(layer "In5.Cu")
		(net "P5E_PEX1_STN1_RX_DN<31>")
	)
	(segment
		(start 162.076384 -151.575262)
		(end 162.04692 -151.937466)
		(width 0.1651)
		(layer "In5.Cu")
		(net "P5E_PEX1_STN1_RX_DN<31>")
	)
	(segment
		(start 168.342564 -136.69645)
		(end 168.342564 -136.696196)
		(width 0.1651)
		(layer "In5.Cu")
		(net "P5E_PEX1_STN1_RX_DN<31>")
	)
	(segment
		(start 162.04692 -151.937466)
		(end 161.898838 -152.062942)
		(width 0.1651)
		(layer "In5.Cu")
		(net "P5E_PEX1_STN1_RX_DN<31>")
	)
	(segment
		(start 161.869374 -152.424892)
		(end 161.99485 -152.57272)
		(width 0.1651)
		(layer "In5.Cu")
		(net "P5E_PEX1_STN1_RX_DN<31>")
	)
	(segment
		(start 165.650926 -144.885156)
		(end 165.297866 -145.232628)
		(width 0.1651)
		(layer "In5.Cu")
		(net "P5E_PEX1_STN1_RX_DN<31>")
	)
	(segment
		(start 168.051988 -136.40562)
		(end 167.791892 -136.40562)
		(width 0.1651)
		(layer "In5.Cu")
		(net "P5E_PEX1_STN1_RX_DN<31>")
	)
	(segment
		(start 164.428678 -146.087846)
		(end 164.267134 -146.08683)
		(width 0.1651)
		(layer "In5.Cu")
		(net "P5E_PEX1_STN1_RX_DN<31>")
	)
	(segment
		(start 166.678356 -143.032988)
		(end 166.490904 -143.491712)
		(width 0.1651)
		(layer "In5.Cu")
		(net "P5E_PEX1_STN1_RX_DN<31>")
	)
	(segment
		(start 167.381428 -139.57935)
		(end 167.381428 -140.07465)
		(width 0.1651)
		(layer "In5.Cu")
		(net "P5E_PEX1_STN1_RX_DN<31>")
	)
	(segment
		(start 164.267134 -146.08683)
		(end 163.522152 -146.819874)
		(width 0.1651)
		(layer "In5.Cu")
		(net "P5E_PEX1_STN1_RX_DN<31>")
	)
	(segment
		(start 166.490904 -143.491712)
		(end 166.341552 -143.554196)
		(width 0.1651)
		(layer "In5.Cu")
		(net "P5E_PEX1_STN1_RX_DN<31>")
	)
	(segment
		(start 167.381428 -137.77595)
		(end 167.381428 -138.27125)
		(width 0.1651)
		(layer "In5.Cu")
		(net "P5E_PEX1_STN1_RX_DN<31>")
	)
	(segment
		(start 167.381428 -138.27125)
		(end 167.267128 -138.38555)
		(width 0.1651)
		(layer "In5.Cu")
		(net "P5E_PEX1_STN1_RX_DN<31>")
	)
	(segment
		(start 167.267128 -140.18895)
		(end 167.267128 -141.292072)
		(width 0.1651)
		(layer "In5.Cu")
		(net "P5E_PEX1_STN1_RX_DN<31>")
	)
	(segment
		(start 165.136068 -145.231358)
		(end 164.783262 -145.578576)
		(width 0.1651)
		(layer "In5.Cu")
		(net "P5E_PEX1_STN1_RX_DN<31>")
	)
	(segment
		(start 189.665864 -267.04544)
		(end 189.665864 -271.570958)
		(width 0.1651)
		(layer "In5.Cu")
		(net "P5E_PEX1_STN1_RX_DN<31>")
	)
	(segment
		(start 189.88532 -275.379688)
		(end 189.99962 -275.265388)
		(width 0.1143)
		(layer "In5.Cu")
		(net "P5E_PEX1_STN1_RX_DN<31>")
	)
	(segment
		(start 167.267128 -141.292072)
		(end 167.077644 -141.755368)
		(width 0.1651)
		(layer "In5.Cu")
		(net "P5E_PEX1_STN1_RX_DN<31>")
	)
	(segment
		(start 189.620144 -275.27631)
		(end 189.723522 -275.379688)
		(width 0.1143)
		(layer "In5.Cu")
		(net "P5E_PEX1_STN1_RX_DN<31>")
	)
	(segment
		(start 167.267128 -139.46505)
		(end 167.381428 -139.57935)
		(width 0.1651)
		(layer "In5.Cu")
		(net "P5E_PEX1_STN1_RX_DN<31>")
	)
	(segment
		(start 189.665864 -271.570958)
		(end 189.665864 -271.599406)
		(width 0.1143)
		(layer "In5.Cu")
		(net "P5E_PEX1_STN1_RX_DN<31>")
	)
	(segment
		(start 165.65245 -144.723358)
		(end 165.650926 -144.885156)
		(width 0.1651)
		(layer "In5.Cu")
		(net "P5E_PEX1_STN1_RX_DN<31>")
	)
	(segment
		(start 161.965386 -152.934924)
		(end 161.817304 -153.060654)
		(width 0.1651)
		(layer "In5.Cu")
		(net "P5E_PEX1_STN1_RX_DN<31>")
	)
	(segment
		(start 168.342564 -136.696196)
		(end 168.051988 -136.40562)
		(width 0.1651)
		(layer "In5.Cu")
		(net "P5E_PEX1_STN1_RX_DN<31>")
	)
	(segment
		(start 161.950908 -151.427434)
		(end 162.076384 -151.575262)
		(width 0.1651)
		(layer "In5.Cu")
		(net "P5E_PEX1_STN1_RX_DN<31>")
	)
	(segment
		(start 166.615872 -142.88389)
		(end 166.678356 -143.032988)
		(width 0.1651)
		(layer "In5.Cu")
		(net "P5E_PEX1_STN1_RX_DN<31>")
	)
	(segment
		(start 161.344864 -158.854394)
		(end 161.42716 -160.725866)
		(width 0.1651)
		(layer "In5.Cu")
		(net "P5E_PEX1_STN1_RX_DN<31>")
	)
	(segment
		(start 167.791892 -136.40562)
		(end 167.351456 -136.846056)
		(width 0.1651)
		(layer "In5.Cu")
		(net "P5E_PEX1_STN1_RX_DN<31>")
	)
	(segment
		(start 167.077644 -141.755368)
		(end 167.140128 -141.904466)
		(width 0.1651)
		(layer "In5.Cu")
		(net "P5E_PEX1_STN1_RX_DN<31>")
	)
	(segment
		(start 166.341552 -143.554196)
		(end 166.005256 -144.37614)
		(width 0.1651)
		(layer "In5.Cu")
		(net "P5E_PEX1_STN1_RX_DN<31>")
	)
	(segment
		(start 162.207956 -148.271484)
		(end 161.950908 -151.427434)
		(width 0.1651)
		(layer "In5.Cu")
		(net "P5E_PEX1_STN1_RX_DN<31>")
	)
	(segment
		(start 164.781738 -145.740374)
		(end 164.428678 -146.087846)
		(width 0.1651)
		(layer "In5.Cu")
		(net "P5E_PEX1_STN1_RX_DN<31>")
	)
	(segment
		(start 124.592588 -351.316798)
		(end 124.592588 -350.685354)
		(width 0.13462)
		(layer "F.Cu")
		(net "P5E_PEX1_STN6_TX_C_DP<97>")
	)
	(segment
		(start 124.592588 -350.685354)
		(end 124.272548 -350.365314)
		(width 0.13462)
		(layer "F.Cu")
		(net "P5E_PEX1_STN6_TX_C_DP<97>")
	)
	(segment
		(start 124.297948 -351.611438)
		(end 124.592588 -351.316798)
		(width 0.13462)
		(layer "F.Cu")
		(net "P5E_PEX1_STN6_TX_C_DP<97>")
	)
	(segment
		(start 123.034298 -353.975162)
		(end 123.034298 -358.315768)
		(width 0.1651)
		(layer "In7.Cu")
		(net "P5E_PEX1_STN6_TX_C_DP<97>")
	)
	(segment
		(start 127.143256 -364.670848)
		(end 127.423418 -365.079026)
		(width 0.1651)
		(layer "In7.Cu")
		(net "P5E_PEX1_STN6_TX_C_DP<97>")
	)
	(segment
		(start 129.236978 -382.699006)
		(end 129.109978 -382.572006)
		(width 0.1651)
		(layer "In7.Cu")
		(net "P5E_PEX1_STN6_TX_C_DP<97>")
	)
	(segment
		(start 127.78994 -365.613442)
		(end 128.070102 -366.02162)
		(width 0.1651)
		(layer "In7.Cu")
		(net "P5E_PEX1_STN6_TX_C_DP<97>")
	)
	(segment
		(start 126.756922 -364.24235)
		(end 127.037338 -364.651036)
		(width 0.1651)
		(layer "In7.Cu")
		(net "P5E_PEX1_STN6_TX_C_DP<97>")
	)
	(segment
		(start 129.887472 -369.033298)
		(end 129.887472 -382.280668)
		(width 0.1651)
		(layer "In7.Cu")
		(net "P5E_PEX1_STN6_TX_C_DP<97>")
	)
	(segment
		(start 123.034298 -358.315768)
		(end 123.241308 -358.983534)
		(width 0.1651)
		(layer "In7.Cu")
		(net "P5E_PEX1_STN6_TX_C_DP<97>")
	)
	(segment
		(start 127.037338 -364.651036)
		(end 127.143256 -364.670848)
		(width 0.1651)
		(layer "In7.Cu")
		(net "P5E_PEX1_STN6_TX_C_DP<97>")
	)
	(segment
		(start 128.436624 -366.556036)
		(end 129.616454 -368.275616)
		(width 0.1651)
		(layer "In7.Cu")
		(net "P5E_PEX1_STN6_TX_C_DP<97>")
	)
	(segment
		(start 129.109978 -382.572006)
		(end 129.109978 -382.18999)
		(width 0.1651)
		(layer "In7.Cu")
		(net "P5E_PEX1_STN6_TX_C_DP<97>")
	)
	(segment
		(start 129.616454 -368.275616)
		(end 129.887472 -369.033298)
		(width 0.1651)
		(layer "In7.Cu")
		(net "P5E_PEX1_STN6_TX_C_DP<97>")
	)
	(segment
		(start 124.588778 -351.902268)
		(end 124.588778 -352.420682)
		(width 0.1651)
		(layer "In7.Cu")
		(net "P5E_PEX1_STN6_TX_C_DP<97>")
	)
	(segment
		(start 129.887472 -382.280668)
		(end 129.469134 -382.699006)
		(width 0.1651)
		(layer "In7.Cu")
		(net "P5E_PEX1_STN6_TX_C_DP<97>")
	)
	(segment
		(start 123.241308 -358.983534)
		(end 126.776734 -364.136432)
		(width 0.1651)
		(layer "In7.Cu")
		(net "P5E_PEX1_STN6_TX_C_DP<97>")
	)
	(segment
		(start 128.330706 -366.536224)
		(end 128.436624 -366.556036)
		(width 0.1651)
		(layer "In7.Cu")
		(net "P5E_PEX1_STN6_TX_C_DP<97>")
	)
	(segment
		(start 127.423418 -365.079026)
		(end 127.403606 -365.184944)
		(width 0.1651)
		(layer "In7.Cu")
		(net "P5E_PEX1_STN6_TX_C_DP<97>")
	)
	(segment
		(start 126.776734 -364.136432)
		(end 126.756922 -364.24235)
		(width 0.1651)
		(layer "In7.Cu")
		(net "P5E_PEX1_STN6_TX_C_DP<97>")
	)
	(segment
		(start 129.469134 -382.699006)
		(end 129.236978 -382.699006)
		(width 0.1651)
		(layer "In7.Cu")
		(net "P5E_PEX1_STN6_TX_C_DP<97>")
	)
	(segment
		(start 128.05029 -366.127538)
		(end 128.330706 -366.536224)
		(width 0.1651)
		(layer "In7.Cu")
		(net "P5E_PEX1_STN6_TX_C_DP<97>")
	)
	(segment
		(start 128.070102 -366.02162)
		(end 128.05029 -366.127538)
		(width 0.1651)
		(layer "In7.Cu")
		(net "P5E_PEX1_STN6_TX_C_DP<97>")
	)
	(segment
		(start 127.403606 -365.184944)
		(end 127.684022 -365.59363)
		(width 0.1651)
		(layer "In7.Cu")
		(net "P5E_PEX1_STN6_TX_C_DP<97>")
	)
	(segment
		(start 124.297948 -351.611438)
		(end 124.588778 -351.902268)
		(width 0.1651)
		(layer "In7.Cu")
		(net "P5E_PEX1_STN6_TX_C_DP<97>")
	)
	(segment
		(start 124.588778 -352.420682)
		(end 123.034298 -353.975162)
		(width 0.1651)
		(layer "In7.Cu")
		(net "P5E_PEX1_STN6_TX_C_DP<97>")
	)
	(segment
		(start 127.684022 -365.59363)
		(end 127.78994 -365.613442)
		(width 0.1651)
		(layer "In7.Cu")
		(net "P5E_PEX1_STN6_TX_C_DP<97>")
	)
	(segment
		(start 284.442662 -133.096508)
		(end 284.141418 -132.795264)
		(width 0.13462)
		(layer "F.Cu")
		(net "P5E_PEX2_STN1_RX_DN<29>")
	)
	(segment
		(start 283.49321 -132.795264)
		(end 283.323538 -132.964936)
		(width 0.13462)
		(layer "F.Cu")
		(net "P5E_PEX2_STN1_RX_DN<29>")
	)
	(segment
		(start 284.141418 -132.795264)
		(end 283.49321 -132.795264)
		(width 0.13462)
		(layer "F.Cu")
		(net "P5E_PEX2_STN1_RX_DN<29>")
	)
	(segment
		(start 283.323538 -132.964936)
		(end 282.842462 -132.964936)
		(width 0.13462)
		(layer "F.Cu")
		(net "P5E_PEX2_STN1_RX_DN<29>")
	)
	(segment
		(start 303.820068 -275.276056)
		(end 303.923446 -275.379434)
		(width 0.1143)
		(layer "In5.Cu")
		(net "P5E_PEX2_STN1_RX_DN<29>")
	)
	(segment
		(start 281.490674 -136.473692)
		(end 281.341068 -136.535668)
		(width 0.1651)
		(layer "In5.Cu")
		(net "P5E_PEX2_STN1_RX_DN<29>")
	)
	(segment
		(start 283.934916 -132.805678)
		(end 283.726636 -132.892038)
		(width 0.1651)
		(layer "In5.Cu")
		(net "P5E_PEX2_STN1_RX_DN<29>")
	)
	(segment
		(start 281.618182 -135.866632)
		(end 281.680158 -136.015984)
		(width 0.1651)
		(layer "In5.Cu")
		(net "P5E_PEX2_STN1_RX_DN<29>")
	)
	(segment
		(start 303.865788 -267.461238)
		(end 303.865788 -271.570704)
		(width 0.1651)
		(layer "In5.Cu")
		(net "P5E_PEX2_STN1_RX_DN<29>")
	)
	(segment
		(start 279.519634 -143.745204)
		(end 279.358344 -143.73733)
		(width 0.1651)
		(layer "In5.Cu")
		(net "P5E_PEX2_STN1_RX_DN<29>")
	)
	(segment
		(start 303.865788 -271.570704)
		(end 303.865788 -271.599152)
		(width 0.1143)
		(layer "In5.Cu")
		(net "P5E_PEX2_STN1_RX_DN<29>")
	)
	(segment
		(start 274.651724 -147.013168)
		(end 274.210272 -147.823936)
		(width 0.1651)
		(layer "In5.Cu")
		(net "P5E_PEX2_STN1_RX_DN<29>")
	)
	(segment
		(start 303.865788 -271.599152)
		(end 303.820068 -271.644872)
		(width 0.1143)
		(layer "In5.Cu")
		(net "P5E_PEX2_STN1_RX_DN<29>")
	)
	(segment
		(start 281.265884 -138.44524)
		(end 281.265884 -138.94054)
		(width 0.1651)
		(layer "In5.Cu")
		(net "P5E_PEX2_STN1_RX_DN<29>")
	)
	(segment
		(start 281.151584 -139.55014)
		(end 281.265884 -139.66444)
		(width 0.1651)
		(layer "In5.Cu")
		(net "P5E_PEX2_STN1_RX_DN<29>")
	)
	(segment
		(start 303.923446 -275.379434)
		(end 304.085244 -275.379434)
		(width 0.1143)
		(layer "In5.Cu")
		(net "P5E_PEX2_STN1_RX_DN<29>")
	)
	(segment
		(start 281.807666 -135.409178)
		(end 281.618182 -135.866632)
		(width 0.1651)
		(layer "In5.Cu")
		(net "P5E_PEX2_STN1_RX_DN<29>")
	)
	(segment
		(start 279.895046 -143.25092)
		(end 279.886918 -143.412464)
		(width 0.1651)
		(layer "In5.Cu")
		(net "P5E_PEX2_STN1_RX_DN<29>")
	)
	(segment
		(start 279.886918 -143.412464)
		(end 279.519634 -143.745204)
		(width 0.1651)
		(layer "In5.Cu")
		(net "P5E_PEX2_STN1_RX_DN<29>")
	)
	(segment
		(start 303.820068 -271.644872)
		(end 303.820068 -275.276056)
		(width 0.1143)
		(layer "In5.Cu")
		(net "P5E_PEX2_STN1_RX_DN<29>")
	)
	(segment
		(start 280.477976 -142.396464)
		(end 280.261822 -142.918434)
		(width 0.1651)
		(layer "In5.Cu")
		(net "P5E_PEX2_STN1_RX_DN<29>")
	)
	(segment
		(start 281.341068 -136.535668)
		(end 281.151584 -136.993122)
		(width 0.1651)
		(layer "In5.Cu")
		(net "P5E_PEX2_STN1_RX_DN<29>")
	)
	(segment
		(start 284.151832 -132.805678)
		(end 283.934916 -132.805678)
		(width 0.1651)
		(layer "In5.Cu")
		(net "P5E_PEX2_STN1_RX_DN<29>")
	)
	(segment
		(start 281.265884 -139.66444)
		(end 281.265884 -140.15974)
		(width 0.1651)
		(layer "In5.Cu")
		(net "P5E_PEX2_STN1_RX_DN<29>")
	)
	(segment
		(start 275.204174 -146.477736)
		(end 274.839176 -146.783806)
		(width 0.1651)
		(layer "In5.Cu")
		(net "P5E_PEX2_STN1_RX_DN<29>")
	)
	(segment
		(start 283.726636 -132.892038)
		(end 283.657294 -132.96138)
		(width 0.1651)
		(layer "In5.Cu")
		(net "P5E_PEX2_STN1_RX_DN<29>")
	)
	(segment
		(start 283.260546 -133.337046)
		(end 283.256228 -133.498844)
		(width 0.1651)
		(layer "In5.Cu")
		(net "P5E_PEX2_STN1_RX_DN<29>")
	)
	(segment
		(start 278.337772 -144.662144)
		(end 277.934928 -145.264632)
		(width 0.1651)
		(layer "In5.Cu")
		(net "P5E_PEX2_STN1_RX_DN<29>")
	)
	(segment
		(start 282.28163 -134.2644)
		(end 282.08478 -134.740142)
		(width 0.1651)
		(layer "In5.Cu")
		(net "P5E_PEX2_STN1_RX_DN<29>")
	)
	(segment
		(start 283.256228 -133.498844)
		(end 282.89631 -133.839712)
		(width 0.1651)
		(layer "In5.Cu")
		(net "P5E_PEX2_STN1_RX_DN<29>")
	)
	(segment
		(start 280.261822 -142.918434)
		(end 279.895046 -143.25092)
		(width 0.1651)
		(layer "In5.Cu")
		(net "P5E_PEX2_STN1_RX_DN<29>")
	)
	(segment
		(start 276.892766 -146.056604)
		(end 276.420834 -146.207734)
		(width 0.1651)
		(layer "In5.Cu")
		(net "P5E_PEX2_STN1_RX_DN<29>")
	)
	(segment
		(start 275.516086 -160.843468)
		(end 303.865788 -267.461238)
		(width 0.1651)
		(layer "In5.Cu")
		(net "P5E_PEX2_STN1_RX_DN<29>")
	)
	(segment
		(start 281.265884 -138.94054)
		(end 281.151584 -139.05484)
		(width 0.1651)
		(layer "In5.Cu")
		(net "P5E_PEX2_STN1_RX_DN<29>")
	)
	(segment
		(start 276.420834 -146.207734)
		(end 276.27707 -146.13382)
		(width 0.1651)
		(layer "In5.Cu")
		(net "P5E_PEX2_STN1_RX_DN<29>")
	)
	(segment
		(start 282.146502 -134.889494)
		(end 281.957018 -135.347202)
		(width 0.1651)
		(layer "In5.Cu")
		(net "P5E_PEX2_STN1_RX_DN<29>")
	)
	(segment
		(start 304.199544 -275.265134)
		(end 304.199544 -274.999704)
		(width 0.1143)
		(layer "In5.Cu")
		(net "P5E_PEX2_STN1_RX_DN<29>")
	)
	(segment
		(start 281.151584 -138.33094)
		(end 281.265884 -138.44524)
		(width 0.1651)
		(layer "In5.Cu")
		(net "P5E_PEX2_STN1_RX_DN<29>")
	)
	(segment
		(start 274.210272 -147.823936)
		(end 274.790662 -156.74721)
		(width 0.1651)
		(layer "In5.Cu")
		(net "P5E_PEX2_STN1_RX_DN<29>")
	)
	(segment
		(start 280.754836 -141.727428)
		(end 280.816812 -141.87678)
		(width 0.1651)
		(layer "In5.Cu")
		(net "P5E_PEX2_STN1_RX_DN<29>")
	)
	(segment
		(start 304.085244 -275.379434)
		(end 304.199544 -275.265134)
		(width 0.1143)
		(layer "In5.Cu")
		(net "P5E_PEX2_STN1_RX_DN<29>")
	)
	(segment
		(start 281.151584 -140.76934)
		(end 280.754836 -141.727428)
		(width 0.1651)
		(layer "In5.Cu")
		(net "P5E_PEX2_STN1_RX_DN<29>")
	)
	(segment
		(start 274.790662 -156.74721)
		(end 275.516086 -160.843468)
		(width 0.1651)
		(layer "In5.Cu")
		(net "P5E_PEX2_STN1_RX_DN<29>")
	)
	(segment
		(start 276.96668 -145.912586)
		(end 276.892766 -146.056604)
		(width 0.1651)
		(layer "In5.Cu")
		(net "P5E_PEX2_STN1_RX_DN<29>")
	)
	(segment
		(start 277.934928 -145.264632)
		(end 277.438104 -145.761456)
		(width 0.1651)
		(layer "In5.Cu")
		(net "P5E_PEX2_STN1_RX_DN<29>")
	)
	(segment
		(start 281.680158 -136.015984)
		(end 281.490674 -136.473692)
		(width 0.1651)
		(layer "In5.Cu")
		(net "P5E_PEX2_STN1_RX_DN<29>")
	)
	(segment
		(start 280.627328 -142.334742)
		(end 280.477976 -142.396464)
		(width 0.1651)
		(layer "In5.Cu")
		(net "P5E_PEX2_STN1_RX_DN<29>")
	)
	(segment
		(start 280.816812 -141.87678)
		(end 280.627328 -142.334742)
		(width 0.1651)
		(layer "In5.Cu")
		(net "P5E_PEX2_STN1_RX_DN<29>")
	)
	(segment
		(start 284.442662 -133.096508)
		(end 284.151832 -132.805678)
		(width 0.1651)
		(layer "In5.Cu")
		(net "P5E_PEX2_STN1_RX_DN<29>")
	)
	(segment
		(start 282.89631 -133.839712)
		(end 282.734766 -133.83514)
		(width 0.1651)
		(layer "In5.Cu")
		(net "P5E_PEX2_STN1_RX_DN<29>")
	)
	(segment
		(start 276.27707 -146.13382)
		(end 275.204174 -146.477736)
		(width 0.1651)
		(layer "In5.Cu")
		(net "P5E_PEX2_STN1_RX_DN<29>")
	)
	(segment
		(start 274.839176 -146.783806)
		(end 274.651724 -147.013168)
		(width 0.1651)
		(layer "In5.Cu")
		(net "P5E_PEX2_STN1_RX_DN<29>")
	)
	(segment
		(start 281.957018 -135.347202)
		(end 281.807666 -135.409178)
		(width 0.1651)
		(layer "In5.Cu")
		(net "P5E_PEX2_STN1_RX_DN<29>")
	)
	(segment
		(start 281.265884 -140.15974)
		(end 281.151584 -140.27404)
		(width 0.1651)
		(layer "In5.Cu")
		(net "P5E_PEX2_STN1_RX_DN<29>")
	)
	(segment
		(start 282.734766 -133.83514)
		(end 282.28163 -134.2644)
		(width 0.1651)
		(layer "In5.Cu")
		(net "P5E_PEX2_STN1_RX_DN<29>")
	)
	(segment
		(start 281.151584 -139.05484)
		(end 281.151584 -139.55014)
		(width 0.1651)
		(layer "In5.Cu")
		(net "P5E_PEX2_STN1_RX_DN<29>")
	)
	(segment
		(start 283.657294 -132.96138)
		(end 283.260546 -133.337046)
		(width 0.1651)
		(layer "In5.Cu")
		(net "P5E_PEX2_STN1_RX_DN<29>")
	)
	(segment
		(start 282.08478 -134.740142)
		(end 282.146502 -134.889494)
		(width 0.1651)
		(layer "In5.Cu")
		(net "P5E_PEX2_STN1_RX_DN<29>")
	)
	(segment
		(start 279.358344 -143.73733)
		(end 278.337772 -144.662144)
		(width 0.1651)
		(layer "In5.Cu")
		(net "P5E_PEX2_STN1_RX_DN<29>")
	)
	(segment
		(start 281.151584 -140.27404)
		(end 281.151584 -140.76934)
		(width 0.1651)
		(layer "In5.Cu")
		(net "P5E_PEX2_STN1_RX_DN<29>")
	)
	(segment
		(start 277.438104 -145.761456)
		(end 276.96668 -145.912586)
		(width 0.1651)
		(layer "In5.Cu")
		(net "P5E_PEX2_STN1_RX_DN<29>")
	)
	(segment
		(start 281.151584 -136.993122)
		(end 281.151584 -138.33094)
		(width 0.1651)
		(layer "In5.Cu")
		(net "P5E_PEX2_STN1_RX_DN<29>")
	)
	(segment
		(start 325.507604 -350.685354)
		(end 325.507604 -351.316798)
		(width 0.13462)
		(layer "F.Cu")
		(net "P5E_PEX2_STN5_TX_C_DN<86>")
	)
	(segment
		(start 325.827644 -350.365314)
		(end 325.507604 -350.685354)
		(width 0.13462)
		(layer "F.Cu")
		(net "P5E_PEX2_STN5_TX_C_DN<86>")
	)
	(segment
		(start 325.507604 -351.316798)
		(end 325.802244 -351.611438)
		(width 0.13462)
		(layer "F.Cu")
		(net "P5E_PEX2_STN5_TX_C_DN<86>")
	)
	(segment
		(start 345.81592 -404.629112)
		(end 345.364054 -405.080978)
		(width 0.1651)
		(layer "In7.Cu")
		(net "P5E_PEX2_STN5_TX_C_DN<86>")
	)
	(segment
		(start 323.956934 -358.872028)
		(end 329.426062 -384.368548)
		(width 0.1651)
		(layer "In7.Cu")
		(net "P5E_PEX2_STN5_TX_C_DN<86>")
	)
	(segment
		(start 323.956934 -354.027486)
		(end 323.956934 -358.872028)
		(width 0.1651)
		(layer "In7.Cu")
		(net "P5E_PEX2_STN5_TX_C_DN<86>")
	)
	(segment
		(start 345.364054 -405.080978)
		(end 344.816938 -405.080978)
		(width 0.1651)
		(layer "In7.Cu")
		(net "P5E_PEX2_STN5_TX_C_DN<86>")
	)
	(segment
		(start 344.689938 -405.207978)
		(end 344.689938 -405.589994)
		(width 0.1651)
		(layer "In7.Cu")
		(net "P5E_PEX2_STN5_TX_C_DN<86>")
	)
	(segment
		(start 345.261946 -394.025882)
		(end 345.81592 -394.7922)
		(width 0.1651)
		(layer "In7.Cu")
		(net "P5E_PEX2_STN5_TX_C_DN<86>")
	)
	(segment
		(start 330.016358 -385.838446)
		(end 331.041248 -386.87756)
		(width 0.1651)
		(layer "In7.Cu")
		(net "P5E_PEX2_STN5_TX_C_DN<86>")
	)
	(segment
		(start 329.426062 -384.368548)
		(end 330.016358 -385.838446)
		(width 0.1651)
		(layer "In7.Cu")
		(net "P5E_PEX2_STN5_TX_C_DN<86>")
	)
	(segment
		(start 345.81592 -394.7922)
		(end 345.81592 -404.629112)
		(width 0.1651)
		(layer "In7.Cu")
		(net "P5E_PEX2_STN5_TX_C_DN<86>")
	)
	(segment
		(start 325.511414 -352.473006)
		(end 323.956934 -354.027486)
		(width 0.1651)
		(layer "In7.Cu")
		(net "P5E_PEX2_STN5_TX_C_DN<86>")
	)
	(segment
		(start 331.041248 -386.87756)
		(end 337.037172 -389.35406)
		(width 0.1651)
		(layer "In7.Cu")
		(net "P5E_PEX2_STN5_TX_C_DN<86>")
	)
	(segment
		(start 325.511414 -351.902268)
		(end 325.511414 -352.473006)
		(width 0.1651)
		(layer "In7.Cu")
		(net "P5E_PEX2_STN5_TX_C_DN<86>")
	)
	(segment
		(start 344.816938 -405.080978)
		(end 344.689938 -405.207978)
		(width 0.1651)
		(layer "In7.Cu")
		(net "P5E_PEX2_STN5_TX_C_DN<86>")
	)
	(segment
		(start 325.802244 -351.611438)
		(end 325.511414 -351.902268)
		(width 0.1651)
		(layer "In7.Cu")
		(net "P5E_PEX2_STN5_TX_C_DN<86>")
	)
	(segment
		(start 337.037172 -389.35406)
		(end 345.261946 -394.025882)
		(width 0.1651)
		(layer "In7.Cu")
		(net "P5E_PEX2_STN5_TX_C_DN<86>")
	)
	(segment
		(start 431.032412 -350.365314)
		(end 431.35296 -350.685862)
		(width 0.13462)
		(layer "F.Cu")
		(net "P5E_PEX3_STN7_TX_C_DN<122>")
	)
	(segment
		(start 431.35296 -351.31629)
		(end 431.057812 -351.611438)
		(width 0.13462)
		(layer "F.Cu")
		(net "P5E_PEX3_STN7_TX_C_DN<122>")
	)
	(segment
		(start 431.35296 -350.685862)
		(end 431.35296 -351.31629)
		(width 0.13462)
		(layer "F.Cu")
		(net "P5E_PEX3_STN7_TX_C_DN<122>")
	)
	(segment
		(start 429.794162 -353.910646)
		(end 431.348642 -352.356166)
		(width 0.1651)
		(layer "In11.Cu")
		(net "P5E_PEX3_STN7_TX_C_DN<122>")
	)
	(segment
		(start 427.705774 -362.867448)
		(end 427.93285 -362.427012)
		(width 0.1651)
		(layer "In11.Cu")
		(net "P5E_PEX3_STN7_TX_C_DN<122>")
	)
	(segment
		(start 427.93285 -362.427012)
		(end 428.035466 -362.393992)
		(width 0.1651)
		(layer "In11.Cu")
		(net "P5E_PEX3_STN7_TX_C_DN<122>")
	)
	(segment
		(start 423.889932 -374.772174)
		(end 424.016932 -374.899174)
		(width 0.1651)
		(layer "In11.Cu")
		(net "P5E_PEX3_STN7_TX_C_DN<122>")
	)
	(segment
		(start 427.055534 -364.29696)
		(end 427.006258 -364.143036)
		(width 0.1651)
		(layer "In11.Cu")
		(net "P5E_PEX3_STN7_TX_C_DN<122>")
	)
	(segment
		(start 429.794162 -358.07015)
		(end 429.794162 -353.910646)
		(width 0.1651)
		(layer "In11.Cu")
		(net "P5E_PEX3_STN7_TX_C_DN<122>")
	)
	(segment
		(start 428.770796 -360.715814)
		(end 428.997872 -360.275124)
		(width 0.1651)
		(layer "In11.Cu")
		(net "P5E_PEX3_STN7_TX_C_DN<122>")
	)
	(segment
		(start 426.447966 -365.227108)
		(end 426.675042 -364.786418)
		(width 0.1651)
		(layer "In11.Cu")
		(net "P5E_PEX3_STN7_TX_C_DN<122>")
	)
	(segment
		(start 425.889674 -366.31118)
		(end 426.11675 -365.87049)
		(width 0.1651)
		(layer "In11.Cu")
		(net "P5E_PEX3_STN7_TX_C_DN<122>")
	)
	(segment
		(start 428.43958 -361.359196)
		(end 428.593504 -361.30992)
		(width 0.1651)
		(layer "In11.Cu")
		(net "P5E_PEX3_STN7_TX_C_DN<122>")
	)
	(segment
		(start 428.262034 -361.95381)
		(end 428.212504 -361.799886)
		(width 0.1651)
		(layer "In11.Cu")
		(net "P5E_PEX3_STN7_TX_C_DN<122>")
	)
	(segment
		(start 424.733974 -369.72367)
		(end 425.15409 -367.989358)
		(width 0.1651)
		(layer "In11.Cu")
		(net "P5E_PEX3_STN7_TX_C_DN<122>")
	)
	(segment
		(start 424.447208 -374.899174)
		(end 424.733974 -374.612408)
		(width 0.1651)
		(layer "In11.Cu")
		(net "P5E_PEX3_STN7_TX_C_DN<122>")
	)
	(segment
		(start 423.889932 -374.390158)
		(end 423.889932 -374.772174)
		(width 0.1651)
		(layer "In11.Cu")
		(net "P5E_PEX3_STN7_TX_C_DN<122>")
	)
	(segment
		(start 427.738794 -362.970064)
		(end 427.705774 -362.867448)
		(width 0.1651)
		(layer "In11.Cu")
		(net "P5E_PEX3_STN7_TX_C_DN<122>")
	)
	(segment
		(start 428.593504 -361.30992)
		(end 428.820072 -360.869738)
		(width 0.1651)
		(layer "In11.Cu")
		(net "P5E_PEX3_STN7_TX_C_DN<122>")
	)
	(segment
		(start 426.828712 -364.736888)
		(end 427.05528 -364.29696)
		(width 0.1651)
		(layer "In11.Cu")
		(net "P5E_PEX3_STN7_TX_C_DN<122>")
	)
	(segment
		(start 426.497242 -365.381032)
		(end 426.447966 -365.227108)
		(width 0.1651)
		(layer "In11.Cu")
		(net "P5E_PEX3_STN7_TX_C_DN<122>")
	)
	(segment
		(start 426.828966 -364.737142)
		(end 426.828712 -364.736888)
		(width 0.1651)
		(layer "In11.Cu")
		(net "P5E_PEX3_STN7_TX_C_DN<122>")
	)
	(segment
		(start 428.997872 -360.275124)
		(end 429.151796 -360.225848)
		(width 0.1651)
		(layer "In11.Cu")
		(net "P5E_PEX3_STN7_TX_C_DN<122>")
	)
	(segment
		(start 428.212504 -361.799886)
		(end 428.43958 -361.359196)
		(width 0.1651)
		(layer "In11.Cu")
		(net "P5E_PEX3_STN7_TX_C_DN<122>")
	)
	(segment
		(start 426.675042 -364.786418)
		(end 426.828966 -364.737142)
		(width 0.1651)
		(layer "In11.Cu")
		(net "P5E_PEX3_STN7_TX_C_DN<122>")
	)
	(segment
		(start 425.558458 -366.954562)
		(end 425.712382 -366.905286)
		(width 0.1651)
		(layer "In11.Cu")
		(net "P5E_PEX3_STN7_TX_C_DN<122>")
	)
	(segment
		(start 428.035212 -362.393738)
		(end 428.26178 -361.95381)
		(width 0.1651)
		(layer "In11.Cu")
		(net "P5E_PEX3_STN7_TX_C_DN<122>")
	)
	(segment
		(start 425.712382 -366.905286)
		(end 425.93895 -366.465104)
		(width 0.1651)
		(layer "In11.Cu")
		(net "P5E_PEX3_STN7_TX_C_DN<122>")
	)
	(segment
		(start 427.73854 -362.970064)
		(end 427.738794 -362.970064)
		(width 0.1651)
		(layer "In11.Cu")
		(net "P5E_PEX3_STN7_TX_C_DN<122>")
	)
	(segment
		(start 427.38675 -363.652562)
		(end 427.73854 -362.970064)
		(width 0.1651)
		(layer "In11.Cu")
		(net "P5E_PEX3_STN7_TX_C_DN<122>")
	)
	(segment
		(start 424.733974 -374.612408)
		(end 424.733974 -369.72367)
		(width 0.1651)
		(layer "In11.Cu")
		(net "P5E_PEX3_STN7_TX_C_DN<122>")
	)
	(segment
		(start 425.380658 -367.549176)
		(end 425.331382 -367.395252)
		(width 0.1651)
		(layer "In11.Cu")
		(net "P5E_PEX3_STN7_TX_C_DN<122>")
	)
	(segment
		(start 426.11675 -365.87049)
		(end 426.270674 -365.821214)
		(width 0.1651)
		(layer "In11.Cu")
		(net "P5E_PEX3_STN7_TX_C_DN<122>")
	)
	(segment
		(start 429.151796 -360.225848)
		(end 429.378364 -359.785666)
		(width 0.1651)
		(layer "In11.Cu")
		(net "P5E_PEX3_STN7_TX_C_DN<122>")
	)
	(segment
		(start 427.006258 -364.143036)
		(end 427.233334 -363.702346)
		(width 0.1651)
		(layer "In11.Cu")
		(net "P5E_PEX3_STN7_TX_C_DN<122>")
	)
	(segment
		(start 424.016932 -374.899174)
		(end 424.447208 -374.899174)
		(width 0.1651)
		(layer "In11.Cu")
		(net "P5E_PEX3_STN7_TX_C_DN<122>")
	)
	(segment
		(start 427.387258 -363.65307)
		(end 427.38675 -363.652562)
		(width 0.1651)
		(layer "In11.Cu")
		(net "P5E_PEX3_STN7_TX_C_DN<122>")
	)
	(segment
		(start 431.348642 -351.902268)
		(end 431.057812 -351.611438)
		(width 0.1651)
		(layer "In11.Cu")
		(net "P5E_PEX3_STN7_TX_C_DN<122>")
	)
	(segment
		(start 429.378364 -359.785666)
		(end 429.794162 -358.07015)
		(width 0.1651)
		(layer "In11.Cu")
		(net "P5E_PEX3_STN7_TX_C_DN<122>")
	)
	(segment
		(start 426.270674 -365.821214)
		(end 426.497242 -365.381032)
		(width 0.1651)
		(layer "In11.Cu")
		(net "P5E_PEX3_STN7_TX_C_DN<122>")
	)
	(segment
		(start 428.035466 -362.393992)
		(end 428.035212 -362.393738)
		(width 0.1651)
		(layer "In11.Cu")
		(net "P5E_PEX3_STN7_TX_C_DN<122>")
	)
	(segment
		(start 425.15409 -367.989358)
		(end 425.380658 -367.549176)
		(width 0.1651)
		(layer "In11.Cu")
		(net "P5E_PEX3_STN7_TX_C_DN<122>")
	)
	(segment
		(start 428.820072 -360.869738)
		(end 428.770796 -360.715814)
		(width 0.1651)
		(layer "In11.Cu")
		(net "P5E_PEX3_STN7_TX_C_DN<122>")
	)
	(segment
		(start 425.331382 -367.395252)
		(end 425.558458 -366.954562)
		(width 0.1651)
		(layer "In11.Cu")
		(net "P5E_PEX3_STN7_TX_C_DN<122>")
	)
	(segment
		(start 428.26178 -361.95381)
		(end 428.262034 -361.95381)
		(width 0.1651)
		(layer "In11.Cu")
		(net "P5E_PEX3_STN7_TX_C_DN<122>")
	)
	(segment
		(start 427.233334 -363.702346)
		(end 427.387258 -363.65307)
		(width 0.1651)
		(layer "In11.Cu")
		(net "P5E_PEX3_STN7_TX_C_DN<122>")
	)
	(segment
		(start 425.93895 -366.465104)
		(end 425.889674 -366.31118)
		(width 0.1651)
		(layer "In11.Cu")
		(net "P5E_PEX3_STN7_TX_C_DN<122>")
	)
	(segment
		(start 431.348642 -352.356166)
		(end 431.348642 -351.902268)
		(width 0.1651)
		(layer "In11.Cu")
		(net "P5E_PEX3_STN7_TX_C_DN<122>")
	)
	(segment
		(start 427.05528 -364.29696)
		(end 427.055534 -364.29696)
		(width 0.1651)
		(layer "In11.Cu")
		(net "P5E_PEX3_STN7_TX_C_DN<122>")
	)
	(segment
		(start 414.391348 -100.640134)
		(end 416.95751 -100.640134)
		(width 0.13208)
		(layer "F.Cu")
		(net "NCSI_NIC7_TX_EN")
	)
	(segment
		(start 407.695146 -101.782372)
		(end 412.516066 -101.782372)
		(width 0.13208)
		(layer "F.Cu")
		(net "NCSI_NIC7_TX_EN")
	)
	(segment
		(start 412.516066 -101.782372)
		(end 413.24911 -101.782372)
		(width 0.13208)
		(layer "F.Cu")
		(net "NCSI_NIC7_TX_EN")
	)
	(segment
		(start 413.24911 -101.782372)
		(end 414.391348 -100.640134)
		(width 0.13208)
		(layer "F.Cu")
		(net "NCSI_NIC7_TX_EN")
	)
	(via
		(at 412.516066 -101.782372)
		(size 0.762)
		(drill 0.381)
		(layers "F.Cu" "B.Cu")
		(net "NCSI_NIC7_TX_EN")
	)
	(segment
		(start 67.351402 -150.11781)
		(end 67.05727 -149.823678)
		(width 0.13462)
		(layer "F.Cu")
		(net "P5E_PEX0_STN0_RX_DN<12>")
	)
	(segment
		(start 68.65747 -149.954996)
		(end 68.169536 -149.954996)
		(width 0.13462)
		(layer "F.Cu")
		(net "P5E_PEX0_STN0_RX_DN<12>")
	)
	(segment
		(start 68.169536 -149.954996)
		(end 68.006722 -150.11781)
		(width 0.13462)
		(layer "F.Cu")
		(net "P5E_PEX0_STN0_RX_DN<12>")
	)
	(segment
		(start 68.006722 -150.11781)
		(end 67.351402 -150.11781)
		(width 0.13462)
		(layer "F.Cu")
		(net "P5E_PEX0_STN0_RX_DN<12>")
	)
	(segment
		(start 67.938396 -150.114508)
		(end 69.448934 -151.59863)
		(width 0.1651)
		(layer "In5.Cu")
		(net "P5E_PEX0_STN0_RX_DN<12>")
	)
	(segment
		(start 73.142856 -158.362396)
		(end 74.302366 -161.1503)
		(width 0.1651)
		(layer "In5.Cu")
		(net "P5E_PEX0_STN0_RX_DN<12>")
	)
	(segment
		(start 70.343776 -153.725626)
		(end 70.867524 -154.97175)
		(width 0.1651)
		(layer "In5.Cu")
		(net "P5E_PEX0_STN0_RX_DN<12>")
	)
	(segment
		(start 77.89545 -268.061186)
		(end 77.36586 -270.786098)
		(width 0.1651)
		(layer "In5.Cu")
		(net "P5E_PEX0_STN0_RX_DN<12>")
	)
	(segment
		(start 77.32014 -271.848072)
		(end 77.32014 -275.27631)
		(width 0.1143)
		(layer "In5.Cu")
		(net "P5E_PEX0_STN0_RX_DN<12>")
	)
	(segment
		(start 77.32014 -275.27631)
		(end 77.423518 -275.379688)
		(width 0.1143)
		(layer "In5.Cu")
		(net "P5E_PEX0_STN0_RX_DN<12>")
	)
	(segment
		(start 73.132188 -158.336488)
		(end 73.14311 -158.362396)
		(width 0.1651)
		(layer "In5.Cu")
		(net "P5E_PEX0_STN0_RX_DN<12>")
	)
	(segment
		(start 67.05727 -149.823678)
		(end 67.3481 -150.114508)
		(width 0.1651)
		(layer "In5.Cu")
		(net "P5E_PEX0_STN0_RX_DN<12>")
	)
	(segment
		(start 70.343268 -153.725372)
		(end 70.343776 -153.725626)
		(width 0.1651)
		(layer "In5.Cu")
		(net "P5E_PEX0_STN0_RX_DN<12>")
	)
	(segment
		(start 77.36586 -270.786098)
		(end 77.36586 -271.773904)
		(width 0.1651)
		(layer "In5.Cu")
		(net "P5E_PEX0_STN0_RX_DN<12>")
	)
	(segment
		(start 69.448934 -151.59863)
		(end 70.343268 -153.725372)
		(width 0.1651)
		(layer "In5.Cu")
		(net "P5E_PEX0_STN0_RX_DN<12>")
	)
	(segment
		(start 77.36586 -271.773904)
		(end 77.36586 -271.802352)
		(width 0.1143)
		(layer "In5.Cu")
		(net "P5E_PEX0_STN0_RX_DN<12>")
	)
	(segment
		(start 67.3481 -150.114508)
		(end 67.938396 -150.114508)
		(width 0.1651)
		(layer "In5.Cu")
		(net "P5E_PEX0_STN0_RX_DN<12>")
	)
	(segment
		(start 77.585316 -275.379688)
		(end 77.699616 -275.265388)
		(width 0.1143)
		(layer "In5.Cu")
		(net "P5E_PEX0_STN0_RX_DN<12>")
	)
	(segment
		(start 77.699616 -275.265388)
		(end 77.699616 -274.999958)
		(width 0.1143)
		(layer "In5.Cu")
		(net "P5E_PEX0_STN0_RX_DN<12>")
	)
	(segment
		(start 77.423518 -275.379688)
		(end 77.585316 -275.379688)
		(width 0.1143)
		(layer "In5.Cu")
		(net "P5E_PEX0_STN0_RX_DN<12>")
	)
	(segment
		(start 74.302366 -161.1503)
		(end 77.832712 -260.768084)
		(width 0.1651)
		(layer "In5.Cu")
		(net "P5E_PEX0_STN0_RX_DN<12>")
	)
	(segment
		(start 77.832712 -260.768084)
		(end 77.89545 -268.061186)
		(width 0.1651)
		(layer "In5.Cu")
		(net "P5E_PEX0_STN0_RX_DN<12>")
	)
	(segment
		(start 70.867524 -154.97175)
		(end 73.132188 -158.336488)
		(width 0.1651)
		(layer "In5.Cu")
		(net "P5E_PEX0_STN0_RX_DN<12>")
	)
	(segment
		(start 77.36586 -271.802352)
		(end 77.32014 -271.848072)
		(width 0.1143)
		(layer "In5.Cu")
		(net "P5E_PEX0_STN0_RX_DN<12>")
	)
	(segment
		(start 73.14311 -158.362396)
		(end 73.142856 -158.362396)
		(width 0.1651)
		(layer "In5.Cu")
		(net "P5E_PEX0_STN0_RX_DN<12>")
	)
	(segment
		(start 168.048178 -121.592086)
		(end 168.342564 -121.886472)
		(width 0.13462)
		(layer "F.Cu")
		(net "P5E_PEX1_STN1_RX_DN<25>")
	)
	(segment
		(start 167.393112 -121.592086)
		(end 168.048178 -121.592086)
		(width 0.13462)
		(layer "F.Cu")
		(net "P5E_PEX1_STN1_RX_DN<25>")
	)
	(segment
		(start 166.742364 -121.7549)
		(end 167.230298 -121.7549)
		(width 0.13462)
		(layer "F.Cu")
		(net "P5E_PEX1_STN1_RX_DN<25>")
	)
	(segment
		(start 167.230298 -121.7549)
		(end 167.393112 -121.592086)
		(width 0.13462)
		(layer "F.Cu")
		(net "P5E_PEX1_STN1_RX_DN<25>")
	)
	(segment
		(start 184.299606 -275.26488)
		(end 184.185052 -275.379434)
		(width 0.1143)
		(layer "In5.Cu")
		(net "P5E_PEX1_STN1_RX_DN<25>")
	)
	(segment
		(start 161.013648 -127.366014)
		(end 161.322258 -126.978918)
		(width 0.1651)
		(layer "In5.Cu")
		(net "P5E_PEX1_STN1_RX_DN<25>")
	)
	(segment
		(start 160.561782 -127.93218)
		(end 160.722564 -127.914146)
		(width 0.1651)
		(layer "In5.Cu")
		(net "P5E_PEX1_STN1_RX_DN<25>")
	)
	(segment
		(start 163.691824 -124.719334)
		(end 164.058854 -124.38634)
		(width 0.1651)
		(layer "In5.Cu")
		(net "P5E_PEX1_STN1_RX_DN<25>")
	)
	(segment
		(start 161.792158 -126.57328)
		(end 161.77387 -126.412752)
		(width 0.1651)
		(layer "In5.Cu")
		(net "P5E_PEX1_STN1_RX_DN<25>")
	)
	(segment
		(start 161.322258 -126.978918)
		(end 161.48304 -126.960884)
		(width 0.1651)
		(layer "In5.Cu")
		(net "P5E_PEX1_STN1_RX_DN<25>")
	)
	(segment
		(start 183.919876 -271.848072)
		(end 183.965596 -271.802352)
		(width 0.1143)
		(layer "In5.Cu")
		(net "P5E_PEX1_STN1_RX_DN<25>")
	)
	(segment
		(start 157.263084 -142.023084)
		(end 157.399228 -141.54658)
		(width 0.1651)
		(layer "In5.Cu")
		(net "P5E_PEX1_STN1_RX_DN<25>")
	)
	(segment
		(start 166.84752 -122.133106)
		(end 167.308022 -121.949718)
		(width 0.1651)
		(layer "In5.Cu")
		(net "P5E_PEX1_STN1_RX_DN<25>")
	)
	(segment
		(start 164.066728 -124.224796)
		(end 164.43325 -123.892056)
		(width 0.1651)
		(layer "In5.Cu")
		(net "P5E_PEX1_STN1_RX_DN<25>")
	)
	(segment
		(start 164.058854 -124.38634)
		(end 164.066728 -124.224796)
		(width 0.1651)
		(layer "In5.Cu")
		(net "P5E_PEX1_STN1_RX_DN<25>")
	)
	(segment
		(start 160.722564 -127.914146)
		(end 161.031682 -127.526542)
		(width 0.1651)
		(layer "In5.Cu")
		(net "P5E_PEX1_STN1_RX_DN<25>")
	)
	(segment
		(start 161.031682 -127.526542)
		(end 161.013648 -127.366014)
		(width 0.1651)
		(layer "In5.Cu")
		(net "P5E_PEX1_STN1_RX_DN<25>")
	)
	(segment
		(start 166.23919 -122.25274)
		(end 166.699184 -122.069352)
		(width 0.1651)
		(layer "In5.Cu")
		(net "P5E_PEX1_STN1_RX_DN<25>")
	)
	(segment
		(start 165.872668 -122.58548)
		(end 166.23919 -122.25274)
		(width 0.1651)
		(layer "In5.Cu")
		(net "P5E_PEX1_STN1_RX_DN<25>")
	)
	(segment
		(start 165.33622 -123.072398)
		(end 165.497764 -123.080018)
		(width 0.1651)
		(layer "In5.Cu")
		(net "P5E_PEX1_STN1_RX_DN<25>")
	)
	(segment
		(start 162.082734 -126.025656)
		(end 162.62731 -125.531372)
		(width 0.1651)
		(layer "In5.Cu")
		(net "P5E_PEX1_STN1_RX_DN<25>")
	)
	(segment
		(start 165.497764 -123.080018)
		(end 165.864794 -122.747024)
		(width 0.1651)
		(layer "In5.Cu")
		(net "P5E_PEX1_STN1_RX_DN<25>")
	)
	(segment
		(start 163.53028 -124.711714)
		(end 163.691824 -124.719334)
		(width 0.1651)
		(layer "In5.Cu")
		(net "P5E_PEX1_STN1_RX_DN<25>")
	)
	(segment
		(start 164.961824 -123.566682)
		(end 164.969698 -123.405138)
		(width 0.1651)
		(layer "In5.Cu")
		(net "P5E_PEX1_STN1_RX_DN<25>")
	)
	(segment
		(start 161.48304 -126.960884)
		(end 161.792158 -126.57328)
		(width 0.1651)
		(layer "In5.Cu")
		(net "P5E_PEX1_STN1_RX_DN<25>")
	)
	(segment
		(start 184.299606 -274.999704)
		(end 184.299606 -275.26488)
		(width 0.1143)
		(layer "In5.Cu")
		(net "P5E_PEX1_STN1_RX_DN<25>")
	)
	(segment
		(start 160.024572 -128.605788)
		(end 160.561782 -127.93218)
		(width 0.1651)
		(layer "In5.Cu")
		(net "P5E_PEX1_STN1_RX_DN<25>")
	)
	(segment
		(start 157.399228 -141.54658)
		(end 157.320742 -141.405356)
		(width 0.1651)
		(layer "In5.Cu")
		(net "P5E_PEX1_STN1_RX_DN<25>")
	)
	(segment
		(start 164.969698 -123.405138)
		(end 165.33622 -123.072398)
		(width 0.1651)
		(layer "In5.Cu")
		(net "P5E_PEX1_STN1_RX_DN<25>")
	)
	(segment
		(start 158.296864 -137.99439)
		(end 159.864552 -128.970024)
		(width 0.1651)
		(layer "In5.Cu")
		(net "P5E_PEX1_STN1_RX_DN<25>")
	)
	(segment
		(start 165.864794 -122.747024)
		(end 165.872668 -122.58548)
		(width 0.1651)
		(layer "In5.Cu")
		(net "P5E_PEX1_STN1_RX_DN<25>")
	)
	(segment
		(start 162.62731 -125.531372)
		(end 162.788854 -125.538992)
		(width 0.1651)
		(layer "In5.Cu")
		(net "P5E_PEX1_STN1_RX_DN<25>")
	)
	(segment
		(start 167.371776 -121.800874)
		(end 167.886634 -121.595642)
		(width 0.1651)
		(layer "In5.Cu")
		(net "P5E_PEX1_STN1_RX_DN<25>")
	)
	(segment
		(start 154.645614 -145.714212)
		(end 156.93136 -142.766034)
		(width 0.1651)
		(layer "In5.Cu")
		(net "P5E_PEX1_STN1_RX_DN<25>")
	)
	(segment
		(start 154.234896 -147.294346)
		(end 154.645614 -145.714212)
		(width 0.1651)
		(layer "In5.Cu")
		(net "P5E_PEX1_STN1_RX_DN<25>")
	)
	(segment
		(start 164.594794 -123.899676)
		(end 164.961824 -123.566682)
		(width 0.1651)
		(layer "In5.Cu")
		(net "P5E_PEX1_STN1_RX_DN<25>")
	)
	(segment
		(start 155.78074 -162.364166)
		(end 154.843988 -157.221936)
		(width 0.1651)
		(layer "In5.Cu")
		(net "P5E_PEX1_STN1_RX_DN<25>")
	)
	(segment
		(start 167.308022 -121.949718)
		(end 167.371776 -121.800874)
		(width 0.1651)
		(layer "In5.Cu")
		(net "P5E_PEX1_STN1_RX_DN<25>")
	)
	(segment
		(start 157.320742 -141.405356)
		(end 158.296864 -137.99439)
		(width 0.1651)
		(layer "In5.Cu")
		(net "P5E_PEX1_STN1_RX_DN<25>")
	)
	(segment
		(start 183.965596 -268.037056)
		(end 155.78074 -162.364166)
		(width 0.1651)
		(layer "In5.Cu")
		(net "P5E_PEX1_STN1_RX_DN<25>")
	)
	(segment
		(start 166.699184 -122.069352)
		(end 166.84752 -122.133106)
		(width 0.1651)
		(layer "In5.Cu")
		(net "P5E_PEX1_STN1_RX_DN<25>")
	)
	(segment
		(start 167.886634 -121.595642)
		(end 168.051734 -121.595642)
		(width 0.1651)
		(layer "In5.Cu")
		(net "P5E_PEX1_STN1_RX_DN<25>")
	)
	(segment
		(start 163.163758 -125.044454)
		(end 163.53028 -124.711714)
		(width 0.1651)
		(layer "In5.Cu")
		(net "P5E_PEX1_STN1_RX_DN<25>")
	)
	(segment
		(start 162.788854 -125.538992)
		(end 163.155884 -125.205998)
		(width 0.1651)
		(layer "In5.Cu")
		(net "P5E_PEX1_STN1_RX_DN<25>")
	)
	(segment
		(start 159.864552 -128.970024)
		(end 160.024572 -128.605788)
		(width 0.1651)
		(layer "In5.Cu")
		(net "P5E_PEX1_STN1_RX_DN<25>")
	)
	(segment
		(start 183.965596 -271.773904)
		(end 183.965596 -268.037056)
		(width 0.1651)
		(layer "In5.Cu")
		(net "P5E_PEX1_STN1_RX_DN<25>")
	)
	(segment
		(start 183.965596 -271.802352)
		(end 183.965596 -271.773904)
		(width 0.1143)
		(layer "In5.Cu")
		(net "P5E_PEX1_STN1_RX_DN<25>")
	)
	(segment
		(start 157.121352 -142.10157)
		(end 157.263084 -142.023084)
		(width 0.1651)
		(layer "In5.Cu")
		(net "P5E_PEX1_STN1_RX_DN<25>")
	)
	(segment
		(start 161.77387 -126.412752)
		(end 162.082734 -126.025656)
		(width 0.1651)
		(layer "In5.Cu")
		(net "P5E_PEX1_STN1_RX_DN<25>")
	)
	(segment
		(start 183.919876 -275.276056)
		(end 183.919876 -271.848072)
		(width 0.1143)
		(layer "In5.Cu")
		(net "P5E_PEX1_STN1_RX_DN<25>")
	)
	(segment
		(start 154.843988 -157.221936)
		(end 154.234896 -147.294346)
		(width 0.1651)
		(layer "In5.Cu")
		(net "P5E_PEX1_STN1_RX_DN<25>")
	)
	(segment
		(start 184.023254 -275.379434)
		(end 183.919876 -275.276056)
		(width 0.1143)
		(layer "In5.Cu")
		(net "P5E_PEX1_STN1_RX_DN<25>")
	)
	(segment
		(start 164.43325 -123.892056)
		(end 164.594794 -123.899676)
		(width 0.1651)
		(layer "In5.Cu")
		(net "P5E_PEX1_STN1_RX_DN<25>")
	)
	(segment
		(start 168.051734 -121.595642)
		(end 168.342564 -121.886472)
		(width 0.1651)
		(layer "In5.Cu")
		(net "P5E_PEX1_STN1_RX_DN<25>")
	)
	(segment
		(start 163.155884 -125.205998)
		(end 163.163758 -125.044454)
		(width 0.1651)
		(layer "In5.Cu")
		(net "P5E_PEX1_STN1_RX_DN<25>")
	)
	(segment
		(start 184.185052 -275.379434)
		(end 184.023254 -275.379434)
		(width 0.1143)
		(layer "In5.Cu")
		(net "P5E_PEX1_STN1_RX_DN<25>")
	)
	(segment
		(start 156.93136 -142.766034)
		(end 157.121352 -142.10157)
		(width 0.1651)
		(layer "In5.Cu")
		(net "P5E_PEX1_STN1_RX_DN<25>")
	)
	(segment
		(start 128.270508 -345.465146)
		(end 127.975868 -345.170506)
		(width 0.13462)
		(layer "F.Cu")
		(net "P5E_PEX1_STN6_TX_C_DN<96>")
	)
	(segment
		(start 127.975868 -345.170506)
		(end 127.975868 -344.539062)
		(width 0.13462)
		(layer "F.Cu")
		(net "P5E_PEX1_STN6_TX_C_DN<96>")
	)
	(segment
		(start 127.975868 -344.539062)
		(end 128.295908 -344.219022)
		(width 0.13462)
		(layer "F.Cu")
		(net "P5E_PEX1_STN6_TX_C_DN<96>")
	)
	(segment
		(start 131.310126 -384.20802)
		(end 131.43738 -384.080766)
		(width 0.1651)
		(layer "In7.Cu")
		(net "P5E_PEX1_STN6_TX_C_DN<96>")
	)
	(segment
		(start 126.801372 -360.145838)
		(end 126.425198 -358.906064)
		(width 0.1651)
		(layer "In7.Cu")
		(net "P5E_PEX1_STN6_TX_C_DN<96>")
	)
	(segment
		(start 131.310126 -384.590036)
		(end 131.310126 -384.20802)
		(width 0.1651)
		(layer "In7.Cu")
		(net "P5E_PEX1_STN6_TX_C_DN<96>")
	)
	(segment
		(start 127.979678 -346.477082)
		(end 127.979678 -345.755976)
		(width 0.1651)
		(layer "In7.Cu")
		(net "P5E_PEX1_STN6_TX_C_DN<96>")
	)
	(segment
		(start 131.43738 -384.080766)
		(end 131.786122 -384.080766)
		(width 0.1651)
		(layer "In7.Cu")
		(net "P5E_PEX1_STN6_TX_C_DN<96>")
	)
	(segment
		(start 132.36956 -383.497328)
		(end 132.36956 -368.479324)
		(width 0.1651)
		(layer "In7.Cu")
		(net "P5E_PEX1_STN6_TX_C_DN<96>")
	)
	(segment
		(start 126.425198 -358.906064)
		(end 126.425198 -348.031562)
		(width 0.1651)
		(layer "In7.Cu")
		(net "P5E_PEX1_STN6_TX_C_DN<96>")
	)
	(segment
		(start 132.36956 -368.479324)
		(end 126.801372 -360.145838)
		(width 0.1651)
		(layer "In7.Cu")
		(net "P5E_PEX1_STN6_TX_C_DN<96>")
	)
	(segment
		(start 127.979678 -345.755976)
		(end 128.270508 -345.465146)
		(width 0.1651)
		(layer "In7.Cu")
		(net "P5E_PEX1_STN6_TX_C_DN<96>")
	)
	(segment
		(start 126.425198 -348.031562)
		(end 127.979678 -346.477082)
		(width 0.1651)
		(layer "In7.Cu")
		(net "P5E_PEX1_STN6_TX_C_DN<96>")
	)
	(segment
		(start 131.786122 -384.080766)
		(end 132.36956 -383.497328)
		(width 0.1651)
		(layer "In7.Cu")
		(net "P5E_PEX1_STN6_TX_C_DN<96>")
	)
	(segment
		(start 284.442662 -104.71277)
		(end 284.146752 -105.00868)
		(width 0.13462)
		(layer "F.Cu")
		(net "P5E_PEX2_STN1_RX_DP<19>")
	)
	(segment
		(start 283.32176 -104.845104)
		(end 282.842462 -104.845104)
		(width 0.13462)
		(layer "F.Cu")
		(net "P5E_PEX2_STN1_RX_DP<19>")
	)
	(segment
		(start 284.146752 -105.00868)
		(end 283.485336 -105.00868)
		(width 0.13462)
		(layer "F.Cu")
		(net "P5E_PEX2_STN1_RX_DP<19>")
	)
	(segment
		(start 283.485336 -105.00868)
		(end 283.32176 -104.845104)
		(width 0.13462)
		(layer "F.Cu")
		(net "P5E_PEX2_STN1_RX_DP<19>")
	)
	(segment
		(start 294.12946 -275.355304)
		(end 294.344344 -275.570188)
		(width 0.1143)
		(layer "In5.Cu")
		(net "P5E_PEX2_STN1_RX_DP<19>")
	)
	(segment
		(start 294.344344 -275.570188)
		(end 294.585136 -275.570188)
		(width 0.1143)
		(layer "In5.Cu")
		(net "P5E_PEX2_STN1_RX_DP<19>")
	)
	(segment
		(start 269.696438 -119.163592)
		(end 268.385036 -120.760236)
		(width 0.1651)
		(layer "In5.Cu")
		(net "P5E_PEX2_STN1_RX_DP<19>")
	)
	(segment
		(start 265.603482 -122.76328)
		(end 264.923778 -126.351538)
		(width 0.1651)
		(layer "In5.Cu")
		(net "P5E_PEX2_STN1_RX_DP<19>")
	)
	(segment
		(start 283.603192 -105.0036)
		(end 277.234396 -108.444538)
		(width 0.1651)
		(layer "In5.Cu")
		(net "P5E_PEX2_STN1_RX_DP<19>")
	)
	(segment
		(start 294.08374 -269.528544)
		(end 294.08374 -271.570958)
		(width 0.1651)
		(layer "In5.Cu")
		(net "P5E_PEX2_STN1_RX_DP<19>")
	)
	(segment
		(start 294.699436 -275.684488)
		(end 294.699436 -275.949918)
		(width 0.1143)
		(layer "In5.Cu")
		(net "P5E_PEX2_STN1_RX_DP<19>")
	)
	(segment
		(start 263.58469 -154.627072)
		(end 263.716008 -156.689806)
		(width 0.1651)
		(layer "In5.Cu")
		(net "P5E_PEX2_STN1_RX_DP<19>")
	)
	(segment
		(start 263.32053 -150.48357)
		(end 263.584436 -154.627072)
		(width 0.1651)
		(layer "In5.Cu")
		(net "P5E_PEX2_STN1_RX_DP<19>")
	)
	(segment
		(start 277.234396 -108.444538)
		(end 272.857976 -112.68202)
		(width 0.1651)
		(layer "In5.Cu")
		(net "P5E_PEX2_STN1_RX_DP<19>")
	)
	(segment
		(start 294.585136 -275.570188)
		(end 294.699436 -275.684488)
		(width 0.1143)
		(layer "In5.Cu")
		(net "P5E_PEX2_STN1_RX_DP<19>")
	)
	(segment
		(start 263.716008 -156.69006)
		(end 263.848596 -158.768034)
		(width 0.1651)
		(layer "In5.Cu")
		(net "P5E_PEX2_STN1_RX_DP<19>")
	)
	(segment
		(start 263.584436 -154.627072)
		(end 263.58469 -154.627072)
		(width 0.1651)
		(layer "In5.Cu")
		(net "P5E_PEX2_STN1_RX_DP<19>")
	)
	(segment
		(start 284.442662 -104.71277)
		(end 284.151832 -105.0036)
		(width 0.1651)
		(layer "In5.Cu")
		(net "P5E_PEX2_STN1_RX_DP<19>")
	)
	(segment
		(start 263.848596 -158.768034)
		(end 264.94994 -165.18255)
		(width 0.1651)
		(layer "In5.Cu")
		(net "P5E_PEX2_STN1_RX_DP<19>")
	)
	(segment
		(start 263.716008 -156.689806)
		(end 263.715754 -156.689806)
		(width 0.1651)
		(layer "In5.Cu")
		(net "P5E_PEX2_STN1_RX_DP<19>")
	)
	(segment
		(start 268.385036 -120.760236)
		(end 266.349226 -121.856246)
		(width 0.1651)
		(layer "In5.Cu")
		(net "P5E_PEX2_STN1_RX_DP<19>")
	)
	(segment
		(start 272.857976 -112.68202)
		(end 269.696438 -119.163592)
		(width 0.1651)
		(layer "In5.Cu")
		(net "P5E_PEX2_STN1_RX_DP<19>")
	)
	(segment
		(start 266.349226 -121.856246)
		(end 265.603482 -122.76328)
		(width 0.1651)
		(layer "In5.Cu")
		(net "P5E_PEX2_STN1_RX_DP<19>")
	)
	(segment
		(start 284.151832 -105.0036)
		(end 283.603192 -105.0036)
		(width 0.1651)
		(layer "In5.Cu")
		(net "P5E_PEX2_STN1_RX_DP<19>")
	)
	(segment
		(start 264.923778 -126.351538)
		(end 263.32053 -150.48357)
		(width 0.1651)
		(layer "In5.Cu")
		(net "P5E_PEX2_STN1_RX_DP<19>")
	)
	(segment
		(start 294.08374 -271.570958)
		(end 294.08374 -271.599406)
		(width 0.1143)
		(layer "In5.Cu")
		(net "P5E_PEX2_STN1_RX_DP<19>")
	)
	(segment
		(start 294.08374 -271.599406)
		(end 294.12946 -271.645126)
		(width 0.1143)
		(layer "In5.Cu")
		(net "P5E_PEX2_STN1_RX_DP<19>")
	)
	(segment
		(start 263.715754 -156.689806)
		(end 263.716008 -156.69006)
		(width 0.1651)
		(layer "In5.Cu")
		(net "P5E_PEX2_STN1_RX_DP<19>")
	)
	(segment
		(start 264.94994 -165.18255)
		(end 294.08374 -269.528544)
		(width 0.1651)
		(layer "In5.Cu")
		(net "P5E_PEX2_STN1_RX_DP<19>")
	)
	(segment
		(start 294.12946 -271.645126)
		(end 294.12946 -275.355304)
		(width 0.1143)
		(layer "In5.Cu")
		(net "P5E_PEX2_STN1_RX_DP<19>")
	)
	(segment
		(start 385.483862 -321.863974)
		(end 385.483862 -318.950848)
		(width 0.1651)
		(layer "In9.Cu")
		(net "P5E_PEX3_STN7_RX_DN<122>")
	)
	(segment
		(start 429.794162 -341.766398)
		(end 429.601376 -341.48776)
		(width 0.1651)
		(layer "In9.Cu")
		(net "P5E_PEX3_STN7_RX_DN<122>")
	)
	(segment
		(start 425.125642 -368.619786)
		(end 425.06773 -368.469164)
		(width 0.1651)
		(layer "In9.Cu")
		(net "P5E_PEX3_STN7_RX_DN<122>")
	)
	(segment
		(start 428.468028 -360.810302)
		(end 428.668942 -360.357166)
		(width 0.1651)
		(layer "In9.Cu")
		(net "P5E_PEX3_STN7_RX_DN<122>")
	)
	(segment
		(start 385.440682 -316.799722)
		(end 385.149852 -316.799722)
		(width 0.1143)
		(layer "In9.Cu")
		(net "P5E_PEX3_STN7_RX_DN<122>")
	)
	(segment
		(start 428.820072 -360.299254)
		(end 429.020986 -359.846626)
		(width 0.1651)
		(layer "In9.Cu")
		(net "P5E_PEX3_STN7_RX_DN<122>")
	)
	(segment
		(start 425.914566 -366.843564)
		(end 425.914312 -366.843564)
		(width 0.1651)
		(layer "In9.Cu")
		(net "P5E_PEX3_STN7_RX_DN<122>")
	)
	(segment
		(start 425.268644 -368.016028)
		(end 425.419774 -367.958116)
		(width 0.1651)
		(layer "In9.Cu")
		(net "P5E_PEX3_STN7_RX_DN<122>")
	)
	(segment
		(start 425.914312 -366.843564)
		(end 426.115226 -366.390936)
		(width 0.1651)
		(layer "In9.Cu")
		(net "P5E_PEX3_STN7_RX_DN<122>")
	)
	(segment
		(start 426.115226 -366.390936)
		(end 426.11548 -366.390936)
		(width 0.1651)
		(layer "In9.Cu")
		(net "P5E_PEX3_STN7_RX_DN<122>")
	)
	(segment
		(start 428.668942 -360.357166)
		(end 428.820072 -360.299254)
		(width 0.1651)
		(layer "In9.Cu")
		(net "P5E_PEX3_STN7_RX_DN<122>")
	)
	(segment
		(start 428.062136 -362.00588)
		(end 428.023528 -361.905296)
		(width 0.1651)
		(layer "In9.Cu")
		(net "P5E_PEX3_STN7_RX_DN<122>")
	)
	(segment
		(start 428.023528 -361.905296)
		(end 428.224696 -361.452414)
		(width 0.1651)
		(layer "In9.Cu")
		(net "P5E_PEX3_STN7_RX_DN<122>")
	)
	(segment
		(start 429.31461 -359.184956)
		(end 429.794162 -358.105202)
		(width 0.1651)
		(layer "In9.Cu")
		(net "P5E_PEX3_STN7_RX_DN<122>")
	)
	(segment
		(start 423.495216 -339.20176)
		(end 408.095704 -331.940916)
		(width 0.1651)
		(layer "In9.Cu")
		(net "P5E_PEX3_STN7_RX_DN<122>")
	)
	(segment
		(start 428.526194 -360.961178)
		(end 428.468028 -360.810302)
		(width 0.1651)
		(layer "In9.Cu")
		(net "P5E_PEX3_STN7_RX_DN<122>")
	)
	(segment
		(start 385.483862 -318.950848)
		(end 385.483862 -318.9224)
		(width 0.1143)
		(layer "In9.Cu")
		(net "P5E_PEX3_STN7_RX_DN<122>")
	)
	(segment
		(start 386.428996 -324.146164)
		(end 385.483862 -321.863974)
		(width 0.1651)
		(layer "In9.Cu")
		(net "P5E_PEX3_STN7_RX_DN<122>")
	)
	(segment
		(start 429.314864 -359.184956)
		(end 429.31461 -359.184956)
		(width 0.1651)
		(layer "In9.Cu")
		(net "P5E_PEX3_STN7_RX_DN<122>")
	)
	(segment
		(start 429.163734 -359.242868)
		(end 429.314864 -359.184956)
		(width 0.1651)
		(layer "In9.Cu")
		(net "P5E_PEX3_STN7_RX_DN<122>")
	)
	(segment
		(start 425.620688 -367.505488)
		(end 425.562522 -367.354612)
		(width 0.1651)
		(layer "In9.Cu")
		(net "P5E_PEX3_STN7_RX_DN<122>")
	)
	(segment
		(start 425.562522 -367.354612)
		(end 425.763436 -366.90173)
		(width 0.1651)
		(layer "In9.Cu")
		(net "P5E_PEX3_STN7_RX_DN<122>")
	)
	(segment
		(start 385.483862 -318.9224)
		(end 385.529582 -318.87668)
		(width 0.1143)
		(layer "In9.Cu")
		(net "P5E_PEX3_STN7_RX_DN<122>")
	)
	(segment
		(start 426.409358 -365.729012)
		(end 426.409104 -365.729012)
		(width 0.1651)
		(layer "In9.Cu")
		(net "P5E_PEX3_STN7_RX_DN<122>")
	)
	(segment
		(start 424.764962 -369.432586)
		(end 425.125642 -368.619786)
		(width 0.1651)
		(layer "In9.Cu")
		(net "P5E_PEX3_STN7_RX_DN<122>")
	)
	(segment
		(start 429.020986 -359.846626)
		(end 428.96282 -359.696004)
		(width 0.1651)
		(layer "In9.Cu")
		(net "P5E_PEX3_STN7_RX_DN<122>")
	)
	(segment
		(start 408.095704 -331.940916)
		(end 388.75843 -325.81977)
		(width 0.1651)
		(layer "In9.Cu")
		(net "P5E_PEX3_STN7_RX_DN<122>")
	)
	(segment
		(start 425.763436 -366.90173)
		(end 425.914566 -366.843564)
		(width 0.1651)
		(layer "In9.Cu")
		(net "P5E_PEX3_STN7_RX_DN<122>")
	)
	(segment
		(start 426.11548 -366.390936)
		(end 426.057314 -366.24006)
		(width 0.1651)
		(layer "In9.Cu")
		(net "P5E_PEX3_STN7_RX_DN<122>")
	)
	(segment
		(start 429.601376 -341.48776)
		(end 423.495216 -339.20176)
		(width 0.1651)
		(layer "In9.Cu")
		(net "P5E_PEX3_STN7_RX_DN<122>")
	)
	(segment
		(start 425.620434 -367.505488)
		(end 425.620688 -367.505488)
		(width 0.1651)
		(layer "In9.Cu")
		(net "P5E_PEX3_STN7_RX_DN<122>")
	)
	(segment
		(start 388.75843 -325.81977)
		(end 386.428996 -324.146164)
		(width 0.1651)
		(layer "In9.Cu")
		(net "P5E_PEX3_STN7_RX_DN<122>")
	)
	(segment
		(start 426.258228 -365.787178)
		(end 426.409358 -365.729012)
		(width 0.1651)
		(layer "In9.Cu")
		(net "P5E_PEX3_STN7_RX_DN<122>")
	)
	(segment
		(start 428.96282 -359.696004)
		(end 429.163734 -359.242868)
		(width 0.1651)
		(layer "In9.Cu")
		(net "P5E_PEX3_STN7_RX_DN<122>")
	)
	(segment
		(start 423.889932 -382.18999)
		(end 423.889932 -382.572006)
		(width 0.1651)
		(layer "In9.Cu")
		(net "P5E_PEX3_STN7_RX_DN<122>")
	)
	(segment
		(start 424.016932 -382.699006)
		(end 424.238928 -382.699006)
		(width 0.1651)
		(layer "In9.Cu")
		(net "P5E_PEX3_STN7_RX_DN<122>")
	)
	(segment
		(start 425.06773 -368.469164)
		(end 425.268644 -368.016028)
		(width 0.1651)
		(layer "In9.Cu")
		(net "P5E_PEX3_STN7_RX_DN<122>")
	)
	(segment
		(start 425.419774 -367.958116)
		(end 425.41952 -367.957862)
		(width 0.1651)
		(layer "In9.Cu")
		(net "P5E_PEX3_STN7_RX_DN<122>")
	)
	(segment
		(start 428.32528 -361.413806)
		(end 428.526194 -360.961178)
		(width 0.1651)
		(layer "In9.Cu")
		(net "P5E_PEX3_STN7_RX_DN<122>")
	)
	(segment
		(start 423.889932 -382.572006)
		(end 424.016932 -382.699006)
		(width 0.1651)
		(layer "In9.Cu")
		(net "P5E_PEX3_STN7_RX_DN<122>")
	)
	(segment
		(start 426.057314 -366.24006)
		(end 426.258228 -365.787178)
		(width 0.1651)
		(layer "In9.Cu")
		(net "P5E_PEX3_STN7_RX_DN<122>")
	)
	(segment
		(start 426.409104 -365.729012)
		(end 428.062136 -362.00588)
		(width 0.1651)
		(layer "In9.Cu")
		(net "P5E_PEX3_STN7_RX_DN<122>")
	)
	(segment
		(start 429.794162 -358.105202)
		(end 429.794162 -341.766398)
		(width 0.1651)
		(layer "In9.Cu")
		(net "P5E_PEX3_STN7_RX_DN<122>")
	)
	(segment
		(start 385.529582 -318.87668)
		(end 385.529582 -316.888622)
		(width 0.1143)
		(layer "In9.Cu")
		(net "P5E_PEX3_STN7_RX_DN<122>")
	)
	(segment
		(start 424.764962 -382.172972)
		(end 424.764962 -369.432586)
		(width 0.1651)
		(layer "In9.Cu")
		(net "P5E_PEX3_STN7_RX_DN<122>")
	)
	(segment
		(start 425.41952 -367.957862)
		(end 425.620434 -367.505488)
		(width 0.1651)
		(layer "In9.Cu")
		(net "P5E_PEX3_STN7_RX_DN<122>")
	)
	(segment
		(start 424.238928 -382.699006)
		(end 424.764962 -382.172972)
		(width 0.1651)
		(layer "In9.Cu")
		(net "P5E_PEX3_STN7_RX_DN<122>")
	)
	(segment
		(start 385.529582 -316.888622)
		(end 385.440682 -316.799722)
		(width 0.1143)
		(layer "In9.Cu")
		(net "P5E_PEX3_STN7_RX_DN<122>")
	)
	(segment
		(start 428.224696 -361.452414)
		(end 428.32528 -361.413806)
		(width 0.1651)
		(layer "In9.Cu")
		(net "P5E_PEX3_STN7_RX_DN<122>")
	)
	(segment
		(start 407.695146 -103.814372)
		(end 412.206694 -103.814372)
		(width 0.13208)
		(layer "F.Cu")
		(net "NCSI_NIC7_TXD0")
	)
	(segment
		(start 414.435798 -102.609904)
		(end 414.435798 -102.606094)
		(width 0.13208)
		(layer "F.Cu")
		(net "NCSI_NIC7_TXD0")
	)
	(segment
		(start 415.201862 -101.84003)
		(end 416.95751 -101.84003)
		(width 0.13208)
		(layer "F.Cu")
		(net "NCSI_NIC7_TXD0")
	)
	(segment
		(start 412.206694 -103.814372)
		(end 413.23133 -103.814372)
		(width 0.13208)
		(layer "F.Cu")
		(net "NCSI_NIC7_TXD0")
	)
	(segment
		(start 414.435798 -102.606094)
		(end 415.201862 -101.84003)
		(width 0.13208)
		(layer "F.Cu")
		(net "NCSI_NIC7_TXD0")
	)
	(segment
		(start 413.23133 -103.814372)
		(end 414.435798 -102.609904)
		(width 0.13208)
		(layer "F.Cu")
		(net "NCSI_NIC7_TXD0")
	)
	(via
		(at 412.206694 -103.814372)
		(size 0.762)
		(drill 0.381)
		(layers "F.Cu" "B.Cu")
		(net "NCSI_NIC7_TXD0")
	)
	(segment
		(start 68.65747 -130.6449)
		(end 68.169536 -130.6449)
		(width 0.13462)
		(layer "F.Cu")
		(net "P5E_PEX0_STN0_RX_DP<4>")
	)
	(segment
		(start 67.352418 -130.482086)
		(end 67.05727 -130.777234)
		(width 0.13462)
		(layer "F.Cu")
		(net "P5E_PEX0_STN0_RX_DP<4>")
	)
	(segment
		(start 68.169536 -130.6449)
		(end 68.006722 -130.482086)
		(width 0.13462)
		(layer "F.Cu")
		(net "P5E_PEX0_STN0_RX_DP<4>")
	)
	(segment
		(start 68.006722 -130.482086)
		(end 67.352418 -130.482086)
		(width 0.13462)
		(layer "F.Cu")
		(net "P5E_PEX0_STN0_RX_DP<4>")
	)
	(segment
		(start 71.61657 -132.55244)
		(end 71.178674 -132.3213)
		(width 0.1651)
		(layer "In5.Cu")
		(net "P5E_PEX0_STN0_RX_DP<4>")
	)
	(segment
		(start 95.492062 -269.76578)
		(end 87.072724 -240.959894)
		(width 0.1651)
		(layer "In5.Cu")
		(net "P5E_PEX0_STN0_RX_DP<4>")
	)
	(segment
		(start 68.429632 -130.99796)
		(end 68.382134 -130.843528)
		(width 0.1651)
		(layer "In5.Cu")
		(net "P5E_PEX0_STN0_RX_DP<4>")
	)
	(segment
		(start 75.406504 -135.295894)
		(end 75.037188 -134.965694)
		(width 0.1651)
		(layer "In5.Cu")
		(net "P5E_PEX0_STN0_RX_DP<4>")
	)
	(segment
		(start 72.6948 -133.122162)
		(end 72.256904 -132.891022)
		(width 0.1651)
		(layer "In5.Cu")
		(net "P5E_PEX0_STN0_RX_DP<4>")
	)
	(segment
		(start 85.188298 -232.261156)
		(end 85.790278 -168.33342)
		(width 0.1651)
		(layer "In5.Cu")
		(net "P5E_PEX0_STN0_RX_DP<4>")
	)
	(segment
		(start 69.022214 -131.181856)
		(end 68.867782 -131.229608)
		(width 0.1651)
		(layer "In5.Cu")
		(net "P5E_PEX0_STN0_RX_DP<4>")
	)
	(segment
		(start 73.180702 -133.508242)
		(end 72.742298 -133.276594)
		(width 0.1651)
		(layer "In5.Cu")
		(net "P5E_PEX0_STN0_RX_DP<4>")
	)
	(segment
		(start 79.057246 -140.067284)
		(end 78.318614 -138.195812)
		(width 0.1651)
		(layer "In5.Cu")
		(net "P5E_PEX0_STN0_RX_DP<4>")
	)
	(segment
		(start 81.916778 -148.56206)
		(end 80.674718 -148.26488)
		(width 0.1651)
		(layer "In5.Cu")
		(net "P5E_PEX0_STN0_RX_DP<4>")
	)
	(segment
		(start 72.102472 -132.93852)
		(end 71.664068 -132.706872)
		(width 0.1651)
		(layer "In5.Cu")
		(net "P5E_PEX0_STN0_RX_DP<4>")
	)
	(segment
		(start 87.072724 -240.959894)
		(end 85.188298 -232.261156)
		(width 0.1651)
		(layer "In5.Cu")
		(net "P5E_PEX0_STN0_RX_DP<4>")
	)
	(segment
		(start 80.674718 -148.26488)
		(end 80.212438 -147.778978)
		(width 0.1651)
		(layer "In5.Cu")
		(net "P5E_PEX0_STN0_RX_DP<4>")
	)
	(segment
		(start 72.742298 -133.276594)
		(end 72.6948 -133.122162)
		(width 0.1651)
		(layer "In5.Cu")
		(net "P5E_PEX0_STN0_RX_DP<4>")
	)
	(segment
		(start 85.790278 -168.33342)
		(end 85.424518 -151.55164)
		(width 0.1651)
		(layer "In5.Cu")
		(net "P5E_PEX0_STN0_RX_DP<4>")
	)
	(segment
		(start 83.8962 -283.883862)
		(end 83.924648 -283.883862)
		(width 0.1143)
		(layer "In5.Cu")
		(net "P5E_PEX0_STN0_RX_DP<4>")
	)
	(segment
		(start 77.543914 -137.053066)
		(end 75.568048 -135.287004)
		(width 0.1651)
		(layer "In5.Cu")
		(net "P5E_PEX0_STN0_RX_DP<4>")
	)
	(segment
		(start 79.59979 -284.499812)
		(end 79.86522 -284.499812)
		(width 0.1143)
		(layer "In5.Cu")
		(net "P5E_PEX0_STN0_RX_DP<4>")
	)
	(segment
		(start 72.256904 -132.891022)
		(end 72.102472 -132.93852)
		(width 0.1651)
		(layer "In5.Cu")
		(net "P5E_PEX0_STN0_RX_DP<4>")
	)
	(segment
		(start 79.86522 -284.499812)
		(end 79.97952 -284.385512)
		(width 0.1143)
		(layer "In5.Cu")
		(net "P5E_PEX0_STN0_RX_DP<4>")
	)
	(segment
		(start 93.491558 -275.89226)
		(end 95.39605 -272.49501)
		(width 0.1651)
		(layer "In5.Cu")
		(net "P5E_PEX0_STN0_RX_DP<4>")
	)
	(segment
		(start 85.951822 -283.180536)
		(end 93.491558 -275.89226)
		(width 0.1651)
		(layer "In5.Cu")
		(net "P5E_PEX0_STN0_RX_DP<4>")
	)
	(segment
		(start 75.028044 -134.80415)
		(end 73.798938 -133.7056)
		(width 0.1651)
		(layer "In5.Cu")
		(net "P5E_PEX0_STN0_RX_DP<4>")
	)
	(segment
		(start 85.424518 -151.55164)
		(end 85.122258 -150.85568)
		(width 0.1651)
		(layer "In5.Cu")
		(net "P5E_PEX0_STN0_RX_DP<4>")
	)
	(segment
		(start 79.97952 -284.385512)
		(end 79.97952 -284.173676)
		(width 0.1143)
		(layer "In5.Cu")
		(net "P5E_PEX0_STN0_RX_DP<4>")
	)
	(segment
		(start 80.223614 -283.929582)
		(end 83.85048 -283.929582)
		(width 0.1143)
		(layer "In5.Cu")
		(net "P5E_PEX0_STN0_RX_DP<4>")
	)
	(segment
		(start 71.664068 -132.706872)
		(end 71.61657 -132.55244)
		(width 0.1651)
		(layer "In5.Cu")
		(net "P5E_PEX0_STN0_RX_DP<4>")
	)
	(segment
		(start 69.507608 -131.567682)
		(end 69.46011 -131.412996)
		(width 0.1651)
		(layer "In5.Cu")
		(net "P5E_PEX0_STN0_RX_DP<4>")
	)
	(segment
		(start 67.70624 -130.486404)
		(end 67.3481 -130.486404)
		(width 0.1651)
		(layer "In5.Cu")
		(net "P5E_PEX0_STN0_RX_DP<4>")
	)
	(segment
		(start 68.382134 -130.843528)
		(end 67.70624 -130.486404)
		(width 0.1651)
		(layer "In5.Cu")
		(net "P5E_PEX0_STN0_RX_DP<4>")
	)
	(segment
		(start 71.023988 -132.368798)
		(end 70.585838 -132.137404)
		(width 0.1651)
		(layer "In5.Cu")
		(net "P5E_PEX0_STN0_RX_DP<4>")
	)
	(segment
		(start 78.318614 -138.195812)
		(end 77.543914 -137.053066)
		(width 0.1651)
		(layer "In5.Cu")
		(net "P5E_PEX0_STN0_RX_DP<4>")
	)
	(segment
		(start 70.585838 -132.137404)
		(end 70.53834 -131.982718)
		(width 0.1651)
		(layer "In5.Cu")
		(net "P5E_PEX0_STN0_RX_DP<4>")
	)
	(segment
		(start 83.85048 -283.929582)
		(end 83.8962 -283.883862)
		(width 0.1143)
		(layer "In5.Cu")
		(net "P5E_PEX0_STN0_RX_DP<4>")
	)
	(segment
		(start 79.97952 -284.173676)
		(end 80.223614 -283.929582)
		(width 0.1143)
		(layer "In5.Cu")
		(net "P5E_PEX0_STN0_RX_DP<4>")
	)
	(segment
		(start 75.568048 -135.287004)
		(end 75.406504 -135.295894)
		(width 0.1651)
		(layer "In5.Cu")
		(net "P5E_PEX0_STN0_RX_DP<4>")
	)
	(segment
		(start 83.021678 -149.80666)
		(end 81.916778 -148.56206)
		(width 0.1651)
		(layer "In5.Cu")
		(net "P5E_PEX0_STN0_RX_DP<4>")
	)
	(segment
		(start 70.53834 -131.982718)
		(end 70.100444 -131.751578)
		(width 0.1651)
		(layer "In5.Cu")
		(net "P5E_PEX0_STN0_RX_DP<4>")
	)
	(segment
		(start 68.867782 -131.229608)
		(end 68.429632 -130.99796)
		(width 0.1651)
		(layer "In5.Cu")
		(net "P5E_PEX0_STN0_RX_DP<4>")
	)
	(segment
		(start 69.46011 -131.412996)
		(end 69.022214 -131.181856)
		(width 0.1651)
		(layer "In5.Cu")
		(net "P5E_PEX0_STN0_RX_DP<4>")
	)
	(segment
		(start 67.3481 -130.486404)
		(end 67.05727 -130.777234)
		(width 0.1651)
		(layer "In5.Cu")
		(net "P5E_PEX0_STN0_RX_DP<4>")
	)
	(segment
		(start 75.037188 -134.965694)
		(end 75.028044 -134.80415)
		(width 0.1651)
		(layer "In5.Cu")
		(net "P5E_PEX0_STN0_RX_DP<4>")
	)
	(segment
		(start 71.178674 -132.3213)
		(end 71.023988 -132.368798)
		(width 0.1651)
		(layer "In5.Cu")
		(net "P5E_PEX0_STN0_RX_DP<4>")
	)
	(segment
		(start 80.212438 -147.778978)
		(end 79.057246 -140.067284)
		(width 0.1651)
		(layer "In5.Cu")
		(net "P5E_PEX0_STN0_RX_DP<4>")
	)
	(segment
		(start 73.335134 -133.460744)
		(end 73.180702 -133.508242)
		(width 0.1651)
		(layer "In5.Cu")
		(net "P5E_PEX0_STN0_RX_DP<4>")
	)
	(segment
		(start 95.39605 -272.49501)
		(end 95.492062 -269.76578)
		(width 0.1651)
		(layer "In5.Cu")
		(net "P5E_PEX0_STN0_RX_DP<4>")
	)
	(segment
		(start 84.949538 -283.883862)
		(end 85.951822 -283.180536)
		(width 0.1651)
		(layer "In5.Cu")
		(net "P5E_PEX0_STN0_RX_DP<4>")
	)
	(segment
		(start 69.945758 -131.799076)
		(end 69.507608 -131.567682)
		(width 0.1651)
		(layer "In5.Cu")
		(net "P5E_PEX0_STN0_RX_DP<4>")
	)
	(segment
		(start 73.798938 -133.7056)
		(end 73.335134 -133.460744)
		(width 0.1651)
		(layer "In5.Cu")
		(net "P5E_PEX0_STN0_RX_DP<4>")
	)
	(segment
		(start 85.122258 -150.85568)
		(end 83.021678 -149.80666)
		(width 0.1651)
		(layer "In5.Cu")
		(net "P5E_PEX0_STN0_RX_DP<4>")
	)
	(segment
		(start 70.100444 -131.751578)
		(end 69.945758 -131.799076)
		(width 0.1651)
		(layer "In5.Cu")
		(net "P5E_PEX0_STN0_RX_DP<4>")
	)
	(segment
		(start 83.924648 -283.883862)
		(end 84.949538 -283.883862)
		(width 0.1651)
		(layer "In5.Cu")
		(net "P5E_PEX0_STN0_RX_DP<4>")
	)
	(segment
		(start 169.902124 -123.391676)
		(end 170.196764 -123.686316)
		(width 0.13462)
		(layer "F.Cu")
		(net "P5E_PEX1_STN1_RX_DN<26>")
	)
	(segment
		(start 167.393112 -123.392184)
		(end 169.901616 -123.392184)
		(width 0.13462)
		(layer "F.Cu")
		(net "P5E_PEX1_STN1_RX_DN<26>")
	)
	(segment
		(start 169.901616 -123.392184)
		(end 169.902124 -123.391676)
		(width 0.13462)
		(layer "F.Cu")
		(net "P5E_PEX1_STN1_RX_DN<26>")
	)
	(segment
		(start 166.742364 -123.554998)
		(end 167.230298 -123.554998)
		(width 0.13462)
		(layer "F.Cu")
		(net "P5E_PEX1_STN1_RX_DN<26>")
	)
	(segment
		(start 167.230298 -123.554998)
		(end 167.393112 -123.392184)
		(width 0.13462)
		(layer "F.Cu")
		(net "P5E_PEX1_STN1_RX_DN<26>")
	)
	(segment
		(start 155.51404 -146.275806)
		(end 158.015178 -142.91818)
		(width 0.1651)
		(layer "In5.Cu")
		(net "P5E_PEX1_STN1_RX_DN<26>")
	)
	(segment
		(start 167.139366 -124.060204)
		(end 167.17645 -123.902978)
		(width 0.1651)
		(layer "In5.Cu")
		(net "P5E_PEX1_STN1_RX_DN<26>")
	)
	(segment
		(start 161.32937 -128.959864)
		(end 161.63671 -128.57099)
		(width 0.1651)
		(layer "In5.Cu")
		(net "P5E_PEX1_STN1_RX_DN<26>")
	)
	(segment
		(start 166.560246 -124.283216)
		(end 166.717472 -124.320554)
		(width 0.1651)
		(layer "In5.Cu")
		(net "P5E_PEX1_STN1_RX_DN<26>")
	)
	(segment
		(start 165.063678 -125.340618)
		(end 165.101016 -125.183138)
		(width 0.1651)
		(layer "In5.Cu")
		(net "P5E_PEX1_STN1_RX_DN<26>")
	)
	(segment
		(start 166.717472 -124.320554)
		(end 167.139366 -124.060204)
		(width 0.1651)
		(layer "In5.Cu")
		(net "P5E_PEX1_STN1_RX_DN<26>")
	)
	(segment
		(start 166.13886 -124.543058)
		(end 166.560246 -124.283216)
		(width 0.1651)
		(layer "In5.Cu")
		(net "P5E_PEX1_STN1_RX_DN<26>")
	)
	(segment
		(start 161.63671 -128.57099)
		(end 161.617914 -128.410462)
		(width 0.1651)
		(layer "In5.Cu")
		(net "P5E_PEX1_STN1_RX_DN<26>")
	)
	(segment
		(start 156.666946 -161.883598)
		(end 155.855924 -157.384496)
		(width 0.1651)
		(layer "In5.Cu")
		(net "P5E_PEX1_STN1_RX_DN<26>")
	)
	(segment
		(start 168.608756 -123.509786)
		(end 169.104056 -123.509786)
		(width 0.1651)
		(layer "In5.Cu")
		(net "P5E_PEX1_STN1_RX_DN<26>")
	)
	(segment
		(start 167.17645 -123.902978)
		(end 167.999156 -123.395486)
		(width 0.1651)
		(layer "In5.Cu")
		(net "P5E_PEX1_STN1_RX_DN<26>")
	)
	(segment
		(start 184.91581 -271.773904)
		(end 184.91581 -267.893546)
		(width 0.1651)
		(layer "In5.Cu")
		(net "P5E_PEX1_STN1_RX_DN<26>")
	)
	(segment
		(start 164.484558 -125.56363)
		(end 164.641784 -125.600714)
		(width 0.1651)
		(layer "In5.Cu")
		(net "P5E_PEX1_STN1_RX_DN<26>")
	)
	(segment
		(start 160.393888 -132.245354)
		(end 160.478216 -131.756912)
		(width 0.1651)
		(layer "In5.Cu")
		(net "P5E_PEX1_STN1_RX_DN<26>")
	)
	(segment
		(start 160.384998 -131.624832)
		(end 160.469072 -131.136898)
		(width 0.1651)
		(layer "In5.Cu")
		(net "P5E_PEX1_STN1_RX_DN<26>")
	)
	(segment
		(start 168.494456 -123.395486)
		(end 168.608756 -123.509786)
		(width 0.1651)
		(layer "In5.Cu")
		(net "P5E_PEX1_STN1_RX_DN<26>")
	)
	(segment
		(start 162.392868 -127.614426)
		(end 162.374072 -127.453898)
		(width 0.1651)
		(layer "In5.Cu")
		(net "P5E_PEX1_STN1_RX_DN<26>")
	)
	(segment
		(start 167.999156 -123.395486)
		(end 168.494456 -123.395486)
		(width 0.1651)
		(layer "In5.Cu")
		(net "P5E_PEX1_STN1_RX_DN<26>")
	)
	(segment
		(start 165.679628 -124.960634)
		(end 166.101522 -124.700284)
		(width 0.1651)
		(layer "In5.Cu")
		(net "P5E_PEX1_STN1_RX_DN<26>")
	)
	(segment
		(start 184.91581 -271.802352)
		(end 184.91581 -271.773904)
		(width 0.1143)
		(layer "In5.Cu")
		(net "P5E_PEX1_STN1_RX_DN<26>")
	)
	(segment
		(start 160.601152 -131.04368)
		(end 160.68548 -130.555238)
		(width 0.1651)
		(layer "In5.Cu")
		(net "P5E_PEX1_STN1_RX_DN<26>")
	)
	(segment
		(start 169.104056 -123.509786)
		(end 169.218356 -123.395486)
		(width 0.1651)
		(layer "In5.Cu")
		(net "P5E_PEX1_STN1_RX_DN<26>")
	)
	(segment
		(start 161.925 -128.022096)
		(end 162.085528 -128.0033)
		(width 0.1651)
		(layer "In5.Cu")
		(net "P5E_PEX1_STN1_RX_DN<26>")
	)
	(segment
		(start 184.87009 -273.376136)
		(end 184.87009 -271.848072)
		(width 0.1143)
		(layer "In5.Cu")
		(net "P5E_PEX1_STN1_RX_DN<26>")
	)
	(segment
		(start 162.085528 -128.0033)
		(end 162.392868 -127.614426)
		(width 0.1651)
		(layer "In5.Cu")
		(net "P5E_PEX1_STN1_RX_DN<26>")
	)
	(segment
		(start 184.87009 -271.848072)
		(end 184.91581 -271.802352)
		(width 0.1143)
		(layer "In5.Cu")
		(net "P5E_PEX1_STN1_RX_DN<26>")
	)
	(segment
		(start 155.21051 -147.433538)
		(end 155.51404 -146.275806)
		(width 0.1651)
		(layer "In5.Cu")
		(net "P5E_PEX1_STN1_RX_DN<26>")
	)
	(segment
		(start 185.135266 -273.479514)
		(end 184.973468 -273.479514)
		(width 0.1143)
		(layer "In5.Cu")
		(net "P5E_PEX1_STN1_RX_DN<26>")
	)
	(segment
		(start 162.99942 -126.66218)
		(end 163.66871 -126.066804)
		(width 0.1651)
		(layer "In5.Cu")
		(net "P5E_PEX1_STN1_RX_DN<26>")
	)
	(segment
		(start 161.617914 -128.410462)
		(end 161.925 -128.022096)
		(width 0.1651)
		(layer "In5.Cu")
		(net "P5E_PEX1_STN1_RX_DN<26>")
	)
	(segment
		(start 160.468818 -131.136898)
		(end 160.601152 -131.04368)
		(width 0.1651)
		(layer "In5.Cu")
		(net "P5E_PEX1_STN1_RX_DN<26>")
	)
	(segment
		(start 160.861756 -129.367026)
		(end 161.168842 -128.97866)
		(width 0.1651)
		(layer "In5.Cu")
		(net "P5E_PEX1_STN1_RX_DN<26>")
	)
	(segment
		(start 164.641784 -125.600714)
		(end 165.063678 -125.340618)
		(width 0.1651)
		(layer "In5.Cu")
		(net "P5E_PEX1_STN1_RX_DN<26>")
	)
	(segment
		(start 169.905934 -123.395486)
		(end 170.196764 -123.686316)
		(width 0.1651)
		(layer "In5.Cu")
		(net "P5E_PEX1_STN1_RX_DN<26>")
	)
	(segment
		(start 163.66871 -126.066804)
		(end 164.484558 -125.56363)
		(width 0.1651)
		(layer "In5.Cu")
		(net "P5E_PEX1_STN1_RX_DN<26>")
	)
	(segment
		(start 161.168842 -128.97866)
		(end 161.32937 -128.959864)
		(width 0.1651)
		(layer "In5.Cu")
		(net "P5E_PEX1_STN1_RX_DN<26>")
	)
	(segment
		(start 184.973468 -273.479514)
		(end 184.87009 -273.376136)
		(width 0.1143)
		(layer "In5.Cu")
		(net "P5E_PEX1_STN1_RX_DN<26>")
	)
	(segment
		(start 184.91581 -267.893546)
		(end 156.666946 -161.883598)
		(width 0.1651)
		(layer "In5.Cu")
		(net "P5E_PEX1_STN1_RX_DN<26>")
	)
	(segment
		(start 185.24982 -273.099784)
		(end 185.24982 -273.36496)
		(width 0.1143)
		(layer "In5.Cu")
		(net "P5E_PEX1_STN1_RX_DN<26>")
	)
	(segment
		(start 160.68548 -130.555238)
		(end 160.592262 -130.423158)
		(width 0.1651)
		(layer "In5.Cu")
		(net "P5E_PEX1_STN1_RX_DN<26>")
	)
	(segment
		(start 160.592262 -130.423158)
		(end 160.720786 -129.678176)
		(width 0.1651)
		(layer "In5.Cu")
		(net "P5E_PEX1_STN1_RX_DN<26>")
	)
	(segment
		(start 165.101016 -125.183138)
		(end 165.522402 -124.923296)
		(width 0.1651)
		(layer "In5.Cu")
		(net "P5E_PEX1_STN1_RX_DN<26>")
	)
	(segment
		(start 162.374072 -127.453644)
		(end 162.99942 -126.66218)
		(width 0.1651)
		(layer "In5.Cu")
		(net "P5E_PEX1_STN1_RX_DN<26>")
	)
	(segment
		(start 185.24982 -273.36496)
		(end 185.135266 -273.479514)
		(width 0.1143)
		(layer "In5.Cu")
		(net "P5E_PEX1_STN1_RX_DN<26>")
	)
	(segment
		(start 169.218356 -123.395486)
		(end 169.905934 -123.395486)
		(width 0.1651)
		(layer "In5.Cu")
		(net "P5E_PEX1_STN1_RX_DN<26>")
	)
	(segment
		(start 165.522402 -124.923296)
		(end 165.679628 -124.960634)
		(width 0.1651)
		(layer "In5.Cu")
		(net "P5E_PEX1_STN1_RX_DN<26>")
	)
	(segment
		(start 160.261554 -132.338572)
		(end 160.393888 -132.245354)
		(width 0.1651)
		(layer "In5.Cu")
		(net "P5E_PEX1_STN1_RX_DN<26>")
	)
	(segment
		(start 159.054038 -139.332462)
		(end 160.261554 -132.338572)
		(width 0.1651)
		(layer "In5.Cu")
		(net "P5E_PEX1_STN1_RX_DN<26>")
	)
	(segment
		(start 162.374072 -127.453898)
		(end 162.374072 -127.453644)
		(width 0.1651)
		(layer "In5.Cu")
		(net "P5E_PEX1_STN1_RX_DN<26>")
	)
	(segment
		(start 155.855924 -157.384496)
		(end 155.21051 -147.433538)
		(width 0.1651)
		(layer "In5.Cu")
		(net "P5E_PEX1_STN1_RX_DN<26>")
	)
	(segment
		(start 160.469072 -131.136898)
		(end 160.468818 -131.136898)
		(width 0.1651)
		(layer "In5.Cu")
		(net "P5E_PEX1_STN1_RX_DN<26>")
	)
	(segment
		(start 158.015178 -142.91818)
		(end 159.054038 -139.332462)
		(width 0.1651)
		(layer "In5.Cu")
		(net "P5E_PEX1_STN1_RX_DN<26>")
	)
	(segment
		(start 160.720786 -129.678176)
		(end 160.861756 -129.367026)
		(width 0.1651)
		(layer "In5.Cu")
		(net "P5E_PEX1_STN1_RX_DN<26>")
	)
	(segment
		(start 166.101522 -124.700284)
		(end 166.13886 -124.543058)
		(width 0.1651)
		(layer "In5.Cu")
		(net "P5E_PEX1_STN1_RX_DN<26>")
	)
	(segment
		(start 160.478216 -131.756912)
		(end 160.384998 -131.624832)
		(width 0.1651)
		(layer "In5.Cu")
		(net "P5E_PEX1_STN1_RX_DN<26>")
	)
	(segment
		(start 123.354084 -366.161828)
		(end 123.069858 -366.551718)
		(width 0.1651)
		(layer "In5.Cu")
		(net "P5E_PEX1_STN6_RX_DP<101>")
	)
	(segment
		(start 167.932354 -321.081146)
		(end 167.525954 -321.321176)
		(width 0.1651)
		(layer "In5.Cu")
		(net "P5E_PEX1_STN6_RX_DP<101>")
	)
	(segment
		(start 129.252218 -357.98252)
		(end 129.200402 -358.140508)
		(width 0.1651)
		(layer "In5.Cu")
		(net "P5E_PEX1_STN6_RX_DP<101>")
	)
	(segment
		(start 168.755568 -316.229492)
		(end 168.529762 -316.455298)
		(width 0.1143)
		(layer "In5.Cu")
		(net "P5E_PEX1_STN6_RX_DP<101>")
	)
	(segment
		(start 124.488448 -364.60557)
		(end 124.383038 -364.62208)
		(width 0.1651)
		(layer "In5.Cu")
		(net "P5E_PEX1_STN6_RX_DP<101>")
	)
	(segment
		(start 120.437148 -374.899174)
		(end 120.310148 -374.772174)
		(width 0.1651)
		(layer "In5.Cu")
		(net "P5E_PEX1_STN6_RX_DP<101>")
	)
	(segment
		(start 167.525954 -321.321176)
		(end 155.379674 -328.500486)
		(width 0.1651)
		(layer "In5.Cu")
		(net "P5E_PEX1_STN6_RX_DP<101>")
	)
	(segment
		(start 121.953528 -368.083592)
		(end 121.669302 -368.473482)
		(width 0.1651)
		(layer "In5.Cu")
		(net "P5E_PEX1_STN6_RX_DP<101>")
	)
	(segment
		(start 129.200402 -358.140508)
		(end 124.488448 -364.60557)
		(width 0.1651)
		(layer "In5.Cu")
		(net "P5E_PEX1_STN6_RX_DP<101>")
	)
	(segment
		(start 123.33478 -366.039908)
		(end 123.354084 -366.161828)
		(width 0.1651)
		(layer "In5.Cu")
		(net "P5E_PEX1_STN6_RX_DP<101>")
	)
	(segment
		(start 122.653806 -367.12271)
		(end 122.36958 -367.5126)
		(width 0.1651)
		(layer "In5.Cu")
		(net "P5E_PEX1_STN6_RX_DP<101>")
	)
	(segment
		(start 168.529762 -319.89268)
		(end 168.484042 -319.9384)
		(width 0.1143)
		(layer "In5.Cu")
		(net "P5E_PEX1_STN6_RX_DP<101>")
	)
	(segment
		(start 122.21337 -367.537238)
		(end 121.92889 -367.927382)
		(width 0.1651)
		(layer "In5.Cu")
		(net "P5E_PEX1_STN6_RX_DP<101>")
	)
	(segment
		(start 129.89941 -341.117682)
		(end 129.252218 -342.008206)
		(width 0.1651)
		(layer "In5.Cu")
		(net "P5E_PEX1_STN6_RX_DP<101>")
	)
	(segment
		(start 168.484042 -319.966848)
		(end 168.484042 -320.529458)
		(width 0.1651)
		(layer "In5.Cu")
		(net "P5E_PEX1_STN6_RX_DP<101>")
	)
	(segment
		(start 168.985692 -316.229492)
		(end 168.755568 -316.229492)
		(width 0.1143)
		(layer "In5.Cu")
		(net "P5E_PEX1_STN6_RX_DP<101>")
	)
	(segment
		(start 146.44116 -334.170528)
		(end 129.89941 -341.117682)
		(width 0.1651)
		(layer "In5.Cu")
		(net "P5E_PEX1_STN6_RX_DP<101>")
	)
	(segment
		(start 168.484042 -319.9384)
		(end 168.484042 -319.966848)
		(width 0.1143)
		(layer "In5.Cu")
		(net "P5E_PEX1_STN6_RX_DP<101>")
	)
	(segment
		(start 122.913648 -366.576356)
		(end 122.629168 -366.9665)
		(width 0.1651)
		(layer "In5.Cu")
		(net "P5E_PEX1_STN6_RX_DP<101>")
	)
	(segment
		(start 121.087642 -374.681496)
		(end 120.869964 -374.899174)
		(width 0.1651)
		(layer "In5.Cu")
		(net "P5E_PEX1_STN6_RX_DP<101>")
	)
	(segment
		(start 123.069858 -366.551718)
		(end 122.913648 -366.576356)
		(width 0.1651)
		(layer "In5.Cu")
		(net "P5E_PEX1_STN6_RX_DP<101>")
	)
	(segment
		(start 124.061728 -365.190786)
		(end 123.770136 -365.590836)
		(width 0.1651)
		(layer "In5.Cu")
		(net "P5E_PEX1_STN6_RX_DP<101>")
	)
	(segment
		(start 121.669302 -368.473482)
		(end 121.087642 -369.696238)
		(width 0.1651)
		(layer "In5.Cu")
		(net "P5E_PEX1_STN6_RX_DP<101>")
	)
	(segment
		(start 121.92889 -367.927382)
		(end 121.953528 -368.083592)
		(width 0.1651)
		(layer "In5.Cu")
		(net "P5E_PEX1_STN6_RX_DP<101>")
	)
	(segment
		(start 155.379674 -328.500486)
		(end 146.44116 -334.170528)
		(width 0.1651)
		(layer "In5.Cu")
		(net "P5E_PEX1_STN6_RX_DP<101>")
	)
	(segment
		(start 169.099992 -316.115192)
		(end 168.985692 -316.229492)
		(width 0.1143)
		(layer "In5.Cu")
		(net "P5E_PEX1_STN6_RX_DP<101>")
	)
	(segment
		(start 123.648216 -365.61014)
		(end 123.33478 -366.039908)
		(width 0.1651)
		(layer "In5.Cu")
		(net "P5E_PEX1_STN6_RX_DP<101>")
	)
	(segment
		(start 129.252218 -342.008206)
		(end 129.252218 -357.98252)
		(width 0.1651)
		(layer "In5.Cu")
		(net "P5E_PEX1_STN6_RX_DP<101>")
	)
	(segment
		(start 123.770136 -365.590836)
		(end 123.648216 -365.61014)
		(width 0.1651)
		(layer "In5.Cu")
		(net "P5E_PEX1_STN6_RX_DP<101>")
	)
	(segment
		(start 124.045218 -365.085376)
		(end 124.061728 -365.190786)
		(width 0.1651)
		(layer "In5.Cu")
		(net "P5E_PEX1_STN6_RX_DP<101>")
	)
	(segment
		(start 121.087642 -369.696238)
		(end 121.087642 -374.681496)
		(width 0.1651)
		(layer "In5.Cu")
		(net "P5E_PEX1_STN6_RX_DP<101>")
	)
	(segment
		(start 168.529762 -316.455298)
		(end 168.529762 -319.89268)
		(width 0.1143)
		(layer "In5.Cu")
		(net "P5E_PEX1_STN6_RX_DP<101>")
	)
	(segment
		(start 122.629168 -366.9665)
		(end 122.653806 -367.12271)
		(width 0.1651)
		(layer "In5.Cu")
		(net "P5E_PEX1_STN6_RX_DP<101>")
	)
	(segment
		(start 124.383038 -364.62208)
		(end 124.045218 -365.085376)
		(width 0.1651)
		(layer "In5.Cu")
		(net "P5E_PEX1_STN6_RX_DP<101>")
	)
	(segment
		(start 120.310148 -374.772174)
		(end 120.310148 -374.390158)
		(width 0.1651)
		(layer "In5.Cu")
		(net "P5E_PEX1_STN6_RX_DP<101>")
	)
	(segment
		(start 120.869964 -374.899174)
		(end 120.437148 -374.899174)
		(width 0.1651)
		(layer "In5.Cu")
		(net "P5E_PEX1_STN6_RX_DP<101>")
	)
	(segment
		(start 168.484042 -320.529458)
		(end 167.932354 -321.081146)
		(width 0.1651)
		(layer "In5.Cu")
		(net "P5E_PEX1_STN6_RX_DP<101>")
	)
	(segment
		(start 122.36958 -367.5126)
		(end 122.21337 -367.537238)
		(width 0.1651)
		(layer "In5.Cu")
		(net "P5E_PEX1_STN6_RX_DP<101>")
	)
	(segment
		(start 169.099992 -315.849762)
		(end 169.099992 -316.115192)
		(width 0.1143)
		(layer "In5.Cu")
		(net "P5E_PEX1_STN6_RX_DP<101>")
	)
	(segment
		(start 284.442662 -125.486414)
		(end 284.152848 -125.1966)
		(width 0.13462)
		(layer "F.Cu")
		(net "P5E_PEX2_STN1_RX_DN<27>")
	)
	(segment
		(start 283.323284 -125.355096)
		(end 282.842462 -125.355096)
		(width 0.13462)
		(layer "F.Cu")
		(net "P5E_PEX2_STN1_RX_DN<27>")
	)
	(segment
		(start 284.152848 -125.1966)
		(end 283.48178 -125.1966)
		(width 0.13462)
		(layer "F.Cu")
		(net "P5E_PEX2_STN1_RX_DN<27>")
	)
	(segment
		(start 283.48178 -125.1966)
		(end 283.323284 -125.355096)
		(width 0.13462)
		(layer "F.Cu")
		(net "P5E_PEX2_STN1_RX_DN<27>")
	)
	(segment
		(start 302.023272 -275.379688)
		(end 302.18507 -275.379688)
		(width 0.1143)
		(layer "In5.Cu")
		(net "P5E_PEX2_STN1_RX_DN<27>")
	)
	(segment
		(start 280.510996 -133.232144)
		(end 280.299668 -133.680708)
		(width 0.1651)
		(layer "In5.Cu")
		(net "P5E_PEX2_STN1_RX_DN<27>")
	)
	(segment
		(start 281.431746 -131.705096)
		(end 281.272996 -131.73583)
		(width 0.1651)
		(layer "In5.Cu")
		(net "P5E_PEX2_STN1_RX_DN<27>")
	)
	(segment
		(start 279.054306 -136.452102)
		(end 279.130506 -136.594596)
		(width 0.1651)
		(layer "In5.Cu")
		(net "P5E_PEX2_STN1_RX_DN<27>")
	)
	(segment
		(start 281.678634 -131.135628)
		(end 281.709368 -131.294378)
		(width 0.1651)
		(layer "In5.Cu")
		(net "P5E_PEX2_STN1_RX_DN<27>")
	)
	(segment
		(start 282.503118 -129.415032)
		(end 281.955748 -130.725418)
		(width 0.1651)
		(layer "In5.Cu")
		(net "P5E_PEX2_STN1_RX_DN<27>")
	)
	(segment
		(start 283.408374 -125.612906)
		(end 282.973272 -126.66345)
		(width 0.1651)
		(layer "In5.Cu")
		(net "P5E_PEX2_STN1_RX_DN<27>")
	)
	(segment
		(start 281.272996 -131.73583)
		(end 280.667206 -132.632196)
		(width 0.1651)
		(layer "In5.Cu")
		(net "P5E_PEX2_STN1_RX_DN<27>")
	)
	(segment
		(start 277.92299 -140.56868)
		(end 277.780242 -140.64488)
		(width 0.1651)
		(layer "In5.Cu")
		(net "P5E_PEX2_STN1_RX_DN<27>")
	)
	(segment
		(start 278.421338 -138.928094)
		(end 278.27732 -139.402312)
		(width 0.1651)
		(layer "In5.Cu")
		(net "P5E_PEX2_STN1_RX_DN<27>")
	)
	(segment
		(start 301.919894 -275.27631)
		(end 302.023272 -275.379688)
		(width 0.1143)
		(layer "In5.Cu")
		(net "P5E_PEX2_STN1_RX_DN<27>")
	)
	(segment
		(start 278.27732 -139.402312)
		(end 278.134318 -139.478258)
		(width 0.1651)
		(layer "In5.Cu")
		(net "P5E_PEX2_STN1_RX_DN<27>")
	)
	(segment
		(start 278.134826 -139.478258)
		(end 277.990808 -139.951968)
		(width 0.1651)
		(layer "In5.Cu")
		(net "P5E_PEX2_STN1_RX_DN<27>")
	)
	(segment
		(start 280.667206 -132.632196)
		(end 280.456386 -133.080252)
		(width 0.1651)
		(layer "In5.Cu")
		(net "P5E_PEX2_STN1_RX_DN<27>")
	)
	(segment
		(start 272.280634 -147.588986)
		(end 272.88871 -157.00756)
		(width 0.1651)
		(layer "In5.Cu")
		(net "P5E_PEX2_STN1_RX_DN<27>")
	)
	(segment
		(start 274.434046 -144.095978)
		(end 272.525236 -146.657822)
		(width 0.1651)
		(layer "In5.Cu")
		(net "P5E_PEX2_STN1_RX_DN<27>")
	)
	(segment
		(start 280.299668 -133.680708)
		(end 280.147522 -133.735318)
		(width 0.1651)
		(layer "In5.Cu")
		(net "P5E_PEX2_STN1_RX_DN<27>")
	)
	(segment
		(start 279.780238 -134.78383)
		(end 279.628092 -134.83844)
		(width 0.1651)
		(layer "In5.Cu")
		(net "P5E_PEX2_STN1_RX_DN<27>")
	)
	(segment
		(start 279.991312 -134.33552)
		(end 279.780238 -134.78383)
		(width 0.1651)
		(layer "In5.Cu")
		(net "P5E_PEX2_STN1_RX_DN<27>")
	)
	(segment
		(start 281.955748 -130.725418)
		(end 281.678634 -131.135628)
		(width 0.1651)
		(layer "In5.Cu")
		(net "P5E_PEX2_STN1_RX_DN<27>")
	)
	(segment
		(start 282.652978 -129.353564)
		(end 282.503118 -129.415032)
		(width 0.1651)
		(layer "In5.Cu")
		(net "P5E_PEX2_STN1_RX_DN<27>")
	)
	(segment
		(start 272.525236 -146.657822)
		(end 272.280634 -147.588986)
		(width 0.1651)
		(layer "In5.Cu")
		(net "P5E_PEX2_STN1_RX_DN<27>")
	)
	(segment
		(start 282.782518 -128.746758)
		(end 282.843986 -128.89611)
		(width 0.1651)
		(layer "In5.Cu")
		(net "P5E_PEX2_STN1_RX_DN<27>")
	)
	(segment
		(start 277.640034 -141.106652)
		(end 275.395436 -143.147034)
		(width 0.1651)
		(layer "In5.Cu")
		(net "P5E_PEX2_STN1_RX_DN<27>")
	)
	(segment
		(start 284.151832 -125.195584)
		(end 283.825696 -125.195584)
		(width 0.1651)
		(layer "In5.Cu")
		(net "P5E_PEX2_STN1_RX_DN<27>")
	)
	(segment
		(start 278.775668 -137.761472)
		(end 278.631904 -138.235436)
		(width 0.1651)
		(layer "In5.Cu")
		(net "P5E_PEX2_STN1_RX_DN<27>")
	)
	(segment
		(start 302.29937 -275.265388)
		(end 302.29937 -274.999958)
		(width 0.1143)
		(layer "In5.Cu")
		(net "P5E_PEX2_STN1_RX_DN<27>")
	)
	(segment
		(start 284.442662 -125.486414)
		(end 284.151832 -125.195584)
		(width 0.1651)
		(layer "In5.Cu")
		(net "P5E_PEX2_STN1_RX_DN<27>")
	)
	(segment
		(start 278.843486 -137.145014)
		(end 278.699722 -137.618724)
		(width 0.1651)
		(layer "In5.Cu")
		(net "P5E_PEX2_STN1_RX_DN<27>")
	)
	(segment
		(start 279.628092 -134.83844)
		(end 279.392126 -135.339836)
		(width 0.1651)
		(layer "In5.Cu")
		(net "P5E_PEX2_STN1_RX_DN<27>")
	)
	(segment
		(start 302.18507 -275.379688)
		(end 302.29937 -275.265388)
		(width 0.1143)
		(layer "In5.Cu")
		(net "P5E_PEX2_STN1_RX_DN<27>")
	)
	(segment
		(start 301.965614 -271.570958)
		(end 301.965614 -271.599406)
		(width 0.1143)
		(layer "In5.Cu")
		(net "P5E_PEX2_STN1_RX_DN<27>")
	)
	(segment
		(start 280.456386 -133.080252)
		(end 280.510996 -133.232144)
		(width 0.1651)
		(layer "In5.Cu")
		(net "P5E_PEX2_STN1_RX_DN<27>")
	)
	(segment
		(start 282.973272 -126.66345)
		(end 282.973272 -128.289812)
		(width 0.1651)
		(layer "In5.Cu")
		(net "P5E_PEX2_STN1_RX_DN<27>")
	)
	(segment
		(start 283.825696 -125.195584)
		(end 283.408374 -125.612906)
		(width 0.1651)
		(layer "In5.Cu")
		(net "P5E_PEX2_STN1_RX_DN<27>")
	)
	(segment
		(start 272.88871 -157.00756)
		(end 273.658838 -161.3535)
		(width 0.1651)
		(layer "In5.Cu")
		(net "P5E_PEX2_STN1_RX_DN<27>")
	)
	(segment
		(start 282.843986 -128.89611)
		(end 282.652978 -129.353564)
		(width 0.1651)
		(layer "In5.Cu")
		(net "P5E_PEX2_STN1_RX_DN<27>")
	)
	(segment
		(start 301.965614 -271.599406)
		(end 301.919894 -271.645126)
		(width 0.1143)
		(layer "In5.Cu")
		(net "P5E_PEX2_STN1_RX_DN<27>")
	)
	(segment
		(start 278.699722 -137.618724)
		(end 278.775668 -137.761472)
		(width 0.1651)
		(layer "In5.Cu")
		(net "P5E_PEX2_STN1_RX_DN<27>")
	)
	(segment
		(start 277.990808 -139.951968)
		(end 278.067008 -140.094716)
		(width 0.1651)
		(layer "In5.Cu")
		(net "P5E_PEX2_STN1_RX_DN<27>")
	)
	(segment
		(start 301.919894 -271.645126)
		(end 301.919894 -275.27631)
		(width 0.1143)
		(layer "In5.Cu")
		(net "P5E_PEX2_STN1_RX_DN<27>")
	)
	(segment
		(start 279.936702 -134.183374)
		(end 279.991312 -134.33552)
		(width 0.1651)
		(layer "In5.Cu")
		(net "P5E_PEX2_STN1_RX_DN<27>")
	)
	(segment
		(start 279.392126 -135.339836)
		(end 279.054306 -136.452102)
		(width 0.1651)
		(layer "In5.Cu")
		(net "P5E_PEX2_STN1_RX_DN<27>")
	)
	(segment
		(start 278.631904 -138.235436)
		(end 278.488902 -138.311636)
		(width 0.1651)
		(layer "In5.Cu")
		(net "P5E_PEX2_STN1_RX_DN<27>")
	)
	(segment
		(start 278.134318 -139.478258)
		(end 278.134826 -139.478258)
		(width 0.1651)
		(layer "In5.Cu")
		(net "P5E_PEX2_STN1_RX_DN<27>")
	)
	(segment
		(start 275.395436 -143.147034)
		(end 274.434046 -144.095978)
		(width 0.1651)
		(layer "In5.Cu")
		(net "P5E_PEX2_STN1_RX_DN<27>")
	)
	(segment
		(start 278.986488 -137.068814)
		(end 278.843486 -137.145014)
		(width 0.1651)
		(layer "In5.Cu")
		(net "P5E_PEX2_STN1_RX_DN<27>")
	)
	(segment
		(start 273.658838 -161.3535)
		(end 301.965614 -267.748512)
		(width 0.1651)
		(layer "In5.Cu")
		(net "P5E_PEX2_STN1_RX_DN<27>")
	)
	(segment
		(start 278.489156 -138.311636)
		(end 278.345138 -138.785346)
		(width 0.1651)
		(layer "In5.Cu")
		(net "P5E_PEX2_STN1_RX_DN<27>")
	)
	(segment
		(start 281.709368 -131.294378)
		(end 281.431746 -131.705096)
		(width 0.1651)
		(layer "In5.Cu")
		(net "P5E_PEX2_STN1_RX_DN<27>")
	)
	(segment
		(start 278.488902 -138.311636)
		(end 278.489156 -138.311636)
		(width 0.1651)
		(layer "In5.Cu")
		(net "P5E_PEX2_STN1_RX_DN<27>")
	)
	(segment
		(start 279.130506 -136.594596)
		(end 278.986488 -137.068814)
		(width 0.1651)
		(layer "In5.Cu")
		(net "P5E_PEX2_STN1_RX_DN<27>")
	)
	(segment
		(start 301.965614 -267.748512)
		(end 301.965614 -271.570958)
		(width 0.1651)
		(layer "In5.Cu")
		(net "P5E_PEX2_STN1_RX_DN<27>")
	)
	(segment
		(start 278.345138 -138.785346)
		(end 278.421338 -138.928094)
		(width 0.1651)
		(layer "In5.Cu")
		(net "P5E_PEX2_STN1_RX_DN<27>")
	)
	(segment
		(start 277.780242 -140.64488)
		(end 277.640034 -141.106652)
		(width 0.1651)
		(layer "In5.Cu")
		(net "P5E_PEX2_STN1_RX_DN<27>")
	)
	(segment
		(start 278.067008 -140.094716)
		(end 277.92299 -140.56868)
		(width 0.1651)
		(layer "In5.Cu")
		(net "P5E_PEX2_STN1_RX_DN<27>")
	)
	(segment
		(start 282.973272 -128.289812)
		(end 282.782518 -128.746758)
		(width 0.1651)
		(layer "In5.Cu")
		(net "P5E_PEX2_STN1_RX_DN<27>")
	)
	(segment
		(start 280.147522 -133.735318)
		(end 279.936702 -134.183374)
		(width 0.1651)
		(layer "In5.Cu")
		(net "P5E_PEX2_STN1_RX_DN<27>")
	)
	(segment
		(start 373.35333 -305.51247)
		(end 373.497094 -305.51247)
		(width 0.1651)
		(layer "In9.Cu")
		(net "P5E_PEX3_STN7_RX_DN<113>")
	)
	(segment
		(start 406.249378 -349.342202)
		(end 404.365206 -341.910416)
		(width 0.1651)
		(layer "In9.Cu")
		(net "P5E_PEX3_STN7_RX_DN<113>")
	)
	(segment
		(start 383.96672 -302.170084)
		(end 385.40182 -302.170084)
		(width 0.1143)
		(layer "In9.Cu")
		(net "P5E_PEX3_STN7_RX_DN<113>")
	)
	(segment
		(start 418.34816 -392.450574)
		(end 414.134046 -389.01624)
		(width 0.1651)
		(layer "In9.Cu")
		(net "P5E_PEX3_STN7_RX_DN<113>")
	)
	(segment
		(start 422.85412 -409.38196)
		(end 422.85412 -395.501876)
		(width 0.1651)
		(layer "In9.Cu")
		(net "P5E_PEX3_STN7_RX_DN<113>")
	)
	(segment
		(start 421.816784 -410.080968)
		(end 422.155112 -410.080968)
		(width 0.1651)
		(layer "In9.Cu")
		(net "P5E_PEX3_STN7_RX_DN<113>")
	)
	(segment
		(start 404.365206 -341.910416)
		(end 403.765766 -341.203534)
		(width 0.1651)
		(layer "In9.Cu")
		(net "P5E_PEX3_STN7_RX_DN<113>")
	)
	(segment
		(start 370.898166 -310.017414)
		(end 370.856256 -309.879746)
		(width 0.1651)
		(layer "In9.Cu")
		(net "P5E_PEX3_STN7_RX_DN<113>")
	)
	(segment
		(start 421.689784 -410.207968)
		(end 421.816784 -410.080968)
		(width 0.1651)
		(layer "In9.Cu")
		(net "P5E_PEX3_STN7_RX_DN<113>")
	)
	(segment
		(start 370.101622 -311.507632)
		(end 370.335302 -311.070498)
		(width 0.1651)
		(layer "In9.Cu")
		(net "P5E_PEX3_STN7_RX_DN<113>")
	)
	(segment
		(start 369.964208 -311.549288)
		(end 369.963954 -311.549288)
		(width 0.1651)
		(layer "In9.Cu")
		(net "P5E_PEX3_STN7_RX_DN<113>")
	)
	(segment
		(start 383.892552 -302.215804)
		(end 383.921 -302.215804)
		(width 0.1143)
		(layer "In9.Cu")
		(net "P5E_PEX3_STN7_RX_DN<113>")
	)
	(segment
		(start 371.41912 -308.826662)
		(end 371.652546 -308.390036)
		(width 0.1651)
		(layer "In9.Cu")
		(net "P5E_PEX3_STN7_RX_DN<113>")
	)
	(segment
		(start 383.921 -302.215804)
		(end 383.96672 -302.170084)
		(width 0.1143)
		(layer "In9.Cu")
		(net "P5E_PEX3_STN7_RX_DN<113>")
	)
	(segment
		(start 372.352824 -307.295042)
		(end 372.586758 -306.858162)
		(width 0.1651)
		(layer "In9.Cu")
		(net "P5E_PEX3_STN7_RX_DN<113>")
	)
	(segment
		(start 412.039816 -385.114292)
		(end 410.917644 -376.79757)
		(width 0.1651)
		(layer "In9.Cu")
		(net "P5E_PEX3_STN7_RX_DN<113>")
	)
	(segment
		(start 372.586758 -306.858162)
		(end 372.544848 -306.720494)
		(width 0.1651)
		(layer "In9.Cu")
		(net "P5E_PEX3_STN7_RX_DN<113>")
	)
	(segment
		(start 373.84736 -305.01844)
		(end 374.197372 -304.668174)
		(width 0.1651)
		(layer "In9.Cu")
		(net "P5E_PEX3_STN7_RX_DN<113>")
	)
	(segment
		(start 374.197372 -304.668174)
		(end 374.341136 -304.668174)
		(width 0.1651)
		(layer "In9.Cu")
		(net "P5E_PEX3_STN7_RX_DN<113>")
	)
	(segment
		(start 422.402508 -394.411708)
		(end 421.597074 -393.606274)
		(width 0.1651)
		(layer "In9.Cu")
		(net "P5E_PEX3_STN7_RX_DN<113>")
	)
	(segment
		(start 421.597074 -393.606274)
		(end 418.34816 -392.450574)
		(width 0.1651)
		(layer "In9.Cu")
		(net "P5E_PEX3_STN7_RX_DN<113>")
	)
	(segment
		(start 371.46103 -308.96433)
		(end 371.41912 -308.826662)
		(width 0.1651)
		(layer "In9.Cu")
		(net "P5E_PEX3_STN7_RX_DN<113>")
	)
	(segment
		(start 385.534154 -302.453802)
		(end 385.438142 -302.549814)
		(width 0.1143)
		(layer "In9.Cu")
		(net "P5E_PEX3_STN7_RX_DN<113>")
	)
	(segment
		(start 371.981984 -307.773578)
		(end 372.21541 -307.336952)
		(width 0.1651)
		(layer "In9.Cu")
		(net "P5E_PEX3_STN7_RX_DN<113>")
	)
	(segment
		(start 370.856256 -309.879746)
		(end 370.85651 -309.879746)
		(width 0.1651)
		(layer "In9.Cu")
		(net "P5E_PEX3_STN7_RX_DN<113>")
	)
	(segment
		(start 370.293646 -310.933084)
		(end 370.527072 -310.496204)
		(width 0.1651)
		(layer "In9.Cu")
		(net "P5E_PEX3_STN7_RX_DN<113>")
	)
	(segment
		(start 372.023894 -307.911246)
		(end 371.981984 -307.773578)
		(width 0.1651)
		(layer "In9.Cu")
		(net "P5E_PEX3_STN7_RX_DN<113>")
	)
	(segment
		(start 374.691402 -304.17389)
		(end 375.246392 -303.6189)
		(width 0.1651)
		(layer "In9.Cu")
		(net "P5E_PEX3_STN7_RX_DN<113>")
	)
	(segment
		(start 385.40182 -302.170084)
		(end 385.534154 -302.302418)
		(width 0.1143)
		(layer "In9.Cu")
		(net "P5E_PEX3_STN7_RX_DN<113>")
	)
	(segment
		(start 369.383564 -312.635646)
		(end 369.964208 -311.549288)
		(width 0.1651)
		(layer "In9.Cu")
		(net "P5E_PEX3_STN7_RX_DN<113>")
	)
	(segment
		(start 380.58979 -302.215804)
		(end 383.892552 -302.215804)
		(width 0.1651)
		(layer "In9.Cu")
		(net "P5E_PEX3_STN7_RX_DN<113>")
	)
	(segment
		(start 370.293392 -310.93283)
		(end 370.293646 -310.933084)
		(width 0.1651)
		(layer "In9.Cu")
		(net "P5E_PEX3_STN7_RX_DN<113>")
	)
	(segment
		(start 370.527072 -310.496204)
		(end 370.526818 -310.496204)
		(width 0.1651)
		(layer "In9.Cu")
		(net "P5E_PEX3_STN7_RX_DN<113>")
	)
	(segment
		(start 375.246392 -303.6189)
		(end 376.571256 -303.070006)
		(width 0.1651)
		(layer "In9.Cu")
		(net "P5E_PEX3_STN7_RX_DN<113>")
	)
	(segment
		(start 373.003318 -305.862736)
		(end 373.35333 -305.51247)
		(width 0.1651)
		(layer "In9.Cu")
		(net "P5E_PEX3_STN7_RX_DN<113>")
	)
	(segment
		(start 406.35936 -351.910904)
		(end 406.249378 -349.342202)
		(width 0.1651)
		(layer "In9.Cu")
		(net "P5E_PEX3_STN7_RX_DN<113>")
	)
	(segment
		(start 367.034064 -323.350636)
		(end 367.034064 -318.308736)
		(width 0.1651)
		(layer "In9.Cu")
		(net "P5E_PEX3_STN7_RX_DN<113>")
	)
	(segment
		(start 367.034064 -318.308736)
		(end 369.383564 -312.635646)
		(width 0.1651)
		(layer "In9.Cu")
		(net "P5E_PEX3_STN7_RX_DN<113>")
	)
	(segment
		(start 371.089682 -309.44312)
		(end 371.22735 -309.40121)
		(width 0.1651)
		(layer "In9.Cu")
		(net "P5E_PEX3_STN7_RX_DN<113>")
	)
	(segment
		(start 369.963954 -311.549288)
		(end 370.101622 -311.507632)
		(width 0.1651)
		(layer "In9.Cu")
		(net "P5E_PEX3_STN7_RX_DN<113>")
	)
	(segment
		(start 422.85412 -395.501876)
		(end 422.402508 -394.411708)
		(width 0.1651)
		(layer "In9.Cu")
		(net "P5E_PEX3_STN7_RX_DN<113>")
	)
	(segment
		(start 412.726378 -386.92074)
		(end 412.039816 -385.114292)
		(width 0.1651)
		(layer "In9.Cu")
		(net "P5E_PEX3_STN7_RX_DN<113>")
	)
	(segment
		(start 422.155112 -410.080968)
		(end 422.85412 -409.38196)
		(width 0.1651)
		(layer "In9.Cu")
		(net "P5E_PEX3_STN7_RX_DN<113>")
	)
	(segment
		(start 370.335302 -311.070498)
		(end 370.293392 -310.93283)
		(width 0.1651)
		(layer "In9.Cu")
		(net "P5E_PEX3_STN7_RX_DN<113>")
	)
	(segment
		(start 421.689784 -410.589984)
		(end 421.689784 -410.207968)
		(width 0.1651)
		(layer "In9.Cu")
		(net "P5E_PEX3_STN7_RX_DN<113>")
	)
	(segment
		(start 385.534154 -302.302418)
		(end 385.534154 -302.453802)
		(width 0.1143)
		(layer "In9.Cu")
		(net "P5E_PEX3_STN7_RX_DN<113>")
	)
	(segment
		(start 376.571256 -303.070006)
		(end 379.061726 -302.700182)
		(width 0.1651)
		(layer "In9.Cu")
		(net "P5E_PEX3_STN7_RX_DN<113>")
	)
	(segment
		(start 371.78996 -308.348126)
		(end 372.023894 -307.911246)
		(width 0.1651)
		(layer "In9.Cu")
		(net "P5E_PEX3_STN7_RX_DN<113>")
	)
	(segment
		(start 374.179846 -332.673198)
		(end 368.573304 -327.06691)
		(width 0.1651)
		(layer "In9.Cu")
		(net "P5E_PEX3_STN7_RX_DN<113>")
	)
	(segment
		(start 373.497094 -305.51247)
		(end 373.84736 -305.16195)
		(width 0.1651)
		(layer "In9.Cu")
		(net "P5E_PEX3_STN7_RX_DN<113>")
	)
	(segment
		(start 374.691402 -304.317654)
		(end 374.691402 -304.17389)
		(width 0.1651)
		(layer "In9.Cu")
		(net "P5E_PEX3_STN7_RX_DN<113>")
	)
	(segment
		(start 410.917644 -376.79757)
		(end 406.35936 -351.910904)
		(width 0.1651)
		(layer "In9.Cu")
		(net "P5E_PEX3_STN7_RX_DN<113>")
	)
	(segment
		(start 370.664486 -310.454294)
		(end 370.898166 -310.017414)
		(width 0.1651)
		(layer "In9.Cu")
		(net "P5E_PEX3_STN7_RX_DN<113>")
	)
	(segment
		(start 379.061726 -302.700182)
		(end 380.58979 -302.215804)
		(width 0.1651)
		(layer "In9.Cu")
		(net "P5E_PEX3_STN7_RX_DN<113>")
	)
	(segment
		(start 378.19711 -333.94015)
		(end 374.179846 -332.673198)
		(width 0.1651)
		(layer "In9.Cu")
		(net "P5E_PEX3_STN7_RX_DN<113>")
	)
	(segment
		(start 368.573304 -327.06691)
		(end 367.034064 -323.350636)
		(width 0.1651)
		(layer "In9.Cu")
		(net "P5E_PEX3_STN7_RX_DN<113>")
	)
	(segment
		(start 374.341136 -304.668174)
		(end 374.691402 -304.317654)
		(width 0.1651)
		(layer "In9.Cu")
		(net "P5E_PEX3_STN7_RX_DN<113>")
	)
	(segment
		(start 371.652546 -308.390036)
		(end 371.78996 -308.348126)
		(width 0.1651)
		(layer "In9.Cu")
		(net "P5E_PEX3_STN7_RX_DN<113>")
	)
	(segment
		(start 403.765766 -341.203534)
		(end 397.044672 -338.264246)
		(width 0.1651)
		(layer "In9.Cu")
		(net "P5E_PEX3_STN7_RX_DN<113>")
	)
	(segment
		(start 414.134046 -389.01624)
		(end 412.726378 -386.92074)
		(width 0.1651)
		(layer "In9.Cu")
		(net "P5E_PEX3_STN7_RX_DN<113>")
	)
	(segment
		(start 373.84736 -305.16195)
		(end 373.84736 -305.01844)
		(width 0.1651)
		(layer "In9.Cu")
		(net "P5E_PEX3_STN7_RX_DN<113>")
	)
	(segment
		(start 385.438142 -302.549814)
		(end 385.149852 -302.549814)
		(width 0.1143)
		(layer "In9.Cu")
		(net "P5E_PEX3_STN7_RX_DN<113>")
	)
	(segment
		(start 370.85651 -309.879746)
		(end 371.089936 -309.44312)
		(width 0.1651)
		(layer "In9.Cu")
		(net "P5E_PEX3_STN7_RX_DN<113>")
	)
	(segment
		(start 371.22735 -309.40121)
		(end 371.46103 -308.96433)
		(width 0.1651)
		(layer "In9.Cu")
		(net "P5E_PEX3_STN7_RX_DN<113>")
	)
	(segment
		(start 370.526818 -310.496204)
		(end 370.664486 -310.454294)
		(width 0.1651)
		(layer "In9.Cu")
		(net "P5E_PEX3_STN7_RX_DN<113>")
	)
	(segment
		(start 372.544848 -306.720494)
		(end 373.003318 -305.862736)
		(width 0.1651)
		(layer "In9.Cu")
		(net "P5E_PEX3_STN7_RX_DN<113>")
	)
	(segment
		(start 371.089936 -309.44312)
		(end 371.089682 -309.44312)
		(width 0.1651)
		(layer "In9.Cu")
		(net "P5E_PEX3_STN7_RX_DN<113>")
	)
	(segment
		(start 372.21541 -307.336952)
		(end 372.352824 -307.295042)
		(width 0.1651)
		(layer "In9.Cu")
		(net "P5E_PEX3_STN7_RX_DN<113>")
	)
	(segment
		(start 397.044672 -338.264246)
		(end 378.19711 -333.94015)
		(width 0.1651)
		(layer "In9.Cu")
		(net "P5E_PEX3_STN7_RX_DN<113>")
	)
	(segment
		(start 415.663634 -115.234974)
		(end 415.612834 -115.285774)
		(width 0.13208)
		(layer "F.Cu")
		(net "RST_NIC7_PERST1_R_N")
	)
	(segment
		(start 416.95751 -115.234974)
		(end 415.663634 -115.234974)
		(width 0.13208)
		(layer "F.Cu")
		(net "RST_NIC7_PERST1_R_N")
	)
	(segment
		(start 428.923704 -88.05799)
		(end 428.923704 -87.749126)
		(width 0.13208)
		(layer "F.Cu")
		(net "RST_NIC7_PERST1_R_N")
	)
	(segment
		(start 428.605696 -88.375998)
		(end 428.923704 -88.05799)
		(width 0.13208)
		(layer "F.Cu")
		(net "RST_NIC7_PERST1_R_N")
	)
	(via
		(at 428.605696 -88.375998)
		(size 0.508)
		(drill 0.254)
		(layers "F.Cu" "B.Cu")
		(net "RST_NIC7_PERST1_R_N")
	)
	(via
		(at 415.612834 -115.285774)
		(size 0.508)
		(drill 0.254)
		(layers "F.Cu" "B.Cu")
		(net "RST_NIC7_PERST1_R_N")
	)
	(segment
		(start 422.307258 -94.123764)
		(end 428.055024 -88.375998)
		(width 0.15494)
		(layer "In11.Cu")
		(net "RST_NIC7_PERST1_R_N")
	)
	(segment
		(start 421.175942 -108.328714)
		(end 421.42791 -108.076746)
		(width 0.15494)
		(layer "In11.Cu")
		(net "RST_NIC7_PERST1_R_N")
	)
	(segment
		(start 417.196524 -111.065564)
		(end 419.933374 -108.328714)
		(width 0.15494)
		(layer "In11.Cu")
		(net "RST_NIC7_PERST1_R_N")
	)
	(segment
		(start 428.055024 -88.375998)
		(end 428.605696 -88.375998)
		(width 0.15494)
		(layer "In11.Cu")
		(net "RST_NIC7_PERST1_R_N")
	)
	(segment
		(start 421.42791 -108.076746)
		(end 421.42791 -106.150156)
		(width 0.15494)
		(layer "In11.Cu")
		(net "RST_NIC7_PERST1_R_N")
	)
	(segment
		(start 415.612834 -115.285774)
		(end 416.15995 -115.285774)
		(width 0.15494)
		(layer "In11.Cu")
		(net "RST_NIC7_PERST1_R_N")
	)
	(segment
		(start 417.196524 -114.2492)
		(end 417.196524 -111.065564)
		(width 0.15494)
		(layer "In11.Cu")
		(net "RST_NIC7_PERST1_R_N")
	)
	(segment
		(start 420.506652 -105.228898)
		(end 420.506652 -97.780856)
		(width 0.15494)
		(layer "In11.Cu")
		(net "RST_NIC7_PERST1_R_N")
	)
	(segment
		(start 419.933374 -108.328714)
		(end 421.175942 -108.328714)
		(width 0.15494)
		(layer "In11.Cu")
		(net "RST_NIC7_PERST1_R_N")
	)
	(segment
		(start 422.307258 -95.98025)
		(end 422.307258 -94.123764)
		(width 0.15494)
		(layer "In11.Cu")
		(net "RST_NIC7_PERST1_R_N")
	)
	(segment
		(start 416.15995 -115.285774)
		(end 417.196524 -114.2492)
		(width 0.15494)
		(layer "In11.Cu")
		(net "RST_NIC7_PERST1_R_N")
	)
	(segment
		(start 421.42791 -106.150156)
		(end 420.506652 -105.228898)
		(width 0.15494)
		(layer "In11.Cu")
		(net "RST_NIC7_PERST1_R_N")
	)
	(segment
		(start 420.506652 -97.780856)
		(end 422.307258 -95.98025)
		(width 0.15494)
		(layer "In11.Cu")
		(net "RST_NIC7_PERST1_R_N")
	)
	(segment
		(start 79.425038 -142.917926)
		(end 79.752698 -142.590266)
		(width 0.13462)
		(layer "F.Cu")
		(net "P5E_PEX0_STN0_TX_C_DN<8>")
	)
	(segment
		(start 73.745852 -142.755112)
		(end 73.908666 -142.917926)
		(width 0.13462)
		(layer "F.Cu")
		(net "P5E_PEX0_STN0_TX_C_DN<8>")
	)
	(segment
		(start 73.257664 -142.755112)
		(end 73.745852 -142.755112)
		(width 0.13462)
		(layer "F.Cu")
		(net "P5E_PEX0_STN0_TX_C_DN<8>")
	)
	(segment
		(start 73.908666 -142.917926)
		(end 79.425038 -142.917926)
		(width 0.13462)
		(layer "F.Cu")
		(net "P5E_PEX0_STN0_TX_C_DN<8>")
	)
	(segment
		(start 162.14217 -121.7549)
		(end 161.654236 -121.7549)
		(width 0.13462)
		(layer "F.Cu")
		(net "P5E_PEX1_STN1_TX_C_DP<25>")
	)
	(segment
		(start 161.491422 -121.592086)
		(end 155.974796 -121.592086)
		(width 0.13462)
		(layer "F.Cu")
		(net "P5E_PEX1_STN1_TX_C_DP<25>")
	)
	(segment
		(start 155.974796 -121.592086)
		(end 155.647136 -121.919746)
		(width 0.13462)
		(layer "F.Cu")
		(net "P5E_PEX1_STN1_TX_C_DP<25>")
	)
	(segment
		(start 161.654236 -121.7549)
		(end 161.491422 -121.592086)
		(width 0.13462)
		(layer "F.Cu")
		(net "P5E_PEX1_STN1_TX_C_DP<25>")
	)
	(segment
		(start 269.105126 -104.695498)
		(end 269.418308 -105.00868)
		(width 0.13462)
		(layer "F.Cu")
		(net "P5E_PEX2_STN1_TX_C_DN<19>")
	)
	(segment
		(start 277.579328 -105.00868)
		(end 277.742904 -104.845104)
		(width 0.13462)
		(layer "F.Cu")
		(net "P5E_PEX2_STN1_TX_C_DN<19>")
	)
	(segment
		(start 269.418308 -105.00868)
		(end 277.579328 -105.00868)
		(width 0.13462)
		(layer "F.Cu")
		(net "P5E_PEX2_STN1_TX_C_DN<19>")
	)
	(segment
		(start 277.742904 -104.845104)
		(end 278.242268 -104.845104)
		(width 0.13462)
		(layer "F.Cu")
		(net "P5E_PEX2_STN1_TX_C_DN<19>")
	)
	(segment
		(start 428.052738 -118.670324)
		(end 427.731682 -118.99138)
		(width 0.13462)
		(layer "F.Cu")
		(net "P5E_PEX3_STN0_TX_C_DN<0>")
	)
	(segment
		(start 422.042082 -118.834916)
		(end 421.557704 -118.834916)
		(width 0.13462)
		(layer "F.Cu")
		(net "P5E_PEX3_STN0_TX_C_DN<0>")
	)
	(segment
		(start 422.198546 -118.99138)
		(end 422.042082 -118.834916)
		(width 0.13462)
		(layer "F.Cu")
		(net "P5E_PEX3_STN0_TX_C_DN<0>")
	)
	(segment
		(start 427.731682 -118.99138)
		(end 422.198546 -118.99138)
		(width 0.13462)
		(layer "F.Cu")
		(net "P5E_PEX3_STN0_TX_C_DN<0>")
	)
	(segment
		(start 369.934236 -319.361312)
		(end 371.130068 -316.473586)
		(width 0.1651)
		(layer "In9.Cu")
		(net "P5E_PEX3_STN7_RX_DN<116>")
	)
	(segment
		(start 373.708676 -311.864502)
		(end 373.666766 -311.726834)
		(width 0.1651)
		(layer "In9.Cu")
		(net "P5E_PEX3_STN7_RX_DN<116>")
	)
	(segment
		(start 373.474996 -312.301382)
		(end 373.708676 -311.864502)
		(width 0.1651)
		(layer "In9.Cu")
		(net "P5E_PEX3_STN7_RX_DN<116>")
	)
	(segment
		(start 383.96672 -305.020218)
		(end 387.301994 -305.020218)
		(width 0.1143)
		(layer "In9.Cu")
		(net "P5E_PEX3_STN7_RX_DN<116>")
	)
	(segment
		(start 397.958564 -335.291938)
		(end 377.250452 -330.541122)
		(width 0.1651)
		(layer "In9.Cu")
		(net "P5E_PEX3_STN7_RX_DN<116>")
	)
	(segment
		(start 374.27154 -310.811418)
		(end 374.22963 -310.67375)
		(width 0.1651)
		(layer "In9.Cu")
		(net "P5E_PEX3_STN7_RX_DN<116>")
	)
	(segment
		(start 429.446944 -395.215618)
		(end 428.807118 -394.054584)
		(width 0.1651)
		(layer "In9.Cu")
		(net "P5E_PEX3_STN7_RX_DN<116>")
	)
	(segment
		(start 372.582948 -313.97067)
		(end 372.541038 -313.833002)
		(width 0.1651)
		(layer "In9.Cu")
		(net "P5E_PEX3_STN7_RX_DN<116>")
	)
	(segment
		(start 377.655582 -306.667662)
		(end 377.655582 -306.523898)
		(width 0.1651)
		(layer "In9.Cu")
		(net "P5E_PEX3_STN7_RX_DN<116>")
	)
	(segment
		(start 428.75581 -408.981148)
		(end 429.446944 -408.290014)
		(width 0.1651)
		(layer "In9.Cu")
		(net "P5E_PEX3_STN7_RX_DN<116>")
	)
	(segment
		(start 383.892552 -305.065938)
		(end 383.921 -305.065938)
		(width 0.1143)
		(layer "In9.Cu")
		(net "P5E_PEX3_STN7_RX_DN<116>")
	)
	(segment
		(start 424.174412 -391.127488)
		(end 419.011354 -389.290052)
		(width 0.1651)
		(layer "In9.Cu")
		(net "P5E_PEX3_STN7_RX_DN<116>")
	)
	(segment
		(start 373.145812 -312.917586)
		(end 373.103902 -312.779918)
		(width 0.1651)
		(layer "In9.Cu")
		(net "P5E_PEX3_STN7_RX_DN<116>")
	)
	(segment
		(start 387.434328 -305.303936)
		(end 387.338316 -305.399948)
		(width 0.1143)
		(layer "In9.Cu")
		(net "P5E_PEX3_STN7_RX_DN<116>")
	)
	(segment
		(start 376.811286 -307.511958)
		(end 376.811286 -307.368194)
		(width 0.1651)
		(layer "In9.Cu")
		(net "P5E_PEX3_STN7_RX_DN<116>")
	)
	(segment
		(start 374.83415 -309.758334)
		(end 374.792494 -309.62092)
		(width 0.1651)
		(layer "In9.Cu")
		(net "P5E_PEX3_STN7_RX_DN<116>")
	)
	(segment
		(start 376.460766 -307.862478)
		(end 376.811286 -307.511958)
		(width 0.1651)
		(layer "In9.Cu")
		(net "P5E_PEX3_STN7_RX_DN<116>")
	)
	(segment
		(start 372.541292 -313.833256)
		(end 372.774718 -313.39663)
		(width 0.1651)
		(layer "In9.Cu")
		(net "P5E_PEX3_STN7_RX_DN<116>")
	)
	(segment
		(start 411.422342 -341.91575)
		(end 410.777436 -340.897972)
		(width 0.1651)
		(layer "In9.Cu")
		(net "P5E_PEX3_STN7_RX_DN<116>")
	)
	(segment
		(start 373.666766 -311.726834)
		(end 373.900192 -311.290208)
		(width 0.1651)
		(layer "In9.Cu")
		(net "P5E_PEX3_STN7_RX_DN<116>")
	)
	(segment
		(start 377.305062 -307.018182)
		(end 377.655582 -306.667662)
		(width 0.1651)
		(layer "In9.Cu")
		(net "P5E_PEX3_STN7_RX_DN<116>")
	)
	(segment
		(start 387.434328 -305.152552)
		(end 387.434328 -305.303936)
		(width 0.1143)
		(layer "In9.Cu")
		(net "P5E_PEX3_STN7_RX_DN<116>")
	)
	(segment
		(start 419.011354 -389.290052)
		(end 416.375342 -387.142482)
		(width 0.1651)
		(layer "In9.Cu")
		(net "P5E_PEX3_STN7_RX_DN<116>")
	)
	(segment
		(start 381.42926 -305.065938)
		(end 383.892552 -305.065938)
		(width 0.1651)
		(layer "In9.Cu")
		(net "P5E_PEX3_STN7_RX_DN<116>")
	)
	(segment
		(start 373.337328 -312.343292)
		(end 373.474996 -312.301382)
		(width 0.1651)
		(layer "In9.Cu")
		(net "P5E_PEX3_STN7_RX_DN<116>")
	)
	(segment
		(start 376.317002 -307.862478)
		(end 376.460766 -307.862478)
		(width 0.1651)
		(layer "In9.Cu")
		(net "P5E_PEX3_STN7_RX_DN<116>")
	)
	(segment
		(start 377.655582 -306.523898)
		(end 378.090938 -306.088542)
		(width 0.1651)
		(layer "In9.Cu")
		(net "P5E_PEX3_STN7_RX_DN<116>")
	)
	(segment
		(start 410.777436 -340.897972)
		(end 397.958564 -335.291938)
		(width 0.1651)
		(layer "In9.Cu")
		(net "P5E_PEX3_STN7_RX_DN<116>")
	)
	(segment
		(start 374.792494 -309.62092)
		(end 375.060464 -309.11927)
		(width 0.1651)
		(layer "In9.Cu")
		(net "P5E_PEX3_STN7_RX_DN<116>")
	)
	(segment
		(start 372.774464 -313.396376)
		(end 372.912132 -313.354466)
		(width 0.1651)
		(layer "In9.Cu")
		(net "P5E_PEX3_STN7_RX_DN<116>")
	)
	(segment
		(start 428.289974 -409.490164)
		(end 428.289974 -409.108148)
		(width 0.1651)
		(layer "In9.Cu")
		(net "P5E_PEX3_STN7_RX_DN<116>")
	)
	(segment
		(start 377.250452 -330.541122)
		(end 375.585736 -330.016104)
		(width 0.1651)
		(layer "In9.Cu")
		(net "P5E_PEX3_STN7_RX_DN<116>")
	)
	(segment
		(start 375.585736 -330.016104)
		(end 371.029992 -325.460614)
		(width 0.1651)
		(layer "In9.Cu")
		(net "P5E_PEX3_STN7_RX_DN<116>")
	)
	(segment
		(start 372.541038 -313.833002)
		(end 372.541292 -313.833256)
		(width 0.1651)
		(layer "In9.Cu")
		(net "P5E_PEX3_STN7_RX_DN<116>")
	)
	(segment
		(start 372.211854 -314.449714)
		(end 372.2116 -314.44946)
		(width 0.1651)
		(layer "In9.Cu")
		(net "P5E_PEX3_STN7_RX_DN<116>")
	)
	(segment
		(start 372.912132 -313.354466)
		(end 373.145812 -312.917586)
		(width 0.1651)
		(layer "In9.Cu")
		(net "P5E_PEX3_STN7_RX_DN<116>")
	)
	(segment
		(start 374.03786 -311.248298)
		(end 374.27154 -310.811418)
		(width 0.1651)
		(layer "In9.Cu")
		(net "P5E_PEX3_STN7_RX_DN<116>")
	)
	(segment
		(start 369.934236 -322.81495)
		(end 369.934236 -319.361312)
		(width 0.1651)
		(layer "In9.Cu")
		(net "P5E_PEX3_STN7_RX_DN<116>")
	)
	(segment
		(start 371.130068 -316.473586)
		(end 372.211854 -314.449714)
		(width 0.1651)
		(layer "In9.Cu")
		(net "P5E_PEX3_STN7_RX_DN<116>")
	)
	(segment
		(start 374.463056 -310.237124)
		(end 374.60047 -310.195468)
		(width 0.1651)
		(layer "In9.Cu")
		(net "P5E_PEX3_STN7_RX_DN<116>")
	)
	(segment
		(start 415.427668 -385.73202)
		(end 414.946592 -384.464814)
		(width 0.1651)
		(layer "In9.Cu")
		(net "P5E_PEX3_STN7_RX_DN<116>")
	)
	(segment
		(start 411.422342 -358.352598)
		(end 411.422342 -341.91575)
		(width 0.1651)
		(layer "In9.Cu")
		(net "P5E_PEX3_STN7_RX_DN<116>")
	)
	(segment
		(start 387.338316 -305.399948)
		(end 387.050026 -305.399948)
		(width 0.1143)
		(layer "In9.Cu")
		(net "P5E_PEX3_STN7_RX_DN<116>")
	)
	(segment
		(start 377.161298 -307.018182)
		(end 377.305062 -307.018182)
		(width 0.1651)
		(layer "In9.Cu")
		(net "P5E_PEX3_STN7_RX_DN<116>")
	)
	(segment
		(start 428.289974 -409.108148)
		(end 428.416974 -408.981148)
		(width 0.1651)
		(layer "In9.Cu")
		(net "P5E_PEX3_STN7_RX_DN<116>")
	)
	(segment
		(start 414.946592 -384.464814)
		(end 411.422342 -358.352598)
		(width 0.1651)
		(layer "In9.Cu")
		(net "P5E_PEX3_STN7_RX_DN<116>")
	)
	(segment
		(start 374.22963 -310.67375)
		(end 374.463056 -310.237124)
		(width 0.1651)
		(layer "In9.Cu")
		(net "P5E_PEX3_STN7_RX_DN<116>")
	)
	(segment
		(start 383.921 -305.065938)
		(end 383.96672 -305.020218)
		(width 0.1143)
		(layer "In9.Cu")
		(net "P5E_PEX3_STN7_RX_DN<116>")
	)
	(segment
		(start 428.807118 -394.054584)
		(end 424.174412 -391.127488)
		(width 0.1651)
		(layer "In9.Cu")
		(net "P5E_PEX3_STN7_RX_DN<116>")
	)
	(segment
		(start 416.375342 -387.142482)
		(end 415.427668 -385.73202)
		(width 0.1651)
		(layer "In9.Cu")
		(net "P5E_PEX3_STN7_RX_DN<116>")
	)
	(segment
		(start 371.029992 -325.460614)
		(end 369.934236 -322.81495)
		(width 0.1651)
		(layer "In9.Cu")
		(net "P5E_PEX3_STN7_RX_DN<116>")
	)
	(segment
		(start 372.349268 -314.407804)
		(end 372.582948 -313.97067)
		(width 0.1651)
		(layer "In9.Cu")
		(net "P5E_PEX3_STN7_RX_DN<116>")
	)
	(segment
		(start 378.090938 -306.088542)
		(end 379.51283 -305.805586)
		(width 0.1651)
		(layer "In9.Cu")
		(net "P5E_PEX3_STN7_RX_DN<116>")
	)
	(segment
		(start 379.51283 -305.805586)
		(end 381.42926 -305.065938)
		(width 0.1651)
		(layer "In9.Cu")
		(net "P5E_PEX3_STN7_RX_DN<116>")
	)
	(segment
		(start 373.103902 -312.779918)
		(end 373.104156 -312.779918)
		(width 0.1651)
		(layer "In9.Cu")
		(net "P5E_PEX3_STN7_RX_DN<116>")
	)
	(segment
		(start 375.060464 -309.11927)
		(end 376.317002 -307.862478)
		(width 0.1651)
		(layer "In9.Cu")
		(net "P5E_PEX3_STN7_RX_DN<116>")
	)
	(segment
		(start 428.416974 -408.981148)
		(end 428.75581 -408.981148)
		(width 0.1651)
		(layer "In9.Cu")
		(net "P5E_PEX3_STN7_RX_DN<116>")
	)
	(segment
		(start 373.900192 -311.290208)
		(end 374.03786 -311.248298)
		(width 0.1651)
		(layer "In9.Cu")
		(net "P5E_PEX3_STN7_RX_DN<116>")
	)
	(segment
		(start 429.446944 -408.290014)
		(end 429.446944 -395.215618)
		(width 0.1651)
		(layer "In9.Cu")
		(net "P5E_PEX3_STN7_RX_DN<116>")
	)
	(segment
		(start 376.811286 -307.368194)
		(end 377.161298 -307.018182)
		(width 0.1651)
		(layer "In9.Cu")
		(net "P5E_PEX3_STN7_RX_DN<116>")
	)
	(segment
		(start 374.60047 -310.195468)
		(end 374.83415 -309.758334)
		(width 0.1651)
		(layer "In9.Cu")
		(net "P5E_PEX3_STN7_RX_DN<116>")
	)
	(segment
		(start 373.104156 -312.779918)
		(end 373.337582 -312.343292)
		(width 0.1651)
		(layer "In9.Cu")
		(net "P5E_PEX3_STN7_RX_DN<116>")
	)
	(segment
		(start 373.337582 -312.343292)
		(end 373.337328 -312.343292)
		(width 0.1651)
		(layer "In9.Cu")
		(net "P5E_PEX3_STN7_RX_DN<116>")
	)
	(segment
		(start 372.2116 -314.44946)
		(end 372.349268 -314.407804)
		(width 0.1651)
		(layer "In9.Cu")
		(net "P5E_PEX3_STN7_RX_DN<116>")
	)
	(segment
		(start 372.774718 -313.39663)
		(end 372.774464 -313.396376)
		(width 0.1651)
		(layer "In9.Cu")
		(net "P5E_PEX3_STN7_RX_DN<116>")
	)
	(segment
		(start 387.301994 -305.020218)
		(end 387.434328 -305.152552)
		(width 0.1143)
		(layer "In9.Cu")
		(net "P5E_PEX3_STN7_RX_DN<116>")
	)
	(segment
		(start 421.557704 -97.64014)
		(end 422.60012 -97.64014)
		(width 0.13208)
		(layer "F.Cu")
		(net "NIC7_MAIN_PWR_EN_R")
	)
	(via
		(at 421.57904 -98.552)
		(size 0.6604)
		(drill 0.3302)
		(layers "F.Cu" "B.Cu")
		(net "NIC7_MAIN_PWR_EN_R")
	)
	(via
		(at 422.60012 -97.64014)
		(size 0.508)
		(drill 0.254)
		(layers "F.Cu" "B.Cu")
		(net "NIC7_MAIN_PWR_EN_R")
	)
	(segment
		(start 422.60012 -97.64014)
		(end 422.06926 -98.171)
		(width 0.13208)
		(layer "B.Cu")
		(net "NIC7_MAIN_PWR_EN_R")
	)
	(segment
		(start 422.06926 -98.171)
		(end 421.96004 -98.171)
		(width 0.13208)
		(layer "B.Cu")
		(net "NIC7_MAIN_PWR_EN_R")
	)
	(segment
		(start 421.96004 -98.171)
		(end 421.57904 -98.552)
		(width 0.13208)
		(layer "B.Cu")
		(net "NIC7_MAIN_PWR_EN_R")
	)
	(segment
		(start 421.57904 -98.552)
		(end 420.45509 -98.552)
		(width 0.13208)
		(layer "B.Cu")
		(net "NIC7_MAIN_PWR_EN_R")
	)
	(segment
		(start 73.745852 -130.044952)
		(end 73.908666 -130.207766)
		(width 0.13462)
		(layer "F.Cu")
		(net "P5E_PEX0_STN0_TX_C_DN<4>")
	)
	(segment
		(start 73.908666 -130.207766)
		(end 79.425038 -130.207766)
		(width 0.13462)
		(layer "F.Cu")
		(net "P5E_PEX0_STN0_TX_C_DN<4>")
	)
	(segment
		(start 73.257664 -130.044952)
		(end 73.745852 -130.044952)
		(width 0.13462)
		(layer "F.Cu")
		(net "P5E_PEX0_STN0_TX_C_DN<4>")
	)
	(segment
		(start 79.425038 -130.207766)
		(end 79.752698 -129.880106)
		(width 0.13462)
		(layer "F.Cu")
		(net "P5E_PEX0_STN0_TX_C_DN<4>")
	)
	(segment
		(start 166.742364 -134.765034)
		(end 167.230298 -134.765034)
		(width 0.13462)
		(layer "F.Cu")
		(net "P5E_PEX1_STN1_RX_DN<30>")
	)
	(segment
		(start 169.901616 -134.60222)
		(end 169.902124 -134.601712)
		(width 0.13462)
		(layer "F.Cu")
		(net "P5E_PEX1_STN1_RX_DN<30>")
	)
	(segment
		(start 169.902124 -134.601712)
		(end 170.196764 -134.896352)
		(width 0.13462)
		(layer "F.Cu")
		(net "P5E_PEX1_STN1_RX_DN<30>")
	)
	(segment
		(start 167.230298 -134.765034)
		(end 167.393112 -134.60222)
		(width 0.13462)
		(layer "F.Cu")
		(net "P5E_PEX1_STN1_RX_DN<30>")
	)
	(segment
		(start 167.393112 -134.60222)
		(end 169.901616 -134.60222)
		(width 0.13462)
		(layer "F.Cu")
		(net "P5E_PEX1_STN1_RX_DN<30>")
	)
	(segment
		(start 159.533336 -154.847036)
		(end 159.60344 -154.767026)
		(width 0.1651)
		(layer "In5.Cu")
		(net "P5E_PEX1_STN1_RX_DN<30>")
	)
	(segment
		(start 165.674802 -142.586202)
		(end 165.864286 -142.128494)
		(width 0.1651)
		(layer "In5.Cu")
		(net "P5E_PEX1_STN1_RX_DN<30>")
	)
	(segment
		(start 166.12108 -139.495276)
		(end 166.23538 -139.380976)
		(width 0.1651)
		(layer "In5.Cu")
		(net "P5E_PEX1_STN1_RX_DN<30>")
	)
	(segment
		(start 159.411162 -153.009346)
		(end 159.378396 -152.515316)
		(width 0.1651)
		(layer "In5.Cu")
		(net "P5E_PEX1_STN1_RX_DN<30>")
	)
	(segment
		(start 167.12311 -135.044688)
		(end 167.235632 -134.937754)
		(width 0.1651)
		(layer "In5.Cu")
		(net "P5E_PEX1_STN1_RX_DN<30>")
	)
	(segment
		(start 159.33801 -147.574)
		(end 159.664654 -147.328636)
		(width 0.1651)
		(layer "In5.Cu")
		(net "P5E_PEX1_STN1_RX_DN<30>")
	)
	(segment
		(start 159.297624 -151.298656)
		(end 159.40405 -151.17699)
		(width 0.1651)
		(layer "In5.Cu")
		(net "P5E_PEX1_STN1_RX_DN<30>")
	)
	(segment
		(start 166.911528 -135.492236)
		(end 167.12311 -135.044688)
		(width 0.1651)
		(layer "In5.Cu")
		(net "P5E_PEX1_STN1_RX_DN<30>")
	)
	(segment
		(start 161.796984 -146.674586)
		(end 162.550602 -145.920968)
		(width 0.1651)
		(layer "In5.Cu")
		(net "P5E_PEX1_STN1_RX_DN<30>")
	)
	(segment
		(start 166.23538 -140.104876)
		(end 166.12108 -139.990576)
		(width 0.1651)
		(layer "In5.Cu")
		(net "P5E_PEX1_STN1_RX_DN<30>")
	)
	(segment
		(start 166.12108 -140.714476)
		(end 166.23538 -140.600176)
		(width 0.1651)
		(layer "In5.Cu")
		(net "P5E_PEX1_STN1_RX_DN<30>")
	)
	(segment
		(start 188.71565 -271.554448)
		(end 188.71565 -271.526)
		(width 0.1143)
		(layer "In5.Cu")
		(net "P5E_PEX1_STN1_RX_DN<30>")
	)
	(segment
		(start 165.525196 -142.648178)
		(end 165.674802 -142.586202)
		(width 0.1651)
		(layer "In5.Cu")
		(net "P5E_PEX1_STN1_RX_DN<30>")
	)
	(segment
		(start 166.601648 -136.147302)
		(end 166.601648 -136.147048)
		(width 0.1651)
		(layer "In5.Cu")
		(net "P5E_PEX1_STN1_RX_DN<30>")
	)
	(segment
		(start 166.12108 -141.209776)
		(end 166.12108 -140.714476)
		(width 0.1651)
		(layer "In5.Cu")
		(net "P5E_PEX1_STN1_RX_DN<30>")
	)
	(segment
		(start 164.286946 -144.286478)
		(end 165.242494 -143.33093)
		(width 0.1651)
		(layer "In5.Cu")
		(net "P5E_PEX1_STN1_RX_DN<30>")
	)
	(segment
		(start 159.60344 -154.767026)
		(end 159.568896 -154.245564)
		(width 0.1651)
		(layer "In5.Cu")
		(net "P5E_PEX1_STN1_RX_DN<30>")
	)
	(segment
		(start 168.53281 -134.605522)
		(end 168.64711 -134.719822)
		(width 0.1651)
		(layer "In5.Cu")
		(net "P5E_PEX1_STN1_RX_DN<30>")
	)
	(segment
		(start 159.455866 -153.681176)
		(end 159.53867 -153.586688)
		(width 0.1651)
		(layer "In5.Cu")
		(net "P5E_PEX1_STN1_RX_DN<30>")
	)
	(segment
		(start 166.753794 -136.092438)
		(end 166.965884 -135.644382)
		(width 0.1651)
		(layer "In5.Cu")
		(net "P5E_PEX1_STN1_RX_DN<30>")
	)
	(segment
		(start 162.863022 -145.454624)
		(end 164.286946 -144.286478)
		(width 0.1651)
		(layer "In5.Cu")
		(net "P5E_PEX1_STN1_RX_DN<30>")
	)
	(segment
		(start 169.25671 -134.605522)
		(end 169.897552 -134.605522)
		(width 0.1651)
		(layer "In5.Cu")
		(net "P5E_PEX1_STN1_RX_DN<30>")
	)
	(segment
		(start 159.664654 -147.328636)
		(end 159.807148 -147.257262)
		(width 0.1651)
		(layer "In5.Cu")
		(net "P5E_PEX1_STN1_RX_DN<30>")
	)
	(segment
		(start 188.935106 -273.479514)
		(end 188.773308 -273.479514)
		(width 0.1143)
		(layer "In5.Cu")
		(net "P5E_PEX1_STN1_RX_DN<30>")
	)
	(segment
		(start 165.864286 -142.128494)
		(end 165.802564 -141.979142)
		(width 0.1651)
		(layer "In5.Cu")
		(net "P5E_PEX1_STN1_RX_DN<30>")
	)
	(segment
		(start 160.36798 -160.706816)
		(end 159.65678 -156.713936)
		(width 0.1651)
		(layer "In5.Cu")
		(net "P5E_PEX1_STN1_RX_DN<30>")
	)
	(segment
		(start 188.773308 -273.479514)
		(end 188.66993 -273.376136)
		(width 0.1143)
		(layer "In5.Cu")
		(net "P5E_PEX1_STN1_RX_DN<30>")
	)
	(segment
		(start 159.08528 -148.099526)
		(end 159.33801 -147.574)
		(width 0.1651)
		(layer "In5.Cu")
		(net "P5E_PEX1_STN1_RX_DN<30>")
	)
	(segment
		(start 166.23538 -138.885676)
		(end 166.12108 -138.771376)
		(width 0.1651)
		(layer "In5.Cu")
		(net "P5E_PEX1_STN1_RX_DN<30>")
	)
	(segment
		(start 166.23538 -139.380976)
		(end 166.23538 -138.885676)
		(width 0.1651)
		(layer "In5.Cu")
		(net "P5E_PEX1_STN1_RX_DN<30>")
	)
	(segment
		(start 159.249364 -150.576026)
		(end 159.249618 -150.576026)
		(width 0.1651)
		(layer "In5.Cu")
		(net "P5E_PEX1_STN1_RX_DN<30>")
	)
	(segment
		(start 169.897552 -134.605522)
		(end 169.903648 -134.603236)
		(width 0.1651)
		(layer "In5.Cu")
		(net "P5E_PEX1_STN1_RX_DN<30>")
	)
	(segment
		(start 165.802564 -141.979142)
		(end 166.12108 -141.209776)
		(width 0.1651)
		(layer "In5.Cu")
		(net "P5E_PEX1_STN1_RX_DN<30>")
	)
	(segment
		(start 188.66993 -273.376136)
		(end 188.66993 -271.600168)
		(width 0.1143)
		(layer "In5.Cu")
		(net "P5E_PEX1_STN1_RX_DN<30>")
	)
	(segment
		(start 165.242494 -143.33093)
		(end 165.525196 -142.648432)
		(width 0.1651)
		(layer "In5.Cu")
		(net "P5E_PEX1_STN1_RX_DN<30>")
	)
	(segment
		(start 166.601648 -136.147048)
		(end 166.753794 -136.092438)
		(width 0.1651)
		(layer "In5.Cu")
		(net "P5E_PEX1_STN1_RX_DN<30>")
	)
	(segment
		(start 169.903648 -134.603236)
		(end 170.196764 -134.896352)
		(width 0.1651)
		(layer "In5.Cu")
		(net "P5E_PEX1_STN1_RX_DN<30>")
	)
	(segment
		(start 169.14241 -134.719822)
		(end 169.25671 -134.605522)
		(width 0.1651)
		(layer "In5.Cu")
		(net "P5E_PEX1_STN1_RX_DN<30>")
	)
	(segment
		(start 166.12108 -137.163302)
		(end 166.601648 -136.147302)
		(width 0.1651)
		(layer "In5.Cu")
		(net "P5E_PEX1_STN1_RX_DN<30>")
	)
	(segment
		(start 166.12108 -138.771376)
		(end 166.12108 -137.163302)
		(width 0.1651)
		(layer "In5.Cu")
		(net "P5E_PEX1_STN1_RX_DN<30>")
	)
	(segment
		(start 188.71565 -267.233654)
		(end 160.36798 -160.706816)
		(width 0.1651)
		(layer "In5.Cu")
		(net "P5E_PEX1_STN1_RX_DN<30>")
	)
	(segment
		(start 159.440626 -151.889206)
		(end 159.33039 -151.792686)
		(width 0.1651)
		(layer "In5.Cu")
		(net "P5E_PEX1_STN1_RX_DN<30>")
	)
	(segment
		(start 166.12108 -139.990576)
		(end 166.12108 -139.495276)
		(width 0.1651)
		(layer "In5.Cu")
		(net "P5E_PEX1_STN1_RX_DN<30>")
	)
	(segment
		(start 159.378396 -152.515316)
		(end 159.474916 -152.40508)
		(width 0.1651)
		(layer "In5.Cu")
		(net "P5E_PEX1_STN1_RX_DN<30>")
	)
	(segment
		(start 159.505904 -153.09215)
		(end 159.411162 -153.009346)
		(width 0.1651)
		(layer "In5.Cu")
		(net "P5E_PEX1_STN1_RX_DN<30>")
	)
	(segment
		(start 159.65678 -156.713936)
		(end 159.533336 -154.847036)
		(width 0.1651)
		(layer "In5.Cu")
		(net "P5E_PEX1_STN1_RX_DN<30>")
	)
	(segment
		(start 159.488378 -154.175206)
		(end 159.455866 -153.681176)
		(width 0.1651)
		(layer "In5.Cu")
		(net "P5E_PEX1_STN1_RX_DN<30>")
	)
	(segment
		(start 188.71565 -271.526)
		(end 188.71565 -267.233654)
		(width 0.1651)
		(layer "In5.Cu")
		(net "P5E_PEX1_STN1_RX_DN<30>")
	)
	(segment
		(start 189.04966 -273.36496)
		(end 188.935106 -273.479514)
		(width 0.1143)
		(layer "In5.Cu")
		(net "P5E_PEX1_STN1_RX_DN<30>")
	)
	(segment
		(start 160.106106 -147.17014)
		(end 160.60039 -147.17014)
		(width 0.1651)
		(layer "In5.Cu")
		(net "P5E_PEX1_STN1_RX_DN<30>")
	)
	(segment
		(start 167.235632 -134.937754)
		(end 168.03751 -134.605522)
		(width 0.1651)
		(layer "In5.Cu")
		(net "P5E_PEX1_STN1_RX_DN<30>")
	)
	(segment
		(start 159.568896 -154.245564)
		(end 159.488378 -154.175206)
		(width 0.1651)
		(layer "In5.Cu")
		(net "P5E_PEX1_STN1_RX_DN<30>")
	)
	(segment
		(start 189.04966 -273.099784)
		(end 189.04966 -273.36496)
		(width 0.1143)
		(layer "In5.Cu")
		(net "P5E_PEX1_STN1_RX_DN<30>")
	)
	(segment
		(start 188.66993 -271.600168)
		(end 188.71565 -271.554448)
		(width 0.1143)
		(layer "In5.Cu")
		(net "P5E_PEX1_STN1_RX_DN<30>")
	)
	(segment
		(start 159.474916 -152.40508)
		(end 159.440626 -151.889206)
		(width 0.1651)
		(layer "In5.Cu")
		(net "P5E_PEX1_STN1_RX_DN<30>")
	)
	(segment
		(start 159.40405 -151.17699)
		(end 159.371284 -150.682452)
		(width 0.1651)
		(layer "In5.Cu")
		(net "P5E_PEX1_STN1_RX_DN<30>")
	)
	(segment
		(start 168.03751 -134.605522)
		(end 168.53281 -134.605522)
		(width 0.1651)
		(layer "In5.Cu")
		(net "P5E_PEX1_STN1_RX_DN<30>")
	)
	(segment
		(start 159.807148 -147.257262)
		(end 160.106106 -147.17014)
		(width 0.1651)
		(layer "In5.Cu")
		(net "P5E_PEX1_STN1_RX_DN<30>")
	)
	(segment
		(start 159.33039 -151.792686)
		(end 159.297624 -151.298656)
		(width 0.1651)
		(layer "In5.Cu")
		(net "P5E_PEX1_STN1_RX_DN<30>")
	)
	(segment
		(start 159.249618 -150.576026)
		(end 159.08528 -148.099526)
		(width 0.1651)
		(layer "In5.Cu")
		(net "P5E_PEX1_STN1_RX_DN<30>")
	)
	(segment
		(start 166.965884 -135.644382)
		(end 166.911528 -135.492236)
		(width 0.1651)
		(layer "In5.Cu")
		(net "P5E_PEX1_STN1_RX_DN<30>")
	)
	(segment
		(start 159.371284 -150.682452)
		(end 159.249364 -150.576026)
		(width 0.1651)
		(layer "In5.Cu")
		(net "P5E_PEX1_STN1_RX_DN<30>")
	)
	(segment
		(start 166.23538 -140.600176)
		(end 166.23538 -140.104876)
		(width 0.1651)
		(layer "In5.Cu")
		(net "P5E_PEX1_STN1_RX_DN<30>")
	)
	(segment
		(start 159.53867 -153.586688)
		(end 159.505904 -153.09215)
		(width 0.1651)
		(layer "In5.Cu")
		(net "P5E_PEX1_STN1_RX_DN<30>")
	)
	(segment
		(start 165.525196 -142.648432)
		(end 165.525196 -142.648178)
		(width 0.1651)
		(layer "In5.Cu")
		(net "P5E_PEX1_STN1_RX_DN<30>")
	)
	(segment
		(start 162.550602 -145.920968)
		(end 162.863022 -145.454624)
		(width 0.1651)
		(layer "In5.Cu")
		(net "P5E_PEX1_STN1_RX_DN<30>")
	)
	(segment
		(start 168.64711 -134.719822)
		(end 169.14241 -134.719822)
		(width 0.1651)
		(layer "In5.Cu")
		(net "P5E_PEX1_STN1_RX_DN<30>")
	)
	(segment
		(start 160.60039 -147.17014)
		(end 161.796984 -146.674586)
		(width 0.1651)
		(layer "In5.Cu")
		(net "P5E_PEX1_STN1_RX_DN<30>")
	)
	(segment
		(start 284.150054 -121.31548)
		(end 283.482034 -121.31548)
		(width 0.13462)
		(layer "F.Cu")
		(net "P5E_PEX2_STN1_RX_DP<25>")
	)
	(segment
		(start 284.442662 -121.022872)
		(end 284.150054 -121.31548)
		(width 0.13462)
		(layer "F.Cu")
		(net "P5E_PEX2_STN1_RX_DP<25>")
	)
	(segment
		(start 283.482034 -121.31548)
		(end 283.321506 -121.154952)
		(width 0.13462)
		(layer "F.Cu")
		(net "P5E_PEX2_STN1_RX_DP<25>")
	)
	(segment
		(start 283.321506 -121.154952)
		(end 282.842462 -121.154952)
		(width 0.13462)
		(layer "F.Cu")
		(net "P5E_PEX2_STN1_RX_DP<25>")
	)
	(segment
		(start 300.39945 -275.684234)
		(end 300.39945 -275.949664)
		(width 0.1143)
		(layer "In5.Cu")
		(net "P5E_PEX2_STN1_RX_DP<25>")
	)
	(segment
		(start 300.28515 -275.569934)
		(end 300.39945 -275.684234)
		(width 0.1143)
		(layer "In5.Cu")
		(net "P5E_PEX2_STN1_RX_DP<25>")
	)
	(segment
		(start 277.97633 -125.831854)
		(end 275.881084 -128.458722)
		(width 0.1651)
		(layer "In5.Cu")
		(net "P5E_PEX2_STN1_RX_DP<25>")
	)
	(segment
		(start 299.829474 -271.644872)
		(end 299.829474 -275.35505)
		(width 0.1143)
		(layer "In5.Cu")
		(net "P5E_PEX2_STN1_RX_DP<25>")
	)
	(segment
		(start 272.775172 -142.635986)
		(end 270.487394 -145.587212)
		(width 0.1651)
		(layer "In5.Cu")
		(net "P5E_PEX2_STN1_RX_DP<25>")
	)
	(segment
		(start 274.121626 -137.931144)
		(end 272.775172 -142.635986)
		(width 0.1651)
		(layer "In5.Cu")
		(net "P5E_PEX2_STN1_RX_DP<25>")
	)
	(segment
		(start 270.053308 -147.311364)
		(end 270.053562 -147.311364)
		(width 0.1651)
		(layer "In5.Cu")
		(net "P5E_PEX2_STN1_RX_DP<25>")
	)
	(segment
		(start 299.783754 -268.07414)
		(end 299.783754 -271.570704)
		(width 0.1651)
		(layer "In5.Cu")
		(net "P5E_PEX2_STN1_RX_DP<25>")
	)
	(segment
		(start 270.66367 -157.255972)
		(end 271.605248 -162.425888)
		(width 0.1651)
		(layer "In5.Cu")
		(net "P5E_PEX2_STN1_RX_DP<25>")
	)
	(segment
		(start 299.829474 -275.35505)
		(end 300.044358 -275.569934)
		(width 0.1143)
		(layer "In5.Cu")
		(net "P5E_PEX2_STN1_RX_DP<25>")
	)
	(segment
		(start 299.783754 -271.599152)
		(end 299.829474 -271.644872)
		(width 0.1143)
		(layer "In5.Cu")
		(net "P5E_PEX2_STN1_RX_DP<25>")
	)
	(segment
		(start 284.151832 -121.313702)
		(end 283.932376 -121.313702)
		(width 0.1651)
		(layer "In5.Cu")
		(net "P5E_PEX2_STN1_RX_DP<25>")
	)
	(segment
		(start 275.881084 -128.458722)
		(end 275.692616 -128.887982)
		(width 0.1651)
		(layer "In5.Cu")
		(net "P5E_PEX2_STN1_RX_DP<25>")
	)
	(segment
		(start 284.442662 -121.022872)
		(end 284.151832 -121.313702)
		(width 0.1651)
		(layer "In5.Cu")
		(net "P5E_PEX2_STN1_RX_DP<25>")
	)
	(segment
		(start 282.187396 -122.009662)
		(end 277.97633 -125.831854)
		(width 0.1651)
		(layer "In5.Cu")
		(net "P5E_PEX2_STN1_RX_DP<25>")
	)
	(segment
		(start 299.783754 -271.570704)
		(end 299.783754 -271.599152)
		(width 0.1143)
		(layer "In5.Cu")
		(net "P5E_PEX2_STN1_RX_DP<25>")
	)
	(segment
		(start 300.044358 -275.569934)
		(end 300.28515 -275.569934)
		(width 0.1143)
		(layer "In5.Cu")
		(net "P5E_PEX2_STN1_RX_DP<25>")
	)
	(segment
		(start 270.053562 -147.311364)
		(end 270.66367 -157.255972)
		(width 0.1651)
		(layer "In5.Cu")
		(net "P5E_PEX2_STN1_RX_DP<25>")
	)
	(segment
		(start 270.487394 -145.587212)
		(end 270.050768 -147.266914)
		(width 0.1651)
		(layer "In5.Cu")
		(net "P5E_PEX2_STN1_RX_DP<25>")
	)
	(segment
		(start 283.932376 -121.313702)
		(end 282.187396 -122.009662)
		(width 0.1651)
		(layer "In5.Cu")
		(net "P5E_PEX2_STN1_RX_DP<25>")
	)
	(segment
		(start 271.605248 -162.425888)
		(end 299.783754 -268.07414)
		(width 0.1651)
		(layer "In5.Cu")
		(net "P5E_PEX2_STN1_RX_DP<25>")
	)
	(segment
		(start 270.050768 -147.266914)
		(end 270.053308 -147.311364)
		(width 0.1651)
		(layer "In5.Cu")
		(net "P5E_PEX2_STN1_RX_DP<25>")
	)
	(segment
		(start 275.692616 -128.887982)
		(end 274.121626 -137.931144)
		(width 0.1651)
		(layer "In5.Cu")
		(net "P5E_PEX2_STN1_RX_DP<25>")
	)
	(segment
		(start 333.006446 -395.268958)
		(end 333.148432 -395.245844)
		(width 0.1651)
		(layer "In9.Cu")
		(net "P5E_PEX2_STN5_RX_DP<80>")
	)
	(segment
		(start 335.824068 -391.951718)
		(end 349.668084 -385.341876)
		(width 0.1651)
		(layer "In9.Cu")
		(net "P5E_PEX2_STN5_RX_DP<80>")
	)
	(segment
		(start 349.668084 -385.341876)
		(end 349.94215 -384.909568)
		(width 0.1651)
		(layer "In9.Cu")
		(net "P5E_PEX2_STN5_RX_DP<80>")
	)
	(segment
		(start 331.964538 -340.905338)
		(end 331.964538 -340.905084)
		(width 0.1651)
		(layer "In9.Cu")
		(net "P5E_PEX2_STN5_RX_DP<80>")
	)
	(segment
		(start 290.32962 -316.455044)
		(end 290.555172 -316.229492)
		(width 0.1143)
		(layer "In9.Cu")
		(net "P5E_PEX2_STN5_RX_DP<80>")
	)
	(segment
		(start 290.81095 -316.229492)
		(end 290.89985 -316.140592)
		(width 0.1143)
		(layer "In9.Cu")
		(net "P5E_PEX2_STN5_RX_DP<80>")
	)
	(segment
		(start 331.964538 -340.905084)
		(end 331.071982 -340.10092)
		(width 0.1651)
		(layer "In9.Cu")
		(net "P5E_PEX2_STN5_RX_DP<80>")
	)
	(segment
		(start 332.716886 -395.671294)
		(end 333.006446 -395.268958)
		(width 0.1651)
		(layer "In9.Cu")
		(net "P5E_PEX2_STN5_RX_DP<80>")
	)
	(segment
		(start 296.203116 -327.160636)
		(end 293.30523 -325.30161)
		(width 0.1651)
		(layer "In9.Cu")
		(net "P5E_PEX2_STN5_RX_DP<80>")
	)
	(segment
		(start 333.84617 -394.276834)
		(end 334.738726 -393.03706)
		(width 0.1651)
		(layer "In9.Cu")
		(net "P5E_PEX2_STN5_RX_DP<80>")
	)
	(segment
		(start 331.071982 -340.10092)
		(end 296.203116 -327.160636)
		(width 0.1651)
		(layer "In9.Cu")
		(net "P5E_PEX2_STN5_RX_DP<80>")
	)
	(segment
		(start 333.704184 -394.299948)
		(end 333.84617 -394.276834)
		(width 0.1651)
		(layer "In9.Cu")
		(net "P5E_PEX2_STN5_RX_DP<80>")
	)
	(segment
		(start 334.738726 -393.03706)
		(end 335.824068 -391.951718)
		(width 0.1651)
		(layer "In9.Cu")
		(net "P5E_PEX2_STN5_RX_DP<80>")
	)
	(segment
		(start 293.30523 -325.30161)
		(end 290.560506 -322.556886)
		(width 0.1651)
		(layer "In9.Cu")
		(net "P5E_PEX2_STN5_RX_DP<80>")
	)
	(segment
		(start 333.001874 -358.572054)
		(end 333.001874 -342.003126)
		(width 0.1651)
		(layer "In9.Cu")
		(net "P5E_PEX2_STN5_RX_DP<80>")
	)
	(segment
		(start 333.437738 -394.844016)
		(end 333.414624 -394.702284)
		(width 0.1651)
		(layer "In9.Cu")
		(net "P5E_PEX2_STN5_RX_DP<80>")
	)
	(segment
		(start 331.839062 -396.999206)
		(end 332.005432 -396.83309)
		(width 0.1651)
		(layer "In9.Cu")
		(net "P5E_PEX2_STN5_RX_DP<80>")
	)
	(segment
		(start 290.89985 -316.140592)
		(end 290.89985 -315.849762)
		(width 0.1143)
		(layer "In9.Cu")
		(net "P5E_PEX2_STN5_RX_DP<80>")
	)
	(segment
		(start 290.2839 -319.8876)
		(end 290.32962 -319.84188)
		(width 0.1143)
		(layer "In9.Cu")
		(net "P5E_PEX2_STN5_RX_DP<80>")
	)
	(segment
		(start 290.2839 -319.916048)
		(end 290.2839 -319.8876)
		(width 0.1143)
		(layer "In9.Cu")
		(net "P5E_PEX2_STN5_RX_DP<80>")
	)
	(segment
		(start 336.136234 -360.122978)
		(end 333.402686 -358.972866)
		(width 0.1651)
		(layer "In9.Cu")
		(net "P5E_PEX2_STN5_RX_DP<80>")
	)
	(segment
		(start 290.2839 -322.142866)
		(end 290.2839 -319.916048)
		(width 0.1651)
		(layer "In9.Cu")
		(net "P5E_PEX2_STN5_RX_DP<80>")
	)
	(segment
		(start 349.467932 -368.15141)
		(end 345.512898 -364.93069)
		(width 0.1651)
		(layer "In9.Cu")
		(net "P5E_PEX2_STN5_RX_DP<80>")
	)
	(segment
		(start 350.223582 -369.62207)
		(end 349.467932 -368.15141)
		(width 0.1651)
		(layer "In9.Cu")
		(net "P5E_PEX2_STN5_RX_DP<80>")
	)
	(segment
		(start 290.32962 -319.84188)
		(end 290.32962 -316.455044)
		(width 0.1143)
		(layer "In9.Cu")
		(net "P5E_PEX2_STN5_RX_DP<80>")
	)
	(segment
		(start 332.005432 -396.83309)
		(end 332.74 -395.813026)
		(width 0.1651)
		(layer "In9.Cu")
		(net "P5E_PEX2_STN5_RX_DP<80>")
	)
	(segment
		(start 331.490066 -396.872206)
		(end 331.617066 -396.999206)
		(width 0.1651)
		(layer "In9.Cu")
		(net "P5E_PEX2_STN5_RX_DP<80>")
	)
	(segment
		(start 345.512898 -364.93069)
		(end 336.136234 -360.122978)
		(width 0.1651)
		(layer "In9.Cu")
		(net "P5E_PEX2_STN5_RX_DP<80>")
	)
	(segment
		(start 333.414624 -394.702284)
		(end 333.704184 -394.299948)
		(width 0.1651)
		(layer "In9.Cu")
		(net "P5E_PEX2_STN5_RX_DP<80>")
	)
	(segment
		(start 349.94215 -384.909568)
		(end 350.223582 -369.62207)
		(width 0.1651)
		(layer "In9.Cu")
		(net "P5E_PEX2_STN5_RX_DP<80>")
	)
	(segment
		(start 333.402686 -358.972866)
		(end 333.001874 -358.572054)
		(width 0.1651)
		(layer "In9.Cu")
		(net "P5E_PEX2_STN5_RX_DP<80>")
	)
	(segment
		(start 290.560506 -322.556886)
		(end 290.2839 -322.142866)
		(width 0.1651)
		(layer "In9.Cu")
		(net "P5E_PEX2_STN5_RX_DP<80>")
	)
	(segment
		(start 332.856586 -341.709502)
		(end 331.964538 -340.905338)
		(width 0.1651)
		(layer "In9.Cu")
		(net "P5E_PEX2_STN5_RX_DP<80>")
	)
	(segment
		(start 331.617066 -396.999206)
		(end 331.839062 -396.999206)
		(width 0.1651)
		(layer "In9.Cu")
		(net "P5E_PEX2_STN5_RX_DP<80>")
	)
	(segment
		(start 331.490066 -396.49019)
		(end 331.490066 -396.872206)
		(width 0.1651)
		(layer "In9.Cu")
		(net "P5E_PEX2_STN5_RX_DP<80>")
	)
	(segment
		(start 290.555172 -316.229492)
		(end 290.81095 -316.229492)
		(width 0.1143)
		(layer "In9.Cu")
		(net "P5E_PEX2_STN5_RX_DP<80>")
	)
	(segment
		(start 333.148432 -395.245844)
		(end 333.437738 -394.844016)
		(width 0.1651)
		(layer "In9.Cu")
		(net "P5E_PEX2_STN5_RX_DP<80>")
	)
	(segment
		(start 333.001874 -342.003126)
		(end 332.856586 -341.709502)
		(width 0.1651)
		(layer "In9.Cu")
		(net "P5E_PEX2_STN5_RX_DP<80>")
	)
	(segment
		(start 332.74 -395.813026)
		(end 332.716886 -395.671294)
		(width 0.1651)
		(layer "In9.Cu")
		(net "P5E_PEX2_STN5_RX_DP<80>")
	)
	(segment
		(start 422.217088 -153.99512)
		(end 422.057068 -154.15514)
		(width 0.13462)
		(layer "F.Cu")
		(net "P5E_PEX3_STN0_TX_C_DN<14>")
	)
	(segment
		(start 422.057068 -154.15514)
		(end 421.557704 -154.15514)
		(width 0.13462)
		(layer "F.Cu")
		(net "P5E_PEX3_STN0_TX_C_DN<14>")
	)
	(segment
		(start 428.052738 -154.304746)
		(end 427.743112 -153.99512)
		(width 0.13462)
		(layer "F.Cu")
		(net "P5E_PEX3_STN0_TX_C_DN<14>")
	)
	(segment
		(start 427.743112 -153.99512)
		(end 422.217088 -153.99512)
		(width 0.13462)
		(layer "F.Cu")
		(net "P5E_PEX3_STN0_TX_C_DN<14>")
	)
	(segment
		(start 435.355238 -384.08102)
		(end 436.0545 -383.381758)
		(width 0.1651)
		(layer "In9.Cu")
		(net "P5E_PEX3_STN7_RX_DN<127>")
	)
	(segment
		(start 443.642242 -341.357204)
		(end 442.920882 -340.383622)
		(width 0.1651)
		(layer "In9.Cu")
		(net "P5E_PEX3_STN7_RX_DN<127>")
	)
	(segment
		(start 436.0545 -369.74272)
		(end 436.640732 -367.94567)
		(width 0.1651)
		(layer "In9.Cu")
		(net "P5E_PEX3_STN7_RX_DN<127>")
	)
	(segment
		(start 390.713214 -320.616834)
		(end 390.515856 -320.41973)
		(width 0.1651)
		(layer "In9.Cu")
		(net "P5E_PEX3_STN7_RX_DN<127>")
	)
	(segment
		(start 435.01691 -384.08102)
		(end 435.355238 -384.08102)
		(width 0.1651)
		(layer "In9.Cu")
		(net "P5E_PEX3_STN7_RX_DN<127>")
	)
	(segment
		(start 390.849866 -318.409066)
		(end 390.849866 -318.699896)
		(width 0.1143)
		(layer "In9.Cu")
		(net "P5E_PEX3_STN7_RX_DN<127>")
	)
	(segment
		(start 443.646814 -357.827326)
		(end 443.642242 -341.357204)
		(width 0.1651)
		(layer "In9.Cu")
		(net "P5E_PEX3_STN7_RX_DN<127>")
	)
	(segment
		(start 439.69813 -339.399626)
		(end 421.242744 -332.485492)
		(width 0.1651)
		(layer "In9.Cu")
		(net "P5E_PEX3_STN7_RX_DN<127>")
	)
	(segment
		(start 442.920882 -340.383622)
		(end 439.69813 -339.399626)
		(width 0.1651)
		(layer "In9.Cu")
		(net "P5E_PEX3_STN7_RX_DN<127>")
	)
	(segment
		(start 390.470136 -318.447674)
		(end 390.597644 -318.320166)
		(width 0.1143)
		(layer "In9.Cu")
		(net "P5E_PEX3_STN7_RX_DN<127>")
	)
	(segment
		(start 390.597644 -318.320166)
		(end 390.760966 -318.320166)
		(width 0.1143)
		(layer "In9.Cu")
		(net "P5E_PEX3_STN7_RX_DN<127>")
	)
	(segment
		(start 390.760966 -318.320166)
		(end 390.849866 -318.409066)
		(width 0.1143)
		(layer "In9.Cu")
		(net "P5E_PEX3_STN7_RX_DN<127>")
	)
	(segment
		(start 421.242744 -332.485492)
		(end 407.0223 -325.779638)
		(width 0.1651)
		(layer "In9.Cu")
		(net "P5E_PEX3_STN7_RX_DN<127>")
	)
	(segment
		(start 442.903102 -359.36809)
		(end 443.646814 -357.827326)
		(width 0.1651)
		(layer "In9.Cu")
		(net "P5E_PEX3_STN7_RX_DN<127>")
	)
	(segment
		(start 436.0545 -383.381758)
		(end 436.0545 -369.74272)
		(width 0.1651)
		(layer "In9.Cu")
		(net "P5E_PEX3_STN7_RX_DN<127>")
	)
	(segment
		(start 407.0223 -325.779638)
		(end 394.10894 -321.691762)
		(width 0.1651)
		(layer "In9.Cu")
		(net "P5E_PEX3_STN7_RX_DN<127>")
	)
	(segment
		(start 434.88991 -384.20802)
		(end 435.01691 -384.08102)
		(width 0.1651)
		(layer "In9.Cu")
		(net "P5E_PEX3_STN7_RX_DN<127>")
	)
	(segment
		(start 390.515856 -319.865248)
		(end 390.470136 -319.819528)
		(width 0.1143)
		(layer "In9.Cu")
		(net "P5E_PEX3_STN7_RX_DN<127>")
	)
	(segment
		(start 436.640732 -367.94567)
		(end 442.903102 -359.36809)
		(width 0.1651)
		(layer "In9.Cu")
		(net "P5E_PEX3_STN7_RX_DN<127>")
	)
	(segment
		(start 394.10894 -321.691762)
		(end 394.04925 -321.576954)
		(width 0.1651)
		(layer "In9.Cu")
		(net "P5E_PEX3_STN7_RX_DN<127>")
	)
	(segment
		(start 394.04925 -321.576954)
		(end 393.57681 -321.427348)
		(width 0.1651)
		(layer "In9.Cu")
		(net "P5E_PEX3_STN7_RX_DN<127>")
	)
	(segment
		(start 393.462002 -321.487038)
		(end 390.713214 -320.616834)
		(width 0.1651)
		(layer "In9.Cu")
		(net "P5E_PEX3_STN7_RX_DN<127>")
	)
	(segment
		(start 390.515856 -320.41973)
		(end 390.515856 -319.893696)
		(width 0.1651)
		(layer "In9.Cu")
		(net "P5E_PEX3_STN7_RX_DN<127>")
	)
	(segment
		(start 390.470136 -319.819528)
		(end 390.470136 -318.447674)
		(width 0.1143)
		(layer "In9.Cu")
		(net "P5E_PEX3_STN7_RX_DN<127>")
	)
	(segment
		(start 390.515856 -319.893696)
		(end 390.515856 -319.865248)
		(width 0.1143)
		(layer "In9.Cu")
		(net "P5E_PEX3_STN7_RX_DN<127>")
	)
	(segment
		(start 393.57681 -321.427348)
		(end 393.462002 -321.487038)
		(width 0.1651)
		(layer "In9.Cu")
		(net "P5E_PEX3_STN7_RX_DN<127>")
	)
	(segment
		(start 434.88991 -384.590036)
		(end 434.88991 -384.20802)
		(width 0.1651)
		(layer "In9.Cu")
		(net "P5E_PEX3_STN7_RX_DN<127>")
	)
	(segment
		(start 409.869132 -102.798372)
		(end 413.34182 -102.798372)
		(width 0.13208)
		(layer "F.Cu")
		(net "NCSI_NIC7_TXD1")
	)
	(segment
		(start 413.34182 -102.798372)
		(end 414.90011 -101.240082)
		(width 0.13208)
		(layer "F.Cu")
		(net "NCSI_NIC7_TXD1")
	)
	(segment
		(start 414.90011 -101.240082)
		(end 416.95751 -101.240082)
		(width 0.13208)
		(layer "F.Cu")
		(net "NCSI_NIC7_TXD1")
	)
	(segment
		(start 407.695146 -102.798372)
		(end 409.869132 -102.798372)
		(width 0.13208)
		(layer "F.Cu")
		(net "NCSI_NIC7_TXD1")
	)
	(via
		(at 409.869132 -102.798372)
		(size 0.762)
		(drill 0.381)
		(layers "F.Cu" "B.Cu")
		(net "NCSI_NIC7_TXD1")
	)
	(segment
		(start 124.27204 -24.807418)
		(end 125.102366 -24.807418)
		(width 0.13208)
		(layer "F.Cu")
		(net "PU_CLKREQ4")
	)
	(segment
		(start 125.119638 -24.790146)
		(end 125.102366 -24.807418)
		(width 0.13208)
		(layer "F.Cu")
		(net "PU_CLKREQ4")
	)
	(segment
		(start 126.76505 -24.790146)
		(end 125.119638 -24.790146)
		(width 0.13208)
		(layer "F.Cu")
		(net "PU_CLKREQ4")
	)
	(via
		(at 125.102366 -24.807418)
		(size 0.508)
		(drill 0.254)
		(layers "F.Cu" "B.Cu")
		(net "PU_CLKREQ4")
	)
	(segment
		(start 82.075782 -148.592286)
		(end 82.394806 -148.91131)
		(width 0.13462)
		(layer "F.Cu")
		(net "P5E_PEX0_STN0_TX_C_DP<11>")
	)
	(segment
		(start 73.745852 -148.7551)
		(end 73.908666 -148.592286)
		(width 0.13462)
		(layer "F.Cu")
		(net "P5E_PEX0_STN0_TX_C_DP<11>")
	)
	(segment
		(start 73.257664 -148.7551)
		(end 73.745852 -148.7551)
		(width 0.13462)
		(layer "F.Cu")
		(net "P5E_PEX0_STN0_TX_C_DP<11>")
	)
	(segment
		(start 73.908666 -148.592286)
		(end 82.075782 -148.592286)
		(width 0.13462)
		(layer "F.Cu")
		(net "P5E_PEX0_STN0_TX_C_DP<11>")
	)
	(segment
		(start 161.654236 -119.355108)
		(end 161.491422 -119.517922)
		(width 0.13462)
		(layer "F.Cu")
		(net "P5E_PEX1_STN1_TX_C_DP<24>")
	)
	(segment
		(start 161.491422 -119.517922)
		(end 153.324052 -119.517922)
		(width 0.13462)
		(layer "F.Cu")
		(net "P5E_PEX1_STN1_TX_C_DP<24>")
	)
	(segment
		(start 162.14217 -119.355108)
		(end 161.654236 -119.355108)
		(width 0.13462)
		(layer "F.Cu")
		(net "P5E_PEX1_STN1_TX_C_DP<24>")
	)
	(segment
		(start 153.324052 -119.517922)
		(end 153.005028 -119.198898)
		(width 0.13462)
		(layer "F.Cu")
		(net "P5E_PEX1_STN1_TX_C_DP<24>")
	)
	(segment
		(start 277.739348 -132.964936)
		(end 278.242268 -132.964936)
		(width 0.13462)
		(layer "F.Cu")
		(net "P5E_PEX2_STN1_TX_C_DP<29>")
	)
	(segment
		(start 272.065496 -132.81152)
		(end 277.585932 -132.81152)
		(width 0.13462)
		(layer "F.Cu")
		(net "P5E_PEX2_STN1_TX_C_DP<29>")
	)
	(segment
		(start 271.747234 -133.129782)
		(end 272.065496 -132.81152)
		(width 0.13462)
		(layer "F.Cu")
		(net "P5E_PEX2_STN1_TX_C_DP<29>")
	)
	(segment
		(start 277.585932 -132.81152)
		(end 277.739348 -132.964936)
		(width 0.13462)
		(layer "F.Cu")
		(net "P5E_PEX2_STN1_TX_C_DP<29>")
	)
	(segment
		(start 293.41572 -319.8876)
		(end 293.41572 -319.916048)
		(width 0.1143)
		(layer "In9.Cu")
		(net "P5E_PEX2_STN5_RX_DN<83>")
	)
	(segment
		(start 353.379532 -388.035038)
		(end 352.717354 -388.513828)
		(width 0.1651)
		(layer "In9.Cu")
		(net "P5E_PEX2_STN5_RX_DN<83>")
	)
	(segment
		(start 354.682552 -386.17271)
		(end 354.311458 -386.908548)
		(width 0.1651)
		(layer "In9.Cu")
		(net "P5E_PEX2_STN5_RX_DN<83>")
	)
	(segment
		(start 339.375496 -394.863574)
		(end 339.215984 -395.26718)
		(width 0.1651)
		(layer "In9.Cu")
		(net "P5E_PEX2_STN5_RX_DN<83>")
	)
	(segment
		(start 354.965762 -370.737638)
		(end 354.682552 -386.17271)
		(width 0.1651)
		(layer "In9.Cu")
		(net "P5E_PEX2_STN5_RX_DN<83>")
	)
	(segment
		(start 342.02624 -340.42096)
		(end 342.610694 -342.157558)
		(width 0.1651)
		(layer "In9.Cu")
		(net "P5E_PEX2_STN5_RX_DN<83>")
	)
	(segment
		(start 298.87672 -324.63867)
		(end 298.87672 -324.638416)
		(width 0.1651)
		(layer "In9.Cu")
		(net "P5E_PEX2_STN5_RX_DN<83>")
	)
	(segment
		(start 293.74973 -318.699896)
		(end 293.74973 -318.409066)
		(width 0.1143)
		(layer "In9.Cu")
		(net "P5E_PEX2_STN5_RX_DN<83>")
	)
	(segment
		(start 338.764118 -398.38122)
		(end 338.217002 -398.38122)
		(width 0.1651)
		(layer "In9.Cu")
		(net "P5E_PEX2_STN5_RX_DN<83>")
	)
	(segment
		(start 353.341432 -366.766094)
		(end 354.47224 -368.75974)
		(width 0.1651)
		(layer "In9.Cu")
		(net "P5E_PEX2_STN5_RX_DN<83>")
	)
	(segment
		(start 293.41572 -319.916048)
		(end 293.41572 -320.415412)
		(width 0.1651)
		(layer "In9.Cu")
		(net "P5E_PEX2_STN5_RX_DN<83>")
	)
	(segment
		(start 297.26128 -324.047612)
		(end 298.220638 -324.398386)
		(width 0.1651)
		(layer "In9.Cu")
		(net "P5E_PEX2_STN5_RX_DN<83>")
	)
	(segment
		(start 338.090002 -398.50822)
		(end 338.090002 -398.890236)
		(width 0.1651)
		(layer "In9.Cu")
		(net "P5E_PEX2_STN5_RX_DN<83>")
	)
	(segment
		(start 293.37 -318.434212)
		(end 293.37 -319.84188)
		(width 0.1143)
		(layer "In9.Cu")
		(net "P5E_PEX2_STN5_RX_DN<83>")
	)
	(segment
		(start 293.74973 -318.409066)
		(end 293.66083 -318.320166)
		(width 0.1143)
		(layer "In9.Cu")
		(net "P5E_PEX2_STN5_RX_DN<83>")
	)
	(segment
		(start 293.484046 -318.320166)
		(end 293.37 -318.434212)
		(width 0.1143)
		(layer "In9.Cu")
		(net "P5E_PEX2_STN5_RX_DN<83>")
	)
	(segment
		(start 342.610694 -358.511094)
		(end 342.93556 -358.83596)
		(width 0.1651)
		(layer "In9.Cu")
		(net "P5E_PEX2_STN5_RX_DN<83>")
	)
	(segment
		(start 293.66083 -318.320166)
		(end 293.484046 -318.320166)
		(width 0.1143)
		(layer "In9.Cu")
		(net "P5E_PEX2_STN5_RX_DN<83>")
	)
	(segment
		(start 347.692472 -361.920028)
		(end 353.341432 -366.766094)
		(width 0.1651)
		(layer "In9.Cu")
		(net "P5E_PEX2_STN5_RX_DN<83>")
	)
	(segment
		(start 352.717354 -388.513828)
		(end 343.805256 -391.990072)
		(width 0.1651)
		(layer "In9.Cu")
		(net "P5E_PEX2_STN5_RX_DN<83>")
	)
	(segment
		(start 294.337486 -321.794886)
		(end 295.406572 -322.863972)
		(width 0.1651)
		(layer "In9.Cu")
		(net "P5E_PEX2_STN5_RX_DN<83>")
	)
	(segment
		(start 295.406572 -322.863972)
		(end 297.26128 -324.047612)
		(width 0.1651)
		(layer "In9.Cu")
		(net "P5E_PEX2_STN5_RX_DN<83>")
	)
	(segment
		(start 293.41572 -320.415412)
		(end 294.337486 -321.794886)
		(width 0.1651)
		(layer "In9.Cu")
		(net "P5E_PEX2_STN5_RX_DN<83>")
	)
	(segment
		(start 298.220638 -324.398386)
		(end 298.35094 -324.337934)
		(width 0.1651)
		(layer "In9.Cu")
		(net "P5E_PEX2_STN5_RX_DN<83>")
	)
	(segment
		(start 342.93556 -358.83596)
		(end 347.692472 -361.920028)
		(width 0.1651)
		(layer "In9.Cu")
		(net "P5E_PEX2_STN5_RX_DN<83>")
	)
	(segment
		(start 293.37 -319.84188)
		(end 293.41572 -319.8876)
		(width 0.1143)
		(layer "In9.Cu")
		(net "P5E_PEX2_STN5_RX_DN<83>")
	)
	(segment
		(start 342.610694 -342.157558)
		(end 342.610694 -358.511094)
		(width 0.1651)
		(layer "In9.Cu")
		(net "P5E_PEX2_STN5_RX_DN<83>")
	)
	(segment
		(start 339.215984 -395.26718)
		(end 339.215984 -397.929354)
		(width 0.1651)
		(layer "In9.Cu")
		(net "P5E_PEX2_STN5_RX_DN<83>")
	)
	(segment
		(start 298.87672 -324.638416)
		(end 342.02624 -340.42096)
		(width 0.1651)
		(layer "In9.Cu")
		(net "P5E_PEX2_STN5_RX_DN<83>")
	)
	(segment
		(start 298.816268 -324.508114)
		(end 298.87672 -324.63867)
		(width 0.1651)
		(layer "In9.Cu")
		(net "P5E_PEX2_STN5_RX_DN<83>")
	)
	(segment
		(start 354.311458 -386.908548)
		(end 353.379532 -388.035038)
		(width 0.1651)
		(layer "In9.Cu")
		(net "P5E_PEX2_STN5_RX_DN<83>")
	)
	(segment
		(start 339.215984 -397.929354)
		(end 338.764118 -398.38122)
		(width 0.1651)
		(layer "In9.Cu")
		(net "P5E_PEX2_STN5_RX_DN<83>")
	)
	(segment
		(start 354.47224 -368.75974)
		(end 354.965762 -370.737638)
		(width 0.1651)
		(layer "In9.Cu")
		(net "P5E_PEX2_STN5_RX_DN<83>")
	)
	(segment
		(start 343.805256 -391.990072)
		(end 339.375496 -394.863574)
		(width 0.1651)
		(layer "In9.Cu")
		(net "P5E_PEX2_STN5_RX_DN<83>")
	)
	(segment
		(start 338.217002 -398.38122)
		(end 338.090002 -398.50822)
		(width 0.1651)
		(layer "In9.Cu")
		(net "P5E_PEX2_STN5_RX_DN<83>")
	)
	(segment
		(start 298.35094 -324.337934)
		(end 298.816268 -324.508114)
		(width 0.1651)
		(layer "In9.Cu")
		(net "P5E_PEX2_STN5_RX_DN<83>")
	)
	(segment
		(start 416.312604 -118.999)
		(end 416.476688 -118.834916)
		(width 0.13462)
		(layer "F.Cu")
		(net "P5E_PEX3_STN0_RX_DN<0>")
	)
	(segment
		(start 416.476688 -118.834916)
		(end 416.95751 -118.834916)
		(width 0.13462)
		(layer "F.Cu")
		(net "P5E_PEX3_STN0_RX_DN<0>")
	)
	(segment
		(start 415.652712 -118.999)
		(end 416.312604 -118.999)
		(width 0.13462)
		(layer "F.Cu")
		(net "P5E_PEX3_STN0_RX_DN<0>")
	)
	(segment
		(start 415.35731 -118.703598)
		(end 415.652712 -118.999)
		(width 0.13462)
		(layer "F.Cu")
		(net "P5E_PEX3_STN0_RX_DN<0>")
	)
	(segment
		(start 428.58436 -288.299906)
		(end 428.47006 -288.185606)
		(width 0.1143)
		(layer "In5.Cu")
		(net "P5E_PEX3_STN0_RX_DN<0>")
	)
	(segment
		(start 434.476144 -131.877562)
		(end 433.688998 -130.84302)
		(width 0.1651)
		(layer "In5.Cu")
		(net "P5E_PEX3_STN0_RX_DN<0>")
	)
	(segment
		(start 415.64814 -118.994428)
		(end 415.35731 -118.703598)
		(width 0.1651)
		(layer "In5.Cu")
		(net "P5E_PEX3_STN0_RX_DN<0>")
	)
	(segment
		(start 428.84979 -288.299906)
		(end 428.58436 -288.299906)
		(width 0.1143)
		(layer "In5.Cu")
		(net "P5E_PEX3_STN0_RX_DN<0>")
	)
	(segment
		(start 422.492678 -122.49404)
		(end 420.968678 -120.97512)
		(width 0.1651)
		(layer "In5.Cu")
		(net "P5E_PEX3_STN0_RX_DN<0>")
	)
	(segment
		(start 437.555894 -145.583656)
		(end 434.476144 -131.877562)
		(width 0.1651)
		(layer "In5.Cu")
		(net "P5E_PEX3_STN0_RX_DN<0>")
	)
	(segment
		(start 447.788538 -273.725132)
		(end 447.974466 -269.124938)
		(width 0.1651)
		(layer "In5.Cu")
		(net "P5E_PEX3_STN0_RX_DN<0>")
	)
	(segment
		(start 416.183064 -118.994428)
		(end 415.64814 -118.994428)
		(width 0.1651)
		(layer "In5.Cu")
		(net "P5E_PEX3_STN0_RX_DN<0>")
	)
	(segment
		(start 439.267092 -239.218724)
		(end 437.73979 -231.87533)
		(width 0.1651)
		(layer "In5.Cu")
		(net "P5E_PEX3_STN0_RX_DN<0>")
	)
	(segment
		(start 428.47006 -288.052764)
		(end 428.602648 -287.920176)
		(width 0.1143)
		(layer "In5.Cu")
		(net "P5E_PEX3_STN0_RX_DN<0>")
	)
	(segment
		(start 447.974466 -269.124938)
		(end 439.267092 -239.218724)
		(width 0.1651)
		(layer "In5.Cu")
		(net "P5E_PEX3_STN0_RX_DN<0>")
	)
	(segment
		(start 432.19624 -287.965896)
		(end 432.224688 -287.965896)
		(width 0.1143)
		(layer "In5.Cu")
		(net "P5E_PEX3_STN0_RX_DN<0>")
	)
	(segment
		(start 438.406032 -168.524174)
		(end 437.953404 -149.82825)
		(width 0.1651)
		(layer "In5.Cu")
		(net "P5E_PEX3_STN0_RX_DN<0>")
	)
	(segment
		(start 428.47006 -288.185606)
		(end 428.47006 -288.052764)
		(width 0.1143)
		(layer "In5.Cu")
		(net "P5E_PEX3_STN0_RX_DN<0>")
	)
	(segment
		(start 434.808884 -287.965896)
		(end 436.034434 -287.19272)
		(width 0.1651)
		(layer "In5.Cu")
		(net "P5E_PEX3_STN0_RX_DN<0>")
	)
	(segment
		(start 436.034434 -287.19272)
		(end 445.140842 -278.399748)
		(width 0.1651)
		(layer "In5.Cu")
		(net "P5E_PEX3_STN0_RX_DN<0>")
	)
	(segment
		(start 437.73979 -231.87533)
		(end 438.406032 -168.524174)
		(width 0.1651)
		(layer "In5.Cu")
		(net "P5E_PEX3_STN0_RX_DN<0>")
	)
	(segment
		(start 432.15052 -287.920176)
		(end 432.19624 -287.965896)
		(width 0.1143)
		(layer "In5.Cu")
		(net "P5E_PEX3_STN0_RX_DN<0>")
	)
	(segment
		(start 433.688998 -130.84302)
		(end 422.492678 -122.49404)
		(width 0.1651)
		(layer "In5.Cu")
		(net "P5E_PEX3_STN0_RX_DN<0>")
	)
	(segment
		(start 420.968678 -120.97512)
		(end 416.183064 -118.994428)
		(width 0.1651)
		(layer "In5.Cu")
		(net "P5E_PEX3_STN0_RX_DN<0>")
	)
	(segment
		(start 428.602648 -287.920176)
		(end 432.15052 -287.920176)
		(width 0.1143)
		(layer "In5.Cu")
		(net "P5E_PEX3_STN0_RX_DN<0>")
	)
	(segment
		(start 437.953404 -149.82825)
		(end 437.555894 -145.583656)
		(width 0.1651)
		(layer "In5.Cu")
		(net "P5E_PEX3_STN0_RX_DN<0>")
	)
	(segment
		(start 432.224688 -287.965896)
		(end 434.808884 -287.965896)
		(width 0.1651)
		(layer "In5.Cu")
		(net "P5E_PEX3_STN0_RX_DN<0>")
	)
	(segment
		(start 445.140842 -278.399748)
		(end 447.788538 -273.725132)
		(width 0.1651)
		(layer "In5.Cu")
		(net "P5E_PEX3_STN0_RX_DN<0>")
	)
	(segment
		(start 415.487612 -356.511606)
		(end 415.80816 -356.832154)
		(width 0.13462)
		(layer "F.Cu")
		(net "P5E_PEX3_STN7_TX_C_DP<115>")
	)
	(segment
		(start 415.80816 -356.832154)
		(end 415.80816 -357.462582)
		(width 0.13462)
		(layer "F.Cu")
		(net "P5E_PEX3_STN7_TX_C_DP<115>")
	)
	(segment
		(start 415.80816 -357.462582)
		(end 415.513012 -357.75773)
		(width 0.13462)
		(layer "F.Cu")
		(net "P5E_PEX3_STN7_TX_C_DP<115>")
	)
	(segment
		(start 414.385252 -367.020348)
		(end 414.46577 -366.531398)
		(width 0.1651)
		(layer "In11.Cu")
		(net "P5E_PEX3_STN7_TX_C_DP<115>")
	)
	(segment
		(start 426.107606 -394.704316)
		(end 426.107606 -394.578586)
		(width 0.1651)
		(layer "In11.Cu")
		(net "P5E_PEX3_STN7_TX_C_DP<115>")
	)
	(segment
		(start 413.716978 -383.518156)
		(end 414.156906 -368.876834)
		(width 0.1651)
		(layer "In11.Cu")
		(net "P5E_PEX3_STN7_TX_C_DP<115>")
	)
	(segment
		(start 414.633918 -365.979964)
		(end 414.57118 -365.892588)
		(width 0.1651)
		(layer "In11.Cu")
		(net "P5E_PEX3_STN7_TX_C_DP<115>")
	)
	(segment
		(start 426.583856 -395.054836)
		(end 426.458126 -395.054836)
		(width 0.1651)
		(layer "In11.Cu")
		(net "P5E_PEX3_STN7_TX_C_DP<115>")
	)
	(segment
		(start 426.216826 -401.999196)
		(end 426.647102 -401.999196)
		(width 0.1651)
		(layer "In11.Cu")
		(net "P5E_PEX3_STN7_TX_C_DP<115>")
	)
	(segment
		(start 426.647102 -401.999196)
		(end 426.933868 -401.71243)
		(width 0.1651)
		(layer "In11.Cu")
		(net "P5E_PEX3_STN7_TX_C_DP<115>")
	)
	(segment
		(start 415.803842 -358.04856)
		(end 415.513012 -357.75773)
		(width 0.1651)
		(layer "In11.Cu")
		(net "P5E_PEX3_STN7_TX_C_DP<115>")
	)
	(segment
		(start 415.803842 -358.876346)
		(end 415.803842 -358.04856)
		(width 0.1651)
		(layer "In11.Cu")
		(net "P5E_PEX3_STN7_TX_C_DP<115>")
	)
	(segment
		(start 414.448244 -367.107978)
		(end 414.385252 -367.020348)
		(width 0.1651)
		(layer "In11.Cu")
		(net "P5E_PEX3_STN7_TX_C_DP<115>")
	)
	(segment
		(start 426.933868 -401.71243)
		(end 426.933868 -395.404848)
		(width 0.1651)
		(layer "In11.Cu")
		(net "P5E_PEX3_STN7_TX_C_DP<115>")
	)
	(segment
		(start 426.933868 -395.404848)
		(end 426.583856 -395.054836)
		(width 0.1651)
		(layer "In11.Cu")
		(net "P5E_PEX3_STN7_TX_C_DP<115>")
	)
	(segment
		(start 415.704782 -389.183626)
		(end 414.000188 -385.782058)
		(width 0.1651)
		(layer "In11.Cu")
		(net "P5E_PEX3_STN7_TX_C_DP<115>")
	)
	(segment
		(start 414.156906 -368.876834)
		(end 414.448244 -367.107978)
		(width 0.1651)
		(layer "In11.Cu")
		(net "P5E_PEX3_STN7_TX_C_DP<115>")
	)
	(segment
		(start 415.803588 -358.8766)
		(end 415.803842 -358.876346)
		(width 0.1651)
		(layer "In11.Cu")
		(net "P5E_PEX3_STN7_TX_C_DP<115>")
	)
	(segment
		(start 414.739582 -365.340646)
		(end 414.739074 -365.340646)
		(width 0.1651)
		(layer "In11.Cu")
		(net "P5E_PEX3_STN7_TX_C_DP<115>")
	)
	(segment
		(start 414.000188 -385.782058)
		(end 413.716978 -383.518156)
		(width 0.1651)
		(layer "In11.Cu")
		(net "P5E_PEX3_STN7_TX_C_DP<115>")
	)
	(segment
		(start 426.107606 -394.578586)
		(end 425.31284 -393.78382)
		(width 0.1651)
		(layer "In11.Cu")
		(net "P5E_PEX3_STN7_TX_C_DP<115>")
	)
	(segment
		(start 414.739074 -365.340646)
		(end 415.803588 -358.8766)
		(width 0.1651)
		(layer "In11.Cu")
		(net "P5E_PEX3_STN7_TX_C_DP<115>")
	)
	(segment
		(start 426.458126 -395.054836)
		(end 426.107606 -394.704316)
		(width 0.1651)
		(layer "In11.Cu")
		(net "P5E_PEX3_STN7_TX_C_DP<115>")
	)
	(segment
		(start 426.089826 -401.49018)
		(end 426.089826 -401.872196)
		(width 0.1651)
		(layer "In11.Cu")
		(net "P5E_PEX3_STN7_TX_C_DP<115>")
	)
	(segment
		(start 414.651698 -365.403638)
		(end 414.739582 -365.340646)
		(width 0.1651)
		(layer "In11.Cu")
		(net "P5E_PEX3_STN7_TX_C_DP<115>")
	)
	(segment
		(start 414.46577 -366.531398)
		(end 414.553654 -366.46866)
		(width 0.1651)
		(layer "In11.Cu")
		(net "P5E_PEX3_STN7_TX_C_DP<115>")
	)
	(segment
		(start 414.553654 -366.46866)
		(end 414.633918 -365.979964)
		(width 0.1651)
		(layer "In11.Cu")
		(net "P5E_PEX3_STN7_TX_C_DP<115>")
	)
	(segment
		(start 425.31284 -393.78382)
		(end 415.704782 -389.183626)
		(width 0.1651)
		(layer "In11.Cu")
		(net "P5E_PEX3_STN7_TX_C_DP<115>")
	)
	(segment
		(start 414.57118 -365.892588)
		(end 414.651698 -365.403638)
		(width 0.1651)
		(layer "In11.Cu")
		(net "P5E_PEX3_STN7_TX_C_DP<115>")
	)
	(segment
		(start 426.089826 -401.872196)
		(end 426.216826 -401.999196)
		(width 0.1651)
		(layer "In11.Cu")
		(net "P5E_PEX3_STN7_TX_C_DP<115>")
	)
	(segment
		(start 420.24173 -113.43513)
		(end 421.557704 -113.43513)
		(width 0.13208)
		(layer "F.Cu")
		(net "NIC7_BIF1_N")
	)
	(segment
		(start 419.046406 -112.239806)
		(end 420.24173 -113.43513)
		(width 0.13208)
		(layer "F.Cu")
		(net "NIC7_BIF1_N")
	)
	(segment
		(start 419.046406 -111.884206)
		(end 419.046406 -112.239806)
		(width 0.13208)
		(layer "F.Cu")
		(net "NIC7_BIF1_N")
	)
	(via
		(at 419.046406 -111.884206)
		(size 0.508)
		(drill 0.254)
		(layers "F.Cu" "B.Cu")
		(net "NIC7_BIF1_N")
	)
	(segment
		(start 417.281614 -109.133132)
		(end 416.633914 -108.485432)
		(width 0.13208)
		(layer "B.Cu")
		(net "NIC7_BIF1_N")
	)
	(segment
		(start 411.275276 -109.481366)
		(end 410.297376 -109.481366)
		(width 0.13208)
		(layer "B.Cu")
		(net "NIC7_BIF1_N")
	)
	(segment
		(start 416.633914 -108.485432)
		(end 414.803336 -108.485432)
		(width 0.13208)
		(layer "B.Cu")
		(net "NIC7_BIF1_N")
	)
	(segment
		(start 414.803336 -108.485432)
		(end 414.328356 -108.960412)
		(width 0.13208)
		(layer "B.Cu")
		(net "NIC7_BIF1_N")
	)
	(segment
		(start 411.51302 -108.960412)
		(end 411.275276 -109.198156)
		(width 0.13208)
		(layer "B.Cu")
		(net "NIC7_BIF1_N")
	)
	(segment
		(start 414.328356 -108.960412)
		(end 411.51302 -108.960412)
		(width 0.13208)
		(layer "B.Cu")
		(net "NIC7_BIF1_N")
	)
	(segment
		(start 411.275276 -109.198156)
		(end 411.275276 -109.481366)
		(width 0.13208)
		(layer "B.Cu")
		(net "NIC7_BIF1_N")
	)
	(segment
		(start 417.281614 -110.119414)
		(end 417.281614 -109.133132)
		(width 0.13208)
		(layer "B.Cu")
		(net "NIC7_BIF1_N")
	)
	(segment
		(start 419.046406 -111.884206)
		(end 417.281614 -110.119414)
		(width 0.13208)
		(layer "B.Cu")
		(net "NIC7_BIF1_N")
	)
	(segment
		(start 151.119586 -24.790146)
		(end 151.102314 -24.807418)
		(width 0.13208)
		(layer "F.Cu")
		(net "PU_CLKREQ5")
	)
	(segment
		(start 152.764998 -24.790146)
		(end 151.119586 -24.790146)
		(width 0.13208)
		(layer "F.Cu")
		(net "PU_CLKREQ5")
	)
	(segment
		(start 150.271988 -24.807418)
		(end 151.102314 -24.807418)
		(width 0.13208)
		(layer "F.Cu")
		(net "PU_CLKREQ5")
	)
	(via
		(at 151.102314 -24.807418)
		(size 0.508)
		(drill 0.254)
		(layers "F.Cu" "B.Cu")
		(net "PU_CLKREQ5")
	)
	(segment
		(start 79.440278 -134.082282)
		(end 79.752698 -134.394702)
		(width 0.13462)
		(layer "F.Cu")
		(net "P5E_PEX0_STN0_TX_C_DP<6>")
	)
	(segment
		(start 73.908666 -134.082282)
		(end 79.440278 -134.082282)
		(width 0.13462)
		(layer "F.Cu")
		(net "P5E_PEX0_STN0_TX_C_DP<6>")
	)
	(segment
		(start 73.257664 -134.245096)
		(end 73.745852 -134.245096)
		(width 0.13462)
		(layer "F.Cu")
		(net "P5E_PEX0_STN0_TX_C_DP<6>")
	)
	(segment
		(start 73.745852 -134.245096)
		(end 73.908666 -134.082282)
		(width 0.13462)
		(layer "F.Cu")
		(net "P5E_PEX0_STN0_TX_C_DP<6>")
	)
	(segment
		(start 169.902124 -110.68177)
		(end 170.196764 -110.97641)
		(width 0.13462)
		(layer "F.Cu")
		(net "P5E_PEX1_STN1_RX_DN<22>")
	)
	(segment
		(start 166.742364 -110.845092)
		(end 167.230298 -110.845092)
		(width 0.13462)
		(layer "F.Cu")
		(net "P5E_PEX1_STN1_RX_DN<22>")
	)
	(segment
		(start 167.393112 -110.682278)
		(end 169.901616 -110.682278)
		(width 0.13462)
		(layer "F.Cu")
		(net "P5E_PEX1_STN1_RX_DN<22>")
	)
	(segment
		(start 167.230298 -110.845092)
		(end 167.393112 -110.682278)
		(width 0.13462)
		(layer "F.Cu")
		(net "P5E_PEX1_STN1_RX_DN<22>")
	)
	(segment
		(start 169.901616 -110.682278)
		(end 169.902124 -110.68177)
		(width 0.13462)
		(layer "F.Cu")
		(net "P5E_PEX1_STN1_RX_DN<22>")
	)
	(segment
		(start 158.23692 -120.053862)
		(end 158.330646 -120.185688)
		(width 0.1651)
		(layer "In5.Cu")
		(net "P5E_PEX1_STN1_RX_DN<22>")
	)
	(segment
		(start 153.425144 -140.713968)
		(end 151.555958 -144.875758)
		(width 0.1651)
		(layer "In5.Cu")
		(net "P5E_PEX1_STN1_RX_DN<22>")
	)
	(segment
		(start 157.913832 -121.970546)
		(end 155.37942 -137.015474)
		(width 0.1651)
		(layer "In5.Cu")
		(net "P5E_PEX1_STN1_RX_DN<22>")
	)
	(segment
		(start 165.225476 -111.792258)
		(end 165.162738 -111.941356)
		(width 0.1651)
		(layer "In5.Cu")
		(net "P5E_PEX1_STN1_RX_DN<22>")
	)
	(segment
		(start 181.11597 -271.526)
		(end 181.11597 -271.554448)
		(width 0.1143)
		(layer "In5.Cu")
		(net "P5E_PEX1_STN1_RX_DN<22>")
	)
	(segment
		(start 167.484298 -110.87227)
		(end 167.421306 -111.021368)
		(width 0.1651)
		(layer "In5.Cu")
		(net "P5E_PEX1_STN1_RX_DN<22>")
	)
	(segment
		(start 160.47974 -114.5286)
		(end 160.03397 -114.5286)
		(width 0.1651)
		(layer "In5.Cu")
		(net "P5E_PEX1_STN1_RX_DN<22>")
	)
	(segment
		(start 161.292794 -114.184938)
		(end 161.134298 -114.153188)
		(width 0.1651)
		(layer "In5.Cu")
		(net "P5E_PEX1_STN1_RX_DN<22>")
	)
	(segment
		(start 165.162738 -111.941356)
		(end 164.70376 -112.128046)
		(width 0.1651)
		(layer "In5.Cu")
		(net "P5E_PEX1_STN1_RX_DN<22>")
	)
	(segment
		(start 150.459948 -151.040592)
		(end 150.91537 -158.370778)
		(width 0.1651)
		(layer "In5.Cu")
		(net "P5E_PEX1_STN1_RX_DN<22>")
	)
	(segment
		(start 158.24835 -120.674384)
		(end 158.11627 -120.76811)
		(width 0.1651)
		(layer "In5.Cu")
		(net "P5E_PEX1_STN1_RX_DN<22>")
	)
	(segment
		(start 161.73704 -113.751614)
		(end 161.70529 -113.91011)
		(width 0.1651)
		(layer "In5.Cu")
		(net "P5E_PEX1_STN1_RX_DN<22>")
	)
	(segment
		(start 158.034228 -121.256298)
		(end 158.127954 -121.388124)
		(width 0.1651)
		(layer "In5.Cu")
		(net "P5E_PEX1_STN1_RX_DN<22>")
	)
	(segment
		(start 181.11597 -268.786864)
		(end 181.11597 -271.526)
		(width 0.1651)
		(layer "In5.Cu")
		(net "P5E_PEX1_STN1_RX_DN<22>")
	)
	(segment
		(start 158.127954 -121.388124)
		(end 158.045658 -121.87682)
		(width 0.1651)
		(layer "In5.Cu")
		(net "P5E_PEX1_STN1_RX_DN<22>")
	)
	(segment
		(start 167.942768 -110.68558)
		(end 167.484298 -110.87227)
		(width 0.1651)
		(layer "In5.Cu")
		(net "P5E_PEX1_STN1_RX_DN<22>")
	)
	(segment
		(start 170.196764 -110.97641)
		(end 169.905934 -110.68558)
		(width 0.1651)
		(layer "In5.Cu")
		(net "P5E_PEX1_STN1_RX_DN<22>")
	)
	(segment
		(start 164.554916 -112.065308)
		(end 163.817554 -112.365282)
		(width 0.1651)
		(layer "In5.Cu")
		(net "P5E_PEX1_STN1_RX_DN<22>")
	)
	(segment
		(start 181.173628 -273.479514)
		(end 181.335426 -273.479514)
		(width 0.1143)
		(layer "In5.Cu")
		(net "P5E_PEX1_STN1_RX_DN<22>")
	)
	(segment
		(start 169.047668 -110.79988)
		(end 168.552368 -110.79988)
		(width 0.1651)
		(layer "In5.Cu")
		(net "P5E_PEX1_STN1_RX_DN<22>")
	)
	(segment
		(start 166.813484 -111.145574)
		(end 166.35476 -111.332264)
		(width 0.1651)
		(layer "In5.Cu")
		(net "P5E_PEX1_STN1_RX_DN<22>")
	)
	(segment
		(start 161.70529 -113.91011)
		(end 161.292794 -114.184938)
		(width 0.1651)
		(layer "In5.Cu")
		(net "P5E_PEX1_STN1_RX_DN<22>")
	)
	(segment
		(start 166.35476 -111.332264)
		(end 166.292022 -111.481362)
		(width 0.1651)
		(layer "In5.Cu")
		(net "P5E_PEX1_STN1_RX_DN<22>")
	)
	(segment
		(start 162.75177 -113.075466)
		(end 162.72002 -113.233962)
		(width 0.1651)
		(layer "In5.Cu")
		(net "P5E_PEX1_STN1_RX_DN<22>")
	)
	(segment
		(start 158.11627 -120.76811)
		(end 158.034228 -121.256298)
		(width 0.1651)
		(layer "In5.Cu")
		(net "P5E_PEX1_STN1_RX_DN<22>")
	)
	(segment
		(start 165.6842 -111.605568)
		(end 165.225476 -111.792258)
		(width 0.1651)
		(layer "In5.Cu")
		(net "P5E_PEX1_STN1_RX_DN<22>")
	)
	(segment
		(start 169.161968 -110.68558)
		(end 169.047668 -110.79988)
		(width 0.1651)
		(layer "In5.Cu")
		(net "P5E_PEX1_STN1_RX_DN<22>")
	)
	(segment
		(start 151.555958 -144.875758)
		(end 150.459948 -151.040592)
		(width 0.1651)
		(layer "In5.Cu")
		(net "P5E_PEX1_STN1_RX_DN<22>")
	)
	(segment
		(start 150.91537 -158.370778)
		(end 152.000204 -164.419026)
		(width 0.1651)
		(layer "In5.Cu")
		(net "P5E_PEX1_STN1_RX_DN<22>")
	)
	(segment
		(start 164.70376 -112.128046)
		(end 164.554916 -112.065308)
		(width 0.1651)
		(layer "In5.Cu")
		(net "P5E_PEX1_STN1_RX_DN<22>")
	)
	(segment
		(start 158.045658 -121.87682)
		(end 157.913832 -121.970546)
		(width 0.1651)
		(layer "In5.Cu")
		(net "P5E_PEX1_STN1_RX_DN<22>")
	)
	(segment
		(start 166.962328 -111.208312)
		(end 166.813484 -111.145574)
		(width 0.1651)
		(layer "In5.Cu")
		(net "P5E_PEX1_STN1_RX_DN<22>")
	)
	(segment
		(start 161.134298 -114.153188)
		(end 160.72231 -114.427762)
		(width 0.1651)
		(layer "In5.Cu")
		(net "P5E_PEX1_STN1_RX_DN<22>")
	)
	(segment
		(start 158.330646 -120.185688)
		(end 158.24835 -120.674384)
		(width 0.1651)
		(layer "In5.Cu")
		(net "P5E_PEX1_STN1_RX_DN<22>")
	)
	(segment
		(start 160.72231 -114.427762)
		(end 160.47974 -114.5286)
		(width 0.1651)
		(layer "In5.Cu")
		(net "P5E_PEX1_STN1_RX_DN<22>")
	)
	(segment
		(start 158.973012 -115.683538)
		(end 158.23692 -120.053862)
		(width 0.1651)
		(layer "In5.Cu")
		(net "P5E_PEX1_STN1_RX_DN<22>")
	)
	(segment
		(start 181.335426 -273.479514)
		(end 181.449726 -273.365214)
		(width 0.1143)
		(layer "In5.Cu")
		(net "P5E_PEX1_STN1_RX_DN<22>")
	)
	(segment
		(start 163.817554 -112.365282)
		(end 162.75177 -113.075466)
		(width 0.1651)
		(layer "In5.Cu")
		(net "P5E_PEX1_STN1_RX_DN<22>")
	)
	(segment
		(start 166.292022 -111.481362)
		(end 165.833044 -111.668306)
		(width 0.1651)
		(layer "In5.Cu")
		(net "P5E_PEX1_STN1_RX_DN<22>")
	)
	(segment
		(start 181.07025 -273.376136)
		(end 181.173628 -273.479514)
		(width 0.1143)
		(layer "In5.Cu")
		(net "P5E_PEX1_STN1_RX_DN<22>")
	)
	(segment
		(start 159.256222 -115.076478)
		(end 158.973012 -115.683538)
		(width 0.1651)
		(layer "In5.Cu")
		(net "P5E_PEX1_STN1_RX_DN<22>")
	)
	(segment
		(start 165.833044 -111.668306)
		(end 165.6842 -111.605568)
		(width 0.1651)
		(layer "In5.Cu")
		(net "P5E_PEX1_STN1_RX_DN<22>")
	)
	(segment
		(start 168.438068 -110.68558)
		(end 167.942768 -110.68558)
		(width 0.1651)
		(layer "In5.Cu")
		(net "P5E_PEX1_STN1_RX_DN<22>")
	)
	(segment
		(start 162.149028 -113.47704)
		(end 161.73704 -113.751614)
		(width 0.1651)
		(layer "In5.Cu")
		(net "P5E_PEX1_STN1_RX_DN<22>")
	)
	(segment
		(start 169.905934 -110.68558)
		(end 169.161968 -110.68558)
		(width 0.1651)
		(layer "In5.Cu")
		(net "P5E_PEX1_STN1_RX_DN<22>")
	)
	(segment
		(start 181.11597 -271.554448)
		(end 181.07025 -271.600168)
		(width 0.1143)
		(layer "In5.Cu")
		(net "P5E_PEX1_STN1_RX_DN<22>")
	)
	(segment
		(start 162.72002 -113.233962)
		(end 162.307524 -113.50879)
		(width 0.1651)
		(layer "In5.Cu")
		(net "P5E_PEX1_STN1_RX_DN<22>")
	)
	(segment
		(start 160.03397 -114.5286)
		(end 159.521906 -114.76482)
		(width 0.1651)
		(layer "In5.Cu")
		(net "P5E_PEX1_STN1_RX_DN<22>")
	)
	(segment
		(start 168.552368 -110.79988)
		(end 168.438068 -110.68558)
		(width 0.1651)
		(layer "In5.Cu")
		(net "P5E_PEX1_STN1_RX_DN<22>")
	)
	(segment
		(start 159.521906 -114.76482)
		(end 159.256222 -115.076478)
		(width 0.1651)
		(layer "In5.Cu")
		(net "P5E_PEX1_STN1_RX_DN<22>")
	)
	(segment
		(start 181.07025 -271.600168)
		(end 181.07025 -273.376136)
		(width 0.1143)
		(layer "In5.Cu")
		(net "P5E_PEX1_STN1_RX_DN<22>")
	)
	(segment
		(start 167.421306 -111.021368)
		(end 166.962328 -111.208312)
		(width 0.1651)
		(layer "In5.Cu")
		(net "P5E_PEX1_STN1_RX_DN<22>")
	)
	(segment
		(start 181.449726 -273.365214)
		(end 181.449726 -273.099784)
		(width 0.1143)
		(layer "In5.Cu")
		(net "P5E_PEX1_STN1_RX_DN<22>")
	)
	(segment
		(start 162.307524 -113.50879)
		(end 162.149028 -113.47704)
		(width 0.1651)
		(layer "In5.Cu")
		(net "P5E_PEX1_STN1_RX_DN<22>")
	)
	(segment
		(start 152.000204 -164.419026)
		(end 181.11597 -268.786864)
		(width 0.1651)
		(layer "In5.Cu")
		(net "P5E_PEX1_STN1_RX_DN<22>")
	)
	(segment
		(start 155.37942 -137.015474)
		(end 153.425144 -140.713968)
		(width 0.1651)
		(layer "In5.Cu")
		(net "P5E_PEX1_STN1_RX_DN<22>")
	)
	(segment
		(start 277.739348 -125.355096)
		(end 278.242268 -125.355096)
		(width 0.13462)
		(layer "F.Cu")
		(net "P5E_PEX2_STN1_TX_C_DP<27>")
	)
	(segment
		(start 277.580852 -125.1966)
		(end 277.739348 -125.355096)
		(width 0.13462)
		(layer "F.Cu")
		(net "P5E_PEX2_STN1_TX_C_DP<27>")
	)
	(segment
		(start 271.747234 -125.519942)
		(end 272.070576 -125.1966)
		(width 0.13462)
		(layer "F.Cu")
		(net "P5E_PEX2_STN1_TX_C_DP<27>")
	)
	(segment
		(start 272.070576 -125.1966)
		(end 277.580852 -125.1966)
		(width 0.13462)
		(layer "F.Cu")
		(net "P5E_PEX2_STN1_TX_C_DP<27>")
	)
	(segment
		(start 422.23182 -151.92248)
		(end 422.064434 -151.755094)
		(width 0.13462)
		(layer "F.Cu")
		(net "P5E_PEX3_STN0_TX_C_DN<13>")
	)
	(segment
		(start 430.694846 -151.596852)
		(end 430.369218 -151.92248)
		(width 0.13462)
		(layer "F.Cu")
		(net "P5E_PEX3_STN0_TX_C_DN<13>")
	)
	(segment
		(start 430.369218 -151.92248)
		(end 422.23182 -151.92248)
		(width 0.13462)
		(layer "F.Cu")
		(net "P5E_PEX3_STN0_TX_C_DN<13>")
	)
	(segment
		(start 422.064434 -151.755094)
		(end 421.557704 -151.755094)
		(width 0.13462)
		(layer "F.Cu")
		(net "P5E_PEX3_STN0_TX_C_DN<13>")
	)
	(segment
		(start 397.422878 -336.546698)
		(end 377.813316 -332.04785)
		(width 0.1651)
		(layer "In9.Cu")
		(net "P5E_PEX3_STN7_RX_DP<115>")
	)
	(segment
		(start 426.972222 -409.26512)
		(end 426.972222 -396.04696)
		(width 0.1651)
		(layer "In9.Cu")
		(net "P5E_PEX3_STN7_RX_DP<115>")
	)
	(segment
		(start 385.480814 -303.879504)
		(end 385.724654 -304.123344)
		(width 0.1143)
		(layer "In9.Cu")
		(net "P5E_PEX3_STN7_RX_DP<115>")
	)
	(segment
		(start 404.816818 -339.780372)
		(end 397.422878 -336.546698)
		(width 0.1651)
		(layer "In9.Cu")
		(net "P5E_PEX3_STN7_RX_DP<115>")
	)
	(segment
		(start 426.232066 -394.754862)
		(end 426.088302 -394.754862)
		(width 0.1651)
		(layer "In9.Cu")
		(net "P5E_PEX3_STN7_RX_DP<115>")
	)
	(segment
		(start 381.15875 -303.833784)
		(end 383.892552 -303.833784)
		(width 0.1651)
		(layer "In9.Cu")
		(net "P5E_PEX3_STN7_RX_DP<115>")
	)
	(segment
		(start 385.819142 -304.449734)
		(end 386.099812 -304.449734)
		(width 0.1143)
		(layer "In9.Cu")
		(net "P5E_PEX3_STN7_RX_DP<115>")
	)
	(segment
		(start 369.972082 -326.155812)
		(end 368.685572 -323.049646)
		(width 0.1651)
		(layer "In9.Cu")
		(net "P5E_PEX3_STN7_RX_DP<115>")
	)
	(segment
		(start 425.737782 -394.404342)
		(end 425.737782 -394.260578)
		(width 0.1651)
		(layer "In9.Cu")
		(net "P5E_PEX3_STN7_RX_DP<115>")
	)
	(segment
		(start 385.724654 -304.355246)
		(end 385.819142 -304.449734)
		(width 0.1143)
		(layer "In9.Cu")
		(net "P5E_PEX3_STN7_RX_DP<115>")
	)
	(segment
		(start 412.749746 -377.568714)
		(end 408.051254 -351.915984)
		(width 0.1651)
		(layer "In9.Cu")
		(net "P5E_PEX3_STN7_RX_DP<115>")
	)
	(segment
		(start 426.972222 -396.04696)
		(end 426.582078 -395.104874)
		(width 0.1651)
		(layer "In9.Cu")
		(net "P5E_PEX3_STN7_RX_DP<115>")
	)
	(segment
		(start 385.724654 -304.123344)
		(end 385.724654 -304.355246)
		(width 0.1143)
		(layer "In9.Cu")
		(net "P5E_PEX3_STN7_RX_DP<115>")
	)
	(segment
		(start 426.089826 -409.672028)
		(end 426.216826 -409.799028)
		(width 0.1651)
		(layer "In9.Cu")
		(net "P5E_PEX3_STN7_RX_DP<115>")
	)
	(segment
		(start 426.088302 -394.754862)
		(end 425.737782 -394.404342)
		(width 0.1651)
		(layer "In9.Cu")
		(net "P5E_PEX3_STN7_RX_DP<115>")
	)
	(segment
		(start 407.932382 -349.14713)
		(end 405.873966 -341.027258)
		(width 0.1651)
		(layer "In9.Cu")
		(net "P5E_PEX3_STN7_RX_DP<115>")
	)
	(segment
		(start 373.8118 -308.523894)
		(end 377.457462 -304.877978)
		(width 0.1651)
		(layer "In9.Cu")
		(net "P5E_PEX3_STN7_RX_DP<115>")
	)
	(segment
		(start 405.873966 -341.027258)
		(end 404.816818 -339.780372)
		(width 0.1651)
		(layer "In9.Cu")
		(net "P5E_PEX3_STN7_RX_DP<115>")
	)
	(segment
		(start 425.737782 -394.260578)
		(end 423.968926 -392.491722)
		(width 0.1651)
		(layer "In9.Cu")
		(net "P5E_PEX3_STN7_RX_DP<115>")
	)
	(segment
		(start 374.966484 -331.14996)
		(end 369.972082 -326.155812)
		(width 0.1651)
		(layer "In9.Cu")
		(net "P5E_PEX3_STN7_RX_DP<115>")
	)
	(segment
		(start 426.089826 -409.290012)
		(end 426.089826 -409.672028)
		(width 0.1651)
		(layer "In9.Cu")
		(net "P5E_PEX3_STN7_RX_DP<115>")
	)
	(segment
		(start 368.685572 -318.81064)
		(end 369.96497 -315.722)
		(width 0.1651)
		(layer "In9.Cu")
		(net "P5E_PEX3_STN7_RX_DP<115>")
	)
	(segment
		(start 408.051254 -351.915984)
		(end 407.932382 -349.14713)
		(width 0.1651)
		(layer "In9.Cu")
		(net "P5E_PEX3_STN7_RX_DP<115>")
	)
	(segment
		(start 426.438314 -409.799028)
		(end 426.972222 -409.26512)
		(width 0.1651)
		(layer "In9.Cu")
		(net "P5E_PEX3_STN7_RX_DP<115>")
	)
	(segment
		(start 377.813316 -332.04785)
		(end 374.966484 -331.14996)
		(width 0.1651)
		(layer "In9.Cu")
		(net "P5E_PEX3_STN7_RX_DP<115>")
	)
	(segment
		(start 426.216826 -409.799028)
		(end 426.438314 -409.799028)
		(width 0.1651)
		(layer "In9.Cu")
		(net "P5E_PEX3_STN7_RX_DP<115>")
	)
	(segment
		(start 369.96497 -315.722)
		(end 373.8118 -308.523894)
		(width 0.1651)
		(layer "In9.Cu")
		(net "P5E_PEX3_STN7_RX_DP<115>")
	)
	(segment
		(start 423.968926 -392.491722)
		(end 418.665152 -390.604502)
		(width 0.1651)
		(layer "In9.Cu")
		(net "P5E_PEX3_STN7_RX_DP<115>")
	)
	(segment
		(start 383.96672 -303.879504)
		(end 385.480814 -303.879504)
		(width 0.1143)
		(layer "In9.Cu")
		(net "P5E_PEX3_STN7_RX_DP<115>")
	)
	(segment
		(start 383.892552 -303.833784)
		(end 383.921 -303.833784)
		(width 0.1143)
		(layer "In9.Cu")
		(net "P5E_PEX3_STN7_RX_DP<115>")
	)
	(segment
		(start 415.416746 -387.958076)
		(end 414.27527 -386.259324)
		(width 0.1651)
		(layer "In9.Cu")
		(net "P5E_PEX3_STN7_RX_DP<115>")
	)
	(segment
		(start 426.582078 -395.104874)
		(end 426.232066 -394.754862)
		(width 0.1651)
		(layer "In9.Cu")
		(net "P5E_PEX3_STN7_RX_DP<115>")
	)
	(segment
		(start 418.665152 -390.604502)
		(end 415.416746 -387.958076)
		(width 0.1651)
		(layer "In9.Cu")
		(net "P5E_PEX3_STN7_RX_DP<115>")
	)
	(segment
		(start 368.685572 -323.049646)
		(end 368.685572 -318.81064)
		(width 0.1651)
		(layer "In9.Cu")
		(net "P5E_PEX3_STN7_RX_DP<115>")
	)
	(segment
		(start 377.457462 -304.877978)
		(end 379.565408 -304.448464)
		(width 0.1651)
		(layer "In9.Cu")
		(net "P5E_PEX3_STN7_RX_DP<115>")
	)
	(segment
		(start 414.27527 -386.259324)
		(end 413.728408 -384.819398)
		(width 0.1651)
		(layer "In9.Cu")
		(net "P5E_PEX3_STN7_RX_DP<115>")
	)
	(segment
		(start 413.728408 -384.819398)
		(end 412.749746 -377.568714)
		(width 0.1651)
		(layer "In9.Cu")
		(net "P5E_PEX3_STN7_RX_DP<115>")
	)
	(segment
		(start 379.565408 -304.448464)
		(end 381.15875 -303.833784)
		(width 0.1651)
		(layer "In9.Cu")
		(net "P5E_PEX3_STN7_RX_DP<115>")
	)
	(segment
		(start 383.921 -303.833784)
		(end 383.96672 -303.879504)
		(width 0.1143)
		(layer "In9.Cu")
		(net "P5E_PEX3_STN7_RX_DP<115>")
	)
	(segment
		(start 423.033952 -98.240088)
		(end 424.24604 -97.028)
		(width 0.13208)
		(layer "F.Cu")
		(net "NIC7_LD_N")
	)
	(segment
		(start 424.24604 -97.028)
		(end 424.24604 -95.989648)
		(width 0.13208)
		(layer "F.Cu")
		(net "NIC7_LD_N")
	)
	(segment
		(start 421.557704 -98.240088)
		(end 423.033952 -98.240088)
		(width 0.13208)
		(layer "F.Cu")
		(net "NIC7_LD_N")
	)
	(via
		(at 424.24604 -95.989648)
		(size 0.508)
		(drill 0.254)
		(layers "F.Cu" "B.Cu")
		(net "NIC7_LD_N")
	)
	(segment
		(start 424.24604 -95.989648)
		(end 425.441872 -95.989648)
		(width 0.13208)
		(layer "B.Cu")
		(net "NIC7_LD_N")
	)
	(segment
		(start 161.149792 -24.488648)
		(end 161.571686 -24.910542)
		(width 0.13208)
		(layer "F.Cu")
		(net "DUALPORT_N_SSD5")
	)
	(segment
		(start 162.587686 -24.942292)
		(end 161.571686 -24.942292)
		(width 0.13208)
		(layer "F.Cu")
		(net "DUALPORT_N_SSD5")
	)
	(segment
		(start 158.566612 -23.589996)
		(end 158.566612 -24.134572)
		(width 0.13208)
		(layer "F.Cu")
		(net "DUALPORT_N_SSD5")
	)
	(segment
		(start 158.920688 -24.488648)
		(end 161.149792 -24.488648)
		(width 0.13208)
		(layer "F.Cu")
		(net "DUALPORT_N_SSD5")
	)
	(segment
		(start 161.571686 -24.910542)
		(end 161.571686 -24.942292)
		(width 0.13208)
		(layer "F.Cu")
		(net "DUALPORT_N_SSD5")
	)
	(segment
		(start 157.364938 -23.589996)
		(end 158.566612 -23.589996)
		(width 0.13208)
		(layer "F.Cu")
		(net "DUALPORT_N_SSD5")
	)
	(segment
		(start 158.566612 -24.134572)
		(end 158.920688 -24.488648)
		(width 0.13208)
		(layer "F.Cu")
		(net "DUALPORT_N_SSD5")
	)
	(via
		(at 158.566612 -23.589996)
		(size 0.508)
		(drill 0.254)
		(layers "F.Cu" "B.Cu")
		(net "DUALPORT_N_SSD5")
	)
	(segment
		(start 73.90892 -118.99773)
		(end 79.425292 -118.99773)
		(width 0.13462)
		(layer "F.Cu")
		(net "P5E_PEX0_STN0_TX_C_DN<0>")
	)
	(segment
		(start 79.425292 -118.99773)
		(end 79.752698 -118.670324)
		(width 0.13462)
		(layer "F.Cu")
		(net "P5E_PEX0_STN0_TX_C_DN<0>")
	)
	(segment
		(start 73.257664 -118.834916)
		(end 73.746106 -118.834916)
		(width 0.13462)
		(layer "F.Cu")
		(net "P5E_PEX0_STN0_TX_C_DN<0>")
	)
	(segment
		(start 73.746106 -118.834916)
		(end 73.90892 -118.99773)
		(width 0.13462)
		(layer "F.Cu")
		(net "P5E_PEX0_STN0_TX_C_DN<0>")
	)
	(segment
		(start 167.230298 -119.955056)
		(end 167.393112 -119.792242)
		(width 0.13462)
		(layer "F.Cu")
		(net "P5E_PEX1_STN1_RX_DN<24>")
	)
	(segment
		(start 169.902124 -119.791734)
		(end 170.196764 -120.086374)
		(width 0.13462)
		(layer "F.Cu")
		(net "P5E_PEX1_STN1_RX_DN<24>")
	)
	(segment
		(start 166.742364 -119.955056)
		(end 167.230298 -119.955056)
		(width 0.13462)
		(layer "F.Cu")
		(net "P5E_PEX1_STN1_RX_DN<24>")
	)
	(segment
		(start 169.901616 -119.792242)
		(end 169.902124 -119.791734)
		(width 0.13462)
		(layer "F.Cu")
		(net "P5E_PEX1_STN1_RX_DN<24>")
	)
	(segment
		(start 167.393112 -119.792242)
		(end 169.901616 -119.792242)
		(width 0.13462)
		(layer "F.Cu")
		(net "P5E_PEX1_STN1_RX_DN<24>")
	)
	(segment
		(start 163.655248 -123.026932)
		(end 163.493704 -123.022868)
		(width 0.1651)
		(layer "In5.Cu")
		(net "P5E_PEX1_STN1_RX_DN<24>")
	)
	(segment
		(start 182.97017 -271.600168)
		(end 182.97017 -273.376136)
		(width 0.1143)
		(layer "In5.Cu")
		(net "P5E_PEX1_STN1_RX_DN<24>")
	)
	(segment
		(start 160.48101 -126.231904)
		(end 160.212278 -126.648464)
		(width 0.1651)
		(layer "In5.Cu")
		(net "P5E_PEX1_STN1_RX_DN<24>")
	)
	(segment
		(start 160.715198 -125.657864)
		(end 160.446974 -126.073916)
		(width 0.1651)
		(layer "In5.Cu")
		(net "P5E_PEX1_STN1_RX_DN<24>")
	)
	(segment
		(start 157.37332 -137.708894)
		(end 157.058868 -138.264138)
		(width 0.1651)
		(layer "In5.Cu")
		(net "P5E_PEX1_STN1_RX_DN<24>")
	)
	(segment
		(start 164.53993 -122.187716)
		(end 164.378386 -122.183652)
		(width 0.1651)
		(layer "In5.Cu")
		(net "P5E_PEX1_STN1_RX_DN<24>")
	)
	(segment
		(start 163.13023 -123.52528)
		(end 162.770566 -123.866148)
		(width 0.1651)
		(layer "In5.Cu")
		(net "P5E_PEX1_STN1_RX_DN<24>")
	)
	(segment
		(start 156.45765 -139.325096)
		(end 156.50083 -139.480798)
		(width 0.1651)
		(layer "In5.Cu")
		(net "P5E_PEX1_STN1_RX_DN<24>")
	)
	(segment
		(start 162.249866 -124.202444)
		(end 162.245548 -124.364242)
		(width 0.1651)
		(layer "In5.Cu")
		(net "P5E_PEX1_STN1_RX_DN<24>")
	)
	(segment
		(start 164.899594 -121.846594)
		(end 164.53993 -122.187716)
		(width 0.1651)
		(layer "In5.Cu")
		(net "P5E_PEX1_STN1_RX_DN<24>")
	)
	(segment
		(start 164.903912 -121.68505)
		(end 164.899594 -121.846594)
		(width 0.1651)
		(layer "In5.Cu")
		(net "P5E_PEX1_STN1_RX_DN<24>")
	)
	(segment
		(start 182.97017 -273.376136)
		(end 183.073548 -273.479514)
		(width 0.1143)
		(layer "In5.Cu")
		(net "P5E_PEX1_STN1_RX_DN<24>")
	)
	(segment
		(start 183.01589 -271.554448)
		(end 182.97017 -271.600168)
		(width 0.1143)
		(layer "In5.Cu")
		(net "P5E_PEX1_STN1_RX_DN<24>")
	)
	(segment
		(start 183.073548 -273.479514)
		(end 183.235346 -273.479514)
		(width 0.1143)
		(layer "In5.Cu")
		(net "P5E_PEX1_STN1_RX_DN<24>")
	)
	(segment
		(start 156.50083 -139.480798)
		(end 156.256482 -139.91209)
		(width 0.1651)
		(layer "In5.Cu")
		(net "P5E_PEX1_STN1_RX_DN<24>")
	)
	(segment
		(start 155.650438 -140.750036)
		(end 155.367482 -141.376908)
		(width 0.1651)
		(layer "In5.Cu")
		(net "P5E_PEX1_STN1_RX_DN<24>")
	)
	(segment
		(start 156.10078 -139.95527)
		(end 155.650438 -140.750036)
		(width 0.1651)
		(layer "In5.Cu")
		(net "P5E_PEX1_STN1_RX_DN<24>")
	)
	(segment
		(start 168.20007 -119.795544)
		(end 166.258748 -120.400064)
		(width 0.1651)
		(layer "In5.Cu")
		(net "P5E_PEX1_STN1_RX_DN<24>")
	)
	(segment
		(start 155.367482 -141.376908)
		(end 155.424632 -141.528292)
		(width 0.1651)
		(layer "In5.Cu")
		(net "P5E_PEX1_STN1_RX_DN<24>")
	)
	(segment
		(start 160.446974 -126.073916)
		(end 160.48101 -126.231904)
		(width 0.1651)
		(layer "In5.Cu")
		(net "P5E_PEX1_STN1_RX_DN<24>")
	)
	(segment
		(start 161.72434 -124.701046)
		(end 160.715198 -125.657864)
		(width 0.1651)
		(layer "In5.Cu")
		(net "P5E_PEX1_STN1_RX_DN<24>")
	)
	(segment
		(start 163.493704 -123.022868)
		(end 163.134548 -123.363482)
		(width 0.1651)
		(layer "In5.Cu")
		(net "P5E_PEX1_STN1_RX_DN<24>")
	)
	(segment
		(start 157.101794 -138.41984)
		(end 156.857446 -138.851132)
		(width 0.1651)
		(layer "In5.Cu")
		(net "P5E_PEX1_STN1_RX_DN<24>")
	)
	(segment
		(start 169.905934 -119.795544)
		(end 168.20007 -119.795544)
		(width 0.1651)
		(layer "In5.Cu")
		(net "P5E_PEX1_STN1_RX_DN<24>")
	)
	(segment
		(start 164.01923 -122.524266)
		(end 164.014912 -122.686064)
		(width 0.1651)
		(layer "In5.Cu")
		(net "P5E_PEX1_STN1_RX_DN<24>")
	)
	(segment
		(start 164.378386 -122.183652)
		(end 164.01923 -122.524266)
		(width 0.1651)
		(layer "In5.Cu")
		(net "P5E_PEX1_STN1_RX_DN<24>")
	)
	(segment
		(start 153.618438 -145.252186)
		(end 152.4508 -151.578564)
		(width 0.1651)
		(layer "In5.Cu")
		(net "P5E_PEX1_STN1_RX_DN<24>")
	)
	(segment
		(start 152.4508 -151.578564)
		(end 152.883362 -158.172912)
		(width 0.1651)
		(layer "In5.Cu")
		(net "P5E_PEX1_STN1_RX_DN<24>")
	)
	(segment
		(start 156.857446 -138.851132)
		(end 156.701744 -138.894312)
		(width 0.1651)
		(layer "In5.Cu")
		(net "P5E_PEX1_STN1_RX_DN<24>")
	)
	(segment
		(start 161.885884 -124.70511)
		(end 161.72434 -124.701046)
		(width 0.1651)
		(layer "In5.Cu")
		(net "P5E_PEX1_STN1_RX_DN<24>")
	)
	(segment
		(start 162.245548 -124.364242)
		(end 161.885884 -124.70511)
		(width 0.1651)
		(layer "In5.Cu")
		(net "P5E_PEX1_STN1_RX_DN<24>")
	)
	(segment
		(start 153.882344 -163.875974)
		(end 183.01589 -268.381226)
		(width 0.1651)
		(layer "In5.Cu")
		(net "P5E_PEX1_STN1_RX_DN<24>")
	)
	(segment
		(start 162.770566 -123.866148)
		(end 162.609022 -123.86183)
		(width 0.1651)
		(layer "In5.Cu")
		(net "P5E_PEX1_STN1_RX_DN<24>")
	)
	(segment
		(start 166.258748 -120.400064)
		(end 164.903912 -121.68505)
		(width 0.1651)
		(layer "In5.Cu")
		(net "P5E_PEX1_STN1_RX_DN<24>")
	)
	(segment
		(start 163.134548 -123.363482)
		(end 163.13023 -123.52528)
		(width 0.1651)
		(layer "In5.Cu")
		(net "P5E_PEX1_STN1_RX_DN<24>")
	)
	(segment
		(start 164.014912 -122.686064)
		(end 163.655248 -123.026932)
		(width 0.1651)
		(layer "In5.Cu")
		(net "P5E_PEX1_STN1_RX_DN<24>")
	)
	(segment
		(start 157.058868 -138.264138)
		(end 157.101794 -138.41984)
		(width 0.1651)
		(layer "In5.Cu")
		(net "P5E_PEX1_STN1_RX_DN<24>")
	)
	(segment
		(start 162.609022 -123.86183)
		(end 162.249866 -124.202444)
		(width 0.1651)
		(layer "In5.Cu")
		(net "P5E_PEX1_STN1_RX_DN<24>")
	)
	(segment
		(start 183.349646 -273.365214)
		(end 183.349646 -273.099784)
		(width 0.1143)
		(layer "In5.Cu")
		(net "P5E_PEX1_STN1_RX_DN<24>")
	)
	(segment
		(start 160.212278 -126.648464)
		(end 160.05429 -126.682754)
		(width 0.1651)
		(layer "In5.Cu")
		(net "P5E_PEX1_STN1_RX_DN<24>")
	)
	(segment
		(start 158.795466 -128.983232)
		(end 157.37332 -137.708894)
		(width 0.1651)
		(layer "In5.Cu")
		(net "P5E_PEX1_STN1_RX_DN<24>")
	)
	(segment
		(start 183.01589 -271.526)
		(end 183.01589 -271.554448)
		(width 0.1143)
		(layer "In5.Cu")
		(net "P5E_PEX1_STN1_RX_DN<24>")
	)
	(segment
		(start 183.01589 -268.381226)
		(end 183.01589 -271.526)
		(width 0.1651)
		(layer "In5.Cu")
		(net "P5E_PEX1_STN1_RX_DN<24>")
	)
	(segment
		(start 170.196764 -120.086374)
		(end 169.905934 -119.795544)
		(width 0.1651)
		(layer "In5.Cu")
		(net "P5E_PEX1_STN1_RX_DN<24>")
	)
	(segment
		(start 156.256482 -139.91209)
		(end 156.10078 -139.95527)
		(width 0.1651)
		(layer "In5.Cu")
		(net "P5E_PEX1_STN1_RX_DN<24>")
	)
	(segment
		(start 156.701744 -138.894312)
		(end 156.45765 -139.325096)
		(width 0.1651)
		(layer "In5.Cu")
		(net "P5E_PEX1_STN1_RX_DN<24>")
	)
	(segment
		(start 155.424632 -141.528292)
		(end 155.220924 -141.979904)
		(width 0.1651)
		(layer "In5.Cu")
		(net "P5E_PEX1_STN1_RX_DN<24>")
	)
	(segment
		(start 152.883362 -158.172912)
		(end 153.882344 -163.875974)
		(width 0.1651)
		(layer "In5.Cu")
		(net "P5E_PEX1_STN1_RX_DN<24>")
	)
	(segment
		(start 155.220924 -141.979904)
		(end 155.06954 -142.037054)
		(width 0.1651)
		(layer "In5.Cu")
		(net "P5E_PEX1_STN1_RX_DN<24>")
	)
	(segment
		(start 183.235346 -273.479514)
		(end 183.349646 -273.365214)
		(width 0.1143)
		(layer "In5.Cu")
		(net "P5E_PEX1_STN1_RX_DN<24>")
	)
	(segment
		(start 155.06954 -142.037054)
		(end 153.618438 -145.252186)
		(width 0.1651)
		(layer "In5.Cu")
		(net "P5E_PEX1_STN1_RX_DN<24>")
	)
	(segment
		(start 159.12719 -128.120648)
		(end 158.795466 -128.983232)
		(width 0.1651)
		(layer "In5.Cu")
		(net "P5E_PEX1_STN1_RX_DN<24>")
	)
	(segment
		(start 160.05429 -126.682754)
		(end 159.12719 -128.120648)
		(width 0.1651)
		(layer "In5.Cu")
		(net "P5E_PEX1_STN1_RX_DN<24>")
	)
	(segment
		(start 119.507 -368.1984)
		(end 118.887494 -369.698016)
		(width 0.1651)
		(layer "In5.Cu")
		(net "P5E_PEX1_STN6_RX_DP<102>")
	)
	(segment
		(start 167.579802 -319.807082)
		(end 167.534082 -319.852802)
		(width 0.1143)
		(layer "In5.Cu")
		(net "P5E_PEX1_STN6_RX_DP<102>")
	)
	(segment
		(start 167.534082 -320.102484)
		(end 167.294306 -320.34226)
		(width 0.1651)
		(layer "In5.Cu")
		(net "P5E_PEX1_STN6_RX_DP<102>")
	)
	(segment
		(start 118.887494 -369.698016)
		(end 118.887494 -375.78157)
		(width 0.1651)
		(layer "In5.Cu")
		(net "P5E_PEX1_STN6_RX_DP<102>")
	)
	(segment
		(start 126.143258 -357.882444)
		(end 125.838712 -358.873044)
		(width 0.1651)
		(layer "In5.Cu")
		(net "P5E_PEX1_STN6_RX_DP<102>")
	)
	(segment
		(start 118.11 -375.872248)
		(end 118.11 -375.490232)
		(width 0.1651)
		(layer "In5.Cu")
		(net "P5E_PEX1_STN6_RX_DP<102>")
	)
	(segment
		(start 118.669816 -375.999248)
		(end 118.237 -375.999248)
		(width 0.1651)
		(layer "In5.Cu")
		(net "P5E_PEX1_STN6_RX_DP<102>")
	)
	(segment
		(start 119.76481 -367.730024)
		(end 119.778018 -367.799366)
		(width 0.1651)
		(layer "In5.Cu")
		(net "P5E_PEX1_STN6_RX_DP<102>")
	)
	(segment
		(start 167.534082 -319.852802)
		(end 167.534082 -319.88125)
		(width 0.1143)
		(layer "In5.Cu")
		(net "P5E_PEX1_STN6_RX_DP<102>")
	)
	(segment
		(start 120.174766 -367.214912)
		(end 120.105678 -367.22812)
		(width 0.1651)
		(layer "In5.Cu")
		(net "P5E_PEX1_STN6_RX_DP<102>")
	)
	(segment
		(start 167.579802 -318.355472)
		(end 167.579802 -319.807082)
		(width 0.1143)
		(layer "In5.Cu")
		(net "P5E_PEX1_STN6_RX_DP<102>")
	)
	(segment
		(start 125.838712 -358.873044)
		(end 120.842532 -366.231424)
		(width 0.1651)
		(layer "In5.Cu")
		(net "P5E_PEX1_STN6_RX_DP<102>")
	)
	(segment
		(start 154.906726 -327.664064)
		(end 147.26158 -332.514956)
		(width 0.1651)
		(layer "In5.Cu")
		(net "P5E_PEX1_STN6_RX_DP<102>")
	)
	(segment
		(start 120.842532 -366.231424)
		(end 120.750076 -366.249204)
		(width 0.1651)
		(layer "In5.Cu")
		(net "P5E_PEX1_STN6_RX_DP<102>")
	)
	(segment
		(start 147.26158 -332.514956)
		(end 126.951994 -341.044276)
		(width 0.1651)
		(layer "In5.Cu")
		(net "P5E_PEX1_STN6_RX_DP<102>")
	)
	(segment
		(start 126.143258 -342.001602)
		(end 126.143258 -357.882444)
		(width 0.1651)
		(layer "In5.Cu")
		(net "P5E_PEX1_STN6_RX_DP<102>")
	)
	(segment
		(start 120.445784 -366.815878)
		(end 120.174766 -367.214912)
		(width 0.1651)
		(layer "In5.Cu")
		(net "P5E_PEX1_STN6_RX_DP<102>")
	)
	(segment
		(start 168.035732 -318.129666)
		(end 167.805608 -318.129666)
		(width 0.1143)
		(layer "In5.Cu")
		(net "P5E_PEX1_STN6_RX_DP<102>")
	)
	(segment
		(start 118.237 -375.999248)
		(end 118.11 -375.872248)
		(width 0.1651)
		(layer "In5.Cu")
		(net "P5E_PEX1_STN6_RX_DP<102>")
	)
	(segment
		(start 119.778018 -367.799366)
		(end 119.507 -368.1984)
		(width 0.1651)
		(layer "In5.Cu")
		(net "P5E_PEX1_STN6_RX_DP<102>")
	)
	(segment
		(start 167.534082 -319.88125)
		(end 167.534082 -320.102484)
		(width 0.1651)
		(layer "In5.Cu")
		(net "P5E_PEX1_STN6_RX_DP<102>")
	)
	(segment
		(start 126.556516 -341.4395)
		(end 126.143258 -342.001602)
		(width 0.1651)
		(layer "In5.Cu")
		(net "P5E_PEX1_STN6_RX_DP<102>")
	)
	(segment
		(start 167.294306 -320.34226)
		(end 154.906726 -327.664064)
		(width 0.1651)
		(layer "In5.Cu")
		(net "P5E_PEX1_STN6_RX_DP<102>")
	)
	(segment
		(start 126.951994 -341.044276)
		(end 126.556516 -341.4395)
		(width 0.1651)
		(layer "In5.Cu")
		(net "P5E_PEX1_STN6_RX_DP<102>")
	)
	(segment
		(start 120.428004 -366.723168)
		(end 120.445784 -366.815878)
		(width 0.1651)
		(layer "In5.Cu")
		(net "P5E_PEX1_STN6_RX_DP<102>")
	)
	(segment
		(start 118.887494 -375.78157)
		(end 118.669816 -375.999248)
		(width 0.1651)
		(layer "In5.Cu")
		(net "P5E_PEX1_STN6_RX_DP<102>")
	)
	(segment
		(start 120.105678 -367.22812)
		(end 119.76481 -367.730024)
		(width 0.1651)
		(layer "In5.Cu")
		(net "P5E_PEX1_STN6_RX_DP<102>")
	)
	(segment
		(start 168.150032 -317.749936)
		(end 168.150032 -318.015366)
		(width 0.1143)
		(layer "In5.Cu")
		(net "P5E_PEX1_STN6_RX_DP<102>")
	)
	(segment
		(start 120.750076 -366.249204)
		(end 120.428004 -366.723168)
		(width 0.1651)
		(layer "In5.Cu")
		(net "P5E_PEX1_STN6_RX_DP<102>")
	)
	(segment
		(start 168.150032 -318.015366)
		(end 168.035732 -318.129666)
		(width 0.1143)
		(layer "In5.Cu")
		(net "P5E_PEX1_STN6_RX_DP<102>")
	)
	(segment
		(start 167.805608 -318.129666)
		(end 167.579802 -318.355472)
		(width 0.1143)
		(layer "In5.Cu")
		(net "P5E_PEX1_STN6_RX_DP<102>")
	)
	(segment
		(start 277.742904 -121.154952)
		(end 278.242268 -121.154952)
		(width 0.13462)
		(layer "F.Cu")
		(net "P5E_PEX2_STN1_TX_C_DN<25>")
	)
	(segment
		(start 277.582376 -121.31548)
		(end 277.742904 -121.154952)
		(width 0.13462)
		(layer "F.Cu")
		(net "P5E_PEX2_STN1_TX_C_DN<25>")
	)
	(segment
		(start 272.057368 -121.31548)
		(end 277.582376 -121.31548)
		(width 0.13462)
		(layer "F.Cu")
		(net "P5E_PEX2_STN1_TX_C_DN<25>")
	)
	(segment
		(start 271.747234 -121.005346)
		(end 272.057368 -121.31548)
		(width 0.13462)
		(layer "F.Cu")
		(net "P5E_PEX2_STN1_TX_C_DN<25>")
	)
	(segment
		(start 328.616564 -344.539062)
		(end 328.616564 -345.170506)
		(width 0.13462)
		(layer "F.Cu")
		(net "P5E_PEX2_STN5_TX_C_DN<87>")
	)
	(segment
		(start 328.616564 -345.170506)
		(end 328.911204 -345.465146)
		(width 0.13462)
		(layer "F.Cu")
		(net "P5E_PEX2_STN5_TX_C_DN<87>")
	)
	(segment
		(start 328.936604 -344.219022)
		(end 328.616564 -344.539062)
		(width 0.13462)
		(layer "F.Cu")
		(net "P5E_PEX2_STN5_TX_C_DN<87>")
	)
	(segment
		(start 346.890086 -406.308052)
		(end 346.890086 -406.690068)
		(width 0.1651)
		(layer "In7.Cu")
		(net "P5E_PEX2_STN5_TX_C_DN<87>")
	)
	(segment
		(start 347.017086 -406.181052)
		(end 346.890086 -406.308052)
		(width 0.1651)
		(layer "In7.Cu")
		(net "P5E_PEX2_STN5_TX_C_DN<87>")
	)
	(segment
		(start 328.620374 -345.755976)
		(end 328.620374 -346.326714)
		(width 0.1651)
		(layer "In7.Cu")
		(net "P5E_PEX2_STN5_TX_C_DN<87>")
	)
	(segment
		(start 328.620374 -346.326714)
		(end 327.065894 -347.881194)
		(width 0.1651)
		(layer "In7.Cu")
		(net "P5E_PEX2_STN5_TX_C_DN<87>")
	)
	(segment
		(start 346.405962 -393.228322)
		(end 346.85224 -393.524486)
		(width 0.1651)
		(layer "In7.Cu")
		(net "P5E_PEX2_STN5_TX_C_DN<87>")
	)
	(segment
		(start 347.564202 -406.181052)
		(end 347.017086 -406.181052)
		(width 0.1651)
		(layer "In7.Cu")
		(net "P5E_PEX2_STN5_TX_C_DN<87>")
	)
	(segment
		(start 348.016068 -405.729186)
		(end 347.564202 -406.181052)
		(width 0.1651)
		(layer "In7.Cu")
		(net "P5E_PEX2_STN5_TX_C_DN<87>")
	)
	(segment
		(start 346.85224 -393.524486)
		(end 348.016068 -394.63599)
		(width 0.1651)
		(layer "In7.Cu")
		(net "P5E_PEX2_STN5_TX_C_DN<87>")
	)
	(segment
		(start 337.3374 -388.31774)
		(end 346.405962 -393.228322)
		(width 0.1651)
		(layer "In7.Cu")
		(net "P5E_PEX2_STN5_TX_C_DN<87>")
	)
	(segment
		(start 327.065894 -347.881194)
		(end 327.065894 -359.13314)
		(width 0.1651)
		(layer "In7.Cu")
		(net "P5E_PEX2_STN5_TX_C_DN<87>")
	)
	(segment
		(start 331.48016 -385.93522)
		(end 337.3374 -388.31774)
		(width 0.1651)
		(layer "In7.Cu")
		(net "P5E_PEX2_STN5_TX_C_DN<87>")
	)
	(segment
		(start 330.82738 -385.26974)
		(end 331.48016 -385.93522)
		(width 0.1651)
		(layer "In7.Cu")
		(net "P5E_PEX2_STN5_TX_C_DN<87>")
	)
	(segment
		(start 327.065894 -359.13314)
		(end 330.40828 -384.19786)
		(width 0.1651)
		(layer "In7.Cu")
		(net "P5E_PEX2_STN5_TX_C_DN<87>")
	)
	(segment
		(start 330.40828 -384.19786)
		(end 330.82738 -385.26974)
		(width 0.1651)
		(layer "In7.Cu")
		(net "P5E_PEX2_STN5_TX_C_DN<87>")
	)
	(segment
		(start 348.016068 -394.63599)
		(end 348.016068 -405.729186)
		(width 0.1651)
		(layer "In7.Cu")
		(net "P5E_PEX2_STN5_TX_C_DN<87>")
	)
	(segment
		(start 328.911204 -345.465146)
		(end 328.620374 -345.755976)
		(width 0.1651)
		(layer "In7.Cu")
		(net "P5E_PEX2_STN5_TX_C_DN<87>")
	)
	(segment
		(start 416.476434 -133.645148)
		(end 416.314382 -133.8072)
		(width 0.13462)
		(layer "F.Cu")
		(net "P5E_PEX3_STN0_RX_DN<6>")
	)
	(segment
		(start 415.650934 -133.8072)
		(end 415.35731 -133.513576)
		(width 0.13462)
		(layer "F.Cu")
		(net "P5E_PEX3_STN0_RX_DN<6>")
	)
	(segment
		(start 416.314382 -133.8072)
		(end 415.650934 -133.8072)
		(width 0.13462)
		(layer "F.Cu")
		(net "P5E_PEX3_STN0_RX_DN<6>")
	)
	(segment
		(start 416.95751 -133.645148)
		(end 416.476434 -133.645148)
		(width 0.13462)
		(layer "F.Cu")
		(net "P5E_PEX3_STN0_RX_DN<6>")
	)
	(segment
		(start 428.602648 -282.220162)
		(end 432.15052 -282.220162)
		(width 0.1143)
		(layer "In5.Cu")
		(net "P5E_PEX3_STN0_RX_DN<6>")
	)
	(segment
		(start 415.64814 -133.804406)
		(end 415.35731 -133.513576)
		(width 0.1651)
		(layer "In5.Cu")
		(net "P5E_PEX3_STN0_RX_DN<6>")
	)
	(segment
		(start 434.133244 -277.089108)
		(end 434.133244 -276.694646)
		(width 0.1651)
		(layer "In5.Cu")
		(net "P5E_PEX3_STN0_RX_DN<6>")
	)
	(segment
		(start 433.799488 -281.22245)
		(end 434.045106 -280.642822)
		(width 0.1651)
		(layer "In5.Cu")
		(net "P5E_PEX3_STN0_RX_DN<6>")
	)
	(segment
		(start 428.58436 -282.599892)
		(end 428.47006 -282.485592)
		(width 0.1143)
		(layer "In5.Cu")
		(net "P5E_PEX3_STN0_RX_DN<6>")
	)
	(segment
		(start 434.045106 -280.642822)
		(end 434.133244 -277.089108)
		(width 0.1651)
		(layer "In5.Cu")
		(net "P5E_PEX3_STN0_RX_DN<6>")
	)
	(segment
		(start 432.224688 -282.265882)
		(end 432.636168 -282.265882)
		(width 0.1651)
		(layer "In5.Cu")
		(net "P5E_PEX3_STN0_RX_DN<6>")
	)
	(segment
		(start 434.133244 -276.694646)
		(end 433.006754 -270.77416)
		(width 0.1651)
		(layer "In5.Cu")
		(net "P5E_PEX3_STN0_RX_DN<6>")
	)
	(segment
		(start 424.6118 -138.402314)
		(end 416.046666 -133.804406)
		(width 0.1651)
		(layer "In5.Cu")
		(net "P5E_PEX3_STN0_RX_DN<6>")
	)
	(segment
		(start 428.84979 -282.599892)
		(end 428.58436 -282.599892)
		(width 0.1143)
		(layer "In5.Cu")
		(net "P5E_PEX3_STN0_RX_DN<6>")
	)
	(segment
		(start 416.046666 -133.804406)
		(end 415.64814 -133.804406)
		(width 0.1651)
		(layer "In5.Cu")
		(net "P5E_PEX3_STN0_RX_DN<6>")
	)
	(segment
		(start 432.636168 -282.265882)
		(end 433.30622 -281.817826)
		(width 0.1651)
		(layer "In5.Cu")
		(net "P5E_PEX3_STN0_RX_DN<6>")
	)
	(segment
		(start 428.53737 -160.243774)
		(end 425.18584 -140.908278)
		(width 0.1651)
		(layer "In5.Cu")
		(net "P5E_PEX3_STN0_RX_DN<6>")
	)
	(segment
		(start 433.006754 -270.77416)
		(end 432.093624 -264.69721)
		(width 0.1651)
		(layer "In5.Cu")
		(net "P5E_PEX3_STN0_RX_DN<6>")
	)
	(segment
		(start 432.15052 -282.220162)
		(end 432.19624 -282.265882)
		(width 0.1143)
		(layer "In5.Cu")
		(net "P5E_PEX3_STN0_RX_DN<6>")
	)
	(segment
		(start 425.03217 -138.902186)
		(end 424.6118 -138.402314)
		(width 0.1651)
		(layer "In5.Cu")
		(net "P5E_PEX3_STN0_RX_DN<6>")
	)
	(segment
		(start 432.19624 -282.265882)
		(end 432.224688 -282.265882)
		(width 0.1143)
		(layer "In5.Cu")
		(net "P5E_PEX3_STN0_RX_DN<6>")
	)
	(segment
		(start 428.47006 -282.35275)
		(end 428.602648 -282.220162)
		(width 0.1143)
		(layer "In5.Cu")
		(net "P5E_PEX3_STN0_RX_DN<6>")
	)
	(segment
		(start 432.093624 -264.69721)
		(end 428.53737 -160.243774)
		(width 0.1651)
		(layer "In5.Cu")
		(net "P5E_PEX3_STN0_RX_DN<6>")
	)
	(segment
		(start 425.18584 -140.908278)
		(end 425.18584 -139.7889)
		(width 0.1651)
		(layer "In5.Cu")
		(net "P5E_PEX3_STN0_RX_DN<6>")
	)
	(segment
		(start 428.47006 -282.485592)
		(end 428.47006 -282.35275)
		(width 0.1143)
		(layer "In5.Cu")
		(net "P5E_PEX3_STN0_RX_DN<6>")
	)
	(segment
		(start 433.30622 -281.817826)
		(end 433.799488 -281.22245)
		(width 0.1651)
		(layer "In5.Cu")
		(net "P5E_PEX3_STN0_RX_DN<6>")
	)
	(segment
		(start 425.18584 -139.7889)
		(end 425.03217 -138.902186)
		(width 0.1651)
		(layer "In5.Cu")
		(net "P5E_PEX3_STN0_RX_DN<6>")
	)
	(segment
		(start 372.74754 -308.734714)
		(end 372.747286 -308.734714)
		(width 0.1651)
		(layer "In9.Cu")
		(net "P5E_PEX3_STN7_RX_DN<114>")
	)
	(segment
		(start 407.309574 -351.700084)
		(end 407.195274 -349.035116)
		(width 0.1651)
		(layer "In9.Cu")
		(net "P5E_PEX3_STN7_RX_DN<114>")
	)
	(segment
		(start 373.681244 -307.20284)
		(end 373.639588 -307.065426)
		(width 0.1651)
		(layer "In9.Cu")
		(net "P5E_PEX3_STN7_RX_DN<114>")
	)
	(segment
		(start 372.55577 -309.309008)
		(end 372.51386 -309.17134)
		(width 0.1651)
		(layer "In9.Cu")
		(net "P5E_PEX3_STN7_RX_DN<114>")
	)
	(segment
		(start 371.992906 -310.362092)
		(end 371.950996 -310.224424)
		(width 0.1651)
		(layer "In9.Cu")
		(net "P5E_PEX3_STN7_RX_DN<114>")
	)
	(segment
		(start 373.076724 -308.118256)
		(end 373.31015 -307.68163)
		(width 0.1651)
		(layer "In9.Cu")
		(net "P5E_PEX3_STN7_RX_DN<114>")
	)
	(segment
		(start 387.434328 -303.252378)
		(end 387.434328 -303.403762)
		(width 0.1143)
		(layer "In9.Cu")
		(net "P5E_PEX3_STN7_RX_DN<114>")
	)
	(segment
		(start 371.95125 -310.224678)
		(end 372.184676 -309.788052)
		(width 0.1651)
		(layer "In9.Cu")
		(net "P5E_PEX3_STN7_RX_DN<114>")
	)
	(segment
		(start 387.434328 -303.403762)
		(end 387.338316 -303.499774)
		(width 0.1143)
		(layer "In9.Cu")
		(net "P5E_PEX3_STN7_RX_DN<114>")
	)
	(segment
		(start 372.514114 -309.17134)
		(end 372.74754 -308.734714)
		(width 0.1651)
		(layer "In9.Cu")
		(net "P5E_PEX3_STN7_RX_DN<114>")
	)
	(segment
		(start 371.058948 -311.893966)
		(end 371.196362 -311.85231)
		(width 0.1651)
		(layer "In9.Cu")
		(net "P5E_PEX3_STN7_RX_DN<114>")
	)
	(segment
		(start 380.758954 -303.165764)
		(end 383.892552 -303.165764)
		(width 0.1651)
		(layer "In9.Cu")
		(net "P5E_PEX3_STN7_RX_DN<114>")
	)
	(segment
		(start 383.921 -303.165764)
		(end 383.96672 -303.120044)
		(width 0.1143)
		(layer "In9.Cu")
		(net "P5E_PEX3_STN7_RX_DN<114>")
	)
	(segment
		(start 368.000788 -323.172074)
		(end 368.000788 -318.587882)
		(width 0.1651)
		(layer "In9.Cu")
		(net "P5E_PEX3_STN7_RX_DN<114>")
	)
	(segment
		(start 376.711464 -304.053748)
		(end 379.056646 -303.705514)
		(width 0.1651)
		(layer "In9.Cu")
		(net "P5E_PEX3_STN7_RX_DN<114>")
	)
	(segment
		(start 373.639588 -307.065426)
		(end 373.941086 -306.501038)
		(width 0.1651)
		(layer "In9.Cu")
		(net "P5E_PEX3_STN7_RX_DN<114>")
	)
	(segment
		(start 379.056646 -303.705514)
		(end 380.758954 -303.165764)
		(width 0.1651)
		(layer "In9.Cu")
		(net "P5E_PEX3_STN7_RX_DN<114>")
	)
	(segment
		(start 387.338316 -303.499774)
		(end 387.050026 -303.499774)
		(width 0.1143)
		(layer "In9.Cu")
		(net "P5E_PEX3_STN7_RX_DN<114>")
	)
	(segment
		(start 411.973014 -377.161044)
		(end 408.475688 -358.065578)
		(width 0.1651)
		(layer "In9.Cu")
		(net "P5E_PEX3_STN7_RX_DN<114>")
	)
	(segment
		(start 425.054268 -408.28214)
		(end 425.054268 -395.218666)
		(width 0.1651)
		(layer "In9.Cu")
		(net "P5E_PEX3_STN7_RX_DN<114>")
	)
	(segment
		(start 387.301994 -303.120044)
		(end 387.434328 -303.252378)
		(width 0.1143)
		(layer "In9.Cu")
		(net "P5E_PEX3_STN7_RX_DN<114>")
	)
	(segment
		(start 423.10939 -392.91133)
		(end 418.350192 -391.217912)
		(width 0.1651)
		(layer "In9.Cu")
		(net "P5E_PEX3_STN7_RX_DN<114>")
	)
	(segment
		(start 369.3922 -326.531478)
		(end 368.000788 -323.172074)
		(width 0.1651)
		(layer "In9.Cu")
		(net "P5E_PEX3_STN7_RX_DN<114>")
	)
	(segment
		(start 370.825776 -312.330592)
		(end 371.058948 -311.893966)
		(width 0.1651)
		(layer "In9.Cu")
		(net "P5E_PEX3_STN7_RX_DN<114>")
	)
	(segment
		(start 376.159522 -304.282348)
		(end 376.711464 -304.053748)
		(width 0.1651)
		(layer "In9.Cu")
		(net "P5E_PEX3_STN7_RX_DN<114>")
	)
	(segment
		(start 373.31015 -307.68163)
		(end 373.447564 -307.639974)
		(width 0.1651)
		(layer "In9.Cu")
		(net "P5E_PEX3_STN7_RX_DN<114>")
	)
	(segment
		(start 371.38864 -311.277508)
		(end 371.622066 -310.84139)
		(width 0.1651)
		(layer "In9.Cu")
		(net "P5E_PEX3_STN7_RX_DN<114>")
	)
	(segment
		(start 372.884954 -308.692804)
		(end 373.118634 -308.255924)
		(width 0.1651)
		(layer "In9.Cu")
		(net "P5E_PEX3_STN7_RX_DN<114>")
	)
	(segment
		(start 418.350192 -391.217912)
		(end 414.880806 -388.391146)
		(width 0.1651)
		(layer "In9.Cu")
		(net "P5E_PEX3_STN7_RX_DN<114>")
	)
	(segment
		(start 374.737884 -305.848004)
		(end 375.088404 -305.497484)
		(width 0.1651)
		(layer "In9.Cu")
		(net "P5E_PEX3_STN7_RX_DN<114>")
	)
	(segment
		(start 408.475434 -358.065578)
		(end 407.309574 -351.700084)
		(width 0.1651)
		(layer "In9.Cu")
		(net "P5E_PEX3_STN7_RX_DN<114>")
	)
	(segment
		(start 375.08815 -305.35372)
		(end 376.159522 -304.282348)
		(width 0.1651)
		(layer "In9.Cu")
		(net "P5E_PEX3_STN7_RX_DN<114>")
	)
	(segment
		(start 373.118634 -308.255924)
		(end 373.076724 -308.118256)
		(width 0.1651)
		(layer "In9.Cu")
		(net "P5E_PEX3_STN7_RX_DN<114>")
	)
	(segment
		(start 371.759226 -310.799226)
		(end 371.992906 -310.362092)
		(width 0.1651)
		(layer "In9.Cu")
		(net "P5E_PEX3_STN7_RX_DN<114>")
	)
	(segment
		(start 425.054268 -395.218666)
		(end 424.797982 -394.599922)
		(width 0.1651)
		(layer "In9.Cu")
		(net "P5E_PEX3_STN7_RX_DN<114>")
	)
	(segment
		(start 370.633752 -312.905394)
		(end 370.867432 -312.46826)
		(width 0.1651)
		(layer "In9.Cu")
		(net "P5E_PEX3_STN7_RX_DN<114>")
	)
	(segment
		(start 414.880806 -388.391146)
		(end 413.6263 -386.523484)
		(width 0.1651)
		(layer "In9.Cu")
		(net "P5E_PEX3_STN7_RX_DN<114>")
	)
	(segment
		(start 405.26716 -341.429086)
		(end 404.366222 -340.36635)
		(width 0.1651)
		(layer "In9.Cu")
		(net "P5E_PEX3_STN7_RX_DN<114>")
	)
	(segment
		(start 372.184676 -309.788052)
		(end 372.184422 -309.787798)
		(width 0.1651)
		(layer "In9.Cu")
		(net "P5E_PEX3_STN7_RX_DN<114>")
	)
	(segment
		(start 374.648476 -331.7875)
		(end 369.3922 -326.531478)
		(width 0.1651)
		(layer "In9.Cu")
		(net "P5E_PEX3_STN7_RX_DN<114>")
	)
	(segment
		(start 423.889932 -409.490164)
		(end 423.889932 -409.108148)
		(width 0.1651)
		(layer "In9.Cu")
		(net "P5E_PEX3_STN7_RX_DN<114>")
	)
	(segment
		(start 373.941086 -306.501038)
		(end 374.59412 -305.848004)
		(width 0.1651)
		(layer "In9.Cu")
		(net "P5E_PEX3_STN7_RX_DN<114>")
	)
	(segment
		(start 371.388386 -311.277508)
		(end 371.38864 -311.277508)
		(width 0.1651)
		(layer "In9.Cu")
		(net "P5E_PEX3_STN7_RX_DN<114>")
	)
	(segment
		(start 413.6263 -386.523484)
		(end 413.021526 -384.931666)
		(width 0.1651)
		(layer "In9.Cu")
		(net "P5E_PEX3_STN7_RX_DN<114>")
	)
	(segment
		(start 370.867432 -312.46826)
		(end 370.825776 -312.330592)
		(width 0.1651)
		(layer "In9.Cu")
		(net "P5E_PEX3_STN7_RX_DN<114>")
	)
	(segment
		(start 407.195274 -349.035116)
		(end 405.26716 -341.429086)
		(width 0.1651)
		(layer "In9.Cu")
		(net "P5E_PEX3_STN7_RX_DN<114>")
	)
	(segment
		(start 397.497554 -337.3628)
		(end 378.524008 -333.009748)
		(width 0.1651)
		(layer "In9.Cu")
		(net "P5E_PEX3_STN7_RX_DN<114>")
	)
	(segment
		(start 413.021526 -384.931666)
		(end 411.973014 -377.161044)
		(width 0.1651)
		(layer "In9.Cu")
		(net "P5E_PEX3_STN7_RX_DN<114>")
	)
	(segment
		(start 372.51386 -309.17134)
		(end 372.514114 -309.17134)
		(width 0.1651)
		(layer "In9.Cu")
		(net "P5E_PEX3_STN7_RX_DN<114>")
	)
	(segment
		(start 371.950996 -310.224424)
		(end 371.95125 -310.224678)
		(width 0.1651)
		(layer "In9.Cu")
		(net "P5E_PEX3_STN7_RX_DN<114>")
	)
	(segment
		(start 368.000788 -318.587882)
		(end 369.788186 -314.272168)
		(width 0.1651)
		(layer "In9.Cu")
		(net "P5E_PEX3_STN7_RX_DN<114>")
	)
	(segment
		(start 373.447564 -307.639974)
		(end 373.681244 -307.20284)
		(width 0.1651)
		(layer "In9.Cu")
		(net "P5E_PEX3_STN7_RX_DN<114>")
	)
	(segment
		(start 404.366222 -340.36635)
		(end 397.497554 -337.3628)
		(width 0.1651)
		(layer "In9.Cu")
		(net "P5E_PEX3_STN7_RX_DN<114>")
	)
	(segment
		(start 372.184422 -309.787798)
		(end 372.32209 -309.745888)
		(width 0.1651)
		(layer "In9.Cu")
		(net "P5E_PEX3_STN7_RX_DN<114>")
	)
	(segment
		(start 383.892552 -303.165764)
		(end 383.921 -303.165764)
		(width 0.1143)
		(layer "In9.Cu")
		(net "P5E_PEX3_STN7_RX_DN<114>")
	)
	(segment
		(start 371.430042 -311.415176)
		(end 371.388386 -311.277508)
		(width 0.1651)
		(layer "In9.Cu")
		(net "P5E_PEX3_STN7_RX_DN<114>")
	)
	(segment
		(start 372.32209 -309.745888)
		(end 372.55577 -309.309008)
		(width 0.1651)
		(layer "In9.Cu")
		(net "P5E_PEX3_STN7_RX_DN<114>")
	)
	(segment
		(start 371.621558 -310.840882)
		(end 371.759226 -310.799226)
		(width 0.1651)
		(layer "In9.Cu")
		(net "P5E_PEX3_STN7_RX_DN<114>")
	)
	(segment
		(start 375.088404 -305.497484)
		(end 375.08815 -305.35372)
		(width 0.1651)
		(layer "In9.Cu")
		(net "P5E_PEX3_STN7_RX_DN<114>")
	)
	(segment
		(start 372.747286 -308.734714)
		(end 372.884954 -308.692804)
		(width 0.1651)
		(layer "In9.Cu")
		(net "P5E_PEX3_STN7_RX_DN<114>")
	)
	(segment
		(start 424.016932 -408.981148)
		(end 424.35526 -408.981148)
		(width 0.1651)
		(layer "In9.Cu")
		(net "P5E_PEX3_STN7_RX_DN<114>")
	)
	(segment
		(start 371.196362 -311.85231)
		(end 371.430042 -311.415176)
		(width 0.1651)
		(layer "In9.Cu")
		(net "P5E_PEX3_STN7_RX_DN<114>")
	)
	(segment
		(start 378.524008 -333.009748)
		(end 378.523754 -333.009748)
		(width 0.1651)
		(layer "In9.Cu")
		(net "P5E_PEX3_STN7_RX_DN<114>")
	)
	(segment
		(start 424.35526 -408.981148)
		(end 425.054268 -408.28214)
		(width 0.1651)
		(layer "In9.Cu")
		(net "P5E_PEX3_STN7_RX_DN<114>")
	)
	(segment
		(start 369.788186 -314.272168)
		(end 370.496338 -312.94705)
		(width 0.1651)
		(layer "In9.Cu")
		(net "P5E_PEX3_STN7_RX_DN<114>")
	)
	(segment
		(start 378.523754 -333.009748)
		(end 374.648476 -331.7875)
		(width 0.1651)
		(layer "In9.Cu")
		(net "P5E_PEX3_STN7_RX_DN<114>")
	)
	(segment
		(start 370.496338 -312.94705)
		(end 370.496084 -312.94705)
		(width 0.1651)
		(layer "In9.Cu")
		(net "P5E_PEX3_STN7_RX_DN<114>")
	)
	(segment
		(start 424.797982 -394.599922)
		(end 423.10939 -392.91133)
		(width 0.1651)
		(layer "In9.Cu")
		(net "P5E_PEX3_STN7_RX_DN<114>")
	)
	(segment
		(start 423.889932 -409.108148)
		(end 424.016932 -408.981148)
		(width 0.1651)
		(layer "In9.Cu")
		(net "P5E_PEX3_STN7_RX_DN<114>")
	)
	(segment
		(start 383.96672 -303.120044)
		(end 387.301994 -303.120044)
		(width 0.1143)
		(layer "In9.Cu")
		(net "P5E_PEX3_STN7_RX_DN<114>")
	)
	(segment
		(start 371.622066 -310.84139)
		(end 371.621558 -310.840882)
		(width 0.1651)
		(layer "In9.Cu")
		(net "P5E_PEX3_STN7_RX_DN<114>")
	)
	(segment
		(start 408.475688 -358.065578)
		(end 408.475434 -358.065578)
		(width 0.1651)
		(layer "In9.Cu")
		(net "P5E_PEX3_STN7_RX_DN<114>")
	)
	(segment
		(start 370.496084 -312.94705)
		(end 370.633752 -312.905394)
		(width 0.1651)
		(layer "In9.Cu")
		(net "P5E_PEX3_STN7_RX_DN<114>")
	)
	(segment
		(start 374.59412 -305.848004)
		(end 374.737884 -305.848004)
		(width 0.1651)
		(layer "In9.Cu")
		(net "P5E_PEX3_STN7_RX_DN<114>")
	)
	(segment
		(start 412.37789 -116.550186)
		(end 413.767778 -116.550186)
		(width 0.13208)
		(layer "F.Cu")
		(net "PRSNTB2_NIC7_N")
	)
	(segment
		(start 412.37789 -117.566186)
		(end 412.37789 -116.550186)
		(width 0.13208)
		(layer "F.Cu")
		(net "PRSNTB2_NIC7_N")
	)
	(segment
		(start 415.451798 -115.834922)
		(end 416.95751 -115.834922)
		(width 0.13208)
		(layer "F.Cu")
		(net "PRSNTB2_NIC7_N")
	)
	(segment
		(start 414.83915 -116.44757)
		(end 415.451798 -115.834922)
		(width 0.13208)
		(layer "F.Cu")
		(net "PRSNTB2_NIC7_N")
	)
	(segment
		(start 413.767778 -116.550186)
		(end 413.870394 -116.44757)
		(width 0.13208)
		(layer "F.Cu")
		(net "PRSNTB2_NIC7_N")
	)
	(segment
		(start 413.870394 -116.44757)
		(end 414.83915 -116.44757)
		(width 0.13208)
		(layer "F.Cu")
		(net "PRSNTB2_NIC7_N")
	)
	(via
		(at 414.83915 -116.44757)
		(size 0.508)
		(drill 0.254)
		(layers "F.Cu" "B.Cu")
		(net "PRSNTB2_NIC7_N")
	)
	(segment
		(start 135.149844 -24.488648)
		(end 132.92074 -24.488648)
		(width 0.13208)
		(layer "F.Cu")
		(net "DUALPORT_N_SSD4")
	)
	(segment
		(start 135.571738 -24.942292)
		(end 135.571738 -24.910542)
		(width 0.13208)
		(layer "F.Cu")
		(net "DUALPORT_N_SSD4")
	)
	(segment
		(start 132.566664 -24.134572)
		(end 132.566664 -23.589996)
		(width 0.13208)
		(layer "F.Cu")
		(net "DUALPORT_N_SSD4")
	)
	(segment
		(start 135.571738 -24.910542)
		(end 135.149844 -24.488648)
		(width 0.13208)
		(layer "F.Cu")
		(net "DUALPORT_N_SSD4")
	)
	(segment
		(start 136.587738 -24.942292)
		(end 135.571738 -24.942292)
		(width 0.13208)
		(layer "F.Cu")
		(net "DUALPORT_N_SSD4")
	)
	(segment
		(start 132.566664 -23.589996)
		(end 131.36499 -23.589996)
		(width 0.13208)
		(layer "F.Cu")
		(net "DUALPORT_N_SSD4")
	)
	(segment
		(start 132.92074 -24.488648)
		(end 132.566664 -24.134572)
		(width 0.13208)
		(layer "F.Cu")
		(net "DUALPORT_N_SSD4")
	)
	(via
		(at 132.566664 -23.589996)
		(size 0.508)
		(drill 0.254)
		(layers "F.Cu" "B.Cu")
		(net "DUALPORT_N_SSD4")
	)
	(segment
		(start 73.745852 -120.635014)
		(end 73.908666 -120.797828)
		(width 0.13462)
		(layer "F.Cu")
		(net "P5E_PEX0_STN0_TX_C_DN<1>")
	)
	(segment
		(start 82.07375 -120.797828)
		(end 82.394806 -120.476772)
		(width 0.13462)
		(layer "F.Cu")
		(net "P5E_PEX0_STN0_TX_C_DN<1>")
	)
	(segment
		(start 73.908666 -120.797828)
		(end 82.07375 -120.797828)
		(width 0.13462)
		(layer "F.Cu")
		(net "P5E_PEX0_STN0_TX_C_DN<1>")
	)
	(segment
		(start 73.257664 -120.635014)
		(end 73.745852 -120.635014)
		(width 0.13462)
		(layer "F.Cu")
		(net "P5E_PEX0_STN0_TX_C_DN<1>")
	)
	(segment
		(start 168.048432 -108.88218)
		(end 167.393112 -108.88218)
		(width 0.13462)
		(layer "F.Cu")
		(net "P5E_PEX1_STN1_RX_DN<21>")
	)
	(segment
		(start 168.342564 -109.176312)
		(end 168.048432 -108.88218)
		(width 0.13462)
		(layer "F.Cu")
		(net "P5E_PEX1_STN1_RX_DN<21>")
	)
	(segment
		(start 167.393112 -108.88218)
		(end 167.230298 -109.044994)
		(width 0.13462)
		(layer "F.Cu")
		(net "P5E_PEX1_STN1_RX_DN<21>")
	)
	(segment
		(start 167.230298 -109.044994)
		(end 166.742364 -109.044994)
		(width 0.13462)
		(layer "F.Cu")
		(net "P5E_PEX1_STN1_RX_DN<21>")
	)
	(segment
		(start 163.167822 -111.469932)
		(end 158.82366 -113.93424)
		(width 0.1651)
		(layer "In5.Cu")
		(net "P5E_PEX1_STN1_RX_DN<21>")
	)
	(segment
		(start 180.16601 -271.599152)
		(end 180.12029 -271.644872)
		(width 0.1143)
		(layer "In5.Cu")
		(net "P5E_PEX1_STN1_RX_DN<21>")
	)
	(segment
		(start 153.904188 -129.54635)
		(end 153.75382 -129.606294)
		(width 0.1651)
		(layer "In5.Cu")
		(net "P5E_PEX1_STN1_RX_DN<21>")
	)
	(segment
		(start 163.754816 -111.268256)
		(end 163.323778 -111.512858)
		(width 0.1651)
		(layer "In5.Cu")
		(net "P5E_PEX1_STN1_RX_DN<21>")
	)
	(segment
		(start 154.099768 -129.090928)
		(end 153.904188 -129.54635)
		(width 0.1651)
		(layer "In5.Cu")
		(net "P5E_PEX1_STN1_RX_DN<21>")
	)
	(segment
		(start 149.47519 -150.684484)
		(end 149.959822 -158.511494)
		(width 0.1651)
		(layer "In5.Cu")
		(net "P5E_PEX1_STN1_RX_DN<21>")
	)
	(segment
		(start 153.558494 -130.061208)
		(end 153.618438 -130.211322)
		(width 0.1651)
		(layer "In5.Cu")
		(net "P5E_PEX1_STN1_RX_DN<21>")
	)
	(segment
		(start 165.50259 -110.145322)
		(end 164.858192 -110.510828)
		(width 0.1651)
		(layer "In5.Cu")
		(net "P5E_PEX1_STN1_RX_DN<21>")
	)
	(segment
		(start 156.002228 -124.370846)
		(end 155.001976 -126.700026)
		(width 0.1651)
		(layer "In5.Cu")
		(net "P5E_PEX1_STN1_RX_DN<21>")
	)
	(segment
		(start 152.652984 -136.432798)
		(end 151.459946 -139.737338)
		(width 0.1651)
		(layer "In5.Cu")
		(net "P5E_PEX1_STN1_RX_DN<21>")
	)
	(segment
		(start 168.342564 -109.176312)
		(end 168.051734 -108.885482)
		(width 0.1651)
		(layer "In5.Cu")
		(net "P5E_PEX1_STN1_RX_DN<21>")
	)
	(segment
		(start 165.658292 -110.188248)
		(end 165.50259 -110.145322)
		(width 0.1651)
		(layer "In5.Cu")
		(net "P5E_PEX1_STN1_RX_DN<21>")
	)
	(segment
		(start 155.06192 -126.85014)
		(end 154.866594 -127.305562)
		(width 0.1651)
		(layer "In5.Cu")
		(net "P5E_PEX1_STN1_RX_DN<21>")
	)
	(segment
		(start 180.12029 -271.644872)
		(end 180.12029 -275.276056)
		(width 0.1143)
		(layer "In5.Cu")
		(net "P5E_PEX1_STN1_RX_DN<21>")
	)
	(segment
		(start 154.866594 -127.305562)
		(end 154.716226 -127.365506)
		(width 0.1651)
		(layer "In5.Cu")
		(net "P5E_PEX1_STN1_RX_DN<21>")
	)
	(segment
		(start 154.580844 -127.970534)
		(end 154.385518 -128.425956)
		(width 0.1651)
		(layer "In5.Cu")
		(net "P5E_PEX1_STN1_RX_DN<21>")
	)
	(segment
		(start 164.858192 -110.510828)
		(end 164.815266 -110.66653)
		(width 0.1651)
		(layer "In5.Cu")
		(net "P5E_PEX1_STN1_RX_DN<21>")
	)
	(segment
		(start 153.423112 -130.666744)
		(end 153.272744 -130.726688)
		(width 0.1651)
		(layer "In5.Cu")
		(net "P5E_PEX1_STN1_RX_DN<21>")
	)
	(segment
		(start 166.08933 -109.943646)
		(end 165.658292 -110.188248)
		(width 0.1651)
		(layer "In5.Cu")
		(net "P5E_PEX1_STN1_RX_DN<21>")
	)
	(segment
		(start 149.959822 -158.511494)
		(end 151.011636 -164.60978)
		(width 0.1651)
		(layer "In5.Cu")
		(net "P5E_PEX1_STN1_RX_DN<21>")
	)
	(segment
		(start 158.771844 -113.984532)
		(end 158.11119 -115.159028)
		(width 0.1651)
		(layer "In5.Cu")
		(net "P5E_PEX1_STN1_RX_DN<21>")
	)
	(segment
		(start 166.56304 -109.543596)
		(end 166.132256 -109.787944)
		(width 0.1651)
		(layer "In5.Cu")
		(net "P5E_PEX1_STN1_RX_DN<21>")
	)
	(segment
		(start 155.001976 -126.700026)
		(end 155.06192 -126.85014)
		(width 0.1651)
		(layer "In5.Cu")
		(net "P5E_PEX1_STN1_RX_DN<21>")
	)
	(segment
		(start 180.16601 -271.570704)
		(end 180.16601 -271.599152)
		(width 0.1143)
		(layer "In5.Cu")
		(net "P5E_PEX1_STN1_RX_DN<21>")
	)
	(segment
		(start 154.039824 -128.940814)
		(end 154.099768 -129.090928)
		(width 0.1651)
		(layer "In5.Cu")
		(net "P5E_PEX1_STN1_RX_DN<21>")
	)
	(segment
		(start 166.718742 -109.586522)
		(end 166.56304 -109.543596)
		(width 0.1651)
		(layer "In5.Cu")
		(net "P5E_PEX1_STN1_RX_DN<21>")
	)
	(segment
		(start 152.652984 -132.169662)
		(end 152.652984 -136.432798)
		(width 0.1651)
		(layer "In5.Cu")
		(net "P5E_PEX1_STN1_RX_DN<21>")
	)
	(segment
		(start 180.385466 -275.379434)
		(end 180.499766 -275.265134)
		(width 0.1143)
		(layer "In5.Cu")
		(net "P5E_PEX1_STN1_RX_DN<21>")
	)
	(segment
		(start 151.459946 -139.737338)
		(end 149.47519 -150.684484)
		(width 0.1651)
		(layer "In5.Cu")
		(net "P5E_PEX1_STN1_RX_DN<21>")
	)
	(segment
		(start 163.797742 -111.112554)
		(end 163.754816 -111.268256)
		(width 0.1651)
		(layer "In5.Cu")
		(net "P5E_PEX1_STN1_RX_DN<21>")
	)
	(segment
		(start 154.5209 -127.82042)
		(end 154.580844 -127.970534)
		(width 0.1651)
		(layer "In5.Cu")
		(net "P5E_PEX1_STN1_RX_DN<21>")
	)
	(segment
		(start 153.618438 -130.211322)
		(end 153.423112 -130.666744)
		(width 0.1651)
		(layer "In5.Cu")
		(net "P5E_PEX1_STN1_RX_DN<21>")
	)
	(segment
		(start 180.223668 -275.379434)
		(end 180.385466 -275.379434)
		(width 0.1143)
		(layer "In5.Cu")
		(net "P5E_PEX1_STN1_RX_DN<21>")
	)
	(segment
		(start 167.19296 -109.186218)
		(end 167.150034 -109.34192)
		(width 0.1651)
		(layer "In5.Cu")
		(net "P5E_PEX1_STN1_RX_DN<21>")
	)
	(segment
		(start 163.323778 -111.512858)
		(end 163.167822 -111.469932)
		(width 0.1651)
		(layer "In5.Cu")
		(net "P5E_PEX1_STN1_RX_DN<21>")
	)
	(segment
		(start 180.499766 -275.265134)
		(end 180.499766 -274.999704)
		(width 0.1143)
		(layer "In5.Cu")
		(net "P5E_PEX1_STN1_RX_DN<21>")
	)
	(segment
		(start 154.716226 -127.365506)
		(end 154.5209 -127.82042)
		(width 0.1651)
		(layer "In5.Cu")
		(net "P5E_PEX1_STN1_RX_DN<21>")
	)
	(segment
		(start 167.723058 -108.885482)
		(end 167.19296 -109.186218)
		(width 0.1651)
		(layer "In5.Cu")
		(net "P5E_PEX1_STN1_RX_DN<21>")
	)
	(segment
		(start 154.23515 -128.4859)
		(end 154.039824 -128.940814)
		(width 0.1651)
		(layer "In5.Cu")
		(net "P5E_PEX1_STN1_RX_DN<21>")
	)
	(segment
		(start 158.82366 -113.93424)
		(end 158.771844 -113.984532)
		(width 0.1651)
		(layer "In5.Cu")
		(net "P5E_PEX1_STN1_RX_DN<21>")
	)
	(segment
		(start 154.385518 -128.425956)
		(end 154.23515 -128.4859)
		(width 0.1651)
		(layer "In5.Cu")
		(net "P5E_PEX1_STN1_RX_DN<21>")
	)
	(segment
		(start 164.228526 -110.868206)
		(end 163.797742 -111.112554)
		(width 0.1651)
		(layer "In5.Cu")
		(net "P5E_PEX1_STN1_RX_DN<21>")
	)
	(segment
		(start 153.272744 -130.726688)
		(end 152.652984 -132.169662)
		(width 0.1651)
		(layer "In5.Cu")
		(net "P5E_PEX1_STN1_RX_DN<21>")
	)
	(segment
		(start 167.150034 -109.34192)
		(end 166.718742 -109.586522)
		(width 0.1651)
		(layer "In5.Cu")
		(net "P5E_PEX1_STN1_RX_DN<21>")
	)
	(segment
		(start 180.16601 -269.144496)
		(end 180.16601 -271.570704)
		(width 0.1651)
		(layer "In5.Cu")
		(net "P5E_PEX1_STN1_RX_DN<21>")
	)
	(segment
		(start 164.384228 -110.911132)
		(end 164.228526 -110.868206)
		(width 0.1651)
		(layer "In5.Cu")
		(net "P5E_PEX1_STN1_RX_DN<21>")
	)
	(segment
		(start 158.11119 -115.159028)
		(end 156.002228 -124.370846)
		(width 0.1651)
		(layer "In5.Cu")
		(net "P5E_PEX1_STN1_RX_DN<21>")
	)
	(segment
		(start 166.132256 -109.787944)
		(end 166.08933 -109.943646)
		(width 0.1651)
		(layer "In5.Cu")
		(net "P5E_PEX1_STN1_RX_DN<21>")
	)
	(segment
		(start 164.815266 -110.66653)
		(end 164.384228 -110.911132)
		(width 0.1651)
		(layer "In5.Cu")
		(net "P5E_PEX1_STN1_RX_DN<21>")
	)
	(segment
		(start 168.051734 -108.885482)
		(end 167.723058 -108.885482)
		(width 0.1651)
		(layer "In5.Cu")
		(net "P5E_PEX1_STN1_RX_DN<21>")
	)
	(segment
		(start 151.011636 -164.60978)
		(end 180.16601 -269.144496)
		(width 0.1651)
		(layer "In5.Cu")
		(net "P5E_PEX1_STN1_RX_DN<21>")
	)
	(segment
		(start 180.12029 -275.276056)
		(end 180.223668 -275.379434)
		(width 0.1143)
		(layer "In5.Cu")
		(net "P5E_PEX1_STN1_RX_DN<21>")
	)
	(segment
		(start 153.75382 -129.606294)
		(end 153.558494 -130.061208)
		(width 0.1651)
		(layer "In5.Cu")
		(net "P5E_PEX1_STN1_RX_DN<21>")
	)
	(segment
		(start 115.540028 -356.831646)
		(end 115.860068 -356.511606)
		(width 0.13462)
		(layer "F.Cu")
		(net "P5E_PEX1_STN6_TX_C_DN<101>")
	)
	(segment
		(start 115.540028 -357.46309)
		(end 115.540028 -356.831646)
		(width 0.13462)
		(layer "F.Cu")
		(net "P5E_PEX1_STN6_TX_C_DN<101>")
	)
	(segment
		(start 115.834668 -357.75773)
		(end 115.540028 -357.46309)
		(width 0.13462)
		(layer "F.Cu")
		(net "P5E_PEX1_STN6_TX_C_DN<101>")
	)
	(segment
		(start 120.437402 -382.980946)
		(end 120.310148 -383.1082)
		(width 0.1651)
		(layer "In7.Cu")
		(net "P5E_PEX1_STN6_TX_C_DN<101>")
	)
	(segment
		(start 115.834668 -357.75773)
		(end 115.543838 -358.04856)
		(width 0.1651)
		(layer "In7.Cu")
		(net "P5E_PEX1_STN6_TX_C_DN<101>")
	)
	(segment
		(start 121.369582 -369.304824)
		(end 121.369582 -382.397508)
		(width 0.1651)
		(layer "In7.Cu")
		(net "P5E_PEX1_STN6_TX_C_DN<101>")
	)
	(segment
		(start 120.786144 -382.980946)
		(end 120.437402 -382.980946)
		(width 0.1651)
		(layer "In7.Cu")
		(net "P5E_PEX1_STN6_TX_C_DN<101>")
	)
	(segment
		(start 120.310148 -383.1082)
		(end 120.310148 -383.490216)
		(width 0.1651)
		(layer "In7.Cu")
		(net "P5E_PEX1_STN6_TX_C_DN<101>")
	)
	(segment
		(start 121.369582 -382.397508)
		(end 120.786144 -382.980946)
		(width 0.1651)
		(layer "In7.Cu")
		(net "P5E_PEX1_STN6_TX_C_DN<101>")
	)
	(segment
		(start 115.738402 -359.462324)
		(end 120.988074 -367.856516)
		(width 0.1651)
		(layer "In7.Cu")
		(net "P5E_PEX1_STN6_TX_C_DN<101>")
	)
	(segment
		(start 115.543838 -358.21366)
		(end 115.738402 -359.462324)
		(width 0.1651)
		(layer "In7.Cu")
		(net "P5E_PEX1_STN6_TX_C_DN<101>")
	)
	(segment
		(start 115.543838 -358.04856)
		(end 115.543838 -358.21366)
		(width 0.1651)
		(layer "In7.Cu")
		(net "P5E_PEX1_STN6_TX_C_DN<101>")
	)
	(segment
		(start 120.988074 -367.856516)
		(end 121.369582 -369.304824)
		(width 0.1651)
		(layer "In7.Cu")
		(net "P5E_PEX1_STN6_TX_C_DN<101>")
	)
	(segment
		(start 283.478478 -99.59848)
		(end 283.325062 -99.445064)
		(width 0.13462)
		(layer "F.Cu")
		(net "P5E_PEX2_STN1_RX_DP<16>")
	)
	(segment
		(start 286.011112 -99.59848)
		(end 283.478478 -99.59848)
		(width 0.13462)
		(layer "F.Cu")
		(net "P5E_PEX2_STN1_RX_DP<16>")
	)
	(segment
		(start 286.296862 -99.31273)
		(end 286.011112 -99.59848)
		(width 0.13462)
		(layer "F.Cu")
		(net "P5E_PEX2_STN1_RX_DP<16>")
	)
	(segment
		(start 283.325062 -99.445064)
		(end 282.842462 -99.445064)
		(width 0.13462)
		(layer "F.Cu")
		(net "P5E_PEX2_STN1_RX_DP<16>")
	)
	(segment
		(start 291.735256 -273.66976)
		(end 291.849556 -273.78406)
		(width 0.1143)
		(layer "In5.Cu")
		(net "P5E_PEX2_STN1_RX_DP<16>")
	)
	(segment
		(start 286.296862 -99.31273)
		(end 286.006032 -99.60356)
		(width 0.1651)
		(layer "In5.Cu")
		(net "P5E_PEX2_STN1_RX_DP<16>")
	)
	(segment
		(start 291.23386 -271.525746)
		(end 291.23386 -271.554194)
		(width 0.1143)
		(layer "In5.Cu")
		(net "P5E_PEX2_STN1_RX_DP<16>")
	)
	(segment
		(start 260.215126 -149.955758)
		(end 260.21538 -149.955758)
		(width 0.1651)
		(layer "In5.Cu")
		(net "P5E_PEX2_STN1_RX_DP<16>")
	)
	(segment
		(start 284.091888 -99.60356)
		(end 277.106888 -103.095806)
		(width 0.1651)
		(layer "In5.Cu")
		(net "P5E_PEX2_STN1_RX_DP<16>")
	)
	(segment
		(start 268.133576 -109.97438)
		(end 266.495022 -110.640876)
		(width 0.1651)
		(layer "In5.Cu")
		(net "P5E_PEX2_STN1_RX_DP<16>")
	)
	(segment
		(start 260.21411 -149.937724)
		(end 260.215126 -149.955758)
		(width 0.1651)
		(layer "In5.Cu")
		(net "P5E_PEX2_STN1_RX_DP<16>")
	)
	(segment
		(start 291.23386 -270.105124)
		(end 291.23386 -271.525746)
		(width 0.1651)
		(layer "In5.Cu")
		(net "P5E_PEX2_STN1_RX_DP<16>")
	)
	(segment
		(start 286.006032 -99.60356)
		(end 284.091888 -99.60356)
		(width 0.1651)
		(layer "In5.Cu")
		(net "P5E_PEX2_STN1_RX_DP<16>")
	)
	(segment
		(start 277.106888 -103.095806)
		(end 271.232376 -107.761532)
		(width 0.1651)
		(layer "In5.Cu")
		(net "P5E_PEX2_STN1_RX_DP<16>")
	)
	(segment
		(start 291.849556 -273.78406)
		(end 291.849556 -274.04949)
		(width 0.1143)
		(layer "In5.Cu")
		(net "P5E_PEX2_STN1_RX_DP<16>")
	)
	(segment
		(start 260.21538 -149.955758)
		(end 260.888734 -159.572198)
		(width 0.1651)
		(layer "In5.Cu")
		(net "P5E_PEX2_STN1_RX_DP<16>")
	)
	(segment
		(start 271.232376 -107.761532)
		(end 268.78915 -109.382306)
		(width 0.1651)
		(layer "In5.Cu")
		(net "P5E_PEX2_STN1_RX_DP<16>")
	)
	(segment
		(start 291.494464 -273.66976)
		(end 291.735256 -273.66976)
		(width 0.1143)
		(layer "In5.Cu")
		(net "P5E_PEX2_STN1_RX_DP<16>")
	)
	(segment
		(start 291.27958 -271.599914)
		(end 291.27958 -273.454876)
		(width 0.1143)
		(layer "In5.Cu")
		(net "P5E_PEX2_STN1_RX_DP<16>")
	)
	(segment
		(start 266.021566 -111.125508)
		(end 263.220962 -119.642636)
		(width 0.1651)
		(layer "In5.Cu")
		(net "P5E_PEX2_STN1_RX_DP<16>")
	)
	(segment
		(start 263.220962 -119.642636)
		(end 261.597902 -126.35865)
		(width 0.1651)
		(layer "In5.Cu")
		(net "P5E_PEX2_STN1_RX_DP<16>")
	)
	(segment
		(start 262.144256 -166.070534)
		(end 291.23386 -270.105124)
		(width 0.1651)
		(layer "In5.Cu")
		(net "P5E_PEX2_STN1_RX_DP<16>")
	)
	(segment
		(start 291.23386 -271.554194)
		(end 291.27958 -271.599914)
		(width 0.1143)
		(layer "In5.Cu")
		(net "P5E_PEX2_STN1_RX_DP<16>")
	)
	(segment
		(start 268.78915 -109.382306)
		(end 268.133576 -109.97438)
		(width 0.1651)
		(layer "In5.Cu")
		(net "P5E_PEX2_STN1_RX_DP<16>")
	)
	(segment
		(start 261.597902 -126.35865)
		(end 260.21411 -149.937724)
		(width 0.1651)
		(layer "In5.Cu")
		(net "P5E_PEX2_STN1_RX_DP<16>")
	)
	(segment
		(start 291.27958 -273.454876)
		(end 291.494464 -273.66976)
		(width 0.1143)
		(layer "In5.Cu")
		(net "P5E_PEX2_STN1_RX_DP<16>")
	)
	(segment
		(start 260.888734 -159.572198)
		(end 262.144256 -166.070534)
		(width 0.1651)
		(layer "In5.Cu")
		(net "P5E_PEX2_STN1_RX_DP<16>")
	)
	(segment
		(start 266.495022 -110.640876)
		(end 266.021566 -111.125508)
		(width 0.1651)
		(layer "In5.Cu")
		(net "P5E_PEX2_STN1_RX_DP<16>")
	)
	(segment
		(start 416.476434 -122.435112)
		(end 416.95751 -122.435112)
		(width 0.13462)
		(layer "F.Cu")
		(net "P5E_PEX3_STN0_RX_DN<2>")
	)
	(segment
		(start 416.313366 -122.59818)
		(end 416.476434 -122.435112)
		(width 0.13462)
		(layer "F.Cu")
		(net "P5E_PEX3_STN0_RX_DN<2>")
	)
	(segment
		(start 415.35731 -122.30354)
		(end 415.65195 -122.59818)
		(width 0.13462)
		(layer "F.Cu")
		(net "P5E_PEX3_STN0_RX_DN<2>")
	)
	(segment
		(start 415.65195 -122.59818)
		(end 416.313366 -122.59818)
		(width 0.13462)
		(layer "F.Cu")
		(net "P5E_PEX3_STN0_RX_DN<2>")
	)
	(segment
		(start 433.8193 -286.034226)
		(end 433.787804 -286.065722)
		(width 0.1651)
		(layer "In5.Cu")
		(net "P5E_PEX3_STN0_RX_DN<2>")
	)
	(segment
		(start 432.243484 -138.329924)
		(end 435.035706 -143.552926)
		(width 0.1651)
		(layer "In5.Cu")
		(net "P5E_PEX3_STN0_RX_DN<2>")
	)
	(segment
		(start 432.224688 -286.065722)
		(end 432.19624 -286.065722)
		(width 0.1143)
		(layer "In5.Cu")
		(net "P5E_PEX3_STN0_RX_DN<2>")
	)
	(segment
		(start 428.47006 -286.285432)
		(end 428.58436 -286.399732)
		(width 0.1143)
		(layer "In5.Cu")
		(net "P5E_PEX3_STN0_RX_DN<2>")
	)
	(segment
		(start 435.94655 -149.960838)
		(end 436.442612 -168.455086)
		(width 0.1651)
		(layer "In5.Cu")
		(net "P5E_PEX3_STN0_RX_DN<2>")
	)
	(segment
		(start 435.736238 -232.139744)
		(end 437.383936 -239.882426)
		(width 0.1651)
		(layer "In5.Cu")
		(net "P5E_PEX3_STN0_RX_DN<2>")
	)
	(segment
		(start 437.383936 -239.882426)
		(end 446.03543 -269.474696)
		(width 0.1651)
		(layer "In5.Cu")
		(net "P5E_PEX3_STN0_RX_DN<2>")
	)
	(segment
		(start 435.035706 -143.552926)
		(end 435.94655 -149.960838)
		(width 0.1651)
		(layer "In5.Cu")
		(net "P5E_PEX3_STN0_RX_DN<2>")
	)
	(segment
		(start 443.53861 -277.258272)
		(end 435.24043 -285.298642)
		(width 0.1651)
		(layer "In5.Cu")
		(net "P5E_PEX3_STN0_RX_DN<2>")
	)
	(segment
		(start 415.64814 -122.59437)
		(end 416.274504 -122.59437)
		(width 0.1651)
		(layer "In5.Cu")
		(net "P5E_PEX3_STN0_RX_DN<2>")
	)
	(segment
		(start 445.867028 -273.153378)
		(end 443.53861 -277.258272)
		(width 0.1651)
		(layer "In5.Cu")
		(net "P5E_PEX3_STN0_RX_DN<2>")
	)
	(segment
		(start 420.988998 -124.55398)
		(end 422.904158 -126.48184)
		(width 0.1651)
		(layer "In5.Cu")
		(net "P5E_PEX3_STN0_RX_DN<2>")
	)
	(segment
		(start 428.47006 -286.15259)
		(end 428.47006 -286.285432)
		(width 0.1143)
		(layer "In5.Cu")
		(net "P5E_PEX3_STN0_RX_DN<2>")
	)
	(segment
		(start 435.24043 -285.298642)
		(end 433.8193 -286.034226)
		(width 0.1651)
		(layer "In5.Cu")
		(net "P5E_PEX3_STN0_RX_DN<2>")
	)
	(segment
		(start 432.15052 -286.020002)
		(end 428.602648 -286.020002)
		(width 0.1143)
		(layer "In5.Cu")
		(net "P5E_PEX3_STN0_RX_DN<2>")
	)
	(segment
		(start 416.274504 -122.59437)
		(end 420.988998 -124.55398)
		(width 0.1651)
		(layer "In5.Cu")
		(net "P5E_PEX3_STN0_RX_DN<2>")
	)
	(segment
		(start 428.602648 -286.020002)
		(end 428.47006 -286.15259)
		(width 0.1143)
		(layer "In5.Cu")
		(net "P5E_PEX3_STN0_RX_DN<2>")
	)
	(segment
		(start 415.35731 -122.30354)
		(end 415.64814 -122.59437)
		(width 0.1651)
		(layer "In5.Cu")
		(net "P5E_PEX3_STN0_RX_DN<2>")
	)
	(segment
		(start 446.03543 -269.474696)
		(end 445.867028 -273.153378)
		(width 0.1651)
		(layer "In5.Cu")
		(net "P5E_PEX3_STN0_RX_DN<2>")
	)
	(segment
		(start 436.442612 -168.455086)
		(end 435.736238 -232.139744)
		(width 0.1651)
		(layer "In5.Cu")
		(net "P5E_PEX3_STN0_RX_DN<2>")
	)
	(segment
		(start 422.904158 -126.48184)
		(end 427.948598 -134.04088)
		(width 0.1651)
		(layer "In5.Cu")
		(net "P5E_PEX3_STN0_RX_DN<2>")
	)
	(segment
		(start 427.948598 -134.04088)
		(end 432.243484 -138.329924)
		(width 0.1651)
		(layer "In5.Cu")
		(net "P5E_PEX3_STN0_RX_DN<2>")
	)
	(segment
		(start 432.19624 -286.065722)
		(end 432.15052 -286.020002)
		(width 0.1143)
		(layer "In5.Cu")
		(net "P5E_PEX3_STN0_RX_DN<2>")
	)
	(segment
		(start 433.787804 -286.065722)
		(end 432.224688 -286.065722)
		(width 0.1651)
		(layer "In5.Cu")
		(net "P5E_PEX3_STN0_RX_DN<2>")
	)
	(segment
		(start 428.58436 -286.399732)
		(end 428.84979 -286.399732)
		(width 0.1143)
		(layer "In5.Cu")
		(net "P5E_PEX3_STN0_RX_DN<2>")
	)
	(segment
		(start 416.08248 -344.538554)
		(end 416.08248 -345.171014)
		(width 0.13462)
		(layer "F.Cu")
		(net "P5E_PEX3_STN7_TX_C_DN<114>")
	)
	(segment
		(start 416.08248 -345.171014)
		(end 416.376612 -345.465146)
		(width 0.13462)
		(layer "F.Cu")
		(net "P5E_PEX3_STN7_TX_C_DN<114>")
	)
	(segment
		(start 416.402012 -344.219022)
		(end 416.08248 -344.538554)
		(width 0.13462)
		(layer "F.Cu")
		(net "P5E_PEX3_STN7_TX_C_DN<114>")
	)
	(segment
		(start 413.258 -386.0038)
		(end 412.906972 -383.56921)
		(width 0.1651)
		(layer "In11.Cu")
		(net "P5E_PEX3_STN7_TX_C_DN<114>")
	)
	(segment
		(start 414.531302 -347.881194)
		(end 416.085782 -346.326714)
		(width 0.1651)
		(layer "In11.Cu")
		(net "P5E_PEX3_STN7_TX_C_DN<114>")
	)
	(segment
		(start 425.015914 -400.729196)
		(end 425.015914 -394.764514)
		(width 0.1651)
		(layer "In11.Cu")
		(net "P5E_PEX3_STN7_TX_C_DN<114>")
	)
	(segment
		(start 416.085782 -345.755976)
		(end 416.376612 -345.465146)
		(width 0.1651)
		(layer "In11.Cu")
		(net "P5E_PEX3_STN7_TX_C_DN<114>")
	)
	(segment
		(start 425.015914 -394.764514)
		(end 424.326558 -394.075158)
		(width 0.1651)
		(layer "In11.Cu")
		(net "P5E_PEX3_STN7_TX_C_DN<114>")
	)
	(segment
		(start 423.889932 -401.308062)
		(end 424.016932 -401.181062)
		(width 0.1651)
		(layer "In11.Cu")
		(net "P5E_PEX3_STN7_TX_C_DN<114>")
	)
	(segment
		(start 423.889932 -401.690078)
		(end 423.889932 -401.308062)
		(width 0.1651)
		(layer "In11.Cu")
		(net "P5E_PEX3_STN7_TX_C_DN<114>")
	)
	(segment
		(start 412.906972 -383.56921)
		(end 413.32404 -368.822986)
		(width 0.1651)
		(layer "In11.Cu")
		(net "P5E_PEX3_STN7_TX_C_DN<114>")
	)
	(segment
		(start 424.016932 -401.181062)
		(end 424.564048 -401.181062)
		(width 0.1651)
		(layer "In11.Cu")
		(net "P5E_PEX3_STN7_TX_C_DN<114>")
	)
	(segment
		(start 424.564048 -401.181062)
		(end 425.015914 -400.729196)
		(width 0.1651)
		(layer "In11.Cu")
		(net "P5E_PEX3_STN7_TX_C_DN<114>")
	)
	(segment
		(start 424.326558 -394.075158)
		(end 415.201354 -389.77316)
		(width 0.1651)
		(layer "In11.Cu")
		(net "P5E_PEX3_STN7_TX_C_DN<114>")
	)
	(segment
		(start 413.32404 -368.822986)
		(end 414.531302 -358.842818)
		(width 0.1651)
		(layer "In11.Cu")
		(net "P5E_PEX3_STN7_TX_C_DN<114>")
	)
	(segment
		(start 416.085782 -346.326714)
		(end 416.085782 -345.755976)
		(width 0.1651)
		(layer "In11.Cu")
		(net "P5E_PEX3_STN7_TX_C_DN<114>")
	)
	(segment
		(start 414.531302 -358.842818)
		(end 414.531302 -347.881194)
		(width 0.1651)
		(layer "In11.Cu")
		(net "P5E_PEX3_STN7_TX_C_DN<114>")
	)
	(segment
		(start 415.201354 -389.77316)
		(end 413.258 -386.0038)
		(width 0.1651)
		(layer "In11.Cu")
		(net "P5E_PEX3_STN7_TX_C_DN<114>")
	)
	(segment
		(start 421.557704 -100.039932)
		(end 422.558972 -100.039932)
		(width 0.13208)
		(layer "F.Cu")
		(net "NIC7_CLK")
	)
	(via
		(at 422.558972 -100.039932)
		(size 0.508)
		(drill 0.254)
		(layers "F.Cu" "B.Cu")
		(net "NIC7_CLK")
	)
	(segment
		(start 424.439588 -100.039932)
		(end 422.558972 -100.039932)
		(width 0.13208)
		(layer "B.Cu")
		(net "NIC7_CLK")
	)
	(segment
		(start 425.441872 -99.037648)
		(end 424.439588 -100.039932)
		(width 0.13208)
		(layer "B.Cu")
		(net "NIC7_CLK")
	)
	(segment
		(start 151.002238 -25.940004)
		(end 151.002238 -26.266394)
		(width 0.13208)
		(layer "F.Cu")
		(net "PRSNT_SSD5_N")
	)
	(segment
		(start 152.764998 -25.390094)
		(end 151.552148 -25.390094)
		(width 0.13208)
		(layer "F.Cu")
		(net "PRSNT_SSD5_N")
	)
	(segment
		(start 151.552148 -25.390094)
		(end 151.002238 -25.940004)
		(width 0.13208)
		(layer "F.Cu")
		(net "PRSNT_SSD5_N")
	)
	(segment
		(start 151.002238 -26.266394)
		(end 150.22068 -26.266394)
		(width 0.13208)
		(layer "F.Cu")
		(net "PRSNT_SSD5_N")
	)
	(via
		(at 151.002238 -26.266394)
		(size 0.508)
		(drill 0.254)
		(layers "F.Cu" "B.Cu")
		(net "PRSNT_SSD5_N")
	)
	(segment
		(start 153.005028 -112.809782)
		(end 153.332688 -112.482122)
		(width 0.13462)
		(layer "F.Cu")
		(net "P5E_PEX1_STN1_TX_C_DP<23>")
	)
	(segment
		(start 161.491422 -112.482122)
		(end 161.654236 -112.644936)
		(width 0.13462)
		(layer "F.Cu")
		(net "P5E_PEX1_STN1_TX_C_DP<23>")
	)
	(segment
		(start 161.654236 -112.644936)
		(end 162.14217 -112.644936)
		(width 0.13462)
		(layer "F.Cu")
		(net "P5E_PEX1_STN1_TX_C_DP<23>")
	)
	(segment
		(start 153.332688 -112.482122)
		(end 161.491422 -112.482122)
		(width 0.13462)
		(layer "F.Cu")
		(net "P5E_PEX1_STN1_TX_C_DP<23>")
	)
	(segment
		(start 283.495496 -136.39292)
		(end 283.323284 -136.565132)
		(width 0.13462)
		(layer "F.Cu")
		(net "P5E_PEX2_STN1_RX_DN<31>")
	)
	(segment
		(start 283.323284 -136.565132)
		(end 282.842462 -136.565132)
		(width 0.13462)
		(layer "F.Cu")
		(net "P5E_PEX2_STN1_RX_DN<31>")
	)
	(segment
		(start 284.139132 -136.39292)
		(end 283.495496 -136.39292)
		(width 0.13462)
		(layer "F.Cu")
		(net "P5E_PEX2_STN1_RX_DN<31>")
	)
	(segment
		(start 284.442662 -136.69645)
		(end 284.139132 -136.39292)
		(width 0.13462)
		(layer "F.Cu")
		(net "P5E_PEX2_STN1_RX_DN<31>")
	)
	(segment
		(start 283.369512 -137.66165)
		(end 283.483812 -137.77595)
		(width 0.1651)
		(layer "In5.Cu")
		(net "P5E_PEX2_STN1_RX_DN<31>")
	)
	(segment
		(start 283.4513 -136.846056)
		(end 283.369512 -137.043668)
		(width 0.1651)
		(layer "In5.Cu")
		(net "P5E_PEX2_STN1_RX_DN<31>")
	)
	(segment
		(start 283.05252 -142.36319)
		(end 282.903168 -142.425674)
		(width 0.1651)
		(layer "In5.Cu")
		(net "P5E_PEX2_STN1_RX_DN<31>")
	)
	(segment
		(start 280.528522 -146.087846)
		(end 280.366978 -146.08683)
		(width 0.1651)
		(layer "In5.Cu")
		(net "P5E_PEX2_STN1_RX_DN<31>")
	)
	(segment
		(start 283.483812 -139.57935)
		(end 283.483812 -140.07465)
		(width 0.1651)
		(layer "In5.Cu")
		(net "P5E_PEX2_STN1_RX_DN<31>")
	)
	(segment
		(start 305.985164 -275.379688)
		(end 306.099464 -275.265388)
		(width 0.1143)
		(layer "In5.Cu")
		(net "P5E_PEX2_STN1_RX_DN<31>")
	)
	(segment
		(start 283.891736 -136.40562)
		(end 283.4513 -136.846056)
		(width 0.1651)
		(layer "In5.Cu")
		(net "P5E_PEX2_STN1_RX_DN<31>")
	)
	(segment
		(start 282.441396 -143.554196)
		(end 282.1051 -144.37614)
		(width 0.1651)
		(layer "In5.Cu")
		(net "P5E_PEX2_STN1_RX_DN<31>")
	)
	(segment
		(start 305.765708 -271.599406)
		(end 305.719988 -271.645126)
		(width 0.1143)
		(layer "In5.Cu")
		(net "P5E_PEX2_STN1_RX_DN<31>")
	)
	(segment
		(start 278.18207 -151.219916)
		(end 278.141684 -151.713946)
		(width 0.1651)
		(layer "In5.Cu")
		(net "P5E_PEX2_STN1_RX_DN<31>")
	)
	(segment
		(start 278.01824 -151.818594)
		(end 277.978108 -152.312116)
		(width 0.1651)
		(layer "In5.Cu")
		(net "P5E_PEX2_STN1_RX_DN<31>")
	)
	(segment
		(start 283.369512 -137.043668)
		(end 283.369512 -137.66165)
		(width 0.1651)
		(layer "In5.Cu")
		(net "P5E_PEX2_STN1_RX_DN<31>")
	)
	(segment
		(start 283.483812 -138.27125)
		(end 283.369512 -138.38555)
		(width 0.1651)
		(layer "In5.Cu")
		(net "P5E_PEX2_STN1_RX_DN<31>")
	)
	(segment
		(start 305.765708 -271.570958)
		(end 305.765708 -271.599406)
		(width 0.1143)
		(layer "In5.Cu")
		(net "P5E_PEX2_STN1_RX_DN<31>")
	)
	(segment
		(start 278.141684 -151.713946)
		(end 278.01824 -151.818594)
		(width 0.1651)
		(layer "In5.Cu")
		(net "P5E_PEX2_STN1_RX_DN<31>")
	)
	(segment
		(start 283.483812 -140.07465)
		(end 283.369512 -140.18895)
		(width 0.1651)
		(layer "In5.Cu")
		(net "P5E_PEX2_STN1_RX_DN<31>")
	)
	(segment
		(start 281.75077 -144.885156)
		(end 281.39771 -145.232628)
		(width 0.1651)
		(layer "In5.Cu")
		(net "P5E_PEX2_STN1_RX_DN<31>")
	)
	(segment
		(start 277.432516 -160.37052)
		(end 305.69789 -266.542774)
		(width 0.1651)
		(layer "In5.Cu")
		(net "P5E_PEX2_STN1_RX_DN<31>")
	)
	(segment
		(start 278.73071 -147.32)
		(end 278.3078 -148.271484)
		(width 0.1651)
		(layer "In5.Cu")
		(net "P5E_PEX2_STN1_RX_DN<31>")
	)
	(segment
		(start 283.177488 -141.755368)
		(end 283.239972 -141.904466)
		(width 0.1651)
		(layer "In5.Cu")
		(net "P5E_PEX2_STN1_RX_DN<31>")
	)
	(segment
		(start 281.752294 -144.723358)
		(end 281.75077 -144.885156)
		(width 0.1651)
		(layer "In5.Cu")
		(net "P5E_PEX2_STN1_RX_DN<31>")
	)
	(segment
		(start 277.918926 -153.033984)
		(end 277.3934 -159.47898)
		(width 0.1651)
		(layer "In5.Cu")
		(net "P5E_PEX2_STN1_RX_DN<31>")
	)
	(segment
		(start 284.442662 -136.69645)
		(end 284.151832 -136.40562)
		(width 0.1651)
		(layer "In5.Cu")
		(net "P5E_PEX2_STN1_RX_DN<31>")
	)
	(segment
		(start 282.1051 -144.37614)
		(end 281.752294 -144.723358)
		(width 0.1651)
		(layer "In5.Cu")
		(net "P5E_PEX2_STN1_RX_DN<31>")
	)
	(segment
		(start 282.590748 -143.491712)
		(end 282.441396 -143.554196)
		(width 0.1651)
		(layer "In5.Cu")
		(net "P5E_PEX2_STN1_RX_DN<31>")
	)
	(segment
		(start 283.369512 -138.38555)
		(end 283.369512 -139.46505)
		(width 0.1651)
		(layer "In5.Cu")
		(net "P5E_PEX2_STN1_RX_DN<31>")
	)
	(segment
		(start 278.082756 -152.435306)
		(end 278.04237 -152.929336)
		(width 0.1651)
		(layer "In5.Cu")
		(net "P5E_PEX2_STN1_RX_DN<31>")
	)
	(segment
		(start 305.719988 -271.645126)
		(end 305.719988 -275.27631)
		(width 0.1143)
		(layer "In5.Cu")
		(net "P5E_PEX2_STN1_RX_DN<31>")
	)
	(segment
		(start 306.099464 -275.265388)
		(end 306.099464 -274.999958)
		(width 0.1143)
		(layer "In5.Cu")
		(net "P5E_PEX2_STN1_RX_DN<31>")
	)
	(segment
		(start 280.366978 -146.08683)
		(end 279.621996 -146.819874)
		(width 0.1651)
		(layer "In5.Cu")
		(net "P5E_PEX2_STN1_RX_DN<31>")
	)
	(segment
		(start 277.3934 -159.47898)
		(end 277.432516 -160.37052)
		(width 0.1651)
		(layer "In5.Cu")
		(net "P5E_PEX2_STN1_RX_DN<31>")
	)
	(segment
		(start 280.881582 -145.740374)
		(end 280.528522 -146.087846)
		(width 0.1651)
		(layer "In5.Cu")
		(net "P5E_PEX2_STN1_RX_DN<31>")
	)
	(segment
		(start 278.96566 -147.088606)
		(end 278.73071 -147.32)
		(width 0.1651)
		(layer "In5.Cu")
		(net "P5E_PEX2_STN1_RX_DN<31>")
	)
	(segment
		(start 277.978108 -152.312116)
		(end 278.082756 -152.435306)
		(width 0.1651)
		(layer "In5.Cu")
		(net "P5E_PEX2_STN1_RX_DN<31>")
	)
	(segment
		(start 283.369512 -139.46505)
		(end 283.483812 -139.57935)
		(width 0.1651)
		(layer "In5.Cu")
		(net "P5E_PEX2_STN1_RX_DN<31>")
	)
	(segment
		(start 283.369512 -140.18895)
		(end 283.369512 -141.285976)
		(width 0.1651)
		(layer "In5.Cu")
		(net "P5E_PEX2_STN1_RX_DN<31>")
	)
	(segment
		(start 280.883106 -145.578576)
		(end 280.881582 -145.740374)
		(width 0.1651)
		(layer "In5.Cu")
		(net "P5E_PEX2_STN1_RX_DN<31>")
	)
	(segment
		(start 282.903168 -142.425674)
		(end 282.715716 -142.88389)
		(width 0.1651)
		(layer "In5.Cu")
		(net "P5E_PEX2_STN1_RX_DN<31>")
	)
	(segment
		(start 282.715716 -142.88389)
		(end 282.7782 -143.032988)
		(width 0.1651)
		(layer "In5.Cu")
		(net "P5E_PEX2_STN1_RX_DN<31>")
	)
	(segment
		(start 281.235912 -145.231358)
		(end 280.883106 -145.578576)
		(width 0.1651)
		(layer "In5.Cu")
		(net "P5E_PEX2_STN1_RX_DN<31>")
	)
	(segment
		(start 283.239972 -141.904466)
		(end 283.05252 -142.36319)
		(width 0.1651)
		(layer "In5.Cu")
		(net "P5E_PEX2_STN1_RX_DN<31>")
	)
	(segment
		(start 305.69789 -266.542774)
		(end 305.765708 -267.061188)
		(width 0.1651)
		(layer "In5.Cu")
		(net "P5E_PEX2_STN1_RX_DN<31>")
	)
	(segment
		(start 283.483812 -137.77595)
		(end 283.483812 -138.27125)
		(width 0.1651)
		(layer "In5.Cu")
		(net "P5E_PEX2_STN1_RX_DN<31>")
	)
	(segment
		(start 278.3078 -148.271484)
		(end 278.077422 -151.096726)
		(width 0.1651)
		(layer "In5.Cu")
		(net "P5E_PEX2_STN1_RX_DN<31>")
	)
	(segment
		(start 305.823366 -275.379688)
		(end 305.985164 -275.379688)
		(width 0.1143)
		(layer "In5.Cu")
		(net "P5E_PEX2_STN1_RX_DN<31>")
	)
	(segment
		(start 282.7782 -143.032988)
		(end 282.590748 -143.491712)
		(width 0.1651)
		(layer "In5.Cu")
		(net "P5E_PEX2_STN1_RX_DN<31>")
	)
	(segment
		(start 305.719988 -275.27631)
		(end 305.823366 -275.379688)
		(width 0.1143)
		(layer "In5.Cu")
		(net "P5E_PEX2_STN1_RX_DN<31>")
	)
	(segment
		(start 305.765708 -267.061188)
		(end 305.765708 -271.570958)
		(width 0.1651)
		(layer "In5.Cu")
		(net "P5E_PEX2_STN1_RX_DN<31>")
	)
	(segment
		(start 283.369512 -141.285976)
		(end 283.177488 -141.755368)
		(width 0.1651)
		(layer "In5.Cu")
		(net "P5E_PEX2_STN1_RX_DN<31>")
	)
	(segment
		(start 284.151832 -136.40562)
		(end 283.891736 -136.40562)
		(width 0.1651)
		(layer "In5.Cu")
		(net "P5E_PEX2_STN1_RX_DN<31>")
	)
	(segment
		(start 278.077422 -151.096726)
		(end 278.18207 -151.219916)
		(width 0.1651)
		(layer "In5.Cu")
		(net "P5E_PEX2_STN1_RX_DN<31>")
	)
	(segment
		(start 278.04237 -152.929336)
		(end 277.918926 -153.033984)
		(width 0.1651)
		(layer "In5.Cu")
		(net "P5E_PEX2_STN1_RX_DN<31>")
	)
	(segment
		(start 281.39771 -145.232628)
		(end 281.235912 -145.231358)
		(width 0.1651)
		(layer "In5.Cu")
		(net "P5E_PEX2_STN1_RX_DN<31>")
	)
	(segment
		(start 279.621996 -146.819874)
		(end 278.96566 -147.088606)
		(width 0.1651)
		(layer "In5.Cu")
		(net "P5E_PEX2_STN1_RX_DN<31>")
	)
	(segment
		(start 322.124324 -356.831646)
		(end 322.124324 -357.46309)
		(width 0.13462)
		(layer "F.Cu")
		(net "P5E_PEX2_STN5_TX_C_DP<85>")
	)
	(segment
		(start 321.804284 -356.511606)
		(end 322.124324 -356.831646)
		(width 0.13462)
		(layer "F.Cu")
		(net "P5E_PEX2_STN5_TX_C_DP<85>")
	)
	(segment
		(start 322.124324 -357.46309)
		(end 321.829684 -357.75773)
		(width 0.13462)
		(layer "F.Cu")
		(net "P5E_PEX2_STN5_TX_C_DP<85>")
	)
	(segment
		(start 343.334086 -395.530324)
		(end 343.334086 -405.612346)
		(width 0.1651)
		(layer "In7.Cu")
		(net "P5E_PEX2_STN5_TX_C_DP<85>")
	)
	(segment
		(start 337.38693 -390.990836)
		(end 340.190582 -392.853164)
		(width 0.1651)
		(layer "In7.Cu")
		(net "P5E_PEX2_STN5_TX_C_DP<85>")
	)
	(segment
		(start 341.724742 -393.872466)
		(end 342.624664 -394.470128)
		(width 0.1651)
		(layer "In7.Cu")
		(net "P5E_PEX2_STN5_TX_C_DP<85>")
	)
	(segment
		(start 322.120514 -358.04856)
		(end 322.120514 -358.88676)
		(width 0.1651)
		(layer "In7.Cu")
		(net "P5E_PEX2_STN5_TX_C_DP<85>")
	)
	(segment
		(start 342.490044 -405.772112)
		(end 342.490044 -405.390096)
		(width 0.1651)
		(layer "In7.Cu")
		(net "P5E_PEX2_STN5_TX_C_DP<85>")
	)
	(segment
		(start 328.266552 -384.874008)
		(end 328.963782 -386.558028)
		(width 0.1651)
		(layer "In7.Cu")
		(net "P5E_PEX2_STN5_TX_C_DP<85>")
	)
	(segment
		(start 342.617044 -405.899112)
		(end 342.490044 -405.772112)
		(width 0.1651)
		(layer "In7.Cu")
		(net "P5E_PEX2_STN5_TX_C_DP<85>")
	)
	(segment
		(start 342.624664 -394.470128)
		(end 343.334086 -395.530324)
		(width 0.1651)
		(layer "In7.Cu")
		(net "P5E_PEX2_STN5_TX_C_DP<85>")
	)
	(segment
		(start 322.120514 -358.88676)
		(end 328.266552 -384.874008)
		(width 0.1651)
		(layer "In7.Cu")
		(net "P5E_PEX2_STN5_TX_C_DP<85>")
	)
	(segment
		(start 340.628224 -393.250674)
		(end 340.751414 -393.226036)
		(width 0.1651)
		(layer "In7.Cu")
		(net "P5E_PEX2_STN5_TX_C_DP<85>")
	)
	(segment
		(start 328.963782 -386.558028)
		(end 330.546964 -388.149338)
		(width 0.1651)
		(layer "In7.Cu")
		(net "P5E_PEX2_STN5_TX_C_DP<85>")
	)
	(segment
		(start 340.190582 -392.853164)
		(end 340.215474 -392.976354)
		(width 0.1651)
		(layer "In7.Cu")
		(net "P5E_PEX2_STN5_TX_C_DP<85>")
	)
	(segment
		(start 343.334086 -405.612346)
		(end 343.04732 -405.899112)
		(width 0.1651)
		(layer "In7.Cu")
		(net "P5E_PEX2_STN5_TX_C_DP<85>")
	)
	(segment
		(start 341.188802 -393.623038)
		(end 341.601552 -393.897358)
		(width 0.1651)
		(layer "In7.Cu")
		(net "P5E_PEX2_STN5_TX_C_DP<85>")
	)
	(segment
		(start 343.04732 -405.899112)
		(end 342.617044 -405.899112)
		(width 0.1651)
		(layer "In7.Cu")
		(net "P5E_PEX2_STN5_TX_C_DP<85>")
	)
	(segment
		(start 321.829684 -357.75773)
		(end 322.120514 -358.04856)
		(width 0.1651)
		(layer "In7.Cu")
		(net "P5E_PEX2_STN5_TX_C_DP<85>")
	)
	(segment
		(start 340.215474 -392.976354)
		(end 340.628224 -393.250674)
		(width 0.1651)
		(layer "In7.Cu")
		(net "P5E_PEX2_STN5_TX_C_DP<85>")
	)
	(segment
		(start 340.751414 -393.226036)
		(end 341.16391 -393.499848)
		(width 0.1651)
		(layer "In7.Cu")
		(net "P5E_PEX2_STN5_TX_C_DP<85>")
	)
	(segment
		(start 341.16391 -393.499848)
		(end 341.188802 -393.623038)
		(width 0.1651)
		(layer "In7.Cu")
		(net "P5E_PEX2_STN5_TX_C_DP<85>")
	)
	(segment
		(start 341.601552 -393.897358)
		(end 341.724742 -393.872466)
		(width 0.1651)
		(layer "In7.Cu")
		(net "P5E_PEX2_STN5_TX_C_DP<85>")
	)
	(segment
		(start 330.546964 -388.149338)
		(end 337.38693 -390.990836)
		(width 0.1651)
		(layer "In7.Cu")
		(net "P5E_PEX2_STN5_TX_C_DP<85>")
	)
	(segment
		(start 430.387252 -124.68352)
		(end 422.211754 -124.68352)
		(width 0.13462)
		(layer "F.Cu")
		(net "P5E_PEX3_STN0_TX_C_DP<3>")
	)
	(segment
		(start 430.694846 -124.991114)
		(end 430.387252 -124.68352)
		(width 0.13462)
		(layer "F.Cu")
		(net "P5E_PEX3_STN0_TX_C_DP<3>")
	)
	(segment
		(start 422.211754 -124.68352)
		(end 422.06037 -124.834904)
		(width 0.13462)
		(layer "F.Cu")
		(net "P5E_PEX3_STN0_TX_C_DP<3>")
	)
	(segment
		(start 422.06037 -124.834904)
		(end 421.557704 -124.834904)
		(width 0.13462)
		(layer "F.Cu")
		(net "P5E_PEX3_STN0_TX_C_DP<3>")
	)
	(segment
		(start 375.338594 -316.148466)
		(end 375.196608 -316.169548)
		(width 0.1651)
		(layer "In9.Cu")
		(net "P5E_PEX3_STN7_RX_DN<119>")
	)
	(segment
		(start 382.46431 -308.10073)
		(end 381.000762 -309.564278)
		(width 0.1651)
		(layer "In9.Cu")
		(net "P5E_PEX3_STN7_RX_DN<119>")
	)
	(segment
		(start 420.749222 -342.04148)
		(end 420.749222 -358.245664)
		(width 0.1651)
		(layer "In9.Cu")
		(net "P5E_PEX3_STN7_RX_DN<119>")
	)
	(segment
		(start 372.82374 -320.127376)
		(end 372.82374 -322.257928)
		(width 0.1651)
		(layer "In9.Cu")
		(net "P5E_PEX3_STN7_RX_DN<119>")
	)
	(segment
		(start 418.59073 -385.230116)
		(end 420.341552 -386.657596)
		(width 0.1651)
		(layer "In9.Cu")
		(net "P5E_PEX3_STN7_RX_DN<119>")
	)
	(segment
		(start 418.12337 -384.534918)
		(end 418.59073 -385.230116)
		(width 0.1651)
		(layer "In9.Cu")
		(net "P5E_PEX3_STN7_RX_DN<119>")
	)
	(segment
		(start 385.534154 -308.153816)
		(end 385.534154 -308.002432)
		(width 0.1143)
		(layer "In9.Cu")
		(net "P5E_PEX3_STN7_RX_DN<119>")
	)
	(segment
		(start 379.805946 -310.902858)
		(end 379.662182 -310.902858)
		(width 0.1651)
		(layer "In9.Cu")
		(net "P5E_PEX3_STN7_RX_DN<119>")
	)
	(segment
		(start 374.627394 -317.107316)
		(end 374.485408 -317.128398)
		(width 0.1651)
		(layer "In9.Cu")
		(net "P5E_PEX3_STN7_RX_DN<119>")
	)
	(segment
		(start 378.198634 -327.775316)
		(end 400.830542 -332.968092)
		(width 0.1651)
		(layer "In9.Cu")
		(net "P5E_PEX3_STN7_RX_DN<119>")
	)
	(segment
		(start 420.341552 -386.657596)
		(end 426.936662 -389.004302)
		(width 0.1651)
		(layer "In9.Cu")
		(net "P5E_PEX3_STN7_RX_DN<119>")
	)
	(segment
		(start 375.633996 -315.750194)
		(end 375.338594 -316.148466)
		(width 0.1651)
		(layer "In9.Cu")
		(net "P5E_PEX3_STN7_RX_DN<119>")
	)
	(segment
		(start 400.830542 -332.968092)
		(end 418.055298 -340.498176)
		(width 0.1651)
		(layer "In9.Cu")
		(net "P5E_PEX3_STN7_RX_DN<119>")
	)
	(segment
		(start 435.01691 -410.080968)
		(end 434.88991 -410.207968)
		(width 0.1651)
		(layer "In9.Cu")
		(net "P5E_PEX3_STN7_RX_DN<119>")
	)
	(segment
		(start 436.04688 -409.389834)
		(end 435.355746 -410.080968)
		(width 0.1651)
		(layer "In9.Cu")
		(net "P5E_PEX3_STN7_RX_DN<119>")
	)
	(segment
		(start 378.817886 -311.747154)
		(end 377.49607 -313.06897)
		(width 0.1651)
		(layer "In9.Cu")
		(net "P5E_PEX3_STN7_RX_DN<119>")
	)
	(segment
		(start 420.749222 -358.245664)
		(end 418.36721 -370.269262)
		(width 0.1651)
		(layer "In9.Cu")
		(net "P5E_PEX3_STN7_RX_DN<119>")
	)
	(segment
		(start 376.619008 -314.25134)
		(end 376.324114 -314.649104)
		(width 0.1651)
		(layer "In9.Cu")
		(net "P5E_PEX3_STN7_RX_DN<119>")
	)
	(segment
		(start 418.36721 -370.269262)
		(end 417.870894 -383.647442)
		(width 0.1651)
		(layer "In9.Cu")
		(net "P5E_PEX3_STN7_RX_DN<119>")
	)
	(segment
		(start 436.04688 -395.994128)
		(end 436.04688 -409.389834)
		(width 0.1651)
		(layer "In9.Cu")
		(net "P5E_PEX3_STN7_RX_DN<119>")
	)
	(segment
		(start 426.936662 -389.004302)
		(end 434.0733 -393.51331)
		(width 0.1651)
		(layer "In9.Cu")
		(net "P5E_PEX3_STN7_RX_DN<119>")
	)
	(segment
		(start 435.355746 -410.080968)
		(end 435.01691 -410.080968)
		(width 0.1651)
		(layer "In9.Cu")
		(net "P5E_PEX3_STN7_RX_DN<119>")
	)
	(segment
		(start 381.000762 -309.564278)
		(end 381.000762 -309.708042)
		(width 0.1651)
		(layer "In9.Cu")
		(net "P5E_PEX3_STN7_RX_DN<119>")
	)
	(segment
		(start 380.156466 -310.408574)
		(end 380.156466 -310.552338)
		(width 0.1651)
		(layer "In9.Cu")
		(net "P5E_PEX3_STN7_RX_DN<119>")
	)
	(segment
		(start 434.88991 -410.207968)
		(end 434.88991 -410.589984)
		(width 0.1651)
		(layer "In9.Cu")
		(net "P5E_PEX3_STN7_RX_DN<119>")
	)
	(segment
		(start 385.438142 -308.249828)
		(end 385.534154 -308.153816)
		(width 0.1143)
		(layer "In9.Cu")
		(net "P5E_PEX3_STN7_RX_DN<119>")
	)
	(segment
		(start 378.96165 -311.747154)
		(end 378.817886 -311.747154)
		(width 0.1651)
		(layer "In9.Cu")
		(net "P5E_PEX3_STN7_RX_DN<119>")
	)
	(segment
		(start 420.1922 -341.243158)
		(end 420.749222 -342.04148)
		(width 0.1651)
		(layer "In9.Cu")
		(net "P5E_PEX3_STN7_RX_DN<119>")
	)
	(segment
		(start 374.901714 -316.567312)
		(end 374.922796 -316.709298)
		(width 0.1651)
		(layer "In9.Cu")
		(net "P5E_PEX3_STN7_RX_DN<119>")
	)
	(segment
		(start 435.703472 -395.143482)
		(end 436.04688 -395.994128)
		(width 0.1651)
		(layer "In9.Cu")
		(net "P5E_PEX3_STN7_RX_DN<119>")
	)
	(segment
		(start 385.149852 -308.249828)
		(end 385.438142 -308.249828)
		(width 0.1143)
		(layer "In9.Cu")
		(net "P5E_PEX3_STN7_RX_DN<119>")
	)
	(segment
		(start 380.156466 -310.552338)
		(end 379.805946 -310.902858)
		(width 0.1651)
		(layer "In9.Cu")
		(net "P5E_PEX3_STN7_RX_DN<119>")
	)
	(segment
		(start 383.921 -307.915818)
		(end 383.892552 -307.915818)
		(width 0.1143)
		(layer "In9.Cu")
		(net "P5E_PEX3_STN7_RX_DN<119>")
	)
	(segment
		(start 417.870894 -383.647442)
		(end 418.12337 -384.534918)
		(width 0.1651)
		(layer "In9.Cu")
		(net "P5E_PEX3_STN7_RX_DN<119>")
	)
	(segment
		(start 375.196608 -316.169548)
		(end 374.901714 -316.567312)
		(width 0.1651)
		(layer "In9.Cu")
		(net "P5E_PEX3_STN7_RX_DN<119>")
	)
	(segment
		(start 377.040648 -327.410826)
		(end 378.198634 -327.775316)
		(width 0.1651)
		(layer "In9.Cu")
		(net "P5E_PEX3_STN7_RX_DN<119>")
	)
	(segment
		(start 376.049794 -315.189362)
		(end 375.907808 -315.210444)
		(width 0.1651)
		(layer "In9.Cu")
		(net "P5E_PEX3_STN7_RX_DN<119>")
	)
	(segment
		(start 385.40182 -307.870098)
		(end 383.96672 -307.870098)
		(width 0.1143)
		(layer "In9.Cu")
		(net "P5E_PEX3_STN7_RX_DN<119>")
	)
	(segment
		(start 381.000762 -309.708042)
		(end 380.650242 -310.058562)
		(width 0.1651)
		(layer "In9.Cu")
		(net "P5E_PEX3_STN7_RX_DN<119>")
	)
	(segment
		(start 385.534154 -308.002432)
		(end 385.40182 -307.870098)
		(width 0.1143)
		(layer "In9.Cu")
		(net "P5E_PEX3_STN7_RX_DN<119>")
	)
	(segment
		(start 383.892552 -307.915818)
		(end 382.910588 -307.915818)
		(width 0.1651)
		(layer "In9.Cu")
		(net "P5E_PEX3_STN7_RX_DN<119>")
	)
	(segment
		(start 383.96672 -307.870098)
		(end 383.921 -307.915818)
		(width 0.1143)
		(layer "In9.Cu")
		(net "P5E_PEX3_STN7_RX_DN<119>")
	)
	(segment
		(start 434.0733 -393.51331)
		(end 435.703472 -395.143482)
		(width 0.1651)
		(layer "In9.Cu")
		(net "P5E_PEX3_STN7_RX_DN<119>")
	)
	(segment
		(start 379.662182 -310.902858)
		(end 379.31217 -311.25287)
		(width 0.1651)
		(layer "In9.Cu")
		(net "P5E_PEX3_STN7_RX_DN<119>")
	)
	(segment
		(start 379.31217 -311.396634)
		(end 378.96165 -311.747154)
		(width 0.1651)
		(layer "In9.Cu")
		(net "P5E_PEX3_STN7_RX_DN<119>")
	)
	(segment
		(start 373.532908 -318.412368)
		(end 372.82374 -320.127376)
		(width 0.1651)
		(layer "In9.Cu")
		(net "P5E_PEX3_STN7_RX_DN<119>")
	)
	(segment
		(start 375.612914 -315.608208)
		(end 375.633996 -315.750194)
		(width 0.1651)
		(layer "In9.Cu")
		(net "P5E_PEX3_STN7_RX_DN<119>")
	)
	(segment
		(start 382.910588 -307.915818)
		(end 382.46431 -308.10073)
		(width 0.1651)
		(layer "In9.Cu")
		(net "P5E_PEX3_STN7_RX_DN<119>")
	)
	(segment
		(start 374.922796 -316.709298)
		(end 374.627394 -317.107316)
		(width 0.1651)
		(layer "In9.Cu")
		(net "P5E_PEX3_STN7_RX_DN<119>")
	)
	(segment
		(start 374.485408 -317.128398)
		(end 373.532908 -318.412368)
		(width 0.1651)
		(layer "In9.Cu")
		(net "P5E_PEX3_STN7_RX_DN<119>")
	)
	(segment
		(start 380.650242 -310.058562)
		(end 380.506478 -310.058562)
		(width 0.1651)
		(layer "In9.Cu")
		(net "P5E_PEX3_STN7_RX_DN<119>")
	)
	(segment
		(start 376.324114 -314.649104)
		(end 376.345196 -314.79109)
		(width 0.1651)
		(layer "In9.Cu")
		(net "P5E_PEX3_STN7_RX_DN<119>")
	)
	(segment
		(start 373.485918 -323.858128)
		(end 377.040648 -327.410826)
		(width 0.1651)
		(layer "In9.Cu")
		(net "P5E_PEX3_STN7_RX_DN<119>")
	)
	(segment
		(start 377.05665 -313.83224)
		(end 376.761248 -314.230258)
		(width 0.1651)
		(layer "In9.Cu")
		(net "P5E_PEX3_STN7_RX_DN<119>")
	)
	(segment
		(start 376.345196 -314.79109)
		(end 376.049794 -315.189362)
		(width 0.1651)
		(layer "In9.Cu")
		(net "P5E_PEX3_STN7_RX_DN<119>")
	)
	(segment
		(start 380.506478 -310.058562)
		(end 380.156466 -310.408574)
		(width 0.1651)
		(layer "In9.Cu")
		(net "P5E_PEX3_STN7_RX_DN<119>")
	)
	(segment
		(start 377.035568 -313.69)
		(end 377.05665 -313.83224)
		(width 0.1651)
		(layer "In9.Cu")
		(net "P5E_PEX3_STN7_RX_DN<119>")
	)
	(segment
		(start 418.055298 -340.498176)
		(end 420.1922 -341.243158)
		(width 0.1651)
		(layer "In9.Cu")
		(net "P5E_PEX3_STN7_RX_DN<119>")
	)
	(segment
		(start 376.761248 -314.230258)
		(end 376.619008 -314.25134)
		(width 0.1651)
		(layer "In9.Cu")
		(net "P5E_PEX3_STN7_RX_DN<119>")
	)
	(segment
		(start 372.82374 -322.257928)
		(end 373.485918 -323.858128)
		(width 0.1651)
		(layer "In9.Cu")
		(net "P5E_PEX3_STN7_RX_DN<119>")
	)
	(segment
		(start 375.907808 -315.210444)
		(end 375.612914 -315.608208)
		(width 0.1651)
		(layer "In9.Cu")
		(net "P5E_PEX3_STN7_RX_DN<119>")
	)
	(segment
		(start 377.49607 -313.06897)
		(end 377.035568 -313.69)
		(width 0.1651)
		(layer "In9.Cu")
		(net "P5E_PEX3_STN7_RX_DN<119>")
	)
	(segment
		(start 379.31217 -311.25287)
		(end 379.31217 -311.396634)
		(width 0.1651)
		(layer "In9.Cu")
		(net "P5E_PEX3_STN7_RX_DN<119>")
	)
	(segment
		(start 421.557704 -99.439984)
		(end 423.99204 -99.439984)
		(width 0.13208)
		(layer "F.Cu")
		(net "NIC7_DATA_OUT")
	)
	(via
		(at 423.99204 -99.439984)
		(size 0.508)
		(drill 0.254)
		(layers "F.Cu" "B.Cu")
		(net "NIC7_DATA_OUT")
	)
	(segment
		(start 425.441872 -98.021648)
		(end 424.023536 -99.439984)
		(width 0.13208)
		(layer "B.Cu")
		(net "NIC7_DATA_OUT")
	)
	(segment
		(start 424.023536 -99.439984)
		(end 423.99204 -99.439984)
		(width 0.13208)
		(layer "B.Cu")
		(net "NIC7_DATA_OUT")
	)
	(segment
		(start 125.00229 -25.940004)
		(end 125.00229 -26.266394)
		(width 0.13208)
		(layer "F.Cu")
		(net "PRSNT_SSD4_N")
	)
	(segment
		(start 126.76505 -25.390094)
		(end 125.5522 -25.390094)
		(width 0.13208)
		(layer "F.Cu")
		(net "PRSNT_SSD4_N")
	)
	(segment
		(start 124.220732 -26.266394)
		(end 125.00229 -26.266394)
		(width 0.13208)
		(layer "F.Cu")
		(net "PRSNT_SSD4_N")
	)
	(segment
		(start 125.5522 -25.390094)
		(end 125.00229 -25.940004)
		(width 0.13208)
		(layer "F.Cu")
		(net "PRSNT_SSD4_N")
	)
	(via
		(at 125.00229 -26.266394)
		(size 0.508)
		(drill 0.254)
		(layers "F.Cu" "B.Cu")
		(net "PRSNT_SSD4_N")
	)
	(segment
		(start 161.654236 -105.445052)
		(end 162.14217 -105.445052)
		(width 0.13462)
		(layer "F.Cu")
		(net "P5E_PEX1_STN1_TX_C_DP<19>")
	)
	(segment
		(start 161.491422 -105.282238)
		(end 161.654236 -105.445052)
		(width 0.13462)
		(layer "F.Cu")
		(net "P5E_PEX1_STN1_TX_C_DP<19>")
	)
	(segment
		(start 153.332688 -105.282238)
		(end 161.491422 -105.282238)
		(width 0.13462)
		(layer "F.Cu")
		(net "P5E_PEX1_STN1_TX_C_DP<19>")
	)
	(segment
		(start 153.005028 -105.609898)
		(end 153.332688 -105.282238)
		(width 0.13462)
		(layer "F.Cu")
		(net "P5E_PEX1_STN1_TX_C_DP<19>")
	)
	(segment
		(start 285.988252 -130.9878)
		(end 283.497274 -130.9878)
		(width 0.13462)
		(layer "F.Cu")
		(net "P5E_PEX2_STN1_RX_DN<28>")
	)
	(segment
		(start 283.319982 -131.165092)
		(end 282.842462 -131.165092)
		(width 0.13462)
		(layer "F.Cu")
		(net "P5E_PEX2_STN1_RX_DN<28>")
	)
	(segment
		(start 283.497274 -130.9878)
		(end 283.319982 -131.165092)
		(width 0.13462)
		(layer "F.Cu")
		(net "P5E_PEX2_STN1_RX_DN<28>")
	)
	(segment
		(start 286.296862 -131.29641)
		(end 285.988252 -130.9878)
		(width 0.13462)
		(layer "F.Cu")
		(net "P5E_PEX2_STN1_RX_DN<28>")
	)
	(segment
		(start 273.838416 -156.892244)
		(end 274.59178 -161.14268)
		(width 0.1651)
		(layer "In5.Cu")
		(net "P5E_PEX2_STN1_RX_DN<28>")
	)
	(segment
		(start 284.86735 -131.11988)
		(end 284.75305 -131.00558)
		(width 0.1651)
		(layer "In5.Cu")
		(net "P5E_PEX2_STN1_RX_DN<28>")
	)
	(segment
		(start 281.046682 -134.450074)
		(end 280.857198 -134.907528)
		(width 0.1651)
		(layer "In5.Cu")
		(net "P5E_PEX2_STN1_RX_DN<28>")
	)
	(segment
		(start 274.790662 -145.218658)
		(end 274.814538 -145.378424)
		(width 0.1651)
		(layer "In5.Cu")
		(net "P5E_PEX2_STN1_RX_DN<28>")
	)
	(segment
		(start 274.814538 -145.378424)
		(end 274.51939 -145.776696)
		(width 0.1651)
		(layer "In5.Cu")
		(net "P5E_PEX2_STN1_RX_DN<28>")
	)
	(segment
		(start 274.359624 -145.800572)
		(end 273.412204 -147.079716)
		(width 0.1651)
		(layer "In5.Cu")
		(net "P5E_PEX2_STN1_RX_DN<28>")
	)
	(segment
		(start 277.185628 -143.055848)
		(end 277.154132 -143.214344)
		(width 0.1651)
		(layer "In5.Cu")
		(net "P5E_PEX2_STN1_RX_DN<28>")
	)
	(segment
		(start 280.919174 -135.05688)
		(end 280.72969 -135.514842)
		(width 0.1651)
		(layer "In5.Cu")
		(net "P5E_PEX2_STN1_RX_DN<28>")
	)
	(segment
		(start 302.915828 -267.605256)
		(end 302.915828 -271.526)
		(width 0.1651)
		(layer "In5.Cu")
		(net "P5E_PEX2_STN1_RX_DN<28>")
	)
	(segment
		(start 282.029662 -132.874512)
		(end 281.86888 -132.890514)
		(width 0.1651)
		(layer "In5.Cu")
		(net "P5E_PEX2_STN1_RX_DN<28>")
	)
	(segment
		(start 282.328366 -132.330698)
		(end 282.344368 -132.49148)
		(width 0.1651)
		(layer "In5.Cu")
		(net "P5E_PEX2_STN1_RX_DN<28>")
	)
	(segment
		(start 280.857198 -134.907528)
		(end 280.919174 -135.05688)
		(width 0.1651)
		(layer "In5.Cu")
		(net "P5E_PEX2_STN1_RX_DN<28>")
	)
	(segment
		(start 281.385772 -133.93039)
		(end 281.196288 -134.388352)
		(width 0.1651)
		(layer "In5.Cu")
		(net "P5E_PEX2_STN1_RX_DN<28>")
	)
	(segment
		(start 281.196288 -134.388352)
		(end 281.046682 -134.450074)
		(width 0.1651)
		(layer "In5.Cu")
		(net "P5E_PEX2_STN1_RX_DN<28>")
	)
	(segment
		(start 283.416248 -131.00558)
		(end 283.10205 -131.388358)
		(width 0.1651)
		(layer "In5.Cu")
		(net "P5E_PEX2_STN1_RX_DN<28>")
	)
	(segment
		(start 280.196544 -136.502648)
		(end 280.196544 -140.348462)
		(width 0.1651)
		(layer "In5.Cu")
		(net "P5E_PEX2_STN1_RX_DN<28>")
	)
	(segment
		(start 303.135284 -273.479514)
		(end 303.249584 -273.365214)
		(width 0.1143)
		(layer "In5.Cu")
		(net "P5E_PEX2_STN1_RX_DN<28>")
	)
	(segment
		(start 284.75305 -131.00558)
		(end 283.416248 -131.00558)
		(width 0.1651)
		(layer "In5.Cu")
		(net "P5E_PEX2_STN1_RX_DN<28>")
	)
	(segment
		(start 278.167846 -142.536926)
		(end 277.755858 -142.812262)
		(width 0.1651)
		(layer "In5.Cu")
		(net "P5E_PEX2_STN1_RX_DN<28>")
	)
	(segment
		(start 283.10205 -131.388358)
		(end 283.117798 -131.54914)
		(width 0.1651)
		(layer "In5.Cu")
		(net "P5E_PEX2_STN1_RX_DN<28>")
	)
	(segment
		(start 282.803346 -131.932172)
		(end 282.642564 -131.94792)
		(width 0.1651)
		(layer "In5.Cu")
		(net "P5E_PEX2_STN1_RX_DN<28>")
	)
	(segment
		(start 282.642564 -131.94792)
		(end 282.328366 -132.330698)
		(width 0.1651)
		(layer "In5.Cu")
		(net "P5E_PEX2_STN1_RX_DN<28>")
	)
	(segment
		(start 302.870108 -273.376136)
		(end 302.973486 -273.479514)
		(width 0.1143)
		(layer "In5.Cu")
		(net "P5E_PEX2_STN1_RX_DN<28>")
	)
	(segment
		(start 303.249584 -273.365214)
		(end 303.249584 -273.099784)
		(width 0.1143)
		(layer "In5.Cu")
		(net "P5E_PEX2_STN1_RX_DN<28>")
	)
	(segment
		(start 280.196544 -140.348462)
		(end 279.975564 -140.883132)
		(width 0.1651)
		(layer "In5.Cu")
		(net "P5E_PEX2_STN1_RX_DN<28>")
	)
	(segment
		(start 283.117798 -131.54914)
		(end 282.803346 -131.932172)
		(width 0.1651)
		(layer "In5.Cu")
		(net "P5E_PEX2_STN1_RX_DN<28>")
	)
	(segment
		(start 285.36265 -131.11988)
		(end 284.86735 -131.11988)
		(width 0.1651)
		(layer "In5.Cu")
		(net "P5E_PEX2_STN1_RX_DN<28>")
	)
	(segment
		(start 276.171914 -143.733266)
		(end 275.085302 -144.82064)
		(width 0.1651)
		(layer "In5.Cu")
		(net "P5E_PEX2_STN1_RX_DN<28>")
	)
	(segment
		(start 275.085302 -144.82064)
		(end 274.790662 -145.218658)
		(width 0.1651)
		(layer "In5.Cu")
		(net "P5E_PEX2_STN1_RX_DN<28>")
	)
	(segment
		(start 277.154132 -143.214344)
		(end 276.742144 -143.48968)
		(width 0.1651)
		(layer "In5.Cu")
		(net "P5E_PEX2_STN1_RX_DN<28>")
	)
	(segment
		(start 286.006032 -131.00558)
		(end 285.47695 -131.00558)
		(width 0.1651)
		(layer "In5.Cu")
		(net "P5E_PEX2_STN1_RX_DN<28>")
	)
	(segment
		(start 281.323796 -133.781038)
		(end 281.385772 -133.93039)
		(width 0.1651)
		(layer "In5.Cu")
		(net "P5E_PEX2_STN1_RX_DN<28>")
	)
	(segment
		(start 285.47695 -131.00558)
		(end 285.36265 -131.11988)
		(width 0.1651)
		(layer "In5.Cu")
		(net "P5E_PEX2_STN1_RX_DN<28>")
	)
	(segment
		(start 276.583648 -143.458184)
		(end 276.171914 -143.733266)
		(width 0.1651)
		(layer "In5.Cu")
		(net "P5E_PEX2_STN1_RX_DN<28>")
	)
	(segment
		(start 273.412204 -147.079716)
		(end 273.244056 -147.684744)
		(width 0.1651)
		(layer "In5.Cu")
		(net "P5E_PEX2_STN1_RX_DN<28>")
	)
	(segment
		(start 277.755858 -142.812262)
		(end 277.597362 -142.780766)
		(width 0.1651)
		(layer "In5.Cu")
		(net "P5E_PEX2_STN1_RX_DN<28>")
	)
	(segment
		(start 281.86888 -132.890514)
		(end 281.51328 -133.323584)
		(width 0.1651)
		(layer "In5.Cu")
		(net "P5E_PEX2_STN1_RX_DN<28>")
	)
	(segment
		(start 279.975564 -140.883132)
		(end 279.045416 -141.813026)
		(width 0.1651)
		(layer "In5.Cu")
		(net "P5E_PEX2_STN1_RX_DN<28>")
	)
	(segment
		(start 274.59178 -161.14268)
		(end 302.915828 -267.605256)
		(width 0.1651)
		(layer "In5.Cu")
		(net "P5E_PEX2_STN1_RX_DN<28>")
	)
	(segment
		(start 274.51939 -145.776696)
		(end 274.359624 -145.800572)
		(width 0.1651)
		(layer "In5.Cu")
		(net "P5E_PEX2_STN1_RX_DN<28>")
	)
	(segment
		(start 302.915828 -271.526)
		(end 302.915828 -271.554448)
		(width 0.1143)
		(layer "In5.Cu")
		(net "P5E_PEX2_STN1_RX_DN<28>")
	)
	(segment
		(start 302.973486 -273.479514)
		(end 303.135284 -273.479514)
		(width 0.1143)
		(layer "In5.Cu")
		(net "P5E_PEX2_STN1_RX_DN<28>")
	)
	(segment
		(start 280.580084 -135.576564)
		(end 280.196544 -136.502648)
		(width 0.1651)
		(layer "In5.Cu")
		(net "P5E_PEX2_STN1_RX_DN<28>")
	)
	(segment
		(start 277.597362 -142.780766)
		(end 277.185628 -143.055848)
		(width 0.1651)
		(layer "In5.Cu")
		(net "P5E_PEX2_STN1_RX_DN<28>")
	)
	(segment
		(start 286.296862 -131.29641)
		(end 286.006032 -131.00558)
		(width 0.1651)
		(layer "In5.Cu")
		(net "P5E_PEX2_STN1_RX_DN<28>")
	)
	(segment
		(start 278.199342 -142.37843)
		(end 278.167846 -142.536926)
		(width 0.1651)
		(layer "In5.Cu")
		(net "P5E_PEX2_STN1_RX_DN<28>")
	)
	(segment
		(start 273.244056 -147.684744)
		(end 273.838416 -156.892244)
		(width 0.1651)
		(layer "In5.Cu")
		(net "P5E_PEX2_STN1_RX_DN<28>")
	)
	(segment
		(start 279.045416 -141.813026)
		(end 278.199342 -142.37843)
		(width 0.1651)
		(layer "In5.Cu")
		(net "P5E_PEX2_STN1_RX_DN<28>")
	)
	(segment
		(start 280.72969 -135.514842)
		(end 280.580084 -135.576564)
		(width 0.1651)
		(layer "In5.Cu")
		(net "P5E_PEX2_STN1_RX_DN<28>")
	)
	(segment
		(start 282.344368 -132.49148)
		(end 282.029662 -132.874512)
		(width 0.1651)
		(layer "In5.Cu")
		(net "P5E_PEX2_STN1_RX_DN<28>")
	)
	(segment
		(start 302.870108 -271.600168)
		(end 302.870108 -273.376136)
		(width 0.1143)
		(layer "In5.Cu")
		(net "P5E_PEX2_STN1_RX_DN<28>")
	)
	(segment
		(start 302.915828 -271.554448)
		(end 302.870108 -271.600168)
		(width 0.1143)
		(layer "In5.Cu")
		(net "P5E_PEX2_STN1_RX_DN<28>")
	)
	(segment
		(start 276.742144 -143.48968)
		(end 276.583648 -143.458184)
		(width 0.1651)
		(layer "In5.Cu")
		(net "P5E_PEX2_STN1_RX_DN<28>")
	)
	(segment
		(start 281.51328 -133.323584)
		(end 281.323796 -133.781038)
		(width 0.1651)
		(layer "In5.Cu")
		(net "P5E_PEX2_STN1_RX_DN<28>")
	)
	(segment
		(start 339.219794 -341.89924)
		(end 338.6582 -340.657942)
		(width 0.1651)
		(layer "In9.Cu")
		(net "P5E_PEX2_STN5_RX_DP<82>")
	)
	(segment
		(start 336.73415 -395.558518)
		(end 337.12023 -395.177518)
		(width 0.1651)
		(layer "In9.Cu")
		(net "P5E_PEX2_STN5_RX_DP<82>")
	)
	(segment
		(start 339.251798 -393.074398)
		(end 339.885528 -392.709654)
		(width 0.1651)
		(layer "In9.Cu")
		(net "P5E_PEX2_STN5_RX_DP<82>")
	)
	(segment
		(start 353.633278 -370.622068)
		(end 353.251008 -369.131088)
		(width 0.1651)
		(layer "In9.Cu")
		(net "P5E_PEX2_STN5_RX_DP<82>")
	)
	(segment
		(start 339.918294 -392.588496)
		(end 340.347808 -392.3411)
		(width 0.1651)
		(layer "In9.Cu")
		(net "P5E_PEX2_STN5_RX_DP<82>")
	)
	(segment
		(start 337.953096 -394.231114)
		(end 338.305902 -393.88288)
		(width 0.1651)
		(layer "In9.Cu")
		(net "P5E_PEX2_STN5_RX_DP<82>")
	)
	(segment
		(start 353.355402 -385.726686)
		(end 353.633278 -370.622068)
		(width 0.1651)
		(layer "In9.Cu")
		(net "P5E_PEX2_STN5_RX_DP<82>")
	)
	(segment
		(start 292.71087 -316.229492)
		(end 292.79977 -316.140592)
		(width 0.1143)
		(layer "In9.Cu")
		(net "P5E_PEX2_STN5_RX_DP<82>")
	)
	(segment
		(start 337.95208 -394.35659)
		(end 337.952334 -394.356844)
		(width 0.1651)
		(layer "In9.Cu")
		(net "P5E_PEX2_STN5_RX_DP<82>")
	)
	(segment
		(start 335.890108 -396.49019)
		(end 335.890108 -396.872206)
		(width 0.1651)
		(layer "In9.Cu")
		(net "P5E_PEX2_STN5_RX_DP<82>")
	)
	(segment
		(start 336.017108 -396.999206)
		(end 336.447384 -396.999206)
		(width 0.1651)
		(layer "In9.Cu")
		(net "P5E_PEX2_STN5_RX_DP<82>")
	)
	(segment
		(start 292.79977 -316.140592)
		(end 292.79977 -315.849762)
		(width 0.1143)
		(layer "In9.Cu")
		(net "P5E_PEX2_STN5_RX_DP<82>")
	)
	(segment
		(start 336.447384 -396.999206)
		(end 336.73415 -396.71244)
		(width 0.1651)
		(layer "In9.Cu")
		(net "P5E_PEX2_STN5_RX_DP<82>")
	)
	(segment
		(start 352.095562 -387.390894)
		(end 352.515932 -387.119876)
		(width 0.1651)
		(layer "In9.Cu")
		(net "P5E_PEX2_STN5_RX_DP<82>")
	)
	(segment
		(start 338.305902 -393.88288)
		(end 338.431632 -393.883896)
		(width 0.1651)
		(layer "In9.Cu")
		(net "P5E_PEX2_STN5_RX_DP<82>")
	)
	(segment
		(start 337.599782 -394.704316)
		(end 337.95208 -394.35659)
		(width 0.1651)
		(layer "In9.Cu")
		(net "P5E_PEX2_STN5_RX_DP<82>")
	)
	(segment
		(start 292.22954 -319.84188)
		(end 292.22954 -316.455044)
		(width 0.1143)
		(layer "In9.Cu")
		(net "P5E_PEX2_STN5_RX_DP<82>")
	)
	(segment
		(start 292.18382 -319.8876)
		(end 292.22954 -319.84188)
		(width 0.1143)
		(layer "In9.Cu")
		(net "P5E_PEX2_STN5_RX_DP<82>")
	)
	(segment
		(start 342.879426 -390.986772)
		(end 352.095562 -387.390894)
		(width 0.1651)
		(layer "In9.Cu")
		(net "P5E_PEX2_STN5_RX_DP<82>")
	)
	(segment
		(start 292.455092 -316.229492)
		(end 292.71087 -316.229492)
		(width 0.1143)
		(layer "In9.Cu")
		(net "P5E_PEX2_STN5_RX_DP<82>")
	)
	(segment
		(start 339.64118 -359.03662)
		(end 339.219794 -358.615234)
		(width 0.1651)
		(layer "In9.Cu")
		(net "P5E_PEX2_STN5_RX_DP<82>")
	)
	(segment
		(start 292.22954 -316.455044)
		(end 292.455092 -316.229492)
		(width 0.1143)
		(layer "In9.Cu")
		(net "P5E_PEX2_STN5_RX_DP<82>")
	)
	(segment
		(start 339.885528 -392.709654)
		(end 339.885528 -392.709908)
		(width 0.1651)
		(layer "In9.Cu")
		(net "P5E_PEX2_STN5_RX_DP<82>")
	)
	(segment
		(start 340.347808 -392.3411)
		(end 340.468966 -392.373866)
		(width 0.1651)
		(layer "In9.Cu")
		(net "P5E_PEX2_STN5_RX_DP<82>")
	)
	(segment
		(start 337.120992 -395.051788)
		(end 337.474052 -394.703808)
		(width 0.1651)
		(layer "In9.Cu")
		(net "P5E_PEX2_STN5_RX_DP<82>")
	)
	(segment
		(start 336.73415 -396.71244)
		(end 336.73415 -395.558518)
		(width 0.1651)
		(layer "In9.Cu")
		(net "P5E_PEX2_STN5_RX_DP<82>")
	)
	(segment
		(start 340.468966 -392.373866)
		(end 342.879426 -390.986772)
		(width 0.1651)
		(layer "In9.Cu")
		(net "P5E_PEX2_STN5_RX_DP<82>")
	)
	(segment
		(start 339.885528 -392.709908)
		(end 339.918294 -392.588496)
		(width 0.1651)
		(layer "In9.Cu")
		(net "P5E_PEX2_STN5_RX_DP<82>")
	)
	(segment
		(start 346.743528 -363.102144)
		(end 339.64118 -359.03662)
		(width 0.1651)
		(layer "In9.Cu")
		(net "P5E_PEX2_STN5_RX_DP<82>")
	)
	(segment
		(start 338.431632 -393.883642)
		(end 339.251798 -393.074398)
		(width 0.1651)
		(layer "In9.Cu")
		(net "P5E_PEX2_STN5_RX_DP<82>")
	)
	(segment
		(start 293.425118 -322.660518)
		(end 292.18382 -320.803016)
		(width 0.1651)
		(layer "In9.Cu")
		(net "P5E_PEX2_STN5_RX_DP<82>")
	)
	(segment
		(start 292.18382 -319.916048)
		(end 292.18382 -319.8876)
		(width 0.1143)
		(layer "In9.Cu")
		(net "P5E_PEX2_STN5_RX_DP<82>")
	)
	(segment
		(start 335.890108 -396.872206)
		(end 336.017108 -396.999206)
		(width 0.1651)
		(layer "In9.Cu")
		(net "P5E_PEX2_STN5_RX_DP<82>")
	)
	(segment
		(start 337.599782 -394.70457)
		(end 337.599782 -394.704316)
		(width 0.1651)
		(layer "In9.Cu")
		(net "P5E_PEX2_STN5_RX_DP<82>")
	)
	(segment
		(start 353.142296 -386.32384)
		(end 353.355402 -385.726686)
		(width 0.1651)
		(layer "In9.Cu")
		(net "P5E_PEX2_STN5_RX_DP<82>")
	)
	(segment
		(start 338.431632 -393.883896)
		(end 338.431632 -393.883642)
		(width 0.1651)
		(layer "In9.Cu")
		(net "P5E_PEX2_STN5_RX_DP<82>")
	)
	(segment
		(start 352.515932 -387.119876)
		(end 353.142296 -386.32384)
		(width 0.1651)
		(layer "In9.Cu")
		(net "P5E_PEX2_STN5_RX_DP<82>")
	)
	(segment
		(start 352.644964 -368.077496)
		(end 346.743528 -363.102144)
		(width 0.1651)
		(layer "In9.Cu")
		(net "P5E_PEX2_STN5_RX_DP<82>")
	)
	(segment
		(start 338.655914 -340.65718)
		(end 297.115738 -325.428864)
		(width 0.1651)
		(layer "In9.Cu")
		(net "P5E_PEX2_STN5_RX_DP<82>")
	)
	(segment
		(start 292.18382 -320.803016)
		(end 292.18382 -319.916048)
		(width 0.1651)
		(layer "In9.Cu")
		(net "P5E_PEX2_STN5_RX_DP<82>")
	)
	(segment
		(start 337.12023 -395.177518)
		(end 337.120992 -395.051788)
		(width 0.1651)
		(layer "In9.Cu")
		(net "P5E_PEX2_STN5_RX_DP<82>")
	)
	(segment
		(start 294.562784 -323.798438)
		(end 293.425118 -322.660518)
		(width 0.1651)
		(layer "In9.Cu")
		(net "P5E_PEX2_STN5_RX_DP<82>")
	)
	(segment
		(start 297.115738 -325.428864)
		(end 294.562784 -323.798438)
		(width 0.1651)
		(layer "In9.Cu")
		(net "P5E_PEX2_STN5_RX_DP<82>")
	)
	(segment
		(start 337.952334 -394.356844)
		(end 337.953096 -394.231114)
		(width 0.1651)
		(layer "In9.Cu")
		(net "P5E_PEX2_STN5_RX_DP<82>")
	)
	(segment
		(start 353.251008 -369.131088)
		(end 352.644964 -368.077496)
		(width 0.1651)
		(layer "In9.Cu")
		(net "P5E_PEX2_STN5_RX_DP<82>")
	)
	(segment
		(start 337.474052 -394.703808)
		(end 337.599782 -394.70457)
		(width 0.1651)
		(layer "In9.Cu")
		(net "P5E_PEX2_STN5_RX_DP<82>")
	)
	(segment
		(start 339.219794 -358.615234)
		(end 339.219794 -341.89924)
		(width 0.1651)
		(layer "In9.Cu")
		(net "P5E_PEX2_STN5_RX_DP<82>")
	)
	(segment
		(start 338.6582 -340.657942)
		(end 338.655914 -340.65718)
		(width 0.1651)
		(layer "In9.Cu")
		(net "P5E_PEX2_STN5_RX_DP<82>")
	)
	(segment
		(start 416.476688 -149.954996)
		(end 416.95751 -149.954996)
		(width 0.13462)
		(layer "F.Cu")
		(net "P5E_PEX3_STN0_RX_DN<12>")
	)
	(segment
		(start 415.35731 -149.823678)
		(end 415.652712 -150.11908)
		(width 0.13462)
		(layer "F.Cu")
		(net "P5E_PEX3_STN0_RX_DN<12>")
	)
	(segment
		(start 416.312604 -150.11908)
		(end 416.476688 -149.954996)
		(width 0.13462)
		(layer "F.Cu")
		(net "P5E_PEX3_STN0_RX_DN<12>")
	)
	(segment
		(start 415.652712 -150.11908)
		(end 416.312604 -150.11908)
		(width 0.13462)
		(layer "F.Cu")
		(net "P5E_PEX3_STN0_RX_DN<12>")
	)
	(segment
		(start 421.432228 -158.336488)
		(end 421.44315 -158.362396)
		(width 0.1651)
		(layer "In5.Cu")
		(net "P5E_PEX3_STN0_RX_DN<12>")
	)
	(segment
		(start 415.35731 -149.823678)
		(end 415.64814 -150.114508)
		(width 0.1651)
		(layer "In5.Cu")
		(net "P5E_PEX3_STN0_RX_DN<12>")
	)
	(segment
		(start 425.6659 -270.786098)
		(end 425.6659 -271.570958)
		(width 0.1651)
		(layer "In5.Cu")
		(net "P5E_PEX3_STN0_RX_DN<12>")
	)
	(segment
		(start 415.64814 -150.114508)
		(end 416.238436 -150.114508)
		(width 0.1651)
		(layer "In5.Cu")
		(net "P5E_PEX3_STN0_RX_DN<12>")
	)
	(segment
		(start 426.132752 -260.768084)
		(end 426.19549 -268.061186)
		(width 0.1651)
		(layer "In5.Cu")
		(net "P5E_PEX3_STN0_RX_DN<12>")
	)
	(segment
		(start 418.643816 -153.725626)
		(end 419.167564 -154.97175)
		(width 0.1651)
		(layer "In5.Cu")
		(net "P5E_PEX3_STN0_RX_DN<12>")
	)
	(segment
		(start 425.885356 -275.379688)
		(end 425.999656 -275.265388)
		(width 0.1143)
		(layer "In5.Cu")
		(net "P5E_PEX3_STN0_RX_DN<12>")
	)
	(segment
		(start 425.62018 -271.645126)
		(end 425.62018 -275.27631)
		(width 0.1143)
		(layer "In5.Cu")
		(net "P5E_PEX3_STN0_RX_DN<12>")
	)
	(segment
		(start 421.44315 -158.362396)
		(end 421.442896 -158.362396)
		(width 0.1651)
		(layer "In5.Cu")
		(net "P5E_PEX3_STN0_RX_DN<12>")
	)
	(segment
		(start 425.6659 -271.570958)
		(end 425.6659 -271.599406)
		(width 0.1143)
		(layer "In5.Cu")
		(net "P5E_PEX3_STN0_RX_DN<12>")
	)
	(segment
		(start 425.723558 -275.379688)
		(end 425.885356 -275.379688)
		(width 0.1143)
		(layer "In5.Cu")
		(net "P5E_PEX3_STN0_RX_DN<12>")
	)
	(segment
		(start 422.602406 -161.1503)
		(end 426.132752 -260.768084)
		(width 0.1651)
		(layer "In5.Cu")
		(net "P5E_PEX3_STN0_RX_DN<12>")
	)
	(segment
		(start 426.19549 -268.061186)
		(end 425.6659 -270.786098)
		(width 0.1651)
		(layer "In5.Cu")
		(net "P5E_PEX3_STN0_RX_DN<12>")
	)
	(segment
		(start 418.643308 -153.725372)
		(end 418.643816 -153.725626)
		(width 0.1651)
		(layer "In5.Cu")
		(net "P5E_PEX3_STN0_RX_DN<12>")
	)
	(segment
		(start 425.999656 -275.265388)
		(end 425.999656 -274.999958)
		(width 0.1143)
		(layer "In5.Cu")
		(net "P5E_PEX3_STN0_RX_DN<12>")
	)
	(segment
		(start 419.167564 -154.97175)
		(end 421.432228 -158.336488)
		(width 0.1651)
		(layer "In5.Cu")
		(net "P5E_PEX3_STN0_RX_DN<12>")
	)
	(segment
		(start 425.6659 -271.599406)
		(end 425.62018 -271.645126)
		(width 0.1143)
		(layer "In5.Cu")
		(net "P5E_PEX3_STN0_RX_DN<12>")
	)
	(segment
		(start 417.748974 -151.59863)
		(end 418.643308 -153.725372)
		(width 0.1651)
		(layer "In5.Cu")
		(net "P5E_PEX3_STN0_RX_DN<12>")
	)
	(segment
		(start 425.62018 -275.27631)
		(end 425.723558 -275.379688)
		(width 0.1143)
		(layer "In5.Cu")
		(net "P5E_PEX3_STN0_RX_DN<12>")
	)
	(segment
		(start 421.442896 -158.362396)
		(end 422.602406 -161.1503)
		(width 0.1651)
		(layer "In5.Cu")
		(net "P5E_PEX3_STN0_RX_DN<12>")
	)
	(segment
		(start 416.238436 -150.114508)
		(end 417.748974 -151.59863)
		(width 0.1651)
		(layer "In5.Cu")
		(net "P5E_PEX3_STN0_RX_DN<12>")
	)
	(segment
		(start 430.076102 -341.67826)
		(end 429.782986 -341.254588)
		(width 0.1651)
		(layer "In9.Cu")
		(net "P5E_PEX3_STN7_RX_DP<122>")
	)
	(segment
		(start 385.765802 -318.950848)
		(end 385.765802 -318.9224)
		(width 0.1143)
		(layer "In9.Cu")
		(net "P5E_PEX3_STN7_RX_DP<122>")
	)
	(segment
		(start 424.016932 -382.980946)
		(end 424.355768 -382.980946)
		(width 0.1651)
		(layer "In9.Cu")
		(net "P5E_PEX3_STN7_RX_DP<122>")
	)
	(segment
		(start 423.889932 -383.490216)
		(end 423.889932 -383.107946)
		(width 0.1651)
		(layer "In9.Cu")
		(net "P5E_PEX3_STN7_RX_DP<122>")
	)
	(segment
		(start 423.604944 -338.941664)
		(end 408.198828 -331.677772)
		(width 0.1651)
		(layer "In9.Cu")
		(net "P5E_PEX3_STN7_RX_DP<122>")
	)
	(segment
		(start 385.720082 -318.87668)
		(end 385.720082 -316.888622)
		(width 0.1143)
		(layer "In9.Cu")
		(net "P5E_PEX3_STN7_RX_DP<122>")
	)
	(segment
		(start 425.046902 -382.289812)
		(end 425.046902 -369.49253)
		(width 0.1651)
		(layer "In9.Cu")
		(net "P5E_PEX3_STN7_RX_DP<122>")
	)
	(segment
		(start 408.198828 -331.677772)
		(end 388.886446 -325.5645)
		(width 0.1651)
		(layer "In9.Cu")
		(net "P5E_PEX3_STN7_RX_DP<122>")
	)
	(segment
		(start 386.658866 -323.963792)
		(end 385.765802 -321.80784)
		(width 0.1651)
		(layer "In9.Cu")
		(net "P5E_PEX3_STN7_RX_DP<122>")
	)
	(segment
		(start 385.765802 -318.9224)
		(end 385.720082 -318.87668)
		(width 0.1143)
		(layer "In9.Cu")
		(net "P5E_PEX3_STN7_RX_DP<122>")
	)
	(segment
		(start 424.355768 -382.980946)
		(end 425.046902 -382.289812)
		(width 0.1651)
		(layer "In9.Cu")
		(net "P5E_PEX3_STN7_RX_DP<122>")
	)
	(segment
		(start 429.782986 -341.254588)
		(end 423.604944 -338.941664)
		(width 0.1651)
		(layer "In9.Cu")
		(net "P5E_PEX3_STN7_RX_DP<122>")
	)
	(segment
		(start 423.889932 -383.107946)
		(end 424.016932 -382.980946)
		(width 0.1651)
		(layer "In9.Cu")
		(net "P5E_PEX3_STN7_RX_DP<122>")
	)
	(segment
		(start 425.046902 -369.49253)
		(end 430.076102 -358.165146)
		(width 0.1651)
		(layer "In9.Cu")
		(net "P5E_PEX3_STN7_RX_DP<122>")
	)
	(segment
		(start 385.765802 -321.80784)
		(end 385.765802 -318.950848)
		(width 0.1651)
		(layer "In9.Cu")
		(net "P5E_PEX3_STN7_RX_DP<122>")
	)
	(segment
		(start 385.720082 -316.888622)
		(end 385.808982 -316.799722)
		(width 0.1143)
		(layer "In9.Cu")
		(net "P5E_PEX3_STN7_RX_DP<122>")
	)
	(segment
		(start 388.886446 -325.5645)
		(end 386.658866 -323.963792)
		(width 0.1651)
		(layer "In9.Cu")
		(net "P5E_PEX3_STN7_RX_DP<122>")
	)
	(segment
		(start 385.808982 -316.799722)
		(end 386.099812 -316.799722)
		(width 0.1143)
		(layer "In9.Cu")
		(net "P5E_PEX3_STN7_RX_DP<122>")
	)
	(segment
		(start 430.076102 -358.165146)
		(end 430.076102 -341.67826)
		(width 0.1651)
		(layer "In9.Cu")
		(net "P5E_PEX3_STN7_RX_DP<122>")
	)
	(segment
		(start 167.230298 -125.355096)
		(end 166.742364 -125.355096)
		(width 0.13462)
		(layer "F.Cu")
		(net "P5E_PEX1_STN1_RX_DN<27>")
	)
	(segment
		(start 167.393112 -125.192282)
		(end 167.230298 -125.355096)
		(width 0.13462)
		(layer "F.Cu")
		(net "P5E_PEX1_STN1_RX_DN<27>")
	)
	(segment
		(start 168.048432 -125.192282)
		(end 167.393112 -125.192282)
		(width 0.13462)
		(layer "F.Cu")
		(net "P5E_PEX1_STN1_RX_DN<27>")
	)
	(segment
		(start 168.342564 -125.486414)
		(end 168.048432 -125.192282)
		(width 0.13462)
		(layer "F.Cu")
		(net "P5E_PEX1_STN1_RX_DN<27>")
	)
	(segment
		(start 163.527994 -134.83844)
		(end 163.68014 -134.78383)
		(width 0.1651)
		(layer "In5.Cu")
		(net "P5E_PEX1_STN1_RX_DN<27>")
	)
	(segment
		(start 186.084972 -275.379688)
		(end 185.923174 -275.379688)
		(width 0.1143)
		(layer "In5.Cu")
		(net "P5E_PEX1_STN1_RX_DN<27>")
	)
	(segment
		(start 165.331648 -131.705096)
		(end 165.60927 -131.294378)
		(width 0.1651)
		(layer "In5.Cu")
		(net "P5E_PEX1_STN1_RX_DN<27>")
	)
	(segment
		(start 156.788612 -157.00756)
		(end 156.180536 -147.588986)
		(width 0.1651)
		(layer "In5.Cu")
		(net "P5E_PEX1_STN1_RX_DN<27>")
	)
	(segment
		(start 164.567108 -132.632196)
		(end 165.172898 -131.73583)
		(width 0.1651)
		(layer "In5.Cu")
		(net "P5E_PEX1_STN1_RX_DN<27>")
	)
	(segment
		(start 158.333948 -144.095978)
		(end 159.295338 -143.147034)
		(width 0.1651)
		(layer "In5.Cu")
		(net "P5E_PEX1_STN1_RX_DN<27>")
	)
	(segment
		(start 162.177222 -139.402312)
		(end 162.32124 -138.928094)
		(width 0.1651)
		(layer "In5.Cu")
		(net "P5E_PEX1_STN1_RX_DN<27>")
	)
	(segment
		(start 166.40302 -129.415032)
		(end 166.55288 -129.353564)
		(width 0.1651)
		(layer "In5.Cu")
		(net "P5E_PEX1_STN1_RX_DN<27>")
	)
	(segment
		(start 162.388804 -138.311636)
		(end 162.531806 -138.235436)
		(width 0.1651)
		(layer "In5.Cu")
		(net "P5E_PEX1_STN1_RX_DN<27>")
	)
	(segment
		(start 162.24504 -138.785346)
		(end 162.389058 -138.311636)
		(width 0.1651)
		(layer "In5.Cu")
		(net "P5E_PEX1_STN1_RX_DN<27>")
	)
	(segment
		(start 166.743888 -128.89611)
		(end 166.68242 -128.746758)
		(width 0.1651)
		(layer "In5.Cu")
		(net "P5E_PEX1_STN1_RX_DN<27>")
	)
	(segment
		(start 161.822892 -140.56868)
		(end 161.96691 -140.094716)
		(width 0.1651)
		(layer "In5.Cu")
		(net "P5E_PEX1_STN1_RX_DN<27>")
	)
	(segment
		(start 162.32124 -138.928094)
		(end 162.24504 -138.785346)
		(width 0.1651)
		(layer "In5.Cu")
		(net "P5E_PEX1_STN1_RX_DN<27>")
	)
	(segment
		(start 164.047424 -133.735318)
		(end 164.19957 -133.680708)
		(width 0.1651)
		(layer "In5.Cu")
		(net "P5E_PEX1_STN1_RX_DN<27>")
	)
	(segment
		(start 166.55288 -129.353564)
		(end 166.743888 -128.89611)
		(width 0.1651)
		(layer "In5.Cu")
		(net "P5E_PEX1_STN1_RX_DN<27>")
	)
	(segment
		(start 185.865516 -271.802352)
		(end 185.865516 -271.773904)
		(width 0.1143)
		(layer "In5.Cu")
		(net "P5E_PEX1_STN1_RX_DN<27>")
	)
	(segment
		(start 163.836604 -134.183374)
		(end 164.047424 -133.735318)
		(width 0.1651)
		(layer "In5.Cu")
		(net "P5E_PEX1_STN1_RX_DN<27>")
	)
	(segment
		(start 163.292028 -135.339836)
		(end 163.527994 -134.83844)
		(width 0.1651)
		(layer "In5.Cu")
		(net "P5E_PEX1_STN1_RX_DN<27>")
	)
	(segment
		(start 157.55874 -161.3535)
		(end 156.788612 -157.00756)
		(width 0.1651)
		(layer "In5.Cu")
		(net "P5E_PEX1_STN1_RX_DN<27>")
	)
	(segment
		(start 164.410898 -133.232144)
		(end 164.356288 -133.080252)
		(width 0.1651)
		(layer "In5.Cu")
		(net "P5E_PEX1_STN1_RX_DN<27>")
	)
	(segment
		(start 156.180536 -147.588986)
		(end 156.425138 -146.657822)
		(width 0.1651)
		(layer "In5.Cu")
		(net "P5E_PEX1_STN1_RX_DN<27>")
	)
	(segment
		(start 186.199526 -275.265134)
		(end 186.084972 -275.379688)
		(width 0.1143)
		(layer "In5.Cu")
		(net "P5E_PEX1_STN1_RX_DN<27>")
	)
	(segment
		(start 166.68242 -128.746758)
		(end 166.873174 -128.289812)
		(width 0.1651)
		(layer "In5.Cu")
		(net "P5E_PEX1_STN1_RX_DN<27>")
	)
	(segment
		(start 162.03422 -139.478258)
		(end 162.177222 -139.402312)
		(width 0.1651)
		(layer "In5.Cu")
		(net "P5E_PEX1_STN1_RX_DN<27>")
	)
	(segment
		(start 185.923174 -275.379688)
		(end 185.819796 -275.27631)
		(width 0.1143)
		(layer "In5.Cu")
		(net "P5E_PEX1_STN1_RX_DN<27>")
	)
	(segment
		(start 161.539936 -141.106652)
		(end 161.680144 -140.64488)
		(width 0.1651)
		(layer "In5.Cu")
		(net "P5E_PEX1_STN1_RX_DN<27>")
	)
	(segment
		(start 162.034728 -139.478258)
		(end 162.03422 -139.478258)
		(width 0.1651)
		(layer "In5.Cu")
		(net "P5E_PEX1_STN1_RX_DN<27>")
	)
	(segment
		(start 166.873174 -128.289812)
		(end 166.873174 -126.66345)
		(width 0.1651)
		(layer "In5.Cu")
		(net "P5E_PEX1_STN1_RX_DN<27>")
	)
	(segment
		(start 165.60927 -131.294378)
		(end 165.578536 -131.135628)
		(width 0.1651)
		(layer "In5.Cu")
		(net "P5E_PEX1_STN1_RX_DN<27>")
	)
	(segment
		(start 165.85565 -130.725418)
		(end 166.40302 -129.415032)
		(width 0.1651)
		(layer "In5.Cu")
		(net "P5E_PEX1_STN1_RX_DN<27>")
	)
	(segment
		(start 162.67557 -137.761472)
		(end 162.599624 -137.618724)
		(width 0.1651)
		(layer "In5.Cu")
		(net "P5E_PEX1_STN1_RX_DN<27>")
	)
	(segment
		(start 162.88639 -137.068814)
		(end 163.030408 -136.594596)
		(width 0.1651)
		(layer "In5.Cu")
		(net "P5E_PEX1_STN1_RX_DN<27>")
	)
	(segment
		(start 168.051734 -125.195584)
		(end 168.342564 -125.486414)
		(width 0.1651)
		(layer "In5.Cu")
		(net "P5E_PEX1_STN1_RX_DN<27>")
	)
	(segment
		(start 186.199526 -274.999958)
		(end 186.199526 -275.265134)
		(width 0.1143)
		(layer "In5.Cu")
		(net "P5E_PEX1_STN1_RX_DN<27>")
	)
	(segment
		(start 165.172898 -131.73583)
		(end 165.331648 -131.705096)
		(width 0.1651)
		(layer "In5.Cu")
		(net "P5E_PEX1_STN1_RX_DN<27>")
	)
	(segment
		(start 161.96691 -140.094716)
		(end 161.89071 -139.951968)
		(width 0.1651)
		(layer "In5.Cu")
		(net "P5E_PEX1_STN1_RX_DN<27>")
	)
	(segment
		(start 164.19957 -133.680708)
		(end 164.410898 -133.232144)
		(width 0.1651)
		(layer "In5.Cu")
		(net "P5E_PEX1_STN1_RX_DN<27>")
	)
	(segment
		(start 162.743388 -137.145014)
		(end 162.88639 -137.068814)
		(width 0.1651)
		(layer "In5.Cu")
		(net "P5E_PEX1_STN1_RX_DN<27>")
	)
	(segment
		(start 163.68014 -134.78383)
		(end 163.891214 -134.33552)
		(width 0.1651)
		(layer "In5.Cu")
		(net "P5E_PEX1_STN1_RX_DN<27>")
	)
	(segment
		(start 159.295338 -143.147034)
		(end 161.539936 -141.106652)
		(width 0.1651)
		(layer "In5.Cu")
		(net "P5E_PEX1_STN1_RX_DN<27>")
	)
	(segment
		(start 185.865516 -271.773904)
		(end 185.865516 -267.748512)
		(width 0.1651)
		(layer "In5.Cu")
		(net "P5E_PEX1_STN1_RX_DN<27>")
	)
	(segment
		(start 167.725598 -125.195584)
		(end 168.051734 -125.195584)
		(width 0.1651)
		(layer "In5.Cu")
		(net "P5E_PEX1_STN1_RX_DN<27>")
	)
	(segment
		(start 165.578536 -131.135628)
		(end 165.85565 -130.725418)
		(width 0.1651)
		(layer "In5.Cu")
		(net "P5E_PEX1_STN1_RX_DN<27>")
	)
	(segment
		(start 163.030408 -136.594596)
		(end 162.954208 -136.452102)
		(width 0.1651)
		(layer "In5.Cu")
		(net "P5E_PEX1_STN1_RX_DN<27>")
	)
	(segment
		(start 162.954208 -136.452102)
		(end 163.292028 -135.339836)
		(width 0.1651)
		(layer "In5.Cu")
		(net "P5E_PEX1_STN1_RX_DN<27>")
	)
	(segment
		(start 185.819796 -271.848072)
		(end 185.865516 -271.802352)
		(width 0.1143)
		(layer "In5.Cu")
		(net "P5E_PEX1_STN1_RX_DN<27>")
	)
	(segment
		(start 185.819796 -275.27631)
		(end 185.819796 -271.848072)
		(width 0.1143)
		(layer "In5.Cu")
		(net "P5E_PEX1_STN1_RX_DN<27>")
	)
	(segment
		(start 167.308276 -125.612906)
		(end 167.725598 -125.195584)
		(width 0.1651)
		(layer "In5.Cu")
		(net "P5E_PEX1_STN1_RX_DN<27>")
	)
	(segment
		(start 166.873174 -126.66345)
		(end 167.308276 -125.612906)
		(width 0.1651)
		(layer "In5.Cu")
		(net "P5E_PEX1_STN1_RX_DN<27>")
	)
	(segment
		(start 156.425138 -146.657822)
		(end 158.333948 -144.095978)
		(width 0.1651)
		(layer "In5.Cu")
		(net "P5E_PEX1_STN1_RX_DN<27>")
	)
	(segment
		(start 161.680144 -140.64488)
		(end 161.822892 -140.56868)
		(width 0.1651)
		(layer "In5.Cu")
		(net "P5E_PEX1_STN1_RX_DN<27>")
	)
	(segment
		(start 185.865516 -267.748512)
		(end 157.55874 -161.3535)
		(width 0.1651)
		(layer "In5.Cu")
		(net "P5E_PEX1_STN1_RX_DN<27>")
	)
	(segment
		(start 161.89071 -139.951968)
		(end 162.034728 -139.478258)
		(width 0.1651)
		(layer "In5.Cu")
		(net "P5E_PEX1_STN1_RX_DN<27>")
	)
	(segment
		(start 162.599624 -137.618724)
		(end 162.743388 -137.145014)
		(width 0.1651)
		(layer "In5.Cu")
		(net "P5E_PEX1_STN1_RX_DN<27>")
	)
	(segment
		(start 163.891214 -134.33552)
		(end 163.836604 -134.183374)
		(width 0.1651)
		(layer "In5.Cu")
		(net "P5E_PEX1_STN1_RX_DN<27>")
	)
	(segment
		(start 162.531806 -138.235436)
		(end 162.67557 -137.761472)
		(width 0.1651)
		(layer "In5.Cu")
		(net "P5E_PEX1_STN1_RX_DN<27>")
	)
	(segment
		(start 162.389058 -138.311636)
		(end 162.388804 -138.311636)
		(width 0.1651)
		(layer "In5.Cu")
		(net "P5E_PEX1_STN1_RX_DN<27>")
	)
	(segment
		(start 164.356288 -133.080252)
		(end 164.567108 -132.632196)
		(width 0.1651)
		(layer "In5.Cu")
		(net "P5E_PEX1_STN1_RX_DN<27>")
	)
	(segment
		(start 283.489654 -119.7864)
		(end 283.320998 -119.955056)
		(width 0.13462)
		(layer "F.Cu")
		(net "P5E_PEX2_STN1_RX_DN<24>")
	)
	(segment
		(start 286.296862 -120.086374)
		(end 285.996888 -119.7864)
		(width 0.13462)
		(layer "F.Cu")
		(net "P5E_PEX2_STN1_RX_DN<24>")
	)
	(segment
		(start 285.996888 -119.7864)
		(end 283.489654 -119.7864)
		(width 0.13462)
		(layer "F.Cu")
		(net "P5E_PEX2_STN1_RX_DN<24>")
	)
	(segment
		(start 283.320998 -119.955056)
		(end 282.842462 -119.955056)
		(width 0.13462)
		(layer "F.Cu")
		(net "P5E_PEX2_STN1_RX_DN<24>")
	)
	(segment
		(start 273.473164 -137.708894)
		(end 273.158712 -138.264138)
		(width 0.1651)
		(layer "In5.Cu")
		(net "P5E_PEX2_STN1_RX_DN<24>")
	)
	(segment
		(start 268.983206 -158.172912)
		(end 269.982188 -163.875974)
		(width 0.1651)
		(layer "In5.Cu")
		(net "P5E_PEX2_STN1_RX_DN<24>")
	)
	(segment
		(start 272.801588 -138.894312)
		(end 272.557494 -139.325096)
		(width 0.1651)
		(layer "In5.Cu")
		(net "P5E_PEX2_STN1_RX_DN<24>")
	)
	(segment
		(start 280.119074 -122.524266)
		(end 280.114756 -122.686064)
		(width 0.1651)
		(layer "In5.Cu")
		(net "P5E_PEX2_STN1_RX_DN<24>")
	)
	(segment
		(start 271.524476 -141.528292)
		(end 271.320768 -141.979904)
		(width 0.1651)
		(layer "In5.Cu")
		(net "P5E_PEX2_STN1_RX_DN<24>")
	)
	(segment
		(start 278.87041 -123.866148)
		(end 278.708866 -123.86183)
		(width 0.1651)
		(layer "In5.Cu")
		(net "P5E_PEX2_STN1_RX_DN<24>")
	)
	(segment
		(start 272.557494 -139.325096)
		(end 272.600674 -139.480798)
		(width 0.1651)
		(layer "In5.Cu")
		(net "P5E_PEX2_STN1_RX_DN<24>")
	)
	(segment
		(start 271.467326 -141.376908)
		(end 271.524476 -141.528292)
		(width 0.1651)
		(layer "In5.Cu")
		(net "P5E_PEX2_STN1_RX_DN<24>")
	)
	(segment
		(start 276.815042 -125.657864)
		(end 276.546818 -126.073916)
		(width 0.1651)
		(layer "In5.Cu")
		(net "P5E_PEX2_STN1_RX_DN<24>")
	)
	(segment
		(start 277.985728 -124.70511)
		(end 277.824184 -124.701046)
		(width 0.1651)
		(layer "In5.Cu")
		(net "P5E_PEX2_STN1_RX_DN<24>")
	)
	(segment
		(start 286.296862 -120.086374)
		(end 286.006032 -119.795544)
		(width 0.1651)
		(layer "In5.Cu")
		(net "P5E_PEX2_STN1_RX_DN<24>")
	)
	(segment
		(start 273.201638 -138.41984)
		(end 272.95729 -138.851132)
		(width 0.1651)
		(layer "In5.Cu")
		(net "P5E_PEX2_STN1_RX_DN<24>")
	)
	(segment
		(start 271.169384 -142.037054)
		(end 269.718282 -145.252186)
		(width 0.1651)
		(layer "In5.Cu")
		(net "P5E_PEX2_STN1_RX_DN<24>")
	)
	(segment
		(start 279.234392 -123.363482)
		(end 279.230074 -123.52528)
		(width 0.1651)
		(layer "In5.Cu")
		(net "P5E_PEX2_STN1_RX_DN<24>")
	)
	(segment
		(start 273.158712 -138.264138)
		(end 273.201638 -138.41984)
		(width 0.1651)
		(layer "In5.Cu")
		(net "P5E_PEX2_STN1_RX_DN<24>")
	)
	(segment
		(start 276.154134 -126.682754)
		(end 275.227034 -128.120648)
		(width 0.1651)
		(layer "In5.Cu")
		(net "P5E_PEX2_STN1_RX_DN<24>")
	)
	(segment
		(start 276.312122 -126.648464)
		(end 276.154134 -126.682754)
		(width 0.1651)
		(layer "In5.Cu")
		(net "P5E_PEX2_STN1_RX_DN<24>")
	)
	(segment
		(start 280.114756 -122.686064)
		(end 279.755092 -123.026932)
		(width 0.1651)
		(layer "In5.Cu")
		(net "P5E_PEX2_STN1_RX_DN<24>")
	)
	(segment
		(start 299.33519 -273.479514)
		(end 299.44949 -273.365214)
		(width 0.1143)
		(layer "In5.Cu")
		(net "P5E_PEX2_STN1_RX_DN<24>")
	)
	(segment
		(start 278.34971 -124.202444)
		(end 278.345392 -124.364242)
		(width 0.1651)
		(layer "In5.Cu")
		(net "P5E_PEX2_STN1_RX_DN<24>")
	)
	(segment
		(start 280.999438 -121.846594)
		(end 280.639774 -122.187716)
		(width 0.1651)
		(layer "In5.Cu")
		(net "P5E_PEX2_STN1_RX_DN<24>")
	)
	(segment
		(start 280.47823 -122.183652)
		(end 280.119074 -122.524266)
		(width 0.1651)
		(layer "In5.Cu")
		(net "P5E_PEX2_STN1_RX_DN<24>")
	)
	(segment
		(start 280.639774 -122.187716)
		(end 280.47823 -122.183652)
		(width 0.1651)
		(layer "In5.Cu")
		(net "P5E_PEX2_STN1_RX_DN<24>")
	)
	(segment
		(start 279.755092 -123.026932)
		(end 279.593548 -123.022868)
		(width 0.1651)
		(layer "In5.Cu")
		(net "P5E_PEX2_STN1_RX_DN<24>")
	)
	(segment
		(start 282.358592 -120.400064)
		(end 281.003756 -121.68505)
		(width 0.1651)
		(layer "In5.Cu")
		(net "P5E_PEX2_STN1_RX_DN<24>")
	)
	(segment
		(start 281.003756 -121.68505)
		(end 280.999438 -121.846594)
		(width 0.1651)
		(layer "In5.Cu")
		(net "P5E_PEX2_STN1_RX_DN<24>")
	)
	(segment
		(start 299.070014 -271.600168)
		(end 299.070014 -273.376136)
		(width 0.1143)
		(layer "In5.Cu")
		(net "P5E_PEX2_STN1_RX_DN<24>")
	)
	(segment
		(start 278.345392 -124.364242)
		(end 277.985728 -124.70511)
		(width 0.1651)
		(layer "In5.Cu")
		(net "P5E_PEX2_STN1_RX_DN<24>")
	)
	(segment
		(start 269.982188 -163.875974)
		(end 299.115734 -268.381226)
		(width 0.1651)
		(layer "In5.Cu")
		(net "P5E_PEX2_STN1_RX_DN<24>")
	)
	(segment
		(start 299.070014 -273.376136)
		(end 299.173392 -273.479514)
		(width 0.1143)
		(layer "In5.Cu")
		(net "P5E_PEX2_STN1_RX_DN<24>")
	)
	(segment
		(start 271.750282 -140.750036)
		(end 271.467326 -141.376908)
		(width 0.1651)
		(layer "In5.Cu")
		(net "P5E_PEX2_STN1_RX_DN<24>")
	)
	(segment
		(start 299.115734 -271.554448)
		(end 299.070014 -271.600168)
		(width 0.1143)
		(layer "In5.Cu")
		(net "P5E_PEX2_STN1_RX_DN<24>")
	)
	(segment
		(start 269.718282 -145.252186)
		(end 268.550644 -151.578564)
		(width 0.1651)
		(layer "In5.Cu")
		(net "P5E_PEX2_STN1_RX_DN<24>")
	)
	(segment
		(start 299.115734 -271.526)
		(end 299.115734 -271.554448)
		(width 0.1143)
		(layer "In5.Cu")
		(net "P5E_PEX2_STN1_RX_DN<24>")
	)
	(segment
		(start 276.546818 -126.073916)
		(end 276.580854 -126.231904)
		(width 0.1651)
		(layer "In5.Cu")
		(net "P5E_PEX2_STN1_RX_DN<24>")
	)
	(segment
		(start 279.593548 -123.022868)
		(end 279.234392 -123.363482)
		(width 0.1651)
		(layer "In5.Cu")
		(net "P5E_PEX2_STN1_RX_DN<24>")
	)
	(segment
		(start 284.299914 -119.795544)
		(end 282.358592 -120.400064)
		(width 0.1651)
		(layer "In5.Cu")
		(net "P5E_PEX2_STN1_RX_DN<24>")
	)
	(segment
		(start 299.115734 -268.381226)
		(end 299.115734 -271.526)
		(width 0.1651)
		(layer "In5.Cu")
		(net "P5E_PEX2_STN1_RX_DN<24>")
	)
	(segment
		(start 275.227034 -128.120648)
		(end 274.89531 -128.983232)
		(width 0.1651)
		(layer "In5.Cu")
		(net "P5E_PEX2_STN1_RX_DN<24>")
	)
	(segment
		(start 272.95729 -138.851132)
		(end 272.801588 -138.894312)
		(width 0.1651)
		(layer "In5.Cu")
		(net "P5E_PEX2_STN1_RX_DN<24>")
	)
	(segment
		(start 279.230074 -123.52528)
		(end 278.87041 -123.866148)
		(width 0.1651)
		(layer "In5.Cu")
		(net "P5E_PEX2_STN1_RX_DN<24>")
	)
	(segment
		(start 272.600674 -139.480798)
		(end 272.356326 -139.91209)
		(width 0.1651)
		(layer "In5.Cu")
		(net "P5E_PEX2_STN1_RX_DN<24>")
	)
	(segment
		(start 278.708866 -123.86183)
		(end 278.34971 -124.202444)
		(width 0.1651)
		(layer "In5.Cu")
		(net "P5E_PEX2_STN1_RX_DN<24>")
	)
	(segment
		(start 286.006032 -119.795544)
		(end 284.299914 -119.795544)
		(width 0.1651)
		(layer "In5.Cu")
		(net "P5E_PEX2_STN1_RX_DN<24>")
	)
	(segment
		(start 299.173392 -273.479514)
		(end 299.33519 -273.479514)
		(width 0.1143)
		(layer "In5.Cu")
		(net "P5E_PEX2_STN1_RX_DN<24>")
	)
	(segment
		(start 277.824184 -124.701046)
		(end 276.815042 -125.657864)
		(width 0.1651)
		(layer "In5.Cu")
		(net "P5E_PEX2_STN1_RX_DN<24>")
	)
	(segment
		(start 299.44949 -273.365214)
		(end 299.44949 -273.099784)
		(width 0.1143)
		(layer "In5.Cu")
		(net "P5E_PEX2_STN1_RX_DN<24>")
	)
	(segment
		(start 272.200624 -139.95527)
		(end 271.750282 -140.750036)
		(width 0.1651)
		(layer "In5.Cu")
		(net "P5E_PEX2_STN1_RX_DN<24>")
	)
	(segment
		(start 276.580854 -126.231904)
		(end 276.312122 -126.648464)
		(width 0.1651)
		(layer "In5.Cu")
		(net "P5E_PEX2_STN1_RX_DN<24>")
	)
	(segment
		(start 274.89531 -128.983232)
		(end 273.473164 -137.708894)
		(width 0.1651)
		(layer "In5.Cu")
		(net "P5E_PEX2_STN1_RX_DN<24>")
	)
	(segment
		(start 268.550644 -151.578564)
		(end 268.983206 -158.172912)
		(width 0.1651)
		(layer "In5.Cu")
		(net "P5E_PEX2_STN1_RX_DN<24>")
	)
	(segment
		(start 272.356326 -139.91209)
		(end 272.200624 -139.95527)
		(width 0.1651)
		(layer "In5.Cu")
		(net "P5E_PEX2_STN1_RX_DN<24>")
	)
	(segment
		(start 271.320768 -141.979904)
		(end 271.169384 -142.037054)
		(width 0.1651)
		(layer "In5.Cu")
		(net "P5E_PEX2_STN1_RX_DN<24>")
	)
	(segment
		(start 343.616026 -395.68374)
		(end 344.099642 -394.527786)
		(width 0.1651)
		(layer "In9.Cu")
		(net "P5E_PEX2_STN5_RX_DN<85>")
	)
	(segment
		(start 356.69855 -386.308092)
		(end 356.993444 -370.205508)
		(width 0.1651)
		(layer "In9.Cu")
		(net "P5E_PEX2_STN5_RX_DN<85>")
	)
	(segment
		(start 295.315894 -320.055494)
		(end 295.315894 -319.865248)
		(width 0.1651)
		(layer "In9.Cu")
		(net "P5E_PEX2_STN5_RX_DN<85>")
	)
	(segment
		(start 295.315894 -319.865248)
		(end 295.315894 -319.8368)
		(width 0.1143)
		(layer "In9.Cu")
		(net "P5E_PEX2_STN5_RX_DN<85>")
	)
	(segment
		(start 343.616026 -397.718534)
		(end 343.616026 -395.68374)
		(width 0.1651)
		(layer "In9.Cu")
		(net "P5E_PEX2_STN5_RX_DN<85>")
	)
	(segment
		(start 345.134946 -339.933534)
		(end 342.730836 -338.4423)
		(width 0.1651)
		(layer "In9.Cu")
		(net "P5E_PEX2_STN5_RX_DN<85>")
	)
	(segment
		(start 295.270174 -318.434212)
		(end 295.38422 -318.320166)
		(width 0.1143)
		(layer "In9.Cu")
		(net "P5E_PEX2_STN5_RX_DN<85>")
	)
	(segment
		(start 346.268548 -341.016082)
		(end 345.134946 -339.933534)
		(width 0.1651)
		(layer "In9.Cu")
		(net "P5E_PEX2_STN5_RX_DN<85>")
	)
	(segment
		(start 344.099642 -394.527786)
		(end 344.699336 -393.928346)
		(width 0.1651)
		(layer "In9.Cu")
		(net "P5E_PEX2_STN5_RX_DN<85>")
	)
	(segment
		(start 356.175056 -387.721094)
		(end 356.69855 -386.308092)
		(width 0.1651)
		(layer "In9.Cu")
		(net "P5E_PEX2_STN5_RX_DN<85>")
	)
	(segment
		(start 296.628566 -321.368166)
		(end 295.315894 -320.055494)
		(width 0.1651)
		(layer "In9.Cu")
		(net "P5E_PEX2_STN5_RX_DN<85>")
	)
	(segment
		(start 299.004228 -322.363084)
		(end 298.936156 -322.216018)
		(width 0.1651)
		(layer "In9.Cu")
		(net "P5E_PEX2_STN5_RX_DN<85>")
	)
	(segment
		(start 344.699336 -393.928346)
		(end 353.187762 -390.591548)
		(width 0.1651)
		(layer "In9.Cu")
		(net "P5E_PEX2_STN5_RX_DN<85>")
	)
	(segment
		(start 295.315894 -319.8368)
		(end 295.270174 -319.79108)
		(width 0.1143)
		(layer "In9.Cu")
		(net "P5E_PEX2_STN5_RX_DN<85>")
	)
	(segment
		(start 342.490044 -398.50822)
		(end 342.617044 -398.38122)
		(width 0.1651)
		(layer "In9.Cu")
		(net "P5E_PEX2_STN5_RX_DN<85>")
	)
	(segment
		(start 297.076622 -321.65417)
		(end 296.628566 -321.368166)
		(width 0.1651)
		(layer "In9.Cu")
		(net "P5E_PEX2_STN5_RX_DN<85>")
	)
	(segment
		(start 298.936156 -322.216018)
		(end 298.471082 -322.045076)
		(width 0.1651)
		(layer "In9.Cu")
		(net "P5E_PEX2_STN5_RX_DN<85>")
	)
	(segment
		(start 342.95334 -398.38122)
		(end 343.616026 -397.718534)
		(width 0.1651)
		(layer "In9.Cu")
		(net "P5E_PEX2_STN5_RX_DN<85>")
	)
	(segment
		(start 354.718874 -389.48233)
		(end 356.175056 -387.721094)
		(width 0.1651)
		(layer "In9.Cu")
		(net "P5E_PEX2_STN5_RX_DN<85>")
	)
	(segment
		(start 342.490044 -398.890236)
		(end 342.490044 -398.50822)
		(width 0.1651)
		(layer "In9.Cu")
		(net "P5E_PEX2_STN5_RX_DN<85>")
	)
	(segment
		(start 298.471082 -322.045076)
		(end 298.324524 -322.112894)
		(width 0.1651)
		(layer "In9.Cu")
		(net "P5E_PEX2_STN5_RX_DN<85>")
	)
	(segment
		(start 295.561004 -318.320166)
		(end 295.649904 -318.409066)
		(width 0.1143)
		(layer "In9.Cu")
		(net "P5E_PEX2_STN5_RX_DN<85>")
	)
	(segment
		(start 356.993444 -370.205508)
		(end 356.76586 -368.83594)
		(width 0.1651)
		(layer "In9.Cu")
		(net "P5E_PEX2_STN5_RX_DN<85>")
	)
	(segment
		(start 342.730836 -338.4423)
		(end 299.004228 -322.363084)
		(width 0.1651)
		(layer "In9.Cu")
		(net "P5E_PEX2_STN5_RX_DN<85>")
	)
	(segment
		(start 356.76586 -368.83594)
		(end 346.268548 -341.016082)
		(width 0.1651)
		(layer "In9.Cu")
		(net "P5E_PEX2_STN5_RX_DN<85>")
	)
	(segment
		(start 295.38422 -318.320166)
		(end 295.561004 -318.320166)
		(width 0.1143)
		(layer "In9.Cu")
		(net "P5E_PEX2_STN5_RX_DN<85>")
	)
	(segment
		(start 353.187762 -390.591548)
		(end 354.718874 -389.48233)
		(width 0.1651)
		(layer "In9.Cu")
		(net "P5E_PEX2_STN5_RX_DN<85>")
	)
	(segment
		(start 295.270174 -319.79108)
		(end 295.270174 -318.434212)
		(width 0.1143)
		(layer "In9.Cu")
		(net "P5E_PEX2_STN5_RX_DN<85>")
	)
	(segment
		(start 295.649904 -318.409066)
		(end 295.649904 -318.699896)
		(width 0.1143)
		(layer "In9.Cu")
		(net "P5E_PEX2_STN5_RX_DN<85>")
	)
	(segment
		(start 342.617044 -398.38122)
		(end 342.95334 -398.38122)
		(width 0.1651)
		(layer "In9.Cu")
		(net "P5E_PEX2_STN5_RX_DN<85>")
	)
	(segment
		(start 298.324524 -322.112894)
		(end 297.076622 -321.65417)
		(width 0.1651)
		(layer "In9.Cu")
		(net "P5E_PEX2_STN5_RX_DN<85>")
	)
	(segment
		(start 430.694846 -136.20115)
		(end 430.378616 -135.88492)
		(width 0.13462)
		(layer "F.Cu")
		(net "P5E_PEX3_STN0_TX_C_DP<7>")
	)
	(segment
		(start 422.06037 -136.04494)
		(end 421.557704 -136.04494)
		(width 0.13462)
		(layer "F.Cu")
		(net "P5E_PEX3_STN0_TX_C_DP<7>")
	)
	(segment
		(start 422.22039 -135.88492)
		(end 422.06037 -136.04494)
		(width 0.13462)
		(layer "F.Cu")
		(net "P5E_PEX3_STN0_TX_C_DP<7>")
	)
	(segment
		(start 430.378616 -135.88492)
		(end 422.22039 -135.88492)
		(width 0.13462)
		(layer "F.Cu")
		(net "P5E_PEX3_STN0_TX_C_DP<7>")
	)
	(segment
		(start 404.521162 -348.171516)
		(end 403.830282 -347.285056)
		(width 0.1651)
		(layer "In9.Cu")
		(net "P5E_PEX3_STN7_RX_DN<112>")
	)
	(segment
		(start 371.317266 -306.722272)
		(end 371.45468 -306.680362)
		(width 0.1651)
		(layer "In9.Cu")
		(net "P5E_PEX3_STN7_RX_DN<112>")
	)
	(segment
		(start 384.75412 -301.220124)
		(end 387.301994 -301.220124)
		(width 0.1143)
		(layer "In9.Cu")
		(net "P5E_PEX3_STN7_RX_DN<112>")
	)
	(segment
		(start 370.000022 -309.402734)
		(end 369.958112 -309.265066)
		(width 0.1651)
		(layer "In9.Cu")
		(net "P5E_PEX3_STN7_RX_DN<112>")
	)
	(segment
		(start 369.628674 -309.881524)
		(end 369.766342 -309.839614)
		(width 0.1651)
		(layer "In9.Cu")
		(net "P5E_PEX3_STN7_RX_DN<112>")
	)
	(segment
		(start 419.48989 -409.490164)
		(end 419.48989 -409.108148)
		(width 0.1651)
		(layer "In9.Cu")
		(net "P5E_PEX3_STN7_RX_DN<112>")
	)
	(segment
		(start 403.830282 -347.285056)
		(end 401.971764 -346.630498)
		(width 0.1651)
		(layer "In9.Cu")
		(net "P5E_PEX3_STN7_RX_DN<112>")
	)
	(segment
		(start 370.891816 -307.733446)
		(end 371.12575 -307.296566)
		(width 0.1651)
		(layer "In9.Cu")
		(net "P5E_PEX3_STN7_RX_DN<112>")
	)
	(segment
		(start 384.679952 -301.265844)
		(end 384.7084 -301.265844)
		(width 0.1143)
		(layer "In9.Cu")
		(net "P5E_PEX3_STN7_RX_DN<112>")
	)
	(segment
		(start 387.434328 -301.503842)
		(end 387.338316 -301.599854)
		(width 0.1143)
		(layer "In9.Cu")
		(net "P5E_PEX3_STN7_RX_DN<112>")
	)
	(segment
		(start 368.295174 -312.480198)
		(end 368.484658 -312.022744)
		(width 0.1651)
		(layer "In9.Cu")
		(net "P5E_PEX3_STN7_RX_DN<112>")
	)
	(segment
		(start 413.388302 -389.642604)
		(end 411.824932 -387.315456)
		(width 0.1651)
		(layer "In9.Cu")
		(net "P5E_PEX3_STN7_RX_DN<112>")
	)
	(segment
		(start 371.45468 -306.680362)
		(end 371.688614 -306.243482)
		(width 0.1651)
		(layer "In9.Cu")
		(net "P5E_PEX3_STN7_RX_DN<112>")
	)
	(segment
		(start 400.599148 -340.91499)
		(end 396.59433 -339.163406)
		(width 0.1651)
		(layer "In9.Cu")
		(net "P5E_PEX3_STN7_RX_DN<112>")
	)
	(segment
		(start 367.893346 -313.716162)
		(end 367.838228 -313.58332)
		(width 0.1651)
		(layer "In9.Cu")
		(net "P5E_PEX3_STN7_RX_DN<112>")
	)
	(segment
		(start 371.688614 -306.243482)
		(end 371.646704 -306.105814)
		(width 0.1651)
		(layer "In9.Cu")
		(net "P5E_PEX3_STN7_RX_DN<112>")
	)
	(segment
		(start 370.520976 -308.211982)
		(end 370.754402 -307.775356)
		(width 0.1651)
		(layer "In9.Cu")
		(net "P5E_PEX3_STN7_RX_DN<112>")
	)
	(segment
		(start 420.646606 -408.28976)
		(end 420.646606 -394.860272)
		(width 0.1651)
		(layer "In9.Cu")
		(net "P5E_PEX3_STN7_RX_DN<112>")
	)
	(segment
		(start 367.114074 -315.33211)
		(end 367.11382 -315.33211)
		(width 0.1651)
		(layer "In9.Cu")
		(net "P5E_PEX3_STN7_RX_DN<112>")
	)
	(segment
		(start 371.08384 -307.158898)
		(end 371.317266 -306.722272)
		(width 0.1651)
		(layer "In9.Cu")
		(net "P5E_PEX3_STN7_RX_DN<112>")
	)
	(segment
		(start 369.766342 -309.839614)
		(end 370.000022 -309.402734)
		(width 0.1651)
		(layer "In9.Cu")
		(net "P5E_PEX3_STN7_RX_DN<112>")
	)
	(segment
		(start 377.890278 -334.876902)
		(end 373.711216 -333.558896)
		(width 0.1651)
		(layer "In9.Cu")
		(net "P5E_PEX3_STN7_RX_DN<112>")
	)
	(segment
		(start 368.160554 -313.070748)
		(end 368.350292 -312.61304)
		(width 0.1651)
		(layer "In9.Cu")
		(net "P5E_PEX3_STN7_RX_DN<112>")
	)
	(segment
		(start 370.562886 -308.34965)
		(end 370.520976 -308.211982)
		(width 0.1651)
		(layer "In9.Cu")
		(net "P5E_PEX3_STN7_RX_DN<112>")
	)
	(segment
		(start 419.857174 -394.07084)
		(end 418.020754 -393.417552)
		(width 0.1651)
		(layer "In9.Cu")
		(net "P5E_PEX3_STN7_RX_DN<112>")
	)
	(segment
		(start 401.531582 -346.189554)
		(end 401.31873 -345.675712)
		(width 0.1651)
		(layer "In9.Cu")
		(net "P5E_PEX3_STN7_RX_DN<112>")
	)
	(segment
		(start 367.246662 -315.276992)
		(end 367.4364 -314.819284)
		(width 0.1651)
		(layer "In9.Cu")
		(net "P5E_PEX3_STN7_RX_DN<112>")
	)
	(segment
		(start 367.703608 -314.17387)
		(end 367.893346 -313.716162)
		(width 0.1651)
		(layer "In9.Cu")
		(net "P5E_PEX3_STN7_RX_DN<112>")
	)
	(segment
		(start 367.381282 -314.686442)
		(end 367.381536 -314.686442)
		(width 0.1651)
		(layer "In9.Cu")
		(net "P5E_PEX3_STN7_RX_DN<112>")
	)
	(segment
		(start 387.434328 -301.352458)
		(end 387.434328 -301.503842)
		(width 0.1143)
		(layer "In9.Cu")
		(net "P5E_PEX3_STN7_RX_DN<112>")
	)
	(segment
		(start 370.329206 -308.78653)
		(end 370.562886 -308.34965)
		(width 0.1651)
		(layer "In9.Cu")
		(net "P5E_PEX3_STN7_RX_DN<112>")
	)
	(segment
		(start 366.06734 -323.529198)
		(end 366.06734 -317.85941)
		(width 0.1651)
		(layer "In9.Cu")
		(net "P5E_PEX3_STN7_RX_DN<112>")
	)
	(segment
		(start 419.61689 -408.981148)
		(end 419.955218 -408.981148)
		(width 0.1651)
		(layer "In9.Cu")
		(net "P5E_PEX3_STN7_RX_DN<112>")
	)
	(segment
		(start 367.838482 -313.58332)
		(end 368.027712 -313.12612)
		(width 0.1651)
		(layer "In9.Cu")
		(net "P5E_PEX3_STN7_RX_DN<112>")
	)
	(segment
		(start 418.020754 -393.417552)
		(end 413.388302 -389.642604)
		(width 0.1651)
		(layer "In9.Cu")
		(net "P5E_PEX3_STN7_RX_DN<112>")
	)
	(segment
		(start 367.838228 -313.58332)
		(end 367.838482 -313.58332)
		(width 0.1651)
		(layer "In9.Cu")
		(net "P5E_PEX3_STN7_RX_DN<112>")
	)
	(segment
		(start 405.195278 -350.953832)
		(end 404.840694 -349.82277)
		(width 0.1651)
		(layer "In9.Cu")
		(net "P5E_PEX3_STN7_RX_DN<112>")
	)
	(segment
		(start 369.958112 -309.265066)
		(end 370.191538 -308.82844)
		(width 0.1651)
		(layer "In9.Cu")
		(net "P5E_PEX3_STN7_RX_DN<112>")
	)
	(segment
		(start 372.059454 -305.333654)
		(end 374.559322 -302.833532)
		(width 0.1651)
		(layer "In9.Cu")
		(net "P5E_PEX3_STN7_RX_DN<112>")
	)
	(segment
		(start 370.754402 -307.775356)
		(end 370.891816 -307.733446)
		(width 0.1651)
		(layer "In9.Cu")
		(net "P5E_PEX3_STN7_RX_DN<112>")
	)
	(segment
		(start 371.12575 -307.296566)
		(end 371.08384 -307.158898)
		(width 0.1651)
		(layer "In9.Cu")
		(net "P5E_PEX3_STN7_RX_DN<112>")
	)
	(segment
		(start 368.027712 -313.12612)
		(end 368.027712 -313.125866)
		(width 0.1651)
		(layer "In9.Cu")
		(net "P5E_PEX3_STN7_RX_DN<112>")
	)
	(segment
		(start 367.11382 -315.33211)
		(end 367.246662 -315.276992)
		(width 0.1651)
		(layer "In9.Cu")
		(net "P5E_PEX3_STN7_RX_DN<112>")
	)
	(segment
		(start 366.06734 -317.85941)
		(end 367.114074 -315.33211)
		(width 0.1651)
		(layer "In9.Cu")
		(net "P5E_PEX3_STN7_RX_DN<112>")
	)
	(segment
		(start 367.4364 -314.819284)
		(end 367.381282 -314.686442)
		(width 0.1651)
		(layer "In9.Cu")
		(net "P5E_PEX3_STN7_RX_DN<112>")
	)
	(segment
		(start 401.971764 -346.630498)
		(end 401.531582 -346.189554)
		(width 0.1651)
		(layer "In9.Cu")
		(net "P5E_PEX3_STN7_RX_DN<112>")
	)
	(segment
		(start 367.381536 -314.686442)
		(end 367.57102 -314.228988)
		(width 0.1651)
		(layer "In9.Cu")
		(net "P5E_PEX3_STN7_RX_DN<112>")
	)
	(segment
		(start 373.711216 -333.558896)
		(end 367.754154 -327.602088)
		(width 0.1651)
		(layer "In9.Cu")
		(net "P5E_PEX3_STN7_RX_DN<112>")
	)
	(segment
		(start 367.570766 -314.228988)
		(end 367.703608 -314.17387)
		(width 0.1651)
		(layer "In9.Cu")
		(net "P5E_PEX3_STN7_RX_DN<112>")
	)
	(segment
		(start 409.862274 -376.434096)
		(end 405.195278 -350.953832)
		(width 0.1651)
		(layer "In9.Cu")
		(net "P5E_PEX3_STN7_RX_DN<112>")
	)
	(segment
		(start 374.559322 -302.833532)
		(end 376.49277 -302.031908)
		(width 0.1651)
		(layer "In9.Cu")
		(net "P5E_PEX3_STN7_RX_DN<112>")
	)
	(segment
		(start 376.49277 -302.031908)
		(end 379.83541 -301.265844)
		(width 0.1651)
		(layer "In9.Cu")
		(net "P5E_PEX3_STN7_RX_DN<112>")
	)
	(segment
		(start 411.824932 -387.315456)
		(end 411.058106 -385.296918)
		(width 0.1651)
		(layer "In9.Cu")
		(net "P5E_PEX3_STN7_RX_DN<112>")
	)
	(segment
		(start 419.48989 -409.108148)
		(end 419.61689 -408.981148)
		(width 0.1651)
		(layer "In9.Cu")
		(net "P5E_PEX3_STN7_RX_DN<112>")
	)
	(segment
		(start 401.31873 -345.675712)
		(end 401.31873 -342.015064)
		(width 0.1651)
		(layer "In9.Cu")
		(net "P5E_PEX3_STN7_RX_DN<112>")
	)
	(segment
		(start 420.646606 -394.860272)
		(end 419.857174 -394.07084)
		(width 0.1651)
		(layer "In9.Cu")
		(net "P5E_PEX3_STN7_RX_DN<112>")
	)
	(segment
		(start 387.301994 -301.220124)
		(end 387.434328 -301.352458)
		(width 0.1143)
		(layer "In9.Cu")
		(net "P5E_PEX3_STN7_RX_DN<112>")
	)
	(segment
		(start 368.484658 -312.022744)
		(end 369.628674 -309.881524)
		(width 0.1651)
		(layer "In9.Cu")
		(net "P5E_PEX3_STN7_RX_DN<112>")
	)
	(segment
		(start 404.840694 -349.82277)
		(end 404.521162 -348.171516)
		(width 0.1651)
		(layer "In9.Cu")
		(net "P5E_PEX3_STN7_RX_DN<112>")
	)
	(segment
		(start 370.191538 -308.82844)
		(end 370.329206 -308.78653)
		(width 0.1651)
		(layer "In9.Cu")
		(net "P5E_PEX3_STN7_RX_DN<112>")
	)
	(segment
		(start 384.7084 -301.265844)
		(end 384.75412 -301.220124)
		(width 0.1143)
		(layer "In9.Cu")
		(net "P5E_PEX3_STN7_RX_DN<112>")
	)
	(segment
		(start 396.59433 -339.163406)
		(end 377.890278 -334.876902)
		(width 0.1651)
		(layer "In9.Cu")
		(net "P5E_PEX3_STN7_RX_DN<112>")
	)
	(segment
		(start 401.31873 -342.015064)
		(end 400.599148 -340.91499)
		(width 0.1651)
		(layer "In9.Cu")
		(net "P5E_PEX3_STN7_RX_DN<112>")
	)
	(segment
		(start 368.027712 -313.125866)
		(end 368.160554 -313.070748)
		(width 0.1651)
		(layer "In9.Cu")
		(net "P5E_PEX3_STN7_RX_DN<112>")
	)
	(segment
		(start 387.338316 -301.599854)
		(end 387.050026 -301.599854)
		(width 0.1143)
		(layer "In9.Cu")
		(net "P5E_PEX3_STN7_RX_DN<112>")
	)
	(segment
		(start 367.57102 -314.228988)
		(end 367.570766 -314.228988)
		(width 0.1651)
		(layer "In9.Cu")
		(net "P5E_PEX3_STN7_RX_DN<112>")
	)
	(segment
		(start 368.350292 -312.61304)
		(end 368.295174 -312.480198)
		(width 0.1651)
		(layer "In9.Cu")
		(net "P5E_PEX3_STN7_RX_DN<112>")
	)
	(segment
		(start 379.83541 -301.265844)
		(end 384.679952 -301.265844)
		(width 0.1651)
		(layer "In9.Cu")
		(net "P5E_PEX3_STN7_RX_DN<112>")
	)
	(segment
		(start 367.754154 -327.602088)
		(end 366.06734 -323.529198)
		(width 0.1651)
		(layer "In9.Cu")
		(net "P5E_PEX3_STN7_RX_DN<112>")
	)
	(segment
		(start 419.955218 -408.981148)
		(end 420.646606 -408.28976)
		(width 0.1651)
		(layer "In9.Cu")
		(net "P5E_PEX3_STN7_RX_DN<112>")
	)
	(segment
		(start 371.646704 -306.105814)
		(end 372.059454 -305.333654)
		(width 0.1651)
		(layer "In9.Cu")
		(net "P5E_PEX3_STN7_RX_DN<112>")
	)
	(segment
		(start 411.058106 -385.296918)
		(end 409.862274 -376.434096)
		(width 0.1651)
		(layer "In9.Cu")
		(net "P5E_PEX3_STN7_RX_DN<112>")
	)
	(segment
		(start 281.44343 -169.710862)
		(end 281.44343 -168.917874)
		(width 0.13208)
		(layer "F.Cu")
		(net "RST_HP_NIC4_N")
	)
	(segment
		(start 281.44343 -168.917874)
		(end 281.015948 -168.490392)
		(width 0.13208)
		(layer "F.Cu")
		(net "RST_HP_NIC4_N")
	)
	(segment
		(start 281.015948 -167.166544)
		(end 280.402284 -166.55288)
		(width 0.13208)
		(layer "F.Cu")
		(net "RST_HP_NIC4_N")
	)
	(segment
		(start 281.015948 -168.490392)
		(end 281.015948 -167.166544)
		(width 0.13208)
		(layer "F.Cu")
		(net "RST_HP_NIC4_N")
	)
	(segment
		(start 280.402284 -166.55288)
		(end 279.65908 -166.55288)
		(width 0.13208)
		(layer "F.Cu")
		(net "RST_HP_NIC4_N")
	)
	(segment
		(start 281.44343 -170.77944)
		(end 281.44343 -169.710862)
		(width 0.13208)
		(layer "F.Cu")
		(net "RST_HP_NIC4_N")
	)
	(via
		(at 281.44343 -169.710862)
		(size 0.508)
		(drill 0.254)
		(layers "F.Cu" "B.Cu")
		(net "RST_HP_NIC4_N")
	)
	(segment
		(start 421.557704 -137.24509)
		(end 427.20895 -137.24509)
		(width 0.13208)
		(layer "F.Cu")
		(net "PRSNTB0_NIC7_N")
	)
	(segment
		(start 428.039022 -137.24509)
		(end 428.43958 -137.645648)
		(width 0.13208)
		(layer "F.Cu")
		(net "PRSNTB0_NIC7_N")
	)
	(segment
		(start 428.43958 -138.661648)
		(end 428.43958 -137.645648)
		(width 0.13208)
		(layer "F.Cu")
		(net "PRSNTB0_NIC7_N")
	)
	(segment
		(start 427.20895 -137.24509)
		(end 428.039022 -137.24509)
		(width 0.13208)
		(layer "F.Cu")
		(net "PRSNTB0_NIC7_N")
	)
	(via
		(at 427.20895 -137.24509)
		(size 0.762)
		(drill 0.381)
		(layers "F.Cu" "B.Cu")
		(net "PRSNTB0_NIC7_N")
	)
	(segment
		(start 390.766554 -23.589996)
		(end 390.766554 -24.134572)
		(width 0.13208)
		(layer "F.Cu")
		(net "DUALPORT_N_SSD13")
	)
	(segment
		(start 390.766554 -24.134572)
		(end 391.12063 -24.488648)
		(width 0.13208)
		(layer "F.Cu")
		(net "DUALPORT_N_SSD13")
	)
	(segment
		(start 391.12063 -24.488648)
		(end 393.349734 -24.488648)
		(width 0.13208)
		(layer "F.Cu")
		(net "DUALPORT_N_SSD13")
	)
	(segment
		(start 389.56488 -23.589996)
		(end 390.766554 -23.589996)
		(width 0.13208)
		(layer "F.Cu")
		(net "DUALPORT_N_SSD13")
	)
	(segment
		(start 393.349734 -24.488648)
		(end 393.771628 -24.910542)
		(width 0.13208)
		(layer "F.Cu")
		(net "DUALPORT_N_SSD13")
	)
	(segment
		(start 394.787628 -24.942292)
		(end 393.771628 -24.942292)
		(width 0.13208)
		(layer "F.Cu")
		(net "DUALPORT_N_SSD13")
	)
	(segment
		(start 393.771628 -24.910542)
		(end 393.771628 -24.942292)
		(width 0.13208)
		(layer "F.Cu")
		(net "DUALPORT_N_SSD13")
	)
	(via
		(at 390.766554 -23.589996)
		(size 0.508)
		(drill 0.254)
		(layers "F.Cu" "B.Cu")
		(net "DUALPORT_N_SSD13")
	)
	(segment
		(start 161.491422 -107.082082)
		(end 161.654236 -107.244896)
		(width 0.13462)
		(layer "F.Cu")
		(net "P5E_PEX1_STN1_TX_C_DN<20>")
	)
	(segment
		(start 155.968192 -107.082082)
		(end 161.491422 -107.082082)
		(width 0.13462)
		(layer "F.Cu")
		(net "P5E_PEX1_STN1_TX_C_DN<20>")
	)
	(segment
		(start 161.654236 -107.244896)
		(end 162.14217 -107.244896)
		(width 0.13462)
		(layer "F.Cu")
		(net "P5E_PEX1_STN1_TX_C_DN<20>")
	)
	(segment
		(start 155.647136 -107.403138)
		(end 155.968192 -107.082082)
		(width 0.13462)
		(layer "F.Cu")
		(net "P5E_PEX1_STN1_TX_C_DN<20>")
	)
	(segment
		(start 112.431068 -351.316798)
		(end 112.431068 -350.685354)
		(width 0.13462)
		(layer "F.Cu")
		(net "P5E_PEX1_STN6_TX_C_DN<103>")
	)
	(segment
		(start 112.431068 -350.685354)
		(end 112.751108 -350.365314)
		(width 0.13462)
		(layer "F.Cu")
		(net "P5E_PEX1_STN6_TX_C_DN<103>")
	)
	(segment
		(start 112.725708 -351.611438)
		(end 112.431068 -351.316798)
		(width 0.13462)
		(layer "F.Cu")
		(net "P5E_PEX1_STN6_TX_C_DN<103>")
	)
	(segment
		(start 116.03736 -382.980946)
		(end 116.386102 -382.980946)
		(width 0.1651)
		(layer "In7.Cu")
		(net "P5E_PEX1_STN6_TX_C_DN<103>")
	)
	(segment
		(start 116.386102 -382.980946)
		(end 116.96954 -382.397508)
		(width 0.1651)
		(layer "In7.Cu")
		(net "P5E_PEX1_STN6_TX_C_DN<103>")
	)
	(segment
		(start 115.910106 -383.490216)
		(end 115.910106 -383.1082)
		(width 0.1651)
		(layer "In7.Cu")
		(net "P5E_PEX1_STN6_TX_C_DN<103>")
	)
	(segment
		(start 116.96954 -382.397508)
		(end 116.96954 -369.5573)
		(width 0.1651)
		(layer "In7.Cu")
		(net "P5E_PEX1_STN6_TX_C_DN<103>")
	)
	(segment
		(start 116.96954 -369.5573)
		(end 116.842794 -368.821208)
		(width 0.1651)
		(layer "In7.Cu")
		(net "P5E_PEX1_STN6_TX_C_DN<103>")
	)
	(segment
		(start 115.910106 -383.1082)
		(end 116.03736 -382.980946)
		(width 0.1651)
		(layer "In7.Cu")
		(net "P5E_PEX1_STN6_TX_C_DN<103>")
	)
	(segment
		(start 112.434878 -357.927656)
		(end 112.434878 -351.902268)
		(width 0.1651)
		(layer "In7.Cu")
		(net "P5E_PEX1_STN6_TX_C_DN<103>")
	)
	(segment
		(start 112.434878 -351.902268)
		(end 112.725708 -351.611438)
		(width 0.1651)
		(layer "In7.Cu")
		(net "P5E_PEX1_STN6_TX_C_DN<103>")
	)
	(segment
		(start 116.842794 -368.821208)
		(end 114.679222 -364.871762)
		(width 0.1651)
		(layer "In7.Cu")
		(net "P5E_PEX1_STN6_TX_C_DN<103>")
	)
	(segment
		(start 114.679222 -364.871762)
		(end 112.6998 -359.3846)
		(width 0.1651)
		(layer "In7.Cu")
		(net "P5E_PEX1_STN6_TX_C_DN<103>")
	)
	(segment
		(start 112.6998 -359.3846)
		(end 112.434878 -357.927656)
		(width 0.1651)
		(layer "In7.Cu")
		(net "P5E_PEX1_STN6_TX_C_DN<103>")
	)
	(segment
		(start 285.99511 -103.47452)
		(end 283.490416 -103.47452)
		(width 0.13462)
		(layer "F.Cu")
		(net "P5E_PEX2_STN1_RX_DN<18>")
	)
	(segment
		(start 283.319982 -103.644954)
		(end 282.842462 -103.644954)
		(width 0.13462)
		(layer "F.Cu")
		(net "P5E_PEX2_STN1_RX_DN<18>")
	)
	(segment
		(start 283.490416 -103.47452)
		(end 283.319982 -103.644954)
		(width 0.13462)
		(layer "F.Cu")
		(net "P5E_PEX2_STN1_RX_DN<18>")
	)
	(segment
		(start 286.296862 -103.776272)
		(end 285.99511 -103.47452)
		(width 0.13462)
		(layer "F.Cu")
		(net "P5E_PEX2_STN1_RX_DN<18>")
	)
	(segment
		(start 293.749476 -273.365214)
		(end 293.749476 -273.099784)
		(width 0.1143)
		(layer "In5.Cu")
		(net "P5E_PEX2_STN1_RX_DN<18>")
	)
	(segment
		(start 274.450302 -109.905038)
		(end 266.272772 -118.469918)
		(width 0.1651)
		(layer "In5.Cu")
		(net "P5E_PEX2_STN1_RX_DN<18>")
	)
	(segment
		(start 275.453856 -109.01934)
		(end 275.292312 -109.02315)
		(width 0.1651)
		(layer "In5.Cu")
		(net "P5E_PEX2_STN1_RX_DN<18>")
	)
	(segment
		(start 278.146002 -106.591862)
		(end 277.102316 -107.127294)
		(width 0.1651)
		(layer "In5.Cu")
		(net "P5E_PEX2_STN1_RX_DN<18>")
	)
	(segment
		(start 274.954238 -109.542834)
		(end 274.611846 -109.901228)
		(width 0.1651)
		(layer "In5.Cu")
		(net "P5E_PEX2_STN1_RX_DN<18>")
	)
	(segment
		(start 278.790146 -106.261408)
		(end 278.74087 -106.415078)
		(width 0.1651)
		(layer "In5.Cu")
		(net "P5E_PEX2_STN1_RX_DN<18>")
	)
	(segment
		(start 276.638258 -107.779058)
		(end 276.295866 -108.137452)
		(width 0.1651)
		(layer "In5.Cu")
		(net "P5E_PEX2_STN1_RX_DN<18>")
	)
	(segment
		(start 280.31567 -105.47858)
		(end 279.875234 -105.70464)
		(width 0.1651)
		(layer "In5.Cu")
		(net "P5E_PEX2_STN1_RX_DN<18>")
	)
	(segment
		(start 276.295866 -108.137452)
		(end 276.134322 -108.141262)
		(width 0.1651)
		(layer "In5.Cu")
		(net "P5E_PEX2_STN1_RX_DN<18>")
	)
	(segment
		(start 279.825704 -105.85831)
		(end 279.38476 -106.084878)
		(width 0.1651)
		(layer "In5.Cu")
		(net "P5E_PEX2_STN1_RX_DN<18>")
	)
	(segment
		(start 274.611846 -109.901228)
		(end 274.450302 -109.905038)
		(width 0.1651)
		(layer "In5.Cu")
		(net "P5E_PEX2_STN1_RX_DN<18>")
	)
	(segment
		(start 263.141968 -158.75762)
		(end 264.263632 -165.241986)
		(width 0.1651)
		(layer "In5.Cu")
		(net "P5E_PEX2_STN1_RX_DN<18>")
	)
	(segment
		(start 283.129482 -104.034336)
		(end 283.129482 -104.034082)
		(width 0.1651)
		(layer "In5.Cu")
		(net "P5E_PEX2_STN1_RX_DN<18>")
	)
	(segment
		(start 284.199076 -103.485442)
		(end 283.129482 -104.034336)
		(width 0.1651)
		(layer "In5.Cu")
		(net "P5E_PEX2_STN1_RX_DN<18>")
	)
	(segment
		(start 276.134322 -108.141262)
		(end 275.792438 -108.499402)
		(width 0.1651)
		(layer "In5.Cu")
		(net "P5E_PEX2_STN1_RX_DN<18>")
	)
	(segment
		(start 293.37 -271.600168)
		(end 293.37 -273.376136)
		(width 0.1143)
		(layer "In5.Cu")
		(net "P5E_PEX2_STN1_RX_DN<18>")
	)
	(segment
		(start 266.272772 -118.469918)
		(end 265.314176 -120.46712)
		(width 0.1651)
		(layer "In5.Cu")
		(net "P5E_PEX2_STN1_RX_DN<18>")
	)
	(segment
		(start 281.554428 -104.971342)
		(end 281.400504 -104.921812)
		(width 0.1651)
		(layer "In5.Cu")
		(net "P5E_PEX2_STN1_RX_DN<18>")
	)
	(segment
		(start 293.41572 -271.526)
		(end 293.41572 -271.554448)
		(width 0.1143)
		(layer "In5.Cu")
		(net "P5E_PEX2_STN1_RX_DN<18>")
	)
	(segment
		(start 264.263632 -165.241986)
		(end 293.41572 -269.734284)
		(width 0.1651)
		(layer "In5.Cu")
		(net "P5E_PEX2_STN1_RX_DN<18>")
	)
	(segment
		(start 275.796248 -108.660946)
		(end 275.453856 -109.01934)
		(width 0.1651)
		(layer "In5.Cu")
		(net "P5E_PEX2_STN1_RX_DN<18>")
	)
	(segment
		(start 280.910538 -105.301796)
		(end 280.469594 -105.52811)
		(width 0.1651)
		(layer "In5.Cu")
		(net "P5E_PEX2_STN1_RX_DN<18>")
	)
	(segment
		(start 275.292312 -109.02315)
		(end 274.950428 -109.38129)
		(width 0.1651)
		(layer "In5.Cu")
		(net "P5E_PEX2_STN1_RX_DN<18>")
	)
	(segment
		(start 279.875234 -105.70464)
		(end 279.825704 -105.85831)
		(width 0.1651)
		(layer "In5.Cu")
		(net "P5E_PEX2_STN1_RX_DN<18>")
	)
	(segment
		(start 283.129482 -104.034082)
		(end 283.080206 -104.188006)
		(width 0.1651)
		(layer "In5.Cu")
		(net "P5E_PEX2_STN1_RX_DN<18>")
	)
	(segment
		(start 281.995372 -104.745028)
		(end 281.554428 -104.971342)
		(width 0.1651)
		(layer "In5.Cu")
		(net "P5E_PEX2_STN1_RX_DN<18>")
	)
	(segment
		(start 279.38476 -106.084878)
		(end 279.230836 -106.035348)
		(width 0.1651)
		(layer "In5.Cu")
		(net "P5E_PEX2_STN1_RX_DN<18>")
	)
	(segment
		(start 283.080206 -104.188006)
		(end 282.639262 -104.414574)
		(width 0.1651)
		(layer "In5.Cu")
		(net "P5E_PEX2_STN1_RX_DN<18>")
	)
	(segment
		(start 278.74087 -106.415078)
		(end 278.299672 -106.641392)
		(width 0.1651)
		(layer "In5.Cu")
		(net "P5E_PEX2_STN1_RX_DN<18>")
	)
	(segment
		(start 293.635176 -273.479514)
		(end 293.749476 -273.365214)
		(width 0.1143)
		(layer "In5.Cu")
		(net "P5E_PEX2_STN1_RX_DN<18>")
	)
	(segment
		(start 286.296862 -103.776272)
		(end 286.006032 -103.485442)
		(width 0.1651)
		(layer "In5.Cu")
		(net "P5E_PEX2_STN1_RX_DN<18>")
	)
	(segment
		(start 282.485338 -104.365044)
		(end 282.044902 -104.591104)
		(width 0.1651)
		(layer "In5.Cu")
		(net "P5E_PEX2_STN1_RX_DN<18>")
	)
	(segment
		(start 286.006032 -103.485442)
		(end 284.199076 -103.485442)
		(width 0.1651)
		(layer "In5.Cu")
		(net "P5E_PEX2_STN1_RX_DN<18>")
	)
	(segment
		(start 281.400504 -104.921812)
		(end 280.960068 -105.147872)
		(width 0.1651)
		(layer "In5.Cu")
		(net "P5E_PEX2_STN1_RX_DN<18>")
	)
	(segment
		(start 275.792438 -108.499402)
		(end 275.796248 -108.660946)
		(width 0.1651)
		(layer "In5.Cu")
		(net "P5E_PEX2_STN1_RX_DN<18>")
	)
	(segment
		(start 280.960068 -105.147872)
		(end 280.910538 -105.301796)
		(width 0.1651)
		(layer "In5.Cu")
		(net "P5E_PEX2_STN1_RX_DN<18>")
	)
	(segment
		(start 265.314176 -120.46712)
		(end 264.186162 -126.637796)
		(width 0.1651)
		(layer "In5.Cu")
		(net "P5E_PEX2_STN1_RX_DN<18>")
	)
	(segment
		(start 278.299672 -106.641392)
		(end 278.146002 -106.591862)
		(width 0.1651)
		(layer "In5.Cu")
		(net "P5E_PEX2_STN1_RX_DN<18>")
	)
	(segment
		(start 282.044902 -104.591104)
		(end 281.995372 -104.745028)
		(width 0.1651)
		(layer "In5.Cu")
		(net "P5E_PEX2_STN1_RX_DN<18>")
	)
	(segment
		(start 262.584438 -150.341584)
		(end 263.141968 -158.75762)
		(width 0.1651)
		(layer "In5.Cu")
		(net "P5E_PEX2_STN1_RX_DN<18>")
	)
	(segment
		(start 277.102316 -107.127294)
		(end 276.634448 -107.61726)
		(width 0.1651)
		(layer "In5.Cu")
		(net "P5E_PEX2_STN1_RX_DN<18>")
	)
	(segment
		(start 293.41572 -269.734284)
		(end 293.41572 -271.526)
		(width 0.1651)
		(layer "In5.Cu")
		(net "P5E_PEX2_STN1_RX_DN<18>")
	)
	(segment
		(start 276.634448 -107.61726)
		(end 276.638258 -107.779058)
		(width 0.1651)
		(layer "In5.Cu")
		(net "P5E_PEX2_STN1_RX_DN<18>")
	)
	(segment
		(start 264.186162 -126.637796)
		(end 262.584438 -150.341584)
		(width 0.1651)
		(layer "In5.Cu")
		(net "P5E_PEX2_STN1_RX_DN<18>")
	)
	(segment
		(start 293.37 -273.376136)
		(end 293.473378 -273.479514)
		(width 0.1143)
		(layer "In5.Cu")
		(net "P5E_PEX2_STN1_RX_DN<18>")
	)
	(segment
		(start 293.473378 -273.479514)
		(end 293.635176 -273.479514)
		(width 0.1143)
		(layer "In5.Cu")
		(net "P5E_PEX2_STN1_RX_DN<18>")
	)
	(segment
		(start 274.950428 -109.38129)
		(end 274.954238 -109.542834)
		(width 0.1651)
		(layer "In5.Cu")
		(net "P5E_PEX2_STN1_RX_DN<18>")
	)
	(segment
		(start 279.230836 -106.035348)
		(end 278.790146 -106.261408)
		(width 0.1651)
		(layer "In5.Cu")
		(net "P5E_PEX2_STN1_RX_DN<18>")
	)
	(segment
		(start 280.469594 -105.52811)
		(end 280.31567 -105.47858)
		(width 0.1651)
		(layer "In5.Cu")
		(net "P5E_PEX2_STN1_RX_DN<18>")
	)
	(segment
		(start 293.41572 -271.554448)
		(end 293.37 -271.600168)
		(width 0.1143)
		(layer "In5.Cu")
		(net "P5E_PEX2_STN1_RX_DN<18>")
	)
	(segment
		(start 282.639262 -104.414574)
		(end 282.485338 -104.365044)
		(width 0.1651)
		(layer "In5.Cu")
		(net "P5E_PEX2_STN1_RX_DN<18>")
	)
	(segment
		(start 413.50311 -135.313674)
		(end 413.800036 -135.6106)
		(width 0.13462)
		(layer "F.Cu")
		(net "P5E_PEX3_STN0_RX_DN<7>")
	)
	(segment
		(start 416.314382 -135.6106)
		(end 416.47999 -135.444992)
		(width 0.13462)
		(layer "F.Cu")
		(net "P5E_PEX3_STN0_RX_DN<7>")
	)
	(segment
		(start 413.800036 -135.6106)
		(end 416.314382 -135.6106)
		(width 0.13462)
		(layer "F.Cu")
		(net "P5E_PEX3_STN0_RX_DN<7>")
	)
	(segment
		(start 416.47999 -135.444992)
		(end 416.95751 -135.444992)
		(width 0.13462)
		(layer "F.Cu")
		(net "P5E_PEX3_STN0_RX_DN<7>")
	)
	(segment
		(start 430.484534 -281.649932)
		(end 430.749964 -281.649932)
		(width 0.1143)
		(layer "In5.Cu")
		(net "P5E_PEX3_STN0_RX_DN<7>")
	)
	(segment
		(start 424.12031 -145.28546)
		(end 424.120564 -145.286476)
		(width 0.1651)
		(layer "In5.Cu")
		(net "P5E_PEX3_STN0_RX_DN<7>")
	)
	(segment
		(start 424.391074 -146.474434)
		(end 424.391328 -146.47545)
		(width 0.1651)
		(layer "In5.Cu")
		(net "P5E_PEX3_STN0_RX_DN<7>")
	)
	(segment
		(start 421.987472 -139.464288)
		(end 421.987472 -139.870434)
		(width 0.1651)
		(layer "In5.Cu")
		(net "P5E_PEX3_STN0_RX_DN<7>")
	)
	(segment
		(start 432.97221 -280.46807)
		(end 432.698398 -281.107134)
		(width 0.1651)
		(layer "In5.Cu")
		(net "P5E_PEX3_STN0_RX_DN<7>")
	)
	(segment
		(start 432.17592 -281.270202)
		(end 430.473866 -281.270202)
		(width 0.1143)
		(layer "In5.Cu")
		(net "P5E_PEX3_STN0_RX_DN<7>")
	)
	(segment
		(start 433.060602 -276.308312)
		(end 432.97221 -280.46807)
		(width 0.1651)
		(layer "In5.Cu")
		(net "P5E_PEX3_STN0_RX_DN<7>")
	)
	(segment
		(start 430.370234 -281.373834)
		(end 430.370234 -281.535632)
		(width 0.1143)
		(layer "In5.Cu")
		(net "P5E_PEX3_STN0_RX_DN<7>")
	)
	(segment
		(start 424.120564 -145.286476)
		(end 424.230292 -145.768314)
		(width 0.1651)
		(layer "In5.Cu")
		(net "P5E_PEX3_STN0_RX_DN<7>")
	)
	(segment
		(start 424.230292 -145.768314)
		(end 424.230546 -145.76933)
		(width 0.1651)
		(layer "In5.Cu")
		(net "P5E_PEX3_STN0_RX_DN<7>")
	)
	(segment
		(start 423.849546 -144.096486)
		(end 423.8498 -144.097502)
		(width 0.1651)
		(layer "In5.Cu")
		(net "P5E_PEX3_STN0_RX_DN<7>")
	)
	(segment
		(start 415.773362 -135.604504)
		(end 420.266622 -137.43178)
		(width 0.1651)
		(layer "In5.Cu")
		(net "P5E_PEX3_STN0_RX_DN<7>")
	)
	(segment
		(start 420.266622 -137.43178)
		(end 421.569642 -138.752834)
		(width 0.1651)
		(layer "In5.Cu")
		(net "P5E_PEX3_STN0_RX_DN<7>")
	)
	(segment
		(start 421.987472 -139.870434)
		(end 422.263824 -140.537438)
		(width 0.1651)
		(layer "In5.Cu")
		(net "P5E_PEX3_STN0_RX_DN<7>")
	)
	(segment
		(start 423.305732 -141.708886)
		(end 423.849546 -144.096486)
		(width 0.1651)
		(layer "In5.Cu")
		(net "P5E_PEX3_STN0_RX_DN<7>")
	)
	(segment
		(start 424.230546 -145.76933)
		(end 424.391074 -146.474434)
		(width 0.1651)
		(layer "In5.Cu")
		(net "P5E_PEX3_STN0_RX_DN<7>")
	)
	(segment
		(start 431.134266 -264.832846)
		(end 431.78476 -269.423388)
		(width 0.1651)
		(layer "In5.Cu")
		(net "P5E_PEX3_STN0_RX_DN<7>")
	)
	(segment
		(start 423.8498 -144.097502)
		(end 423.959528 -144.57934)
		(width 0.1651)
		(layer "In5.Cu")
		(net "P5E_PEX3_STN0_RX_DN<7>")
	)
	(segment
		(start 423.959528 -144.57934)
		(end 423.959782 -144.580356)
		(width 0.1651)
		(layer "In5.Cu")
		(net "P5E_PEX3_STN0_RX_DN<7>")
	)
	(segment
		(start 427.57979 -160.476184)
		(end 431.134266 -264.832846)
		(width 0.1651)
		(layer "In5.Cu")
		(net "P5E_PEX3_STN0_RX_DN<7>")
	)
	(segment
		(start 432.698398 -281.107134)
		(end 432.48834 -281.315922)
		(width 0.1651)
		(layer "In5.Cu")
		(net "P5E_PEX3_STN0_RX_DN<7>")
	)
	(segment
		(start 427.573694 -160.449006)
		(end 427.57979 -160.455102)
		(width 0.1651)
		(layer "In5.Cu")
		(net "P5E_PEX3_STN0_RX_DN<7>")
	)
	(segment
		(start 423.121074 -141.394688)
		(end 423.305478 -141.708632)
		(width 0.1651)
		(layer "In5.Cu")
		(net "P5E_PEX3_STN0_RX_DN<7>")
	)
	(segment
		(start 427.57979 -160.455102)
		(end 427.57979 -160.476184)
		(width 0.1651)
		(layer "In5.Cu")
		(net "P5E_PEX3_STN0_RX_DN<7>")
	)
	(segment
		(start 430.473866 -281.270202)
		(end 430.370234 -281.373834)
		(width 0.1143)
		(layer "In5.Cu")
		(net "P5E_PEX3_STN0_RX_DN<7>")
	)
	(segment
		(start 423.305478 -141.708632)
		(end 423.305478 -141.708378)
		(width 0.1651)
		(layer "In5.Cu")
		(net "P5E_PEX3_STN0_RX_DN<7>")
	)
	(segment
		(start 432.48834 -281.315922)
		(end 432.250088 -281.315922)
		(width 0.1651)
		(layer "In5.Cu")
		(net "P5E_PEX3_STN0_RX_DN<7>")
	)
	(segment
		(start 432.250088 -281.315922)
		(end 432.22164 -281.315922)
		(width 0.1143)
		(layer "In5.Cu")
		(net "P5E_PEX3_STN0_RX_DN<7>")
	)
	(segment
		(start 432.22164 -281.315922)
		(end 432.17592 -281.270202)
		(width 0.1143)
		(layer "In5.Cu")
		(net "P5E_PEX3_STN0_RX_DN<7>")
	)
	(segment
		(start 413.79394 -135.604504)
		(end 415.773362 -135.604504)
		(width 0.1651)
		(layer "In5.Cu")
		(net "P5E_PEX3_STN0_RX_DN<7>")
	)
	(segment
		(start 430.370234 -281.535632)
		(end 430.484534 -281.649932)
		(width 0.1143)
		(layer "In5.Cu")
		(net "P5E_PEX3_STN0_RX_DN<7>")
	)
	(segment
		(start 422.263824 -140.537438)
		(end 423.121074 -141.394688)
		(width 0.1651)
		(layer "In5.Cu")
		(net "P5E_PEX3_STN0_RX_DN<7>")
	)
	(segment
		(start 421.569642 -138.752834)
		(end 421.987472 -139.464288)
		(width 0.1651)
		(layer "In5.Cu")
		(net "P5E_PEX3_STN0_RX_DN<7>")
	)
	(segment
		(start 423.305478 -141.708378)
		(end 423.305732 -141.708886)
		(width 0.1651)
		(layer "In5.Cu")
		(net "P5E_PEX3_STN0_RX_DN<7>")
	)
	(segment
		(start 423.959782 -144.580356)
		(end 424.12031 -145.28546)
		(width 0.1651)
		(layer "In5.Cu")
		(net "P5E_PEX3_STN0_RX_DN<7>")
	)
	(segment
		(start 431.78476 -269.423388)
		(end 433.060602 -276.308312)
		(width 0.1651)
		(layer "In5.Cu")
		(net "P5E_PEX3_STN0_RX_DN<7>")
	)
	(segment
		(start 413.50311 -135.313674)
		(end 413.79394 -135.604504)
		(width 0.1651)
		(layer "In5.Cu")
		(net "P5E_PEX3_STN0_RX_DN<7>")
	)
	(segment
		(start 424.391328 -146.47545)
		(end 427.573694 -160.449006)
		(width 0.1651)
		(layer "In5.Cu")
		(net "P5E_PEX3_STN0_RX_DN<7>")
	)
	(segment
		(start 390.849866 -318.040766)
		(end 390.849866 -317.749936)
		(width 0.1143)
		(layer "In9.Cu")
		(net "P5E_PEX3_STN7_RX_DP<127>")
	)
	(segment
		(start 437.46801 -366.334294)
		(end 437.759856 -365.934498)
		(width 0.1651)
		(layer "In9.Cu")
		(net "P5E_PEX3_STN7_RX_DP<127>")
	)
	(segment
		(start 435.238398 -383.79908)
		(end 435.77256 -383.264918)
		(width 0.1651)
		(layer "In9.Cu")
		(net "P5E_PEX3_STN7_RX_DP<127>")
	)
	(segment
		(start 434.88991 -383.290064)
		(end 434.88991 -383.67208)
		(width 0.1651)
		(layer "In9.Cu")
		(net "P5E_PEX3_STN7_RX_DP<127>")
	)
	(segment
		(start 438.433972 -365.011208)
		(end 438.417462 -364.904528)
		(width 0.1651)
		(layer "In9.Cu")
		(net "P5E_PEX3_STN7_RX_DP<127>")
	)
	(segment
		(start 437.743346 -365.827818)
		(end 438.0357 -365.427514)
		(width 0.1651)
		(layer "In9.Cu")
		(net "P5E_PEX3_STN7_RX_DP<127>")
	)
	(segment
		(start 390.51865 -318.129666)
		(end 390.760966 -318.129666)
		(width 0.1143)
		(layer "In9.Cu")
		(net "P5E_PEX3_STN7_RX_DP<127>")
	)
	(segment
		(start 435.01691 -383.79908)
		(end 435.238398 -383.79908)
		(width 0.1651)
		(layer "In9.Cu")
		(net "P5E_PEX3_STN7_RX_DP<127>")
	)
	(segment
		(start 438.709816 -364.504224)
		(end 438.816242 -364.487714)
		(width 0.1651)
		(layer "In9.Cu")
		(net "P5E_PEX3_STN7_RX_DP<127>")
	)
	(segment
		(start 443.360302 -341.450422)
		(end 442.749686 -340.626192)
		(width 0.1651)
		(layer "In9.Cu")
		(net "P5E_PEX3_STN7_RX_DP<127>")
	)
	(segment
		(start 438.142126 -365.411004)
		(end 438.433972 -365.011208)
		(width 0.1651)
		(layer "In9.Cu")
		(net "P5E_PEX3_STN7_RX_DP<127>")
	)
	(segment
		(start 443.36462 -357.76281)
		(end 443.360302 -341.450422)
		(width 0.1651)
		(layer "In9.Cu")
		(net "P5E_PEX3_STN7_RX_DP<127>")
	)
	(segment
		(start 437.36133 -366.351058)
		(end 437.46801 -366.334294)
		(width 0.1651)
		(layer "In9.Cu")
		(net "P5E_PEX3_STN7_RX_DP<127>")
	)
	(segment
		(start 390.279636 -318.36868)
		(end 390.51865 -318.129666)
		(width 0.1143)
		(layer "In9.Cu")
		(net "P5E_PEX3_STN7_RX_DP<127>")
	)
	(segment
		(start 434.88991 -383.67208)
		(end 435.01691 -383.79908)
		(width 0.1651)
		(layer "In9.Cu")
		(net "P5E_PEX3_STN7_RX_DP<127>")
	)
	(segment
		(start 438.417462 -364.904528)
		(end 438.709816 -364.504224)
		(width 0.1651)
		(layer "In9.Cu")
		(net "P5E_PEX3_STN7_RX_DP<127>")
	)
	(segment
		(start 438.816242 -364.487714)
		(end 442.660024 -359.222294)
		(width 0.1651)
		(layer "In9.Cu")
		(net "P5E_PEX3_STN7_RX_DP<127>")
	)
	(segment
		(start 442.749686 -340.626192)
		(end 439.607452 -339.666834)
		(width 0.1651)
		(layer "In9.Cu")
		(net "P5E_PEX3_STN7_RX_DP<127>")
	)
	(segment
		(start 436.386478 -367.815622)
		(end 437.08574 -366.857788)
		(width 0.1651)
		(layer "In9.Cu")
		(net "P5E_PEX3_STN7_RX_DP<127>")
	)
	(segment
		(start 390.233916 -319.865248)
		(end 390.279636 -319.819528)
		(width 0.1143)
		(layer "In9.Cu")
		(net "P5E_PEX3_STN7_RX_DP<127>")
	)
	(segment
		(start 439.607452 -339.666834)
		(end 421.132762 -332.745588)
		(width 0.1651)
		(layer "In9.Cu")
		(net "P5E_PEX3_STN7_RX_DP<127>")
	)
	(segment
		(start 435.77256 -369.697762)
		(end 436.386478 -367.815622)
		(width 0.1651)
		(layer "In9.Cu")
		(net "P5E_PEX3_STN7_RX_DP<127>")
	)
	(segment
		(start 437.06923 -366.751362)
		(end 437.36133 -366.351058)
		(width 0.1651)
		(layer "In9.Cu")
		(net "P5E_PEX3_STN7_RX_DP<127>")
	)
	(segment
		(start 442.660024 -359.222294)
		(end 443.36462 -357.76281)
		(width 0.1651)
		(layer "In9.Cu")
		(net "P5E_PEX3_STN7_RX_DP<127>")
	)
	(segment
		(start 390.233916 -320.53657)
		(end 390.233916 -319.893696)
		(width 0.1651)
		(layer "In9.Cu")
		(net "P5E_PEX3_STN7_RX_DP<127>")
	)
	(segment
		(start 421.132762 -332.745588)
		(end 406.919176 -326.042782)
		(width 0.1651)
		(layer "In9.Cu")
		(net "P5E_PEX3_STN7_RX_DP<127>")
	)
	(segment
		(start 390.279636 -319.819528)
		(end 390.279636 -318.36868)
		(width 0.1143)
		(layer "In9.Cu")
		(net "P5E_PEX3_STN7_RX_DP<127>")
	)
	(segment
		(start 438.0357 -365.427514)
		(end 438.142126 -365.411004)
		(width 0.1651)
		(layer "In9.Cu")
		(net "P5E_PEX3_STN7_RX_DP<127>")
	)
	(segment
		(start 390.760966 -318.129666)
		(end 390.849866 -318.040766)
		(width 0.1143)
		(layer "In9.Cu")
		(net "P5E_PEX3_STN7_RX_DP<127>")
	)
	(segment
		(start 406.919176 -326.042782)
		(end 390.562338 -320.864992)
		(width 0.1651)
		(layer "In9.Cu")
		(net "P5E_PEX3_STN7_RX_DP<127>")
	)
	(segment
		(start 435.77256 -383.264918)
		(end 435.77256 -369.697762)
		(width 0.1651)
		(layer "In9.Cu")
		(net "P5E_PEX3_STN7_RX_DP<127>")
	)
	(segment
		(start 390.562338 -320.864992)
		(end 390.233916 -320.53657)
		(width 0.1651)
		(layer "In9.Cu")
		(net "P5E_PEX3_STN7_RX_DP<127>")
	)
	(segment
		(start 390.233916 -319.893696)
		(end 390.233916 -319.865248)
		(width 0.1143)
		(layer "In9.Cu")
		(net "P5E_PEX3_STN7_RX_DP<127>")
	)
	(segment
		(start 437.759856 -365.934498)
		(end 437.743346 -365.827818)
		(width 0.1651)
		(layer "In9.Cu")
		(net "P5E_PEX3_STN7_RX_DP<127>")
	)
	(segment
		(start 437.08574 -366.857788)
		(end 437.06923 -366.751362)
		(width 0.1651)
		(layer "In9.Cu")
		(net "P5E_PEX3_STN7_RX_DP<127>")
	)
	(segment
		(start 358.964992 -24.790146)
		(end 357.31958 -24.790146)
		(width 0.13208)
		(layer "F.Cu")
		(net "PU_CLKREQ12")
	)
	(segment
		(start 356.471982 -24.807418)
		(end 357.302308 -24.807418)
		(width 0.13208)
		(layer "F.Cu")
		(net "PU_CLKREQ12")
	)
	(segment
		(start 357.31958 -24.790146)
		(end 357.302308 -24.807418)
		(width 0.13208)
		(layer "F.Cu")
		(net "PU_CLKREQ12")
	)
	(via
		(at 357.302308 -24.807418)
		(size 0.508)
		(drill 0.254)
		(layers "F.Cu" "B.Cu")
		(net "PU_CLKREQ12")
	)
	(segment
		(start 161.491422 -99.607878)
		(end 161.654236 -99.445064)
		(width 0.13462)
		(layer "F.Cu")
		(net "P5E_PEX1_STN1_TX_C_DP<16>")
	)
	(segment
		(start 155.96616 -99.607878)
		(end 161.491422 -99.607878)
		(width 0.13462)
		(layer "F.Cu")
		(net "P5E_PEX1_STN1_TX_C_DP<16>")
	)
	(segment
		(start 155.647136 -99.288854)
		(end 155.96616 -99.607878)
		(width 0.13462)
		(layer "F.Cu")
		(net "P5E_PEX1_STN1_TX_C_DP<16>")
	)
	(segment
		(start 161.654236 -99.445064)
		(end 162.14217 -99.445064)
		(width 0.13462)
		(layer "F.Cu")
		(net "P5E_PEX1_STN1_TX_C_DP<16>")
	)
	(segment
		(start 277.742904 -101.244908)
		(end 278.242268 -101.244908)
		(width 0.13462)
		(layer "F.Cu")
		(net "P5E_PEX2_STN1_TX_C_DN<17>")
	)
	(segment
		(start 269.714726 -101.095302)
		(end 270.033496 -101.414072)
		(width 0.13462)
		(layer "F.Cu")
		(net "P5E_PEX2_STN1_TX_C_DN<17>")
	)
	(segment
		(start 277.57374 -101.414072)
		(end 277.742904 -101.244908)
		(width 0.13462)
		(layer "F.Cu")
		(net "P5E_PEX2_STN1_TX_C_DN<17>")
	)
	(segment
		(start 270.033496 -101.414072)
		(end 277.57374 -101.414072)
		(width 0.13462)
		(layer "F.Cu")
		(net "P5E_PEX2_STN1_TX_C_DN<17>")
	)
	(segment
		(start 422.218612 -152.1968)
		(end 422.06037 -152.355042)
		(width 0.13462)
		(layer "F.Cu")
		(net "P5E_PEX3_STN0_TX_C_DP<13>")
	)
	(segment
		(start 422.06037 -152.355042)
		(end 421.557704 -152.355042)
		(width 0.13462)
		(layer "F.Cu")
		(net "P5E_PEX3_STN0_TX_C_DP<13>")
	)
	(segment
		(start 430.694846 -152.511252)
		(end 430.380394 -152.1968)
		(width 0.13462)
		(layer "F.Cu")
		(net "P5E_PEX3_STN0_TX_C_DP<13>")
	)
	(segment
		(start 430.380394 -152.1968)
		(end 422.218612 -152.1968)
		(width 0.13462)
		(layer "F.Cu")
		(net "P5E_PEX3_STN0_TX_C_DP<13>")
	)
	(segment
		(start 371.709696 -313.055508)
		(end 371.847364 -313.013598)
		(width 0.1651)
		(layer "In9.Cu")
		(net "P5E_PEX3_STN7_RX_DN<115>")
	)
	(segment
		(start 369.405154 -317.80988)
		(end 369.537996 -317.755016)
		(width 0.1651)
		(layer "In9.Cu")
		(net "P5E_PEX3_STN7_RX_DN<115>")
	)
	(segment
		(start 408.213052 -349.105982)
		(end 406.131268 -340.89467)
		(width 0.1651)
		(layer "In9.Cu")
		(net "P5E_PEX3_STN7_RX_DN<115>")
	)
	(segment
		(start 426.089826 -410.207968)
		(end 426.216826 -410.080968)
		(width 0.1651)
		(layer "In9.Cu")
		(net "P5E_PEX3_STN7_RX_DN<115>")
	)
	(segment
		(start 374.040908 -308.69382)
		(end 377.596908 -305.137312)
		(width 0.1651)
		(layer "In9.Cu")
		(net "P5E_PEX3_STN7_RX_DN<115>")
	)
	(segment
		(start 408.332178 -351.884488)
		(end 408.213052 -349.105982)
		(width 0.1651)
		(layer "In9.Cu")
		(net "P5E_PEX3_STN7_RX_DN<115>")
	)
	(segment
		(start 397.511778 -336.277712)
		(end 377.887484 -331.775562)
		(width 0.1651)
		(layer "In9.Cu")
		(net "P5E_PEX3_STN7_RX_DN<115>")
	)
	(segment
		(start 379.64491 -304.720244)
		(end 381.211328 -304.115724)
		(width 0.1651)
		(layer "In9.Cu")
		(net "P5E_PEX3_STN7_RX_DN<115>")
	)
	(segment
		(start 418.805614 -390.355074)
		(end 415.627566 -387.765798)
		(width 0.1651)
		(layer "In9.Cu")
		(net "P5E_PEX3_STN7_RX_DN<115>")
	)
	(segment
		(start 371.146832 -314.108592)
		(end 371.2845 -314.066682)
		(width 0.1651)
		(layer "In9.Cu")
		(net "P5E_PEX3_STN7_RX_DN<115>")
	)
	(segment
		(start 415.627566 -387.765798)
		(end 414.527492 -386.128768)
		(width 0.1651)
		(layer "In9.Cu")
		(net "P5E_PEX3_STN7_RX_DN<115>")
	)
	(segment
		(start 373.398288 -309.896256)
		(end 373.535702 -309.8546)
		(width 0.1651)
		(layer "In9.Cu")
		(net "P5E_PEX3_STN7_RX_DN<115>")
	)
	(segment
		(start 385.534154 -304.202338)
		(end 385.534154 -304.353722)
		(width 0.1143)
		(layer "In9.Cu")
		(net "P5E_PEX3_STN7_RX_DN<115>")
	)
	(segment
		(start 373.535702 -309.8546)
		(end 373.769382 -309.417466)
		(width 0.1651)
		(layer "In9.Cu")
		(net "P5E_PEX3_STN7_RX_DN<115>")
	)
	(segment
		(start 373.164862 -310.332882)
		(end 373.398288 -309.896256)
		(width 0.1651)
		(layer "In9.Cu")
		(net "P5E_PEX3_STN7_RX_DN<115>")
	)
	(segment
		(start 424.123358 -392.247374)
		(end 418.805614 -390.355074)
		(width 0.1651)
		(layer "In9.Cu")
		(net "P5E_PEX3_STN7_RX_DN<115>")
	)
	(segment
		(start 377.596908 -305.137312)
		(end 379.64491 -304.720244)
		(width 0.1651)
		(layer "In9.Cu")
		(net "P5E_PEX3_STN7_RX_DN<115>")
	)
	(segment
		(start 372.039134 -312.43905)
		(end 372.039388 -312.43905)
		(width 0.1651)
		(layer "In9.Cu")
		(net "P5E_PEX3_STN7_RX_DN<115>")
	)
	(segment
		(start 369.537996 -317.755016)
		(end 369.727734 -317.297054)
		(width 0.1651)
		(layer "In9.Cu")
		(net "P5E_PEX3_STN7_RX_DN<115>")
	)
	(segment
		(start 370.721636 -315.12002)
		(end 370.955316 -314.682886)
		(width 0.1651)
		(layer "In9.Cu")
		(net "P5E_PEX3_STN7_RX_DN<115>")
	)
	(segment
		(start 372.081044 -312.576718)
		(end 372.039134 -312.43905)
		(width 0.1651)
		(layer "In9.Cu")
		(net "P5E_PEX3_STN7_RX_DN<115>")
	)
	(segment
		(start 426.555154 -410.080968)
		(end 427.254162 -409.38196)
		(width 0.1651)
		(layer "In9.Cu")
		(net "P5E_PEX3_STN7_RX_DN<115>")
	)
	(segment
		(start 406.131268 -340.89467)
		(end 404.989792 -339.547962)
		(width 0.1651)
		(layer "In9.Cu")
		(net "P5E_PEX3_STN7_RX_DN<115>")
	)
	(segment
		(start 372.601998 -311.385966)
		(end 372.835424 -310.94934)
		(width 0.1651)
		(layer "In9.Cu")
		(net "P5E_PEX3_STN7_RX_DN<115>")
	)
	(segment
		(start 414.527492 -386.128768)
		(end 414.00349 -384.749548)
		(width 0.1651)
		(layer "In9.Cu")
		(net "P5E_PEX3_STN7_RX_DN<115>")
	)
	(segment
		(start 385.534154 -304.353722)
		(end 385.438142 -304.449734)
		(width 0.1143)
		(layer "In9.Cu")
		(net "P5E_PEX3_STN7_RX_DN<115>")
	)
	(segment
		(start 383.96672 -304.070004)
		(end 385.40182 -304.070004)
		(width 0.1143)
		(layer "In9.Cu")
		(net "P5E_PEX3_STN7_RX_DN<115>")
	)
	(segment
		(start 426.821092 -394.945108)
		(end 424.123358 -392.247374)
		(width 0.1651)
		(layer "In9.Cu")
		(net "P5E_PEX3_STN7_RX_DN<115>")
	)
	(segment
		(start 373.206772 -310.47055)
		(end 373.164862 -310.332882)
		(width 0.1651)
		(layer "In9.Cu")
		(net "P5E_PEX3_STN7_RX_DN<115>")
	)
	(segment
		(start 369.727734 -317.297054)
		(end 369.67287 -317.164466)
		(width 0.1651)
		(layer "In9.Cu")
		(net "P5E_PEX3_STN7_RX_DN<115>")
	)
	(segment
		(start 371.47627 -313.492134)
		(end 371.476524 -313.492134)
		(width 0.1651)
		(layer "In9.Cu")
		(net "P5E_PEX3_STN7_RX_DN<115>")
	)
	(segment
		(start 381.211328 -304.115724)
		(end 383.892552 -304.115724)
		(width 0.1651)
		(layer "In9.Cu")
		(net "P5E_PEX3_STN7_RX_DN<115>")
	)
	(segment
		(start 427.254162 -395.990826)
		(end 426.821092 -394.945108)
		(width 0.1651)
		(layer "In9.Cu")
		(net "P5E_PEX3_STN7_RX_DN<115>")
	)
	(segment
		(start 385.438142 -304.449734)
		(end 385.149852 -304.449734)
		(width 0.1143)
		(layer "In9.Cu")
		(net "P5E_PEX3_STN7_RX_DN<115>")
	)
	(segment
		(start 372.409974 -311.960514)
		(end 372.643908 -311.523634)
		(width 0.1651)
		(layer "In9.Cu")
		(net "P5E_PEX3_STN7_RX_DN<115>")
	)
	(segment
		(start 371.476524 -313.492134)
		(end 371.70995 -313.055508)
		(width 0.1651)
		(layer "In9.Cu")
		(net "P5E_PEX3_STN7_RX_DN<115>")
	)
	(segment
		(start 370.91366 -314.545218)
		(end 371.147086 -314.108592)
		(width 0.1651)
		(layer "In9.Cu")
		(net "P5E_PEX3_STN7_RX_DN<115>")
	)
	(segment
		(start 372.972838 -310.90743)
		(end 373.206772 -310.47055)
		(width 0.1651)
		(layer "In9.Cu")
		(net "P5E_PEX3_STN7_RX_DN<115>")
	)
	(segment
		(start 426.089826 -410.589984)
		(end 426.089826 -410.207968)
		(width 0.1651)
		(layer "In9.Cu")
		(net "P5E_PEX3_STN7_RX_DN<115>")
	)
	(segment
		(start 368.967512 -318.866774)
		(end 369.405408 -317.80988)
		(width 0.1651)
		(layer "In9.Cu")
		(net "P5E_PEX3_STN7_RX_DN<115>")
	)
	(segment
		(start 373.727726 -309.279798)
		(end 374.040908 -308.69382)
		(width 0.1651)
		(layer "In9.Cu")
		(net "P5E_PEX3_STN7_RX_DN<115>")
	)
	(segment
		(start 426.216826 -410.080968)
		(end 426.555154 -410.080968)
		(width 0.1651)
		(layer "In9.Cu")
		(net "P5E_PEX3_STN7_RX_DN<115>")
	)
	(segment
		(start 370.583968 -315.161676)
		(end 370.721636 -315.12002)
		(width 0.1651)
		(layer "In9.Cu")
		(net "P5E_PEX3_STN7_RX_DN<115>")
	)
	(segment
		(start 372.27256 -312.002424)
		(end 372.409974 -311.960514)
		(width 0.1651)
		(layer "In9.Cu")
		(net "P5E_PEX3_STN7_RX_DN<115>")
	)
	(segment
		(start 369.67287 -317.164466)
		(end 370.22024 -315.84265)
		(width 0.1651)
		(layer "In9.Cu")
		(net "P5E_PEX3_STN7_RX_DN<115>")
	)
	(segment
		(start 369.405408 -317.80988)
		(end 369.405154 -317.80988)
		(width 0.1651)
		(layer "In9.Cu")
		(net "P5E_PEX3_STN7_RX_DN<115>")
	)
	(segment
		(start 370.22024 -315.84265)
		(end 370.584222 -315.161676)
		(width 0.1651)
		(layer "In9.Cu")
		(net "P5E_PEX3_STN7_RX_DN<115>")
	)
	(segment
		(start 370.913406 -314.545218)
		(end 370.91366 -314.545218)
		(width 0.1651)
		(layer "In9.Cu")
		(net "P5E_PEX3_STN7_RX_DN<115>")
	)
	(segment
		(start 414.00349 -384.749548)
		(end 413.028384 -377.524518)
		(width 0.1651)
		(layer "In9.Cu")
		(net "P5E_PEX3_STN7_RX_DN<115>")
	)
	(segment
		(start 413.028384 -377.524518)
		(end 408.332178 -351.884488)
		(width 0.1651)
		(layer "In9.Cu")
		(net "P5E_PEX3_STN7_RX_DN<115>")
	)
	(segment
		(start 373.769382 -309.417466)
		(end 373.727726 -309.279798)
		(width 0.1651)
		(layer "In9.Cu")
		(net "P5E_PEX3_STN7_RX_DN<115>")
	)
	(segment
		(start 383.892552 -304.115724)
		(end 383.921 -304.115724)
		(width 0.1143)
		(layer "In9.Cu")
		(net "P5E_PEX3_STN7_RX_DN<115>")
	)
	(segment
		(start 372.27256 -312.002678)
		(end 372.27256 -312.002424)
		(width 0.1651)
		(layer "In9.Cu")
		(net "P5E_PEX3_STN7_RX_DN<115>")
	)
	(segment
		(start 372.039388 -312.43905)
		(end 372.27256 -312.002678)
		(width 0.1651)
		(layer "In9.Cu")
		(net "P5E_PEX3_STN7_RX_DN<115>")
	)
	(segment
		(start 371.70995 -313.055508)
		(end 371.709696 -313.055508)
		(width 0.1651)
		(layer "In9.Cu")
		(net "P5E_PEX3_STN7_RX_DN<115>")
	)
	(segment
		(start 371.147086 -314.108592)
		(end 371.146832 -314.108592)
		(width 0.1651)
		(layer "In9.Cu")
		(net "P5E_PEX3_STN7_RX_DN<115>")
	)
	(segment
		(start 372.643908 -311.523634)
		(end 372.601998 -311.385966)
		(width 0.1651)
		(layer "In9.Cu")
		(net "P5E_PEX3_STN7_RX_DN<115>")
	)
	(segment
		(start 383.921 -304.115724)
		(end 383.96672 -304.070004)
		(width 0.1143)
		(layer "In9.Cu")
		(net "P5E_PEX3_STN7_RX_DN<115>")
	)
	(segment
		(start 372.835424 -310.94934)
		(end 372.972838 -310.90743)
		(width 0.1651)
		(layer "In9.Cu")
		(net "P5E_PEX3_STN7_RX_DN<115>")
	)
	(segment
		(start 404.989792 -339.547962)
		(end 397.511778 -336.277712)
		(width 0.1651)
		(layer "In9.Cu")
		(net "P5E_PEX3_STN7_RX_DN<115>")
	)
	(segment
		(start 385.40182 -304.070004)
		(end 385.534154 -304.202338)
		(width 0.1143)
		(layer "In9.Cu")
		(net "P5E_PEX3_STN7_RX_DN<115>")
	)
	(segment
		(start 371.51818 -313.629802)
		(end 371.47627 -313.492134)
		(width 0.1651)
		(layer "In9.Cu")
		(net "P5E_PEX3_STN7_RX_DN<115>")
	)
	(segment
		(start 370.955316 -314.682886)
		(end 370.913406 -314.545218)
		(width 0.1651)
		(layer "In9.Cu")
		(net "P5E_PEX3_STN7_RX_DN<115>")
	)
	(segment
		(start 377.887484 -331.775562)
		(end 375.117106 -330.901802)
		(width 0.1651)
		(layer "In9.Cu")
		(net "P5E_PEX3_STN7_RX_DN<115>")
	)
	(segment
		(start 370.211096 -325.996046)
		(end 368.967512 -322.993512)
		(width 0.1651)
		(layer "In9.Cu")
		(net "P5E_PEX3_STN7_RX_DN<115>")
	)
	(segment
		(start 370.584222 -315.161676)
		(end 370.583968 -315.161676)
		(width 0.1651)
		(layer "In9.Cu")
		(net "P5E_PEX3_STN7_RX_DN<115>")
	)
	(segment
		(start 371.2845 -314.066682)
		(end 371.51818 -313.629802)
		(width 0.1651)
		(layer "In9.Cu")
		(net "P5E_PEX3_STN7_RX_DN<115>")
	)
	(segment
		(start 375.117106 -330.901802)
		(end 370.211096 -325.996046)
		(width 0.1651)
		(layer "In9.Cu")
		(net "P5E_PEX3_STN7_RX_DN<115>")
	)
	(segment
		(start 368.967512 -322.993512)
		(end 368.967512 -318.866774)
		(width 0.1651)
		(layer "In9.Cu")
		(net "P5E_PEX3_STN7_RX_DN<115>")
	)
	(segment
		(start 371.847364 -313.013598)
		(end 372.081044 -312.576718)
		(width 0.1651)
		(layer "In9.Cu")
		(net "P5E_PEX3_STN7_RX_DN<115>")
	)
	(segment
		(start 427.254162 -409.38196)
		(end 427.254162 -395.990826)
		(width 0.1651)
		(layer "In9.Cu")
		(net "P5E_PEX3_STN7_RX_DN<115>")
	)
	(segment
		(start 284.24505 -175.182276)
		(end 284.18917 -175.238156)
		(width 0.13208)
		(layer "F.Cu")
		(net "HP_NIC4_PWRGD_R")
	)
	(segment
		(start 284.368748 -173.49597)
		(end 285.045912 -173.49597)
		(width 0.13208)
		(layer "F.Cu")
		(net "HP_NIC4_PWRGD_R")
	)
	(segment
		(start 285.045912 -173.49597)
		(end 285.045912 -174.058834)
		(width 0.13208)
		(layer "F.Cu")
		(net "HP_NIC4_PWRGD_R")
	)
	(segment
		(start 283.34335 -173.229524)
		(end 284.102302 -173.229524)
		(width 0.13208)
		(layer "F.Cu")
		(net "HP_NIC4_PWRGD_R")
	)
	(segment
		(start 284.18917 -175.238156)
		(end 284.18917 -176.478438)
		(width 0.13208)
		(layer "F.Cu")
		(net "HP_NIC4_PWRGD_R")
	)
	(segment
		(start 284.102302 -173.229524)
		(end 284.368748 -173.49597)
		(width 0.13208)
		(layer "F.Cu")
		(net "HP_NIC4_PWRGD_R")
	)
	(segment
		(start 284.24505 -174.859696)
		(end 284.24505 -175.182276)
		(width 0.13208)
		(layer "F.Cu")
		(net "HP_NIC4_PWRGD_R")
	)
	(segment
		(start 285.045912 -174.058834)
		(end 284.24505 -174.859696)
		(width 0.13208)
		(layer "F.Cu")
		(net "HP_NIC4_PWRGD_R")
	)
	(via
		(at 285.045912 -173.49597)
		(size 0.762)
		(drill 0.381)
		(layers "F.Cu" "B.Cu")
		(net "HP_NIC4_PWRGD_R")
	)
	(segment
		(start 363.564932 -23.589996)
		(end 364.766606 -23.589996)
		(width 0.13208)
		(layer "F.Cu")
		(net "DUALPORT_N_SSD12")
	)
	(segment
		(start 364.766606 -24.134572)
		(end 365.120682 -24.488648)
		(width 0.13208)
		(layer "F.Cu")
		(net "DUALPORT_N_SSD12")
	)
	(segment
		(start 365.120682 -24.488648)
		(end 367.349786 -24.488648)
		(width 0.13208)
		(layer "F.Cu")
		(net "DUALPORT_N_SSD12")
	)
	(segment
		(start 364.766606 -23.589996)
		(end 364.766606 -24.134572)
		(width 0.13208)
		(layer "F.Cu")
		(net "DUALPORT_N_SSD12")
	)
	(segment
		(start 367.349786 -24.488648)
		(end 367.77168 -24.910542)
		(width 0.13208)
		(layer "F.Cu")
		(net "DUALPORT_N_SSD12")
	)
	(segment
		(start 368.78768 -24.942292)
		(end 367.77168 -24.942292)
		(width 0.13208)
		(layer "F.Cu")
		(net "DUALPORT_N_SSD12")
	)
	(segment
		(start 367.77168 -24.910542)
		(end 367.77168 -24.942292)
		(width 0.13208)
		(layer "F.Cu")
		(net "DUALPORT_N_SSD12")
	)
	(via
		(at 364.766606 -23.589996)
		(size 0.508)
		(drill 0.254)
		(layers "F.Cu" "B.Cu")
		(net "DUALPORT_N_SSD12")
	)
	(segment
		(start 169.901616 -130.727958)
		(end 170.196764 -130.43281)
		(width 0.13462)
		(layer "F.Cu")
		(net "P5E_PEX1_STN1_RX_DP<28>")
	)
	(segment
		(start 167.393112 -130.727958)
		(end 169.901616 -130.727958)
		(width 0.13462)
		(layer "F.Cu")
		(net "P5E_PEX1_STN1_RX_DP<28>")
	)
	(segment
		(start 167.230298 -130.565144)
		(end 167.393112 -130.727958)
		(width 0.13462)
		(layer "F.Cu")
		(net "P5E_PEX1_STN1_RX_DP<28>")
	)
	(segment
		(start 166.742364 -130.565144)
		(end 167.230298 -130.565144)
		(width 0.13462)
		(layer "F.Cu")
		(net "P5E_PEX1_STN1_RX_DP<28>")
	)
	(segment
		(start 157.457902 -156.926026)
		(end 156.859478 -147.65528)
		(width 0.1651)
		(layer "In5.Cu")
		(net "P5E_PEX1_STN1_RX_DP<28>")
	)
	(segment
		(start 167.1828 -130.72364)
		(end 169.905934 -130.72364)
		(width 0.1651)
		(layer "In5.Cu")
		(net "P5E_PEX1_STN1_RX_DP<28>")
	)
	(segment
		(start 186.53379 -271.802352)
		(end 186.53379 -271.773904)
		(width 0.1143)
		(layer "In5.Cu")
		(net "P5E_PEX1_STN1_RX_DP<28>")
	)
	(segment
		(start 186.57951 -273.45513)
		(end 186.57951 -271.848072)
		(width 0.1143)
		(layer "In5.Cu")
		(net "P5E_PEX1_STN1_RX_DP<28>")
	)
	(segment
		(start 187.035186 -273.670014)
		(end 186.794394 -273.670014)
		(width 0.1143)
		(layer "In5.Cu")
		(net "P5E_PEX1_STN1_RX_DP<28>")
	)
	(segment
		(start 165.16858 -133.177026)
		(end 167.1828 -130.72364)
		(width 0.1651)
		(layer "In5.Cu")
		(net "P5E_PEX1_STN1_RX_DP<28>")
	)
	(segment
		(start 186.57951 -271.848072)
		(end 186.53379 -271.802352)
		(width 0.1143)
		(layer "In5.Cu")
		(net "P5E_PEX1_STN1_RX_DP<28>")
	)
	(segment
		(start 164.26434 -135.360156)
		(end 165.16858 -133.177026)
		(width 0.1651)
		(layer "In5.Cu")
		(net "P5E_PEX1_STN1_RX_DP<28>")
	)
	(segment
		(start 157.054296 -146.953732)
		(end 158.771082 -144.635982)
		(width 0.1651)
		(layer "In5.Cu")
		(net "P5E_PEX1_STN1_RX_DP<28>")
	)
	(segment
		(start 163.814506 -140.292328)
		(end 163.814506 -136.446514)
		(width 0.1651)
		(layer "In5.Cu")
		(net "P5E_PEX1_STN1_RX_DP<28>")
	)
	(segment
		(start 186.53379 -267.64234)
		(end 158.216092 -161.20364)
		(width 0.1651)
		(layer "In5.Cu")
		(net "P5E_PEX1_STN1_RX_DP<28>")
	)
	(segment
		(start 158.771082 -144.635982)
		(end 159.891984 -143.514318)
		(width 0.1651)
		(layer "In5.Cu")
		(net "P5E_PEX1_STN1_RX_DP<28>")
	)
	(segment
		(start 163.636198 -140.723366)
		(end 163.814506 -140.292328)
		(width 0.1651)
		(layer "In5.Cu")
		(net "P5E_PEX1_STN1_RX_DP<28>")
	)
	(segment
		(start 187.14974 -274.049744)
		(end 187.14974 -273.784568)
		(width 0.1143)
		(layer "In5.Cu")
		(net "P5E_PEX1_STN1_RX_DP<28>")
	)
	(segment
		(start 159.891984 -143.514318)
		(end 162.765486 -141.594078)
		(width 0.1651)
		(layer "In5.Cu")
		(net "P5E_PEX1_STN1_RX_DP<28>")
	)
	(segment
		(start 186.794394 -273.670014)
		(end 186.57951 -273.45513)
		(width 0.1143)
		(layer "In5.Cu")
		(net "P5E_PEX1_STN1_RX_DP<28>")
	)
	(segment
		(start 187.14974 -273.784568)
		(end 187.035186 -273.670014)
		(width 0.1143)
		(layer "In5.Cu")
		(net "P5E_PEX1_STN1_RX_DP<28>")
	)
	(segment
		(start 156.859478 -147.65528)
		(end 157.054296 -146.953732)
		(width 0.1651)
		(layer "In5.Cu")
		(net "P5E_PEX1_STN1_RX_DP<28>")
	)
	(segment
		(start 158.216092 -161.20364)
		(end 157.457902 -156.926026)
		(width 0.1651)
		(layer "In5.Cu")
		(net "P5E_PEX1_STN1_RX_DP<28>")
	)
	(segment
		(start 169.905934 -130.72364)
		(end 170.196764 -130.43281)
		(width 0.1651)
		(layer "In5.Cu")
		(net "P5E_PEX1_STN1_RX_DP<28>")
	)
	(segment
		(start 162.765486 -141.594078)
		(end 163.636198 -140.723366)
		(width 0.1651)
		(layer "In5.Cu")
		(net "P5E_PEX1_STN1_RX_DP<28>")
	)
	(segment
		(start 186.53379 -271.773904)
		(end 186.53379 -267.64234)
		(width 0.1651)
		(layer "In5.Cu")
		(net "P5E_PEX1_STN1_RX_DP<28>")
	)
	(segment
		(start 164.264086 -135.36041)
		(end 164.26434 -135.360156)
		(width 0.1651)
		(layer "In5.Cu")
		(net "P5E_PEX1_STN1_RX_DP<28>")
	)
	(segment
		(start 163.814506 -136.446514)
		(end 164.264086 -135.36041)
		(width 0.1651)
		(layer "In5.Cu")
		(net "P5E_PEX1_STN1_RX_DP<28>")
	)
	(segment
		(start 121.188988 -345.465146)
		(end 121.483628 -345.170506)
		(width 0.13462)
		(layer "F.Cu")
		(net "P5E_PEX1_STN6_TX_C_DP<99>")
	)
	(segment
		(start 121.483628 -344.539062)
		(end 121.163588 -344.219022)
		(width 0.13462)
		(layer "F.Cu")
		(net "P5E_PEX1_STN6_TX_C_DP<99>")
	)
	(segment
		(start 121.483628 -345.170506)
		(end 121.483628 -344.539062)
		(width 0.13462)
		(layer "F.Cu")
		(net "P5E_PEX1_STN6_TX_C_DP<99>")
	)
	(segment
		(start 122.82805 -365.16564)
		(end 123.103386 -365.577628)
		(width 0.1651)
		(layer "In7.Cu")
		(net "P5E_PEX1_STN6_TX_C_DP<99>")
	)
	(segment
		(start 124.479558 -367.499646)
		(end 125.487684 -369.00866)
		(width 0.1651)
		(layer "In7.Cu")
		(net "P5E_PEX1_STN6_TX_C_DP<99>")
	)
	(segment
		(start 123.463304 -366.116108)
		(end 123.73864 -366.528096)
		(width 0.1651)
		(layer "In7.Cu")
		(net "P5E_PEX1_STN6_TX_C_DP<99>")
	)
	(segment
		(start 120.46966 -361.498642)
		(end 122.849132 -365.059976)
		(width 0.1651)
		(layer "In7.Cu")
		(net "P5E_PEX1_STN6_TX_C_DP<99>")
	)
	(segment
		(start 121.479818 -345.755976)
		(end 121.479818 -346.360242)
		(width 0.1651)
		(layer "In7.Cu")
		(net "P5E_PEX1_STN6_TX_C_DP<99>")
	)
	(segment
		(start 123.73864 -366.528096)
		(end 123.844304 -366.549178)
		(width 0.1651)
		(layer "In7.Cu")
		(net "P5E_PEX1_STN6_TX_C_DP<99>")
	)
	(segment
		(start 123.484132 -366.010444)
		(end 123.463304 -366.116108)
		(width 0.1651)
		(layer "In7.Cu")
		(net "P5E_PEX1_STN6_TX_C_DP<99>")
	)
	(segment
		(start 124.37364 -367.478564)
		(end 124.479558 -367.499646)
		(width 0.1651)
		(layer "In7.Cu")
		(net "P5E_PEX1_STN6_TX_C_DP<99>")
	)
	(segment
		(start 121.188988 -345.465146)
		(end 121.479818 -345.755976)
		(width 0.1651)
		(layer "In7.Cu")
		(net "P5E_PEX1_STN6_TX_C_DP<99>")
	)
	(segment
		(start 124.098304 -367.066576)
		(end 124.37364 -367.478564)
		(width 0.1651)
		(layer "In7.Cu")
		(net "P5E_PEX1_STN6_TX_C_DP<99>")
	)
	(segment
		(start 123.103386 -365.577628)
		(end 123.20905 -365.59871)
		(width 0.1651)
		(layer "In7.Cu")
		(net "P5E_PEX1_STN6_TX_C_DP<99>")
	)
	(segment
		(start 124.71019 -382.572006)
		(end 124.71019 -382.18999)
		(width 0.1651)
		(layer "In7.Cu")
		(net "P5E_PEX1_STN6_TX_C_DP<99>")
	)
	(segment
		(start 124.119386 -366.960912)
		(end 124.098304 -367.066576)
		(width 0.1651)
		(layer "In7.Cu")
		(net "P5E_PEX1_STN6_TX_C_DP<99>")
	)
	(segment
		(start 121.479818 -346.360242)
		(end 119.925338 -347.914722)
		(width 0.1651)
		(layer "In7.Cu")
		(net "P5E_PEX1_STN6_TX_C_DP<99>")
	)
	(segment
		(start 125.487684 -382.280668)
		(end 125.069346 -382.699006)
		(width 0.1651)
		(layer "In7.Cu")
		(net "P5E_PEX1_STN6_TX_C_DP<99>")
	)
	(segment
		(start 124.83719 -382.699006)
		(end 124.71019 -382.572006)
		(width 0.1651)
		(layer "In7.Cu")
		(net "P5E_PEX1_STN6_TX_C_DP<99>")
	)
	(segment
		(start 119.925338 -347.914722)
		(end 119.925338 -359.703624)
		(width 0.1651)
		(layer "In7.Cu")
		(net "P5E_PEX1_STN6_TX_C_DP<99>")
	)
	(segment
		(start 123.20905 -365.59871)
		(end 123.484132 -366.010444)
		(width 0.1651)
		(layer "In7.Cu")
		(net "P5E_PEX1_STN6_TX_C_DP<99>")
	)
	(segment
		(start 119.925338 -359.703624)
		(end 120.46966 -361.498642)
		(width 0.1651)
		(layer "In7.Cu")
		(net "P5E_PEX1_STN6_TX_C_DP<99>")
	)
	(segment
		(start 125.069346 -382.699006)
		(end 124.83719 -382.699006)
		(width 0.1651)
		(layer "In7.Cu")
		(net "P5E_PEX1_STN6_TX_C_DP<99>")
	)
	(segment
		(start 125.487684 -369.00866)
		(end 125.487684 -382.280668)
		(width 0.1651)
		(layer "In7.Cu")
		(net "P5E_PEX1_STN6_TX_C_DP<99>")
	)
	(segment
		(start 122.849132 -365.059976)
		(end 122.82805 -365.16564)
		(width 0.1651)
		(layer "In7.Cu")
		(net "P5E_PEX1_STN6_TX_C_DP<99>")
	)
	(segment
		(start 123.844304 -366.549178)
		(end 124.119386 -366.960912)
		(width 0.1651)
		(layer "In7.Cu")
		(net "P5E_PEX1_STN6_TX_C_DP<99>")
	)
	(segment
		(start 283.321506 -112.044988)
		(end 282.842462 -112.044988)
		(width 0.13462)
		(layer "F.Cu")
		(net "P5E_PEX2_STN1_RX_DP<23>")
	)
	(segment
		(start 283.493718 -112.2172)
		(end 283.321506 -112.044988)
		(width 0.13462)
		(layer "F.Cu")
		(net "P5E_PEX2_STN1_RX_DP<23>")
	)
	(segment
		(start 284.13837 -112.2172)
		(end 283.493718 -112.2172)
		(width 0.13462)
		(layer "F.Cu")
		(net "P5E_PEX2_STN1_RX_DP<23>")
	)
	(segment
		(start 284.442662 -111.912908)
		(end 284.13837 -112.2172)
		(width 0.13462)
		(layer "F.Cu")
		(net "P5E_PEX2_STN1_RX_DP<23>")
	)
	(segment
		(start 267.743432 -158.33471)
		(end 268.730222 -164.093144)
		(width 0.1651)
		(layer "In5.Cu")
		(net "P5E_PEX2_STN1_RX_DP<23>")
	)
	(segment
		(start 275.293582 -120.951244)
		(end 273.64563 -128.369314)
		(width 0.1651)
		(layer "In5.Cu")
		(net "P5E_PEX2_STN1_RX_DP<23>")
	)
	(segment
		(start 297.929554 -271.645126)
		(end 297.929554 -275.355304)
		(width 0.1143)
		(layer "In5.Cu")
		(net "P5E_PEX2_STN1_RX_DP<23>")
	)
	(segment
		(start 272.18259 -137.393934)
		(end 270.192754 -140.990066)
		(width 0.1651)
		(layer "In5.Cu")
		(net "P5E_PEX2_STN1_RX_DP<23>")
	)
	(segment
		(start 297.883834 -268.60881)
		(end 297.883834 -271.570958)
		(width 0.1651)
		(layer "In5.Cu")
		(net "P5E_PEX2_STN1_RX_DP<23>")
	)
	(segment
		(start 273.64563 -128.369314)
		(end 272.18259 -137.393934)
		(width 0.1651)
		(layer "In5.Cu")
		(net "P5E_PEX2_STN1_RX_DP<23>")
	)
	(segment
		(start 297.883834 -271.599406)
		(end 297.929554 -271.645126)
		(width 0.1143)
		(layer "In5.Cu")
		(net "P5E_PEX2_STN1_RX_DP<23>")
	)
	(segment
		(start 268.730222 -164.093144)
		(end 297.883834 -268.60881)
		(width 0.1651)
		(layer "In5.Cu")
		(net "P5E_PEX2_STN1_RX_DP<23>")
	)
	(segment
		(start 278.417528 -114.704622)
		(end 277.806658 -116.017548)
		(width 0.1651)
		(layer "In5.Cu")
		(net "P5E_PEX2_STN1_RX_DP<23>")
	)
	(segment
		(start 270.192754 -140.990066)
		(end 268.40561 -145.064734)
		(width 0.1651)
		(layer "In5.Cu")
		(net "P5E_PEX2_STN1_RX_DP<23>")
	)
	(segment
		(start 297.929554 -275.355304)
		(end 298.144438 -275.570188)
		(width 0.1143)
		(layer "In5.Cu")
		(net "P5E_PEX2_STN1_RX_DP<23>")
	)
	(segment
		(start 298.38523 -275.570188)
		(end 298.49953 -275.684488)
		(width 0.1143)
		(layer "In5.Cu")
		(net "P5E_PEX2_STN1_RX_DP<23>")
	)
	(segment
		(start 297.883834 -271.570958)
		(end 297.883834 -271.599406)
		(width 0.1143)
		(layer "In5.Cu")
		(net "P5E_PEX2_STN1_RX_DP<23>")
	)
	(segment
		(start 298.49953 -275.684488)
		(end 298.49953 -275.949918)
		(width 0.1143)
		(layer "In5.Cu")
		(net "P5E_PEX2_STN1_RX_DP<23>")
	)
	(segment
		(start 298.144438 -275.570188)
		(end 298.38523 -275.570188)
		(width 0.1143)
		(layer "In5.Cu")
		(net "P5E_PEX2_STN1_RX_DP<23>")
	)
	(segment
		(start 284.442662 -111.912908)
		(end 284.151832 -112.203738)
		(width 0.1651)
		(layer "In5.Cu")
		(net "P5E_PEX2_STN1_RX_DP<23>")
	)
	(segment
		(start 283.466286 -112.203738)
		(end 279.217882 -113.941098)
		(width 0.1651)
		(layer "In5.Cu")
		(net "P5E_PEX2_STN1_RX_DP<23>")
	)
	(segment
		(start 267.278866 -151.208994)
		(end 267.511784 -154.781758)
		(width 0.1651)
		(layer "In5.Cu")
		(net "P5E_PEX2_STN1_RX_DP<23>")
	)
	(segment
		(start 284.151832 -112.203738)
		(end 283.466286 -112.203738)
		(width 0.1651)
		(layer "In5.Cu")
		(net "P5E_PEX2_STN1_RX_DP<23>")
	)
	(segment
		(start 277.149052 -116.962174)
		(end 275.293582 -120.951244)
		(width 0.1651)
		(layer "In5.Cu")
		(net "P5E_PEX2_STN1_RX_DP<23>")
	)
	(segment
		(start 267.842492 -148.135594)
		(end 267.842492 -148.135848)
		(width 0.1651)
		(layer "In5.Cu")
		(net "P5E_PEX2_STN1_RX_DP<23>")
	)
	(segment
		(start 277.806658 -116.017548)
		(end 277.149052 -116.962174)
		(width 0.1651)
		(layer "In5.Cu")
		(net "P5E_PEX2_STN1_RX_DP<23>")
	)
	(segment
		(start 279.217882 -113.941098)
		(end 278.417528 -114.704622)
		(width 0.1651)
		(layer "In5.Cu")
		(net "P5E_PEX2_STN1_RX_DP<23>")
	)
	(segment
		(start 267.842492 -148.135848)
		(end 267.278866 -151.208994)
		(width 0.1651)
		(layer "In5.Cu")
		(net "P5E_PEX2_STN1_RX_DP<23>")
	)
	(segment
		(start 268.40561 -145.064734)
		(end 267.842492 -148.135594)
		(width 0.1651)
		(layer "In5.Cu")
		(net "P5E_PEX2_STN1_RX_DP<23>")
	)
	(segment
		(start 267.511784 -154.781758)
		(end 267.743432 -158.33471)
		(width 0.1651)
		(layer "In5.Cu")
		(net "P5E_PEX2_STN1_RX_DP<23>")
	)
	(segment
		(start 322.718684 -344.219022)
		(end 322.398644 -344.539062)
		(width 0.13462)
		(layer "F.Cu")
		(net "P5E_PEX2_STN5_TX_C_DN<84>")
	)
	(segment
		(start 322.398644 -345.170506)
		(end 322.693284 -345.465146)
		(width 0.13462)
		(layer "F.Cu")
		(net "P5E_PEX2_STN5_TX_C_DN<84>")
	)
	(segment
		(start 322.398644 -344.539062)
		(end 322.398644 -345.170506)
		(width 0.13462)
		(layer "F.Cu")
		(net "P5E_PEX2_STN5_TX_C_DN<84>")
	)
	(segment
		(start 340.964266 -405.080978)
		(end 341.416132 -404.629112)
		(width 0.1651)
		(layer "In7.Cu")
		(net "P5E_PEX2_STN5_TX_C_DN<84>")
	)
	(segment
		(start 320.847974 -358.8512)
		(end 320.847974 -347.881194)
		(width 0.1651)
		(layer "In7.Cu")
		(net "P5E_PEX2_STN5_TX_C_DN<84>")
	)
	(segment
		(start 341.416132 -395.08684)
		(end 340.82228 -394.23594)
		(width 0.1651)
		(layer "In7.Cu")
		(net "P5E_PEX2_STN5_TX_C_DN<84>")
	)
	(segment
		(start 328.49058 -387.18998)
		(end 327.45426 -384.70332)
		(width 0.1651)
		(layer "In7.Cu")
		(net "P5E_PEX2_STN5_TX_C_DN<84>")
	)
	(segment
		(start 330.02474 -388.72668)
		(end 328.49058 -387.18998)
		(width 0.1651)
		(layer "In7.Cu")
		(net "P5E_PEX2_STN5_TX_C_DN<84>")
	)
	(segment
		(start 327.45426 -384.70332)
		(end 320.847974 -358.8512)
		(width 0.1651)
		(layer "In7.Cu")
		(net "P5E_PEX2_STN5_TX_C_DN<84>")
	)
	(segment
		(start 340.29015 -405.589994)
		(end 340.29015 -405.207978)
		(width 0.1651)
		(layer "In7.Cu")
		(net "P5E_PEX2_STN5_TX_C_DN<84>")
	)
	(segment
		(start 320.847974 -347.881194)
		(end 322.402454 -346.326714)
		(width 0.1651)
		(layer "In7.Cu")
		(net "P5E_PEX2_STN5_TX_C_DN<84>")
	)
	(segment
		(start 341.416132 -404.629112)
		(end 341.416132 -395.08684)
		(width 0.1651)
		(layer "In7.Cu")
		(net "P5E_PEX2_STN5_TX_C_DN<84>")
	)
	(segment
		(start 340.29015 -405.207978)
		(end 340.41715 -405.080978)
		(width 0.1651)
		(layer "In7.Cu")
		(net "P5E_PEX2_STN5_TX_C_DN<84>")
	)
	(segment
		(start 322.402454 -345.755976)
		(end 322.693284 -345.465146)
		(width 0.1651)
		(layer "In7.Cu")
		(net "P5E_PEX2_STN5_TX_C_DN<84>")
	)
	(segment
		(start 340.41715 -405.080978)
		(end 340.964266 -405.080978)
		(width 0.1651)
		(layer "In7.Cu")
		(net "P5E_PEX2_STN5_TX_C_DN<84>")
	)
	(segment
		(start 340.82228 -394.23594)
		(end 336.7913 -391.541)
		(width 0.1651)
		(layer "In7.Cu")
		(net "P5E_PEX2_STN5_TX_C_DN<84>")
	)
	(segment
		(start 322.402454 -346.326714)
		(end 322.402454 -345.755976)
		(width 0.1651)
		(layer "In7.Cu")
		(net "P5E_PEX2_STN5_TX_C_DN<84>")
	)
	(segment
		(start 336.7913 -391.541)
		(end 330.02474 -388.72668)
		(width 0.1651)
		(layer "In7.Cu")
		(net "P5E_PEX2_STN5_TX_C_DN<84>")
	)
	(segment
		(start 415.68497 -153.75128)
		(end 416.280346 -153.75128)
		(width 0.13462)
		(layer "F.Cu")
		(net "P5E_PEX3_STN0_RX_DN<14>")
	)
	(segment
		(start 415.35731 -153.42362)
		(end 415.68497 -153.75128)
		(width 0.13462)
		(layer "F.Cu")
		(net "P5E_PEX3_STN0_RX_DN<14>")
	)
	(segment
		(start 416.280346 -153.75128)
		(end 416.476688 -153.554938)
		(width 0.13462)
		(layer "F.Cu")
		(net "P5E_PEX3_STN0_RX_DN<14>")
	)
	(segment
		(start 416.476688 -153.554938)
		(end 416.95751 -153.554938)
		(width 0.13462)
		(layer "F.Cu")
		(net "P5E_PEX3_STN0_RX_DN<14>")
	)
	(segment
		(start 417.08324 -160.386776)
		(end 417.198556 -162.064446)
		(width 0.1651)
		(layer "In5.Cu")
		(net "P5E_PEX3_STN0_RX_DN<14>")
	)
	(segment
		(start 423.72026 -271.644872)
		(end 423.72026 -275.276056)
		(width 0.1143)
		(layer "In5.Cu")
		(net "P5E_PEX3_STN0_RX_DN<14>")
	)
	(segment
		(start 423.823638 -275.379434)
		(end 423.985436 -275.379434)
		(width 0.1143)
		(layer "In5.Cu")
		(net "P5E_PEX3_STN0_RX_DN<14>")
	)
	(segment
		(start 416.815524 -154.733752)
		(end 417.082732 -158.632144)
		(width 0.1651)
		(layer "In5.Cu")
		(net "P5E_PEX3_STN0_RX_DN<14>")
	)
	(segment
		(start 424.261026 -267.81125)
		(end 423.76598 -270.457168)
		(width 0.1651)
		(layer "In5.Cu")
		(net "P5E_PEX3_STN0_RX_DN<14>")
	)
	(segment
		(start 423.76598 -270.457168)
		(end 423.76598 -271.570704)
		(width 0.1651)
		(layer "In5.Cu")
		(net "P5E_PEX3_STN0_RX_DN<14>")
	)
	(segment
		(start 416.578034 -154.211528)
		(end 416.815524 -154.733752)
		(width 0.1651)
		(layer "In5.Cu")
		(net "P5E_PEX3_STN0_RX_DN<14>")
	)
	(segment
		(start 424.099736 -275.265134)
		(end 424.099736 -274.999704)
		(width 0.1143)
		(layer "In5.Cu")
		(net "P5E_PEX3_STN0_RX_DN<14>")
	)
	(segment
		(start 423.76598 -271.599152)
		(end 423.72026 -271.644872)
		(width 0.1143)
		(layer "In5.Cu")
		(net "P5E_PEX3_STN0_RX_DN<14>")
	)
	(segment
		(start 423.72026 -275.276056)
		(end 423.823638 -275.379434)
		(width 0.1143)
		(layer "In5.Cu")
		(net "P5E_PEX3_STN0_RX_DN<14>")
	)
	(segment
		(start 417.614608 -164.671502)
		(end 424.045634 -258.322826)
		(width 0.1651)
		(layer "In5.Cu")
		(net "P5E_PEX3_STN0_RX_DN<14>")
	)
	(segment
		(start 416.079686 -153.71318)
		(end 416.578034 -154.211528)
		(width 0.1651)
		(layer "In5.Cu")
		(net "P5E_PEX3_STN0_RX_DN<14>")
	)
	(segment
		(start 417.082732 -158.632144)
		(end 417.08324 -158.632652)
		(width 0.1651)
		(layer "In5.Cu")
		(net "P5E_PEX3_STN0_RX_DN<14>")
	)
	(segment
		(start 417.198556 -162.064446)
		(end 417.614608 -164.671502)
		(width 0.1651)
		(layer "In5.Cu")
		(net "P5E_PEX3_STN0_RX_DN<14>")
	)
	(segment
		(start 415.64687 -153.71318)
		(end 416.079686 -153.71318)
		(width 0.1651)
		(layer "In5.Cu")
		(net "P5E_PEX3_STN0_RX_DN<14>")
	)
	(segment
		(start 423.76598 -271.570704)
		(end 423.76598 -271.599152)
		(width 0.1143)
		(layer "In5.Cu")
		(net "P5E_PEX3_STN0_RX_DN<14>")
	)
	(segment
		(start 415.35731 -153.42362)
		(end 415.64687 -153.71318)
		(width 0.1651)
		(layer "In5.Cu")
		(net "P5E_PEX3_STN0_RX_DN<14>")
	)
	(segment
		(start 417.08324 -158.632652)
		(end 417.08324 -160.386776)
		(width 0.1651)
		(layer "In5.Cu")
		(net "P5E_PEX3_STN0_RX_DN<14>")
	)
	(segment
		(start 423.985436 -275.379434)
		(end 424.099736 -275.265134)
		(width 0.1143)
		(layer "In5.Cu")
		(net "P5E_PEX3_STN0_RX_DN<14>")
	)
	(segment
		(start 424.045634 -258.322826)
		(end 424.261026 -267.81125)
		(width 0.1651)
		(layer "In5.Cu")
		(net "P5E_PEX3_STN0_RX_DN<14>")
	)
	(segment
		(start 434.73624 -345.171014)
		(end 435.030372 -345.465146)
		(width 0.13462)
		(layer "F.Cu")
		(net "P5E_PEX3_STN7_TX_C_DN<123>")
	)
	(segment
		(start 435.055772 -344.219022)
		(end 434.73624 -344.538554)
		(width 0.13462)
		(layer "F.Cu")
		(net "P5E_PEX3_STN7_TX_C_DN<123>")
	)
	(segment
		(start 434.73624 -344.538554)
		(end 434.73624 -345.171014)
		(width 0.13462)
		(layer "F.Cu")
		(net "P5E_PEX3_STN7_TX_C_DN<123>")
	)
	(segment
		(start 426.763942 -376.281188)
		(end 427.215808 -375.829322)
		(width 0.1651)
		(layer "In11.Cu")
		(net "P5E_PEX3_STN7_TX_C_DN<123>")
	)
	(segment
		(start 426.089826 -376.790204)
		(end 426.089826 -376.408188)
		(width 0.1651)
		(layer "In11.Cu")
		(net "P5E_PEX3_STN7_TX_C_DN<123>")
	)
	(segment
		(start 427.215808 -375.829322)
		(end 427.215808 -369.656614)
		(width 0.1651)
		(layer "In11.Cu")
		(net "P5E_PEX3_STN7_TX_C_DN<123>")
	)
	(segment
		(start 427.215808 -369.656614)
		(end 427.61408 -368.227864)
		(width 0.1651)
		(layer "In11.Cu")
		(net "P5E_PEX3_STN7_TX_C_DN<123>")
	)
	(segment
		(start 432.77917 -359.68686)
		(end 433.185062 -358.230932)
		(width 0.1651)
		(layer "In11.Cu")
		(net "P5E_PEX3_STN7_TX_C_DN<123>")
	)
	(segment
		(start 434.739542 -345.755976)
		(end 435.030372 -345.465146)
		(width 0.1651)
		(layer "In11.Cu")
		(net "P5E_PEX3_STN7_TX_C_DN<123>")
	)
	(segment
		(start 433.185062 -358.230932)
		(end 433.185062 -347.881194)
		(width 0.1651)
		(layer "In11.Cu")
		(net "P5E_PEX3_STN7_TX_C_DN<123>")
	)
	(segment
		(start 433.185062 -347.881194)
		(end 434.739542 -346.326714)
		(width 0.1651)
		(layer "In11.Cu")
		(net "P5E_PEX3_STN7_TX_C_DN<123>")
	)
	(segment
		(start 427.61408 -368.227864)
		(end 432.77917 -359.68686)
		(width 0.1651)
		(layer "In11.Cu")
		(net "P5E_PEX3_STN7_TX_C_DN<123>")
	)
	(segment
		(start 426.216826 -376.281188)
		(end 426.763942 -376.281188)
		(width 0.1651)
		(layer "In11.Cu")
		(net "P5E_PEX3_STN7_TX_C_DN<123>")
	)
	(segment
		(start 426.089826 -376.408188)
		(end 426.216826 -376.281188)
		(width 0.1651)
		(layer "In11.Cu")
		(net "P5E_PEX3_STN7_TX_C_DN<123>")
	)
	(segment
		(start 434.739542 -346.326714)
		(end 434.739542 -345.755976)
		(width 0.1651)
		(layer "In11.Cu")
		(net "P5E_PEX3_STN7_TX_C_DN<123>")
	)
	(segment
		(start 383.319528 -24.790146)
		(end 383.302256 -24.807418)
		(width 0.13208)
		(layer "F.Cu")
		(net "PU_CLKREQ13")
	)
	(segment
		(start 382.47193 -24.807418)
		(end 383.302256 -24.807418)
		(width 0.13208)
		(layer "F.Cu")
		(net "PU_CLKREQ13")
	)
	(segment
		(start 384.96494 -24.790146)
		(end 383.319528 -24.790146)
		(width 0.13208)
		(layer "F.Cu")
		(net "PU_CLKREQ13")
	)
	(via
		(at 383.302256 -24.807418)
		(size 0.508)
		(drill 0.254)
		(layers "F.Cu" "B.Cu")
		(net "PU_CLKREQ13")
	)
	(segment
		(start 161.654236 -112.044988)
		(end 162.14217 -112.044988)
		(width 0.13462)
		(layer "F.Cu")
		(net "P5E_PEX1_STN1_TX_C_DN<23>")
	)
	(segment
		(start 153.005028 -111.895382)
		(end 153.317448 -112.207802)
		(width 0.13462)
		(layer "F.Cu")
		(net "P5E_PEX1_STN1_TX_C_DN<23>")
	)
	(segment
		(start 153.317448 -112.207802)
		(end 161.491422 -112.207802)
		(width 0.13462)
		(layer "F.Cu")
		(net "P5E_PEX1_STN1_TX_C_DN<23>")
	)
	(segment
		(start 161.491422 -112.207802)
		(end 161.654236 -112.044988)
		(width 0.13462)
		(layer "F.Cu")
		(net "P5E_PEX1_STN1_TX_C_DN<23>")
	)
	(segment
		(start 127.406908 -345.465146)
		(end 127.701548 -345.170506)
		(width 0.13462)
		(layer "F.Cu")
		(net "P5E_PEX1_STN6_TX_C_DP<96>")
	)
	(segment
		(start 127.701548 -345.170506)
		(end 127.701548 -344.539062)
		(width 0.13462)
		(layer "F.Cu")
		(net "P5E_PEX1_STN6_TX_C_DP<96>")
	)
	(segment
		(start 127.701548 -344.539062)
		(end 127.381508 -344.219022)
		(width 0.13462)
		(layer "F.Cu")
		(net "P5E_PEX1_STN6_TX_C_DP<96>")
	)
	(segment
		(start 129.909316 -365.442246)
		(end 129.930144 -365.336582)
		(width 0.1651)
		(layer "In7.Cu")
		(net "P5E_PEX1_STN6_TX_C_DP<96>")
	)
	(segment
		(start 130.290316 -365.875316)
		(end 130.184652 -365.854234)
		(width 0.1651)
		(layer "In7.Cu")
		(net "P5E_PEX1_STN6_TX_C_DP<96>")
	)
	(segment
		(start 129.930144 -365.336582)
		(end 126.543562 -360.267758)
		(width 0.1651)
		(layer "In7.Cu")
		(net "P5E_PEX1_STN6_TX_C_DP<96>")
	)
	(segment
		(start 131.669282 -383.798826)
		(end 132.08762 -383.380488)
		(width 0.1651)
		(layer "In7.Cu")
		(net "P5E_PEX1_STN6_TX_C_DP<96>")
	)
	(segment
		(start 130.819906 -366.804702)
		(end 130.54457 -366.392714)
		(width 0.1651)
		(layer "In7.Cu")
		(net "P5E_PEX1_STN6_TX_C_DP<96>")
	)
	(segment
		(start 126.543562 -360.267758)
		(end 126.143258 -358.947974)
		(width 0.1651)
		(layer "In7.Cu")
		(net "P5E_PEX1_STN6_TX_C_DP<96>")
	)
	(segment
		(start 127.697738 -345.755976)
		(end 127.406908 -345.465146)
		(width 0.1651)
		(layer "In7.Cu")
		(net "P5E_PEX1_STN6_TX_C_DP<96>")
	)
	(segment
		(start 126.143258 -358.947974)
		(end 126.143258 -347.914722)
		(width 0.1651)
		(layer "In7.Cu")
		(net "P5E_PEX1_STN6_TX_C_DP<96>")
	)
	(segment
		(start 130.565398 -366.28705)
		(end 130.290316 -365.875316)
		(width 0.1651)
		(layer "In7.Cu")
		(net "P5E_PEX1_STN6_TX_C_DP<96>")
	)
	(segment
		(start 131.437126 -383.798826)
		(end 131.669282 -383.798826)
		(width 0.1651)
		(layer "In7.Cu")
		(net "P5E_PEX1_STN6_TX_C_DP<96>")
	)
	(segment
		(start 131.310126 -383.671826)
		(end 131.437126 -383.798826)
		(width 0.1651)
		(layer "In7.Cu")
		(net "P5E_PEX1_STN6_TX_C_DP<96>")
	)
	(segment
		(start 127.697738 -346.360242)
		(end 127.697738 -345.755976)
		(width 0.1651)
		(layer "In7.Cu")
		(net "P5E_PEX1_STN6_TX_C_DP<96>")
	)
	(segment
		(start 131.310126 -383.290064)
		(end 131.310126 -383.671826)
		(width 0.1651)
		(layer "In7.Cu")
		(net "P5E_PEX1_STN6_TX_C_DP<96>")
	)
	(segment
		(start 130.184652 -365.854234)
		(end 129.909316 -365.442246)
		(width 0.1651)
		(layer "In7.Cu")
		(net "P5E_PEX1_STN6_TX_C_DP<96>")
	)
	(segment
		(start 130.54457 -366.392714)
		(end 130.565398 -366.28705)
		(width 0.1651)
		(layer "In7.Cu")
		(net "P5E_PEX1_STN6_TX_C_DP<96>")
	)
	(segment
		(start 132.08762 -368.564922)
		(end 130.92557 -366.825784)
		(width 0.1651)
		(layer "In7.Cu")
		(net "P5E_PEX1_STN6_TX_C_DP<96>")
	)
	(segment
		(start 132.08762 -383.380488)
		(end 132.08762 -368.564922)
		(width 0.1651)
		(layer "In7.Cu")
		(net "P5E_PEX1_STN6_TX_C_DP<96>")
	)
	(segment
		(start 126.143258 -347.914722)
		(end 127.697738 -346.360242)
		(width 0.1651)
		(layer "In7.Cu")
		(net "P5E_PEX1_STN6_TX_C_DP<96>")
	)
	(segment
		(start 130.92557 -366.825784)
		(end 130.819906 -366.804702)
		(width 0.1651)
		(layer "In7.Cu")
		(net "P5E_PEX1_STN6_TX_C_DP<96>")
	)
	(segment
		(start 272.058638 -136.41832)
		(end 277.611078 -136.41832)
		(width 0.13462)
		(layer "F.Cu")
		(net "P5E_PEX2_STN1_TX_C_DP<31>")
	)
	(segment
		(start 277.611078 -136.41832)
		(end 277.75789 -136.565132)
		(width 0.13462)
		(layer "F.Cu")
		(net "P5E_PEX2_STN1_TX_C_DP<31>")
	)
	(segment
		(start 271.747234 -136.729724)
		(end 272.058638 -136.41832)
		(width 0.13462)
		(layer "F.Cu")
		(net "P5E_PEX2_STN1_TX_C_DP<31>")
	)
	(segment
		(start 277.75789 -136.565132)
		(end 278.242268 -136.565132)
		(width 0.13462)
		(layer "F.Cu")
		(net "P5E_PEX2_STN1_TX_C_DP<31>")
	)
	(segment
		(start 298.09948 -320.03492)
		(end 298.1452 -319.9892)
		(width 0.1143)
		(layer "In9.Cu")
		(net "P5E_PEX2_STN5_RX_DN<87>")
	)
	(segment
		(start 298.1452 -319.9892)
		(end 298.173648 -319.9892)
		(width 0.1143)
		(layer "In9.Cu")
		(net "P5E_PEX2_STN5_RX_DN<87>")
	)
	(segment
		(start 297.40352 -320.03492)
		(end 298.09948 -320.03492)
		(width 0.1143)
		(layer "In9.Cu")
		(net "P5E_PEX2_STN5_RX_DN<87>")
	)
	(segment
		(start 348.016068 -397.929354)
		(end 347.564202 -398.38122)
		(width 0.1651)
		(layer "In9.Cu")
		(net "P5E_PEX2_STN5_RX_DN<87>")
	)
	(segment
		(start 347.922596 -339.914738)
		(end 358.84866 -368.66322)
		(width 0.1651)
		(layer "In9.Cu")
		(net "P5E_PEX2_STN5_RX_DN<87>")
	)
	(segment
		(start 346.47251 -338.380578)
		(end 347.922596 -339.914738)
		(width 0.1651)
		(layer "In9.Cu")
		(net "P5E_PEX2_STN5_RX_DN<87>")
	)
	(segment
		(start 348.277942 -394.796518)
		(end 348.016068 -395.058392)
		(width 0.1651)
		(layer "In9.Cu")
		(net "P5E_PEX2_STN5_RX_DN<87>")
	)
	(segment
		(start 297.549824 -318.699896)
		(end 297.549824 -318.409066)
		(width 0.1143)
		(layer "In9.Cu")
		(net "P5E_PEX2_STN5_RX_DN<87>")
	)
	(segment
		(start 343.01049 -336.07248)
		(end 346.47251 -338.380578)
		(width 0.1651)
		(layer "In9.Cu")
		(net "P5E_PEX2_STN5_RX_DN<87>")
	)
	(segment
		(start 298.86275 -319.9892)
		(end 343.01049 -336.07248)
		(width 0.1651)
		(layer "In9.Cu")
		(net "P5E_PEX2_STN5_RX_DN<87>")
	)
	(segment
		(start 359.044494 -370.080794)
		(end 358.710992 -386.389372)
		(width 0.1651)
		(layer "In9.Cu")
		(net "P5E_PEX2_STN5_RX_DN<87>")
	)
	(segment
		(start 358.710992 -386.389372)
		(end 357.8225 -388.789672)
		(width 0.1651)
		(layer "In9.Cu")
		(net "P5E_PEX2_STN5_RX_DN<87>")
	)
	(segment
		(start 297.549824 -318.409066)
		(end 297.460924 -318.320166)
		(width 0.1143)
		(layer "In9.Cu")
		(net "P5E_PEX2_STN5_RX_DN<87>")
	)
	(segment
		(start 358.84866 -368.66322)
		(end 359.044494 -370.080794)
		(width 0.1651)
		(layer "In9.Cu")
		(net "P5E_PEX2_STN5_RX_DN<87>")
	)
	(segment
		(start 347.564202 -398.38122)
		(end 347.017086 -398.38122)
		(width 0.1651)
		(layer "In9.Cu")
		(net "P5E_PEX2_STN5_RX_DN<87>")
	)
	(segment
		(start 297.460924 -318.320166)
		(end 297.28414 -318.320166)
		(width 0.1143)
		(layer "In9.Cu")
		(net "P5E_PEX2_STN5_RX_DN<87>")
	)
	(segment
		(start 297.169332 -319.800732)
		(end 297.40352 -320.03492)
		(width 0.1143)
		(layer "In9.Cu")
		(net "P5E_PEX2_STN5_RX_DN<87>")
	)
	(segment
		(start 347.017086 -398.38122)
		(end 346.890086 -398.50822)
		(width 0.1651)
		(layer "In9.Cu")
		(net "P5E_PEX2_STN5_RX_DN<87>")
	)
	(segment
		(start 357.8225 -388.789672)
		(end 356.070408 -390.908032)
		(width 0.1651)
		(layer "In9.Cu")
		(net "P5E_PEX2_STN5_RX_DN<87>")
	)
	(segment
		(start 297.169332 -318.434974)
		(end 297.169332 -319.800732)
		(width 0.1143)
		(layer "In9.Cu")
		(net "P5E_PEX2_STN5_RX_DN<87>")
	)
	(segment
		(start 353.50196 -392.748262)
		(end 348.277942 -394.796518)
		(width 0.1651)
		(layer "In9.Cu")
		(net "P5E_PEX2_STN5_RX_DN<87>")
	)
	(segment
		(start 356.070408 -390.908032)
		(end 353.50196 -392.748262)
		(width 0.1651)
		(layer "In9.Cu")
		(net "P5E_PEX2_STN5_RX_DN<87>")
	)
	(segment
		(start 348.016068 -395.058392)
		(end 348.016068 -397.929354)
		(width 0.1651)
		(layer "In9.Cu")
		(net "P5E_PEX2_STN5_RX_DN<87>")
	)
	(segment
		(start 298.173648 -319.9892)
		(end 298.86275 -319.9892)
		(width 0.1651)
		(layer "In9.Cu")
		(net "P5E_PEX2_STN5_RX_DN<87>")
	)
	(segment
		(start 346.890086 -398.50822)
		(end 346.890086 -398.890236)
		(width 0.1651)
		(layer "In9.Cu")
		(net "P5E_PEX2_STN5_RX_DN<87>")
	)
	(segment
		(start 297.28414 -318.320166)
		(end 297.169332 -318.434974)
		(width 0.1143)
		(layer "In9.Cu")
		(net "P5E_PEX2_STN5_RX_DN<87>")
	)
	(segment
		(start 428.052738 -133.480302)
		(end 427.72584 -133.8072)
		(width 0.13462)
		(layer "F.Cu")
		(net "P5E_PEX3_STN0_TX_C_DN<6>")
	)
	(segment
		(start 427.72584 -133.8072)
		(end 422.222676 -133.8072)
		(width 0.13462)
		(layer "F.Cu")
		(net "P5E_PEX3_STN0_TX_C_DN<6>")
	)
	(segment
		(start 422.222676 -133.8072)
		(end 422.060624 -133.645148)
		(width 0.13462)
		(layer "F.Cu")
		(net "P5E_PEX3_STN0_TX_C_DN<6>")
	)
	(segment
		(start 422.060624 -133.645148)
		(end 421.557704 -133.645148)
		(width 0.13462)
		(layer "F.Cu")
		(net "P5E_PEX3_STN0_TX_C_DN<6>")
	)
	(segment
		(start 435.055772 -356.511606)
		(end 434.73624 -356.831138)
		(width 0.13462)
		(layer "F.Cu")
		(net "P5E_PEX3_STN7_TX_C_DN<124>")
	)
	(segment
		(start 434.73624 -356.831138)
		(end 434.73624 -357.463598)
		(width 0.13462)
		(layer "F.Cu")
		(net "P5E_PEX3_STN7_TX_C_DN<124>")
	)
	(segment
		(start 434.73624 -357.463598)
		(end 435.030372 -357.75773)
		(width 0.13462)
		(layer "F.Cu")
		(net "P5E_PEX3_STN7_TX_C_DN<124>")
	)
	(segment
		(start 428.289974 -375.69013)
		(end 428.289974 -375.308114)
		(width 0.1651)
		(layer "In11.Cu")
		(net "P5E_PEX3_STN7_TX_C_DN<124>")
	)
	(segment
		(start 434.739542 -358.502712)
		(end 434.739542 -358.04856)
		(width 0.1651)
		(layer "In11.Cu")
		(net "P5E_PEX3_STN7_TX_C_DN<124>")
	)
	(segment
		(start 429.415956 -369.791742)
		(end 429.876204 -367.983516)
		(width 0.1651)
		(layer "In11.Cu")
		(net "P5E_PEX3_STN7_TX_C_DN<124>")
	)
	(segment
		(start 428.96409 -375.181114)
		(end 429.415956 -374.729248)
		(width 0.1651)
		(layer "In11.Cu")
		(net "P5E_PEX3_STN7_TX_C_DN<124>")
	)
	(segment
		(start 434.739542 -358.04856)
		(end 435.030372 -357.75773)
		(width 0.1651)
		(layer "In11.Cu")
		(net "P5E_PEX3_STN7_TX_C_DN<124>")
	)
	(segment
		(start 428.416974 -375.181114)
		(end 428.96409 -375.181114)
		(width 0.1651)
		(layer "In11.Cu")
		(net "P5E_PEX3_STN7_TX_C_DN<124>")
	)
	(segment
		(start 429.415956 -374.729248)
		(end 429.415956 -369.791742)
		(width 0.1651)
		(layer "In11.Cu")
		(net "P5E_PEX3_STN7_TX_C_DN<124>")
	)
	(segment
		(start 428.289974 -375.308114)
		(end 428.416974 -375.181114)
		(width 0.1651)
		(layer "In11.Cu")
		(net "P5E_PEX3_STN7_TX_C_DN<124>")
	)
	(segment
		(start 434.477668 -359.531158)
		(end 434.739542 -358.502712)
		(width 0.1651)
		(layer "In11.Cu")
		(net "P5E_PEX3_STN7_TX_C_DN<124>")
	)
	(segment
		(start 429.876204 -367.983516)
		(end 434.477668 -359.531158)
		(width 0.1651)
		(layer "In11.Cu")
		(net "P5E_PEX3_STN7_TX_C_DN<124>")
	)
	(segment
		(start 415.669222 -96.702372)
		(end 416.006788 -97.039938)
		(width 0.13208)
		(layer "F.Cu")
		(net "RST_NIC7_PERST2_R_N")
	)
	(segment
		(start 409.72359 -96.702372)
		(end 415.669222 -96.702372)
		(width 0.13208)
		(layer "F.Cu")
		(net "RST_NIC7_PERST2_R_N")
	)
	(segment
		(start 416.006788 -97.039938)
		(end 416.95751 -97.039938)
		(width 0.13208)
		(layer "F.Cu")
		(net "RST_NIC7_PERST2_R_N")
	)
	(segment
		(start 407.695146 -96.702372)
		(end 409.72359 -96.702372)
		(width 0.13208)
		(layer "F.Cu")
		(net "RST_NIC7_PERST2_R_N")
	)
	(via
		(at 409.72359 -96.702372)
		(size 0.762)
		(drill 0.381)
		(layers "F.Cu" "B.Cu")
		(net "RST_NIC7_PERST2_R_N")
	)
	(segment
		(start 161.654236 -106.644948)
		(end 162.14217 -106.644948)
		(width 0.13462)
		(layer "F.Cu")
		(net "P5E_PEX1_STN1_TX_C_DP<20>")
	)
	(segment
		(start 155.647136 -106.488738)
		(end 155.96616 -106.807762)
		(width 0.13462)
		(layer "F.Cu")
		(net "P5E_PEX1_STN1_TX_C_DP<20>")
	)
	(segment
		(start 155.96616 -106.807762)
		(end 161.491422 -106.807762)
		(width 0.13462)
		(layer "F.Cu")
		(net "P5E_PEX1_STN1_TX_C_DP<20>")
	)
	(segment
		(start 161.491422 -106.807762)
		(end 161.654236 -106.644948)
		(width 0.13462)
		(layer "F.Cu")
		(net "P5E_PEX1_STN1_TX_C_DP<20>")
	)
	(segment
		(start 269.714726 -102.009702)
		(end 270.036036 -101.688392)
		(width 0.13462)
		(layer "F.Cu")
		(net "P5E_PEX2_STN1_TX_C_DP<17>")
	)
	(segment
		(start 277.734522 -101.84511)
		(end 278.242268 -101.84511)
		(width 0.13462)
		(layer "F.Cu")
		(net "P5E_PEX2_STN1_TX_C_DP<17>")
	)
	(segment
		(start 270.036036 -101.688392)
		(end 277.577804 -101.688392)
		(width 0.13462)
		(layer "F.Cu")
		(net "P5E_PEX2_STN1_TX_C_DP<17>")
	)
	(segment
		(start 277.577804 -101.688392)
		(end 277.734522 -101.84511)
		(width 0.13462)
		(layer "F.Cu")
		(net "P5E_PEX2_STN1_TX_C_DP<17>")
	)
	(segment
		(start 416.47999 -155.355036)
		(end 416.318446 -155.51658)
		(width 0.13462)
		(layer "F.Cu")
		(net "P5E_PEX3_STN0_RX_DN<15>")
	)
	(segment
		(start 416.318446 -155.51658)
		(end 413.795972 -155.51658)
		(width 0.13462)
		(layer "F.Cu")
		(net "P5E_PEX3_STN0_RX_DN<15>")
	)
	(segment
		(start 416.95751 -155.355036)
		(end 416.47999 -155.355036)
		(width 0.13462)
		(layer "F.Cu")
		(net "P5E_PEX3_STN0_RX_DN<15>")
	)
	(segment
		(start 413.795972 -155.51658)
		(end 413.50311 -155.223718)
		(width 0.13462)
		(layer "F.Cu")
		(net "P5E_PEX3_STN0_RX_DN<15>")
	)
	(segment
		(start 422.873678 -273.479514)
		(end 422.7703 -273.376136)
		(width 0.1143)
		(layer "In5.Cu")
		(net "P5E_PEX3_STN0_RX_DN<15>")
	)
	(segment
		(start 414.643062 -155.514548)
		(end 413.79394 -155.514548)
		(width 0.1651)
		(layer "In5.Cu")
		(net "P5E_PEX3_STN0_RX_DN<15>")
	)
	(segment
		(start 416.211258 -162.860736)
		(end 415.26333 -156.134562)
		(width 0.1651)
		(layer "In5.Cu")
		(net "P5E_PEX3_STN0_RX_DN<15>")
	)
	(segment
		(start 416.211258 -162.860482)
		(end 416.211258 -162.860736)
		(width 0.1651)
		(layer "In5.Cu")
		(net "P5E_PEX3_STN0_RX_DN<15>")
	)
	(segment
		(start 422.7703 -271.600168)
		(end 422.81602 -271.554448)
		(width 0.1143)
		(layer "In5.Cu")
		(net "P5E_PEX3_STN0_RX_DN<15>")
	)
	(segment
		(start 415.26333 -156.134562)
		(end 414.643062 -155.514548)
		(width 0.1651)
		(layer "In5.Cu")
		(net "P5E_PEX3_STN0_RX_DN<15>")
	)
	(segment
		(start 422.7703 -273.376136)
		(end 422.7703 -271.600168)
		(width 0.1143)
		(layer "In5.Cu")
		(net "P5E_PEX3_STN0_RX_DN<15>")
	)
	(segment
		(start 422.81602 -271.554448)
		(end 422.81602 -271.526)
		(width 0.1143)
		(layer "In5.Cu")
		(net "P5E_PEX3_STN0_RX_DN<15>")
	)
	(segment
		(start 422.81602 -271.526)
		(end 422.81602 -270.231616)
		(width 0.1651)
		(layer "In5.Cu")
		(net "P5E_PEX3_STN0_RX_DN<15>")
	)
	(segment
		(start 423.149776 -273.099784)
		(end 423.149776 -273.365214)
		(width 0.1143)
		(layer "In5.Cu")
		(net "P5E_PEX3_STN0_RX_DN<15>")
	)
	(segment
		(start 422.81602 -270.231616)
		(end 423.289222 -267.76807)
		(width 0.1651)
		(layer "In5.Cu")
		(net "P5E_PEX3_STN0_RX_DN<15>")
	)
	(segment
		(start 423.119296 -261.27202)
		(end 416.211258 -162.860482)
		(width 0.1651)
		(layer "In5.Cu")
		(net "P5E_PEX3_STN0_RX_DN<15>")
	)
	(segment
		(start 413.79394 -155.514548)
		(end 413.50311 -155.223718)
		(width 0.1651)
		(layer "In5.Cu")
		(net "P5E_PEX3_STN0_RX_DN<15>")
	)
	(segment
		(start 423.289222 -267.76807)
		(end 423.119296 -261.27202)
		(width 0.1651)
		(layer "In5.Cu")
		(net "P5E_PEX3_STN0_RX_DN<15>")
	)
	(segment
		(start 423.035476 -273.479514)
		(end 422.873678 -273.479514)
		(width 0.1143)
		(layer "In5.Cu")
		(net "P5E_PEX3_STN0_RX_DN<15>")
	)
	(segment
		(start 423.149776 -273.365214)
		(end 423.035476 -273.479514)
		(width 0.1143)
		(layer "In5.Cu")
		(net "P5E_PEX3_STN0_RX_DN<15>")
	)
	(segment
		(start 421.816784 -384.08102)
		(end 421.689784 -384.20802)
		(width 0.1651)
		(layer "In9.Cu")
		(net "P5E_PEX3_STN7_RX_DP<121>")
	)
	(segment
		(start 385.929886 -324.63232)
		(end 388.674102 -326.604122)
		(width 0.1651)
		(layer "In9.Cu")
		(net "P5E_PEX3_STN7_RX_DP<121>")
	)
	(segment
		(start 385.720082 -310.238648)
		(end 385.720082 -310.443372)
		(width 0.1143)
		(layer "In9.Cu")
		(net "P5E_PEX3_STN7_RX_DP<121>")
	)
	(segment
		(start 385.720082 -310.443372)
		(end 385.443476 -310.719978)
		(width 0.1143)
		(layer "In9.Cu")
		(net "P5E_PEX3_STN7_RX_DP<121>")
	)
	(segment
		(start 384.681984 -310.86171)
		(end 384.681984 -310.926734)
		(width 0.1143)
		(layer "In9.Cu")
		(net "P5E_PEX3_STN7_RX_DP<121>")
	)
	(segment
		(start 408.431492 -332.858364)
		(end 424.627548 -340.500462)
		(width 0.1651)
		(layer "In9.Cu")
		(net "P5E_PEX3_STN7_RX_DP<121>")
	)
	(segment
		(start 383.831592 -318.622172)
		(end 384.336036 -321.328288)
		(width 0.1651)
		(layer "In9.Cu")
		(net "P5E_PEX3_STN7_RX_DP<121>")
	)
	(segment
		(start 384.823716 -310.719978)
		(end 384.681984 -310.86171)
		(width 0.1143)
		(layer "In9.Cu")
		(net "P5E_PEX3_STN7_RX_DP<121>")
	)
	(segment
		(start 384.993388 -323.35089)
		(end 385.929886 -324.63232)
		(width 0.1651)
		(layer "In9.Cu")
		(net "P5E_PEX3_STN7_RX_DP<121>")
	)
	(segment
		(start 424.627548 -340.500462)
		(end 426.33519 -341.13978)
		(width 0.1651)
		(layer "In9.Cu")
		(net "P5E_PEX3_STN7_RX_DP<121>")
	)
	(segment
		(start 422.846754 -369.19662)
		(end 422.846754 -383.389886)
		(width 0.1651)
		(layer "In9.Cu")
		(net "P5E_PEX3_STN7_RX_DP<121>")
	)
	(segment
		(start 422.15562 -384.08102)
		(end 421.816784 -384.08102)
		(width 0.1651)
		(layer "In9.Cu")
		(net "P5E_PEX3_STN7_RX_DP<121>")
	)
	(segment
		(start 386.099812 -310.149748)
		(end 385.808982 -310.149748)
		(width 0.1143)
		(layer "In9.Cu")
		(net "P5E_PEX3_STN7_RX_DP<121>")
	)
	(segment
		(start 422.846754 -383.389886)
		(end 422.15562 -384.08102)
		(width 0.1651)
		(layer "In9.Cu")
		(net "P5E_PEX3_STN7_RX_DP<121>")
	)
	(segment
		(start 385.808982 -310.149748)
		(end 385.720082 -310.238648)
		(width 0.1143)
		(layer "In9.Cu")
		(net "P5E_PEX3_STN7_RX_DP<121>")
	)
	(segment
		(start 383.653792 -316.311788)
		(end 383.831592 -318.622172)
		(width 0.1651)
		(layer "In9.Cu")
		(net "P5E_PEX3_STN7_RX_DP<121>")
	)
	(segment
		(start 384.661918 -310.9468)
		(end 383.903728 -311.70499)
		(width 0.1651)
		(layer "In9.Cu")
		(net "P5E_PEX3_STN7_RX_DP<121>")
	)
	(segment
		(start 384.681984 -310.926734)
		(end 384.661918 -310.9468)
		(width 0.1143)
		(layer "In9.Cu")
		(net "P5E_PEX3_STN7_RX_DP<121>")
	)
	(segment
		(start 384.336036 -321.328288)
		(end 384.993388 -323.35089)
		(width 0.1651)
		(layer "In9.Cu")
		(net "P5E_PEX3_STN7_RX_DP<121>")
	)
	(segment
		(start 426.33519 -341.13978)
		(end 426.967142 -342.053926)
		(width 0.1651)
		(layer "In9.Cu")
		(net "P5E_PEX3_STN7_RX_DP<121>")
	)
	(segment
		(start 385.443476 -310.719978)
		(end 384.823716 -310.719978)
		(width 0.1143)
		(layer "In9.Cu")
		(net "P5E_PEX3_STN7_RX_DP<121>")
	)
	(segment
		(start 383.903728 -311.70499)
		(end 383.72034 -312.147712)
		(width 0.1651)
		(layer "In9.Cu")
		(net "P5E_PEX3_STN7_RX_DP<121>")
	)
	(segment
		(start 383.72034 -312.147712)
		(end 383.72034 -314.121038)
		(width 0.1651)
		(layer "In9.Cu")
		(net "P5E_PEX3_STN7_RX_DP<121>")
	)
	(segment
		(start 383.72034 -314.121038)
		(end 383.653792 -316.311788)
		(width 0.1651)
		(layer "In9.Cu")
		(net "P5E_PEX3_STN7_RX_DP<121>")
	)
	(segment
		(start 421.689784 -384.20802)
		(end 421.689784 -384.590036)
		(width 0.1651)
		(layer "In9.Cu")
		(net "P5E_PEX3_STN7_RX_DP<121>")
	)
	(segment
		(start 426.967142 -342.053926)
		(end 426.967142 -358.234996)
		(width 0.1651)
		(layer "In9.Cu")
		(net "P5E_PEX3_STN7_RX_DP<121>")
	)
	(segment
		(start 426.967142 -358.234996)
		(end 422.846754 -369.19662)
		(width 0.1651)
		(layer "In9.Cu")
		(net "P5E_PEX3_STN7_RX_DP<121>")
	)
	(segment
		(start 388.674102 -326.604122)
		(end 408.431492 -332.858364)
		(width 0.1651)
		(layer "In9.Cu")
		(net "P5E_PEX3_STN7_RX_DP<121>")
	)
	(segment
		(start 419.122098 -112.989614)
		(end 420.051484 -113.919)
		(width 0.13208)
		(layer "F.Cu")
		(net "NIC7_BIF2_N")
	)
	(segment
		(start 420.93261 -113.919)
		(end 421.048688 -114.035078)
		(width 0.13208)
		(layer "F.Cu")
		(net "NIC7_BIF2_N")
	)
	(segment
		(start 420.051484 -113.919)
		(end 420.93261 -113.919)
		(width 0.13208)
		(layer "F.Cu")
		(net "NIC7_BIF2_N")
	)
	(segment
		(start 421.048688 -114.035078)
		(end 421.557704 -114.035078)
		(width 0.13208)
		(layer "F.Cu")
		(net "NIC7_BIF2_N")
	)
	(via
		(at 419.122098 -112.989614)
		(size 0.508)
		(drill 0.254)
		(layers "F.Cu" "B.Cu")
		(net "NIC7_BIF2_N")
	)
	(via
		(at 413.831786 -109.982762)
		(size 0.6604)
		(drill 0.3302)
		(layers "F.Cu" "B.Cu")
		(net "NIC7_BIF2_N")
	)
	(segment
		(start 411.275276 -110.497366)
		(end 410.297376 -110.497366)
		(width 0.13208)
		(layer "B.Cu")
		(net "NIC7_BIF2_N")
	)
	(segment
		(start 413.831786 -109.982762)
		(end 414.278318 -109.982762)
		(width 0.13208)
		(layer "B.Cu")
		(net "NIC7_BIF2_N")
	)
	(segment
		(start 416.864038 -109.219492)
		(end 416.864038 -110.429802)
		(width 0.13208)
		(layer "B.Cu")
		(net "NIC7_BIF2_N")
	)
	(segment
		(start 414.278318 -109.982762)
		(end 415.491168 -108.769912)
		(width 0.13208)
		(layer "B.Cu")
		(net "NIC7_BIF2_N")
	)
	(segment
		(start 416.864038 -110.429802)
		(end 418.540946 -112.10671)
		(width 0.13208)
		(layer "B.Cu")
		(net "NIC7_BIF2_N")
	)
	(segment
		(start 411.275276 -110.497366)
		(end 411.275276 -110.19917)
		(width 0.13208)
		(layer "B.Cu")
		(net "NIC7_BIF2_N")
	)
	(segment
		(start 418.75456 -112.622076)
		(end 419.122098 -112.989614)
		(width 0.13208)
		(layer "B.Cu")
		(net "NIC7_BIF2_N")
	)
	(segment
		(start 416.414458 -108.769912)
		(end 416.864038 -109.219492)
		(width 0.13208)
		(layer "B.Cu")
		(net "NIC7_BIF2_N")
	)
	(segment
		(start 411.491684 -109.982762)
		(end 413.831786 -109.982762)
		(width 0.13208)
		(layer "B.Cu")
		(net "NIC7_BIF2_N")
	)
	(segment
		(start 415.491168 -108.769912)
		(end 416.414458 -108.769912)
		(width 0.13208)
		(layer "B.Cu")
		(net "NIC7_BIF2_N")
	)
	(segment
		(start 418.540946 -112.10671)
		(end 418.75456 -112.622076)
		(width 0.13208)
		(layer "B.Cu")
		(net "NIC7_BIF2_N")
	)
	(segment
		(start 411.275276 -110.19917)
		(end 411.491684 -109.982762)
		(width 0.13208)
		(layer "B.Cu")
		(net "NIC7_BIF2_N")
	)
	(segment
		(start 161.654236 -136.565132)
		(end 161.491168 -136.402064)
		(width 0.13462)
		(layer "F.Cu")
		(net "P5E_PEX1_STN1_TX_C_DP<31>")
	)
	(segment
		(start 161.491168 -136.402064)
		(end 155.974796 -136.402064)
		(width 0.13462)
		(layer "F.Cu")
		(net "P5E_PEX1_STN1_TX_C_DP<31>")
	)
	(segment
		(start 155.974796 -136.402064)
		(end 155.647136 -136.729724)
		(width 0.13462)
		(layer "F.Cu")
		(net "P5E_PEX1_STN1_TX_C_DP<31>")
	)
	(segment
		(start 162.14217 -136.565132)
		(end 161.654236 -136.565132)
		(width 0.13462)
		(layer "F.Cu")
		(net "P5E_PEX1_STN1_TX_C_DP<31>")
	)
	(segment
		(start 127.9652 -368.6048)
		(end 127.687578 -369.845082)
		(width 0.1651)
		(layer "In5.Cu")
		(net "P5E_PEX1_STN6_RX_DP<98>")
	)
	(segment
		(start 171.333922 -319.8876)
		(end 171.333922 -319.916048)
		(width 0.1143)
		(layer "In5.Cu")
		(net "P5E_PEX1_STN6_RX_DP<98>")
	)
	(segment
		(start 157.239716 -330.815696)
		(end 146.850354 -337.439508)
		(width 0.1651)
		(layer "In5.Cu")
		(net "P5E_PEX1_STN6_RX_DP<98>")
	)
	(segment
		(start 171.949872 -317.749936)
		(end 171.949872 -318.015366)
		(width 0.1143)
		(layer "In5.Cu")
		(net "P5E_PEX1_STN6_RX_DP<98>")
	)
	(segment
		(start 138.579098 -357.921814)
		(end 138.202162 -358.831896)
		(width 0.1651)
		(layer "In5.Cu")
		(net "P5E_PEX1_STN6_RX_DP<98>")
	)
	(segment
		(start 136.506458 -360.5276)
		(end 129.383282 -367.263934)
		(width 0.1651)
		(layer "In5.Cu")
		(net "P5E_PEX1_STN6_RX_DP<98>")
	)
	(segment
		(start 171.605448 -318.129666)
		(end 171.379642 -318.355472)
		(width 0.1143)
		(layer "In5.Cu")
		(net "P5E_PEX1_STN6_RX_DP<98>")
	)
	(segment
		(start 169.713148 -323.443092)
		(end 157.239716 -330.815696)
		(width 0.1651)
		(layer "In5.Cu")
		(net "P5E_PEX1_STN6_RX_DP<98>")
	)
	(segment
		(start 171.333922 -321.332098)
		(end 170.283124 -322.904104)
		(width 0.1651)
		(layer "In5.Cu")
		(net "P5E_PEX1_STN6_RX_DP<98>")
	)
	(segment
		(start 127.687578 -369.845082)
		(end 127.687578 -375.78157)
		(width 0.1651)
		(layer "In5.Cu")
		(net "P5E_PEX1_STN6_RX_DP<98>")
	)
	(segment
		(start 171.949872 -318.015366)
		(end 171.835572 -318.129666)
		(width 0.1143)
		(layer "In5.Cu")
		(net "P5E_PEX1_STN6_RX_DP<98>")
	)
	(segment
		(start 146.850354 -337.439508)
		(end 139.0396 -340.741)
		(width 0.1651)
		(layer "In5.Cu")
		(net "P5E_PEX1_STN6_RX_DP<98>")
	)
	(segment
		(start 138.579098 -341.201502)
		(end 138.579098 -357.921814)
		(width 0.1651)
		(layer "In5.Cu")
		(net "P5E_PEX1_STN6_RX_DP<98>")
	)
	(segment
		(start 138.202162 -358.831896)
		(end 136.506458 -360.5276)
		(width 0.1651)
		(layer "In5.Cu")
		(net "P5E_PEX1_STN6_RX_DP<98>")
	)
	(segment
		(start 127.4699 -375.999248)
		(end 127.037084 -375.999248)
		(width 0.1651)
		(layer "In5.Cu")
		(net "P5E_PEX1_STN6_RX_DP<98>")
	)
	(segment
		(start 170.283124 -322.904104)
		(end 169.713148 -323.443092)
		(width 0.1651)
		(layer "In5.Cu")
		(net "P5E_PEX1_STN6_RX_DP<98>")
	)
	(segment
		(start 127.687578 -375.78157)
		(end 127.4699 -375.999248)
		(width 0.1651)
		(layer "In5.Cu")
		(net "P5E_PEX1_STN6_RX_DP<98>")
	)
	(segment
		(start 171.379642 -318.355472)
		(end 171.379642 -319.84188)
		(width 0.1143)
		(layer "In5.Cu")
		(net "P5E_PEX1_STN6_RX_DP<98>")
	)
	(segment
		(start 129.225294 -367.259362)
		(end 128.874266 -367.59134)
		(width 0.1651)
		(layer "In5.Cu")
		(net "P5E_PEX1_STN6_RX_DP<98>")
	)
	(segment
		(start 128.869948 -367.749328)
		(end 127.9652 -368.6048)
		(width 0.1651)
		(layer "In5.Cu")
		(net "P5E_PEX1_STN6_RX_DP<98>")
	)
	(segment
		(start 139.0396 -340.741)
		(end 138.579098 -341.201502)
		(width 0.1651)
		(layer "In5.Cu")
		(net "P5E_PEX1_STN6_RX_DP<98>")
	)
	(segment
		(start 129.383282 -367.263934)
		(end 129.225294 -367.259362)
		(width 0.1651)
		(layer "In5.Cu")
		(net "P5E_PEX1_STN6_RX_DP<98>")
	)
	(segment
		(start 171.379642 -319.84188)
		(end 171.333922 -319.8876)
		(width 0.1143)
		(layer "In5.Cu")
		(net "P5E_PEX1_STN6_RX_DP<98>")
	)
	(segment
		(start 127.037084 -375.999248)
		(end 126.910084 -375.872248)
		(width 0.1651)
		(layer "In5.Cu")
		(net "P5E_PEX1_STN6_RX_DP<98>")
	)
	(segment
		(start 171.333922 -319.916048)
		(end 171.333922 -321.332098)
		(width 0.1651)
		(layer "In5.Cu")
		(net "P5E_PEX1_STN6_RX_DP<98>")
	)
	(segment
		(start 126.910084 -375.872248)
		(end 126.910084 -375.490232)
		(width 0.1651)
		(layer "In5.Cu")
		(net "P5E_PEX1_STN6_RX_DP<98>")
	)
	(segment
		(start 128.874266 -367.59134)
		(end 128.869948 -367.749328)
		(width 0.1651)
		(layer "In5.Cu")
		(net "P5E_PEX1_STN6_RX_DP<98>")
	)
	(segment
		(start 171.835572 -318.129666)
		(end 171.605448 -318.129666)
		(width 0.1143)
		(layer "In5.Cu")
		(net "P5E_PEX1_STN6_RX_DP<98>")
	)
	(segment
		(start 272.07591 -136.144)
		(end 277.563834 -136.144)
		(width 0.13462)
		(layer "F.Cu")
		(net "P5E_PEX2_STN1_TX_C_DN<31>")
	)
	(segment
		(start 277.563834 -136.144)
		(end 277.742904 -135.96493)
		(width 0.13462)
		(layer "F.Cu")
		(net "P5E_PEX2_STN1_TX_C_DN<31>")
	)
	(segment
		(start 277.742904 -135.96493)
		(end 278.242268 -135.96493)
		(width 0.13462)
		(layer "F.Cu")
		(net "P5E_PEX2_STN1_TX_C_DN<31>")
	)
	(segment
		(start 271.747234 -135.815324)
		(end 272.07591 -136.144)
		(width 0.13462)
		(layer "F.Cu")
		(net "P5E_PEX2_STN1_TX_C_DN<31>")
	)
	(segment
		(start 346.844366 -340.606126)
		(end 357.537004 -368.824256)
		(width 0.1651)
		(layer "In9.Cu")
		(net "P5E_PEX2_STN5_RX_DP<86>")
	)
	(segment
		(start 296.018966 -316.455298)
		(end 296.018966 -319.73266)
		(width 0.1143)
		(layer "In9.Cu")
		(net "P5E_PEX2_STN5_RX_DP<86>")
	)
	(segment
		(start 357.724456 -370.221256)
		(end 357.430324 -386.275072)
		(width 0.1651)
		(layer "In9.Cu")
		(net "P5E_PEX2_STN5_RX_DP<86>")
	)
	(segment
		(start 296.925746 -320.704464)
		(end 296.945812 -320.72453)
		(width 0.1143)
		(layer "In9.Cu")
		(net "P5E_PEX2_STN5_RX_DP<86>")
	)
	(segment
		(start 347.642942 -393.599416)
		(end 347.270578 -393.899898)
		(width 0.1651)
		(layer "In9.Cu")
		(net "P5E_PEX2_STN5_RX_DP<86>")
	)
	(segment
		(start 296.244772 -316.229492)
		(end 296.018966 -316.455298)
		(width 0.1143)
		(layer "In9.Cu")
		(net "P5E_PEX2_STN5_RX_DP<86>")
	)
	(segment
		(start 348.74708 -393.069826)
		(end 348.285816 -393.251182)
		(width 0.1651)
		(layer "In9.Cu")
		(net "P5E_PEX2_STN5_RX_DP<86>")
	)
	(segment
		(start 296.945812 -320.72453)
		(end 297.061636 -320.840354)
		(width 0.1651)
		(layer "In9.Cu")
		(net "P5E_PEX2_STN5_RX_DP<86>")
	)
	(segment
		(start 348.862396 -393.120118)
		(end 348.74708 -393.069826)
		(width 0.1651)
		(layer "In9.Cu")
		(net "P5E_PEX2_STN5_RX_DP<86>")
	)
	(segment
		(start 345.493086 -396.545054)
		(end 345.038934 -396.999206)
		(width 0.1651)
		(layer "In9.Cu")
		(net "P5E_PEX2_STN5_RX_DP<86>")
	)
	(segment
		(start 348.285816 -393.251182)
		(end 348.235524 -393.366498)
		(width 0.1651)
		(layer "In9.Cu")
		(net "P5E_PEX2_STN5_RX_DP<86>")
	)
	(segment
		(start 350.922336 -392.214862)
		(end 350.461072 -392.396218)
		(width 0.1651)
		(layer "In9.Cu")
		(net "P5E_PEX2_STN5_RX_DP<86>")
	)
	(segment
		(start 298.464986 -321.17538)
		(end 342.350598 -337.288886)
		(width 0.1651)
		(layer "In9.Cu")
		(net "P5E_PEX2_STN5_RX_DP<86>")
	)
	(segment
		(start 349.323152 -392.939016)
		(end 348.862396 -393.120118)
		(width 0.1651)
		(layer "In9.Cu")
		(net "P5E_PEX2_STN5_RX_DP<86>")
	)
	(segment
		(start 356.766876 -388.067042)
		(end 355.160834 -390.00938)
		(width 0.1651)
		(layer "In9.Cu")
		(net "P5E_PEX2_STN5_RX_DP<86>")
	)
	(segment
		(start 297.227752 -320.929254)
		(end 298.464986 -321.17538)
		(width 0.1651)
		(layer "In9.Cu")
		(net "P5E_PEX2_STN5_RX_DP<86>")
	)
	(segment
		(start 350.461072 -392.396218)
		(end 350.41078 -392.511534)
		(width 0.1651)
		(layer "In9.Cu")
		(net "P5E_PEX2_STN5_RX_DP<86>")
	)
	(segment
		(start 349.950024 -392.692636)
		(end 349.834708 -392.642344)
		(width 0.1651)
		(layer "In9.Cu")
		(net "P5E_PEX2_STN5_RX_DP<86>")
	)
	(segment
		(start 345.038934 -396.999206)
		(end 344.816938 -396.999206)
		(width 0.1651)
		(layer "In9.Cu")
		(net "P5E_PEX2_STN5_RX_DP<86>")
	)
	(segment
		(start 296.925746 -320.63944)
		(end 296.925746 -320.704464)
		(width 0.1143)
		(layer "In9.Cu")
		(net "P5E_PEX2_STN5_RX_DP<86>")
	)
	(segment
		(start 344.816938 -396.999206)
		(end 344.689938 -396.872206)
		(width 0.1651)
		(layer "In9.Cu")
		(net "P5E_PEX2_STN5_RX_DP<86>")
	)
	(segment
		(start 342.350598 -337.288886)
		(end 345.675966 -339.4202)
		(width 0.1651)
		(layer "In9.Cu")
		(net "P5E_PEX2_STN5_RX_DP<86>")
	)
	(segment
		(start 349.373444 -392.8237)
		(end 349.323152 -392.939016)
		(width 0.1651)
		(layer "In9.Cu")
		(net "P5E_PEX2_STN5_RX_DP<86>")
	)
	(segment
		(start 348.235524 -393.366498)
		(end 347.642942 -393.599416)
		(width 0.1651)
		(layer "In9.Cu")
		(net "P5E_PEX2_STN5_RX_DP<86>")
	)
	(segment
		(start 296.599864 -315.849762)
		(end 296.599864 -316.102492)
		(width 0.1143)
		(layer "In9.Cu")
		(net "P5E_PEX2_STN5_RX_DP<86>")
	)
	(segment
		(start 357.537004 -368.824256)
		(end 357.724456 -370.221256)
		(width 0.1651)
		(layer "In9.Cu")
		(net "P5E_PEX2_STN5_RX_DP<86>")
	)
	(segment
		(start 355.160834 -390.00938)
		(end 353.245674 -391.397236)
		(width 0.1651)
		(layer "In9.Cu")
		(net "P5E_PEX2_STN5_RX_DP<86>")
	)
	(segment
		(start 296.018966 -319.73266)
		(end 296.925746 -320.63944)
		(width 0.1143)
		(layer "In9.Cu")
		(net "P5E_PEX2_STN5_RX_DP<86>")
	)
	(segment
		(start 344.689938 -396.872206)
		(end 344.689938 -396.49019)
		(width 0.1651)
		(layer "In9.Cu")
		(net "P5E_PEX2_STN5_RX_DP<86>")
	)
	(segment
		(start 296.472864 -316.229492)
		(end 296.244772 -316.229492)
		(width 0.1143)
		(layer "In9.Cu")
		(net "P5E_PEX2_STN5_RX_DP<86>")
	)
	(segment
		(start 296.599864 -316.102492)
		(end 296.472864 -316.229492)
		(width 0.1143)
		(layer "In9.Cu")
		(net "P5E_PEX2_STN5_RX_DP<86>")
	)
	(segment
		(start 345.675966 -339.4202)
		(end 346.844366 -340.606126)
		(width 0.1651)
		(layer "In9.Cu")
		(net "P5E_PEX2_STN5_RX_DP<86>")
	)
	(segment
		(start 357.430324 -386.275072)
		(end 356.766876 -388.067042)
		(width 0.1651)
		(layer "In9.Cu")
		(net "P5E_PEX2_STN5_RX_DP<86>")
	)
	(segment
		(start 347.270578 -393.899898)
		(end 345.493086 -396.545054)
		(width 0.1651)
		(layer "In9.Cu")
		(net "P5E_PEX2_STN5_RX_DP<86>")
	)
	(segment
		(start 350.41078 -392.511534)
		(end 349.950024 -392.692636)
		(width 0.1651)
		(layer "In9.Cu")
		(net "P5E_PEX2_STN5_RX_DP<86>")
	)
	(segment
		(start 351.037652 -392.265154)
		(end 350.922336 -392.214862)
		(width 0.1651)
		(layer "In9.Cu")
		(net "P5E_PEX2_STN5_RX_DP<86>")
	)
	(segment
		(start 353.245674 -391.397236)
		(end 351.037652 -392.265154)
		(width 0.1651)
		(layer "In9.Cu")
		(net "P5E_PEX2_STN5_RX_DP<86>")
	)
	(segment
		(start 349.834708 -392.642344)
		(end 349.373444 -392.8237)
		(width 0.1651)
		(layer "In9.Cu")
		(net "P5E_PEX2_STN5_RX_DP<86>")
	)
	(segment
		(start 297.061636 -320.840354)
		(end 297.227752 -320.929254)
		(width 0.1651)
		(layer "In9.Cu")
		(net "P5E_PEX2_STN5_RX_DP<86>")
	)
	(segment
		(start 422.224962 -148.31568)
		(end 422.064434 -148.155152)
		(width 0.13462)
		(layer "F.Cu")
		(net "P5E_PEX3_STN0_TX_C_DN<11>")
	)
	(segment
		(start 430.694846 -147.99691)
		(end 430.376076 -148.31568)
		(width 0.13462)
		(layer "F.Cu")
		(net "P5E_PEX3_STN0_TX_C_DN<11>")
	)
	(segment
		(start 430.376076 -148.31568)
		(end 422.224962 -148.31568)
		(width 0.13462)
		(layer "F.Cu")
		(net "P5E_PEX3_STN0_TX_C_DN<11>")
	)
	(segment
		(start 422.064434 -148.155152)
		(end 421.557704 -148.155152)
		(width 0.13462)
		(layer "F.Cu")
		(net "P5E_PEX3_STN0_TX_C_DN<11>")
	)
	(segment
		(start 424.814492 -350.365314)
		(end 425.13504 -350.685862)
		(width 0.13462)
		(layer "F.Cu")
		(net "P5E_PEX3_STN7_TX_C_DP<119>")
	)
	(segment
		(start 425.13504 -350.685862)
		(end 425.13504 -351.31629)
		(width 0.13462)
		(layer "F.Cu")
		(net "P5E_PEX3_STN7_TX_C_DP<119>")
	)
	(segment
		(start 425.13504 -351.31629)
		(end 424.839892 -351.611438)
		(width 0.13462)
		(layer "F.Cu")
		(net "P5E_PEX3_STN7_TX_C_DP<119>")
	)
	(segment
		(start 435.733952 -401.71243)
		(end 435.447186 -401.999196)
		(width 0.1651)
		(layer "In11.Cu")
		(net "P5E_PEX3_STN7_TX_C_DP<119>")
	)
	(segment
		(start 424.839892 -351.611438)
		(end 425.130722 -351.902268)
		(width 0.1651)
		(layer "In11.Cu")
		(net "P5E_PEX3_STN7_TX_C_DP<119>")
	)
	(segment
		(start 435.733952 -395.314932)
		(end 435.733952 -401.71243)
		(width 0.1651)
		(layer "In11.Cu")
		(net "P5E_PEX3_STN7_TX_C_DP<119>")
	)
	(segment
		(start 423.576242 -359.002838)
		(end 418.156644 -369.238276)
		(width 0.1651)
		(layer "In11.Cu")
		(net "P5E_PEX3_STN7_TX_C_DP<119>")
	)
	(segment
		(start 418.136832 -384.849624)
		(end 418.36848 -385.445508)
		(width 0.1651)
		(layer "In11.Cu")
		(net "P5E_PEX3_STN7_TX_C_DP<119>")
	)
	(segment
		(start 422.574212 -387.54812)
		(end 422.613836 -387.6675)
		(width 0.1651)
		(layer "In11.Cu")
		(net "P5E_PEX3_STN7_TX_C_DP<119>")
	)
	(segment
		(start 422.613836 -387.6675)
		(end 423.057066 -387.889242)
		(width 0.1651)
		(layer "In11.Cu")
		(net "P5E_PEX3_STN7_TX_C_DP<119>")
	)
	(segment
		(start 423.659046 -388.190232)
		(end 424.102276 -388.411974)
		(width 0.1651)
		(layer "In11.Cu")
		(net "P5E_PEX3_STN7_TX_C_DP<119>")
	)
	(segment
		(start 434.942488 -394.667232)
		(end 435.086252 -394.667232)
		(width 0.1651)
		(layer "In11.Cu")
		(net "P5E_PEX3_STN7_TX_C_DP<119>")
	)
	(segment
		(start 425.130722 -351.902268)
		(end 425.130722 -352.356166)
		(width 0.1651)
		(layer "In11.Cu")
		(net "P5E_PEX3_STN7_TX_C_DP<119>")
	)
	(segment
		(start 434.591968 -394.316712)
		(end 434.942488 -394.667232)
		(width 0.1651)
		(layer "In11.Cu")
		(net "P5E_PEX3_STN7_TX_C_DP<119>")
	)
	(segment
		(start 418.156644 -369.238276)
		(end 418.005006 -383.373376)
		(width 0.1651)
		(layer "In11.Cu")
		(net "P5E_PEX3_STN7_TX_C_DP<119>")
	)
	(segment
		(start 423.057066 -387.889242)
		(end 423.176446 -387.849618)
		(width 0.1651)
		(layer "In11.Cu")
		(net "P5E_PEX3_STN7_TX_C_DP<119>")
	)
	(segment
		(start 423.576242 -353.910646)
		(end 423.576242 -359.002838)
		(width 0.1651)
		(layer "In11.Cu")
		(net "P5E_PEX3_STN7_TX_C_DP<119>")
	)
	(segment
		(start 424.102276 -388.411974)
		(end 424.221656 -388.37235)
		(width 0.1651)
		(layer "In11.Cu")
		(net "P5E_PEX3_STN7_TX_C_DP<119>")
	)
	(segment
		(start 434.88991 -401.872196)
		(end 434.88991 -401.49018)
		(width 0.1651)
		(layer "In11.Cu")
		(net "P5E_PEX3_STN7_TX_C_DP<119>")
	)
	(segment
		(start 423.176446 -387.849618)
		(end 423.619422 -388.071106)
		(width 0.1651)
		(layer "In11.Cu")
		(net "P5E_PEX3_STN7_TX_C_DP<119>")
	)
	(segment
		(start 424.221656 -388.37235)
		(end 433.360068 -392.941302)
		(width 0.1651)
		(layer "In11.Cu")
		(net "P5E_PEX3_STN7_TX_C_DP<119>")
	)
	(segment
		(start 418.36848 -385.445508)
		(end 422.574212 -387.54812)
		(width 0.1651)
		(layer "In11.Cu")
		(net "P5E_PEX3_STN7_TX_C_DP<119>")
	)
	(segment
		(start 435.01691 -401.999196)
		(end 434.88991 -401.872196)
		(width 0.1651)
		(layer "In11.Cu")
		(net "P5E_PEX3_STN7_TX_C_DP<119>")
	)
	(segment
		(start 435.447186 -401.999196)
		(end 435.01691 -401.999196)
		(width 0.1651)
		(layer "In11.Cu")
		(net "P5E_PEX3_STN7_TX_C_DP<119>")
	)
	(segment
		(start 433.360068 -392.941302)
		(end 434.591968 -394.172948)
		(width 0.1651)
		(layer "In11.Cu")
		(net "P5E_PEX3_STN7_TX_C_DP<119>")
	)
	(segment
		(start 434.591968 -394.172948)
		(end 434.591968 -394.316712)
		(width 0.1651)
		(layer "In11.Cu")
		(net "P5E_PEX3_STN7_TX_C_DP<119>")
	)
	(segment
		(start 418.005006 -383.373376)
		(end 418.136832 -384.849624)
		(width 0.1651)
		(layer "In11.Cu")
		(net "P5E_PEX3_STN7_TX_C_DP<119>")
	)
	(segment
		(start 425.130722 -352.356166)
		(end 423.576242 -353.910646)
		(width 0.1651)
		(layer "In11.Cu")
		(net "P5E_PEX3_STN7_TX_C_DP<119>")
	)
	(segment
		(start 435.086252 -394.667232)
		(end 435.733952 -395.314932)
		(width 0.1651)
		(layer "In11.Cu")
		(net "P5E_PEX3_STN7_TX_C_DP<119>")
	)
	(segment
		(start 423.619422 -388.071106)
		(end 423.659046 -388.190232)
		(width 0.1651)
		(layer "In11.Cu")
		(net "P5E_PEX3_STN7_TX_C_DP<119>")
	)
	(segment
		(start 412.609284 -99.439984)
		(end 416.95751 -99.439984)
		(width 0.13208)
		(layer "F.Cu")
		(net "NIC7_RBT_ARB_OUT")
	)
	(segment
		(start 411.473396 -99.439984)
		(end 412.609284 -99.439984)
		(width 0.13208)
		(layer "F.Cu")
		(net "NIC7_RBT_ARB_OUT")
	)
	(segment
		(start 406.895046 -99.062794)
		(end 407.022046 -99.189794)
		(width 0.13208)
		(layer "F.Cu")
		(net "NIC7_RBT_ARB_OUT")
	)
	(segment
		(start 411.223206 -99.189794)
		(end 411.473396 -99.439984)
		(width 0.13208)
		(layer "F.Cu")
		(net "NIC7_RBT_ARB_OUT")
	)
	(segment
		(start 406.895046 -98.734372)
		(end 406.895046 -99.062794)
		(width 0.13208)
		(layer "F.Cu")
		(net "NIC7_RBT_ARB_OUT")
	)
	(segment
		(start 407.022046 -99.189794)
		(end 411.223206 -99.189794)
		(width 0.13208)
		(layer "F.Cu")
		(net "NIC7_RBT_ARB_OUT")
	)
	(via
		(at 412.609284 -99.439984)
		(size 0.762)
		(drill 0.381)
		(layers "F.Cu" "B.Cu")
		(net "NIC7_RBT_ARB_OUT")
	)
	(segment
		(start 167.230298 -112.644936)
		(end 167.393112 -112.482122)
		(width 0.13462)
		(layer "F.Cu")
		(net "P5E_PEX1_STN1_RX_DN<23>")
	)
	(segment
		(start 168.048178 -112.482122)
		(end 168.342564 -112.776508)
		(width 0.13462)
		(layer "F.Cu")
		(net "P5E_PEX1_STN1_RX_DN<23>")
	)
	(segment
		(start 167.393112 -112.482122)
		(end 168.048178 -112.482122)
		(width 0.13462)
		(layer "F.Cu")
		(net "P5E_PEX1_STN1_RX_DN<23>")
	)
	(segment
		(start 166.742364 -112.644936)
		(end 167.230298 -112.644936)
		(width 0.13462)
		(layer "F.Cu")
		(net "P5E_PEX1_STN1_RX_DN<23>")
	)
	(segment
		(start 182.285386 -275.379688)
		(end 182.123588 -275.379688)
		(width 0.1143)
		(layer "In5.Cu")
		(net "P5E_PEX1_STN1_RX_DN<23>")
	)
	(segment
		(start 161.952432 -116.158772)
		(end 162.55111 -114.872008)
		(width 0.1651)
		(layer "In5.Cu")
		(net "P5E_PEX1_STN1_RX_DN<23>")
	)
	(segment
		(start 160.491678 -118.829836)
		(end 161.294826 -117.103398)
		(width 0.1651)
		(layer "In5.Cu")
		(net "P5E_PEX1_STN1_RX_DN<23>")
	)
	(segment
		(start 159.153098 -122.961654)
		(end 159.066484 -122.825256)
		(width 0.1651)
		(layer "In5.Cu")
		(net "P5E_PEX1_STN1_RX_DN<23>")
	)
	(segment
		(start 158.80207 -124.0155)
		(end 158.909258 -123.532138)
		(width 0.1651)
		(layer "In5.Cu")
		(net "P5E_PEX1_STN1_RX_DN<23>")
	)
	(segment
		(start 182.399686 -274.999958)
		(end 182.399686 -275.265388)
		(width 0.1143)
		(layer "In5.Cu")
		(net "P5E_PEX1_STN1_RX_DN<23>")
	)
	(segment
		(start 166.963852 -112.67313)
		(end 167.422068 -112.485678)
		(width 0.1651)
		(layer "In5.Cu")
		(net "P5E_PEX1_STN1_RX_DN<23>")
	)
	(segment
		(start 182.06593 -271.599406)
		(end 182.06593 -271.570958)
		(width 0.1143)
		(layer "In5.Cu")
		(net "P5E_PEX1_STN1_RX_DN<23>")
	)
	(segment
		(start 159.671766 -120.592088)
		(end 159.823658 -120.536716)
		(width 0.1651)
		(layer "In5.Cu")
		(net "P5E_PEX1_STN1_RX_DN<23>")
	)
	(segment
		(start 159.46247 -121.04243)
		(end 159.671766 -120.592088)
		(width 0.1651)
		(layer "In5.Cu")
		(net "P5E_PEX1_STN1_RX_DN<23>")
	)
	(segment
		(start 160.338008 -119.431054)
		(end 160.54705 -118.981728)
		(width 0.1651)
		(layer "In5.Cu")
		(net "P5E_PEX1_STN1_RX_DN<23>")
	)
	(segment
		(start 158.537656 -125.205744)
		(end 158.644844 -124.722382)
		(width 0.1651)
		(layer "In5.Cu")
		(net "P5E_PEX1_STN1_RX_DN<23>")
	)
	(segment
		(start 182.02021 -271.645126)
		(end 182.06593 -271.599406)
		(width 0.1143)
		(layer "In5.Cu")
		(net "P5E_PEX1_STN1_RX_DN<23>")
	)
	(segment
		(start 151.924004 -158.30169)
		(end 151.46274 -151.225504)
		(width 0.1651)
		(layer "In5.Cu")
		(net "P5E_PEX1_STN1_RX_DN<23>")
	)
	(segment
		(start 159.330898 -121.635012)
		(end 159.46247 -121.04243)
		(width 0.1651)
		(layer "In5.Cu")
		(net "P5E_PEX1_STN1_RX_DN<23>")
	)
	(segment
		(start 158.644844 -124.722382)
		(end 158.781242 -124.635768)
		(width 0.1651)
		(layer "In5.Cu")
		(net "P5E_PEX1_STN1_RX_DN<23>")
	)
	(segment
		(start 159.310324 -122.25528)
		(end 159.417766 -121.77141)
		(width 0.1651)
		(layer "In5.Cu")
		(net "P5E_PEX1_STN1_RX_DN<23>")
	)
	(segment
		(start 151.46274 -151.225504)
		(end 152.577292 -145.148046)
		(width 0.1651)
		(layer "In5.Cu")
		(net "P5E_PEX1_STN1_RX_DN<23>")
	)
	(segment
		(start 165.165024 -113.408968)
		(end 165.313868 -113.471452)
		(width 0.1651)
		(layer "In5.Cu")
		(net "P5E_PEX1_STN1_RX_DN<23>")
	)
	(segment
		(start 182.06593 -268.570202)
		(end 152.905968 -164.031168)
		(width 0.1651)
		(layer "In5.Cu")
		(net "P5E_PEX1_STN1_RX_DN<23>")
	)
	(segment
		(start 159.823658 -120.536716)
		(end 160.0327 -120.087136)
		(width 0.1651)
		(layer "In5.Cu")
		(net "P5E_PEX1_STN1_RX_DN<23>")
	)
	(segment
		(start 158.781242 -124.635768)
		(end 158.888684 -124.151898)
		(width 0.1651)
		(layer "In5.Cu")
		(net "P5E_PEX1_STN1_RX_DN<23>")
	)
	(segment
		(start 160.0327 -120.087136)
		(end 159.977328 -119.935498)
		(width 0.1651)
		(layer "In5.Cu")
		(net "P5E_PEX1_STN1_RX_DN<23>")
	)
	(segment
		(start 158.516828 -125.826012)
		(end 158.62427 -125.342142)
		(width 0.1651)
		(layer "In5.Cu")
		(net "P5E_PEX1_STN1_RX_DN<23>")
	)
	(segment
		(start 159.066484 -122.825256)
		(end 159.173672 -122.341894)
		(width 0.1651)
		(layer "In5.Cu")
		(net "P5E_PEX1_STN1_RX_DN<23>")
	)
	(segment
		(start 182.123588 -275.379688)
		(end 182.02021 -275.27631)
		(width 0.1143)
		(layer "In5.Cu")
		(net "P5E_PEX1_STN1_RX_DN<23>")
	)
	(segment
		(start 163.274248 -114.182144)
		(end 165.165024 -113.408968)
		(width 0.1651)
		(layer "In5.Cu")
		(net "P5E_PEX1_STN1_RX_DN<23>")
	)
	(segment
		(start 166.293546 -112.94745)
		(end 166.442644 -113.009934)
		(width 0.1651)
		(layer "In5.Cu")
		(net "P5E_PEX1_STN1_RX_DN<23>")
	)
	(segment
		(start 159.977328 -119.935498)
		(end 160.186116 -119.486426)
		(width 0.1651)
		(layer "In5.Cu")
		(net "P5E_PEX1_STN1_RX_DN<23>")
	)
	(segment
		(start 162.55111 -114.872008)
		(end 163.274248 -114.182144)
		(width 0.1651)
		(layer "In5.Cu")
		(net "P5E_PEX1_STN1_RX_DN<23>")
	)
	(segment
		(start 182.399686 -275.265388)
		(end 182.285386 -275.379688)
		(width 0.1143)
		(layer "In5.Cu")
		(net "P5E_PEX1_STN1_RX_DN<23>")
	)
	(segment
		(start 158.888684 -124.151898)
		(end 158.80207 -124.0155)
		(width 0.1651)
		(layer "In5.Cu")
		(net "P5E_PEX1_STN1_RX_DN<23>")
	)
	(segment
		(start 159.417766 -121.77141)
		(end 159.330898 -121.635012)
		(width 0.1651)
		(layer "In5.Cu")
		(net "P5E_PEX1_STN1_RX_DN<23>")
	)
	(segment
		(start 166.901114 -112.822482)
		(end 166.963852 -112.67313)
		(width 0.1651)
		(layer "In5.Cu")
		(net "P5E_PEX1_STN1_RX_DN<23>")
	)
	(segment
		(start 165.83533 -113.134902)
		(end 166.293546 -112.94745)
		(width 0.1651)
		(layer "In5.Cu")
		(net "P5E_PEX1_STN1_RX_DN<23>")
	)
	(segment
		(start 154.345894 -141.115288)
		(end 156.353256 -137.487406)
		(width 0.1651)
		(layer "In5.Cu")
		(net "P5E_PEX1_STN1_RX_DN<23>")
	)
	(segment
		(start 165.313868 -113.471452)
		(end 165.772592 -113.284)
		(width 0.1651)
		(layer "In5.Cu")
		(net "P5E_PEX1_STN1_RX_DN<23>")
	)
	(segment
		(start 159.173672 -122.341894)
		(end 159.310324 -122.25528)
		(width 0.1651)
		(layer "In5.Cu")
		(net "P5E_PEX1_STN1_RX_DN<23>")
	)
	(segment
		(start 160.54705 -118.981728)
		(end 160.491678 -118.829836)
		(width 0.1651)
		(layer "In5.Cu")
		(net "P5E_PEX1_STN1_RX_DN<23>")
	)
	(segment
		(start 152.577292 -145.148046)
		(end 154.345894 -141.115288)
		(width 0.1651)
		(layer "In5.Cu")
		(net "P5E_PEX1_STN1_RX_DN<23>")
	)
	(segment
		(start 160.186116 -119.486426)
		(end 160.338008 -119.431054)
		(width 0.1651)
		(layer "In5.Cu")
		(net "P5E_PEX1_STN1_RX_DN<23>")
	)
	(segment
		(start 152.905968 -164.031168)
		(end 151.924004 -158.30169)
		(width 0.1651)
		(layer "In5.Cu")
		(net "P5E_PEX1_STN1_RX_DN<23>")
	)
	(segment
		(start 182.02021 -275.27631)
		(end 182.02021 -271.645126)
		(width 0.1143)
		(layer "In5.Cu")
		(net "P5E_PEX1_STN1_RX_DN<23>")
	)
	(segment
		(start 158.62427 -125.342142)
		(end 158.537656 -125.205744)
		(width 0.1651)
		(layer "In5.Cu")
		(net "P5E_PEX1_STN1_RX_DN<23>")
	)
	(segment
		(start 158.38043 -125.912626)
		(end 158.516828 -125.826012)
		(width 0.1651)
		(layer "In5.Cu")
		(net "P5E_PEX1_STN1_RX_DN<23>")
	)
	(segment
		(start 182.06593 -271.570958)
		(end 182.06593 -268.570202)
		(width 0.1651)
		(layer "In5.Cu")
		(net "P5E_PEX1_STN1_RX_DN<23>")
	)
	(segment
		(start 167.422068 -112.485678)
		(end 168.051734 -112.485678)
		(width 0.1651)
		(layer "In5.Cu")
		(net "P5E_PEX1_STN1_RX_DN<23>")
	)
	(segment
		(start 166.442644 -113.009934)
		(end 166.901114 -112.822482)
		(width 0.1651)
		(layer "In5.Cu")
		(net "P5E_PEX1_STN1_RX_DN<23>")
	)
	(segment
		(start 158.909258 -123.532138)
		(end 159.045656 -123.445524)
		(width 0.1651)
		(layer "In5.Cu")
		(net "P5E_PEX1_STN1_RX_DN<23>")
	)
	(segment
		(start 156.353256 -137.487406)
		(end 157.8229 -128.4224)
		(width 0.1651)
		(layer "In5.Cu")
		(net "P5E_PEX1_STN1_RX_DN<23>")
	)
	(segment
		(start 157.8229 -128.4224)
		(end 158.38043 -125.912626)
		(width 0.1651)
		(layer "In5.Cu")
		(net "P5E_PEX1_STN1_RX_DN<23>")
	)
	(segment
		(start 161.294826 -117.103398)
		(end 161.952432 -116.158772)
		(width 0.1651)
		(layer "In5.Cu")
		(net "P5E_PEX1_STN1_RX_DN<23>")
	)
	(segment
		(start 168.051734 -112.485678)
		(end 168.342564 -112.776508)
		(width 0.1651)
		(layer "In5.Cu")
		(net "P5E_PEX1_STN1_RX_DN<23>")
	)
	(segment
		(start 165.772592 -113.284)
		(end 165.83533 -113.134902)
		(width 0.1651)
		(layer "In5.Cu")
		(net "P5E_PEX1_STN1_RX_DN<23>")
	)
	(segment
		(start 159.045656 -123.445524)
		(end 159.153098 -122.961654)
		(width 0.1651)
		(layer "In5.Cu")
		(net "P5E_PEX1_STN1_RX_DN<23>")
	)
	(segment
		(start 146.134836 -326.475598)
		(end 146.13509 -326.475598)
		(width 0.1651)
		(layer "In15.Cu")
		(net "P5E_PEX1_STN6_RX_DP<111>")
	)
	(segment
		(start 110.027212 -340.955122)
		(end 111.293402 -339.688932)
		(width 0.1651)
		(layer "In15.Cu")
		(net "P5E_PEX1_STN6_RX_DP<111>")
	)
	(segment
		(start 116.34089 -394.416788)
		(end 115.227608 -393.955778)
		(width 0.1651)
		(layer "In15.Cu")
		(net "P5E_PEX1_STN6_RX_DP<111>")
	)
	(segment
		(start 107.721654 -363.337602)
		(end 108.841794 -345.199462)
		(width 0.1651)
		(layer "In15.Cu")
		(net "P5E_PEX1_STN6_RX_DP<111>")
	)
	(segment
		(start 113.139728 -392.803126)
		(end 112.75568 -392.489944)
		(width 0.1651)
		(layer "In15.Cu")
		(net "P5E_PEX1_STN6_RX_DP<111>")
	)
	(segment
		(start 112.253776 -392.08075)
		(end 111.869728 -391.767568)
		(width 0.1651)
		(layer "In15.Cu")
		(net "P5E_PEX1_STN6_RX_DP<111>")
	)
	(segment
		(start 115.078256 -394.0175)
		(end 114.620548 -393.828016)
		(width 0.1651)
		(layer "In15.Cu")
		(net "P5E_PEX1_STN6_RX_DP<111>")
	)
	(segment
		(start 146.13509 -326.475598)
		(end 150.149814 -324.576186)
		(width 0.1651)
		(layer "In15.Cu")
		(net "P5E_PEX1_STN6_RX_DP<111>")
	)
	(segment
		(start 114.620548 -393.828016)
		(end 114.558572 -393.67841)
		(width 0.1651)
		(layer "In15.Cu")
		(net "P5E_PEX1_STN6_RX_DP<111>")
	)
	(segment
		(start 158.983934 -319.865248)
		(end 158.983934 -319.8368)
		(width 0.1143)
		(layer "In15.Cu")
		(net "P5E_PEX1_STN6_RX_DP<111>")
	)
	(segment
		(start 111.869728 -391.767568)
		(end 111.858806 -391.660126)
		(width 0.1651)
		(layer "In15.Cu")
		(net "P5E_PEX1_STN6_RX_DP<111>")
	)
	(segment
		(start 109.615732 -341.88908)
		(end 110.027212 -340.955122)
		(width 0.1651)
		(layer "In15.Cu")
		(net "P5E_PEX1_STN6_RX_DP<111>")
	)
	(segment
		(start 115.910106 -400.390106)
		(end 115.910106 -400.772122)
		(width 0.1651)
		(layer "In15.Cu")
		(net "P5E_PEX1_STN6_RX_DP<111>")
	)
	(segment
		(start 113.05667 -338.959698)
		(end 117.074696 -338.20481)
		(width 0.1651)
		(layer "In15.Cu")
		(net "P5E_PEX1_STN6_RX_DP<111>")
	)
	(segment
		(start 115.910106 -400.772122)
		(end 116.037106 -400.899122)
		(width 0.1651)
		(layer "In15.Cu")
		(net "P5E_PEX1_STN6_RX_DP<111>")
	)
	(segment
		(start 150.149814 -324.576186)
		(end 150.15083 -324.575932)
		(width 0.1651)
		(layer "In15.Cu")
		(net "P5E_PEX1_STN6_RX_DP<111>")
	)
	(segment
		(start 107.573064 -385.452874)
		(end 107.721654 -363.337602)
		(width 0.1651)
		(layer "In15.Cu")
		(net "P5E_PEX1_STN6_RX_DP<111>")
	)
	(segment
		(start 116.784882 -394.86078)
		(end 116.34089 -394.416788)
		(width 0.1651)
		(layer "In15.Cu")
		(net "P5E_PEX1_STN6_RX_DP<111>")
	)
	(segment
		(start 112.360964 -392.069828)
		(end 112.253776 -392.08075)
		(width 0.1651)
		(layer "In15.Cu")
		(net "P5E_PEX1_STN6_RX_DP<111>")
	)
	(segment
		(start 108.841794 -345.199462)
		(end 109.615732 -341.88908)
		(width 0.1651)
		(layer "In15.Cu")
		(net "P5E_PEX1_STN6_RX_DP<111>")
	)
	(segment
		(start 158.983934 -320.030602)
		(end 158.983934 -319.865248)
		(width 0.1651)
		(layer "In15.Cu")
		(net "P5E_PEX1_STN6_RX_DP<111>")
	)
	(segment
		(start 116.037106 -400.899122)
		(end 116.258594 -400.899122)
		(width 0.1651)
		(layer "In15.Cu")
		(net "P5E_PEX1_STN6_RX_DP<111>")
	)
	(segment
		(start 159.029654 -319.79108)
		(end 159.029654 -316.467998)
		(width 0.1143)
		(layer "In15.Cu")
		(net "P5E_PEX1_STN6_RX_DP<111>")
	)
	(segment
		(start 142.126208 -328.371962)
		(end 146.134836 -326.475598)
		(width 0.1651)
		(layer "In15.Cu")
		(net "P5E_PEX1_STN6_RX_DP<111>")
	)
	(segment
		(start 159.599884 -316.140592)
		(end 159.599884 -315.849762)
		(width 0.1143)
		(layer "In15.Cu")
		(net "P5E_PEX1_STN6_RX_DP<111>")
	)
	(segment
		(start 122.895868 -336.337148)
		(end 142.126208 -328.371962)
		(width 0.1651)
		(layer "In15.Cu")
		(net "P5E_PEX1_STN6_RX_DP<111>")
	)
	(segment
		(start 111.293402 -339.688932)
		(end 113.05667 -338.959698)
		(width 0.1651)
		(layer "In15.Cu")
		(net "P5E_PEX1_STN6_RX_DP<111>")
	)
	(segment
		(start 109.829854 -390.00557)
		(end 108.138468 -387.489192)
		(width 0.1651)
		(layer "In15.Cu")
		(net "P5E_PEX1_STN6_RX_DP<111>")
	)
	(segment
		(start 112.744758 -392.382756)
		(end 112.360964 -392.069828)
		(width 0.1651)
		(layer "In15.Cu")
		(net "P5E_PEX1_STN6_RX_DP<111>")
	)
	(segment
		(start 115.227608 -393.955778)
		(end 115.078256 -394.0175)
		(width 0.1651)
		(layer "In15.Cu")
		(net "P5E_PEX1_STN6_RX_DP<111>")
	)
	(segment
		(start 159.510984 -316.229492)
		(end 159.599884 -316.140592)
		(width 0.1143)
		(layer "In15.Cu")
		(net "P5E_PEX1_STN6_RX_DP<111>")
	)
	(segment
		(start 150.15083 -324.575932)
		(end 158.287974 -320.726562)
		(width 0.1651)
		(layer "In15.Cu")
		(net "P5E_PEX1_STN6_RX_DP<111>")
	)
	(segment
		(start 116.258594 -400.899122)
		(end 116.784882 -400.372834)
		(width 0.1651)
		(layer "In15.Cu")
		(net "P5E_PEX1_STN6_RX_DP<111>")
	)
	(segment
		(start 111.858806 -391.660126)
		(end 109.829854 -390.00557)
		(width 0.1651)
		(layer "In15.Cu")
		(net "P5E_PEX1_STN6_RX_DP<111>")
	)
	(segment
		(start 113.246916 -392.792204)
		(end 113.139728 -392.803126)
		(width 0.1651)
		(layer "In15.Cu")
		(net "P5E_PEX1_STN6_RX_DP<111>")
	)
	(segment
		(start 114.101118 -393.488926)
		(end 113.246916 -392.792204)
		(width 0.1651)
		(layer "In15.Cu")
		(net "P5E_PEX1_STN6_RX_DP<111>")
	)
	(segment
		(start 158.983934 -319.8368)
		(end 159.029654 -319.79108)
		(width 0.1143)
		(layer "In15.Cu")
		(net "P5E_PEX1_STN6_RX_DP<111>")
	)
	(segment
		(start 108.138468 -387.489192)
		(end 107.573064 -385.452874)
		(width 0.1651)
		(layer "In15.Cu")
		(net "P5E_PEX1_STN6_RX_DP<111>")
	)
	(segment
		(start 114.558572 -393.67841)
		(end 114.101118 -393.488926)
		(width 0.1651)
		(layer "In15.Cu")
		(net "P5E_PEX1_STN6_RX_DP<111>")
	)
	(segment
		(start 116.784882 -400.372834)
		(end 116.784882 -394.86078)
		(width 0.1651)
		(layer "In15.Cu")
		(net "P5E_PEX1_STN6_RX_DP<111>")
	)
	(segment
		(start 112.75568 -392.489944)
		(end 112.744758 -392.382756)
		(width 0.1651)
		(layer "In15.Cu")
		(net "P5E_PEX1_STN6_RX_DP<111>")
	)
	(segment
		(start 158.287974 -320.726562)
		(end 158.983934 -320.030602)
		(width 0.1651)
		(layer "In15.Cu")
		(net "P5E_PEX1_STN6_RX_DP<111>")
	)
	(segment
		(start 117.074696 -338.20481)
		(end 122.895868 -336.337148)
		(width 0.1651)
		(layer "In15.Cu")
		(net "P5E_PEX1_STN6_RX_DP<111>")
	)
	(segment
		(start 159.029654 -316.467998)
		(end 159.26816 -316.229492)
		(width 0.1143)
		(layer "In15.Cu")
		(net "P5E_PEX1_STN6_RX_DP<111>")
	)
	(segment
		(start 159.26816 -316.229492)
		(end 159.510984 -316.229492)
		(width 0.1143)
		(layer "In15.Cu")
		(net "P5E_PEX1_STN6_RX_DP<111>")
	)
	(segment
		(start 269.443708 -112.4712)
		(end 277.565612 -112.4712)
		(width 0.13462)
		(layer "F.Cu")
		(net "P5E_PEX2_STN1_TX_C_DP<23>")
	)
	(segment
		(start 277.739348 -112.644936)
		(end 278.242268 -112.644936)
		(width 0.13462)
		(layer "F.Cu")
		(net "P5E_PEX2_STN1_TX_C_DP<23>")
	)
	(segment
		(start 277.565612 -112.4712)
		(end 277.739348 -112.644936)
		(width 0.13462)
		(layer "F.Cu")
		(net "P5E_PEX2_STN1_TX_C_DP<23>")
	)
	(segment
		(start 269.105126 -112.809782)
		(end 269.443708 -112.4712)
		(width 0.13462)
		(layer "F.Cu")
		(net "P5E_PEX2_STN1_TX_C_DP<23>")
	)
	(segment
		(start 294.12946 -319.84188)
		(end 294.12946 -316.455044)
		(width 0.1143)
		(layer "In9.Cu")
		(net "P5E_PEX2_STN5_RX_DP<84>")
	)
	(segment
		(start 294.08374 -320.400426)
		(end 294.08374 -319.916048)
		(width 0.1651)
		(layer "In9.Cu")
		(net "P5E_PEX2_STN5_RX_DP<84>")
	)
	(segment
		(start 343.811606 -340.701122)
		(end 343.38895 -340.442296)
		(width 0.1651)
		(layer "In9.Cu")
		(net "P5E_PEX2_STN5_RX_DP<84>")
	)
	(segment
		(start 342.159082 -394.690854)
		(end 342.299798 -394.662152)
		(width 0.1651)
		(layer "In9.Cu")
		(net "P5E_PEX2_STN5_RX_DP<84>")
	)
	(segment
		(start 294.355012 -316.229492)
		(end 294.61079 -316.229492)
		(width 0.1143)
		(layer "In9.Cu")
		(net "P5E_PEX2_STN5_RX_DP<84>")
	)
	(segment
		(start 342.816942 -339.97265)
		(end 297.13555 -323.161914)
		(width 0.1651)
		(layer "In9.Cu")
		(net "P5E_PEX2_STN5_RX_DP<84>")
	)
	(segment
		(start 340.651338 -396.98676)
		(end 340.98357 -396.654528)
		(width 0.1651)
		(layer "In9.Cu")
		(net "P5E_PEX2_STN5_RX_DP<84>")
	)
	(segment
		(start 341.885778 -395.104366)
		(end 342.159082 -394.690854)
		(width 0.1651)
		(layer "In9.Cu")
		(net "P5E_PEX2_STN5_RX_DP<84>")
	)
	(segment
		(start 340.41715 -396.98676)
		(end 340.651338 -396.98676)
		(width 0.1651)
		(layer "In9.Cu")
		(net "P5E_PEX2_STN5_RX_DP<84>")
	)
	(segment
		(start 297.13555 -323.161914)
		(end 295.81348 -322.316094)
		(width 0.1651)
		(layer "In9.Cu")
		(net "P5E_PEX2_STN5_RX_DP<84>")
	)
	(segment
		(start 342.858344 -393.816332)
		(end 344.29446 -392.637518)
		(width 0.1651)
		(layer "In9.Cu")
		(net "P5E_PEX2_STN5_RX_DP<84>")
	)
	(segment
		(start 341.256366 -396.24127)
		(end 341.227664 -396.100554)
		(width 0.1651)
		(layer "In9.Cu")
		(net "P5E_PEX2_STN5_RX_DP<84>")
	)
	(segment
		(start 341.91448 -395.245082)
		(end 341.885778 -395.104366)
		(width 0.1651)
		(layer "In9.Cu")
		(net "P5E_PEX2_STN5_RX_DP<84>")
	)
	(segment
		(start 345.183206 -341.696802)
		(end 344.378026 -340.92896)
		(width 0.1651)
		(layer "In9.Cu")
		(net "P5E_PEX2_STN5_RX_DP<84>")
	)
	(segment
		(start 294.69969 -316.140592)
		(end 294.69969 -315.849762)
		(width 0.1143)
		(layer "In9.Cu")
		(net "P5E_PEX2_STN5_RX_DP<84>")
	)
	(segment
		(start 294.457882 -320.960496)
		(end 294.08374 -320.400426)
		(width 0.1651)
		(layer "In9.Cu")
		(net "P5E_PEX2_STN5_RX_DP<84>")
	)
	(segment
		(start 341.500968 -395.687042)
		(end 341.641684 -395.65834)
		(width 0.1651)
		(layer "In9.Cu")
		(net "P5E_PEX2_STN5_RX_DP<84>")
	)
	(segment
		(start 343.355422 -340.302596)
		(end 342.816942 -339.97265)
		(width 0.1651)
		(layer "In9.Cu")
		(net "P5E_PEX2_STN5_RX_DP<84>")
	)
	(segment
		(start 340.98357 -396.654528)
		(end 341.256366 -396.24127)
		(width 0.1651)
		(layer "In9.Cu")
		(net "P5E_PEX2_STN5_RX_DP<84>")
	)
	(segment
		(start 344.378026 -340.92896)
		(end 343.951306 -340.667594)
		(width 0.1651)
		(layer "In9.Cu")
		(net "P5E_PEX2_STN5_RX_DP<84>")
	)
	(segment
		(start 341.227664 -396.100554)
		(end 341.500968 -395.687042)
		(width 0.1651)
		(layer "In9.Cu")
		(net "P5E_PEX2_STN5_RX_DP<84>")
	)
	(segment
		(start 294.12946 -316.455044)
		(end 294.355012 -316.229492)
		(width 0.1143)
		(layer "In9.Cu")
		(net "P5E_PEX2_STN5_RX_DP<84>")
	)
	(segment
		(start 355.667818 -370.30406)
		(end 355.397054 -369.039902)
		(width 0.1651)
		(layer "In9.Cu")
		(net "P5E_PEX2_STN5_RX_DP<84>")
	)
	(segment
		(start 294.08374 -319.8876)
		(end 294.12946 -319.84188)
		(width 0.1143)
		(layer "In9.Cu")
		(net "P5E_PEX2_STN5_RX_DP<84>")
	)
	(segment
		(start 352.69551 -389.360664)
		(end 353.92487 -388.47141)
		(width 0.1651)
		(layer "In9.Cu")
		(net "P5E_PEX2_STN5_RX_DP<84>")
	)
	(segment
		(start 341.641684 -395.65834)
		(end 341.91448 -395.245082)
		(width 0.1651)
		(layer "In9.Cu")
		(net "P5E_PEX2_STN5_RX_DP<84>")
	)
	(segment
		(start 340.29015 -396.49019)
		(end 340.29015 -396.85976)
		(width 0.1651)
		(layer "In9.Cu")
		(net "P5E_PEX2_STN5_RX_DP<84>")
	)
	(segment
		(start 342.299798 -394.662152)
		(end 342.858344 -393.816332)
		(width 0.1651)
		(layer "In9.Cu")
		(net "P5E_PEX2_STN5_RX_DP<84>")
	)
	(segment
		(start 353.92487 -388.47141)
		(end 355.072188 -387.084316)
		(width 0.1651)
		(layer "In9.Cu")
		(net "P5E_PEX2_STN5_RX_DP<84>")
	)
	(segment
		(start 294.08374 -319.916048)
		(end 294.08374 -319.8876)
		(width 0.1143)
		(layer "In9.Cu")
		(net "P5E_PEX2_STN5_RX_DP<84>")
	)
	(segment
		(start 294.61079 -316.229492)
		(end 294.69969 -316.140592)
		(width 0.1143)
		(layer "In9.Cu")
		(net "P5E_PEX2_STN5_RX_DP<84>")
	)
	(segment
		(start 355.072188 -387.084316)
		(end 355.38029 -386.252466)
		(width 0.1651)
		(layer "In9.Cu")
		(net "P5E_PEX2_STN5_RX_DP<84>")
	)
	(segment
		(start 340.29015 -396.85976)
		(end 340.41715 -396.98676)
		(width 0.1651)
		(layer "In9.Cu")
		(net "P5E_PEX2_STN5_RX_DP<84>")
	)
	(segment
		(start 355.38029 -386.252466)
		(end 355.667818 -370.30406)
		(width 0.1651)
		(layer "In9.Cu")
		(net "P5E_PEX2_STN5_RX_DP<84>")
	)
	(segment
		(start 343.951306 -340.667594)
		(end 343.811606 -340.701122)
		(width 0.1651)
		(layer "In9.Cu")
		(net "P5E_PEX2_STN5_RX_DP<84>")
	)
	(segment
		(start 343.38895 -340.442296)
		(end 343.355422 -340.302596)
		(width 0.1651)
		(layer "In9.Cu")
		(net "P5E_PEX2_STN5_RX_DP<84>")
	)
	(segment
		(start 295.81348 -322.316094)
		(end 294.457882 -320.960496)
		(width 0.1651)
		(layer "In9.Cu")
		(net "P5E_PEX2_STN5_RX_DP<84>")
	)
	(segment
		(start 355.397054 -369.039902)
		(end 345.183206 -341.696802)
		(width 0.1651)
		(layer "In9.Cu")
		(net "P5E_PEX2_STN5_RX_DP<84>")
	)
	(segment
		(start 344.29446 -392.637518)
		(end 352.69551 -389.360664)
		(width 0.1651)
		(layer "In9.Cu")
		(net "P5E_PEX2_STN5_RX_DP<84>")
	)
	(segment
		(start 427.735492 -122.86742)
		(end 422.224708 -122.86742)
		(width 0.13462)
		(layer "F.Cu")
		(net "P5E_PEX3_STN0_TX_C_DP<2>")
	)
	(segment
		(start 422.057068 -123.03506)
		(end 421.557704 -123.03506)
		(width 0.13462)
		(layer "F.Cu")
		(net "P5E_PEX3_STN0_TX_C_DP<2>")
	)
	(segment
		(start 428.052738 -123.184666)
		(end 427.735492 -122.86742)
		(width 0.13462)
		(layer "F.Cu")
		(net "P5E_PEX3_STN0_TX_C_DP<2>")
	)
	(segment
		(start 422.224708 -122.86742)
		(end 422.057068 -123.03506)
		(width 0.13462)
		(layer "F.Cu")
		(net "P5E_PEX3_STN0_TX_C_DP<2>")
	)
	(segment
		(start 428.51832 -357.463598)
		(end 428.812452 -357.75773)
		(width 0.13462)
		(layer "F.Cu")
		(net "P5E_PEX3_STN7_TX_C_DP<121>")
	)
	(segment
		(start 428.837852 -356.511606)
		(end 428.51832 -356.831138)
		(width 0.13462)
		(layer "F.Cu")
		(net "P5E_PEX3_STN7_TX_C_DP<121>")
	)
	(segment
		(start 428.51832 -356.831138)
		(end 428.51832 -357.463598)
		(width 0.13462)
		(layer "F.Cu")
		(net "P5E_PEX3_STN7_TX_C_DP<121>")
	)
	(segment
		(start 422.3639 -376.281188)
		(end 422.815766 -375.829322)
		(width 0.1651)
		(layer "In11.Cu")
		(net "P5E_PEX3_STN7_TX_C_DP<121>")
	)
	(segment
		(start 428.227998 -359.507028)
		(end 428.521622 -358.420924)
		(width 0.1651)
		(layer "In11.Cu")
		(net "P5E_PEX3_STN7_TX_C_DP<121>")
	)
	(segment
		(start 421.816784 -376.281188)
		(end 422.3639 -376.281188)
		(width 0.1651)
		(layer "In11.Cu")
		(net "P5E_PEX3_STN7_TX_C_DP<121>")
	)
	(segment
		(start 421.689784 -376.790204)
		(end 421.689784 -376.408188)
		(width 0.1651)
		(layer "In11.Cu")
		(net "P5E_PEX3_STN7_TX_C_DP<121>")
	)
	(segment
		(start 428.521622 -358.420924)
		(end 428.521622 -358.04856)
		(width 0.1651)
		(layer "In11.Cu")
		(net "P5E_PEX3_STN7_TX_C_DP<121>")
	)
	(segment
		(start 421.689784 -376.408188)
		(end 421.816784 -376.281188)
		(width 0.1651)
		(layer "In11.Cu")
		(net "P5E_PEX3_STN7_TX_C_DP<121>")
	)
	(segment
		(start 428.521622 -358.04856)
		(end 428.812452 -357.75773)
		(width 0.1651)
		(layer "In11.Cu")
		(net "P5E_PEX3_STN7_TX_C_DP<121>")
	)
	(segment
		(start 423.28465 -367.985802)
		(end 428.227998 -359.507028)
		(width 0.1651)
		(layer "In11.Cu")
		(net "P5E_PEX3_STN7_TX_C_DP<121>")
	)
	(segment
		(start 422.815766 -375.829322)
		(end 422.815766 -369.720622)
		(width 0.1651)
		(layer "In11.Cu")
		(net "P5E_PEX3_STN7_TX_C_DP<121>")
	)
	(segment
		(start 422.815766 -369.720622)
		(end 423.28465 -367.985802)
		(width 0.1651)
		(layer "In11.Cu")
		(net "P5E_PEX3_STN7_TX_C_DP<121>")
	)
	(segment
		(start 383.75209 -25.390094)
		(end 383.20218 -25.940004)
		(width 0.13208)
		(layer "F.Cu")
		(net "PRSNT_SSD13_N")
	)
	(segment
		(start 383.20218 -25.940004)
		(end 383.20218 -26.266394)
		(width 0.13208)
		(layer "F.Cu")
		(net "PRSNT_SSD13_N")
	)
	(segment
		(start 383.20218 -26.266394)
		(end 382.420622 -26.266394)
		(width 0.13208)
		(layer "F.Cu")
		(net "PRSNT_SSD13_N")
	)
	(segment
		(start 384.96494 -25.390094)
		(end 383.75209 -25.390094)
		(width 0.13208)
		(layer "F.Cu")
		(net "PRSNT_SSD13_N")
	)
	(via
		(at 383.20218 -26.266394)
		(size 0.508)
		(drill 0.254)
		(layers "F.Cu" "B.Cu")
		(net "PRSNT_SSD13_N")
	)
	(segment
		(start 167.393366 -101.682042)
		(end 168.048178 -101.682042)
		(width 0.13462)
		(layer "F.Cu")
		(net "P5E_PEX1_STN1_RX_DN<17>")
	)
	(segment
		(start 166.742364 -101.84511)
		(end 167.230298 -101.84511)
		(width 0.13462)
		(layer "F.Cu")
		(net "P5E_PEX1_STN1_RX_DN<17>")
	)
	(segment
		(start 168.048178 -101.682042)
		(end 168.342564 -101.976428)
		(width 0.13462)
		(layer "F.Cu")
		(net "P5E_PEX1_STN1_RX_DN<17>")
	)
	(segment
		(start 167.230298 -101.84511)
		(end 167.393366 -101.682042)
		(width 0.13462)
		(layer "F.Cu")
		(net "P5E_PEX1_STN1_RX_DN<17>")
	)
	(segment
		(start 147.17522 -165.351968)
		(end 145.985738 -158.838138)
		(width 0.1651)
		(layer "In5.Cu")
		(net "P5E_PEX1_STN1_RX_DN<17>")
	)
	(segment
		(start 162.350196 -104.84866)
		(end 162.392868 -104.692704)
		(width 0.1651)
		(layer "In5.Cu")
		(net "P5E_PEX1_STN1_RX_DN<17>")
	)
	(segment
		(start 176.699672 -274.999704)
		(end 176.699672 -275.265134)
		(width 0.1143)
		(layer "In5.Cu")
		(net "P5E_PEX1_STN1_RX_DN<17>")
	)
	(segment
		(start 163.426902 -104.102662)
		(end 163.582858 -104.145334)
		(width 0.1651)
		(layer "In5.Cu")
		(net "P5E_PEX1_STN1_RX_DN<17>")
	)
	(segment
		(start 176.365916 -271.599152)
		(end 176.365916 -271.570704)
		(width 0.1143)
		(layer "In5.Cu")
		(net "P5E_PEX1_STN1_RX_DN<17>")
	)
	(segment
		(start 176.423574 -275.379434)
		(end 176.320196 -275.276056)
		(width 0.1143)
		(layer "In5.Cu")
		(net "P5E_PEX1_STN1_RX_DN<17>")
	)
	(segment
		(start 158.313374 -108.288582)
		(end 158.65602 -107.931204)
		(width 0.1651)
		(layer "In5.Cu")
		(net "P5E_PEX1_STN1_RX_DN<17>")
	)
	(segment
		(start 160.001204 -106.528362)
		(end 160.997646 -105.488994)
		(width 0.1651)
		(layer "In5.Cu")
		(net "P5E_PEX1_STN1_RX_DN<17>")
	)
	(segment
		(start 162.392868 -104.692704)
		(end 163.426902 -104.102662)
		(width 0.1651)
		(layer "In5.Cu")
		(net "P5E_PEX1_STN1_RX_DN<17>")
	)
	(segment
		(start 158.65602 -107.931204)
		(end 158.817564 -107.927902)
		(width 0.1651)
		(layer "In5.Cu")
		(net "P5E_PEX1_STN1_RX_DN<17>")
	)
	(segment
		(start 165.114986 -103.139494)
		(end 165.545008 -102.89413)
		(width 0.1651)
		(layer "In5.Cu")
		(net "P5E_PEX1_STN1_RX_DN<17>")
	)
	(segment
		(start 167.19042 -102.086918)
		(end 167.233092 -101.930962)
		(width 0.1651)
		(layer "In5.Cu")
		(net "P5E_PEX1_STN1_RX_DN<17>")
	)
	(segment
		(start 165.545008 -102.89413)
		(end 165.70071 -102.936802)
		(width 0.1651)
		(layer "In5.Cu")
		(net "P5E_PEX1_STN1_RX_DN<17>")
	)
	(segment
		(start 164.641784 -103.541068)
		(end 165.072314 -103.29545)
		(width 0.1651)
		(layer "In5.Cu")
		(net "P5E_PEX1_STN1_RX_DN<17>")
	)
	(segment
		(start 159.661606 -107.047792)
		(end 160.004506 -106.689906)
		(width 0.1651)
		(layer "In5.Cu")
		(net "P5E_PEX1_STN1_RX_DN<17>")
	)
	(segment
		(start 149.66696 -117.307614)
		(end 157.812232 -108.811314)
		(width 0.1651)
		(layer "In5.Cu")
		(net "P5E_PEX1_STN1_RX_DN<17>")
	)
	(segment
		(start 161.763964 -105.051606)
		(end 161.91992 -105.094278)
		(width 0.1651)
		(layer "In5.Cu")
		(net "P5E_PEX1_STN1_RX_DN<17>")
	)
	(segment
		(start 166.173912 -102.535228)
		(end 166.603934 -102.289864)
		(width 0.1651)
		(layer "In5.Cu")
		(net "P5E_PEX1_STN1_RX_DN<17>")
	)
	(segment
		(start 161.91992 -105.094278)
		(end 162.350196 -104.84866)
		(width 0.1651)
		(layer "In5.Cu")
		(net "P5E_PEX1_STN1_RX_DN<17>")
	)
	(segment
		(start 164.486082 -103.498396)
		(end 164.641784 -103.541068)
		(width 0.1651)
		(layer "In5.Cu")
		(net "P5E_PEX1_STN1_RX_DN<17>")
	)
	(segment
		(start 158.817564 -107.927902)
		(end 159.160464 -107.570016)
		(width 0.1651)
		(layer "In5.Cu")
		(net "P5E_PEX1_STN1_RX_DN<17>")
	)
	(segment
		(start 160.997646 -105.488994)
		(end 161.763964 -105.051606)
		(width 0.1651)
		(layer "In5.Cu")
		(net "P5E_PEX1_STN1_RX_DN<17>")
	)
	(segment
		(start 158.316676 -108.450126)
		(end 158.313374 -108.288582)
		(width 0.1651)
		(layer "In5.Cu")
		(net "P5E_PEX1_STN1_RX_DN<17>")
	)
	(segment
		(start 166.603934 -102.289864)
		(end 166.75989 -102.332536)
		(width 0.1651)
		(layer "In5.Cu")
		(net "P5E_PEX1_STN1_RX_DN<17>")
	)
	(segment
		(start 176.365916 -271.570704)
		(end 176.365916 -269.900654)
		(width 0.1651)
		(layer "In5.Cu")
		(net "P5E_PEX1_STN1_RX_DN<17>")
	)
	(segment
		(start 164.05606 -103.74376)
		(end 164.486082 -103.498396)
		(width 0.1651)
		(layer "In5.Cu")
		(net "P5E_PEX1_STN1_RX_DN<17>")
	)
	(segment
		(start 159.499808 -107.051094)
		(end 159.661606 -107.047792)
		(width 0.1651)
		(layer "In5.Cu")
		(net "P5E_PEX1_STN1_RX_DN<17>")
	)
	(segment
		(start 148.331682 -119.95023)
		(end 149.66696 -117.307614)
		(width 0.1651)
		(layer "In5.Cu")
		(net "P5E_PEX1_STN1_RX_DN<17>")
	)
	(segment
		(start 176.365916 -269.900654)
		(end 147.17522 -165.351968)
		(width 0.1651)
		(layer "In5.Cu")
		(net "P5E_PEX1_STN1_RX_DN<17>")
	)
	(segment
		(start 166.75989 -102.332536)
		(end 167.19042 -102.086918)
		(width 0.1651)
		(layer "In5.Cu")
		(net "P5E_PEX1_STN1_RX_DN<17>")
	)
	(segment
		(start 167.233092 -101.930962)
		(end 167.663114 -101.685598)
		(width 0.1651)
		(layer "In5.Cu")
		(net "P5E_PEX1_STN1_RX_DN<17>")
	)
	(segment
		(start 166.13124 -102.691184)
		(end 166.173912 -102.535228)
		(width 0.1651)
		(layer "In5.Cu")
		(net "P5E_PEX1_STN1_RX_DN<17>")
	)
	(segment
		(start 159.160464 -107.570016)
		(end 159.157162 -107.408472)
		(width 0.1651)
		(layer "In5.Cu")
		(net "P5E_PEX1_STN1_RX_DN<17>")
	)
	(segment
		(start 168.342564 -101.976174)
		(end 168.342564 -101.976428)
		(width 0.1651)
		(layer "In5.Cu")
		(net "P5E_PEX1_STN1_RX_DN<17>")
	)
	(segment
		(start 160.004506 -106.689906)
		(end 160.001204 -106.528362)
		(width 0.1651)
		(layer "In5.Cu")
		(net "P5E_PEX1_STN1_RX_DN<17>")
	)
	(segment
		(start 163.582858 -104.145334)
		(end 164.013388 -103.899716)
		(width 0.1651)
		(layer "In5.Cu")
		(net "P5E_PEX1_STN1_RX_DN<17>")
	)
	(segment
		(start 159.157162 -107.408472)
		(end 159.499808 -107.051094)
		(width 0.1651)
		(layer "In5.Cu")
		(net "P5E_PEX1_STN1_RX_DN<17>")
	)
	(segment
		(start 164.013388 -103.899716)
		(end 164.05606 -103.74376)
		(width 0.1651)
		(layer "In5.Cu")
		(net "P5E_PEX1_STN1_RX_DN<17>")
	)
	(segment
		(start 167.663114 -101.685598)
		(end 168.051988 -101.685598)
		(width 0.1651)
		(layer "In5.Cu")
		(net "P5E_PEX1_STN1_RX_DN<17>")
	)
	(segment
		(start 176.585372 -275.379434)
		(end 176.423574 -275.379434)
		(width 0.1143)
		(layer "In5.Cu")
		(net "P5E_PEX1_STN1_RX_DN<17>")
	)
	(segment
		(start 165.70071 -102.936802)
		(end 166.13124 -102.691184)
		(width 0.1651)
		(layer "In5.Cu")
		(net "P5E_PEX1_STN1_RX_DN<17>")
	)
	(segment
		(start 165.072314 -103.29545)
		(end 165.114986 -103.139494)
		(width 0.1651)
		(layer "In5.Cu")
		(net "P5E_PEX1_STN1_RX_DN<17>")
	)
	(segment
		(start 176.320196 -271.644872)
		(end 176.365916 -271.599152)
		(width 0.1143)
		(layer "In5.Cu")
		(net "P5E_PEX1_STN1_RX_DN<17>")
	)
	(segment
		(start 157.812232 -108.811314)
		(end 157.973776 -108.808012)
		(width 0.1651)
		(layer "In5.Cu")
		(net "P5E_PEX1_STN1_RX_DN<17>")
	)
	(segment
		(start 145.985738 -158.838138)
		(end 145.418048 -150.180294)
		(width 0.1651)
		(layer "In5.Cu")
		(net "P5E_PEX1_STN1_RX_DN<17>")
	)
	(segment
		(start 157.973776 -108.808012)
		(end 158.316676 -108.450126)
		(width 0.1651)
		(layer "In5.Cu")
		(net "P5E_PEX1_STN1_RX_DN<17>")
	)
	(segment
		(start 176.699672 -275.265134)
		(end 176.585372 -275.379434)
		(width 0.1143)
		(layer "In5.Cu")
		(net "P5E_PEX1_STN1_RX_DN<17>")
	)
	(segment
		(start 145.418048 -150.180294)
		(end 146.84121 -126.612142)
		(width 0.1651)
		(layer "In5.Cu")
		(net "P5E_PEX1_STN1_RX_DN<17>")
	)
	(segment
		(start 176.320196 -275.276056)
		(end 176.320196 -271.644872)
		(width 0.1143)
		(layer "In5.Cu")
		(net "P5E_PEX1_STN1_RX_DN<17>")
	)
	(segment
		(start 146.84121 -126.612142)
		(end 148.331682 -119.95023)
		(width 0.1651)
		(layer "In5.Cu")
		(net "P5E_PEX1_STN1_RX_DN<17>")
	)
	(segment
		(start 168.051988 -101.685598)
		(end 168.342564 -101.976174)
		(width 0.1651)
		(layer "In5.Cu")
		(net "P5E_PEX1_STN1_RX_DN<17>")
	)
	(segment
		(start 161.500058 -316.508892)
		(end 161.411158 -316.419992)
		(width 0.1143)
		(layer "In15.Cu")
		(net "P5E_PEX1_STN6_RX_DN<109>")
	)
	(segment
		(start 121.466864 -394.970508)
		(end 121.466864 -400.489674)
		(width 0.1651)
		(layer "In15.Cu")
		(net "P5E_PEX1_STN6_RX_DN<109>")
	)
	(segment
		(start 161.166048 -319.865248)
		(end 161.166048 -320.288666)
		(width 0.1651)
		(layer "In15.Cu")
		(net "P5E_PEX1_STN6_RX_DN<109>")
	)
	(segment
		(start 113.989358 -342.095582)
		(end 113.989358 -352.349054)
		(width 0.1651)
		(layer "In15.Cu")
		(net "P5E_PEX1_STN6_RX_DN<109>")
	)
	(segment
		(start 161.247328 -316.419992)
		(end 161.120328 -316.546992)
		(width 0.1143)
		(layer "In15.Cu")
		(net "P5E_PEX1_STN6_RX_DN<109>")
	)
	(segment
		(start 109.924088 -367.276126)
		(end 109.805978 -385.08051)
		(width 0.1651)
		(layer "In15.Cu")
		(net "P5E_PEX1_STN6_RX_DN<109>")
	)
	(segment
		(start 121.466864 -400.489674)
		(end 120.775476 -401.181062)
		(width 0.1651)
		(layer "In15.Cu")
		(net "P5E_PEX1_STN6_RX_DN<109>")
	)
	(segment
		(start 161.120328 -316.546992)
		(end 161.120328 -319.79108)
		(width 0.1143)
		(layer "In15.Cu")
		(net "P5E_PEX1_STN6_RX_DN<109>")
	)
	(segment
		(start 161.411158 -316.419992)
		(end 161.247328 -316.419992)
		(width 0.1143)
		(layer "In15.Cu")
		(net "P5E_PEX1_STN6_RX_DN<109>")
	)
	(segment
		(start 161.166048 -320.288666)
		(end 160.730692 -321.341242)
		(width 0.1651)
		(layer "In15.Cu")
		(net "P5E_PEX1_STN6_RX_DN<109>")
	)
	(segment
		(start 111.551974 -388.544054)
		(end 114.59337 -391.02411)
		(width 0.1651)
		(layer "In15.Cu")
		(net "P5E_PEX1_STN6_RX_DN<109>")
	)
	(segment
		(start 114.464084 -341.371682)
		(end 114.227102 -341.733124)
		(width 0.1651)
		(layer "In15.Cu")
		(net "P5E_PEX1_STN6_RX_DN<109>")
	)
	(segment
		(start 119.591328 -393.094972)
		(end 121.466864 -394.970508)
		(width 0.1651)
		(layer "In15.Cu")
		(net "P5E_PEX1_STN6_RX_DN<109>")
	)
	(segment
		(start 114.227102 -341.733124)
		(end 114.226848 -341.733632)
		(width 0.1651)
		(layer "In15.Cu")
		(net "P5E_PEX1_STN6_RX_DN<109>")
	)
	(segment
		(start 113.989358 -352.349054)
		(end 109.924088 -367.276126)
		(width 0.1651)
		(layer "In15.Cu")
		(net "P5E_PEX1_STN6_RX_DN<109>")
	)
	(segment
		(start 159.475424 -322.59651)
		(end 143.053816 -330.3651)
		(width 0.1651)
		(layer "In15.Cu")
		(net "P5E_PEX1_STN6_RX_DN<109>")
	)
	(segment
		(start 123.41225 -338.50072)
		(end 114.464084 -341.371682)
		(width 0.1651)
		(layer "In15.Cu")
		(net "P5E_PEX1_STN6_RX_DN<109>")
	)
	(segment
		(start 161.120328 -319.79108)
		(end 161.166048 -319.8368)
		(width 0.1143)
		(layer "In15.Cu")
		(net "P5E_PEX1_STN6_RX_DN<109>")
	)
	(segment
		(start 114.226848 -341.733632)
		(end 113.989358 -342.095582)
		(width 0.1651)
		(layer "In15.Cu")
		(net "P5E_PEX1_STN6_RX_DN<109>")
	)
	(segment
		(start 114.59337 -391.02411)
		(end 119.591328 -393.094972)
		(width 0.1651)
		(layer "In15.Cu")
		(net "P5E_PEX1_STN6_RX_DN<109>")
	)
	(segment
		(start 120.775476 -401.181062)
		(end 120.437148 -401.181062)
		(width 0.1651)
		(layer "In15.Cu")
		(net "P5E_PEX1_STN6_RX_DN<109>")
	)
	(segment
		(start 161.500058 -316.799722)
		(end 161.500058 -316.508892)
		(width 0.1143)
		(layer "In15.Cu")
		(net "P5E_PEX1_STN6_RX_DN<109>")
	)
	(segment
		(start 110.215426 -386.554726)
		(end 111.551974 -388.544054)
		(width 0.1651)
		(layer "In15.Cu")
		(net "P5E_PEX1_STN6_RX_DN<109>")
	)
	(segment
		(start 160.730692 -321.341242)
		(end 159.475424 -322.59651)
		(width 0.1651)
		(layer "In15.Cu")
		(net "P5E_PEX1_STN6_RX_DN<109>")
	)
	(segment
		(start 109.805978 -385.08051)
		(end 110.215426 -386.554726)
		(width 0.1651)
		(layer "In15.Cu")
		(net "P5E_PEX1_STN6_RX_DN<109>")
	)
	(segment
		(start 161.166048 -319.8368)
		(end 161.166048 -319.865248)
		(width 0.1143)
		(layer "In15.Cu")
		(net "P5E_PEX1_STN6_RX_DN<109>")
	)
	(segment
		(start 143.053816 -330.3651)
		(end 123.41225 -338.50072)
		(width 0.1651)
		(layer "In15.Cu")
		(net "P5E_PEX1_STN6_RX_DN<109>")
	)
	(segment
		(start 120.310148 -401.308062)
		(end 120.310148 -401.690078)
		(width 0.1651)
		(layer "In15.Cu")
		(net "P5E_PEX1_STN6_RX_DN<109>")
	)
	(segment
		(start 120.437148 -401.181062)
		(end 120.310148 -401.308062)
		(width 0.1651)
		(layer "In15.Cu")
		(net "P5E_PEX1_STN6_RX_DN<109>")
	)
	(segment
		(start 277.577296 -105.283)
		(end 277.739348 -105.445052)
		(width 0.13462)
		(layer "F.Cu")
		(net "P5E_PEX2_STN1_TX_C_DP<19>")
	)
	(segment
		(start 269.432024 -105.283)
		(end 277.577296 -105.283)
		(width 0.13462)
		(layer "F.Cu")
		(net "P5E_PEX2_STN1_TX_C_DP<19>")
	)
	(segment
		(start 277.739348 -105.445052)
		(end 278.242268 -105.445052)
		(width 0.13462)
		(layer "F.Cu")
		(net "P5E_PEX2_STN1_TX_C_DP<19>")
	)
	(segment
		(start 269.105126 -105.609898)
		(end 269.432024 -105.283)
		(width 0.13462)
		(layer "F.Cu")
		(net "P5E_PEX2_STN1_TX_C_DP<19>")
	)
	(segment
		(start 430.36236 -124.4092)
		(end 422.238678 -124.4092)
		(width 0.13462)
		(layer "F.Cu")
		(net "P5E_PEX3_STN0_TX_C_DN<3>")
	)
	(segment
		(start 422.238678 -124.4092)
		(end 422.064434 -124.234956)
		(width 0.13462)
		(layer "F.Cu")
		(net "P5E_PEX3_STN0_TX_C_DN<3>")
	)
	(segment
		(start 422.064434 -124.234956)
		(end 421.557704 -124.234956)
		(width 0.13462)
		(layer "F.Cu")
		(net "P5E_PEX3_STN0_TX_C_DN<3>")
	)
	(segment
		(start 430.694846 -124.076714)
		(end 430.36236 -124.4092)
		(width 0.13462)
		(layer "F.Cu")
		(net "P5E_PEX3_STN0_TX_C_DN<3>")
	)
	(segment
		(start 428.51832 -344.538554)
		(end 428.51832 -345.171014)
		(width 0.13462)
		(layer "F.Cu")
		(net "P5E_PEX3_STN7_TX_C_DN<120>")
	)
	(segment
		(start 428.51832 -345.171014)
		(end 428.812452 -345.465146)
		(width 0.13462)
		(layer "F.Cu")
		(net "P5E_PEX3_STN7_TX_C_DN<120>")
	)
	(segment
		(start 428.837852 -344.219022)
		(end 428.51832 -344.538554)
		(width 0.13462)
		(layer "F.Cu")
		(net "P5E_PEX3_STN7_TX_C_DN<120>")
	)
	(segment
		(start 426.967142 -347.881194)
		(end 428.521622 -346.326714)
		(width 0.1651)
		(layer "In11.Cu")
		(net "P5E_PEX3_STN7_TX_C_DN<120>")
	)
	(segment
		(start 420.164006 -375.181114)
		(end 420.615872 -374.729248)
		(width 0.1651)
		(layer "In11.Cu")
		(net "P5E_PEX3_STN7_TX_C_DN<120>")
	)
	(segment
		(start 428.521622 -345.755976)
		(end 428.812452 -345.465146)
		(width 0.1651)
		(layer "In11.Cu")
		(net "P5E_PEX3_STN7_TX_C_DN<120>")
	)
	(segment
		(start 419.48989 -375.69013)
		(end 419.48989 -375.308114)
		(width 0.1651)
		(layer "In11.Cu")
		(net "P5E_PEX3_STN7_TX_C_DN<120>")
	)
	(segment
		(start 420.615872 -369.954048)
		(end 421.220646 -367.905538)
		(width 0.1651)
		(layer "In11.Cu")
		(net "P5E_PEX3_STN7_TX_C_DN<120>")
	)
	(segment
		(start 419.61689 -375.181114)
		(end 420.164006 -375.181114)
		(width 0.1651)
		(layer "In11.Cu")
		(net "P5E_PEX3_STN7_TX_C_DN<120>")
	)
	(segment
		(start 420.615872 -374.729248)
		(end 420.615872 -369.954048)
		(width 0.1651)
		(layer "In11.Cu")
		(net "P5E_PEX3_STN7_TX_C_DN<120>")
	)
	(segment
		(start 421.220646 -367.905538)
		(end 426.459142 -359.805732)
		(width 0.1651)
		(layer "In11.Cu")
		(net "P5E_PEX3_STN7_TX_C_DN<120>")
	)
	(segment
		(start 426.459142 -359.805732)
		(end 426.967142 -358.084374)
		(width 0.1651)
		(layer "In11.Cu")
		(net "P5E_PEX3_STN7_TX_C_DN<120>")
	)
	(segment
		(start 419.48989 -375.308114)
		(end 419.61689 -375.181114)
		(width 0.1651)
		(layer "In11.Cu")
		(net "P5E_PEX3_STN7_TX_C_DN<120>")
	)
	(segment
		(start 428.521622 -346.326714)
		(end 428.521622 -345.755976)
		(width 0.1651)
		(layer "In11.Cu")
		(net "P5E_PEX3_STN7_TX_C_DN<120>")
	)
	(segment
		(start 426.967142 -358.084374)
		(end 426.967142 -347.881194)
		(width 0.1651)
		(layer "In11.Cu")
		(net "P5E_PEX3_STN7_TX_C_DN<120>")
	)
	(segment
		(start 407.695146 -104.830372)
		(end 409.910534 -104.830372)
		(width 0.13208)
		(layer "F.Cu")
		(net "CLK_50M_NIC7_RBT_REF")
	)
	(segment
		(start 409.920186 -104.840024)
		(end 416.95751 -104.840024)
		(width 0.13208)
		(layer "F.Cu")
		(net "CLK_50M_NIC7_RBT_REF")
	)
	(segment
		(start 409.910534 -104.830372)
		(end 409.920186 -104.840024)
		(width 0.13208)
		(layer "F.Cu")
		(net "CLK_50M_NIC7_RBT_REF")
	)
	(via
		(at 409.910534 -104.830372)
		(size 0.762)
		(drill 0.381)
		(layers "F.Cu" "B.Cu")
		(net "CLK_50M_NIC7_RBT_REF")
	)
	(segment
		(start 161.491422 -103.20782)
		(end 161.654236 -103.045006)
		(width 0.13462)
		(layer "F.Cu")
		(net "P5E_PEX1_STN1_TX_C_DP<18>")
	)
	(segment
		(start 155.96616 -103.20782)
		(end 161.491422 -103.20782)
		(width 0.13462)
		(layer "F.Cu")
		(net "P5E_PEX1_STN1_TX_C_DP<18>")
	)
	(segment
		(start 161.654236 -103.045006)
		(end 162.14217 -103.045006)
		(width 0.13462)
		(layer "F.Cu")
		(net "P5E_PEX1_STN1_TX_C_DP<18>")
	)
	(segment
		(start 155.647136 -102.888796)
		(end 155.96616 -103.20782)
		(width 0.13462)
		(layer "F.Cu")
		(net "P5E_PEX1_STN1_TX_C_DP<18>")
	)
	(segment
		(start 138.861038 -341.318342)
		(end 138.861038 -357.977948)
		(width 0.1651)
		(layer "In5.Cu")
		(net "P5E_PEX1_STN6_RX_DN<98>")
	)
	(segment
		(start 127.037084 -376.281188)
		(end 126.910084 -376.408188)
		(width 0.1651)
		(layer "In5.Cu")
		(net "P5E_PEX1_STN6_RX_DN<98>")
	)
	(segment
		(start 171.949872 -318.434466)
		(end 171.835572 -318.320166)
		(width 0.1143)
		(layer "In5.Cu")
		(net "P5E_PEX1_STN6_RX_DN<98>")
	)
	(segment
		(start 171.570142 -319.84188)
		(end 171.615862 -319.8876)
		(width 0.1143)
		(layer "In5.Cu")
		(net "P5E_PEX1_STN6_RX_DN<98>")
	)
	(segment
		(start 171.615862 -319.8876)
		(end 171.615862 -319.916048)
		(width 0.1143)
		(layer "In5.Cu")
		(net "P5E_PEX1_STN6_RX_DN<98>")
	)
	(segment
		(start 171.684442 -318.320166)
		(end 171.570142 -318.434466)
		(width 0.1143)
		(layer "In5.Cu")
		(net "P5E_PEX1_STN6_RX_DN<98>")
	)
	(segment
		(start 170.50004 -323.087238)
		(end 169.88409 -323.669914)
		(width 0.1651)
		(layer "In5.Cu")
		(net "P5E_PEX1_STN6_RX_DN<98>")
	)
	(segment
		(start 171.615862 -321.417696)
		(end 170.50004 -323.087238)
		(width 0.1651)
		(layer "In5.Cu")
		(net "P5E_PEX1_STN6_RX_DN<98>")
	)
	(segment
		(start 146.98218 -337.690206)
		(end 139.200128 -340.979252)
		(width 0.1651)
		(layer "In5.Cu")
		(net "P5E_PEX1_STN6_RX_DN<98>")
	)
	(segment
		(start 157.38729 -331.05598)
		(end 146.98218 -337.690206)
		(width 0.1651)
		(layer "In5.Cu")
		(net "P5E_PEX1_STN6_RX_DN<98>")
	)
	(segment
		(start 126.910084 -376.408188)
		(end 126.910084 -376.790204)
		(width 0.1651)
		(layer "In5.Cu")
		(net "P5E_PEX1_STN6_RX_DN<98>")
	)
	(segment
		(start 171.570142 -318.434466)
		(end 171.570142 -319.84188)
		(width 0.1143)
		(layer "In5.Cu")
		(net "P5E_PEX1_STN6_RX_DN<98>")
	)
	(segment
		(start 127.969518 -369.876324)
		(end 127.969518 -375.89841)
		(width 0.1651)
		(layer "In5.Cu")
		(net "P5E_PEX1_STN6_RX_DN<98>")
	)
	(segment
		(start 171.835572 -318.320166)
		(end 171.684442 -318.320166)
		(width 0.1143)
		(layer "In5.Cu")
		(net "P5E_PEX1_STN6_RX_DN<98>")
	)
	(segment
		(start 139.200128 -340.979252)
		(end 138.861038 -341.318342)
		(width 0.1651)
		(layer "In5.Cu")
		(net "P5E_PEX1_STN6_RX_DN<98>")
	)
	(segment
		(start 136.703054 -360.729784)
		(end 128.22174 -368.750596)
		(width 0.1651)
		(layer "In5.Cu")
		(net "P5E_PEX1_STN6_RX_DN<98>")
	)
	(segment
		(start 171.949872 -318.699896)
		(end 171.949872 -318.434466)
		(width 0.1143)
		(layer "In5.Cu")
		(net "P5E_PEX1_STN6_RX_DN<98>")
	)
	(segment
		(start 138.861038 -357.977948)
		(end 138.441176 -358.991662)
		(width 0.1651)
		(layer "In5.Cu")
		(net "P5E_PEX1_STN6_RX_DN<98>")
	)
	(segment
		(start 169.88409 -323.669914)
		(end 157.38729 -331.05598)
		(width 0.1651)
		(layer "In5.Cu")
		(net "P5E_PEX1_STN6_RX_DN<98>")
	)
	(segment
		(start 171.615862 -319.916048)
		(end 171.615862 -321.417696)
		(width 0.1651)
		(layer "In5.Cu")
		(net "P5E_PEX1_STN6_RX_DN<98>")
	)
	(segment
		(start 127.58674 -376.281188)
		(end 127.037084 -376.281188)
		(width 0.1651)
		(layer "In5.Cu")
		(net "P5E_PEX1_STN6_RX_DN<98>")
	)
	(segment
		(start 138.441176 -358.991662)
		(end 136.703054 -360.729784)
		(width 0.1651)
		(layer "In5.Cu")
		(net "P5E_PEX1_STN6_RX_DN<98>")
	)
	(segment
		(start 128.22174 -368.750596)
		(end 127.969518 -369.876324)
		(width 0.1651)
		(layer "In5.Cu")
		(net "P5E_PEX1_STN6_RX_DN<98>")
	)
	(segment
		(start 127.969518 -375.89841)
		(end 127.58674 -376.281188)
		(width 0.1651)
		(layer "In5.Cu")
		(net "P5E_PEX1_STN6_RX_DN<98>")
	)
	(segment
		(start 283.488892 -124.92228)
		(end 283.32176 -124.755148)
		(width 0.13462)
		(layer "F.Cu")
		(net "P5E_PEX2_STN1_RX_DP<27>")
	)
	(segment
		(start 284.143196 -124.92228)
		(end 283.488892 -124.92228)
		(width 0.13462)
		(layer "F.Cu")
		(net "P5E_PEX2_STN1_RX_DP<27>")
	)
	(segment
		(start 284.442662 -124.622814)
		(end 284.143196 -124.92228)
		(width 0.13462)
		(layer "F.Cu")
		(net "P5E_PEX2_STN1_RX_DP<27>")
	)
	(segment
		(start 283.32176 -124.755148)
		(end 282.842462 -124.755148)
		(width 0.13462)
		(layer "F.Cu")
		(net "P5E_PEX2_STN1_RX_DP<27>")
	)
	(segment
		(start 277.544276 -140.451078)
		(end 277.392384 -140.950442)
		(width 0.1651)
		(layer "In5.Cu")
		(net "P5E_PEX2_STN1_RX_DP<27>")
	)
	(segment
		(start 281.70632 -130.590798)
		(end 280.42108 -132.492242)
		(width 0.1651)
		(layer "In5.Cu")
		(net "P5E_PEX2_STN1_RX_DP<27>")
	)
	(segment
		(start 301.683674 -267.785596)
		(end 301.683674 -271.570958)
		(width 0.1651)
		(layer "In5.Cu")
		(net "P5E_PEX2_STN1_RX_DP<27>")
	)
	(segment
		(start 284.442662 -124.622814)
		(end 284.151832 -124.913644)
		(width 0.1651)
		(layer "In5.Cu")
		(net "P5E_PEX2_STN1_RX_DP<27>")
	)
	(segment
		(start 301.683674 -271.570958)
		(end 301.683674 -271.599406)
		(width 0.1143)
		(layer "In5.Cu")
		(net "P5E_PEX2_STN1_RX_DP<27>")
	)
	(segment
		(start 271.999202 -147.60702)
		(end 272.608294 -157.041342)
		(width 0.1651)
		(layer "In5.Cu")
		(net "P5E_PEX2_STN1_RX_DP<27>")
	)
	(segment
		(start 301.683674 -271.599406)
		(end 301.729394 -271.645126)
		(width 0.1143)
		(layer "In5.Cu")
		(net "P5E_PEX2_STN1_RX_DP<27>")
	)
	(segment
		(start 271.998948 -147.60702)
		(end 271.999202 -147.60702)
		(width 0.1651)
		(layer "In5.Cu")
		(net "P5E_PEX2_STN1_RX_DP<27>")
	)
	(segment
		(start 302.29937 -275.684488)
		(end 302.29937 -275.949918)
		(width 0.1143)
		(layer "In5.Cu")
		(net "P5E_PEX2_STN1_RX_DP<27>")
	)
	(segment
		(start 279.892506 -133.614922)
		(end 279.892252 -133.61543)
		(width 0.1651)
		(layer "In5.Cu")
		(net "P5E_PEX2_STN1_RX_DP<27>")
	)
	(segment
		(start 283.708856 -124.913644)
		(end 283.16936 -125.45314)
		(width 0.1651)
		(layer "In5.Cu")
		(net "P5E_PEX2_STN1_RX_DP<27>")
	)
	(segment
		(start 277.392384 -140.950442)
		(end 275.20138 -142.94231)
		(width 0.1651)
		(layer "In5.Cu")
		(net "P5E_PEX2_STN1_RX_DP<27>")
	)
	(segment
		(start 279.892252 -133.61543)
		(end 279.12822 -135.238236)
		(width 0.1651)
		(layer "In5.Cu")
		(net "P5E_PEX2_STN1_RX_DP<27>")
	)
	(segment
		(start 273.383248 -161.41446)
		(end 301.683674 -267.785596)
		(width 0.1651)
		(layer "In5.Cu")
		(net "P5E_PEX2_STN1_RX_DP<27>")
	)
	(segment
		(start 283.16936 -125.45314)
		(end 282.691332 -126.607316)
		(width 0.1651)
		(layer "In5.Cu")
		(net "P5E_PEX2_STN1_RX_DP<27>")
	)
	(segment
		(start 301.729394 -271.645126)
		(end 301.729394 -275.355304)
		(width 0.1143)
		(layer "In5.Cu")
		(net "P5E_PEX2_STN1_RX_DP<27>")
	)
	(segment
		(start 282.691332 -126.607316)
		(end 282.691332 -128.23317)
		(width 0.1651)
		(layer "In5.Cu")
		(net "P5E_PEX2_STN1_RX_DP<27>")
	)
	(segment
		(start 272.608294 -157.041342)
		(end 273.383248 -161.41446)
		(width 0.1651)
		(layer "In5.Cu")
		(net "P5E_PEX2_STN1_RX_DP<27>")
	)
	(segment
		(start 301.729394 -275.355304)
		(end 301.944278 -275.570188)
		(width 0.1143)
		(layer "In5.Cu")
		(net "P5E_PEX2_STN1_RX_DP<27>")
	)
	(segment
		(start 279.12822 -135.238236)
		(end 277.544022 -140.451078)
		(width 0.1651)
		(layer "In5.Cu")
		(net "P5E_PEX2_STN1_RX_DP<27>")
	)
	(segment
		(start 284.151832 -124.913644)
		(end 283.708856 -124.913644)
		(width 0.1651)
		(layer "In5.Cu")
		(net "P5E_PEX2_STN1_RX_DP<27>")
	)
	(segment
		(start 301.944278 -275.570188)
		(end 302.18507 -275.570188)
		(width 0.1143)
		(layer "In5.Cu")
		(net "P5E_PEX2_STN1_RX_DP<27>")
	)
	(segment
		(start 282.691332 -128.23317)
		(end 282.243022 -129.306066)
		(width 0.1651)
		(layer "In5.Cu")
		(net "P5E_PEX2_STN1_RX_DP<27>")
	)
	(segment
		(start 277.544022 -140.451078)
		(end 277.544276 -140.451078)
		(width 0.1651)
		(layer "In5.Cu")
		(net "P5E_PEX2_STN1_RX_DP<27>")
	)
	(segment
		(start 282.242768 -129.306574)
		(end 281.70632 -130.590798)
		(width 0.1651)
		(layer "In5.Cu")
		(net "P5E_PEX2_STN1_RX_DP<27>")
	)
	(segment
		(start 275.20138 -142.94231)
		(end 274.220686 -143.910304)
		(width 0.1651)
		(layer "In5.Cu")
		(net "P5E_PEX2_STN1_RX_DP<27>")
	)
	(segment
		(start 282.243022 -129.306066)
		(end 282.242768 -129.306574)
		(width 0.1651)
		(layer "In5.Cu")
		(net "P5E_PEX2_STN1_RX_DP<27>")
	)
	(segment
		(start 280.42108 -132.492242)
		(end 279.892506 -133.614922)
		(width 0.1651)
		(layer "In5.Cu")
		(net "P5E_PEX2_STN1_RX_DP<27>")
	)
	(segment
		(start 274.220686 -143.910304)
		(end 272.266156 -146.533108)
		(width 0.1651)
		(layer "In5.Cu")
		(net "P5E_PEX2_STN1_RX_DP<27>")
	)
	(segment
		(start 271.996154 -147.561554)
		(end 271.998948 -147.60702)
		(width 0.1651)
		(layer "In5.Cu")
		(net "P5E_PEX2_STN1_RX_DP<27>")
	)
	(segment
		(start 302.18507 -275.570188)
		(end 302.29937 -275.684488)
		(width 0.1143)
		(layer "In5.Cu")
		(net "P5E_PEX2_STN1_RX_DP<27>")
	)
	(segment
		(start 272.266156 -146.533108)
		(end 271.996154 -147.561554)
		(width 0.1651)
		(layer "In5.Cu")
		(net "P5E_PEX2_STN1_RX_DP<27>")
	)
	(segment
		(start 416.32124 -132.0038)
		(end 413.793178 -132.0038)
		(width 0.13462)
		(layer "F.Cu")
		(net "P5E_PEX3_STN0_RX_DN<5>")
	)
	(segment
		(start 416.47999 -131.84505)
		(end 416.32124 -132.0038)
		(width 0.13462)
		(layer "F.Cu")
		(net "P5E_PEX3_STN0_RX_DN<5>")
	)
	(segment
		(start 416.95751 -131.84505)
		(end 416.47999 -131.84505)
		(width 0.13462)
		(layer "F.Cu")
		(net "P5E_PEX3_STN0_RX_DN<5>")
	)
	(segment
		(start 413.793178 -132.0038)
		(end 413.50311 -131.713732)
		(width 0.13462)
		(layer "F.Cu")
		(net "P5E_PEX3_STN0_RX_DN<5>")
	)
	(segment
		(start 430.484534 -283.549852)
		(end 430.370234 -283.435552)
		(width 0.1143)
		(layer "In5.Cu")
		(net "P5E_PEX3_STN0_RX_DN<5>")
	)
	(segment
		(start 429.582834 -160.702752)
		(end 428.19955 -151.3586)
		(width 0.1651)
		(layer "In5.Cu")
		(net "P5E_PEX3_STN0_RX_DN<5>")
	)
	(segment
		(start 425.234608 -137.449052)
		(end 425.20616 -137.405872)
		(width 0.1651)
		(layer "In5.Cu")
		(net "P5E_PEX3_STN0_RX_DN<5>")
	)
	(segment
		(start 432.951382 -283.215842)
		(end 433.874164 -282.609036)
		(width 0.1651)
		(layer "In5.Cu")
		(net "P5E_PEX3_STN0_RX_DN<5>")
	)
	(segment
		(start 430.473866 -283.170122)
		(end 432.143408 -283.170122)
		(width 0.1143)
		(layer "In5.Cu")
		(net "P5E_PEX3_STN0_RX_DN<5>")
	)
	(segment
		(start 413.79394 -132.004562)
		(end 413.50311 -131.713732)
		(width 0.1651)
		(layer "In5.Cu")
		(net "P5E_PEX3_STN0_RX_DN<5>")
	)
	(segment
		(start 432.143408 -283.170122)
		(end 432.189128 -283.215842)
		(width 0.1143)
		(layer "In5.Cu")
		(net "P5E_PEX3_STN0_RX_DN<5>")
	)
	(segment
		(start 430.370234 -283.435552)
		(end 430.370234 -283.273754)
		(width 0.1143)
		(layer "In5.Cu")
		(net "P5E_PEX3_STN0_RX_DN<5>")
	)
	(segment
		(start 432.828954 -233.312462)
		(end 431.795174 -222.600774)
		(width 0.1651)
		(layer "In5.Cu")
		(net "P5E_PEX3_STN0_RX_DN<5>")
	)
	(segment
		(start 431.795174 -222.600774)
		(end 429.582834 -160.702752)
		(width 0.1651)
		(layer "In5.Cu")
		(net "P5E_PEX3_STN0_RX_DN<5>")
	)
	(segment
		(start 435.447948 -244.131846)
		(end 432.828954 -233.312462)
		(width 0.1651)
		(layer "In5.Cu")
		(net "P5E_PEX3_STN0_RX_DN<5>")
	)
	(segment
		(start 425.20616 -137.405872)
		(end 422.512998 -135.46074)
		(width 0.1651)
		(layer "In5.Cu")
		(net "P5E_PEX3_STN0_RX_DN<5>")
	)
	(segment
		(start 426.817282 -142.021306)
		(end 426.201332 -139.151868)
		(width 0.1651)
		(layer "In5.Cu")
		(net "P5E_PEX3_STN0_RX_DN<5>")
	)
	(segment
		(start 422.512998 -135.46074)
		(end 415.627058 -132.004562)
		(width 0.1651)
		(layer "In5.Cu")
		(net "P5E_PEX3_STN0_RX_DN<5>")
	)
	(segment
		(start 425.915328 -138.484864)
		(end 425.234608 -137.449306)
		(width 0.1651)
		(layer "In5.Cu")
		(net "P5E_PEX3_STN0_RX_DN<5>")
	)
	(segment
		(start 425.234608 -137.449306)
		(end 425.234608 -137.449052)
		(width 0.1651)
		(layer "In5.Cu")
		(net "P5E_PEX3_STN0_RX_DN<5>")
	)
	(segment
		(start 428.19955 -151.3586)
		(end 428.199804 -151.3586)
		(width 0.1651)
		(layer "In5.Cu")
		(net "P5E_PEX3_STN0_RX_DN<5>")
	)
	(segment
		(start 443.08395 -270.233394)
		(end 435.447948 -244.131846)
		(width 0.1651)
		(layer "In5.Cu")
		(net "P5E_PEX3_STN0_RX_DN<5>")
	)
	(segment
		(start 433.874164 -282.609036)
		(end 441.27166 -275.417788)
		(width 0.1651)
		(layer "In5.Cu")
		(net "P5E_PEX3_STN0_RX_DN<5>")
	)
	(segment
		(start 432.189128 -283.215842)
		(end 432.217576 -283.215842)
		(width 0.1143)
		(layer "In5.Cu")
		(net "P5E_PEX3_STN0_RX_DN<5>")
	)
	(segment
		(start 430.370234 -283.273754)
		(end 430.473866 -283.170122)
		(width 0.1143)
		(layer "In5.Cu")
		(net "P5E_PEX3_STN0_RX_DN<5>")
	)
	(segment
		(start 441.27166 -275.417788)
		(end 443.029086 -272.307558)
		(width 0.1651)
		(layer "In5.Cu")
		(net "P5E_PEX3_STN0_RX_DN<5>")
	)
	(segment
		(start 426.201332 -139.151868)
		(end 425.915328 -138.484864)
		(width 0.1651)
		(layer "In5.Cu")
		(net "P5E_PEX3_STN0_RX_DN<5>")
	)
	(segment
		(start 415.627058 -132.004562)
		(end 413.79394 -132.004562)
		(width 0.1651)
		(layer "In5.Cu")
		(net "P5E_PEX3_STN0_RX_DN<5>")
	)
	(segment
		(start 430.749964 -283.549852)
		(end 430.484534 -283.549852)
		(width 0.1143)
		(layer "In5.Cu")
		(net "P5E_PEX3_STN0_RX_DN<5>")
	)
	(segment
		(start 443.029086 -272.307558)
		(end 443.08395 -270.233394)
		(width 0.1651)
		(layer "In5.Cu")
		(net "P5E_PEX3_STN0_RX_DN<5>")
	)
	(segment
		(start 432.217576 -283.215842)
		(end 432.951382 -283.215842)
		(width 0.1651)
		(layer "In5.Cu")
		(net "P5E_PEX3_STN0_RX_DN<5>")
	)
	(segment
		(start 428.199804 -151.3586)
		(end 426.817282 -142.021306)
		(width 0.1651)
		(layer "In5.Cu")
		(net "P5E_PEX3_STN0_RX_DN<5>")
	)
	(segment
		(start 423.838878 -100.640134)
		(end 424.268392 -101.069648)
		(width 0.13208)
		(layer "F.Cu")
		(net "NIC7_SLOT_ID0")
	)
	(segment
		(start 421.557704 -100.640134)
		(end 423.838878 -100.640134)
		(width 0.13208)
		(layer "F.Cu")
		(net "NIC7_SLOT_ID0")
	)
	(via
		(at 424.268392 -101.069648)
		(size 0.508)
		(drill 0.254)
		(layers "F.Cu" "B.Cu")
		(net "NIC7_SLOT_ID0")
	)
	(segment
		(start 425.441872 -100.056696)
		(end 425.441872 -101.069648)
		(width 0.13208)
		(layer "B.Cu")
		(net "NIC7_SLOT_ID0")
	)
	(segment
		(start 425.441872 -101.069648)
		(end 424.268392 -101.069648)
		(width 0.13208)
		(layer "B.Cu")
		(net "NIC7_SLOT_ID0")
	)
	(segment
		(start 161.654236 -130.565144)
		(end 161.491422 -130.727958)
		(width 0.13462)
		(layer "F.Cu")
		(net "P5E_PEX1_STN1_TX_C_DP<28>")
	)
	(segment
		(start 161.491422 -130.727958)
		(end 153.324052 -130.727958)
		(width 0.13462)
		(layer "F.Cu")
		(net "P5E_PEX1_STN1_TX_C_DP<28>")
	)
	(segment
		(start 162.14217 -130.565144)
		(end 161.654236 -130.565144)
		(width 0.13462)
		(layer "F.Cu")
		(net "P5E_PEX1_STN1_TX_C_DP<28>")
	)
	(segment
		(start 153.324052 -130.727958)
		(end 153.005028 -130.408934)
		(width 0.13462)
		(layer "F.Cu")
		(net "P5E_PEX1_STN1_TX_C_DP<28>")
	)
	(segment
		(start 121.757948 -344.539062)
		(end 122.077988 -344.219022)
		(width 0.13462)
		(layer "F.Cu")
		(net "P5E_PEX1_STN6_TX_C_DN<99>")
	)
	(segment
		(start 122.052588 -345.465146)
		(end 121.757948 -345.170506)
		(width 0.13462)
		(layer "F.Cu")
		(net "P5E_PEX1_STN6_TX_C_DN<99>")
	)
	(segment
		(start 121.757948 -345.170506)
		(end 121.757948 -344.539062)
		(width 0.13462)
		(layer "F.Cu")
		(net "P5E_PEX1_STN6_TX_C_DN<99>")
	)
	(segment
		(start 121.761758 -345.755976)
		(end 122.052588 -345.465146)
		(width 0.1651)
		(layer "In7.Cu")
		(net "P5E_PEX1_STN6_TX_C_DN<99>")
	)
	(segment
		(start 125.186186 -382.980946)
		(end 125.769624 -382.397508)
		(width 0.1651)
		(layer "In7.Cu")
		(net "P5E_PEX1_STN6_TX_C_DN<99>")
	)
	(segment
		(start 125.769624 -368.923062)
		(end 120.72747 -361.376722)
		(width 0.1651)
		(layer "In7.Cu")
		(net "P5E_PEX1_STN6_TX_C_DN<99>")
	)
	(segment
		(start 121.761758 -346.477082)
		(end 121.761758 -345.755976)
		(width 0.1651)
		(layer "In7.Cu")
		(net "P5E_PEX1_STN6_TX_C_DN<99>")
	)
	(segment
		(start 120.72747 -361.376722)
		(end 120.207278 -359.661714)
		(width 0.1651)
		(layer "In7.Cu")
		(net "P5E_PEX1_STN6_TX_C_DN<99>")
	)
	(segment
		(start 124.71019 -383.1082)
		(end 124.837444 -382.980946)
		(width 0.1651)
		(layer "In7.Cu")
		(net "P5E_PEX1_STN6_TX_C_DN<99>")
	)
	(segment
		(start 125.769624 -382.397508)
		(end 125.769624 -368.923062)
		(width 0.1651)
		(layer "In7.Cu")
		(net "P5E_PEX1_STN6_TX_C_DN<99>")
	)
	(segment
		(start 120.207278 -359.661714)
		(end 120.207278 -348.031562)
		(width 0.1651)
		(layer "In7.Cu")
		(net "P5E_PEX1_STN6_TX_C_DN<99>")
	)
	(segment
		(start 124.71019 -383.490216)
		(end 124.71019 -383.1082)
		(width 0.1651)
		(layer "In7.Cu")
		(net "P5E_PEX1_STN6_TX_C_DN<99>")
	)
	(segment
		(start 124.837444 -382.980946)
		(end 125.186186 -382.980946)
		(width 0.1651)
		(layer "In7.Cu")
		(net "P5E_PEX1_STN6_TX_C_DN<99>")
	)
	(segment
		(start 120.207278 -348.031562)
		(end 121.761758 -346.477082)
		(width 0.1651)
		(layer "In7.Cu")
		(net "P5E_PEX1_STN6_TX_C_DN<99>")
	)
	(segment
		(start 271.747234 -102.888796)
		(end 272.063718 -103.20528)
		(width 0.13462)
		(layer "F.Cu")
		(net "P5E_PEX2_STN1_TX_C_DP<18>")
	)
	(segment
		(start 277.579328 -103.20528)
		(end 277.739602 -103.045006)
		(width 0.13462)
		(layer "F.Cu")
		(net "P5E_PEX2_STN1_TX_C_DP<18>")
	)
	(segment
		(start 272.063718 -103.20528)
		(end 277.579328 -103.20528)
		(width 0.13462)
		(layer "F.Cu")
		(net "P5E_PEX2_STN1_TX_C_DP<18>")
	)
	(segment
		(start 277.739602 -103.045006)
		(end 278.242268 -103.045006)
		(width 0.13462)
		(layer "F.Cu")
		(net "P5E_PEX2_STN1_TX_C_DP<18>")
	)
	(segment
		(start 416.47491 -121.234962)
		(end 416.311588 -121.07164)
		(width 0.13462)
		(layer "F.Cu")
		(net "P5E_PEX3_STN0_RX_DP<1>")
	)
	(segment
		(start 416.95751 -121.234962)
		(end 416.47491 -121.234962)
		(width 0.13462)
		(layer "F.Cu")
		(net "P5E_PEX3_STN0_RX_DP<1>")
	)
	(segment
		(start 416.311588 -121.07164)
		(end 413.798766 -121.07164)
		(width 0.13462)
		(layer "F.Cu")
		(net "P5E_PEX3_STN0_RX_DP<1>")
	)
	(segment
		(start 413.798766 -121.07164)
		(end 413.50311 -121.367296)
		(width 0.13462)
		(layer "F.Cu")
		(net "P5E_PEX3_STN0_RX_DP<1>")
	)
	(segment
		(start 434.220366 -286.733996)
		(end 435.600856 -285.886398)
		(width 0.1651)
		(layer "In5.Cu")
		(net "P5E_PEX3_STN0_RX_DP<1>")
	)
	(segment
		(start 435.600856 -285.886398)
		(end 444.152274 -277.634192)
		(width 0.1651)
		(layer "In5.Cu")
		(net "P5E_PEX3_STN0_RX_DP<1>")
	)
	(segment
		(start 444.152274 -277.634192)
		(end 446.567306 -273.294602)
		(width 0.1651)
		(layer "In5.Cu")
		(net "P5E_PEX3_STN0_RX_DP<1>")
	)
	(segment
		(start 416.985196 -121.54535)
		(end 416.83559 -121.606818)
		(width 0.1651)
		(layer "In5.Cu")
		(net "P5E_PEX3_STN0_RX_DP<1>")
	)
	(segment
		(start 418.568124 -122.20448)
		(end 418.110924 -122.014234)
		(width 0.1651)
		(layer "In5.Cu")
		(net "P5E_PEX3_STN0_RX_DP<1>")
	)
	(segment
		(start 418.110924 -122.014234)
		(end 417.961318 -122.075702)
		(width 0.1651)
		(layer "In5.Cu")
		(net "P5E_PEX3_STN0_RX_DP<1>")
	)
	(segment
		(start 433.9717 -135.332724)
		(end 433.512722 -134.61873)
		(width 0.1651)
		(layer "In5.Cu")
		(net "P5E_PEX3_STN0_RX_DP<1>")
	)
	(segment
		(start 416.316668 -121.266966)
		(end 415.859468 -121.076466)
		(width 0.1651)
		(layer "In5.Cu")
		(net "P5E_PEX3_STN0_RX_DP<1>")
	)
	(segment
		(start 417.961318 -122.075702)
		(end 417.503864 -121.885202)
		(width 0.1651)
		(layer "In5.Cu")
		(net "P5E_PEX3_STN0_RX_DP<1>")
	)
	(segment
		(start 430.843182 -132.942584)
		(end 428.682404 -131.751578)
		(width 0.1651)
		(layer "In5.Cu")
		(net "P5E_PEX3_STN0_RX_DP<1>")
	)
	(segment
		(start 416.378136 -121.416572)
		(end 416.316668 -121.266712)
		(width 0.1651)
		(layer "In5.Cu")
		(net "P5E_PEX3_STN0_RX_DP<1>")
	)
	(segment
		(start 420.99738 -123.215908)
		(end 420.36238 -122.951494)
		(width 0.1651)
		(layer "In5.Cu")
		(net "P5E_PEX3_STN0_RX_DP<1>")
	)
	(segment
		(start 423.19321 -125.386846)
		(end 420.99738 -123.215908)
		(width 0.1651)
		(layer "In5.Cu")
		(net "P5E_PEX3_STN0_RX_DP<1>")
	)
	(segment
		(start 424.734482 -127.310134)
		(end 424.410886 -126.934722)
		(width 0.1651)
		(layer "In5.Cu")
		(net "P5E_PEX3_STN0_RX_DP<1>")
	)
	(segment
		(start 429.800004 -287.349946)
		(end 430.065434 -287.349946)
		(width 0.1143)
		(layer "In5.Cu")
		(net "P5E_PEX3_STN0_RX_DP<1>")
	)
	(segment
		(start 413.79394 -121.076466)
		(end 413.50311 -121.367296)
		(width 0.1651)
		(layer "In5.Cu")
		(net "P5E_PEX3_STN0_RX_DP<1>")
	)
	(segment
		(start 420.36238 -122.951494)
		(end 420.212774 -123.013216)
		(width 0.1651)
		(layer "In5.Cu")
		(net "P5E_PEX3_STN0_RX_DP<1>")
	)
	(segment
		(start 424.096688 -126.434342)
		(end 423.971466 -126.425198)
		(width 0.1651)
		(layer "In5.Cu")
		(net "P5E_PEX3_STN0_RX_DP<1>")
	)
	(segment
		(start 423.647616 -126.049786)
		(end 423.65676 -125.924564)
		(width 0.1651)
		(layer "In5.Cu")
		(net "P5E_PEX3_STN0_RX_DP<1>")
	)
	(segment
		(start 416.316668 -121.266712)
		(end 416.316668 -121.266966)
		(width 0.1651)
		(layer "In5.Cu")
		(net "P5E_PEX3_STN0_RX_DP<1>")
	)
	(segment
		(start 425.174156 -127.819658)
		(end 425.1833 -127.694182)
		(width 0.1651)
		(layer "In5.Cu")
		(net "P5E_PEX3_STN0_RX_DP<1>")
	)
	(segment
		(start 433.512722 -134.61873)
		(end 431.272188 -133.37159)
		(width 0.1651)
		(layer "In5.Cu")
		(net "P5E_PEX3_STN0_RX_DP<1>")
	)
	(segment
		(start 431.272188 -133.37159)
		(end 430.843182 -132.942584)
		(width 0.1651)
		(layer "In5.Cu")
		(net "P5E_PEX3_STN0_RX_DP<1>")
	)
	(segment
		(start 417.503864 -121.885202)
		(end 417.442396 -121.735596)
		(width 0.1651)
		(layer "In5.Cu")
		(net "P5E_PEX3_STN0_RX_DP<1>")
	)
	(segment
		(start 419.087046 -122.544586)
		(end 418.629592 -122.354086)
		(width 0.1651)
		(layer "In5.Cu")
		(net "P5E_PEX3_STN0_RX_DP<1>")
	)
	(segment
		(start 420.212774 -123.013216)
		(end 419.75532 -122.822716)
		(width 0.1651)
		(layer "In5.Cu")
		(net "P5E_PEX3_STN0_RX_DP<1>")
	)
	(segment
		(start 428.682404 -131.751578)
		(end 425.623228 -128.204214)
		(width 0.1651)
		(layer "In5.Cu")
		(net "P5E_PEX3_STN0_RX_DP<1>")
	)
	(segment
		(start 424.42003 -126.809246)
		(end 424.096688 -126.434342)
		(width 0.1651)
		(layer "In5.Cu")
		(net "P5E_PEX3_STN0_RX_DP<1>")
	)
	(segment
		(start 419.236652 -122.482864)
		(end 419.087046 -122.544586)
		(width 0.1651)
		(layer "In5.Cu")
		(net "P5E_PEX3_STN0_RX_DP<1>")
	)
	(segment
		(start 430.179734 -286.994854)
		(end 430.394872 -286.779716)
		(width 0.1143)
		(layer "In5.Cu")
		(net "P5E_PEX3_STN0_RX_DP<1>")
	)
	(segment
		(start 416.83559 -121.606818)
		(end 416.378136 -121.416572)
		(width 0.1651)
		(layer "In5.Cu")
		(net "P5E_PEX3_STN0_RX_DP<1>")
	)
	(segment
		(start 430.394872 -286.779716)
		(end 432.17592 -286.779716)
		(width 0.1143)
		(layer "In5.Cu")
		(net "P5E_PEX3_STN0_RX_DP<1>")
	)
	(segment
		(start 423.971466 -126.425198)
		(end 423.647616 -126.049786)
		(width 0.1651)
		(layer "In5.Cu")
		(net "P5E_PEX3_STN0_RX_DP<1>")
	)
	(segment
		(start 437.939942 -239.260888)
		(end 436.485284 -232.123996)
		(width 0.1651)
		(layer "In5.Cu")
		(net "P5E_PEX3_STN0_RX_DP<1>")
	)
	(segment
		(start 437.148478 -168.536366)
		(end 436.640478 -149.910546)
		(width 0.1651)
		(layer "In5.Cu")
		(net "P5E_PEX3_STN0_RX_DP<1>")
	)
	(segment
		(start 425.623228 -128.204214)
		(end 425.497752 -128.19507)
		(width 0.1651)
		(layer "In5.Cu")
		(net "P5E_PEX3_STN0_RX_DP<1>")
	)
	(segment
		(start 425.497752 -128.19507)
		(end 425.174156 -127.819658)
		(width 0.1651)
		(layer "In5.Cu")
		(net "P5E_PEX3_STN0_RX_DP<1>")
	)
	(segment
		(start 418.629592 -122.354086)
		(end 418.568124 -122.20448)
		(width 0.1651)
		(layer "In5.Cu")
		(net "P5E_PEX3_STN0_RX_DP<1>")
	)
	(segment
		(start 425.1833 -127.694182)
		(end 424.859958 -127.319278)
		(width 0.1651)
		(layer "In5.Cu")
		(net "P5E_PEX3_STN0_RX_DP<1>")
	)
	(segment
		(start 419.75532 -122.822716)
		(end 419.693852 -122.67311)
		(width 0.1651)
		(layer "In5.Cu")
		(net "P5E_PEX3_STN0_RX_DP<1>")
	)
	(segment
		(start 436.640478 -149.910546)
		(end 436.383938 -146.3929)
		(width 0.1651)
		(layer "In5.Cu")
		(net "P5E_PEX3_STN0_RX_DP<1>")
	)
	(segment
		(start 446.567306 -273.294602)
		(end 446.715134 -269.313406)
		(width 0.1651)
		(layer "In5.Cu")
		(net "P5E_PEX3_STN0_RX_DP<1>")
	)
	(segment
		(start 446.715134 -269.313406)
		(end 437.939942 -239.260888)
		(width 0.1651)
		(layer "In5.Cu")
		(net "P5E_PEX3_STN0_RX_DP<1>")
	)
	(segment
		(start 417.442396 -121.735596)
		(end 416.985196 -121.54535)
		(width 0.1651)
		(layer "In5.Cu")
		(net "P5E_PEX3_STN0_RX_DP<1>")
	)
	(segment
		(start 430.065434 -287.349946)
		(end 430.179734 -287.235646)
		(width 0.1143)
		(layer "In5.Cu")
		(net "P5E_PEX3_STN0_RX_DP<1>")
	)
	(segment
		(start 419.693852 -122.67311)
		(end 419.236652 -122.482864)
		(width 0.1651)
		(layer "In5.Cu")
		(net "P5E_PEX3_STN0_RX_DP<1>")
	)
	(segment
		(start 415.859468 -121.076466)
		(end 413.79394 -121.076466)
		(width 0.1651)
		(layer "In5.Cu")
		(net "P5E_PEX3_STN0_RX_DP<1>")
	)
	(segment
		(start 436.383938 -146.3929)
		(end 433.9717 -135.332724)
		(width 0.1651)
		(layer "In5.Cu")
		(net "P5E_PEX3_STN0_RX_DP<1>")
	)
	(segment
		(start 432.22164 -286.733996)
		(end 432.250088 -286.733996)
		(width 0.1143)
		(layer "In5.Cu")
		(net "P5E_PEX3_STN0_RX_DP<1>")
	)
	(segment
		(start 432.17592 -286.779716)
		(end 432.22164 -286.733996)
		(width 0.1143)
		(layer "In5.Cu")
		(net "P5E_PEX3_STN0_RX_DP<1>")
	)
	(segment
		(start 432.250088 -286.733996)
		(end 434.220366 -286.733996)
		(width 0.1651)
		(layer "In5.Cu")
		(net "P5E_PEX3_STN0_RX_DP<1>")
	)
	(segment
		(start 424.859958 -127.319278)
		(end 424.734482 -127.310134)
		(width 0.1651)
		(layer "In5.Cu")
		(net "P5E_PEX3_STN0_RX_DP<1>")
	)
	(segment
		(start 430.179734 -287.235646)
		(end 430.179734 -286.994854)
		(width 0.1143)
		(layer "In5.Cu")
		(net "P5E_PEX3_STN0_RX_DP<1>")
	)
	(segment
		(start 423.65676 -125.924564)
		(end 423.19321 -125.386846)
		(width 0.1651)
		(layer "In5.Cu")
		(net "P5E_PEX3_STN0_RX_DP<1>")
	)
	(segment
		(start 436.485284 -232.123996)
		(end 437.148478 -168.536366)
		(width 0.1651)
		(layer "In5.Cu")
		(net "P5E_PEX3_STN0_RX_DP<1>")
	)
	(segment
		(start 424.410886 -126.934722)
		(end 424.42003 -126.809246)
		(width 0.1651)
		(layer "In5.Cu")
		(net "P5E_PEX3_STN0_RX_DP<1>")
	)
	(segment
		(start 410.23032 -99.750372)
		(end 410.51988 -100.039932)
		(width 0.13208)
		(layer "F.Cu")
		(net "NIC7_SLOT_ID1")
	)
	(segment
		(start 407.695146 -100.766372)
		(end 407.695146 -99.750372)
		(width 0.13208)
		(layer "F.Cu")
		(net "NIC7_SLOT_ID1")
	)
	(segment
		(start 407.695146 -99.750372)
		(end 410.23032 -99.750372)
		(width 0.13208)
		(layer "F.Cu")
		(net "NIC7_SLOT_ID1")
	)
	(segment
		(start 410.51988 -100.039932)
		(end 416.95751 -100.039932)
		(width 0.13208)
		(layer "F.Cu")
		(net "NIC7_SLOT_ID1")
	)
	(via
		(at 410.51988 -100.039932)
		(size 0.762)
		(drill 0.381)
		(layers "F.Cu" "B.Cu")
		(net "NIC7_SLOT_ID1")
	)
	(segment
		(start 167.230298 -122.95505)
		(end 167.393112 -123.117864)
		(width 0.13462)
		(layer "F.Cu")
		(net "P5E_PEX1_STN1_RX_DP<26>")
	)
	(segment
		(start 166.742364 -122.95505)
		(end 167.230298 -122.95505)
		(width 0.13462)
		(layer "F.Cu")
		(net "P5E_PEX1_STN1_RX_DP<26>")
	)
	(segment
		(start 169.901616 -123.117864)
		(end 170.196764 -122.822716)
		(width 0.13462)
		(layer "F.Cu")
		(net "P5E_PEX1_STN1_RX_DP<26>")
	)
	(segment
		(start 167.393112 -123.117864)
		(end 169.901616 -123.117864)
		(width 0.13462)
		(layer "F.Cu")
		(net "P5E_PEX1_STN1_RX_DP<26>")
	)
	(segment
		(start 185.135266 -273.670014)
		(end 184.894474 -273.670014)
		(width 0.1143)
		(layer "In5.Cu")
		(net "P5E_PEX1_STN1_RX_DP<26>")
	)
	(segment
		(start 156.391356 -161.945066)
		(end 155.575508 -157.418786)
		(width 0.1651)
		(layer "In5.Cu")
		(net "P5E_PEX1_STN1_RX_DP<26>")
	)
	(segment
		(start 163.499546 -125.839474)
		(end 167.919146 -123.113546)
		(width 0.1651)
		(layer "In5.Cu")
		(net "P5E_PEX1_STN1_RX_DP<26>")
	)
	(segment
		(start 162.793426 -126.46787)
		(end 163.499546 -125.839474)
		(width 0.1651)
		(layer "In5.Cu")
		(net "P5E_PEX1_STN1_RX_DP<26>")
	)
	(segment
		(start 185.24982 -273.784568)
		(end 185.135266 -273.670014)
		(width 0.1143)
		(layer "In5.Cu")
		(net "P5E_PEX1_STN1_RX_DP<26>")
	)
	(segment
		(start 184.63387 -271.802352)
		(end 184.63387 -271.773904)
		(width 0.1143)
		(layer "In5.Cu")
		(net "P5E_PEX1_STN1_RX_DP<26>")
	)
	(segment
		(start 184.67959 -273.45513)
		(end 184.67959 -271.848072)
		(width 0.1143)
		(layer "In5.Cu")
		(net "P5E_PEX1_STN1_RX_DP<26>")
	)
	(segment
		(start 154.92603 -147.406106)
		(end 155.25496 -146.151092)
		(width 0.1651)
		(layer "In5.Cu")
		(net "P5E_PEX1_STN1_RX_DP<26>")
	)
	(segment
		(start 155.25496 -146.151092)
		(end 157.758384 -142.790672)
		(width 0.1651)
		(layer "In5.Cu")
		(net "P5E_PEX1_STN1_RX_DP<26>")
	)
	(segment
		(start 184.63387 -271.773904)
		(end 184.63387 -267.93063)
		(width 0.1651)
		(layer "In5.Cu")
		(net "P5E_PEX1_STN1_RX_DP<26>")
	)
	(segment
		(start 158.778702 -139.268962)
		(end 160.449006 -129.59461)
		(width 0.1651)
		(layer "In5.Cu")
		(net "P5E_PEX1_STN1_RX_DP<26>")
	)
	(segment
		(start 169.905934 -123.113546)
		(end 170.196764 -122.822716)
		(width 0.1651)
		(layer "In5.Cu")
		(net "P5E_PEX1_STN1_RX_DP<26>")
	)
	(segment
		(start 185.24982 -274.049744)
		(end 185.24982 -273.784568)
		(width 0.1143)
		(layer "In5.Cu")
		(net "P5E_PEX1_STN1_RX_DP<26>")
	)
	(segment
		(start 157.758384 -142.790672)
		(end 158.778702 -139.268962)
		(width 0.1651)
		(layer "In5.Cu")
		(net "P5E_PEX1_STN1_RX_DP<26>")
	)
	(segment
		(start 184.67959 -271.848072)
		(end 184.63387 -271.802352)
		(width 0.1143)
		(layer "In5.Cu")
		(net "P5E_PEX1_STN1_RX_DP<26>")
	)
	(segment
		(start 155.575508 -157.418786)
		(end 154.92603 -147.406106)
		(width 0.1651)
		(layer "In5.Cu")
		(net "P5E_PEX1_STN1_RX_DP<26>")
	)
	(segment
		(start 167.919146 -123.113546)
		(end 169.905934 -123.113546)
		(width 0.1651)
		(layer "In5.Cu")
		(net "P5E_PEX1_STN1_RX_DP<26>")
	)
	(segment
		(start 184.63387 -267.93063)
		(end 156.391356 -161.945066)
		(width 0.1651)
		(layer "In5.Cu")
		(net "P5E_PEX1_STN1_RX_DP<26>")
	)
	(segment
		(start 184.894474 -273.670014)
		(end 184.67959 -273.45513)
		(width 0.1143)
		(layer "In5.Cu")
		(net "P5E_PEX1_STN1_RX_DP<26>")
	)
	(segment
		(start 160.449006 -129.59461)
		(end 160.619186 -129.219198)
		(width 0.1651)
		(layer "In5.Cu")
		(net "P5E_PEX1_STN1_RX_DP<26>")
	)
	(segment
		(start 160.619186 -129.219198)
		(end 162.793426 -126.46787)
		(width 0.1651)
		(layer "In5.Cu")
		(net "P5E_PEX1_STN1_RX_DP<26>")
	)
	(segment
		(start 173.850046 -317.749936)
		(end 173.850046 -318.015366)
		(width 0.1143)
		(layer "In5.Cu")
		(net "P5E_PEX1_STN6_RX_DP<96>")
	)
	(segment
		(start 147.330922 -351.877376)
		(end 144.993868 -358.154732)
		(width 0.1651)
		(layer "In5.Cu")
		(net "P5E_PEX1_STN6_RX_DP<96>")
	)
	(segment
		(start 173.234096 -319.883282)
		(end 173.234096 -319.91173)
		(width 0.1143)
		(layer "In5.Cu")
		(net "P5E_PEX1_STN6_RX_DP<96>")
	)
	(segment
		(start 131.869942 -375.999248)
		(end 131.437126 -375.999248)
		(width 0.1651)
		(layer "In5.Cu")
		(net "P5E_PEX1_STN6_RX_DP<96>")
	)
	(segment
		(start 132.6388 -368.5286)
		(end 132.08762 -369.938046)
		(width 0.1651)
		(layer "In5.Cu")
		(net "P5E_PEX1_STN6_RX_DP<96>")
	)
	(segment
		(start 155.426664 -335.711546)
		(end 147.330922 -351.877376)
		(width 0.1651)
		(layer "In5.Cu")
		(net "P5E_PEX1_STN6_RX_DP<96>")
	)
	(segment
		(start 134.643368 -366.801146)
		(end 134.485888 -366.787176)
		(width 0.1651)
		(layer "In5.Cu")
		(net "P5E_PEX1_STN6_RX_DP<96>")
	)
	(segment
		(start 173.735746 -318.129666)
		(end 173.505622 -318.129666)
		(width 0.1143)
		(layer "In5.Cu")
		(net "P5E_PEX1_STN6_RX_DP<96>")
	)
	(segment
		(start 132.08762 -375.78157)
		(end 131.869942 -375.999248)
		(width 0.1651)
		(layer "In5.Cu")
		(net "P5E_PEX1_STN6_RX_DP<96>")
	)
	(segment
		(start 133.731 -367.5634)
		(end 132.6388 -368.5286)
		(width 0.1651)
		(layer "In5.Cu")
		(net "P5E_PEX1_STN6_RX_DP<96>")
	)
	(segment
		(start 158.27502 -332.52791)
		(end 155.426664 -335.711546)
		(width 0.1651)
		(layer "In5.Cu")
		(net "P5E_PEX1_STN6_RX_DP<96>")
	)
	(segment
		(start 171.235624 -324.879716)
		(end 158.27502 -332.52791)
		(width 0.1651)
		(layer "In5.Cu")
		(net "P5E_PEX1_STN6_RX_DP<96>")
	)
	(segment
		(start 173.279816 -318.355472)
		(end 173.279816 -319.837562)
		(width 0.1143)
		(layer "In5.Cu")
		(net "P5E_PEX1_STN6_RX_DP<96>")
	)
	(segment
		(start 144.993868 -358.154732)
		(end 134.643368 -366.801146)
		(width 0.1651)
		(layer "In5.Cu")
		(net "P5E_PEX1_STN6_RX_DP<96>")
	)
	(segment
		(start 173.279816 -319.837562)
		(end 173.234096 -319.883282)
		(width 0.1143)
		(layer "In5.Cu")
		(net "P5E_PEX1_STN6_RX_DP<96>")
	)
	(segment
		(start 131.310126 -375.872248)
		(end 131.310126 -375.490232)
		(width 0.1651)
		(layer "In5.Cu")
		(net "P5E_PEX1_STN6_RX_DP<96>")
	)
	(segment
		(start 132.08762 -369.938046)
		(end 132.08762 -375.78157)
		(width 0.1651)
		(layer "In5.Cu")
		(net "P5E_PEX1_STN6_RX_DP<96>")
	)
	(segment
		(start 173.234096 -321.928998)
		(end 171.312078 -324.803262)
		(width 0.1651)
		(layer "In5.Cu")
		(net "P5E_PEX1_STN6_RX_DP<96>")
	)
	(segment
		(start 131.437126 -375.999248)
		(end 131.310126 -375.872248)
		(width 0.1651)
		(layer "In5.Cu")
		(net "P5E_PEX1_STN6_RX_DP<96>")
	)
	(segment
		(start 134.115302 -367.096802)
		(end 134.101332 -367.254028)
		(width 0.1651)
		(layer "In5.Cu")
		(net "P5E_PEX1_STN6_RX_DP<96>")
	)
	(segment
		(start 173.850046 -318.015366)
		(end 173.735746 -318.129666)
		(width 0.1143)
		(layer "In5.Cu")
		(net "P5E_PEX1_STN6_RX_DP<96>")
	)
	(segment
		(start 173.234096 -319.91173)
		(end 173.234096 -321.928998)
		(width 0.1651)
		(layer "In5.Cu")
		(net "P5E_PEX1_STN6_RX_DP<96>")
	)
	(segment
		(start 134.485888 -366.787176)
		(end 134.115302 -367.096802)
		(width 0.1651)
		(layer "In5.Cu")
		(net "P5E_PEX1_STN6_RX_DP<96>")
	)
	(segment
		(start 171.312078 -324.803262)
		(end 171.235624 -324.879716)
		(width 0.1651)
		(layer "In5.Cu")
		(net "P5E_PEX1_STN6_RX_DP<96>")
	)
	(segment
		(start 134.101332 -367.254028)
		(end 133.731 -367.5634)
		(width 0.1651)
		(layer "In5.Cu")
		(net "P5E_PEX1_STN6_RX_DP<96>")
	)
	(segment
		(start 173.505622 -318.129666)
		(end 173.279816 -318.355472)
		(width 0.1143)
		(layer "In5.Cu")
		(net "P5E_PEX1_STN6_RX_DP<96>")
	)
	(segment
		(start 272.063972 -107.0864)
		(end 277.577042 -107.0864)
		(width 0.13462)
		(layer "F.Cu")
		(net "P5E_PEX2_STN1_TX_C_DN<20>")
	)
	(segment
		(start 277.735538 -107.244896)
		(end 278.242268 -107.244896)
		(width 0.13462)
		(layer "F.Cu")
		(net "P5E_PEX2_STN1_TX_C_DN<20>")
	)
	(segment
		(start 277.577042 -107.0864)
		(end 277.735538 -107.244896)
		(width 0.13462)
		(layer "F.Cu")
		(net "P5E_PEX2_STN1_TX_C_DN<20>")
	)
	(segment
		(start 271.747234 -107.403138)
		(end 272.063972 -107.0864)
		(width 0.13462)
		(layer "F.Cu")
		(net "P5E_PEX2_STN1_TX_C_DN<20>")
	)
	(segment
		(start 416.476434 -142.755112)
		(end 416.95751 -142.755112)
		(width 0.13462)
		(layer "F.Cu")
		(net "P5E_PEX3_STN0_RX_DN<8>")
	)
	(segment
		(start 416.313366 -142.91818)
		(end 416.476434 -142.755112)
		(width 0.13462)
		(layer "F.Cu")
		(net "P5E_PEX3_STN0_RX_DN<8>")
	)
	(segment
		(start 415.65195 -142.91818)
		(end 416.313366 -142.91818)
		(width 0.13462)
		(layer "F.Cu")
		(net "P5E_PEX3_STN0_RX_DN<8>")
	)
	(segment
		(start 415.35731 -142.62354)
		(end 415.65195 -142.91818)
		(width 0.13462)
		(layer "F.Cu")
		(net "P5E_PEX3_STN0_RX_DN<8>")
	)
	(segment
		(start 430.89195 -272.10385)
		(end 430.84623 -272.14957)
		(width 0.1143)
		(layer "In5.Cu")
		(net "P5E_PEX3_STN0_RX_DN<8>")
	)
	(segment
		(start 430.84623 -273.35861)
		(end 430.370234 -273.834606)
		(width 0.1143)
		(layer "In5.Cu")
		(net "P5E_PEX3_STN0_RX_DN<8>")
	)
	(segment
		(start 421.566848 -149.895306)
		(end 422.113964 -151.432514)
		(width 0.1651)
		(layer "In5.Cu")
		(net "P5E_PEX3_STN0_RX_DN<8>")
	)
	(segment
		(start 430.84623 -272.14957)
		(end 430.84623 -273.35861)
		(width 0.1143)
		(layer "In5.Cu")
		(net "P5E_PEX3_STN0_RX_DN<8>")
	)
	(segment
		(start 415.35731 -142.62354)
		(end 415.64814 -142.91437)
		(width 0.1651)
		(layer "In5.Cu")
		(net "P5E_PEX3_STN0_RX_DN<8>")
	)
	(segment
		(start 417.976558 -144.304258)
		(end 421.566848 -149.895306)
		(width 0.1651)
		(layer "In5.Cu")
		(net "P5E_PEX3_STN0_RX_DN<8>")
	)
	(segment
		(start 430.89195 -271.535652)
		(end 430.89195 -272.075402)
		(width 0.1651)
		(layer "In5.Cu")
		(net "P5E_PEX3_STN0_RX_DN<8>")
	)
	(segment
		(start 424.963844 -154.698954)
		(end 426.474128 -159.983424)
		(width 0.1651)
		(layer "In5.Cu")
		(net "P5E_PEX3_STN0_RX_DN<8>")
	)
	(segment
		(start 430.370234 -274.885404)
		(end 430.484534 -274.999704)
		(width 0.1143)
		(layer "In5.Cu")
		(net "P5E_PEX3_STN0_RX_DN<8>")
	)
	(segment
		(start 430.89195 -272.075402)
		(end 430.89195 -272.10385)
		(width 0.1143)
		(layer "In5.Cu")
		(net "P5E_PEX3_STN0_RX_DN<8>")
	)
	(segment
		(start 430.370234 -273.834606)
		(end 430.370234 -274.885404)
		(width 0.1143)
		(layer "In5.Cu")
		(net "P5E_PEX3_STN0_RX_DN<8>")
	)
	(segment
		(start 426.474128 -159.983424)
		(end 426.572934 -160.610042)
		(width 0.1651)
		(layer "In5.Cu")
		(net "P5E_PEX3_STN0_RX_DN<8>")
	)
	(segment
		(start 423.575988 -152.831292)
		(end 424.963844 -154.698954)
		(width 0.1651)
		(layer "In5.Cu")
		(net "P5E_PEX3_STN0_RX_DN<8>")
	)
	(segment
		(start 422.113964 -151.432514)
		(end 423.575988 -152.831292)
		(width 0.1651)
		(layer "In5.Cu")
		(net "P5E_PEX3_STN0_RX_DN<8>")
	)
	(segment
		(start 415.896298 -142.91437)
		(end 417.976558 -144.304258)
		(width 0.1651)
		(layer "In5.Cu")
		(net "P5E_PEX3_STN0_RX_DN<8>")
	)
	(segment
		(start 426.572934 -160.610042)
		(end 430.185068 -265.20775)
		(width 0.1651)
		(layer "In5.Cu")
		(net "P5E_PEX3_STN0_RX_DN<8>")
	)
	(segment
		(start 415.64814 -142.91437)
		(end 415.896298 -142.91437)
		(width 0.1651)
		(layer "In5.Cu")
		(net "P5E_PEX3_STN0_RX_DN<8>")
	)
	(segment
		(start 430.484534 -274.999704)
		(end 430.749964 -274.999704)
		(width 0.1143)
		(layer "In5.Cu")
		(net "P5E_PEX3_STN0_RX_DN<8>")
	)
	(segment
		(start 430.185068 -265.20775)
		(end 430.844452 -270.75384)
		(width 0.1651)
		(layer "In5.Cu")
		(net "P5E_PEX3_STN0_RX_DN<8>")
	)
	(segment
		(start 430.844452 -270.75384)
		(end 430.891442 -271.535144)
		(width 0.1651)
		(layer "In5.Cu")
		(net "P5E_PEX3_STN0_RX_DN<8>")
	)
	(segment
		(start 430.891442 -271.535144)
		(end 430.89195 -271.535652)
		(width 0.1651)
		(layer "In5.Cu")
		(net "P5E_PEX3_STN0_RX_DN<8>")
	)
	(segment
		(start 421.557704 -101.240082)
		(end 422.97604 -101.240082)
		(width 0.13208)
		(layer "F.Cu")
		(net "NCSI_NIC7_RXD1")
	)
	(via
		(at 422.97604 -101.240082)
		(size 0.508)
		(drill 0.254)
		(layers "F.Cu" "B.Cu")
		(net "NCSI_NIC7_RXD1")
	)
	(segment
		(start 424.22699 -102.088696)
		(end 423.378376 -101.240082)
		(width 0.13208)
		(layer "B.Cu")
		(net "NCSI_NIC7_RXD1")
	)
	(segment
		(start 425.441872 -102.088696)
		(end 424.22699 -102.088696)
		(width 0.13208)
		(layer "B.Cu")
		(net "NCSI_NIC7_RXD1")
	)
	(segment
		(start 423.378376 -101.240082)
		(end 422.97604 -101.240082)
		(width 0.13208)
		(layer "B.Cu")
		(net "NCSI_NIC7_RXD1")
	)
	(segment
		(start 161.654236 -121.154952)
		(end 161.491422 -121.317766)
		(width 0.13462)
		(layer "F.Cu")
		(net "P5E_PEX1_STN1_TX_C_DN<25>")
	)
	(segment
		(start 162.14217 -121.154952)
		(end 161.654236 -121.154952)
		(width 0.13462)
		(layer "F.Cu")
		(net "P5E_PEX1_STN1_TX_C_DN<25>")
	)
	(segment
		(start 161.491422 -121.317766)
		(end 155.959556 -121.317766)
		(width 0.13462)
		(layer "F.Cu")
		(net "P5E_PEX1_STN1_TX_C_DN<25>")
	)
	(segment
		(start 155.959556 -121.317766)
		(end 155.647136 -121.005346)
		(width 0.13462)
		(layer "F.Cu")
		(net "P5E_PEX1_STN1_TX_C_DN<25>")
	)
	(segment
		(start 123.84786 -341.372698)
		(end 123.316238 -342.094566)
		(width 0.1651)
		(layer "In5.Cu")
		(net "P5E_PEX1_STN6_RX_DN<103>")
	)
	(segment
		(start 164.70376 -321.05727)
		(end 154.546808 -327.07072)
		(width 0.1651)
		(layer "In5.Cu")
		(net "P5E_PEX1_STN6_RX_DN<103>")
	)
	(segment
		(start 166.934642 -316.419992)
		(end 166.820342 -316.534292)
		(width 0.1143)
		(layer "In5.Cu")
		(net "P5E_PEX1_STN6_RX_DN<103>")
	)
	(segment
		(start 115.910106 -375.308114)
		(end 115.910106 -375.69013)
		(width 0.1651)
		(layer "In5.Cu")
		(net "P5E_PEX1_STN6_RX_DN<103>")
	)
	(segment
		(start 167.200072 -316.799722)
		(end 167.200072 -316.534292)
		(width 0.1143)
		(layer "In5.Cu")
		(net "P5E_PEX1_STN6_RX_DN<103>")
	)
	(segment
		(start 116.037106 -375.181114)
		(end 115.910106 -375.308114)
		(width 0.1651)
		(layer "In5.Cu")
		(net "P5E_PEX1_STN6_RX_DN<103>")
	)
	(segment
		(start 167.085772 -316.419992)
		(end 166.934642 -316.419992)
		(width 0.1143)
		(layer "In5.Cu")
		(net "P5E_PEX1_STN6_RX_DN<103>")
	)
	(segment
		(start 154.546808 -327.07072)
		(end 147.177252 -331.747114)
		(width 0.1651)
		(layer "In5.Cu")
		(net "P5E_PEX1_STN6_RX_DN<103>")
	)
	(segment
		(start 116.96954 -374.798336)
		(end 116.586762 -375.181114)
		(width 0.1651)
		(layer "In5.Cu")
		(net "P5E_PEX1_STN6_RX_DN<103>")
	)
	(segment
		(start 165.93312 -320.2051)
		(end 165.8874 -320.25082)
		(width 0.1143)
		(layer "In5.Cu")
		(net "P5E_PEX1_STN6_RX_DN<103>")
	)
	(segment
		(start 144.215612 -332.607412)
		(end 123.84786 -341.372698)
		(width 0.1651)
		(layer "In5.Cu")
		(net "P5E_PEX1_STN6_RX_DN<103>")
	)
	(segment
		(start 116.586762 -375.181114)
		(end 116.037106 -375.181114)
		(width 0.1651)
		(layer "In5.Cu")
		(net "P5E_PEX1_STN6_RX_DN<103>")
	)
	(segment
		(start 166.820342 -316.534292)
		(end 166.820342 -319.870074)
		(width 0.1143)
		(layer "In5.Cu")
		(net "P5E_PEX1_STN6_RX_DN<103>")
	)
	(segment
		(start 123.316238 -358.221026)
		(end 122.888756 -359.73639)
		(width 0.1651)
		(layer "In5.Cu")
		(net "P5E_PEX1_STN6_RX_DN<103>")
	)
	(segment
		(start 165.8874 -320.25082)
		(end 165.858952 -320.25082)
		(width 0.1143)
		(layer "In5.Cu")
		(net "P5E_PEX1_STN6_RX_DN<103>")
	)
	(segment
		(start 122.888756 -359.73639)
		(end 117.4496 -368.609372)
		(width 0.1651)
		(layer "In5.Cu")
		(net "P5E_PEX1_STN6_RX_DN<103>")
	)
	(segment
		(start 166.820342 -319.870074)
		(end 166.485316 -320.2051)
		(width 0.1143)
		(layer "In5.Cu")
		(net "P5E_PEX1_STN6_RX_DN<103>")
	)
	(segment
		(start 147.177252 -331.747114)
		(end 144.215612 -332.607412)
		(width 0.1651)
		(layer "In5.Cu")
		(net "P5E_PEX1_STN6_RX_DN<103>")
	)
	(segment
		(start 166.485316 -320.2051)
		(end 165.93312 -320.2051)
		(width 0.1143)
		(layer "In5.Cu")
		(net "P5E_PEX1_STN6_RX_DN<103>")
	)
	(segment
		(start 167.200072 -316.534292)
		(end 167.085772 -316.419992)
		(width 0.1143)
		(layer "In5.Cu")
		(net "P5E_PEX1_STN6_RX_DN<103>")
	)
	(segment
		(start 123.316238 -342.094566)
		(end 123.316238 -358.221026)
		(width 0.1651)
		(layer "In5.Cu")
		(net "P5E_PEX1_STN6_RX_DN<103>")
	)
	(segment
		(start 165.686486 -320.25082)
		(end 164.70376 -321.05727)
		(width 0.1651)
		(layer "In5.Cu")
		(net "P5E_PEX1_STN6_RX_DN<103>")
	)
	(segment
		(start 165.858952 -320.25082)
		(end 165.686486 -320.25082)
		(width 0.1651)
		(layer "In5.Cu")
		(net "P5E_PEX1_STN6_RX_DN<103>")
	)
	(segment
		(start 116.96954 -370.311172)
		(end 116.96954 -374.798336)
		(width 0.1651)
		(layer "In5.Cu")
		(net "P5E_PEX1_STN6_RX_DN<103>")
	)
	(segment
		(start 117.4496 -368.609372)
		(end 116.96954 -370.311172)
		(width 0.1651)
		(layer "In5.Cu")
		(net "P5E_PEX1_STN6_RX_DN<103>")
	)
	(segment
		(start 428.052738 -143.504666)
		(end 427.727872 -143.1798)
		(width 0.13462)
		(layer "F.Cu")
		(net "P5E_PEX3_STN0_TX_C_DP<8>")
	)
	(segment
		(start 422.057068 -143.35506)
		(end 421.557704 -143.35506)
		(width 0.13462)
		(layer "F.Cu")
		(net "P5E_PEX3_STN0_TX_C_DP<8>")
	)
	(segment
		(start 422.232328 -143.1798)
		(end 422.057068 -143.35506)
		(width 0.13462)
		(layer "F.Cu")
		(net "P5E_PEX3_STN0_TX_C_DP<8>")
	)
	(segment
		(start 427.727872 -143.1798)
		(end 422.232328 -143.1798)
		(width 0.13462)
		(layer "F.Cu")
		(net "P5E_PEX3_STN0_TX_C_DP<8>")
	)
	(segment
		(start 283.29128 -164.198046)
		(end 284.264354 -165.17112)
		(width 0.13208)
		(layer "F.Cu")
		(net "RST_NIC4_PERST1_R_N")
	)
	(segment
		(start 284.187138 -140.127482)
		(end 284.149546 -140.165074)
		(width 0.13208)
		(layer "F.Cu")
		(net "RST_NIC4_PERST1_R_N")
	)
	(segment
		(start 284.264354 -165.17112)
		(end 284.264354 -165.902894)
		(width 0.13208)
		(layer "F.Cu")
		(net "RST_NIC4_PERST1_R_N")
	)
	(segment
		(start 284.149546 -140.165074)
		(end 282.842462 -140.165074)
		(width 0.13208)
		(layer "F.Cu")
		(net "RST_NIC4_PERST1_R_N")
	)
	(via
		(at 284.187138 -140.127482)
		(size 0.508)
		(drill 0.254)
		(layers "F.Cu" "B.Cu")
		(net "RST_NIC4_PERST1_R_N")
	)
	(via
		(at 283.29128 -164.198046)
		(size 0.508)
		(drill 0.254)
		(layers "F.Cu" "B.Cu")
		(net "RST_NIC4_PERST1_R_N")
	)
	(segment
		(start 284.187138 -140.127482)
		(end 285.473648 -141.413992)
		(width 0.15494)
		(layer "In7.Cu")
		(net "RST_NIC4_PERST1_R_N")
	)
	(segment
		(start 283.29128 -150.471632)
		(end 283.29128 -164.198046)
		(width 0.15494)
		(layer "In7.Cu")
		(net "RST_NIC4_PERST1_R_N")
	)
	(segment
		(start 285.473648 -148.289264)
		(end 283.29128 -150.471632)
		(width 0.15494)
		(layer "In7.Cu")
		(net "RST_NIC4_PERST1_R_N")
	)
	(segment
		(start 285.473648 -141.413992)
		(end 285.473648 -148.289264)
		(width 0.15494)
		(layer "In7.Cu")
		(net "RST_NIC4_PERST1_R_N")
	)
	(segment
		(start 357.752142 -25.390094)
		(end 357.202232 -25.940004)
		(width 0.13208)
		(layer "F.Cu")
		(net "PRSNT_SSD12_N")
	)
	(segment
		(start 357.202232 -26.266394)
		(end 356.420674 -26.266394)
		(width 0.13208)
		(layer "F.Cu")
		(net "PRSNT_SSD12_N")
	)
	(segment
		(start 358.964992 -25.390094)
		(end 357.752142 -25.390094)
		(width 0.13208)
		(layer "F.Cu")
		(net "PRSNT_SSD12_N")
	)
	(segment
		(start 357.202232 -25.940004)
		(end 357.202232 -26.266394)
		(width 0.13208)
		(layer "F.Cu")
		(net "PRSNT_SSD12_N")
	)
	(via
		(at 357.202232 -26.266394)
		(size 0.508)
		(drill 0.254)
		(layers "F.Cu" "B.Cu")
		(net "PRSNT_SSD12_N")
	)
	(segment
		(start 168.342564 -104.71277)
		(end 168.342564 -104.713024)
		(width 0.13462)
		(layer "F.Cu")
		(net "P5E_PEX1_STN1_RX_DP<19>")
	)
	(segment
		(start 168.04767 -105.007918)
		(end 167.393112 -105.007918)
		(width 0.13462)
		(layer "F.Cu")
		(net "P5E_PEX1_STN1_RX_DP<19>")
	)
	(segment
		(start 168.342564 -104.713024)
		(end 168.04767 -105.007918)
		(width 0.13462)
		(layer "F.Cu")
		(net "P5E_PEX1_STN1_RX_DP<19>")
	)
	(segment
		(start 167.230298 -104.845104)
		(end 166.742364 -104.845104)
		(width 0.13462)
		(layer "F.Cu")
		(net "P5E_PEX1_STN1_RX_DP<19>")
	)
	(segment
		(start 167.393112 -105.007918)
		(end 167.230298 -104.845104)
		(width 0.13462)
		(layer "F.Cu")
		(net "P5E_PEX1_STN1_RX_DP<19>")
	)
	(segment
		(start 178.029616 -271.645126)
		(end 177.983896 -271.599406)
		(width 0.1143)
		(layer "In5.Cu")
		(net "P5E_PEX1_STN1_RX_DP<19>")
	)
	(segment
		(start 153.596594 -119.163592)
		(end 156.758132 -112.68202)
		(width 0.1651)
		(layer "In5.Cu")
		(net "P5E_PEX1_STN1_RX_DP<19>")
	)
	(segment
		(start 147.748752 -158.768034)
		(end 147.616164 -156.69006)
		(width 0.1651)
		(layer "In5.Cu")
		(net "P5E_PEX1_STN1_RX_DP<19>")
	)
	(segment
		(start 149.503638 -122.76328)
		(end 150.249382 -121.856246)
		(width 0.1651)
		(layer "In5.Cu")
		(net "P5E_PEX1_STN1_RX_DP<19>")
	)
	(segment
		(start 161.134552 -108.444538)
		(end 167.503348 -105.0036)
		(width 0.1651)
		(layer "In5.Cu")
		(net "P5E_PEX1_STN1_RX_DP<19>")
	)
	(segment
		(start 168.051734 -105.0036)
		(end 168.342564 -104.71277)
		(width 0.1651)
		(layer "In5.Cu")
		(net "P5E_PEX1_STN1_RX_DP<19>")
	)
	(segment
		(start 178.599592 -275.949918)
		(end 178.599592 -275.684488)
		(width 0.1143)
		(layer "In5.Cu")
		(net "P5E_PEX1_STN1_RX_DP<19>")
	)
	(segment
		(start 148.823934 -126.351538)
		(end 149.503638 -122.76328)
		(width 0.1651)
		(layer "In5.Cu")
		(net "P5E_PEX1_STN1_RX_DP<19>")
	)
	(segment
		(start 147.220686 -150.48357)
		(end 148.823934 -126.351538)
		(width 0.1651)
		(layer "In5.Cu")
		(net "P5E_PEX1_STN1_RX_DP<19>")
	)
	(segment
		(start 177.983896 -271.570958)
		(end 177.983896 -269.528544)
		(width 0.1651)
		(layer "In5.Cu")
		(net "P5E_PEX1_STN1_RX_DP<19>")
	)
	(segment
		(start 148.850096 -165.18255)
		(end 147.748752 -158.768034)
		(width 0.1651)
		(layer "In5.Cu")
		(net "P5E_PEX1_STN1_RX_DP<19>")
	)
	(segment
		(start 147.61591 -156.689806)
		(end 147.616164 -156.689806)
		(width 0.1651)
		(layer "In5.Cu")
		(net "P5E_PEX1_STN1_RX_DP<19>")
	)
	(segment
		(start 177.983896 -271.599406)
		(end 177.983896 -271.570958)
		(width 0.1143)
		(layer "In5.Cu")
		(net "P5E_PEX1_STN1_RX_DP<19>")
	)
	(segment
		(start 147.616164 -156.689806)
		(end 147.220686 -150.48357)
		(width 0.1651)
		(layer "In5.Cu")
		(net "P5E_PEX1_STN1_RX_DP<19>")
	)
	(segment
		(start 147.616164 -156.69006)
		(end 147.61591 -156.689806)
		(width 0.1651)
		(layer "In5.Cu")
		(net "P5E_PEX1_STN1_RX_DP<19>")
	)
	(segment
		(start 178.485292 -275.570188)
		(end 178.2445 -275.570188)
		(width 0.1143)
		(layer "In5.Cu")
		(net "P5E_PEX1_STN1_RX_DP<19>")
	)
	(segment
		(start 150.249382 -121.856246)
		(end 152.285192 -120.760236)
		(width 0.1651)
		(layer "In5.Cu")
		(net "P5E_PEX1_STN1_RX_DP<19>")
	)
	(segment
		(start 152.285192 -120.760236)
		(end 153.596594 -119.163592)
		(width 0.1651)
		(layer "In5.Cu")
		(net "P5E_PEX1_STN1_RX_DP<19>")
	)
	(segment
		(start 156.758132 -112.68202)
		(end 161.134552 -108.444538)
		(width 0.1651)
		(layer "In5.Cu")
		(net "P5E_PEX1_STN1_RX_DP<19>")
	)
	(segment
		(start 178.599592 -275.684488)
		(end 178.485292 -275.570188)
		(width 0.1143)
		(layer "In5.Cu")
		(net "P5E_PEX1_STN1_RX_DP<19>")
	)
	(segment
		(start 167.503348 -105.0036)
		(end 168.051734 -105.0036)
		(width 0.1651)
		(layer "In5.Cu")
		(net "P5E_PEX1_STN1_RX_DP<19>")
	)
	(segment
		(start 178.029616 -275.355304)
		(end 178.029616 -271.645126)
		(width 0.1143)
		(layer "In5.Cu")
		(net "P5E_PEX1_STN1_RX_DP<19>")
	)
	(segment
		(start 177.983896 -269.528544)
		(end 148.850096 -165.18255)
		(width 0.1651)
		(layer "In5.Cu")
		(net "P5E_PEX1_STN1_RX_DP<19>")
	)
	(segment
		(start 178.2445 -275.570188)
		(end 178.029616 -275.355304)
		(width 0.1143)
		(layer "In5.Cu")
		(net "P5E_PEX1_STN1_RX_DP<19>")
	)
	(segment
		(start 115.540028 -351.316798)
		(end 115.540028 -350.685354)
		(width 0.13462)
		(layer "F.Cu")
		(net "P5E_PEX1_STN6_TX_C_DN<110>")
	)
	(segment
		(start 115.834668 -351.611438)
		(end 115.540028 -351.316798)
		(width 0.13462)
		(layer "F.Cu")
		(net "P5E_PEX1_STN6_TX_C_DN<110>")
	)
	(segment
		(start 115.540028 -350.685354)
		(end 115.860068 -350.365314)
		(width 0.13462)
		(layer "F.Cu")
		(net "P5E_PEX1_STN6_TX_C_DN<110>")
	)
	(segment
		(start 117.631972 -393.45108)
		(end 114.386106 -392.10615)
		(width 0.1651)
		(layer "In13.Cu")
		(net "P5E_PEX1_STN6_TX_C_DN<110>")
	)
	(segment
		(start 118.575328 -410.080968)
		(end 119.266716 -409.38958)
		(width 0.1651)
		(layer "In13.Cu")
		(net "P5E_PEX1_STN6_TX_C_DN<110>")
	)
	(segment
		(start 110.747048 -389.138414)
		(end 109.290358 -386.970524)
		(width 0.1651)
		(layer "In13.Cu")
		(net "P5E_PEX1_STN6_TX_C_DN<110>")
	)
	(segment
		(start 119.266716 -395.085824)
		(end 117.631972 -393.45108)
		(width 0.1651)
		(layer "In13.Cu")
		(net "P5E_PEX1_STN6_TX_C_DN<110>")
	)
	(segment
		(start 119.266716 -409.38958)
		(end 119.266716 -395.085824)
		(width 0.1651)
		(layer "In13.Cu")
		(net "P5E_PEX1_STN6_TX_C_DN<110>")
	)
	(segment
		(start 118.11 -410.589984)
		(end 118.11 -410.207968)
		(width 0.1651)
		(layer "In13.Cu")
		(net "P5E_PEX1_STN6_TX_C_DN<110>")
	)
	(segment
		(start 109.290358 -386.970524)
		(end 108.47832 -384.045714)
		(width 0.1651)
		(layer "In13.Cu")
		(net "P5E_PEX1_STN6_TX_C_DN<110>")
	)
	(segment
		(start 108.59897 -365.935768)
		(end 113.928652 -354.167694)
		(width 0.1651)
		(layer "In13.Cu")
		(net "P5E_PEX1_STN6_TX_C_DN<110>")
	)
	(segment
		(start 115.543838 -352.552508)
		(end 115.543838 -351.902268)
		(width 0.1651)
		(layer "In13.Cu")
		(net "P5E_PEX1_STN6_TX_C_DN<110>")
	)
	(segment
		(start 108.47832 -384.045714)
		(end 108.59897 -365.935768)
		(width 0.1651)
		(layer "In13.Cu")
		(net "P5E_PEX1_STN6_TX_C_DN<110>")
	)
	(segment
		(start 114.386106 -392.10615)
		(end 110.747048 -389.138414)
		(width 0.1651)
		(layer "In13.Cu")
		(net "P5E_PEX1_STN6_TX_C_DN<110>")
	)
	(segment
		(start 113.928652 -354.167694)
		(end 115.543838 -352.552508)
		(width 0.1651)
		(layer "In13.Cu")
		(net "P5E_PEX1_STN6_TX_C_DN<110>")
	)
	(segment
		(start 118.11 -410.207968)
		(end 118.237 -410.080968)
		(width 0.1651)
		(layer "In13.Cu")
		(net "P5E_PEX1_STN6_TX_C_DN<110>")
	)
	(segment
		(start 118.237 -410.080968)
		(end 118.575328 -410.080968)
		(width 0.1651)
		(layer "In13.Cu")
		(net "P5E_PEX1_STN6_TX_C_DN<110>")
	)
	(segment
		(start 115.543838 -351.902268)
		(end 115.834668 -351.611438)
		(width 0.1651)
		(layer "In13.Cu")
		(net "P5E_PEX1_STN6_TX_C_DN<110>")
	)
	(segment
		(start 333.56296 -358.73436)
		(end 333.283814 -358.455214)
		(width 0.1651)
		(layer "In9.Cu")
		(net "P5E_PEX2_STN5_RX_DN<80>")
	)
	(segment
		(start 291.609018 -323.206618)
		(end 291.609018 -323.116702)
		(width 0.1651)
		(layer "In9.Cu")
		(net "P5E_PEX2_STN5_RX_DN<80>")
	)
	(segment
		(start 335.989168 -392.185398)
		(end 349.862902 -385.561586)
		(width 0.1651)
		(layer "In9.Cu")
		(net "P5E_PEX2_STN5_RX_DN<80>")
	)
	(segment
		(start 291.168582 -322.766182)
		(end 290.779454 -322.377054)
		(width 0.1651)
		(layer "In9.Cu")
		(net "P5E_PEX2_STN5_RX_DN<80>")
	)
	(segment
		(start 336.25536 -359.8672)
		(end 333.56296 -358.73436)
		(width 0.1651)
		(layer "In9.Cu")
		(net "P5E_PEX2_STN5_RX_DN<80>")
	)
	(segment
		(start 331.220826 -339.855048)
		(end 296.329862 -326.90689)
		(width 0.1651)
		(layer "In9.Cu")
		(net "P5E_PEX2_STN5_RX_DN<80>")
	)
	(segment
		(start 345.668092 -364.6932)
		(end 336.25536 -359.8672)
		(width 0.1651)
		(layer "In9.Cu")
		(net "P5E_PEX2_STN5_RX_DN<80>")
	)
	(segment
		(start 331.490066 -397.408146)
		(end 331.617066 -397.281146)
		(width 0.1651)
		(layer "In9.Cu")
		(net "P5E_PEX2_STN5_RX_DN<80>")
	)
	(segment
		(start 334.954372 -393.220448)
		(end 335.989168 -392.185398)
		(width 0.1651)
		(layer "In9.Cu")
		(net "P5E_PEX2_STN5_RX_DN<80>")
	)
	(segment
		(start 290.634166 -316.419992)
		(end 290.81095 -316.419992)
		(width 0.1143)
		(layer "In9.Cu")
		(net "P5E_PEX2_STN5_RX_DN<80>")
	)
	(segment
		(start 290.89985 -316.508892)
		(end 290.89985 -316.799722)
		(width 0.1143)
		(layer "In9.Cu")
		(net "P5E_PEX2_STN5_RX_DN<80>")
	)
	(segment
		(start 331.955902 -397.281146)
		(end 332.220824 -397.016478)
		(width 0.1651)
		(layer "In9.Cu")
		(net "P5E_PEX2_STN5_RX_DN<80>")
	)
	(segment
		(start 350.506792 -369.556284)
		(end 349.69196 -367.9698)
		(width 0.1651)
		(layer "In9.Cu")
		(net "P5E_PEX2_STN5_RX_DN<80>")
	)
	(segment
		(start 291.258498 -322.766182)
		(end 291.168582 -322.766182)
		(width 0.1651)
		(layer "In9.Cu")
		(net "P5E_PEX2_STN5_RX_DN<80>")
	)
	(segment
		(start 332.220824 -397.016478)
		(end 334.954372 -393.220448)
		(width 0.1651)
		(layer "In9.Cu")
		(net "P5E_PEX2_STN5_RX_DN<80>")
	)
	(segment
		(start 290.56584 -322.057268)
		(end 290.56584 -319.916048)
		(width 0.1651)
		(layer "In9.Cu")
		(net "P5E_PEX2_STN5_RX_DN<80>")
	)
	(segment
		(start 333.085694 -341.53602)
		(end 331.220826 -339.855048)
		(width 0.1651)
		(layer "In9.Cu")
		(net "P5E_PEX2_STN5_RX_DN<80>")
	)
	(segment
		(start 290.56584 -319.916048)
		(end 290.56584 -319.8876)
		(width 0.1143)
		(layer "In9.Cu")
		(net "P5E_PEX2_STN5_RX_DN<80>")
	)
	(segment
		(start 333.283814 -358.455214)
		(end 333.283814 -341.937086)
		(width 0.1651)
		(layer "In9.Cu")
		(net "P5E_PEX2_STN5_RX_DN<80>")
	)
	(segment
		(start 349.69196 -367.9698)
		(end 345.668092 -364.6932)
		(width 0.1651)
		(layer "In9.Cu")
		(net "P5E_PEX2_STN5_RX_DN<80>")
	)
	(segment
		(start 290.52012 -316.534038)
		(end 290.634166 -316.419992)
		(width 0.1143)
		(layer "In9.Cu")
		(net "P5E_PEX2_STN5_RX_DN<80>")
	)
	(segment
		(start 296.329862 -326.90689)
		(end 293.48303 -325.08063)
		(width 0.1651)
		(layer "In9.Cu")
		(net "P5E_PEX2_STN5_RX_DN<80>")
	)
	(segment
		(start 331.490066 -397.790162)
		(end 331.490066 -397.408146)
		(width 0.1651)
		(layer "In9.Cu")
		(net "P5E_PEX2_STN5_RX_DN<80>")
	)
	(segment
		(start 331.617066 -397.281146)
		(end 331.955902 -397.281146)
		(width 0.1651)
		(layer "In9.Cu")
		(net "P5E_PEX2_STN5_RX_DN<80>")
	)
	(segment
		(start 290.81095 -316.419992)
		(end 290.89985 -316.508892)
		(width 0.1143)
		(layer "In9.Cu")
		(net "P5E_PEX2_STN5_RX_DN<80>")
	)
	(segment
		(start 349.862902 -385.561586)
		(end 350.22282 -384.993896)
		(width 0.1651)
		(layer "In9.Cu")
		(net "P5E_PEX2_STN5_RX_DN<80>")
	)
	(segment
		(start 290.56584 -319.8876)
		(end 290.52012 -319.84188)
		(width 0.1143)
		(layer "In9.Cu")
		(net "P5E_PEX2_STN5_RX_DN<80>")
	)
	(segment
		(start 290.779454 -322.377054)
		(end 290.56584 -322.057268)
		(width 0.1651)
		(layer "In9.Cu")
		(net "P5E_PEX2_STN5_RX_DN<80>")
	)
	(segment
		(start 333.283814 -341.937086)
		(end 333.085694 -341.53602)
		(width 0.1651)
		(layer "In9.Cu")
		(net "P5E_PEX2_STN5_RX_DN<80>")
	)
	(segment
		(start 293.48303 -325.08063)
		(end 291.609018 -323.206618)
		(width 0.1651)
		(layer "In9.Cu")
		(net "P5E_PEX2_STN5_RX_DN<80>")
	)
	(segment
		(start 290.52012 -319.84188)
		(end 290.52012 -316.534038)
		(width 0.1143)
		(layer "In9.Cu")
		(net "P5E_PEX2_STN5_RX_DN<80>")
	)
	(segment
		(start 350.22282 -384.993896)
		(end 350.506792 -369.556284)
		(width 0.1651)
		(layer "In9.Cu")
		(net "P5E_PEX2_STN5_RX_DN<80>")
	)
	(segment
		(start 291.609018 -323.116702)
		(end 291.258498 -322.766182)
		(width 0.1651)
		(layer "In9.Cu")
		(net "P5E_PEX2_STN5_RX_DN<80>")
	)
	(segment
		(start 422.223184 -132.0038)
		(end 422.064434 -131.84505)
		(width 0.13462)
		(layer "F.Cu")
		(net "P5E_PEX3_STN0_TX_C_DN<5>")
	)
	(segment
		(start 422.064434 -131.84505)
		(end 421.557704 -131.84505)
		(width 0.13462)
		(layer "F.Cu")
		(net "P5E_PEX3_STN0_TX_C_DN<5>")
	)
	(segment
		(start 430.377854 -132.0038)
		(end 422.223184 -132.0038)
		(width 0.13462)
		(layer "F.Cu")
		(net "P5E_PEX3_STN0_TX_C_DN<5>")
	)
	(segment
		(start 430.694846 -131.686808)
		(end 430.377854 -132.0038)
		(width 0.13462)
		(layer "F.Cu")
		(net "P5E_PEX3_STN0_TX_C_DN<5>")
	)
	(segment
		(start 414.778952 -137.24509)
		(end 416.95751 -137.24509)
		(width 0.13208)
		(layer "F.Cu")
		(net "PRSNTB1_NIC7_N")
	)
	(segment
		(start 413.347154 -137.848848)
		(end 414.175194 -137.848848)
		(width 0.13208)
		(layer "F.Cu")
		(net "PRSNTB1_NIC7_N")
	)
	(segment
		(start 412.17088 -137.848848)
		(end 413.347154 -137.848848)
		(width 0.13208)
		(layer "F.Cu")
		(net "PRSNTB1_NIC7_N")
	)
	(segment
		(start 414.175194 -137.848848)
		(end 414.778952 -137.24509)
		(width 0.13208)
		(layer "F.Cu")
		(net "PRSNTB1_NIC7_N")
	)
	(segment
		(start 412.17088 -138.864848)
		(end 412.17088 -137.848848)
		(width 0.13208)
		(layer "F.Cu")
		(net "PRSNTB1_NIC7_N")
	)
	(via
		(at 413.347154 -137.848848)
		(size 0.762)
		(drill 0.381)
		(layers "F.Cu" "B.Cu")
		(net "PRSNTB1_NIC7_N")
	)
	(segment
		(start 161.653982 -135.96493)
		(end 161.491168 -136.127744)
		(width 0.13462)
		(layer "F.Cu")
		(net "P5E_PEX1_STN1_TX_C_DN<31>")
	)
	(segment
		(start 161.491168 -136.127744)
		(end 155.959556 -136.127744)
		(width 0.13462)
		(layer "F.Cu")
		(net "P5E_PEX1_STN1_TX_C_DN<31>")
	)
	(segment
		(start 162.14217 -135.96493)
		(end 161.653982 -135.96493)
		(width 0.13462)
		(layer "F.Cu")
		(net "P5E_PEX1_STN1_TX_C_DN<31>")
	)
	(segment
		(start 155.959556 -136.127744)
		(end 155.647136 -135.815324)
		(width 0.13462)
		(layer "F.Cu")
		(net "P5E_PEX1_STN1_TX_C_DN<31>")
	)
	(segment
		(start 160.460944 -318.129666)
		(end 160.21812 -318.129666)
		(width 0.1143)
		(layer "In15.Cu")
		(net "P5E_PEX1_STN6_RX_DP<110>")
	)
	(segment
		(start 114.239802 -392.351006)
		(end 115.29949 -392.789918)
		(width 0.1651)
		(layer "In15.Cu")
		(net "P5E_PEX1_STN6_RX_DP<110>")
	)
	(segment
		(start 111.185198 -341.18931)
		(end 111.162084 -341.223854)
		(width 0.1651)
		(layer "In15.Cu")
		(net "P5E_PEX1_STN6_RX_DP<110>")
	)
	(segment
		(start 112.09401 -340.441788)
		(end 111.185198 -341.18931)
		(width 0.1651)
		(layer "In15.Cu")
		(net "P5E_PEX1_STN6_RX_DP<110>")
	)
	(segment
		(start 116.963444 -339.256878)
		(end 113.290604 -339.946742)
		(width 0.1651)
		(layer "In15.Cu")
		(net "P5E_PEX1_STN6_RX_DP<110>")
	)
	(segment
		(start 118.334536 -394.552424)
		(end 118.984776 -395.202664)
		(width 0.1651)
		(layer "In15.Cu")
		(net "P5E_PEX1_STN6_RX_DP<110>")
	)
	(segment
		(start 160.21812 -318.129666)
		(end 159.979614 -318.368172)
		(width 0.1143)
		(layer "In15.Cu")
		(net "P5E_PEX1_STN6_RX_DP<110>")
	)
	(segment
		(start 115.29949 -392.789918)
		(end 115.340638 -392.889486)
		(width 0.1651)
		(layer "In15.Cu")
		(net "P5E_PEX1_STN6_RX_DP<110>")
	)
	(segment
		(start 110.536228 -389.330692)
		(end 114.239802 -392.351006)
		(width 0.1651)
		(layer "In15.Cu")
		(net "P5E_PEX1_STN6_RX_DP<110>")
	)
	(segment
		(start 159.979614 -319.79108)
		(end 159.933894 -319.8368)
		(width 0.1143)
		(layer "In15.Cu")
		(net "P5E_PEX1_STN6_RX_DP<110>")
	)
	(segment
		(start 115.898168 -393.038076)
		(end 116.355622 -393.22756)
		(width 0.1651)
		(layer "In15.Cu")
		(net "P5E_PEX1_STN6_RX_DP<110>")
	)
	(segment
		(start 118.458488 -401.999196)
		(end 118.237 -401.999196)
		(width 0.1651)
		(layer "In15.Cu")
		(net "P5E_PEX1_STN6_RX_DP<110>")
	)
	(segment
		(start 110.476538 -342.515698)
		(end 110.007654 -344.863928)
		(width 0.1651)
		(layer "In15.Cu")
		(net "P5E_PEX1_STN6_RX_DP<110>")
	)
	(segment
		(start 142.532608 -329.239626)
		(end 123.106688 -337.286092)
		(width 0.1651)
		(layer "In15.Cu")
		(net "P5E_PEX1_STN6_RX_DP<110>")
	)
	(segment
		(start 160.549844 -318.040766)
		(end 160.460944 -318.129666)
		(width 0.1143)
		(layer "In15.Cu")
		(net "P5E_PEX1_STN6_RX_DP<110>")
	)
	(segment
		(start 116.39677 -393.326874)
		(end 116.854732 -393.516866)
		(width 0.1651)
		(layer "In15.Cu")
		(net "P5E_PEX1_STN6_RX_DP<110>")
	)
	(segment
		(start 118.237 -401.999196)
		(end 118.11 -401.872196)
		(width 0.1651)
		(layer "In15.Cu")
		(net "P5E_PEX1_STN6_RX_DP<110>")
	)
	(segment
		(start 159.979614 -318.368172)
		(end 159.979614 -319.79108)
		(width 0.1143)
		(layer "In15.Cu")
		(net "P5E_PEX1_STN6_RX_DP<110>")
	)
	(segment
		(start 113.290604 -339.946742)
		(end 112.09401 -340.441788)
		(width 0.1651)
		(layer "In15.Cu")
		(net "P5E_PEX1_STN6_RX_DP<110>")
	)
	(segment
		(start 116.854732 -393.516866)
		(end 116.9543 -393.475464)
		(width 0.1651)
		(layer "In15.Cu")
		(net "P5E_PEX1_STN6_RX_DP<110>")
	)
	(segment
		(start 111.162084 -341.223854)
		(end 110.76686 -341.815166)
		(width 0.1651)
		(layer "In15.Cu")
		(net "P5E_PEX1_STN6_RX_DP<110>")
	)
	(segment
		(start 118.984776 -398.789398)
		(end 118.985538 -398.79016)
		(width 0.1651)
		(layer "In15.Cu")
		(net "P5E_PEX1_STN6_RX_DP<110>")
	)
	(segment
		(start 110.76686 -341.815166)
		(end 110.476538 -342.515698)
		(width 0.1651)
		(layer "In15.Cu")
		(net "P5E_PEX1_STN6_RX_DP<110>")
	)
	(segment
		(start 159.933894 -319.8368)
		(end 159.933894 -319.865248)
		(width 0.1143)
		(layer "In15.Cu")
		(net "P5E_PEX1_STN6_RX_DP<110>")
	)
	(segment
		(start 116.355622 -393.22756)
		(end 116.39677 -393.326874)
		(width 0.1651)
		(layer "In15.Cu")
		(net "P5E_PEX1_STN6_RX_DP<110>")
	)
	(segment
		(start 118.25097 -394.552424)
		(end 118.334536 -394.552424)
		(width 0.1651)
		(layer "In15.Cu")
		(net "P5E_PEX1_STN6_RX_DP<110>")
	)
	(segment
		(start 115.340638 -392.889486)
		(end 115.7986 -393.079224)
		(width 0.1651)
		(layer "In15.Cu")
		(net "P5E_PEX1_STN6_RX_DP<110>")
	)
	(segment
		(start 115.7986 -393.079224)
		(end 115.898168 -393.038076)
		(width 0.1651)
		(layer "In15.Cu")
		(net "P5E_PEX1_STN6_RX_DP<110>")
	)
	(segment
		(start 110.007654 -344.863928)
		(end 108.684568 -364.810548)
		(width 0.1651)
		(layer "In15.Cu")
		(net "P5E_PEX1_STN6_RX_DP<110>")
	)
	(segment
		(start 108.684568 -364.810548)
		(end 108.547408 -385.349242)
		(width 0.1651)
		(layer "In15.Cu")
		(net "P5E_PEX1_STN6_RX_DP<110>")
	)
	(segment
		(start 118.985538 -398.79016)
		(end 118.985538 -401.472146)
		(width 0.1651)
		(layer "In15.Cu")
		(net "P5E_PEX1_STN6_RX_DP<110>")
	)
	(segment
		(start 118.11 -401.872196)
		(end 118.11 -401.49018)
		(width 0.1651)
		(layer "In15.Cu")
		(net "P5E_PEX1_STN6_RX_DP<110>")
	)
	(segment
		(start 116.9543 -393.475464)
		(end 117.472206 -393.690094)
		(width 0.1651)
		(layer "In15.Cu")
		(net "P5E_PEX1_STN6_RX_DP<110>")
	)
	(segment
		(start 118.985538 -401.472146)
		(end 118.458488 -401.999196)
		(width 0.1651)
		(layer "In15.Cu")
		(net "P5E_PEX1_STN6_RX_DP<110>")
	)
	(segment
		(start 117.822218 -394.040106)
		(end 117.822218 -394.123672)
		(width 0.1651)
		(layer "In15.Cu")
		(net "P5E_PEX1_STN6_RX_DP<110>")
	)
	(segment
		(start 159.933894 -320.387726)
		(end 158.757112 -321.564508)
		(width 0.1651)
		(layer "In15.Cu")
		(net "P5E_PEX1_STN6_RX_DP<110>")
	)
	(segment
		(start 160.549844 -317.749936)
		(end 160.549844 -318.040766)
		(width 0.1143)
		(layer "In15.Cu")
		(net "P5E_PEX1_STN6_RX_DP<110>")
	)
	(segment
		(start 117.472206 -393.690094)
		(end 117.822218 -394.040106)
		(width 0.1651)
		(layer "In15.Cu")
		(net "P5E_PEX1_STN6_RX_DP<110>")
	)
	(segment
		(start 118.984776 -395.202664)
		(end 118.984776 -398.789398)
		(width 0.1651)
		(layer "In15.Cu")
		(net "P5E_PEX1_STN6_RX_DP<110>")
	)
	(segment
		(start 108.547408 -385.349242)
		(end 109.03077 -387.089904)
		(width 0.1651)
		(layer "In15.Cu")
		(net "P5E_PEX1_STN6_RX_DP<110>")
	)
	(segment
		(start 109.03077 -387.089904)
		(end 110.536228 -389.330692)
		(width 0.1651)
		(layer "In15.Cu")
		(net "P5E_PEX1_STN6_RX_DP<110>")
	)
	(segment
		(start 123.106688 -337.286092)
		(end 116.963444 -339.256878)
		(width 0.1651)
		(layer "In15.Cu")
		(net "P5E_PEX1_STN6_RX_DP<110>")
	)
	(segment
		(start 159.933894 -319.865248)
		(end 159.933894 -320.387726)
		(width 0.1651)
		(layer "In15.Cu")
		(net "P5E_PEX1_STN6_RX_DP<110>")
	)
	(segment
		(start 117.822218 -394.123672)
		(end 118.25097 -394.552424)
		(width 0.1651)
		(layer "In15.Cu")
		(net "P5E_PEX1_STN6_RX_DP<110>")
	)
	(segment
		(start 158.757112 -321.564508)
		(end 142.532608 -329.239626)
		(width 0.1651)
		(layer "In15.Cu")
		(net "P5E_PEX1_STN6_RX_DP<110>")
	)
	(segment
		(start 295.99128 -322.095114)
		(end 294.67683 -320.780664)
		(width 0.1651)
		(layer "In9.Cu")
		(net "P5E_PEX2_STN5_RX_DN<84>")
	)
	(segment
		(start 340.29015 -397.790162)
		(end 340.29015 -397.408146)
		(width 0.1651)
		(layer "In9.Cu")
		(net "P5E_PEX2_STN5_RX_DN<84>")
	)
	(segment
		(start 294.61079 -316.419992)
		(end 294.69969 -316.508892)
		(width 0.1143)
		(layer "In9.Cu")
		(net "P5E_PEX2_STN5_RX_DN<84>")
	)
	(segment
		(start 340.29015 -397.408146)
		(end 340.429596 -397.2687)
		(width 0.1651)
		(layer "In9.Cu")
		(net "P5E_PEX2_STN5_RX_DN<84>")
	)
	(segment
		(start 344.551 -340.70417)
		(end 342.94064 -339.71738)
		(width 0.1651)
		(layer "In9.Cu")
		(net "P5E_PEX2_STN5_RX_DN<84>")
	)
	(segment
		(start 341.20328 -396.833852)
		(end 343.07018 -394.00734)
		(width 0.1651)
		(layer "In9.Cu")
		(net "P5E_PEX2_STN5_RX_DN<84>")
	)
	(segment
		(start 341.20328 -396.833598)
		(end 341.20328 -396.833852)
		(width 0.1651)
		(layer "In9.Cu")
		(net "P5E_PEX2_STN5_RX_DN<84>")
	)
	(segment
		(start 294.67683 -320.780664)
		(end 294.36568 -320.314828)
		(width 0.1651)
		(layer "In9.Cu")
		(net "P5E_PEX2_STN5_RX_DN<84>")
	)
	(segment
		(start 344.438732 -392.883898)
		(end 352.831654 -389.610346)
		(width 0.1651)
		(layer "In9.Cu")
		(net "P5E_PEX2_STN5_RX_DN<84>")
	)
	(segment
		(start 298.135294 -323.229224)
		(end 297.261788 -322.907914)
		(width 0.1651)
		(layer "In9.Cu")
		(net "P5E_PEX2_STN5_RX_DN<84>")
	)
	(segment
		(start 354.119434 -388.678928)
		(end 355.320092 -387.227064)
		(width 0.1651)
		(layer "In9.Cu")
		(net "P5E_PEX2_STN5_RX_DN<84>")
	)
	(segment
		(start 294.36568 -319.8876)
		(end 294.31996 -319.84188)
		(width 0.1143)
		(layer "In9.Cu")
		(net "P5E_PEX2_STN5_RX_DN<84>")
	)
	(segment
		(start 294.69969 -316.508892)
		(end 294.69969 -316.799722)
		(width 0.1143)
		(layer "In9.Cu")
		(net "P5E_PEX2_STN5_RX_DN<84>")
	)
	(segment
		(start 297.261788 -322.907914)
		(end 295.99128 -322.095114)
		(width 0.1651)
		(layer "In9.Cu")
		(net "P5E_PEX2_STN5_RX_DN<84>")
	)
	(segment
		(start 294.31996 -316.534038)
		(end 294.434006 -316.419992)
		(width 0.1143)
		(layer "In9.Cu")
		(net "P5E_PEX2_STN5_RX_DN<84>")
	)
	(segment
		(start 294.36568 -320.314828)
		(end 294.36568 -319.916048)
		(width 0.1651)
		(layer "In9.Cu")
		(net "P5E_PEX2_STN5_RX_DN<84>")
	)
	(segment
		(start 298.791122 -323.470524)
		(end 298.791122 -323.470778)
		(width 0.1651)
		(layer "In9.Cu")
		(net "P5E_PEX2_STN5_RX_DN<84>")
	)
	(segment
		(start 355.320092 -387.227064)
		(end 355.661468 -386.305552)
		(width 0.1651)
		(layer "In9.Cu")
		(net "P5E_PEX2_STN5_RX_DN<84>")
	)
	(segment
		(start 294.36568 -319.916048)
		(end 294.36568 -319.8876)
		(width 0.1143)
		(layer "In9.Cu")
		(net "P5E_PEX2_STN5_RX_DN<84>")
	)
	(segment
		(start 345.42476 -341.537544)
		(end 344.551 -340.70417)
		(width 0.1651)
		(layer "In9.Cu")
		(net "P5E_PEX2_STN5_RX_DN<84>")
	)
	(segment
		(start 355.661468 -386.305552)
		(end 355.95052 -370.276628)
		(width 0.1651)
		(layer "In9.Cu")
		(net "P5E_PEX2_STN5_RX_DN<84>")
	)
	(segment
		(start 298.791122 -323.470778)
		(end 298.73067 -323.339968)
		(width 0.1651)
		(layer "In9.Cu")
		(net "P5E_PEX2_STN5_RX_DN<84>")
	)
	(segment
		(start 343.07018 -394.00734)
		(end 344.438732 -392.883898)
		(width 0.1651)
		(layer "In9.Cu")
		(net "P5E_PEX2_STN5_RX_DN<84>")
	)
	(segment
		(start 340.429596 -397.2687)
		(end 340.768178 -397.2687)
		(width 0.1651)
		(layer "In9.Cu")
		(net "P5E_PEX2_STN5_RX_DN<84>")
	)
	(segment
		(start 355.66858 -368.9604)
		(end 345.42476 -341.537544)
		(width 0.1651)
		(layer "In9.Cu")
		(net "P5E_PEX2_STN5_RX_DN<84>")
	)
	(segment
		(start 352.831654 -389.610346)
		(end 354.119434 -388.678928)
		(width 0.1651)
		(layer "In9.Cu")
		(net "P5E_PEX2_STN5_RX_DN<84>")
	)
	(segment
		(start 294.31996 -319.84188)
		(end 294.31996 -316.534038)
		(width 0.1143)
		(layer "In9.Cu")
		(net "P5E_PEX2_STN5_RX_DN<84>")
	)
	(segment
		(start 294.434006 -316.419992)
		(end 294.61079 -316.419992)
		(width 0.1143)
		(layer "In9.Cu")
		(net "P5E_PEX2_STN5_RX_DN<84>")
	)
	(segment
		(start 355.95052 -370.276628)
		(end 355.66858 -368.9604)
		(width 0.1651)
		(layer "In9.Cu")
		(net "P5E_PEX2_STN5_RX_DN<84>")
	)
	(segment
		(start 340.768178 -397.2687)
		(end 341.20328 -396.833598)
		(width 0.1651)
		(layer "In9.Cu")
		(net "P5E_PEX2_STN5_RX_DN<84>")
	)
	(segment
		(start 342.94064 -339.71738)
		(end 298.791122 -323.470524)
		(width 0.1651)
		(layer "In9.Cu")
		(net "P5E_PEX2_STN5_RX_DN<84>")
	)
	(segment
		(start 298.73067 -323.339968)
		(end 298.265596 -323.169026)
		(width 0.1651)
		(layer "In9.Cu")
		(net "P5E_PEX2_STN5_RX_DN<84>")
	)
	(segment
		(start 298.265596 -323.169026)
		(end 298.135294 -323.229224)
		(width 0.1651)
		(layer "In9.Cu")
		(net "P5E_PEX2_STN5_RX_DN<84>")
	)
	(segment
		(start 416.478212 -150.554944)
		(end 416.95751 -150.554944)
		(width 0.13462)
		(layer "F.Cu")
		(net "P5E_PEX3_STN0_RX_DP<12>")
	)
	(segment
		(start 416.316668 -150.3934)
		(end 416.478212 -150.554944)
		(width 0.13462)
		(layer "F.Cu")
		(net "P5E_PEX3_STN0_RX_DP<12>")
	)
	(segment
		(start 415.651188 -150.3934)
		(end 416.316668 -150.3934)
		(width 0.13462)
		(layer "F.Cu")
		(net "P5E_PEX3_STN0_RX_DP<12>")
	)
	(segment
		(start 415.35731 -150.687278)
		(end 415.651188 -150.3934)
		(width 0.13462)
		(layer "F.Cu")
		(net "P5E_PEX3_STN0_RX_DP<12>")
	)
	(segment
		(start 425.885356 -275.570188)
		(end 425.999656 -275.684488)
		(width 0.1143)
		(layer "In5.Cu")
		(net "P5E_PEX3_STN0_RX_DP<12>")
	)
	(segment
		(start 421.182546 -158.4706)
		(end 422.322244 -161.211514)
		(width 0.1651)
		(layer "In5.Cu")
		(net "P5E_PEX3_STN0_RX_DP<12>")
	)
	(segment
		(start 425.38396 -271.599406)
		(end 425.42968 -271.645126)
		(width 0.1143)
		(layer "In5.Cu")
		(net "P5E_PEX3_STN0_RX_DP<12>")
	)
	(segment
		(start 418.918136 -155.10637)
		(end 421.182546 -158.4706)
		(width 0.1651)
		(layer "In5.Cu")
		(net "P5E_PEX3_STN0_RX_DP<12>")
	)
	(segment
		(start 418.120068 -153.438352)
		(end 418.312346 -153.895298)
		(width 0.1651)
		(layer "In5.Cu")
		(net "P5E_PEX3_STN0_RX_DP<12>")
	)
	(segment
		(start 425.850812 -260.77418)
		(end 425.913296 -268.035278)
		(width 0.1651)
		(layer "In5.Cu")
		(net "P5E_PEX3_STN0_RX_DP<12>")
	)
	(segment
		(start 425.38396 -270.75892)
		(end 425.38396 -271.570958)
		(width 0.1651)
		(layer "In5.Cu")
		(net "P5E_PEX3_STN0_RX_DP<12>")
	)
	(segment
		(start 416.122866 -150.396448)
		(end 417.510976 -151.760174)
		(width 0.1651)
		(layer "In5.Cu")
		(net "P5E_PEX3_STN0_RX_DP<12>")
	)
	(segment
		(start 425.999656 -275.684488)
		(end 425.999656 -275.949918)
		(width 0.1143)
		(layer "In5.Cu")
		(net "P5E_PEX3_STN0_RX_DP<12>")
	)
	(segment
		(start 425.644564 -275.570188)
		(end 425.885356 -275.570188)
		(width 0.1143)
		(layer "In5.Cu")
		(net "P5E_PEX3_STN0_RX_DP<12>")
	)
	(segment
		(start 425.42968 -271.645126)
		(end 425.42968 -275.355304)
		(width 0.1143)
		(layer "In5.Cu")
		(net "P5E_PEX3_STN0_RX_DP<12>")
	)
	(segment
		(start 425.42968 -275.355304)
		(end 425.644564 -275.570188)
		(width 0.1143)
		(layer "In5.Cu")
		(net "P5E_PEX3_STN0_RX_DP<12>")
	)
	(segment
		(start 415.35731 -150.687278)
		(end 415.64814 -150.396448)
		(width 0.1651)
		(layer "In5.Cu")
		(net "P5E_PEX3_STN0_RX_DP<12>")
	)
	(segment
		(start 417.510976 -151.760174)
		(end 417.714684 -152.244806)
		(width 0.1651)
		(layer "In5.Cu")
		(net "P5E_PEX3_STN0_RX_DP<12>")
	)
	(segment
		(start 415.64814 -150.396448)
		(end 416.122866 -150.396448)
		(width 0.1651)
		(layer "In5.Cu")
		(net "P5E_PEX3_STN0_RX_DP<12>")
	)
	(segment
		(start 418.428932 -153.942796)
		(end 418.918136 -155.10637)
		(width 0.1651)
		(layer "In5.Cu")
		(net "P5E_PEX3_STN0_RX_DP<12>")
	)
	(segment
		(start 425.913296 -268.035278)
		(end 425.38396 -270.75892)
		(width 0.1651)
		(layer "In5.Cu")
		(net "P5E_PEX3_STN0_RX_DP<12>")
	)
	(segment
		(start 417.859464 -152.818084)
		(end 417.975796 -152.865582)
		(width 0.1651)
		(layer "In5.Cu")
		(net "P5E_PEX3_STN0_RX_DP<12>")
	)
	(segment
		(start 417.975796 -152.865582)
		(end 418.167566 -153.32202)
		(width 0.1651)
		(layer "In5.Cu")
		(net "P5E_PEX3_STN0_RX_DP<12>")
	)
	(segment
		(start 418.312346 -153.895298)
		(end 418.428932 -153.942796)
		(width 0.1651)
		(layer "In5.Cu")
		(net "P5E_PEX3_STN0_RX_DP<12>")
	)
	(segment
		(start 425.38396 -271.570958)
		(end 425.38396 -271.599406)
		(width 0.1143)
		(layer "In5.Cu")
		(net "P5E_PEX3_STN0_RX_DP<12>")
	)
	(segment
		(start 417.667186 -152.361392)
		(end 417.859464 -152.818084)
		(width 0.1651)
		(layer "In5.Cu")
		(net "P5E_PEX3_STN0_RX_DP<12>")
	)
	(segment
		(start 422.322244 -161.211514)
		(end 425.850812 -260.77418)
		(width 0.1651)
		(layer "In5.Cu")
		(net "P5E_PEX3_STN0_RX_DP<12>")
	)
	(segment
		(start 417.714684 -152.244806)
		(end 417.667186 -152.361392)
		(width 0.1651)
		(layer "In5.Cu")
		(net "P5E_PEX3_STN0_RX_DP<12>")
	)
	(segment
		(start 418.167566 -153.32202)
		(end 418.120068 -153.438352)
		(width 0.1651)
		(layer "In5.Cu")
		(net "P5E_PEX3_STN0_RX_DP<12>")
	)
	(segment
		(start 411.750002 -318.015366)
		(end 411.750002 -317.749936)
		(width 0.1143)
		(layer "In5.Cu")
		(net "P5E_PEX3_STN5_RX_DP<85>")
	)
	(segment
		(start 386.489956 -397.97609)
		(end 386.616956 -398.10309)
		(width 0.1651)
		(layer "In5.Cu")
		(net "P5E_PEX3_STN5_RX_DP<85>")
	)
	(segment
		(start 397.256 -390.282684)
		(end 398.823434 -389.000492)
		(width 0.1651)
		(layer "In5.Cu")
		(net "P5E_PEX3_STN5_RX_DP<85>")
	)
	(segment
		(start 411.134052 -323.53504)
		(end 411.134052 -319.916048)
		(width 0.1651)
		(layer "In5.Cu")
		(net "P5E_PEX3_STN5_RX_DP<85>")
	)
	(segment
		(start 387.366002 -395.172946)
		(end 387.820408 -394.493242)
		(width 0.1651)
		(layer "In5.Cu")
		(net "P5E_PEX3_STN5_RX_DP<85>")
	)
	(segment
		(start 402.49729 -363.742732)
		(end 402.435568 -363.633258)
		(width 0.1651)
		(layer "In5.Cu")
		(net "P5E_PEX3_STN5_RX_DP<85>")
	)
	(segment
		(start 386.489956 -397.59001)
		(end 386.489956 -397.97609)
		(width 0.1651)
		(layer "In5.Cu")
		(net "P5E_PEX3_STN5_RX_DP<85>")
	)
	(segment
		(start 402.881338 -362.03001)
		(end 402.991066 -361.968288)
		(width 0.1651)
		(layer "In5.Cu")
		(net "P5E_PEX3_STN5_RX_DP<85>")
	)
	(segment
		(start 411.179772 -318.355472)
		(end 411.405578 -318.129666)
		(width 0.1143)
		(layer "In5.Cu")
		(net "P5E_PEX3_STN5_RX_DP<85>")
	)
	(segment
		(start 402.435568 -363.633258)
		(end 402.568156 -363.155738)
		(width 0.1651)
		(layer "In5.Cu")
		(net "P5E_PEX3_STN5_RX_DP<85>")
	)
	(segment
		(start 411.179772 -319.84188)
		(end 411.179772 -318.355472)
		(width 0.1143)
		(layer "In5.Cu")
		(net "P5E_PEX3_STN5_RX_DP<85>")
	)
	(segment
		(start 400.54276 -373.129048)
		(end 401.906486 -365.866934)
		(width 0.1651)
		(layer "In5.Cu")
		(net "P5E_PEX3_STN5_RX_DP<85>")
	)
	(segment
		(start 411.635702 -318.129666)
		(end 411.750002 -318.015366)
		(width 0.1143)
		(layer "In5.Cu")
		(net "P5E_PEX3_STN5_RX_DP<85>")
	)
	(segment
		(start 388.565136 -393.88161)
		(end 397.256 -390.282684)
		(width 0.1651)
		(layer "In5.Cu")
		(net "P5E_PEX3_STN5_RX_DP<85>")
	)
	(segment
		(start 404.30958 -342.28659)
		(end 404.881334 -339.92185)
		(width 0.1651)
		(layer "In5.Cu")
		(net "P5E_PEX3_STN5_RX_DP<85>")
	)
	(segment
		(start 398.823434 -389.000492)
		(end 399.721324 -387.665976)
		(width 0.1651)
		(layer "In5.Cu")
		(net "P5E_PEX3_STN5_RX_DP<85>")
	)
	(segment
		(start 401.906486 -365.866934)
		(end 402.49729 -363.742732)
		(width 0.1651)
		(layer "In5.Cu")
		(net "P5E_PEX3_STN5_RX_DP<85>")
	)
	(segment
		(start 411.134052 -319.8876)
		(end 411.179772 -319.84188)
		(width 0.1143)
		(layer "In5.Cu")
		(net "P5E_PEX3_STN5_RX_DP<85>")
	)
	(segment
		(start 399.721324 -387.665976)
		(end 400.171158 -386.22859)
		(width 0.1651)
		(layer "In5.Cu")
		(net "P5E_PEX3_STN5_RX_DP<85>")
	)
	(segment
		(start 410.631386 -326.058022)
		(end 411.134052 -323.53504)
		(width 0.1651)
		(layer "In5.Cu")
		(net "P5E_PEX3_STN5_RX_DP<85>")
	)
	(segment
		(start 387.366002 -397.770604)
		(end 387.366002 -395.172946)
		(width 0.1651)
		(layer "In5.Cu")
		(net "P5E_PEX3_STN5_RX_DP<85>")
	)
	(segment
		(start 386.616956 -398.10309)
		(end 387.033516 -398.10309)
		(width 0.1651)
		(layer "In5.Cu")
		(net "P5E_PEX3_STN5_RX_DP<85>")
	)
	(segment
		(start 402.74875 -362.50753)
		(end 402.881338 -362.03001)
		(width 0.1651)
		(layer "In5.Cu")
		(net "P5E_PEX3_STN5_RX_DP<85>")
	)
	(segment
		(start 387.820408 -394.493242)
		(end 388.565136 -393.88161)
		(width 0.1651)
		(layer "In5.Cu")
		(net "P5E_PEX3_STN5_RX_DP<85>")
	)
	(segment
		(start 402.568156 -363.155738)
		(end 402.677884 -363.094016)
		(width 0.1651)
		(layer "In5.Cu")
		(net "P5E_PEX3_STN5_RX_DP<85>")
	)
	(segment
		(start 404.881334 -339.92185)
		(end 410.631386 -326.058022)
		(width 0.1651)
		(layer "In5.Cu")
		(net "P5E_PEX3_STN5_RX_DP<85>")
	)
	(segment
		(start 402.677884 -363.094016)
		(end 402.810472 -362.617004)
		(width 0.1651)
		(layer "In5.Cu")
		(net "P5E_PEX3_STN5_RX_DP<85>")
	)
	(segment
		(start 402.810472 -362.617004)
		(end 402.74875 -362.50753)
		(width 0.1651)
		(layer "In5.Cu")
		(net "P5E_PEX3_STN5_RX_DP<85>")
	)
	(segment
		(start 400.32051 -375.349262)
		(end 400.54276 -373.129048)
		(width 0.1651)
		(layer "In5.Cu")
		(net "P5E_PEX3_STN5_RX_DP<85>")
	)
	(segment
		(start 402.991066 -361.968288)
		(end 404.232872 -357.504492)
		(width 0.1651)
		(layer "In5.Cu")
		(net "P5E_PEX3_STN5_RX_DP<85>")
	)
	(segment
		(start 400.171158 -386.22859)
		(end 400.32051 -375.349262)
		(width 0.1651)
		(layer "In5.Cu")
		(net "P5E_PEX3_STN5_RX_DP<85>")
	)
	(segment
		(start 411.405578 -318.129666)
		(end 411.635702 -318.129666)
		(width 0.1143)
		(layer "In5.Cu")
		(net "P5E_PEX3_STN5_RX_DP<85>")
	)
	(segment
		(start 387.033516 -398.10309)
		(end 387.366002 -397.770604)
		(width 0.1651)
		(layer "In5.Cu")
		(net "P5E_PEX3_STN5_RX_DP<85>")
	)
	(segment
		(start 411.134052 -319.916048)
		(end 411.134052 -319.8876)
		(width 0.1143)
		(layer "In5.Cu")
		(net "P5E_PEX3_STN5_RX_DP<85>")
	)
	(segment
		(start 404.232872 -357.504492)
		(end 404.30958 -342.28659)
		(width 0.1651)
		(layer "In5.Cu")
		(net "P5E_PEX3_STN5_RX_DP<85>")
	)
	(segment
		(start 162.14217 -132.964936)
		(end 161.654236 -132.964936)
		(width 0.13462)
		(layer "F.Cu")
		(net "P5E_PEX1_STN1_TX_C_DP<29>")
	)
	(segment
		(start 155.974796 -132.802122)
		(end 155.647136 -133.129782)
		(width 0.13462)
		(layer "F.Cu")
		(net "P5E_PEX1_STN1_TX_C_DP<29>")
	)
	(segment
		(start 161.491422 -132.802122)
		(end 155.974796 -132.802122)
		(width 0.13462)
		(layer "F.Cu")
		(net "P5E_PEX1_STN1_TX_C_DP<29>")
	)
	(segment
		(start 161.654236 -132.964936)
		(end 161.491422 -132.802122)
		(width 0.13462)
		(layer "F.Cu")
		(net "P5E_PEX1_STN1_TX_C_DP<29>")
	)
	(segment
		(start 112.156748 -350.685354)
		(end 111.836708 -350.365314)
		(width 0.13462)
		(layer "F.Cu")
		(net "P5E_PEX1_STN6_TX_C_DP<103>")
	)
	(segment
		(start 112.156748 -351.316798)
		(end 112.156748 -350.685354)
		(width 0.13462)
		(layer "F.Cu")
		(net "P5E_PEX1_STN6_TX_C_DP<103>")
	)
	(segment
		(start 111.862108 -351.611438)
		(end 112.156748 -351.316798)
		(width 0.13462)
		(layer "F.Cu")
		(net "P5E_PEX1_STN6_TX_C_DP<103>")
	)
	(segment
		(start 116.6876 -382.280668)
		(end 116.269262 -382.699006)
		(width 0.1651)
		(layer "In7.Cu")
		(net "P5E_PEX1_STN6_TX_C_DP<103>")
	)
	(segment
		(start 116.6876 -369.58143)
		(end 116.6876 -382.280668)
		(width 0.1651)
		(layer "In7.Cu")
		(net "P5E_PEX1_STN6_TX_C_DP<103>")
	)
	(segment
		(start 115.254532 -366.693704)
		(end 115.375182 -366.72901)
		(width 0.1651)
		(layer "In7.Cu")
		(net "P5E_PEX1_STN6_TX_C_DP<103>")
	)
	(segment
		(start 116.037106 -382.699006)
		(end 115.910106 -382.572006)
		(width 0.1651)
		(layer "In7.Cu")
		(net "P5E_PEX1_STN6_TX_C_DP<103>")
	)
	(segment
		(start 115.815872 -367.718594)
		(end 115.936522 -367.7539)
		(width 0.1651)
		(layer "In7.Cu")
		(net "P5E_PEX1_STN6_TX_C_DP<103>")
	)
	(segment
		(start 115.051586 -366.13846)
		(end 115.01628 -366.25911)
		(width 0.1651)
		(layer "In7.Cu")
		(net "P5E_PEX1_STN6_TX_C_DP<103>")
	)
	(segment
		(start 115.910106 -382.572006)
		(end 115.910106 -382.18999)
		(width 0.1651)
		(layer "In7.Cu")
		(net "P5E_PEX1_STN6_TX_C_DP<103>")
	)
	(segment
		(start 112.426496 -359.45826)
		(end 114.421412 -364.988094)
		(width 0.1651)
		(layer "In7.Cu")
		(net "P5E_PEX1_STN6_TX_C_DP<103>")
	)
	(segment
		(start 115.57762 -367.284)
		(end 115.815872 -367.718594)
		(width 0.1651)
		(layer "In7.Cu")
		(net "P5E_PEX1_STN6_TX_C_DP<103>")
	)
	(segment
		(start 112.152938 -351.902268)
		(end 112.152938 -357.95331)
		(width 0.1651)
		(layer "In7.Cu")
		(net "P5E_PEX1_STN6_TX_C_DP<103>")
	)
	(segment
		(start 112.152938 -357.95331)
		(end 112.426496 -359.45826)
		(width 0.1651)
		(layer "In7.Cu")
		(net "P5E_PEX1_STN6_TX_C_DP<103>")
	)
	(segment
		(start 114.421412 -364.988094)
		(end 115.051586 -366.13846)
		(width 0.1651)
		(layer "In7.Cu")
		(net "P5E_PEX1_STN6_TX_C_DP<103>")
	)
	(segment
		(start 111.862108 -351.611438)
		(end 112.152938 -351.902268)
		(width 0.1651)
		(layer "In7.Cu")
		(net "P5E_PEX1_STN6_TX_C_DP<103>")
	)
	(segment
		(start 116.269262 -382.699006)
		(end 116.037106 -382.699006)
		(width 0.1651)
		(layer "In7.Cu")
		(net "P5E_PEX1_STN6_TX_C_DP<103>")
	)
	(segment
		(start 115.375182 -366.72901)
		(end 115.612926 -367.16335)
		(width 0.1651)
		(layer "In7.Cu")
		(net "P5E_PEX1_STN6_TX_C_DP<103>")
	)
	(segment
		(start 115.936522 -367.7539)
		(end 116.572792 -368.915442)
		(width 0.1651)
		(layer "In7.Cu")
		(net "P5E_PEX1_STN6_TX_C_DP<103>")
	)
	(segment
		(start 115.01628 -366.25911)
		(end 115.254532 -366.693704)
		(width 0.1651)
		(layer "In7.Cu")
		(net "P5E_PEX1_STN6_TX_C_DP<103>")
	)
	(segment
		(start 116.572792 -368.915442)
		(end 116.6876 -369.58143)
		(width 0.1651)
		(layer "In7.Cu")
		(net "P5E_PEX1_STN6_TX_C_DP<103>")
	)
	(segment
		(start 115.612926 -367.16335)
		(end 115.57762 -367.284)
		(width 0.1651)
		(layer "In7.Cu")
		(net "P5E_PEX1_STN6_TX_C_DP<103>")
	)
	(segment
		(start 428.052738 -119.584724)
		(end 427.733714 -119.2657)
		(width 0.13462)
		(layer "F.Cu")
		(net "P5E_PEX3_STN0_TX_C_DP<0>")
	)
	(segment
		(start 422.057068 -119.435118)
		(end 421.557704 -119.435118)
		(width 0.13462)
		(layer "F.Cu")
		(net "P5E_PEX3_STN0_TX_C_DP<0>")
	)
	(segment
		(start 427.733714 -119.2657)
		(end 422.226486 -119.2657)
		(width 0.13462)
		(layer "F.Cu")
		(net "P5E_PEX3_STN0_TX_C_DP<0>")
	)
	(segment
		(start 422.226486 -119.2657)
		(end 422.057068 -119.435118)
		(width 0.13462)
		(layer "F.Cu")
		(net "P5E_PEX3_STN0_TX_C_DP<0>")
	)
	(segment
		(start 393.245848 -357.462582)
		(end 392.9507 -357.75773)
		(width 0.13462)
		(layer "F.Cu")
		(net "P5E_PEX3_STN5_TX_C_DP<83>")
	)
	(segment
		(start 393.245848 -356.832154)
		(end 393.245848 -357.462582)
		(width 0.13462)
		(layer "F.Cu")
		(net "P5E_PEX3_STN5_TX_C_DP<83>")
	)
	(segment
		(start 392.9253 -356.511606)
		(end 393.245848 -356.832154)
		(width 0.13462)
		(layer "F.Cu")
		(net "P5E_PEX3_STN5_TX_C_DP<83>")
	)
	(segment
		(start 393.24153 -358.82199)
		(end 395.554708 -363.35081)
		(width 0.1651)
		(layer "In7.Cu")
		(net "P5E_PEX3_STN5_TX_C_DP<83>")
	)
	(segment
		(start 397.24076 -387.974586)
		(end 384.728974 -393.13358)
		(width 0.1651)
		(layer "In7.Cu")
		(net "P5E_PEX3_STN5_TX_C_DP<83>")
	)
	(segment
		(start 395.741398 -363.911642)
		(end 395.861032 -363.950504)
		(width 0.1651)
		(layer "In7.Cu")
		(net "P5E_PEX3_STN5_TX_C_DP<83>")
	)
	(segment
		(start 395.515846 -363.470444)
		(end 395.741398 -363.911642)
		(width 0.1651)
		(layer "In7.Cu")
		(net "P5E_PEX3_STN5_TX_C_DP<83>")
	)
	(segment
		(start 397.78432 -367.7158)
		(end 398.28978 -369.7859)
		(width 0.1651)
		(layer "In7.Cu")
		(net "P5E_PEX3_STN5_TX_C_DP<83>")
	)
	(segment
		(start 398.021556 -386.56387)
		(end 397.24076 -387.974586)
		(width 0.1651)
		(layer "In7.Cu")
		(net "P5E_PEX3_STN5_TX_C_DP<83>")
	)
	(segment
		(start 382.64719 -405.899112)
		(end 382.216914 -405.899112)
		(width 0.1651)
		(layer "In7.Cu")
		(net "P5E_PEX3_STN5_TX_C_DP<83>")
	)
	(segment
		(start 395.554708 -363.35081)
		(end 395.515846 -363.470444)
		(width 0.1651)
		(layer "In7.Cu")
		(net "P5E_PEX3_STN5_TX_C_DP<83>")
	)
	(segment
		(start 382.933956 -395.58976)
		(end 382.933956 -405.612346)
		(width 0.1651)
		(layer "In7.Cu")
		(net "P5E_PEX3_STN5_TX_C_DP<83>")
	)
	(segment
		(start 395.861032 -363.950504)
		(end 397.78432 -367.7158)
		(width 0.1651)
		(layer "In7.Cu")
		(net "P5E_PEX3_STN5_TX_C_DP<83>")
	)
	(segment
		(start 382.089914 -405.772112)
		(end 382.089914 -405.390096)
		(width 0.1651)
		(layer "In7.Cu")
		(net "P5E_PEX3_STN5_TX_C_DP<83>")
	)
	(segment
		(start 393.24153 -358.04856)
		(end 393.24153 -358.82199)
		(width 0.1651)
		(layer "In7.Cu")
		(net "P5E_PEX3_STN5_TX_C_DP<83>")
	)
	(segment
		(start 398.28978 -369.7859)
		(end 398.021556 -386.56387)
		(width 0.1651)
		(layer "In7.Cu")
		(net "P5E_PEX3_STN5_TX_C_DP<83>")
	)
	(segment
		(start 382.933956 -405.612346)
		(end 382.64719 -405.899112)
		(width 0.1651)
		(layer "In7.Cu")
		(net "P5E_PEX3_STN5_TX_C_DP<83>")
	)
	(segment
		(start 383.413 -394.4493)
		(end 382.933956 -395.58976)
		(width 0.1651)
		(layer "In7.Cu")
		(net "P5E_PEX3_STN5_TX_C_DP<83>")
	)
	(segment
		(start 384.728974 -393.13358)
		(end 383.413 -394.4493)
		(width 0.1651)
		(layer "In7.Cu")
		(net "P5E_PEX3_STN5_TX_C_DP<83>")
	)
	(segment
		(start 392.9507 -357.75773)
		(end 393.24153 -358.04856)
		(width 0.1651)
		(layer "In7.Cu")
		(net "P5E_PEX3_STN5_TX_C_DP<83>")
	)
	(segment
		(start 382.216914 -405.899112)
		(end 382.089914 -405.772112)
		(width 0.1651)
		(layer "In7.Cu")
		(net "P5E_PEX3_STN5_TX_C_DP<83>")
	)
	(segment
		(start 272.027142 -142.080234)
		(end 272.58137 -142.080234)
		(width 0.13208)
		(layer "F.Cu")
		(net "NIC4_BIF1_N")
	)
	(segment
		(start 273.262344 -142.080234)
		(end 273.37766 -141.964918)
		(width 0.13208)
		(layer "F.Cu")
		(net "NIC4_BIF1_N")
	)
	(segment
		(start 270.752316 -142.34795)
		(end 271.759426 -142.34795)
		(width 0.13208)
		(layer "F.Cu")
		(net "NIC4_BIF1_N")
	)
	(segment
		(start 270.582644 -142.178278)
		(end 270.752316 -142.34795)
		(width 0.13208)
		(layer "F.Cu")
		(net "NIC4_BIF1_N")
	)
	(segment
		(start 271.759426 -142.34795)
		(end 272.027142 -142.080234)
		(width 0.13208)
		(layer "F.Cu")
		(net "NIC4_BIF1_N")
	)
	(segment
		(start 273.37766 -141.964918)
		(end 278.242268 -141.964918)
		(width 0.13208)
		(layer "F.Cu")
		(net "NIC4_BIF1_N")
	)
	(segment
		(start 270.582644 -141.87297)
		(end 270.582644 -142.178278)
		(width 0.13208)
		(layer "F.Cu")
		(net "NIC4_BIF1_N")
	)
	(segment
		(start 272.58137 -142.080234)
		(end 273.262344 -142.080234)
		(width 0.13208)
		(layer "F.Cu")
		(net "NIC4_BIF1_N")
	)
	(segment
		(start 269.604744 -141.87297)
		(end 270.582644 -141.87297)
		(width 0.13208)
		(layer "F.Cu")
		(net "NIC4_BIF1_N")
	)
	(via
		(at 272.58137 -142.080234)
		(size 0.762)
		(drill 0.381)
		(layers "F.Cu" "B.Cu")
		(net "NIC4_BIF1_N")
	)
	(segment
		(start 412.37789 -115.283742)
		(end 414.231074 -115.283742)
		(width 0.13208)
		(layer "F.Cu")
		(net "RST_SMB_NIC7_MUX_ISO_R_N")
	)
	(segment
		(start 415.479738 -114.035078)
		(end 416.95751 -114.035078)
		(width 0.13208)
		(layer "F.Cu")
		(net "RST_SMB_NIC7_MUX_ISO_R_N")
	)
	(segment
		(start 414.231074 -115.283742)
		(end 414.639506 -114.87531)
		(width 0.13208)
		(layer "F.Cu")
		(net "RST_SMB_NIC7_MUX_ISO_R_N")
	)
	(segment
		(start 414.639506 -114.87531)
		(end 415.479738 -114.035078)
		(width 0.13208)
		(layer "F.Cu")
		(net "RST_SMB_NIC7_MUX_ISO_R_N")
	)
	(via
		(at 414.639506 -114.87531)
		(size 0.508)
		(drill 0.254)
		(layers "F.Cu" "B.Cu")
		(net "RST_SMB_NIC7_MUX_ISO_R_N")
	)
	(segment
		(start 169.902124 -99.88169)
		(end 170.196764 -100.17633)
		(width 0.13462)
		(layer "F.Cu")
		(net "P5E_PEX1_STN1_RX_DN<16>")
	)
	(segment
		(start 167.230298 -100.045012)
		(end 167.393112 -99.882198)
		(width 0.13462)
		(layer "F.Cu")
		(net "P5E_PEX1_STN1_RX_DN<16>")
	)
	(segment
		(start 169.901616 -99.882198)
		(end 169.902124 -99.88169)
		(width 0.13462)
		(layer "F.Cu")
		(net "P5E_PEX1_STN1_RX_DN<16>")
	)
	(segment
		(start 167.393112 -99.882198)
		(end 169.901616 -99.882198)
		(width 0.13462)
		(layer "F.Cu")
		(net "P5E_PEX1_STN1_RX_DN<16>")
	)
	(segment
		(start 166.742364 -100.045012)
		(end 167.230298 -100.045012)
		(width 0.13462)
		(layer "F.Cu")
		(net "P5E_PEX1_STN1_RX_DN<16>")
	)
	(segment
		(start 162.977576 -102.426262)
		(end 162.5346 -102.647496)
		(width 0.1651)
		(layer "In5.Cu")
		(net "P5E_PEX1_STN1_RX_DN<16>")
	)
	(segment
		(start 159.077406 -105.134664)
		(end 158.916878 -105.116376)
		(width 0.1651)
		(layer "In5.Cu")
		(net "P5E_PEX1_STN1_RX_DN<16>")
	)
	(segment
		(start 175.749712 -273.36496)
		(end 175.749712 -273.09953)
		(width 0.1143)
		(layer "In5.Cu")
		(net "P5E_PEX1_STN1_RX_DN<16>")
	)
	(segment
		(start 175.370236 -271.599914)
		(end 175.370236 -273.375882)
		(width 0.1143)
		(layer "In5.Cu")
		(net "P5E_PEX1_STN1_RX_DN<16>")
	)
	(segment
		(start 157.962092 -105.87482)
		(end 155.298394 -107.989878)
		(width 0.1651)
		(layer "In5.Cu")
		(net "P5E_PEX1_STN1_RX_DN<16>")
	)
	(segment
		(start 160.032192 -104.37622)
		(end 159.871664 -104.357932)
		(width 0.1651)
		(layer "In5.Cu")
		(net "P5E_PEX1_STN1_RX_DN<16>")
	)
	(segment
		(start 159.871664 -104.357932)
		(end 159.48406 -104.66578)
		(width 0.1651)
		(layer "In5.Cu")
		(net "P5E_PEX1_STN1_RX_DN<16>")
	)
	(segment
		(start 169.905934 -99.8855)
		(end 168.058846 -99.8855)
		(width 0.1651)
		(layer "In5.Cu")
		(net "P5E_PEX1_STN1_RX_DN<16>")
	)
	(segment
		(start 160.438846 -103.907336)
		(end 160.420304 -104.068118)
		(width 0.1651)
		(layer "In5.Cu")
		(net "P5E_PEX1_STN1_RX_DN<16>")
	)
	(segment
		(start 175.415956 -270.066262)
		(end 175.415956 -271.525746)
		(width 0.1651)
		(layer "In5.Cu")
		(net "P5E_PEX1_STN1_RX_DN<16>")
	)
	(segment
		(start 158.12262 -105.893108)
		(end 157.962092 -105.87482)
		(width 0.1651)
		(layer "In5.Cu")
		(net "P5E_PEX1_STN1_RX_DN<16>")
	)
	(segment
		(start 166.897304 -100.466144)
		(end 166.84625 -100.61956)
		(width 0.1651)
		(layer "In5.Cu")
		(net "P5E_PEX1_STN1_RX_DN<16>")
	)
	(segment
		(start 145.069052 -159.535368)
		(end 146.31924 -166.005764)
		(width 0.1651)
		(layer "In5.Cu")
		(net "P5E_PEX1_STN1_RX_DN<16>")
	)
	(segment
		(start 161.159444 -103.335074)
		(end 160.438846 -103.907336)
		(width 0.1651)
		(layer "In5.Cu")
		(net "P5E_PEX1_STN1_RX_DN<16>")
	)
	(segment
		(start 164.664898 -101.710236)
		(end 164.221668 -101.931978)
		(width 0.1651)
		(layer "In5.Cu")
		(net "P5E_PEX1_STN1_RX_DN<16>")
	)
	(segment
		(start 163.574222 -102.255574)
		(end 163.130992 -102.477316)
		(width 0.1651)
		(layer "In5.Cu")
		(net "P5E_PEX1_STN1_RX_DN<16>")
	)
	(segment
		(start 147.392644 -119.720106)
		(end 145.77822 -126.400306)
		(width 0.1651)
		(layer "In5.Cu")
		(net "P5E_PEX1_STN1_RX_DN<16>")
	)
	(segment
		(start 152.185878 -110.21695)
		(end 150.55596 -110.87989)
		(width 0.1651)
		(layer "In5.Cu")
		(net "P5E_PEX1_STN1_RX_DN<16>")
	)
	(segment
		(start 159.48406 -104.66578)
		(end 159.465518 -104.826562)
		(width 0.1651)
		(layer "In5.Cu")
		(net "P5E_PEX1_STN1_RX_DN<16>")
	)
	(segment
		(start 158.510732 -105.584752)
		(end 158.12262 -105.893108)
		(width 0.1651)
		(layer "In5.Cu")
		(net "P5E_PEX1_STN1_RX_DN<16>")
	)
	(segment
		(start 166.84625 -100.61956)
		(end 166.40302 -100.841302)
		(width 0.1651)
		(layer "In5.Cu")
		(net "P5E_PEX1_STN1_RX_DN<16>")
	)
	(segment
		(start 162.483546 -102.800912)
		(end 162.040316 -103.022654)
		(width 0.1651)
		(layer "In5.Cu")
		(net "P5E_PEX1_STN1_RX_DN<16>")
	)
	(segment
		(start 162.040316 -103.022654)
		(end 161.8869 -102.9716)
		(width 0.1651)
		(layer "In5.Cu")
		(net "P5E_PEX1_STN1_RX_DN<16>")
	)
	(segment
		(start 150.55596 -110.87989)
		(end 150.169372 -111.275876)
		(width 0.1651)
		(layer "In5.Cu")
		(net "P5E_PEX1_STN1_RX_DN<16>")
	)
	(segment
		(start 163.625276 -102.102158)
		(end 163.574222 -102.255574)
		(width 0.1651)
		(layer "In5.Cu")
		(net "P5E_PEX1_STN1_RX_DN<16>")
	)
	(segment
		(start 175.415956 -271.525746)
		(end 175.415956 -271.554194)
		(width 0.1143)
		(layer "In5.Cu")
		(net "P5E_PEX1_STN1_RX_DN<16>")
	)
	(segment
		(start 163.130992 -102.477316)
		(end 162.977576 -102.426262)
		(width 0.1651)
		(layer "In5.Cu")
		(net "P5E_PEX1_STN1_RX_DN<16>")
	)
	(segment
		(start 165.158928 -101.335586)
		(end 164.715952 -101.55682)
		(width 0.1651)
		(layer "In5.Cu")
		(net "P5E_PEX1_STN1_RX_DN<16>")
	)
	(segment
		(start 170.196764 -100.17633)
		(end 169.905934 -99.8855)
		(width 0.1651)
		(layer "In5.Cu")
		(net "P5E_PEX1_STN1_RX_DN<16>")
	)
	(segment
		(start 159.465518 -104.826562)
		(end 159.077406 -105.134664)
		(width 0.1651)
		(layer "In5.Cu")
		(net "P5E_PEX1_STN1_RX_DN<16>")
	)
	(segment
		(start 166.40302 -100.841302)
		(end 166.249604 -100.790248)
		(width 0.1651)
		(layer "In5.Cu")
		(net "P5E_PEX1_STN1_RX_DN<16>")
	)
	(segment
		(start 165.312344 -101.38664)
		(end 165.158928 -101.335586)
		(width 0.1651)
		(layer "In5.Cu")
		(net "P5E_PEX1_STN1_RX_DN<16>")
	)
	(segment
		(start 160.420304 -104.068118)
		(end 160.032192 -104.37622)
		(width 0.1651)
		(layer "In5.Cu")
		(net "P5E_PEX1_STN1_RX_DN<16>")
	)
	(segment
		(start 175.635412 -273.47926)
		(end 175.749712 -273.36496)
		(width 0.1143)
		(layer "In5.Cu")
		(net "P5E_PEX1_STN1_RX_DN<16>")
	)
	(segment
		(start 158.916878 -105.116376)
		(end 158.52902 -105.424224)
		(width 0.1651)
		(layer "In5.Cu")
		(net "P5E_PEX1_STN1_RX_DN<16>")
	)
	(segment
		(start 168.058846 -99.8855)
		(end 166.897304 -100.466144)
		(width 0.1651)
		(layer "In5.Cu")
		(net "P5E_PEX1_STN1_RX_DN<16>")
	)
	(segment
		(start 164.715952 -101.55682)
		(end 164.664898 -101.710236)
		(width 0.1651)
		(layer "In5.Cu")
		(net "P5E_PEX1_STN1_RX_DN<16>")
	)
	(segment
		(start 158.52902 -105.424224)
		(end 158.510732 -105.584752)
		(width 0.1651)
		(layer "In5.Cu")
		(net "P5E_PEX1_STN1_RX_DN<16>")
	)
	(segment
		(start 162.5346 -102.647496)
		(end 162.483546 -102.800912)
		(width 0.1651)
		(layer "In5.Cu")
		(net "P5E_PEX1_STN1_RX_DN<16>")
	)
	(segment
		(start 161.8869 -102.9716)
		(end 161.159444 -103.335074)
		(width 0.1651)
		(layer "In5.Cu")
		(net "P5E_PEX1_STN1_RX_DN<16>")
	)
	(segment
		(start 175.370236 -273.375882)
		(end 175.473614 -273.47926)
		(width 0.1143)
		(layer "In5.Cu")
		(net "P5E_PEX1_STN1_RX_DN<16>")
	)
	(segment
		(start 164.221668 -101.931978)
		(end 164.068252 -101.880924)
		(width 0.1651)
		(layer "In5.Cu")
		(net "P5E_PEX1_STN1_RX_DN<16>")
	)
	(segment
		(start 165.755574 -101.164898)
		(end 165.312344 -101.38664)
		(width 0.1651)
		(layer "In5.Cu")
		(net "P5E_PEX1_STN1_RX_DN<16>")
	)
	(segment
		(start 144.396968 -149.9362)
		(end 145.069052 -159.535368)
		(width 0.1651)
		(layer "In5.Cu")
		(net "P5E_PEX1_STN1_RX_DN<16>")
	)
	(segment
		(start 150.169372 -111.275876)
		(end 147.392644 -119.720106)
		(width 0.1651)
		(layer "In5.Cu")
		(net "P5E_PEX1_STN1_RX_DN<16>")
	)
	(segment
		(start 165.806628 -101.011482)
		(end 165.755574 -101.164898)
		(width 0.1651)
		(layer "In5.Cu")
		(net "P5E_PEX1_STN1_RX_DN<16>")
	)
	(segment
		(start 152.862788 -109.605572)
		(end 152.185878 -110.21695)
		(width 0.1651)
		(layer "In5.Cu")
		(net "P5E_PEX1_STN1_RX_DN<16>")
	)
	(segment
		(start 166.249604 -100.790248)
		(end 165.806628 -101.011482)
		(width 0.1651)
		(layer "In5.Cu")
		(net "P5E_PEX1_STN1_RX_DN<16>")
	)
	(segment
		(start 146.31924 -166.005764)
		(end 175.415956 -270.066262)
		(width 0.1651)
		(layer "In5.Cu")
		(net "P5E_PEX1_STN1_RX_DN<16>")
	)
	(segment
		(start 175.473614 -273.47926)
		(end 175.635412 -273.47926)
		(width 0.1143)
		(layer "In5.Cu")
		(net "P5E_PEX1_STN1_RX_DN<16>")
	)
	(segment
		(start 175.415956 -271.554194)
		(end 175.370236 -271.599914)
		(width 0.1143)
		(layer "In5.Cu")
		(net "P5E_PEX1_STN1_RX_DN<16>")
	)
	(segment
		(start 164.068252 -101.880924)
		(end 163.625276 -102.102158)
		(width 0.1651)
		(layer "In5.Cu")
		(net "P5E_PEX1_STN1_RX_DN<16>")
	)
	(segment
		(start 145.77822 -126.400306)
		(end 144.396968 -149.9362)
		(width 0.1651)
		(layer "In5.Cu")
		(net "P5E_PEX1_STN1_RX_DN<16>")
	)
	(segment
		(start 155.298394 -107.989878)
		(end 152.862788 -109.605572)
		(width 0.1651)
		(layer "In5.Cu")
		(net "P5E_PEX1_STN1_RX_DN<16>")
	)
	(segment
		(start 118.648988 -345.170506)
		(end 118.648988 -344.539062)
		(width 0.13462)
		(layer "F.Cu")
		(net "P5E_PEX1_STN6_TX_C_DN<109>")
	)
	(segment
		(start 118.943628 -345.465146)
		(end 118.648988 -345.170506)
		(width 0.13462)
		(layer "F.Cu")
		(net "P5E_PEX1_STN6_TX_C_DN<109>")
	)
	(segment
		(start 118.648988 -344.539062)
		(end 118.969028 -344.219022)
		(width 0.13462)
		(layer "F.Cu")
		(net "P5E_PEX1_STN6_TX_C_DN<109>")
	)
	(segment
		(start 120.437148 -408.981148)
		(end 120.775476 -408.981148)
		(width 0.1651)
		(layer "In13.Cu")
		(net "P5E_PEX1_STN6_TX_C_DN<109>")
	)
	(segment
		(start 117.098318 -358.098598)
		(end 117.098318 -347.98635)
		(width 0.1651)
		(layer "In13.Cu")
		(net "P5E_PEX1_STN6_TX_C_DN<109>")
	)
	(segment
		(start 120.775476 -408.981148)
		(end 121.466864 -408.28976)
		(width 0.1651)
		(layer "In13.Cu")
		(net "P5E_PEX1_STN6_TX_C_DN<109>")
	)
	(segment
		(start 114.59337 -391.02411)
		(end 111.551974 -388.544054)
		(width 0.1651)
		(layer "In13.Cu")
		(net "P5E_PEX1_STN6_TX_C_DN<109>")
	)
	(segment
		(start 118.652798 -345.755976)
		(end 118.943628 -345.465146)
		(width 0.1651)
		(layer "In13.Cu")
		(net "P5E_PEX1_STN6_TX_C_DN<109>")
	)
	(segment
		(start 119.591328 -393.094972)
		(end 114.59337 -391.02411)
		(width 0.1651)
		(layer "In13.Cu")
		(net "P5E_PEX1_STN6_TX_C_DN<109>")
	)
	(segment
		(start 121.466864 -408.28976)
		(end 121.466864 -394.970508)
		(width 0.1651)
		(layer "In13.Cu")
		(net "P5E_PEX1_STN6_TX_C_DN<109>")
	)
	(segment
		(start 121.466864 -394.970508)
		(end 119.591328 -393.094972)
		(width 0.1651)
		(layer "In13.Cu")
		(net "P5E_PEX1_STN6_TX_C_DN<109>")
	)
	(segment
		(start 120.310148 -409.490164)
		(end 120.310148 -409.108148)
		(width 0.1651)
		(layer "In13.Cu")
		(net "P5E_PEX1_STN6_TX_C_DN<109>")
	)
	(segment
		(start 110.215426 -386.554726)
		(end 109.46384 -383.84861)
		(width 0.1651)
		(layer "In13.Cu")
		(net "P5E_PEX1_STN6_TX_C_DN<109>")
	)
	(segment
		(start 109.46384 -383.84861)
		(end 109.57814 -366.663224)
		(width 0.1651)
		(layer "In13.Cu")
		(net "P5E_PEX1_STN6_TX_C_DN<109>")
	)
	(segment
		(start 120.310148 -409.108148)
		(end 120.437148 -408.981148)
		(width 0.1651)
		(layer "In13.Cu")
		(net "P5E_PEX1_STN6_TX_C_DN<109>")
	)
	(segment
		(start 118.652798 -346.43187)
		(end 118.652798 -345.755976)
		(width 0.1651)
		(layer "In13.Cu")
		(net "P5E_PEX1_STN6_TX_C_DN<109>")
	)
	(segment
		(start 111.551974 -388.544054)
		(end 110.215426 -386.554726)
		(width 0.1651)
		(layer "In13.Cu")
		(net "P5E_PEX1_STN6_TX_C_DN<109>")
	)
	(segment
		(start 109.57814 -366.663224)
		(end 110.123478 -365.577374)
		(width 0.1651)
		(layer "In13.Cu")
		(net "P5E_PEX1_STN6_TX_C_DN<109>")
	)
	(segment
		(start 110.123478 -365.577374)
		(end 116.798598 -358.827578)
		(width 0.1651)
		(layer "In13.Cu")
		(net "P5E_PEX1_STN6_TX_C_DN<109>")
	)
	(segment
		(start 116.798598 -358.827578)
		(end 117.098318 -358.098598)
		(width 0.1651)
		(layer "In13.Cu")
		(net "P5E_PEX1_STN6_TX_C_DN<109>")
	)
	(segment
		(start 117.098318 -347.98635)
		(end 118.652798 -346.43187)
		(width 0.1651)
		(layer "In13.Cu")
		(net "P5E_PEX1_STN6_TX_C_DN<109>")
	)
	(segment
		(start 313.071764 -351.316798)
		(end 313.366404 -351.611438)
		(width 0.13462)
		(layer "F.Cu")
		(net "P5E_PEX2_STN5_TX_C_DN<80>")
	)
	(segment
		(start 313.071764 -350.685354)
		(end 313.071764 -351.316798)
		(width 0.13462)
		(layer "F.Cu")
		(net "P5E_PEX2_STN5_TX_C_DN<80>")
	)
	(segment
		(start 313.391804 -350.365314)
		(end 313.071764 -350.685354)
		(width 0.13462)
		(layer "F.Cu")
		(net "P5E_PEX2_STN5_TX_C_DN<80>")
	)
	(segment
		(start 323.809106 -386.398262)
		(end 313.075574 -358.81818)
		(width 0.1651)
		(layer "In7.Cu")
		(net "P5E_PEX2_STN5_TX_C_DN<80>")
	)
	(segment
		(start 332.616048 -404.629112)
		(end 332.616048 -395.065758)
		(width 0.1651)
		(layer "In7.Cu")
		(net "P5E_PEX2_STN5_TX_C_DN<80>")
	)
	(segment
		(start 332.616048 -395.065758)
		(end 332.286864 -394.378688)
		(width 0.1651)
		(layer "In7.Cu")
		(net "P5E_PEX2_STN5_TX_C_DN<80>")
	)
	(segment
		(start 331.617066 -405.080978)
		(end 332.164182 -405.080978)
		(width 0.1651)
		(layer "In7.Cu")
		(net "P5E_PEX2_STN5_TX_C_DN<80>")
	)
	(segment
		(start 331.490066 -405.207978)
		(end 331.617066 -405.080978)
		(width 0.1651)
		(layer "In7.Cu")
		(net "P5E_PEX2_STN5_TX_C_DN<80>")
	)
	(segment
		(start 313.075574 -358.81818)
		(end 313.075574 -351.902268)
		(width 0.1651)
		(layer "In7.Cu")
		(net "P5E_PEX2_STN5_TX_C_DN<80>")
	)
	(segment
		(start 325.123556 -389.51154)
		(end 323.809106 -386.398262)
		(width 0.1651)
		(layer "In7.Cu")
		(net "P5E_PEX2_STN5_TX_C_DN<80>")
	)
	(segment
		(start 331.490066 -405.589994)
		(end 331.490066 -405.207978)
		(width 0.1651)
		(layer "In7.Cu")
		(net "P5E_PEX2_STN5_TX_C_DN<80>")
	)
	(segment
		(start 313.075574 -351.902268)
		(end 313.366404 -351.611438)
		(width 0.1651)
		(layer "In7.Cu")
		(net "P5E_PEX2_STN5_TX_C_DN<80>")
	)
	(segment
		(start 332.286864 -394.378688)
		(end 328.308208 -392.767312)
		(width 0.1651)
		(layer "In7.Cu")
		(net "P5E_PEX2_STN5_TX_C_DN<80>")
	)
	(segment
		(start 328.308208 -392.767312)
		(end 325.123556 -389.51154)
		(width 0.1651)
		(layer "In7.Cu")
		(net "P5E_PEX2_STN5_TX_C_DN<80>")
	)
	(segment
		(start 332.164182 -405.080978)
		(end 332.616048 -404.629112)
		(width 0.1651)
		(layer "In7.Cu")
		(net "P5E_PEX2_STN5_TX_C_DN<80>")
	)
	(segment
		(start 428.052738 -147.104608)
		(end 427.73473 -146.7866)
		(width 0.13462)
		(layer "F.Cu")
		(net "P5E_PEX3_STN0_TX_C_DP<10>")
	)
	(segment
		(start 427.73473 -146.7866)
		(end 422.22547 -146.7866)
		(width 0.13462)
		(layer "F.Cu")
		(net "P5E_PEX3_STN0_TX_C_DP<10>")
	)
	(segment
		(start 422.057068 -146.955002)
		(end 421.557704 -146.955002)
		(width 0.13462)
		(layer "F.Cu")
		(net "P5E_PEX3_STN0_TX_C_DP<10>")
	)
	(segment
		(start 422.22547 -146.7866)
		(end 422.057068 -146.955002)
		(width 0.13462)
		(layer "F.Cu")
		(net "P5E_PEX3_STN0_TX_C_DP<10>")
	)
	(segment
		(start 406.429718 -319.888362)
		(end 406.429718 -316.455298)
		(width 0.1143)
		(layer "In5.Cu")
		(net "P5E_PEX3_STN5_RX_DP<80>")
	)
	(segment
		(start 376.366024 -396.67053)
		(end 376.366024 -395.748002)
		(width 0.1651)
		(layer "In5.Cu")
		(net "P5E_PEX3_STN5_RX_DP<80>")
	)
	(segment
		(start 388.57809 -358.79024)
		(end 388.57809 -341.85987)
		(width 0.1651)
		(layer "In5.Cu")
		(net "P5E_PEX3_STN5_RX_DP<80>")
	)
	(segment
		(start 391.624312 -364.646972)
		(end 391.504424 -364.609126)
		(width 0.1651)
		(layer "In5.Cu")
		(net "P5E_PEX3_STN5_RX_DP<80>")
	)
	(segment
		(start 405.01697 -325.942452)
		(end 405.965914 -323.82079)
		(width 0.1651)
		(layer "In5.Cu")
		(net "P5E_PEX3_STN5_RX_DP<80>")
	)
	(segment
		(start 391.504424 -364.609126)
		(end 391.27557 -364.169452)
		(width 0.1651)
		(layer "In5.Cu")
		(net "P5E_PEX3_STN5_RX_DP<80>")
	)
	(segment
		(start 405.965914 -323.82079)
		(end 406.383998 -321.864228)
		(width 0.1651)
		(layer "In5.Cu")
		(net "P5E_PEX3_STN5_RX_DP<80>")
	)
	(segment
		(start 392.1633 -365.6838)
		(end 392.043412 -365.645954)
		(width 0.1651)
		(layer "In5.Cu")
		(net "P5E_PEX3_STN5_RX_DP<80>")
	)
	(segment
		(start 406.383998 -319.96253)
		(end 406.383998 -319.934082)
		(width 0.1143)
		(layer "In5.Cu")
		(net "P5E_PEX3_STN5_RX_DP<80>")
	)
	(segment
		(start 406.999948 -316.115192)
		(end 406.999948 -315.849762)
		(width 0.1143)
		(layer "In5.Cu")
		(net "P5E_PEX3_STN5_RX_DP<80>")
	)
	(segment
		(start 376.033538 -397.003016)
		(end 376.366024 -396.67053)
		(width 0.1651)
		(layer "In5.Cu")
		(net "P5E_PEX3_STN5_RX_DP<80>")
	)
	(segment
		(start 382.727454 -391.097008)
		(end 391.216388 -386.946394)
		(width 0.1651)
		(layer "In5.Cu")
		(net "P5E_PEX3_STN5_RX_DP<80>")
	)
	(segment
		(start 388.57809 -341.85987)
		(end 389.103362 -340.938866)
		(width 0.1651)
		(layer "In5.Cu")
		(net "P5E_PEX3_STN5_RX_DP<80>")
	)
	(segment
		(start 393.928854 -369.07851)
		(end 392.1633 -365.6838)
		(width 0.1651)
		(layer "In5.Cu")
		(net "P5E_PEX3_STN5_RX_DP<80>")
	)
	(segment
		(start 391.623804 -364.64748)
		(end 391.624312 -364.646972)
		(width 0.1651)
		(layer "In5.Cu")
		(net "P5E_PEX3_STN5_RX_DP<80>")
	)
	(segment
		(start 378.750068 -393.481052)
		(end 382.727454 -391.097008)
		(width 0.1651)
		(layer "In5.Cu")
		(net "P5E_PEX3_STN5_RX_DP<80>")
	)
	(segment
		(start 375.489978 -396.49019)
		(end 375.489978 -396.876016)
		(width 0.1651)
		(layer "In5.Cu")
		(net "P5E_PEX3_STN5_RX_DP<80>")
	)
	(segment
		(start 391.852658 -365.086392)
		(end 391.852404 -365.086392)
		(width 0.1651)
		(layer "In5.Cu")
		(net "P5E_PEX3_STN5_RX_DP<80>")
	)
	(segment
		(start 406.383998 -319.934082)
		(end 406.429718 -319.888362)
		(width 0.1143)
		(layer "In5.Cu")
		(net "P5E_PEX3_STN5_RX_DP<80>")
	)
	(segment
		(start 375.489978 -396.876016)
		(end 375.616978 -397.003016)
		(width 0.1651)
		(layer "In5.Cu")
		(net "P5E_PEX3_STN5_RX_DP<80>")
	)
	(segment
		(start 406.383998 -321.864228)
		(end 406.383998 -319.96253)
		(width 0.1651)
		(layer "In5.Cu")
		(net "P5E_PEX3_STN5_RX_DP<80>")
	)
	(segment
		(start 392.043412 -365.645954)
		(end 391.814812 -365.20628)
		(width 0.1651)
		(layer "In5.Cu")
		(net "P5E_PEX3_STN5_RX_DP<80>")
	)
	(segment
		(start 406.885648 -316.229492)
		(end 406.999948 -316.115192)
		(width 0.1143)
		(layer "In5.Cu")
		(net "P5E_PEX3_STN5_RX_DP<80>")
	)
	(segment
		(start 391.27557 -364.169452)
		(end 391.313416 -364.049564)
		(width 0.1651)
		(layer "In5.Cu")
		(net "P5E_PEX3_STN5_RX_DP<80>")
	)
	(segment
		(start 376.366024 -395.748002)
		(end 378.750068 -393.481052)
		(width 0.1651)
		(layer "In5.Cu")
		(net "P5E_PEX3_STN5_RX_DP<80>")
	)
	(segment
		(start 391.313416 -364.049564)
		(end 388.57809 -358.79024)
		(width 0.1651)
		(layer "In5.Cu")
		(net "P5E_PEX3_STN5_RX_DP<80>")
	)
	(segment
		(start 406.429718 -316.455298)
		(end 406.655524 -316.229492)
		(width 0.1143)
		(layer "In5.Cu")
		(net "P5E_PEX3_STN5_RX_DP<80>")
	)
	(segment
		(start 391.852404 -365.086392)
		(end 391.623804 -364.64748)
		(width 0.1651)
		(layer "In5.Cu")
		(net "P5E_PEX3_STN5_RX_DP<80>")
	)
	(segment
		(start 393.573762 -385.60629)
		(end 393.92098 -385.001516)
		(width 0.1651)
		(layer "In5.Cu")
		(net "P5E_PEX3_STN5_RX_DP<80>")
	)
	(segment
		(start 393.92098 -385.001516)
		(end 393.928854 -369.07851)
		(width 0.1651)
		(layer "In5.Cu")
		(net "P5E_PEX3_STN5_RX_DP<80>")
	)
	(segment
		(start 406.655524 -316.229492)
		(end 406.885648 -316.229492)
		(width 0.1143)
		(layer "In5.Cu")
		(net "P5E_PEX3_STN5_RX_DP<80>")
	)
	(segment
		(start 375.616978 -397.003016)
		(end 376.033538 -397.003016)
		(width 0.1651)
		(layer "In5.Cu")
		(net "P5E_PEX3_STN5_RX_DP<80>")
	)
	(segment
		(start 391.814812 -365.20628)
		(end 391.852658 -365.086392)
		(width 0.1651)
		(layer "In5.Cu")
		(net "P5E_PEX3_STN5_RX_DP<80>")
	)
	(segment
		(start 391.216388 -386.946394)
		(end 393.573762 -385.60629)
		(width 0.1651)
		(layer "In5.Cu")
		(net "P5E_PEX3_STN5_RX_DP<80>")
	)
	(segment
		(start 389.103362 -340.938866)
		(end 405.01697 -325.942452)
		(width 0.1651)
		(layer "In5.Cu")
		(net "P5E_PEX3_STN5_RX_DP<80>")
	)
	(segment
		(start 421.106346 -112.834928)
		(end 421.557704 -112.834928)
		(width 0.13208)
		(layer "F.Cu")
		(net "NIC7_BIF0_N")
	)
	(segment
		(start 419.541452 -112.277398)
		(end 420.344854 -113.0808)
		(width 0.13208)
		(layer "F.Cu")
		(net "NIC7_BIF0_N")
	)
	(segment
		(start 419.111176 -110.530132)
		(end 419.541452 -110.960408)
		(width 0.13208)
		(layer "F.Cu")
		(net "NIC7_BIF0_N")
	)
	(segment
		(start 420.344854 -113.0808)
		(end 420.860474 -113.0808)
		(width 0.13208)
		(layer "F.Cu")
		(net "NIC7_BIF0_N")
	)
	(segment
		(start 420.860474 -113.0808)
		(end 421.106346 -112.834928)
		(width 0.13208)
		(layer "F.Cu")
		(net "NIC7_BIF0_N")
	)
	(segment
		(start 419.541452 -110.960408)
		(end 419.541452 -112.277398)
		(width 0.13208)
		(layer "F.Cu")
		(net "NIC7_BIF0_N")
	)
	(via
		(at 419.111176 -110.530132)
		(size 0.508)
		(drill 0.254)
		(layers "F.Cu" "B.Cu")
		(net "NIC7_BIF0_N")
	)
	(segment
		(start 414.678114 -108.199682)
		(end 414.329626 -107.851194)
		(width 0.13208)
		(layer "B.Cu")
		(net "NIC7_BIF0_N")
	)
	(segment
		(start 416.780726 -108.199682)
		(end 414.678114 -108.199682)
		(width 0.13208)
		(layer "B.Cu")
		(net "NIC7_BIF0_N")
	)
	(segment
		(start 419.111176 -110.530132)
		(end 416.780726 -108.199682)
		(width 0.13208)
		(layer "B.Cu")
		(net "NIC7_BIF0_N")
	)
	(segment
		(start 414.329626 -107.851194)
		(end 411.41904 -107.851194)
		(width 0.13208)
		(layer "B.Cu")
		(net "NIC7_BIF0_N")
	)
	(segment
		(start 411.283404 -107.98683)
		(end 411.283404 -108.462318)
		(width 0.13208)
		(layer "B.Cu")
		(net "NIC7_BIF0_N")
	)
	(segment
		(start 411.41904 -107.851194)
		(end 411.283404 -107.98683)
		(width 0.13208)
		(layer "B.Cu")
		(net "NIC7_BIF0_N")
	)
	(segment
		(start 411.283404 -108.462318)
		(end 410.300424 -108.462318)
		(width 0.13208)
		(layer "B.Cu")
		(net "NIC7_BIF0_N")
	)
	(segment
		(start 410.300424 -108.462318)
		(end 410.297376 -108.465366)
		(width 0.13208)
		(layer "B.Cu")
		(net "NIC7_BIF0_N")
	)
	(segment
		(start 162.14217 -101.84511)
		(end 161.654236 -101.84511)
		(width 0.13462)
		(layer "F.Cu")
		(net "P5E_PEX1_STN1_TX_C_DP<17>")
	)
	(segment
		(start 161.654236 -101.84511)
		(end 161.491168 -101.682042)
		(width 0.13462)
		(layer "F.Cu")
		(net "P5E_PEX1_STN1_TX_C_DP<17>")
	)
	(segment
		(start 161.491168 -101.682042)
		(end 153.942288 -101.682042)
		(width 0.13462)
		(layer "F.Cu")
		(net "P5E_PEX1_STN1_TX_C_DP<17>")
	)
	(segment
		(start 153.942288 -101.682042)
		(end 153.614628 -102.009702)
		(width 0.13462)
		(layer "F.Cu")
		(net "P5E_PEX1_STN1_TX_C_DP<17>")
	)
	(segment
		(start 173.516036 -322.014596)
		(end 171.531026 -324.983094)
		(width 0.1651)
		(layer "In5.Cu")
		(net "P5E_PEX1_STN6_RX_DN<96>")
	)
	(segment
		(start 133.914896 -367.777268)
		(end 132.876798 -368.69497)
		(width 0.1651)
		(layer "In5.Cu")
		(net "P5E_PEX1_STN6_RX_DN<96>")
	)
	(segment
		(start 155.661868 -335.871566)
		(end 147.590002 -351.990152)
		(width 0.1651)
		(layer "In5.Cu")
		(net "P5E_PEX1_STN6_RX_DN<96>")
	)
	(segment
		(start 173.850046 -318.434466)
		(end 173.735746 -318.320166)
		(width 0.1143)
		(layer "In5.Cu")
		(net "P5E_PEX1_STN6_RX_DN<96>")
	)
	(segment
		(start 171.409614 -325.104506)
		(end 158.456122 -332.748636)
		(width 0.1651)
		(layer "In5.Cu")
		(net "P5E_PEX1_STN6_RX_DN<96>")
	)
	(segment
		(start 131.310126 -376.408188)
		(end 131.310126 -376.790204)
		(width 0.1651)
		(layer "In5.Cu")
		(net "P5E_PEX1_STN6_RX_DN<96>")
	)
	(segment
		(start 173.470316 -318.434466)
		(end 173.470316 -319.837562)
		(width 0.1143)
		(layer "In5.Cu")
		(net "P5E_PEX1_STN6_RX_DN<96>")
	)
	(segment
		(start 173.516036 -319.883282)
		(end 173.516036 -319.91173)
		(width 0.1143)
		(layer "In5.Cu")
		(net "P5E_PEX1_STN6_RX_DN<96>")
	)
	(segment
		(start 131.986782 -376.281188)
		(end 131.437126 -376.281188)
		(width 0.1651)
		(layer "In5.Cu")
		(net "P5E_PEX1_STN6_RX_DN<96>")
	)
	(segment
		(start 173.735746 -318.320166)
		(end 173.584616 -318.320166)
		(width 0.1143)
		(layer "In5.Cu")
		(net "P5E_PEX1_STN6_RX_DN<96>")
	)
	(segment
		(start 132.876798 -368.69497)
		(end 132.36956 -369.991386)
		(width 0.1651)
		(layer "In5.Cu")
		(net "P5E_PEX1_STN6_RX_DN<96>")
	)
	(segment
		(start 132.36956 -369.991386)
		(end 132.36956 -375.89841)
		(width 0.1651)
		(layer "In5.Cu")
		(net "P5E_PEX1_STN6_RX_DN<96>")
	)
	(segment
		(start 173.584616 -318.320166)
		(end 173.470316 -318.434466)
		(width 0.1143)
		(layer "In5.Cu")
		(net "P5E_PEX1_STN6_RX_DN<96>")
	)
	(segment
		(start 158.456122 -332.748636)
		(end 155.661868 -335.871566)
		(width 0.1651)
		(layer "In5.Cu")
		(net "P5E_PEX1_STN6_RX_DN<96>")
	)
	(segment
		(start 171.531026 -324.983094)
		(end 171.409614 -325.104506)
		(width 0.1651)
		(layer "In5.Cu")
		(net "P5E_PEX1_STN6_RX_DN<96>")
	)
	(segment
		(start 173.516036 -319.91173)
		(end 173.516036 -322.014596)
		(width 0.1651)
		(layer "In5.Cu")
		(net "P5E_PEX1_STN6_RX_DN<96>")
	)
	(segment
		(start 131.437126 -376.281188)
		(end 131.310126 -376.408188)
		(width 0.1651)
		(layer "In5.Cu")
		(net "P5E_PEX1_STN6_RX_DN<96>")
	)
	(segment
		(start 173.850046 -318.699896)
		(end 173.850046 -318.434466)
		(width 0.1143)
		(layer "In5.Cu")
		(net "P5E_PEX1_STN6_RX_DN<96>")
	)
	(segment
		(start 173.470316 -319.837562)
		(end 173.516036 -319.883282)
		(width 0.1143)
		(layer "In5.Cu")
		(net "P5E_PEX1_STN6_RX_DN<96>")
	)
	(segment
		(start 145.23212 -358.323134)
		(end 133.914896 -367.777268)
		(width 0.1651)
		(layer "In5.Cu")
		(net "P5E_PEX1_STN6_RX_DN<96>")
	)
	(segment
		(start 147.590002 -351.990152)
		(end 145.23212 -358.323134)
		(width 0.1651)
		(layer "In5.Cu")
		(net "P5E_PEX1_STN6_RX_DN<96>")
	)
	(segment
		(start 132.36956 -375.89841)
		(end 131.986782 -376.281188)
		(width 0.1651)
		(layer "In5.Cu")
		(net "P5E_PEX1_STN6_RX_DN<96>")
	)
	(segment
		(start 416.47491 -124.834904)
		(end 416.303206 -124.6632)
		(width 0.13462)
		(layer "F.Cu")
		(net "P5E_PEX3_STN0_RX_DP<3>")
	)
	(segment
		(start 413.807148 -124.6632)
		(end 413.50311 -124.967238)
		(width 0.13462)
		(layer "F.Cu")
		(net "P5E_PEX3_STN0_RX_DP<3>")
	)
	(segment
		(start 416.95751 -124.834904)
		(end 416.47491 -124.834904)
		(width 0.13462)
		(layer "F.Cu")
		(net "P5E_PEX3_STN0_RX_DP<3>")
	)
	(segment
		(start 416.303206 -124.6632)
		(end 413.807148 -124.6632)
		(width 0.13462)
		(layer "F.Cu")
		(net "P5E_PEX3_STN0_RX_DP<3>")
	)
	(segment
		(start 423.63263 -130.334512)
		(end 423.632884 -130.334512)
		(width 0.1651)
		(layer "In5.Cu")
		(net "P5E_PEX3_STN0_RX_DP<3>")
	)
	(segment
		(start 430.67224 -140.240512)
		(end 430.35093 -139.342368)
		(width 0.1651)
		(layer "In5.Cu")
		(net "P5E_PEX3_STN0_RX_DP<3>")
	)
	(segment
		(start 416.889692 -125.051058)
		(end 416.403282 -124.957078)
		(width 0.1651)
		(layer "In5.Cu")
		(net "P5E_PEX3_STN0_RX_DP<3>")
	)
	(segment
		(start 433.887118 -144.429226)
		(end 430.67224 -140.240512)
		(width 0.1651)
		(layer "In5.Cu")
		(net "P5E_PEX3_STN0_RX_DP<3>")
	)
	(segment
		(start 434.682138 -150.0505)
		(end 433.887118 -144.429226)
		(width 0.1651)
		(layer "In5.Cu")
		(net "P5E_PEX3_STN0_RX_DP<3>")
	)
	(segment
		(start 424.511978 -131.806188)
		(end 424.257978 -131.381246)
		(width 0.1651)
		(layer "In5.Cu")
		(net "P5E_PEX3_STN0_RX_DP<3>")
	)
	(segment
		(start 424.883326 -132.42798)
		(end 424.726608 -132.38861)
		(width 0.1651)
		(layer "In5.Cu")
		(net "P5E_PEX3_STN0_RX_DP<3>")
	)
	(segment
		(start 416.403282 -124.957078)
		(end 416.312604 -124.822966)
		(width 0.1651)
		(layer "In5.Cu")
		(net "P5E_PEX3_STN0_RX_DP<3>")
	)
	(segment
		(start 424.472354 -131.96316)
		(end 424.511978 -131.806188)
		(width 0.1651)
		(layer "In5.Cu")
		(net "P5E_PEX3_STN0_RX_DP<3>")
	)
	(segment
		(start 422.189148 -127.918464)
		(end 421.771572 -127.219456)
		(width 0.1651)
		(layer "In5.Cu")
		(net "P5E_PEX3_STN0_RX_DP<3>")
	)
	(segment
		(start 423.88663 -130.759454)
		(end 423.63263 -130.334512)
		(width 0.1651)
		(layer "In5.Cu")
		(net "P5E_PEX3_STN0_RX_DP<3>")
	)
	(segment
		(start 429.800004 -285.449772)
		(end 430.065434 -285.449772)
		(width 0.1143)
		(layer "In5.Cu")
		(net "P5E_PEX3_STN0_RX_DP<3>")
	)
	(segment
		(start 424.726608 -132.38861)
		(end 424.472354 -131.96316)
		(width 0.1651)
		(layer "In5.Cu")
		(net "P5E_PEX3_STN0_RX_DP<3>")
	)
	(segment
		(start 413.79394 -124.676408)
		(end 413.50311 -124.967238)
		(width 0.1651)
		(layer "In5.Cu")
		(net "P5E_PEX3_STN0_RX_DP<3>")
	)
	(segment
		(start 423.847006 -130.916426)
		(end 423.88663 -130.759454)
		(width 0.1651)
		(layer "In5.Cu")
		(net "P5E_PEX3_STN0_RX_DP<3>")
	)
	(segment
		(start 422.149524 -128.075182)
		(end 422.189148 -127.918464)
		(width 0.1651)
		(layer "In5.Cu")
		(net "P5E_PEX3_STN0_RX_DP<3>")
	)
	(segment
		(start 433.50053 -284.833822)
		(end 434.600604 -284.196028)
		(width 0.1651)
		(layer "In5.Cu")
		(net "P5E_PEX3_STN0_RX_DP<3>")
	)
	(segment
		(start 428.138082 -137.875264)
		(end 424.883326 -132.42798)
		(width 0.1651)
		(layer "In5.Cu")
		(net "P5E_PEX3_STN0_RX_DP<3>")
	)
	(segment
		(start 430.179734 -285.335472)
		(end 430.179734 -285.09468)
		(width 0.1143)
		(layer "In5.Cu")
		(net "P5E_PEX3_STN0_RX_DP<3>")
	)
	(segment
		(start 416.312604 -124.822966)
		(end 415.554668 -124.676408)
		(width 0.1651)
		(layer "In5.Cu")
		(net "P5E_PEX3_STN0_RX_DP<3>")
	)
	(segment
		(start 419.071806 -125.642624)
		(end 418.922454 -125.704346)
		(width 0.1651)
		(layer "In5.Cu")
		(net "P5E_PEX3_STN0_RX_DP<3>")
	)
	(segment
		(start 430.065434 -285.449772)
		(end 430.179734 -285.335472)
		(width 0.1143)
		(layer "In5.Cu")
		(net "P5E_PEX3_STN0_RX_DP<3>")
	)
	(segment
		(start 418.465 -125.514354)
		(end 418.403278 -125.364748)
		(width 0.1651)
		(layer "In5.Cu")
		(net "P5E_PEX3_STN0_RX_DP<3>")
	)
	(segment
		(start 444.64478 -272.77822)
		(end 444.754508 -269.578836)
		(width 0.1651)
		(layer "In5.Cu")
		(net "P5E_PEX3_STN0_RX_DP<3>")
	)
	(segment
		(start 423.221658 -129.869692)
		(end 423.261282 -129.712974)
		(width 0.1651)
		(layer "In5.Cu")
		(net "P5E_PEX3_STN0_RX_DP<3>")
	)
	(segment
		(start 434.489352 -232.225596)
		(end 435.144418 -168.404286)
		(width 0.1651)
		(layer "In5.Cu")
		(net "P5E_PEX3_STN0_RX_DP<3>")
	)
	(segment
		(start 423.261282 -129.712974)
		(end 422.56075 -128.540256)
		(width 0.1651)
		(layer "In5.Cu")
		(net "P5E_PEX3_STN0_RX_DP<3>")
	)
	(segment
		(start 420.958772 -126.426722)
		(end 419.071806 -125.642624)
		(width 0.1651)
		(layer "In5.Cu")
		(net "P5E_PEX3_STN0_RX_DP<3>")
	)
	(segment
		(start 418.403278 -125.364494)
		(end 417.786058 -125.107954)
		(width 0.1651)
		(layer "In5.Cu")
		(net "P5E_PEX3_STN0_RX_DP<3>")
	)
	(segment
		(start 432.250088 -284.833822)
		(end 433.50053 -284.833822)
		(width 0.1651)
		(layer "In5.Cu")
		(net "P5E_PEX3_STN0_RX_DP<3>")
	)
	(segment
		(start 444.754508 -269.578836)
		(end 436.219854 -240.358422)
		(width 0.1651)
		(layer "In5.Cu")
		(net "P5E_PEX3_STN0_RX_DP<3>")
	)
	(segment
		(start 423.632884 -130.334512)
		(end 423.476166 -130.295142)
		(width 0.1651)
		(layer "In5.Cu")
		(net "P5E_PEX3_STN0_RX_DP<3>")
	)
	(segment
		(start 430.394872 -284.879542)
		(end 432.17592 -284.879542)
		(width 0.1143)
		(layer "In5.Cu")
		(net "P5E_PEX3_STN0_RX_DP<3>")
	)
	(segment
		(start 430.35093 -139.342368)
		(end 428.138082 -137.875264)
		(width 0.1651)
		(layer "In5.Cu")
		(net "P5E_PEX3_STN0_RX_DP<3>")
	)
	(segment
		(start 432.22164 -284.833822)
		(end 432.250088 -284.833822)
		(width 0.1143)
		(layer "In5.Cu")
		(net "P5E_PEX3_STN0_RX_DP<3>")
	)
	(segment
		(start 417.02355 -124.960634)
		(end 416.889692 -125.051058)
		(width 0.1651)
		(layer "In5.Cu")
		(net "P5E_PEX3_STN0_RX_DP<3>")
	)
	(segment
		(start 424.10126 -131.341876)
		(end 423.847006 -130.916426)
		(width 0.1651)
		(layer "In5.Cu")
		(net "P5E_PEX3_STN0_RX_DP<3>")
	)
	(segment
		(start 422.404032 -128.500632)
		(end 422.149524 -128.075182)
		(width 0.1651)
		(layer "In5.Cu")
		(net "P5E_PEX3_STN0_RX_DP<3>")
	)
	(segment
		(start 434.600604 -284.196028)
		(end 442.552836 -276.487382)
		(width 0.1651)
		(layer "In5.Cu")
		(net "P5E_PEX3_STN0_RX_DP<3>")
	)
	(segment
		(start 422.56075 -128.540256)
		(end 422.404032 -128.500632)
		(width 0.1651)
		(layer "In5.Cu")
		(net "P5E_PEX3_STN0_RX_DP<3>")
	)
	(segment
		(start 421.771572 -127.219456)
		(end 420.958772 -126.426722)
		(width 0.1651)
		(layer "In5.Cu")
		(net "P5E_PEX3_STN0_RX_DP<3>")
	)
	(segment
		(start 415.554668 -124.676408)
		(end 413.79394 -124.676408)
		(width 0.1651)
		(layer "In5.Cu")
		(net "P5E_PEX3_STN0_RX_DP<3>")
	)
	(segment
		(start 423.476166 -130.295142)
		(end 423.221658 -129.869692)
		(width 0.1651)
		(layer "In5.Cu")
		(net "P5E_PEX3_STN0_RX_DP<3>")
	)
	(segment
		(start 424.257978 -131.381246)
		(end 424.10126 -131.341876)
		(width 0.1651)
		(layer "In5.Cu")
		(net "P5E_PEX3_STN0_RX_DP<3>")
	)
	(segment
		(start 417.786058 -125.107954)
		(end 417.02355 -124.960634)
		(width 0.1651)
		(layer "In5.Cu")
		(net "P5E_PEX3_STN0_RX_DP<3>")
	)
	(segment
		(start 436.219854 -240.358422)
		(end 434.489352 -232.225596)
		(width 0.1651)
		(layer "In5.Cu")
		(net "P5E_PEX3_STN0_RX_DP<3>")
	)
	(segment
		(start 442.552836 -276.487382)
		(end 444.64478 -272.77822)
		(width 0.1651)
		(layer "In5.Cu")
		(net "P5E_PEX3_STN0_RX_DP<3>")
	)
	(segment
		(start 430.179734 -285.09468)
		(end 430.394872 -284.879542)
		(width 0.1143)
		(layer "In5.Cu")
		(net "P5E_PEX3_STN0_RX_DP<3>")
	)
	(segment
		(start 418.403278 -125.364748)
		(end 418.403278 -125.364494)
		(width 0.1651)
		(layer "In5.Cu")
		(net "P5E_PEX3_STN0_RX_DP<3>")
	)
	(segment
		(start 435.144418 -168.404286)
		(end 434.682138 -150.0505)
		(width 0.1651)
		(layer "In5.Cu")
		(net "P5E_PEX3_STN0_RX_DP<3>")
	)
	(segment
		(start 432.17592 -284.879542)
		(end 432.22164 -284.833822)
		(width 0.1143)
		(layer "In5.Cu")
		(net "P5E_PEX3_STN0_RX_DP<3>")
	)
	(segment
		(start 418.922454 -125.704346)
		(end 418.465 -125.514354)
		(width 0.1651)
		(layer "In5.Cu")
		(net "P5E_PEX3_STN0_RX_DP<3>")
	)
	(segment
		(start 409.735528 -318.320166)
		(end 409.849828 -318.434466)
		(width 0.1143)
		(layer "In5.Cu")
		(net "P5E_PEX3_STN5_RX_DN<83>")
	)
	(segment
		(start 382.750314 -398.38503)
		(end 383.2479 -397.887444)
		(width 0.1651)
		(layer "In5.Cu")
		(net "P5E_PEX3_STN5_RX_DN<83>")
	)
	(segment
		(start 409.515818 -319.883282)
		(end 409.470098 -319.837562)
		(width 0.1143)
		(layer "In5.Cu")
		(net "P5E_PEX3_STN5_RX_DN<83>")
	)
	(segment
		(start 382.089914 -398.51203)
		(end 382.216914 -398.38503)
		(width 0.1651)
		(layer "In5.Cu")
		(net "P5E_PEX3_STN5_RX_DN<83>")
	)
	(segment
		(start 397.60779 -387.869176)
		(end 398.210024 -386.981192)
		(width 0.1651)
		(layer "In5.Cu")
		(net "P5E_PEX3_STN5_RX_DN<83>")
	)
	(segment
		(start 396.373604 -388.874762)
		(end 397.60779 -387.869176)
		(width 0.1651)
		(layer "In5.Cu")
		(net "P5E_PEX3_STN5_RX_DN<83>")
	)
	(segment
		(start 383.2479 -397.887444)
		(end 383.2479 -395.32814)
		(width 0.1651)
		(layer "In5.Cu")
		(net "P5E_PEX3_STN5_RX_DN<83>")
	)
	(segment
		(start 398.210024 -386.981192)
		(end 398.504664 -386.045964)
		(width 0.1651)
		(layer "In5.Cu")
		(net "P5E_PEX3_STN5_RX_DN<83>")
	)
	(segment
		(start 409.470098 -319.837562)
		(end 409.470098 -318.434466)
		(width 0.1143)
		(layer "In5.Cu")
		(net "P5E_PEX3_STN5_RX_DN<83>")
	)
	(segment
		(start 409.515818 -322.741798)
		(end 409.515818 -319.91173)
		(width 0.1651)
		(layer "In5.Cu")
		(net "P5E_PEX3_STN5_RX_DN<83>")
	)
	(segment
		(start 385.297172 -393.46251)
		(end 396.373604 -388.874762)
		(width 0.1651)
		(layer "In5.Cu")
		(net "P5E_PEX3_STN5_RX_DN<83>")
	)
	(segment
		(start 409.515818 -319.91173)
		(end 409.515818 -319.883282)
		(width 0.1143)
		(layer "In5.Cu")
		(net "P5E_PEX3_STN5_RX_DN<83>")
	)
	(segment
		(start 409.584398 -318.320166)
		(end 409.735528 -318.320166)
		(width 0.1143)
		(layer "In5.Cu")
		(net "P5E_PEX3_STN5_RX_DN<83>")
	)
	(segment
		(start 383.77876 -394.59916)
		(end 385.297172 -393.46251)
		(width 0.1651)
		(layer "In5.Cu")
		(net "P5E_PEX3_STN5_RX_DN<83>")
	)
	(segment
		(start 398.509998 -340.886542)
		(end 408.028648 -327.472294)
		(width 0.1651)
		(layer "In5.Cu")
		(net "P5E_PEX3_STN5_RX_DN<83>")
	)
	(segment
		(start 383.2479 -395.32814)
		(end 383.77876 -394.59916)
		(width 0.1651)
		(layer "In5.Cu")
		(net "P5E_PEX3_STN5_RX_DN<83>")
	)
	(segment
		(start 398.18691 -342.044782)
		(end 398.509998 -340.886542)
		(width 0.1651)
		(layer "In5.Cu")
		(net "P5E_PEX3_STN5_RX_DN<83>")
	)
	(segment
		(start 408.967686 -325.343012)
		(end 409.515818 -322.741798)
		(width 0.1651)
		(layer "In5.Cu")
		(net "P5E_PEX3_STN5_RX_DN<83>")
	)
	(segment
		(start 398.483074 -367.558828)
		(end 398.18691 -358.721152)
		(width 0.1651)
		(layer "In5.Cu")
		(net "P5E_PEX3_STN5_RX_DN<83>")
	)
	(segment
		(start 409.849828 -318.434466)
		(end 409.849828 -318.699896)
		(width 0.1143)
		(layer "In5.Cu")
		(net "P5E_PEX3_STN5_RX_DN<83>")
	)
	(segment
		(start 409.470098 -318.434466)
		(end 409.584398 -318.320166)
		(width 0.1143)
		(layer "In5.Cu")
		(net "P5E_PEX3_STN5_RX_DN<83>")
	)
	(segment
		(start 382.216914 -398.38503)
		(end 382.750314 -398.38503)
		(width 0.1651)
		(layer "In5.Cu")
		(net "P5E_PEX3_STN5_RX_DN<83>")
	)
	(segment
		(start 398.18691 -358.721152)
		(end 398.18691 -342.044782)
		(width 0.1651)
		(layer "In5.Cu")
		(net "P5E_PEX3_STN5_RX_DN<83>")
	)
	(segment
		(start 398.723104 -370.520722)
		(end 398.483074 -367.558828)
		(width 0.1651)
		(layer "In5.Cu")
		(net "P5E_PEX3_STN5_RX_DN<83>")
	)
	(segment
		(start 408.028648 -327.472294)
		(end 408.967686 -325.343012)
		(width 0.1651)
		(layer "In5.Cu")
		(net "P5E_PEX3_STN5_RX_DN<83>")
	)
	(segment
		(start 382.089914 -398.890236)
		(end 382.089914 -398.51203)
		(width 0.1651)
		(layer "In5.Cu")
		(net "P5E_PEX3_STN5_RX_DN<83>")
	)
	(segment
		(start 398.504664 -386.045964)
		(end 398.723104 -370.520722)
		(width 0.1651)
		(layer "In5.Cu")
		(net "P5E_PEX3_STN5_RX_DN<83>")
	)
	(segment
		(start 275.131276 -154.759914)
		(end 274.343622 -153.97226)
		(width 0.13208)
		(layer "F.Cu")
		(net "NIC4_SLOT_ID0")
	)
	(segment
		(start 271.729962 -153.3144)
		(end 271.207992 -153.3144)
		(width 0.13208)
		(layer "F.Cu")
		(net "NIC4_SLOT_ID0")
	)
	(segment
		(start 278.242268 -154.759914)
		(end 275.131276 -154.759914)
		(width 0.13208)
		(layer "F.Cu")
		(net "NIC4_SLOT_ID0")
	)
	(segment
		(start 272.387822 -153.97226)
		(end 271.729962 -153.3144)
		(width 0.13208)
		(layer "F.Cu")
		(net "NIC4_SLOT_ID0")
	)
	(segment
		(start 274.343622 -153.97226)
		(end 272.387822 -153.97226)
		(width 0.13208)
		(layer "F.Cu")
		(net "NIC4_SLOT_ID0")
	)
	(segment
		(start 271.199864 -153.322528)
		(end 271.207992 -153.3144)
		(width 0.13208)
		(layer "F.Cu")
		(net "NIC4_SLOT_ID0")
	)
	(segment
		(start 271.199864 -154.327352)
		(end 271.199864 -153.322528)
		(width 0.13208)
		(layer "F.Cu")
		(net "NIC4_SLOT_ID0")
	)
	(via
		(at 272.387822 -153.97226)
		(size 0.762)
		(drill 0.381)
		(layers "F.Cu" "B.Cu")
		(net "NIC4_SLOT_ID0")
	)
	(segment
		(start 421.557704 -104.840024)
		(end 423.038016 -104.840024)
		(width 0.13208)
		(layer "F.Cu")
		(net "NCSI_NIC7_CRS_DV")
	)
	(segment
		(start 423.038016 -104.840024)
		(end 423.99204 -103.886)
		(width 0.13208)
		(layer "F.Cu")
		(net "NCSI_NIC7_CRS_DV")
	)
	(via
		(at 423.99204 -103.886)
		(size 0.508)
		(drill 0.254)
		(layers "F.Cu" "B.Cu")
		(net "NCSI_NIC7_CRS_DV")
	)
	(segment
		(start 425.441872 -104.120696)
		(end 424.734736 -104.120696)
		(width 0.13208)
		(layer "B.Cu")
		(net "NCSI_NIC7_CRS_DV")
	)
	(segment
		(start 424.50004 -103.886)
		(end 423.99204 -103.886)
		(width 0.13208)
		(layer "B.Cu")
		(net "NCSI_NIC7_CRS_DV")
	)
	(segment
		(start 424.734736 -104.120696)
		(end 424.50004 -103.886)
		(width 0.13208)
		(layer "B.Cu")
		(net "NCSI_NIC7_CRS_DV")
	)
	(segment
		(start 168.048178 -132.802122)
		(end 168.342564 -133.096508)
		(width 0.13462)
		(layer "F.Cu")
		(net "P5E_PEX1_STN1_RX_DN<29>")
	)
	(segment
		(start 166.742364 -132.964936)
		(end 167.230298 -132.964936)
		(width 0.13462)
		(layer "F.Cu")
		(net "P5E_PEX1_STN1_RX_DN<29>")
	)
	(segment
		(start 167.230298 -132.964936)
		(end 167.393112 -132.802122)
		(width 0.13462)
		(layer "F.Cu")
		(net "P5E_PEX1_STN1_RX_DN<29>")
	)
	(segment
		(start 167.393112 -132.802122)
		(end 168.048178 -132.802122)
		(width 0.13462)
		(layer "F.Cu")
		(net "P5E_PEX1_STN1_RX_DN<29>")
	)
	(segment
		(start 165.165786 -139.66444)
		(end 165.051486 -139.55014)
		(width 0.1651)
		(layer "In5.Cu")
		(net "P5E_PEX1_STN1_RX_DN<29>")
	)
	(segment
		(start 165.165786 -140.15974)
		(end 165.165786 -139.66444)
		(width 0.1651)
		(layer "In5.Cu")
		(net "P5E_PEX1_STN1_RX_DN<29>")
	)
	(segment
		(start 166.796212 -133.839712)
		(end 167.15613 -133.498844)
		(width 0.1651)
		(layer "In5.Cu")
		(net "P5E_PEX1_STN1_RX_DN<29>")
	)
	(segment
		(start 165.165786 -138.44524)
		(end 165.051486 -138.33094)
		(width 0.1651)
		(layer "In5.Cu")
		(net "P5E_PEX1_STN1_RX_DN<29>")
	)
	(segment
		(start 160.176972 -146.13382)
		(end 160.320736 -146.207734)
		(width 0.1651)
		(layer "In5.Cu")
		(net "P5E_PEX1_STN1_RX_DN<29>")
	)
	(segment
		(start 164.377878 -142.396464)
		(end 164.52723 -142.334742)
		(width 0.1651)
		(layer "In5.Cu")
		(net "P5E_PEX1_STN1_RX_DN<29>")
	)
	(segment
		(start 165.051486 -140.27404)
		(end 165.165786 -140.15974)
		(width 0.1651)
		(layer "In5.Cu")
		(net "P5E_PEX1_STN1_RX_DN<29>")
	)
	(segment
		(start 165.165786 -138.94054)
		(end 165.165786 -138.44524)
		(width 0.1651)
		(layer "In5.Cu")
		(net "P5E_PEX1_STN1_RX_DN<29>")
	)
	(segment
		(start 188.0997 -274.999704)
		(end 188.0997 -275.26488)
		(width 0.1143)
		(layer "In5.Cu")
		(net "P5E_PEX1_STN1_RX_DN<29>")
	)
	(segment
		(start 161.338006 -145.761456)
		(end 161.83483 -145.264632)
		(width 0.1651)
		(layer "In5.Cu")
		(net "P5E_PEX1_STN1_RX_DN<29>")
	)
	(segment
		(start 165.518084 -135.866632)
		(end 165.707568 -135.409178)
		(width 0.1651)
		(layer "In5.Cu")
		(net "P5E_PEX1_STN1_RX_DN<29>")
	)
	(segment
		(start 167.626538 -132.892038)
		(end 167.834818 -132.805678)
		(width 0.1651)
		(layer "In5.Cu")
		(net "P5E_PEX1_STN1_RX_DN<29>")
	)
	(segment
		(start 158.110174 -147.823936)
		(end 158.551626 -147.013168)
		(width 0.1651)
		(layer "In5.Cu")
		(net "P5E_PEX1_STN1_RX_DN<29>")
	)
	(segment
		(start 187.823348 -275.379434)
		(end 187.71997 -275.276056)
		(width 0.1143)
		(layer "In5.Cu")
		(net "P5E_PEX1_STN1_RX_DN<29>")
	)
	(segment
		(start 165.051486 -138.33094)
		(end 165.051486 -136.993122)
		(width 0.1651)
		(layer "In5.Cu")
		(net "P5E_PEX1_STN1_RX_DN<29>")
	)
	(segment
		(start 166.181532 -134.2644)
		(end 166.634668 -133.83514)
		(width 0.1651)
		(layer "In5.Cu")
		(net "P5E_PEX1_STN1_RX_DN<29>")
	)
	(segment
		(start 163.419536 -143.745204)
		(end 163.78682 -143.412464)
		(width 0.1651)
		(layer "In5.Cu")
		(net "P5E_PEX1_STN1_RX_DN<29>")
	)
	(segment
		(start 160.792668 -146.056604)
		(end 160.866582 -145.912586)
		(width 0.1651)
		(layer "In5.Cu")
		(net "P5E_PEX1_STN1_RX_DN<29>")
	)
	(segment
		(start 163.258246 -143.73733)
		(end 163.419536 -143.745204)
		(width 0.1651)
		(layer "In5.Cu")
		(net "P5E_PEX1_STN1_RX_DN<29>")
	)
	(segment
		(start 160.866582 -145.912586)
		(end 161.338006 -145.761456)
		(width 0.1651)
		(layer "In5.Cu")
		(net "P5E_PEX1_STN1_RX_DN<29>")
	)
	(segment
		(start 167.834818 -132.805678)
		(end 168.051734 -132.805678)
		(width 0.1651)
		(layer "In5.Cu")
		(net "P5E_PEX1_STN1_RX_DN<29>")
	)
	(segment
		(start 159.415988 -160.843468)
		(end 158.690564 -156.74721)
		(width 0.1651)
		(layer "In5.Cu")
		(net "P5E_PEX1_STN1_RX_DN<29>")
	)
	(segment
		(start 165.707568 -135.409178)
		(end 165.85692 -135.347202)
		(width 0.1651)
		(layer "In5.Cu")
		(net "P5E_PEX1_STN1_RX_DN<29>")
	)
	(segment
		(start 163.78682 -143.412464)
		(end 163.794948 -143.25092)
		(width 0.1651)
		(layer "In5.Cu")
		(net "P5E_PEX1_STN1_RX_DN<29>")
	)
	(segment
		(start 165.85692 -135.347202)
		(end 166.046404 -134.889494)
		(width 0.1651)
		(layer "In5.Cu")
		(net "P5E_PEX1_STN1_RX_DN<29>")
	)
	(segment
		(start 158.739078 -146.783806)
		(end 159.104076 -146.477736)
		(width 0.1651)
		(layer "In5.Cu")
		(net "P5E_PEX1_STN1_RX_DN<29>")
	)
	(segment
		(start 163.794948 -143.25092)
		(end 164.161724 -142.918434)
		(width 0.1651)
		(layer "In5.Cu")
		(net "P5E_PEX1_STN1_RX_DN<29>")
	)
	(segment
		(start 187.76569 -271.802352)
		(end 187.76569 -271.773904)
		(width 0.1143)
		(layer "In5.Cu")
		(net "P5E_PEX1_STN1_RX_DN<29>")
	)
	(segment
		(start 167.160448 -133.337046)
		(end 167.557196 -132.96138)
		(width 0.1651)
		(layer "In5.Cu")
		(net "P5E_PEX1_STN1_RX_DN<29>")
	)
	(segment
		(start 187.71997 -271.848072)
		(end 187.76569 -271.802352)
		(width 0.1143)
		(layer "In5.Cu")
		(net "P5E_PEX1_STN1_RX_DN<29>")
	)
	(segment
		(start 166.634668 -133.83514)
		(end 166.796212 -133.839712)
		(width 0.1651)
		(layer "In5.Cu")
		(net "P5E_PEX1_STN1_RX_DN<29>")
	)
	(segment
		(start 165.051486 -139.55014)
		(end 165.051486 -139.05484)
		(width 0.1651)
		(layer "In5.Cu")
		(net "P5E_PEX1_STN1_RX_DN<29>")
	)
	(segment
		(start 167.15613 -133.498844)
		(end 167.160448 -133.337046)
		(width 0.1651)
		(layer "In5.Cu")
		(net "P5E_PEX1_STN1_RX_DN<29>")
	)
	(segment
		(start 187.76569 -267.461238)
		(end 159.415988 -160.843468)
		(width 0.1651)
		(layer "In5.Cu")
		(net "P5E_PEX1_STN1_RX_DN<29>")
	)
	(segment
		(start 187.985146 -275.379434)
		(end 187.823348 -275.379434)
		(width 0.1143)
		(layer "In5.Cu")
		(net "P5E_PEX1_STN1_RX_DN<29>")
	)
	(segment
		(start 166.046404 -134.889494)
		(end 165.984682 -134.740142)
		(width 0.1651)
		(layer "In5.Cu")
		(net "P5E_PEX1_STN1_RX_DN<29>")
	)
	(segment
		(start 158.551626 -147.013168)
		(end 158.739078 -146.783806)
		(width 0.1651)
		(layer "In5.Cu")
		(net "P5E_PEX1_STN1_RX_DN<29>")
	)
	(segment
		(start 165.051486 -139.05484)
		(end 165.165786 -138.94054)
		(width 0.1651)
		(layer "In5.Cu")
		(net "P5E_PEX1_STN1_RX_DN<29>")
	)
	(segment
		(start 161.83483 -145.264632)
		(end 162.237674 -144.662144)
		(width 0.1651)
		(layer "In5.Cu")
		(net "P5E_PEX1_STN1_RX_DN<29>")
	)
	(segment
		(start 164.716714 -141.87678)
		(end 164.654738 -141.727428)
		(width 0.1651)
		(layer "In5.Cu")
		(net "P5E_PEX1_STN1_RX_DN<29>")
	)
	(segment
		(start 160.320736 -146.207734)
		(end 160.792668 -146.056604)
		(width 0.1651)
		(layer "In5.Cu")
		(net "P5E_PEX1_STN1_RX_DN<29>")
	)
	(segment
		(start 167.557196 -132.96138)
		(end 167.626538 -132.892038)
		(width 0.1651)
		(layer "In5.Cu")
		(net "P5E_PEX1_STN1_RX_DN<29>")
	)
	(segment
		(start 164.161724 -142.918434)
		(end 164.377878 -142.396464)
		(width 0.1651)
		(layer "In5.Cu")
		(net "P5E_PEX1_STN1_RX_DN<29>")
	)
	(segment
		(start 187.71997 -275.276056)
		(end 187.71997 -271.848072)
		(width 0.1143)
		(layer "In5.Cu")
		(net "P5E_PEX1_STN1_RX_DN<29>")
	)
	(segment
		(start 165.390576 -136.473692)
		(end 165.58006 -136.015984)
		(width 0.1651)
		(layer "In5.Cu")
		(net "P5E_PEX1_STN1_RX_DN<29>")
	)
	(segment
		(start 165.24097 -136.535668)
		(end 165.390576 -136.473692)
		(width 0.1651)
		(layer "In5.Cu")
		(net "P5E_PEX1_STN1_RX_DN<29>")
	)
	(segment
		(start 165.051486 -136.993122)
		(end 165.24097 -136.535668)
		(width 0.1651)
		(layer "In5.Cu")
		(net "P5E_PEX1_STN1_RX_DN<29>")
	)
	(segment
		(start 165.58006 -136.015984)
		(end 165.518084 -135.866632)
		(width 0.1651)
		(layer "In5.Cu")
		(net "P5E_PEX1_STN1_RX_DN<29>")
	)
	(segment
		(start 162.237674 -144.662144)
		(end 163.258246 -143.73733)
		(width 0.1651)
		(layer "In5.Cu")
		(net "P5E_PEX1_STN1_RX_DN<29>")
	)
	(segment
		(start 165.051486 -140.76934)
		(end 165.051486 -140.27404)
		(width 0.1651)
		(layer "In5.Cu")
		(net "P5E_PEX1_STN1_RX_DN<29>")
	)
	(segment
		(start 164.52723 -142.334742)
		(end 164.716714 -141.87678)
		(width 0.1651)
		(layer "In5.Cu")
		(net "P5E_PEX1_STN1_RX_DN<29>")
	)
	(segment
		(start 168.051734 -132.805678)
		(end 168.342564 -133.096508)
		(width 0.1651)
		(layer "In5.Cu")
		(net "P5E_PEX1_STN1_RX_DN<29>")
	)
	(segment
		(start 164.654738 -141.727428)
		(end 165.051486 -140.76934)
		(width 0.1651)
		(layer "In5.Cu")
		(net "P5E_PEX1_STN1_RX_DN<29>")
	)
	(segment
		(start 187.76569 -271.773904)
		(end 187.76569 -267.461238)
		(width 0.1651)
		(layer "In5.Cu")
		(net "P5E_PEX1_STN1_RX_DN<29>")
	)
	(segment
		(start 159.104076 -146.477736)
		(end 160.176972 -146.13382)
		(width 0.1651)
		(layer "In5.Cu")
		(net "P5E_PEX1_STN1_RX_DN<29>")
	)
	(segment
		(start 165.984682 -134.740142)
		(end 166.181532 -134.2644)
		(width 0.1651)
		(layer "In5.Cu")
		(net "P5E_PEX1_STN1_RX_DN<29>")
	)
	(segment
		(start 188.0997 -275.26488)
		(end 187.985146 -275.379434)
		(width 0.1143)
		(layer "In5.Cu")
		(net "P5E_PEX1_STN1_RX_DN<29>")
	)
	(segment
		(start 158.690564 -156.74721)
		(end 158.110174 -147.823936)
		(width 0.1651)
		(layer "In5.Cu")
		(net "P5E_PEX1_STN1_RX_DN<29>")
	)
	(segment
		(start 295.033954 -319.8368)
		(end 295.033954 -319.865248)
		(width 0.1143)
		(layer "In9.Cu")
		(net "P5E_PEX2_STN5_RX_DP<85>")
	)
	(segment
		(start 348.311978 -392.20521)
		(end 347.851222 -392.386312)
		(width 0.1651)
		(layer "In9.Cu")
		(net "P5E_PEX2_STN5_RX_DP<85>")
	)
	(segment
		(start 342.617044 -398.09928)
		(end 342.490044 -397.97228)
		(width 0.1651)
		(layer "In9.Cu")
		(net "P5E_PEX2_STN5_RX_DP<85>")
	)
	(segment
		(start 356.417372 -386.255006)
		(end 355.927152 -387.578092)
		(width 0.1651)
		(layer "In9.Cu")
		(net "P5E_PEX2_STN5_RX_DP<85>")
	)
	(segment
		(start 346.763594 -392.813794)
		(end 346.648278 -392.763502)
		(width 0.1651)
		(layer "In9.Cu")
		(net "P5E_PEX2_STN5_RX_DP<85>")
	)
	(segment
		(start 346.136722 -393.060174)
		(end 344.541348 -393.6873)
		(width 0.1651)
		(layer "In9.Cu")
		(net "P5E_PEX2_STN5_RX_DP<85>")
	)
	(segment
		(start 296.950638 -321.908424)
		(end 342.60663 -338.697062)
		(width 0.1651)
		(layer "In9.Cu")
		(net "P5E_PEX2_STN5_RX_DP<85>")
	)
	(segment
		(start 343.334086 -395.627098)
		(end 343.334086 -397.601694)
		(width 0.1651)
		(layer "In9.Cu")
		(net "P5E_PEX2_STN5_RX_DP<85>")
	)
	(segment
		(start 356.492048 -368.9096)
		(end 356.710996 -370.226336)
		(width 0.1651)
		(layer "In9.Cu")
		(net "P5E_PEX2_STN5_RX_DP<85>")
	)
	(segment
		(start 346.648278 -392.763502)
		(end 346.187014 -392.944858)
		(width 0.1651)
		(layer "In9.Cu")
		(net "P5E_PEX2_STN5_RX_DP<85>")
	)
	(segment
		(start 348.36227 -392.089894)
		(end 348.311978 -392.20521)
		(width 0.1651)
		(layer "In9.Cu")
		(net "P5E_PEX2_STN5_RX_DP<85>")
	)
	(segment
		(start 347.22435 -392.632692)
		(end 346.763594 -392.813794)
		(width 0.1651)
		(layer "In9.Cu")
		(net "P5E_PEX2_STN5_RX_DP<85>")
	)
	(segment
		(start 346.187014 -392.944858)
		(end 346.136722 -393.060174)
		(width 0.1651)
		(layer "In9.Cu")
		(net "P5E_PEX2_STN5_RX_DP<85>")
	)
	(segment
		(start 295.649904 -317.749936)
		(end 295.649904 -318.040766)
		(width 0.1143)
		(layer "In9.Cu")
		(net "P5E_PEX2_STN5_RX_DP<85>")
	)
	(segment
		(start 295.079674 -318.355218)
		(end 295.079674 -319.79108)
		(width 0.1143)
		(layer "In9.Cu")
		(net "P5E_PEX2_STN5_RX_DP<85>")
	)
	(segment
		(start 343.860882 -394.367766)
		(end 343.334086 -395.627098)
		(width 0.1651)
		(layer "In9.Cu")
		(net "P5E_PEX2_STN5_RX_DP<85>")
	)
	(segment
		(start 347.274642 -392.517376)
		(end 347.22435 -392.632692)
		(width 0.1651)
		(layer "In9.Cu")
		(net "P5E_PEX2_STN5_RX_DP<85>")
	)
	(segment
		(start 296.450766 -321.5894)
		(end 296.950638 -321.908424)
		(width 0.1651)
		(layer "In9.Cu")
		(net "P5E_PEX2_STN5_RX_DP<85>")
	)
	(segment
		(start 295.561004 -318.129666)
		(end 295.305226 -318.129666)
		(width 0.1143)
		(layer "In9.Cu")
		(net "P5E_PEX2_STN5_RX_DP<85>")
	)
	(segment
		(start 295.033954 -320.172334)
		(end 296.450766 -321.5894)
		(width 0.1651)
		(layer "In9.Cu")
		(net "P5E_PEX2_STN5_RX_DP<85>")
	)
	(segment
		(start 342.8365 -398.09928)
		(end 342.617044 -398.09928)
		(width 0.1651)
		(layer "In9.Cu")
		(net "P5E_PEX2_STN5_RX_DP<85>")
	)
	(segment
		(start 354.52431 -389.275066)
		(end 353.051364 -390.34212)
		(width 0.1651)
		(layer "In9.Cu")
		(net "P5E_PEX2_STN5_RX_DP<85>")
	)
	(segment
		(start 347.851222 -392.386312)
		(end 347.735906 -392.33602)
		(width 0.1651)
		(layer "In9.Cu")
		(net "P5E_PEX2_STN5_RX_DP<85>")
	)
	(segment
		(start 344.541348 -393.6873)
		(end 343.860882 -394.367766)
		(width 0.1651)
		(layer "In9.Cu")
		(net "P5E_PEX2_STN5_RX_DP<85>")
	)
	(segment
		(start 295.649904 -318.040766)
		(end 295.561004 -318.129666)
		(width 0.1143)
		(layer "In9.Cu")
		(net "P5E_PEX2_STN5_RX_DP<85>")
	)
	(segment
		(start 295.033954 -319.865248)
		(end 295.033954 -320.172334)
		(width 0.1651)
		(layer "In9.Cu")
		(net "P5E_PEX2_STN5_RX_DP<85>")
	)
	(segment
		(start 347.735906 -392.33602)
		(end 347.274642 -392.517376)
		(width 0.1651)
		(layer "In9.Cu")
		(net "P5E_PEX2_STN5_RX_DP<85>")
	)
	(segment
		(start 356.710996 -370.226336)
		(end 356.417372 -386.255006)
		(width 0.1651)
		(layer "In9.Cu")
		(net "P5E_PEX2_STN5_RX_DP<85>")
	)
	(segment
		(start 344.96121 -340.157816)
		(end 346.027248 -341.175848)
		(width 0.1651)
		(layer "In9.Cu")
		(net "P5E_PEX2_STN5_RX_DP<85>")
	)
	(segment
		(start 348.93885 -391.95883)
		(end 348.823534 -391.908538)
		(width 0.1651)
		(layer "In9.Cu")
		(net "P5E_PEX2_STN5_RX_DP<85>")
	)
	(segment
		(start 353.051364 -390.34212)
		(end 348.93885 -391.95883)
		(width 0.1651)
		(layer "In9.Cu")
		(net "P5E_PEX2_STN5_RX_DP<85>")
	)
	(segment
		(start 295.305226 -318.129666)
		(end 295.079674 -318.355218)
		(width 0.1143)
		(layer "In9.Cu")
		(net "P5E_PEX2_STN5_RX_DP<85>")
	)
	(segment
		(start 348.823534 -391.908538)
		(end 348.36227 -392.089894)
		(width 0.1651)
		(layer "In9.Cu")
		(net "P5E_PEX2_STN5_RX_DP<85>")
	)
	(segment
		(start 295.079674 -319.79108)
		(end 295.033954 -319.8368)
		(width 0.1143)
		(layer "In9.Cu")
		(net "P5E_PEX2_STN5_RX_DP<85>")
	)
	(segment
		(start 342.490044 -397.97228)
		(end 342.490044 -397.59001)
		(width 0.1651)
		(layer "In9.Cu")
		(net "P5E_PEX2_STN5_RX_DP<85>")
	)
	(segment
		(start 343.334086 -397.601694)
		(end 342.8365 -398.09928)
		(width 0.1651)
		(layer "In9.Cu")
		(net "P5E_PEX2_STN5_RX_DP<85>")
	)
	(segment
		(start 342.60663 -338.697062)
		(end 344.96121 -340.157816)
		(width 0.1651)
		(layer "In9.Cu")
		(net "P5E_PEX2_STN5_RX_DP<85>")
	)
	(segment
		(start 346.027248 -341.175848)
		(end 356.492048 -368.9096)
		(width 0.1651)
		(layer "In9.Cu")
		(net "P5E_PEX2_STN5_RX_DP<85>")
	)
	(segment
		(start 355.927152 -387.578092)
		(end 354.52431 -389.275066)
		(width 0.1651)
		(layer "In9.Cu")
		(net "P5E_PEX2_STN5_RX_DP<85>")
	)
	(segment
		(start 415.652966 -134.08152)
		(end 415.35731 -134.377176)
		(width 0.13462)
		(layer "F.Cu")
		(net "P5E_PEX3_STN0_RX_DP<6>")
	)
	(segment
		(start 416.95751 -134.245096)
		(end 416.478466 -134.245096)
		(width 0.13462)
		(layer "F.Cu")
		(net "P5E_PEX3_STN0_RX_DP<6>")
	)
	(segment
		(start 416.31489 -134.08152)
		(end 415.652966 -134.08152)
		(width 0.13462)
		(layer "F.Cu")
		(net "P5E_PEX3_STN0_RX_DP<6>")
	)
	(segment
		(start 416.478466 -134.245096)
		(end 416.31489 -134.08152)
		(width 0.13462)
		(layer "F.Cu")
		(net "P5E_PEX3_STN0_RX_DP<6>")
	)
	(segment
		(start 421.483536 -137.04316)
		(end 421.047164 -136.808972)
		(width 0.1651)
		(layer "In5.Cu")
		(net "P5E_PEX3_STN0_RX_DP<6>")
	)
	(segment
		(start 432.15052 -282.029662)
		(end 432.19624 -281.983942)
		(width 0.1143)
		(layer "In5.Cu")
		(net "P5E_PEX3_STN0_RX_DP<6>")
	)
	(segment
		(start 418.443918 -135.541258)
		(end 418.007292 -135.306816)
		(width 0.1651)
		(layer "In5.Cu")
		(net "P5E_PEX3_STN0_RX_DP<6>")
	)
	(segment
		(start 424.9039 -139.813284)
		(end 424.767248 -139.025376)
		(width 0.1651)
		(layer "In5.Cu")
		(net "P5E_PEX3_STN0_RX_DP<6>")
	)
	(segment
		(start 421.530018 -137.197846)
		(end 421.483536 -137.04316)
		(width 0.1651)
		(layer "In5.Cu")
		(net "P5E_PEX3_STN0_RX_DP<6>")
	)
	(segment
		(start 415.975546 -134.086346)
		(end 415.64814 -134.086346)
		(width 0.1651)
		(layer "In5.Cu")
		(net "P5E_PEX3_STN0_RX_DP<6>")
	)
	(segment
		(start 428.523654 -282.029662)
		(end 432.15052 -282.029662)
		(width 0.1143)
		(layer "In5.Cu")
		(net "P5E_PEX3_STN0_RX_DP<6>")
	)
	(segment
		(start 424.9039 -140.932662)
		(end 424.9039 -139.813284)
		(width 0.1651)
		(layer "In5.Cu")
		(net "P5E_PEX3_STN0_RX_DP<6>")
	)
	(segment
		(start 417.524438 -134.917942)
		(end 417.369752 -134.964678)
		(width 0.1651)
		(layer "In5.Cu")
		(net "P5E_PEX3_STN0_RX_DP<6>")
	)
	(segment
		(start 415.64814 -134.086346)
		(end 415.35731 -134.377176)
		(width 0.1651)
		(layer "In5.Cu")
		(net "P5E_PEX3_STN0_RX_DP<6>")
	)
	(segment
		(start 423.196004 -137.96264)
		(end 423.041064 -138.009122)
		(width 0.1651)
		(layer "In5.Cu")
		(net "P5E_PEX3_STN0_RX_DP<6>")
	)
	(segment
		(start 417.96081 -135.15213)
		(end 417.524438 -134.917942)
		(width 0.1651)
		(layer "In5.Cu")
		(net "P5E_PEX3_STN0_RX_DP<6>")
	)
	(segment
		(start 420.409116 -136.46658)
		(end 419.673278 -136.07161)
		(width 0.1651)
		(layer "In5.Cu")
		(net "P5E_PEX3_STN0_RX_DP<6>")
	)
	(segment
		(start 432.19624 -281.983942)
		(end 432.224688 -281.983942)
		(width 0.1143)
		(layer "In5.Cu")
		(net "P5E_PEX3_STN0_RX_DP<6>")
	)
	(segment
		(start 432.55057 -281.983942)
		(end 433.115212 -281.606244)
		(width 0.1651)
		(layer "In5.Cu")
		(net "P5E_PEX3_STN0_RX_DP<6>")
	)
	(segment
		(start 417.369752 -134.964678)
		(end 416.933126 -134.729982)
		(width 0.1651)
		(layer "In5.Cu")
		(net "P5E_PEX3_STN0_RX_DP<6>")
	)
	(segment
		(start 428.256192 -160.27273)
		(end 424.9039 -140.932662)
		(width 0.1651)
		(layer "In5.Cu")
		(net "P5E_PEX3_STN0_RX_DP<6>")
	)
	(segment
		(start 428.27956 -282.485592)
		(end 428.27956 -282.273756)
		(width 0.1143)
		(layer "In5.Cu")
		(net "P5E_PEX3_STN0_RX_DP<6>")
	)
	(segment
		(start 419.03523 -135.728964)
		(end 418.598858 -135.494776)
		(width 0.1651)
		(layer "In5.Cu")
		(net "P5E_PEX3_STN0_RX_DP<6>")
	)
	(segment
		(start 421.047164 -136.808972)
		(end 420.892224 -136.855708)
		(width 0.1651)
		(layer "In5.Cu")
		(net "P5E_PEX3_STN0_RX_DP<6>")
	)
	(segment
		(start 416.933126 -134.729982)
		(end 416.88639 -134.575296)
		(width 0.1651)
		(layer "In5.Cu")
		(net "P5E_PEX3_STN0_RX_DP<6>")
	)
	(segment
		(start 418.007292 -135.306816)
		(end 417.96081 -135.15213)
		(width 0.1651)
		(layer "In5.Cu")
		(net "P5E_PEX3_STN0_RX_DP<6>")
	)
	(segment
		(start 419.518338 -136.118092)
		(end 419.081712 -135.88365)
		(width 0.1651)
		(layer "In5.Cu")
		(net "P5E_PEX3_STN0_RX_DP<6>")
	)
	(segment
		(start 433.555902 -281.074368)
		(end 433.764436 -280.582116)
		(width 0.1651)
		(layer "In5.Cu")
		(net "P5E_PEX3_STN0_RX_DP<6>")
	)
	(segment
		(start 422.557956 -137.619994)
		(end 422.121584 -137.385806)
		(width 0.1651)
		(layer "In5.Cu")
		(net "P5E_PEX3_STN0_RX_DP<6>")
	)
	(segment
		(start 419.081712 -135.88365)
		(end 419.03523 -135.728964)
		(width 0.1651)
		(layer "In5.Cu")
		(net "P5E_PEX3_STN0_RX_DP<6>")
	)
	(segment
		(start 421.966644 -137.432288)
		(end 421.530018 -137.197846)
		(width 0.1651)
		(layer "In5.Cu")
		(net "P5E_PEX3_STN0_RX_DP<6>")
	)
	(segment
		(start 423.041064 -138.009122)
		(end 422.604438 -137.77468)
		(width 0.1651)
		(layer "In5.Cu")
		(net "P5E_PEX3_STN0_RX_DP<6>")
	)
	(segment
		(start 432.728624 -270.821404)
		(end 431.812192 -264.723118)
		(width 0.1651)
		(layer "In5.Cu")
		(net "P5E_PEX3_STN0_RX_DP<6>")
	)
	(segment
		(start 433.851304 -277.085552)
		(end 433.851304 -276.721316)
		(width 0.1651)
		(layer "In5.Cu")
		(net "P5E_PEX3_STN0_RX_DP<6>")
	)
	(segment
		(start 419.673278 -136.07161)
		(end 419.518338 -136.118092)
		(width 0.1651)
		(layer "In5.Cu")
		(net "P5E_PEX3_STN0_RX_DP<6>")
	)
	(segment
		(start 420.892224 -136.855708)
		(end 420.455598 -136.621266)
		(width 0.1651)
		(layer "In5.Cu")
		(net "P5E_PEX3_STN0_RX_DP<6>")
	)
	(segment
		(start 416.88639 -134.575296)
		(end 415.975546 -134.086346)
		(width 0.1651)
		(layer "In5.Cu")
		(net "P5E_PEX3_STN0_RX_DP<6>")
	)
	(segment
		(start 420.455598 -136.621266)
		(end 420.409116 -136.46658)
		(width 0.1651)
		(layer "In5.Cu")
		(net "P5E_PEX3_STN0_RX_DP<6>")
	)
	(segment
		(start 431.812192 -264.723118)
		(end 428.256192 -160.27273)
		(width 0.1651)
		(layer "In5.Cu")
		(net "P5E_PEX3_STN0_RX_DP<6>")
	)
	(segment
		(start 433.851304 -276.721316)
		(end 432.728624 -270.821404)
		(width 0.1651)
		(layer "In5.Cu")
		(net "P5E_PEX3_STN0_RX_DP<6>")
	)
	(segment
		(start 428.16526 -282.599892)
		(end 428.27956 -282.485592)
		(width 0.1143)
		(layer "In5.Cu")
		(net "P5E_PEX3_STN0_RX_DP<6>")
	)
	(segment
		(start 427.89983 -282.599892)
		(end 428.16526 -282.599892)
		(width 0.1143)
		(layer "In5.Cu")
		(net "P5E_PEX3_STN0_RX_DP<6>")
	)
	(segment
		(start 423.196258 -137.96264)
		(end 423.196004 -137.96264)
		(width 0.1651)
		(layer "In5.Cu")
		(net "P5E_PEX3_STN0_RX_DP<6>")
	)
	(segment
		(start 422.604438 -137.77468)
		(end 422.557956 -137.619994)
		(width 0.1651)
		(layer "In5.Cu")
		(net "P5E_PEX3_STN0_RX_DP<6>")
	)
	(segment
		(start 433.764436 -280.582116)
		(end 433.851304 -277.085552)
		(width 0.1651)
		(layer "In5.Cu")
		(net "P5E_PEX3_STN0_RX_DP<6>")
	)
	(segment
		(start 432.224688 -281.983942)
		(end 432.55057 -281.983942)
		(width 0.1651)
		(layer "In5.Cu")
		(net "P5E_PEX3_STN0_RX_DP<6>")
	)
	(segment
		(start 418.598858 -135.494776)
		(end 418.443918 -135.541258)
		(width 0.1651)
		(layer "In5.Cu")
		(net "P5E_PEX3_STN0_RX_DP<6>")
	)
	(segment
		(start 433.115212 -281.606244)
		(end 433.555902 -281.074368)
		(width 0.1651)
		(layer "In5.Cu")
		(net "P5E_PEX3_STN0_RX_DP<6>")
	)
	(segment
		(start 428.27956 -282.273756)
		(end 428.523654 -282.029662)
		(width 0.1143)
		(layer "In5.Cu")
		(net "P5E_PEX3_STN0_RX_DP<6>")
	)
	(segment
		(start 422.121584 -137.385806)
		(end 421.966644 -137.432288)
		(width 0.1651)
		(layer "In5.Cu")
		(net "P5E_PEX3_STN0_RX_DP<6>")
	)
	(segment
		(start 424.430698 -138.625326)
		(end 423.196258 -137.96264)
		(width 0.1651)
		(layer "In5.Cu")
		(net "P5E_PEX3_STN0_RX_DP<6>")
	)
	(segment
		(start 424.767248 -139.025376)
		(end 424.430698 -138.625326)
		(width 0.1651)
		(layer "In5.Cu")
		(net "P5E_PEX3_STN0_RX_DP<6>")
	)
	(segment
		(start 390.136888 -344.53957)
		(end 390.136888 -345.169998)
		(width 0.13462)
		(layer "F.Cu")
		(net "P5E_PEX3_STN5_TX_C_DP<88>")
	)
	(segment
		(start 390.136888 -345.169998)
		(end 389.84174 -345.465146)
		(width 0.13462)
		(layer "F.Cu")
		(net "P5E_PEX3_STN5_TX_C_DP<88>")
	)
	(segment
		(start 389.81634 -344.219022)
		(end 390.136888 -344.53957)
		(width 0.13462)
		(layer "F.Cu")
		(net "P5E_PEX3_STN5_TX_C_DP<88>")
	)
	(segment
		(start 387.862318 -359.468674)
		(end 381.557276 -364.532418)
		(width 0.1651)
		(layer "In13.Cu")
		(net "P5E_PEX3_STN5_TX_C_DP<88>")
	)
	(segment
		(start 377.142756 -368.078004)
		(end 376.33402 -369.765326)
		(width 0.1651)
		(layer "In13.Cu")
		(net "P5E_PEX3_STN5_TX_C_DP<88>")
	)
	(segment
		(start 376.33402 -378.512324)
		(end 376.047254 -378.79909)
		(width 0.1651)
		(layer "In13.Cu")
		(net "P5E_PEX3_STN5_TX_C_DP<88>")
	)
	(segment
		(start 379.223778 -366.292638)
		(end 379.210062 -366.417606)
		(width 0.1651)
		(layer "In13.Cu")
		(net "P5E_PEX3_STN5_TX_C_DP<88>")
	)
	(segment
		(start 376.33402 -369.765326)
		(end 376.33402 -378.512324)
		(width 0.1651)
		(layer "In13.Cu")
		(net "P5E_PEX3_STN5_TX_C_DP<88>")
	)
	(segment
		(start 381.557276 -364.532418)
		(end 381.432308 -364.518702)
		(width 0.1651)
		(layer "In13.Cu")
		(net "P5E_PEX3_STN5_TX_C_DP<88>")
	)
	(segment
		(start 375.489978 -378.67209)
		(end 375.489978 -378.290074)
		(width 0.1651)
		(layer "In13.Cu")
		(net "P5E_PEX3_STN5_TX_C_DP<88>")
	)
	(segment
		(start 388.57809 -347.764354)
		(end 388.57809 -357.976678)
		(width 0.1651)
		(layer "In13.Cu")
		(net "P5E_PEX3_STN5_TX_C_DP<88>")
	)
	(segment
		(start 381.032258 -364.954058)
		(end 380.646178 -365.264192)
		(width 0.1651)
		(layer "In13.Cu")
		(net "P5E_PEX3_STN5_TX_C_DP<88>")
	)
	(segment
		(start 388.57809 -357.976678)
		(end 387.862318 -359.468674)
		(width 0.1651)
		(layer "In13.Cu")
		(net "P5E_PEX3_STN5_TX_C_DP<88>")
	)
	(segment
		(start 380.12116 -365.685832)
		(end 379.73508 -365.995966)
		(width 0.1651)
		(layer "In13.Cu")
		(net "P5E_PEX3_STN5_TX_C_DP<88>")
	)
	(segment
		(start 379.73508 -365.995966)
		(end 379.610112 -365.98225)
		(width 0.1651)
		(layer "In13.Cu")
		(net "P5E_PEX3_STN5_TX_C_DP<88>")
	)
	(segment
		(start 379.210062 -366.417606)
		(end 377.142756 -368.078004)
		(width 0.1651)
		(layer "In13.Cu")
		(net "P5E_PEX3_STN5_TX_C_DP<88>")
	)
	(segment
		(start 379.610112 -365.98225)
		(end 379.223778 -366.292638)
		(width 0.1651)
		(layer "In13.Cu")
		(net "P5E_PEX3_STN5_TX_C_DP<88>")
	)
	(segment
		(start 390.13257 -345.755976)
		(end 390.13257 -346.209874)
		(width 0.1651)
		(layer "In13.Cu")
		(net "P5E_PEX3_STN5_TX_C_DP<88>")
	)
	(segment
		(start 380.52121 -365.250476)
		(end 380.134876 -365.560864)
		(width 0.1651)
		(layer "In13.Cu")
		(net "P5E_PEX3_STN5_TX_C_DP<88>")
	)
	(segment
		(start 390.13257 -346.209874)
		(end 388.57809 -347.764354)
		(width 0.1651)
		(layer "In13.Cu")
		(net "P5E_PEX3_STN5_TX_C_DP<88>")
	)
	(segment
		(start 381.045974 -364.82909)
		(end 381.032258 -364.954058)
		(width 0.1651)
		(layer "In13.Cu")
		(net "P5E_PEX3_STN5_TX_C_DP<88>")
	)
	(segment
		(start 381.432308 -364.518702)
		(end 381.045974 -364.82909)
		(width 0.1651)
		(layer "In13.Cu")
		(net "P5E_PEX3_STN5_TX_C_DP<88>")
	)
	(segment
		(start 389.84174 -345.465146)
		(end 390.13257 -345.755976)
		(width 0.1651)
		(layer "In13.Cu")
		(net "P5E_PEX3_STN5_TX_C_DP<88>")
	)
	(segment
		(start 380.134876 -365.560864)
		(end 380.12116 -365.685832)
		(width 0.1651)
		(layer "In13.Cu")
		(net "P5E_PEX3_STN5_TX_C_DP<88>")
	)
	(segment
		(start 376.047254 -378.79909)
		(end 375.616978 -378.79909)
		(width 0.1651)
		(layer "In13.Cu")
		(net "P5E_PEX3_STN5_TX_C_DP<88>")
	)
	(segment
		(start 375.616978 -378.79909)
		(end 375.489978 -378.67209)
		(width 0.1651)
		(layer "In13.Cu")
		(net "P5E_PEX3_STN5_TX_C_DP<88>")
	)
	(segment
		(start 380.646178 -365.264192)
		(end 380.52121 -365.250476)
		(width 0.1651)
		(layer "In13.Cu")
		(net "P5E_PEX3_STN5_TX_C_DP<88>")
	)
	(segment
		(start 282.842462 -155.360116)
		(end 283.711904 -155.360116)
		(width 0.13208)
		(layer "F.Cu")
		(net "NIC4_SLOT_ID1")
	)
	(segment
		(start 283.711904 -155.360116)
		(end 283.950156 -155.598368)
		(width 0.13208)
		(layer "F.Cu")
		(net "NIC4_SLOT_ID1")
	)
	(via
		(at 283.950156 -155.598368)
		(size 0.508)
		(drill 0.254)
		(layers "F.Cu" "B.Cu")
		(net "NIC4_SLOT_ID1")
	)
	(segment
		(start 282.563316 -155.0416)
		(end 283.120084 -155.598368)
		(width 0.13208)
		(layer "B.Cu")
		(net "NIC4_SLOT_ID1")
	)
	(segment
		(start 283.120084 -155.598368)
		(end 283.950156 -155.598368)
		(width 0.13208)
		(layer "B.Cu")
		(net "NIC4_SLOT_ID1")
	)
	(segment
		(start 282.155392 -155.0416)
		(end 282.563316 -155.0416)
		(width 0.13208)
		(layer "B.Cu")
		(net "NIC4_SLOT_ID1")
	)
	(segment
		(start 282.155392 -156.0576)
		(end 282.155392 -155.0416)
		(width 0.13208)
		(layer "B.Cu")
		(net "NIC4_SLOT_ID1")
	)
	(segment
		(start 425.144946 -158.219648)
		(end 427.232064 -158.219648)
		(width 0.13208)
		(layer "F.Cu")
		(net "PRSNTB3_NIC7_N")
	)
	(segment
		(start 427.232064 -158.219648)
		(end 428.43958 -158.219648)
		(width 0.13208)
		(layer "F.Cu")
		(net "PRSNTB3_NIC7_N")
	)
	(segment
		(start 428.43958 -159.235648)
		(end 428.43958 -158.219648)
		(width 0.13208)
		(layer "F.Cu")
		(net "PRSNTB3_NIC7_N")
	)
	(segment
		(start 421.557704 -158.35503)
		(end 425.009564 -158.35503)
		(width 0.13208)
		(layer "F.Cu")
		(net "PRSNTB3_NIC7_N")
	)
	(segment
		(start 425.009564 -158.35503)
		(end 425.144946 -158.219648)
		(width 0.13208)
		(layer "F.Cu")
		(net "PRSNTB3_NIC7_N")
	)
	(via
		(at 427.232064 -158.219648)
		(size 0.762)
		(drill 0.381)
		(layers "F.Cu" "B.Cu")
		(net "PRSNTB3_NIC7_N")
	)
	(segment
		(start 168.04767 -108.60786)
		(end 167.393112 -108.60786)
		(width 0.13462)
		(layer "F.Cu")
		(net "P5E_PEX1_STN1_RX_DP<21>")
	)
	(segment
		(start 168.342564 -108.312712)
		(end 168.342564 -108.312966)
		(width 0.13462)
		(layer "F.Cu")
		(net "P5E_PEX1_STN1_RX_DP<21>")
	)
	(segment
		(start 168.342564 -108.312966)
		(end 168.04767 -108.60786)
		(width 0.13462)
		(layer "F.Cu")
		(net "P5E_PEX1_STN1_RX_DP<21>")
	)
	(segment
		(start 167.230298 -108.445046)
		(end 166.742364 -108.445046)
		(width 0.13462)
		(layer "F.Cu")
		(net "P5E_PEX1_STN1_RX_DP<21>")
	)
	(segment
		(start 167.393112 -108.60786)
		(end 167.230298 -108.445046)
		(width 0.13462)
		(layer "F.Cu")
		(net "P5E_PEX1_STN1_RX_DP<21>")
	)
	(segment
		(start 157.845252 -115.056158)
		(end 155.732988 -124.282962)
		(width 0.1651)
		(layer "In5.Cu")
		(net "P5E_PEX1_STN1_RX_DP<21>")
	)
	(segment
		(start 180.144674 -275.569934)
		(end 180.385466 -275.569934)
		(width 0.1143)
		(layer "In5.Cu")
		(net "P5E_PEX1_STN1_RX_DP<21>")
	)
	(segment
		(start 179.88407 -269.183104)
		(end 179.88407 -271.570704)
		(width 0.1651)
		(layer "In5.Cu")
		(net "P5E_PEX1_STN1_RX_DP<21>")
	)
	(segment
		(start 179.92979 -275.35505)
		(end 180.144674 -275.569934)
		(width 0.1143)
		(layer "In5.Cu")
		(net "P5E_PEX1_STN1_RX_DP<21>")
	)
	(segment
		(start 179.88407 -271.599152)
		(end 179.92979 -271.644872)
		(width 0.1143)
		(layer "In5.Cu")
		(net "P5E_PEX1_STN1_RX_DP<21>")
	)
	(segment
		(start 180.499766 -275.684234)
		(end 180.499766 -275.949664)
		(width 0.1143)
		(layer "In5.Cu")
		(net "P5E_PEX1_STN1_RX_DP<21>")
	)
	(segment
		(start 155.732988 -124.282962)
		(end 152.371044 -132.111496)
		(width 0.1651)
		(layer "In5.Cu")
		(net "P5E_PEX1_STN1_RX_DP<21>")
	)
	(segment
		(start 149.191472 -150.66772)
		(end 149.679152 -158.54426)
		(width 0.1651)
		(layer "In5.Cu")
		(net "P5E_PEX1_STN1_RX_DP<21>")
	)
	(segment
		(start 151.186642 -139.663932)
		(end 149.191472 -150.66772)
		(width 0.1651)
		(layer "In5.Cu")
		(net "P5E_PEX1_STN1_RX_DP<21>")
	)
	(segment
		(start 180.385466 -275.569934)
		(end 180.499766 -275.684234)
		(width 0.1143)
		(layer "In5.Cu")
		(net "P5E_PEX1_STN1_RX_DP<21>")
	)
	(segment
		(start 158.652972 -113.706656)
		(end 158.546038 -113.810542)
		(width 0.1651)
		(layer "In5.Cu")
		(net "P5E_PEX1_STN1_RX_DP<21>")
	)
	(segment
		(start 158.546038 -113.810542)
		(end 157.845252 -115.056158)
		(width 0.1651)
		(layer "In5.Cu")
		(net "P5E_PEX1_STN1_RX_DP<21>")
	)
	(segment
		(start 179.92979 -271.644872)
		(end 179.92979 -275.35505)
		(width 0.1143)
		(layer "In5.Cu")
		(net "P5E_PEX1_STN1_RX_DP<21>")
	)
	(segment
		(start 152.371044 -132.111496)
		(end 152.371044 -136.383268)
		(width 0.1651)
		(layer "In5.Cu")
		(net "P5E_PEX1_STN1_RX_DP<21>")
	)
	(segment
		(start 167.648382 -108.603542)
		(end 158.652972 -113.706656)
		(width 0.1651)
		(layer "In5.Cu")
		(net "P5E_PEX1_STN1_RX_DP<21>")
	)
	(segment
		(start 168.342564 -108.312712)
		(end 168.051734 -108.603542)
		(width 0.1651)
		(layer "In5.Cu")
		(net "P5E_PEX1_STN1_RX_DP<21>")
	)
	(segment
		(start 150.736046 -164.671756)
		(end 179.88407 -269.183104)
		(width 0.1651)
		(layer "In5.Cu")
		(net "P5E_PEX1_STN1_RX_DP<21>")
	)
	(segment
		(start 152.371044 -136.383268)
		(end 151.186642 -139.663932)
		(width 0.1651)
		(layer "In5.Cu")
		(net "P5E_PEX1_STN1_RX_DP<21>")
	)
	(segment
		(start 168.051734 -108.603542)
		(end 167.648382 -108.603542)
		(width 0.1651)
		(layer "In5.Cu")
		(net "P5E_PEX1_STN1_RX_DP<21>")
	)
	(segment
		(start 149.679152 -158.54426)
		(end 150.736046 -164.671756)
		(width 0.1651)
		(layer "In5.Cu")
		(net "P5E_PEX1_STN1_RX_DP<21>")
	)
	(segment
		(start 179.88407 -271.570704)
		(end 179.88407 -271.599152)
		(width 0.1143)
		(layer "In5.Cu")
		(net "P5E_PEX1_STN1_RX_DP<21>")
	)
	(segment
		(start 121.483628 -357.46309)
		(end 121.483628 -356.831646)
		(width 0.13462)
		(layer "F.Cu")
		(net "P5E_PEX1_STN6_TX_C_DP<98>")
	)
	(segment
		(start 121.188988 -357.75773)
		(end 121.483628 -357.46309)
		(width 0.13462)
		(layer "F.Cu")
		(net "P5E_PEX1_STN6_TX_C_DP<98>")
	)
	(segment
		(start 121.483628 -356.831646)
		(end 121.163588 -356.511606)
		(width 0.13462)
		(layer "F.Cu")
		(net "P5E_PEX1_STN6_TX_C_DP<98>")
	)
	(segment
		(start 127.687578 -369.410234)
		(end 127.461264 -368.66449)
		(width 0.1651)
		(layer "In7.Cu")
		(net "P5E_PEX1_STN6_TX_C_DP<98>")
	)
	(segment
		(start 127.037084 -383.798826)
		(end 127.26924 -383.798826)
		(width 0.1651)
		(layer "In7.Cu")
		(net "P5E_PEX1_STN6_TX_C_DP<98>")
	)
	(segment
		(start 125.668786 -366.118902)
		(end 125.689614 -366.013238)
		(width 0.1651)
		(layer "In7.Cu")
		(net "P5E_PEX1_STN6_TX_C_DP<98>")
	)
	(segment
		(start 127.687578 -383.380488)
		(end 127.687578 -369.410234)
		(width 0.1651)
		(layer "In7.Cu")
		(net "P5E_PEX1_STN6_TX_C_DP<98>")
	)
	(segment
		(start 126.324868 -366.963706)
		(end 126.049786 -366.551972)
		(width 0.1651)
		(layer "In7.Cu")
		(net "P5E_PEX1_STN6_TX_C_DP<98>")
	)
	(segment
		(start 127.26924 -383.798826)
		(end 127.687578 -383.380488)
		(width 0.1651)
		(layer "In7.Cu")
		(net "P5E_PEX1_STN6_TX_C_DP<98>")
	)
	(segment
		(start 126.049786 -366.551972)
		(end 125.944122 -366.53089)
		(width 0.1651)
		(layer "In7.Cu")
		(net "P5E_PEX1_STN6_TX_C_DP<98>")
	)
	(segment
		(start 121.479818 -359.712514)
		(end 121.479818 -358.04856)
		(width 0.1651)
		(layer "In7.Cu")
		(net "P5E_PEX1_STN6_TX_C_DP<98>")
	)
	(segment
		(start 125.944122 -366.53089)
		(end 125.668786 -366.118902)
		(width 0.1651)
		(layer "In7.Cu")
		(net "P5E_PEX1_STN6_TX_C_DP<98>")
	)
	(segment
		(start 126.910084 -383.290064)
		(end 126.910084 -383.671826)
		(width 0.1651)
		(layer "In7.Cu")
		(net "P5E_PEX1_STN6_TX_C_DP<98>")
	)
	(segment
		(start 126.910084 -383.671826)
		(end 127.037084 -383.798826)
		(width 0.1651)
		(layer "In7.Cu")
		(net "P5E_PEX1_STN6_TX_C_DP<98>")
	)
	(segment
		(start 126.684786 -367.50244)
		(end 126.579122 -367.481358)
		(width 0.1651)
		(layer "In7.Cu")
		(net "P5E_PEX1_STN6_TX_C_DP<98>")
	)
	(segment
		(start 127.461264 -368.66449)
		(end 126.684786 -367.50244)
		(width 0.1651)
		(layer "In7.Cu")
		(net "P5E_PEX1_STN6_TX_C_DP<98>")
	)
	(segment
		(start 125.689614 -366.013238)
		(end 121.479818 -359.712514)
		(width 0.1651)
		(layer "In7.Cu")
		(net "P5E_PEX1_STN6_TX_C_DP<98>")
	)
	(segment
		(start 121.479818 -358.04856)
		(end 121.188988 -357.75773)
		(width 0.1651)
		(layer "In7.Cu")
		(net "P5E_PEX1_STN6_TX_C_DP<98>")
	)
	(segment
		(start 126.303786 -367.06937)
		(end 126.324868 -366.963706)
		(width 0.1651)
		(layer "In7.Cu")
		(net "P5E_PEX1_STN6_TX_C_DP<98>")
	)
	(segment
		(start 126.579122 -367.481358)
		(end 126.303786 -367.06937)
		(width 0.1651)
		(layer "In7.Cu")
		(net "P5E_PEX1_STN6_TX_C_DP<98>")
	)
	(segment
		(start 322.398644 -357.46309)
		(end 322.693284 -357.75773)
		(width 0.13462)
		(layer "F.Cu")
		(net "P5E_PEX2_STN5_TX_C_DN<85>")
	)
	(segment
		(start 322.398644 -356.831646)
		(end 322.398644 -357.46309)
		(width 0.13462)
		(layer "F.Cu")
		(net "P5E_PEX2_STN5_TX_C_DN<85>")
	)
	(segment
		(start 322.718684 -356.511606)
		(end 322.398644 -356.831646)
		(width 0.13462)
		(layer "F.Cu")
		(net "P5E_PEX2_STN5_TX_C_DN<85>")
	)
	(segment
		(start 322.402454 -358.04856)
		(end 322.402454 -358.85374)
		(width 0.1651)
		(layer "In7.Cu")
		(net "P5E_PEX2_STN5_TX_C_DN<85>")
	)
	(segment
		(start 342.827864 -394.266166)
		(end 343.616026 -395.444726)
		(width 0.1651)
		(layer "In7.Cu")
		(net "P5E_PEX2_STN5_TX_C_DN<85>")
	)
	(segment
		(start 330.707238 -387.910578)
		(end 337.52028 -390.7409)
		(width 0.1651)
		(layer "In7.Cu")
		(net "P5E_PEX2_STN5_TX_C_DN<85>")
	)
	(segment
		(start 342.490044 -406.308052)
		(end 342.490044 -406.690068)
		(width 0.1651)
		(layer "In7.Cu")
		(net "P5E_PEX2_STN5_TX_C_DN<85>")
	)
	(segment
		(start 343.616026 -405.729186)
		(end 343.16416 -406.181052)
		(width 0.1651)
		(layer "In7.Cu")
		(net "P5E_PEX2_STN5_TX_C_DN<85>")
	)
	(segment
		(start 322.693284 -357.75773)
		(end 322.402454 -358.04856)
		(width 0.1651)
		(layer "In7.Cu")
		(net "P5E_PEX2_STN5_TX_C_DN<85>")
	)
	(segment
		(start 342.617044 -406.181052)
		(end 342.490044 -406.308052)
		(width 0.1651)
		(layer "In7.Cu")
		(net "P5E_PEX2_STN5_TX_C_DN<85>")
	)
	(segment
		(start 337.52028 -390.7409)
		(end 342.827864 -394.266166)
		(width 0.1651)
		(layer "In7.Cu")
		(net "P5E_PEX2_STN5_TX_C_DN<85>")
	)
	(segment
		(start 322.402454 -358.85374)
		(end 328.535792 -384.78714)
		(width 0.1651)
		(layer "In7.Cu")
		(net "P5E_PEX2_STN5_TX_C_DN<85>")
	)
	(segment
		(start 343.616026 -395.444726)
		(end 343.616026 -405.729186)
		(width 0.1651)
		(layer "In7.Cu")
		(net "P5E_PEX2_STN5_TX_C_DN<85>")
	)
	(segment
		(start 328.535792 -384.78714)
		(end 329.20305 -386.39877)
		(width 0.1651)
		(layer "In7.Cu")
		(net "P5E_PEX2_STN5_TX_C_DN<85>")
	)
	(segment
		(start 343.16416 -406.181052)
		(end 342.617044 -406.181052)
		(width 0.1651)
		(layer "In7.Cu")
		(net "P5E_PEX2_STN5_TX_C_DN<85>")
	)
	(segment
		(start 329.20305 -386.39877)
		(end 330.707238 -387.910578)
		(width 0.1651)
		(layer "In7.Cu")
		(net "P5E_PEX2_STN5_TX_C_DN<85>")
	)
	(segment
		(start 422.21785 -146.51228)
		(end 422.060624 -146.355054)
		(width 0.13462)
		(layer "F.Cu")
		(net "P5E_PEX3_STN0_TX_C_DN<10>")
	)
	(segment
		(start 428.052738 -146.190208)
		(end 427.730666 -146.51228)
		(width 0.13462)
		(layer "F.Cu")
		(net "P5E_PEX3_STN0_TX_C_DN<10>")
	)
	(segment
		(start 427.730666 -146.51228)
		(end 422.21785 -146.51228)
		(width 0.13462)
		(layer "F.Cu")
		(net "P5E_PEX3_STN0_TX_C_DN<10>")
	)
	(segment
		(start 422.060624 -146.355054)
		(end 421.557704 -146.355054)
		(width 0.13462)
		(layer "F.Cu")
		(net "P5E_PEX3_STN0_TX_C_DN<10>")
	)
	(segment
		(start 386.70738 -356.511606)
		(end 387.027928 -356.832154)
		(width 0.13462)
		(layer "F.Cu")
		(net "P5E_PEX3_STN5_TX_C_DP<80>")
	)
	(segment
		(start 387.027928 -357.462582)
		(end 386.73278 -357.75773)
		(width 0.13462)
		(layer "F.Cu")
		(net "P5E_PEX3_STN5_TX_C_DP<80>")
	)
	(segment
		(start 387.027928 -356.832154)
		(end 387.027928 -357.462582)
		(width 0.13462)
		(layer "F.Cu")
		(net "P5E_PEX3_STN5_TX_C_DP<80>")
	)
	(segment
		(start 391.81786 -365.669576)
		(end 391.794238 -365.79302)
		(width 0.1651)
		(layer "In7.Cu")
		(net "P5E_PEX3_STN5_TX_C_DP<80>")
	)
	(segment
		(start 375.616978 -404.799038)
		(end 375.489978 -404.672038)
		(width 0.1651)
		(layer "In7.Cu")
		(net "P5E_PEX3_STN5_TX_C_DP<80>")
	)
	(segment
		(start 387.02361 -358.58196)
		(end 390.508236 -363.733588)
		(width 0.1651)
		(layer "In7.Cu")
		(net "P5E_PEX3_STN5_TX_C_DP<80>")
	)
	(segment
		(start 391.540492 -365.259366)
		(end 391.81786 -365.669576)
		(width 0.1651)
		(layer "In7.Cu")
		(net "P5E_PEX3_STN5_TX_C_DP<80>")
	)
	(segment
		(start 391.794238 -365.79302)
		(end 392.07186 -366.203484)
		(width 0.1651)
		(layer "In7.Cu")
		(net "P5E_PEX3_STN5_TX_C_DP<80>")
	)
	(segment
		(start 394.08354 -369.01882)
		(end 393.91209 -385.34213)
		(width 0.1651)
		(layer "In7.Cu")
		(net "P5E_PEX3_STN5_TX_C_DP<80>")
	)
	(segment
		(start 392.195304 -366.22736)
		(end 394.08354 -369.01882)
		(width 0.1651)
		(layer "In7.Cu")
		(net "P5E_PEX3_STN5_TX_C_DP<80>")
	)
	(segment
		(start 376.90552 -394.34516)
		(end 376.33402 -395.982444)
		(width 0.1651)
		(layer "In7.Cu")
		(net "P5E_PEX3_STN5_TX_C_DP<80>")
	)
	(segment
		(start 376.33402 -404.512272)
		(end 376.047254 -404.799038)
		(width 0.1651)
		(layer "In7.Cu")
		(net "P5E_PEX3_STN5_TX_C_DP<80>")
	)
	(segment
		(start 390.762236 -364.26775)
		(end 390.88568 -364.291372)
		(width 0.1651)
		(layer "In7.Cu")
		(net "P5E_PEX3_STN5_TX_C_DP<80>")
	)
	(segment
		(start 376.047254 -404.799038)
		(end 375.616978 -404.799038)
		(width 0.1651)
		(layer "In7.Cu")
		(net "P5E_PEX3_STN5_TX_C_DP<80>")
	)
	(segment
		(start 390.508236 -363.733588)
		(end 390.48436 -363.857032)
		(width 0.1651)
		(layer "In7.Cu")
		(net "P5E_PEX3_STN5_TX_C_DP<80>")
	)
	(segment
		(start 391.163048 -364.701582)
		(end 391.139172 -364.825026)
		(width 0.1651)
		(layer "In7.Cu")
		(net "P5E_PEX3_STN5_TX_C_DP<80>")
	)
	(segment
		(start 387.02361 -358.04856)
		(end 387.02361 -358.58196)
		(width 0.1651)
		(layer "In7.Cu")
		(net "P5E_PEX3_STN5_TX_C_DP<80>")
	)
	(segment
		(start 386.73278 -357.75773)
		(end 387.02361 -358.04856)
		(width 0.1651)
		(layer "In7.Cu")
		(net "P5E_PEX3_STN5_TX_C_DP<80>")
	)
	(segment
		(start 393.91209 -385.34213)
		(end 393.44346 -385.81076)
		(width 0.1651)
		(layer "In7.Cu")
		(net "P5E_PEX3_STN5_TX_C_DP<80>")
	)
	(segment
		(start 393.44346 -385.81076)
		(end 383.17424 -390.31926)
		(width 0.1651)
		(layer "In7.Cu")
		(net "P5E_PEX3_STN5_TX_C_DP<80>")
	)
	(segment
		(start 376.33402 -395.982444)
		(end 376.33402 -404.512272)
		(width 0.1651)
		(layer "In7.Cu")
		(net "P5E_PEX3_STN5_TX_C_DP<80>")
	)
	(segment
		(start 390.48436 -363.857032)
		(end 390.762236 -364.26775)
		(width 0.1651)
		(layer "In7.Cu")
		(net "P5E_PEX3_STN5_TX_C_DP<80>")
	)
	(segment
		(start 383.17424 -390.31926)
		(end 376.90552 -394.34516)
		(width 0.1651)
		(layer "In7.Cu")
		(net "P5E_PEX3_STN5_TX_C_DP<80>")
	)
	(segment
		(start 391.417048 -365.235744)
		(end 391.540492 -365.259366)
		(width 0.1651)
		(layer "In7.Cu")
		(net "P5E_PEX3_STN5_TX_C_DP<80>")
	)
	(segment
		(start 390.88568 -364.291372)
		(end 391.163048 -364.701582)
		(width 0.1651)
		(layer "In7.Cu")
		(net "P5E_PEX3_STN5_TX_C_DP<80>")
	)
	(segment
		(start 392.07186 -366.203484)
		(end 392.195304 -366.22736)
		(width 0.1651)
		(layer "In7.Cu")
		(net "P5E_PEX3_STN5_TX_C_DP<80>")
	)
	(segment
		(start 375.489978 -404.672038)
		(end 375.489978 -404.290022)
		(width 0.1651)
		(layer "In7.Cu")
		(net "P5E_PEX3_STN5_TX_C_DP<80>")
	)
	(segment
		(start 391.139172 -364.825026)
		(end 391.417048 -365.235744)
		(width 0.1651)
		(layer "In7.Cu")
		(net "P5E_PEX3_STN5_TX_C_DP<80>")
	)
	(segment
		(start 278.242268 -150.560024)
		(end 275.134324 -150.560024)
		(width 0.13208)
		(layer "F.Cu")
		(net "NCSI_NIC4_CRS_DV")
	)
	(segment
		(start 274.786852 -150.212552)
		(end 272.591022 -150.212552)
		(width 0.13208)
		(layer "F.Cu")
		(net "NCSI_NIC4_CRS_DV")
	)
	(segment
		(start 275.134324 -150.560024)
		(end 274.786852 -150.212552)
		(width 0.13208)
		(layer "F.Cu")
		(net "NCSI_NIC4_CRS_DV")
	)
	(segment
		(start 272.591022 -150.212552)
		(end 272.540222 -150.263352)
		(width 0.13208)
		(layer "F.Cu")
		(net "NCSI_NIC4_CRS_DV")
	)
	(segment
		(start 272.540222 -150.263352)
		(end 271.199864 -150.263352)
		(width 0.13208)
		(layer "F.Cu")
		(net "NCSI_NIC4_CRS_DV")
	)
	(via
		(at 272.591022 -150.212552)
		(size 0.762)
		(drill 0.381)
		(layers "F.Cu" "B.Cu")
		(net "NCSI_NIC4_CRS_DV")
	)
	(segment
		(start 167.393112 -119.517922)
		(end 169.901616 -119.517922)
		(width 0.13462)
		(layer "F.Cu")
		(net "P5E_PEX1_STN1_RX_DP<24>")
	)
	(segment
		(start 169.901616 -119.517922)
		(end 170.196764 -119.222774)
		(width 0.13462)
		(layer "F.Cu")
		(net "P5E_PEX1_STN1_RX_DP<24>")
	)
	(segment
		(start 166.742364 -119.355108)
		(end 167.230298 -119.355108)
		(width 0.13462)
		(layer "F.Cu")
		(net "P5E_PEX1_STN1_RX_DP<24>")
	)
	(segment
		(start 167.230298 -119.355108)
		(end 167.393112 -119.517922)
		(width 0.13462)
		(layer "F.Cu")
		(net "P5E_PEX1_STN1_RX_DP<24>")
	)
	(segment
		(start 158.874206 -127.992124)
		(end 158.521654 -128.909064)
		(width 0.1651)
		(layer "In5.Cu")
		(net "P5E_PEX1_STN1_RX_DP<24>")
	)
	(segment
		(start 182.77967 -273.45513)
		(end 182.994554 -273.670014)
		(width 0.1143)
		(layer "In5.Cu")
		(net "P5E_PEX1_STN1_RX_DP<24>")
	)
	(segment
		(start 153.606754 -163.938458)
		(end 182.73395 -268.419834)
		(width 0.1651)
		(layer "In5.Cu")
		(net "P5E_PEX1_STN1_RX_DP<24>")
	)
	(segment
		(start 158.521654 -128.909064)
		(end 157.103064 -137.613898)
		(width 0.1651)
		(layer "In5.Cu")
		(net "P5E_PEX1_STN1_RX_DP<24>")
	)
	(segment
		(start 183.235346 -273.670014)
		(end 183.349646 -273.784314)
		(width 0.1143)
		(layer "In5.Cu")
		(net "P5E_PEX1_STN1_RX_DP<24>")
	)
	(segment
		(start 182.994554 -273.670014)
		(end 183.235346 -273.670014)
		(width 0.1143)
		(layer "In5.Cu")
		(net "P5E_PEX1_STN1_RX_DP<24>")
	)
	(segment
		(start 153.347166 -145.16735)
		(end 152.167082 -151.562054)
		(width 0.1651)
		(layer "In5.Cu")
		(net "P5E_PEX1_STN1_RX_DP<24>")
	)
	(segment
		(start 152.167082 -151.562054)
		(end 152.602946 -158.20644)
		(width 0.1651)
		(layer "In5.Cu")
		(net "P5E_PEX1_STN1_RX_DP<24>")
	)
	(segment
		(start 152.602946 -158.20644)
		(end 153.606754 -163.938458)
		(width 0.1651)
		(layer "In5.Cu")
		(net "P5E_PEX1_STN1_RX_DP<24>")
	)
	(segment
		(start 166.11219 -120.150382)
		(end 160.496504 -125.476508)
		(width 0.1651)
		(layer "In5.Cu")
		(net "P5E_PEX1_STN1_RX_DP<24>")
	)
	(segment
		(start 170.196764 -119.222774)
		(end 169.905934 -119.513604)
		(width 0.1651)
		(layer "In5.Cu")
		(net "P5E_PEX1_STN1_RX_DP<24>")
	)
	(segment
		(start 155.398724 -140.622274)
		(end 153.347166 -145.16735)
		(width 0.1651)
		(layer "In5.Cu")
		(net "P5E_PEX1_STN1_RX_DP<24>")
	)
	(segment
		(start 160.496504 -125.476508)
		(end 158.874206 -127.992124)
		(width 0.1651)
		(layer "In5.Cu")
		(net "P5E_PEX1_STN1_RX_DP<24>")
	)
	(segment
		(start 182.77967 -271.600168)
		(end 182.77967 -273.45513)
		(width 0.1143)
		(layer "In5.Cu")
		(net "P5E_PEX1_STN1_RX_DP<24>")
	)
	(segment
		(start 168.157144 -119.513604)
		(end 166.11219 -120.150382)
		(width 0.1651)
		(layer "In5.Cu")
		(net "P5E_PEX1_STN1_RX_DP<24>")
	)
	(segment
		(start 182.73395 -268.419834)
		(end 182.73395 -271.526)
		(width 0.1651)
		(layer "In5.Cu")
		(net "P5E_PEX1_STN1_RX_DP<24>")
	)
	(segment
		(start 157.103064 -137.613898)
		(end 155.398724 -140.622274)
		(width 0.1651)
		(layer "In5.Cu")
		(net "P5E_PEX1_STN1_RX_DP<24>")
	)
	(segment
		(start 182.73395 -271.554448)
		(end 182.77967 -271.600168)
		(width 0.1143)
		(layer "In5.Cu")
		(net "P5E_PEX1_STN1_RX_DP<24>")
	)
	(segment
		(start 183.349646 -273.784314)
		(end 183.349646 -274.049744)
		(width 0.1143)
		(layer "In5.Cu")
		(net "P5E_PEX1_STN1_RX_DP<24>")
	)
	(segment
		(start 182.73395 -271.526)
		(end 182.73395 -271.554448)
		(width 0.1143)
		(layer "In5.Cu")
		(net "P5E_PEX1_STN1_RX_DP<24>")
	)
	(segment
		(start 169.905934 -119.513604)
		(end 168.157144 -119.513604)
		(width 0.1651)
		(layer "In5.Cu")
		(net "P5E_PEX1_STN1_RX_DP<24>")
	)
	(segment
		(start 170.999912 -316.799722)
		(end 170.999912 -316.534292)
		(width 0.1143)
		(layer "In5.Cu")
		(net "P5E_PEX1_STN6_RX_DN<99>")
	)
	(segment
		(start 136.739884 -340.982046)
		(end 135.752078 -341.969852)
		(width 0.1651)
		(layer "In5.Cu")
		(net "P5E_PEX1_STN6_RX_DN<99>")
	)
	(segment
		(start 170.999912 -316.534292)
		(end 170.885612 -316.419992)
		(width 0.1143)
		(layer "In5.Cu")
		(net "P5E_PEX1_STN6_RX_DN<99>")
	)
	(segment
		(start 169.087292 -323.002402)
		(end 156.549852 -330.41209)
		(width 0.1651)
		(layer "In5.Cu")
		(net "P5E_PEX1_STN6_RX_DN<99>")
	)
	(segment
		(start 124.83719 -375.181114)
		(end 124.71019 -375.308114)
		(width 0.1651)
		(layer "In5.Cu")
		(net "P5E_PEX1_STN6_RX_DN<99>")
	)
	(segment
		(start 126.284736 -368.525044)
		(end 125.769624 -369.382294)
		(width 0.1651)
		(layer "In5.Cu")
		(net "P5E_PEX1_STN6_RX_DN<99>")
	)
	(segment
		(start 170.66514 -321.185286)
		(end 169.087292 -323.002402)
		(width 0.1651)
		(layer "In5.Cu")
		(net "P5E_PEX1_STN6_RX_DN<99>")
	)
	(segment
		(start 170.66514 -319.90665)
		(end 170.66514 -319.935098)
		(width 0.1143)
		(layer "In5.Cu")
		(net "P5E_PEX1_STN6_RX_DN<99>")
	)
	(segment
		(start 125.769624 -369.382294)
		(end 125.769624 -374.798336)
		(width 0.1651)
		(layer "In5.Cu")
		(net "P5E_PEX1_STN6_RX_DN<99>")
	)
	(segment
		(start 125.769624 -374.798336)
		(end 125.386846 -375.181114)
		(width 0.1651)
		(layer "In5.Cu")
		(net "P5E_PEX1_STN6_RX_DN<99>")
	)
	(segment
		(start 124.71019 -375.308114)
		(end 124.71019 -375.69013)
		(width 0.1651)
		(layer "In5.Cu")
		(net "P5E_PEX1_STN6_RX_DN<99>")
	)
	(segment
		(start 170.885612 -316.419992)
		(end 170.734482 -316.419992)
		(width 0.1143)
		(layer "In5.Cu")
		(net "P5E_PEX1_STN6_RX_DN<99>")
	)
	(segment
		(start 170.61942 -319.86093)
		(end 170.66514 -319.90665)
		(width 0.1143)
		(layer "In5.Cu")
		(net "P5E_PEX1_STN6_RX_DN<99>")
	)
	(segment
		(start 156.549852 -330.41209)
		(end 146.171412 -336.995516)
		(width 0.1651)
		(layer "In5.Cu")
		(net "P5E_PEX1_STN6_RX_DN<99>")
	)
	(segment
		(start 135.099044 -359.585768)
		(end 126.284736 -368.525044)
		(width 0.1651)
		(layer "In5.Cu")
		(net "P5E_PEX1_STN6_RX_DN<99>")
	)
	(segment
		(start 170.734482 -316.419992)
		(end 170.61942 -316.535054)
		(width 0.1143)
		(layer "In5.Cu")
		(net "P5E_PEX1_STN6_RX_DN<99>")
	)
	(segment
		(start 135.752078 -357.993188)
		(end 135.099044 -359.585768)
		(width 0.1651)
		(layer "In5.Cu")
		(net "P5E_PEX1_STN6_RX_DN<99>")
	)
	(segment
		(start 135.752078 -341.969852)
		(end 135.752078 -357.993188)
		(width 0.1651)
		(layer "In5.Cu")
		(net "P5E_PEX1_STN6_RX_DN<99>")
	)
	(segment
		(start 170.66514 -319.935098)
		(end 170.66514 -321.185286)
		(width 0.1651)
		(layer "In5.Cu")
		(net "P5E_PEX1_STN6_RX_DN<99>")
	)
	(segment
		(start 170.61942 -316.535054)
		(end 170.61942 -319.86093)
		(width 0.1143)
		(layer "In5.Cu")
		(net "P5E_PEX1_STN6_RX_DN<99>")
	)
	(segment
		(start 146.171412 -336.995516)
		(end 136.739884 -340.982046)
		(width 0.1651)
		(layer "In5.Cu")
		(net "P5E_PEX1_STN6_RX_DN<99>")
	)
	(segment
		(start 125.386846 -375.181114)
		(end 124.83719 -375.181114)
		(width 0.1651)
		(layer "In5.Cu")
		(net "P5E_PEX1_STN6_RX_DN<99>")
	)
	(segment
		(start 296.59961 -316.534038)
		(end 296.485564 -316.419992)
		(width 0.1143)
		(layer "In9.Cu")
		(net "P5E_PEX2_STN5_RX_DN<86>")
	)
	(segment
		(start 296.485564 -316.419992)
		(end 296.323766 -316.419992)
		(width 0.1143)
		(layer "In9.Cu")
		(net "P5E_PEX2_STN5_RX_DN<86>")
	)
	(segment
		(start 296.323766 -316.419992)
		(end 296.209466 -316.534292)
		(width 0.1143)
		(layer "In9.Cu")
		(net "P5E_PEX2_STN5_RX_DN<86>")
	)
	(segment
		(start 353.382072 -391.646664)
		(end 347.786452 -393.84605)
		(width 0.1651)
		(layer "In9.Cu")
		(net "P5E_PEX2_STN5_RX_DN<86>")
	)
	(segment
		(start 297.124882 -320.50482)
		(end 297.145202 -320.52514)
		(width 0.1143)
		(layer "In9.Cu")
		(net "P5E_PEX2_STN5_RX_DN<86>")
	)
	(segment
		(start 345.854782 -339.199728)
		(end 347.08719 -340.450424)
		(width 0.1651)
		(layer "In9.Cu")
		(net "P5E_PEX2_STN5_RX_DN<86>")
	)
	(segment
		(start 297.324018 -320.660776)
		(end 298.54144 -320.903092)
		(width 0.1651)
		(layer "In9.Cu")
		(net "P5E_PEX2_STN5_RX_DN<86>")
	)
	(segment
		(start 347.48089 -394.092684)
		(end 345.71178 -396.72514)
		(width 0.1651)
		(layer "In9.Cu")
		(net "P5E_PEX2_STN5_RX_DN<86>")
	)
	(segment
		(start 358.006904 -370.205)
		(end 357.711502 -386.328158)
		(width 0.1651)
		(layer "In9.Cu")
		(net "P5E_PEX2_STN5_RX_DN<86>")
	)
	(segment
		(start 296.599864 -316.799722)
		(end 296.599864 -316.534038)
		(width 0.1143)
		(layer "In9.Cu")
		(net "P5E_PEX2_STN5_RX_DN<86>")
	)
	(segment
		(start 345.155774 -397.281146)
		(end 344.816938 -397.281146)
		(width 0.1651)
		(layer "In9.Cu")
		(net "P5E_PEX2_STN5_RX_DN<86>")
	)
	(segment
		(start 357.81234 -368.75466)
		(end 358.006904 -370.205)
		(width 0.1651)
		(layer "In9.Cu")
		(net "P5E_PEX2_STN5_RX_DN<86>")
	)
	(segment
		(start 296.209466 -316.534292)
		(end 296.209466 -319.653666)
		(width 0.1143)
		(layer "In9.Cu")
		(net "P5E_PEX2_STN5_RX_DN<86>")
	)
	(segment
		(start 347.08719 -340.450424)
		(end 357.81234 -368.75466)
		(width 0.1651)
		(layer "In9.Cu")
		(net "P5E_PEX2_STN5_RX_DN<86>")
	)
	(segment
		(start 296.599864 -316.534038)
		(end 296.59961 -316.534038)
		(width 0.1143)
		(layer "In9.Cu")
		(net "P5E_PEX2_STN5_RX_DN<86>")
	)
	(segment
		(start 298.54144 -320.903092)
		(end 342.476836 -337.034886)
		(width 0.1651)
		(layer "In9.Cu")
		(net "P5E_PEX2_STN5_RX_DN<86>")
	)
	(segment
		(start 347.786452 -393.84605)
		(end 347.48089 -394.092684)
		(width 0.1651)
		(layer "In9.Cu")
		(net "P5E_PEX2_STN5_RX_DN<86>")
	)
	(segment
		(start 345.71178 -396.72514)
		(end 345.155774 -397.281146)
		(width 0.1651)
		(layer "In9.Cu")
		(net "P5E_PEX2_STN5_RX_DN<86>")
	)
	(segment
		(start 357.711502 -386.328158)
		(end 357.01478 -388.20979)
		(width 0.1651)
		(layer "In9.Cu")
		(net "P5E_PEX2_STN5_RX_DN<86>")
	)
	(segment
		(start 297.060874 -320.505074)
		(end 297.124882 -320.505074)
		(width 0.1143)
		(layer "In9.Cu")
		(net "P5E_PEX2_STN5_RX_DN<86>")
	)
	(segment
		(start 355.355398 -390.216644)
		(end 353.382072 -391.646664)
		(width 0.1651)
		(layer "In9.Cu")
		(net "P5E_PEX2_STN5_RX_DN<86>")
	)
	(segment
		(start 297.145202 -320.52514)
		(end 297.231562 -320.6115)
		(width 0.1651)
		(layer "In9.Cu")
		(net "P5E_PEX2_STN5_RX_DN<86>")
	)
	(segment
		(start 344.689938 -397.408146)
		(end 344.689938 -397.790162)
		(width 0.1651)
		(layer "In9.Cu")
		(net "P5E_PEX2_STN5_RX_DN<86>")
	)
	(segment
		(start 296.209466 -319.653666)
		(end 297.060874 -320.505074)
		(width 0.1143)
		(layer "In9.Cu")
		(net "P5E_PEX2_STN5_RX_DN<86>")
	)
	(segment
		(start 344.816938 -397.281146)
		(end 344.689938 -397.408146)
		(width 0.1651)
		(layer "In9.Cu")
		(net "P5E_PEX2_STN5_RX_DN<86>")
	)
	(segment
		(start 342.476836 -337.034886)
		(end 345.854782 -339.199728)
		(width 0.1651)
		(layer "In9.Cu")
		(net "P5E_PEX2_STN5_RX_DN<86>")
	)
	(segment
		(start 357.01478 -388.20979)
		(end 355.355398 -390.216644)
		(width 0.1651)
		(layer "In9.Cu")
		(net "P5E_PEX2_STN5_RX_DN<86>")
	)
	(segment
		(start 297.231562 -320.6115)
		(end 297.324018 -320.660776)
		(width 0.1651)
		(layer "In9.Cu")
		(net "P5E_PEX2_STN5_RX_DN<86>")
	)
	(segment
		(start 297.124882 -320.505074)
		(end 297.124882 -320.50482)
		(width 0.1143)
		(layer "In9.Cu")
		(net "P5E_PEX2_STN5_RX_DN<86>")
	)
	(segment
		(start 422.060624 -130.044952)
		(end 421.557704 -130.044952)
		(width 0.13462)
		(layer "F.Cu")
		(net "P5E_PEX3_STN0_TX_C_DN<4>")
	)
	(segment
		(start 422.208452 -130.19278)
		(end 422.060624 -130.044952)
		(width 0.13462)
		(layer "F.Cu")
		(net "P5E_PEX3_STN0_TX_C_DN<4>")
	)
	(segment
		(start 428.052738 -129.880106)
		(end 427.740064 -130.19278)
		(width 0.13462)
		(layer "F.Cu")
		(net "P5E_PEX3_STN0_TX_C_DN<4>")
	)
	(segment
		(start 427.740064 -130.19278)
		(end 422.208452 -130.19278)
		(width 0.13462)
		(layer "F.Cu")
		(net "P5E_PEX3_STN0_TX_C_DN<4>")
	)
	(segment
		(start 420.679626 -320.04508)
		(end 420.679626 -318.344804)
		(width 0.1143)
		(layer "In15.Cu")
		(net "P5E_PEX3_STN5_RX_DP<95>")
	)
	(segment
		(start 410.846524 -337.678776)
		(end 410.97073 -337.658964)
		(width 0.1651)
		(layer "In15.Cu")
		(net "P5E_PEX3_STN5_RX_DP<95>")
	)
	(segment
		(start 411.946852 -336.311494)
		(end 411.92704 -336.187542)
		(width 0.1651)
		(layer "In15.Cu")
		(net "P5E_PEX3_STN5_RX_DP<95>")
	)
	(segment
		(start 411.532324 -336.732626)
		(end 411.656276 -336.71256)
		(width 0.1651)
		(layer "In15.Cu")
		(net "P5E_PEX3_STN5_RX_DP<95>")
	)
	(segment
		(start 391.447274 -372.099078)
		(end 391.73404 -371.812312)
		(width 0.1651)
		(layer "In15.Cu")
		(net "P5E_PEX3_STN5_RX_DP<95>")
	)
	(segment
		(start 410.575506 -338.204302)
		(end 410.555694 -338.080096)
		(width 0.1651)
		(layer "In15.Cu")
		(net "P5E_PEX3_STN5_RX_DP<95>")
	)
	(segment
		(start 421.135556 -318.129666)
		(end 421.249856 -318.015366)
		(width 0.1143)
		(layer "In15.Cu")
		(net "P5E_PEX3_STN5_RX_DP<95>")
	)
	(segment
		(start 404.663148 -359.324148)
		(end 405.48052 -357.507286)
		(width 0.1651)
		(layer "In15.Cu")
		(net "P5E_PEX3_STN5_RX_DP<95>")
	)
	(segment
		(start 390.889998 -371.972078)
		(end 391.016998 -372.099078)
		(width 0.1651)
		(layer "In15.Cu")
		(net "P5E_PEX3_STN5_RX_DP<95>")
	)
	(segment
		(start 392.101832 -368.477292)
		(end 404.663148 -359.324148)
		(width 0.1651)
		(layer "In15.Cu")
		(net "P5E_PEX3_STN5_RX_DP<95>")
	)
	(segment
		(start 420.633906 -320.119248)
		(end 420.633906 -320.0908)
		(width 0.1143)
		(layer "In15.Cu")
		(net "P5E_PEX3_STN5_RX_DP<95>")
	)
	(segment
		(start 411.656276 -336.71256)
		(end 411.946852 -336.311494)
		(width 0.1651)
		(layer "In15.Cu")
		(net "P5E_PEX3_STN5_RX_DP<95>")
	)
	(segment
		(start 421.249856 -318.015366)
		(end 421.249856 -317.749936)
		(width 0.1143)
		(layer "In15.Cu")
		(net "P5E_PEX3_STN5_RX_DP<95>")
	)
	(segment
		(start 391.016998 -372.099078)
		(end 391.447274 -372.099078)
		(width 0.1651)
		(layer "In15.Cu")
		(net "P5E_PEX3_STN5_RX_DP<95>")
	)
	(segment
		(start 391.73404 -371.812312)
		(end 391.73404 -369.34648)
		(width 0.1651)
		(layer "In15.Cu")
		(net "P5E_PEX3_STN5_RX_DP<95>")
	)
	(segment
		(start 420.894764 -318.129666)
		(end 421.135556 -318.129666)
		(width 0.1143)
		(layer "In15.Cu")
		(net "P5E_PEX3_STN5_RX_DP<95>")
	)
	(segment
		(start 411.92704 -336.187542)
		(end 412.21787 -335.786222)
		(width 0.1651)
		(layer "In15.Cu")
		(net "P5E_PEX3_STN5_RX_DP<95>")
	)
	(segment
		(start 412.341822 -335.76641)
		(end 418.655754 -327.052178)
		(width 0.1651)
		(layer "In15.Cu")
		(net "P5E_PEX3_STN5_RX_DP<95>")
	)
	(segment
		(start 420.633906 -320.0908)
		(end 420.679626 -320.04508)
		(width 0.1143)
		(layer "In15.Cu")
		(net "P5E_PEX3_STN5_RX_DP<95>")
	)
	(segment
		(start 408.484832 -341.089742)
		(end 410.575506 -338.204302)
		(width 0.1651)
		(layer "In15.Cu")
		(net "P5E_PEX3_STN5_RX_DP<95>")
	)
	(segment
		(start 420.679626 -318.344804)
		(end 420.894764 -318.129666)
		(width 0.1143)
		(layer "In15.Cu")
		(net "P5E_PEX3_STN5_RX_DP<95>")
	)
	(segment
		(start 407.970482 -342.067896)
		(end 408.484832 -341.089742)
		(width 0.1651)
		(layer "In15.Cu")
		(net "P5E_PEX3_STN5_RX_DP<95>")
	)
	(segment
		(start 418.655754 -327.052178)
		(end 420.633906 -323.514212)
		(width 0.1651)
		(layer "In15.Cu")
		(net "P5E_PEX3_STN5_RX_DP<95>")
	)
	(segment
		(start 391.73404 -369.34648)
		(end 392.101832 -368.477292)
		(width 0.1651)
		(layer "In15.Cu")
		(net "P5E_PEX3_STN5_RX_DP<95>")
	)
	(segment
		(start 405.48052 -357.507286)
		(end 407.970482 -342.067896)
		(width 0.1651)
		(layer "In15.Cu")
		(net "P5E_PEX3_STN5_RX_DP<95>")
	)
	(segment
		(start 410.97073 -337.658964)
		(end 411.261306 -337.257898)
		(width 0.1651)
		(layer "In15.Cu")
		(net "P5E_PEX3_STN5_RX_DP<95>")
	)
	(segment
		(start 390.889998 -371.590062)
		(end 390.889998 -371.972078)
		(width 0.1651)
		(layer "In15.Cu")
		(net "P5E_PEX3_STN5_RX_DP<95>")
	)
	(segment
		(start 410.555694 -338.080096)
		(end 410.846524 -337.678776)
		(width 0.1651)
		(layer "In15.Cu")
		(net "P5E_PEX3_STN5_RX_DP<95>")
	)
	(segment
		(start 412.21787 -335.786222)
		(end 412.341822 -335.76641)
		(width 0.1651)
		(layer "In15.Cu")
		(net "P5E_PEX3_STN5_RX_DP<95>")
	)
	(segment
		(start 411.261306 -337.257898)
		(end 411.241494 -337.133946)
		(width 0.1651)
		(layer "In15.Cu")
		(net "P5E_PEX3_STN5_RX_DP<95>")
	)
	(segment
		(start 420.633906 -323.514212)
		(end 420.633906 -320.119248)
		(width 0.1651)
		(layer "In15.Cu")
		(net "P5E_PEX3_STN5_RX_DP<95>")
	)
	(segment
		(start 411.241494 -337.133946)
		(end 411.532324 -336.732626)
		(width 0.1651)
		(layer "In15.Cu")
		(net "P5E_PEX3_STN5_RX_DP<95>")
	)
	(segment
		(start 285.658052 -158.36011)
		(end 286.149542 -158.8516)
		(width 0.13208)
		(layer "F.Cu")
		(net "RST_NIC4_PERST2_R_N")
	)
	(segment
		(start 282.842462 -158.36011)
		(end 285.658052 -158.36011)
		(width 0.13208)
		(layer "F.Cu")
		(net "RST_NIC4_PERST2_R_N")
	)
	(segment
		(start 286.555942 -158.8516)
		(end 287.781492 -158.8516)
		(width 0.13208)
		(layer "F.Cu")
		(net "RST_NIC4_PERST2_R_N")
	)
	(segment
		(start 286.149542 -158.8516)
		(end 286.555942 -158.8516)
		(width 0.13208)
		(layer "F.Cu")
		(net "RST_NIC4_PERST2_R_N")
	)
	(via
		(at 286.555942 -158.8516)
		(size 0.762)
		(drill 0.381)
		(layers "F.Cu" "B.Cu")
		(net "RST_NIC4_PERST2_R_N")
	)
	(segment
		(start 168.342564 -105.57637)
		(end 168.048432 -105.282238)
		(width 0.13462)
		(layer "F.Cu")
		(net "P5E_PEX1_STN1_RX_DN<19>")
	)
	(segment
		(start 167.230298 -105.445052)
		(end 166.742364 -105.445052)
		(width 0.13462)
		(layer "F.Cu")
		(net "P5E_PEX1_STN1_RX_DN<19>")
	)
	(segment
		(start 168.048432 -105.282238)
		(end 167.393112 -105.282238)
		(width 0.13462)
		(layer "F.Cu")
		(net "P5E_PEX1_STN1_RX_DN<19>")
	)
	(segment
		(start 167.393112 -105.282238)
		(end 167.230298 -105.445052)
		(width 0.13462)
		(layer "F.Cu")
		(net "P5E_PEX1_STN1_RX_DN<19>")
	)
	(segment
		(start 149.10435 -126.387352)
		(end 149.76729 -122.886724)
		(width 0.1651)
		(layer "In5.Cu")
		(net "P5E_PEX1_STN1_RX_DN<19>")
	)
	(segment
		(start 159.869886 -110.06201)
		(end 160.03143 -110.06455)
		(width 0.1651)
		(layer "In5.Cu")
		(net "P5E_PEX1_STN1_RX_DN<19>")
	)
	(segment
		(start 164.511482 -107.070652)
		(end 164.9476 -106.83494)
		(width 0.1651)
		(layer "In5.Cu")
		(net "P5E_PEX1_STN1_RX_DN<19>")
	)
	(segment
		(start 178.599592 -275.265388)
		(end 178.485292 -275.379688)
		(width 0.1143)
		(layer "In5.Cu")
		(net "P5E_PEX1_STN1_RX_DN<19>")
	)
	(segment
		(start 162.365944 -108.229908)
		(end 162.802062 -107.994196)
		(width 0.1651)
		(layer "In5.Cu")
		(net "P5E_PEX1_STN1_RX_DN<19>")
	)
	(segment
		(start 162.211258 -108.18368)
		(end 162.365944 -108.229908)
		(width 0.1651)
		(layer "In5.Cu")
		(net "P5E_PEX1_STN1_RX_DN<19>")
	)
	(segment
		(start 163.874958 -107.414568)
		(end 163.921186 -107.259628)
		(width 0.1651)
		(layer "In5.Cu")
		(net "P5E_PEX1_STN1_RX_DN<19>")
	)
	(segment
		(start 178.323494 -275.379688)
		(end 178.220116 -275.27631)
		(width 0.1143)
		(layer "In5.Cu")
		(net "P5E_PEX1_STN1_RX_DN<19>")
	)
	(segment
		(start 158.637986 -111.25454)
		(end 158.99384 -110.910116)
		(width 0.1651)
		(layer "In5.Cu")
		(net "P5E_PEX1_STN1_RX_DN<19>")
	)
	(segment
		(start 166.06647 -106.100372)
		(end 166.50208 -105.865168)
		(width 0.1651)
		(layer "In5.Cu")
		(net "P5E_PEX1_STN1_RX_DN<19>")
	)
	(segment
		(start 149.76729 -122.886724)
		(end 150.432008 -122.078242)
		(width 0.1651)
		(layer "In5.Cu")
		(net "P5E_PEX1_STN1_RX_DN<19>")
	)
	(segment
		(start 165.584124 -106.491024)
		(end 166.020242 -106.255312)
		(width 0.1651)
		(layer "In5.Cu")
		(net "P5E_PEX1_STN1_RX_DN<19>")
	)
	(segment
		(start 165.429438 -106.444796)
		(end 165.584124 -106.491024)
		(width 0.1651)
		(layer "In5.Cu")
		(net "P5E_PEX1_STN1_RX_DN<19>")
	)
	(segment
		(start 160.390078 -109.558074)
		(end 161.302954 -108.674408)
		(width 0.1651)
		(layer "In5.Cu")
		(net "P5E_PEX1_STN1_RX_DN<19>")
	)
	(segment
		(start 158.635446 -111.416084)
		(end 158.637986 -111.25454)
		(width 0.1651)
		(layer "In5.Cu")
		(net "P5E_PEX1_STN1_RX_DN<19>")
	)
	(segment
		(start 162.802062 -107.994196)
		(end 162.84829 -107.839256)
		(width 0.1651)
		(layer "In5.Cu")
		(net "P5E_PEX1_STN1_RX_DN<19>")
	)
	(segment
		(start 178.265836 -271.599406)
		(end 178.265836 -271.570958)
		(width 0.1143)
		(layer "In5.Cu")
		(net "P5E_PEX1_STN1_RX_DN<19>")
	)
	(segment
		(start 159.514032 -110.406434)
		(end 159.869886 -110.06201)
		(width 0.1651)
		(layer "In5.Cu")
		(net "P5E_PEX1_STN1_RX_DN<19>")
	)
	(segment
		(start 164.356796 -107.024424)
		(end 164.511482 -107.070652)
		(width 0.1651)
		(layer "In5.Cu")
		(net "P5E_PEX1_STN1_RX_DN<19>")
	)
	(segment
		(start 162.84829 -107.839256)
		(end 163.2839 -107.604052)
		(width 0.1651)
		(layer "In5.Cu")
		(net "P5E_PEX1_STN1_RX_DN<19>")
	)
	(segment
		(start 159.155384 -110.91291)
		(end 159.511492 -110.567978)
		(width 0.1651)
		(layer "In5.Cu")
		(net "P5E_PEX1_STN1_RX_DN<19>")
	)
	(segment
		(start 149.125686 -165.120574)
		(end 148.029168 -158.735014)
		(width 0.1651)
		(layer "In5.Cu")
		(net "P5E_PEX1_STN1_RX_DN<19>")
	)
	(segment
		(start 163.2839 -107.604052)
		(end 163.43884 -107.65028)
		(width 0.1651)
		(layer "In5.Cu")
		(net "P5E_PEX1_STN1_RX_DN<19>")
	)
	(segment
		(start 178.485292 -275.379688)
		(end 178.323494 -275.379688)
		(width 0.1143)
		(layer "In5.Cu")
		(net "P5E_PEX1_STN1_RX_DN<19>")
	)
	(segment
		(start 164.993828 -106.68)
		(end 165.429438 -106.444796)
		(width 0.1651)
		(layer "In5.Cu")
		(net "P5E_PEX1_STN1_RX_DN<19>")
	)
	(segment
		(start 158.99384 -110.910116)
		(end 159.155384 -110.91291)
		(width 0.1651)
		(layer "In5.Cu")
		(net "P5E_PEX1_STN1_RX_DN<19>")
	)
	(segment
		(start 166.656766 -105.911396)
		(end 167.092884 -105.675684)
		(width 0.1651)
		(layer "In5.Cu")
		(net "P5E_PEX1_STN1_RX_DN<19>")
	)
	(segment
		(start 159.511492 -110.567978)
		(end 159.514032 -110.406434)
		(width 0.1651)
		(layer "In5.Cu")
		(net "P5E_PEX1_STN1_RX_DN<19>")
	)
	(segment
		(start 150.432008 -122.078242)
		(end 152.467818 -120.982232)
		(width 0.1651)
		(layer "In5.Cu")
		(net "P5E_PEX1_STN1_RX_DN<19>")
	)
	(segment
		(start 166.020242 -106.255312)
		(end 166.06647 -106.100372)
		(width 0.1651)
		(layer "In5.Cu")
		(net "P5E_PEX1_STN1_RX_DN<19>")
	)
	(segment
		(start 158.117794 -111.758222)
		(end 158.279338 -111.761016)
		(width 0.1651)
		(layer "In5.Cu")
		(net "P5E_PEX1_STN1_RX_DN<19>")
	)
	(segment
		(start 160.387538 -109.719618)
		(end 160.390078 -109.558074)
		(width 0.1651)
		(layer "In5.Cu")
		(net "P5E_PEX1_STN1_RX_DN<19>")
	)
	(segment
		(start 164.9476 -106.83494)
		(end 164.993828 -106.68)
		(width 0.1651)
		(layer "In5.Cu")
		(net "P5E_PEX1_STN1_RX_DN<19>")
	)
	(segment
		(start 166.50208 -105.865168)
		(end 166.656766 -105.911396)
		(width 0.1651)
		(layer "In5.Cu")
		(net "P5E_PEX1_STN1_RX_DN<19>")
	)
	(segment
		(start 153.835608 -119.317008)
		(end 156.990034 -112.850168)
		(width 0.1651)
		(layer "In5.Cu")
		(net "P5E_PEX1_STN1_RX_DN<19>")
	)
	(segment
		(start 178.265836 -271.570958)
		(end 178.265836 -269.489682)
		(width 0.1651)
		(layer "In5.Cu")
		(net "P5E_PEX1_STN1_RX_DN<19>")
	)
	(segment
		(start 161.302954 -108.674408)
		(end 162.211258 -108.18368)
		(width 0.1651)
		(layer "In5.Cu")
		(net "P5E_PEX1_STN1_RX_DN<19>")
	)
	(segment
		(start 163.43884 -107.65028)
		(end 163.874958 -107.414568)
		(width 0.1651)
		(layer "In5.Cu")
		(net "P5E_PEX1_STN1_RX_DN<19>")
	)
	(segment
		(start 156.990034 -112.850168)
		(end 158.117794 -111.758222)
		(width 0.1651)
		(layer "In5.Cu")
		(net "P5E_PEX1_STN1_RX_DN<19>")
	)
	(segment
		(start 152.467818 -120.982232)
		(end 153.835608 -119.317008)
		(width 0.1651)
		(layer "In5.Cu")
		(net "P5E_PEX1_STN1_RX_DN<19>")
	)
	(segment
		(start 178.220116 -275.27631)
		(end 178.220116 -271.645126)
		(width 0.1143)
		(layer "In5.Cu")
		(net "P5E_PEX1_STN1_RX_DN<19>")
	)
	(segment
		(start 178.599592 -274.999958)
		(end 178.599592 -275.265388)
		(width 0.1143)
		(layer "In5.Cu")
		(net "P5E_PEX1_STN1_RX_DN<19>")
	)
	(segment
		(start 167.574722 -105.28554)
		(end 168.051734 -105.28554)
		(width 0.1651)
		(layer "In5.Cu")
		(net "P5E_PEX1_STN1_RX_DN<19>")
	)
	(segment
		(start 167.092884 -105.675684)
		(end 167.139112 -105.520998)
		(width 0.1651)
		(layer "In5.Cu")
		(net "P5E_PEX1_STN1_RX_DN<19>")
	)
	(segment
		(start 160.03143 -110.06455)
		(end 160.387538 -109.719618)
		(width 0.1651)
		(layer "In5.Cu")
		(net "P5E_PEX1_STN1_RX_DN<19>")
	)
	(segment
		(start 178.220116 -271.645126)
		(end 178.265836 -271.599406)
		(width 0.1143)
		(layer "In5.Cu")
		(net "P5E_PEX1_STN1_RX_DN<19>")
	)
	(segment
		(start 147.503388 -150.483824)
		(end 149.10435 -126.387352)
		(width 0.1651)
		(layer "In5.Cu")
		(net "P5E_PEX1_STN1_RX_DN<19>")
	)
	(segment
		(start 158.279338 -111.761016)
		(end 158.635446 -111.416084)
		(width 0.1651)
		(layer "In5.Cu")
		(net "P5E_PEX1_STN1_RX_DN<19>")
	)
	(segment
		(start 167.139112 -105.520998)
		(end 167.574722 -105.28554)
		(width 0.1651)
		(layer "In5.Cu")
		(net "P5E_PEX1_STN1_RX_DN<19>")
	)
	(segment
		(start 168.051734 -105.28554)
		(end 168.342564 -105.57637)
		(width 0.1651)
		(layer "In5.Cu")
		(net "P5E_PEX1_STN1_RX_DN<19>")
	)
	(segment
		(start 148.029168 -158.735014)
		(end 147.503388 -150.483824)
		(width 0.1651)
		(layer "In5.Cu")
		(net "P5E_PEX1_STN1_RX_DN<19>")
	)
	(segment
		(start 163.921186 -107.259628)
		(end 164.356796 -107.024424)
		(width 0.1651)
		(layer "In5.Cu")
		(net "P5E_PEX1_STN1_RX_DN<19>")
	)
	(segment
		(start 178.265836 -269.489682)
		(end 149.125686 -165.120574)
		(width 0.1651)
		(layer "In5.Cu")
		(net "P5E_PEX1_STN1_RX_DN<19>")
	)
	(segment
		(start 118.374668 -357.46309)
		(end 118.374668 -356.831646)
		(width 0.13462)
		(layer "F.Cu")
		(net "P5E_PEX1_STN6_TX_C_DP<108>")
	)
	(segment
		(start 118.374668 -356.831646)
		(end 118.054628 -356.511606)
		(width 0.13462)
		(layer "F.Cu")
		(net "P5E_PEX1_STN6_TX_C_DP<108>")
	)
	(segment
		(start 118.080028 -357.75773)
		(end 118.374668 -357.46309)
		(width 0.13462)
		(layer "F.Cu")
		(net "P5E_PEX1_STN6_TX_C_DP<108>")
	)
	(segment
		(start 122.510042 -409.672028)
		(end 122.637042 -409.799028)
		(width 0.1651)
		(layer "In13.Cu")
		(net "P5E_PEX1_STN6_TX_C_DP<108>")
	)
	(segment
		(start 110.278164 -366.982248)
		(end 110.795562 -365.95177)
		(width 0.1651)
		(layer "In13.Cu")
		(net "P5E_PEX1_STN6_TX_C_DP<108>")
	)
	(segment
		(start 118.370858 -358.564434)
		(end 118.370858 -358.04856)
		(width 0.1651)
		(layer "In13.Cu")
		(net "P5E_PEX1_STN6_TX_C_DP<108>")
	)
	(segment
		(start 110.166658 -383.687066)
		(end 110.278164 -366.982248)
		(width 0.1651)
		(layer "In13.Cu")
		(net "P5E_PEX1_STN6_TX_C_DP<108>")
	)
	(segment
		(start 122.510042 -409.290012)
		(end 122.510042 -409.672028)
		(width 0.1651)
		(layer "In13.Cu")
		(net "P5E_PEX1_STN6_TX_C_DP<108>")
	)
	(segment
		(start 122.637042 -409.799028)
		(end 122.85853 -409.799028)
		(width 0.1651)
		(layer "In13.Cu")
		(net "P5E_PEX1_STN6_TX_C_DP<108>")
	)
	(segment
		(start 114.912394 -390.397492)
		(end 113.529364 -389.269732)
		(width 0.1651)
		(layer "In13.Cu")
		(net "P5E_PEX1_STN6_TX_C_DP<108>")
	)
	(segment
		(start 118.2751 -358.788716)
		(end 118.370858 -358.564434)
		(width 0.1651)
		(layer "In13.Cu")
		(net "P5E_PEX1_STN6_TX_C_DP<108>")
	)
	(segment
		(start 120.684036 -392.788394)
		(end 114.912394 -390.397492)
		(width 0.1651)
		(layer "In13.Cu")
		(net "P5E_PEX1_STN6_TX_C_DP<108>")
	)
	(segment
		(start 123.384818 -395.48943)
		(end 120.684036 -392.788648)
		(width 0.1651)
		(layer "In13.Cu")
		(net "P5E_PEX1_STN6_TX_C_DP<108>")
	)
	(segment
		(start 118.370858 -358.04856)
		(end 118.080028 -357.75773)
		(width 0.1651)
		(layer "In13.Cu")
		(net "P5E_PEX1_STN6_TX_C_DP<108>")
	)
	(segment
		(start 112.146334 -388.141972)
		(end 110.880906 -386.258308)
		(width 0.1651)
		(layer "In13.Cu")
		(net "P5E_PEX1_STN6_TX_C_DP<108>")
	)
	(segment
		(start 110.880906 -386.258308)
		(end 110.166658 -383.687066)
		(width 0.1651)
		(layer "In13.Cu")
		(net "P5E_PEX1_STN6_TX_C_DP<108>")
	)
	(segment
		(start 122.85853 -409.799028)
		(end 123.384818 -409.27274)
		(width 0.1651)
		(layer "In13.Cu")
		(net "P5E_PEX1_STN6_TX_C_DP<108>")
	)
	(segment
		(start 113.529618 -389.269732)
		(end 112.146334 -388.141972)
		(width 0.1651)
		(layer "In13.Cu")
		(net "P5E_PEX1_STN6_TX_C_DP<108>")
	)
	(segment
		(start 113.529364 -389.269732)
		(end 113.529618 -389.269732)
		(width 0.1651)
		(layer "In13.Cu")
		(net "P5E_PEX1_STN6_TX_C_DP<108>")
	)
	(segment
		(start 110.795562 -365.95177)
		(end 118.2751 -358.788716)
		(width 0.1651)
		(layer "In13.Cu")
		(net "P5E_PEX1_STN6_TX_C_DP<108>")
	)
	(segment
		(start 123.384818 -409.27274)
		(end 123.384818 -395.48943)
		(width 0.1651)
		(layer "In13.Cu")
		(net "P5E_PEX1_STN6_TX_C_DP<108>")
	)
	(segment
		(start 120.684036 -392.788648)
		(end 120.684036 -392.788394)
		(width 0.1651)
		(layer "In13.Cu")
		(net "P5E_PEX1_STN6_TX_C_DP<108>")
	)
	(segment
		(start 416.478466 -123.03506)
		(end 416.95751 -123.03506)
		(width 0.13462)
		(layer "F.Cu")
		(net "P5E_PEX3_STN0_RX_DP<2>")
	)
	(segment
		(start 416.315906 -122.8725)
		(end 416.478466 -123.03506)
		(width 0.13462)
		(layer "F.Cu")
		(net "P5E_PEX3_STN0_RX_DP<2>")
	)
	(segment
		(start 415.35731 -123.16714)
		(end 415.65195 -122.8725)
		(width 0.13462)
		(layer "F.Cu")
		(net "P5E_PEX3_STN0_RX_DP<2>")
	)
	(segment
		(start 415.65195 -122.8725)
		(end 416.315906 -122.8725)
		(width 0.13462)
		(layer "F.Cu")
		(net "P5E_PEX3_STN0_RX_DP<2>")
	)
	(segment
		(start 433.68976 -285.783782)
		(end 432.224688 -285.783782)
		(width 0.1651)
		(layer "In5.Cu")
		(net "P5E_PEX3_STN0_RX_DP<2>")
	)
	(segment
		(start 428.27956 -286.285432)
		(end 428.16526 -286.399732)
		(width 0.1143)
		(layer "In5.Cu")
		(net "P5E_PEX3_STN0_RX_DP<2>")
	)
	(segment
		(start 435.07406 -285.067248)
		(end 433.68976 -285.783782)
		(width 0.1651)
		(layer "In5.Cu")
		(net "P5E_PEX3_STN0_RX_DP<2>")
	)
	(segment
		(start 425.868084 -131.431284)
		(end 427.72965 -134.220712)
		(width 0.1651)
		(layer "In5.Cu")
		(net "P5E_PEX3_STN0_RX_DP<2>")
	)
	(segment
		(start 424.514518 -129.40284)
		(end 424.514264 -129.40284)
		(width 0.1651)
		(layer "In5.Cu")
		(net "P5E_PEX3_STN0_RX_DP<2>")
	)
	(segment
		(start 424.112436 -128.800606)
		(end 424.080686 -128.959102)
		(width 0.1651)
		(layer "In5.Cu")
		(net "P5E_PEX3_STN0_RX_DP<2>")
	)
	(segment
		(start 445.751458 -269.508732)
		(end 445.58839 -273.073114)
		(width 0.1651)
		(layer "In5.Cu")
		(net "P5E_PEX3_STN0_RX_DP<2>")
	)
	(segment
		(start 428.16526 -286.399732)
		(end 427.89983 -286.399732)
		(width 0.1143)
		(layer "In5.Cu")
		(net "P5E_PEX3_STN0_RX_DP<2>")
	)
	(segment
		(start 435.665118 -149.98446)
		(end 436.160418 -168.457372)
		(width 0.1651)
		(layer "In5.Cu")
		(net "P5E_PEX3_STN0_RX_DP<2>")
	)
	(segment
		(start 425.434252 -130.987546)
		(end 425.709588 -131.399788)
		(width 0.1651)
		(layer "In5.Cu")
		(net "P5E_PEX3_STN0_RX_DP<2>")
	)
	(segment
		(start 420.828724 -124.79274)
		(end 422.684702 -126.661164)
		(width 0.1651)
		(layer "In5.Cu")
		(net "P5E_PEX3_STN0_RX_DP<2>")
	)
	(segment
		(start 417.86302 -123.68403)
		(end 418.320728 -123.874276)
		(width 0.1651)
		(layer "In5.Cu")
		(net "P5E_PEX3_STN0_RX_DP<2>")
	)
	(segment
		(start 445.58839 -273.073114)
		(end 443.313058 -277.083774)
		(width 0.1651)
		(layer "In5.Cu")
		(net "P5E_PEX3_STN0_RX_DP<2>")
	)
	(segment
		(start 417.801298 -123.534424)
		(end 417.86302 -123.68403)
		(width 0.1651)
		(layer "In5.Cu")
		(net "P5E_PEX3_STN0_RX_DP<2>")
	)
	(segment
		(start 432.19624 -285.783782)
		(end 432.15052 -285.829502)
		(width 0.1143)
		(layer "In5.Cu")
		(net "P5E_PEX3_STN0_RX_DP<2>")
	)
	(segment
		(start 416.737038 -123.215908)
		(end 417.194746 -123.406154)
		(width 0.1651)
		(layer "In5.Cu")
		(net "P5E_PEX3_STN0_RX_DP<2>")
	)
	(segment
		(start 432.014376 -138.49985)
		(end 434.763418 -143.64208)
		(width 0.1651)
		(layer "In5.Cu")
		(net "P5E_PEX3_STN0_RX_DP<2>")
	)
	(segment
		(start 415.64814 -122.87631)
		(end 416.218116 -122.87631)
		(width 0.1651)
		(layer "In5.Cu")
		(net "P5E_PEX3_STN0_RX_DP<2>")
	)
	(segment
		(start 427.72965 -134.220712)
		(end 432.014376 -138.49985)
		(width 0.1651)
		(layer "In5.Cu")
		(net "P5E_PEX3_STN0_RX_DP<2>")
	)
	(segment
		(start 424.514264 -129.40284)
		(end 424.789092 -129.814574)
		(width 0.1651)
		(layer "In5.Cu")
		(net "P5E_PEX3_STN0_RX_DP<2>")
	)
	(segment
		(start 436.160418 -168.457372)
		(end 435.45379 -232.167938)
		(width 0.1651)
		(layer "In5.Cu")
		(net "P5E_PEX3_STN0_RX_DP<2>")
	)
	(segment
		(start 434.763418 -143.64208)
		(end 435.665118 -149.98446)
		(width 0.1651)
		(layer "In5.Cu")
		(net "P5E_PEX3_STN0_RX_DP<2>")
	)
	(segment
		(start 419.596062 -124.280676)
		(end 420.828724 -124.79274)
		(width 0.1651)
		(layer "In5.Cu")
		(net "P5E_PEX3_STN0_RX_DP<2>")
	)
	(segment
		(start 417.194746 -123.406154)
		(end 417.344098 -123.344432)
		(width 0.1651)
		(layer "In5.Cu")
		(net "P5E_PEX3_STN0_RX_DP<2>")
	)
	(segment
		(start 437.110378 -239.951514)
		(end 445.751458 -269.508732)
		(width 0.1651)
		(layer "In5.Cu")
		(net "P5E_PEX3_STN0_RX_DP<2>")
	)
	(segment
		(start 416.675316 -123.066302)
		(end 416.737038 -123.215908)
		(width 0.1651)
		(layer "In5.Cu")
		(net "P5E_PEX3_STN0_RX_DP<2>")
	)
	(segment
		(start 425.191174 -130.417062)
		(end 425.466002 -130.828796)
		(width 0.1651)
		(layer "In5.Cu")
		(net "P5E_PEX3_STN0_RX_DP<2>")
	)
	(segment
		(start 435.45379 -232.167938)
		(end 437.110378 -239.951514)
		(width 0.1651)
		(layer "In5.Cu")
		(net "P5E_PEX3_STN0_RX_DP<2>")
	)
	(segment
		(start 424.080686 -128.959102)
		(end 424.356022 -129.371344)
		(width 0.1651)
		(layer "In5.Cu")
		(net "P5E_PEX3_STN0_RX_DP<2>")
	)
	(segment
		(start 425.709588 -131.399788)
		(end 425.868084 -131.431284)
		(width 0.1651)
		(layer "In5.Cu")
		(net "P5E_PEX3_STN0_RX_DP<2>")
	)
	(segment
		(start 418.989002 -124.152152)
		(end 419.44671 -124.342144)
		(width 0.1651)
		(layer "In5.Cu")
		(net "P5E_PEX3_STN0_RX_DP<2>")
	)
	(segment
		(start 432.15052 -285.829502)
		(end 428.523654 -285.829502)
		(width 0.1143)
		(layer "In5.Cu")
		(net "P5E_PEX3_STN0_RX_DP<2>")
	)
	(segment
		(start 432.224688 -285.783782)
		(end 432.19624 -285.783782)
		(width 0.1143)
		(layer "In5.Cu")
		(net "P5E_PEX3_STN0_RX_DP<2>")
	)
	(segment
		(start 424.757342 -129.973324)
		(end 425.032678 -130.385566)
		(width 0.1651)
		(layer "In5.Cu")
		(net "P5E_PEX3_STN0_RX_DP<2>")
	)
	(segment
		(start 416.218116 -122.87631)
		(end 416.675316 -123.066302)
		(width 0.1651)
		(layer "In5.Cu")
		(net "P5E_PEX3_STN0_RX_DP<2>")
	)
	(segment
		(start 424.789092 -129.814574)
		(end 424.757342 -129.973324)
		(width 0.1651)
		(layer "In5.Cu")
		(net "P5E_PEX3_STN0_RX_DP<2>")
	)
	(segment
		(start 418.320728 -123.874276)
		(end 418.47008 -123.812554)
		(width 0.1651)
		(layer "In5.Cu")
		(net "P5E_PEX3_STN0_RX_DP<2>")
	)
	(segment
		(start 428.523654 -285.829502)
		(end 428.27956 -286.073596)
		(width 0.1143)
		(layer "In5.Cu")
		(net "P5E_PEX3_STN0_RX_DP<2>")
	)
	(segment
		(start 424.356022 -129.371344)
		(end 424.514518 -129.40284)
		(width 0.1651)
		(layer "In5.Cu")
		(net "P5E_PEX3_STN0_RX_DP<2>")
	)
	(segment
		(start 425.032678 -130.385566)
		(end 425.191174 -130.417062)
		(width 0.1651)
		(layer "In5.Cu")
		(net "P5E_PEX3_STN0_RX_DP<2>")
	)
	(segment
		(start 417.344098 -123.344432)
		(end 417.801298 -123.534424)
		(width 0.1651)
		(layer "In5.Cu")
		(net "P5E_PEX3_STN0_RX_DP<2>")
	)
	(segment
		(start 443.313058 -277.083774)
		(end 435.07406 -285.067248)
		(width 0.1651)
		(layer "In5.Cu")
		(net "P5E_PEX3_STN0_RX_DP<2>")
	)
	(segment
		(start 422.684702 -126.661164)
		(end 424.112436 -128.800606)
		(width 0.1651)
		(layer "In5.Cu")
		(net "P5E_PEX3_STN0_RX_DP<2>")
	)
	(segment
		(start 418.47008 -123.812554)
		(end 418.92728 -124.002546)
		(width 0.1651)
		(layer "In5.Cu")
		(net "P5E_PEX3_STN0_RX_DP<2>")
	)
	(segment
		(start 425.466002 -130.828796)
		(end 425.434252 -130.987546)
		(width 0.1651)
		(layer "In5.Cu")
		(net "P5E_PEX3_STN0_RX_DP<2>")
	)
	(segment
		(start 428.27956 -286.073596)
		(end 428.27956 -286.285432)
		(width 0.1143)
		(layer "In5.Cu")
		(net "P5E_PEX3_STN0_RX_DP<2>")
	)
	(segment
		(start 415.35731 -123.16714)
		(end 415.64814 -122.87631)
		(width 0.1651)
		(layer "In5.Cu")
		(net "P5E_PEX3_STN0_RX_DP<2>")
	)
	(segment
		(start 418.92728 -124.002546)
		(end 418.989002 -124.152152)
		(width 0.1651)
		(layer "In5.Cu")
		(net "P5E_PEX3_STN0_RX_DP<2>")
	)
	(segment
		(start 419.44671 -124.342144)
		(end 419.596062 -124.280676)
		(width 0.1651)
		(layer "In5.Cu")
		(net "P5E_PEX3_STN0_RX_DP<2>")
	)
	(segment
		(start 417.116006 -319.969896)
		(end 417.116006 -319.941448)
		(width 0.1143)
		(layer "In15.Cu")
		(net "P5E_PEX3_STN5_RX_DN<91>")
	)
	(segment
		(start 417.070286 -318.423798)
		(end 417.173918 -318.320166)
		(width 0.1143)
		(layer "In15.Cu")
		(net "P5E_PEX3_STN5_RX_DN<91>")
	)
	(segment
		(start 382.089914 -372.890034)
		(end 382.089914 -372.508018)
		(width 0.1651)
		(layer "In15.Cu")
		(net "P5E_PEX3_STN5_RX_DN<91>")
	)
	(segment
		(start 382.216914 -372.381018)
		(end 382.76403 -372.381018)
		(width 0.1651)
		(layer "In15.Cu")
		(net "P5E_PEX3_STN5_RX_DN<91>")
	)
	(segment
		(start 383.65049 -368.79022)
		(end 394.43152 -359.483914)
		(width 0.1651)
		(layer "In15.Cu")
		(net "P5E_PEX3_STN5_RX_DN<91>")
	)
	(segment
		(start 417.116006 -321.968622)
		(end 417.116006 -319.969896)
		(width 0.1651)
		(layer "In15.Cu")
		(net "P5E_PEX3_STN5_RX_DN<91>")
	)
	(segment
		(start 383.215896 -371.929152)
		(end 383.215896 -369.828064)
		(width 0.1651)
		(layer "In15.Cu")
		(net "P5E_PEX3_STN5_RX_DN<91>")
	)
	(segment
		(start 382.089914 -372.508018)
		(end 382.216914 -372.381018)
		(width 0.1651)
		(layer "In15.Cu")
		(net "P5E_PEX3_STN5_RX_DN<91>")
	)
	(segment
		(start 415.777934 -323.824346)
		(end 417.116006 -321.968622)
		(width 0.1651)
		(layer "In15.Cu")
		(net "P5E_PEX3_STN5_RX_DN<91>")
	)
	(segment
		(start 395.07795 -358.071928)
		(end 395.07795 -342.16721)
		(width 0.1651)
		(layer "In15.Cu")
		(net "P5E_PEX3_STN5_RX_DN<91>")
	)
	(segment
		(start 417.116006 -319.941448)
		(end 417.070286 -319.895728)
		(width 0.1143)
		(layer "In15.Cu")
		(net "P5E_PEX3_STN5_RX_DN<91>")
	)
	(segment
		(start 383.215896 -369.828064)
		(end 383.65049 -368.79022)
		(width 0.1651)
		(layer "In15.Cu")
		(net "P5E_PEX3_STN5_RX_DN<91>")
	)
	(segment
		(start 395.07795 -342.16721)
		(end 395.311376 -341.557864)
		(width 0.1651)
		(layer "In15.Cu")
		(net "P5E_PEX3_STN5_RX_DN<91>")
	)
	(segment
		(start 382.76403 -372.381018)
		(end 383.215896 -371.929152)
		(width 0.1651)
		(layer "In15.Cu")
		(net "P5E_PEX3_STN5_RX_DN<91>")
	)
	(segment
		(start 399.146776 -338.234274)
		(end 415.777934 -323.824346)
		(width 0.1651)
		(layer "In15.Cu")
		(net "P5E_PEX3_STN5_RX_DN<91>")
	)
	(segment
		(start 417.173918 -318.320166)
		(end 417.335716 -318.320166)
		(width 0.1143)
		(layer "In15.Cu")
		(net "P5E_PEX3_STN5_RX_DN<91>")
	)
	(segment
		(start 399.146776 -338.234528)
		(end 399.146776 -338.234274)
		(width 0.1651)
		(layer "In15.Cu")
		(net "P5E_PEX3_STN5_RX_DN<91>")
	)
	(segment
		(start 395.311376 -341.557864)
		(end 399.146776 -338.234528)
		(width 0.1651)
		(layer "In15.Cu")
		(net "P5E_PEX3_STN5_RX_DN<91>")
	)
	(segment
		(start 417.335716 -318.320166)
		(end 417.450016 -318.434466)
		(width 0.1143)
		(layer "In15.Cu")
		(net "P5E_PEX3_STN5_RX_DN<91>")
	)
	(segment
		(start 394.43152 -359.483914)
		(end 395.07795 -358.071928)
		(width 0.1651)
		(layer "In15.Cu")
		(net "P5E_PEX3_STN5_RX_DN<91>")
	)
	(segment
		(start 417.450016 -318.434466)
		(end 417.450016 -318.699896)
		(width 0.1143)
		(layer "In15.Cu")
		(net "P5E_PEX3_STN5_RX_DN<91>")
	)
	(segment
		(start 417.070286 -319.895728)
		(end 417.070286 -318.423798)
		(width 0.1143)
		(layer "In15.Cu")
		(net "P5E_PEX3_STN5_RX_DN<91>")
	)
	(segment
		(start 279.273254 -139.029186)
		(end 279.273254 -138.564112)
		(width 0.13208)
		(layer "F.Cu")
		(net "NIC4_AUX_PWR_EN_R")
	)
	(segment
		(start 278.737314 -139.565126)
		(end 279.273254 -139.029186)
		(width 0.13208)
		(layer "F.Cu")
		(net "NIC4_AUX_PWR_EN_R")
	)
	(segment
		(start 278.242268 -139.565126)
		(end 278.737314 -139.565126)
		(width 0.13208)
		(layer "F.Cu")
		(net "NIC4_AUX_PWR_EN_R")
	)
	(via
		(at 279.273254 -138.564112)
		(size 0.508)
		(drill 0.254)
		(layers "F.Cu" "B.Cu")
		(net "NIC4_AUX_PWR_EN_R")
	)
	(segment
		(start 280.665936 -138.421618)
		(end 280.665936 -137.795)
		(width 0.13208)
		(layer "B.Cu")
		(net "NIC4_AUX_PWR_EN_R")
	)
	(segment
		(start 286.164782 -138.54684)
		(end 286.164782 -140.181076)
		(width 0.13208)
		(layer "B.Cu")
		(net "NIC4_AUX_PWR_EN_R")
	)
	(segment
		(start 279.69083 -138.564112)
		(end 279.833324 -138.421618)
		(width 0.13208)
		(layer "B.Cu")
		(net "NIC4_AUX_PWR_EN_R")
	)
	(segment
		(start 280.792936 -137.668)
		(end 285.285942 -137.668)
		(width 0.13208)
		(layer "B.Cu")
		(net "NIC4_AUX_PWR_EN_R")
	)
	(segment
		(start 280.665936 -137.795)
		(end 280.792936 -137.668)
		(width 0.13208)
		(layer "B.Cu")
		(net "NIC4_AUX_PWR_EN_R")
	)
	(segment
		(start 285.285942 -137.668)
		(end 286.164782 -138.54684)
		(width 0.13208)
		(layer "B.Cu")
		(net "NIC4_AUX_PWR_EN_R")
	)
	(segment
		(start 279.273254 -138.564112)
		(end 279.69083 -138.564112)
		(width 0.13208)
		(layer "B.Cu")
		(net "NIC4_AUX_PWR_EN_R")
	)
	(segment
		(start 279.833324 -138.421618)
		(end 280.665936 -138.421618)
		(width 0.13208)
		(layer "B.Cu")
		(net "NIC4_AUX_PWR_EN_R")
	)
	(segment
		(start 155.647136 -110.088934)
		(end 155.96616 -110.407958)
		(width 0.13462)
		(layer "F.Cu")
		(net "P5E_PEX1_STN1_TX_C_DP<22>")
	)
	(segment
		(start 161.654236 -110.245144)
		(end 162.14217 -110.245144)
		(width 0.13462)
		(layer "F.Cu")
		(net "P5E_PEX1_STN1_TX_C_DP<22>")
	)
	(segment
		(start 155.96616 -110.407958)
		(end 161.491422 -110.407958)
		(width 0.13462)
		(layer "F.Cu")
		(net "P5E_PEX1_STN1_TX_C_DP<22>")
	)
	(segment
		(start 161.491422 -110.407958)
		(end 161.654236 -110.245144)
		(width 0.13462)
		(layer "F.Cu")
		(net "P5E_PEX1_STN1_TX_C_DP<22>")
	)
	(segment
		(start 113.707418 -352.311208)
		(end 109.642148 -367.237518)
		(width 0.1651)
		(layer "In15.Cu")
		(net "P5E_PEX1_STN6_RX_DP<109>")
	)
	(segment
		(start 121.184924 -395.087348)
		(end 121.184924 -400.372834)
		(width 0.1651)
		(layer "In15.Cu")
		(net "P5E_PEX1_STN6_RX_DP<109>")
	)
	(segment
		(start 109.955838 -386.674106)
		(end 111.341154 -388.736332)
		(width 0.1651)
		(layer "In15.Cu")
		(net "P5E_PEX1_STN6_RX_DP<109>")
	)
	(segment
		(start 160.929828 -319.79108)
		(end 160.884108 -319.8368)
		(width 0.1143)
		(layer "In15.Cu")
		(net "P5E_PEX1_STN6_RX_DP<109>")
	)
	(segment
		(start 160.491424 -321.181476)
		(end 159.900874 -321.77228)
		(width 0.1651)
		(layer "In15.Cu")
		(net "P5E_PEX1_STN6_RX_DP<109>")
	)
	(segment
		(start 118.37543 -392.896344)
		(end 118.416578 -392.995912)
		(width 0.1651)
		(layer "In15.Cu")
		(net "P5E_PEX1_STN6_RX_DP<109>")
	)
	(segment
		(start 117.319298 -392.458702)
		(end 117.360446 -392.55827)
		(width 0.1651)
		(layer "In15.Cu")
		(net "P5E_PEX1_STN6_RX_DP<109>")
	)
	(segment
		(start 117.818408 -392.748262)
		(end 117.917976 -392.70686)
		(width 0.1651)
		(layer "In15.Cu")
		(net "P5E_PEX1_STN6_RX_DP<109>")
	)
	(segment
		(start 159.900874 -321.77228)
		(end 159.90062 -321.77228)
		(width 0.1651)
		(layer "In15.Cu")
		(net "P5E_PEX1_STN6_RX_DP<109>")
	)
	(segment
		(start 121.184924 -400.372834)
		(end 120.658636 -400.899122)
		(width 0.1651)
		(layer "In15.Cu")
		(net "P5E_PEX1_STN6_RX_DP<109>")
	)
	(segment
		(start 161.168334 -316.229492)
		(end 160.929828 -316.467998)
		(width 0.1143)
		(layer "In15.Cu")
		(net "P5E_PEX1_STN6_RX_DP<109>")
	)
	(segment
		(start 116.861844 -392.269472)
		(end 117.319044 -392.458956)
		(width 0.1651)
		(layer "In15.Cu")
		(net "P5E_PEX1_STN6_RX_DP<109>")
	)
	(segment
		(start 116.861844 -392.269218)
		(end 116.861844 -392.269472)
		(width 0.1651)
		(layer "In15.Cu")
		(net "P5E_PEX1_STN6_RX_DP<109>")
	)
	(segment
		(start 114.282982 -341.133684)
		(end 113.707418 -342.011254)
		(width 0.1651)
		(layer "In15.Cu")
		(net "P5E_PEX1_STN6_RX_DP<109>")
	)
	(segment
		(start 160.884108 -320.232532)
		(end 160.491424 -321.181476)
		(width 0.1651)
		(layer "In15.Cu")
		(net "P5E_PEX1_STN6_RX_DP<109>")
	)
	(segment
		(start 116.304314 -392.120628)
		(end 116.762276 -392.31062)
		(width 0.1651)
		(layer "In15.Cu")
		(net "P5E_PEX1_STN6_RX_DP<109>")
	)
	(segment
		(start 114.447066 -391.268966)
		(end 116.262912 -392.021314)
		(width 0.1651)
		(layer "In15.Cu")
		(net "P5E_PEX1_STN6_RX_DP<109>")
	)
	(segment
		(start 118.974108 -393.144502)
		(end 119.431562 -393.333986)
		(width 0.1651)
		(layer "In15.Cu")
		(net "P5E_PEX1_STN6_RX_DP<109>")
	)
	(segment
		(start 120.310148 -400.772122)
		(end 120.310148 -400.390106)
		(width 0.1651)
		(layer "In15.Cu")
		(net "P5E_PEX1_STN6_RX_DP<109>")
	)
	(segment
		(start 113.707418 -342.011254)
		(end 113.707418 -352.311208)
		(width 0.1651)
		(layer "In15.Cu")
		(net "P5E_PEX1_STN6_RX_DP<109>")
	)
	(segment
		(start 117.319044 -392.458956)
		(end 117.319298 -392.458702)
		(width 0.1651)
		(layer "In15.Cu")
		(net "P5E_PEX1_STN6_RX_DP<109>")
	)
	(segment
		(start 116.262912 -392.021314)
		(end 116.263166 -392.02106)
		(width 0.1651)
		(layer "In15.Cu")
		(net "P5E_PEX1_STN6_RX_DP<109>")
	)
	(segment
		(start 161.500058 -315.849762)
		(end 161.500058 -316.140592)
		(width 0.1143)
		(layer "In15.Cu")
		(net "P5E_PEX1_STN6_RX_DP<109>")
	)
	(segment
		(start 160.884108 -319.8368)
		(end 160.884108 -319.865248)
		(width 0.1143)
		(layer "In15.Cu")
		(net "P5E_PEX1_STN6_RX_DP<109>")
	)
	(segment
		(start 119.431562 -393.333986)
		(end 121.184924 -395.087348)
		(width 0.1651)
		(layer "In15.Cu")
		(net "P5E_PEX1_STN6_RX_DP<109>")
	)
	(segment
		(start 123.314968 -338.235798)
		(end 114.282982 -341.133684)
		(width 0.1651)
		(layer "In15.Cu")
		(net "P5E_PEX1_STN6_RX_DP<109>")
	)
	(segment
		(start 118.416578 -392.995912)
		(end 118.87454 -393.18565)
		(width 0.1651)
		(layer "In15.Cu")
		(net "P5E_PEX1_STN6_RX_DP<109>")
	)
	(segment
		(start 112.89411 -390.002522)
		(end 112.89411 -390.002776)
		(width 0.1651)
		(layer "In15.Cu")
		(net "P5E_PEX1_STN6_RX_DP<109>")
	)
	(segment
		(start 161.411158 -316.229492)
		(end 161.168334 -316.229492)
		(width 0.1143)
		(layer "In15.Cu")
		(net "P5E_PEX1_STN6_RX_DP<109>")
	)
	(segment
		(start 159.310578 -322.362576)
		(end 142.939516 -330.107036)
		(width 0.1651)
		(layer "In15.Cu")
		(net "P5E_PEX1_STN6_RX_DP<109>")
	)
	(segment
		(start 112.89411 -390.002776)
		(end 114.447066 -391.268966)
		(width 0.1651)
		(layer "In15.Cu")
		(net "P5E_PEX1_STN6_RX_DP<109>")
	)
	(segment
		(start 142.939516 -330.107036)
		(end 123.314968 -338.235798)
		(width 0.1651)
		(layer "In15.Cu")
		(net "P5E_PEX1_STN6_RX_DP<109>")
	)
	(segment
		(start 160.884108 -319.865248)
		(end 160.884108 -320.232532)
		(width 0.1651)
		(layer "In15.Cu")
		(net "P5E_PEX1_STN6_RX_DP<109>")
	)
	(segment
		(start 161.500058 -316.140592)
		(end 161.411158 -316.229492)
		(width 0.1143)
		(layer "In15.Cu")
		(net "P5E_PEX1_STN6_RX_DP<109>")
	)
	(segment
		(start 117.360446 -392.55827)
		(end 117.818408 -392.748262)
		(width 0.1651)
		(layer "In15.Cu")
		(net "P5E_PEX1_STN6_RX_DP<109>")
	)
	(segment
		(start 111.341154 -388.736332)
		(end 112.89411 -390.002522)
		(width 0.1651)
		(layer "In15.Cu")
		(net "P5E_PEX1_STN6_RX_DP<109>")
	)
	(segment
		(start 109.642148 -367.237518)
		(end 109.52353 -385.118102)
		(width 0.1651)
		(layer "In15.Cu")
		(net "P5E_PEX1_STN6_RX_DP<109>")
	)
	(segment
		(start 120.658636 -400.899122)
		(end 120.437148 -400.899122)
		(width 0.1651)
		(layer "In15.Cu")
		(net "P5E_PEX1_STN6_RX_DP<109>")
	)
	(segment
		(start 117.917976 -392.70686)
		(end 118.37543 -392.896344)
		(width 0.1651)
		(layer "In15.Cu")
		(net "P5E_PEX1_STN6_RX_DP<109>")
	)
	(segment
		(start 116.762276 -392.31062)
		(end 116.861844 -392.269218)
		(width 0.1651)
		(layer "In15.Cu")
		(net "P5E_PEX1_STN6_RX_DP<109>")
	)
	(segment
		(start 116.263166 -392.02106)
		(end 116.304314 -392.120628)
		(width 0.1651)
		(layer "In15.Cu")
		(net "P5E_PEX1_STN6_RX_DP<109>")
	)
	(segment
		(start 120.437148 -400.899122)
		(end 120.310148 -400.772122)
		(width 0.1651)
		(layer "In15.Cu")
		(net "P5E_PEX1_STN6_RX_DP<109>")
	)
	(segment
		(start 159.90062 -321.77228)
		(end 159.310578 -322.362576)
		(width 0.1651)
		(layer "In15.Cu")
		(net "P5E_PEX1_STN6_RX_DP<109>")
	)
	(segment
		(start 118.87454 -393.18565)
		(end 118.974108 -393.144502)
		(width 0.1651)
		(layer "In15.Cu")
		(net "P5E_PEX1_STN6_RX_DP<109>")
	)
	(segment
		(start 109.52353 -385.118102)
		(end 109.955838 -386.674106)
		(width 0.1651)
		(layer "In15.Cu")
		(net "P5E_PEX1_STN6_RX_DP<109>")
	)
	(segment
		(start 160.929828 -316.467998)
		(end 160.929828 -319.79108)
		(width 0.1143)
		(layer "In15.Cu")
		(net "P5E_PEX1_STN6_RX_DP<109>")
	)
	(segment
		(start 335.75498 -340.4108)
		(end 296.813478 -326.054466)
		(width 0.1651)
		(layer "In9.Cu")
		(net "P5E_PEX2_STN5_RX_DN<81>")
	)
	(segment
		(start 334.364076 -398.38122)
		(end 334.815942 -397.929354)
		(width 0.1651)
		(layer "In9.Cu")
		(net "P5E_PEX2_STN5_RX_DN<81>")
	)
	(segment
		(start 336.338164 -393.453112)
		(end 342.863932 -390.111234)
		(width 0.1651)
		(layer "In9.Cu")
		(net "P5E_PEX2_STN5_RX_DN<81>")
	)
	(segment
		(start 352.455226 -385.70535)
		(end 352.74504 -369.941856)
		(width 0.1651)
		(layer "In9.Cu")
		(net "P5E_PEX2_STN5_RX_DN<81>")
	)
	(segment
		(start 336.392774 -341.809324)
		(end 335.75498 -340.4108)
		(width 0.1651)
		(layer "In9.Cu")
		(net "P5E_PEX2_STN5_RX_DN<81>")
	)
	(segment
		(start 334.815942 -395.394942)
		(end 335.16697 -394.624306)
		(width 0.1651)
		(layer "In9.Cu")
		(net "P5E_PEX2_STN5_RX_DN<81>")
	)
	(segment
		(start 291.47008 -318.434212)
		(end 291.584126 -318.320166)
		(width 0.1143)
		(layer "In9.Cu")
		(net "P5E_PEX2_STN5_RX_DN<81>")
	)
	(segment
		(start 294.09136 -324.31228)
		(end 292.907212 -323.128132)
		(width 0.1651)
		(layer "In9.Cu")
		(net "P5E_PEX2_STN5_RX_DN<81>")
	)
	(segment
		(start 351.788984 -386.774436)
		(end 352.134678 -386.494274)
		(width 0.1651)
		(layer "In9.Cu")
		(net "P5E_PEX2_STN5_RX_DN<81>")
	)
	(segment
		(start 333.68996 -398.890236)
		(end 333.68996 -398.50822)
		(width 0.1651)
		(layer "In9.Cu")
		(net "P5E_PEX2_STN5_RX_DN<81>")
	)
	(segment
		(start 336.69732 -358.7877)
		(end 336.392774 -358.483154)
		(width 0.1651)
		(layer "In9.Cu")
		(net "P5E_PEX2_STN5_RX_DN<81>")
	)
	(segment
		(start 352.74504 -369.941856)
		(end 351.960434 -368.41811)
		(width 0.1651)
		(layer "In9.Cu")
		(net "P5E_PEX2_STN5_RX_DN<81>")
	)
	(segment
		(start 333.68996 -398.50822)
		(end 333.81696 -398.38122)
		(width 0.1651)
		(layer "In9.Cu")
		(net "P5E_PEX2_STN5_RX_DN<81>")
	)
	(segment
		(start 352.134678 -386.494274)
		(end 352.261678 -386.308346)
		(width 0.1651)
		(layer "In9.Cu")
		(net "P5E_PEX2_STN5_RX_DN<81>")
	)
	(segment
		(start 342.863932 -390.111234)
		(end 351.788984 -386.774436)
		(width 0.1651)
		(layer "In9.Cu")
		(net "P5E_PEX2_STN5_RX_DN<81>")
	)
	(segment
		(start 346.352114 -363.818678)
		(end 340.11108 -360.30916)
		(width 0.1651)
		(layer "In9.Cu")
		(net "P5E_PEX2_STN5_RX_DN<81>")
	)
	(segment
		(start 296.813478 -326.054466)
		(end 294.09136 -324.31228)
		(width 0.1651)
		(layer "In9.Cu")
		(net "P5E_PEX2_STN5_RX_DN<81>")
	)
	(segment
		(start 336.392774 -358.483154)
		(end 336.392774 -341.809324)
		(width 0.1651)
		(layer "In9.Cu")
		(net "P5E_PEX2_STN5_RX_DN<81>")
	)
	(segment
		(start 291.5158 -321.046094)
		(end 291.5158 -319.916048)
		(width 0.1651)
		(layer "In9.Cu")
		(net "P5E_PEX2_STN5_RX_DN<81>")
	)
	(segment
		(start 292.907212 -323.128132)
		(end 291.5158 -321.046094)
		(width 0.1651)
		(layer "In9.Cu")
		(net "P5E_PEX2_STN5_RX_DN<81>")
	)
	(segment
		(start 291.584126 -318.320166)
		(end 291.76091 -318.320166)
		(width 0.1143)
		(layer "In9.Cu")
		(net "P5E_PEX2_STN5_RX_DN<81>")
	)
	(segment
		(start 291.76091 -318.320166)
		(end 291.84981 -318.409066)
		(width 0.1143)
		(layer "In9.Cu")
		(net "P5E_PEX2_STN5_RX_DN<81>")
	)
	(segment
		(start 340.11108 -360.30916)
		(end 336.69732 -358.7877)
		(width 0.1651)
		(layer "In9.Cu")
		(net "P5E_PEX2_STN5_RX_DN<81>")
	)
	(segment
		(start 333.81696 -398.38122)
		(end 334.364076 -398.38122)
		(width 0.1651)
		(layer "In9.Cu")
		(net "P5E_PEX2_STN5_RX_DN<81>")
	)
	(segment
		(start 335.16697 -394.624306)
		(end 336.338164 -393.453112)
		(width 0.1651)
		(layer "In9.Cu")
		(net "P5E_PEX2_STN5_RX_DN<81>")
	)
	(segment
		(start 291.84981 -318.409066)
		(end 291.84981 -318.699896)
		(width 0.1143)
		(layer "In9.Cu")
		(net "P5E_PEX2_STN5_RX_DN<81>")
	)
	(segment
		(start 291.5158 -319.8876)
		(end 291.47008 -319.84188)
		(width 0.1143)
		(layer "In9.Cu")
		(net "P5E_PEX2_STN5_RX_DN<81>")
	)
	(segment
		(start 351.960434 -368.41811)
		(end 346.352114 -363.818678)
		(width 0.1651)
		(layer "In9.Cu")
		(net "P5E_PEX2_STN5_RX_DN<81>")
	)
	(segment
		(start 291.5158 -319.916048)
		(end 291.5158 -319.8876)
		(width 0.1143)
		(layer "In9.Cu")
		(net "P5E_PEX2_STN5_RX_DN<81>")
	)
	(segment
		(start 291.47008 -319.84188)
		(end 291.47008 -318.434212)
		(width 0.1143)
		(layer "In9.Cu")
		(net "P5E_PEX2_STN5_RX_DN<81>")
	)
	(segment
		(start 352.261678 -386.308346)
		(end 352.455226 -385.70535)
		(width 0.1651)
		(layer "In9.Cu")
		(net "P5E_PEX2_STN5_RX_DN<81>")
	)
	(segment
		(start 334.815942 -397.929354)
		(end 334.815942 -395.394942)
		(width 0.1651)
		(layer "In9.Cu")
		(net "P5E_PEX2_STN5_RX_DN<81>")
	)
	(segment
		(start 430.374552 -155.7909)
		(end 422.224454 -155.7909)
		(width 0.13462)
		(layer "F.Cu")
		(net "P5E_PEX3_STN0_TX_C_DP<15>")
	)
	(segment
		(start 422.224454 -155.7909)
		(end 422.06037 -155.954984)
		(width 0.13462)
		(layer "F.Cu")
		(net "P5E_PEX3_STN0_TX_C_DP<15>")
	)
	(segment
		(start 422.06037 -155.954984)
		(end 421.557704 -155.954984)
		(width 0.13462)
		(layer "F.Cu")
		(net "P5E_PEX3_STN0_TX_C_DP<15>")
	)
	(segment
		(start 430.694846 -156.111194)
		(end 430.374552 -155.7909)
		(width 0.13462)
		(layer "F.Cu")
		(net "P5E_PEX3_STN0_TX_C_DP<15>")
	)
	(segment
		(start 390.411208 -351.317306)
		(end 390.70534 -351.611438)
		(width 0.13462)
		(layer "F.Cu")
		(net "P5E_PEX3_STN5_TX_C_DN<81>")
	)
	(segment
		(start 390.73074 -350.365314)
		(end 390.411208 -350.684846)
		(width 0.13462)
		(layer "F.Cu")
		(net "P5E_PEX3_STN5_TX_C_DN<81>")
	)
	(segment
		(start 390.411208 -350.684846)
		(end 390.411208 -351.317306)
		(width 0.13462)
		(layer "F.Cu")
		(net "P5E_PEX3_STN5_TX_C_DN<81>")
	)
	(segment
		(start 377.689872 -406.690068)
		(end 377.689872 -406.308052)
		(width 0.1651)
		(layer "In7.Cu")
		(net "P5E_PEX3_STN5_TX_C_DN<81>")
	)
	(segment
		(start 379.072648 -394.761466)
		(end 383.593594 -391.605516)
		(width 0.1651)
		(layer "In7.Cu")
		(net "P5E_PEX3_STN5_TX_C_DN<81>")
	)
	(segment
		(start 395.950948 -386.656834)
		(end 396.060168 -386.613146)
		(width 0.1651)
		(layer "In7.Cu")
		(net "P5E_PEX3_STN5_TX_C_DN<81>")
	)
	(segment
		(start 396.543022 -369.799108)
		(end 396.009622 -368.140234)
		(width 0.1651)
		(layer "In7.Cu")
		(net "P5E_PEX3_STN5_TX_C_DN<81>")
	)
	(segment
		(start 396.060168 -386.613146)
		(end 396.348712 -385.933188)
		(width 0.1651)
		(layer "In7.Cu")
		(net "P5E_PEX3_STN5_TX_C_DN<81>")
	)
	(segment
		(start 396.009622 -368.140234)
		(end 388.86003 -358.297226)
		(width 0.1651)
		(layer "In7.Cu")
		(net "P5E_PEX3_STN5_TX_C_DN<81>")
	)
	(segment
		(start 396.348712 -385.933188)
		(end 396.543022 -369.799108)
		(width 0.1651)
		(layer "In7.Cu")
		(net "P5E_PEX3_STN5_TX_C_DN<81>")
	)
	(segment
		(start 378.815854 -405.729186)
		(end 378.815854 -396.089378)
		(width 0.1651)
		(layer "In7.Cu")
		(net "P5E_PEX3_STN5_TX_C_DN<81>")
	)
	(segment
		(start 390.41451 -352.473006)
		(end 390.41451 -351.902268)
		(width 0.1651)
		(layer "In7.Cu")
		(net "P5E_PEX3_STN5_TX_C_DN<81>")
	)
	(segment
		(start 388.86003 -354.027486)
		(end 390.41451 -352.473006)
		(width 0.1651)
		(layer "In7.Cu")
		(net "P5E_PEX3_STN5_TX_C_DN<81>")
	)
	(segment
		(start 377.816872 -406.181052)
		(end 378.363988 -406.181052)
		(width 0.1651)
		(layer "In7.Cu")
		(net "P5E_PEX3_STN5_TX_C_DN<81>")
	)
	(segment
		(start 383.593594 -391.605516)
		(end 395.950948 -386.656834)
		(width 0.1651)
		(layer "In7.Cu")
		(net "P5E_PEX3_STN5_TX_C_DN<81>")
	)
	(segment
		(start 388.86003 -358.297226)
		(end 388.86003 -354.027486)
		(width 0.1651)
		(layer "In7.Cu")
		(net "P5E_PEX3_STN5_TX_C_DN<81>")
	)
	(segment
		(start 377.689872 -406.308052)
		(end 377.816872 -406.181052)
		(width 0.1651)
		(layer "In7.Cu")
		(net "P5E_PEX3_STN5_TX_C_DN<81>")
	)
	(segment
		(start 378.363988 -406.181052)
		(end 378.815854 -405.729186)
		(width 0.1651)
		(layer "In7.Cu")
		(net "P5E_PEX3_STN5_TX_C_DN<81>")
	)
	(segment
		(start 378.815854 -396.089378)
		(end 379.072648 -394.761466)
		(width 0.1651)
		(layer "In7.Cu")
		(net "P5E_PEX3_STN5_TX_C_DN<81>")
	)
	(segment
		(start 390.41451 -351.902268)
		(end 390.70534 -351.611438)
		(width 0.1651)
		(layer "In7.Cu")
		(net "P5E_PEX3_STN5_TX_C_DN<81>")
	)
	(segment
		(start 283.878782 -156.687012)
		(end 283.878782 -157.0736)
		(width 0.13208)
		(layer "F.Cu")
		(net "NIC4_RBT_ARB_IN")
	)
	(segment
		(start 283.751782 -156.560012)
		(end 283.878782 -156.687012)
		(width 0.13208)
		(layer "F.Cu")
		(net "NIC4_RBT_ARB_IN")
	)
	(segment
		(start 282.842462 -156.560012)
		(end 283.751782 -156.560012)
		(width 0.13208)
		(layer "F.Cu")
		(net "NIC4_RBT_ARB_IN")
	)
	(via
		(at 283.878782 -157.0736)
		(size 0.508)
		(drill 0.254)
		(layers "F.Cu" "B.Cu")
		(net "NIC4_RBT_ARB_IN")
	)
	(segment
		(start 282.155392 -157.0736)
		(end 283.878782 -157.0736)
		(width 0.13208)
		(layer "B.Cu")
		(net "NIC4_RBT_ARB_IN")
	)
	(segment
		(start 161.491168 -101.407722)
		(end 153.927048 -101.407722)
		(width 0.13462)
		(layer "F.Cu")
		(net "P5E_PEX1_STN1_TX_C_DN<17>")
	)
	(segment
		(start 153.927048 -101.407722)
		(end 153.614628 -101.095302)
		(width 0.13462)
		(layer "F.Cu")
		(net "P5E_PEX1_STN1_TX_C_DN<17>")
	)
	(segment
		(start 161.653982 -101.244908)
		(end 161.491168 -101.407722)
		(width 0.13462)
		(layer "F.Cu")
		(net "P5E_PEX1_STN1_TX_C_DN<17>")
	)
	(segment
		(start 162.14217 -101.244908)
		(end 161.653982 -101.244908)
		(width 0.13462)
		(layer "F.Cu")
		(net "P5E_PEX1_STN1_TX_C_DN<17>")
	)
	(segment
		(start 413.50311 -152.487376)
		(end 413.793686 -152.1968)
		(width 0.13462)
		(layer "F.Cu")
		(net "P5E_PEX3_STN0_RX_DP<13>")
	)
	(segment
		(start 413.793686 -152.1968)
		(end 416.316668 -152.1968)
		(width 0.13462)
		(layer "F.Cu")
		(net "P5E_PEX3_STN0_RX_DP<13>")
	)
	(segment
		(start 416.316668 -152.1968)
		(end 416.47491 -152.355042)
		(width 0.13462)
		(layer "F.Cu")
		(net "P5E_PEX3_STN0_RX_DP<13>")
	)
	(segment
		(start 416.47491 -152.355042)
		(end 416.95751 -152.355042)
		(width 0.13462)
		(layer "F.Cu")
		(net "P5E_PEX3_STN0_RX_DP<13>")
	)
	(segment
		(start 417.78174 -155.185618)
		(end 418.82568 -156.730954)
		(width 0.1651)
		(layer "In5.Cu")
		(net "P5E_PEX3_STN0_RX_DP<13>")
	)
	(segment
		(start 419.455854 -157.822646)
		(end 419.733476 -158.233364)
		(width 0.1651)
		(layer "In5.Cu")
		(net "P5E_PEX3_STN0_RX_DP<13>")
	)
	(segment
		(start 413.50311 -152.487376)
		(end 413.79394 -152.196546)
		(width 0.1651)
		(layer "In5.Cu")
		(net "P5E_PEX3_STN0_RX_DP<13>")
	)
	(segment
		(start 424.694604 -273.670014)
		(end 424.935396 -273.670014)
		(width 0.1143)
		(layer "In5.Cu")
		(net "P5E_PEX3_STN0_RX_DP<13>")
	)
	(segment
		(start 424.47972 -271.600168)
		(end 424.47972 -273.45513)
		(width 0.1143)
		(layer "In5.Cu")
		(net "P5E_PEX3_STN0_RX_DP<13>")
	)
	(segment
		(start 424.935396 -273.670014)
		(end 425.049696 -273.784314)
		(width 0.1143)
		(layer "In5.Cu")
		(net "P5E_PEX3_STN0_RX_DP<13>")
	)
	(segment
		(start 424.47972 -273.45513)
		(end 424.694604 -273.670014)
		(width 0.1143)
		(layer "In5.Cu")
		(net "P5E_PEX3_STN0_RX_DP<13>")
	)
	(segment
		(start 416.92068 -153.119074)
		(end 417.78174 -155.185618)
		(width 0.1651)
		(layer "In5.Cu")
		(net "P5E_PEX3_STN0_RX_DP<13>")
	)
	(segment
		(start 424.434 -270.513048)
		(end 424.434 -271.526)
		(width 0.1651)
		(layer "In5.Cu")
		(net "P5E_PEX3_STN0_RX_DP<13>")
	)
	(segment
		(start 419.202616 -157.288992)
		(end 419.47973 -157.699202)
		(width 0.1651)
		(layer "In5.Cu")
		(net "P5E_PEX3_STN0_RX_DP<13>")
	)
	(segment
		(start 419.733476 -158.233364)
		(end 419.856666 -158.25724)
		(width 0.1651)
		(layer "In5.Cu")
		(net "P5E_PEX3_STN0_RX_DP<13>")
	)
	(segment
		(start 418.82568 -156.730954)
		(end 418.801804 -156.854398)
		(width 0.1651)
		(layer "In5.Cu")
		(net "P5E_PEX3_STN0_RX_DP<13>")
	)
	(segment
		(start 424.950382 -267.84427)
		(end 424.434 -270.513048)
		(width 0.1651)
		(layer "In5.Cu")
		(net "P5E_PEX3_STN0_RX_DP<13>")
	)
	(segment
		(start 413.79394 -152.196546)
		(end 415.998152 -152.196546)
		(width 0.1651)
		(layer "In5.Cu")
		(net "P5E_PEX3_STN0_RX_DP<13>")
	)
	(segment
		(start 420.31539 -158.936436)
		(end 421.321484 -161.356548)
		(width 0.1651)
		(layer "In5.Cu")
		(net "P5E_PEX3_STN0_RX_DP<13>")
	)
	(segment
		(start 424.875706 -260.651244)
		(end 424.950382 -267.84427)
		(width 0.1651)
		(layer "In5.Cu")
		(net "P5E_PEX3_STN0_RX_DP<13>")
	)
	(segment
		(start 415.998152 -152.196546)
		(end 416.92068 -153.119074)
		(width 0.1651)
		(layer "In5.Cu")
		(net "P5E_PEX3_STN0_RX_DP<13>")
	)
	(segment
		(start 424.434 -271.526)
		(end 424.434 -271.554448)
		(width 0.1143)
		(layer "In5.Cu")
		(net "P5E_PEX3_STN0_RX_DP<13>")
	)
	(segment
		(start 418.801804 -156.854398)
		(end 419.079172 -157.265116)
		(width 0.1651)
		(layer "In5.Cu")
		(net "P5E_PEX3_STN0_RX_DP<13>")
	)
	(segment
		(start 419.47973 -157.699202)
		(end 419.455854 -157.822646)
		(width 0.1651)
		(layer "In5.Cu")
		(net "P5E_PEX3_STN0_RX_DP<13>")
	)
	(segment
		(start 425.049696 -273.784314)
		(end 425.049696 -274.049744)
		(width 0.1143)
		(layer "In5.Cu")
		(net "P5E_PEX3_STN0_RX_DP<13>")
	)
	(segment
		(start 424.434 -271.554448)
		(end 424.47972 -271.600168)
		(width 0.1143)
		(layer "In5.Cu")
		(net "P5E_PEX3_STN0_RX_DP<13>")
	)
	(segment
		(start 419.856666 -158.25724)
		(end 420.31539 -158.936436)
		(width 0.1651)
		(layer "In5.Cu")
		(net "P5E_PEX3_STN0_RX_DP<13>")
	)
	(segment
		(start 421.321484 -161.356548)
		(end 424.875706 -260.651244)
		(width 0.1651)
		(layer "In5.Cu")
		(net "P5E_PEX3_STN0_RX_DP<13>")
	)
	(segment
		(start 419.079172 -157.265116)
		(end 419.202616 -157.288992)
		(width 0.1651)
		(layer "In5.Cu")
		(net "P5E_PEX3_STN0_RX_DP<13>")
	)
	(segment
		(start 393.520168 -356.831138)
		(end 393.520168 -357.463598)
		(width 0.13462)
		(layer "F.Cu")
		(net "P5E_PEX3_STN5_TX_C_DN<83>")
	)
	(segment
		(start 393.520168 -357.463598)
		(end 393.8143 -357.75773)
		(width 0.13462)
		(layer "F.Cu")
		(net "P5E_PEX3_STN5_TX_C_DN<83>")
	)
	(segment
		(start 393.8397 -356.511606)
		(end 393.520168 -356.831138)
		(width 0.13462)
		(layer "F.Cu")
		(net "P5E_PEX3_STN5_TX_C_DN<83>")
	)
	(segment
		(start 398.572482 -369.75415)
		(end 398.050512 -367.616994)
		(width 0.1651)
		(layer "In7.Cu")
		(net "P5E_PEX3_STN5_TX_C_DN<83>")
	)
	(segment
		(start 382.089914 -406.308052)
		(end 382.216914 -406.181052)
		(width 0.1651)
		(layer "In7.Cu")
		(net "P5E_PEX3_STN5_TX_C_DN<83>")
	)
	(segment
		(start 383.215896 -395.646656)
		(end 383.651506 -394.609574)
		(width 0.1651)
		(layer "In7.Cu")
		(net "P5E_PEX3_STN5_TX_C_DN<83>")
	)
	(segment
		(start 384.888486 -393.372848)
		(end 397.439642 -388.197598)
		(width 0.1651)
		(layer "In7.Cu")
		(net "P5E_PEX3_STN5_TX_C_DN<83>")
	)
	(segment
		(start 383.651506 -394.609574)
		(end 384.888486 -393.372848)
		(width 0.1651)
		(layer "In7.Cu")
		(net "P5E_PEX3_STN5_TX_C_DN<83>")
	)
	(segment
		(start 393.52347 -358.753918)
		(end 393.52347 -358.04856)
		(width 0.1651)
		(layer "In7.Cu")
		(net "P5E_PEX3_STN5_TX_C_DN<83>")
	)
	(segment
		(start 382.76403 -406.181052)
		(end 383.215896 -405.729186)
		(width 0.1651)
		(layer "In7.Cu")
		(net "P5E_PEX3_STN5_TX_C_DN<83>")
	)
	(segment
		(start 397.439642 -388.197598)
		(end 398.30248 -386.6388)
		(width 0.1651)
		(layer "In7.Cu")
		(net "P5E_PEX3_STN5_TX_C_DN<83>")
	)
	(segment
		(start 398.30248 -386.6388)
		(end 398.572482 -369.75415)
		(width 0.1651)
		(layer "In7.Cu")
		(net "P5E_PEX3_STN5_TX_C_DN<83>")
	)
	(segment
		(start 383.215896 -405.729186)
		(end 383.215896 -395.646656)
		(width 0.1651)
		(layer "In7.Cu")
		(net "P5E_PEX3_STN5_TX_C_DN<83>")
	)
	(segment
		(start 398.050512 -367.616994)
		(end 393.52347 -358.753918)
		(width 0.1651)
		(layer "In7.Cu")
		(net "P5E_PEX3_STN5_TX_C_DN<83>")
	)
	(segment
		(start 382.216914 -406.181052)
		(end 382.76403 -406.181052)
		(width 0.1651)
		(layer "In7.Cu")
		(net "P5E_PEX3_STN5_TX_C_DN<83>")
	)
	(segment
		(start 393.52347 -358.04856)
		(end 393.8143 -357.75773)
		(width 0.1651)
		(layer "In7.Cu")
		(net "P5E_PEX3_STN5_TX_C_DN<83>")
	)
	(segment
		(start 382.089914 -406.690068)
		(end 382.089914 -406.308052)
		(width 0.1651)
		(layer "In7.Cu")
		(net "P5E_PEX3_STN5_TX_C_DN<83>")
	)
	(segment
		(start 278.242268 -97.045018)
		(end 274.790408 -97.045018)
		(width 0.13208)
		(layer "F.Cu")
		(net "PRSNTB3_NIC4_N")
	)
	(segment
		(start 271.360392 -96.1644)
		(end 271.360392 -97.1804)
		(width 0.13208)
		(layer "F.Cu")
		(net "PRSNTB3_NIC4_N")
	)
	(segment
		(start 274.655026 -97.1804)
		(end 272.567908 -97.1804)
		(width 0.13208)
		(layer "F.Cu")
		(net "PRSNTB3_NIC4_N")
	)
	(segment
		(start 272.567908 -97.1804)
		(end 271.360392 -97.1804)
		(width 0.13208)
		(layer "F.Cu")
		(net "PRSNTB3_NIC4_N")
	)
	(segment
		(start 274.790408 -97.045018)
		(end 274.655026 -97.1804)
		(width 0.13208)
		(layer "F.Cu")
		(net "PRSNTB3_NIC4_N")
	)
	(via
		(at 272.567908 -97.1804)
		(size 0.762)
		(drill 0.381)
		(layers "F.Cu" "B.Cu")
		(net "PRSNTB3_NIC4_N")
	)
	(segment
		(start 168.04767 -132.527802)
		(end 168.342564 -132.232908)
		(width 0.13462)
		(layer "F.Cu")
		(net "P5E_PEX1_STN1_RX_DP<29>")
	)
	(segment
		(start 167.393112 -132.527802)
		(end 168.04767 -132.527802)
		(width 0.13462)
		(layer "F.Cu")
		(net "P5E_PEX1_STN1_RX_DP<29>")
	)
	(segment
		(start 167.230298 -132.364988)
		(end 167.393112 -132.527802)
		(width 0.13462)
		(layer "F.Cu")
		(net "P5E_PEX1_STN1_RX_DP<29>")
	)
	(segment
		(start 166.742364 -132.364988)
		(end 167.230298 -132.364988)
		(width 0.13462)
		(layer "F.Cu")
		(net "P5E_PEX1_STN1_RX_DP<29>")
	)
	(segment
		(start 165.943788 -134.100824)
		(end 167.3606 -132.759196)
		(width 0.1651)
		(layer "In5.Cu")
		(net "P5E_PEX1_STN1_RX_DP<29>")
	)
	(segment
		(start 188.0997 -275.684488)
		(end 187.985146 -275.569934)
		(width 0.1143)
		(layer "In5.Cu")
		(net "P5E_PEX1_STN1_RX_DP<29>")
	)
	(segment
		(start 164.769546 -140.713206)
		(end 164.769546 -136.936988)
		(width 0.1651)
		(layer "In5.Cu")
		(net "P5E_PEX1_STN1_RX_DP<29>")
	)
	(segment
		(start 158.316422 -146.854926)
		(end 158.537656 -146.58467)
		(width 0.1651)
		(layer "In5.Cu")
		(net "P5E_PEX1_STN1_RX_DP<29>")
	)
	(segment
		(start 187.744354 -275.569934)
		(end 187.52947 -275.35505)
		(width 0.1143)
		(layer "In5.Cu")
		(net "P5E_PEX1_STN1_RX_DP<29>")
	)
	(segment
		(start 167.466772 -132.653024)
		(end 167.778684 -132.523738)
		(width 0.1651)
		(layer "In5.Cu")
		(net "P5E_PEX1_STN1_RX_DP<29>")
	)
	(segment
		(start 157.823408 -147.76069)
		(end 158.316422 -146.854926)
		(width 0.1651)
		(layer "In5.Cu")
		(net "P5E_PEX1_STN1_RX_DP<29>")
	)
	(segment
		(start 158.537656 -146.58467)
		(end 158.965138 -146.226022)
		(width 0.1651)
		(layer "In5.Cu")
		(net "P5E_PEX1_STN1_RX_DP<29>")
	)
	(segment
		(start 163.92525 -142.75181)
		(end 164.769546 -140.713206)
		(width 0.1651)
		(layer "In5.Cu")
		(net "P5E_PEX1_STN1_RX_DP<29>")
	)
	(segment
		(start 187.985146 -275.569934)
		(end 187.744354 -275.569934)
		(width 0.1143)
		(layer "In5.Cu")
		(net "P5E_PEX1_STN1_RX_DP<29>")
	)
	(segment
		(start 158.410148 -156.780992)
		(end 157.823408 -147.76069)
		(width 0.1651)
		(layer "In5.Cu")
		(net "P5E_PEX1_STN1_RX_DP<29>")
	)
	(segment
		(start 187.52947 -271.848072)
		(end 187.48375 -271.802352)
		(width 0.1143)
		(layer "In5.Cu")
		(net "P5E_PEX1_STN1_RX_DP<29>")
	)
	(segment
		(start 168.051734 -132.523738)
		(end 168.342564 -132.232908)
		(width 0.1651)
		(layer "In5.Cu")
		(net "P5E_PEX1_STN1_RX_DP<29>")
	)
	(segment
		(start 161.186876 -145.513806)
		(end 161.615882 -145.0848)
		(width 0.1651)
		(layer "In5.Cu")
		(net "P5E_PEX1_STN1_RX_DP<29>")
	)
	(segment
		(start 167.3606 -132.759196)
		(end 167.466772 -132.653024)
		(width 0.1651)
		(layer "In5.Cu")
		(net "P5E_PEX1_STN1_RX_DP<29>")
	)
	(segment
		(start 159.140398 -160.904428)
		(end 158.410148 -156.780992)
		(width 0.1651)
		(layer "In5.Cu")
		(net "P5E_PEX1_STN1_RX_DP<29>")
	)
	(segment
		(start 162.022536 -144.47647)
		(end 163.92525 -142.75181)
		(width 0.1651)
		(layer "In5.Cu")
		(net "P5E_PEX1_STN1_RX_DP<29>")
	)
	(segment
		(start 187.52947 -275.35505)
		(end 187.52947 -271.848072)
		(width 0.1143)
		(layer "In5.Cu")
		(net "P5E_PEX1_STN1_RX_DP<29>")
	)
	(segment
		(start 158.965138 -146.226022)
		(end 161.186876 -145.513806)
		(width 0.1651)
		(layer "In5.Cu")
		(net "P5E_PEX1_STN1_RX_DP<29>")
	)
	(segment
		(start 161.615882 -145.0848)
		(end 162.022536 -144.47647)
		(width 0.1651)
		(layer "In5.Cu")
		(net "P5E_PEX1_STN1_RX_DP<29>")
	)
	(segment
		(start 187.48375 -267.498322)
		(end 159.140398 -160.904428)
		(width 0.1651)
		(layer "In5.Cu")
		(net "P5E_PEX1_STN1_RX_DP<29>")
	)
	(segment
		(start 164.769546 -136.936988)
		(end 165.943788 -134.100824)
		(width 0.1651)
		(layer "In5.Cu")
		(net "P5E_PEX1_STN1_RX_DP<29>")
	)
	(segment
		(start 167.778684 -132.523738)
		(end 168.051734 -132.523738)
		(width 0.1651)
		(layer "In5.Cu")
		(net "P5E_PEX1_STN1_RX_DP<29>")
	)
	(segment
		(start 188.0997 -275.949664)
		(end 188.0997 -275.684488)
		(width 0.1143)
		(layer "In5.Cu")
		(net "P5E_PEX1_STN1_RX_DP<29>")
	)
	(segment
		(start 187.48375 -271.773904)
		(end 187.48375 -267.498322)
		(width 0.1651)
		(layer "In5.Cu")
		(net "P5E_PEX1_STN1_RX_DP<29>")
	)
	(segment
		(start 187.48375 -271.802352)
		(end 187.48375 -271.773904)
		(width 0.1143)
		(layer "In5.Cu")
		(net "P5E_PEX1_STN1_RX_DP<29>")
	)
	(segment
		(start 111.862108 -345.465146)
		(end 112.156748 -345.170506)
		(width 0.13462)
		(layer "F.Cu")
		(net "P5E_PEX1_STN6_TX_C_DP<111>")
	)
	(segment
		(start 112.156748 -345.170506)
		(end 112.156748 -344.539062)
		(width 0.13462)
		(layer "F.Cu")
		(net "P5E_PEX1_STN6_TX_C_DP<111>")
	)
	(segment
		(start 112.156748 -344.539062)
		(end 111.836708 -344.219022)
		(width 0.13462)
		(layer "F.Cu")
		(net "P5E_PEX1_STN6_TX_C_DP<111>")
	)
	(segment
		(start 112.014254 -391.90168)
		(end 112.139222 -391.88898)
		(width 0.1651)
		(layer "In13.Cu")
		(net "P5E_PEX1_STN6_TX_C_DP<111>")
	)
	(segment
		(start 110.724696 -390.849866)
		(end 111.108744 -391.163048)
		(width 0.1651)
		(layer "In13.Cu")
		(net "P5E_PEX1_STN6_TX_C_DP<111>")
	)
	(segment
		(start 107.211368 -384.148838)
		(end 108.138468 -387.488938)
		(width 0.1651)
		(layer "In13.Cu")
		(net "P5E_PEX1_STN6_TX_C_DP<111>")
	)
	(segment
		(start 116.34089 -394.416788)
		(end 116.784882 -394.86078)
		(width 0.1651)
		(layer "In13.Cu")
		(net "P5E_PEX1_STN6_TX_C_DP<111>")
	)
	(segment
		(start 108.138468 -387.488938)
		(end 109.829854 -390.00557)
		(width 0.1651)
		(layer "In13.Cu")
		(net "P5E_PEX1_STN6_TX_C_DP<111>")
	)
	(segment
		(start 111.630206 -391.588498)
		(end 112.014254 -391.90168)
		(width 0.1651)
		(layer "In13.Cu")
		(net "P5E_PEX1_STN6_TX_C_DP<111>")
	)
	(segment
		(start 110.711742 -390.724644)
		(end 110.724696 -390.849866)
		(width 0.1651)
		(layer "In13.Cu")
		(net "P5E_PEX1_STN6_TX_C_DP<111>")
	)
	(segment
		(start 114.101118 -393.488926)
		(end 116.34089 -394.416788)
		(width 0.1651)
		(layer "In13.Cu")
		(net "P5E_PEX1_STN6_TX_C_DP<111>")
	)
	(segment
		(start 112.139222 -391.88898)
		(end 112.523016 -392.201908)
		(width 0.1651)
		(layer "In13.Cu")
		(net "P5E_PEX1_STN6_TX_C_DP<111>")
	)
	(segment
		(start 111.108744 -391.163048)
		(end 111.233712 -391.150348)
		(width 0.1651)
		(layer "In13.Cu")
		(net "P5E_PEX1_STN6_TX_C_DP<111>")
	)
	(segment
		(start 111.617506 -391.463276)
		(end 111.630206 -391.588498)
		(width 0.1651)
		(layer "In13.Cu")
		(net "P5E_PEX1_STN6_TX_C_DP<111>")
	)
	(segment
		(start 113.044732 -392.627358)
		(end 114.101118 -393.488926)
		(width 0.1651)
		(layer "In13.Cu")
		(net "P5E_PEX1_STN6_TX_C_DP<111>")
	)
	(segment
		(start 112.152938 -346.284296)
		(end 110.499398 -347.937836)
		(width 0.1651)
		(layer "In13.Cu")
		(net "P5E_PEX1_STN6_TX_C_DP<111>")
	)
	(segment
		(start 115.910106 -408.572208)
		(end 115.910106 -408.190192)
		(width 0.1651)
		(layer "In13.Cu")
		(net "P5E_PEX1_STN6_TX_C_DP<111>")
	)
	(segment
		(start 111.862108 -345.465146)
		(end 112.152938 -345.755976)
		(width 0.1651)
		(layer "In13.Cu")
		(net "P5E_PEX1_STN6_TX_C_DP<111>")
	)
	(segment
		(start 112.152938 -345.755976)
		(end 112.152938 -346.284296)
		(width 0.1651)
		(layer "In13.Cu")
		(net "P5E_PEX1_STN6_TX_C_DP<111>")
	)
	(segment
		(start 116.258594 -408.699208)
		(end 116.037106 -408.699208)
		(width 0.1651)
		(layer "In13.Cu")
		(net "P5E_PEX1_STN6_TX_C_DP<111>")
	)
	(segment
		(start 107.338114 -365.163354)
		(end 107.211368 -384.148838)
		(width 0.1651)
		(layer "In13.Cu")
		(net "P5E_PEX1_STN6_TX_C_DP<111>")
	)
	(segment
		(start 110.499398 -347.937836)
		(end 107.338114 -365.163354)
		(width 0.1651)
		(layer "In13.Cu")
		(net "P5E_PEX1_STN6_TX_C_DP<111>")
	)
	(segment
		(start 112.535716 -392.326876)
		(end 112.919764 -392.640058)
		(width 0.1651)
		(layer "In13.Cu")
		(net "P5E_PEX1_STN6_TX_C_DP<111>")
	)
	(segment
		(start 111.233712 -391.150348)
		(end 111.617506 -391.463276)
		(width 0.1651)
		(layer "In13.Cu")
		(net "P5E_PEX1_STN6_TX_C_DP<111>")
	)
	(segment
		(start 116.784882 -394.86078)
		(end 116.784882 -408.17292)
		(width 0.1651)
		(layer "In13.Cu")
		(net "P5E_PEX1_STN6_TX_C_DP<111>")
	)
	(segment
		(start 109.829854 -390.00557)
		(end 110.711742 -390.724644)
		(width 0.1651)
		(layer "In13.Cu")
		(net "P5E_PEX1_STN6_TX_C_DP<111>")
	)
	(segment
		(start 116.037106 -408.699208)
		(end 115.910106 -408.572208)
		(width 0.1651)
		(layer "In13.Cu")
		(net "P5E_PEX1_STN6_TX_C_DP<111>")
	)
	(segment
		(start 112.919764 -392.640058)
		(end 113.044732 -392.627358)
		(width 0.1651)
		(layer "In13.Cu")
		(net "P5E_PEX1_STN6_TX_C_DP<111>")
	)
	(segment
		(start 116.784882 -408.17292)
		(end 116.258594 -408.699208)
		(width 0.1651)
		(layer "In13.Cu")
		(net "P5E_PEX1_STN6_TX_C_DP<111>")
	)
	(segment
		(start 112.523016 -392.201908)
		(end 112.535716 -392.326876)
		(width 0.1651)
		(layer "In13.Cu")
		(net "P5E_PEX1_STN6_TX_C_DP<111>")
	)
	(segment
		(start 422.064434 -135.444992)
		(end 421.557704 -135.444992)
		(width 0.13462)
		(layer "F.Cu")
		(net "P5E_PEX3_STN0_TX_C_DN<7>")
	)
	(segment
		(start 422.230042 -135.6106)
		(end 422.064434 -135.444992)
		(width 0.13462)
		(layer "F.Cu")
		(net "P5E_PEX3_STN0_TX_C_DN<7>")
	)
	(segment
		(start 430.694846 -135.28675)
		(end 430.370996 -135.6106)
		(width 0.13462)
		(layer "F.Cu")
		(net "P5E_PEX3_STN0_TX_C_DN<7>")
	)
	(segment
		(start 430.370996 -135.6106)
		(end 422.230042 -135.6106)
		(width 0.13462)
		(layer "F.Cu")
		(net "P5E_PEX3_STN0_TX_C_DN<7>")
	)
	(segment
		(start 387.62178 -356.511606)
		(end 387.302248 -356.831138)
		(width 0.13462)
		(layer "F.Cu")
		(net "P5E_PEX3_STN5_TX_C_DN<80>")
	)
	(segment
		(start 387.302248 -356.831138)
		(end 387.302248 -357.463598)
		(width 0.13462)
		(layer "F.Cu")
		(net "P5E_PEX3_STN5_TX_C_DN<80>")
	)
	(segment
		(start 387.302248 -357.463598)
		(end 387.59638 -357.75773)
		(width 0.13462)
		(layer "F.Cu")
		(net "P5E_PEX3_STN5_TX_C_DN<80>")
	)
	(segment
		(start 376.61596 -404.629112)
		(end 376.61596 -396.03045)
		(width 0.1651)
		(layer "In7.Cu")
		(net "P5E_PEX3_STN5_TX_C_DN<80>")
	)
	(segment
		(start 394.366496 -368.93373)
		(end 387.30555 -358.495346)
		(width 0.1651)
		(layer "In7.Cu")
		(net "P5E_PEX3_STN5_TX_C_DN<80>")
	)
	(segment
		(start 377.139962 -394.530072)
		(end 383.308098 -390.568688)
		(width 0.1651)
		(layer "In7.Cu")
		(net "P5E_PEX3_STN5_TX_C_DN<80>")
	)
	(segment
		(start 375.489978 -405.589994)
		(end 375.489978 -405.207978)
		(width 0.1651)
		(layer "In7.Cu")
		(net "P5E_PEX3_STN5_TX_C_DN<80>")
	)
	(segment
		(start 394.36548 -369.021614)
		(end 394.366496 -368.93373)
		(width 0.1651)
		(layer "In7.Cu")
		(net "P5E_PEX3_STN5_TX_C_DN<80>")
	)
	(segment
		(start 387.30555 -358.04856)
		(end 387.59638 -357.75773)
		(width 0.1651)
		(layer "In7.Cu")
		(net "P5E_PEX3_STN5_TX_C_DN<80>")
	)
	(segment
		(start 376.61596 -396.03045)
		(end 377.139962 -394.530072)
		(width 0.1651)
		(layer "In7.Cu")
		(net "P5E_PEX3_STN5_TX_C_DN<80>")
	)
	(segment
		(start 393.605512 -386.047742)
		(end 394.193014 -385.46024)
		(width 0.1651)
		(layer "In7.Cu")
		(net "P5E_PEX3_STN5_TX_C_DN<80>")
	)
	(segment
		(start 383.308098 -390.568688)
		(end 393.605512 -386.047742)
		(width 0.1651)
		(layer "In7.Cu")
		(net "P5E_PEX3_STN5_TX_C_DN<80>")
	)
	(segment
		(start 376.164094 -405.080978)
		(end 376.61596 -404.629112)
		(width 0.1651)
		(layer "In7.Cu")
		(net "P5E_PEX3_STN5_TX_C_DN<80>")
	)
	(segment
		(start 387.30555 -358.495346)
		(end 387.30555 -358.04856)
		(width 0.1651)
		(layer "In7.Cu")
		(net "P5E_PEX3_STN5_TX_C_DN<80>")
	)
	(segment
		(start 375.616978 -405.080978)
		(end 376.164094 -405.080978)
		(width 0.1651)
		(layer "In7.Cu")
		(net "P5E_PEX3_STN5_TX_C_DN<80>")
	)
	(segment
		(start 375.489978 -405.207978)
		(end 375.616978 -405.080978)
		(width 0.1651)
		(layer "In7.Cu")
		(net "P5E_PEX3_STN5_TX_C_DN<80>")
	)
	(segment
		(start 394.193014 -385.46024)
		(end 394.36548 -369.021614)
		(width 0.1651)
		(layer "In7.Cu")
		(net "P5E_PEX3_STN5_TX_C_DN<80>")
	)
	(segment
		(start 272.600166 -157.73273)
		(end 272.597626 -157.73527)
		(width 0.13208)
		(layer "F.Cu")
		(net "NIC4_DATA_IN")
	)
	(segment
		(start 272.240756 -157.3784)
		(end 271.207992 -157.3784)
		(width 0.13208)
		(layer "F.Cu")
		(net "NIC4_DATA_IN")
	)
	(segment
		(start 278.242268 -156.560012)
		(end 276.179026 -156.560012)
		(width 0.13208)
		(layer "F.Cu")
		(net "NIC4_DATA_IN")
	)
	(segment
		(start 276.179026 -156.560012)
		(end 275.006308 -157.73273)
		(width 0.13208)
		(layer "F.Cu")
		(net "NIC4_DATA_IN")
	)
	(segment
		(start 275.006308 -157.73273)
		(end 272.600166 -157.73273)
		(width 0.13208)
		(layer "F.Cu")
		(net "NIC4_DATA_IN")
	)
	(segment
		(start 272.597626 -157.73527)
		(end 272.240756 -157.3784)
		(width 0.13208)
		(layer "F.Cu")
		(net "NIC4_DATA_IN")
	)
	(via
		(at 272.597626 -157.73527)
		(size 0.762)
		(drill 0.381)
		(layers "F.Cu" "B.Cu")
		(net "NIC4_DATA_IN")
	)
	(segment
		(start 51.130454 -123.554998)
		(end 51.293268 -123.392184)
		(width 0.13462)
		(layer "F.Cu")
		(net "P5E_PEX0_STN1_RX_DN<26>")
	)
	(segment
		(start 53.80228 -123.391676)
		(end 54.09692 -123.686316)
		(width 0.13462)
		(layer "F.Cu")
		(net "P5E_PEX0_STN1_RX_DN<26>")
	)
	(segment
		(start 50.64252 -123.554998)
		(end 51.130454 -123.554998)
		(width 0.13462)
		(layer "F.Cu")
		(net "P5E_PEX0_STN1_RX_DN<26>")
	)
	(segment
		(start 51.293268 -123.392184)
		(end 53.801772 -123.392184)
		(width 0.13462)
		(layer "F.Cu")
		(net "P5E_PEX0_STN1_RX_DN<26>")
	)
	(segment
		(start 53.801772 -123.392184)
		(end 53.80228 -123.391676)
		(width 0.13462)
		(layer "F.Cu")
		(net "P5E_PEX0_STN1_RX_DN<26>")
	)
	(segment
		(start 50.001678 -124.700284)
		(end 49.579784 -124.960634)
		(width 0.1651)
		(layer "In5.Cu")
		(net "P5E_PEX0_STN1_RX_DN<26>")
	)
	(segment
		(start 44.16171 -132.338572)
		(end 42.954194 -139.332462)
		(width 0.1651)
		(layer "In5.Cu")
		(net "P5E_PEX0_STN1_RX_DN<26>")
	)
	(segment
		(start 45.068998 -128.97866)
		(end 44.761912 -129.367026)
		(width 0.1651)
		(layer "In5.Cu")
		(net "P5E_PEX0_STN1_RX_DN<26>")
	)
	(segment
		(start 42.954194 -139.332462)
		(end 41.915334 -142.91818)
		(width 0.1651)
		(layer "In5.Cu")
		(net "P5E_PEX0_STN1_RX_DN<26>")
	)
	(segment
		(start 52.394612 -123.395486)
		(end 51.899312 -123.395486)
		(width 0.1651)
		(layer "In5.Cu")
		(net "P5E_PEX0_STN1_RX_DN<26>")
	)
	(segment
		(start 44.501308 -131.04368)
		(end 44.368974 -131.136898)
		(width 0.1651)
		(layer "In5.Cu")
		(net "P5E_PEX0_STN1_RX_DN<26>")
	)
	(segment
		(start 49.579784 -124.960634)
		(end 49.422558 -124.923296)
		(width 0.1651)
		(layer "In5.Cu")
		(net "P5E_PEX0_STN1_RX_DN<26>")
	)
	(segment
		(start 44.378372 -131.756912)
		(end 44.294044 -132.245354)
		(width 0.1651)
		(layer "In5.Cu")
		(net "P5E_PEX0_STN1_RX_DN<26>")
	)
	(segment
		(start 47.568866 -126.066804)
		(end 46.899576 -126.66218)
		(width 0.1651)
		(layer "In5.Cu")
		(net "P5E_PEX0_STN1_RX_DN<26>")
	)
	(segment
		(start 46.274228 -127.453644)
		(end 46.274228 -127.453898)
		(width 0.1651)
		(layer "In5.Cu")
		(net "P5E_PEX0_STN1_RX_DN<26>")
	)
	(segment
		(start 49.422558 -124.923296)
		(end 49.001172 -125.183138)
		(width 0.1651)
		(layer "In5.Cu")
		(net "P5E_PEX0_STN1_RX_DN<26>")
	)
	(segment
		(start 40.567102 -161.883598)
		(end 68.815966 -267.893546)
		(width 0.1651)
		(layer "In5.Cu")
		(net "P5E_PEX0_STN1_RX_DN<26>")
	)
	(segment
		(start 48.54194 -125.600714)
		(end 48.384714 -125.56363)
		(width 0.1651)
		(layer "In5.Cu")
		(net "P5E_PEX0_STN1_RX_DN<26>")
	)
	(segment
		(start 39.110666 -147.433538)
		(end 39.75608 -157.384496)
		(width 0.1651)
		(layer "In5.Cu")
		(net "P5E_PEX0_STN1_RX_DN<26>")
	)
	(segment
		(start 53.80609 -123.395486)
		(end 53.118512 -123.395486)
		(width 0.1651)
		(layer "In5.Cu")
		(net "P5E_PEX0_STN1_RX_DN<26>")
	)
	(segment
		(start 50.617628 -124.320554)
		(end 50.460402 -124.283216)
		(width 0.1651)
		(layer "In5.Cu")
		(net "P5E_PEX0_STN1_RX_DN<26>")
	)
	(segment
		(start 50.039016 -124.543058)
		(end 50.001678 -124.700284)
		(width 0.1651)
		(layer "In5.Cu")
		(net "P5E_PEX0_STN1_RX_DN<26>")
	)
	(segment
		(start 54.09692 -123.686316)
		(end 53.80609 -123.395486)
		(width 0.1651)
		(layer "In5.Cu")
		(net "P5E_PEX0_STN1_RX_DN<26>")
	)
	(segment
		(start 45.536866 -128.57099)
		(end 45.229526 -128.959864)
		(width 0.1651)
		(layer "In5.Cu")
		(net "P5E_PEX0_STN1_RX_DN<26>")
	)
	(segment
		(start 45.985684 -128.0033)
		(end 45.825156 -128.022096)
		(width 0.1651)
		(layer "In5.Cu")
		(net "P5E_PEX0_STN1_RX_DN<26>")
	)
	(segment
		(start 44.620942 -129.678176)
		(end 44.492418 -130.423158)
		(width 0.1651)
		(layer "In5.Cu")
		(net "P5E_PEX0_STN1_RX_DN<26>")
	)
	(segment
		(start 46.274228 -127.453898)
		(end 46.293024 -127.614426)
		(width 0.1651)
		(layer "In5.Cu")
		(net "P5E_PEX0_STN1_RX_DN<26>")
	)
	(segment
		(start 46.293024 -127.614426)
		(end 45.985684 -128.0033)
		(width 0.1651)
		(layer "In5.Cu")
		(net "P5E_PEX0_STN1_RX_DN<26>")
	)
	(segment
		(start 45.825156 -128.022096)
		(end 45.51807 -128.410462)
		(width 0.1651)
		(layer "In5.Cu")
		(net "P5E_PEX0_STN1_RX_DN<26>")
	)
	(segment
		(start 39.75608 -157.384496)
		(end 40.567102 -161.883598)
		(width 0.1651)
		(layer "In5.Cu")
		(net "P5E_PEX0_STN1_RX_DN<26>")
	)
	(segment
		(start 45.51807 -128.410462)
		(end 45.536866 -128.57099)
		(width 0.1651)
		(layer "In5.Cu")
		(net "P5E_PEX0_STN1_RX_DN<26>")
	)
	(segment
		(start 45.229526 -128.959864)
		(end 45.068998 -128.97866)
		(width 0.1651)
		(layer "In5.Cu")
		(net "P5E_PEX0_STN1_RX_DN<26>")
	)
	(segment
		(start 44.294044 -132.245354)
		(end 44.16171 -132.338572)
		(width 0.1651)
		(layer "In5.Cu")
		(net "P5E_PEX0_STN1_RX_DN<26>")
	)
	(segment
		(start 48.963834 -125.340618)
		(end 48.54194 -125.600714)
		(width 0.1651)
		(layer "In5.Cu")
		(net "P5E_PEX0_STN1_RX_DN<26>")
	)
	(segment
		(start 48.384714 -125.56363)
		(end 47.568866 -126.066804)
		(width 0.1651)
		(layer "In5.Cu")
		(net "P5E_PEX0_STN1_RX_DN<26>")
	)
	(segment
		(start 44.761912 -129.367026)
		(end 44.620942 -129.678176)
		(width 0.1651)
		(layer "In5.Cu")
		(net "P5E_PEX0_STN1_RX_DN<26>")
	)
	(segment
		(start 51.039522 -124.060204)
		(end 50.617628 -124.320554)
		(width 0.1651)
		(layer "In5.Cu")
		(net "P5E_PEX0_STN1_RX_DN<26>")
	)
	(segment
		(start 53.118512 -123.395486)
		(end 53.004212 -123.509786)
		(width 0.1651)
		(layer "In5.Cu")
		(net "P5E_PEX0_STN1_RX_DN<26>")
	)
	(segment
		(start 44.369228 -131.136898)
		(end 44.285154 -131.624832)
		(width 0.1651)
		(layer "In5.Cu")
		(net "P5E_PEX0_STN1_RX_DN<26>")
	)
	(segment
		(start 68.770246 -273.376136)
		(end 68.873624 -273.479514)
		(width 0.1143)
		(layer "In5.Cu")
		(net "P5E_PEX0_STN1_RX_DN<26>")
	)
	(segment
		(start 68.815966 -271.773904)
		(end 68.815966 -271.802352)
		(width 0.1143)
		(layer "In5.Cu")
		(net "P5E_PEX0_STN1_RX_DN<26>")
	)
	(segment
		(start 41.915334 -142.91818)
		(end 39.414196 -146.275806)
		(width 0.1651)
		(layer "In5.Cu")
		(net "P5E_PEX0_STN1_RX_DN<26>")
	)
	(segment
		(start 68.815966 -267.893546)
		(end 68.815966 -271.773904)
		(width 0.1651)
		(layer "In5.Cu")
		(net "P5E_PEX0_STN1_RX_DN<26>")
	)
	(segment
		(start 39.414196 -146.275806)
		(end 39.110666 -147.433538)
		(width 0.1651)
		(layer "In5.Cu")
		(net "P5E_PEX0_STN1_RX_DN<26>")
	)
	(segment
		(start 69.149722 -273.365214)
		(end 69.149722 -273.099784)
		(width 0.1143)
		(layer "In5.Cu")
		(net "P5E_PEX0_STN1_RX_DN<26>")
	)
	(segment
		(start 49.001172 -125.183138)
		(end 48.963834 -125.340618)
		(width 0.1651)
		(layer "In5.Cu")
		(net "P5E_PEX0_STN1_RX_DN<26>")
	)
	(segment
		(start 44.368974 -131.136898)
		(end 44.369228 -131.136898)
		(width 0.1651)
		(layer "In5.Cu")
		(net "P5E_PEX0_STN1_RX_DN<26>")
	)
	(segment
		(start 69.035422 -273.479514)
		(end 69.149722 -273.365214)
		(width 0.1143)
		(layer "In5.Cu")
		(net "P5E_PEX0_STN1_RX_DN<26>")
	)
	(segment
		(start 44.285154 -131.624832)
		(end 44.378372 -131.756912)
		(width 0.1651)
		(layer "In5.Cu")
		(net "P5E_PEX0_STN1_RX_DN<26>")
	)
	(segment
		(start 51.899312 -123.395486)
		(end 51.076606 -123.902978)
		(width 0.1651)
		(layer "In5.Cu")
		(net "P5E_PEX0_STN1_RX_DN<26>")
	)
	(segment
		(start 51.076606 -123.902978)
		(end 51.039522 -124.060204)
		(width 0.1651)
		(layer "In5.Cu")
		(net "P5E_PEX0_STN1_RX_DN<26>")
	)
	(segment
		(start 52.508912 -123.509786)
		(end 52.394612 -123.395486)
		(width 0.1651)
		(layer "In5.Cu")
		(net "P5E_PEX0_STN1_RX_DN<26>")
	)
	(segment
		(start 68.770246 -271.848072)
		(end 68.770246 -273.376136)
		(width 0.1143)
		(layer "In5.Cu")
		(net "P5E_PEX0_STN1_RX_DN<26>")
	)
	(segment
		(start 50.460402 -124.283216)
		(end 50.039016 -124.543058)
		(width 0.1651)
		(layer "In5.Cu")
		(net "P5E_PEX0_STN1_RX_DN<26>")
	)
	(segment
		(start 53.004212 -123.509786)
		(end 52.508912 -123.509786)
		(width 0.1651)
		(layer "In5.Cu")
		(net "P5E_PEX0_STN1_RX_DN<26>")
	)
	(segment
		(start 68.815966 -271.802352)
		(end 68.770246 -271.848072)
		(width 0.1143)
		(layer "In5.Cu")
		(net "P5E_PEX0_STN1_RX_DN<26>")
	)
	(segment
		(start 46.899576 -126.66218)
		(end 46.274228 -127.453644)
		(width 0.1651)
		(layer "In5.Cu")
		(net "P5E_PEX0_STN1_RX_DN<26>")
	)
	(segment
		(start 44.585636 -130.555238)
		(end 44.501308 -131.04368)
		(width 0.1651)
		(layer "In5.Cu")
		(net "P5E_PEX0_STN1_RX_DN<26>")
	)
	(segment
		(start 68.873624 -273.479514)
		(end 69.035422 -273.479514)
		(width 0.1143)
		(layer "In5.Cu")
		(net "P5E_PEX0_STN1_RX_DN<26>")
	)
	(segment
		(start 44.492418 -130.423158)
		(end 44.585636 -130.555238)
		(width 0.1651)
		(layer "In5.Cu")
		(net "P5E_PEX0_STN1_RX_DN<26>")
	)
	(segment
		(start 167.393366 -136.127744)
		(end 168.04767 -136.127744)
		(width 0.13462)
		(layer "F.Cu")
		(net "P5E_PEX1_STN1_RX_DP<31>")
	)
	(segment
		(start 166.742364 -135.96493)
		(end 167.230552 -135.96493)
		(width 0.13462)
		(layer "F.Cu")
		(net "P5E_PEX1_STN1_RX_DP<31>")
	)
	(segment
		(start 167.230552 -135.96493)
		(end 167.393366 -136.127744)
		(width 0.13462)
		(layer "F.Cu")
		(net "P5E_PEX1_STN1_RX_DP<31>")
	)
	(segment
		(start 168.04767 -136.127744)
		(end 168.342564 -135.83285)
		(width 0.13462)
		(layer "F.Cu")
		(net "P5E_PEX1_STN1_RX_DP<31>")
	)
	(segment
		(start 163.36391 -146.579844)
		(end 162.707574 -146.848576)
		(width 0.1651)
		(layer "In5.Cu")
		(net "P5E_PEX1_STN1_RX_DP<31>")
	)
	(segment
		(start 161.930842 -148.199094)
		(end 161.930588 -148.200872)
		(width 0.1651)
		(layer "In5.Cu")
		(net "P5E_PEX1_STN1_RX_DP<31>")
	)
	(segment
		(start 166.985188 -136.99363)
		(end 166.985188 -141.236446)
		(width 0.1651)
		(layer "In5.Cu")
		(net "P5E_PEX1_STN1_RX_DP<31>")
	)
	(segment
		(start 161.062416 -158.84906)
		(end 161.146744 -160.768792)
		(width 0.1651)
		(layer "In5.Cu")
		(net "P5E_PEX1_STN1_RX_DP<31>")
	)
	(segment
		(start 189.383924 -267.07973)
		(end 189.383924 -271.570958)
		(width 0.1651)
		(layer "In5.Cu")
		(net "P5E_PEX1_STN1_RX_DP<31>")
	)
	(segment
		(start 189.99962 -275.684488)
		(end 189.99962 -275.949918)
		(width 0.1143)
		(layer "In5.Cu")
		(net "P5E_PEX1_STN1_RX_DP<31>")
	)
	(segment
		(start 168.051988 -136.12368)
		(end 167.675052 -136.12368)
		(width 0.1651)
		(layer "In5.Cu")
		(net "P5E_PEX1_STN1_RX_DP<31>")
	)
	(segment
		(start 189.429644 -271.645126)
		(end 189.429644 -275.355304)
		(width 0.1143)
		(layer "In5.Cu")
		(net "P5E_PEX1_STN1_RX_DP<31>")
	)
	(segment
		(start 166.985188 -141.236446)
		(end 165.765988 -144.215612)
		(width 0.1651)
		(layer "In5.Cu")
		(net "P5E_PEX1_STN1_RX_DP<31>")
	)
	(segment
		(start 165.765988 -144.215612)
		(end 163.36391 -146.579844)
		(width 0.1651)
		(layer "In5.Cu")
		(net "P5E_PEX1_STN1_RX_DP<31>")
	)
	(segment
		(start 189.320678 -266.597638)
		(end 189.383924 -267.07973)
		(width 0.1651)
		(layer "In5.Cu")
		(net "P5E_PEX1_STN1_RX_DP<31>")
	)
	(segment
		(start 189.383924 -271.599406)
		(end 189.429644 -271.645126)
		(width 0.1143)
		(layer "In5.Cu")
		(net "P5E_PEX1_STN1_RX_DP<31>")
	)
	(segment
		(start 189.383924 -271.570958)
		(end 189.383924 -271.599406)
		(width 0.1143)
		(layer "In5.Cu")
		(net "P5E_PEX1_STN1_RX_DP<31>")
	)
	(segment
		(start 167.675052 -136.12368)
		(end 167.112442 -136.68629)
		(width 0.1651)
		(layer "In5.Cu")
		(net "P5E_PEX1_STN1_RX_DP<31>")
	)
	(segment
		(start 161.146744 -160.768792)
		(end 189.320678 -266.597638)
		(width 0.1651)
		(layer "In5.Cu")
		(net "P5E_PEX1_STN1_RX_DP<31>")
	)
	(segment
		(start 161.930588 -148.200872)
		(end 161.062416 -158.84906)
		(width 0.1651)
		(layer "In5.Cu")
		(net "P5E_PEX1_STN1_RX_DP<31>")
	)
	(segment
		(start 168.342564 -135.83285)
		(end 168.342564 -135.833104)
		(width 0.1651)
		(layer "In5.Cu")
		(net "P5E_PEX1_STN1_RX_DP<31>")
	)
	(segment
		(start 189.429644 -275.355304)
		(end 189.644528 -275.570188)
		(width 0.1143)
		(layer "In5.Cu")
		(net "P5E_PEX1_STN1_RX_DP<31>")
	)
	(segment
		(start 189.88532 -275.570188)
		(end 189.99962 -275.684488)
		(width 0.1143)
		(layer "In5.Cu")
		(net "P5E_PEX1_STN1_RX_DP<31>")
	)
	(segment
		(start 167.112442 -136.68629)
		(end 166.985188 -136.99363)
		(width 0.1651)
		(layer "In5.Cu")
		(net "P5E_PEX1_STN1_RX_DP<31>")
	)
	(segment
		(start 162.3949 -147.156424)
		(end 161.930842 -148.199094)
		(width 0.1651)
		(layer "In5.Cu")
		(net "P5E_PEX1_STN1_RX_DP<31>")
	)
	(segment
		(start 168.342564 -135.833104)
		(end 168.051988 -136.12368)
		(width 0.1651)
		(layer "In5.Cu")
		(net "P5E_PEX1_STN1_RX_DP<31>")
	)
	(segment
		(start 189.644528 -275.570188)
		(end 189.88532 -275.570188)
		(width 0.1143)
		(layer "In5.Cu")
		(net "P5E_PEX1_STN1_RX_DP<31>")
	)
	(segment
		(start 162.707574 -146.848576)
		(end 162.3949 -147.156424)
		(width 0.1651)
		(layer "In5.Cu")
		(net "P5E_PEX1_STN1_RX_DP<31>")
	)
	(segment
		(start 145.325338 -336.009742)
		(end 155.878784 -329.315318)
		(width 0.1651)
		(layer "In5.Cu")
		(net "P5E_PEX1_STN6_RX_DP<100>")
	)
	(segment
		(start 169.434002 -320.66103)
		(end 169.434002 -319.916048)
		(width 0.1651)
		(layer "In5.Cu")
		(net "P5E_PEX1_STN6_RX_DP<100>")
	)
	(segment
		(start 132.04825 -358.718866)
		(end 132.361178 -357.877872)
		(width 0.1651)
		(layer "In5.Cu")
		(net "P5E_PEX1_STN6_RX_DP<100>")
	)
	(segment
		(start 133.048248 -341.165942)
		(end 145.325338 -336.009742)
		(width 0.1651)
		(layer "In5.Cu")
		(net "P5E_PEX1_STN6_RX_DP<100>")
	)
	(segment
		(start 122.510042 -375.490232)
		(end 122.510042 -375.872248)
		(width 0.1651)
		(layer "In5.Cu")
		(net "P5E_PEX1_STN6_RX_DP<100>")
	)
	(segment
		(start 132.775198 -341.438992)
		(end 133.048248 -341.165942)
		(width 0.1651)
		(layer "In5.Cu")
		(net "P5E_PEX1_STN6_RX_DP<100>")
	)
	(segment
		(start 124.601478 -367.171224)
		(end 124.9172 -366.805718)
		(width 0.1651)
		(layer "In5.Cu")
		(net "P5E_PEX1_STN6_RX_DP<100>")
	)
	(segment
		(start 123.287536 -375.78157)
		(end 123.287536 -369.77066)
		(width 0.1651)
		(layer "In5.Cu")
		(net "P5E_PEX1_STN6_RX_DP<100>")
	)
	(segment
		(start 125.074934 -366.794034)
		(end 132.04825 -358.718866)
		(width 0.1651)
		(layer "In5.Cu")
		(net "P5E_PEX1_STN6_RX_DP<100>")
	)
	(segment
		(start 124.9172 -366.805718)
		(end 125.074934 -366.794034)
		(width 0.1651)
		(layer "In5.Cu")
		(net "P5E_PEX1_STN6_RX_DP<100>")
	)
	(segment
		(start 122.510042 -375.872248)
		(end 122.637042 -375.999248)
		(width 0.1651)
		(layer "In5.Cu")
		(net "P5E_PEX1_STN6_RX_DP<100>")
	)
	(segment
		(start 169.935652 -318.129666)
		(end 170.049952 -318.015366)
		(width 0.1143)
		(layer "In5.Cu")
		(net "P5E_PEX1_STN6_RX_DP<100>")
	)
	(segment
		(start 123.287536 -369.77066)
		(end 123.880626 -368.177064)
		(width 0.1651)
		(layer "In5.Cu")
		(net "P5E_PEX1_STN6_RX_DP<100>")
	)
	(segment
		(start 122.637042 -375.999248)
		(end 123.069858 -375.999248)
		(width 0.1651)
		(layer "In5.Cu")
		(net "P5E_PEX1_STN6_RX_DP<100>")
	)
	(segment
		(start 132.361178 -341.994998)
		(end 132.775198 -341.438992)
		(width 0.1651)
		(layer "In5.Cu")
		(net "P5E_PEX1_STN6_RX_DP<100>")
	)
	(segment
		(start 169.434002 -319.8876)
		(end 169.479722 -319.84188)
		(width 0.1143)
		(layer "In5.Cu")
		(net "P5E_PEX1_STN6_RX_DP<100>")
	)
	(segment
		(start 169.479722 -318.355472)
		(end 169.705528 -318.129666)
		(width 0.1143)
		(layer "In5.Cu")
		(net "P5E_PEX1_STN6_RX_DP<100>")
	)
	(segment
		(start 123.069858 -375.999248)
		(end 123.287536 -375.78157)
		(width 0.1651)
		(layer "In5.Cu")
		(net "P5E_PEX1_STN6_RX_DP<100>")
	)
	(segment
		(start 169.705528 -318.129666)
		(end 169.935652 -318.129666)
		(width 0.1143)
		(layer "In5.Cu")
		(net "P5E_PEX1_STN6_RX_DP<100>")
	)
	(segment
		(start 169.434002 -319.916048)
		(end 169.434002 -319.8876)
		(width 0.1143)
		(layer "In5.Cu")
		(net "P5E_PEX1_STN6_RX_DP<100>")
	)
	(segment
		(start 132.361178 -357.877872)
		(end 132.361178 -341.994998)
		(width 0.1651)
		(layer "In5.Cu")
		(net "P5E_PEX1_STN6_RX_DP<100>")
	)
	(segment
		(start 170.049952 -318.015366)
		(end 170.049952 -317.749936)
		(width 0.1143)
		(layer "In5.Cu")
		(net "P5E_PEX1_STN6_RX_DP<100>")
	)
	(segment
		(start 168.287446 -321.981068)
		(end 169.434002 -320.66103)
		(width 0.1651)
		(layer "In5.Cu")
		(net "P5E_PEX1_STN6_RX_DP<100>")
	)
	(segment
		(start 123.880626 -368.177064)
		(end 124.613162 -367.328704)
		(width 0.1651)
		(layer "In5.Cu")
		(net "P5E_PEX1_STN6_RX_DP<100>")
	)
	(segment
		(start 124.613162 -367.328704)
		(end 124.601478 -367.171224)
		(width 0.1651)
		(layer "In5.Cu")
		(net "P5E_PEX1_STN6_RX_DP<100>")
	)
	(segment
		(start 155.878784 -329.315318)
		(end 168.287446 -321.981068)
		(width 0.1651)
		(layer "In5.Cu")
		(net "P5E_PEX1_STN6_RX_DP<100>")
	)
	(segment
		(start 169.479722 -319.84188)
		(end 169.479722 -318.355472)
		(width 0.1143)
		(layer "In5.Cu")
		(net "P5E_PEX1_STN6_RX_DP<100>")
	)
	(segment
		(start 315.906404 -344.539062)
		(end 315.906404 -345.170506)
		(width 0.13462)
		(layer "F.Cu")
		(net "P5E_PEX2_STN5_TX_C_DP<81>")
	)
	(segment
		(start 315.906404 -345.170506)
		(end 315.611764 -345.465146)
		(width 0.13462)
		(layer "F.Cu")
		(net "P5E_PEX2_STN5_TX_C_DP<81>")
	)
	(segment
		(start 315.586364 -344.219022)
		(end 315.906404 -344.539062)
		(width 0.13462)
		(layer "F.Cu")
		(net "P5E_PEX2_STN5_TX_C_DP<81>")
	)
	(segment
		(start 333.341218 -394.184378)
		(end 332.816454 -393.672314)
		(width 0.1651)
		(layer "In7.Cu")
		(net "P5E_PEX2_STN5_TX_C_DP<81>")
	)
	(segment
		(start 333.69758 -394.65631)
		(end 333.342742 -394.310108)
		(width 0.1651)
		(layer "In7.Cu")
		(net "P5E_PEX2_STN5_TX_C_DP<81>")
	)
	(segment
		(start 333.68996 -405.390096)
		(end 333.68996 -405.772112)
		(width 0.1651)
		(layer "In7.Cu")
		(net "P5E_PEX2_STN5_TX_C_DP<81>")
	)
	(segment
		(start 331.783182 -393.346686)
		(end 331.734668 -393.230608)
		(width 0.1651)
		(layer "In7.Cu")
		(net "P5E_PEX2_STN5_TX_C_DP<81>")
	)
	(segment
		(start 333.342742 -394.310108)
		(end 333.341218 -394.184378)
		(width 0.1651)
		(layer "In7.Cu")
		(net "P5E_PEX2_STN5_TX_C_DP<81>")
	)
	(segment
		(start 325.712582 -389.066024)
		(end 324.475856 -386.098288)
		(width 0.1651)
		(layer "In7.Cu")
		(net "P5E_PEX2_STN5_TX_C_DP<81>")
	)
	(segment
		(start 332.357984 -393.48537)
		(end 332.24216 -393.533884)
		(width 0.1651)
		(layer "In7.Cu")
		(net "P5E_PEX2_STN5_TX_C_DP<81>")
	)
	(segment
		(start 328.624692 -391.961624)
		(end 325.712582 -389.066024)
		(width 0.1651)
		(layer "In7.Cu")
		(net "P5E_PEX2_STN5_TX_C_DP<81>")
	)
	(segment
		(start 334.17764 -395.00048)
		(end 333.82331 -394.654786)
		(width 0.1651)
		(layer "In7.Cu")
		(net "P5E_PEX2_STN5_TX_C_DP<81>")
	)
	(segment
		(start 331.734668 -393.230608)
		(end 328.624692 -391.961624)
		(width 0.1651)
		(layer "In7.Cu")
		(net "P5E_PEX2_STN5_TX_C_DP<81>")
	)
	(segment
		(start 315.902594 -345.755976)
		(end 315.611764 -345.465146)
		(width 0.1651)
		(layer "In7.Cu")
		(net "P5E_PEX2_STN5_TX_C_DP<81>")
	)
	(segment
		(start 334.534002 -395.89964)
		(end 334.17764 -395.00048)
		(width 0.1651)
		(layer "In7.Cu")
		(net "P5E_PEX2_STN5_TX_C_DP<81>")
	)
	(segment
		(start 333.81696 -405.899112)
		(end 334.247236 -405.899112)
		(width 0.1651)
		(layer "In7.Cu")
		(net "P5E_PEX2_STN5_TX_C_DP<81>")
	)
	(segment
		(start 314.348114 -358.87914)
		(end 314.348114 -347.764354)
		(width 0.1651)
		(layer "In7.Cu")
		(net "P5E_PEX2_STN5_TX_C_DP<81>")
	)
	(segment
		(start 314.348114 -347.764354)
		(end 315.902594 -346.209874)
		(width 0.1651)
		(layer "In7.Cu")
		(net "P5E_PEX2_STN5_TX_C_DP<81>")
	)
	(segment
		(start 332.24216 -393.533884)
		(end 331.783182 -393.346686)
		(width 0.1651)
		(layer "In7.Cu")
		(net "P5E_PEX2_STN5_TX_C_DP<81>")
	)
	(segment
		(start 315.902594 -346.209874)
		(end 315.902594 -345.755976)
		(width 0.1651)
		(layer "In7.Cu")
		(net "P5E_PEX2_STN5_TX_C_DP<81>")
	)
	(segment
		(start 332.816454 -393.672314)
		(end 332.357984 -393.48537)
		(width 0.1651)
		(layer "In7.Cu")
		(net "P5E_PEX2_STN5_TX_C_DP<81>")
	)
	(segment
		(start 324.475856 -386.098288)
		(end 314.348114 -358.87914)
		(width 0.1651)
		(layer "In7.Cu")
		(net "P5E_PEX2_STN5_TX_C_DP<81>")
	)
	(segment
		(start 334.534002 -405.612346)
		(end 334.534002 -395.89964)
		(width 0.1651)
		(layer "In7.Cu")
		(net "P5E_PEX2_STN5_TX_C_DP<81>")
	)
	(segment
		(start 333.82331 -394.654786)
		(end 333.69758 -394.65631)
		(width 0.1651)
		(layer "In7.Cu")
		(net "P5E_PEX2_STN5_TX_C_DP<81>")
	)
	(segment
		(start 333.68996 -405.772112)
		(end 333.81696 -405.899112)
		(width 0.1651)
		(layer "In7.Cu")
		(net "P5E_PEX2_STN5_TX_C_DP<81>")
	)
	(segment
		(start 334.247236 -405.899112)
		(end 334.534002 -405.612346)
		(width 0.1651)
		(layer "In7.Cu")
		(net "P5E_PEX2_STN5_TX_C_DP<81>")
	)
	(segment
		(start 430.381918 -120.7897)
		(end 422.21912 -120.7897)
		(width 0.13462)
		(layer "F.Cu")
		(net "P5E_PEX3_STN0_TX_C_DN<1>")
	)
	(segment
		(start 422.21912 -120.7897)
		(end 422.064434 -120.635014)
		(width 0.13462)
		(layer "F.Cu")
		(net "P5E_PEX3_STN0_TX_C_DN<1>")
	)
	(segment
		(start 430.694846 -120.476772)
		(end 430.381918 -120.7897)
		(width 0.13462)
		(layer "F.Cu")
		(net "P5E_PEX3_STN0_TX_C_DN<1>")
	)
	(segment
		(start 422.064434 -120.635014)
		(end 421.557704 -120.635014)
		(width 0.13462)
		(layer "F.Cu")
		(net "P5E_PEX3_STN0_TX_C_DN<1>")
	)
	(segment
		(start 399.738088 -350.684846)
		(end 399.738088 -351.317306)
		(width 0.13462)
		(layer "F.Cu")
		(net "P5E_PEX3_STN5_TX_C_DN<93>")
	)
	(segment
		(start 400.05762 -350.365314)
		(end 399.738088 -350.684846)
		(width 0.13462)
		(layer "F.Cu")
		(net "P5E_PEX3_STN5_TX_C_DN<93>")
	)
	(segment
		(start 399.738088 -351.317306)
		(end 400.03222 -351.611438)
		(width 0.13462)
		(layer "F.Cu")
		(net "P5E_PEX3_STN5_TX_C_DN<93>")
	)
	(segment
		(start 387.615938 -379.729238)
		(end 387.615938 -369.727988)
		(width 0.1651)
		(layer "In13.Cu")
		(net "P5E_PEX3_STN5_TX_C_DN<93>")
	)
	(segment
		(start 388.229094 -368.322606)
		(end 397.425164 -359.788206)
		(width 0.1651)
		(layer "In13.Cu")
		(net "P5E_PEX3_STN5_TX_C_DN<93>")
	)
	(segment
		(start 386.489956 -380.69012)
		(end 386.489956 -380.308104)
		(width 0.1651)
		(layer "In13.Cu")
		(net "P5E_PEX3_STN5_TX_C_DN<93>")
	)
	(segment
		(start 399.74139 -352.473006)
		(end 399.74139 -351.902268)
		(width 0.1651)
		(layer "In13.Cu")
		(net "P5E_PEX3_STN5_TX_C_DN<93>")
	)
	(segment
		(start 398.18691 -358.041702)
		(end 398.18691 -354.027486)
		(width 0.1651)
		(layer "In13.Cu")
		(net "P5E_PEX3_STN5_TX_C_DN<93>")
	)
	(segment
		(start 386.489956 -380.308104)
		(end 386.616956 -380.181104)
		(width 0.1651)
		(layer "In13.Cu")
		(net "P5E_PEX3_STN5_TX_C_DN<93>")
	)
	(segment
		(start 387.164072 -380.181104)
		(end 387.615938 -379.729238)
		(width 0.1651)
		(layer "In13.Cu")
		(net "P5E_PEX3_STN5_TX_C_DN<93>")
	)
	(segment
		(start 387.615938 -369.727988)
		(end 388.229094 -368.322606)
		(width 0.1651)
		(layer "In13.Cu")
		(net "P5E_PEX3_STN5_TX_C_DN<93>")
	)
	(segment
		(start 397.425164 -359.788206)
		(end 398.18691 -358.041702)
		(width 0.1651)
		(layer "In13.Cu")
		(net "P5E_PEX3_STN5_TX_C_DN<93>")
	)
	(segment
		(start 398.18691 -354.027486)
		(end 399.74139 -352.473006)
		(width 0.1651)
		(layer "In13.Cu")
		(net "P5E_PEX3_STN5_TX_C_DN<93>")
	)
	(segment
		(start 386.616956 -380.181104)
		(end 387.164072 -380.181104)
		(width 0.1651)
		(layer "In13.Cu")
		(net "P5E_PEX3_STN5_TX_C_DN<93>")
	)
	(segment
		(start 399.74139 -351.902268)
		(end 400.03222 -351.611438)
		(width 0.1651)
		(layer "In13.Cu")
		(net "P5E_PEX3_STN5_TX_C_DN<93>")
	)
	(segment
		(start 53.801772 -119.792242)
		(end 53.80228 -119.791734)
		(width 0.13462)
		(layer "F.Cu")
		(net "P5E_PEX0_STN1_RX_DN<24>")
	)
	(segment
		(start 50.64252 -119.955056)
		(end 51.130454 -119.955056)
		(width 0.13462)
		(layer "F.Cu")
		(net "P5E_PEX0_STN1_RX_DN<24>")
	)
	(segment
		(start 53.80228 -119.791734)
		(end 54.09692 -120.086374)
		(width 0.13462)
		(layer "F.Cu")
		(net "P5E_PEX0_STN1_RX_DN<24>")
	)
	(segment
		(start 51.130454 -119.955056)
		(end 51.293268 -119.792242)
		(width 0.13462)
		(layer "F.Cu")
		(net "P5E_PEX0_STN1_RX_DN<24>")
	)
	(segment
		(start 51.293268 -119.792242)
		(end 53.801772 -119.792242)
		(width 0.13462)
		(layer "F.Cu")
		(net "P5E_PEX0_STN1_RX_DN<24>")
	)
	(segment
		(start 44.6151 -125.657864)
		(end 44.346876 -126.073916)
		(width 0.1651)
		(layer "In5.Cu")
		(net "P5E_PEX0_STN1_RX_DN<24>")
	)
	(segment
		(start 66.97345 -273.479514)
		(end 67.135248 -273.479514)
		(width 0.1143)
		(layer "In5.Cu")
		(net "P5E_PEX0_STN1_RX_DN<24>")
	)
	(segment
		(start 47.393606 -123.022868)
		(end 47.03445 -123.363482)
		(width 0.1651)
		(layer "In5.Cu")
		(net "P5E_PEX0_STN1_RX_DN<24>")
	)
	(segment
		(start 40.000682 -139.95527)
		(end 39.55034 -140.750036)
		(width 0.1651)
		(layer "In5.Cu")
		(net "P5E_PEX0_STN1_RX_DN<24>")
	)
	(segment
		(start 67.135248 -273.479514)
		(end 67.249548 -273.365214)
		(width 0.1143)
		(layer "In5.Cu")
		(net "P5E_PEX0_STN1_RX_DN<24>")
	)
	(segment
		(start 54.09692 -120.086374)
		(end 53.80609 -119.795544)
		(width 0.1651)
		(layer "In5.Cu")
		(net "P5E_PEX0_STN1_RX_DN<24>")
	)
	(segment
		(start 39.55034 -140.750036)
		(end 39.267384 -141.376908)
		(width 0.1651)
		(layer "In5.Cu")
		(net "P5E_PEX0_STN1_RX_DN<24>")
	)
	(segment
		(start 48.278288 -122.183652)
		(end 47.919132 -122.524266)
		(width 0.1651)
		(layer "In5.Cu")
		(net "P5E_PEX0_STN1_RX_DN<24>")
	)
	(segment
		(start 43.954192 -126.682754)
		(end 43.027092 -128.120648)
		(width 0.1651)
		(layer "In5.Cu")
		(net "P5E_PEX0_STN1_RX_DN<24>")
	)
	(segment
		(start 48.799496 -121.846594)
		(end 48.439832 -122.187716)
		(width 0.1651)
		(layer "In5.Cu")
		(net "P5E_PEX0_STN1_RX_DN<24>")
	)
	(segment
		(start 43.027092 -128.120648)
		(end 42.695368 -128.983232)
		(width 0.1651)
		(layer "In5.Cu")
		(net "P5E_PEX0_STN1_RX_DN<24>")
	)
	(segment
		(start 46.149768 -124.202444)
		(end 46.14545 -124.364242)
		(width 0.1651)
		(layer "In5.Cu")
		(net "P5E_PEX0_STN1_RX_DN<24>")
	)
	(segment
		(start 40.601646 -138.894312)
		(end 40.357552 -139.325096)
		(width 0.1651)
		(layer "In5.Cu")
		(net "P5E_PEX0_STN1_RX_DN<24>")
	)
	(segment
		(start 48.803814 -121.68505)
		(end 48.799496 -121.846594)
		(width 0.1651)
		(layer "In5.Cu")
		(net "P5E_PEX0_STN1_RX_DN<24>")
	)
	(segment
		(start 39.267384 -141.376908)
		(end 39.324534 -141.528292)
		(width 0.1651)
		(layer "In5.Cu")
		(net "P5E_PEX0_STN1_RX_DN<24>")
	)
	(segment
		(start 66.915792 -271.773904)
		(end 66.915792 -271.802352)
		(width 0.1143)
		(layer "In5.Cu")
		(net "P5E_PEX0_STN1_RX_DN<24>")
	)
	(segment
		(start 37.51834 -145.252186)
		(end 36.350702 -151.578564)
		(width 0.1651)
		(layer "In5.Cu")
		(net "P5E_PEX0_STN1_RX_DN<24>")
	)
	(segment
		(start 47.03445 -123.363482)
		(end 47.030132 -123.52528)
		(width 0.1651)
		(layer "In5.Cu")
		(net "P5E_PEX0_STN1_RX_DN<24>")
	)
	(segment
		(start 45.624242 -124.701046)
		(end 44.6151 -125.657864)
		(width 0.1651)
		(layer "In5.Cu")
		(net "P5E_PEX0_STN1_RX_DN<24>")
	)
	(segment
		(start 46.14545 -124.364242)
		(end 45.785786 -124.70511)
		(width 0.1651)
		(layer "In5.Cu")
		(net "P5E_PEX0_STN1_RX_DN<24>")
	)
	(segment
		(start 66.870072 -271.848072)
		(end 66.870072 -273.376136)
		(width 0.1143)
		(layer "In5.Cu")
		(net "P5E_PEX0_STN1_RX_DN<24>")
	)
	(segment
		(start 47.030132 -123.52528)
		(end 46.670468 -123.866148)
		(width 0.1651)
		(layer "In5.Cu")
		(net "P5E_PEX0_STN1_RX_DN<24>")
	)
	(segment
		(start 41.001696 -138.41984)
		(end 40.757348 -138.851132)
		(width 0.1651)
		(layer "In5.Cu")
		(net "P5E_PEX0_STN1_RX_DN<24>")
	)
	(segment
		(start 46.670468 -123.866148)
		(end 46.508924 -123.86183)
		(width 0.1651)
		(layer "In5.Cu")
		(net "P5E_PEX0_STN1_RX_DN<24>")
	)
	(segment
		(start 44.11218 -126.648464)
		(end 43.954192 -126.682754)
		(width 0.1651)
		(layer "In5.Cu")
		(net "P5E_PEX0_STN1_RX_DN<24>")
	)
	(segment
		(start 47.914814 -122.686064)
		(end 47.55515 -123.026932)
		(width 0.1651)
		(layer "In5.Cu")
		(net "P5E_PEX0_STN1_RX_DN<24>")
	)
	(segment
		(start 36.783264 -158.172912)
		(end 37.782246 -163.875974)
		(width 0.1651)
		(layer "In5.Cu")
		(net "P5E_PEX0_STN1_RX_DN<24>")
	)
	(segment
		(start 53.80609 -119.795544)
		(end 52.099972 -119.795544)
		(width 0.1651)
		(layer "In5.Cu")
		(net "P5E_PEX0_STN1_RX_DN<24>")
	)
	(segment
		(start 40.357552 -139.325096)
		(end 40.400732 -139.480798)
		(width 0.1651)
		(layer "In5.Cu")
		(net "P5E_PEX0_STN1_RX_DN<24>")
	)
	(segment
		(start 45.785786 -124.70511)
		(end 45.624242 -124.701046)
		(width 0.1651)
		(layer "In5.Cu")
		(net "P5E_PEX0_STN1_RX_DN<24>")
	)
	(segment
		(start 42.695368 -128.983232)
		(end 41.273222 -137.708894)
		(width 0.1651)
		(layer "In5.Cu")
		(net "P5E_PEX0_STN1_RX_DN<24>")
	)
	(segment
		(start 40.757348 -138.851132)
		(end 40.601646 -138.894312)
		(width 0.1651)
		(layer "In5.Cu")
		(net "P5E_PEX0_STN1_RX_DN<24>")
	)
	(segment
		(start 50.15865 -120.400064)
		(end 48.803814 -121.68505)
		(width 0.1651)
		(layer "In5.Cu")
		(net "P5E_PEX0_STN1_RX_DN<24>")
	)
	(segment
		(start 39.120826 -141.979904)
		(end 38.969442 -142.037054)
		(width 0.1651)
		(layer "In5.Cu")
		(net "P5E_PEX0_STN1_RX_DN<24>")
	)
	(segment
		(start 38.969442 -142.037054)
		(end 37.51834 -145.252186)
		(width 0.1651)
		(layer "In5.Cu")
		(net "P5E_PEX0_STN1_RX_DN<24>")
	)
	(segment
		(start 66.915792 -268.381226)
		(end 66.915792 -271.773904)
		(width 0.1651)
		(layer "In5.Cu")
		(net "P5E_PEX0_STN1_RX_DN<24>")
	)
	(segment
		(start 41.273222 -137.708894)
		(end 40.95877 -138.264138)
		(width 0.1651)
		(layer "In5.Cu")
		(net "P5E_PEX0_STN1_RX_DN<24>")
	)
	(segment
		(start 40.95877 -138.264138)
		(end 41.001696 -138.41984)
		(width 0.1651)
		(layer "In5.Cu")
		(net "P5E_PEX0_STN1_RX_DN<24>")
	)
	(segment
		(start 48.439832 -122.187716)
		(end 48.278288 -122.183652)
		(width 0.1651)
		(layer "In5.Cu")
		(net "P5E_PEX0_STN1_RX_DN<24>")
	)
	(segment
		(start 37.782246 -163.875974)
		(end 66.915792 -268.381226)
		(width 0.1651)
		(layer "In5.Cu")
		(net "P5E_PEX0_STN1_RX_DN<24>")
	)
	(segment
		(start 47.919132 -122.524266)
		(end 47.914814 -122.686064)
		(width 0.1651)
		(layer "In5.Cu")
		(net "P5E_PEX0_STN1_RX_DN<24>")
	)
	(segment
		(start 66.915792 -271.802352)
		(end 66.870072 -271.848072)
		(width 0.1143)
		(layer "In5.Cu")
		(net "P5E_PEX0_STN1_RX_DN<24>")
	)
	(segment
		(start 40.400732 -139.480798)
		(end 40.156384 -139.91209)
		(width 0.1651)
		(layer "In5.Cu")
		(net "P5E_PEX0_STN1_RX_DN<24>")
	)
	(segment
		(start 46.508924 -123.86183)
		(end 46.149768 -124.202444)
		(width 0.1651)
		(layer "In5.Cu")
		(net "P5E_PEX0_STN1_RX_DN<24>")
	)
	(segment
		(start 36.350702 -151.578564)
		(end 36.783264 -158.172912)
		(width 0.1651)
		(layer "In5.Cu")
		(net "P5E_PEX0_STN1_RX_DN<24>")
	)
	(segment
		(start 40.156384 -139.91209)
		(end 40.000682 -139.95527)
		(width 0.1651)
		(layer "In5.Cu")
		(net "P5E_PEX0_STN1_RX_DN<24>")
	)
	(segment
		(start 44.346876 -126.073916)
		(end 44.380912 -126.231904)
		(width 0.1651)
		(layer "In5.Cu")
		(net "P5E_PEX0_STN1_RX_DN<24>")
	)
	(segment
		(start 67.249548 -273.365214)
		(end 67.249548 -273.099784)
		(width 0.1143)
		(layer "In5.Cu")
		(net "P5E_PEX0_STN1_RX_DN<24>")
	)
	(segment
		(start 52.099972 -119.795544)
		(end 50.15865 -120.400064)
		(width 0.1651)
		(layer "In5.Cu")
		(net "P5E_PEX0_STN1_RX_DN<24>")
	)
	(segment
		(start 39.324534 -141.528292)
		(end 39.120826 -141.979904)
		(width 0.1651)
		(layer "In5.Cu")
		(net "P5E_PEX0_STN1_RX_DN<24>")
	)
	(segment
		(start 47.55515 -123.026932)
		(end 47.393606 -123.022868)
		(width 0.1651)
		(layer "In5.Cu")
		(net "P5E_PEX0_STN1_RX_DN<24>")
	)
	(segment
		(start 44.380912 -126.231904)
		(end 44.11218 -126.648464)
		(width 0.1651)
		(layer "In5.Cu")
		(net "P5E_PEX0_STN1_RX_DN<24>")
	)
	(segment
		(start 66.870072 -273.376136)
		(end 66.97345 -273.479514)
		(width 0.1143)
		(layer "In5.Cu")
		(net "P5E_PEX0_STN1_RX_DN<24>")
	)
	(segment
		(start 169.901616 -110.407958)
		(end 170.196764 -110.11281)
		(width 0.13462)
		(layer "F.Cu")
		(net "P5E_PEX1_STN1_RX_DP<22>")
	)
	(segment
		(start 167.393112 -110.407958)
		(end 169.901616 -110.407958)
		(width 0.13462)
		(layer "F.Cu")
		(net "P5E_PEX1_STN1_RX_DP<22>")
	)
	(segment
		(start 166.742364 -110.245144)
		(end 167.230298 -110.245144)
		(width 0.13462)
		(layer "F.Cu")
		(net "P5E_PEX1_STN1_RX_DP<22>")
	)
	(segment
		(start 167.230298 -110.245144)
		(end 167.393112 -110.407958)
		(width 0.13462)
		(layer "F.Cu")
		(net "P5E_PEX1_STN1_RX_DP<22>")
	)
	(segment
		(start 181.449726 -273.784314)
		(end 181.449726 -274.049744)
		(width 0.1143)
		(layer "In5.Cu")
		(net "P5E_PEX1_STN1_RX_DP<22>")
	)
	(segment
		(start 158.701232 -115.598956)
		(end 155.10891 -136.92378)
		(width 0.1651)
		(layer "In5.Cu")
		(net "P5E_PEX1_STN1_RX_DP<22>")
	)
	(segment
		(start 153.171398 -140.590016)
		(end 151.284178 -144.791938)
		(width 0.1651)
		(layer "In5.Cu")
		(net "P5E_PEX1_STN1_RX_DP<22>")
	)
	(segment
		(start 159.97174 -114.24666)
		(end 159.347408 -114.534442)
		(width 0.1651)
		(layer "In5.Cu")
		(net "P5E_PEX1_STN1_RX_DP<22>")
	)
	(segment
		(start 181.094634 -273.670014)
		(end 181.335426 -273.670014)
		(width 0.1143)
		(layer "In5.Cu")
		(net "P5E_PEX1_STN1_RX_DP<22>")
	)
	(segment
		(start 150.634954 -158.40456)
		(end 151.724868 -164.482018)
		(width 0.1651)
		(layer "In5.Cu")
		(net "P5E_PEX1_STN1_RX_DP<22>")
	)
	(segment
		(start 180.83403 -271.526)
		(end 180.83403 -271.554448)
		(width 0.1143)
		(layer "In5.Cu")
		(net "P5E_PEX1_STN1_RX_DP<22>")
	)
	(segment
		(start 169.905934 -110.40364)
		(end 167.887396 -110.40364)
		(width 0.1651)
		(layer "In5.Cu")
		(net "P5E_PEX1_STN1_RX_DP<22>")
	)
	(segment
		(start 170.196764 -110.11281)
		(end 169.905934 -110.40364)
		(width 0.1651)
		(layer "In5.Cu")
		(net "P5E_PEX1_STN1_RX_DP<22>")
	)
	(segment
		(start 160.588706 -114.177826)
		(end 160.423352 -114.24666)
		(width 0.1651)
		(layer "In5.Cu")
		(net "P5E_PEX1_STN1_RX_DP<22>")
	)
	(segment
		(start 180.87975 -271.600168)
		(end 180.87975 -273.45513)
		(width 0.1143)
		(layer "In5.Cu")
		(net "P5E_PEX1_STN1_RX_DP<22>")
	)
	(segment
		(start 150.17623 -151.024336)
		(end 150.634954 -158.40456)
		(width 0.1651)
		(layer "In5.Cu")
		(net "P5E_PEX1_STN1_RX_DP<22>")
	)
	(segment
		(start 159.0167 -114.922554)
		(end 158.701232 -115.598956)
		(width 0.1651)
		(layer "In5.Cu")
		(net "P5E_PEX1_STN1_RX_DP<22>")
	)
	(segment
		(start 180.87975 -273.45513)
		(end 181.094634 -273.670014)
		(width 0.1143)
		(layer "In5.Cu")
		(net "P5E_PEX1_STN1_RX_DP<22>")
	)
	(segment
		(start 181.335426 -273.670014)
		(end 181.449726 -273.784314)
		(width 0.1143)
		(layer "In5.Cu")
		(net "P5E_PEX1_STN1_RX_DP<22>")
	)
	(segment
		(start 151.284178 -144.791938)
		(end 150.17623 -151.024336)
		(width 0.1651)
		(layer "In5.Cu")
		(net "P5E_PEX1_STN1_RX_DP<22>")
	)
	(segment
		(start 151.724868 -164.482018)
		(end 180.83403 -268.825472)
		(width 0.1651)
		(layer "In5.Cu")
		(net "P5E_PEX1_STN1_RX_DP<22>")
	)
	(segment
		(start 180.83403 -271.554448)
		(end 180.87975 -271.600168)
		(width 0.1143)
		(layer "In5.Cu")
		(net "P5E_PEX1_STN1_RX_DP<22>")
	)
	(segment
		(start 163.684712 -112.114584)
		(end 160.588706 -114.177826)
		(width 0.1651)
		(layer "In5.Cu")
		(net "P5E_PEX1_STN1_RX_DP<22>")
	)
	(segment
		(start 155.10891 -136.92378)
		(end 153.171398 -140.590016)
		(width 0.1651)
		(layer "In5.Cu")
		(net "P5E_PEX1_STN1_RX_DP<22>")
	)
	(segment
		(start 159.347408 -114.534442)
		(end 159.0167 -114.922554)
		(width 0.1651)
		(layer "In5.Cu")
		(net "P5E_PEX1_STN1_RX_DP<22>")
	)
	(segment
		(start 167.887396 -110.40364)
		(end 163.684712 -112.114584)
		(width 0.1651)
		(layer "In5.Cu")
		(net "P5E_PEX1_STN1_RX_DP<22>")
	)
	(segment
		(start 180.83403 -268.825472)
		(end 180.83403 -271.526)
		(width 0.1651)
		(layer "In5.Cu")
		(net "P5E_PEX1_STN1_RX_DP<22>")
	)
	(segment
		(start 160.423352 -114.24666)
		(end 159.97174 -114.24666)
		(width 0.1651)
		(layer "In5.Cu")
		(net "P5E_PEX1_STN1_RX_DP<22>")
	)
	(segment
		(start 118.080028 -351.611438)
		(end 118.374668 -351.316798)
		(width 0.13462)
		(layer "F.Cu")
		(net "P5E_PEX1_STN6_TX_C_DP<100>")
	)
	(segment
		(start 118.374668 -350.685354)
		(end 118.054628 -350.365314)
		(width 0.13462)
		(layer "F.Cu")
		(net "P5E_PEX1_STN6_TX_C_DP<100>")
	)
	(segment
		(start 118.374668 -351.316798)
		(end 118.374668 -350.685354)
		(width 0.13462)
		(layer "F.Cu")
		(net "P5E_PEX1_STN6_TX_C_DP<100>")
	)
	(segment
		(start 116.816378 -353.975162)
		(end 118.370858 -352.420682)
		(width 0.1651)
		(layer "In7.Cu")
		(net "P5E_PEX1_STN6_TX_C_DP<100>")
	)
	(segment
		(start 118.370858 -351.902268)
		(end 118.080028 -351.611438)
		(width 0.1651)
		(layer "In7.Cu")
		(net "P5E_PEX1_STN6_TX_C_DP<100>")
	)
	(segment
		(start 116.816378 -358.885236)
		(end 116.816378 -353.975162)
		(width 0.1651)
		(layer "In7.Cu")
		(net "P5E_PEX1_STN6_TX_C_DP<100>")
	)
	(segment
		(start 122.869198 -383.798826)
		(end 123.287536 -383.380488)
		(width 0.1651)
		(layer "In7.Cu")
		(net "P5E_PEX1_STN6_TX_C_DP<100>")
	)
	(segment
		(start 121.722642 -366.364774)
		(end 121.447306 -365.952786)
		(width 0.1651)
		(layer "In7.Cu")
		(net "P5E_PEX1_STN6_TX_C_DP<100>")
	)
	(segment
		(start 122.082306 -366.903508)
		(end 122.103388 -366.79759)
		(width 0.1651)
		(layer "In7.Cu")
		(net "P5E_PEX1_STN6_TX_C_DP<100>")
	)
	(segment
		(start 121.447306 -365.952786)
		(end 121.468134 -365.847122)
		(width 0.1651)
		(layer "In7.Cu")
		(net "P5E_PEX1_STN6_TX_C_DP<100>")
	)
	(segment
		(start 121.828306 -366.385856)
		(end 121.722642 -366.364774)
		(width 0.1651)
		(layer "In7.Cu")
		(net "P5E_PEX1_STN6_TX_C_DP<100>")
	)
	(segment
		(start 122.46356 -367.336578)
		(end 122.357896 -367.315496)
		(width 0.1651)
		(layer "In7.Cu")
		(net "P5E_PEX1_STN6_TX_C_DP<100>")
	)
	(segment
		(start 123.287536 -383.380488)
		(end 123.287536 -368.569748)
		(width 0.1651)
		(layer "In7.Cu")
		(net "P5E_PEX1_STN6_TX_C_DP<100>")
	)
	(segment
		(start 123.287536 -368.569748)
		(end 122.46356 -367.336578)
		(width 0.1651)
		(layer "In7.Cu")
		(net "P5E_PEX1_STN6_TX_C_DP<100>")
	)
	(segment
		(start 122.103388 -366.79759)
		(end 121.828306 -366.385856)
		(width 0.1651)
		(layer "In7.Cu")
		(net "P5E_PEX1_STN6_TX_C_DP<100>")
	)
	(segment
		(start 122.510042 -383.671826)
		(end 122.637042 -383.798826)
		(width 0.1651)
		(layer "In7.Cu")
		(net "P5E_PEX1_STN6_TX_C_DP<100>")
	)
	(segment
		(start 122.357896 -367.315496)
		(end 122.082306 -366.903508)
		(width 0.1651)
		(layer "In7.Cu")
		(net "P5E_PEX1_STN6_TX_C_DP<100>")
	)
	(segment
		(start 121.468134 -365.847122)
		(end 116.816378 -358.885236)
		(width 0.1651)
		(layer "In7.Cu")
		(net "P5E_PEX1_STN6_TX_C_DP<100>")
	)
	(segment
		(start 118.370858 -352.420682)
		(end 118.370858 -351.902268)
		(width 0.1651)
		(layer "In7.Cu")
		(net "P5E_PEX1_STN6_TX_C_DP<100>")
	)
	(segment
		(start 122.637042 -383.798826)
		(end 122.869198 -383.798826)
		(width 0.1651)
		(layer "In7.Cu")
		(net "P5E_PEX1_STN6_TX_C_DP<100>")
	)
	(segment
		(start 122.510042 -383.290064)
		(end 122.510042 -383.671826)
		(width 0.1651)
		(layer "In7.Cu")
		(net "P5E_PEX1_STN6_TX_C_DP<100>")
	)
	(segment
		(start 416.476688 -130.044952)
		(end 416.32124 -130.2004)
		(width 0.13462)
		(layer "F.Cu")
		(net "P5E_PEX3_STN0_RX_DN<4>")
	)
	(segment
		(start 416.95751 -130.044952)
		(end 416.476688 -130.044952)
		(width 0.13462)
		(layer "F.Cu")
		(net "P5E_PEX3_STN0_RX_DN<4>")
	)
	(segment
		(start 416.32124 -130.2004)
		(end 415.644076 -130.2004)
		(width 0.13462)
		(layer "F.Cu")
		(net "P5E_PEX3_STN0_RX_DN<4>")
	)
	(segment
		(start 415.644076 -130.2004)
		(end 415.35731 -129.913634)
		(width 0.13462)
		(layer "F.Cu")
		(net "P5E_PEX3_STN0_RX_DN<4>")
	)
	(segment
		(start 428.778162 -147.649184)
		(end 427.631352 -139.993624)
		(width 0.1651)
		(layer "In5.Cu")
		(net "P5E_PEX3_STN0_RX_DN<4>")
	)
	(segment
		(start 416.076384 -130.204464)
		(end 415.64814 -130.204464)
		(width 0.1651)
		(layer "In5.Cu")
		(net "P5E_PEX3_STN0_RX_DN<4>")
	)
	(segment
		(start 428.602648 -284.120082)
		(end 432.15052 -284.120082)
		(width 0.1143)
		(layer "In5.Cu")
		(net "P5E_PEX3_STN0_RX_DN<4>")
	)
	(segment
		(start 443.97549 -272.573242)
		(end 444.075566 -269.73022)
		(width 0.1651)
		(layer "In5.Cu")
		(net "P5E_PEX3_STN0_RX_DN<4>")
	)
	(segment
		(start 426.058076 -136.865868)
		(end 424.056048 -135.076692)
		(width 0.1651)
		(layer "In5.Cu")
		(net "P5E_PEX3_STN0_RX_DN<4>")
	)
	(segment
		(start 422.261284 -133.472428)
		(end 416.076384 -130.204464)
		(width 0.1651)
		(layer "In5.Cu")
		(net "P5E_PEX3_STN0_RX_DN<4>")
	)
	(segment
		(start 415.64814 -130.204464)
		(end 415.35731 -129.913634)
		(width 0.1651)
		(layer "In5.Cu")
		(net "P5E_PEX3_STN0_RX_DN<4>")
	)
	(segment
		(start 430.28235 -148.287486)
		(end 430.28235 -148.28774)
		(width 0.1651)
		(layer "In5.Cu")
		(net "P5E_PEX3_STN0_RX_DN<4>")
	)
	(segment
		(start 428.84979 -284.499812)
		(end 428.58436 -284.499812)
		(width 0.1143)
		(layer "In5.Cu")
		(net "P5E_PEX3_STN0_RX_DN<4>")
	)
	(segment
		(start 431.49647 -149.578568)
		(end 430.368964 -148.308314)
		(width 0.1651)
		(layer "In5.Cu")
		(net "P5E_PEX3_STN0_RX_DN<4>")
	)
	(segment
		(start 428.47006 -284.25267)
		(end 428.602648 -284.120082)
		(width 0.1143)
		(layer "In5.Cu")
		(net "P5E_PEX3_STN0_RX_DN<4>")
	)
	(segment
		(start 424.056048 -135.076692)
		(end 424.056048 -135.076438)
		(width 0.1651)
		(layer "In5.Cu")
		(net "P5E_PEX3_STN0_RX_DN<4>")
	)
	(segment
		(start 434.005482 -151.490172)
		(end 433.64023 -150.649178)
		(width 0.1651)
		(layer "In5.Cu")
		(net "P5E_PEX3_STN0_RX_DN<4>")
	)
	(segment
		(start 429.121316 -148.009864)
		(end 428.778162 -147.649184)
		(width 0.1651)
		(layer "In5.Cu")
		(net "P5E_PEX3_STN0_RX_DN<4>")
	)
	(segment
		(start 427.631352 -139.993624)
		(end 426.869606 -138.063478)
		(width 0.1651)
		(layer "In5.Cu")
		(net "P5E_PEX3_STN0_RX_DN<4>")
	)
	(segment
		(start 428.47006 -284.385512)
		(end 428.47006 -284.25267)
		(width 0.1143)
		(layer "In5.Cu")
		(net "P5E_PEX3_STN0_RX_DN<4>")
	)
	(segment
		(start 433.770786 -232.2322)
		(end 434.372512 -168.331642)
		(width 0.1651)
		(layer "In5.Cu")
		(net "P5E_PEX3_STN0_RX_DN<4>")
	)
	(segment
		(start 434.372512 -168.331642)
		(end 434.005482 -151.490172)
		(width 0.1651)
		(layer "In5.Cu")
		(net "P5E_PEX3_STN0_RX_DN<4>")
	)
	(segment
		(start 435.646322 -240.890298)
		(end 433.770786 -232.2322)
		(width 0.1651)
		(layer "In5.Cu")
		(net "P5E_PEX3_STN0_RX_DN<4>")
	)
	(segment
		(start 428.58436 -284.499812)
		(end 428.47006 -284.385512)
		(width 0.1143)
		(layer "In5.Cu")
		(net "P5E_PEX3_STN0_RX_DN<4>")
	)
	(segment
		(start 424.056048 -135.076438)
		(end 422.261284 -133.472428)
		(width 0.1651)
		(layer "In5.Cu")
		(net "P5E_PEX3_STN0_RX_DN<4>")
	)
	(segment
		(start 442.017404 -276.06625)
		(end 443.97549 -272.573242)
		(width 0.1651)
		(layer "In5.Cu")
		(net "P5E_PEX3_STN0_RX_DN<4>")
	)
	(segment
		(start 430.368964 -148.308314)
		(end 430.28235 -148.287486)
		(width 0.1651)
		(layer "In5.Cu")
		(net "P5E_PEX3_STN0_RX_DN<4>")
	)
	(segment
		(start 426.869606 -138.063478)
		(end 426.058076 -136.865868)
		(width 0.1651)
		(layer "In5.Cu")
		(net "P5E_PEX3_STN0_RX_DN<4>")
	)
	(segment
		(start 433.64023 -150.649178)
		(end 431.49647 -149.578568)
		(width 0.1651)
		(layer "In5.Cu")
		(net "P5E_PEX3_STN0_RX_DN<4>")
	)
	(segment
		(start 434.431948 -283.398722)
		(end 442.017404 -276.06625)
		(width 0.1651)
		(layer "In5.Cu")
		(net "P5E_PEX3_STN0_RX_DN<4>")
	)
	(segment
		(start 432.15052 -284.120082)
		(end 432.19624 -284.165802)
		(width 0.1143)
		(layer "In5.Cu")
		(net "P5E_PEX3_STN0_RX_DN<4>")
	)
	(segment
		(start 430.28235 -148.28774)
		(end 429.121316 -148.009864)
		(width 0.1651)
		(layer "In5.Cu")
		(net "P5E_PEX3_STN0_RX_DN<4>")
	)
	(segment
		(start 432.19624 -284.165802)
		(end 432.224688 -284.165802)
		(width 0.1143)
		(layer "In5.Cu")
		(net "P5E_PEX3_STN0_RX_DN<4>")
	)
	(segment
		(start 432.224688 -284.165802)
		(end 433.338986 -284.165802)
		(width 0.1651)
		(layer "In5.Cu")
		(net "P5E_PEX3_STN0_RX_DN<4>")
	)
	(segment
		(start 444.075566 -269.73022)
		(end 435.646322 -240.890298)
		(width 0.1651)
		(layer "In5.Cu")
		(net "P5E_PEX3_STN0_RX_DN<4>")
	)
	(segment
		(start 433.338986 -284.165802)
		(end 434.431948 -283.398722)
		(width 0.1651)
		(layer "In5.Cu")
		(net "P5E_PEX3_STN0_RX_DN<4>")
	)
	(segment
		(start 402.572728 -344.53957)
		(end 402.572728 -345.169998)
		(width 0.13462)
		(layer "F.Cu")
		(net "P5E_PEX3_STN5_TX_C_DP<94>")
	)
	(segment
		(start 402.572728 -345.169998)
		(end 402.27758 -345.465146)
		(width 0.13462)
		(layer "F.Cu")
		(net "P5E_PEX3_STN5_TX_C_DP<94>")
	)
	(segment
		(start 402.25218 -344.219022)
		(end 402.572728 -344.53957)
		(width 0.13462)
		(layer "F.Cu")
		(net "P5E_PEX3_STN5_TX_C_DP<94>")
	)
	(segment
		(start 391.832338 -366.755934)
		(end 391.707116 -366.74552)
		(width 0.1651)
		(layer "In13.Cu")
		(net "P5E_PEX3_STN5_TX_C_DP<94>")
	)
	(segment
		(start 388.81685 -378.79909)
		(end 388.68985 -378.67209)
		(width 0.1651)
		(layer "In13.Cu")
		(net "P5E_PEX3_STN5_TX_C_DP<94>")
	)
	(segment
		(start 390.360154 -368.00155)
		(end 389.533892 -369.78336)
		(width 0.1651)
		(layer "In13.Cu")
		(net "P5E_PEX3_STN5_TX_C_DP<94>")
	)
	(segment
		(start 401.01393 -357.932228)
		(end 400.206972 -359.671112)
		(width 0.1651)
		(layer "In13.Cu")
		(net "P5E_PEX3_STN5_TX_C_DP<94>")
	)
	(segment
		(start 391.328656 -367.065814)
		(end 391.318242 -367.191036)
		(width 0.1651)
		(layer "In13.Cu")
		(net "P5E_PEX3_STN5_TX_C_DP<94>")
	)
	(segment
		(start 391.707116 -366.74552)
		(end 391.328656 -367.065814)
		(width 0.1651)
		(layer "In13.Cu")
		(net "P5E_PEX3_STN5_TX_C_DP<94>")
	)
	(segment
		(start 388.68985 -378.67209)
		(end 388.68985 -378.290074)
		(width 0.1651)
		(layer "In13.Cu")
		(net "P5E_PEX3_STN5_TX_C_DP<94>")
	)
	(segment
		(start 401.01393 -347.764354)
		(end 401.01393 -357.932228)
		(width 0.1651)
		(layer "In13.Cu")
		(net "P5E_PEX3_STN5_TX_C_DP<94>")
	)
	(segment
		(start 402.56841 -345.755976)
		(end 402.56841 -346.209874)
		(width 0.1651)
		(layer "In13.Cu")
		(net "P5E_PEX3_STN5_TX_C_DP<94>")
	)
	(segment
		(start 392.21029 -366.436148)
		(end 391.832338 -366.755934)
		(width 0.1651)
		(layer "In13.Cu")
		(net "P5E_PEX3_STN5_TX_C_DP<94>")
	)
	(segment
		(start 389.533892 -378.512324)
		(end 389.247126 -378.79909)
		(width 0.1651)
		(layer "In13.Cu")
		(net "P5E_PEX3_STN5_TX_C_DP<94>")
	)
	(segment
		(start 393.616434 -365.246666)
		(end 393.491212 -365.235998)
		(width 0.1651)
		(layer "In13.Cu")
		(net "P5E_PEX3_STN5_TX_C_DP<94>")
	)
	(segment
		(start 389.247126 -378.79909)
		(end 388.81685 -378.79909)
		(width 0.1651)
		(layer "In13.Cu")
		(net "P5E_PEX3_STN5_TX_C_DP<94>")
	)
	(segment
		(start 392.220704 -366.310926)
		(end 392.21029 -366.436148)
		(width 0.1651)
		(layer "In13.Cu")
		(net "P5E_PEX3_STN5_TX_C_DP<94>")
	)
	(segment
		(start 400.206972 -359.671112)
		(end 393.616434 -365.246666)
		(width 0.1651)
		(layer "In13.Cu")
		(net "P5E_PEX3_STN5_TX_C_DP<94>")
	)
	(segment
		(start 393.102338 -365.681514)
		(end 392.724386 -366.0013)
		(width 0.1651)
		(layer "In13.Cu")
		(net "P5E_PEX3_STN5_TX_C_DP<94>")
	)
	(segment
		(start 393.112752 -365.556292)
		(end 393.102338 -365.681514)
		(width 0.1651)
		(layer "In13.Cu")
		(net "P5E_PEX3_STN5_TX_C_DP<94>")
	)
	(segment
		(start 392.599164 -365.990632)
		(end 392.220704 -366.310926)
		(width 0.1651)
		(layer "In13.Cu")
		(net "P5E_PEX3_STN5_TX_C_DP<94>")
	)
	(segment
		(start 393.491212 -365.235998)
		(end 393.112752 -365.556292)
		(width 0.1651)
		(layer "In13.Cu")
		(net "P5E_PEX3_STN5_TX_C_DP<94>")
	)
	(segment
		(start 391.318242 -367.191036)
		(end 390.360154 -368.00155)
		(width 0.1651)
		(layer "In13.Cu")
		(net "P5E_PEX3_STN5_TX_C_DP<94>")
	)
	(segment
		(start 392.724386 -366.0013)
		(end 392.599164 -365.990632)
		(width 0.1651)
		(layer "In13.Cu")
		(net "P5E_PEX3_STN5_TX_C_DP<94>")
	)
	(segment
		(start 389.533892 -369.78336)
		(end 389.533892 -378.512324)
		(width 0.1651)
		(layer "In13.Cu")
		(net "P5E_PEX3_STN5_TX_C_DP<94>")
	)
	(segment
		(start 402.27758 -345.465146)
		(end 402.56841 -345.755976)
		(width 0.1651)
		(layer "In13.Cu")
		(net "P5E_PEX3_STN5_TX_C_DP<94>")
	)
	(segment
		(start 402.56841 -346.209874)
		(end 401.01393 -347.764354)
		(width 0.1651)
		(layer "In13.Cu")
		(net "P5E_PEX3_STN5_TX_C_DP<94>")
	)
	(segment
		(start 282.842462 -153.560018)
		(end 285.031942 -153.560018)
		(width 0.13208)
		(layer "F.Cu")
		(net "NCSI_NIC4_TXD0")
	)
	(via
		(at 285.031942 -153.560018)
		(size 0.508)
		(drill 0.254)
		(layers "F.Cu" "B.Cu")
		(net "NCSI_NIC4_TXD0")
	)
	(segment
		(start 284.117796 -151.9936)
		(end 285.031942 -152.907746)
		(width 0.13208)
		(layer "B.Cu")
		(net "NCSI_NIC4_TXD0")
	)
	(segment
		(start 285.031942 -152.907746)
		(end 285.031942 -153.560018)
		(width 0.13208)
		(layer "B.Cu")
		(net "NCSI_NIC4_TXD0")
	)
	(segment
		(start 282.155392 -151.9936)
		(end 284.117796 -151.9936)
		(width 0.13208)
		(layer "B.Cu")
		(net "NCSI_NIC4_TXD0")
	)
	(segment
		(start 46.042326 -121.154952)
		(end 45.554392 -121.154952)
		(width 0.13462)
		(layer "F.Cu")
		(net "P5E_PEX0_STN1_TX_C_DN<25>")
	)
	(segment
		(start 39.859712 -121.317766)
		(end 39.547292 -121.005346)
		(width 0.13462)
		(layer "F.Cu")
		(net "P5E_PEX0_STN1_TX_C_DN<25>")
	)
	(segment
		(start 45.391578 -121.317766)
		(end 39.859712 -121.317766)
		(width 0.13462)
		(layer "F.Cu")
		(net "P5E_PEX0_STN1_TX_C_DN<25>")
	)
	(segment
		(start 45.554392 -121.154952)
		(end 45.391578 -121.317766)
		(width 0.13462)
		(layer "F.Cu")
		(net "P5E_PEX0_STN1_TX_C_DN<25>")
	)
	(segment
		(start 168.04767 -112.207802)
		(end 168.342564 -111.912908)
		(width 0.13462)
		(layer "F.Cu")
		(net "P5E_PEX1_STN1_RX_DP<23>")
	)
	(segment
		(start 166.742364 -112.044988)
		(end 167.230298 -112.044988)
		(width 0.13462)
		(layer "F.Cu")
		(net "P5E_PEX1_STN1_RX_DP<23>")
	)
	(segment
		(start 167.230298 -112.044988)
		(end 167.393112 -112.207802)
		(width 0.13462)
		(layer "F.Cu")
		(net "P5E_PEX1_STN1_RX_DP<23>")
	)
	(segment
		(start 167.393112 -112.207802)
		(end 168.04767 -112.207802)
		(width 0.13462)
		(layer "F.Cu")
		(net "P5E_PEX1_STN1_RX_DP<23>")
	)
	(segment
		(start 168.051734 -112.203738)
		(end 168.342564 -111.912908)
		(width 0.1651)
		(layer "In5.Cu")
		(net "P5E_PEX1_STN1_RX_DP<23>")
	)
	(segment
		(start 182.285386 -275.570188)
		(end 182.044594 -275.570188)
		(width 0.1143)
		(layer "In5.Cu")
		(net "P5E_PEX1_STN1_RX_DP<23>")
	)
	(segment
		(start 182.399686 -275.949918)
		(end 182.399686 -275.684488)
		(width 0.1143)
		(layer "In5.Cu")
		(net "P5E_PEX1_STN1_RX_DP<23>")
	)
	(segment
		(start 181.78399 -271.599406)
		(end 181.78399 -271.570958)
		(width 0.1143)
		(layer "In5.Cu")
		(net "P5E_PEX1_STN1_RX_DP<23>")
	)
	(segment
		(start 181.82971 -271.645126)
		(end 181.78399 -271.599406)
		(width 0.1143)
		(layer "In5.Cu")
		(net "P5E_PEX1_STN1_RX_DP<23>")
	)
	(segment
		(start 151.643588 -158.33471)
		(end 151.179022 -151.208994)
		(width 0.1651)
		(layer "In5.Cu")
		(net "P5E_PEX1_STN1_RX_DP<23>")
	)
	(segment
		(start 157.545786 -128.369314)
		(end 159.193738 -120.951244)
		(width 0.1651)
		(layer "In5.Cu")
		(net "P5E_PEX1_STN1_RX_DP<23>")
	)
	(segment
		(start 163.118038 -113.941098)
		(end 167.366442 -112.203738)
		(width 0.1651)
		(layer "In5.Cu")
		(net "P5E_PEX1_STN1_RX_DP<23>")
	)
	(segment
		(start 161.049208 -116.962174)
		(end 161.706814 -116.017548)
		(width 0.1651)
		(layer "In5.Cu")
		(net "P5E_PEX1_STN1_RX_DP<23>")
	)
	(segment
		(start 151.179022 -151.208994)
		(end 152.305766 -145.064734)
		(width 0.1651)
		(layer "In5.Cu")
		(net "P5E_PEX1_STN1_RX_DP<23>")
	)
	(segment
		(start 162.317684 -114.704622)
		(end 163.118038 -113.941098)
		(width 0.1651)
		(layer "In5.Cu")
		(net "P5E_PEX1_STN1_RX_DP<23>")
	)
	(segment
		(start 181.82971 -275.355304)
		(end 181.82971 -271.645126)
		(width 0.1143)
		(layer "In5.Cu")
		(net "P5E_PEX1_STN1_RX_DP<23>")
	)
	(segment
		(start 181.78399 -268.60881)
		(end 152.630378 -164.093144)
		(width 0.1651)
		(layer "In5.Cu")
		(net "P5E_PEX1_STN1_RX_DP<23>")
	)
	(segment
		(start 182.044594 -275.570188)
		(end 181.82971 -275.355304)
		(width 0.1143)
		(layer "In5.Cu")
		(net "P5E_PEX1_STN1_RX_DP<23>")
	)
	(segment
		(start 181.78399 -271.570958)
		(end 181.78399 -268.60881)
		(width 0.1651)
		(layer "In5.Cu")
		(net "P5E_PEX1_STN1_RX_DP<23>")
	)
	(segment
		(start 156.082746 -137.393934)
		(end 157.545786 -128.369314)
		(width 0.1651)
		(layer "In5.Cu")
		(net "P5E_PEX1_STN1_RX_DP<23>")
	)
	(segment
		(start 161.706814 -116.017548)
		(end 162.317684 -114.704622)
		(width 0.1651)
		(layer "In5.Cu")
		(net "P5E_PEX1_STN1_RX_DP<23>")
	)
	(segment
		(start 167.366442 -112.203738)
		(end 168.051734 -112.203738)
		(width 0.1651)
		(layer "In5.Cu")
		(net "P5E_PEX1_STN1_RX_DP<23>")
	)
	(segment
		(start 152.305766 -145.064734)
		(end 154.09291 -140.990066)
		(width 0.1651)
		(layer "In5.Cu")
		(net "P5E_PEX1_STN1_RX_DP<23>")
	)
	(segment
		(start 154.09291 -140.990066)
		(end 156.082746 -137.393934)
		(width 0.1651)
		(layer "In5.Cu")
		(net "P5E_PEX1_STN1_RX_DP<23>")
	)
	(segment
		(start 152.630378 -164.093144)
		(end 151.643588 -158.33471)
		(width 0.1651)
		(layer "In5.Cu")
		(net "P5E_PEX1_STN1_RX_DP<23>")
	)
	(segment
		(start 159.193738 -120.951244)
		(end 161.049208 -116.962174)
		(width 0.1651)
		(layer "In5.Cu")
		(net "P5E_PEX1_STN1_RX_DP<23>")
	)
	(segment
		(start 182.399686 -275.684488)
		(end 182.285386 -275.570188)
		(width 0.1143)
		(layer "In5.Cu")
		(net "P5E_PEX1_STN1_RX_DP<23>")
	)
	(segment
		(start 416.317684 -120.79732)
		(end 413.796734 -120.79732)
		(width 0.13462)
		(layer "F.Cu")
		(net "P5E_PEX3_STN0_RX_DN<1>")
	)
	(segment
		(start 416.95751 -120.635014)
		(end 416.47999 -120.635014)
		(width 0.13462)
		(layer "F.Cu")
		(net "P5E_PEX3_STN0_RX_DN<1>")
	)
	(segment
		(start 416.47999 -120.635014)
		(end 416.317684 -120.79732)
		(width 0.13462)
		(layer "F.Cu")
		(net "P5E_PEX3_STN0_RX_DN<1>")
	)
	(segment
		(start 413.796734 -120.79732)
		(end 413.50311 -120.503696)
		(width 0.13462)
		(layer "F.Cu")
		(net "P5E_PEX3_STN0_RX_DN<1>")
	)
	(segment
		(start 436.663846 -146.35226)
		(end 434.236368 -135.222996)
		(width 0.1651)
		(layer "In5.Cu")
		(net "P5E_PEX3_STN0_RX_DN<1>")
	)
	(segment
		(start 434.36794 -286.974534)
		(end 434.36794 -286.97428)
		(width 0.1651)
		(layer "In5.Cu")
		(net "P5E_PEX3_STN0_RX_DN<1>")
	)
	(segment
		(start 430.749964 -287.349946)
		(end 430.484534 -287.349946)
		(width 0.1143)
		(layer "In5.Cu")
		(net "P5E_PEX3_STN0_RX_DN<1>")
	)
	(segment
		(start 421.156638 -122.97664)
		(end 415.915856 -120.794526)
		(width 0.1651)
		(layer "In5.Cu")
		(net "P5E_PEX3_STN0_RX_DN<1>")
	)
	(segment
		(start 415.915856 -120.794526)
		(end 413.79394 -120.794526)
		(width 0.1651)
		(layer "In5.Cu")
		(net "P5E_PEX3_STN0_RX_DN<1>")
	)
	(segment
		(start 446.998598 -269.2781)
		(end 438.214008 -239.19307)
		(width 0.1651)
		(layer "In5.Cu")
		(net "P5E_PEX3_STN0_RX_DN<1>")
	)
	(segment
		(start 413.79394 -120.794526)
		(end 413.50311 -120.503696)
		(width 0.1651)
		(layer "In5.Cu")
		(net "P5E_PEX3_STN0_RX_DN<1>")
	)
	(segment
		(start 432.17592 -286.970216)
		(end 432.22164 -287.015936)
		(width 0.1143)
		(layer "In5.Cu")
		(net "P5E_PEX3_STN0_RX_DN<1>")
	)
	(segment
		(start 430.484534 -287.349946)
		(end 430.370234 -287.235646)
		(width 0.1143)
		(layer "In5.Cu")
		(net "P5E_PEX3_STN0_RX_DN<1>")
	)
	(segment
		(start 444.378334 -277.807928)
		(end 446.846706 -273.37258)
		(width 0.1651)
		(layer "In5.Cu")
		(net "P5E_PEX3_STN0_RX_DN<1>")
	)
	(segment
		(start 437.430672 -168.53408)
		(end 436.922164 -149.896322)
		(width 0.1651)
		(layer "In5.Cu")
		(net "P5E_PEX3_STN0_RX_DN<1>")
	)
	(segment
		(start 430.370234 -287.073848)
		(end 430.473866 -286.970216)
		(width 0.1143)
		(layer "In5.Cu")
		(net "P5E_PEX3_STN0_RX_DN<1>")
	)
	(segment
		(start 432.22164 -287.015936)
		(end 432.250088 -287.015936)
		(width 0.1143)
		(layer "In5.Cu")
		(net "P5E_PEX3_STN0_RX_DN<1>")
	)
	(segment
		(start 438.214008 -239.19307)
		(end 436.767732 -232.097072)
		(width 0.1651)
		(layer "In5.Cu")
		(net "P5E_PEX3_STN0_RX_DN<1>")
	)
	(segment
		(start 435.774592 -286.11068)
		(end 444.378334 -277.807928)
		(width 0.1651)
		(layer "In5.Cu")
		(net "P5E_PEX3_STN0_RX_DN<1>")
	)
	(segment
		(start 433.711858 -134.40664)
		(end 431.443638 -133.14426)
		(width 0.1651)
		(layer "In5.Cu")
		(net "P5E_PEX3_STN0_RX_DN<1>")
	)
	(segment
		(start 431.443638 -133.14426)
		(end 431.014378 -132.715)
		(width 0.1651)
		(layer "In5.Cu")
		(net "P5E_PEX3_STN0_RX_DN<1>")
	)
	(segment
		(start 430.473866 -286.970216)
		(end 432.17592 -286.970216)
		(width 0.1143)
		(layer "In5.Cu")
		(net "P5E_PEX3_STN0_RX_DN<1>")
	)
	(segment
		(start 431.014378 -132.715)
		(end 428.862998 -131.52882)
		(width 0.1651)
		(layer "In5.Cu")
		(net "P5E_PEX3_STN0_RX_DN<1>")
	)
	(segment
		(start 434.236368 -135.222996)
		(end 433.711858 -134.40664)
		(width 0.1651)
		(layer "In5.Cu")
		(net "P5E_PEX3_STN0_RX_DN<1>")
	)
	(segment
		(start 436.922164 -149.896322)
		(end 436.663846 -146.35226)
		(width 0.1651)
		(layer "In5.Cu")
		(net "P5E_PEX3_STN0_RX_DN<1>")
	)
	(segment
		(start 430.370234 -287.235646)
		(end 430.370234 -287.073848)
		(width 0.1143)
		(layer "In5.Cu")
		(net "P5E_PEX3_STN0_RX_DN<1>")
	)
	(segment
		(start 428.862998 -131.52882)
		(end 423.399458 -125.19406)
		(width 0.1651)
		(layer "In5.Cu")
		(net "P5E_PEX3_STN0_RX_DN<1>")
	)
	(segment
		(start 432.250088 -287.015936)
		(end 434.300122 -287.015936)
		(width 0.1651)
		(layer "In5.Cu")
		(net "P5E_PEX3_STN0_RX_DN<1>")
	)
	(segment
		(start 434.36794 -286.97428)
		(end 435.774592 -286.11068)
		(width 0.1651)
		(layer "In5.Cu")
		(net "P5E_PEX3_STN0_RX_DN<1>")
	)
	(segment
		(start 423.399458 -125.19406)
		(end 421.156638 -122.97664)
		(width 0.1651)
		(layer "In5.Cu")
		(net "P5E_PEX3_STN0_RX_DN<1>")
	)
	(segment
		(start 446.846706 -273.37258)
		(end 446.998598 -269.2781)
		(width 0.1651)
		(layer "In5.Cu")
		(net "P5E_PEX3_STN0_RX_DN<1>")
	)
	(segment
		(start 434.300122 -287.015936)
		(end 434.36794 -286.974534)
		(width 0.1651)
		(layer "In5.Cu")
		(net "P5E_PEX3_STN0_RX_DN<1>")
	)
	(segment
		(start 436.767732 -232.097072)
		(end 437.430672 -168.53408)
		(width 0.1651)
		(layer "In5.Cu")
		(net "P5E_PEX3_STN0_RX_DN<1>")
	)
	(segment
		(start 391.016998 -398.38503)
		(end 391.550398 -398.38503)
		(width 0.1651)
		(layer "In5.Cu")
		(net "P5E_PEX3_STN5_RX_DN<87>")
	)
	(segment
		(start 413.270192 -319.89268)
		(end 413.270192 -318.434466)
		(width 0.1143)
		(layer "In5.Cu")
		(net "P5E_PEX3_STN5_RX_DN<87>")
	)
	(segment
		(start 413.270192 -318.434466)
		(end 413.384492 -318.320166)
		(width 0.1143)
		(layer "In5.Cu")
		(net "P5E_PEX3_STN5_RX_DN<87>")
	)
	(segment
		(start 413.315912 -323.906388)
		(end 413.315912 -319.966848)
		(width 0.1651)
		(layer "In5.Cu")
		(net "P5E_PEX3_STN5_RX_DN<87>")
	)
	(segment
		(start 407.0858 -340.614)
		(end 412.669736 -327.150984)
		(width 0.1651)
		(layer "In5.Cu")
		(net "P5E_PEX3_STN5_RX_DN<87>")
	)
	(segment
		(start 391.550398 -398.38503)
		(end 392.047984 -397.887444)
		(width 0.1651)
		(layer "In5.Cu")
		(net "P5E_PEX3_STN5_RX_DN<87>")
	)
	(segment
		(start 390.889998 -398.890236)
		(end 390.889998 -398.51203)
		(width 0.1651)
		(layer "In5.Cu")
		(net "P5E_PEX3_STN5_RX_DN<87>")
	)
	(segment
		(start 406.527 -342.9254)
		(end 407.0858 -340.614)
		(width 0.1651)
		(layer "In5.Cu")
		(net "P5E_PEX3_STN5_RX_DN<87>")
	)
	(segment
		(start 413.315912 -319.966848)
		(end 413.315912 -319.9384)
		(width 0.1143)
		(layer "In5.Cu")
		(net "P5E_PEX3_STN5_RX_DN<87>")
	)
	(segment
		(start 413.315912 -319.9384)
		(end 413.270192 -319.89268)
		(width 0.1143)
		(layer "In5.Cu")
		(net "P5E_PEX3_STN5_RX_DN<87>")
	)
	(segment
		(start 402.844 -376.4026)
		(end 403.4282 -371.221)
		(width 0.1651)
		(layer "In5.Cu")
		(net "P5E_PEX3_STN5_RX_DN<87>")
	)
	(segment
		(start 398.78127 -392.027664)
		(end 400.211036 -390.92505)
		(width 0.1651)
		(layer "In5.Cu")
		(net "P5E_PEX3_STN5_RX_DN<87>")
	)
	(segment
		(start 392.28268 -394.776452)
		(end 398.78127 -392.027664)
		(width 0.1651)
		(layer "In5.Cu")
		(net "P5E_PEX3_STN5_RX_DN<87>")
	)
	(segment
		(start 401.651216 -388.887462)
		(end 402.5392 -386.3594)
		(width 0.1651)
		(layer "In5.Cu")
		(net "P5E_PEX3_STN5_RX_DN<87>")
	)
	(segment
		(start 392.047984 -397.887444)
		(end 392.047984 -395.19098)
		(width 0.1651)
		(layer "In5.Cu")
		(net "P5E_PEX3_STN5_RX_DN<87>")
	)
	(segment
		(start 412.669736 -327.150984)
		(end 413.315912 -323.906388)
		(width 0.1651)
		(layer "In5.Cu")
		(net "P5E_PEX3_STN5_RX_DN<87>")
	)
	(segment
		(start 392.047984 -395.19098)
		(end 392.28268 -394.776452)
		(width 0.1651)
		(layer "In5.Cu")
		(net "P5E_PEX3_STN5_RX_DN<87>")
	)
	(segment
		(start 406.441402 -359.892092)
		(end 406.527 -342.9254)
		(width 0.1651)
		(layer "In5.Cu")
		(net "P5E_PEX3_STN5_RX_DN<87>")
	)
	(segment
		(start 401.651724 -388.887462)
		(end 401.651216 -388.887462)
		(width 0.1651)
		(layer "In5.Cu")
		(net "P5E_PEX3_STN5_RX_DN<87>")
	)
	(segment
		(start 390.889998 -398.51203)
		(end 391.016998 -398.38503)
		(width 0.1651)
		(layer "In5.Cu")
		(net "P5E_PEX3_STN5_RX_DN<87>")
	)
	(segment
		(start 413.535622 -318.320166)
		(end 413.649922 -318.434466)
		(width 0.1143)
		(layer "In5.Cu")
		(net "P5E_PEX3_STN5_RX_DN<87>")
	)
	(segment
		(start 402.5392 -386.3594)
		(end 402.844 -376.4026)
		(width 0.1651)
		(layer "In5.Cu")
		(net "P5E_PEX3_STN5_RX_DN<87>")
	)
	(segment
		(start 403.4282 -371.221)
		(end 406.441402 -359.892092)
		(width 0.1651)
		(layer "In5.Cu")
		(net "P5E_PEX3_STN5_RX_DN<87>")
	)
	(segment
		(start 413.384492 -318.320166)
		(end 413.535622 -318.320166)
		(width 0.1143)
		(layer "In5.Cu")
		(net "P5E_PEX3_STN5_RX_DN<87>")
	)
	(segment
		(start 401.65147 -388.887716)
		(end 401.651724 -388.887462)
		(width 0.1651)
		(layer "In5.Cu")
		(net "P5E_PEX3_STN5_RX_DN<87>")
	)
	(segment
		(start 413.649922 -318.434466)
		(end 413.649922 -318.699896)
		(width 0.1143)
		(layer "In5.Cu")
		(net "P5E_PEX3_STN5_RX_DN<87>")
	)
	(segment
		(start 400.211036 -390.92505)
		(end 401.65147 -388.887716)
		(width 0.1651)
		(layer "In5.Cu")
		(net "P5E_PEX3_STN5_RX_DN<87>")
	)
	(segment
		(start 282.842462 -139.565126)
		(end 286.47009 -139.565126)
		(width 0.13208)
		(layer "F.Cu")
		(net "PRSNTB2_NIC4_N")
	)
	(segment
		(start 287.164018 -139.565126)
		(end 287.248092 -139.6492)
		(width 0.13208)
		(layer "F.Cu")
		(net "PRSNTB2_NIC4_N")
	)
	(segment
		(start 286.47009 -139.565126)
		(end 287.164018 -139.565126)
		(width 0.13208)
		(layer "F.Cu")
		(net "PRSNTB2_NIC4_N")
	)
	(segment
		(start 287.679892 -138.6332)
		(end 287.679892 -139.6492)
		(width 0.13208)
		(layer "F.Cu")
		(net "PRSNTB2_NIC4_N")
	)
	(segment
		(start 287.248092 -139.6492)
		(end 287.679892 -139.6492)
		(width 0.13208)
		(layer "F.Cu")
		(net "PRSNTB2_NIC4_N")
	)
	(via
		(at 286.47009 -139.565126)
		(size 0.762)
		(drill 0.381)
		(layers "F.Cu" "B.Cu")
		(net "PRSNTB2_NIC4_N")
	)
	(segment
		(start 46.042326 -121.7549)
		(end 45.554392 -121.7549)
		(width 0.13462)
		(layer "F.Cu")
		(net "P5E_PEX0_STN1_TX_C_DP<25>")
	)
	(segment
		(start 45.391578 -121.592086)
		(end 39.874952 -121.592086)
		(width 0.13462)
		(layer "F.Cu")
		(net "P5E_PEX0_STN1_TX_C_DP<25>")
	)
	(segment
		(start 39.874952 -121.592086)
		(end 39.547292 -121.919746)
		(width 0.13462)
		(layer "F.Cu")
		(net "P5E_PEX0_STN1_TX_C_DP<25>")
	)
	(segment
		(start 45.554392 -121.7549)
		(end 45.391578 -121.592086)
		(width 0.13462)
		(layer "F.Cu")
		(net "P5E_PEX0_STN1_TX_C_DP<25>")
	)
	(segment
		(start 167.230298 -124.755148)
		(end 166.742364 -124.755148)
		(width 0.13462)
		(layer "F.Cu")
		(net "P5E_PEX1_STN1_RX_DP<27>")
	)
	(segment
		(start 168.04767 -124.917962)
		(end 167.393112 -124.917962)
		(width 0.13462)
		(layer "F.Cu")
		(net "P5E_PEX1_STN1_RX_DP<27>")
	)
	(segment
		(start 167.393112 -124.917962)
		(end 167.230298 -124.755148)
		(width 0.13462)
		(layer "F.Cu")
		(net "P5E_PEX1_STN1_RX_DP<27>")
	)
	(segment
		(start 168.342564 -124.623068)
		(end 168.04767 -124.917962)
		(width 0.13462)
		(layer "F.Cu")
		(net "P5E_PEX1_STN1_RX_DP<27>")
	)
	(segment
		(start 168.342564 -124.622814)
		(end 168.342564 -124.623068)
		(width 0.13462)
		(layer "F.Cu")
		(net "P5E_PEX1_STN1_RX_DP<27>")
	)
	(segment
		(start 185.583576 -271.773904)
		(end 185.583576 -271.802352)
		(width 0.1143)
		(layer "In5.Cu")
		(net "P5E_PEX1_STN1_RX_DP<27>")
	)
	(segment
		(start 166.142924 -129.306066)
		(end 166.14267 -129.306574)
		(width 0.1651)
		(layer "In5.Cu")
		(net "P5E_PEX1_STN1_RX_DP<27>")
	)
	(segment
		(start 163.792154 -133.61543)
		(end 163.028122 -135.238236)
		(width 0.1651)
		(layer "In5.Cu")
		(net "P5E_PEX1_STN1_RX_DP<27>")
	)
	(segment
		(start 185.629296 -275.355304)
		(end 185.84418 -275.570188)
		(width 0.1143)
		(layer "In5.Cu")
		(net "P5E_PEX1_STN1_RX_DP<27>")
	)
	(segment
		(start 186.084972 -275.570188)
		(end 186.199526 -275.684742)
		(width 0.1143)
		(layer "In5.Cu")
		(net "P5E_PEX1_STN1_RX_DP<27>")
	)
	(segment
		(start 158.120588 -143.910304)
		(end 156.166058 -146.533108)
		(width 0.1651)
		(layer "In5.Cu")
		(net "P5E_PEX1_STN1_RX_DP<27>")
	)
	(segment
		(start 185.583576 -267.785596)
		(end 185.583576 -271.773904)
		(width 0.1651)
		(layer "In5.Cu")
		(net "P5E_PEX1_STN1_RX_DP<27>")
	)
	(segment
		(start 163.792408 -133.614922)
		(end 163.792154 -133.61543)
		(width 0.1651)
		(layer "In5.Cu")
		(net "P5E_PEX1_STN1_RX_DP<27>")
	)
	(segment
		(start 167.069262 -125.45314)
		(end 166.591234 -126.607316)
		(width 0.1651)
		(layer "In5.Cu")
		(net "P5E_PEX1_STN1_RX_DP<27>")
	)
	(segment
		(start 159.101282 -142.94231)
		(end 158.120588 -143.910304)
		(width 0.1651)
		(layer "In5.Cu")
		(net "P5E_PEX1_STN1_RX_DP<27>")
	)
	(segment
		(start 161.292286 -140.950442)
		(end 159.101282 -142.94231)
		(width 0.1651)
		(layer "In5.Cu")
		(net "P5E_PEX1_STN1_RX_DP<27>")
	)
	(segment
		(start 185.629296 -271.848072)
		(end 185.629296 -275.355304)
		(width 0.1143)
		(layer "In5.Cu")
		(net "P5E_PEX1_STN1_RX_DP<27>")
	)
	(segment
		(start 155.899104 -147.60702)
		(end 156.508196 -157.041342)
		(width 0.1651)
		(layer "In5.Cu")
		(net "P5E_PEX1_STN1_RX_DP<27>")
	)
	(segment
		(start 168.051734 -124.913644)
		(end 167.608758 -124.913644)
		(width 0.1651)
		(layer "In5.Cu")
		(net "P5E_PEX1_STN1_RX_DP<27>")
	)
	(segment
		(start 166.14267 -129.306574)
		(end 165.606222 -130.590798)
		(width 0.1651)
		(layer "In5.Cu")
		(net "P5E_PEX1_STN1_RX_DP<27>")
	)
	(segment
		(start 166.591234 -128.23317)
		(end 166.142924 -129.306066)
		(width 0.1651)
		(layer "In5.Cu")
		(net "P5E_PEX1_STN1_RX_DP<27>")
	)
	(segment
		(start 164.320982 -132.492242)
		(end 163.792408 -133.614922)
		(width 0.1651)
		(layer "In5.Cu")
		(net "P5E_PEX1_STN1_RX_DP<27>")
	)
	(segment
		(start 161.444178 -140.451078)
		(end 161.292286 -140.950442)
		(width 0.1651)
		(layer "In5.Cu")
		(net "P5E_PEX1_STN1_RX_DP<27>")
	)
	(segment
		(start 156.508196 -157.041342)
		(end 157.28315 -161.41446)
		(width 0.1651)
		(layer "In5.Cu")
		(net "P5E_PEX1_STN1_RX_DP<27>")
	)
	(segment
		(start 157.28315 -161.41446)
		(end 185.583576 -267.785596)
		(width 0.1651)
		(layer "In5.Cu")
		(net "P5E_PEX1_STN1_RX_DP<27>")
	)
	(segment
		(start 185.84418 -275.570188)
		(end 186.084972 -275.570188)
		(width 0.1143)
		(layer "In5.Cu")
		(net "P5E_PEX1_STN1_RX_DP<27>")
	)
	(segment
		(start 163.028122 -135.238236)
		(end 161.443924 -140.451078)
		(width 0.1651)
		(layer "In5.Cu")
		(net "P5E_PEX1_STN1_RX_DP<27>")
	)
	(segment
		(start 167.608758 -124.913644)
		(end 167.069262 -125.45314)
		(width 0.1651)
		(layer "In5.Cu")
		(net "P5E_PEX1_STN1_RX_DP<27>")
	)
	(segment
		(start 155.896056 -147.561554)
		(end 155.89885 -147.60702)
		(width 0.1651)
		(layer "In5.Cu")
		(net "P5E_PEX1_STN1_RX_DP<27>")
	)
	(segment
		(start 186.199526 -275.684742)
		(end 186.199526 -275.949918)
		(width 0.1143)
		(layer "In5.Cu")
		(net "P5E_PEX1_STN1_RX_DP<27>")
	)
	(segment
		(start 155.89885 -147.60702)
		(end 155.899104 -147.60702)
		(width 0.1651)
		(layer "In5.Cu")
		(net "P5E_PEX1_STN1_RX_DP<27>")
	)
	(segment
		(start 166.591234 -126.607316)
		(end 166.591234 -128.23317)
		(width 0.1651)
		(layer "In5.Cu")
		(net "P5E_PEX1_STN1_RX_DP<27>")
	)
	(segment
		(start 185.583576 -271.802352)
		(end 185.629296 -271.848072)
		(width 0.1143)
		(layer "In5.Cu")
		(net "P5E_PEX1_STN1_RX_DP<27>")
	)
	(segment
		(start 156.166058 -146.533108)
		(end 155.896056 -147.561554)
		(width 0.1651)
		(layer "In5.Cu")
		(net "P5E_PEX1_STN1_RX_DP<27>")
	)
	(segment
		(start 165.606222 -130.590798)
		(end 164.320982 -132.492242)
		(width 0.1651)
		(layer "In5.Cu")
		(net "P5E_PEX1_STN1_RX_DP<27>")
	)
	(segment
		(start 161.443924 -140.451078)
		(end 161.444178 -140.451078)
		(width 0.1651)
		(layer "In5.Cu")
		(net "P5E_PEX1_STN1_RX_DP<27>")
	)
	(segment
		(start 168.342564 -124.622814)
		(end 168.051734 -124.913644)
		(width 0.1651)
		(layer "In5.Cu")
		(net "P5E_PEX1_STN1_RX_DP<27>")
	)
	(segment
		(start 115.834668 -345.465146)
		(end 115.540028 -345.170506)
		(width 0.13462)
		(layer "F.Cu")
		(net "P5E_PEX1_STN6_TX_C_DN<102>")
	)
	(segment
		(start 115.540028 -344.539062)
		(end 115.860068 -344.219022)
		(width 0.13462)
		(layer "F.Cu")
		(net "P5E_PEX1_STN6_TX_C_DN<102>")
	)
	(segment
		(start 115.540028 -345.170506)
		(end 115.540028 -344.539062)
		(width 0.13462)
		(layer "F.Cu")
		(net "P5E_PEX1_STN6_TX_C_DN<102>")
	)
	(segment
		(start 115.54714 -345.752674)
		(end 115.54714 -346.44584)
		(width 0.1651)
		(layer "In7.Cu")
		(net "P5E_PEX1_STN6_TX_C_DN<102>")
	)
	(segment
		(start 113.989358 -358.73182)
		(end 114.183922 -359.4608)
		(width 0.1651)
		(layer "In7.Cu")
		(net "P5E_PEX1_STN6_TX_C_DN<102>")
	)
	(segment
		(start 115.834668 -345.465146)
		(end 115.54714 -345.752674)
		(width 0.1651)
		(layer "In7.Cu")
		(net "P5E_PEX1_STN6_TX_C_DN<102>")
	)
	(segment
		(start 115.54714 -346.44584)
		(end 113.989358 -348.003622)
		(width 0.1651)
		(layer "In7.Cu")
		(net "P5E_PEX1_STN6_TX_C_DN<102>")
	)
	(segment
		(start 118.237254 -384.080766)
		(end 118.11 -384.20802)
		(width 0.1651)
		(layer "In7.Cu")
		(net "P5E_PEX1_STN6_TX_C_DN<102>")
	)
	(segment
		(start 119.169434 -383.497328)
		(end 118.585996 -384.080766)
		(width 0.1651)
		(layer "In7.Cu")
		(net "P5E_PEX1_STN6_TX_C_DN<102>")
	)
	(segment
		(start 116.783104 -364.558326)
		(end 119.169434 -368.681254)
		(width 0.1651)
		(layer "In7.Cu")
		(net "P5E_PEX1_STN6_TX_C_DN<102>")
	)
	(segment
		(start 119.169434 -368.681254)
		(end 119.169434 -383.497328)
		(width 0.1651)
		(layer "In7.Cu")
		(net "P5E_PEX1_STN6_TX_C_DN<102>")
	)
	(segment
		(start 113.989358 -348.003622)
		(end 113.989358 -358.73182)
		(width 0.1651)
		(layer "In7.Cu")
		(net "P5E_PEX1_STN6_TX_C_DN<102>")
	)
	(segment
		(start 114.183922 -359.4608)
		(end 116.783104 -364.558326)
		(width 0.1651)
		(layer "In7.Cu")
		(net "P5E_PEX1_STN6_TX_C_DN<102>")
	)
	(segment
		(start 118.585996 -384.080766)
		(end 118.237254 -384.080766)
		(width 0.1651)
		(layer "In7.Cu")
		(net "P5E_PEX1_STN6_TX_C_DN<102>")
	)
	(segment
		(start 118.11 -384.20802)
		(end 118.11 -384.590036)
		(width 0.1651)
		(layer "In7.Cu")
		(net "P5E_PEX1_STN6_TX_C_DN<102>")
	)
	(segment
		(start 355.876352 -390.700006)
		(end 353.366324 -392.49858)
		(width 0.1651)
		(layer "In9.Cu")
		(net "P5E_PEX2_STN5_RX_DP<87>")
	)
	(segment
		(start 348.120208 -394.555472)
		(end 347.734128 -394.941552)
		(width 0.1651)
		(layer "In9.Cu")
		(net "P5E_PEX2_STN5_RX_DP<87>")
	)
	(segment
		(start 347.734128 -394.941552)
		(end 347.734128 -397.812514)
		(width 0.1651)
		(layer "In9.Cu")
		(net "P5E_PEX2_STN5_RX_DP<87>")
	)
	(segment
		(start 346.289376 -338.597748)
		(end 347.678756 -340.067646)
		(width 0.1651)
		(layer "In9.Cu")
		(net "P5E_PEX2_STN5_RX_DP<87>")
	)
	(segment
		(start 346.890086 -397.97228)
		(end 346.890086 -397.59001)
		(width 0.1651)
		(layer "In9.Cu")
		(net "P5E_PEX2_STN5_RX_DP<87>")
	)
	(segment
		(start 353.366324 -392.49858)
		(end 351.686368 -393.156948)
		(width 0.1651)
		(layer "In9.Cu")
		(net "P5E_PEX2_STN5_RX_DP<87>")
	)
	(segment
		(start 358.430068 -386.336032)
		(end 357.574596 -388.646924)
		(width 0.1651)
		(layer "In9.Cu")
		(net "P5E_PEX2_STN5_RX_DP<87>")
	)
	(segment
		(start 349.331788 -393.971272)
		(end 348.87027 -394.15212)
		(width 0.1651)
		(layer "In9.Cu")
		(net "P5E_PEX2_STN5_RX_DP<87>")
	)
	(segment
		(start 347.017086 -398.09928)
		(end 346.890086 -397.97228)
		(width 0.1651)
		(layer "In9.Cu")
		(net "P5E_PEX2_STN5_RX_DP<87>")
	)
	(segment
		(start 347.678756 -340.067646)
		(end 358.573578 -368.733578)
		(width 0.1651)
		(layer "In9.Cu")
		(net "P5E_PEX2_STN5_RX_DP<87>")
	)
	(segment
		(start 349.981774 -393.716002)
		(end 349.92437 -393.848082)
		(width 0.1651)
		(layer "In9.Cu")
		(net "P5E_PEX2_STN5_RX_DP<87>")
	)
	(segment
		(start 348.87027 -394.15212)
		(end 348.812866 -394.283946)
		(width 0.1651)
		(layer "In9.Cu")
		(net "P5E_PEX2_STN5_RX_DP<87>")
	)
	(segment
		(start 342.88222 -336.325972)
		(end 346.289376 -338.597748)
		(width 0.1651)
		(layer "In9.Cu")
		(net "P5E_PEX2_STN5_RX_DP<87>")
	)
	(segment
		(start 297.324526 -320.22542)
		(end 298.09948 -320.22542)
		(width 0.1143)
		(layer "In9.Cu")
		(net "P5E_PEX2_STN5_RX_DP<87>")
	)
	(segment
		(start 297.460924 -318.129666)
		(end 297.205146 -318.129666)
		(width 0.1143)
		(layer "In9.Cu")
		(net "P5E_PEX2_STN5_RX_DP<87>")
	)
	(segment
		(start 351.554796 -393.099544)
		(end 351.093278 -393.280138)
		(width 0.1651)
		(layer "In9.Cu")
		(net "P5E_PEX2_STN5_RX_DP<87>")
	)
	(segment
		(start 351.035874 -393.412218)
		(end 350.574864 -393.592812)
		(width 0.1651)
		(layer "In9.Cu")
		(net "P5E_PEX2_STN5_RX_DP<87>")
	)
	(segment
		(start 298.09948 -320.22542)
		(end 298.1452 -320.27114)
		(width 0.1143)
		(layer "In9.Cu")
		(net "P5E_PEX2_STN5_RX_DP<87>")
	)
	(segment
		(start 350.574864 -393.592812)
		(end 350.443292 -393.535408)
		(width 0.1651)
		(layer "In9.Cu")
		(net "P5E_PEX2_STN5_RX_DP<87>")
	)
	(segment
		(start 349.92437 -393.848082)
		(end 349.46336 -394.028676)
		(width 0.1651)
		(layer "In9.Cu")
		(net "P5E_PEX2_STN5_RX_DP<87>")
	)
	(segment
		(start 347.734128 -397.812514)
		(end 347.447362 -398.09928)
		(width 0.1651)
		(layer "In9.Cu")
		(net "P5E_PEX2_STN5_RX_DP<87>")
	)
	(segment
		(start 298.173648 -320.27114)
		(end 298.812966 -320.27114)
		(width 0.1651)
		(layer "In9.Cu")
		(net "P5E_PEX2_STN5_RX_DP<87>")
	)
	(segment
		(start 358.762046 -370.097304)
		(end 358.430068 -386.336032)
		(width 0.1651)
		(layer "In9.Cu")
		(net "P5E_PEX2_STN5_RX_DP<87>")
	)
	(segment
		(start 296.978832 -318.35598)
		(end 296.978832 -319.879726)
		(width 0.1143)
		(layer "In9.Cu")
		(net "P5E_PEX2_STN5_RX_DP<87>")
	)
	(segment
		(start 297.205146 -318.129666)
		(end 296.978832 -318.35598)
		(width 0.1143)
		(layer "In9.Cu")
		(net "P5E_PEX2_STN5_RX_DP<87>")
	)
	(segment
		(start 296.978832 -319.879726)
		(end 297.324526 -320.22542)
		(width 0.1143)
		(layer "In9.Cu")
		(net "P5E_PEX2_STN5_RX_DP<87>")
	)
	(segment
		(start 347.447362 -398.09928)
		(end 347.017086 -398.09928)
		(width 0.1651)
		(layer "In9.Cu")
		(net "P5E_PEX2_STN5_RX_DP<87>")
	)
	(segment
		(start 298.812966 -320.27114)
		(end 342.88222 -336.325972)
		(width 0.1651)
		(layer "In9.Cu")
		(net "P5E_PEX2_STN5_RX_DP<87>")
	)
	(segment
		(start 348.812866 -394.283946)
		(end 348.120208 -394.555472)
		(width 0.1651)
		(layer "In9.Cu")
		(net "P5E_PEX2_STN5_RX_DP<87>")
	)
	(segment
		(start 349.46336 -394.028676)
		(end 349.331788 -393.971272)
		(width 0.1651)
		(layer "In9.Cu")
		(net "P5E_PEX2_STN5_RX_DP<87>")
	)
	(segment
		(start 351.686368 -393.156948)
		(end 351.554796 -393.099544)
		(width 0.1651)
		(layer "In9.Cu")
		(net "P5E_PEX2_STN5_RX_DP<87>")
	)
	(segment
		(start 297.549824 -318.040766)
		(end 297.460924 -318.129666)
		(width 0.1143)
		(layer "In9.Cu")
		(net "P5E_PEX2_STN5_RX_DP<87>")
	)
	(segment
		(start 358.573578 -368.733578)
		(end 358.762046 -370.097304)
		(width 0.1651)
		(layer "In9.Cu")
		(net "P5E_PEX2_STN5_RX_DP<87>")
	)
	(segment
		(start 350.443292 -393.535408)
		(end 349.981774 -393.716002)
		(width 0.1651)
		(layer "In9.Cu")
		(net "P5E_PEX2_STN5_RX_DP<87>")
	)
	(segment
		(start 297.549824 -317.749936)
		(end 297.549824 -318.040766)
		(width 0.1143)
		(layer "In9.Cu")
		(net "P5E_PEX2_STN5_RX_DP<87>")
	)
	(segment
		(start 298.1452 -320.27114)
		(end 298.173648 -320.27114)
		(width 0.1143)
		(layer "In9.Cu")
		(net "P5E_PEX2_STN5_RX_DP<87>")
	)
	(segment
		(start 357.574596 -388.646924)
		(end 355.876352 -390.700006)
		(width 0.1651)
		(layer "In9.Cu")
		(net "P5E_PEX2_STN5_RX_DP<87>")
	)
	(segment
		(start 351.093278 -393.280138)
		(end 351.035874 -393.412218)
		(width 0.1651)
		(layer "In9.Cu")
		(net "P5E_PEX2_STN5_RX_DP<87>")
	)
	(segment
		(start 422.06037 -132.444998)
		(end 421.557704 -132.444998)
		(width 0.13462)
		(layer "F.Cu")
		(net "P5E_PEX3_STN0_TX_C_DP<5>")
	)
	(segment
		(start 422.227248 -132.27812)
		(end 422.06037 -132.444998)
		(width 0.13462)
		(layer "F.Cu")
		(net "P5E_PEX3_STN0_TX_C_DP<5>")
	)
	(segment
		(start 430.694846 -132.601208)
		(end 430.371758 -132.27812)
		(width 0.13462)
		(layer "F.Cu")
		(net "P5E_PEX3_STN0_TX_C_DP<5>")
	)
	(segment
		(start 430.371758 -132.27812)
		(end 422.227248 -132.27812)
		(width 0.13462)
		(layer "F.Cu")
		(net "P5E_PEX3_STN0_TX_C_DP<5>")
	)
	(segment
		(start 382.862836 -391.345166)
		(end 391.348214 -387.195822)
		(width 0.1651)
		(layer "In5.Cu")
		(net "P5E_PEX3_STN5_RX_DN<80>")
	)
	(segment
		(start 406.620218 -316.534292)
		(end 406.734518 -316.419992)
		(width 0.1143)
		(layer "In5.Cu")
		(net "P5E_PEX3_STN5_RX_DN<80>")
	)
	(segment
		(start 376.150378 -397.284956)
		(end 376.647964 -396.78737)
		(width 0.1651)
		(layer "In5.Cu")
		(net "P5E_PEX3_STN5_RX_DN<80>")
	)
	(segment
		(start 376.647964 -396.78737)
		(end 376.647964 -395.86916)
		(width 0.1651)
		(layer "In5.Cu")
		(net "P5E_PEX3_STN5_RX_DN<80>")
	)
	(segment
		(start 389.327644 -341.115396)
		(end 405.251412 -326.109076)
		(width 0.1651)
		(layer "In5.Cu")
		(net "P5E_PEX3_STN5_RX_DN<80>")
	)
	(segment
		(start 382.862836 -391.344912)
		(end 382.862836 -391.345166)
		(width 0.1651)
		(layer "In5.Cu")
		(net "P5E_PEX3_STN5_RX_DN<80>")
	)
	(segment
		(start 406.999948 -316.534292)
		(end 406.999948 -316.799722)
		(width 0.1143)
		(layer "In5.Cu")
		(net "P5E_PEX3_STN5_RX_DN<80>")
	)
	(segment
		(start 394.203174 -385.076954)
		(end 394.211048 -369.009676)
		(width 0.1651)
		(layer "In5.Cu")
		(net "P5E_PEX3_STN5_RX_DN<80>")
	)
	(segment
		(start 375.616978 -397.284956)
		(end 376.150378 -397.284956)
		(width 0.1651)
		(layer "In5.Cu")
		(net "P5E_PEX3_STN5_RX_DN<80>")
	)
	(segment
		(start 406.885648 -316.419992)
		(end 406.999948 -316.534292)
		(width 0.1143)
		(layer "In5.Cu")
		(net "P5E_PEX3_STN5_RX_DN<80>")
	)
	(segment
		(start 375.489978 -397.790162)
		(end 375.489978 -397.411956)
		(width 0.1651)
		(layer "In5.Cu")
		(net "P5E_PEX3_STN5_RX_DN<80>")
	)
	(segment
		(start 406.235662 -323.908928)
		(end 406.665938 -321.8942)
		(width 0.1651)
		(layer "In5.Cu")
		(net "P5E_PEX3_STN5_RX_DN<80>")
	)
	(segment
		(start 406.665938 -319.96253)
		(end 406.665938 -319.934082)
		(width 0.1143)
		(layer "In5.Cu")
		(net "P5E_PEX3_STN5_RX_DN<80>")
	)
	(segment
		(start 391.348976 -387.195568)
		(end 393.78001 -385.813554)
		(width 0.1651)
		(layer "In5.Cu")
		(net "P5E_PEX3_STN5_RX_DN<80>")
	)
	(segment
		(start 405.251412 -326.109076)
		(end 406.235662 -323.908928)
		(width 0.1651)
		(layer "In5.Cu")
		(net "P5E_PEX3_STN5_RX_DN<80>")
	)
	(segment
		(start 406.665938 -319.934082)
		(end 406.620218 -319.888362)
		(width 0.1143)
		(layer "In5.Cu")
		(net "P5E_PEX3_STN5_RX_DN<80>")
	)
	(segment
		(start 406.665938 -321.8942)
		(end 406.665938 -319.96253)
		(width 0.1651)
		(layer "In5.Cu")
		(net "P5E_PEX3_STN5_RX_DN<80>")
	)
	(segment
		(start 394.211048 -369.009676)
		(end 388.86003 -358.721152)
		(width 0.1651)
		(layer "In5.Cu")
		(net "P5E_PEX3_STN5_RX_DN<80>")
	)
	(segment
		(start 388.86003 -358.721152)
		(end 388.86003 -341.9348)
		(width 0.1651)
		(layer "In5.Cu")
		(net "P5E_PEX3_STN5_RX_DN<80>")
	)
	(segment
		(start 388.86003 -341.9348)
		(end 389.327644 -341.115396)
		(width 0.1651)
		(layer "In5.Cu")
		(net "P5E_PEX3_STN5_RX_DN<80>")
	)
	(segment
		(start 393.78001 -385.813554)
		(end 394.203174 -385.076954)
		(width 0.1651)
		(layer "In5.Cu")
		(net "P5E_PEX3_STN5_RX_DN<80>")
	)
	(segment
		(start 391.348214 -387.195822)
		(end 391.348976 -387.195568)
		(width 0.1651)
		(layer "In5.Cu")
		(net "P5E_PEX3_STN5_RX_DN<80>")
	)
	(segment
		(start 378.921772 -393.706858)
		(end 382.862836 -391.344912)
		(width 0.1651)
		(layer "In5.Cu")
		(net "P5E_PEX3_STN5_RX_DN<80>")
	)
	(segment
		(start 406.620218 -319.888362)
		(end 406.620218 -316.534292)
		(width 0.1143)
		(layer "In5.Cu")
		(net "P5E_PEX3_STN5_RX_DN<80>")
	)
	(segment
		(start 406.734518 -316.419992)
		(end 406.885648 -316.419992)
		(width 0.1143)
		(layer "In5.Cu")
		(net "P5E_PEX3_STN5_RX_DN<80>")
	)
	(segment
		(start 375.489978 -397.411956)
		(end 375.616978 -397.284956)
		(width 0.1651)
		(layer "In5.Cu")
		(net "P5E_PEX3_STN5_RX_DN<80>")
	)
	(segment
		(start 376.647964 -395.86916)
		(end 378.921772 -393.706858)
		(width 0.1651)
		(layer "In5.Cu")
		(net "P5E_PEX3_STN5_RX_DN<80>")
	)
	(segment
		(start 274.572984 -155.360116)
		(end 278.242268 -155.360116)
		(width 0.13208)
		(layer "F.Cu")
		(net "NIC4_CLK")
	)
	(segment
		(start 274.438872 -155.226004)
		(end 274.572984 -155.360116)
		(width 0.13208)
		(layer "F.Cu")
		(net "NIC4_CLK")
	)
	(segment
		(start 271.63268 -155.3464)
		(end 271.753076 -155.226004)
		(width 0.13208)
		(layer "F.Cu")
		(net "NIC4_CLK")
	)
	(segment
		(start 271.753076 -155.226004)
		(end 272.598388 -155.226004)
		(width 0.13208)
		(layer "F.Cu")
		(net "NIC4_CLK")
	)
	(segment
		(start 271.207992 -155.3464)
		(end 271.63268 -155.3464)
		(width 0.13208)
		(layer "F.Cu")
		(net "NIC4_CLK")
	)
	(segment
		(start 272.598388 -155.226004)
		(end 274.438872 -155.226004)
		(width 0.13208)
		(layer "F.Cu")
		(net "NIC4_CLK")
	)
	(via
		(at 272.598388 -155.226004)
		(size 0.762)
		(drill 0.381)
		(layers "F.Cu" "B.Cu")
		(net "NIC4_CLK")
	)
	(segment
		(start 45.391324 -101.407722)
		(end 37.827204 -101.407722)
		(width 0.13462)
		(layer "F.Cu")
		(net "P5E_PEX0_STN1_TX_C_DN<17>")
	)
	(segment
		(start 37.827204 -101.407722)
		(end 37.514784 -101.095302)
		(width 0.13462)
		(layer "F.Cu")
		(net "P5E_PEX0_STN1_TX_C_DN<17>")
	)
	(segment
		(start 45.554138 -101.244908)
		(end 45.391324 -101.407722)
		(width 0.13462)
		(layer "F.Cu")
		(net "P5E_PEX0_STN1_TX_C_DN<17>")
	)
	(segment
		(start 46.042326 -101.244908)
		(end 45.554138 -101.244908)
		(width 0.13462)
		(layer "F.Cu")
		(net "P5E_PEX0_STN1_TX_C_DN<17>")
	)
	(segment
		(start 155.959556 -132.527802)
		(end 155.647136 -132.215382)
		(width 0.13462)
		(layer "F.Cu")
		(net "P5E_PEX1_STN1_TX_C_DN<29>")
	)
	(segment
		(start 161.654236 -132.364988)
		(end 161.491422 -132.527802)
		(width 0.13462)
		(layer "F.Cu")
		(net "P5E_PEX1_STN1_TX_C_DN<29>")
	)
	(segment
		(start 161.491422 -132.527802)
		(end 155.959556 -132.527802)
		(width 0.13462)
		(layer "F.Cu")
		(net "P5E_PEX1_STN1_TX_C_DN<29>")
	)
	(segment
		(start 162.14217 -132.364988)
		(end 161.654236 -132.364988)
		(width 0.13462)
		(layer "F.Cu")
		(net "P5E_PEX1_STN1_TX_C_DN<29>")
	)
	(segment
		(start 116.816378 -342.011254)
		(end 116.816378 -357.89235)
		(width 0.1651)
		(layer "In15.Cu")
		(net "P5E_PEX1_STN6_RX_DP<108>")
	)
	(segment
		(start 116.816378 -357.89235)
		(end 116.679726 -358.359202)
		(width 0.1651)
		(layer "In15.Cu")
		(net "P5E_PEX1_STN6_RX_DP<108>")
	)
	(segment
		(start 110.512352 -384.932174)
		(end 110.880906 -386.258308)
		(width 0.1651)
		(layer "In15.Cu")
		(net "P5E_PEX1_STN6_RX_DP<108>")
	)
	(segment
		(start 116.679726 -358.359202)
		(end 112.43564 -364.987586)
		(width 0.1651)
		(layer "In15.Cu")
		(net "P5E_PEX1_STN6_RX_DP<108>")
	)
	(segment
		(start 122.57659 -394.788898)
		(end 122.926856 -395.139418)
		(width 0.1651)
		(layer "In15.Cu")
		(net "P5E_PEX1_STN6_RX_DP<108>")
	)
	(segment
		(start 159.878776 -323.153786)
		(end 143.346424 -330.974446)
		(width 0.1651)
		(layer "In15.Cu")
		(net "P5E_PEX1_STN6_RX_DP<108>")
	)
	(segment
		(start 133.433312 -335.080356)
		(end 123.5202 -339.18652)
		(width 0.1651)
		(layer "In15.Cu")
		(net "P5E_PEX1_STN6_RX_DP<108>")
	)
	(segment
		(start 123.034806 -395.139418)
		(end 123.384818 -395.48943)
		(width 0.1651)
		(layer "In15.Cu")
		(net "P5E_PEX1_STN6_RX_DP<108>")
	)
	(segment
		(start 121.732294 -393.836906)
		(end 121.732294 -393.98067)
		(width 0.1651)
		(layer "In15.Cu")
		(net "P5E_PEX1_STN6_RX_DP<108>")
	)
	(segment
		(start 162.450018 -318.040766)
		(end 162.361118 -318.129666)
		(width 0.1143)
		(layer "In15.Cu")
		(net "P5E_PEX1_STN6_RX_DP<108>")
	)
	(segment
		(start 122.637042 -401.999196)
		(end 122.510042 -401.872196)
		(width 0.1651)
		(layer "In15.Cu")
		(net "P5E_PEX1_STN6_RX_DP<108>")
	)
	(segment
		(start 161.834068 -320.29146)
		(end 161.193734 -321.838828)
		(width 0.1651)
		(layer "In15.Cu")
		(net "P5E_PEX1_STN6_RX_DP<108>")
	)
	(segment
		(start 122.926856 -395.139418)
		(end 123.034806 -395.139418)
		(width 0.1651)
		(layer "In15.Cu")
		(net "P5E_PEX1_STN6_RX_DP<108>")
	)
	(segment
		(start 162.361118 -318.129666)
		(end 162.118294 -318.129666)
		(width 0.1143)
		(layer "In15.Cu")
		(net "P5E_PEX1_STN6_RX_DP<108>")
	)
	(segment
		(start 117.376194 -341.157814)
		(end 116.816378 -342.011254)
		(width 0.1651)
		(layer "In15.Cu")
		(net "P5E_PEX1_STN6_RX_DP<108>")
	)
	(segment
		(start 161.193734 -321.838828)
		(end 159.878776 -323.153786)
		(width 0.1651)
		(layer "In15.Cu")
		(net "P5E_PEX1_STN6_RX_DP<108>")
	)
	(segment
		(start 110.880906 -386.258308)
		(end 112.146334 -388.141972)
		(width 0.1651)
		(layer "In15.Cu")
		(net "P5E_PEX1_STN6_RX_DP<108>")
	)
	(segment
		(start 123.384818 -399.313908)
		(end 123.3932 -399.32229)
		(width 0.1651)
		(layer "In15.Cu")
		(net "P5E_PEX1_STN6_RX_DP<108>")
	)
	(segment
		(start 161.879788 -319.79108)
		(end 161.834068 -319.8368)
		(width 0.1143)
		(layer "In15.Cu")
		(net "P5E_PEX1_STN6_RX_DP<108>")
	)
	(segment
		(start 122.57659 -394.681202)
		(end 122.57659 -394.788898)
		(width 0.1651)
		(layer "In15.Cu")
		(net "P5E_PEX1_STN6_RX_DP<108>")
	)
	(segment
		(start 161.879788 -318.368172)
		(end 161.879788 -319.79108)
		(width 0.1143)
		(layer "In15.Cu")
		(net "P5E_PEX1_STN6_RX_DP<108>")
	)
	(segment
		(start 122.510042 -401.872196)
		(end 122.510042 -401.49018)
		(width 0.1651)
		(layer "In15.Cu")
		(net "P5E_PEX1_STN6_RX_DP<108>")
	)
	(segment
		(start 122.226578 -394.33119)
		(end 122.57659 -394.681202)
		(width 0.1651)
		(layer "In15.Cu")
		(net "P5E_PEX1_STN6_RX_DP<108>")
	)
	(segment
		(start 110.621318 -368.599974)
		(end 110.512352 -384.932174)
		(width 0.1651)
		(layer "In15.Cu")
		(net "P5E_PEX1_STN6_RX_DP<108>")
	)
	(segment
		(start 113.529618 -389.269732)
		(end 113.529364 -389.269732)
		(width 0.1651)
		(layer "In15.Cu")
		(net "P5E_PEX1_STN6_RX_DP<108>")
	)
	(segment
		(start 113.529364 -389.269732)
		(end 114.912394 -390.397492)
		(width 0.1651)
		(layer "In15.Cu")
		(net "P5E_PEX1_STN6_RX_DP<108>")
	)
	(segment
		(start 162.450018 -317.749936)
		(end 162.450018 -318.040766)
		(width 0.1143)
		(layer "In15.Cu")
		(net "P5E_PEX1_STN6_RX_DP<108>")
	)
	(segment
		(start 161.834068 -319.8368)
		(end 161.834068 -319.865248)
		(width 0.1143)
		(layer "In15.Cu")
		(net "P5E_PEX1_STN6_RX_DP<108>")
	)
	(segment
		(start 123.3932 -399.32229)
		(end 123.3932 -401.464526)
		(width 0.1651)
		(layer "In15.Cu")
		(net "P5E_PEX1_STN6_RX_DP<108>")
	)
	(segment
		(start 161.834068 -319.865248)
		(end 161.834068 -320.29146)
		(width 0.1651)
		(layer "In15.Cu")
		(net "P5E_PEX1_STN6_RX_DP<108>")
	)
	(segment
		(start 114.912394 -390.397492)
		(end 120.684036 -392.788648)
		(width 0.1651)
		(layer "In15.Cu")
		(net "P5E_PEX1_STN6_RX_DP<108>")
	)
	(segment
		(start 121.732294 -393.98067)
		(end 122.082814 -394.33119)
		(width 0.1651)
		(layer "In15.Cu")
		(net "P5E_PEX1_STN6_RX_DP<108>")
	)
	(segment
		(start 112.43564 -364.987586)
		(end 110.621318 -368.599974)
		(width 0.1651)
		(layer "In15.Cu")
		(net "P5E_PEX1_STN6_RX_DP<108>")
	)
	(segment
		(start 133.43382 -335.080356)
		(end 133.433312 -335.080356)
		(width 0.1651)
		(layer "In15.Cu")
		(net "P5E_PEX1_STN6_RX_DP<108>")
	)
	(segment
		(start 123.5202 -339.18652)
		(end 117.376194 -341.157814)
		(width 0.1651)
		(layer "In15.Cu")
		(net "P5E_PEX1_STN6_RX_DP<108>")
	)
	(segment
		(start 123.3932 -401.464526)
		(end 122.85853 -401.999196)
		(width 0.1651)
		(layer "In15.Cu")
		(net "P5E_PEX1_STN6_RX_DP<108>")
	)
	(segment
		(start 112.146334 -388.141972)
		(end 113.529618 -389.269732)
		(width 0.1651)
		(layer "In15.Cu")
		(net "P5E_PEX1_STN6_RX_DP<108>")
	)
	(segment
		(start 123.384818 -395.48943)
		(end 123.384818 -399.313908)
		(width 0.1651)
		(layer "In15.Cu")
		(net "P5E_PEX1_STN6_RX_DP<108>")
	)
	(segment
		(start 122.082814 -394.33119)
		(end 122.226578 -394.33119)
		(width 0.1651)
		(layer "In15.Cu")
		(net "P5E_PEX1_STN6_RX_DP<108>")
	)
	(segment
		(start 143.346424 -330.974446)
		(end 133.43382 -335.080356)
		(width 0.1651)
		(layer "In15.Cu")
		(net "P5E_PEX1_STN6_RX_DP<108>")
	)
	(segment
		(start 120.684036 -392.788648)
		(end 121.732294 -393.836906)
		(width 0.1651)
		(layer "In15.Cu")
		(net "P5E_PEX1_STN6_RX_DP<108>")
	)
	(segment
		(start 122.85853 -401.999196)
		(end 122.637042 -401.999196)
		(width 0.1651)
		(layer "In15.Cu")
		(net "P5E_PEX1_STN6_RX_DP<108>")
	)
	(segment
		(start 162.118294 -318.129666)
		(end 161.879788 -318.368172)
		(width 0.1143)
		(layer "In15.Cu")
		(net "P5E_PEX1_STN6_RX_DP<108>")
	)
	(segment
		(start 312.797444 -350.685354)
		(end 312.477404 -350.365314)
		(width 0.13462)
		(layer "F.Cu")
		(net "P5E_PEX2_STN5_TX_C_DP<80>")
	)
	(segment
		(start 312.797444 -351.316798)
		(end 312.797444 -350.685354)
		(width 0.13462)
		(layer "F.Cu")
		(net "P5E_PEX2_STN5_TX_C_DP<80>")
	)
	(segment
		(start 312.502804 -351.611438)
		(end 312.797444 -351.316798)
		(width 0.13462)
		(layer "F.Cu")
		(net "P5E_PEX2_STN5_TX_C_DP<80>")
	)
	(segment
		(start 327.801478 -392.652504)
		(end 328.14768 -393.00658)
		(width 0.1651)
		(layer "In7.Cu")
		(net "P5E_PEX2_STN5_TX_C_DP<80>")
	)
	(segment
		(start 332.334108 -395.13002)
		(end 332.334108 -404.512272)
		(width 0.1651)
		(layer "In7.Cu")
		(net "P5E_PEX2_STN5_TX_C_DP<80>")
	)
	(segment
		(start 323.54774 -386.50418)
		(end 324.884542 -389.670544)
		(width 0.1651)
		(layer "In7.Cu")
		(net "P5E_PEX2_STN5_TX_C_DP<80>")
	)
	(segment
		(start 327.330562 -392.171174)
		(end 327.329038 -392.296904)
		(width 0.1651)
		(layer "In7.Cu")
		(net "P5E_PEX2_STN5_TX_C_DP<80>")
	)
	(segment
		(start 332.047342 -404.799038)
		(end 331.617066 -404.799038)
		(width 0.1651)
		(layer "In7.Cu")
		(net "P5E_PEX2_STN5_TX_C_DP<80>")
	)
	(segment
		(start 329.939142 -393.82827)
		(end 330.054966 -393.779248)
		(width 0.1651)
		(layer "In7.Cu")
		(net "P5E_PEX2_STN5_TX_C_DP<80>")
	)
	(segment
		(start 329.47991 -393.642088)
		(end 329.939142 -393.82827)
		(width 0.1651)
		(layer "In7.Cu")
		(net "P5E_PEX2_STN5_TX_C_DP<80>")
	)
	(segment
		(start 330.054966 -393.779248)
		(end 330.513944 -393.964922)
		(width 0.1651)
		(layer "In7.Cu")
		(net "P5E_PEX2_STN5_TX_C_DP<80>")
	)
	(segment
		(start 332.0796 -394.59916)
		(end 332.334108 -395.13002)
		(width 0.1651)
		(layer "In7.Cu")
		(net "P5E_PEX2_STN5_TX_C_DP<80>")
	)
	(segment
		(start 324.884542 -389.670544)
		(end 327.330562 -392.171174)
		(width 0.1651)
		(layer "In7.Cu")
		(net "P5E_PEX2_STN5_TX_C_DP<80>")
	)
	(segment
		(start 327.329038 -392.296904)
		(end 327.675748 -392.651234)
		(width 0.1651)
		(layer "In7.Cu")
		(net "P5E_PEX2_STN5_TX_C_DP<80>")
	)
	(segment
		(start 312.502804 -351.611438)
		(end 312.793634 -351.902268)
		(width 0.1651)
		(layer "In7.Cu")
		(net "P5E_PEX2_STN5_TX_C_DP<80>")
	)
	(segment
		(start 327.675748 -392.651234)
		(end 327.801478 -392.652504)
		(width 0.1651)
		(layer "In7.Cu")
		(net "P5E_PEX2_STN5_TX_C_DP<80>")
	)
	(segment
		(start 330.562966 -394.080746)
		(end 331.022198 -394.266928)
		(width 0.1651)
		(layer "In7.Cu")
		(net "P5E_PEX2_STN5_TX_C_DP<80>")
	)
	(segment
		(start 331.022198 -394.266928)
		(end 331.138022 -394.217906)
		(width 0.1651)
		(layer "In7.Cu")
		(net "P5E_PEX2_STN5_TX_C_DP<80>")
	)
	(segment
		(start 312.793634 -358.871266)
		(end 323.54774 -386.50418)
		(width 0.1651)
		(layer "In7.Cu")
		(net "P5E_PEX2_STN5_TX_C_DP<80>")
	)
	(segment
		(start 312.793634 -351.902268)
		(end 312.793634 -358.871266)
		(width 0.1651)
		(layer "In7.Cu")
		(net "P5E_PEX2_STN5_TX_C_DP<80>")
	)
	(segment
		(start 332.334108 -404.512272)
		(end 332.047342 -404.799038)
		(width 0.1651)
		(layer "In7.Cu")
		(net "P5E_PEX2_STN5_TX_C_DP<80>")
	)
	(segment
		(start 331.617066 -404.799038)
		(end 331.490066 -404.672038)
		(width 0.1651)
		(layer "In7.Cu")
		(net "P5E_PEX2_STN5_TX_C_DP<80>")
	)
	(segment
		(start 330.513944 -393.964922)
		(end 330.562966 -394.080746)
		(width 0.1651)
		(layer "In7.Cu")
		(net "P5E_PEX2_STN5_TX_C_DP<80>")
	)
	(segment
		(start 331.138022 -394.217906)
		(end 332.0796 -394.59916)
		(width 0.1651)
		(layer "In7.Cu")
		(net "P5E_PEX2_STN5_TX_C_DP<80>")
	)
	(segment
		(start 329.430888 -393.526264)
		(end 329.47991 -393.642088)
		(width 0.1651)
		(layer "In7.Cu")
		(net "P5E_PEX2_STN5_TX_C_DP<80>")
	)
	(segment
		(start 331.490066 -404.672038)
		(end 331.490066 -404.290022)
		(width 0.1651)
		(layer "In7.Cu")
		(net "P5E_PEX2_STN5_TX_C_DP<80>")
	)
	(segment
		(start 328.14768 -393.00658)
		(end 329.430888 -393.526264)
		(width 0.1651)
		(layer "In7.Cu")
		(net "P5E_PEX2_STN5_TX_C_DP<80>")
	)
	(segment
		(start 416.47999 -144.554956)
		(end 416.95751 -144.554956)
		(width 0.13462)
		(layer "F.Cu")
		(net "P5E_PEX3_STN0_RX_DN<9>")
	)
	(segment
		(start 413.50311 -144.423638)
		(end 413.801052 -144.72158)
		(width 0.13462)
		(layer "F.Cu")
		(net "P5E_PEX3_STN0_RX_DN<9>")
	)
	(segment
		(start 413.801052 -144.72158)
		(end 416.313366 -144.72158)
		(width 0.13462)
		(layer "F.Cu")
		(net "P5E_PEX3_STN0_RX_DN<9>")
	)
	(segment
		(start 416.313366 -144.72158)
		(end 416.47999 -144.554956)
		(width 0.13462)
		(layer "F.Cu")
		(net "P5E_PEX3_STN0_RX_DN<9>")
	)
	(segment
		(start 421.381682 -152.48255)
		(end 424.138598 -155.292806)
		(width 0.1651)
		(layer "In5.Cu")
		(net "P5E_PEX3_STN0_RX_DN<9>")
	)
	(segment
		(start 428.47006 -271.600168)
		(end 428.47006 -273.376136)
		(width 0.1143)
		(layer "In5.Cu")
		(net "P5E_PEX3_STN0_RX_DN<9>")
	)
	(segment
		(start 428.51578 -271.225518)
		(end 428.51578 -271.526)
		(width 0.1651)
		(layer "In5.Cu")
		(net "P5E_PEX3_STN0_RX_DN<9>")
	)
	(segment
		(start 429.09998 -261.973314)
		(end 429.09998 -268.288008)
		(width 0.1651)
		(layer "In5.Cu")
		(net "P5E_PEX3_STN0_RX_DN<9>")
	)
	(segment
		(start 428.735236 -273.479514)
		(end 428.849536 -273.365214)
		(width 0.1143)
		(layer "In5.Cu")
		(net "P5E_PEX3_STN0_RX_DN<9>")
	)
	(segment
		(start 425.51731 -160.462976)
		(end 429.09998 -261.973314)
		(width 0.1651)
		(layer "In5.Cu")
		(net "P5E_PEX3_STN0_RX_DN<9>")
	)
	(segment
		(start 424.138598 -155.292806)
		(end 425.424854 -160.116012)
		(width 0.1651)
		(layer "In5.Cu")
		(net "P5E_PEX3_STN0_RX_DN<9>")
	)
	(segment
		(start 428.47006 -273.376136)
		(end 428.573438 -273.479514)
		(width 0.1143)
		(layer "In5.Cu")
		(net "P5E_PEX3_STN0_RX_DN<9>")
	)
	(segment
		(start 428.849536 -273.365214)
		(end 428.849536 -273.099784)
		(width 0.1143)
		(layer "In5.Cu")
		(net "P5E_PEX3_STN0_RX_DN<9>")
	)
	(segment
		(start 425.424854 -160.116012)
		(end 425.424854 -160.115758)
		(width 0.1651)
		(layer "In5.Cu")
		(net "P5E_PEX3_STN0_RX_DN<9>")
	)
	(segment
		(start 428.51578 -271.526)
		(end 428.51578 -271.554448)
		(width 0.1143)
		(layer "In5.Cu")
		(net "P5E_PEX3_STN0_RX_DN<9>")
	)
	(segment
		(start 428.573438 -273.479514)
		(end 428.735236 -273.479514)
		(width 0.1143)
		(layer "In5.Cu")
		(net "P5E_PEX3_STN0_RX_DN<9>")
	)
	(segment
		(start 425.424854 -160.115758)
		(end 425.51731 -160.462976)
		(width 0.1651)
		(layer "In5.Cu")
		(net "P5E_PEX3_STN0_RX_DN<9>")
	)
	(segment
		(start 420.635938 -150.41118)
		(end 421.381682 -152.48255)
		(width 0.1651)
		(layer "In5.Cu")
		(net "P5E_PEX3_STN0_RX_DN<9>")
	)
	(segment
		(start 413.50311 -144.423638)
		(end 413.79394 -144.714468)
		(width 0.1651)
		(layer "In5.Cu")
		(net "P5E_PEX3_STN0_RX_DN<9>")
	)
	(segment
		(start 415.524188 -144.714468)
		(end 416.378644 -145.071846)
		(width 0.1651)
		(layer "In5.Cu")
		(net "P5E_PEX3_STN0_RX_DN<9>")
	)
	(segment
		(start 428.51578 -271.554448)
		(end 428.47006 -271.600168)
		(width 0.1143)
		(layer "In5.Cu")
		(net "P5E_PEX3_STN0_RX_DN<9>")
	)
	(segment
		(start 416.378644 -145.071846)
		(end 418.6936 -147.418806)
		(width 0.1651)
		(layer "In5.Cu")
		(net "P5E_PEX3_STN0_RX_DN<9>")
	)
	(segment
		(start 429.09998 -268.288008)
		(end 428.51578 -271.225518)
		(width 0.1651)
		(layer "In5.Cu")
		(net "P5E_PEX3_STN0_RX_DN<9>")
	)
	(segment
		(start 418.6936 -147.418806)
		(end 420.635938 -150.41118)
		(width 0.1651)
		(layer "In5.Cu")
		(net "P5E_PEX3_STN0_RX_DN<9>")
	)
	(segment
		(start 413.79394 -144.714468)
		(end 415.524188 -144.714468)
		(width 0.1651)
		(layer "In5.Cu")
		(net "P5E_PEX3_STN0_RX_DN<9>")
	)
	(segment
		(start 396.629128 -357.463598)
		(end 396.92326 -357.75773)
		(width 0.13462)
		(layer "F.Cu")
		(net "P5E_PEX3_STN5_TX_C_DN<92>")
	)
	(segment
		(start 396.629128 -356.831138)
		(end 396.629128 -357.463598)
		(width 0.13462)
		(layer "F.Cu")
		(net "P5E_PEX3_STN5_TX_C_DN<92>")
	)
	(segment
		(start 396.94866 -356.511606)
		(end 396.629128 -356.831138)
		(width 0.13462)
		(layer "F.Cu")
		(net "P5E_PEX3_STN5_TX_C_DN<92>")
	)
	(segment
		(start 396.63243 -358.04856)
		(end 396.92326 -357.75773)
		(width 0.1651)
		(layer "In13.Cu")
		(net "P5E_PEX3_STN5_TX_C_DN<92>")
	)
	(segment
		(start 396.63243 -358.456738)
		(end 396.63243 -358.04856)
		(width 0.1651)
		(layer "In13.Cu")
		(net "P5E_PEX3_STN5_TX_C_DN<92>")
	)
	(segment
		(start 384.290062 -379.20803)
		(end 384.417062 -379.08103)
		(width 0.1651)
		(layer "In13.Cu")
		(net "P5E_PEX3_STN5_TX_C_DN<92>")
	)
	(segment
		(start 384.290062 -379.590046)
		(end 384.290062 -379.20803)
		(width 0.1651)
		(layer "In13.Cu")
		(net "P5E_PEX3_STN5_TX_C_DN<92>")
	)
	(segment
		(start 384.417062 -379.08103)
		(end 384.964178 -379.08103)
		(width 0.1651)
		(layer "In13.Cu")
		(net "P5E_PEX3_STN5_TX_C_DN<92>")
	)
	(segment
		(start 385.416044 -369.841272)
		(end 386.117846 -368.298984)
		(width 0.1651)
		(layer "In13.Cu")
		(net "P5E_PEX3_STN5_TX_C_DN<92>")
	)
	(segment
		(start 384.964178 -379.08103)
		(end 385.416044 -378.629164)
		(width 0.1651)
		(layer "In13.Cu")
		(net "P5E_PEX3_STN5_TX_C_DN<92>")
	)
	(segment
		(start 385.416044 -378.629164)
		(end 385.416044 -369.841272)
		(width 0.1651)
		(layer "In13.Cu")
		(net "P5E_PEX3_STN5_TX_C_DN<92>")
	)
	(segment
		(start 386.117846 -368.298984)
		(end 396.11808 -359.586784)
		(width 0.1651)
		(layer "In13.Cu")
		(net "P5E_PEX3_STN5_TX_C_DN<92>")
	)
	(segment
		(start 396.11808 -359.586784)
		(end 396.63243 -358.456738)
		(width 0.1651)
		(layer "In13.Cu")
		(net "P5E_PEX3_STN5_TX_C_DN<92>")
	)
	(segment
		(start 37.232844 -112.482122)
		(end 45.391578 -112.482122)
		(width 0.13462)
		(layer "F.Cu")
		(net "P5E_PEX0_STN1_TX_C_DP<23>")
	)
	(segment
		(start 45.554392 -112.644936)
		(end 46.042326 -112.644936)
		(width 0.13462)
		(layer "F.Cu")
		(net "P5E_PEX0_STN1_TX_C_DP<23>")
	)
	(segment
		(start 36.905184 -112.809782)
		(end 37.232844 -112.482122)
		(width 0.13462)
		(layer "F.Cu")
		(net "P5E_PEX0_STN1_TX_C_DP<23>")
	)
	(segment
		(start 45.391578 -112.482122)
		(end 45.554392 -112.644936)
		(width 0.13462)
		(layer "F.Cu")
		(net "P5E_PEX0_STN1_TX_C_DP<23>")
	)
	(segment
		(start 169.901616 -106.807762)
		(end 170.196764 -106.512614)
		(width 0.13462)
		(layer "F.Cu")
		(net "P5E_PEX1_STN1_RX_DP<20>")
	)
	(segment
		(start 167.230298 -106.644948)
		(end 167.393112 -106.807762)
		(width 0.13462)
		(layer "F.Cu")
		(net "P5E_PEX1_STN1_RX_DP<20>")
	)
	(segment
		(start 166.742364 -106.644948)
		(end 167.230298 -106.644948)
		(width 0.13462)
		(layer "F.Cu")
		(net "P5E_PEX1_STN1_RX_DP<20>")
	)
	(segment
		(start 167.393112 -106.807762)
		(end 169.901616 -106.807762)
		(width 0.13462)
		(layer "F.Cu")
		(net "P5E_PEX1_STN1_RX_DP<20>")
	)
	(segment
		(start 149.74316 -164.725858)
		(end 178.93411 -269.350998)
		(width 0.1651)
		(layer "In5.Cu")
		(net "P5E_PEX1_STN1_RX_DP<20>")
	)
	(segment
		(start 178.97983 -273.45513)
		(end 179.194714 -273.670014)
		(width 0.1143)
		(layer "In5.Cu")
		(net "P5E_PEX1_STN1_RX_DP<20>")
	)
	(segment
		(start 167.68953 -106.803444)
		(end 160.412938 -110.677452)
		(width 0.1651)
		(layer "In5.Cu")
		(net "P5E_PEX1_STN1_RX_DP<20>")
	)
	(segment
		(start 178.93411 -269.350998)
		(end 178.93411 -271.526)
		(width 0.1651)
		(layer "In5.Cu")
		(net "P5E_PEX1_STN1_RX_DP<20>")
	)
	(segment
		(start 149.83714 -129.472436)
		(end 148.196808 -150.509986)
		(width 0.1651)
		(layer "In5.Cu")
		(net "P5E_PEX1_STN1_RX_DP<20>")
	)
	(segment
		(start 179.549806 -273.784314)
		(end 179.549806 -274.049744)
		(width 0.1143)
		(layer "In5.Cu")
		(net "P5E_PEX1_STN1_RX_DP<20>")
	)
	(segment
		(start 148.196808 -150.509986)
		(end 148.717762 -158.750254)
		(width 0.1651)
		(layer "In5.Cu")
		(net "P5E_PEX1_STN1_RX_DP<20>")
	)
	(segment
		(start 170.196764 -106.512614)
		(end 169.905934 -106.803444)
		(width 0.1651)
		(layer "In5.Cu")
		(net "P5E_PEX1_STN1_RX_DP<20>")
	)
	(segment
		(start 160.412938 -110.677452)
		(end 157.783022 -113.218722)
		(width 0.1651)
		(layer "In5.Cu")
		(net "P5E_PEX1_STN1_RX_DP<20>")
	)
	(segment
		(start 178.97983 -271.600168)
		(end 178.97983 -273.45513)
		(width 0.1143)
		(layer "In5.Cu")
		(net "P5E_PEX1_STN1_RX_DP<20>")
	)
	(segment
		(start 157.783022 -113.218722)
		(end 156.94533 -114.696748)
		(width 0.1651)
		(layer "In5.Cu")
		(net "P5E_PEX1_STN1_RX_DP<20>")
	)
	(segment
		(start 178.93411 -271.526)
		(end 178.93411 -271.554448)
		(width 0.1143)
		(layer "In5.Cu")
		(net "P5E_PEX1_STN1_RX_DP<20>")
	)
	(segment
		(start 148.717762 -158.750254)
		(end 149.74316 -164.725858)
		(width 0.1651)
		(layer "In5.Cu")
		(net "P5E_PEX1_STN1_RX_DP<20>")
	)
	(segment
		(start 155.197556 -122.198384)
		(end 154.533346 -122.95759)
		(width 0.1651)
		(layer "In5.Cu")
		(net "P5E_PEX1_STN1_RX_DP<20>")
	)
	(segment
		(start 156.94533 -114.696748)
		(end 155.197556 -122.198384)
		(width 0.1651)
		(layer "In5.Cu")
		(net "P5E_PEX1_STN1_RX_DP<20>")
	)
	(segment
		(start 178.93411 -271.554448)
		(end 178.97983 -271.600168)
		(width 0.1143)
		(layer "In5.Cu")
		(net "P5E_PEX1_STN1_RX_DP<20>")
	)
	(segment
		(start 152.76576 -123.639326)
		(end 149.83714 -129.472436)
		(width 0.1651)
		(layer "In5.Cu")
		(net "P5E_PEX1_STN1_RX_DP<20>")
	)
	(segment
		(start 169.905934 -106.803444)
		(end 167.68953 -106.803444)
		(width 0.1651)
		(layer "In5.Cu")
		(net "P5E_PEX1_STN1_RX_DP<20>")
	)
	(segment
		(start 179.194714 -273.670014)
		(end 179.435506 -273.670014)
		(width 0.1143)
		(layer "In5.Cu")
		(net "P5E_PEX1_STN1_RX_DP<20>")
	)
	(segment
		(start 154.533346 -122.95759)
		(end 152.76576 -123.639326)
		(width 0.1651)
		(layer "In5.Cu")
		(net "P5E_PEX1_STN1_RX_DP<20>")
	)
	(segment
		(start 179.435506 -273.670014)
		(end 179.549806 -273.784314)
		(width 0.1143)
		(layer "In5.Cu")
		(net "P5E_PEX1_STN1_RX_DP<20>")
	)
	(segment
		(start 328.022204 -344.219022)
		(end 328.342244 -344.539062)
		(width 0.13462)
		(layer "F.Cu")
		(net "P5E_PEX2_STN5_TX_C_DP<87>")
	)
	(segment
		(start 328.342244 -345.170506)
		(end 328.047604 -345.465146)
		(width 0.13462)
		(layer "F.Cu")
		(net "P5E_PEX2_STN5_TX_C_DP<87>")
	)
	(segment
		(start 328.342244 -344.539062)
		(end 328.342244 -345.170506)
		(width 0.13462)
		(layer "F.Cu")
		(net "P5E_PEX2_STN5_TX_C_DP<87>")
	)
	(segment
		(start 328.338434 -345.755976)
		(end 328.047604 -345.465146)
		(width 0.1651)
		(layer "In7.Cu")
		(net "P5E_PEX2_STN5_TX_C_DP<87>")
	)
	(segment
		(start 330.585572 -385.426204)
		(end 330.133198 -384.268726)
		(width 0.1651)
		(layer "In7.Cu")
		(net "P5E_PEX2_STN5_TX_C_DP<87>")
	)
	(segment
		(start 344.79738 -392.678158)
		(end 344.67673 -392.713972)
		(width 0.1651)
		(layer "In7.Cu")
		(net "P5E_PEX2_STN5_TX_C_DP<87>")
	)
	(segment
		(start 344.24112 -392.478006)
		(end 344.205052 -392.357356)
		(width 0.1651)
		(layer "In7.Cu")
		(net "P5E_PEX2_STN5_TX_C_DP<87>")
	)
	(segment
		(start 344.205052 -392.357356)
		(end 337.21675 -388.573264)
		(width 0.1651)
		(layer "In7.Cu")
		(net "P5E_PEX2_STN5_TX_C_DP<87>")
	)
	(segment
		(start 345.825064 -393.234672)
		(end 345.704414 -393.270486)
		(width 0.1651)
		(layer "In7.Cu")
		(net "P5E_PEX2_STN5_TX_C_DP<87>")
	)
	(segment
		(start 337.21675 -388.573264)
		(end 331.319886 -386.174488)
		(width 0.1651)
		(layer "In7.Cu")
		(net "P5E_PEX2_STN5_TX_C_DP<87>")
	)
	(segment
		(start 326.783954 -359.151936)
		(end 326.783954 -347.764354)
		(width 0.1651)
		(layer "In7.Cu")
		(net "P5E_PEX2_STN5_TX_C_DP<87>")
	)
	(segment
		(start 347.734128 -405.612346)
		(end 347.734128 -394.75664)
		(width 0.1651)
		(layer "In7.Cu")
		(net "P5E_PEX2_STN5_TX_C_DP<87>")
	)
	(segment
		(start 346.890086 -405.772112)
		(end 347.017086 -405.899112)
		(width 0.1651)
		(layer "In7.Cu")
		(net "P5E_PEX2_STN5_TX_C_DP<87>")
	)
	(segment
		(start 326.783954 -347.764354)
		(end 328.338434 -346.209874)
		(width 0.1651)
		(layer "In7.Cu")
		(net "P5E_PEX2_STN5_TX_C_DP<87>")
	)
	(segment
		(start 345.268804 -393.03452)
		(end 345.232736 -392.91387)
		(width 0.1651)
		(layer "In7.Cu")
		(net "P5E_PEX2_STN5_TX_C_DP<87>")
	)
	(segment
		(start 347.447362 -405.899112)
		(end 347.734128 -405.612346)
		(width 0.1651)
		(layer "In7.Cu")
		(net "P5E_PEX2_STN5_TX_C_DP<87>")
	)
	(segment
		(start 346.675456 -393.74572)
		(end 346.26042 -393.470384)
		(width 0.1651)
		(layer "In7.Cu")
		(net "P5E_PEX2_STN5_TX_C_DP<87>")
	)
	(segment
		(start 347.734128 -394.75664)
		(end 346.675456 -393.74572)
		(width 0.1651)
		(layer "In7.Cu")
		(net "P5E_PEX2_STN5_TX_C_DP<87>")
	)
	(segment
		(start 328.338434 -346.209874)
		(end 328.338434 -345.755976)
		(width 0.1651)
		(layer "In7.Cu")
		(net "P5E_PEX2_STN5_TX_C_DP<87>")
	)
	(segment
		(start 345.704414 -393.270486)
		(end 345.268804 -393.03452)
		(width 0.1651)
		(layer "In7.Cu")
		(net "P5E_PEX2_STN5_TX_C_DP<87>")
	)
	(segment
		(start 344.67673 -392.713972)
		(end 344.24112 -392.478006)
		(width 0.1651)
		(layer "In7.Cu")
		(net "P5E_PEX2_STN5_TX_C_DP<87>")
	)
	(segment
		(start 345.232736 -392.91387)
		(end 344.79738 -392.678158)
		(width 0.1651)
		(layer "In7.Cu")
		(net "P5E_PEX2_STN5_TX_C_DP<87>")
	)
	(segment
		(start 346.26042 -393.470384)
		(end 345.825064 -393.234672)
		(width 0.1651)
		(layer "In7.Cu")
		(net "P5E_PEX2_STN5_TX_C_DP<87>")
	)
	(segment
		(start 330.133198 -384.268726)
		(end 326.783954 -359.151936)
		(width 0.1651)
		(layer "In7.Cu")
		(net "P5E_PEX2_STN5_TX_C_DP<87>")
	)
	(segment
		(start 331.319886 -386.174488)
		(end 330.585572 -385.426204)
		(width 0.1651)
		(layer "In7.Cu")
		(net "P5E_PEX2_STN5_TX_C_DP<87>")
	)
	(segment
		(start 346.890086 -405.390096)
		(end 346.890086 -405.772112)
		(width 0.1651)
		(layer "In7.Cu")
		(net "P5E_PEX2_STN5_TX_C_DP<87>")
	)
	(segment
		(start 347.017086 -405.899112)
		(end 347.447362 -405.899112)
		(width 0.1651)
		(layer "In7.Cu")
		(net "P5E_PEX2_STN5_TX_C_DP<87>")
	)
	(segment
		(start 430.694846 -145.311114)
		(end 430.366932 -144.9832)
		(width 0.13462)
		(layer "F.Cu")
		(net "P5E_PEX3_STN0_TX_C_DP<9>")
	)
	(segment
		(start 430.366932 -144.9832)
		(end 422.232074 -144.9832)
		(width 0.13462)
		(layer "F.Cu")
		(net "P5E_PEX3_STN0_TX_C_DP<9>")
	)
	(segment
		(start 422.232074 -144.9832)
		(end 422.06037 -145.154904)
		(width 0.13462)
		(layer "F.Cu")
		(net "P5E_PEX3_STN0_TX_C_DP<9>")
	)
	(segment
		(start 422.06037 -145.154904)
		(end 421.557704 -145.154904)
		(width 0.13462)
		(layer "F.Cu")
		(net "P5E_PEX3_STN0_TX_C_DP<9>")
	)
	(segment
		(start 420.915846 -323.587872)
		(end 420.915846 -320.119248)
		(width 0.1651)
		(layer "In15.Cu")
		(net "P5E_PEX3_STN5_RX_DN<95>")
	)
	(segment
		(start 418.893752 -327.204324)
		(end 420.915846 -323.587872)
		(width 0.1651)
		(layer "In15.Cu")
		(net "P5E_PEX3_STN5_RX_DN<95>")
	)
	(segment
		(start 391.016998 -372.381018)
		(end 391.564114 -372.381018)
		(width 0.1651)
		(layer "In15.Cu")
		(net "P5E_PEX3_STN5_RX_DN<95>")
	)
	(segment
		(start 392.331194 -368.65941)
		(end 404.889716 -359.508044)
		(width 0.1651)
		(layer "In15.Cu")
		(net "P5E_PEX3_STN5_RX_DN<95>")
	)
	(segment
		(start 408.725116 -341.239094)
		(end 418.893752 -327.204324)
		(width 0.1651)
		(layer "In15.Cu")
		(net "P5E_PEX3_STN5_RX_DN<95>")
	)
	(segment
		(start 408.2415 -342.15832)
		(end 408.725116 -341.239094)
		(width 0.1651)
		(layer "In15.Cu")
		(net "P5E_PEX3_STN5_RX_DN<95>")
	)
	(segment
		(start 420.870126 -318.423798)
		(end 420.973758 -318.320166)
		(width 0.1143)
		(layer "In15.Cu")
		(net "P5E_PEX3_STN5_RX_DN<95>")
	)
	(segment
		(start 421.135556 -318.320166)
		(end 421.249856 -318.434466)
		(width 0.1143)
		(layer "In15.Cu")
		(net "P5E_PEX3_STN5_RX_DN<95>")
	)
	(segment
		(start 392.01598 -369.403884)
		(end 392.331194 -368.65941)
		(width 0.1651)
		(layer "In15.Cu")
		(net "P5E_PEX3_STN5_RX_DN<95>")
	)
	(segment
		(start 390.889998 -372.890034)
		(end 390.889998 -372.508018)
		(width 0.1651)
		(layer "In15.Cu")
		(net "P5E_PEX3_STN5_RX_DN<95>")
	)
	(segment
		(start 392.01598 -371.929152)
		(end 392.01598 -369.403884)
		(width 0.1651)
		(layer "In15.Cu")
		(net "P5E_PEX3_STN5_RX_DN<95>")
	)
	(segment
		(start 420.915846 -320.119248)
		(end 420.915846 -320.0908)
		(width 0.1143)
		(layer "In15.Cu")
		(net "P5E_PEX3_STN5_RX_DN<95>")
	)
	(segment
		(start 404.889716 -359.508044)
		(end 405.753062 -357.589074)
		(width 0.1651)
		(layer "In15.Cu")
		(net "P5E_PEX3_STN5_RX_DN<95>")
	)
	(segment
		(start 420.915846 -320.0908)
		(end 420.870126 -320.04508)
		(width 0.1143)
		(layer "In15.Cu")
		(net "P5E_PEX3_STN5_RX_DN<95>")
	)
	(segment
		(start 421.249856 -318.434466)
		(end 421.249856 -318.699896)
		(width 0.1143)
		(layer "In15.Cu")
		(net "P5E_PEX3_STN5_RX_DN<95>")
	)
	(segment
		(start 390.889998 -372.508018)
		(end 391.016998 -372.381018)
		(width 0.1651)
		(layer "In15.Cu")
		(net "P5E_PEX3_STN5_RX_DN<95>")
	)
	(segment
		(start 405.753062 -357.589074)
		(end 408.2415 -342.15832)
		(width 0.1651)
		(layer "In15.Cu")
		(net "P5E_PEX3_STN5_RX_DN<95>")
	)
	(segment
		(start 420.973758 -318.320166)
		(end 421.135556 -318.320166)
		(width 0.1143)
		(layer "In15.Cu")
		(net "P5E_PEX3_STN5_RX_DN<95>")
	)
	(segment
		(start 391.564114 -372.381018)
		(end 392.01598 -371.929152)
		(width 0.1651)
		(layer "In15.Cu")
		(net "P5E_PEX3_STN5_RX_DN<95>")
	)
	(segment
		(start 420.870126 -320.04508)
		(end 420.870126 -318.423798)
		(width 0.1143)
		(layer "In15.Cu")
		(net "P5E_PEX3_STN5_RX_DN<95>")
	)
	(segment
		(start 288.012632 -140.300202)
		(end 289.18789 -140.300202)
		(width 0.13208)
		(layer "F.Cu")
		(net "RST_SMB_NIC4_MUX_ISO_R_N")
	)
	(segment
		(start 286.475678 -140.867892)
		(end 287.444942 -140.867892)
		(width 0.13208)
		(layer "F.Cu")
		(net "RST_SMB_NIC4_MUX_ISO_R_N")
	)
	(segment
		(start 284.906212 -140.867892)
		(end 286.475678 -140.867892)
		(width 0.13208)
		(layer "F.Cu")
		(net "RST_SMB_NIC4_MUX_ISO_R_N")
	)
	(segment
		(start 289.18789 -140.300202)
		(end 289.864292 -139.6238)
		(width 0.13208)
		(layer "F.Cu")
		(net "RST_SMB_NIC4_MUX_ISO_R_N")
	)
	(segment
		(start 282.842462 -141.36497)
		(end 284.409134 -141.36497)
		(width 0.13208)
		(layer "F.Cu")
		(net "RST_SMB_NIC4_MUX_ISO_R_N")
	)
	(segment
		(start 284.409134 -141.36497)
		(end 284.906212 -140.867892)
		(width 0.13208)
		(layer "F.Cu")
		(net "RST_SMB_NIC4_MUX_ISO_R_N")
	)
	(segment
		(start 287.444942 -140.867892)
		(end 288.012632 -140.300202)
		(width 0.13208)
		(layer "F.Cu")
		(net "RST_SMB_NIC4_MUX_ISO_R_N")
	)
	(via
		(at 286.475678 -140.867892)
		(size 0.762)
		(drill 0.381)
		(layers "F.Cu" "B.Cu")
		(net "RST_SMB_NIC4_MUX_ISO_R_N")
	)
	(segment
		(start 45.391324 -136.402064)
		(end 45.554392 -136.565132)
		(width 0.13462)
		(layer "F.Cu")
		(net "P5E_PEX0_STN1_TX_C_DP<31>")
	)
	(segment
		(start 45.554392 -136.565132)
		(end 46.042326 -136.565132)
		(width 0.13462)
		(layer "F.Cu")
		(net "P5E_PEX0_STN1_TX_C_DP<31>")
	)
	(segment
		(start 39.547292 -136.729724)
		(end 39.874952 -136.402064)
		(width 0.13462)
		(layer "F.Cu")
		(net "P5E_PEX0_STN1_TX_C_DP<31>")
	)
	(segment
		(start 39.874952 -136.402064)
		(end 45.391324 -136.402064)
		(width 0.13462)
		(layer "F.Cu")
		(net "P5E_PEX0_STN1_TX_C_DP<31>")
	)
	(segment
		(start 161.491422 -99.882198)
		(end 161.654236 -100.045012)
		(width 0.13462)
		(layer "F.Cu")
		(net "P5E_PEX1_STN1_TX_C_DN<16>")
	)
	(segment
		(start 161.654236 -100.045012)
		(end 162.14217 -100.045012)
		(width 0.13462)
		(layer "F.Cu")
		(net "P5E_PEX1_STN1_TX_C_DN<16>")
	)
	(segment
		(start 155.968192 -99.882198)
		(end 161.491422 -99.882198)
		(width 0.13462)
		(layer "F.Cu")
		(net "P5E_PEX1_STN1_TX_C_DN<16>")
	)
	(segment
		(start 155.647136 -100.203254)
		(end 155.968192 -99.882198)
		(width 0.13462)
		(layer "F.Cu")
		(net "P5E_PEX1_STN1_TX_C_DN<16>")
	)
	(segment
		(start 129.786634 -375.181114)
		(end 129.236978 -375.181114)
		(width 0.1651)
		(layer "In5.Cu")
		(net "P5E_PEX1_STN6_RX_DN<97>")
	)
	(segment
		(start 141.969998 -357.96982)
		(end 141.49578 -359.029254)
		(width 0.1651)
		(layer "In5.Cu")
		(net "P5E_PEX1_STN6_RX_DN<97>")
	)
	(segment
		(start 143.991076 -353.16414)
		(end 142.897098 -353.16414)
		(width 0.1651)
		(layer "In5.Cu")
		(net "P5E_PEX1_STN6_RX_DN<97>")
	)
	(segment
		(start 141.969998 -354.09124)
		(end 141.969998 -357.96982)
		(width 0.1651)
		(layer "In5.Cu")
		(net "P5E_PEX1_STN6_RX_DN<97>")
	)
	(segment
		(start 172.634656 -316.419992)
		(end 172.520356 -316.534292)
		(width 0.1143)
		(layer "In5.Cu")
		(net "P5E_PEX1_STN6_RX_DN<97>")
	)
	(segment
		(start 172.566076 -319.966848)
		(end 172.566076 -321.71513)
		(width 0.1651)
		(layer "In5.Cu")
		(net "P5E_PEX1_STN6_RX_DN<97>")
	)
	(segment
		(start 158.041086 -331.779118)
		(end 154.008074 -336.287618)
		(width 0.1651)
		(layer "In5.Cu")
		(net "P5E_PEX1_STN6_RX_DN<97>")
	)
	(segment
		(start 130.169412 -374.798336)
		(end 129.786634 -375.181114)
		(width 0.1651)
		(layer "In5.Cu")
		(net "P5E_PEX1_STN6_RX_DN<97>")
	)
	(segment
		(start 172.785786 -316.419992)
		(end 172.634656 -316.419992)
		(width 0.1143)
		(layer "In5.Cu")
		(net "P5E_PEX1_STN6_RX_DN<97>")
	)
	(segment
		(start 154.008074 -336.287618)
		(end 144.567402 -352.829622)
		(width 0.1651)
		(layer "In5.Cu")
		(net "P5E_PEX1_STN6_RX_DN<97>")
	)
	(segment
		(start 130.451098 -368.897916)
		(end 130.169412 -369.38077)
		(width 0.1651)
		(layer "In5.Cu")
		(net "P5E_PEX1_STN6_RX_DN<97>")
	)
	(segment
		(start 172.900086 -316.799722)
		(end 172.900086 -316.534292)
		(width 0.1143)
		(layer "In5.Cu")
		(net "P5E_PEX1_STN6_RX_DN<97>")
	)
	(segment
		(start 172.520356 -319.89268)
		(end 172.566076 -319.9384)
		(width 0.1143)
		(layer "In5.Cu")
		(net "P5E_PEX1_STN6_RX_DN<97>")
	)
	(segment
		(start 172.900086 -316.534292)
		(end 172.785786 -316.419992)
		(width 0.1143)
		(layer "In5.Cu")
		(net "P5E_PEX1_STN6_RX_DN<97>")
	)
	(segment
		(start 170.932094 -324.160388)
		(end 158.041086 -331.779118)
		(width 0.1651)
		(layer "In5.Cu")
		(net "P5E_PEX1_STN6_RX_DN<97>")
	)
	(segment
		(start 172.566076 -319.9384)
		(end 172.566076 -319.966848)
		(width 0.1143)
		(layer "In5.Cu")
		(net "P5E_PEX1_STN6_RX_DN<97>")
	)
	(segment
		(start 130.169412 -369.38077)
		(end 130.169412 -374.798336)
		(width 0.1651)
		(layer "In5.Cu")
		(net "P5E_PEX1_STN6_RX_DN<97>")
	)
	(segment
		(start 129.109978 -375.308114)
		(end 129.109978 -375.69013)
		(width 0.1651)
		(layer "In5.Cu")
		(net "P5E_PEX1_STN6_RX_DN<97>")
	)
	(segment
		(start 142.897098 -353.16414)
		(end 141.969998 -354.09124)
		(width 0.1651)
		(layer "In5.Cu")
		(net "P5E_PEX1_STN6_RX_DN<97>")
	)
	(segment
		(start 172.520356 -316.534292)
		(end 172.520356 -319.89268)
		(width 0.1143)
		(layer "In5.Cu")
		(net "P5E_PEX1_STN6_RX_DN<97>")
	)
	(segment
		(start 172.566076 -321.71513)
		(end 170.932094 -324.160388)
		(width 0.1651)
		(layer "In5.Cu")
		(net "P5E_PEX1_STN6_RX_DN<97>")
	)
	(segment
		(start 129.236978 -375.181114)
		(end 129.109978 -375.308114)
		(width 0.1651)
		(layer "In5.Cu")
		(net "P5E_PEX1_STN6_RX_DN<97>")
	)
	(segment
		(start 144.567402 -352.829622)
		(end 143.991076 -353.16414)
		(width 0.1651)
		(layer "In5.Cu")
		(net "P5E_PEX1_STN6_RX_DN<97>")
	)
	(segment
		(start 141.49578 -359.029254)
		(end 130.451098 -368.897916)
		(width 0.1651)
		(layer "In5.Cu")
		(net "P5E_PEX1_STN6_RX_DN<97>")
	)
	(segment
		(start 416.315906 -144.9959)
		(end 416.47491 -145.154904)
		(width 0.13462)
		(layer "F.Cu")
		(net "P5E_PEX3_STN0_RX_DP<9>")
	)
	(segment
		(start 413.794448 -144.9959)
		(end 416.315906 -144.9959)
		(width 0.13462)
		(layer "F.Cu")
		(net "P5E_PEX3_STN0_RX_DP<9>")
	)
	(segment
		(start 413.50311 -145.287238)
		(end 413.794448 -144.9959)
		(width 0.13462)
		(layer "F.Cu")
		(net "P5E_PEX3_STN0_RX_DP<9>")
	)
	(segment
		(start 416.47491 -145.154904)
		(end 416.95751 -145.154904)
		(width 0.13462)
		(layer "F.Cu")
		(net "P5E_PEX3_STN0_RX_DP<9>")
	)
	(segment
		(start 416.217608 -145.310352)
		(end 416.705796 -145.805398)
		(width 0.1651)
		(layer "In5.Cu")
		(net "P5E_PEX3_STN0_RX_DP<9>")
	)
	(segment
		(start 428.81804 -268.260068)
		(end 428.23384 -271.197578)
		(width 0.1651)
		(layer "In5.Cu")
		(net "P5E_PEX3_STN0_RX_DP<9>")
	)
	(segment
		(start 417.053014 -146.283934)
		(end 417.178744 -146.284696)
		(width 0.1651)
		(layer "In5.Cu")
		(net "P5E_PEX3_STN0_RX_DP<9>")
	)
	(segment
		(start 428.23384 -271.554448)
		(end 428.27956 -271.600168)
		(width 0.1143)
		(layer "In5.Cu")
		(net "P5E_PEX3_STN0_RX_DP<9>")
	)
	(segment
		(start 415.467546 -144.996408)
		(end 416.217608 -145.310352)
		(width 0.1651)
		(layer "In5.Cu")
		(net "P5E_PEX3_STN0_RX_DP<9>")
	)
	(segment
		(start 428.23384 -271.526)
		(end 428.23384 -271.554448)
		(width 0.1143)
		(layer "In5.Cu")
		(net "P5E_PEX3_STN0_RX_DP<9>")
	)
	(segment
		(start 428.23384 -271.197578)
		(end 428.23384 -271.526)
		(width 0.1651)
		(layer "In5.Cu")
		(net "P5E_PEX3_STN0_RX_DP<9>")
	)
	(segment
		(start 417.999418 -147.116546)
		(end 418.47262 -147.596352)
		(width 0.1651)
		(layer "In5.Cu")
		(net "P5E_PEX3_STN0_RX_DP<9>")
	)
	(segment
		(start 416.705796 -145.805398)
		(end 416.705034 -145.931128)
		(width 0.1651)
		(layer "In5.Cu")
		(net "P5E_PEX3_STN0_RX_DP<9>")
	)
	(segment
		(start 421.13708 -152.63622)
		(end 423.885106 -155.437332)
		(width 0.1651)
		(layer "In5.Cu")
		(net "P5E_PEX3_STN0_RX_DP<9>")
	)
	(segment
		(start 423.885106 -155.437332)
		(end 425.23664 -160.504886)
		(width 0.1651)
		(layer "In5.Cu")
		(net "P5E_PEX3_STN0_RX_DP<9>")
	)
	(segment
		(start 428.81804 -261.978394)
		(end 428.81804 -268.260068)
		(width 0.1651)
		(layer "In5.Cu")
		(net "P5E_PEX3_STN0_RX_DP<9>")
	)
	(segment
		(start 417.525708 -146.762978)
		(end 417.873688 -147.115784)
		(width 0.1651)
		(layer "In5.Cu")
		(net "P5E_PEX3_STN0_RX_DP<9>")
	)
	(segment
		(start 425.23664 -160.504886)
		(end 428.81804 -261.978394)
		(width 0.1651)
		(layer "In5.Cu")
		(net "P5E_PEX3_STN0_RX_DP<9>")
	)
	(segment
		(start 428.27956 -273.45513)
		(end 428.494444 -273.670014)
		(width 0.1143)
		(layer "In5.Cu")
		(net "P5E_PEX3_STN0_RX_DP<9>")
	)
	(segment
		(start 413.50311 -145.287238)
		(end 413.79394 -144.996408)
		(width 0.1651)
		(layer "In5.Cu")
		(net "P5E_PEX3_STN0_RX_DP<9>")
	)
	(segment
		(start 428.735236 -273.670014)
		(end 428.849536 -273.784314)
		(width 0.1143)
		(layer "In5.Cu")
		(net "P5E_PEX3_STN0_RX_DP<9>")
	)
	(segment
		(start 420.381684 -150.537418)
		(end 421.13708 -152.63622)
		(width 0.1651)
		(layer "In5.Cu")
		(net "P5E_PEX3_STN0_RX_DP<9>")
	)
	(segment
		(start 417.52647 -146.637248)
		(end 417.525708 -146.762978)
		(width 0.1651)
		(layer "In5.Cu")
		(net "P5E_PEX3_STN0_RX_DP<9>")
	)
	(segment
		(start 428.849536 -273.784314)
		(end 428.849536 -274.049744)
		(width 0.1143)
		(layer "In5.Cu")
		(net "P5E_PEX3_STN0_RX_DP<9>")
	)
	(segment
		(start 417.178744 -146.284696)
		(end 417.52647 -146.637248)
		(width 0.1651)
		(layer "In5.Cu")
		(net "P5E_PEX3_STN0_RX_DP<9>")
	)
	(segment
		(start 416.705034 -145.931128)
		(end 417.053014 -146.283934)
		(width 0.1651)
		(layer "In5.Cu")
		(net "P5E_PEX3_STN0_RX_DP<9>")
	)
	(segment
		(start 428.27956 -271.600168)
		(end 428.27956 -273.45513)
		(width 0.1143)
		(layer "In5.Cu")
		(net "P5E_PEX3_STN0_RX_DP<9>")
	)
	(segment
		(start 413.79394 -144.996408)
		(end 415.467546 -144.996408)
		(width 0.1651)
		(layer "In5.Cu")
		(net "P5E_PEX3_STN0_RX_DP<9>")
	)
	(segment
		(start 418.47262 -147.596352)
		(end 420.381684 -150.537418)
		(width 0.1651)
		(layer "In5.Cu")
		(net "P5E_PEX3_STN0_RX_DP<9>")
	)
	(segment
		(start 428.494444 -273.670014)
		(end 428.735236 -273.670014)
		(width 0.1143)
		(layer "In5.Cu")
		(net "P5E_PEX3_STN0_RX_DP<9>")
	)
	(segment
		(start 417.873688 -147.115784)
		(end 417.999418 -147.116546)
		(width 0.1651)
		(layer "In5.Cu")
		(net "P5E_PEX3_STN0_RX_DP<9>")
	)
	(segment
		(start 381.016002 -369.619276)
		(end 381.7112 -368.15776)
		(width 0.1651)
		(layer "In15.Cu")
		(net "P5E_PEX3_STN5_RX_DN<90>")
	)
	(segment
		(start 391.40003 -359.314242)
		(end 391.96899 -358.024938)
		(width 0.1651)
		(layer "In15.Cu")
		(net "P5E_PEX3_STN5_RX_DN<90>")
	)
	(segment
		(start 416.165792 -321.594734)
		(end 416.165792 -319.969896)
		(width 0.1651)
		(layer "In15.Cu")
		(net "P5E_PEX3_STN5_RX_DN<90>")
	)
	(segment
		(start 380.01702 -371.281198)
		(end 380.564136 -371.281198)
		(width 0.1651)
		(layer "In15.Cu")
		(net "P5E_PEX3_STN5_RX_DN<90>")
	)
	(segment
		(start 416.165792 -319.941448)
		(end 416.120072 -319.895728)
		(width 0.1143)
		(layer "In15.Cu")
		(net "P5E_PEX3_STN5_RX_DN<90>")
	)
	(segment
		(start 379.89002 -371.790214)
		(end 379.89002 -371.408198)
		(width 0.1651)
		(layer "In15.Cu")
		(net "P5E_PEX3_STN5_RX_DN<90>")
	)
	(segment
		(start 415.104834 -323.005196)
		(end 416.165792 -321.594734)
		(width 0.1651)
		(layer "In15.Cu")
		(net "P5E_PEX3_STN5_RX_DN<90>")
	)
	(segment
		(start 391.96899 -358.024938)
		(end 391.96899 -342.168988)
		(width 0.1651)
		(layer "In15.Cu")
		(net "P5E_PEX3_STN5_RX_DN<90>")
	)
	(segment
		(start 416.120072 -319.895728)
		(end 416.120072 -316.523624)
		(width 0.1143)
		(layer "In15.Cu")
		(net "P5E_PEX3_STN5_RX_DN<90>")
	)
	(segment
		(start 379.89002 -371.408198)
		(end 380.01702 -371.281198)
		(width 0.1651)
		(layer "In15.Cu")
		(net "P5E_PEX3_STN5_RX_DN<90>")
	)
	(segment
		(start 380.564136 -371.281198)
		(end 381.016002 -370.829332)
		(width 0.1651)
		(layer "In15.Cu")
		(net "P5E_PEX3_STN5_RX_DN<90>")
	)
	(segment
		(start 416.223704 -316.419992)
		(end 416.385502 -316.419992)
		(width 0.1143)
		(layer "In15.Cu")
		(net "P5E_PEX3_STN5_RX_DN<90>")
	)
	(segment
		(start 392.370564 -341.158576)
		(end 415.104834 -323.005196)
		(width 0.1651)
		(layer "In15.Cu")
		(net "P5E_PEX3_STN5_RX_DN<90>")
	)
	(segment
		(start 416.385502 -316.419992)
		(end 416.499802 -316.534292)
		(width 0.1143)
		(layer "In15.Cu")
		(net "P5E_PEX3_STN5_RX_DN<90>")
	)
	(segment
		(start 381.7112 -368.15776)
		(end 391.40003 -359.314242)
		(width 0.1651)
		(layer "In15.Cu")
		(net "P5E_PEX3_STN5_RX_DN<90>")
	)
	(segment
		(start 381.016002 -370.829332)
		(end 381.016002 -369.619276)
		(width 0.1651)
		(layer "In15.Cu")
		(net "P5E_PEX3_STN5_RX_DN<90>")
	)
	(segment
		(start 416.499802 -316.534292)
		(end 416.499802 -316.799722)
		(width 0.1143)
		(layer "In15.Cu")
		(net "P5E_PEX3_STN5_RX_DN<90>")
	)
	(segment
		(start 416.120072 -316.523624)
		(end 416.223704 -316.419992)
		(width 0.1143)
		(layer "In15.Cu")
		(net "P5E_PEX3_STN5_RX_DN<90>")
	)
	(segment
		(start 391.96899 -342.168988)
		(end 392.370564 -341.158576)
		(width 0.1651)
		(layer "In15.Cu")
		(net "P5E_PEX3_STN5_RX_DN<90>")
	)
	(segment
		(start 416.165792 -319.969896)
		(end 416.165792 -319.941448)
		(width 0.1143)
		(layer "In15.Cu")
		(net "P5E_PEX3_STN5_RX_DN<90>")
	)
	(segment
		(start 79.314802 -82.427572)
		(end 80.413606 -83.526376)
		(width 0.13208)
		(layer "F.Cu")
		(net "HP_NIC1_PWRGD_R")
	)
	(segment
		(start 78.057502 -81.749646)
		(end 79.304388 -81.749646)
		(width 0.13208)
		(layer "F.Cu")
		(net "HP_NIC1_PWRGD_R")
	)
	(segment
		(start 79.304388 -81.749646)
		(end 79.314802 -81.76006)
		(width 0.13208)
		(layer "F.Cu")
		(net "HP_NIC1_PWRGD_R")
	)
	(segment
		(start 80.413606 -83.526376)
		(end 81.349596 -83.526376)
		(width 0.13208)
		(layer "F.Cu")
		(net "HP_NIC1_PWRGD_R")
	)
	(segment
		(start 79.314802 -81.76006)
		(end 79.314802 -82.427572)
		(width 0.13208)
		(layer "F.Cu")
		(net "HP_NIC1_PWRGD_R")
	)
	(via
		(at 79.314802 -82.427572)
		(size 0.508)
		(drill 0.254)
		(layers "F.Cu" "B.Cu")
		(net "HP_NIC1_PWRGD_R")
	)
	(segment
		(start 37.217604 -105.007918)
		(end 45.391578 -105.007918)
		(width 0.13462)
		(layer "F.Cu")
		(net "P5E_PEX0_STN1_TX_C_DN<19>")
	)
	(segment
		(start 45.554392 -104.845104)
		(end 46.042326 -104.845104)
		(width 0.13462)
		(layer "F.Cu")
		(net "P5E_PEX0_STN1_TX_C_DN<19>")
	)
	(segment
		(start 45.391578 -105.007918)
		(end 45.554392 -104.845104)
		(width 0.13462)
		(layer "F.Cu")
		(net "P5E_PEX0_STN1_TX_C_DN<19>")
	)
	(segment
		(start 36.905184 -104.695498)
		(end 37.217604 -105.007918)
		(width 0.13462)
		(layer "F.Cu")
		(net "P5E_PEX0_STN1_TX_C_DN<19>")
	)
	(segment
		(start 161.491422 -123.117864)
		(end 153.324052 -123.117864)
		(width 0.13462)
		(layer "F.Cu")
		(net "P5E_PEX1_STN1_TX_C_DP<26>")
	)
	(segment
		(start 162.14217 -122.95505)
		(end 161.654236 -122.95505)
		(width 0.13462)
		(layer "F.Cu")
		(net "P5E_PEX1_STN1_TX_C_DP<26>")
	)
	(segment
		(start 161.654236 -122.95505)
		(end 161.491422 -123.117864)
		(width 0.13462)
		(layer "F.Cu")
		(net "P5E_PEX1_STN1_TX_C_DP<26>")
	)
	(segment
		(start 153.324052 -123.117864)
		(end 153.005028 -122.79884)
		(width 0.13462)
		(layer "F.Cu")
		(net "P5E_PEX1_STN1_TX_C_DP<26>")
	)
	(segment
		(start 160.170114 -318.447166)
		(end 160.170114 -319.79108)
		(width 0.1143)
		(layer "In15.Cu")
		(net "P5E_PEX1_STN6_RX_DN<110>")
	)
	(segment
		(start 118.11 -402.465032)
		(end 118.11 -402.790152)
		(width 0.1651)
		(layer "In15.Cu")
		(net "P5E_PEX1_STN6_RX_DN<110>")
	)
	(segment
		(start 160.170114 -319.79108)
		(end 160.215834 -319.8368)
		(width 0.1143)
		(layer "In15.Cu")
		(net "P5E_PEX1_STN6_RX_DN<110>")
	)
	(segment
		(start 118.575328 -402.281136)
		(end 118.293896 -402.281136)
		(width 0.1651)
		(layer "In15.Cu")
		(net "P5E_PEX1_STN6_RX_DN<110>")
	)
	(segment
		(start 108.829856 -385.31165)
		(end 109.290358 -386.970524)
		(width 0.1651)
		(layer "In15.Cu")
		(net "P5E_PEX1_STN6_RX_DN<110>")
	)
	(segment
		(start 142.646908 -329.49769)
		(end 123.20397 -337.551014)
		(width 0.1651)
		(layer "In15.Cu")
		(net "P5E_PEX1_STN6_RX_DN<110>")
	)
	(segment
		(start 109.290358 -386.970524)
		(end 110.747048 -389.138414)
		(width 0.1651)
		(layer "In15.Cu")
		(net "P5E_PEX1_STN6_RX_DN<110>")
	)
	(segment
		(start 110.74781 -342.597994)
		(end 110.287816 -344.901012)
		(width 0.1651)
		(layer "In15.Cu")
		(net "P5E_PEX1_STN6_RX_DN<110>")
	)
	(segment
		(start 119.267478 -401.588986)
		(end 118.575328 -402.281136)
		(width 0.1651)
		(layer "In15.Cu")
		(net "P5E_PEX1_STN6_RX_DN<110>")
	)
	(segment
		(start 160.215834 -319.8368)
		(end 160.215834 -319.865248)
		(width 0.1143)
		(layer "In15.Cu")
		(net "P5E_PEX1_STN6_RX_DN<110>")
	)
	(segment
		(start 160.549844 -318.409066)
		(end 160.460944 -318.320166)
		(width 0.1143)
		(layer "In15.Cu")
		(net "P5E_PEX1_STN6_RX_DN<110>")
	)
	(segment
		(start 117.631972 -393.45108)
		(end 119.266716 -395.085824)
		(width 0.1651)
		(layer "In15.Cu")
		(net "P5E_PEX1_STN6_RX_DN<110>")
	)
	(segment
		(start 160.297114 -318.320166)
		(end 160.170114 -318.447166)
		(width 0.1143)
		(layer "In15.Cu")
		(net "P5E_PEX1_STN6_RX_DN<110>")
	)
	(segment
		(start 160.460944 -318.320166)
		(end 160.297114 -318.320166)
		(width 0.1143)
		(layer "In15.Cu")
		(net "P5E_PEX1_STN6_RX_DN<110>")
	)
	(segment
		(start 115.202462 -339.874352)
		(end 115.202208 -339.874606)
		(width 0.1651)
		(layer "In15.Cu")
		(net "P5E_PEX1_STN6_RX_DN<110>")
	)
	(segment
		(start 160.215834 -319.865248)
		(end 160.215834 -320.504566)
		(width 0.1651)
		(layer "In15.Cu")
		(net "P5E_PEX1_STN6_RX_DN<110>")
	)
	(segment
		(start 110.747048 -389.138414)
		(end 114.386106 -392.10615)
		(width 0.1651)
		(layer "In15.Cu")
		(net "P5E_PEX1_STN6_RX_DN<110>")
	)
	(segment
		(start 117.032786 -339.530944)
		(end 115.202462 -339.874352)
		(width 0.1651)
		(layer "In15.Cu")
		(net "P5E_PEX1_STN6_RX_DN<110>")
	)
	(segment
		(start 119.267478 -398.67332)
		(end 119.267478 -401.588986)
		(width 0.1651)
		(layer "In15.Cu")
		(net "P5E_PEX1_STN6_RX_DN<110>")
	)
	(segment
		(start 112.240822 -340.68639)
		(end 111.396526 -341.380572)
		(width 0.1651)
		(layer "In15.Cu")
		(net "P5E_PEX1_STN6_RX_DN<110>")
	)
	(segment
		(start 115.202208 -339.874606)
		(end 113.371376 -340.218522)
		(width 0.1651)
		(layer "In15.Cu")
		(net "P5E_PEX1_STN6_RX_DN<110>")
	)
	(segment
		(start 119.266716 -395.085824)
		(end 119.266716 -398.672558)
		(width 0.1651)
		(layer "In15.Cu")
		(net "P5E_PEX1_STN6_RX_DN<110>")
	)
	(segment
		(start 113.371376 -340.218522)
		(end 112.240822 -340.68639)
		(width 0.1651)
		(layer "In15.Cu")
		(net "P5E_PEX1_STN6_RX_DN<110>")
	)
	(segment
		(start 160.215834 -320.504566)
		(end 158.921958 -321.798442)
		(width 0.1651)
		(layer "In15.Cu")
		(net "P5E_PEX1_STN6_RX_DN<110>")
	)
	(segment
		(start 119.266716 -398.672558)
		(end 119.267478 -398.67332)
		(width 0.1651)
		(layer "In15.Cu")
		(net "P5E_PEX1_STN6_RX_DN<110>")
	)
	(segment
		(start 123.20397 -337.551014)
		(end 117.032786 -339.530944)
		(width 0.1651)
		(layer "In15.Cu")
		(net "P5E_PEX1_STN6_RX_DN<110>")
	)
	(segment
		(start 111.016796 -341.94877)
		(end 110.74781 -342.597994)
		(width 0.1651)
		(layer "In15.Cu")
		(net "P5E_PEX1_STN6_RX_DN<110>")
	)
	(segment
		(start 158.921958 -321.798442)
		(end 142.646908 -329.49769)
		(width 0.1651)
		(layer "In15.Cu")
		(net "P5E_PEX1_STN6_RX_DN<110>")
	)
	(segment
		(start 160.549844 -318.699896)
		(end 160.549844 -318.409066)
		(width 0.1143)
		(layer "In15.Cu")
		(net "P5E_PEX1_STN6_RX_DN<110>")
	)
	(segment
		(start 108.966508 -364.820708)
		(end 108.829856 -385.31165)
		(width 0.1651)
		(layer "In15.Cu")
		(net "P5E_PEX1_STN6_RX_DN<110>")
	)
	(segment
		(start 110.287816 -344.901012)
		(end 108.966508 -364.820708)
		(width 0.1651)
		(layer "In15.Cu")
		(net "P5E_PEX1_STN6_RX_DN<110>")
	)
	(segment
		(start 118.293896 -402.281136)
		(end 118.11 -402.465032)
		(width 0.1651)
		(layer "In15.Cu")
		(net "P5E_PEX1_STN6_RX_DN<110>")
	)
	(segment
		(start 114.386106 -392.10615)
		(end 117.631972 -393.45108)
		(width 0.1651)
		(layer "In15.Cu")
		(net "P5E_PEX1_STN6_RX_DN<110>")
	)
	(segment
		(start 111.396526 -341.380572)
		(end 111.016796 -341.94877)
		(width 0.1651)
		(layer "In15.Cu")
		(net "P5E_PEX1_STN6_RX_DN<110>")
	)
	(segment
		(start 430.694846 -121.391172)
		(end 430.367694 -121.06402)
		(width 0.13462)
		(layer "F.Cu")
		(net "P5E_PEX3_STN0_TX_C_DP<1>")
	)
	(segment
		(start 422.231312 -121.06402)
		(end 422.06037 -121.234962)
		(width 0.13462)
		(layer "F.Cu")
		(net "P5E_PEX3_STN0_TX_C_DP<1>")
	)
	(segment
		(start 430.367694 -121.06402)
		(end 422.231312 -121.06402)
		(width 0.13462)
		(layer "F.Cu")
		(net "P5E_PEX3_STN0_TX_C_DP<1>")
	)
	(segment
		(start 422.06037 -121.234962)
		(end 421.557704 -121.234962)
		(width 0.13462)
		(layer "F.Cu")
		(net "P5E_PEX3_STN0_TX_C_DP<1>")
	)
	(segment
		(start 393.8397 -350.365314)
		(end 393.520168 -350.684846)
		(width 0.13462)
		(layer "F.Cu")
		(net "P5E_PEX3_STN5_TX_C_DN<90>")
	)
	(segment
		(start 393.520168 -350.684846)
		(end 393.520168 -351.317306)
		(width 0.13462)
		(layer "F.Cu")
		(net "P5E_PEX3_STN5_TX_C_DN<90>")
	)
	(segment
		(start 393.520168 -351.317306)
		(end 393.8143 -351.611438)
		(width 0.13462)
		(layer "F.Cu")
		(net "P5E_PEX3_STN5_TX_C_DN<90>")
	)
	(segment
		(start 380.564136 -379.08103)
		(end 381.016002 -378.629164)
		(width 0.1651)
		(layer "In13.Cu")
		(net "P5E_PEX3_STN5_TX_C_DN<90>")
	)
	(segment
		(start 393.52347 -352.473006)
		(end 393.52347 -351.902268)
		(width 0.1651)
		(layer "In13.Cu")
		(net "P5E_PEX3_STN5_TX_C_DN<90>")
	)
	(segment
		(start 381.016002 -369.775486)
		(end 381.724154 -368.197638)
		(width 0.1651)
		(layer "In13.Cu")
		(net "P5E_PEX3_STN5_TX_C_DN<90>")
	)
	(segment
		(start 381.724154 -368.197638)
		(end 391.207244 -359.762298)
		(width 0.1651)
		(layer "In13.Cu")
		(net "P5E_PEX3_STN5_TX_C_DN<90>")
	)
	(segment
		(start 391.96899 -358.06507)
		(end 391.96899 -354.027486)
		(width 0.1651)
		(layer "In13.Cu")
		(net "P5E_PEX3_STN5_TX_C_DN<90>")
	)
	(segment
		(start 379.89002 -379.20803)
		(end 380.01702 -379.08103)
		(width 0.1651)
		(layer "In13.Cu")
		(net "P5E_PEX3_STN5_TX_C_DN<90>")
	)
	(segment
		(start 391.207244 -359.762298)
		(end 391.96899 -358.06507)
		(width 0.1651)
		(layer "In13.Cu")
		(net "P5E_PEX3_STN5_TX_C_DN<90>")
	)
	(segment
		(start 393.52347 -351.902268)
		(end 393.8143 -351.611438)
		(width 0.1651)
		(layer "In13.Cu")
		(net "P5E_PEX3_STN5_TX_C_DN<90>")
	)
	(segment
		(start 381.016002 -378.629164)
		(end 381.016002 -369.775486)
		(width 0.1651)
		(layer "In13.Cu")
		(net "P5E_PEX3_STN5_TX_C_DN<90>")
	)
	(segment
		(start 391.96899 -354.027486)
		(end 393.52347 -352.473006)
		(width 0.1651)
		(layer "In13.Cu")
		(net "P5E_PEX3_STN5_TX_C_DN<90>")
	)
	(segment
		(start 380.01702 -379.08103)
		(end 380.564136 -379.08103)
		(width 0.1651)
		(layer "In13.Cu")
		(net "P5E_PEX3_STN5_TX_C_DN<90>")
	)
	(segment
		(start 379.89002 -379.590046)
		(end 379.89002 -379.20803)
		(width 0.1651)
		(layer "In13.Cu")
		(net "P5E_PEX3_STN5_TX_C_DN<90>")
	)
	(segment
		(start 275.934932 -153.560018)
		(end 274.51558 -152.140412)
		(width 0.13208)
		(layer "F.Cu")
		(net "NCSI_NIC4_RXD0")
	)
	(segment
		(start 273.840448 -151.465534)
		(end 272.382234 -151.465534)
		(width 0.13208)
		(layer "F.Cu")
		(net "NCSI_NIC4_RXD0")
	)
	(segment
		(start 274.51558 -152.140412)
		(end 273.98599 -151.611076)
		(width 0.13208)
		(layer "F.Cu")
		(net "NCSI_NIC4_RXD0")
	)
	(segment
		(start 278.242268 -153.560018)
		(end 275.934932 -153.560018)
		(width 0.13208)
		(layer "F.Cu")
		(net "NCSI_NIC4_RXD0")
	)
	(segment
		(start 273.98599 -151.611076)
		(end 273.840448 -151.465534)
		(width 0.13208)
		(layer "F.Cu")
		(net "NCSI_NIC4_RXD0")
	)
	(segment
		(start 271.63776 -151.279352)
		(end 271.199864 -151.279352)
		(width 0.13208)
		(layer "F.Cu")
		(net "NCSI_NIC4_RXD0")
	)
	(segment
		(start 272.382234 -151.465534)
		(end 271.823942 -151.465534)
		(width 0.13208)
		(layer "F.Cu")
		(net "NCSI_NIC4_RXD0")
	)
	(segment
		(start 271.823942 -151.465534)
		(end 271.63776 -151.279352)
		(width 0.13208)
		(layer "F.Cu")
		(net "NCSI_NIC4_RXD0")
	)
	(via
		(at 272.382234 -151.465534)
		(size 0.762)
		(drill 0.381)
		(layers "F.Cu" "B.Cu")
		(net "NCSI_NIC4_RXD0")
	)
	(segment
		(start 51.947826 -132.527802)
		(end 52.24272 -132.232908)
		(width 0.13462)
		(layer "F.Cu")
		(net "P5E_PEX0_STN1_RX_DP<29>")
	)
	(segment
		(start 51.130454 -132.364988)
		(end 51.293268 -132.527802)
		(width 0.13462)
		(layer "F.Cu")
		(net "P5E_PEX0_STN1_RX_DP<29>")
	)
	(segment
		(start 50.64252 -132.364988)
		(end 51.130454 -132.364988)
		(width 0.13462)
		(layer "F.Cu")
		(net "P5E_PEX0_STN1_RX_DP<29>")
	)
	(segment
		(start 51.293268 -132.527802)
		(end 51.947826 -132.527802)
		(width 0.13462)
		(layer "F.Cu")
		(net "P5E_PEX0_STN1_RX_DP<29>")
	)
	(segment
		(start 51.260756 -132.759196)
		(end 49.843944 -134.100824)
		(width 0.1651)
		(layer "In5.Cu")
		(net "P5E_PEX0_STN1_RX_DP<29>")
	)
	(segment
		(start 48.669702 -136.936988)
		(end 48.669702 -140.713206)
		(width 0.1651)
		(layer "In5.Cu")
		(net "P5E_PEX0_STN1_RX_DP<29>")
	)
	(segment
		(start 71.383906 -271.802352)
		(end 71.429626 -271.848072)
		(width 0.1143)
		(layer "In5.Cu")
		(net "P5E_PEX0_STN1_RX_DP<29>")
	)
	(segment
		(start 51.95189 -132.523738)
		(end 51.67884 -132.523738)
		(width 0.1651)
		(layer "In5.Cu")
		(net "P5E_PEX0_STN1_RX_DP<29>")
	)
	(segment
		(start 45.922692 -144.47647)
		(end 45.516038 -145.0848)
		(width 0.1651)
		(layer "In5.Cu")
		(net "P5E_PEX0_STN1_RX_DP<29>")
	)
	(segment
		(start 45.087032 -145.513806)
		(end 42.865294 -146.226022)
		(width 0.1651)
		(layer "In5.Cu")
		(net "P5E_PEX0_STN1_RX_DP<29>")
	)
	(segment
		(start 51.67884 -132.523738)
		(end 51.366928 -132.653024)
		(width 0.1651)
		(layer "In5.Cu")
		(net "P5E_PEX0_STN1_RX_DP<29>")
	)
	(segment
		(start 71.999602 -275.684234)
		(end 71.999602 -275.949664)
		(width 0.1143)
		(layer "In5.Cu")
		(net "P5E_PEX0_STN1_RX_DP<29>")
	)
	(segment
		(start 42.216578 -146.854926)
		(end 41.723564 -147.76069)
		(width 0.1651)
		(layer "In5.Cu")
		(net "P5E_PEX0_STN1_RX_DP<29>")
	)
	(segment
		(start 71.885302 -275.569934)
		(end 71.999602 -275.684234)
		(width 0.1143)
		(layer "In5.Cu")
		(net "P5E_PEX0_STN1_RX_DP<29>")
	)
	(segment
		(start 51.366928 -132.653024)
		(end 51.260756 -132.759196)
		(width 0.1651)
		(layer "In5.Cu")
		(net "P5E_PEX0_STN1_RX_DP<29>")
	)
	(segment
		(start 42.437812 -146.58467)
		(end 42.216578 -146.854926)
		(width 0.1651)
		(layer "In5.Cu")
		(net "P5E_PEX0_STN1_RX_DP<29>")
	)
	(segment
		(start 47.825406 -142.75181)
		(end 45.922692 -144.47647)
		(width 0.1651)
		(layer "In5.Cu")
		(net "P5E_PEX0_STN1_RX_DP<29>")
	)
	(segment
		(start 43.040554 -160.904428)
		(end 71.383906 -267.498322)
		(width 0.1651)
		(layer "In5.Cu")
		(net "P5E_PEX0_STN1_RX_DP<29>")
	)
	(segment
		(start 42.310304 -156.780992)
		(end 43.040554 -160.904428)
		(width 0.1651)
		(layer "In5.Cu")
		(net "P5E_PEX0_STN1_RX_DP<29>")
	)
	(segment
		(start 49.843944 -134.100824)
		(end 48.669702 -136.936988)
		(width 0.1651)
		(layer "In5.Cu")
		(net "P5E_PEX0_STN1_RX_DP<29>")
	)
	(segment
		(start 52.24272 -132.232908)
		(end 51.95189 -132.523738)
		(width 0.1651)
		(layer "In5.Cu")
		(net "P5E_PEX0_STN1_RX_DP<29>")
	)
	(segment
		(start 71.383906 -271.773904)
		(end 71.383906 -271.802352)
		(width 0.1143)
		(layer "In5.Cu")
		(net "P5E_PEX0_STN1_RX_DP<29>")
	)
	(segment
		(start 71.64451 -275.569934)
		(end 71.885302 -275.569934)
		(width 0.1143)
		(layer "In5.Cu")
		(net "P5E_PEX0_STN1_RX_DP<29>")
	)
	(segment
		(start 71.429626 -271.848072)
		(end 71.429626 -275.35505)
		(width 0.1143)
		(layer "In5.Cu")
		(net "P5E_PEX0_STN1_RX_DP<29>")
	)
	(segment
		(start 41.723564 -147.76069)
		(end 42.310304 -156.780992)
		(width 0.1651)
		(layer "In5.Cu")
		(net "P5E_PEX0_STN1_RX_DP<29>")
	)
	(segment
		(start 48.669702 -140.713206)
		(end 47.825406 -142.75181)
		(width 0.1651)
		(layer "In5.Cu")
		(net "P5E_PEX0_STN1_RX_DP<29>")
	)
	(segment
		(start 71.429626 -275.35505)
		(end 71.64451 -275.569934)
		(width 0.1143)
		(layer "In5.Cu")
		(net "P5E_PEX0_STN1_RX_DP<29>")
	)
	(segment
		(start 42.865294 -146.226022)
		(end 42.437812 -146.58467)
		(width 0.1651)
		(layer "In5.Cu")
		(net "P5E_PEX0_STN1_RX_DP<29>")
	)
	(segment
		(start 45.516038 -145.0848)
		(end 45.087032 -145.513806)
		(width 0.1651)
		(layer "In5.Cu")
		(net "P5E_PEX0_STN1_RX_DP<29>")
	)
	(segment
		(start 71.383906 -267.498322)
		(end 71.383906 -271.773904)
		(width 0.1651)
		(layer "In5.Cu")
		(net "P5E_PEX0_STN1_RX_DP<29>")
	)
	(segment
		(start 161.491422 -110.682278)
		(end 161.654236 -110.845092)
		(width 0.13462)
		(layer "F.Cu")
		(net "P5E_PEX1_STN1_TX_C_DN<22>")
	)
	(segment
		(start 155.968192 -110.682278)
		(end 161.491422 -110.682278)
		(width 0.13462)
		(layer "F.Cu")
		(net "P5E_PEX1_STN1_TX_C_DN<22>")
	)
	(segment
		(start 161.654236 -110.845092)
		(end 162.14217 -110.845092)
		(width 0.13462)
		(layer "F.Cu")
		(net "P5E_PEX1_STN1_TX_C_DN<22>")
	)
	(segment
		(start 155.647136 -111.003334)
		(end 155.968192 -110.682278)
		(width 0.13462)
		(layer "F.Cu")
		(net "P5E_PEX1_STN1_TX_C_DN<22>")
	)
	(segment
		(start 121.369582 -369.759992)
		(end 121.912888 -368.618516)
		(width 0.1651)
		(layer "In5.Cu")
		(net "P5E_PEX1_STN6_RX_DN<101>")
	)
	(segment
		(start 129.534158 -358.027478)
		(end 129.534158 -342.0999)
		(width 0.1651)
		(layer "In5.Cu")
		(net "P5E_PEX1_STN6_RX_DN<101>")
	)
	(segment
		(start 121.369582 -374.798336)
		(end 121.369582 -369.759992)
		(width 0.1651)
		(layer "In5.Cu")
		(net "P5E_PEX1_STN6_RX_DN<101>")
	)
	(segment
		(start 168.765982 -319.9384)
		(end 168.720262 -319.89268)
		(width 0.1143)
		(layer "In5.Cu")
		(net "P5E_PEX1_STN6_RX_DN<101>")
	)
	(segment
		(start 120.310148 -375.69013)
		(end 120.310148 -375.308114)
		(width 0.1651)
		(layer "In5.Cu")
		(net "P5E_PEX1_STN6_RX_DN<101>")
	)
	(segment
		(start 168.765982 -320.646298)
		(end 168.765982 -319.966848)
		(width 0.1651)
		(layer "In5.Cu")
		(net "P5E_PEX1_STN6_RX_DN<101>")
	)
	(segment
		(start 129.534158 -342.0999)
		(end 130.081274 -341.347298)
		(width 0.1651)
		(layer "In5.Cu")
		(net "P5E_PEX1_STN6_RX_DN<101>")
	)
	(segment
		(start 120.986804 -375.181114)
		(end 121.369582 -374.798336)
		(width 0.1651)
		(layer "In5.Cu")
		(net "P5E_PEX1_STN6_RX_DN<101>")
	)
	(segment
		(start 168.106598 -321.305682)
		(end 168.765982 -320.646298)
		(width 0.1651)
		(layer "In5.Cu")
		(net "P5E_PEX1_STN6_RX_DN<101>")
	)
	(segment
		(start 168.834562 -316.419992)
		(end 168.985692 -316.419992)
		(width 0.1143)
		(layer "In5.Cu")
		(net "P5E_PEX1_STN6_RX_DN<101>")
	)
	(segment
		(start 168.765982 -319.966848)
		(end 168.765982 -319.9384)
		(width 0.1143)
		(layer "In5.Cu")
		(net "P5E_PEX1_STN6_RX_DN<101>")
	)
	(segment
		(start 168.985692 -316.419992)
		(end 169.099992 -316.534292)
		(width 0.1143)
		(layer "In5.Cu")
		(net "P5E_PEX1_STN6_RX_DN<101>")
	)
	(segment
		(start 155.526994 -328.741024)
		(end 167.669464 -321.564)
		(width 0.1651)
		(layer "In5.Cu")
		(net "P5E_PEX1_STN6_RX_DN<101>")
	)
	(segment
		(start 130.081274 -341.347298)
		(end 146.572224 -334.42148)
		(width 0.1651)
		(layer "In5.Cu")
		(net "P5E_PEX1_STN6_RX_DN<101>")
	)
	(segment
		(start 168.720262 -316.534292)
		(end 168.834562 -316.419992)
		(width 0.1143)
		(layer "In5.Cu")
		(net "P5E_PEX1_STN6_RX_DN<101>")
	)
	(segment
		(start 167.669464 -321.564)
		(end 168.106598 -321.305682)
		(width 0.1651)
		(layer "In5.Cu")
		(net "P5E_PEX1_STN6_RX_DN<101>")
	)
	(segment
		(start 120.310148 -375.308114)
		(end 120.437148 -375.181114)
		(width 0.1651)
		(layer "In5.Cu")
		(net "P5E_PEX1_STN6_RX_DN<101>")
	)
	(segment
		(start 168.720262 -319.89268)
		(end 168.720262 -316.534292)
		(width 0.1143)
		(layer "In5.Cu")
		(net "P5E_PEX1_STN6_RX_DN<101>")
	)
	(segment
		(start 146.572224 -334.42148)
		(end 155.526994 -328.741024)
		(width 0.1651)
		(layer "In5.Cu")
		(net "P5E_PEX1_STN6_RX_DN<101>")
	)
	(segment
		(start 169.099992 -316.534292)
		(end 169.099992 -316.799722)
		(width 0.1143)
		(layer "In5.Cu")
		(net "P5E_PEX1_STN6_RX_DN<101>")
	)
	(segment
		(start 120.437148 -375.181114)
		(end 120.986804 -375.181114)
		(width 0.1651)
		(layer "In5.Cu")
		(net "P5E_PEX1_STN6_RX_DN<101>")
	)
	(segment
		(start 129.454656 -358.27081)
		(end 129.534158 -358.027478)
		(width 0.1651)
		(layer "In5.Cu")
		(net "P5E_PEX1_STN6_RX_DN<101>")
	)
	(segment
		(start 121.912888 -368.618516)
		(end 129.454656 -358.27081)
		(width 0.1651)
		(layer "In5.Cu")
		(net "P5E_PEX1_STN6_RX_DN<101>")
	)
	(segment
		(start 427.739556 -134.08152)
		(end 422.220644 -134.08152)
		(width 0.13462)
		(layer "F.Cu")
		(net "P5E_PEX3_STN0_TX_C_DP<6>")
	)
	(segment
		(start 422.057068 -134.245096)
		(end 421.557704 -134.245096)
		(width 0.13462)
		(layer "F.Cu")
		(net "P5E_PEX3_STN0_TX_C_DP<6>")
	)
	(segment
		(start 422.220644 -134.08152)
		(end 422.057068 -134.245096)
		(width 0.13462)
		(layer "F.Cu")
		(net "P5E_PEX3_STN0_TX_C_DP<6>")
	)
	(segment
		(start 428.052738 -134.394702)
		(end 427.739556 -134.08152)
		(width 0.13462)
		(layer "F.Cu")
		(net "P5E_PEX3_STN0_TX_C_DP<6>")
	)
	(segment
		(start 402.847048 -351.317306)
		(end 403.14118 -351.611438)
		(width 0.13462)
		(layer "F.Cu")
		(net "P5E_PEX3_STN5_TX_C_DN<87>")
	)
	(segment
		(start 402.847048 -350.684846)
		(end 402.847048 -351.317306)
		(width 0.13462)
		(layer "F.Cu")
		(net "P5E_PEX3_STN5_TX_C_DN<87>")
	)
	(segment
		(start 403.16658 -350.365314)
		(end 402.847048 -350.684846)
		(width 0.13462)
		(layer "F.Cu")
		(net "P5E_PEX3_STN5_TX_C_DN<87>")
	)
	(segment
		(start 402.37283 -387.77545)
		(end 402.462492 -369.084606)
		(width 0.1651)
		(layer "In7.Cu")
		(net "P5E_PEX3_STN5_TX_C_DN<87>")
	)
	(segment
		(start 391.016998 -406.181052)
		(end 391.564114 -406.181052)
		(width 0.1651)
		(layer "In7.Cu")
		(net "P5E_PEX3_STN5_TX_C_DN<87>")
	)
	(segment
		(start 390.889998 -406.308052)
		(end 391.016998 -406.181052)
		(width 0.1651)
		(layer "In7.Cu")
		(net "P5E_PEX3_STN5_TX_C_DN<87>")
	)
	(segment
		(start 392.472418 -394.706856)
		(end 392.505438 -394.706856)
		(width 0.1651)
		(layer "In7.Cu")
		(net "P5E_PEX3_STN5_TX_C_DN<87>")
	)
	(segment
		(start 402.85035 -352.52279)
		(end 402.85035 -351.902268)
		(width 0.1651)
		(layer "In7.Cu")
		(net "P5E_PEX3_STN5_TX_C_DN<87>")
	)
	(segment
		(start 392.505438 -394.706856)
		(end 392.530076 -394.682218)
		(width 0.1651)
		(layer "In7.Cu")
		(net "P5E_PEX3_STN5_TX_C_DN<87>")
	)
	(segment
		(start 402.462492 -369.084606)
		(end 401.29587 -358.80802)
		(width 0.1651)
		(layer "In7.Cu")
		(net "P5E_PEX3_STN5_TX_C_DN<87>")
	)
	(segment
		(start 392.530076 -394.682218)
		(end 400.28114 -391.375138)
		(width 0.1651)
		(layer "In7.Cu")
		(net "P5E_PEX3_STN5_TX_C_DN<87>")
	)
	(segment
		(start 401.29587 -358.80802)
		(end 401.29587 -354.07727)
		(width 0.1651)
		(layer "In7.Cu")
		(net "P5E_PEX3_STN5_TX_C_DN<87>")
	)
	(segment
		(start 401.29587 -354.07727)
		(end 402.85035 -352.52279)
		(width 0.1651)
		(layer "In7.Cu")
		(net "P5E_PEX3_STN5_TX_C_DN<87>")
	)
	(segment
		(start 392.01598 -395.133068)
		(end 392.472418 -394.706856)
		(width 0.1651)
		(layer "In7.Cu")
		(net "P5E_PEX3_STN5_TX_C_DN<87>")
	)
	(segment
		(start 392.01598 -405.729186)
		(end 392.01598 -395.133068)
		(width 0.1651)
		(layer "In7.Cu")
		(net "P5E_PEX3_STN5_TX_C_DN<87>")
	)
	(segment
		(start 391.564114 -406.181052)
		(end 392.01598 -405.729186)
		(width 0.1651)
		(layer "In7.Cu")
		(net "P5E_PEX3_STN5_TX_C_DN<87>")
	)
	(segment
		(start 401.327112 -389.575294)
		(end 402.37283 -387.77545)
		(width 0.1651)
		(layer "In7.Cu")
		(net "P5E_PEX3_STN5_TX_C_DN<87>")
	)
	(segment
		(start 402.85035 -351.902268)
		(end 403.14118 -351.611438)
		(width 0.1651)
		(layer "In7.Cu")
		(net "P5E_PEX3_STN5_TX_C_DN<87>")
	)
	(segment
		(start 400.28114 -391.375138)
		(end 401.327112 -389.575294)
		(width 0.1651)
		(layer "In7.Cu")
		(net "P5E_PEX3_STN5_TX_C_DN<87>")
	)
	(segment
		(start 390.889998 -406.690068)
		(end 390.889998 -406.308052)
		(width 0.1651)
		(layer "In7.Cu")
		(net "P5E_PEX3_STN5_TX_C_DN<87>")
	)
	(segment
		(start 282.842462 -150.560024)
		(end 284.461966 -150.560024)
		(width 0.13208)
		(layer "F.Cu")
		(net "CLK_50M_NIC4_RBT_REF")
	)
	(segment
		(start 284.461966 -150.560024)
		(end 285.158942 -151.257)
		(width 0.13208)
		(layer "F.Cu")
		(net "CLK_50M_NIC4_RBT_REF")
	)
	(via
		(at 285.158942 -151.257)
		(size 0.508)
		(drill 0.254)
		(layers "F.Cu" "B.Cu")
		(net "CLK_50M_NIC4_RBT_REF")
	)
	(segment
		(start 283.061918 -150.560024)
		(end 284.461966 -150.560024)
		(width 0.13208)
		(layer "B.Cu")
		(net "CLK_50M_NIC4_RBT_REF")
	)
	(segment
		(start 284.461966 -150.560024)
		(end 285.158942 -151.257)
		(width 0.13208)
		(layer "B.Cu")
		(net "CLK_50M_NIC4_RBT_REF")
	)
	(segment
		(start 282.155392 -150.9776)
		(end 282.644342 -150.9776)
		(width 0.13208)
		(layer "B.Cu")
		(net "CLK_50M_NIC4_RBT_REF")
	)
	(segment
		(start 282.644342 -150.9776)
		(end 283.061918 -150.560024)
		(width 0.13208)
		(layer "B.Cu")
		(net "CLK_50M_NIC4_RBT_REF")
	)
	(segment
		(start 37.224208 -123.117864)
		(end 36.905184 -122.79884)
		(width 0.13462)
		(layer "F.Cu")
		(net "P5E_PEX0_STN1_TX_C_DP<26>")
	)
	(segment
		(start 46.042326 -122.95505)
		(end 45.554392 -122.95505)
		(width 0.13462)
		(layer "F.Cu")
		(net "P5E_PEX0_STN1_TX_C_DP<26>")
	)
	(segment
		(start 45.391578 -123.117864)
		(end 37.224208 -123.117864)
		(width 0.13462)
		(layer "F.Cu")
		(net "P5E_PEX0_STN1_TX_C_DP<26>")
	)
	(segment
		(start 45.554392 -122.95505)
		(end 45.391578 -123.117864)
		(width 0.13462)
		(layer "F.Cu")
		(net "P5E_PEX0_STN1_TX_C_DP<26>")
	)
	(segment
		(start 161.654236 -124.755148)
		(end 161.491422 -124.917962)
		(width 0.13462)
		(layer "F.Cu")
		(net "P5E_PEX1_STN1_TX_C_DN<27>")
	)
	(segment
		(start 155.959556 -124.917962)
		(end 155.647136 -124.605542)
		(width 0.13462)
		(layer "F.Cu")
		(net "P5E_PEX1_STN1_TX_C_DN<27>")
	)
	(segment
		(start 161.491422 -124.917962)
		(end 155.959556 -124.917962)
		(width 0.13462)
		(layer "F.Cu")
		(net "P5E_PEX1_STN1_TX_C_DN<27>")
	)
	(segment
		(start 162.14217 -124.755148)
		(end 161.654236 -124.755148)
		(width 0.13462)
		(layer "F.Cu")
		(net "P5E_PEX1_STN1_TX_C_DN<27>")
	)
	(segment
		(start 168.035732 -318.320166)
		(end 167.884602 -318.320166)
		(width 0.1143)
		(layer "In5.Cu")
		(net "P5E_PEX1_STN6_RX_DN<102>")
	)
	(segment
		(start 126.771146 -341.623904)
		(end 126.425198 -342.094312)
		(width 0.1651)
		(layer "In5.Cu")
		(net "P5E_PEX1_STN6_RX_DN<102>")
	)
	(segment
		(start 167.884602 -318.320166)
		(end 167.770302 -318.434466)
		(width 0.1143)
		(layer "In5.Cu")
		(net "P5E_PEX1_STN6_RX_DN<102>")
	)
	(segment
		(start 119.169434 -369.75415)
		(end 119.169434 -375.89841)
		(width 0.1651)
		(layer "In5.Cu")
		(net "P5E_PEX1_STN6_RX_DN<102>")
	)
	(segment
		(start 127.112268 -341.282782)
		(end 126.771146 -341.623904)
		(width 0.1651)
		(layer "In5.Cu")
		(net "P5E_PEX1_STN6_RX_DN<102>")
	)
	(segment
		(start 167.46855 -320.566796)
		(end 155.054046 -327.904602)
		(width 0.1651)
		(layer "In5.Cu")
		(net "P5E_PEX1_STN6_RX_DN<102>")
	)
	(segment
		(start 118.11 -376.408188)
		(end 118.11 -376.790204)
		(width 0.1651)
		(layer "In5.Cu")
		(net "P5E_PEX1_STN6_RX_DN<102>")
	)
	(segment
		(start 119.756682 -368.33302)
		(end 119.169434 -369.75415)
		(width 0.1651)
		(layer "In5.Cu")
		(net "P5E_PEX1_STN6_RX_DN<102>")
	)
	(segment
		(start 126.425198 -342.094312)
		(end 126.425198 -357.924862)
		(width 0.1651)
		(layer "In5.Cu")
		(net "P5E_PEX1_STN6_RX_DN<102>")
	)
	(segment
		(start 167.770302 -318.434466)
		(end 167.770302 -319.807082)
		(width 0.1143)
		(layer "In5.Cu")
		(net "P5E_PEX1_STN6_RX_DN<102>")
	)
	(segment
		(start 167.816022 -319.88125)
		(end 167.816022 -320.219324)
		(width 0.1651)
		(layer "In5.Cu")
		(net "P5E_PEX1_STN6_RX_DN<102>")
	)
	(segment
		(start 168.150032 -318.434466)
		(end 168.035732 -318.320166)
		(width 0.1143)
		(layer "In5.Cu")
		(net "P5E_PEX1_STN6_RX_DN<102>")
	)
	(segment
		(start 147.392644 -332.765908)
		(end 127.112268 -341.282782)
		(width 0.1651)
		(layer "In5.Cu")
		(net "P5E_PEX1_STN6_RX_DN<102>")
	)
	(segment
		(start 168.150032 -318.699896)
		(end 168.150032 -318.434466)
		(width 0.1143)
		(layer "In5.Cu")
		(net "P5E_PEX1_STN6_RX_DN<102>")
	)
	(segment
		(start 167.770302 -319.807082)
		(end 167.816022 -319.852802)
		(width 0.1143)
		(layer "In5.Cu")
		(net "P5E_PEX1_STN6_RX_DN<102>")
	)
	(segment
		(start 167.816022 -319.852802)
		(end 167.816022 -319.88125)
		(width 0.1143)
		(layer "In5.Cu")
		(net "P5E_PEX1_STN6_RX_DN<102>")
	)
	(segment
		(start 167.816022 -320.219324)
		(end 167.46855 -320.566796)
		(width 0.1651)
		(layer "In5.Cu")
		(net "P5E_PEX1_STN6_RX_DN<102>")
	)
	(segment
		(start 126.096014 -358.996488)
		(end 119.756682 -368.33302)
		(width 0.1651)
		(layer "In5.Cu")
		(net "P5E_PEX1_STN6_RX_DN<102>")
	)
	(segment
		(start 155.054046 -327.904602)
		(end 147.392644 -332.765908)
		(width 0.1651)
		(layer "In5.Cu")
		(net "P5E_PEX1_STN6_RX_DN<102>")
	)
	(segment
		(start 118.237 -376.281188)
		(end 118.11 -376.408188)
		(width 0.1651)
		(layer "In5.Cu")
		(net "P5E_PEX1_STN6_RX_DN<102>")
	)
	(segment
		(start 119.169434 -375.89841)
		(end 118.786656 -376.281188)
		(width 0.1651)
		(layer "In5.Cu")
		(net "P5E_PEX1_STN6_RX_DN<102>")
	)
	(segment
		(start 126.425198 -357.924862)
		(end 126.096014 -358.996488)
		(width 0.1651)
		(layer "In5.Cu")
		(net "P5E_PEX1_STN6_RX_DN<102>")
	)
	(segment
		(start 118.786656 -376.281188)
		(end 118.237 -376.281188)
		(width 0.1651)
		(layer "In5.Cu")
		(net "P5E_PEX1_STN6_RX_DN<102>")
	)
	(segment
		(start 413.50311 -148.887434)
		(end 413.800544 -148.59)
		(width 0.13462)
		(layer "F.Cu")
		(net "P5E_PEX3_STN0_RX_DP<11>")
	)
	(segment
		(start 413.800544 -148.59)
		(end 416.30981 -148.59)
		(width 0.13462)
		(layer "F.Cu")
		(net "P5E_PEX3_STN0_RX_DP<11>")
	)
	(segment
		(start 416.30981 -148.59)
		(end 416.47491 -148.7551)
		(width 0.13462)
		(layer "F.Cu")
		(net "P5E_PEX3_STN0_RX_DP<11>")
	)
	(segment
		(start 416.47491 -148.7551)
		(end 416.95751 -148.7551)
		(width 0.13462)
		(layer "F.Cu")
		(net "P5E_PEX3_STN0_RX_DP<11>")
	)
	(segment
		(start 423.292778 -161.107882)
		(end 423.292778 -161.108136)
		(width 0.1651)
		(layer "In5.Cu")
		(net "P5E_PEX3_STN0_RX_DP<11>")
	)
	(segment
		(start 415.885376 -148.596604)
		(end 416.57651 -149.287738)
		(width 0.1651)
		(layer "In5.Cu")
		(net "P5E_PEX3_STN0_RX_DP<11>")
	)
	(segment
		(start 416.92703 -149.763988)
		(end 417.05276 -149.763988)
		(width 0.1651)
		(layer "In5.Cu")
		(net "P5E_PEX3_STN0_RX_DP<11>")
	)
	(segment
		(start 423.249598 -160.910778)
		(end 423.292778 -161.107882)
		(width 0.1651)
		(layer "In5.Cu")
		(net "P5E_PEX3_STN0_RX_DP<11>")
	)
	(segment
		(start 416.57651 -149.287738)
		(end 416.57651 -149.413468)
		(width 0.1651)
		(layer "In5.Cu")
		(net "P5E_PEX3_STN0_RX_DP<11>")
	)
	(segment
		(start 417.05276 -149.763988)
		(end 417.402772 -150.114)
		(width 0.1651)
		(layer "In5.Cu")
		(net "P5E_PEX3_STN0_RX_DP<11>")
	)
	(segment
		(start 426.594524 -273.670014)
		(end 426.835316 -273.670014)
		(width 0.1143)
		(layer "In5.Cu")
		(net "P5E_PEX3_STN0_RX_DP<11>")
	)
	(segment
		(start 426.37964 -273.45513)
		(end 426.594524 -273.670014)
		(width 0.1143)
		(layer "In5.Cu")
		(net "P5E_PEX3_STN0_RX_DP<11>")
	)
	(segment
		(start 423.293032 -161.110676)
		(end 423.314368 -161.206942)
		(width 0.1651)
		(layer "In5.Cu")
		(net "P5E_PEX3_STN0_RX_DP<11>")
	)
	(segment
		(start 423.292524 -161.108136)
		(end 423.293032 -161.110676)
		(width 0.1651)
		(layer "In5.Cu")
		(net "P5E_PEX3_STN0_RX_DP<11>")
	)
	(segment
		(start 426.33392 -271.526)
		(end 426.33392 -271.554448)
		(width 0.1143)
		(layer "In5.Cu")
		(net "P5E_PEX3_STN0_RX_DP<11>")
	)
	(segment
		(start 418.345112 -151.05634)
		(end 419.923722 -154.844242)
		(width 0.1651)
		(layer "In5.Cu")
		(net "P5E_PEX3_STN0_RX_DP<11>")
	)
	(segment
		(start 417.402772 -150.23973)
		(end 417.753292 -150.59025)
		(width 0.1651)
		(layer "In5.Cu")
		(net "P5E_PEX3_STN0_RX_DP<11>")
	)
	(segment
		(start 417.402772 -150.114)
		(end 417.402772 -150.23973)
		(width 0.1651)
		(layer "In5.Cu")
		(net "P5E_PEX3_STN0_RX_DP<11>")
	)
	(segment
		(start 426.875956 -268.129258)
		(end 426.33392 -270.887444)
		(width 0.1651)
		(layer "In5.Cu")
		(net "P5E_PEX3_STN0_RX_DP<11>")
	)
	(segment
		(start 416.57651 -149.413468)
		(end 416.92703 -149.763988)
		(width 0.1651)
		(layer "In5.Cu")
		(net "P5E_PEX3_STN0_RX_DP<11>")
	)
	(segment
		(start 419.923722 -154.844242)
		(end 422.050972 -158.044388)
		(width 0.1651)
		(layer "In5.Cu")
		(net "P5E_PEX3_STN0_RX_DP<11>")
	)
	(segment
		(start 422.050972 -158.044388)
		(end 423.249598 -160.910778)
		(width 0.1651)
		(layer "In5.Cu")
		(net "P5E_PEX3_STN0_RX_DP<11>")
	)
	(segment
		(start 426.835316 -273.670014)
		(end 426.949616 -273.784314)
		(width 0.1143)
		(layer "In5.Cu")
		(net "P5E_PEX3_STN0_RX_DP<11>")
	)
	(segment
		(start 426.33392 -270.887444)
		(end 426.33392 -271.526)
		(width 0.1651)
		(layer "In5.Cu")
		(net "P5E_PEX3_STN0_RX_DP<11>")
	)
	(segment
		(start 426.37964 -271.600168)
		(end 426.37964 -273.45513)
		(width 0.1143)
		(layer "In5.Cu")
		(net "P5E_PEX3_STN0_RX_DP<11>")
	)
	(segment
		(start 413.79394 -148.596604)
		(end 415.885376 -148.596604)
		(width 0.1651)
		(layer "In5.Cu")
		(net "P5E_PEX3_STN0_RX_DP<11>")
	)
	(segment
		(start 423.292778 -161.108136)
		(end 423.292524 -161.108136)
		(width 0.1651)
		(layer "In5.Cu")
		(net "P5E_PEX3_STN0_RX_DP<11>")
	)
	(segment
		(start 426.33392 -271.554448)
		(end 426.37964 -271.600168)
		(width 0.1143)
		(layer "In5.Cu")
		(net "P5E_PEX3_STN0_RX_DP<11>")
	)
	(segment
		(start 417.879022 -150.59025)
		(end 418.345112 -151.05634)
		(width 0.1651)
		(layer "In5.Cu")
		(net "P5E_PEX3_STN0_RX_DP<11>")
	)
	(segment
		(start 423.314622 -161.207196)
		(end 423.335958 -161.304478)
		(width 0.1651)
		(layer "In5.Cu")
		(net "P5E_PEX3_STN0_RX_DP<11>")
	)
	(segment
		(start 423.335958 -161.304478)
		(end 426.841158 -260.519164)
		(width 0.1651)
		(layer "In5.Cu")
		(net "P5E_PEX3_STN0_RX_DP<11>")
	)
	(segment
		(start 423.314368 -161.206942)
		(end 423.314622 -161.207196)
		(width 0.1651)
		(layer "In5.Cu")
		(net "P5E_PEX3_STN0_RX_DP<11>")
	)
	(segment
		(start 426.949616 -273.784314)
		(end 426.949616 -274.049744)
		(width 0.1143)
		(layer "In5.Cu")
		(net "P5E_PEX3_STN0_RX_DP<11>")
	)
	(segment
		(start 426.841158 -260.519164)
		(end 426.875956 -268.129258)
		(width 0.1651)
		(layer "In5.Cu")
		(net "P5E_PEX3_STN0_RX_DP<11>")
	)
	(segment
		(start 417.753292 -150.59025)
		(end 417.879022 -150.59025)
		(width 0.1651)
		(layer "In5.Cu")
		(net "P5E_PEX3_STN0_RX_DP<11>")
	)
	(segment
		(start 413.50311 -148.887434)
		(end 413.79394 -148.596604)
		(width 0.1651)
		(layer "In5.Cu")
		(net "P5E_PEX3_STN0_RX_DP<11>")
	)
	(segment
		(start 402.847048 -356.831138)
		(end 402.847048 -357.463598)
		(width 0.13462)
		(layer "F.Cu")
		(net "P5E_PEX3_STN5_TX_C_DN<95>")
	)
	(segment
		(start 403.16658 -356.511606)
		(end 402.847048 -356.831138)
		(width 0.13462)
		(layer "F.Cu")
		(net "P5E_PEX3_STN5_TX_C_DN<95>")
	)
	(segment
		(start 402.847048 -357.463598)
		(end 403.14118 -357.75773)
		(width 0.13462)
		(layer "F.Cu")
		(net "P5E_PEX3_STN5_TX_C_DN<95>")
	)
	(segment
		(start 402.347938 -359.5878)
		(end 402.85035 -358.460294)
		(width 0.1651)
		(layer "In13.Cu")
		(net "P5E_PEX3_STN5_TX_C_DN<95>")
	)
	(segment
		(start 402.85035 -358.460294)
		(end 402.85035 -358.04856)
		(width 0.1651)
		(layer "In13.Cu")
		(net "P5E_PEX3_STN5_TX_C_DN<95>")
	)
	(segment
		(start 391.016998 -380.181104)
		(end 391.564114 -380.181104)
		(width 0.1651)
		(layer "In13.Cu")
		(net "P5E_PEX3_STN5_TX_C_DN<95>")
	)
	(segment
		(start 392.74623 -368.224054)
		(end 402.347684 -359.5878)
		(width 0.1651)
		(layer "In13.Cu")
		(net "P5E_PEX3_STN5_TX_C_DN<95>")
	)
	(segment
		(start 391.564114 -380.181104)
		(end 392.01598 -379.729238)
		(width 0.1651)
		(layer "In13.Cu")
		(net "P5E_PEX3_STN5_TX_C_DN<95>")
	)
	(segment
		(start 390.889998 -380.69012)
		(end 390.889998 -380.308104)
		(width 0.1651)
		(layer "In13.Cu")
		(net "P5E_PEX3_STN5_TX_C_DN<95>")
	)
	(segment
		(start 402.85035 -358.04856)
		(end 403.14118 -357.75773)
		(width 0.1651)
		(layer "In13.Cu")
		(net "P5E_PEX3_STN5_TX_C_DN<95>")
	)
	(segment
		(start 390.889998 -380.308104)
		(end 391.016998 -380.181104)
		(width 0.1651)
		(layer "In13.Cu")
		(net "P5E_PEX3_STN5_TX_C_DN<95>")
	)
	(segment
		(start 392.01598 -379.729238)
		(end 392.01598 -369.862608)
		(width 0.1651)
		(layer "In13.Cu")
		(net "P5E_PEX3_STN5_TX_C_DN<95>")
	)
	(segment
		(start 392.01598 -369.862608)
		(end 392.74623 -368.224054)
		(width 0.1651)
		(layer "In13.Cu")
		(net "P5E_PEX3_STN5_TX_C_DN<95>")
	)
	(segment
		(start 402.347684 -359.5878)
		(end 402.347938 -359.5878)
		(width 0.1651)
		(layer "In13.Cu")
		(net "P5E_PEX3_STN5_TX_C_DN<95>")
	)
	(segment
		(start 75.620626 -87.479632)
		(end 75.620626 -86.247986)
		(width 0.13208)
		(layer "F.Cu")
		(net "RST_HP_NIC1_N")
	)
	(segment
		(start 77.03439 -87.599012)
		(end 75.740006 -87.599012)
		(width 0.13208)
		(layer "F.Cu")
		(net "RST_HP_NIC1_N")
	)
	(segment
		(start 75.946254 -85.426296)
		(end 78.899512 -85.426296)
		(width 0.13208)
		(layer "F.Cu")
		(net "RST_HP_NIC1_N")
	)
	(segment
		(start 75.740006 -87.599012)
		(end 75.620626 -87.479632)
		(width 0.13208)
		(layer "F.Cu")
		(net "RST_HP_NIC1_N")
	)
	(segment
		(start 75.620626 -85.751924)
		(end 75.946254 -85.426296)
		(width 0.13208)
		(layer "F.Cu")
		(net "RST_HP_NIC1_N")
	)
	(segment
		(start 75.620626 -86.247986)
		(end 75.620626 -85.751924)
		(width 0.13208)
		(layer "F.Cu")
		(net "RST_HP_NIC1_N")
	)
	(via
		(at 75.620626 -86.247986)
		(size 0.508)
		(drill 0.254)
		(layers "F.Cu" "B.Cu")
		(net "RST_HP_NIC1_N")
	)
	(segment
		(start 278.242268 -118.154958)
		(end 272.591022 -118.154958)
		(width 0.13208)
		(layer "F.Cu")
		(net "PRSNTB0_NIC4_N")
	)
	(segment
		(start 271.76095 -118.154958)
		(end 271.360392 -117.7544)
		(width 0.13208)
		(layer "F.Cu")
		(net "PRSNTB0_NIC4_N")
	)
	(segment
		(start 271.360392 -116.7384)
		(end 271.360392 -117.7544)
		(width 0.13208)
		(layer "F.Cu")
		(net "PRSNTB0_NIC4_N")
	)
	(segment
		(start 272.591022 -118.154958)
		(end 271.76095 -118.154958)
		(width 0.13208)
		(layer "F.Cu")
		(net "PRSNTB0_NIC4_N")
	)
	(via
		(at 272.591022 -118.154958)
		(size 0.762)
		(drill 0.381)
		(layers "F.Cu" "B.Cu")
		(net "PRSNTB0_NIC4_N")
	)
	(segment
		(start 50.64252 -119.355108)
		(end 51.130454 -119.355108)
		(width 0.13462)
		(layer "F.Cu")
		(net "P5E_PEX0_STN1_RX_DP<24>")
	)
	(segment
		(start 51.130454 -119.355108)
		(end 51.293268 -119.517922)
		(width 0.13462)
		(layer "F.Cu")
		(net "P5E_PEX0_STN1_RX_DP<24>")
	)
	(segment
		(start 51.293268 -119.517922)
		(end 53.801772 -119.517922)
		(width 0.13462)
		(layer "F.Cu")
		(net "P5E_PEX0_STN1_RX_DP<24>")
	)
	(segment
		(start 53.801772 -119.517922)
		(end 54.09692 -119.222774)
		(width 0.13462)
		(layer "F.Cu")
		(net "P5E_PEX0_STN1_RX_DP<24>")
	)
	(segment
		(start 67.249548 -273.784314)
		(end 67.249548 -274.049744)
		(width 0.1143)
		(layer "In5.Cu")
		(net "P5E_PEX0_STN1_RX_DP<24>")
	)
	(segment
		(start 66.633852 -271.773904)
		(end 66.633852 -271.802352)
		(width 0.1143)
		(layer "In5.Cu")
		(net "P5E_PEX0_STN1_RX_DP<24>")
	)
	(segment
		(start 37.506656 -163.938458)
		(end 66.633852 -268.419834)
		(width 0.1651)
		(layer "In5.Cu")
		(net "P5E_PEX0_STN1_RX_DP<24>")
	)
	(segment
		(start 66.633852 -271.802352)
		(end 66.679572 -271.848072)
		(width 0.1143)
		(layer "In5.Cu")
		(net "P5E_PEX0_STN1_RX_DP<24>")
	)
	(segment
		(start 42.774108 -127.992124)
		(end 42.421556 -128.909064)
		(width 0.1651)
		(layer "In5.Cu")
		(net "P5E_PEX0_STN1_RX_DP<24>")
	)
	(segment
		(start 54.09692 -119.222774)
		(end 53.80609 -119.513604)
		(width 0.1651)
		(layer "In5.Cu")
		(net "P5E_PEX0_STN1_RX_DP<24>")
	)
	(segment
		(start 39.298626 -140.622274)
		(end 37.247068 -145.16735)
		(width 0.1651)
		(layer "In5.Cu")
		(net "P5E_PEX0_STN1_RX_DP<24>")
	)
	(segment
		(start 66.679572 -273.45513)
		(end 66.894456 -273.670014)
		(width 0.1143)
		(layer "In5.Cu")
		(net "P5E_PEX0_STN1_RX_DP<24>")
	)
	(segment
		(start 42.421556 -128.909064)
		(end 41.002966 -137.613898)
		(width 0.1651)
		(layer "In5.Cu")
		(net "P5E_PEX0_STN1_RX_DP<24>")
	)
	(segment
		(start 36.502848 -158.20644)
		(end 37.506656 -163.938458)
		(width 0.1651)
		(layer "In5.Cu")
		(net "P5E_PEX0_STN1_RX_DP<24>")
	)
	(segment
		(start 66.633852 -268.419834)
		(end 66.633852 -271.773904)
		(width 0.1651)
		(layer "In5.Cu")
		(net "P5E_PEX0_STN1_RX_DP<24>")
	)
	(segment
		(start 53.80609 -119.513604)
		(end 52.057046 -119.513604)
		(width 0.1651)
		(layer "In5.Cu")
		(net "P5E_PEX0_STN1_RX_DP<24>")
	)
	(segment
		(start 36.066984 -151.562054)
		(end 36.502848 -158.20644)
		(width 0.1651)
		(layer "In5.Cu")
		(net "P5E_PEX0_STN1_RX_DP<24>")
	)
	(segment
		(start 50.012092 -120.150382)
		(end 44.396406 -125.476508)
		(width 0.1651)
		(layer "In5.Cu")
		(net "P5E_PEX0_STN1_RX_DP<24>")
	)
	(segment
		(start 37.247068 -145.16735)
		(end 36.066984 -151.562054)
		(width 0.1651)
		(layer "In5.Cu")
		(net "P5E_PEX0_STN1_RX_DP<24>")
	)
	(segment
		(start 41.002966 -137.613898)
		(end 39.298626 -140.622274)
		(width 0.1651)
		(layer "In5.Cu")
		(net "P5E_PEX0_STN1_RX_DP<24>")
	)
	(segment
		(start 44.396406 -125.476508)
		(end 42.774108 -127.992124)
		(width 0.1651)
		(layer "In5.Cu")
		(net "P5E_PEX0_STN1_RX_DP<24>")
	)
	(segment
		(start 52.057046 -119.513604)
		(end 50.012092 -120.150382)
		(width 0.1651)
		(layer "In5.Cu")
		(net "P5E_PEX0_STN1_RX_DP<24>")
	)
	(segment
		(start 66.679572 -271.848072)
		(end 66.679572 -273.45513)
		(width 0.1143)
		(layer "In5.Cu")
		(net "P5E_PEX0_STN1_RX_DP<24>")
	)
	(segment
		(start 67.135248 -273.670014)
		(end 67.249548 -273.784314)
		(width 0.1143)
		(layer "In5.Cu")
		(net "P5E_PEX0_STN1_RX_DP<24>")
	)
	(segment
		(start 66.894456 -273.670014)
		(end 67.135248 -273.670014)
		(width 0.1143)
		(layer "In5.Cu")
		(net "P5E_PEX0_STN1_RX_DP<24>")
	)
	(segment
		(start 153.326084 -123.392184)
		(end 153.005028 -123.71324)
		(width 0.13462)
		(layer "F.Cu")
		(net "P5E_PEX1_STN1_TX_C_DN<26>")
	)
	(segment
		(start 162.14217 -123.554998)
		(end 161.654236 -123.554998)
		(width 0.13462)
		(layer "F.Cu")
		(net "P5E_PEX1_STN1_TX_C_DN<26>")
	)
	(segment
		(start 161.491422 -123.392184)
		(end 153.326084 -123.392184)
		(width 0.13462)
		(layer "F.Cu")
		(net "P5E_PEX1_STN1_TX_C_DN<26>")
	)
	(segment
		(start 161.654236 -123.554998)
		(end 161.491422 -123.392184)
		(width 0.13462)
		(layer "F.Cu")
		(net "P5E_PEX1_STN1_TX_C_DN<26>")
	)
	(segment
		(start 114.971068 -351.611438)
		(end 115.265708 -351.316798)
		(width 0.13462)
		(layer "F.Cu")
		(net "P5E_PEX1_STN6_TX_C_DP<110>")
	)
	(segment
		(start 115.265708 -350.685354)
		(end 114.945668 -350.365314)
		(width 0.13462)
		(layer "F.Cu")
		(net "P5E_PEX1_STN6_TX_C_DP<110>")
	)
	(segment
		(start 115.265708 -351.316798)
		(end 115.265708 -350.685354)
		(width 0.13462)
		(layer "F.Cu")
		(net "P5E_PEX1_STN6_TX_C_DP<110>")
	)
	(segment
		(start 108.317284 -365.874046)
		(end 113.69294 -354.004626)
		(width 0.1651)
		(layer "In13.Cu")
		(net "P5E_PEX1_STN6_TX_C_DP<110>")
	)
	(segment
		(start 108.195872 -384.083306)
		(end 108.317284 -365.874046)
		(width 0.1651)
		(layer "In13.Cu")
		(net "P5E_PEX1_STN6_TX_C_DP<110>")
	)
	(segment
		(start 118.984776 -395.202664)
		(end 117.472206 -393.690094)
		(width 0.1651)
		(layer "In13.Cu")
		(net "P5E_PEX1_STN6_TX_C_DP<110>")
	)
	(segment
		(start 109.03077 -387.089904)
		(end 108.195872 -384.083306)
		(width 0.1651)
		(layer "In13.Cu")
		(net "P5E_PEX1_STN6_TX_C_DP<110>")
	)
	(segment
		(start 118.11 -409.290012)
		(end 118.11 -409.672028)
		(width 0.1651)
		(layer "In13.Cu")
		(net "P5E_PEX1_STN6_TX_C_DP<110>")
	)
	(segment
		(start 117.472206 -393.690094)
		(end 114.239802 -392.351006)
		(width 0.1651)
		(layer "In13.Cu")
		(net "P5E_PEX1_STN6_TX_C_DP<110>")
	)
	(segment
		(start 118.237 -409.799028)
		(end 118.458488 -409.799028)
		(width 0.1651)
		(layer "In13.Cu")
		(net "P5E_PEX1_STN6_TX_C_DP<110>")
	)
	(segment
		(start 114.239802 -392.351006)
		(end 110.536228 -389.330692)
		(width 0.1651)
		(layer "In13.Cu")
		(net "P5E_PEX1_STN6_TX_C_DP<110>")
	)
	(segment
		(start 118.984776 -409.27274)
		(end 118.984776 -395.202664)
		(width 0.1651)
		(layer "In13.Cu")
		(net "P5E_PEX1_STN6_TX_C_DP<110>")
	)
	(segment
		(start 118.458488 -409.799028)
		(end 118.984776 -409.27274)
		(width 0.1651)
		(layer "In13.Cu")
		(net "P5E_PEX1_STN6_TX_C_DP<110>")
	)
	(segment
		(start 113.69294 -354.004626)
		(end 115.261898 -352.435668)
		(width 0.1651)
		(layer "In13.Cu")
		(net "P5E_PEX1_STN6_TX_C_DP<110>")
	)
	(segment
		(start 115.261898 -352.435668)
		(end 115.261898 -351.902268)
		(width 0.1651)
		(layer "In13.Cu")
		(net "P5E_PEX1_STN6_TX_C_DP<110>")
	)
	(segment
		(start 118.11 -409.672028)
		(end 118.237 -409.799028)
		(width 0.1651)
		(layer "In13.Cu")
		(net "P5E_PEX1_STN6_TX_C_DP<110>")
	)
	(segment
		(start 115.261898 -351.902268)
		(end 114.971068 -351.611438)
		(width 0.1651)
		(layer "In13.Cu")
		(net "P5E_PEX1_STN6_TX_C_DP<110>")
	)
	(segment
		(start 110.536228 -389.330692)
		(end 109.03077 -387.089904)
		(width 0.1651)
		(layer "In13.Cu")
		(net "P5E_PEX1_STN6_TX_C_DP<110>")
	)
	(segment
		(start 413.794956 -148.31568)
		(end 416.319462 -148.31568)
		(width 0.13462)
		(layer "F.Cu")
		(net "P5E_PEX3_STN0_RX_DN<11>")
	)
	(segment
		(start 416.319462 -148.31568)
		(end 416.47999 -148.155152)
		(width 0.13462)
		(layer "F.Cu")
		(net "P5E_PEX3_STN0_RX_DN<11>")
	)
	(segment
		(start 413.50311 -148.023834)
		(end 413.794956 -148.31568)
		(width 0.13462)
		(layer "F.Cu")
		(net "P5E_PEX3_STN0_RX_DN<11>")
	)
	(segment
		(start 416.47999 -148.155152)
		(end 416.95751 -148.155152)
		(width 0.13462)
		(layer "F.Cu")
		(net "P5E_PEX3_STN0_RX_DN<11>")
	)
	(segment
		(start 426.57014 -273.376136)
		(end 426.673518 -273.479514)
		(width 0.1143)
		(layer "In5.Cu")
		(net "P5E_PEX3_STN0_RX_DN<11>")
	)
	(segment
		(start 426.673518 -273.479514)
		(end 426.835316 -273.479514)
		(width 0.1143)
		(layer "In5.Cu")
		(net "P5E_PEX3_STN0_RX_DN<11>")
	)
	(segment
		(start 423.589958 -161.146236)
		(end 423.590212 -161.147506)
		(width 0.1651)
		(layer "In5.Cu")
		(net "P5E_PEX3_STN0_RX_DN<11>")
	)
	(segment
		(start 423.568368 -161.047684)
		(end 423.568876 -161.050224)
		(width 0.1651)
		(layer "In5.Cu")
		(net "P5E_PEX3_STN0_RX_DN<11>")
	)
	(segment
		(start 426.949616 -273.365214)
		(end 426.949616 -273.099784)
		(width 0.1143)
		(layer "In5.Cu")
		(net "P5E_PEX3_STN0_RX_DN<11>")
	)
	(segment
		(start 418.583872 -150.89632)
		(end 420.173658 -154.710638)
		(width 0.1651)
		(layer "In5.Cu")
		(net "P5E_PEX3_STN0_RX_DN<11>")
	)
	(segment
		(start 416.002216 -148.314664)
		(end 418.583872 -150.89632)
		(width 0.1651)
		(layer "In5.Cu")
		(net "P5E_PEX3_STN0_RX_DN<11>")
	)
	(segment
		(start 423.590212 -161.147506)
		(end 423.616882 -161.269172)
		(width 0.1651)
		(layer "In5.Cu")
		(net "P5E_PEX3_STN0_RX_DN<11>")
	)
	(segment
		(start 426.57014 -271.600168)
		(end 426.57014 -273.376136)
		(width 0.1143)
		(layer "In5.Cu")
		(net "P5E_PEX3_STN0_RX_DN<11>")
	)
	(segment
		(start 423.616882 -161.269172)
		(end 427.123098 -260.513576)
		(width 0.1651)
		(layer "In5.Cu")
		(net "P5E_PEX3_STN0_RX_DN<11>")
	)
	(segment
		(start 427.15815 -268.156182)
		(end 426.61586 -270.91513)
		(width 0.1651)
		(layer "In5.Cu")
		(net "P5E_PEX3_STN0_RX_DN<11>")
	)
	(segment
		(start 426.61586 -271.526)
		(end 426.61586 -271.554448)
		(width 0.1143)
		(layer "In5.Cu")
		(net "P5E_PEX3_STN0_RX_DN<11>")
	)
	(segment
		(start 426.61586 -270.91513)
		(end 426.61586 -271.526)
		(width 0.1651)
		(layer "In5.Cu")
		(net "P5E_PEX3_STN0_RX_DN<11>")
	)
	(segment
		(start 420.173658 -154.710638)
		(end 422.300908 -157.91053)
		(width 0.1651)
		(layer "In5.Cu")
		(net "P5E_PEX3_STN0_RX_DN<11>")
	)
	(segment
		(start 426.835316 -273.479514)
		(end 426.949616 -273.365214)
		(width 0.1143)
		(layer "In5.Cu")
		(net "P5E_PEX3_STN0_RX_DN<11>")
	)
	(segment
		(start 422.300908 -157.91053)
		(end 423.5196 -160.825434)
		(width 0.1651)
		(layer "In5.Cu")
		(net "P5E_PEX3_STN0_RX_DN<11>")
	)
	(segment
		(start 423.568876 -161.050224)
		(end 423.589958 -161.146236)
		(width 0.1651)
		(layer "In5.Cu")
		(net "P5E_PEX3_STN0_RX_DN<11>")
	)
	(segment
		(start 426.61586 -271.554448)
		(end 426.57014 -271.600168)
		(width 0.1143)
		(layer "In5.Cu")
		(net "P5E_PEX3_STN0_RX_DN<11>")
	)
	(segment
		(start 423.5196 -160.825434)
		(end 423.568368 -161.047684)
		(width 0.1651)
		(layer "In5.Cu")
		(net "P5E_PEX3_STN0_RX_DN<11>")
	)
	(segment
		(start 427.123098 -260.513576)
		(end 427.15815 -268.156182)
		(width 0.1651)
		(layer "In5.Cu")
		(net "P5E_PEX3_STN0_RX_DN<11>")
	)
	(segment
		(start 413.79394 -148.314664)
		(end 416.002216 -148.314664)
		(width 0.1651)
		(layer "In5.Cu")
		(net "P5E_PEX3_STN0_RX_DN<11>")
	)
	(segment
		(start 413.50311 -148.023834)
		(end 413.79394 -148.314664)
		(width 0.1651)
		(layer "In5.Cu")
		(net "P5E_PEX3_STN0_RX_DN<11>")
	)
	(segment
		(start 399.078704 -387.407658)
		(end 399.495772 -386.081778)
		(width 0.1651)
		(layer "In5.Cu")
		(net "P5E_PEX3_STN5_RX_DN<84>")
	)
	(segment
		(start 410.465778 -319.8876)
		(end 410.420058 -319.84188)
		(width 0.1143)
		(layer "In5.Cu")
		(net "P5E_PEX3_STN5_RX_DN<84>")
	)
	(segment
		(start 401.29587 -341.990934)
		(end 401.550632 -341.267034)
		(width 0.1651)
		(layer "In5.Cu")
		(net "P5E_PEX3_STN5_RX_DN<84>")
	)
	(segment
		(start 400.282918 -370.0272)
		(end 401.29587 -358.733852)
		(width 0.1651)
		(layer "In5.Cu")
		(net "P5E_PEX3_STN5_RX_DN<84>")
	)
	(segment
		(start 384.290062 -397.411956)
		(end 384.417062 -397.284956)
		(width 0.1651)
		(layer "In5.Cu")
		(net "P5E_PEX3_STN5_RX_DN<84>")
	)
	(segment
		(start 410.685488 -316.419992)
		(end 410.799788 -316.534292)
		(width 0.1143)
		(layer "In5.Cu")
		(net "P5E_PEX3_STN5_RX_DN<84>")
	)
	(segment
		(start 410.465778 -323.167502)
		(end 410.465778 -319.916048)
		(width 0.1651)
		(layer "In5.Cu")
		(net "P5E_PEX3_STN5_RX_DN<84>")
	)
	(segment
		(start 385.448048 -396.78737)
		(end 385.448048 -396.231364)
		(width 0.1651)
		(layer "In5.Cu")
		(net "P5E_PEX3_STN5_RX_DN<84>")
	)
	(segment
		(start 410.465778 -319.916048)
		(end 410.465778 -319.8876)
		(width 0.1143)
		(layer "In5.Cu")
		(net "P5E_PEX3_STN5_RX_DN<84>")
	)
	(segment
		(start 410.420058 -316.534292)
		(end 410.534358 -316.419992)
		(width 0.1143)
		(layer "In5.Cu")
		(net "P5E_PEX3_STN5_RX_DN<84>")
	)
	(segment
		(start 401.29587 -358.733852)
		(end 401.29587 -341.990934)
		(width 0.1651)
		(layer "In5.Cu")
		(net "P5E_PEX3_STN5_RX_DN<84>")
	)
	(segment
		(start 409.979114 -325.50481)
		(end 410.465778 -323.167502)
		(width 0.1651)
		(layer "In5.Cu")
		(net "P5E_PEX3_STN5_RX_DN<84>")
	)
	(segment
		(start 396.865602 -389.71093)
		(end 398.319244 -388.526782)
		(width 0.1651)
		(layer "In5.Cu")
		(net "P5E_PEX3_STN5_RX_DN<84>")
	)
	(segment
		(start 398.319244 -388.526782)
		(end 399.078704 -387.407658)
		(width 0.1651)
		(layer "In5.Cu")
		(net "P5E_PEX3_STN5_RX_DN<84>")
	)
	(segment
		(start 386.869686 -394.413994)
		(end 388.017258 -393.372594)
		(width 0.1651)
		(layer "In5.Cu")
		(net "P5E_PEX3_STN5_RX_DN<84>")
	)
	(segment
		(start 384.417062 -397.284956)
		(end 384.950462 -397.284956)
		(width 0.1651)
		(layer "In5.Cu")
		(net "P5E_PEX3_STN5_RX_DN<84>")
	)
	(segment
		(start 410.420058 -319.84188)
		(end 410.420058 -316.534292)
		(width 0.1143)
		(layer "In5.Cu")
		(net "P5E_PEX3_STN5_RX_DN<84>")
	)
	(segment
		(start 399.495772 -386.081778)
		(end 399.653506 -374.4087)
		(width 0.1651)
		(layer "In5.Cu")
		(net "P5E_PEX3_STN5_RX_DN<84>")
	)
	(segment
		(start 399.653506 -374.4087)
		(end 400.282918 -370.0272)
		(width 0.1651)
		(layer "In5.Cu")
		(net "P5E_PEX3_STN5_RX_DN<84>")
	)
	(segment
		(start 384.950462 -397.284956)
		(end 385.448048 -396.78737)
		(width 0.1651)
		(layer "In5.Cu")
		(net "P5E_PEX3_STN5_RX_DN<84>")
	)
	(segment
		(start 410.534358 -316.419992)
		(end 410.685488 -316.419992)
		(width 0.1143)
		(layer "In5.Cu")
		(net "P5E_PEX3_STN5_RX_DN<84>")
	)
	(segment
		(start 408.93365 -327.907142)
		(end 409.979114 -325.50481)
		(width 0.1651)
		(layer "In5.Cu")
		(net "P5E_PEX3_STN5_RX_DN<84>")
	)
	(segment
		(start 401.550632 -341.267034)
		(end 408.93365 -327.907142)
		(width 0.1651)
		(layer "In5.Cu")
		(net "P5E_PEX3_STN5_RX_DN<84>")
	)
	(segment
		(start 385.448048 -396.231364)
		(end 386.869686 -394.413994)
		(width 0.1651)
		(layer "In5.Cu")
		(net "P5E_PEX3_STN5_RX_DN<84>")
	)
	(segment
		(start 384.290062 -397.790162)
		(end 384.290062 -397.411956)
		(width 0.1651)
		(layer "In5.Cu")
		(net "P5E_PEX3_STN5_RX_DN<84>")
	)
	(segment
		(start 388.017258 -393.372594)
		(end 396.865602 -389.71093)
		(width 0.1651)
		(layer "In5.Cu")
		(net "P5E_PEX3_STN5_RX_DN<84>")
	)
	(segment
		(start 410.799788 -316.534292)
		(end 410.799788 -316.799722)
		(width 0.1143)
		(layer "In5.Cu")
		(net "P5E_PEX3_STN5_RX_DN<84>")
	)
	(segment
		(start 274.338796 -160.245044)
		(end 272.591784 -160.245044)
		(width 0.13208)
		(layer "F.Cu")
		(net "NIC4_MAIN_PWR_EN_R")
	)
	(segment
		(start 271.75714 -159.4104)
		(end 271.207992 -159.4104)
		(width 0.13208)
		(layer "F.Cu")
		(net "NIC4_MAIN_PWR_EN_R")
	)
	(segment
		(start 276.823932 -157.759908)
		(end 274.338796 -160.245044)
		(width 0.13208)
		(layer "F.Cu")
		(net "NIC4_MAIN_PWR_EN_R")
	)
	(segment
		(start 278.242268 -157.759908)
		(end 276.823932 -157.759908)
		(width 0.13208)
		(layer "F.Cu")
		(net "NIC4_MAIN_PWR_EN_R")
	)
	(segment
		(start 272.591784 -160.245044)
		(end 271.75714 -159.4104)
		(width 0.13208)
		(layer "F.Cu")
		(net "NIC4_MAIN_PWR_EN_R")
	)
	(via
		(at 272.591784 -160.245044)
		(size 0.762)
		(drill 0.381)
		(layers "F.Cu" "B.Cu")
		(net "NIC4_MAIN_PWR_EN_R")
	)
	(segment
		(start 36.905184 -105.609898)
		(end 37.232844 -105.282238)
		(width 0.13462)
		(layer "F.Cu")
		(net "P5E_PEX0_STN1_TX_C_DP<19>")
	)
	(segment
		(start 45.554392 -105.445052)
		(end 46.042326 -105.445052)
		(width 0.13462)
		(layer "F.Cu")
		(net "P5E_PEX0_STN1_TX_C_DP<19>")
	)
	(segment
		(start 37.232844 -105.282238)
		(end 45.391578 -105.282238)
		(width 0.13462)
		(layer "F.Cu")
		(net "P5E_PEX0_STN1_TX_C_DP<19>")
	)
	(segment
		(start 45.391578 -105.282238)
		(end 45.554392 -105.445052)
		(width 0.13462)
		(layer "F.Cu")
		(net "P5E_PEX0_STN1_TX_C_DP<19>")
	)
	(segment
		(start 166.742364 -103.644954)
		(end 167.230298 -103.644954)
		(width 0.13462)
		(layer "F.Cu")
		(net "P5E_PEX1_STN1_RX_DN<18>")
	)
	(segment
		(start 167.393112 -103.48214)
		(end 169.901616 -103.48214)
		(width 0.13462)
		(layer "F.Cu")
		(net "P5E_PEX1_STN1_RX_DN<18>")
	)
	(segment
		(start 167.230298 -103.644954)
		(end 167.393112 -103.48214)
		(width 0.13462)
		(layer "F.Cu")
		(net "P5E_PEX1_STN1_RX_DN<18>")
	)
	(segment
		(start 169.902124 -103.481632)
		(end 170.196764 -103.776272)
		(width 0.13462)
		(layer "F.Cu")
		(net "P5E_PEX1_STN1_RX_DN<18>")
	)
	(segment
		(start 169.901616 -103.48214)
		(end 169.902124 -103.481632)
		(width 0.13462)
		(layer "F.Cu")
		(net "P5E_PEX1_STN1_RX_DN<18>")
	)
	(segment
		(start 162.046158 -106.591862)
		(end 161.002472 -107.127294)
		(width 0.1651)
		(layer "In5.Cu")
		(net "P5E_PEX1_STN1_RX_DN<18>")
	)
	(segment
		(start 177.270156 -273.376136)
		(end 177.373534 -273.479514)
		(width 0.1143)
		(layer "In5.Cu")
		(net "P5E_PEX1_STN1_RX_DN<18>")
	)
	(segment
		(start 159.696404 -108.660946)
		(end 159.354012 -109.01934)
		(width 0.1651)
		(layer "In5.Cu")
		(net "P5E_PEX1_STN1_RX_DN<18>")
	)
	(segment
		(start 150.172928 -118.469918)
		(end 149.214332 -120.46712)
		(width 0.1651)
		(layer "In5.Cu")
		(net "P5E_PEX1_STN1_RX_DN<18>")
	)
	(segment
		(start 159.192468 -109.02315)
		(end 158.850584 -109.38129)
		(width 0.1651)
		(layer "In5.Cu")
		(net "P5E_PEX1_STN1_RX_DN<18>")
	)
	(segment
		(start 163.284916 -106.084878)
		(end 163.130992 -106.035348)
		(width 0.1651)
		(layer "In5.Cu")
		(net "P5E_PEX1_STN1_RX_DN<18>")
	)
	(segment
		(start 148.163788 -165.241986)
		(end 177.315876 -269.734284)
		(width 0.1651)
		(layer "In5.Cu")
		(net "P5E_PEX1_STN1_RX_DN<18>")
	)
	(segment
		(start 160.538414 -107.779058)
		(end 160.196022 -108.137452)
		(width 0.1651)
		(layer "In5.Cu")
		(net "P5E_PEX1_STN1_RX_DN<18>")
	)
	(segment
		(start 163.130992 -106.035348)
		(end 162.690302 -106.261408)
		(width 0.1651)
		(layer "In5.Cu")
		(net "P5E_PEX1_STN1_RX_DN<18>")
	)
	(segment
		(start 159.354012 -109.01934)
		(end 159.192468 -109.02315)
		(width 0.1651)
		(layer "In5.Cu")
		(net "P5E_PEX1_STN1_RX_DN<18>")
	)
	(segment
		(start 149.214332 -120.46712)
		(end 148.086318 -126.637796)
		(width 0.1651)
		(layer "In5.Cu")
		(net "P5E_PEX1_STN1_RX_DN<18>")
	)
	(segment
		(start 160.034478 -108.141262)
		(end 159.692594 -108.499402)
		(width 0.1651)
		(layer "In5.Cu")
		(net "P5E_PEX1_STN1_RX_DN<18>")
	)
	(segment
		(start 160.534604 -107.61726)
		(end 160.538414 -107.779058)
		(width 0.1651)
		(layer "In5.Cu")
		(net "P5E_PEX1_STN1_RX_DN<18>")
	)
	(segment
		(start 167.029638 -104.034336)
		(end 167.029638 -104.034082)
		(width 0.1651)
		(layer "In5.Cu")
		(net "P5E_PEX1_STN1_RX_DN<18>")
	)
	(segment
		(start 169.905934 -103.485442)
		(end 168.099232 -103.485442)
		(width 0.1651)
		(layer "In5.Cu")
		(net "P5E_PEX1_STN1_RX_DN<18>")
	)
	(segment
		(start 177.315876 -271.554448)
		(end 177.270156 -271.600168)
		(width 0.1143)
		(layer "In5.Cu")
		(net "P5E_PEX1_STN1_RX_DN<18>")
	)
	(segment
		(start 177.649632 -273.365214)
		(end 177.649632 -273.099784)
		(width 0.1143)
		(layer "In5.Cu")
		(net "P5E_PEX1_STN1_RX_DN<18>")
	)
	(segment
		(start 166.539418 -104.414574)
		(end 166.385494 -104.365044)
		(width 0.1651)
		(layer "In5.Cu")
		(net "P5E_PEX1_STN1_RX_DN<18>")
	)
	(segment
		(start 147.042124 -158.75762)
		(end 148.163788 -165.241986)
		(width 0.1651)
		(layer "In5.Cu")
		(net "P5E_PEX1_STN1_RX_DN<18>")
	)
	(segment
		(start 158.512002 -109.901228)
		(end 158.350458 -109.905038)
		(width 0.1651)
		(layer "In5.Cu")
		(net "P5E_PEX1_STN1_RX_DN<18>")
	)
	(segment
		(start 170.196764 -103.776272)
		(end 169.905934 -103.485442)
		(width 0.1651)
		(layer "In5.Cu")
		(net "P5E_PEX1_STN1_RX_DN<18>")
	)
	(segment
		(start 162.641026 -106.415078)
		(end 162.199828 -106.641392)
		(width 0.1651)
		(layer "In5.Cu")
		(net "P5E_PEX1_STN1_RX_DN<18>")
	)
	(segment
		(start 160.196022 -108.137452)
		(end 160.034478 -108.141262)
		(width 0.1651)
		(layer "In5.Cu")
		(net "P5E_PEX1_STN1_RX_DN<18>")
	)
	(segment
		(start 161.002472 -107.127294)
		(end 160.534604 -107.61726)
		(width 0.1651)
		(layer "In5.Cu")
		(net "P5E_PEX1_STN1_RX_DN<18>")
	)
	(segment
		(start 158.350458 -109.905038)
		(end 150.172928 -118.469918)
		(width 0.1651)
		(layer "In5.Cu")
		(net "P5E_PEX1_STN1_RX_DN<18>")
	)
	(segment
		(start 165.895528 -104.745028)
		(end 165.454584 -104.971342)
		(width 0.1651)
		(layer "In5.Cu")
		(net "P5E_PEX1_STN1_RX_DN<18>")
	)
	(segment
		(start 164.36975 -105.52811)
		(end 164.215826 -105.47858)
		(width 0.1651)
		(layer "In5.Cu")
		(net "P5E_PEX1_STN1_RX_DN<18>")
	)
	(segment
		(start 177.270156 -271.600168)
		(end 177.270156 -273.376136)
		(width 0.1143)
		(layer "In5.Cu")
		(net "P5E_PEX1_STN1_RX_DN<18>")
	)
	(segment
		(start 177.315876 -271.526)
		(end 177.315876 -271.554448)
		(width 0.1143)
		(layer "In5.Cu")
		(net "P5E_PEX1_STN1_RX_DN<18>")
	)
	(segment
		(start 165.945058 -104.591104)
		(end 165.895528 -104.745028)
		(width 0.1651)
		(layer "In5.Cu")
		(net "P5E_PEX1_STN1_RX_DN<18>")
	)
	(segment
		(start 177.535332 -273.479514)
		(end 177.649632 -273.365214)
		(width 0.1143)
		(layer "In5.Cu")
		(net "P5E_PEX1_STN1_RX_DN<18>")
	)
	(segment
		(start 146.484594 -150.341584)
		(end 147.042124 -158.75762)
		(width 0.1651)
		(layer "In5.Cu")
		(net "P5E_PEX1_STN1_RX_DN<18>")
	)
	(segment
		(start 177.315876 -269.734284)
		(end 177.315876 -271.526)
		(width 0.1651)
		(layer "In5.Cu")
		(net "P5E_PEX1_STN1_RX_DN<18>")
	)
	(segment
		(start 167.029638 -104.034082)
		(end 166.980362 -104.188006)
		(width 0.1651)
		(layer "In5.Cu")
		(net "P5E_PEX1_STN1_RX_DN<18>")
	)
	(segment
		(start 162.199828 -106.641392)
		(end 162.046158 -106.591862)
		(width 0.1651)
		(layer "In5.Cu")
		(net "P5E_PEX1_STN1_RX_DN<18>")
	)
	(segment
		(start 148.086318 -126.637796)
		(end 146.484594 -150.341584)
		(width 0.1651)
		(layer "In5.Cu")
		(net "P5E_PEX1_STN1_RX_DN<18>")
	)
	(segment
		(start 166.980362 -104.188006)
		(end 166.539418 -104.414574)
		(width 0.1651)
		(layer "In5.Cu")
		(net "P5E_PEX1_STN1_RX_DN<18>")
	)
	(segment
		(start 165.454584 -104.971342)
		(end 165.30066 -104.921812)
		(width 0.1651)
		(layer "In5.Cu")
		(net "P5E_PEX1_STN1_RX_DN<18>")
	)
	(segment
		(start 162.690302 -106.261408)
		(end 162.641026 -106.415078)
		(width 0.1651)
		(layer "In5.Cu")
		(net "P5E_PEX1_STN1_RX_DN<18>")
	)
	(segment
		(start 168.099232 -103.485442)
		(end 167.029638 -104.034336)
		(width 0.1651)
		(layer "In5.Cu")
		(net "P5E_PEX1_STN1_RX_DN<18>")
	)
	(segment
		(start 163.77539 -105.70464)
		(end 163.72586 -105.85831)
		(width 0.1651)
		(layer "In5.Cu")
		(net "P5E_PEX1_STN1_RX_DN<18>")
	)
	(segment
		(start 177.373534 -273.479514)
		(end 177.535332 -273.479514)
		(width 0.1143)
		(layer "In5.Cu")
		(net "P5E_PEX1_STN1_RX_DN<18>")
	)
	(segment
		(start 164.215826 -105.47858)
		(end 163.77539 -105.70464)
		(width 0.1651)
		(layer "In5.Cu")
		(net "P5E_PEX1_STN1_RX_DN<18>")
	)
	(segment
		(start 164.810694 -105.301796)
		(end 164.36975 -105.52811)
		(width 0.1651)
		(layer "In5.Cu")
		(net "P5E_PEX1_STN1_RX_DN<18>")
	)
	(segment
		(start 166.385494 -104.365044)
		(end 165.945058 -104.591104)
		(width 0.1651)
		(layer "In5.Cu")
		(net "P5E_PEX1_STN1_RX_DN<18>")
	)
	(segment
		(start 163.72586 -105.85831)
		(end 163.284916 -106.084878)
		(width 0.1651)
		(layer "In5.Cu")
		(net "P5E_PEX1_STN1_RX_DN<18>")
	)
	(segment
		(start 158.854394 -109.542834)
		(end 158.512002 -109.901228)
		(width 0.1651)
		(layer "In5.Cu")
		(net "P5E_PEX1_STN1_RX_DN<18>")
	)
	(segment
		(start 165.30066 -104.921812)
		(end 164.860224 -105.147872)
		(width 0.1651)
		(layer "In5.Cu")
		(net "P5E_PEX1_STN1_RX_DN<18>")
	)
	(segment
		(start 158.850584 -109.38129)
		(end 158.854394 -109.542834)
		(width 0.1651)
		(layer "In5.Cu")
		(net "P5E_PEX1_STN1_RX_DN<18>")
	)
	(segment
		(start 164.860224 -105.147872)
		(end 164.810694 -105.301796)
		(width 0.1651)
		(layer "In5.Cu")
		(net "P5E_PEX1_STN1_RX_DN<18>")
	)
	(segment
		(start 159.692594 -108.499402)
		(end 159.696404 -108.660946)
		(width 0.1651)
		(layer "In5.Cu")
		(net "P5E_PEX1_STN1_RX_DN<18>")
	)
	(segment
		(start 115.265708 -356.831646)
		(end 114.945668 -356.511606)
		(width 0.13462)
		(layer "F.Cu")
		(net "P5E_PEX1_STN6_TX_C_DP<101>")
	)
	(segment
		(start 114.971068 -357.75773)
		(end 115.265708 -357.46309)
		(width 0.13462)
		(layer "F.Cu")
		(net "P5E_PEX1_STN6_TX_C_DP<101>")
	)
	(segment
		(start 115.265708 -357.46309)
		(end 115.265708 -356.831646)
		(width 0.13462)
		(layer "F.Cu")
		(net "P5E_PEX1_STN6_TX_C_DP<101>")
	)
	(segment
		(start 120.669304 -382.699006)
		(end 121.087642 -382.280668)
		(width 0.1651)
		(layer "In7.Cu")
		(net "P5E_PEX1_STN6_TX_C_DP<101>")
	)
	(segment
		(start 121.087642 -369.3414)
		(end 120.7262 -367.9698)
		(width 0.1651)
		(layer "In7.Cu")
		(net "P5E_PEX1_STN6_TX_C_DP<101>")
	)
	(segment
		(start 120.437148 -382.699006)
		(end 120.669304 -382.699006)
		(width 0.1651)
		(layer "In7.Cu")
		(net "P5E_PEX1_STN6_TX_C_DP<101>")
	)
	(segment
		(start 119.64797 -366.389412)
		(end 119.6721 -366.284256)
		(width 0.1651)
		(layer "In7.Cu")
		(net "P5E_PEX1_STN6_TX_C_DP<101>")
	)
	(segment
		(start 121.087642 -382.280668)
		(end 121.087642 -369.3414)
		(width 0.1651)
		(layer "In7.Cu")
		(net "P5E_PEX1_STN6_TX_C_DP<101>")
	)
	(segment
		(start 118.459758 -364.345728)
		(end 115.468654 -359.562908)
		(width 0.1651)
		(layer "In7.Cu")
		(net "P5E_PEX1_STN6_TX_C_DP<101>")
	)
	(segment
		(start 115.261898 -358.04856)
		(end 114.971068 -357.75773)
		(width 0.1651)
		(layer "In7.Cu")
		(net "P5E_PEX1_STN6_TX_C_DP<101>")
	)
	(segment
		(start 115.468654 -359.562908)
		(end 115.261898 -358.235504)
		(width 0.1651)
		(layer "In7.Cu")
		(net "P5E_PEX1_STN6_TX_C_DP<101>")
	)
	(segment
		(start 118.435374 -364.450884)
		(end 118.459758 -364.345728)
		(width 0.1651)
		(layer "In7.Cu")
		(net "P5E_PEX1_STN6_TX_C_DP<101>")
	)
	(segment
		(start 120.310148 -382.18999)
		(end 120.310148 -382.572006)
		(width 0.1651)
		(layer "In7.Cu")
		(net "P5E_PEX1_STN6_TX_C_DP<101>")
	)
	(segment
		(start 115.261898 -358.235504)
		(end 115.261898 -358.04856)
		(width 0.1651)
		(layer "In7.Cu")
		(net "P5E_PEX1_STN6_TX_C_DP<101>")
	)
	(segment
		(start 118.80342 -364.89513)
		(end 118.698264 -364.871)
		(width 0.1651)
		(layer "In7.Cu")
		(net "P5E_PEX1_STN6_TX_C_DP<101>")
	)
	(segment
		(start 119.065802 -365.314992)
		(end 118.80342 -364.89513)
		(width 0.1651)
		(layer "In7.Cu")
		(net "P5E_PEX1_STN6_TX_C_DP<101>")
	)
	(segment
		(start 119.409718 -365.864394)
		(end 119.304562 -365.840264)
		(width 0.1651)
		(layer "In7.Cu")
		(net "P5E_PEX1_STN6_TX_C_DP<101>")
	)
	(segment
		(start 120.7262 -367.9698)
		(end 120.015762 -366.833658)
		(width 0.1651)
		(layer "In7.Cu")
		(net "P5E_PEX1_STN6_TX_C_DP<101>")
	)
	(segment
		(start 120.310148 -382.572006)
		(end 120.437148 -382.699006)
		(width 0.1651)
		(layer "In7.Cu")
		(net "P5E_PEX1_STN6_TX_C_DP<101>")
	)
	(segment
		(start 118.698264 -364.871)
		(end 118.435374 -364.450884)
		(width 0.1651)
		(layer "In7.Cu")
		(net "P5E_PEX1_STN6_TX_C_DP<101>")
	)
	(segment
		(start 119.91086 -366.809528)
		(end 119.64797 -366.389412)
		(width 0.1651)
		(layer "In7.Cu")
		(net "P5E_PEX1_STN6_TX_C_DP<101>")
	)
	(segment
		(start 119.041672 -365.420148)
		(end 119.065802 -365.314992)
		(width 0.1651)
		(layer "In7.Cu")
		(net "P5E_PEX1_STN6_TX_C_DP<101>")
	)
	(segment
		(start 120.015762 -366.833658)
		(end 119.91086 -366.809528)
		(width 0.1651)
		(layer "In7.Cu")
		(net "P5E_PEX1_STN6_TX_C_DP<101>")
	)
	(segment
		(start 119.304562 -365.840264)
		(end 119.041672 -365.420148)
		(width 0.1651)
		(layer "In7.Cu")
		(net "P5E_PEX1_STN6_TX_C_DP<101>")
	)
	(segment
		(start 119.6721 -366.284256)
		(end 119.409718 -365.864394)
		(width 0.1651)
		(layer "In7.Cu")
		(net "P5E_PEX1_STN6_TX_C_DP<101>")
	)
	(segment
		(start 416.478212 -146.955002)
		(end 416.95751 -146.955002)
		(width 0.13462)
		(layer "F.Cu")
		(net "P5E_PEX3_STN0_RX_DP<10>")
	)
	(segment
		(start 416.30981 -146.7866)
		(end 416.478212 -146.955002)
		(width 0.13462)
		(layer "F.Cu")
		(net "P5E_PEX3_STN0_RX_DP<10>")
	)
	(segment
		(start 415.35731 -147.087336)
		(end 415.658046 -146.7866)
		(width 0.13462)
		(layer "F.Cu")
		(net "P5E_PEX3_STN0_RX_DP<10>")
	)
	(segment
		(start 415.658046 -146.7866)
		(end 416.30981 -146.7866)
		(width 0.13462)
		(layer "F.Cu")
		(net "P5E_PEX3_STN0_RX_DP<10>")
	)
	(segment
		(start 422.916604 -156.139388)
		(end 423.201084 -156.583888)
		(width 0.1651)
		(layer "In5.Cu")
		(net "P5E_PEX3_STN0_RX_DP<10>")
	)
	(segment
		(start 427.28388 -271.570958)
		(end 427.28388 -271.599406)
		(width 0.1143)
		(layer "In5.Cu")
		(net "P5E_PEX3_STN0_RX_DP<10>")
	)
	(segment
		(start 417.699952 -148.367496)
		(end 417.976304 -148.778468)
		(width 0.1651)
		(layer "In5.Cu")
		(net "P5E_PEX3_STN0_RX_DP<10>")
	)
	(segment
		(start 419.31209 -150.765256)
		(end 420.239444 -153.04135)
		(width 0.1651)
		(layer "In5.Cu")
		(net "P5E_PEX3_STN0_RX_DP<10>")
	)
	(segment
		(start 420.239444 -153.04135)
		(end 421.966898 -155.363164)
		(width 0.1651)
		(layer "In5.Cu")
		(net "P5E_PEX3_STN0_RX_DP<10>")
	)
	(segment
		(start 415.64814 -146.796506)
		(end 416.128962 -146.796506)
		(width 0.1651)
		(layer "In5.Cu")
		(net "P5E_PEX3_STN0_RX_DP<10>")
	)
	(segment
		(start 415.35731 -147.087336)
		(end 415.64814 -146.796506)
		(width 0.1651)
		(layer "In5.Cu")
		(net "P5E_PEX3_STN0_RX_DP<10>")
	)
	(segment
		(start 416.829494 -147.622768)
		(end 416.955224 -147.622768)
		(width 0.1651)
		(layer "In5.Cu")
		(net "P5E_PEX3_STN0_RX_DP<10>")
	)
	(segment
		(start 416.478974 -147.272248)
		(end 416.829494 -147.622768)
		(width 0.1651)
		(layer "In5.Cu")
		(net "P5E_PEX3_STN0_RX_DP<10>")
	)
	(segment
		(start 418.35197 -149.337268)
		(end 419.31209 -150.765256)
		(width 0.1651)
		(layer "In5.Cu")
		(net "P5E_PEX3_STN0_RX_DP<10>")
	)
	(segment
		(start 427.544484 -275.570188)
		(end 427.785276 -275.570188)
		(width 0.1143)
		(layer "In5.Cu")
		(net "P5E_PEX3_STN0_RX_DP<10>")
	)
	(segment
		(start 421.966898 -155.363164)
		(end 422.916604 -156.139388)
		(width 0.1651)
		(layer "In5.Cu")
		(net "P5E_PEX3_STN0_RX_DP<10>")
	)
	(segment
		(start 427.28388 -271.599406)
		(end 427.3296 -271.645126)
		(width 0.1143)
		(layer "In5.Cu")
		(net "P5E_PEX3_STN0_RX_DP<10>")
	)
	(segment
		(start 427.28388 -271.013428)
		(end 427.28388 -271.570958)
		(width 0.1651)
		(layer "In5.Cu")
		(net "P5E_PEX3_STN0_RX_DP<10>")
	)
	(segment
		(start 427.3296 -271.645126)
		(end 427.3296 -275.355304)
		(width 0.1143)
		(layer "In5.Cu")
		(net "P5E_PEX3_STN0_RX_DP<10>")
	)
	(segment
		(start 423.749216 -158.81731)
		(end 423.749216 -158.817564)
		(width 0.1651)
		(layer "In5.Cu")
		(net "P5E_PEX3_STN0_RX_DP<10>")
	)
	(segment
		(start 416.128962 -146.796506)
		(end 416.478974 -147.146518)
		(width 0.1651)
		(layer "In5.Cu")
		(net "P5E_PEX3_STN0_RX_DP<10>")
	)
	(segment
		(start 427.845474 -268.155928)
		(end 427.28388 -271.013428)
		(width 0.1651)
		(layer "In5.Cu")
		(net "P5E_PEX3_STN0_RX_DP<10>")
	)
	(segment
		(start 424.297348 -161.050732)
		(end 427.810168 -260.49986)
		(width 0.1651)
		(layer "In5.Cu")
		(net "P5E_PEX3_STN0_RX_DP<10>")
	)
	(segment
		(start 427.3296 -275.355304)
		(end 427.544484 -275.570188)
		(width 0.1143)
		(layer "In5.Cu")
		(net "P5E_PEX3_STN0_RX_DP<10>")
	)
	(segment
		(start 427.899576 -275.684488)
		(end 427.899576 -275.949918)
		(width 0.1143)
		(layer "In5.Cu")
		(net "P5E_PEX3_STN0_RX_DP<10>")
	)
	(segment
		(start 417.95192 -148.901658)
		(end 418.228526 -149.313138)
		(width 0.1651)
		(layer "In5.Cu")
		(net "P5E_PEX3_STN0_RX_DP<10>")
	)
	(segment
		(start 416.955224 -147.622768)
		(end 417.699952 -148.367496)
		(width 0.1651)
		(layer "In5.Cu")
		(net "P5E_PEX3_STN0_RX_DP<10>")
	)
	(segment
		(start 423.201084 -156.583888)
		(end 423.749216 -158.81731)
		(width 0.1651)
		(layer "In5.Cu")
		(net "P5E_PEX3_STN0_RX_DP<10>")
	)
	(segment
		(start 416.478974 -147.146518)
		(end 416.478974 -147.272248)
		(width 0.1651)
		(layer "In5.Cu")
		(net "P5E_PEX3_STN0_RX_DP<10>")
	)
	(segment
		(start 427.785276 -275.570188)
		(end 427.899576 -275.684488)
		(width 0.1143)
		(layer "In5.Cu")
		(net "P5E_PEX3_STN0_RX_DP<10>")
	)
	(segment
		(start 418.228526 -149.313138)
		(end 418.35197 -149.337268)
		(width 0.1651)
		(layer "In5.Cu")
		(net "P5E_PEX3_STN0_RX_DP<10>")
	)
	(segment
		(start 417.976304 -148.778468)
		(end 417.95192 -148.901658)
		(width 0.1651)
		(layer "In5.Cu")
		(net "P5E_PEX3_STN0_RX_DP<10>")
	)
	(segment
		(start 423.749216 -158.817564)
		(end 424.297348 -161.050732)
		(width 0.1651)
		(layer "In5.Cu")
		(net "P5E_PEX3_STN0_RX_DP<10>")
	)
	(segment
		(start 427.810168 -260.49986)
		(end 427.845474 -268.155928)
		(width 0.1651)
		(layer "In5.Cu")
		(net "P5E_PEX3_STN0_RX_DP<10>")
	)
	(segment
		(start 419.349936 -318.434466)
		(end 419.349936 -318.699896)
		(width 0.1143)
		(layer "In15.Cu")
		(net "P5E_PEX3_STN5_RX_DN<93>")
	)
	(segment
		(start 386.616956 -372.381018)
		(end 387.164072 -372.381018)
		(width 0.1651)
		(layer "In15.Cu")
		(net "P5E_PEX3_STN5_RX_DN<93>")
	)
	(segment
		(start 418.970206 -318.423798)
		(end 419.073838 -318.320166)
		(width 0.1143)
		(layer "In15.Cu")
		(net "P5E_PEX3_STN5_RX_DN<93>")
	)
	(segment
		(start 387.164072 -372.381018)
		(end 387.615938 -371.929152)
		(width 0.1651)
		(layer "In15.Cu")
		(net "P5E_PEX3_STN5_RX_DN<93>")
	)
	(segment
		(start 419.015926 -319.969896)
		(end 419.015926 -319.941448)
		(width 0.1143)
		(layer "In15.Cu")
		(net "P5E_PEX3_STN5_RX_DN<93>")
	)
	(segment
		(start 387.615938 -371.929152)
		(end 387.615938 -369.552982)
		(width 0.1651)
		(layer "In15.Cu")
		(net "P5E_PEX3_STN5_RX_DN<93>")
	)
	(segment
		(start 387.865366 -368.971068)
		(end 400.680428 -359.31475)
		(width 0.1651)
		(layer "In15.Cu")
		(net "P5E_PEX3_STN5_RX_DN<93>")
	)
	(segment
		(start 419.073838 -318.320166)
		(end 419.235636 -318.320166)
		(width 0.1143)
		(layer "In15.Cu")
		(net "P5E_PEX3_STN5_RX_DN<93>")
	)
	(segment
		(start 401.762214 -341.056722)
		(end 417.36137 -325.17588)
		(width 0.1651)
		(layer "In15.Cu")
		(net "P5E_PEX3_STN5_RX_DN<93>")
	)
	(segment
		(start 387.615938 -369.552982)
		(end 387.865366 -368.971068)
		(width 0.1651)
		(layer "In15.Cu")
		(net "P5E_PEX3_STN5_RX_DN<93>")
	)
	(segment
		(start 419.015926 -322.675758)
		(end 419.015926 -319.969896)
		(width 0.1651)
		(layer "In15.Cu")
		(net "P5E_PEX3_STN5_RX_DN<93>")
	)
	(segment
		(start 401.29587 -358.08031)
		(end 401.29587 -342.171528)
		(width 0.1651)
		(layer "In15.Cu")
		(net "P5E_PEX3_STN5_RX_DN<93>")
	)
	(segment
		(start 417.36137 -325.17588)
		(end 419.015926 -322.675758)
		(width 0.1651)
		(layer "In15.Cu")
		(net "P5E_PEX3_STN5_RX_DN<93>")
	)
	(segment
		(start 419.015926 -319.941448)
		(end 418.970206 -319.895728)
		(width 0.1143)
		(layer "In15.Cu")
		(net "P5E_PEX3_STN5_RX_DN<93>")
	)
	(segment
		(start 419.235636 -318.320166)
		(end 419.349936 -318.434466)
		(width 0.1143)
		(layer "In15.Cu")
		(net "P5E_PEX3_STN5_RX_DN<93>")
	)
	(segment
		(start 386.489956 -372.508018)
		(end 386.616956 -372.381018)
		(width 0.1651)
		(layer "In15.Cu")
		(net "P5E_PEX3_STN5_RX_DN<93>")
	)
	(segment
		(start 400.680428 -359.31475)
		(end 401.29587 -358.08031)
		(width 0.1651)
		(layer "In15.Cu")
		(net "P5E_PEX3_STN5_RX_DN<93>")
	)
	(segment
		(start 418.970206 -319.895728)
		(end 418.970206 -318.423798)
		(width 0.1143)
		(layer "In15.Cu")
		(net "P5E_PEX3_STN5_RX_DN<93>")
	)
	(segment
		(start 386.489956 -372.890034)
		(end 386.489956 -372.508018)
		(width 0.1651)
		(layer "In15.Cu")
		(net "P5E_PEX3_STN5_RX_DN<93>")
	)
	(segment
		(start 401.29587 -342.171528)
		(end 401.762214 -341.056722)
		(width 0.1651)
		(layer "In15.Cu")
		(net "P5E_PEX3_STN5_RX_DN<93>")
	)
	(segment
		(start 282.842462 -154.159966)
		(end 283.888942 -154.159966)
		(width 0.13208)
		(layer "F.Cu")
		(net "NCSI_NIC4_TXD1")
	)
	(via
		(at 283.888942 -154.159966)
		(size 0.508)
		(drill 0.254)
		(layers "F.Cu" "B.Cu")
		(net "NCSI_NIC4_TXD1")
	)
	(segment
		(start 282.155392 -153.0096)
		(end 282.738576 -153.0096)
		(width 0.13208)
		(layer "B.Cu")
		(net "NCSI_NIC4_TXD1")
	)
	(segment
		(start 282.738576 -153.0096)
		(end 283.888942 -154.159966)
		(width 0.13208)
		(layer "B.Cu")
		(net "NCSI_NIC4_TXD1")
	)
	(segment
		(start 53.80228 -103.481632)
		(end 54.09692 -103.776272)
		(width 0.13462)
		(layer "F.Cu")
		(net "P5E_PEX0_STN1_RX_DN<18>")
	)
	(segment
		(start 53.801772 -103.48214)
		(end 53.80228 -103.481632)
		(width 0.13462)
		(layer "F.Cu")
		(net "P5E_PEX0_STN1_RX_DN<18>")
	)
	(segment
		(start 51.293268 -103.48214)
		(end 53.801772 -103.48214)
		(width 0.13462)
		(layer "F.Cu")
		(net "P5E_PEX0_STN1_RX_DN<18>")
	)
	(segment
		(start 51.130454 -103.644954)
		(end 51.293268 -103.48214)
		(width 0.13462)
		(layer "F.Cu")
		(net "P5E_PEX0_STN1_RX_DN<18>")
	)
	(segment
		(start 50.64252 -103.644954)
		(end 51.130454 -103.644954)
		(width 0.13462)
		(layer "F.Cu")
		(net "P5E_PEX0_STN1_RX_DN<18>")
	)
	(segment
		(start 48.115728 -105.47858)
		(end 47.675292 -105.70464)
		(width 0.1651)
		(layer "In5.Cu")
		(net "P5E_PEX0_STN1_RX_DN<18>")
	)
	(segment
		(start 49.354486 -104.971342)
		(end 49.200562 -104.921812)
		(width 0.1651)
		(layer "In5.Cu")
		(net "P5E_PEX0_STN1_RX_DN<18>")
	)
	(segment
		(start 61.215778 -271.773904)
		(end 61.215778 -271.802352)
		(width 0.1143)
		(layer "In5.Cu")
		(net "P5E_PEX0_STN1_RX_DN<18>")
	)
	(segment
		(start 43.253914 -109.01934)
		(end 43.09237 -109.02315)
		(width 0.1651)
		(layer "In5.Cu")
		(net "P5E_PEX0_STN1_RX_DN<18>")
	)
	(segment
		(start 61.273436 -273.479514)
		(end 61.435234 -273.479514)
		(width 0.1143)
		(layer "In5.Cu")
		(net "P5E_PEX0_STN1_RX_DN<18>")
	)
	(segment
		(start 50.285396 -104.365044)
		(end 49.84496 -104.591104)
		(width 0.1651)
		(layer "In5.Cu")
		(net "P5E_PEX0_STN1_RX_DN<18>")
	)
	(segment
		(start 49.84496 -104.591104)
		(end 49.79543 -104.745028)
		(width 0.1651)
		(layer "In5.Cu")
		(net "P5E_PEX0_STN1_RX_DN<18>")
	)
	(segment
		(start 44.438316 -107.779058)
		(end 44.095924 -108.137452)
		(width 0.1651)
		(layer "In5.Cu")
		(net "P5E_PEX0_STN1_RX_DN<18>")
	)
	(segment
		(start 30.942026 -158.75762)
		(end 32.06369 -165.241986)
		(width 0.1651)
		(layer "In5.Cu")
		(net "P5E_PEX0_STN1_RX_DN<18>")
	)
	(segment
		(start 44.902374 -107.127294)
		(end 44.434506 -107.61726)
		(width 0.1651)
		(layer "In5.Cu")
		(net "P5E_PEX0_STN1_RX_DN<18>")
	)
	(segment
		(start 42.411904 -109.901228)
		(end 42.25036 -109.905038)
		(width 0.1651)
		(layer "In5.Cu")
		(net "P5E_PEX0_STN1_RX_DN<18>")
	)
	(segment
		(start 46.540928 -106.415078)
		(end 46.09973 -106.641392)
		(width 0.1651)
		(layer "In5.Cu")
		(net "P5E_PEX0_STN1_RX_DN<18>")
	)
	(segment
		(start 48.760126 -105.147872)
		(end 48.710596 -105.301796)
		(width 0.1651)
		(layer "In5.Cu")
		(net "P5E_PEX0_STN1_RX_DN<18>")
	)
	(segment
		(start 61.215778 -269.734284)
		(end 61.215778 -271.773904)
		(width 0.1651)
		(layer "In5.Cu")
		(net "P5E_PEX0_STN1_RX_DN<18>")
	)
	(segment
		(start 47.675292 -105.70464)
		(end 47.625762 -105.85831)
		(width 0.1651)
		(layer "In5.Cu")
		(net "P5E_PEX0_STN1_RX_DN<18>")
	)
	(segment
		(start 61.549534 -273.365214)
		(end 61.549534 -273.099784)
		(width 0.1143)
		(layer "In5.Cu")
		(net "P5E_PEX0_STN1_RX_DN<18>")
	)
	(segment
		(start 48.269652 -105.52811)
		(end 48.115728 -105.47858)
		(width 0.1651)
		(layer "In5.Cu")
		(net "P5E_PEX0_STN1_RX_DN<18>")
	)
	(segment
		(start 54.09692 -103.776272)
		(end 53.80609 -103.485442)
		(width 0.1651)
		(layer "In5.Cu")
		(net "P5E_PEX0_STN1_RX_DN<18>")
	)
	(segment
		(start 43.09237 -109.02315)
		(end 42.750486 -109.38129)
		(width 0.1651)
		(layer "In5.Cu")
		(net "P5E_PEX0_STN1_RX_DN<18>")
	)
	(segment
		(start 50.43932 -104.414574)
		(end 50.285396 -104.365044)
		(width 0.1651)
		(layer "In5.Cu")
		(net "P5E_PEX0_STN1_RX_DN<18>")
	)
	(segment
		(start 61.215778 -271.802352)
		(end 61.170058 -271.848072)
		(width 0.1143)
		(layer "In5.Cu")
		(net "P5E_PEX0_STN1_RX_DN<18>")
	)
	(segment
		(start 61.170058 -273.376136)
		(end 61.273436 -273.479514)
		(width 0.1143)
		(layer "In5.Cu")
		(net "P5E_PEX0_STN1_RX_DN<18>")
	)
	(segment
		(start 31.98622 -126.637796)
		(end 30.384496 -150.341584)
		(width 0.1651)
		(layer "In5.Cu")
		(net "P5E_PEX0_STN1_RX_DN<18>")
	)
	(segment
		(start 49.200562 -104.921812)
		(end 48.760126 -105.147872)
		(width 0.1651)
		(layer "In5.Cu")
		(net "P5E_PEX0_STN1_RX_DN<18>")
	)
	(segment
		(start 34.07283 -118.469918)
		(end 33.114234 -120.46712)
		(width 0.1651)
		(layer "In5.Cu")
		(net "P5E_PEX0_STN1_RX_DN<18>")
	)
	(segment
		(start 46.09973 -106.641392)
		(end 45.94606 -106.591862)
		(width 0.1651)
		(layer "In5.Cu")
		(net "P5E_PEX0_STN1_RX_DN<18>")
	)
	(segment
		(start 30.384496 -150.341584)
		(end 30.942026 -158.75762)
		(width 0.1651)
		(layer "In5.Cu")
		(net "P5E_PEX0_STN1_RX_DN<18>")
	)
	(segment
		(start 49.79543 -104.745028)
		(end 49.354486 -104.971342)
		(width 0.1651)
		(layer "In5.Cu")
		(net "P5E_PEX0_STN1_RX_DN<18>")
	)
	(segment
		(start 42.750486 -109.38129)
		(end 42.754296 -109.542834)
		(width 0.1651)
		(layer "In5.Cu")
		(net "P5E_PEX0_STN1_RX_DN<18>")
	)
	(segment
		(start 50.880264 -104.188006)
		(end 50.43932 -104.414574)
		(width 0.1651)
		(layer "In5.Cu")
		(net "P5E_PEX0_STN1_RX_DN<18>")
	)
	(segment
		(start 33.114234 -120.46712)
		(end 31.98622 -126.637796)
		(width 0.1651)
		(layer "In5.Cu")
		(net "P5E_PEX0_STN1_RX_DN<18>")
	)
	(segment
		(start 45.94606 -106.591862)
		(end 44.902374 -107.127294)
		(width 0.1651)
		(layer "In5.Cu")
		(net "P5E_PEX0_STN1_RX_DN<18>")
	)
	(segment
		(start 50.92954 -104.034082)
		(end 50.880264 -104.188006)
		(width 0.1651)
		(layer "In5.Cu")
		(net "P5E_PEX0_STN1_RX_DN<18>")
	)
	(segment
		(start 47.184818 -106.084878)
		(end 47.030894 -106.035348)
		(width 0.1651)
		(layer "In5.Cu")
		(net "P5E_PEX0_STN1_RX_DN<18>")
	)
	(segment
		(start 43.596306 -108.660946)
		(end 43.253914 -109.01934)
		(width 0.1651)
		(layer "In5.Cu")
		(net "P5E_PEX0_STN1_RX_DN<18>")
	)
	(segment
		(start 61.170058 -271.848072)
		(end 61.170058 -273.376136)
		(width 0.1143)
		(layer "In5.Cu")
		(net "P5E_PEX0_STN1_RX_DN<18>")
	)
	(segment
		(start 44.095924 -108.137452)
		(end 43.93438 -108.141262)
		(width 0.1651)
		(layer "In5.Cu")
		(net "P5E_PEX0_STN1_RX_DN<18>")
	)
	(segment
		(start 48.710596 -105.301796)
		(end 48.269652 -105.52811)
		(width 0.1651)
		(layer "In5.Cu")
		(net "P5E_PEX0_STN1_RX_DN<18>")
	)
	(segment
		(start 50.92954 -104.034336)
		(end 50.92954 -104.034082)
		(width 0.1651)
		(layer "In5.Cu")
		(net "P5E_PEX0_STN1_RX_DN<18>")
	)
	(segment
		(start 53.80609 -103.485442)
		(end 51.999134 -103.485442)
		(width 0.1651)
		(layer "In5.Cu")
		(net "P5E_PEX0_STN1_RX_DN<18>")
	)
	(segment
		(start 32.06369 -165.241986)
		(end 61.215778 -269.734284)
		(width 0.1651)
		(layer "In5.Cu")
		(net "P5E_PEX0_STN1_RX_DN<18>")
	)
	(segment
		(start 46.590204 -106.261408)
		(end 46.540928 -106.415078)
		(width 0.1651)
		(layer "In5.Cu")
		(net "P5E_PEX0_STN1_RX_DN<18>")
	)
	(segment
		(start 42.25036 -109.905038)
		(end 34.07283 -118.469918)
		(width 0.1651)
		(layer "In5.Cu")
		(net "P5E_PEX0_STN1_RX_DN<18>")
	)
	(segment
		(start 51.999134 -103.485442)
		(end 50.92954 -104.034336)
		(width 0.1651)
		(layer "In5.Cu")
		(net "P5E_PEX0_STN1_RX_DN<18>")
	)
	(segment
		(start 42.754296 -109.542834)
		(end 42.411904 -109.901228)
		(width 0.1651)
		(layer "In5.Cu")
		(net "P5E_PEX0_STN1_RX_DN<18>")
	)
	(segment
		(start 47.625762 -105.85831)
		(end 47.184818 -106.084878)
		(width 0.1651)
		(layer "In5.Cu")
		(net "P5E_PEX0_STN1_RX_DN<18>")
	)
	(segment
		(start 47.030894 -106.035348)
		(end 46.590204 -106.261408)
		(width 0.1651)
		(layer "In5.Cu")
		(net "P5E_PEX0_STN1_RX_DN<18>")
	)
	(segment
		(start 43.592496 -108.499402)
		(end 43.596306 -108.660946)
		(width 0.1651)
		(layer "In5.Cu")
		(net "P5E_PEX0_STN1_RX_DN<18>")
	)
	(segment
		(start 44.434506 -107.61726)
		(end 44.438316 -107.779058)
		(width 0.1651)
		(layer "In5.Cu")
		(net "P5E_PEX0_STN1_RX_DN<18>")
	)
	(segment
		(start 43.93438 -108.141262)
		(end 43.592496 -108.499402)
		(width 0.1651)
		(layer "In5.Cu")
		(net "P5E_PEX0_STN1_RX_DN<18>")
	)
	(segment
		(start 61.435234 -273.479514)
		(end 61.549534 -273.365214)
		(width 0.1143)
		(layer "In5.Cu")
		(net "P5E_PEX0_STN1_RX_DN<18>")
	)
	(segment
		(start 153.005028 -109.20984)
		(end 153.332688 -108.88218)
		(width 0.13462)
		(layer "F.Cu")
		(net "P5E_PEX1_STN1_TX_C_DP<21>")
	)
	(segment
		(start 153.332688 -108.88218)
		(end 161.491422 -108.88218)
		(width 0.13462)
		(layer "F.Cu")
		(net "P5E_PEX1_STN1_TX_C_DP<21>")
	)
	(segment
		(start 161.491422 -108.88218)
		(end 161.654236 -109.044994)
		(width 0.13462)
		(layer "F.Cu")
		(net "P5E_PEX1_STN1_TX_C_DP<21>")
	)
	(segment
		(start 161.654236 -109.044994)
		(end 162.14217 -109.044994)
		(width 0.13462)
		(layer "F.Cu")
		(net "P5E_PEX1_STN1_TX_C_DP<21>")
	)
	(segment
		(start 170.655488 -316.229492)
		(end 170.42892 -316.45606)
		(width 0.1143)
		(layer "In5.Cu")
		(net "P5E_PEX1_STN6_RX_DP<99>")
	)
	(segment
		(start 170.42892 -316.45606)
		(end 170.42892 -319.86093)
		(width 0.1143)
		(layer "In5.Cu")
		(net "P5E_PEX1_STN6_RX_DP<99>")
	)
	(segment
		(start 170.3832 -319.935098)
		(end 170.3832 -321.079876)
		(width 0.1651)
		(layer "In5.Cu")
		(net "P5E_PEX1_STN6_RX_DP<99>")
	)
	(segment
		(start 127.641604 -366.587532)
		(end 127.642874 -366.745774)
		(width 0.1651)
		(layer "In5.Cu")
		(net "P5E_PEX1_STN6_RX_DP<99>")
	)
	(segment
		(start 126.0602 -368.3508)
		(end 125.487684 -369.304062)
		(width 0.1651)
		(layer "In5.Cu")
		(net "P5E_PEX1_STN6_RX_DP<99>")
	)
	(segment
		(start 127.304038 -367.089182)
		(end 127.14605 -367.090452)
		(width 0.1651)
		(layer "In5.Cu")
		(net "P5E_PEX1_STN6_RX_DP<99>")
	)
	(segment
		(start 134.859268 -359.427272)
		(end 128.97358 -365.396018)
		(width 0.1651)
		(layer "In5.Cu")
		(net "P5E_PEX1_STN6_RX_DP<99>")
	)
	(segment
		(start 135.470138 -341.853012)
		(end 135.470138 -357.937562)
		(width 0.1651)
		(layer "In5.Cu")
		(net "P5E_PEX1_STN6_RX_DP<99>")
	)
	(segment
		(start 128.97358 -365.396018)
		(end 128.815338 -365.397288)
		(width 0.1651)
		(layer "In5.Cu")
		(net "P5E_PEX1_STN6_RX_DP<99>")
	)
	(segment
		(start 170.42892 -319.86093)
		(end 170.3832 -319.90665)
		(width 0.1143)
		(layer "In5.Cu")
		(net "P5E_PEX1_STN6_RX_DP<99>")
	)
	(segment
		(start 136.579356 -340.743794)
		(end 135.470138 -341.853012)
		(width 0.1651)
		(layer "In5.Cu")
		(net "P5E_PEX1_STN6_RX_DP<99>")
	)
	(segment
		(start 127.14605 -367.090452)
		(end 126.80696 -367.434368)
		(width 0.1651)
		(layer "In5.Cu")
		(net "P5E_PEX1_STN6_RX_DP<99>")
	)
	(segment
		(start 125.487684 -369.304062)
		(end 125.487684 -374.681496)
		(width 0.1651)
		(layer "In5.Cu")
		(net "P5E_PEX1_STN6_RX_DP<99>")
	)
	(segment
		(start 170.3832 -319.90665)
		(end 170.3832 -319.935098)
		(width 0.1143)
		(layer "In5.Cu")
		(net "P5E_PEX1_STN6_RX_DP<99>")
	)
	(segment
		(start 125.270006 -374.899174)
		(end 124.83719 -374.899174)
		(width 0.1651)
		(layer "In5.Cu")
		(net "P5E_PEX1_STN6_RX_DP<99>")
	)
	(segment
		(start 170.3832 -321.079876)
		(end 168.904412 -322.782946)
		(width 0.1651)
		(layer "In5.Cu")
		(net "P5E_PEX1_STN6_RX_DP<99>")
	)
	(segment
		(start 128.477518 -365.899192)
		(end 128.138682 -366.2426)
		(width 0.1651)
		(layer "In5.Cu")
		(net "P5E_PEX1_STN6_RX_DP<99>")
	)
	(segment
		(start 128.476248 -365.74095)
		(end 128.477518 -365.899192)
		(width 0.1651)
		(layer "In5.Cu")
		(net "P5E_PEX1_STN6_RX_DP<99>")
	)
	(segment
		(start 170.885612 -316.229492)
		(end 170.655488 -316.229492)
		(width 0.1143)
		(layer "In5.Cu")
		(net "P5E_PEX1_STN6_RX_DP<99>")
	)
	(segment
		(start 128.138682 -366.2426)
		(end 127.980694 -366.243616)
		(width 0.1651)
		(layer "In5.Cu")
		(net "P5E_PEX1_STN6_RX_DP<99>")
	)
	(segment
		(start 168.904412 -322.782946)
		(end 156.402532 -330.171552)
		(width 0.1651)
		(layer "In5.Cu")
		(net "P5E_PEX1_STN6_RX_DP<99>")
	)
	(segment
		(start 156.402532 -330.171552)
		(end 146.040094 -336.744818)
		(width 0.1651)
		(layer "In5.Cu")
		(net "P5E_PEX1_STN6_RX_DP<99>")
	)
	(segment
		(start 125.487684 -374.681496)
		(end 125.270006 -374.899174)
		(width 0.1651)
		(layer "In5.Cu")
		(net "P5E_PEX1_STN6_RX_DP<99>")
	)
	(segment
		(start 127.980694 -366.243616)
		(end 127.641604 -366.587532)
		(width 0.1651)
		(layer "In5.Cu")
		(net "P5E_PEX1_STN6_RX_DP<99>")
	)
	(segment
		(start 146.040094 -336.744818)
		(end 136.579356 -340.743794)
		(width 0.1651)
		(layer "In5.Cu")
		(net "P5E_PEX1_STN6_RX_DP<99>")
	)
	(segment
		(start 127.642874 -366.745774)
		(end 127.304038 -367.089182)
		(width 0.1651)
		(layer "In5.Cu")
		(net "P5E_PEX1_STN6_RX_DP<99>")
	)
	(segment
		(start 135.470138 -357.937562)
		(end 134.859268 -359.427272)
		(width 0.1651)
		(layer "In5.Cu")
		(net "P5E_PEX1_STN6_RX_DP<99>")
	)
	(segment
		(start 170.999912 -316.115192)
		(end 170.885612 -316.229492)
		(width 0.1143)
		(layer "In5.Cu")
		(net "P5E_PEX1_STN6_RX_DP<99>")
	)
	(segment
		(start 126.80823 -367.592356)
		(end 126.0602 -368.3508)
		(width 0.1651)
		(layer "In5.Cu")
		(net "P5E_PEX1_STN6_RX_DP<99>")
	)
	(segment
		(start 126.80696 -367.434368)
		(end 126.80823 -367.592356)
		(width 0.1651)
		(layer "In5.Cu")
		(net "P5E_PEX1_STN6_RX_DP<99>")
	)
	(segment
		(start 124.83719 -374.899174)
		(end 124.71019 -374.772174)
		(width 0.1651)
		(layer "In5.Cu")
		(net "P5E_PEX1_STN6_RX_DP<99>")
	)
	(segment
		(start 128.815338 -365.397288)
		(end 128.476248 -365.74095)
		(width 0.1651)
		(layer "In5.Cu")
		(net "P5E_PEX1_STN6_RX_DP<99>")
	)
	(segment
		(start 170.999912 -315.849762)
		(end 170.999912 -316.115192)
		(width 0.1143)
		(layer "In5.Cu")
		(net "P5E_PEX1_STN6_RX_DP<99>")
	)
	(segment
		(start 124.71019 -374.772174)
		(end 124.71019 -374.390158)
		(width 0.1651)
		(layer "In5.Cu")
		(net "P5E_PEX1_STN6_RX_DP<99>")
	)
	(segment
		(start 422.060624 -122.435112)
		(end 421.557704 -122.435112)
		(width 0.13462)
		(layer "F.Cu")
		(net "P5E_PEX3_STN0_TX_C_DN<2>")
	)
	(segment
		(start 422.218612 -122.5931)
		(end 422.060624 -122.435112)
		(width 0.13462)
		(layer "F.Cu")
		(net "P5E_PEX3_STN0_TX_C_DN<2>")
	)
	(segment
		(start 427.729904 -122.5931)
		(end 422.218612 -122.5931)
		(width 0.13462)
		(layer "F.Cu")
		(net "P5E_PEX3_STN0_TX_C_DN<2>")
	)
	(segment
		(start 428.052738 -122.270266)
		(end 427.729904 -122.5931)
		(width 0.13462)
		(layer "F.Cu")
		(net "P5E_PEX3_STN0_TX_C_DN<2>")
	)
	(segment
		(start 390.136888 -356.832154)
		(end 390.136888 -357.462582)
		(width 0.13462)
		(layer "F.Cu")
		(net "P5E_PEX3_STN5_TX_C_DP<89>")
	)
	(segment
		(start 389.81634 -356.511606)
		(end 390.136888 -356.832154)
		(width 0.13462)
		(layer "F.Cu")
		(net "P5E_PEX3_STN5_TX_C_DP<89>")
	)
	(segment
		(start 390.136888 -357.462582)
		(end 389.84174 -357.75773)
		(width 0.13462)
		(layer "F.Cu")
		(net "P5E_PEX3_STN5_TX_C_DP<89>")
	)
	(segment
		(start 381.154178 -366.51184)
		(end 381.165354 -366.386618)
		(width 0.1651)
		(layer "In13.Cu")
		(net "P5E_PEX3_STN5_TX_C_DP<89>")
	)
	(segment
		(start 377.689872 -379.390148)
		(end 377.689872 -379.772164)
		(width 0.1651)
		(layer "In13.Cu")
		(net "P5E_PEX3_STN5_TX_C_DP<89>")
	)
	(segment
		(start 377.689872 -379.772164)
		(end 377.816872 -379.899164)
		(width 0.1651)
		(layer "In13.Cu")
		(net "P5E_PEX3_STN5_TX_C_DP<89>")
	)
	(segment
		(start 379.262894 -368.091974)
		(end 381.154178 -366.51184)
		(width 0.1651)
		(layer "In13.Cu")
		(net "P5E_PEX3_STN5_TX_C_DP<89>")
	)
	(segment
		(start 378.247148 -379.899164)
		(end 378.533914 -379.612398)
		(width 0.1651)
		(layer "In13.Cu")
		(net "P5E_PEX3_STN5_TX_C_DP<89>")
	)
	(segment
		(start 390.13257 -358.394762)
		(end 390.13257 -358.04856)
		(width 0.1651)
		(layer "In13.Cu")
		(net "P5E_PEX3_STN5_TX_C_DP<89>")
	)
	(segment
		(start 381.165354 -366.386618)
		(end 381.545846 -366.068864)
		(width 0.1651)
		(layer "In13.Cu")
		(net "P5E_PEX3_STN5_TX_C_DP<89>")
	)
	(segment
		(start 378.533914 -379.612398)
		(end 378.533914 -369.650772)
		(width 0.1651)
		(layer "In13.Cu")
		(net "P5E_PEX3_STN5_TX_C_DP<89>")
	)
	(segment
		(start 377.816872 -379.899164)
		(end 378.247148 -379.899164)
		(width 0.1651)
		(layer "In13.Cu")
		(net "P5E_PEX3_STN5_TX_C_DP<89>")
	)
	(segment
		(start 381.545846 -366.068864)
		(end 381.671068 -366.08004)
		(width 0.1651)
		(layer "In13.Cu")
		(net "P5E_PEX3_STN5_TX_C_DP<89>")
	)
	(segment
		(start 381.671068 -366.08004)
		(end 389.66013 -359.405174)
		(width 0.1651)
		(layer "In13.Cu")
		(net "P5E_PEX3_STN5_TX_C_DP<89>")
	)
	(segment
		(start 390.13257 -358.04856)
		(end 389.84174 -357.75773)
		(width 0.1651)
		(layer "In13.Cu")
		(net "P5E_PEX3_STN5_TX_C_DP<89>")
	)
	(segment
		(start 378.533914 -369.650772)
		(end 379.262894 -368.091974)
		(width 0.1651)
		(layer "In13.Cu")
		(net "P5E_PEX3_STN5_TX_C_DP<89>")
	)
	(segment
		(start 389.66013 -359.405174)
		(end 390.13257 -358.394762)
		(width 0.1651)
		(layer "In13.Cu")
		(net "P5E_PEX3_STN5_TX_C_DP<89>")
	)
	(segment
		(start 283.930344 -156.282136)
		(end 285.047436 -156.282136)
		(width 0.13208)
		(layer "F.Cu")
		(net "NIC4_RBT_ARB_OUT")
	)
	(segment
		(start 283.608272 -155.960064)
		(end 283.930344 -156.282136)
		(width 0.13208)
		(layer "F.Cu")
		(net "NIC4_RBT_ARB_OUT")
	)
	(segment
		(start 285.047436 -156.282136)
		(end 285.309818 -156.544518)
		(width 0.13208)
		(layer "F.Cu")
		(net "NIC4_RBT_ARB_OUT")
	)
	(segment
		(start 282.842462 -155.960064)
		(end 283.608272 -155.960064)
		(width 0.13208)
		(layer "F.Cu")
		(net "NIC4_RBT_ARB_OUT")
	)
	(via
		(at 285.309818 -156.544518)
		(size 0.508)
		(drill 0.254)
		(layers "F.Cu" "B.Cu")
		(net "NIC4_RBT_ARB_OUT")
	)
	(segment
		(start 285.047436 -156.282136)
		(end 285.309818 -156.544518)
		(width 0.13208)
		(layer "B.Cu")
		(net "NIC4_RBT_ARB_OUT")
	)
	(segment
		(start 283.054806 -156.282136)
		(end 285.047436 -156.282136)
		(width 0.13208)
		(layer "B.Cu")
		(net "NIC4_RBT_ARB_OUT")
	)
	(segment
		(start 281.355292 -156.718)
		(end 281.482292 -156.591)
		(width 0.13208)
		(layer "B.Cu")
		(net "NIC4_RBT_ARB_OUT")
	)
	(segment
		(start 281.482292 -156.591)
		(end 282.745942 -156.591)
		(width 0.13208)
		(layer "B.Cu")
		(net "NIC4_RBT_ARB_OUT")
	)
	(segment
		(start 282.745942 -156.591)
		(end 283.054806 -156.282136)
		(width 0.13208)
		(layer "B.Cu")
		(net "NIC4_RBT_ARB_OUT")
	)
	(segment
		(start 281.355292 -157.0736)
		(end 281.355292 -156.718)
		(width 0.13208)
		(layer "B.Cu")
		(net "NIC4_RBT_ARB_OUT")
	)
	(segment
		(start 53.801772 -110.682278)
		(end 53.80228 -110.68177)
		(width 0.13462)
		(layer "F.Cu")
		(net "P5E_PEX0_STN1_RX_DN<22>")
	)
	(segment
		(start 50.64252 -110.845092)
		(end 51.130454 -110.845092)
		(width 0.13462)
		(layer "F.Cu")
		(net "P5E_PEX0_STN1_RX_DN<22>")
	)
	(segment
		(start 51.130454 -110.845092)
		(end 51.293268 -110.682278)
		(width 0.13462)
		(layer "F.Cu")
		(net "P5E_PEX0_STN1_RX_DN<22>")
	)
	(segment
		(start 51.293268 -110.682278)
		(end 53.801772 -110.682278)
		(width 0.13462)
		(layer "F.Cu")
		(net "P5E_PEX0_STN1_RX_DN<22>")
	)
	(segment
		(start 53.80228 -110.68177)
		(end 54.09692 -110.97641)
		(width 0.13462)
		(layer "F.Cu")
		(net "P5E_PEX0_STN1_RX_DN<22>")
	)
	(segment
		(start 52.33797 -110.68558)
		(end 51.84267 -110.68558)
		(width 0.1651)
		(layer "In5.Cu")
		(net "P5E_PEX0_STN1_RX_DN<22>")
	)
	(segment
		(start 52.94757 -110.79988)
		(end 52.45227 -110.79988)
		(width 0.1651)
		(layer "In5.Cu")
		(net "P5E_PEX0_STN1_RX_DN<22>")
	)
	(segment
		(start 43.421808 -114.76482)
		(end 43.156124 -115.076478)
		(width 0.1651)
		(layer "In5.Cu")
		(net "P5E_PEX0_STN1_RX_DN<22>")
	)
	(segment
		(start 52.45227 -110.79988)
		(end 52.33797 -110.68558)
		(width 0.1651)
		(layer "In5.Cu")
		(net "P5E_PEX0_STN1_RX_DN<22>")
	)
	(segment
		(start 41.93413 -121.256298)
		(end 42.027856 -121.388124)
		(width 0.1651)
		(layer "In5.Cu")
		(net "P5E_PEX0_STN1_RX_DN<22>")
	)
	(segment
		(start 45.605192 -113.91011)
		(end 45.192696 -114.184938)
		(width 0.1651)
		(layer "In5.Cu")
		(net "P5E_PEX0_STN1_RX_DN<22>")
	)
	(segment
		(start 43.933872 -114.5286)
		(end 43.421808 -114.76482)
		(width 0.1651)
		(layer "In5.Cu")
		(net "P5E_PEX0_STN1_RX_DN<22>")
	)
	(segment
		(start 41.813734 -121.970546)
		(end 39.279322 -137.015474)
		(width 0.1651)
		(layer "In5.Cu")
		(net "P5E_PEX0_STN1_RX_DN<22>")
	)
	(segment
		(start 46.04893 -113.47704)
		(end 45.636942 -113.751614)
		(width 0.1651)
		(layer "In5.Cu")
		(net "P5E_PEX0_STN1_RX_DN<22>")
	)
	(segment
		(start 41.94556 -121.87682)
		(end 41.813734 -121.970546)
		(width 0.1651)
		(layer "In5.Cu")
		(net "P5E_PEX0_STN1_RX_DN<22>")
	)
	(segment
		(start 46.651672 -113.075466)
		(end 46.619922 -113.233962)
		(width 0.1651)
		(layer "In5.Cu")
		(net "P5E_PEX0_STN1_RX_DN<22>")
	)
	(segment
		(start 51.84267 -110.68558)
		(end 51.3842 -110.87227)
		(width 0.1651)
		(layer "In5.Cu")
		(net "P5E_PEX0_STN1_RX_DN<22>")
	)
	(segment
		(start 48.603662 -112.128046)
		(end 48.454818 -112.065308)
		(width 0.1651)
		(layer "In5.Cu")
		(net "P5E_PEX0_STN1_RX_DN<22>")
	)
	(segment
		(start 34.35985 -151.040592)
		(end 34.815272 -158.370778)
		(width 0.1651)
		(layer "In5.Cu")
		(net "P5E_PEX0_STN1_RX_DN<22>")
	)
	(segment
		(start 42.136822 -120.053862)
		(end 42.230548 -120.185688)
		(width 0.1651)
		(layer "In5.Cu")
		(net "P5E_PEX0_STN1_RX_DN<22>")
	)
	(segment
		(start 54.09692 -110.97641)
		(end 53.80609 -110.68558)
		(width 0.1651)
		(layer "In5.Cu")
		(net "P5E_PEX0_STN1_RX_DN<22>")
	)
	(segment
		(start 50.254662 -111.332264)
		(end 50.191924 -111.481362)
		(width 0.1651)
		(layer "In5.Cu")
		(net "P5E_PEX0_STN1_RX_DN<22>")
	)
	(segment
		(start 46.207426 -113.50879)
		(end 46.04893 -113.47704)
		(width 0.1651)
		(layer "In5.Cu")
		(net "P5E_PEX0_STN1_RX_DN<22>")
	)
	(segment
		(start 42.148252 -120.674384)
		(end 42.016172 -120.76811)
		(width 0.1651)
		(layer "In5.Cu")
		(net "P5E_PEX0_STN1_RX_DN<22>")
	)
	(segment
		(start 51.321208 -111.021368)
		(end 50.86223 -111.208312)
		(width 0.1651)
		(layer "In5.Cu")
		(net "P5E_PEX0_STN1_RX_DN<22>")
	)
	(segment
		(start 65.015872 -271.773904)
		(end 65.015872 -271.802352)
		(width 0.1143)
		(layer "In5.Cu")
		(net "P5E_PEX0_STN1_RX_DN<22>")
	)
	(segment
		(start 42.016172 -120.76811)
		(end 41.93413 -121.256298)
		(width 0.1651)
		(layer "In5.Cu")
		(net "P5E_PEX0_STN1_RX_DN<22>")
	)
	(segment
		(start 47.717456 -112.365282)
		(end 46.651672 -113.075466)
		(width 0.1651)
		(layer "In5.Cu")
		(net "P5E_PEX0_STN1_RX_DN<22>")
	)
	(segment
		(start 49.06264 -111.941356)
		(end 48.603662 -112.128046)
		(width 0.1651)
		(layer "In5.Cu")
		(net "P5E_PEX0_STN1_RX_DN<22>")
	)
	(segment
		(start 50.713386 -111.145574)
		(end 50.254662 -111.332264)
		(width 0.1651)
		(layer "In5.Cu")
		(net "P5E_PEX0_STN1_RX_DN<22>")
	)
	(segment
		(start 49.125378 -111.792258)
		(end 49.06264 -111.941356)
		(width 0.1651)
		(layer "In5.Cu")
		(net "P5E_PEX0_STN1_RX_DN<22>")
	)
	(segment
		(start 49.584102 -111.605568)
		(end 49.125378 -111.792258)
		(width 0.1651)
		(layer "In5.Cu")
		(net "P5E_PEX0_STN1_RX_DN<22>")
	)
	(segment
		(start 65.015872 -268.786864)
		(end 65.015872 -271.773904)
		(width 0.1651)
		(layer "In5.Cu")
		(net "P5E_PEX0_STN1_RX_DN<22>")
	)
	(segment
		(start 51.3842 -110.87227)
		(end 51.321208 -111.021368)
		(width 0.1651)
		(layer "In5.Cu")
		(net "P5E_PEX0_STN1_RX_DN<22>")
	)
	(segment
		(start 48.454818 -112.065308)
		(end 47.717456 -112.365282)
		(width 0.1651)
		(layer "In5.Cu")
		(net "P5E_PEX0_STN1_RX_DN<22>")
	)
	(segment
		(start 64.970152 -273.376136)
		(end 65.07353 -273.479514)
		(width 0.1143)
		(layer "In5.Cu")
		(net "P5E_PEX0_STN1_RX_DN<22>")
	)
	(segment
		(start 39.279322 -137.015474)
		(end 37.325046 -140.713968)
		(width 0.1651)
		(layer "In5.Cu")
		(net "P5E_PEX0_STN1_RX_DN<22>")
	)
	(segment
		(start 65.349628 -273.365214)
		(end 65.349628 -273.099784)
		(width 0.1143)
		(layer "In5.Cu")
		(net "P5E_PEX0_STN1_RX_DN<22>")
	)
	(segment
		(start 35.900106 -164.419026)
		(end 65.015872 -268.786864)
		(width 0.1651)
		(layer "In5.Cu")
		(net "P5E_PEX0_STN1_RX_DN<22>")
	)
	(segment
		(start 53.80609 -110.68558)
		(end 53.06187 -110.68558)
		(width 0.1651)
		(layer "In5.Cu")
		(net "P5E_PEX0_STN1_RX_DN<22>")
	)
	(segment
		(start 65.07353 -273.479514)
		(end 65.235328 -273.479514)
		(width 0.1143)
		(layer "In5.Cu")
		(net "P5E_PEX0_STN1_RX_DN<22>")
	)
	(segment
		(start 65.015872 -271.802352)
		(end 64.970152 -271.848072)
		(width 0.1143)
		(layer "In5.Cu")
		(net "P5E_PEX0_STN1_RX_DN<22>")
	)
	(segment
		(start 64.970152 -271.848072)
		(end 64.970152 -273.376136)
		(width 0.1143)
		(layer "In5.Cu")
		(net "P5E_PEX0_STN1_RX_DN<22>")
	)
	(segment
		(start 45.192696 -114.184938)
		(end 45.0342 -114.153188)
		(width 0.1651)
		(layer "In5.Cu")
		(net "P5E_PEX0_STN1_RX_DN<22>")
	)
	(segment
		(start 45.0342 -114.153188)
		(end 44.622212 -114.427762)
		(width 0.1651)
		(layer "In5.Cu")
		(net "P5E_PEX0_STN1_RX_DN<22>")
	)
	(segment
		(start 46.619922 -113.233962)
		(end 46.207426 -113.50879)
		(width 0.1651)
		(layer "In5.Cu")
		(net "P5E_PEX0_STN1_RX_DN<22>")
	)
	(segment
		(start 43.156124 -115.076478)
		(end 42.872914 -115.683538)
		(width 0.1651)
		(layer "In5.Cu")
		(net "P5E_PEX0_STN1_RX_DN<22>")
	)
	(segment
		(start 50.86223 -111.208312)
		(end 50.713386 -111.145574)
		(width 0.1651)
		(layer "In5.Cu")
		(net "P5E_PEX0_STN1_RX_DN<22>")
	)
	(segment
		(start 45.636942 -113.751614)
		(end 45.605192 -113.91011)
		(width 0.1651)
		(layer "In5.Cu")
		(net "P5E_PEX0_STN1_RX_DN<22>")
	)
	(segment
		(start 49.732946 -111.668306)
		(end 49.584102 -111.605568)
		(width 0.1651)
		(layer "In5.Cu")
		(net "P5E_PEX0_STN1_RX_DN<22>")
	)
	(segment
		(start 53.06187 -110.68558)
		(end 52.94757 -110.79988)
		(width 0.1651)
		(layer "In5.Cu")
		(net "P5E_PEX0_STN1_RX_DN<22>")
	)
	(segment
		(start 50.191924 -111.481362)
		(end 49.732946 -111.668306)
		(width 0.1651)
		(layer "In5.Cu")
		(net "P5E_PEX0_STN1_RX_DN<22>")
	)
	(segment
		(start 35.45586 -144.875758)
		(end 34.35985 -151.040592)
		(width 0.1651)
		(layer "In5.Cu")
		(net "P5E_PEX0_STN1_RX_DN<22>")
	)
	(segment
		(start 37.325046 -140.713968)
		(end 35.45586 -144.875758)
		(width 0.1651)
		(layer "In5.Cu")
		(net "P5E_PEX0_STN1_RX_DN<22>")
	)
	(segment
		(start 42.872914 -115.683538)
		(end 42.136822 -120.053862)
		(width 0.1651)
		(layer "In5.Cu")
		(net "P5E_PEX0_STN1_RX_DN<22>")
	)
	(segment
		(start 44.379642 -114.5286)
		(end 43.933872 -114.5286)
		(width 0.1651)
		(layer "In5.Cu")
		(net "P5E_PEX0_STN1_RX_DN<22>")
	)
	(segment
		(start 34.815272 -158.370778)
		(end 35.900106 -164.419026)
		(width 0.1651)
		(layer "In5.Cu")
		(net "P5E_PEX0_STN1_RX_DN<22>")
	)
	(segment
		(start 42.027856 -121.388124)
		(end 41.94556 -121.87682)
		(width 0.1651)
		(layer "In5.Cu")
		(net "P5E_PEX0_STN1_RX_DN<22>")
	)
	(segment
		(start 44.622212 -114.427762)
		(end 44.379642 -114.5286)
		(width 0.1651)
		(layer "In5.Cu")
		(net "P5E_PEX0_STN1_RX_DN<22>")
	)
	(segment
		(start 65.235328 -273.479514)
		(end 65.349628 -273.365214)
		(width 0.1143)
		(layer "In5.Cu")
		(net "P5E_PEX0_STN1_RX_DN<22>")
	)
	(segment
		(start 42.230548 -120.185688)
		(end 42.148252 -120.674384)
		(width 0.1651)
		(layer "In5.Cu")
		(net "P5E_PEX0_STN1_RX_DN<22>")
	)
	(segment
		(start 155.647136 -103.803196)
		(end 155.968192 -103.48214)
		(width 0.13462)
		(layer "F.Cu")
		(net "P5E_PEX1_STN1_TX_C_DN<18>")
	)
	(segment
		(start 155.968192 -103.48214)
		(end 161.491422 -103.48214)
		(width 0.13462)
		(layer "F.Cu")
		(net "P5E_PEX1_STN1_TX_C_DN<18>")
	)
	(segment
		(start 161.491422 -103.48214)
		(end 161.654236 -103.644954)
		(width 0.13462)
		(layer "F.Cu")
		(net "P5E_PEX1_STN1_TX_C_DN<18>")
	)
	(segment
		(start 161.654236 -103.644954)
		(end 162.14217 -103.644954)
		(width 0.13462)
		(layer "F.Cu")
		(net "P5E_PEX1_STN1_TX_C_DN<18>")
	)
	(segment
		(start 415.659824 -130.47472)
		(end 415.35731 -130.777234)
		(width 0.13462)
		(layer "F.Cu")
		(net "P5E_PEX3_STN0_RX_DP<4>")
	)
	(segment
		(start 416.308032 -130.47472)
		(end 415.659824 -130.47472)
		(width 0.13462)
		(layer "F.Cu")
		(net "P5E_PEX3_STN0_RX_DP<4>")
	)
	(segment
		(start 416.478212 -130.6449)
		(end 416.308032 -130.47472)
		(width 0.13462)
		(layer "F.Cu")
		(net "P5E_PEX3_STN0_RX_DP<4>")
	)
	(segment
		(start 416.95751 -130.6449)
		(end 416.478212 -130.6449)
		(width 0.13462)
		(layer "F.Cu")
		(net "P5E_PEX3_STN0_RX_DP<4>")
	)
	(segment
		(start 418.245798 -131.799076)
		(end 417.807648 -131.567682)
		(width 0.1651)
		(layer "In5.Cu")
		(net "P5E_PEX3_STN0_RX_DP<4>")
	)
	(segment
		(start 415.64814 -130.486404)
		(end 415.35731 -130.777234)
		(width 0.1651)
		(layer "In5.Cu")
		(net "P5E_PEX3_STN0_RX_DP<4>")
	)
	(segment
		(start 434.251862 -283.180536)
		(end 441.791598 -275.89226)
		(width 0.1651)
		(layer "In5.Cu")
		(net "P5E_PEX3_STN0_RX_DP<4>")
	)
	(segment
		(start 418.400484 -131.751578)
		(end 418.245798 -131.799076)
		(width 0.1651)
		(layer "In5.Cu")
		(net "P5E_PEX3_STN0_RX_DP<4>")
	)
	(segment
		(start 435.372764 -240.959894)
		(end 433.488338 -232.261156)
		(width 0.1651)
		(layer "In5.Cu")
		(net "P5E_PEX3_STN0_RX_DP<4>")
	)
	(segment
		(start 433.488338 -232.261156)
		(end 434.090318 -168.33342)
		(width 0.1651)
		(layer "In5.Cu")
		(net "P5E_PEX3_STN0_RX_DP<4>")
	)
	(segment
		(start 416.00628 -130.486404)
		(end 415.64814 -130.486404)
		(width 0.1651)
		(layer "In5.Cu")
		(net "P5E_PEX3_STN0_RX_DP<4>")
	)
	(segment
		(start 423.706544 -135.295894)
		(end 423.337228 -134.965694)
		(width 0.1651)
		(layer "In5.Cu")
		(net "P5E_PEX3_STN0_RX_DP<4>")
	)
	(segment
		(start 425.843954 -137.053066)
		(end 423.868088 -135.287004)
		(width 0.1651)
		(layer "In5.Cu")
		(net "P5E_PEX3_STN0_RX_DP<4>")
	)
	(segment
		(start 419.324028 -132.368798)
		(end 418.885878 -132.137404)
		(width 0.1651)
		(layer "In5.Cu")
		(net "P5E_PEX3_STN0_RX_DP<4>")
	)
	(segment
		(start 433.249578 -283.883862)
		(end 434.251862 -283.180536)
		(width 0.1651)
		(layer "In5.Cu")
		(net "P5E_PEX3_STN0_RX_DP<4>")
	)
	(segment
		(start 417.76015 -131.412996)
		(end 417.322254 -131.181856)
		(width 0.1651)
		(layer "In5.Cu")
		(net "P5E_PEX3_STN0_RX_DP<4>")
	)
	(segment
		(start 420.99484 -133.122162)
		(end 420.556944 -132.891022)
		(width 0.1651)
		(layer "In5.Cu")
		(net "P5E_PEX3_STN0_RX_DP<4>")
	)
	(segment
		(start 434.090318 -168.33342)
		(end 433.724558 -151.55164)
		(width 0.1651)
		(layer "In5.Cu")
		(net "P5E_PEX3_STN0_RX_DP<4>")
	)
	(segment
		(start 428.974758 -148.26488)
		(end 428.512478 -147.778978)
		(width 0.1651)
		(layer "In5.Cu")
		(net "P5E_PEX3_STN0_RX_DP<4>")
	)
	(segment
		(start 419.91661 -132.55244)
		(end 419.478714 -132.3213)
		(width 0.1651)
		(layer "In5.Cu")
		(net "P5E_PEX3_STN0_RX_DP<4>")
	)
	(segment
		(start 419.964108 -132.706872)
		(end 419.91661 -132.55244)
		(width 0.1651)
		(layer "In5.Cu")
		(net "P5E_PEX3_STN0_RX_DP<4>")
	)
	(segment
		(start 432.224688 -283.883862)
		(end 433.249578 -283.883862)
		(width 0.1651)
		(layer "In5.Cu")
		(net "P5E_PEX3_STN0_RX_DP<4>")
	)
	(segment
		(start 416.729672 -130.99796)
		(end 416.682174 -130.843528)
		(width 0.1651)
		(layer "In5.Cu")
		(net "P5E_PEX3_STN0_RX_DP<4>")
	)
	(segment
		(start 418.885878 -132.137404)
		(end 418.83838 -131.982718)
		(width 0.1651)
		(layer "In5.Cu")
		(net "P5E_PEX3_STN0_RX_DP<4>")
	)
	(segment
		(start 417.322254 -131.181856)
		(end 417.167822 -131.229608)
		(width 0.1651)
		(layer "In5.Cu")
		(net "P5E_PEX3_STN0_RX_DP<4>")
	)
	(segment
		(start 420.556944 -132.891022)
		(end 420.402512 -132.93852)
		(width 0.1651)
		(layer "In5.Cu")
		(net "P5E_PEX3_STN0_RX_DP<4>")
	)
	(segment
		(start 432.15052 -283.929582)
		(end 432.19624 -283.883862)
		(width 0.1143)
		(layer "In5.Cu")
		(net "P5E_PEX3_STN0_RX_DP<4>")
	)
	(segment
		(start 432.19624 -283.883862)
		(end 432.224688 -283.883862)
		(width 0.1143)
		(layer "In5.Cu")
		(net "P5E_PEX3_STN0_RX_DP<4>")
	)
	(segment
		(start 426.618654 -138.195812)
		(end 425.843954 -137.053066)
		(width 0.1651)
		(layer "In5.Cu")
		(net "P5E_PEX3_STN0_RX_DP<4>")
	)
	(segment
		(start 417.807648 -131.567682)
		(end 417.76015 -131.412996)
		(width 0.1651)
		(layer "In5.Cu")
		(net "P5E_PEX3_STN0_RX_DP<4>")
	)
	(segment
		(start 422.098978 -133.7056)
		(end 421.635174 -133.460744)
		(width 0.1651)
		(layer "In5.Cu")
		(net "P5E_PEX3_STN0_RX_DP<4>")
	)
	(segment
		(start 441.791598 -275.89226)
		(end 443.69609 -272.49501)
		(width 0.1651)
		(layer "In5.Cu")
		(net "P5E_PEX3_STN0_RX_DP<4>")
	)
	(segment
		(start 421.042338 -133.276594)
		(end 420.99484 -133.122162)
		(width 0.1651)
		(layer "In5.Cu")
		(net "P5E_PEX3_STN0_RX_DP<4>")
	)
	(segment
		(start 418.83838 -131.982718)
		(end 418.400484 -131.751578)
		(width 0.1651)
		(layer "In5.Cu")
		(net "P5E_PEX3_STN0_RX_DP<4>")
	)
	(segment
		(start 443.792102 -269.76578)
		(end 435.372764 -240.959894)
		(width 0.1651)
		(layer "In5.Cu")
		(net "P5E_PEX3_STN0_RX_DP<4>")
	)
	(segment
		(start 416.682174 -130.843528)
		(end 416.00628 -130.486404)
		(width 0.1651)
		(layer "In5.Cu")
		(net "P5E_PEX3_STN0_RX_DP<4>")
	)
	(segment
		(start 427.89983 -284.499812)
		(end 428.16526 -284.499812)
		(width 0.1143)
		(layer "In5.Cu")
		(net "P5E_PEX3_STN0_RX_DP<4>")
	)
	(segment
		(start 417.167822 -131.229608)
		(end 416.729672 -130.99796)
		(width 0.1651)
		(layer "In5.Cu")
		(net "P5E_PEX3_STN0_RX_DP<4>")
	)
	(segment
		(start 428.27956 -284.385512)
		(end 428.27956 -284.173676)
		(width 0.1143)
		(layer "In5.Cu")
		(net "P5E_PEX3_STN0_RX_DP<4>")
	)
	(segment
		(start 420.402512 -132.93852)
		(end 419.964108 -132.706872)
		(width 0.1651)
		(layer "In5.Cu")
		(net "P5E_PEX3_STN0_RX_DP<4>")
	)
	(segment
		(start 428.16526 -284.499812)
		(end 428.27956 -284.385512)
		(width 0.1143)
		(layer "In5.Cu")
		(net "P5E_PEX3_STN0_RX_DP<4>")
	)
	(segment
		(start 421.480742 -133.508242)
		(end 421.042338 -133.276594)
		(width 0.1651)
		(layer "In5.Cu")
		(net "P5E_PEX3_STN0_RX_DP<4>")
	)
	(segment
		(start 419.478714 -132.3213)
		(end 419.324028 -132.368798)
		(width 0.1651)
		(layer "In5.Cu")
		(net "P5E_PEX3_STN0_RX_DP<4>")
	)
	(segment
		(start 431.321718 -149.80666)
		(end 430.216818 -148.56206)
		(width 0.1651)
		(layer "In5.Cu")
		(net "P5E_PEX3_STN0_RX_DP<4>")
	)
	(segment
		(start 430.216818 -148.56206)
		(end 428.974758 -148.26488)
		(width 0.1651)
		(layer "In5.Cu")
		(net "P5E_PEX3_STN0_RX_DP<4>")
	)
	(segment
		(start 433.422298 -150.85568)
		(end 431.321718 -149.80666)
		(width 0.1651)
		(layer "In5.Cu")
		(net "P5E_PEX3_STN0_RX_DP<4>")
	)
	(segment
		(start 428.27956 -284.173676)
		(end 428.523654 -283.929582)
		(width 0.1143)
		(layer "In5.Cu")
		(net "P5E_PEX3_STN0_RX_DP<4>")
	)
	(segment
		(start 443.69609 -272.49501)
		(end 443.792102 -269.76578)
		(width 0.1651)
		(layer "In5.Cu")
		(net "P5E_PEX3_STN0_RX_DP<4>")
	)
	(segment
		(start 421.635174 -133.460744)
		(end 421.480742 -133.508242)
		(width 0.1651)
		(layer "In5.Cu")
		(net "P5E_PEX3_STN0_RX_DP<4>")
	)
	(segment
		(start 428.523654 -283.929582)
		(end 432.15052 -283.929582)
		(width 0.1143)
		(layer "In5.Cu")
		(net "P5E_PEX3_STN0_RX_DP<4>")
	)
	(segment
		(start 433.724558 -151.55164)
		(end 433.422298 -150.85568)
		(width 0.1651)
		(layer "In5.Cu")
		(net "P5E_PEX3_STN0_RX_DP<4>")
	)
	(segment
		(start 423.328084 -134.80415)
		(end 422.098978 -133.7056)
		(width 0.1651)
		(layer "In5.Cu")
		(net "P5E_PEX3_STN0_RX_DP<4>")
	)
	(segment
		(start 423.337228 -134.965694)
		(end 423.328084 -134.80415)
		(width 0.1651)
		(layer "In5.Cu")
		(net "P5E_PEX3_STN0_RX_DP<4>")
	)
	(segment
		(start 428.512478 -147.778978)
		(end 427.357286 -140.067284)
		(width 0.1651)
		(layer "In5.Cu")
		(net "P5E_PEX3_STN0_RX_DP<4>")
	)
	(segment
		(start 427.357286 -140.067284)
		(end 426.618654 -138.195812)
		(width 0.1651)
		(layer "In5.Cu")
		(net "P5E_PEX3_STN0_RX_DP<4>")
	)
	(segment
		(start 423.868088 -135.287004)
		(end 423.706544 -135.295894)
		(width 0.1651)
		(layer "In5.Cu")
		(net "P5E_PEX3_STN0_RX_DP<4>")
	)
	(segment
		(start 417.784026 -319.941448)
		(end 417.829746 -319.895728)
		(width 0.1143)
		(layer "In15.Cu")
		(net "P5E_PEX3_STN5_RX_DP<92>")
	)
	(segment
		(start 384.290062 -370.872258)
		(end 384.417062 -370.999258)
		(width 0.1651)
		(layer "In15.Cu")
		(net "P5E_PEX3_STN5_RX_DP<92>")
	)
	(segment
		(start 399.423636 -340.199218)
		(end 399.428716 -340.037674)
		(width 0.1651)
		(layer "In15.Cu")
		(net "P5E_PEX3_STN5_RX_DP<92>")
	)
	(segment
		(start 384.847338 -370.999258)
		(end 385.134104 -370.712492)
		(width 0.1651)
		(layer "In15.Cu")
		(net "P5E_PEX3_STN5_RX_DP<92>")
	)
	(segment
		(start 385.65836 -368.41303)
		(end 397.38427 -359.0163)
		(width 0.1651)
		(layer "In15.Cu")
		(net "P5E_PEX3_STN5_RX_DP<92>")
	)
	(segment
		(start 400.84121 -338.869528)
		(end 401.202398 -338.530946)
		(width 0.1651)
		(layer "In15.Cu")
		(net "P5E_PEX3_STN5_RX_DP<92>")
	)
	(segment
		(start 397.38427 -359.0163)
		(end 397.90497 -357.931974)
		(width 0.1651)
		(layer "In15.Cu")
		(net "P5E_PEX3_STN5_RX_DP<92>")
	)
	(segment
		(start 399.951702 -339.703664)
		(end 400.31289 -339.365082)
		(width 0.1651)
		(layer "In15.Cu")
		(net "P5E_PEX3_STN5_RX_DP<92>")
	)
	(segment
		(start 401.202398 -338.530946)
		(end 401.20697 -338.387182)
		(width 0.1651)
		(layer "In15.Cu")
		(net "P5E_PEX3_STN5_RX_DP<92>")
	)
	(segment
		(start 417.829746 -319.895728)
		(end 417.829746 -316.44463)
		(width 0.1143)
		(layer "In15.Cu")
		(net "P5E_PEX3_STN5_RX_DP<92>")
	)
	(segment
		(start 399.790158 -339.698584)
		(end 399.951702 -339.703664)
		(width 0.1651)
		(layer "In15.Cu")
		(net "P5E_PEX3_STN5_RX_DP<92>")
	)
	(segment
		(start 384.417062 -370.999258)
		(end 384.847338 -370.999258)
		(width 0.1651)
		(layer "In15.Cu")
		(net "P5E_PEX3_STN5_RX_DP<92>")
	)
	(segment
		(start 385.134104 -370.712492)
		(end 385.134104 -369.570254)
		(width 0.1651)
		(layer "In15.Cu")
		(net "P5E_PEX3_STN5_RX_DP<92>")
	)
	(segment
		(start 418.399976 -316.115192)
		(end 418.399976 -315.849762)
		(width 0.1143)
		(layer "In15.Cu")
		(net "P5E_PEX3_STN5_RX_DP<92>")
	)
	(segment
		(start 417.829746 -316.44463)
		(end 418.044884 -316.229492)
		(width 0.1143)
		(layer "In15.Cu")
		(net "P5E_PEX3_STN5_RX_DP<92>")
	)
	(segment
		(start 400.679666 -338.864448)
		(end 400.84121 -338.869528)
		(width 0.1651)
		(layer "In15.Cu")
		(net "P5E_PEX3_STN5_RX_DP<92>")
	)
	(segment
		(start 416.26917 -324.402704)
		(end 417.784026 -322.212208)
		(width 0.1651)
		(layer "In15.Cu")
		(net "P5E_PEX3_STN5_RX_DP<92>")
	)
	(segment
		(start 400.31289 -339.365082)
		(end 400.31797 -339.203538)
		(width 0.1651)
		(layer "In15.Cu")
		(net "P5E_PEX3_STN5_RX_DP<92>")
	)
	(segment
		(start 385.134104 -369.570254)
		(end 385.65836 -368.41303)
		(width 0.1651)
		(layer "In15.Cu")
		(net "P5E_PEX3_STN5_RX_DP<92>")
	)
	(segment
		(start 418.044884 -316.229492)
		(end 418.285676 -316.229492)
		(width 0.1143)
		(layer "In15.Cu")
		(net "P5E_PEX3_STN5_RX_DP<92>")
	)
	(segment
		(start 397.90497 -357.931974)
		(end 397.90497 -342.114886)
		(width 0.1651)
		(layer "In15.Cu")
		(net "P5E_PEX3_STN5_RX_DP<92>")
	)
	(segment
		(start 417.784026 -319.969896)
		(end 417.784026 -319.941448)
		(width 0.1143)
		(layer "In15.Cu")
		(net "P5E_PEX3_STN5_RX_DP<92>")
	)
	(segment
		(start 384.290062 -370.489988)
		(end 384.290062 -370.872258)
		(width 0.1651)
		(layer "In15.Cu")
		(net "P5E_PEX3_STN5_RX_DP<92>")
	)
	(segment
		(start 400.31797 -339.203538)
		(end 400.679666 -338.864448)
		(width 0.1651)
		(layer "In15.Cu")
		(net "P5E_PEX3_STN5_RX_DP<92>")
	)
	(segment
		(start 417.784026 -322.212208)
		(end 417.784026 -319.969896)
		(width 0.1651)
		(layer "In15.Cu")
		(net "P5E_PEX3_STN5_RX_DP<92>")
	)
	(segment
		(start 401.20697 -338.387182)
		(end 401.568666 -338.048092)
		(width 0.1651)
		(layer "In15.Cu")
		(net "P5E_PEX3_STN5_RX_DP<92>")
	)
	(segment
		(start 418.285676 -316.229492)
		(end 418.399976 -316.115192)
		(width 0.1143)
		(layer "In15.Cu")
		(net "P5E_PEX3_STN5_RX_DP<92>")
	)
	(segment
		(start 397.90497 -342.114886)
		(end 398.267936 -341.282782)
		(width 0.1651)
		(layer "In15.Cu")
		(net "P5E_PEX3_STN5_RX_DP<92>")
	)
	(segment
		(start 399.428716 -340.037674)
		(end 399.790158 -339.698584)
		(width 0.1651)
		(layer "In15.Cu")
		(net "P5E_PEX3_STN5_RX_DP<92>")
	)
	(segment
		(start 401.568666 -338.048092)
		(end 401.712176 -338.052918)
		(width 0.1651)
		(layer "In15.Cu")
		(net "P5E_PEX3_STN5_RX_DP<92>")
	)
	(segment
		(start 398.267936 -341.282782)
		(end 399.423636 -340.199218)
		(width 0.1651)
		(layer "In15.Cu")
		(net "P5E_PEX3_STN5_RX_DP<92>")
	)
	(segment
		(start 401.712176 -338.052918)
		(end 416.26917 -324.402704)
		(width 0.1651)
		(layer "In15.Cu")
		(net "P5E_PEX3_STN5_RX_DP<92>")
	)
	(segment
		(start 273.582892 -141.36497)
		(end 278.242268 -141.36497)
		(width 0.13208)
		(layer "F.Cu")
		(net "NIC4_BIF2_N")
	)
	(segment
		(start 269.604744 -140.85697)
		(end 270.582644 -140.85697)
		(width 0.13208)
		(layer "F.Cu")
		(net "NIC4_BIF2_N")
	)
	(segment
		(start 270.754602 -140.379196)
		(end 272.597118 -140.379196)
		(width 0.13208)
		(layer "F.Cu")
		(net "NIC4_BIF2_N")
	)
	(segment
		(start 270.582644 -140.551154)
		(end 270.754602 -140.379196)
		(width 0.13208)
		(layer "F.Cu")
		(net "NIC4_BIF2_N")
	)
	(segment
		(start 272.597118 -140.379196)
		(end 273.582892 -141.36497)
		(width 0.13208)
		(layer "F.Cu")
		(net "NIC4_BIF2_N")
	)
	(segment
		(start 270.582644 -140.85697)
		(end 270.582644 -140.551154)
		(width 0.13208)
		(layer "F.Cu")
		(net "NIC4_BIF2_N")
	)
	(via
		(at 272.597118 -140.379196)
		(size 0.762)
		(drill 0.381)
		(layers "F.Cu" "B.Cu")
		(net "NIC4_BIF2_N")
	)
	(segment
		(start 45.554392 -134.165086)
		(end 45.391578 -134.3279)
		(width 0.13462)
		(layer "F.Cu")
		(net "P5E_PEX0_STN1_TX_C_DP<30>")
	)
	(segment
		(start 37.224208 -134.3279)
		(end 36.905184 -134.008876)
		(width 0.13462)
		(layer "F.Cu")
		(net "P5E_PEX0_STN1_TX_C_DP<30>")
	)
	(segment
		(start 45.391578 -134.3279)
		(end 37.224208 -134.3279)
		(width 0.13462)
		(layer "F.Cu")
		(net "P5E_PEX0_STN1_TX_C_DP<30>")
	)
	(segment
		(start 46.042326 -134.165086)
		(end 45.554392 -134.165086)
		(width 0.13462)
		(layer "F.Cu")
		(net "P5E_PEX0_STN1_TX_C_DP<30>")
	)
	(segment
		(start 161.654236 -131.165092)
		(end 161.491422 -131.002278)
		(width 0.13462)
		(layer "F.Cu")
		(net "P5E_PEX1_STN1_TX_C_DN<28>")
	)
	(segment
		(start 161.491422 -131.002278)
		(end 153.326084 -131.002278)
		(width 0.13462)
		(layer "F.Cu")
		(net "P5E_PEX1_STN1_TX_C_DN<28>")
	)
	(segment
		(start 162.14217 -131.165092)
		(end 161.654236 -131.165092)
		(width 0.13462)
		(layer "F.Cu")
		(net "P5E_PEX1_STN1_TX_C_DN<28>")
	)
	(segment
		(start 153.326084 -131.002278)
		(end 153.005028 -131.323334)
		(width 0.13462)
		(layer "F.Cu")
		(net "P5E_PEX1_STN1_TX_C_DN<28>")
	)
	(segment
		(start 242.21948 -30.62732)
		(end 239.705642 -30.62732)
		(width 0.13462)
		(layer "F.Cu")
		(net "P5E_PEX2_STN2_RX_DP<45>")
	)
	(segment
		(start 242.382294 -30.790134)
		(end 242.21948 -30.62732)
		(width 0.13462)
		(layer "F.Cu")
		(net "P5E_PEX2_STN2_RX_DP<45>")
	)
	(segment
		(start 239.705642 -30.62732)
		(end 239.410494 -30.922468)
		(width 0.13462)
		(layer "F.Cu")
		(net "P5E_PEX2_STN2_RX_DP<45>")
	)
	(segment
		(start 242.864894 -30.790134)
		(end 242.382294 -30.790134)
		(width 0.13462)
		(layer "F.Cu")
		(net "P5E_PEX2_STN2_RX_DP<45>")
	)
	(segment
		(start 278.435562 -273.670014)
		(end 278.242014 -273.670014)
		(width 0.1143)
		(layer "In7.Cu")
		(net "P5E_PEX2_STN2_RX_DP<45>")
	)
	(segment
		(start 244.075458 -85.352382)
		(end 244.266466 -61.48832)
		(width 0.1651)
		(layer "In7.Cu")
		(net "P5E_PEX2_STN2_RX_DP<45>")
	)
	(segment
		(start 249.26544 -102.474014)
		(end 244.075458 -85.352382)
		(width 0.1651)
		(layer "In7.Cu")
		(net "P5E_PEX2_STN2_RX_DP<45>")
	)
	(segment
		(start 277.979632 -273.407632)
		(end 277.979632 -271.41932)
		(width 0.1143)
		(layer "In7.Cu")
		(net "P5E_PEX2_STN2_RX_DP<45>")
	)
	(segment
		(start 242.78082 -37.940234)
		(end 243.306092 -34.981642)
		(width 0.1651)
		(layer "In7.Cu")
		(net "P5E_PEX2_STN2_RX_DP<45>")
	)
	(segment
		(start 278.242014 -273.670014)
		(end 277.979632 -273.407632)
		(width 0.1143)
		(layer "In7.Cu")
		(net "P5E_PEX2_STN2_RX_DP<45>")
	)
	(segment
		(start 278.549862 -274.049744)
		(end 278.549862 -273.784314)
		(width 0.1143)
		(layer "In7.Cu")
		(net "P5E_PEX2_STN2_RX_DP<45>")
	)
	(segment
		(start 277.933912 -271.3736)
		(end 277.933912 -271.345152)
		(width 0.1143)
		(layer "In7.Cu")
		(net "P5E_PEX2_STN2_RX_DP<45>")
	)
	(segment
		(start 242.81765 -40.277288)
		(end 242.78082 -37.940234)
		(width 0.1651)
		(layer "In7.Cu")
		(net "P5E_PEX2_STN2_RX_DP<45>")
	)
	(segment
		(start 244.266466 -61.48832)
		(end 244.266466 -60.146692)
		(width 0.1651)
		(layer "In7.Cu")
		(net "P5E_PEX2_STN2_RX_DP<45>")
	)
	(segment
		(start 276.971506 -263.52119)
		(end 277.048468 -255.658366)
		(width 0.1651)
		(layer "In7.Cu")
		(net "P5E_PEX2_STN2_RX_DP<45>")
	)
	(segment
		(start 275.451062 -238.208566)
		(end 257.74015 -144.549876)
		(width 0.1651)
		(layer "In7.Cu")
		(net "P5E_PEX2_STN2_RX_DP<45>")
	)
	(segment
		(start 242.740688 -31.643574)
		(end 242.390168 -31.293054)
		(width 0.1651)
		(layer "In7.Cu")
		(net "P5E_PEX2_STN2_RX_DP<45>")
	)
	(segment
		(start 249.277632 -102.514654)
		(end 249.277378 -102.513892)
		(width 0.1651)
		(layer "In7.Cu")
		(net "P5E_PEX2_STN2_RX_DP<45>")
	)
	(segment
		(start 242.390168 -31.149544)
		(end 241.872262 -30.631638)
		(width 0.1651)
		(layer "In7.Cu")
		(net "P5E_PEX2_STN2_RX_DP<45>")
	)
	(segment
		(start 249.26544 -102.474522)
		(end 249.26544 -102.474014)
		(width 0.1651)
		(layer "In7.Cu")
		(net "P5E_PEX2_STN2_RX_DP<45>")
	)
	(segment
		(start 277.979632 -271.41932)
		(end 277.933912 -271.3736)
		(width 0.1143)
		(layer "In7.Cu")
		(net "P5E_PEX2_STN2_RX_DP<45>")
	)
	(segment
		(start 239.701324 -30.631638)
		(end 239.410494 -30.922468)
		(width 0.1651)
		(layer "In7.Cu")
		(net "P5E_PEX2_STN2_RX_DP<45>")
	)
	(segment
		(start 243.99875 -57.373774)
		(end 244.115844 -49.884838)
		(width 0.1651)
		(layer "In7.Cu")
		(net "P5E_PEX2_STN2_RX_DP<45>")
	)
	(segment
		(start 277.933912 -270.305276)
		(end 276.971506 -263.52119)
		(width 0.1651)
		(layer "In7.Cu")
		(net "P5E_PEX2_STN2_RX_DP<45>")
	)
	(segment
		(start 244.115844 -49.884838)
		(end 242.81765 -40.277288)
		(width 0.1651)
		(layer "In7.Cu")
		(net "P5E_PEX2_STN2_RX_DP<45>")
	)
	(segment
		(start 254.459994 -119.612156)
		(end 249.277632 -102.514654)
		(width 0.1651)
		(layer "In7.Cu")
		(net "P5E_PEX2_STN2_RX_DP<45>")
	)
	(segment
		(start 240.780062 -30.733238)
		(end 240.678462 -30.631638)
		(width 0.1651)
		(layer "In7.Cu")
		(net "P5E_PEX2_STN2_RX_DP<45>")
	)
	(segment
		(start 244.266466 -60.146692)
		(end 243.99875 -57.373774)
		(width 0.1651)
		(layer "In7.Cu")
		(net "P5E_PEX2_STN2_RX_DP<45>")
	)
	(segment
		(start 242.390168 -31.293054)
		(end 242.390168 -31.149544)
		(width 0.1651)
		(layer "In7.Cu")
		(net "P5E_PEX2_STN2_RX_DP<45>")
	)
	(segment
		(start 241.872262 -30.631638)
		(end 241.376962 -30.631638)
		(width 0.1651)
		(layer "In7.Cu")
		(net "P5E_PEX2_STN2_RX_DP<45>")
	)
	(segment
		(start 277.933912 -271.345152)
		(end 277.933912 -270.305276)
		(width 0.1651)
		(layer "In7.Cu")
		(net "P5E_PEX2_STN2_RX_DP<45>")
	)
	(segment
		(start 241.376962 -30.631638)
		(end 241.275362 -30.733238)
		(width 0.1651)
		(layer "In7.Cu")
		(net "P5E_PEX2_STN2_RX_DP<45>")
	)
	(segment
		(start 242.884198 -31.643574)
		(end 242.740688 -31.643574)
		(width 0.1651)
		(layer "In7.Cu")
		(net "P5E_PEX2_STN2_RX_DP<45>")
	)
	(segment
		(start 243.306092 -34.981642)
		(end 243.32946 -32.088836)
		(width 0.1651)
		(layer "In7.Cu")
		(net "P5E_PEX2_STN2_RX_DP<45>")
	)
	(segment
		(start 241.275362 -30.733238)
		(end 240.780062 -30.733238)
		(width 0.1651)
		(layer "In7.Cu")
		(net "P5E_PEX2_STN2_RX_DP<45>")
	)
	(segment
		(start 240.678462 -30.631638)
		(end 239.701324 -30.631638)
		(width 0.1651)
		(layer "In7.Cu")
		(net "P5E_PEX2_STN2_RX_DP<45>")
	)
	(segment
		(start 249.277378 -102.513892)
		(end 249.26544 -102.474522)
		(width 0.1651)
		(layer "In7.Cu")
		(net "P5E_PEX2_STN2_RX_DP<45>")
	)
	(segment
		(start 257.74015 -144.549876)
		(end 254.459994 -119.612156)
		(width 0.1651)
		(layer "In7.Cu")
		(net "P5E_PEX2_STN2_RX_DP<45>")
	)
	(segment
		(start 277.048468 -255.658366)
		(end 275.451062 -238.208566)
		(width 0.1651)
		(layer "In7.Cu")
		(net "P5E_PEX2_STN2_RX_DP<45>")
	)
	(segment
		(start 278.549862 -273.784314)
		(end 278.435562 -273.670014)
		(width 0.1143)
		(layer "In7.Cu")
		(net "P5E_PEX2_STN2_RX_DP<45>")
	)
	(segment
		(start 243.32946 -32.088836)
		(end 242.884198 -31.643574)
		(width 0.1651)
		(layer "In7.Cu")
		(net "P5E_PEX2_STN2_RX_DP<45>")
	)
	(segment
		(start 416.95751 -155.954984)
		(end 416.47491 -155.954984)
		(width 0.13462)
		(layer "F.Cu")
		(net "P5E_PEX3_STN0_RX_DP<15>")
	)
	(segment
		(start 413.799528 -155.7909)
		(end 413.50311 -156.087318)
		(width 0.13462)
		(layer "F.Cu")
		(net "P5E_PEX3_STN0_RX_DP<15>")
	)
	(segment
		(start 416.310826 -155.7909)
		(end 413.799528 -155.7909)
		(width 0.13462)
		(layer "F.Cu")
		(net "P5E_PEX3_STN0_RX_DP<15>")
	)
	(segment
		(start 416.47491 -155.954984)
		(end 416.310826 -155.7909)
		(width 0.13462)
		(layer "F.Cu")
		(net "P5E_PEX3_STN0_RX_DP<15>")
	)
	(segment
		(start 415.186876 -157.61335)
		(end 415.086292 -157.537912)
		(width 0.1651)
		(layer "In5.Cu")
		(net "P5E_PEX3_STN0_RX_DP<15>")
	)
	(segment
		(start 422.53408 -270.204692)
		(end 423.00652 -267.744956)
		(width 0.1651)
		(layer "In5.Cu")
		(net "P5E_PEX3_STN0_RX_DP<15>")
	)
	(segment
		(start 415.017204 -157.047184)
		(end 415.092896 -156.9466)
		(width 0.1651)
		(layer "In5.Cu")
		(net "P5E_PEX3_STN0_RX_DP<15>")
	)
	(segment
		(start 422.837356 -261.285482)
		(end 415.930588 -162.8902)
		(width 0.1651)
		(layer "In5.Cu")
		(net "P5E_PEX3_STN0_RX_DP<15>")
	)
	(segment
		(start 414.997138 -156.267404)
		(end 414.526222 -155.796488)
		(width 0.1651)
		(layer "In5.Cu")
		(net "P5E_PEX3_STN0_RX_DP<15>")
	)
	(segment
		(start 415.349944 -158.77032)
		(end 415.24936 -158.694882)
		(width 0.1651)
		(layer "In5.Cu")
		(net "P5E_PEX3_STN0_RX_DP<15>")
	)
	(segment
		(start 415.086292 -157.537912)
		(end 415.017204 -157.047184)
		(width 0.1651)
		(layer "In5.Cu")
		(net "P5E_PEX3_STN0_RX_DP<15>")
	)
	(segment
		(start 415.24936 -158.694882)
		(end 415.180272 -158.204154)
		(width 0.1651)
		(layer "In5.Cu")
		(net "P5E_PEX3_STN0_RX_DP<15>")
	)
	(segment
		(start 415.930588 -162.8902)
		(end 415.349944 -158.77032)
		(width 0.1651)
		(layer "In5.Cu")
		(net "P5E_PEX3_STN0_RX_DP<15>")
	)
	(segment
		(start 414.526222 -155.796488)
		(end 413.910526 -155.796488)
		(width 0.1651)
		(layer "In5.Cu")
		(net "P5E_PEX3_STN0_RX_DP<15>")
	)
	(segment
		(start 422.53408 -271.526)
		(end 422.53408 -270.204692)
		(width 0.1651)
		(layer "In5.Cu")
		(net "P5E_PEX3_STN0_RX_DP<15>")
	)
	(segment
		(start 423.149776 -274.049744)
		(end 423.149776 -273.784314)
		(width 0.1143)
		(layer "In5.Cu")
		(net "P5E_PEX3_STN0_RX_DP<15>")
	)
	(segment
		(start 415.255964 -158.10357)
		(end 415.186876 -157.61335)
		(width 0.1651)
		(layer "In5.Cu")
		(net "P5E_PEX3_STN0_RX_DP<15>")
	)
	(segment
		(start 423.00652 -267.744956)
		(end 422.837356 -261.285482)
		(width 0.1651)
		(layer "In5.Cu")
		(net "P5E_PEX3_STN0_RX_DP<15>")
	)
	(segment
		(start 422.5798 -271.600168)
		(end 422.53408 -271.554448)
		(width 0.1143)
		(layer "In5.Cu")
		(net "P5E_PEX3_STN0_RX_DP<15>")
	)
	(segment
		(start 415.092896 -156.9466)
		(end 414.997138 -156.267404)
		(width 0.1651)
		(layer "In5.Cu")
		(net "P5E_PEX3_STN0_RX_DP<15>")
	)
	(segment
		(start 422.5798 -273.45513)
		(end 422.5798 -271.600168)
		(width 0.1143)
		(layer "In5.Cu")
		(net "P5E_PEX3_STN0_RX_DP<15>")
	)
	(segment
		(start 413.910526 -155.796488)
		(end 413.711644 -155.878784)
		(width 0.1651)
		(layer "In5.Cu")
		(net "P5E_PEX3_STN0_RX_DP<15>")
	)
	(segment
		(start 423.149776 -273.784314)
		(end 423.035476 -273.670014)
		(width 0.1143)
		(layer "In5.Cu")
		(net "P5E_PEX3_STN0_RX_DP<15>")
	)
	(segment
		(start 423.035476 -273.670014)
		(end 422.794684 -273.670014)
		(width 0.1143)
		(layer "In5.Cu")
		(net "P5E_PEX3_STN0_RX_DP<15>")
	)
	(segment
		(start 422.794684 -273.670014)
		(end 422.5798 -273.45513)
		(width 0.1143)
		(layer "In5.Cu")
		(net "P5E_PEX3_STN0_RX_DP<15>")
	)
	(segment
		(start 413.711644 -155.878784)
		(end 413.50311 -156.087318)
		(width 0.1651)
		(layer "In5.Cu")
		(net "P5E_PEX3_STN0_RX_DP<15>")
	)
	(segment
		(start 415.180272 -158.204154)
		(end 415.255964 -158.10357)
		(width 0.1651)
		(layer "In5.Cu")
		(net "P5E_PEX3_STN0_RX_DP<15>")
	)
	(segment
		(start 422.53408 -271.554448)
		(end 422.53408 -271.526)
		(width 0.1143)
		(layer "In5.Cu")
		(net "P5E_PEX3_STN0_RX_DP<15>")
	)
	(segment
		(start 399.463768 -350.685862)
		(end 399.463768 -351.31629)
		(width 0.13462)
		(layer "F.Cu")
		(net "P5E_PEX3_STN5_TX_C_DP<93>")
	)
	(segment
		(start 399.463768 -351.31629)
		(end 399.16862 -351.611438)
		(width 0.13462)
		(layer "F.Cu")
		(net "P5E_PEX3_STN5_TX_C_DP<93>")
	)
	(segment
		(start 399.14322 -350.365314)
		(end 399.463768 -350.685862)
		(width 0.13462)
		(layer "F.Cu")
		(net "P5E_PEX3_STN5_TX_C_DP<93>")
	)
	(segment
		(start 386.616956 -379.899164)
		(end 386.489956 -379.772164)
		(width 0.1651)
		(layer "In13.Cu")
		(net "P5E_PEX3_STN5_TX_C_DP<93>")
	)
	(segment
		(start 387.333998 -379.612398)
		(end 387.047232 -379.899164)
		(width 0.1651)
		(layer "In13.Cu")
		(net "P5E_PEX3_STN5_TX_C_DP<93>")
	)
	(segment
		(start 397.190214 -359.621582)
		(end 389.608314 -366.65789)
		(width 0.1651)
		(layer "In13.Cu")
		(net "P5E_PEX3_STN5_TX_C_DP<93>")
	)
	(segment
		(start 387.994144 -368.155982)
		(end 387.333998 -369.66906)
		(width 0.1651)
		(layer "In13.Cu")
		(net "P5E_PEX3_STN5_TX_C_DP<93>")
	)
	(segment
		(start 399.45945 -352.356166)
		(end 397.90497 -353.910646)
		(width 0.1651)
		(layer "In13.Cu")
		(net "P5E_PEX3_STN5_TX_C_DP<93>")
	)
	(segment
		(start 389.482838 -366.653064)
		(end 389.119364 -366.990376)
		(width 0.1651)
		(layer "In13.Cu")
		(net "P5E_PEX3_STN5_TX_C_DP<93>")
	)
	(segment
		(start 387.333998 -369.66906)
		(end 387.333998 -379.612398)
		(width 0.1651)
		(layer "In13.Cu")
		(net "P5E_PEX3_STN5_TX_C_DP<93>")
	)
	(segment
		(start 399.45945 -351.902268)
		(end 399.45945 -352.356166)
		(width 0.1651)
		(layer "In13.Cu")
		(net "P5E_PEX3_STN5_TX_C_DP<93>")
	)
	(segment
		(start 389.119364 -366.990376)
		(end 389.114792 -367.116106)
		(width 0.1651)
		(layer "In13.Cu")
		(net "P5E_PEX3_STN5_TX_C_DP<93>")
	)
	(segment
		(start 386.489956 -379.772164)
		(end 386.489956 -379.390148)
		(width 0.1651)
		(layer "In13.Cu")
		(net "P5E_PEX3_STN5_TX_C_DP<93>")
	)
	(segment
		(start 387.047232 -379.899164)
		(end 386.616956 -379.899164)
		(width 0.1651)
		(layer "In13.Cu")
		(net "P5E_PEX3_STN5_TX_C_DP<93>")
	)
	(segment
		(start 389.608314 -366.65789)
		(end 389.482838 -366.653064)
		(width 0.1651)
		(layer "In13.Cu")
		(net "P5E_PEX3_STN5_TX_C_DP<93>")
	)
	(segment
		(start 397.90497 -357.982774)
		(end 397.190214 -359.621582)
		(width 0.1651)
		(layer "In13.Cu")
		(net "P5E_PEX3_STN5_TX_C_DP<93>")
	)
	(segment
		(start 397.90497 -353.910646)
		(end 397.90497 -357.982774)
		(width 0.1651)
		(layer "In13.Cu")
		(net "P5E_PEX3_STN5_TX_C_DP<93>")
	)
	(segment
		(start 399.16862 -351.611438)
		(end 399.45945 -351.902268)
		(width 0.1651)
		(layer "In13.Cu")
		(net "P5E_PEX3_STN5_TX_C_DP<93>")
	)
	(segment
		(start 389.114792 -367.116106)
		(end 387.994144 -368.155982)
		(width 0.1651)
		(layer "In13.Cu")
		(net "P5E_PEX3_STN5_TX_C_DP<93>")
	)
	(segment
		(start 272.529808 -143.401796)
		(end 272.58137 -143.350234)
		(width 0.13208)
		(layer "F.Cu")
		(net "NIC4_BIF0_N")
	)
	(segment
		(start 269.604744 -142.88897)
		(end 270.587724 -142.88897)
		(width 0.13208)
		(layer "F.Cu")
		(net "NIC4_BIF0_N")
	)
	(segment
		(start 270.587724 -142.88897)
		(end 270.590772 -142.892018)
		(width 0.13208)
		(layer "F.Cu")
		(net "NIC4_BIF0_N")
	)
	(segment
		(start 272.58137 -143.350234)
		(end 273.921982 -143.350234)
		(width 0.13208)
		(layer "F.Cu")
		(net "NIC4_BIF0_N")
	)
	(segment
		(start 270.590772 -142.892018)
		(end 270.590772 -143.274796)
		(width 0.13208)
		(layer "F.Cu")
		(net "NIC4_BIF0_N")
	)
	(segment
		(start 273.921982 -143.350234)
		(end 274.707096 -142.56512)
		(width 0.13208)
		(layer "F.Cu")
		(net "NIC4_BIF0_N")
	)
	(segment
		(start 270.717772 -143.401796)
		(end 272.529808 -143.401796)
		(width 0.13208)
		(layer "F.Cu")
		(net "NIC4_BIF0_N")
	)
	(segment
		(start 274.707096 -142.56512)
		(end 278.242268 -142.56512)
		(width 0.13208)
		(layer "F.Cu")
		(net "NIC4_BIF0_N")
	)
	(segment
		(start 270.590772 -143.274796)
		(end 270.717772 -143.401796)
		(width 0.13208)
		(layer "F.Cu")
		(net "NIC4_BIF0_N")
	)
	(via
		(at 272.58137 -143.350234)
		(size 0.762)
		(drill 0.381)
		(layers "F.Cu" "B.Cu")
		(net "NIC4_BIF0_N")
	)
	(segment
		(start 45.554392 -100.045012)
		(end 45.391578 -99.882198)
		(width 0.13462)
		(layer "F.Cu")
		(net "P5E_PEX0_STN1_TX_C_DN<16>")
	)
	(segment
		(start 45.391578 -99.882198)
		(end 39.868348 -99.882198)
		(width 0.13462)
		(layer "F.Cu")
		(net "P5E_PEX0_STN1_TX_C_DN<16>")
	)
	(segment
		(start 39.868348 -99.882198)
		(end 39.547292 -100.203254)
		(width 0.13462)
		(layer "F.Cu")
		(net "P5E_PEX0_STN1_TX_C_DN<16>")
	)
	(segment
		(start 46.042326 -100.045012)
		(end 45.554392 -100.045012)
		(width 0.13462)
		(layer "F.Cu")
		(net "P5E_PEX0_STN1_TX_C_DN<16>")
	)
	(segment
		(start 167.230298 -131.165092)
		(end 167.393112 -131.002278)
		(width 0.13462)
		(layer "F.Cu")
		(net "P5E_PEX1_STN1_RX_DN<28>")
	)
	(segment
		(start 169.901616 -131.002278)
		(end 169.902124 -131.00177)
		(width 0.13462)
		(layer "F.Cu")
		(net "P5E_PEX1_STN1_RX_DN<28>")
	)
	(segment
		(start 167.393112 -131.002278)
		(end 169.901616 -131.002278)
		(width 0.13462)
		(layer "F.Cu")
		(net "P5E_PEX1_STN1_RX_DN<28>")
	)
	(segment
		(start 169.902124 -131.00177)
		(end 170.196764 -131.29641)
		(width 0.13462)
		(layer "F.Cu")
		(net "P5E_PEX1_STN1_RX_DN<28>")
	)
	(segment
		(start 166.742364 -131.165092)
		(end 167.230298 -131.165092)
		(width 0.13462)
		(layer "F.Cu")
		(net "P5E_PEX1_STN1_RX_DN<28>")
	)
	(segment
		(start 157.738318 -156.892244)
		(end 157.143958 -147.684744)
		(width 0.1651)
		(layer "In5.Cu")
		(net "P5E_PEX1_STN1_RX_DN<28>")
	)
	(segment
		(start 161.65576 -142.812262)
		(end 162.067748 -142.536926)
		(width 0.1651)
		(layer "In5.Cu")
		(net "P5E_PEX1_STN1_RX_DN<28>")
	)
	(segment
		(start 166.24427 -132.49148)
		(end 166.228268 -132.330698)
		(width 0.1651)
		(layer "In5.Cu")
		(net "P5E_PEX1_STN1_RX_DN<28>")
	)
	(segment
		(start 187.035186 -273.479514)
		(end 186.873388 -273.479514)
		(width 0.1143)
		(layer "In5.Cu")
		(net "P5E_PEX1_STN1_RX_DN<28>")
	)
	(segment
		(start 187.14974 -273.099784)
		(end 187.14974 -273.36496)
		(width 0.1143)
		(layer "In5.Cu")
		(net "P5E_PEX1_STN1_RX_DN<28>")
	)
	(segment
		(start 165.413182 -133.323584)
		(end 165.768782 -132.890514)
		(width 0.1651)
		(layer "In5.Cu")
		(net "P5E_PEX1_STN1_RX_DN<28>")
	)
	(segment
		(start 158.690564 -145.218658)
		(end 158.985204 -144.82064)
		(width 0.1651)
		(layer "In5.Cu")
		(net "P5E_PEX1_STN1_RX_DN<28>")
	)
	(segment
		(start 166.703248 -131.932172)
		(end 167.0177 -131.54914)
		(width 0.1651)
		(layer "In5.Cu")
		(net "P5E_PEX1_STN1_RX_DN<28>")
	)
	(segment
		(start 160.48355 -143.458184)
		(end 160.642046 -143.48968)
		(width 0.1651)
		(layer "In5.Cu")
		(net "P5E_PEX1_STN1_RX_DN<28>")
	)
	(segment
		(start 167.001952 -131.388358)
		(end 167.31615 -131.00558)
		(width 0.1651)
		(layer "In5.Cu")
		(net "P5E_PEX1_STN1_RX_DN<28>")
	)
	(segment
		(start 164.7571 -134.907528)
		(end 164.946584 -134.450074)
		(width 0.1651)
		(layer "In5.Cu")
		(net "P5E_PEX1_STN1_RX_DN<28>")
	)
	(segment
		(start 165.09619 -134.388352)
		(end 165.285674 -133.93039)
		(width 0.1651)
		(layer "In5.Cu")
		(net "P5E_PEX1_STN1_RX_DN<28>")
	)
	(segment
		(start 164.819076 -135.05688)
		(end 164.7571 -134.907528)
		(width 0.1651)
		(layer "In5.Cu")
		(net "P5E_PEX1_STN1_RX_DN<28>")
	)
	(segment
		(start 169.905934 -131.00558)
		(end 170.196764 -131.29641)
		(width 0.1651)
		(layer "In5.Cu")
		(net "P5E_PEX1_STN1_RX_DN<28>")
	)
	(segment
		(start 157.143958 -147.684744)
		(end 157.312106 -147.079716)
		(width 0.1651)
		(layer "In5.Cu")
		(net "P5E_PEX1_STN1_RX_DN<28>")
	)
	(segment
		(start 168.767252 -131.11988)
		(end 169.262552 -131.11988)
		(width 0.1651)
		(layer "In5.Cu")
		(net "P5E_PEX1_STN1_RX_DN<28>")
	)
	(segment
		(start 165.223698 -133.781038)
		(end 165.413182 -133.323584)
		(width 0.1651)
		(layer "In5.Cu")
		(net "P5E_PEX1_STN1_RX_DN<28>")
	)
	(segment
		(start 186.873388 -273.479514)
		(end 186.77001 -273.376136)
		(width 0.1143)
		(layer "In5.Cu")
		(net "P5E_PEX1_STN1_RX_DN<28>")
	)
	(segment
		(start 162.945318 -141.813026)
		(end 163.875466 -140.883132)
		(width 0.1651)
		(layer "In5.Cu")
		(net "P5E_PEX1_STN1_RX_DN<28>")
	)
	(segment
		(start 186.77001 -271.848072)
		(end 186.81573 -271.802352)
		(width 0.1143)
		(layer "In5.Cu")
		(net "P5E_PEX1_STN1_RX_DN<28>")
	)
	(segment
		(start 166.228268 -132.330698)
		(end 166.542466 -131.94792)
		(width 0.1651)
		(layer "In5.Cu")
		(net "P5E_PEX1_STN1_RX_DN<28>")
	)
	(segment
		(start 165.929564 -132.874512)
		(end 166.24427 -132.49148)
		(width 0.1651)
		(layer "In5.Cu")
		(net "P5E_PEX1_STN1_RX_DN<28>")
	)
	(segment
		(start 164.629592 -135.514842)
		(end 164.819076 -135.05688)
		(width 0.1651)
		(layer "In5.Cu")
		(net "P5E_PEX1_STN1_RX_DN<28>")
	)
	(segment
		(start 186.81573 -271.802352)
		(end 186.81573 -271.773904)
		(width 0.1143)
		(layer "In5.Cu")
		(net "P5E_PEX1_STN1_RX_DN<28>")
	)
	(segment
		(start 165.768782 -132.890514)
		(end 165.929564 -132.874512)
		(width 0.1651)
		(layer "In5.Cu")
		(net "P5E_PEX1_STN1_RX_DN<28>")
	)
	(segment
		(start 164.096446 -136.502648)
		(end 164.479986 -135.576564)
		(width 0.1651)
		(layer "In5.Cu")
		(net "P5E_PEX1_STN1_RX_DN<28>")
	)
	(segment
		(start 169.262552 -131.11988)
		(end 169.376852 -131.00558)
		(width 0.1651)
		(layer "In5.Cu")
		(net "P5E_PEX1_STN1_RX_DN<28>")
	)
	(segment
		(start 158.259526 -145.800572)
		(end 158.419292 -145.776696)
		(width 0.1651)
		(layer "In5.Cu")
		(net "P5E_PEX1_STN1_RX_DN<28>")
	)
	(segment
		(start 187.14974 -273.36496)
		(end 187.035186 -273.479514)
		(width 0.1143)
		(layer "In5.Cu")
		(net "P5E_PEX1_STN1_RX_DN<28>")
	)
	(segment
		(start 158.419292 -145.776696)
		(end 158.71444 -145.378424)
		(width 0.1651)
		(layer "In5.Cu")
		(net "P5E_PEX1_STN1_RX_DN<28>")
	)
	(segment
		(start 160.071816 -143.733266)
		(end 160.48355 -143.458184)
		(width 0.1651)
		(layer "In5.Cu")
		(net "P5E_PEX1_STN1_RX_DN<28>")
	)
	(segment
		(start 161.054034 -143.214344)
		(end 161.08553 -143.055848)
		(width 0.1651)
		(layer "In5.Cu")
		(net "P5E_PEX1_STN1_RX_DN<28>")
	)
	(segment
		(start 168.652952 -131.00558)
		(end 168.767252 -131.11988)
		(width 0.1651)
		(layer "In5.Cu")
		(net "P5E_PEX1_STN1_RX_DN<28>")
	)
	(segment
		(start 157.312106 -147.079716)
		(end 158.259526 -145.800572)
		(width 0.1651)
		(layer "In5.Cu")
		(net "P5E_PEX1_STN1_RX_DN<28>")
	)
	(segment
		(start 161.497264 -142.780766)
		(end 161.65576 -142.812262)
		(width 0.1651)
		(layer "In5.Cu")
		(net "P5E_PEX1_STN1_RX_DN<28>")
	)
	(segment
		(start 158.71444 -145.378424)
		(end 158.690564 -145.218658)
		(width 0.1651)
		(layer "In5.Cu")
		(net "P5E_PEX1_STN1_RX_DN<28>")
	)
	(segment
		(start 160.642046 -143.48968)
		(end 161.054034 -143.214344)
		(width 0.1651)
		(layer "In5.Cu")
		(net "P5E_PEX1_STN1_RX_DN<28>")
	)
	(segment
		(start 164.479986 -135.576564)
		(end 164.629592 -135.514842)
		(width 0.1651)
		(layer "In5.Cu")
		(net "P5E_PEX1_STN1_RX_DN<28>")
	)
	(segment
		(start 161.08553 -143.055848)
		(end 161.497264 -142.780766)
		(width 0.1651)
		(layer "In5.Cu")
		(net "P5E_PEX1_STN1_RX_DN<28>")
	)
	(segment
		(start 167.0177 -131.54914)
		(end 167.001952 -131.388358)
		(width 0.1651)
		(layer "In5.Cu")
		(net "P5E_PEX1_STN1_RX_DN<28>")
	)
	(segment
		(start 169.376852 -131.00558)
		(end 169.905934 -131.00558)
		(width 0.1651)
		(layer "In5.Cu")
		(net "P5E_PEX1_STN1_RX_DN<28>")
	)
	(segment
		(start 166.542466 -131.94792)
		(end 166.703248 -131.932172)
		(width 0.1651)
		(layer "In5.Cu")
		(net "P5E_PEX1_STN1_RX_DN<28>")
	)
	(segment
		(start 186.81573 -267.605256)
		(end 158.491682 -161.14268)
		(width 0.1651)
		(layer "In5.Cu")
		(net "P5E_PEX1_STN1_RX_DN<28>")
	)
	(segment
		(start 164.096446 -140.348462)
		(end 164.096446 -136.502648)
		(width 0.1651)
		(layer "In5.Cu")
		(net "P5E_PEX1_STN1_RX_DN<28>")
	)
	(segment
		(start 158.491682 -161.14268)
		(end 157.738318 -156.892244)
		(width 0.1651)
		(layer "In5.Cu")
		(net "P5E_PEX1_STN1_RX_DN<28>")
	)
	(segment
		(start 186.77001 -273.376136)
		(end 186.77001 -271.848072)
		(width 0.1143)
		(layer "In5.Cu")
		(net "P5E_PEX1_STN1_RX_DN<28>")
	)
	(segment
		(start 165.285674 -133.93039)
		(end 165.223698 -133.781038)
		(width 0.1651)
		(layer "In5.Cu")
		(net "P5E_PEX1_STN1_RX_DN<28>")
	)
	(segment
		(start 158.985204 -144.82064)
		(end 160.071816 -143.733266)
		(width 0.1651)
		(layer "In5.Cu")
		(net "P5E_PEX1_STN1_RX_DN<28>")
	)
	(segment
		(start 163.875466 -140.883132)
		(end 164.096446 -140.348462)
		(width 0.1651)
		(layer "In5.Cu")
		(net "P5E_PEX1_STN1_RX_DN<28>")
	)
	(segment
		(start 164.946584 -134.450074)
		(end 165.09619 -134.388352)
		(width 0.1651)
		(layer "In5.Cu")
		(net "P5E_PEX1_STN1_RX_DN<28>")
	)
	(segment
		(start 162.099244 -142.37843)
		(end 162.945318 -141.813026)
		(width 0.1651)
		(layer "In5.Cu")
		(net "P5E_PEX1_STN1_RX_DN<28>")
	)
	(segment
		(start 162.067748 -142.536926)
		(end 162.099244 -142.37843)
		(width 0.1651)
		(layer "In5.Cu")
		(net "P5E_PEX1_STN1_RX_DN<28>")
	)
	(segment
		(start 167.31615 -131.00558)
		(end 168.652952 -131.00558)
		(width 0.1651)
		(layer "In5.Cu")
		(net "P5E_PEX1_STN1_RX_DN<28>")
	)
	(segment
		(start 186.81573 -271.773904)
		(end 186.81573 -267.605256)
		(width 0.1651)
		(layer "In5.Cu")
		(net "P5E_PEX1_STN1_RX_DN<28>")
	)
	(segment
		(start 320.225166 -32.14878)
		(end 319.554606 -32.14878)
		(width 0.13462)
		(layer "F.Cu")
		(net "P5E_PEX2_STN2_RX_DN<34>")
	)
	(segment
		(start 319.554606 -32.14878)
		(end 319.264538 -31.858712)
		(width 0.13462)
		(layer "F.Cu")
		(net "P5E_PEX2_STN2_RX_DN<34>")
	)
	(segment
		(start 320.383916 -31.99003)
		(end 320.225166 -32.14878)
		(width 0.13462)
		(layer "F.Cu")
		(net "P5E_PEX2_STN2_RX_DN<34>")
	)
	(segment
		(start 320.864738 -31.99003)
		(end 320.383916 -31.99003)
		(width 0.13462)
		(layer "F.Cu")
		(net "P5E_PEX2_STN2_RX_DN<34>")
	)
	(segment
		(start 288.665666 -271.392904)
		(end 288.665666 -271.421352)
		(width 0.1143)
		(layer "In7.Cu")
		(net "P5E_PEX2_STN2_RX_DN<34>")
	)
	(segment
		(start 320.608198 -34.984944)
		(end 320.082926 -37.803074)
		(width 0.1651)
		(layer "In7.Cu")
		(net "P5E_PEX2_STN2_RX_DN<34>")
	)
	(segment
		(start 319.264538 -31.858712)
		(end 319.555368 -32.149542)
		(width 0.1651)
		(layer "In7.Cu")
		(net "P5E_PEX2_STN2_RX_DN<34>")
	)
	(segment
		(start 321.244976 -61.090556)
		(end 310.258206 -116.468398)
		(width 0.1651)
		(layer "In7.Cu")
		(net "P5E_PEX2_STN2_RX_DN<34>")
	)
	(segment
		(start 320.097912 -38.757098)
		(end 320.112898 -39.71036)
		(width 0.1651)
		(layer "In7.Cu")
		(net "P5E_PEX2_STN2_RX_DN<34>")
	)
	(segment
		(start 288.619946 -275.275802)
		(end 288.723832 -275.379688)
		(width 0.1143)
		(layer "In7.Cu")
		(net "P5E_PEX2_STN2_RX_DN<34>")
	)
	(segment
		(start 309.941976 -143.750284)
		(end 308.55158 -154.552142)
		(width 0.1651)
		(layer "In7.Cu")
		(net "P5E_PEX2_STN2_RX_DN<34>")
	)
	(segment
		(start 320.000884 -32.149542)
		(end 320.642234 -32.790892)
		(width 0.1651)
		(layer "In7.Cu")
		(net "P5E_PEX2_STN2_RX_DN<34>")
	)
	(segment
		(start 320.112898 -39.71036)
		(end 321.427094 -49.435766)
		(width 0.1651)
		(layer "In7.Cu")
		(net "P5E_PEX2_STN2_RX_DN<34>")
	)
	(segment
		(start 320.097912 -38.756844)
		(end 320.097912 -38.757098)
		(width 0.1651)
		(layer "In7.Cu")
		(net "P5E_PEX2_STN2_RX_DN<34>")
	)
	(segment
		(start 320.082926 -37.803074)
		(end 320.097912 -38.756844)
		(width 0.1651)
		(layer "In7.Cu")
		(net "P5E_PEX2_STN2_RX_DN<34>")
	)
	(segment
		(start 288.88563 -275.379688)
		(end 288.99993 -275.265388)
		(width 0.1143)
		(layer "In7.Cu")
		(net "P5E_PEX2_STN2_RX_DN<34>")
	)
	(segment
		(start 308.55158 -154.552142)
		(end 288.992564 -266.859512)
		(width 0.1651)
		(layer "In7.Cu")
		(net "P5E_PEX2_STN2_RX_DN<34>")
	)
	(segment
		(start 288.992564 -266.859512)
		(end 288.665666 -270.653256)
		(width 0.1651)
		(layer "In7.Cu")
		(net "P5E_PEX2_STN2_RX_DN<34>")
	)
	(segment
		(start 288.665666 -271.421352)
		(end 288.619946 -271.467072)
		(width 0.1143)
		(layer "In7.Cu")
		(net "P5E_PEX2_STN2_RX_DN<34>")
	)
	(segment
		(start 320.642234 -32.790892)
		(end 320.608198 -34.984944)
		(width 0.1651)
		(layer "In7.Cu")
		(net "P5E_PEX2_STN2_RX_DN<34>")
	)
	(segment
		(start 321.427094 -49.435766)
		(end 321.244976 -61.090556)
		(width 0.1651)
		(layer "In7.Cu")
		(net "P5E_PEX2_STN2_RX_DN<34>")
	)
	(segment
		(start 288.723832 -275.379688)
		(end 288.88563 -275.379688)
		(width 0.1143)
		(layer "In7.Cu")
		(net "P5E_PEX2_STN2_RX_DN<34>")
	)
	(segment
		(start 288.99993 -275.265388)
		(end 288.99993 -274.999958)
		(width 0.1143)
		(layer "In7.Cu")
		(net "P5E_PEX2_STN2_RX_DN<34>")
	)
	(segment
		(start 310.258206 -116.468398)
		(end 309.941976 -143.750284)
		(width 0.1651)
		(layer "In7.Cu")
		(net "P5E_PEX2_STN2_RX_DN<34>")
	)
	(segment
		(start 288.619946 -271.467072)
		(end 288.619946 -275.275802)
		(width 0.1143)
		(layer "In7.Cu")
		(net "P5E_PEX2_STN2_RX_DN<34>")
	)
	(segment
		(start 319.555368 -32.149542)
		(end 320.000884 -32.149542)
		(width 0.1651)
		(layer "In7.Cu")
		(net "P5E_PEX2_STN2_RX_DN<34>")
	)
	(segment
		(start 288.665666 -270.653256)
		(end 288.665666 -271.392904)
		(width 0.1651)
		(layer "In7.Cu")
		(net "P5E_PEX2_STN2_RX_DN<34>")
	)
	(segment
		(start 415.61893 -154.0256)
		(end 416.348926 -154.0256)
		(width 0.13462)
		(layer "F.Cu")
		(net "P5E_PEX3_STN0_RX_DP<14>")
	)
	(segment
		(start 415.35731 -154.28722)
		(end 415.61893 -154.0256)
		(width 0.13462)
		(layer "F.Cu")
		(net "P5E_PEX3_STN0_RX_DP<14>")
	)
	(segment
		(start 416.348926 -154.0256)
		(end 416.478466 -154.15514)
		(width 0.13462)
		(layer "F.Cu")
		(net "P5E_PEX3_STN0_RX_DP<14>")
	)
	(segment
		(start 416.478466 -154.15514)
		(end 416.95751 -154.15514)
		(width 0.13462)
		(layer "F.Cu")
		(net "P5E_PEX3_STN0_RX_DP<14>")
	)
	(segment
		(start 416.91814 -162.09645)
		(end 417.334192 -164.703506)
		(width 0.1651)
		(layer "In5.Cu")
		(net "P5E_PEX3_STN0_RX_DP<14>")
	)
	(segment
		(start 423.52976 -271.644872)
		(end 423.52976 -275.35505)
		(width 0.1143)
		(layer "In5.Cu")
		(net "P5E_PEX3_STN0_RX_DP<14>")
	)
	(segment
		(start 423.48404 -271.570704)
		(end 423.48404 -271.599152)
		(width 0.1143)
		(layer "In5.Cu")
		(net "P5E_PEX3_STN0_RX_DP<14>")
	)
	(segment
		(start 423.744644 -275.569934)
		(end 423.985436 -275.569934)
		(width 0.1143)
		(layer "In5.Cu")
		(net "P5E_PEX3_STN0_RX_DP<14>")
	)
	(segment
		(start 416.654742 -156.514038)
		(end 416.54857 -156.635958)
		(width 0.1651)
		(layer "In5.Cu")
		(net "P5E_PEX3_STN0_RX_DP<14>")
	)
	(segment
		(start 415.962846 -153.99512)
		(end 416.342576 -154.37485)
		(width 0.1651)
		(layer "In5.Cu")
		(net "P5E_PEX3_STN0_RX_DP<14>")
	)
	(segment
		(start 416.49904 -155.913836)
		(end 416.62096 -156.020008)
		(width 0.1651)
		(layer "In5.Cu")
		(net "P5E_PEX3_STN0_RX_DP<14>")
	)
	(segment
		(start 416.582352 -157.130242)
		(end 416.704526 -157.236414)
		(width 0.1651)
		(layer "In5.Cu")
		(net "P5E_PEX3_STN0_RX_DP<14>")
	)
	(segment
		(start 416.704526 -157.236414)
		(end 416.800538 -158.641796)
		(width 0.1651)
		(layer "In5.Cu")
		(net "P5E_PEX3_STN0_RX_DP<14>")
	)
	(segment
		(start 415.64941 -153.99512)
		(end 415.962846 -153.99512)
		(width 0.1651)
		(layer "In5.Cu")
		(net "P5E_PEX3_STN0_RX_DP<14>")
	)
	(segment
		(start 416.8013 -160.396682)
		(end 416.91814 -162.09645)
		(width 0.1651)
		(layer "In5.Cu")
		(net "P5E_PEX3_STN0_RX_DP<14>")
	)
	(segment
		(start 416.342576 -154.37485)
		(end 416.537648 -154.803856)
		(width 0.1651)
		(layer "In5.Cu")
		(net "P5E_PEX3_STN0_RX_DP<14>")
	)
	(segment
		(start 415.35731 -154.28722)
		(end 415.64941 -153.99512)
		(width 0.1651)
		(layer "In5.Cu")
		(net "P5E_PEX3_STN0_RX_DP<14>")
	)
	(segment
		(start 423.763694 -258.33578)
		(end 423.978324 -267.788136)
		(width 0.1651)
		(layer "In5.Cu")
		(net "P5E_PEX3_STN0_RX_DP<14>")
	)
	(segment
		(start 416.800538 -158.641796)
		(end 416.8013 -158.642304)
		(width 0.1651)
		(layer "In5.Cu")
		(net "P5E_PEX3_STN0_RX_DP<14>")
	)
	(segment
		(start 416.57143 -155.297632)
		(end 416.465258 -155.419552)
		(width 0.1651)
		(layer "In5.Cu")
		(net "P5E_PEX3_STN0_RX_DP<14>")
	)
	(segment
		(start 416.8013 -158.642304)
		(end 416.8013 -160.396682)
		(width 0.1651)
		(layer "In5.Cu")
		(net "P5E_PEX3_STN0_RX_DP<14>")
	)
	(segment
		(start 423.978324 -267.788136)
		(end 423.48404 -270.431006)
		(width 0.1651)
		(layer "In5.Cu")
		(net "P5E_PEX3_STN0_RX_DP<14>")
	)
	(segment
		(start 423.985436 -275.569934)
		(end 424.099736 -275.684234)
		(width 0.1143)
		(layer "In5.Cu")
		(net "P5E_PEX3_STN0_RX_DP<14>")
	)
	(segment
		(start 416.537648 -154.803856)
		(end 416.57143 -155.297632)
		(width 0.1651)
		(layer "In5.Cu")
		(net "P5E_PEX3_STN0_RX_DP<14>")
	)
	(segment
		(start 416.465258 -155.419552)
		(end 416.49904 -155.913836)
		(width 0.1651)
		(layer "In5.Cu")
		(net "P5E_PEX3_STN0_RX_DP<14>")
	)
	(segment
		(start 416.62096 -156.020008)
		(end 416.654742 -156.514038)
		(width 0.1651)
		(layer "In5.Cu")
		(net "P5E_PEX3_STN0_RX_DP<14>")
	)
	(segment
		(start 416.54857 -156.635958)
		(end 416.582352 -157.130242)
		(width 0.1651)
		(layer "In5.Cu")
		(net "P5E_PEX3_STN0_RX_DP<14>")
	)
	(segment
		(start 417.334192 -164.703506)
		(end 423.763694 -258.33578)
		(width 0.1651)
		(layer "In5.Cu")
		(net "P5E_PEX3_STN0_RX_DP<14>")
	)
	(segment
		(start 424.099736 -275.684234)
		(end 424.099736 -275.949664)
		(width 0.1143)
		(layer "In5.Cu")
		(net "P5E_PEX3_STN0_RX_DP<14>")
	)
	(segment
		(start 423.48404 -270.431006)
		(end 423.48404 -271.570704)
		(width 0.1651)
		(layer "In5.Cu")
		(net "P5E_PEX3_STN0_RX_DP<14>")
	)
	(segment
		(start 423.52976 -275.35505)
		(end 423.744644 -275.569934)
		(width 0.1143)
		(layer "In5.Cu")
		(net "P5E_PEX3_STN0_RX_DP<14>")
	)
	(segment
		(start 423.48404 -271.599152)
		(end 423.52976 -271.644872)
		(width 0.1143)
		(layer "In5.Cu")
		(net "P5E_PEX3_STN0_RX_DP<14>")
	)
	(segment
		(start 413.033972 -319.966848)
		(end 413.033972 -319.9384)
		(width 0.1143)
		(layer "In5.Cu")
		(net "P5E_PEX3_STN5_RX_DP<87>")
	)
	(segment
		(start 402.562314 -376.382534)
		(end 403.148038 -371.18925)
		(width 0.1651)
		(layer "In5.Cu")
		(net "P5E_PEX3_STN5_RX_DP<87>")
	)
	(segment
		(start 401.398232 -388.756906)
		(end 402.25853 -386.307076)
		(width 0.1651)
		(layer "In5.Cu")
		(net "P5E_PEX3_STN5_RX_DP<87>")
	)
	(segment
		(start 406.24506 -342.89111)
		(end 406.816814 -340.52637)
		(width 0.1651)
		(layer "In5.Cu")
		(net "P5E_PEX3_STN5_RX_DP<87>")
	)
	(segment
		(start 402.25853 -386.307076)
		(end 402.562314 -376.382534)
		(width 0.1651)
		(layer "In5.Cu")
		(net "P5E_PEX3_STN5_RX_DP<87>")
	)
	(segment
		(start 404.43404 -365.896906)
		(end 404.561294 -365.418116)
		(width 0.1651)
		(layer "In5.Cu")
		(net "P5E_PEX3_STN5_RX_DP<87>")
	)
	(segment
		(start 391.766044 -397.770604)
		(end 391.766044 -395.116558)
		(width 0.1651)
		(layer "In5.Cu")
		(net "P5E_PEX3_STN5_RX_DP<87>")
	)
	(segment
		(start 413.079692 -319.89268)
		(end 413.079692 -318.355472)
		(width 0.1143)
		(layer "In5.Cu")
		(net "P5E_PEX3_STN5_RX_DP<87>")
	)
	(segment
		(start 404.701248 -365.33709)
		(end 406.159462 -359.8545)
		(width 0.1651)
		(layer "In5.Cu")
		(net "P5E_PEX3_STN5_RX_DP<87>")
	)
	(segment
		(start 413.535622 -318.129666)
		(end 413.649922 -318.015366)
		(width 0.1143)
		(layer "In5.Cu")
		(net "P5E_PEX3_STN5_RX_DP<87>")
	)
	(segment
		(start 406.159462 -359.8545)
		(end 406.24506 -342.89111)
		(width 0.1651)
		(layer "In5.Cu")
		(net "P5E_PEX3_STN5_RX_DP<87>")
	)
	(segment
		(start 413.033972 -319.9384)
		(end 413.079692 -319.89268)
		(width 0.1143)
		(layer "In5.Cu")
		(net "P5E_PEX3_STN5_RX_DP<87>")
	)
	(segment
		(start 398.63776 -391.782046)
		(end 400.005042 -390.727438)
		(width 0.1651)
		(layer "In5.Cu")
		(net "P5E_PEX3_STN5_RX_DP<87>")
	)
	(segment
		(start 406.816814 -340.52637)
		(end 412.398464 -327.068688)
		(width 0.1651)
		(layer "In5.Cu")
		(net "P5E_PEX3_STN5_RX_DP<87>")
	)
	(segment
		(start 413.305498 -318.129666)
		(end 413.535622 -318.129666)
		(width 0.1143)
		(layer "In5.Cu")
		(net "P5E_PEX3_STN5_RX_DP<87>")
	)
	(segment
		(start 391.433558 -398.10309)
		(end 391.766044 -397.770604)
		(width 0.1651)
		(layer "In5.Cu")
		(net "P5E_PEX3_STN5_RX_DP<87>")
	)
	(segment
		(start 404.561294 -365.418116)
		(end 404.701502 -365.33709)
		(width 0.1651)
		(layer "In5.Cu")
		(net "P5E_PEX3_STN5_RX_DP<87>")
	)
	(segment
		(start 413.079692 -318.355472)
		(end 413.305498 -318.129666)
		(width 0.1143)
		(layer "In5.Cu")
		(net "P5E_PEX3_STN5_RX_DP<87>")
	)
	(segment
		(start 413.649922 -318.015366)
		(end 413.649922 -317.749936)
		(width 0.1143)
		(layer "In5.Cu")
		(net "P5E_PEX3_STN5_RX_DP<87>")
	)
	(segment
		(start 392.084306 -394.553948)
		(end 398.63776 -391.782046)
		(width 0.1651)
		(layer "In5.Cu")
		(net "P5E_PEX3_STN5_RX_DP<87>")
	)
	(segment
		(start 391.016998 -398.10309)
		(end 391.433558 -398.10309)
		(width 0.1651)
		(layer "In5.Cu")
		(net "P5E_PEX3_STN5_RX_DP<87>")
	)
	(segment
		(start 400.005042 -390.727438)
		(end 401.398232 -388.756906)
		(width 0.1651)
		(layer "In5.Cu")
		(net "P5E_PEX3_STN5_RX_DP<87>")
	)
	(segment
		(start 404.701502 -365.33709)
		(end 404.701248 -365.33709)
		(width 0.1651)
		(layer "In5.Cu")
		(net "P5E_PEX3_STN5_RX_DP<87>")
	)
	(segment
		(start 412.398464 -327.068688)
		(end 413.033972 -323.878448)
		(width 0.1651)
		(layer "In5.Cu")
		(net "P5E_PEX3_STN5_RX_DP<87>")
	)
	(segment
		(start 390.889998 -397.59001)
		(end 390.889998 -397.97609)
		(width 0.1651)
		(layer "In5.Cu")
		(net "P5E_PEX3_STN5_RX_DP<87>")
	)
	(segment
		(start 413.033972 -323.878448)
		(end 413.033972 -319.966848)
		(width 0.1651)
		(layer "In5.Cu")
		(net "P5E_PEX3_STN5_RX_DP<87>")
	)
	(segment
		(start 403.147784 -371.18925)
		(end 403.150324 -371.168676)
		(width 0.1651)
		(layer "In5.Cu")
		(net "P5E_PEX3_STN5_RX_DP<87>")
	)
	(segment
		(start 390.889998 -397.97609)
		(end 391.016998 -398.10309)
		(width 0.1651)
		(layer "In5.Cu")
		(net "P5E_PEX3_STN5_RX_DP<87>")
	)
	(segment
		(start 391.766044 -395.116558)
		(end 392.084306 -394.553948)
		(width 0.1651)
		(layer "In5.Cu")
		(net "P5E_PEX3_STN5_RX_DP<87>")
	)
	(segment
		(start 403.150324 -371.168676)
		(end 404.515066 -366.03686)
		(width 0.1651)
		(layer "In5.Cu")
		(net "P5E_PEX3_STN5_RX_DP<87>")
	)
	(segment
		(start 403.148038 -371.18925)
		(end 403.147784 -371.18925)
		(width 0.1651)
		(layer "In5.Cu")
		(net "P5E_PEX3_STN5_RX_DP<87>")
	)
	(segment
		(start 404.515066 -366.03686)
		(end 404.43404 -365.896906)
		(width 0.1651)
		(layer "In5.Cu")
		(net "P5E_PEX3_STN5_RX_DP<87>")
	)
	(segment
		(start 282.842462 -154.759914)
		(end 283.656786 -154.759914)
		(width 0.13208)
		(layer "F.Cu")
		(net "NCSI_NIC4_TX_EN")
	)
	(segment
		(start 283.656786 -154.759914)
		(end 283.85516 -154.958288)
		(width 0.13208)
		(layer "F.Cu")
		(net "NCSI_NIC4_TX_EN")
	)
	(segment
		(start 283.85516 -154.958288)
		(end 285.326074 -154.958288)
		(width 0.13208)
		(layer "F.Cu")
		(net "NCSI_NIC4_TX_EN")
	)
	(via
		(at 285.326074 -154.958288)
		(size 0.508)
		(drill 0.254)
		(layers "F.Cu" "B.Cu")
		(net "NCSI_NIC4_TX_EN")
	)
	(segment
		(start 282.720542 -154.0256)
		(end 283.65323 -154.958288)
		(width 0.13208)
		(layer "B.Cu")
		(net "NCSI_NIC4_TX_EN")
	)
	(segment
		(start 282.155392 -154.0256)
		(end 282.720542 -154.0256)
		(width 0.13208)
		(layer "B.Cu")
		(net "NCSI_NIC4_TX_EN")
	)
	(segment
		(start 283.65323 -154.958288)
		(end 285.326074 -154.958288)
		(width 0.13208)
		(layer "B.Cu")
		(net "NCSI_NIC4_TX_EN")
	)
	(segment
		(start 390.533382 -24.790146)
		(end 390.77519 -25.031954)
		(width 0.381)
		(layer "F.Cu")
		(net "P3V3_SSD13")
	)
	(segment
		(start 396.185644 -27.492198)
		(end 396.054072 -27.492198)
		(width 0.381)
		(layer "F.Cu")
		(net "P3V3_SSD13")
	)
	(segment
		(start 390.77519 -25.031954)
		(end 392.226546 -25.031954)
		(width 0.381)
		(layer "F.Cu")
		(net "P3V3_SSD13")
	)
	(segment
		(start 396.054072 -27.492198)
		(end 395.533118 -26.971244)
		(width 0.381)
		(layer "F.Cu")
		(net "P3V3_SSD13")
	)
	(segment
		(start 399.860516 -14.799818)
		(end 399.860516 -16.439388)
		(width 0.381)
		(layer "F.Cu")
		(net "P3V3_SSD13")
	)
	(segment
		(start 398.356582 -17.419574)
		(end 398.966182 -17.419574)
		(width 0.508)
		(layer "F.Cu")
		(net "P3V3_SSD13")
	)
	(segment
		(start 367.14684 -37.47516)
		(end 366.441228 -37.47516)
		(width 0.4572)
		(layer "F.Cu")
		(net "P3V3_SSD13")
	)
	(segment
		(start 379.99416 -32.787336)
		(end 380.268734 -32.512762)
		(width 0.381)
		(layer "F.Cu")
		(net "P3V3_SSD13")
	)
	(segment
		(start 392.226546 -25.031954)
		(end 392.869928 -25.031954)
		(width 0.4572)
		(layer "F.Cu")
		(net "P3V3_SSD13")
	)
	(segment
		(start 379.99416 -34.248852)
		(end 379.99416 -32.787336)
		(width 0.381)
		(layer "F.Cu")
		(net "P3V3_SSD13")
	)
	(segment
		(start 398.969484 -20.467574)
		(end 398.356582 -20.467574)
		(width 0.508)
		(layer "F.Cu")
		(net "P3V3_SSD13")
	)
	(segment
		(start 399.26133 -14.735302)
		(end 399.925032 -14.735302)
		(width 0.381)
		(layer "F.Cu")
		(net "P3V3_SSD13")
	)
	(segment
		(start 382.479042 -59.978036)
		(end 382.479042 -60.633356)
		(width 0.381)
		(layer "F.Cu")
		(net "P3V3_SSD13")
	)
	(segment
		(start 389.56488 -24.790146)
		(end 390.533382 -24.790146)
		(width 0.381)
		(layer "F.Cu")
		(net "P3V3_SSD13")
	)
	(segment
		(start 399.925032 -14.735302)
		(end 399.860516 -14.799818)
		(width 0.381)
		(layer "F.Cu")
		(net "P3V3_SSD13")
	)
	(segment
		(start 381.67183 -24.807418)
		(end 381.05334 -24.807418)
		(width 0.4572)
		(layer "F.Cu")
		(net "P3V3_SSD13")
	)
	(segment
		(start 380.268734 -32.512762)
		(end 380.268734 -30.971236)
		(width 0.381)
		(layer "F.Cu")
		(net "P3V3_SSD13")
	)
	(segment
		(start 393.771628 -25.742392)
		(end 393.771628 -26.360882)
		(width 0.4572)
		(layer "F.Cu")
		(net "P3V3_SSD13")
	)
	(segment
		(start 380.268734 -30.971236)
		(end 379.694186 -30.396688)
		(width 0.381)
		(layer "F.Cu")
		(net "P3V3_SSD13")
	)
	(via
		(at 392.869928 -25.031954)
		(size 0.508)
		(drill 0.254)
		(layers "F.Cu" "B.Cu")
		(net "P3V3_SSD13")
	)
	(via
		(at 380.81458 -53.469286)
		(size 0.508)
		(drill 0.254)
		(layers "F.Cu" "B.Cu")
		(net "P3V3_SSD13")
	)
	(via
		(at 399.26133 -14.735302)
		(size 0.508)
		(drill 0.254)
		(layers "F.Cu" "B.Cu")
		(net "P3V3_SSD13")
	)
	(via
		(at 382.699006 -49.574704)
		(size 0.508)
		(drill 0.254)
		(layers "F.Cu" "B.Cu")
		(net "P3V3_SSD13")
	)
	(via
		(at 381.44958 -53.469286)
		(size 0.508)
		(drill 0.254)
		(layers "F.Cu" "B.Cu")
		(net "P3V3_SSD13")
	)
	(via
		(at 382.576578 -50.608992)
		(size 0.508)
		(drill 0.254)
		(layers "F.Cu" "B.Cu")
		(net "P3V3_SSD13")
	)
	(via
		(at 378.610622 -29.614876)
		(size 0.508)
		(drill 0.254)
		(layers "F.Cu" "B.Cu")
		(net "P3V3_SSD13")
	)
	(via
		(at 380.794006 -49.574704)
		(size 0.508)
		(drill 0.254)
		(layers "F.Cu" "B.Cu")
		(net "P3V3_SSD13")
	)
	(via
		(at 395.533118 -26.971244)
		(size 0.508)
		(drill 0.254)
		(layers "F.Cu" "B.Cu")
		(net "P3V3_SSD13")
	)
	(via
		(at 378.610622 -30.376876)
		(size 0.508)
		(drill 0.254)
		(layers "F.Cu" "B.Cu")
		(net "P3V3_SSD13")
	)
	(via
		(at 381.814578 -50.608992)
		(size 0.508)
		(drill 0.254)
		(layers "F.Cu" "B.Cu")
		(net "P3V3_SSD13")
	)
	(via
		(at 381.814578 -51.243992)
		(size 0.508)
		(drill 0.254)
		(layers "F.Cu" "B.Cu")
		(net "P3V3_SSD13")
	)
	(via
		(at 381.264922 -52.528724)
		(size 0.508)
		(drill 0.254)
		(layers "F.Cu" "B.Cu")
		(net "P3V3_SSD13")
	)
	(via
		(at 380.794006 -50.478182)
		(size 0.6604)
		(drill 0.3302)
		(layers "F.Cu" "B.Cu")
		(net "P3V3_SSD13")
	)
	(via
		(at 382.479042 -60.633356)
		(size 0.508)
		(drill 0.254)
		(layers "F.Cu" "B.Cu")
		(net "P3V3_SSD13")
	)
	(via
		(at 381.899922 -52.528724)
		(size 0.508)
		(drill 0.254)
		(layers "F.Cu" "B.Cu")
		(net "P3V3_SSD13")
	)
	(via
		(at 382.576578 -51.320192)
		(size 0.508)
		(drill 0.254)
		(layers "F.Cu" "B.Cu")
		(net "P3V3_SSD13")
	)
	(via
		(at 381.429006 -49.574704)
		(size 0.508)
		(drill 0.254)
		(layers "F.Cu" "B.Cu")
		(net "P3V3_SSD13")
	)
	(via
		(at 381.05334 -24.807418)
		(size 0.508)
		(drill 0.254)
		(layers "F.Cu" "B.Cu")
		(net "P3V3_SSD13")
	)
	(via
		(at 366.441228 -37.47516)
		(size 0.508)
		(drill 0.254)
		(layers "F.Cu" "B.Cu")
		(net "P3V3_SSD13")
	)
	(via
		(at 382.064006 -49.574704)
		(size 0.508)
		(drill 0.254)
		(layers "F.Cu" "B.Cu")
		(net "P3V3_SSD13")
	)
	(via
		(at 398.969484 -20.467574)
		(size 0.508)
		(drill 0.254)
		(layers "F.Cu" "B.Cu")
		(net "P3V3_SSD13")
	)
	(via
		(at 393.771628 -26.360882)
		(size 0.508)
		(drill 0.254)
		(layers "F.Cu" "B.Cu")
		(net "P3V3_SSD13")
	)
	(via
		(at 398.966182 -17.419574)
		(size 0.508)
		(drill 0.254)
		(layers "F.Cu" "B.Cu")
		(net "P3V3_SSD13")
	)
	(segment
		(start 367.288826 -38.322758)
		(end 366.441228 -37.47516)
		(width 0.508)
		(layer "In9.Cu")
		(net "P3V3_SSD13")
	)
	(segment
		(start 376.063764 -37.872924)
		(end 369.3541 -37.872924)
		(width 0.508)
		(layer "In9.Cu")
		(net "P3V3_SSD13")
	)
	(segment
		(start 368.904266 -38.322758)
		(end 367.288826 -38.322758)
		(width 0.508)
		(layer "In9.Cu")
		(net "P3V3_SSD13")
	)
	(segment
		(start 369.3541 -37.872924)
		(end 368.904266 -38.322758)
		(width 0.508)
		(layer "In9.Cu")
		(net "P3V3_SSD13")
	)
	(segment
		(start 53.801772 -130.727958)
		(end 54.09692 -130.43281)
		(width 0.13462)
		(layer "F.Cu")
		(net "P5E_PEX0_STN1_RX_DP<28>")
	)
	(segment
		(start 51.130454 -130.565144)
		(end 51.293268 -130.727958)
		(width 0.13462)
		(layer "F.Cu")
		(net "P5E_PEX0_STN1_RX_DP<28>")
	)
	(segment
		(start 51.293268 -130.727958)
		(end 53.801772 -130.727958)
		(width 0.13462)
		(layer "F.Cu")
		(net "P5E_PEX0_STN1_RX_DP<28>")
	)
	(segment
		(start 50.64252 -130.565144)
		(end 51.130454 -130.565144)
		(width 0.13462)
		(layer "F.Cu")
		(net "P5E_PEX0_STN1_RX_DP<28>")
	)
	(segment
		(start 42.671238 -144.635982)
		(end 40.954452 -146.953732)
		(width 0.1651)
		(layer "In5.Cu")
		(net "P5E_PEX0_STN1_RX_DP<28>")
	)
	(segment
		(start 53.80609 -130.72364)
		(end 51.082956 -130.72364)
		(width 0.1651)
		(layer "In5.Cu")
		(net "P5E_PEX0_STN1_RX_DP<28>")
	)
	(segment
		(start 70.479666 -271.848072)
		(end 70.479666 -273.45513)
		(width 0.1143)
		(layer "In5.Cu")
		(net "P5E_PEX0_STN1_RX_DP<28>")
	)
	(segment
		(start 46.665642 -141.594078)
		(end 43.79214 -143.514318)
		(width 0.1651)
		(layer "In5.Cu")
		(net "P5E_PEX0_STN1_RX_DP<28>")
	)
	(segment
		(start 42.116248 -161.20364)
		(end 70.433946 -267.64234)
		(width 0.1651)
		(layer "In5.Cu")
		(net "P5E_PEX0_STN1_RX_DP<28>")
	)
	(segment
		(start 41.358058 -156.926026)
		(end 42.116248 -161.20364)
		(width 0.1651)
		(layer "In5.Cu")
		(net "P5E_PEX0_STN1_RX_DP<28>")
	)
	(segment
		(start 40.759634 -147.65528)
		(end 41.358058 -156.926026)
		(width 0.1651)
		(layer "In5.Cu")
		(net "P5E_PEX0_STN1_RX_DP<28>")
	)
	(segment
		(start 49.068736 -133.177026)
		(end 48.164496 -135.360156)
		(width 0.1651)
		(layer "In5.Cu")
		(net "P5E_PEX0_STN1_RX_DP<28>")
	)
	(segment
		(start 70.69455 -273.670014)
		(end 70.935342 -273.670014)
		(width 0.1143)
		(layer "In5.Cu")
		(net "P5E_PEX0_STN1_RX_DP<28>")
	)
	(segment
		(start 70.433946 -271.773904)
		(end 70.433946 -271.802352)
		(width 0.1143)
		(layer "In5.Cu")
		(net "P5E_PEX0_STN1_RX_DP<28>")
	)
	(segment
		(start 54.09692 -130.43281)
		(end 53.80609 -130.72364)
		(width 0.1651)
		(layer "In5.Cu")
		(net "P5E_PEX0_STN1_RX_DP<28>")
	)
	(segment
		(start 48.164496 -135.360156)
		(end 48.164242 -135.36041)
		(width 0.1651)
		(layer "In5.Cu")
		(net "P5E_PEX0_STN1_RX_DP<28>")
	)
	(segment
		(start 70.433946 -267.64234)
		(end 70.433946 -271.773904)
		(width 0.1651)
		(layer "In5.Cu")
		(net "P5E_PEX0_STN1_RX_DP<28>")
	)
	(segment
		(start 48.164242 -135.36041)
		(end 47.714662 -136.446514)
		(width 0.1651)
		(layer "In5.Cu")
		(net "P5E_PEX0_STN1_RX_DP<28>")
	)
	(segment
		(start 40.954452 -146.953732)
		(end 40.759634 -147.65528)
		(width 0.1651)
		(layer "In5.Cu")
		(net "P5E_PEX0_STN1_RX_DP<28>")
	)
	(segment
		(start 47.536354 -140.723366)
		(end 46.665642 -141.594078)
		(width 0.1651)
		(layer "In5.Cu")
		(net "P5E_PEX0_STN1_RX_DP<28>")
	)
	(segment
		(start 43.79214 -143.514318)
		(end 42.671238 -144.635982)
		(width 0.1651)
		(layer "In5.Cu")
		(net "P5E_PEX0_STN1_RX_DP<28>")
	)
	(segment
		(start 51.082956 -130.72364)
		(end 49.068736 -133.177026)
		(width 0.1651)
		(layer "In5.Cu")
		(net "P5E_PEX0_STN1_RX_DP<28>")
	)
	(segment
		(start 70.433946 -271.802352)
		(end 70.479666 -271.848072)
		(width 0.1143)
		(layer "In5.Cu")
		(net "P5E_PEX0_STN1_RX_DP<28>")
	)
	(segment
		(start 70.935342 -273.670014)
		(end 71.049642 -273.784314)
		(width 0.1143)
		(layer "In5.Cu")
		(net "P5E_PEX0_STN1_RX_DP<28>")
	)
	(segment
		(start 47.714662 -136.446514)
		(end 47.714662 -140.292328)
		(width 0.1651)
		(layer "In5.Cu")
		(net "P5E_PEX0_STN1_RX_DP<28>")
	)
	(segment
		(start 47.714662 -140.292328)
		(end 47.536354 -140.723366)
		(width 0.1651)
		(layer "In5.Cu")
		(net "P5E_PEX0_STN1_RX_DP<28>")
	)
	(segment
		(start 71.049642 -273.784314)
		(end 71.049642 -274.049744)
		(width 0.1143)
		(layer "In5.Cu")
		(net "P5E_PEX0_STN1_RX_DP<28>")
	)
	(segment
		(start 70.479666 -273.45513)
		(end 70.69455 -273.670014)
		(width 0.1143)
		(layer "In5.Cu")
		(net "P5E_PEX0_STN1_RX_DP<28>")
	)
	(segment
		(start 167.393112 -121.317766)
		(end 168.04767 -121.317766)
		(width 0.13462)
		(layer "F.Cu")
		(net "P5E_PEX1_STN1_RX_DP<25>")
	)
	(segment
		(start 168.04767 -121.317766)
		(end 168.342564 -121.022872)
		(width 0.13462)
		(layer "F.Cu")
		(net "P5E_PEX1_STN1_RX_DP<25>")
	)
	(segment
		(start 167.230298 -121.154952)
		(end 167.393112 -121.317766)
		(width 0.13462)
		(layer "F.Cu")
		(net "P5E_PEX1_STN1_RX_DP<25>")
	)
	(segment
		(start 166.742364 -121.154952)
		(end 167.230298 -121.154952)
		(width 0.13462)
		(layer "F.Cu")
		(net "P5E_PEX1_STN1_RX_DP<25>")
	)
	(segment
		(start 168.051734 -121.313702)
		(end 168.342564 -121.022872)
		(width 0.1651)
		(layer "In5.Cu")
		(net "P5E_PEX1_STN1_RX_DP<25>")
	)
	(segment
		(start 183.683656 -268.07414)
		(end 155.50515 -162.425888)
		(width 0.1651)
		(layer "In5.Cu")
		(net "P5E_PEX1_STN1_RX_DP<25>")
	)
	(segment
		(start 184.299606 -275.684488)
		(end 184.185052 -275.569934)
		(width 0.1143)
		(layer "In5.Cu")
		(net "P5E_PEX1_STN1_RX_DP<25>")
	)
	(segment
		(start 155.50515 -162.425888)
		(end 154.563572 -157.255972)
		(width 0.1651)
		(layer "In5.Cu")
		(net "P5E_PEX1_STN1_RX_DP<25>")
	)
	(segment
		(start 167.832278 -121.313702)
		(end 168.051734 -121.313702)
		(width 0.1651)
		(layer "In5.Cu")
		(net "P5E_PEX1_STN1_RX_DP<25>")
	)
	(segment
		(start 183.729376 -275.35505)
		(end 183.729376 -271.848072)
		(width 0.1143)
		(layer "In5.Cu")
		(net "P5E_PEX1_STN1_RX_DP<25>")
	)
	(segment
		(start 184.185052 -275.569934)
		(end 183.94426 -275.569934)
		(width 0.1143)
		(layer "In5.Cu")
		(net "P5E_PEX1_STN1_RX_DP<25>")
	)
	(segment
		(start 183.729376 -271.848072)
		(end 183.683656 -271.802352)
		(width 0.1143)
		(layer "In5.Cu")
		(net "P5E_PEX1_STN1_RX_DP<25>")
	)
	(segment
		(start 184.299606 -275.949664)
		(end 184.299606 -275.684488)
		(width 0.1143)
		(layer "In5.Cu")
		(net "P5E_PEX1_STN1_RX_DP<25>")
	)
	(segment
		(start 153.953464 -147.311364)
		(end 153.95321 -147.311364)
		(width 0.1651)
		(layer "In5.Cu")
		(net "P5E_PEX1_STN1_RX_DP<25>")
	)
	(segment
		(start 166.087298 -122.009662)
		(end 167.832278 -121.313702)
		(width 0.1651)
		(layer "In5.Cu")
		(net "P5E_PEX1_STN1_RX_DP<25>")
	)
	(segment
		(start 159.592518 -128.887982)
		(end 159.780986 -128.458722)
		(width 0.1651)
		(layer "In5.Cu")
		(net "P5E_PEX1_STN1_RX_DP<25>")
	)
	(segment
		(start 153.95067 -147.266914)
		(end 154.387296 -145.587212)
		(width 0.1651)
		(layer "In5.Cu")
		(net "P5E_PEX1_STN1_RX_DP<25>")
	)
	(segment
		(start 153.95321 -147.311364)
		(end 153.95067 -147.266914)
		(width 0.1651)
		(layer "In5.Cu")
		(net "P5E_PEX1_STN1_RX_DP<25>")
	)
	(segment
		(start 154.563572 -157.255972)
		(end 153.953464 -147.311364)
		(width 0.1651)
		(layer "In5.Cu")
		(net "P5E_PEX1_STN1_RX_DP<25>")
	)
	(segment
		(start 183.94426 -275.569934)
		(end 183.729376 -275.35505)
		(width 0.1143)
		(layer "In5.Cu")
		(net "P5E_PEX1_STN1_RX_DP<25>")
	)
	(segment
		(start 158.021528 -137.931144)
		(end 159.592518 -128.887982)
		(width 0.1651)
		(layer "In5.Cu")
		(net "P5E_PEX1_STN1_RX_DP<25>")
	)
	(segment
		(start 154.387296 -145.587212)
		(end 156.675074 -142.635986)
		(width 0.1651)
		(layer "In5.Cu")
		(net "P5E_PEX1_STN1_RX_DP<25>")
	)
	(segment
		(start 183.683656 -271.802352)
		(end 183.683656 -271.773904)
		(width 0.1143)
		(layer "In5.Cu")
		(net "P5E_PEX1_STN1_RX_DP<25>")
	)
	(segment
		(start 156.675074 -142.635986)
		(end 158.021528 -137.931144)
		(width 0.1651)
		(layer "In5.Cu")
		(net "P5E_PEX1_STN1_RX_DP<25>")
	)
	(segment
		(start 159.780986 -128.458722)
		(end 161.876232 -125.831854)
		(width 0.1651)
		(layer "In5.Cu")
		(net "P5E_PEX1_STN1_RX_DP<25>")
	)
	(segment
		(start 183.683656 -271.773904)
		(end 183.683656 -268.07414)
		(width 0.1651)
		(layer "In5.Cu")
		(net "P5E_PEX1_STN1_RX_DP<25>")
	)
	(segment
		(start 161.876232 -125.831854)
		(end 166.087298 -122.009662)
		(width 0.1651)
		(layer "In5.Cu")
		(net "P5E_PEX1_STN1_RX_DP<25>")
	)
	(segment
		(start 330.05395 -30.6324)
		(end 326.123046 -30.6324)
		(width 0.13462)
		(layer "F.Cu")
		(net "P5E_PEX2_STN2_TX_C_DP<33>")
	)
	(segment
		(start 326.123046 -30.6324)
		(end 325.965312 -30.790134)
		(width 0.13462)
		(layer "F.Cu")
		(net "P5E_PEX2_STN2_TX_C_DP<33>")
	)
	(segment
		(start 325.965312 -30.790134)
		(end 325.464678 -30.790134)
		(width 0.13462)
		(layer "F.Cu")
		(net "P5E_PEX2_STN2_TX_C_DP<33>")
	)
	(segment
		(start 330.36764 -30.94609)
		(end 330.05395 -30.6324)
		(width 0.13462)
		(layer "F.Cu")
		(net "P5E_PEX2_STN2_TX_C_DP<33>")
	)
	(segment
		(start 430.38268 -144.70888)
		(end 422.218358 -144.70888)
		(width 0.13462)
		(layer "F.Cu")
		(net "P5E_PEX3_STN0_TX_C_DN<9>")
	)
	(segment
		(start 422.218358 -144.70888)
		(end 422.064434 -144.554956)
		(width 0.13462)
		(layer "F.Cu")
		(net "P5E_PEX3_STN0_TX_C_DN<9>")
	)
	(segment
		(start 430.694846 -144.396714)
		(end 430.38268 -144.70888)
		(width 0.13462)
		(layer "F.Cu")
		(net "P5E_PEX3_STN0_TX_C_DN<9>")
	)
	(segment
		(start 422.064434 -144.554956)
		(end 421.557704 -144.554956)
		(width 0.13462)
		(layer "F.Cu")
		(net "P5E_PEX3_STN0_TX_C_DN<9>")
	)
	(segment
		(start 379.89002 -396.876016)
		(end 380.01702 -397.003016)
		(width 0.1651)
		(layer "In5.Cu")
		(net "P5E_PEX3_STN5_RX_DP<82>")
	)
	(segment
		(start 396.149576 -364.849664)
		(end 396.035276 -364.367318)
		(width 0.1651)
		(layer "In5.Cu")
		(net "P5E_PEX3_STN5_RX_DP<82>")
	)
	(segment
		(start 395.126972 -340.964266)
		(end 406.66162 -327.025254)
		(width 0.1651)
		(layer "In5.Cu")
		(net "P5E_PEX3_STN5_RX_DP<82>")
	)
	(segment
		(start 397.265906 -385.68757)
		(end 397.395954 -370.894102)
		(width 0.1651)
		(layer "In5.Cu")
		(net "P5E_PEX3_STN5_RX_DP<82>")
	)
	(segment
		(start 408.899868 -316.115192)
		(end 408.899868 -315.849762)
		(width 0.1143)
		(layer "In5.Cu")
		(net "P5E_PEX3_STN5_RX_DP<82>")
	)
	(segment
		(start 395.591538 -387.85927)
		(end 396.705582 -386.961634)
		(width 0.1651)
		(layer "In5.Cu")
		(net "P5E_PEX3_STN5_RX_DP<82>")
	)
	(segment
		(start 396.035276 -364.367318)
		(end 396.101316 -364.260384)
		(width 0.1651)
		(layer "In5.Cu")
		(net "P5E_PEX3_STN5_RX_DP<82>")
	)
	(segment
		(start 408.283918 -319.916048)
		(end 408.283918 -319.8876)
		(width 0.1143)
		(layer "In5.Cu")
		(net "P5E_PEX3_STN5_RX_DP<82>")
	)
	(segment
		(start 408.555444 -316.229492)
		(end 408.785568 -316.229492)
		(width 0.1143)
		(layer "In5.Cu")
		(net "P5E_PEX3_STN5_RX_DP<82>")
	)
	(segment
		(start 384.482086 -392.460988)
		(end 395.591538 -387.85927)
		(width 0.1651)
		(layer "In5.Cu")
		(net "P5E_PEX3_STN5_RX_DP<82>")
	)
	(segment
		(start 406.66162 -327.025254)
		(end 407.734008 -324.863968)
		(width 0.1651)
		(layer "In5.Cu")
		(net "P5E_PEX3_STN5_RX_DP<82>")
	)
	(segment
		(start 408.329638 -316.455298)
		(end 408.555444 -316.229492)
		(width 0.1143)
		(layer "In5.Cu")
		(net "P5E_PEX3_STN5_RX_DP<82>")
	)
	(segment
		(start 397.151606 -368.68989)
		(end 396.256764 -364.91545)
		(width 0.1651)
		(layer "In5.Cu")
		(net "P5E_PEX3_STN5_RX_DP<82>")
	)
	(segment
		(start 395.765782 -363.230414)
		(end 395.831568 -363.12348)
		(width 0.1651)
		(layer "In5.Cu")
		(net "P5E_PEX3_STN5_RX_DP<82>")
	)
	(segment
		(start 379.89002 -396.49019)
		(end 379.89002 -396.876016)
		(width 0.1651)
		(layer "In5.Cu")
		(net "P5E_PEX3_STN5_RX_DP<82>")
	)
	(segment
		(start 397.01089 -386.509006)
		(end 397.265906 -385.68757)
		(width 0.1651)
		(layer "In5.Cu")
		(net "P5E_PEX3_STN5_RX_DP<82>")
	)
	(segment
		(start 407.734008 -324.863968)
		(end 408.283918 -322.519548)
		(width 0.1651)
		(layer "In5.Cu")
		(net "P5E_PEX3_STN5_RX_DP<82>")
	)
	(segment
		(start 396.101316 -364.260384)
		(end 395.98727 -363.778546)
		(width 0.1651)
		(layer "In5.Cu")
		(net "P5E_PEX3_STN5_RX_DP<82>")
	)
	(segment
		(start 397.395954 -370.894102)
		(end 397.151352 -368.68989)
		(width 0.1651)
		(layer "In5.Cu")
		(net "P5E_PEX3_STN5_RX_DP<82>")
	)
	(segment
		(start 394.79601 -341.989664)
		(end 395.126972 -340.964266)
		(width 0.1651)
		(layer "In5.Cu")
		(net "P5E_PEX3_STN5_RX_DP<82>")
	)
	(segment
		(start 380.01702 -397.003016)
		(end 380.43358 -397.003016)
		(width 0.1651)
		(layer "In5.Cu")
		(net "P5E_PEX3_STN5_RX_DP<82>")
	)
	(segment
		(start 395.831568 -363.12348)
		(end 394.79601 -358.754172)
		(width 0.1651)
		(layer "In5.Cu")
		(net "P5E_PEX3_STN5_RX_DP<82>")
	)
	(segment
		(start 397.151352 -368.68989)
		(end 397.151606 -368.68989)
		(width 0.1651)
		(layer "In5.Cu")
		(net "P5E_PEX3_STN5_RX_DP<82>")
	)
	(segment
		(start 382.212596 -394.08227)
		(end 384.482086 -392.460988)
		(width 0.1651)
		(layer "In5.Cu")
		(net "P5E_PEX3_STN5_RX_DP<82>")
	)
	(segment
		(start 394.79601 -358.754172)
		(end 394.79601 -341.989664)
		(width 0.1651)
		(layer "In5.Cu")
		(net "P5E_PEX3_STN5_RX_DP<82>")
	)
	(segment
		(start 395.879828 -363.712506)
		(end 395.765782 -363.230414)
		(width 0.1651)
		(layer "In5.Cu")
		(net "P5E_PEX3_STN5_RX_DP<82>")
	)
	(segment
		(start 408.785568 -316.229492)
		(end 408.899868 -316.115192)
		(width 0.1143)
		(layer "In5.Cu")
		(net "P5E_PEX3_STN5_RX_DP<82>")
	)
	(segment
		(start 380.766066 -396.405608)
		(end 382.212596 -394.08227)
		(width 0.1651)
		(layer "In5.Cu")
		(net "P5E_PEX3_STN5_RX_DP<82>")
	)
	(segment
		(start 395.98727 -363.778546)
		(end 395.879828 -363.712506)
		(width 0.1651)
		(layer "In5.Cu")
		(net "P5E_PEX3_STN5_RX_DP<82>")
	)
	(segment
		(start 396.705582 -386.961634)
		(end 397.01089 -386.509006)
		(width 0.1651)
		(layer "In5.Cu")
		(net "P5E_PEX3_STN5_RX_DP<82>")
	)
	(segment
		(start 408.283918 -322.519548)
		(end 408.283918 -319.916048)
		(width 0.1651)
		(layer "In5.Cu")
		(net "P5E_PEX3_STN5_RX_DP<82>")
	)
	(segment
		(start 380.766066 -396.67053)
		(end 380.766066 -396.405608)
		(width 0.1651)
		(layer "In5.Cu")
		(net "P5E_PEX3_STN5_RX_DP<82>")
	)
	(segment
		(start 380.43358 -397.003016)
		(end 380.766066 -396.67053)
		(width 0.1651)
		(layer "In5.Cu")
		(net "P5E_PEX3_STN5_RX_DP<82>")
	)
	(segment
		(start 408.329638 -319.84188)
		(end 408.329638 -316.455298)
		(width 0.1143)
		(layer "In5.Cu")
		(net "P5E_PEX3_STN5_RX_DP<82>")
	)
	(segment
		(start 396.256764 -364.91545)
		(end 396.149576 -364.849664)
		(width 0.1651)
		(layer "In5.Cu")
		(net "P5E_PEX3_STN5_RX_DP<82>")
	)
	(segment
		(start 408.283918 -319.8876)
		(end 408.329638 -319.84188)
		(width 0.1143)
		(layer "In5.Cu")
		(net "P5E_PEX3_STN5_RX_DP<82>")
	)
	(segment
		(start 287.298892 -157.353)
		(end 287.781492 -157.8356)
		(width 0.13208)
		(layer "F.Cu")
		(net "RST_NIC4_PERST3_R_N")
	)
	(segment
		(start 286.555942 -157.353)
		(end 287.298892 -157.353)
		(width 0.13208)
		(layer "F.Cu")
		(net "RST_NIC4_PERST3_R_N")
	)
	(segment
		(start 284.650942 -157.353)
		(end 286.555942 -157.353)
		(width 0.13208)
		(layer "F.Cu")
		(net "RST_NIC4_PERST3_R_N")
	)
	(segment
		(start 282.842462 -157.759908)
		(end 284.244034 -157.759908)
		(width 0.13208)
		(layer "F.Cu")
		(net "RST_NIC4_PERST3_R_N")
	)
	(segment
		(start 284.244034 -157.759908)
		(end 284.650942 -157.353)
		(width 0.13208)
		(layer "F.Cu")
		(net "RST_NIC4_PERST3_R_N")
	)
	(via
		(at 286.555942 -157.353)
		(size 0.762)
		(drill 0.381)
		(layers "F.Cu" "B.Cu")
		(net "RST_NIC4_PERST3_R_N")
	)
	(segment
		(start 372.356634 -17.419574)
		(end 372.966234 -17.419574)
		(width 0.508)
		(layer "F.Cu")
		(net "P3V3_SSD12")
	)
	(segment
		(start 354.268786 -32.512762)
		(end 354.268786 -30.971236)
		(width 0.381)
		(layer "F.Cu")
		(net "P3V3_SSD12")
	)
	(segment
		(start 341.146892 -37.47516)
		(end 340.44128 -37.47516)
		(width 0.4572)
		(layer "F.Cu")
		(net "P3V3_SSD12")
	)
	(segment
		(start 353.994212 -32.787336)
		(end 354.268786 -32.512762)
		(width 0.381)
		(layer "F.Cu")
		(net "P3V3_SSD12")
	)
	(segment
		(start 373.860568 -14.799818)
		(end 373.860568 -16.439388)
		(width 0.381)
		(layer "F.Cu")
		(net "P3V3_SSD12")
	)
	(segment
		(start 353.994212 -34.248852)
		(end 353.994212 -32.787336)
		(width 0.381)
		(layer "F.Cu")
		(net "P3V3_SSD12")
	)
	(segment
		(start 370.185696 -27.492198)
		(end 370.054124 -27.492198)
		(width 0.381)
		(layer "F.Cu")
		(net "P3V3_SSD12")
	)
	(segment
		(start 355.671882 -24.807418)
		(end 355.053392 -24.807418)
		(width 0.4572)
		(layer "F.Cu")
		(net "P3V3_SSD12")
	)
	(segment
		(start 370.054124 -27.492198)
		(end 369.53317 -26.971244)
		(width 0.381)
		(layer "F.Cu")
		(net "P3V3_SSD12")
	)
	(segment
		(start 356.479094 -59.978036)
		(end 356.479094 -60.633356)
		(width 0.381)
		(layer "F.Cu")
		(net "P3V3_SSD12")
	)
	(segment
		(start 373.925084 -14.735302)
		(end 373.860568 -14.799818)
		(width 0.381)
		(layer "F.Cu")
		(net "P3V3_SSD12")
	)
	(segment
		(start 366.226598 -25.031954)
		(end 366.86998 -25.031954)
		(width 0.4572)
		(layer "F.Cu")
		(net "P3V3_SSD12")
	)
	(segment
		(start 372.969536 -20.467574)
		(end 372.356634 -20.467574)
		(width 0.508)
		(layer "F.Cu")
		(net "P3V3_SSD12")
	)
	(segment
		(start 363.564932 -24.790146)
		(end 364.533434 -24.790146)
		(width 0.381)
		(layer "F.Cu")
		(net "P3V3_SSD12")
	)
	(segment
		(start 367.77168 -25.742392)
		(end 367.77168 -26.360882)
		(width 0.4572)
		(layer "F.Cu")
		(net "P3V3_SSD12")
	)
	(segment
		(start 364.775242 -25.031954)
		(end 366.226598 -25.031954)
		(width 0.381)
		(layer "F.Cu")
		(net "P3V3_SSD12")
	)
	(segment
		(start 364.533434 -24.790146)
		(end 364.775242 -25.031954)
		(width 0.381)
		(layer "F.Cu")
		(net "P3V3_SSD12")
	)
	(segment
		(start 354.268786 -30.971236)
		(end 353.694238 -30.396688)
		(width 0.381)
		(layer "F.Cu")
		(net "P3V3_SSD12")
	)
	(segment
		(start 373.925084 -14.100302)
		(end 373.925084 -14.735302)
		(width 0.381)
		(layer "F.Cu")
		(net "P3V3_SSD12")
	)
	(via
		(at 355.449632 -53.469286)
		(size 0.508)
		(drill 0.254)
		(layers "F.Cu" "B.Cu")
		(net "P3V3_SSD12")
	)
	(via
		(at 355.429058 -49.574704)
		(size 0.508)
		(drill 0.254)
		(layers "F.Cu" "B.Cu")
		(net "P3V3_SSD12")
	)
	(via
		(at 355.899974 -52.528724)
		(size 0.508)
		(drill 0.254)
		(layers "F.Cu" "B.Cu")
		(net "P3V3_SSD12")
	)
	(via
		(at 354.794058 -49.574704)
		(size 0.508)
		(drill 0.254)
		(layers "F.Cu" "B.Cu")
		(net "P3V3_SSD12")
	)
	(via
		(at 355.053392 -24.807418)
		(size 0.508)
		(drill 0.254)
		(layers "F.Cu" "B.Cu")
		(net "P3V3_SSD12")
	)
	(via
		(at 354.814632 -53.469286)
		(size 0.508)
		(drill 0.254)
		(layers "F.Cu" "B.Cu")
		(net "P3V3_SSD12")
	)
	(via
		(at 372.966234 -17.419574)
		(size 0.508)
		(drill 0.254)
		(layers "F.Cu" "B.Cu")
		(net "P3V3_SSD12")
	)
	(via
		(at 356.479094 -60.633356)
		(size 0.508)
		(drill 0.254)
		(layers "F.Cu" "B.Cu")
		(net "P3V3_SSD12")
	)
	(via
		(at 354.794058 -50.478182)
		(size 0.6604)
		(drill 0.3302)
		(layers "F.Cu" "B.Cu")
		(net "P3V3_SSD12")
	)
	(via
		(at 373.925084 -14.100302)
		(size 0.508)
		(drill 0.254)
		(layers "F.Cu" "B.Cu")
		(net "P3V3_SSD12")
	)
	(via
		(at 356.57663 -50.608992)
		(size 0.508)
		(drill 0.254)
		(layers "F.Cu" "B.Cu")
		(net "P3V3_SSD12")
	)
	(via
		(at 356.699058 -49.574704)
		(size 0.508)
		(drill 0.254)
		(layers "F.Cu" "B.Cu")
		(net "P3V3_SSD12")
	)
	(via
		(at 352.610674 -30.376876)
		(size 0.508)
		(drill 0.254)
		(layers "F.Cu" "B.Cu")
		(net "P3V3_SSD12")
	)
	(via
		(at 356.57663 -51.320192)
		(size 0.508)
		(drill 0.254)
		(layers "F.Cu" "B.Cu")
		(net "P3V3_SSD12")
	)
	(via
		(at 355.81463 -51.243992)
		(size 0.508)
		(drill 0.254)
		(layers "F.Cu" "B.Cu")
		(net "P3V3_SSD12")
	)
	(via
		(at 352.610674 -29.614876)
		(size 0.508)
		(drill 0.254)
		(layers "F.Cu" "B.Cu")
		(net "P3V3_SSD12")
	)
	(via
		(at 356.064058 -49.574704)
		(size 0.508)
		(drill 0.254)
		(layers "F.Cu" "B.Cu")
		(net "P3V3_SSD12")
	)
	(via
		(at 355.264974 -52.528724)
		(size 0.508)
		(drill 0.254)
		(layers "F.Cu" "B.Cu")
		(net "P3V3_SSD12")
	)
	(via
		(at 366.86998 -25.031954)
		(size 0.508)
		(drill 0.254)
		(layers "F.Cu" "B.Cu")
		(net "P3V3_SSD12")
	)
	(via
		(at 369.53317 -26.971244)
		(size 0.508)
		(drill 0.254)
		(layers "F.Cu" "B.Cu")
		(net "P3V3_SSD12")
	)
	(via
		(at 355.81463 -50.608992)
		(size 0.508)
		(drill 0.254)
		(layers "F.Cu" "B.Cu")
		(net "P3V3_SSD12")
	)
	(via
		(at 340.44128 -37.47516)
		(size 0.508)
		(drill 0.254)
		(layers "F.Cu" "B.Cu")
		(net "P3V3_SSD12")
	)
	(via
		(at 372.969536 -20.467574)
		(size 0.508)
		(drill 0.254)
		(layers "F.Cu" "B.Cu")
		(net "P3V3_SSD12")
	)
	(via
		(at 367.77168 -26.360882)
		(size 0.508)
		(drill 0.254)
		(layers "F.Cu" "B.Cu")
		(net "P3V3_SSD12")
	)
	(segment
		(start 341.288878 -38.322758)
		(end 340.44128 -37.47516)
		(width 0.508)
		(layer "In9.Cu")
		(net "P3V3_SSD12")
	)
	(segment
		(start 342.904318 -38.322758)
		(end 341.288878 -38.322758)
		(width 0.508)
		(layer "In9.Cu")
		(net "P3V3_SSD12")
	)
	(segment
		(start 343.354152 -37.872924)
		(end 342.904318 -38.322758)
		(width 0.508)
		(layer "In9.Cu")
		(net "P3V3_SSD12")
	)
	(segment
		(start 350.063816 -37.872924)
		(end 343.354152 -37.872924)
		(width 0.508)
		(layer "In9.Cu")
		(net "P3V3_SSD12")
	)
	(segment
		(start 51.293522 -101.407722)
		(end 51.947826 -101.407722)
		(width 0.13462)
		(layer "F.Cu")
		(net "P5E_PEX0_STN1_RX_DP<17>")
	)
	(segment
		(start 51.130708 -101.244908)
		(end 51.293522 -101.407722)
		(width 0.13462)
		(layer "F.Cu")
		(net "P5E_PEX0_STN1_RX_DP<17>")
	)
	(segment
		(start 50.64252 -101.244908)
		(end 51.130708 -101.244908)
		(width 0.13462)
		(layer "F.Cu")
		(net "P5E_PEX0_STN1_RX_DP<17>")
	)
	(segment
		(start 51.947826 -101.407722)
		(end 52.24272 -101.112828)
		(width 0.13462)
		(layer "F.Cu")
		(net "P5E_PEX0_STN1_RX_DP<17>")
	)
	(segment
		(start 51.423062 -101.440742)
		(end 44.722034 -105.264204)
		(width 0.1651)
		(layer "In5.Cu")
		(net "P5E_PEX0_STN1_RX_DP<17>")
	)
	(segment
		(start 52.24272 -101.112828)
		(end 51.95189 -101.403658)
		(width 0.1651)
		(layer "In5.Cu")
		(net "P5E_PEX0_STN1_RX_DP<17>")
	)
	(segment
		(start 51.460146 -101.403658)
		(end 51.423062 -101.440742)
		(width 0.1651)
		(layer "In5.Cu")
		(net "P5E_PEX0_STN1_RX_DP<17>")
	)
	(segment
		(start 60.029598 -275.35505)
		(end 60.244482 -275.569934)
		(width 0.1143)
		(layer "In5.Cu")
		(net "P5E_PEX0_STN1_RX_DP<17>")
	)
	(segment
		(start 60.029598 -271.848072)
		(end 60.029598 -275.35505)
		(width 0.1143)
		(layer "In5.Cu")
		(net "P5E_PEX0_STN1_RX_DP<17>")
	)
	(segment
		(start 33.334198 -117.142768)
		(end 31.963868 -119.854218)
		(width 0.1651)
		(layer "In5.Cu")
		(net "P5E_PEX0_STN1_RX_DP<17>")
	)
	(segment
		(start 59.983878 -271.802352)
		(end 60.029598 -271.848072)
		(width 0.1143)
		(layer "In5.Cu")
		(net "P5E_PEX0_STN1_RX_DP<17>")
	)
	(segment
		(start 29.035248 -150.181056)
		(end 29.605224 -158.872936)
		(width 0.1651)
		(layer "In5.Cu")
		(net "P5E_PEX0_STN1_RX_DP<17>")
	)
	(segment
		(start 60.485274 -275.569934)
		(end 60.599574 -275.684234)
		(width 0.1143)
		(layer "In5.Cu")
		(net "P5E_PEX0_STN1_RX_DP<17>")
	)
	(segment
		(start 51.95189 -101.403658)
		(end 51.460146 -101.403658)
		(width 0.1651)
		(layer "In5.Cu")
		(net "P5E_PEX0_STN1_RX_DP<17>")
	)
	(segment
		(start 59.983878 -269.939516)
		(end 59.983878 -271.773904)
		(width 0.1651)
		(layer "In5.Cu")
		(net "P5E_PEX0_STN1_RX_DP<17>")
	)
	(segment
		(start 44.722034 -105.264204)
		(end 33.334198 -117.142768)
		(width 0.1651)
		(layer "In5.Cu")
		(net "P5E_PEX0_STN1_RX_DP<17>")
	)
	(segment
		(start 31.963868 -119.854218)
		(end 30.46095 -126.572518)
		(width 0.1651)
		(layer "In5.Cu")
		(net "P5E_PEX0_STN1_RX_DP<17>")
	)
	(segment
		(start 60.599574 -275.684234)
		(end 60.599574 -275.949664)
		(width 0.1143)
		(layer "In5.Cu")
		(net "P5E_PEX0_STN1_RX_DP<17>")
	)
	(segment
		(start 30.46095 -126.572518)
		(end 29.035248 -150.181056)
		(width 0.1651)
		(layer "In5.Cu")
		(net "P5E_PEX0_STN1_RX_DP<17>")
	)
	(segment
		(start 30.80004 -165.415214)
		(end 59.983878 -269.939516)
		(width 0.1651)
		(layer "In5.Cu")
		(net "P5E_PEX0_STN1_RX_DP<17>")
	)
	(segment
		(start 60.244482 -275.569934)
		(end 60.485274 -275.569934)
		(width 0.1143)
		(layer "In5.Cu")
		(net "P5E_PEX0_STN1_RX_DP<17>")
	)
	(segment
		(start 29.605224 -158.872936)
		(end 30.80004 -165.415214)
		(width 0.1651)
		(layer "In5.Cu")
		(net "P5E_PEX0_STN1_RX_DP<17>")
	)
	(segment
		(start 59.983878 -271.773904)
		(end 59.983878 -271.802352)
		(width 0.1143)
		(layer "In5.Cu")
		(net "P5E_PEX0_STN1_RX_DP<17>")
	)
	(segment
		(start 166.742364 -101.244908)
		(end 167.230552 -101.244908)
		(width 0.13462)
		(layer "F.Cu")
		(net "P5E_PEX1_STN1_RX_DP<17>")
	)
	(segment
		(start 167.230552 -101.244908)
		(end 167.393366 -101.407722)
		(width 0.13462)
		(layer "F.Cu")
		(net "P5E_PEX1_STN1_RX_DP<17>")
	)
	(segment
		(start 167.393366 -101.407722)
		(end 168.04767 -101.407722)
		(width 0.13462)
		(layer "F.Cu")
		(net "P5E_PEX1_STN1_RX_DP<17>")
	)
	(segment
		(start 168.04767 -101.407722)
		(end 168.342564 -101.112828)
		(width 0.13462)
		(layer "F.Cu")
		(net "P5E_PEX1_STN1_RX_DP<17>")
	)
	(segment
		(start 145.135346 -150.181056)
		(end 145.705322 -158.872936)
		(width 0.1651)
		(layer "In5.Cu")
		(net "P5E_PEX1_STN1_RX_DP<17>")
	)
	(segment
		(start 168.342564 -101.112828)
		(end 168.342564 -101.113082)
		(width 0.1651)
		(layer "In5.Cu")
		(net "P5E_PEX1_STN1_RX_DP<17>")
	)
	(segment
		(start 146.561048 -126.572518)
		(end 145.135346 -150.181056)
		(width 0.1651)
		(layer "In5.Cu")
		(net "P5E_PEX1_STN1_RX_DP<17>")
	)
	(segment
		(start 176.129696 -275.35505)
		(end 176.34458 -275.569934)
		(width 0.1143)
		(layer "In5.Cu")
		(net "P5E_PEX1_STN1_RX_DP<17>")
	)
	(segment
		(start 176.083976 -271.599152)
		(end 176.129696 -271.644872)
		(width 0.1143)
		(layer "In5.Cu")
		(net "P5E_PEX1_STN1_RX_DP<17>")
	)
	(segment
		(start 176.129696 -271.644872)
		(end 176.129696 -275.35505)
		(width 0.1143)
		(layer "In5.Cu")
		(net "P5E_PEX1_STN1_RX_DP<17>")
	)
	(segment
		(start 176.699672 -275.684234)
		(end 176.699672 -275.949664)
		(width 0.1143)
		(layer "In5.Cu")
		(net "P5E_PEX1_STN1_RX_DP<17>")
	)
	(segment
		(start 176.585372 -275.569934)
		(end 176.699672 -275.684234)
		(width 0.1143)
		(layer "In5.Cu")
		(net "P5E_PEX1_STN1_RX_DP<17>")
	)
	(segment
		(start 176.34458 -275.569934)
		(end 176.585372 -275.569934)
		(width 0.1143)
		(layer "In5.Cu")
		(net "P5E_PEX1_STN1_RX_DP<17>")
	)
	(segment
		(start 148.063966 -119.854218)
		(end 146.561048 -126.572518)
		(width 0.1651)
		(layer "In5.Cu")
		(net "P5E_PEX1_STN1_RX_DP<17>")
	)
	(segment
		(start 168.051988 -101.403658)
		(end 167.588184 -101.403658)
		(width 0.1651)
		(layer "In5.Cu")
		(net "P5E_PEX1_STN1_RX_DP<17>")
	)
	(segment
		(start 145.705322 -158.872936)
		(end 146.900138 -165.415214)
		(width 0.1651)
		(layer "In5.Cu")
		(net "P5E_PEX1_STN1_RX_DP<17>")
	)
	(segment
		(start 168.342564 -101.113082)
		(end 168.051988 -101.403658)
		(width 0.1651)
		(layer "In5.Cu")
		(net "P5E_PEX1_STN1_RX_DP<17>")
	)
	(segment
		(start 167.588184 -101.403658)
		(end 160.822132 -105.264204)
		(width 0.1651)
		(layer "In5.Cu")
		(net "P5E_PEX1_STN1_RX_DP<17>")
	)
	(segment
		(start 176.083976 -269.939516)
		(end 176.083976 -271.570704)
		(width 0.1651)
		(layer "In5.Cu")
		(net "P5E_PEX1_STN1_RX_DP<17>")
	)
	(segment
		(start 146.900138 -165.415214)
		(end 176.083976 -269.939516)
		(width 0.1651)
		(layer "In5.Cu")
		(net "P5E_PEX1_STN1_RX_DP<17>")
	)
	(segment
		(start 160.822132 -105.264204)
		(end 149.434296 -117.142768)
		(width 0.1651)
		(layer "In5.Cu")
		(net "P5E_PEX1_STN1_RX_DP<17>")
	)
	(segment
		(start 176.083976 -271.570704)
		(end 176.083976 -271.599152)
		(width 0.1143)
		(layer "In5.Cu")
		(net "P5E_PEX1_STN1_RX_DP<17>")
	)
	(segment
		(start 149.434296 -117.142768)
		(end 148.063966 -119.854218)
		(width 0.1651)
		(layer "In5.Cu")
		(net "P5E_PEX1_STN1_RX_DP<17>")
	)
	(segment
		(start 249.39625 -28.55468)
		(end 248.1326 -28.55468)
		(width 0.13462)
		(layer "F.Cu")
		(net "P5E_PEX2_STN2_TX_C_DN<44>")
	)
	(segment
		(start 247.968008 -28.390088)
		(end 247.464834 -28.390088)
		(width 0.13462)
		(layer "F.Cu")
		(net "P5E_PEX2_STN2_TX_C_DN<44>")
	)
	(segment
		(start 249.725688 -28.225242)
		(end 249.39625 -28.55468)
		(width 0.13462)
		(layer "F.Cu")
		(net "P5E_PEX2_STN2_TX_C_DN<44>")
	)
	(segment
		(start 248.1326 -28.55468)
		(end 247.968008 -28.390088)
		(width 0.13462)
		(layer "F.Cu")
		(net "P5E_PEX2_STN2_TX_C_DN<44>")
	)
	(segment
		(start 430.373536 -148.59)
		(end 422.22547 -148.59)
		(width 0.13462)
		(layer "F.Cu")
		(net "P5E_PEX3_STN0_TX_C_DP<11>")
	)
	(segment
		(start 422.06037 -148.7551)
		(end 421.557704 -148.7551)
		(width 0.13462)
		(layer "F.Cu")
		(net "P5E_PEX3_STN0_TX_C_DP<11>")
	)
	(segment
		(start 422.22547 -148.59)
		(end 422.06037 -148.7551)
		(width 0.13462)
		(layer "F.Cu")
		(net "P5E_PEX3_STN0_TX_C_DP<11>")
	)
	(segment
		(start 430.694846 -148.91131)
		(end 430.373536 -148.59)
		(width 0.13462)
		(layer "F.Cu")
		(net "P5E_PEX3_STN0_TX_C_DP<11>")
	)
	(segment
		(start 387.864096 -393.130786)
		(end 396.719552 -389.466074)
		(width 0.1651)
		(layer "In5.Cu")
		(net "P5E_PEX3_STN5_RX_DP<84>")
	)
	(segment
		(start 386.662168 -394.221208)
		(end 387.864096 -393.130786)
		(width 0.1651)
		(layer "In5.Cu")
		(net "P5E_PEX3_STN5_RX_DP<84>")
	)
	(segment
		(start 400.445224 -365.059976)
		(end 400.364452 -364.963456)
		(width 0.1651)
		(layer "In5.Cu")
		(net "P5E_PEX3_STN5_RX_DP<84>")
	)
	(segment
		(start 399.21434 -386.036566)
		(end 399.37182 -374.386602)
		(width 0.1651)
		(layer "In5.Cu")
		(net "P5E_PEX3_STN5_RX_DP<84>")
	)
	(segment
		(start 400.304508 -365.633762)
		(end 400.401282 -365.553244)
		(width 0.1651)
		(layer "In5.Cu")
		(net "P5E_PEX3_STN5_RX_DP<84>")
	)
	(segment
		(start 409.708858 -325.418958)
		(end 410.183838 -323.138292)
		(width 0.1651)
		(layer "In5.Cu")
		(net "P5E_PEX3_STN5_RX_DP<84>")
	)
	(segment
		(start 385.166108 -396.134082)
		(end 386.662168 -394.221208)
		(width 0.1651)
		(layer "In5.Cu")
		(net "P5E_PEX3_STN5_RX_DP<84>")
	)
	(segment
		(start 410.229558 -316.455298)
		(end 410.455364 -316.229492)
		(width 0.1143)
		(layer "In5.Cu")
		(net "P5E_PEX3_STN5_RX_DP<84>")
	)
	(segment
		(start 384.833622 -397.003016)
		(end 385.166108 -396.67053)
		(width 0.1651)
		(layer "In5.Cu")
		(net "P5E_PEX3_STN5_RX_DP<84>")
	)
	(segment
		(start 398.82191 -387.283452)
		(end 399.21434 -386.036566)
		(width 0.1651)
		(layer "In5.Cu")
		(net "P5E_PEX3_STN5_RX_DP<84>")
	)
	(segment
		(start 400.002756 -369.994434)
		(end 400.34083 -366.223804)
		(width 0.1651)
		(layer "In5.Cu")
		(net "P5E_PEX3_STN5_RX_DP<84>")
	)
	(segment
		(start 400.505676 -364.389416)
		(end 400.505422 -364.389416)
		(width 0.1651)
		(layer "In5.Cu")
		(net "P5E_PEX3_STN5_RX_DP<84>")
	)
	(segment
		(start 410.183838 -319.916048)
		(end 410.183838 -319.8876)
		(width 0.1143)
		(layer "In5.Cu")
		(net "P5E_PEX3_STN5_RX_DP<84>")
	)
	(segment
		(start 410.183838 -319.8876)
		(end 410.229558 -319.84188)
		(width 0.1143)
		(layer "In5.Cu")
		(net "P5E_PEX3_STN5_RX_DP<84>")
	)
	(segment
		(start 384.290062 -396.49019)
		(end 384.290062 -396.876016)
		(width 0.1651)
		(layer "In5.Cu")
		(net "P5E_PEX3_STN5_RX_DP<84>")
	)
	(segment
		(start 400.260312 -366.127284)
		(end 400.304508 -365.633762)
		(width 0.1651)
		(layer "In5.Cu")
		(net "P5E_PEX3_STN5_RX_DP<84>")
	)
	(segment
		(start 401.292314 -341.15121)
		(end 408.680412 -327.782428)
		(width 0.1651)
		(layer "In5.Cu")
		(net "P5E_PEX3_STN5_RX_DP<84>")
	)
	(segment
		(start 410.685488 -316.229492)
		(end 410.799788 -316.115192)
		(width 0.1143)
		(layer "In5.Cu")
		(net "P5E_PEX3_STN5_RX_DP<84>")
	)
	(segment
		(start 384.290062 -396.876016)
		(end 384.417062 -397.003016)
		(width 0.1651)
		(layer "In5.Cu")
		(net "P5E_PEX3_STN5_RX_DP<84>")
	)
	(segment
		(start 401.01393 -341.942674)
		(end 401.292314 -341.15121)
		(width 0.1651)
		(layer "In5.Cu")
		(net "P5E_PEX3_STN5_RX_DP<84>")
	)
	(segment
		(start 400.505422 -364.389416)
		(end 401.01393 -358.721152)
		(width 0.1651)
		(layer "In5.Cu")
		(net "P5E_PEX3_STN5_RX_DP<84>")
	)
	(segment
		(start 399.37182 -374.386602)
		(end 400.002756 -369.994434)
		(width 0.1651)
		(layer "In5.Cu")
		(net "P5E_PEX3_STN5_RX_DP<84>")
	)
	(segment
		(start 410.183838 -323.138292)
		(end 410.183838 -319.916048)
		(width 0.1651)
		(layer "In5.Cu")
		(net "P5E_PEX3_STN5_RX_DP<84>")
	)
	(segment
		(start 408.680412 -327.782428)
		(end 409.708858 -325.418958)
		(width 0.1651)
		(layer "In5.Cu")
		(net "P5E_PEX3_STN5_RX_DP<84>")
	)
	(segment
		(start 400.401282 -365.553244)
		(end 400.401028 -365.553244)
		(width 0.1651)
		(layer "In5.Cu")
		(net "P5E_PEX3_STN5_RX_DP<84>")
	)
	(segment
		(start 410.455364 -316.229492)
		(end 410.685488 -316.229492)
		(width 0.1143)
		(layer "In5.Cu")
		(net "P5E_PEX3_STN5_RX_DP<84>")
	)
	(segment
		(start 398.108932 -388.333996)
		(end 398.82191 -387.283452)
		(width 0.1651)
		(layer "In5.Cu")
		(net "P5E_PEX3_STN5_RX_DP<84>")
	)
	(segment
		(start 396.719552 -389.466074)
		(end 398.108932 -388.333996)
		(width 0.1651)
		(layer "In5.Cu")
		(net "P5E_PEX3_STN5_RX_DP<84>")
	)
	(segment
		(start 401.01393 -358.721152)
		(end 401.01393 -341.942674)
		(width 0.1651)
		(layer "In5.Cu")
		(net "P5E_PEX3_STN5_RX_DP<84>")
	)
	(segment
		(start 400.34083 -366.223804)
		(end 400.260312 -366.127284)
		(width 0.1651)
		(layer "In5.Cu")
		(net "P5E_PEX3_STN5_RX_DP<84>")
	)
	(segment
		(start 410.799788 -316.115192)
		(end 410.799788 -315.849762)
		(width 0.1143)
		(layer "In5.Cu")
		(net "P5E_PEX3_STN5_RX_DP<84>")
	)
	(segment
		(start 400.408902 -364.469934)
		(end 400.505676 -364.389416)
		(width 0.1651)
		(layer "In5.Cu")
		(net "P5E_PEX3_STN5_RX_DP<84>")
	)
	(segment
		(start 400.364452 -364.963456)
		(end 400.408902 -364.469934)
		(width 0.1651)
		(layer "In5.Cu")
		(net "P5E_PEX3_STN5_RX_DP<84>")
	)
	(segment
		(start 384.417062 -397.003016)
		(end 384.833622 -397.003016)
		(width 0.1651)
		(layer "In5.Cu")
		(net "P5E_PEX3_STN5_RX_DP<84>")
	)
	(segment
		(start 400.401028 -365.553244)
		(end 400.445224 -365.059976)
		(width 0.1651)
		(layer "In5.Cu")
		(net "P5E_PEX3_STN5_RX_DP<84>")
	)
	(segment
		(start 385.166108 -396.67053)
		(end 385.166108 -396.134082)
		(width 0.1651)
		(layer "In5.Cu")
		(net "P5E_PEX3_STN5_RX_DP<84>")
	)
	(segment
		(start 410.229558 -319.84188)
		(end 410.229558 -316.455298)
		(width 0.1143)
		(layer "In5.Cu")
		(net "P5E_PEX3_STN5_RX_DP<84>")
	)
	(segment
		(start 278.242268 -157.15996)
		(end 276.552914 -157.15996)
		(width 0.13208)
		(layer "F.Cu")
		(net "NIC4_LD_N")
	)
	(segment
		(start 276.552914 -157.15996)
		(end 274.721574 -158.9913)
		(width 0.13208)
		(layer "F.Cu")
		(net "NIC4_LD_N")
	)
	(segment
		(start 272.387568 -158.9913)
		(end 271.790668 -158.3944)
		(width 0.13208)
		(layer "F.Cu")
		(net "NIC4_LD_N")
	)
	(segment
		(start 271.790668 -158.3944)
		(end 271.207992 -158.3944)
		(width 0.13208)
		(layer "F.Cu")
		(net "NIC4_LD_N")
	)
	(segment
		(start 274.721574 -158.9913)
		(end 272.387568 -158.9913)
		(width 0.13208)
		(layer "F.Cu")
		(net "NIC4_LD_N")
	)
	(via
		(at 272.387568 -158.9913)
		(size 0.762)
		(drill 0.381)
		(layers "F.Cu" "B.Cu")
		(net "NIC4_LD_N")
	)
	(segment
		(start 45.391324 -101.682042)
		(end 37.842444 -101.682042)
		(width 0.13462)
		(layer "F.Cu")
		(net "P5E_PEX0_STN1_TX_C_DP<17>")
	)
	(segment
		(start 37.842444 -101.682042)
		(end 37.514784 -102.009702)
		(width 0.13462)
		(layer "F.Cu")
		(net "P5E_PEX0_STN1_TX_C_DP<17>")
	)
	(segment
		(start 46.042326 -101.84511)
		(end 45.554392 -101.84511)
		(width 0.13462)
		(layer "F.Cu")
		(net "P5E_PEX0_STN1_TX_C_DP<17>")
	)
	(segment
		(start 45.554392 -101.84511)
		(end 45.391324 -101.682042)
		(width 0.13462)
		(layer "F.Cu")
		(net "P5E_PEX0_STN1_TX_C_DP<17>")
	)
	(segment
		(start 162.14217 -134.765034)
		(end 161.654236 -134.765034)
		(width 0.13462)
		(layer "F.Cu")
		(net "P5E_PEX1_STN1_TX_C_DN<30>")
	)
	(segment
		(start 161.654236 -134.765034)
		(end 161.491422 -134.60222)
		(width 0.13462)
		(layer "F.Cu")
		(net "P5E_PEX1_STN1_TX_C_DN<30>")
	)
	(segment
		(start 153.326084 -134.60222)
		(end 153.005028 -134.923276)
		(width 0.13462)
		(layer "F.Cu")
		(net "P5E_PEX1_STN1_TX_C_DN<30>")
	)
	(segment
		(start 161.491422 -134.60222)
		(end 153.326084 -134.60222)
		(width 0.13462)
		(layer "F.Cu")
		(net "P5E_PEX1_STN1_TX_C_DN<30>")
	)
	(segment
		(start 299.96765 -34.390076)
		(end 299.46473 -34.390076)
		(width 0.13462)
		(layer "F.Cu")
		(net "P5E_PEX2_STN2_TX_C_DP<39>")
	)
	(segment
		(start 304.047906 -34.2265)
		(end 300.131226 -34.2265)
		(width 0.13462)
		(layer "F.Cu")
		(net "P5E_PEX2_STN2_TX_C_DP<39>")
	)
	(segment
		(start 304.367692 -34.546286)
		(end 304.047906 -34.2265)
		(width 0.13462)
		(layer "F.Cu")
		(net "P5E_PEX2_STN2_TX_C_DP<39>")
	)
	(segment
		(start 300.131226 -34.2265)
		(end 299.96765 -34.390076)
		(width 0.13462)
		(layer "F.Cu")
		(net "P5E_PEX2_STN2_TX_C_DP<39>")
	)
	(segment
		(start 415.651188 -119.27332)
		(end 416.316668 -119.27332)
		(width 0.13462)
		(layer "F.Cu")
		(net "P5E_PEX3_STN0_RX_DP<0>")
	)
	(segment
		(start 416.478466 -119.435118)
		(end 416.95751 -119.435118)
		(width 0.13462)
		(layer "F.Cu")
		(net "P5E_PEX3_STN0_RX_DP<0>")
	)
	(segment
		(start 415.35731 -119.567198)
		(end 415.651188 -119.27332)
		(width 0.13462)
		(layer "F.Cu")
		(net "P5E_PEX3_STN0_RX_DP<0>")
	)
	(segment
		(start 416.316668 -119.27332)
		(end 416.478466 -119.435118)
		(width 0.13462)
		(layer "F.Cu")
		(net "P5E_PEX3_STN0_RX_DP<0>")
	)
	(segment
		(start 417.773104 -120.081548)
		(end 418.231066 -120.271032)
		(width 0.1651)
		(layer "In5.Cu")
		(net "P5E_PEX3_STN0_RX_DP<0>")
	)
	(segment
		(start 417.710874 -119.931942)
		(end 417.711128 -119.931942)
		(width 0.1651)
		(layer "In5.Cu")
		(net "P5E_PEX3_STN0_RX_DP<0>")
	)
	(segment
		(start 437.671718 -149.84476)
		(end 438.123838 -168.526206)
		(width 0.1651)
		(layer "In5.Cu")
		(net "P5E_PEX3_STN0_RX_DP<0>")
	)
	(segment
		(start 424.838368 -124.595128)
		(end 425.23537 -124.891038)
		(width 0.1651)
		(layer "In5.Cu")
		(net "P5E_PEX3_STN0_RX_DP<0>")
	)
	(segment
		(start 424.678348 -124.618496)
		(end 424.838368 -124.595128)
		(width 0.1651)
		(layer "In5.Cu")
		(net "P5E_PEX3_STN0_RX_DP<0>")
	)
	(segment
		(start 416.584384 -119.465598)
		(end 416.64636 -119.615204)
		(width 0.1651)
		(layer "In5.Cu")
		(net "P5E_PEX3_STN0_RX_DP<0>")
	)
	(segment
		(start 426.212762 -125.620018)
		(end 426.235876 -125.780038)
		(width 0.1651)
		(layer "In5.Cu")
		(net "P5E_PEX3_STN0_RX_DP<0>")
	)
	(segment
		(start 444.915544 -278.22525)
		(end 435.859428 -286.969708)
		(width 0.1651)
		(layer "In5.Cu")
		(net "P5E_PEX3_STN0_RX_DP<0>")
	)
	(segment
		(start 420.809166 -121.214388)
		(end 422.307766 -122.708162)
		(width 0.1651)
		(layer "In5.Cu")
		(net "P5E_PEX3_STN0_RX_DP<0>")
	)
	(segment
		(start 447.509392 -273.645376)
		(end 444.915544 -278.22525)
		(width 0.1651)
		(layer "In5.Cu")
		(net "P5E_PEX3_STN0_RX_DP<0>")
	)
	(segment
		(start 434.214524 -131.999482)
		(end 437.276748 -145.627852)
		(width 0.1651)
		(layer "In5.Cu")
		(net "P5E_PEX3_STN0_RX_DP<0>")
	)
	(segment
		(start 419.507162 -120.6754)
		(end 420.809166 -121.214388)
		(width 0.1651)
		(layer "In5.Cu")
		(net "P5E_PEX3_STN0_RX_DP<0>")
	)
	(segment
		(start 424.281092 -124.322332)
		(end 424.678348 -124.618496)
		(width 0.1651)
		(layer "In5.Cu")
		(net "P5E_PEX3_STN0_RX_DP<0>")
	)
	(segment
		(start 418.231066 -120.271032)
		(end 418.380418 -120.209056)
		(width 0.1651)
		(layer "In5.Cu")
		(net "P5E_PEX3_STN0_RX_DP<0>")
	)
	(segment
		(start 432.19624 -287.683956)
		(end 432.15052 -287.729676)
		(width 0.1143)
		(layer "In5.Cu")
		(net "P5E_PEX3_STN0_RX_DP<0>")
	)
	(segment
		(start 428.523654 -287.729676)
		(end 428.27956 -287.97377)
		(width 0.1143)
		(layer "In5.Cu")
		(net "P5E_PEX3_STN0_RX_DP<0>")
	)
	(segment
		(start 415.35731 -119.567198)
		(end 415.64814 -119.276368)
		(width 0.1651)
		(layer "In5.Cu")
		(net "P5E_PEX3_STN0_RX_DP<0>")
	)
	(segment
		(start 417.711128 -119.931942)
		(end 417.773104 -120.081548)
		(width 0.1651)
		(layer "In5.Cu")
		(net "P5E_PEX3_STN0_RX_DP<0>")
	)
	(segment
		(start 428.27956 -287.97377)
		(end 428.27956 -288.185606)
		(width 0.1143)
		(layer "In5.Cu")
		(net "P5E_PEX3_STN0_RX_DP<0>")
	)
	(segment
		(start 435.859428 -286.969708)
		(end 434.72735 -287.683956)
		(width 0.1651)
		(layer "In5.Cu")
		(net "P5E_PEX3_STN0_RX_DP<0>")
	)
	(segment
		(start 418.899848 -120.547892)
		(end 419.35781 -120.737376)
		(width 0.1651)
		(layer "In5.Cu")
		(net "P5E_PEX3_STN0_RX_DP<0>")
	)
	(segment
		(start 438.99328 -239.28705)
		(end 447.690748 -269.159482)
		(width 0.1651)
		(layer "In5.Cu")
		(net "P5E_PEX3_STN0_RX_DP<0>")
	)
	(segment
		(start 433.488592 -131.045458)
		(end 434.214524 -131.999482)
		(width 0.1651)
		(layer "In5.Cu")
		(net "P5E_PEX3_STN0_RX_DP<0>")
	)
	(segment
		(start 426.633386 -126.076456)
		(end 426.793152 -126.053088)
		(width 0.1651)
		(layer "In5.Cu")
		(net "P5E_PEX3_STN0_RX_DP<0>")
	)
	(segment
		(start 437.276748 -145.627852)
		(end 437.671718 -149.84476)
		(width 0.1651)
		(layer "In5.Cu")
		(net "P5E_PEX3_STN0_RX_DP<0>")
	)
	(segment
		(start 425.81576 -125.324108)
		(end 426.212762 -125.620018)
		(width 0.1651)
		(layer "In5.Cu")
		(net "P5E_PEX3_STN0_RX_DP<0>")
	)
	(segment
		(start 418.837872 -120.398286)
		(end 418.899848 -120.547892)
		(width 0.1651)
		(layer "In5.Cu")
		(net "P5E_PEX3_STN0_RX_DP<0>")
	)
	(segment
		(start 424.257978 -124.162312)
		(end 424.281092 -124.322332)
		(width 0.1651)
		(layer "In5.Cu")
		(net "P5E_PEX3_STN0_RX_DP<0>")
	)
	(segment
		(start 428.27956 -288.185606)
		(end 428.16526 -288.299906)
		(width 0.1143)
		(layer "In5.Cu")
		(net "P5E_PEX3_STN0_RX_DP<0>")
	)
	(segment
		(start 425.23537 -124.891038)
		(end 425.258484 -125.051058)
		(width 0.1651)
		(layer "In5.Cu")
		(net "P5E_PEX3_STN0_RX_DP<0>")
	)
	(segment
		(start 447.690748 -269.159482)
		(end 447.509392 -273.645376)
		(width 0.1651)
		(layer "In5.Cu")
		(net "P5E_PEX3_STN0_RX_DP<0>")
	)
	(segment
		(start 422.307766 -122.708162)
		(end 424.257978 -124.162312)
		(width 0.1651)
		(layer "In5.Cu")
		(net "P5E_PEX3_STN0_RX_DP<0>")
	)
	(segment
		(start 418.380418 -120.209056)
		(end 418.837618 -120.398286)
		(width 0.1651)
		(layer "In5.Cu")
		(net "P5E_PEX3_STN0_RX_DP<0>")
	)
	(segment
		(start 418.837618 -120.398286)
		(end 418.837872 -120.398286)
		(width 0.1651)
		(layer "In5.Cu")
		(net "P5E_PEX3_STN0_RX_DP<0>")
	)
	(segment
		(start 426.793152 -126.053088)
		(end 433.488592 -131.045458)
		(width 0.1651)
		(layer "In5.Cu")
		(net "P5E_PEX3_STN0_RX_DP<0>")
	)
	(segment
		(start 416.126676 -119.276368)
		(end 416.584384 -119.465852)
		(width 0.1651)
		(layer "In5.Cu")
		(net "P5E_PEX3_STN0_RX_DP<0>")
	)
	(segment
		(start 434.72735 -287.683956)
		(end 432.224688 -287.683956)
		(width 0.1651)
		(layer "In5.Cu")
		(net "P5E_PEX3_STN0_RX_DP<0>")
	)
	(segment
		(start 415.64814 -119.276368)
		(end 416.126676 -119.276368)
		(width 0.1651)
		(layer "In5.Cu")
		(net "P5E_PEX3_STN0_RX_DP<0>")
	)
	(segment
		(start 425.258484 -125.051058)
		(end 425.655994 -125.347476)
		(width 0.1651)
		(layer "In5.Cu")
		(net "P5E_PEX3_STN0_RX_DP<0>")
	)
	(segment
		(start 437.457342 -231.903016)
		(end 438.99328 -239.28705)
		(width 0.1651)
		(layer "In5.Cu")
		(net "P5E_PEX3_STN0_RX_DP<0>")
	)
	(segment
		(start 417.253674 -119.742712)
		(end 417.710874 -119.931942)
		(width 0.1651)
		(layer "In5.Cu")
		(net "P5E_PEX3_STN0_RX_DP<0>")
	)
	(segment
		(start 416.584384 -119.465852)
		(end 416.584384 -119.465598)
		(width 0.1651)
		(layer "In5.Cu")
		(net "P5E_PEX3_STN0_RX_DP<0>")
	)
	(segment
		(start 426.235876 -125.780038)
		(end 426.633386 -126.076456)
		(width 0.1651)
		(layer "In5.Cu")
		(net "P5E_PEX3_STN0_RX_DP<0>")
	)
	(segment
		(start 419.35781 -120.737376)
		(end 419.507162 -120.6754)
		(width 0.1651)
		(layer "In5.Cu")
		(net "P5E_PEX3_STN0_RX_DP<0>")
	)
	(segment
		(start 425.655994 -125.347476)
		(end 425.81576 -125.324108)
		(width 0.1651)
		(layer "In5.Cu")
		(net "P5E_PEX3_STN0_RX_DP<0>")
	)
	(segment
		(start 438.123838 -168.526206)
		(end 437.457342 -231.903016)
		(width 0.1651)
		(layer "In5.Cu")
		(net "P5E_PEX3_STN0_RX_DP<0>")
	)
	(segment
		(start 416.64636 -119.615204)
		(end 417.104322 -119.804688)
		(width 0.1651)
		(layer "In5.Cu")
		(net "P5E_PEX3_STN0_RX_DP<0>")
	)
	(segment
		(start 417.104322 -119.804688)
		(end 417.253674 -119.742712)
		(width 0.1651)
		(layer "In5.Cu")
		(net "P5E_PEX3_STN0_RX_DP<0>")
	)
	(segment
		(start 428.16526 -288.299906)
		(end 427.89983 -288.299906)
		(width 0.1143)
		(layer "In5.Cu")
		(net "P5E_PEX3_STN0_RX_DP<0>")
	)
	(segment
		(start 432.15052 -287.729676)
		(end 428.523654 -287.729676)
		(width 0.1143)
		(layer "In5.Cu")
		(net "P5E_PEX3_STN0_RX_DP<0>")
	)
	(segment
		(start 432.224688 -287.683956)
		(end 432.19624 -287.683956)
		(width 0.1143)
		(layer "In5.Cu")
		(net "P5E_PEX3_STN0_RX_DP<0>")
	)
	(segment
		(start 407.949908 -318.434466)
		(end 407.949908 -318.699896)
		(width 0.1143)
		(layer "In5.Cu")
		(net "P5E_PEX3_STN5_RX_DN<81>")
	)
	(segment
		(start 377.689872 -398.890236)
		(end 377.689872 -398.51203)
		(width 0.1651)
		(layer "In5.Cu")
		(net "P5E_PEX3_STN5_RX_DN<81>")
	)
	(segment
		(start 378.350272 -398.38503)
		(end 378.847858 -397.887444)
		(width 0.1651)
		(layer "In5.Cu")
		(net "P5E_PEX3_STN5_RX_DN<81>")
	)
	(segment
		(start 396.580868 -385.450588)
		(end 396.65656 -370.379752)
		(width 0.1651)
		(layer "In5.Cu")
		(net "P5E_PEX3_STN5_RX_DN<81>")
	)
	(segment
		(start 395.2367 -387.161532)
		(end 395.951964 -386.656072)
		(width 0.1651)
		(layer "In5.Cu")
		(net "P5E_PEX3_STN5_RX_DN<81>")
	)
	(segment
		(start 379.4506 -394.57376)
		(end 383.507488 -392.134598)
		(width 0.1651)
		(layer "In5.Cu")
		(net "P5E_PEX3_STN5_RX_DN<81>")
	)
	(segment
		(start 407.615898 -319.916048)
		(end 407.615898 -319.8876)
		(width 0.1143)
		(layer "In5.Cu")
		(net "P5E_PEX3_STN5_RX_DN<81>")
	)
	(segment
		(start 391.96899 -342.057482)
		(end 392.471402 -341.200486)
		(width 0.1651)
		(layer "In5.Cu")
		(net "P5E_PEX3_STN5_RX_DN<81>")
	)
	(segment
		(start 395.951964 -386.656072)
		(end 396.244318 -386.378196)
		(width 0.1651)
		(layer "In5.Cu")
		(net "P5E_PEX3_STN5_RX_DN<81>")
	)
	(segment
		(start 407.570178 -319.84188)
		(end 407.570178 -318.434466)
		(width 0.1143)
		(layer "In5.Cu")
		(net "P5E_PEX3_STN5_RX_DN<81>")
	)
	(segment
		(start 396.353538 -368.713766)
		(end 396.353538 -368.698018)
		(width 0.1651)
		(layer "In5.Cu")
		(net "P5E_PEX3_STN5_RX_DN<81>")
	)
	(segment
		(start 391.96899 -357.971344)
		(end 391.96899 -342.057482)
		(width 0.1651)
		(layer "In5.Cu")
		(net "P5E_PEX3_STN5_RX_DN<81>")
	)
	(segment
		(start 407.615898 -319.8876)
		(end 407.570178 -319.84188)
		(width 0.1143)
		(layer "In5.Cu")
		(net "P5E_PEX3_STN5_RX_DN<81>")
	)
	(segment
		(start 396.244318 -386.378196)
		(end 396.580868 -385.450588)
		(width 0.1651)
		(layer "In5.Cu")
		(net "P5E_PEX3_STN5_RX_DN<81>")
	)
	(segment
		(start 407.570178 -318.434466)
		(end 407.684478 -318.320166)
		(width 0.1143)
		(layer "In5.Cu")
		(net "P5E_PEX3_STN5_RX_DN<81>")
	)
	(segment
		(start 377.689872 -398.51203)
		(end 377.816872 -398.38503)
		(width 0.1651)
		(layer "In5.Cu")
		(net "P5E_PEX3_STN5_RX_DN<81>")
	)
	(segment
		(start 407.615898 -322.142104)
		(end 407.615898 -319.916048)
		(width 0.1651)
		(layer "In5.Cu")
		(net "P5E_PEX3_STN5_RX_DN<81>")
	)
	(segment
		(start 396.353538 -368.698018)
		(end 396.342362 -368.686842)
		(width 0.1651)
		(layer "In5.Cu")
		(net "P5E_PEX3_STN5_RX_DN<81>")
	)
	(segment
		(start 377.816872 -398.38503)
		(end 378.350272 -398.38503)
		(width 0.1651)
		(layer "In5.Cu")
		(net "P5E_PEX3_STN5_RX_DN<81>")
	)
	(segment
		(start 407.684478 -318.320166)
		(end 407.835608 -318.320166)
		(width 0.1143)
		(layer "In5.Cu")
		(net "P5E_PEX3_STN5_RX_DN<81>")
	)
	(segment
		(start 383.507488 -392.134598)
		(end 395.2367 -387.161532)
		(width 0.1651)
		(layer "In5.Cu")
		(net "P5E_PEX3_STN5_RX_DN<81>")
	)
	(segment
		(start 378.847858 -395.3891)
		(end 379.4506 -394.57376)
		(width 0.1651)
		(layer "In5.Cu")
		(net "P5E_PEX3_STN5_RX_DN<81>")
	)
	(segment
		(start 392.471402 -341.200486)
		(end 406.08504 -326.652636)
		(width 0.1651)
		(layer "In5.Cu")
		(net "P5E_PEX3_STN5_RX_DN<81>")
	)
	(segment
		(start 407.835608 -318.320166)
		(end 407.949908 -318.434466)
		(width 0.1143)
		(layer "In5.Cu")
		(net "P5E_PEX3_STN5_RX_DN<81>")
	)
	(segment
		(start 406.08504 -326.652636)
		(end 407.171144 -324.224142)
		(width 0.1651)
		(layer "In5.Cu")
		(net "P5E_PEX3_STN5_RX_DN<81>")
	)
	(segment
		(start 396.342362 -368.686842)
		(end 391.96899 -357.971344)
		(width 0.1651)
		(layer "In5.Cu")
		(net "P5E_PEX3_STN5_RX_DN<81>")
	)
	(segment
		(start 378.847858 -397.887444)
		(end 378.847858 -395.3891)
		(width 0.1651)
		(layer "In5.Cu")
		(net "P5E_PEX3_STN5_RX_DN<81>")
	)
	(segment
		(start 407.171144 -324.224142)
		(end 407.615898 -322.142104)
		(width 0.1651)
		(layer "In5.Cu")
		(net "P5E_PEX3_STN5_RX_DN<81>")
	)
	(segment
		(start 396.65656 -370.379752)
		(end 396.353538 -368.713766)
		(width 0.1651)
		(layer "In5.Cu")
		(net "P5E_PEX3_STN5_RX_DN<81>")
	)
	(segment
		(start 59.395106 -100.766372)
		(end 59.395106 -99.750372)
		(width 0.13208)
		(layer "F.Cu")
		(net "NIC1_SLOT_ID1")
	)
	(segment
		(start 62.21984 -100.039932)
		(end 68.65747 -100.039932)
		(width 0.13208)
		(layer "F.Cu")
		(net "NIC1_SLOT_ID1")
	)
	(segment
		(start 59.395106 -99.750372)
		(end 61.93028 -99.750372)
		(width 0.13208)
		(layer "F.Cu")
		(net "NIC1_SLOT_ID1")
	)
	(segment
		(start 61.93028 -99.750372)
		(end 62.21984 -100.039932)
		(width 0.13208)
		(layer "F.Cu")
		(net "NIC1_SLOT_ID1")
	)
	(via
		(at 62.21984 -100.039932)
		(size 0.762)
		(drill 0.381)
		(layers "F.Cu" "B.Cu")
		(net "NIC1_SLOT_ID1")
	)
	(segment
		(start 51.130454 -121.154952)
		(end 51.293268 -121.317766)
		(width 0.13462)
		(layer "F.Cu")
		(net "P5E_PEX0_STN1_RX_DP<25>")
	)
	(segment
		(start 50.64252 -121.154952)
		(end 51.130454 -121.154952)
		(width 0.13462)
		(layer "F.Cu")
		(net "P5E_PEX0_STN1_RX_DP<25>")
	)
	(segment
		(start 51.293268 -121.317766)
		(end 51.947826 -121.317766)
		(width 0.13462)
		(layer "F.Cu")
		(net "P5E_PEX0_STN1_RX_DP<25>")
	)
	(segment
		(start 51.947826 -121.317766)
		(end 52.24272 -121.022872)
		(width 0.13462)
		(layer "F.Cu")
		(net "P5E_PEX0_STN1_RX_DP<25>")
	)
	(segment
		(start 52.24272 -121.022872)
		(end 51.95189 -121.313702)
		(width 0.1651)
		(layer "In5.Cu")
		(net "P5E_PEX0_STN1_RX_DP<25>")
	)
	(segment
		(start 51.732434 -121.313702)
		(end 49.987454 -122.009662)
		(width 0.1651)
		(layer "In5.Cu")
		(net "P5E_PEX0_STN1_RX_DP<25>")
	)
	(segment
		(start 67.844416 -275.569934)
		(end 68.085208 -275.569934)
		(width 0.1143)
		(layer "In5.Cu")
		(net "P5E_PEX0_STN1_RX_DP<25>")
	)
	(segment
		(start 67.583812 -271.802352)
		(end 67.629532 -271.848072)
		(width 0.1143)
		(layer "In5.Cu")
		(net "P5E_PEX0_STN1_RX_DP<25>")
	)
	(segment
		(start 40.57523 -142.635986)
		(end 38.287452 -145.587212)
		(width 0.1651)
		(layer "In5.Cu")
		(net "P5E_PEX0_STN1_RX_DP<25>")
	)
	(segment
		(start 43.492674 -128.887982)
		(end 41.921684 -137.931144)
		(width 0.1651)
		(layer "In5.Cu")
		(net "P5E_PEX0_STN1_RX_DP<25>")
	)
	(segment
		(start 37.850826 -147.266914)
		(end 37.853366 -147.311364)
		(width 0.1651)
		(layer "In5.Cu")
		(net "P5E_PEX0_STN1_RX_DP<25>")
	)
	(segment
		(start 45.776388 -125.831854)
		(end 43.681142 -128.458722)
		(width 0.1651)
		(layer "In5.Cu")
		(net "P5E_PEX0_STN1_RX_DP<25>")
	)
	(segment
		(start 41.921684 -137.931144)
		(end 40.57523 -142.635986)
		(width 0.1651)
		(layer "In5.Cu")
		(net "P5E_PEX0_STN1_RX_DP<25>")
	)
	(segment
		(start 67.629532 -275.35505)
		(end 67.844416 -275.569934)
		(width 0.1143)
		(layer "In5.Cu")
		(net "P5E_PEX0_STN1_RX_DP<25>")
	)
	(segment
		(start 67.583812 -268.07414)
		(end 67.583812 -271.773904)
		(width 0.1651)
		(layer "In5.Cu")
		(net "P5E_PEX0_STN1_RX_DP<25>")
	)
	(segment
		(start 67.583812 -271.773904)
		(end 67.583812 -271.802352)
		(width 0.1143)
		(layer "In5.Cu")
		(net "P5E_PEX0_STN1_RX_DP<25>")
	)
	(segment
		(start 37.853366 -147.311364)
		(end 37.85362 -147.311364)
		(width 0.1651)
		(layer "In5.Cu")
		(net "P5E_PEX0_STN1_RX_DP<25>")
	)
	(segment
		(start 37.85362 -147.311364)
		(end 38.463728 -157.255972)
		(width 0.1651)
		(layer "In5.Cu")
		(net "P5E_PEX0_STN1_RX_DP<25>")
	)
	(segment
		(start 39.405306 -162.425888)
		(end 67.583812 -268.07414)
		(width 0.1651)
		(layer "In5.Cu")
		(net "P5E_PEX0_STN1_RX_DP<25>")
	)
	(segment
		(start 67.629532 -271.848072)
		(end 67.629532 -275.35505)
		(width 0.1143)
		(layer "In5.Cu")
		(net "P5E_PEX0_STN1_RX_DP<25>")
	)
	(segment
		(start 38.463728 -157.255972)
		(end 39.405306 -162.425888)
		(width 0.1651)
		(layer "In5.Cu")
		(net "P5E_PEX0_STN1_RX_DP<25>")
	)
	(segment
		(start 43.681142 -128.458722)
		(end 43.492674 -128.887982)
		(width 0.1651)
		(layer "In5.Cu")
		(net "P5E_PEX0_STN1_RX_DP<25>")
	)
	(segment
		(start 68.199508 -275.684234)
		(end 68.199508 -275.949664)
		(width 0.1143)
		(layer "In5.Cu")
		(net "P5E_PEX0_STN1_RX_DP<25>")
	)
	(segment
		(start 49.987454 -122.009662)
		(end 45.776388 -125.831854)
		(width 0.1651)
		(layer "In5.Cu")
		(net "P5E_PEX0_STN1_RX_DP<25>")
	)
	(segment
		(start 38.287452 -145.587212)
		(end 37.850826 -147.266914)
		(width 0.1651)
		(layer "In5.Cu")
		(net "P5E_PEX0_STN1_RX_DP<25>")
	)
	(segment
		(start 51.95189 -121.313702)
		(end 51.732434 -121.313702)
		(width 0.1651)
		(layer "In5.Cu")
		(net "P5E_PEX0_STN1_RX_DP<25>")
	)
	(segment
		(start 68.085208 -275.569934)
		(end 68.199508 -275.684234)
		(width 0.1143)
		(layer "In5.Cu")
		(net "P5E_PEX0_STN1_RX_DP<25>")
	)
	(segment
		(start 162.14217 -119.955056)
		(end 161.654236 -119.955056)
		(width 0.13462)
		(layer "F.Cu")
		(net "P5E_PEX1_STN1_TX_C_DN<24>")
	)
	(segment
		(start 161.654236 -119.955056)
		(end 161.491422 -119.792242)
		(width 0.13462)
		(layer "F.Cu")
		(net "P5E_PEX1_STN1_TX_C_DN<24>")
	)
	(segment
		(start 161.491422 -119.792242)
		(end 153.326084 -119.792242)
		(width 0.13462)
		(layer "F.Cu")
		(net "P5E_PEX1_STN1_TX_C_DN<24>")
	)
	(segment
		(start 153.326084 -119.792242)
		(end 153.005028 -120.113298)
		(width 0.13462)
		(layer "F.Cu")
		(net "P5E_PEX1_STN1_TX_C_DN<24>")
	)
	(segment
		(start 320.219324 -30.62732)
		(end 317.705486 -30.62732)
		(width 0.13462)
		(layer "F.Cu")
		(net "P5E_PEX2_STN2_RX_DP<33>")
	)
	(segment
		(start 320.864738 -30.790134)
		(end 320.382138 -30.790134)
		(width 0.13462)
		(layer "F.Cu")
		(net "P5E_PEX2_STN2_RX_DP<33>")
	)
	(segment
		(start 317.705486 -30.62732)
		(end 317.410338 -30.922468)
		(width 0.13462)
		(layer "F.Cu")
		(net "P5E_PEX2_STN2_RX_DP<33>")
	)
	(segment
		(start 320.382138 -30.790134)
		(end 320.219324 -30.62732)
		(width 0.13462)
		(layer "F.Cu")
		(net "P5E_PEX2_STN2_RX_DP<33>")
	)
	(segment
		(start 289.37966 -271.41932)
		(end 289.37966 -273.407632)
		(width 0.1143)
		(layer "In7.Cu")
		(net "P5E_PEX2_STN2_RX_DP<33>")
	)
	(segment
		(start 318.756792 -30.631638)
		(end 318.871092 -30.745938)
		(width 0.1651)
		(layer "In7.Cu")
		(net "P5E_PEX2_STN2_RX_DP<33>")
	)
	(segment
		(start 289.33394 -270.917416)
		(end 289.33394 -271.345152)
		(width 0.1651)
		(layer "In7.Cu")
		(net "P5E_PEX2_STN2_RX_DP<33>")
	)
	(segment
		(start 320.55943 -31.499556)
		(end 320.827908 -31.91637)
		(width 0.1651)
		(layer "In7.Cu")
		(net "P5E_PEX2_STN2_RX_DP<33>")
	)
	(segment
		(start 319.366392 -30.745938)
		(end 319.480692 -30.631638)
		(width 0.1651)
		(layer "In7.Cu")
		(net "P5E_PEX2_STN2_RX_DP<33>")
	)
	(segment
		(start 289.83559 -273.670014)
		(end 289.94989 -273.784314)
		(width 0.1143)
		(layer "In7.Cu")
		(net "P5E_PEX2_STN2_RX_DP<33>")
	)
	(segment
		(start 289.673284 -267.004546)
		(end 289.33394 -270.917416)
		(width 0.1651)
		(layer "In7.Cu")
		(net "P5E_PEX2_STN2_RX_DP<33>")
	)
	(segment
		(start 321.50304 -34.076386)
		(end 320.783458 -38.129464)
		(width 0.1651)
		(layer "In7.Cu")
		(net "P5E_PEX2_STN2_RX_DP<33>")
	)
	(segment
		(start 320.783458 -38.129464)
		(end 320.807842 -39.658036)
		(width 0.1651)
		(layer "In7.Cu")
		(net "P5E_PEX2_STN2_RX_DP<33>")
	)
	(segment
		(start 319.480692 -30.631638)
		(end 320.136774 -30.631638)
		(width 0.1651)
		(layer "In7.Cu")
		(net "P5E_PEX2_STN2_RX_DP<33>")
	)
	(segment
		(start 321.511168 -33.05302)
		(end 321.50304 -34.076386)
		(width 0.1651)
		(layer "In7.Cu")
		(net "P5E_PEX2_STN2_RX_DP<33>")
	)
	(segment
		(start 289.37966 -273.407632)
		(end 289.642042 -273.670014)
		(width 0.1143)
		(layer "In7.Cu")
		(net "P5E_PEX2_STN2_RX_DP<33>")
	)
	(segment
		(start 310.61533 -143.970756)
		(end 309.239412 -154.656282)
		(width 0.1651)
		(layer "In7.Cu")
		(net "P5E_PEX2_STN2_RX_DP<33>")
	)
	(segment
		(start 321.94119 -61.042296)
		(end 310.932576 -116.528342)
		(width 0.1651)
		(layer "In7.Cu")
		(net "P5E_PEX2_STN2_RX_DP<33>")
	)
	(segment
		(start 317.77432 -30.631638)
		(end 318.756792 -30.631638)
		(width 0.1651)
		(layer "In7.Cu")
		(net "P5E_PEX2_STN2_RX_DP<33>")
	)
	(segment
		(start 309.239412 -154.656282)
		(end 289.673284 -267.004546)
		(width 0.1651)
		(layer "In7.Cu")
		(net "P5E_PEX2_STN2_RX_DP<33>")
	)
	(segment
		(start 289.33394 -271.345152)
		(end 289.33394 -271.3736)
		(width 0.1143)
		(layer "In7.Cu")
		(net "P5E_PEX2_STN2_RX_DP<33>")
	)
	(segment
		(start 320.59372 -31.341822)
		(end 320.55943 -31.499556)
		(width 0.1651)
		(layer "In7.Cu")
		(net "P5E_PEX2_STN2_RX_DP<33>")
	)
	(segment
		(start 289.642042 -273.670014)
		(end 289.83559 -273.670014)
		(width 0.1143)
		(layer "In7.Cu")
		(net "P5E_PEX2_STN2_RX_DP<33>")
	)
	(segment
		(start 320.136774 -30.631638)
		(end 320.59372 -31.341822)
		(width 0.1651)
		(layer "In7.Cu")
		(net "P5E_PEX2_STN2_RX_DP<33>")
	)
	(segment
		(start 320.807842 -39.658036)
		(end 322.123308 -49.394364)
		(width 0.1651)
		(layer "In7.Cu")
		(net "P5E_PEX2_STN2_RX_DP<33>")
	)
	(segment
		(start 289.33394 -271.3736)
		(end 289.37966 -271.41932)
		(width 0.1143)
		(layer "In7.Cu")
		(net "P5E_PEX2_STN2_RX_DP<33>")
	)
	(segment
		(start 322.123308 -49.394364)
		(end 321.94119 -61.042296)
		(width 0.1651)
		(layer "In7.Cu")
		(net "P5E_PEX2_STN2_RX_DP<33>")
	)
	(segment
		(start 317.410338 -30.922468)
		(end 317.649352 -30.683454)
		(width 0.1651)
		(layer "In7.Cu")
		(net "P5E_PEX2_STN2_RX_DP<33>")
	)
	(segment
		(start 318.871092 -30.745938)
		(end 319.366392 -30.745938)
		(width 0.1651)
		(layer "In7.Cu")
		(net "P5E_PEX2_STN2_RX_DP<33>")
	)
	(segment
		(start 317.649352 -30.683454)
		(end 317.77432 -30.631638)
		(width 0.1651)
		(layer "In7.Cu")
		(net "P5E_PEX2_STN2_RX_DP<33>")
	)
	(segment
		(start 320.985896 -31.95066)
		(end 321.253866 -32.366966)
		(width 0.1651)
		(layer "In7.Cu")
		(net "P5E_PEX2_STN2_RX_DP<33>")
	)
	(segment
		(start 321.253866 -32.366966)
		(end 321.511168 -33.05302)
		(width 0.1651)
		(layer "In7.Cu")
		(net "P5E_PEX2_STN2_RX_DP<33>")
	)
	(segment
		(start 310.932576 -116.528342)
		(end 310.61533 -143.970756)
		(width 0.1651)
		(layer "In7.Cu")
		(net "P5E_PEX2_STN2_RX_DP<33>")
	)
	(segment
		(start 289.94989 -273.784314)
		(end 289.94989 -274.049744)
		(width 0.1143)
		(layer "In7.Cu")
		(net "P5E_PEX2_STN2_RX_DP<33>")
	)
	(segment
		(start 320.827908 -31.91637)
		(end 320.985896 -31.95066)
		(width 0.1651)
		(layer "In7.Cu")
		(net "P5E_PEX2_STN2_RX_DP<33>")
	)
	(segment
		(start 422.234868 -130.4671)
		(end 422.057068 -130.6449)
		(width 0.13462)
		(layer "F.Cu")
		(net "P5E_PEX3_STN0_TX_C_DP<4>")
	)
	(segment
		(start 427.725332 -130.4671)
		(end 422.234868 -130.4671)
		(width 0.13462)
		(layer "F.Cu")
		(net "P5E_PEX3_STN0_TX_C_DP<4>")
	)
	(segment
		(start 428.052738 -130.794506)
		(end 427.725332 -130.4671)
		(width 0.13462)
		(layer "F.Cu")
		(net "P5E_PEX3_STN0_TX_C_DP<4>")
	)
	(segment
		(start 422.057068 -130.6449)
		(end 421.557704 -130.6449)
		(width 0.13462)
		(layer "F.Cu")
		(net "P5E_PEX3_STN0_TX_C_DP<4>")
	)
	(segment
		(start 399.463768 -345.169998)
		(end 399.16862 -345.465146)
		(width 0.13462)
		(layer "F.Cu")
		(net "P5E_PEX3_STN5_TX_C_DP<85>")
	)
	(segment
		(start 399.14322 -344.219022)
		(end 399.463768 -344.53957)
		(width 0.13462)
		(layer "F.Cu")
		(net "P5E_PEX3_STN5_TX_C_DP<85>")
	)
	(segment
		(start 399.463768 -344.53957)
		(end 399.463768 -345.169998)
		(width 0.13462)
		(layer "F.Cu")
		(net "P5E_PEX3_STN5_TX_C_DP<85>")
	)
	(segment
		(start 397.90497 -347.764354)
		(end 397.90497 -358.868218)
		(width 0.1651)
		(layer "In7.Cu")
		(net "P5E_PEX3_STN5_TX_C_DP<85>")
	)
	(segment
		(start 398.887696 -363.802422)
		(end 398.993614 -363.870494)
		(width 0.1651)
		(layer "In7.Cu")
		(net "P5E_PEX3_STN5_TX_C_DP<85>")
	)
	(segment
		(start 398.707102 -389.53567)
		(end 388.47522 -393.79652)
		(width 0.1651)
		(layer "In7.Cu")
		(net "P5E_PEX3_STN5_TX_C_DP<85>")
	)
	(segment
		(start 386.616956 -405.899112)
		(end 386.489956 -405.772112)
		(width 0.1651)
		(layer "In7.Cu")
		(net "P5E_PEX3_STN5_TX_C_DP<85>")
	)
	(segment
		(start 400.10334 -387.05282)
		(end 398.707102 -389.53567)
		(width 0.1651)
		(layer "In7.Cu")
		(net "P5E_PEX3_STN5_TX_C_DP<85>")
	)
	(segment
		(start 398.850358 -363.21238)
		(end 398.782286 -363.318298)
		(width 0.1651)
		(layer "In7.Cu")
		(net "P5E_PEX3_STN5_TX_C_DP<85>")
	)
	(segment
		(start 387.047232 -405.899112)
		(end 386.616956 -405.899112)
		(width 0.1651)
		(layer "In7.Cu")
		(net "P5E_PEX3_STN5_TX_C_DP<85>")
	)
	(segment
		(start 387.333998 -394.97254)
		(end 387.333998 -405.612346)
		(width 0.1651)
		(layer "In7.Cu")
		(net "P5E_PEX3_STN5_TX_C_DP<85>")
	)
	(segment
		(start 399.45945 -345.755976)
		(end 399.45945 -346.209874)
		(width 0.1651)
		(layer "In7.Cu")
		(net "P5E_PEX3_STN5_TX_C_DP<85>")
	)
	(segment
		(start 399.45945 -346.209874)
		(end 397.90497 -347.764354)
		(width 0.1651)
		(layer "In7.Cu")
		(net "P5E_PEX3_STN5_TX_C_DP<85>")
	)
	(segment
		(start 388.47522 -393.79652)
		(end 387.333998 -394.97254)
		(width 0.1651)
		(layer "In7.Cu")
		(net "P5E_PEX3_STN5_TX_C_DP<85>")
	)
	(segment
		(start 400.23288 -369.56492)
		(end 400.10334 -387.05282)
		(width 0.1651)
		(layer "In7.Cu")
		(net "P5E_PEX3_STN5_TX_C_DP<85>")
	)
	(segment
		(start 387.333998 -405.612346)
		(end 387.047232 -405.899112)
		(width 0.1651)
		(layer "In7.Cu")
		(net "P5E_PEX3_STN5_TX_C_DP<85>")
	)
	(segment
		(start 399.16862 -345.465146)
		(end 399.45945 -345.755976)
		(width 0.1651)
		(layer "In7.Cu")
		(net "P5E_PEX3_STN5_TX_C_DP<85>")
	)
	(segment
		(start 398.993614 -363.870494)
		(end 400.23288 -369.56492)
		(width 0.1651)
		(layer "In7.Cu")
		(net "P5E_PEX3_STN5_TX_C_DP<85>")
	)
	(segment
		(start 398.782286 -363.318298)
		(end 398.887696 -363.802422)
		(width 0.1651)
		(layer "In7.Cu")
		(net "P5E_PEX3_STN5_TX_C_DP<85>")
	)
	(segment
		(start 397.90497 -358.868218)
		(end 398.850358 -363.21238)
		(width 0.1651)
		(layer "In7.Cu")
		(net "P5E_PEX3_STN5_TX_C_DP<85>")
	)
	(segment
		(start 386.489956 -405.772112)
		(end 386.489956 -405.390096)
		(width 0.1651)
		(layer "In7.Cu")
		(net "P5E_PEX3_STN5_TX_C_DP<85>")
	)
	(segment
		(start 68.65747 -98.840036)
		(end 65.777872 -98.840036)
		(width 0.13208)
		(layer "F.Cu")
		(net "NIC1_RBT_ARB_IN")
	)
	(segment
		(start 65.777872 -98.840036)
		(end 65.460372 -98.522536)
		(width 0.13208)
		(layer "F.Cu")
		(net "NIC1_RBT_ARB_IN")
	)
	(segment
		(start 62.519814 -98.522536)
		(end 61.697362 -98.522536)
		(width 0.13208)
		(layer "F.Cu")
		(net "NIC1_RBT_ARB_IN")
	)
	(segment
		(start 65.460372 -98.522536)
		(end 62.519814 -98.522536)
		(width 0.13208)
		(layer "F.Cu")
		(net "NIC1_RBT_ARB_IN")
	)
	(segment
		(start 61.485526 -98.734372)
		(end 59.395106 -98.734372)
		(width 0.13208)
		(layer "F.Cu")
		(net "NIC1_RBT_ARB_IN")
	)
	(segment
		(start 61.697362 -98.522536)
		(end 61.485526 -98.734372)
		(width 0.13208)
		(layer "F.Cu")
		(net "NIC1_RBT_ARB_IN")
	)
	(via
		(at 62.519814 -98.522536)
		(size 0.762)
		(drill 0.381)
		(layers "F.Cu" "B.Cu")
		(net "NIC1_RBT_ARB_IN")
	)
	(segment
		(start 39.547292 -135.815324)
		(end 39.859712 -136.127744)
		(width 0.13462)
		(layer "F.Cu")
		(net "P5E_PEX0_STN1_TX_C_DN<31>")
	)
	(segment
		(start 45.391324 -136.127744)
		(end 45.554138 -135.96493)
		(width 0.13462)
		(layer "F.Cu")
		(net "P5E_PEX0_STN1_TX_C_DN<31>")
	)
	(segment
		(start 45.554138 -135.96493)
		(end 46.042326 -135.96493)
		(width 0.13462)
		(layer "F.Cu")
		(net "P5E_PEX0_STN1_TX_C_DN<31>")
	)
	(segment
		(start 39.859712 -136.127744)
		(end 45.391324 -136.127744)
		(width 0.13462)
		(layer "F.Cu")
		(net "P5E_PEX0_STN1_TX_C_DN<31>")
	)
	(segment
		(start 169.901616 -103.20782)
		(end 170.196764 -102.912672)
		(width 0.13462)
		(layer "F.Cu")
		(net "P5E_PEX1_STN1_RX_DP<18>")
	)
	(segment
		(start 167.393112 -103.20782)
		(end 169.901616 -103.20782)
		(width 0.13462)
		(layer "F.Cu")
		(net "P5E_PEX1_STN1_RX_DP<18>")
	)
	(segment
		(start 166.742364 -103.045006)
		(end 167.230298 -103.045006)
		(width 0.13462)
		(layer "F.Cu")
		(net "P5E_PEX1_STN1_RX_DP<18>")
	)
	(segment
		(start 167.230298 -103.045006)
		(end 167.393112 -103.20782)
		(width 0.13462)
		(layer "F.Cu")
		(net "P5E_PEX1_STN1_RX_DP<18>")
	)
	(segment
		(start 146.201892 -150.34133)
		(end 146.761708 -158.791148)
		(width 0.1651)
		(layer "In5.Cu")
		(net "P5E_PEX1_STN1_RX_DP<18>")
	)
	(segment
		(start 177.033936 -269.772892)
		(end 177.033936 -271.526)
		(width 0.1651)
		(layer "In5.Cu")
		(net "P5E_PEX1_STN1_RX_DP<18>")
	)
	(segment
		(start 177.649632 -273.784314)
		(end 177.649632 -274.049744)
		(width 0.1143)
		(layer "In5.Cu")
		(net "P5E_PEX1_STN1_RX_DP<18>")
	)
	(segment
		(start 177.079656 -271.600168)
		(end 177.079656 -273.45513)
		(width 0.1143)
		(layer "In5.Cu")
		(net "P5E_PEX1_STN1_RX_DP<18>")
	)
	(segment
		(start 169.905934 -103.203502)
		(end 168.030906 -103.203502)
		(width 0.1651)
		(layer "In5.Cu")
		(net "P5E_PEX1_STN1_RX_DP<18>")
	)
	(segment
		(start 147.888198 -165.304216)
		(end 177.033936 -269.772892)
		(width 0.1651)
		(layer "In5.Cu")
		(net "P5E_PEX1_STN1_RX_DP<18>")
	)
	(segment
		(start 146.761708 -158.791148)
		(end 147.888198 -165.304216)
		(width 0.1651)
		(layer "In5.Cu")
		(net "P5E_PEX1_STN1_RX_DP<18>")
	)
	(segment
		(start 177.535332 -273.670014)
		(end 177.649632 -273.784314)
		(width 0.1143)
		(layer "In5.Cu")
		(net "P5E_PEX1_STN1_RX_DP<18>")
	)
	(segment
		(start 170.196764 -102.912672)
		(end 169.905934 -103.203502)
		(width 0.1651)
		(layer "In5.Cu")
		(net "P5E_PEX1_STN1_RX_DP<18>")
	)
	(segment
		(start 148.943568 -120.379236)
		(end 147.805902 -126.602744)
		(width 0.1651)
		(layer "In5.Cu")
		(net "P5E_PEX1_STN1_RX_DP<18>")
	)
	(segment
		(start 177.033936 -271.554448)
		(end 177.079656 -271.600168)
		(width 0.1143)
		(layer "In5.Cu")
		(net "P5E_PEX1_STN1_RX_DP<18>")
	)
	(segment
		(start 160.831276 -106.897932)
		(end 149.937978 -118.307358)
		(width 0.1651)
		(layer "In5.Cu")
		(net "P5E_PEX1_STN1_RX_DP<18>")
	)
	(segment
		(start 177.079656 -273.45513)
		(end 177.29454 -273.670014)
		(width 0.1143)
		(layer "In5.Cu")
		(net "P5E_PEX1_STN1_RX_DP<18>")
	)
	(segment
		(start 177.29454 -273.670014)
		(end 177.535332 -273.670014)
		(width 0.1143)
		(layer "In5.Cu")
		(net "P5E_PEX1_STN1_RX_DP<18>")
	)
	(segment
		(start 149.937978 -118.307358)
		(end 148.943568 -120.379236)
		(width 0.1651)
		(layer "In5.Cu")
		(net "P5E_PEX1_STN1_RX_DP<18>")
	)
	(segment
		(start 147.805902 -126.602744)
		(end 146.201892 -150.34133)
		(width 0.1651)
		(layer "In5.Cu")
		(net "P5E_PEX1_STN1_RX_DP<18>")
	)
	(segment
		(start 168.030906 -103.203502)
		(end 160.831276 -106.897932)
		(width 0.1651)
		(layer "In5.Cu")
		(net "P5E_PEX1_STN1_RX_DP<18>")
	)
	(segment
		(start 177.033936 -271.526)
		(end 177.033936 -271.554448)
		(width 0.1143)
		(layer "In5.Cu")
		(net "P5E_PEX1_STN1_RX_DP<18>")
	)
	(segment
		(start 249.396504 -32.4104)
		(end 248.14403 -32.4104)
		(width 0.13462)
		(layer "F.Cu")
		(net "P5E_PEX2_STN2_TX_C_DP<46>")
	)
	(segment
		(start 249.725688 -32.739584)
		(end 249.396504 -32.4104)
		(width 0.13462)
		(layer "F.Cu")
		(net "P5E_PEX2_STN2_TX_C_DP<46>")
	)
	(segment
		(start 247.964452 -32.589978)
		(end 247.464834 -32.589978)
		(width 0.13462)
		(layer "F.Cu")
		(net "P5E_PEX2_STN2_TX_C_DP<46>")
	)
	(segment
		(start 248.14403 -32.4104)
		(end 247.964452 -32.589978)
		(width 0.13462)
		(layer "F.Cu")
		(net "P5E_PEX2_STN2_TX_C_DP<46>")
	)
	(segment
		(start 430.694846 -155.196794)
		(end 430.37506 -155.51658)
		(width 0.13462)
		(layer "F.Cu")
		(net "P5E_PEX3_STN0_TX_C_DN<15>")
	)
	(segment
		(start 430.37506 -155.51658)
		(end 422.225978 -155.51658)
		(width 0.13462)
		(layer "F.Cu")
		(net "P5E_PEX3_STN0_TX_C_DN<15>")
	)
	(segment
		(start 422.225978 -155.51658)
		(end 422.064434 -155.355036)
		(width 0.13462)
		(layer "F.Cu")
		(net "P5E_PEX3_STN0_TX_C_DN<15>")
	)
	(segment
		(start 422.064434 -155.355036)
		(end 421.557704 -155.355036)
		(width 0.13462)
		(layer "F.Cu")
		(net "P5E_PEX3_STN0_TX_C_DN<15>")
	)
	(segment
		(start 419.965886 -319.969896)
		(end 419.965886 -319.941448)
		(width 0.1143)
		(layer "In15.Cu")
		(net "P5E_PEX3_STN5_RX_DN<94>")
	)
	(segment
		(start 404.090632 -358.834436)
		(end 404.575264 -357.683816)
		(width 0.1651)
		(layer "In15.Cu")
		(net "P5E_PEX3_STN5_RX_DN<94>")
	)
	(segment
		(start 408.061922 -340.188804)
		(end 419.033706 -324.925182)
		(width 0.1651)
		(layer "In15.Cu")
		(net "P5E_PEX3_STN5_RX_DN<94>")
	)
	(segment
		(start 389.815832 -369.640104)
		(end 390.266682 -368.577622)
		(width 0.1651)
		(layer "In15.Cu")
		(net "P5E_PEX3_STN5_RX_DN<94>")
	)
	(segment
		(start 419.033706 -324.925182)
		(end 419.965886 -323.25056)
		(width 0.1651)
		(layer "In15.Cu")
		(net "P5E_PEX3_STN5_RX_DN<94>")
	)
	(segment
		(start 419.920166 -316.523624)
		(end 420.023798 -316.419992)
		(width 0.1143)
		(layer "In15.Cu")
		(net "P5E_PEX3_STN5_RX_DN<94>")
	)
	(segment
		(start 390.266682 -368.577622)
		(end 404.090632 -358.834436)
		(width 0.1651)
		(layer "In15.Cu")
		(net "P5E_PEX3_STN5_RX_DN<94>")
	)
	(segment
		(start 420.299896 -316.534292)
		(end 420.299896 -316.799722)
		(width 0.1143)
		(layer "In15.Cu")
		(net "P5E_PEX3_STN5_RX_DN<94>")
	)
	(segment
		(start 389.363966 -371.281198)
		(end 389.815832 -370.829332)
		(width 0.1651)
		(layer "In15.Cu")
		(net "P5E_PEX3_STN5_RX_DN<94>")
	)
	(segment
		(start 419.965886 -319.941448)
		(end 419.920166 -319.895728)
		(width 0.1143)
		(layer "In15.Cu")
		(net "P5E_PEX3_STN5_RX_DN<94>")
	)
	(segment
		(start 407.195528 -341.704676)
		(end 408.061922 -340.188804)
		(width 0.1651)
		(layer "In15.Cu")
		(net "P5E_PEX3_STN5_RX_DN<94>")
	)
	(segment
		(start 388.68985 -371.408198)
		(end 388.81685 -371.281198)
		(width 0.1651)
		(layer "In15.Cu")
		(net "P5E_PEX3_STN5_RX_DN<94>")
	)
	(segment
		(start 420.185596 -316.419992)
		(end 420.299896 -316.534292)
		(width 0.1143)
		(layer "In15.Cu")
		(net "P5E_PEX3_STN5_RX_DN<94>")
	)
	(segment
		(start 389.815832 -370.829332)
		(end 389.815832 -369.640104)
		(width 0.1651)
		(layer "In15.Cu")
		(net "P5E_PEX3_STN5_RX_DN<94>")
	)
	(segment
		(start 388.81685 -371.281198)
		(end 389.363966 -371.281198)
		(width 0.1651)
		(layer "In15.Cu")
		(net "P5E_PEX3_STN5_RX_DN<94>")
	)
	(segment
		(start 419.920166 -319.895728)
		(end 419.920166 -316.523624)
		(width 0.1143)
		(layer "In15.Cu")
		(net "P5E_PEX3_STN5_RX_DN<94>")
	)
	(segment
		(start 404.575264 -357.683816)
		(end 407.195528 -341.704676)
		(width 0.1651)
		(layer "In15.Cu")
		(net "P5E_PEX3_STN5_RX_DN<94>")
	)
	(segment
		(start 420.023798 -316.419992)
		(end 420.185596 -316.419992)
		(width 0.1143)
		(layer "In15.Cu")
		(net "P5E_PEX3_STN5_RX_DN<94>")
	)
	(segment
		(start 388.68985 -371.790214)
		(end 388.68985 -371.408198)
		(width 0.1651)
		(layer "In15.Cu")
		(net "P5E_PEX3_STN5_RX_DN<94>")
	)
	(segment
		(start 419.965886 -323.25056)
		(end 419.965886 -319.969896)
		(width 0.1651)
		(layer "In15.Cu")
		(net "P5E_PEX3_STN5_RX_DN<94>")
	)
	(segment
		(start 59.395106 -97.718372)
		(end 64.009016 -97.718372)
		(width 0.13208)
		(layer "F.Cu")
		(net "RST_NIC1_PERST3_R_N")
	)
	(segment
		(start 66.005456 -97.64014)
		(end 68.65747 -97.64014)
		(width 0.13208)
		(layer "F.Cu")
		(net "RST_NIC1_PERST3_R_N")
	)
	(segment
		(start 65.927224 -97.718372)
		(end 66.005456 -97.64014)
		(width 0.13208)
		(layer "F.Cu")
		(net "RST_NIC1_PERST3_R_N")
	)
	(segment
		(start 64.009016 -97.718372)
		(end 65.927224 -97.718372)
		(width 0.13208)
		(layer "F.Cu")
		(net "RST_NIC1_PERST3_R_N")
	)
	(via
		(at 64.009016 -97.718372)
		(size 0.762)
		(drill 0.381)
		(layers "F.Cu" "B.Cu")
		(net "RST_NIC1_PERST3_R_N")
	)
	(segment
		(start 287.629092 -116.5352)
		(end 287.629092 -117.5512)
		(width 0.13208)
		(layer "F.Cu")
		(net "PRSNTB1_NIC4_N")
	)
	(segment
		(start 285.624778 -117.5512)
		(end 286.452818 -117.5512)
		(width 0.13208)
		(layer "F.Cu")
		(net "PRSNTB1_NIC4_N")
	)
	(segment
		(start 286.452818 -117.5512)
		(end 287.629092 -117.5512)
		(width 0.13208)
		(layer "F.Cu")
		(net "PRSNTB1_NIC4_N")
	)
	(segment
		(start 285.02102 -118.154958)
		(end 285.624778 -117.5512)
		(width 0.13208)
		(layer "F.Cu")
		(net "PRSNTB1_NIC4_N")
	)
	(segment
		(start 282.842462 -118.154958)
		(end 285.02102 -118.154958)
		(width 0.13208)
		(layer "F.Cu")
		(net "PRSNTB1_NIC4_N")
	)
	(via
		(at 286.452818 -117.5512)
		(size 0.762)
		(drill 0.381)
		(layers "F.Cu" "B.Cu")
		(net "PRSNTB1_NIC4_N")
	)
	(segment
		(start 50.64252 -122.95505)
		(end 51.130454 -122.95505)
		(width 0.13462)
		(layer "F.Cu")
		(net "P5E_PEX0_STN1_RX_DP<26>")
	)
	(segment
		(start 53.801772 -123.117864)
		(end 54.09692 -122.822716)
		(width 0.13462)
		(layer "F.Cu")
		(net "P5E_PEX0_STN1_RX_DP<26>")
	)
	(segment
		(start 51.293268 -123.117864)
		(end 53.801772 -123.117864)
		(width 0.13462)
		(layer "F.Cu")
		(net "P5E_PEX0_STN1_RX_DP<26>")
	)
	(segment
		(start 51.130454 -122.95505)
		(end 51.293268 -123.117864)
		(width 0.13462)
		(layer "F.Cu")
		(net "P5E_PEX0_STN1_RX_DP<26>")
	)
	(segment
		(start 46.693582 -126.46787)
		(end 44.519342 -129.219198)
		(width 0.1651)
		(layer "In5.Cu")
		(net "P5E_PEX0_STN1_RX_DP<26>")
	)
	(segment
		(start 68.534026 -267.93063)
		(end 68.534026 -271.773904)
		(width 0.1651)
		(layer "In5.Cu")
		(net "P5E_PEX0_STN1_RX_DP<26>")
	)
	(segment
		(start 51.819302 -123.113546)
		(end 47.399702 -125.839474)
		(width 0.1651)
		(layer "In5.Cu")
		(net "P5E_PEX0_STN1_RX_DP<26>")
	)
	(segment
		(start 68.579746 -271.848072)
		(end 68.579746 -273.45513)
		(width 0.1143)
		(layer "In5.Cu")
		(net "P5E_PEX0_STN1_RX_DP<26>")
	)
	(segment
		(start 68.79463 -273.670014)
		(end 69.035422 -273.670014)
		(width 0.1143)
		(layer "In5.Cu")
		(net "P5E_PEX0_STN1_RX_DP<26>")
	)
	(segment
		(start 68.534026 -271.802352)
		(end 68.579746 -271.848072)
		(width 0.1143)
		(layer "In5.Cu")
		(net "P5E_PEX0_STN1_RX_DP<26>")
	)
	(segment
		(start 38.826186 -147.406106)
		(end 39.475664 -157.418786)
		(width 0.1651)
		(layer "In5.Cu")
		(net "P5E_PEX0_STN1_RX_DP<26>")
	)
	(segment
		(start 68.579746 -273.45513)
		(end 68.79463 -273.670014)
		(width 0.1143)
		(layer "In5.Cu")
		(net "P5E_PEX0_STN1_RX_DP<26>")
	)
	(segment
		(start 47.399702 -125.839474)
		(end 46.693582 -126.46787)
		(width 0.1651)
		(layer "In5.Cu")
		(net "P5E_PEX0_STN1_RX_DP<26>")
	)
	(segment
		(start 39.475664 -157.418786)
		(end 40.291512 -161.945066)
		(width 0.1651)
		(layer "In5.Cu")
		(net "P5E_PEX0_STN1_RX_DP<26>")
	)
	(segment
		(start 54.09692 -122.822716)
		(end 53.80609 -123.113546)
		(width 0.1651)
		(layer "In5.Cu")
		(net "P5E_PEX0_STN1_RX_DP<26>")
	)
	(segment
		(start 40.291512 -161.945066)
		(end 68.534026 -267.93063)
		(width 0.1651)
		(layer "In5.Cu")
		(net "P5E_PEX0_STN1_RX_DP<26>")
	)
	(segment
		(start 44.349162 -129.59461)
		(end 42.678858 -139.268962)
		(width 0.1651)
		(layer "In5.Cu")
		(net "P5E_PEX0_STN1_RX_DP<26>")
	)
	(segment
		(start 53.80609 -123.113546)
		(end 51.819302 -123.113546)
		(width 0.1651)
		(layer "In5.Cu")
		(net "P5E_PEX0_STN1_RX_DP<26>")
	)
	(segment
		(start 68.534026 -271.773904)
		(end 68.534026 -271.802352)
		(width 0.1143)
		(layer "In5.Cu")
		(net "P5E_PEX0_STN1_RX_DP<26>")
	)
	(segment
		(start 42.678858 -139.268962)
		(end 41.65854 -142.790672)
		(width 0.1651)
		(layer "In5.Cu")
		(net "P5E_PEX0_STN1_RX_DP<26>")
	)
	(segment
		(start 69.035422 -273.670014)
		(end 69.149722 -273.784314)
		(width 0.1143)
		(layer "In5.Cu")
		(net "P5E_PEX0_STN1_RX_DP<26>")
	)
	(segment
		(start 44.519342 -129.219198)
		(end 44.349162 -129.59461)
		(width 0.1651)
		(layer "In5.Cu")
		(net "P5E_PEX0_STN1_RX_DP<26>")
	)
	(segment
		(start 69.149722 -273.784314)
		(end 69.149722 -274.049744)
		(width 0.1143)
		(layer "In5.Cu")
		(net "P5E_PEX0_STN1_RX_DP<26>")
	)
	(segment
		(start 41.65854 -142.790672)
		(end 39.155116 -146.151092)
		(width 0.1651)
		(layer "In5.Cu")
		(net "P5E_PEX0_STN1_RX_DP<26>")
	)
	(segment
		(start 39.155116 -146.151092)
		(end 38.826186 -147.406106)
		(width 0.1651)
		(layer "In5.Cu")
		(net "P5E_PEX0_STN1_RX_DP<26>")
	)
	(segment
		(start 161.491422 -105.007918)
		(end 161.654236 -104.845104)
		(width 0.13462)
		(layer "F.Cu")
		(net "P5E_PEX1_STN1_TX_C_DN<19>")
	)
	(segment
		(start 153.317448 -105.007918)
		(end 161.491422 -105.007918)
		(width 0.13462)
		(layer "F.Cu")
		(net "P5E_PEX1_STN1_TX_C_DN<19>")
	)
	(segment
		(start 161.654236 -104.845104)
		(end 162.14217 -104.845104)
		(width 0.13462)
		(layer "F.Cu")
		(net "P5E_PEX1_STN1_TX_C_DN<19>")
	)
	(segment
		(start 153.005028 -104.695498)
		(end 153.317448 -105.007918)
		(width 0.13462)
		(layer "F.Cu")
		(net "P5E_PEX1_STN1_TX_C_DN<19>")
	)
	(segment
		(start 319.56375 -32.4231)
		(end 319.264538 -32.722312)
		(width 0.13462)
		(layer "F.Cu")
		(net "P5E_PEX2_STN2_RX_DP<34>")
	)
	(segment
		(start 320.218562 -32.4231)
		(end 319.56375 -32.4231)
		(width 0.13462)
		(layer "F.Cu")
		(net "P5E_PEX2_STN2_RX_DP<34>")
	)
	(segment
		(start 320.864738 -32.589978)
		(end 320.38544 -32.589978)
		(width 0.13462)
		(layer "F.Cu")
		(net "P5E_PEX2_STN2_RX_DP<34>")
	)
	(segment
		(start 320.38544 -32.589978)
		(end 320.218562 -32.4231)
		(width 0.13462)
		(layer "F.Cu")
		(net "P5E_PEX2_STN2_RX_DP<34>")
	)
	(segment
		(start 288.429446 -271.467072)
		(end 288.429446 -275.354796)
		(width 0.1143)
		(layer "In7.Cu")
		(net "P5E_PEX2_STN2_RX_DP<34>")
	)
	(segment
		(start 288.383726 -270.641064)
		(end 288.383726 -271.392904)
		(width 0.1651)
		(layer "In7.Cu")
		(net "P5E_PEX2_STN2_RX_DP<34>")
	)
	(segment
		(start 319.800478 -37.779198)
		(end 319.830958 -39.714678)
		(width 0.1651)
		(layer "In7.Cu")
		(net "P5E_PEX2_STN2_RX_DP<34>")
	)
	(segment
		(start 320.232024 -33.660334)
		(end 320.224404 -34.155888)
		(width 0.1651)
		(layer "In7.Cu")
		(net "P5E_PEX2_STN2_RX_DP<34>")
	)
	(segment
		(start 288.712656 -266.82319)
		(end 288.383726 -270.641064)
		(width 0.1651)
		(layer "In7.Cu")
		(net "P5E_PEX2_STN2_RX_DP<34>")
	)
	(segment
		(start 320.10985 -36.119562)
		(end 320.005964 -36.190682)
		(width 0.1651)
		(layer "In7.Cu")
		(net "P5E_PEX2_STN2_RX_DP<34>")
	)
	(segment
		(start 319.915286 -36.677854)
		(end 319.986406 -36.781486)
		(width 0.1651)
		(layer "In7.Cu")
		(net "P5E_PEX2_STN2_RX_DP<34>")
	)
	(segment
		(start 308.272688 -154.509978)
		(end 288.712656 -266.82319)
		(width 0.1651)
		(layer "In7.Cu")
		(net "P5E_PEX2_STN2_RX_DP<34>")
	)
	(segment
		(start 319.830704 -39.714678)
		(end 319.831212 -39.731442)
		(width 0.1651)
		(layer "In7.Cu")
		(net "P5E_PEX2_STN2_RX_DP<34>")
	)
	(segment
		(start 320.96329 -61.060584)
		(end 309.97652 -116.439188)
		(width 0.1651)
		(layer "In7.Cu")
		(net "P5E_PEX2_STN2_RX_DP<34>")
	)
	(segment
		(start 320.005964 -36.190682)
		(end 319.915286 -36.677854)
		(width 0.1651)
		(layer "In7.Cu")
		(net "P5E_PEX2_STN2_RX_DP<34>")
	)
	(segment
		(start 288.644838 -275.570188)
		(end 288.88563 -275.570188)
		(width 0.1143)
		(layer "In7.Cu")
		(net "P5E_PEX2_STN2_RX_DP<34>")
	)
	(segment
		(start 320.326512 -34.95675)
		(end 320.10985 -36.119562)
		(width 0.1651)
		(layer "In7.Cu")
		(net "P5E_PEX2_STN2_RX_DP<34>")
	)
	(segment
		(start 288.383726 -271.392904)
		(end 288.383726 -271.421352)
		(width 0.1143)
		(layer "In7.Cu")
		(net "P5E_PEX2_STN2_RX_DP<34>")
	)
	(segment
		(start 320.224404 -34.155888)
		(end 320.336926 -34.271966)
		(width 0.1651)
		(layer "In7.Cu")
		(net "P5E_PEX2_STN2_RX_DP<34>")
	)
	(segment
		(start 288.383726 -271.421352)
		(end 288.429446 -271.467072)
		(width 0.1143)
		(layer "In7.Cu")
		(net "P5E_PEX2_STN2_RX_DP<34>")
	)
	(segment
		(start 320.358262 -32.905954)
		(end 320.348356 -33.547812)
		(width 0.1651)
		(layer "In7.Cu")
		(net "P5E_PEX2_STN2_RX_DP<34>")
	)
	(segment
		(start 319.49009 -32.49676)
		(end 319.64757 -32.431482)
		(width 0.1651)
		(layer "In7.Cu")
		(net "P5E_PEX2_STN2_RX_DP<34>")
	)
	(segment
		(start 319.64757 -32.431482)
		(end 319.884044 -32.431482)
		(width 0.1651)
		(layer "In7.Cu")
		(net "P5E_PEX2_STN2_RX_DP<34>")
	)
	(segment
		(start 288.99993 -275.684488)
		(end 288.99993 -275.949918)
		(width 0.1143)
		(layer "In7.Cu")
		(net "P5E_PEX2_STN2_RX_DP<34>")
	)
	(segment
		(start 309.97652 -116.439188)
		(end 309.660036 -143.730472)
		(width 0.1651)
		(layer "In7.Cu")
		(net "P5E_PEX2_STN2_RX_DP<34>")
	)
	(segment
		(start 319.264538 -32.722312)
		(end 319.49009 -32.49676)
		(width 0.1651)
		(layer "In7.Cu")
		(net "P5E_PEX2_STN2_RX_DP<34>")
	)
	(segment
		(start 288.429446 -275.354796)
		(end 288.644838 -275.570188)
		(width 0.1143)
		(layer "In7.Cu")
		(net "P5E_PEX2_STN2_RX_DP<34>")
	)
	(segment
		(start 321.144646 -49.45253)
		(end 320.96329 -61.060584)
		(width 0.1651)
		(layer "In7.Cu")
		(net "P5E_PEX2_STN2_RX_DP<34>")
	)
	(segment
		(start 320.336926 -34.271966)
		(end 320.326512 -34.95675)
		(width 0.1651)
		(layer "In7.Cu")
		(net "P5E_PEX2_STN2_RX_DP<34>")
	)
	(segment
		(start 319.884044 -32.431482)
		(end 320.358262 -32.905954)
		(width 0.1651)
		(layer "In7.Cu")
		(net "P5E_PEX2_STN2_RX_DP<34>")
	)
	(segment
		(start 309.660036 -143.730472)
		(end 308.272688 -154.509978)
		(width 0.1651)
		(layer "In7.Cu")
		(net "P5E_PEX2_STN2_RX_DP<34>")
	)
	(segment
		(start 320.348356 -33.547812)
		(end 320.232024 -33.660334)
		(width 0.1651)
		(layer "In7.Cu")
		(net "P5E_PEX2_STN2_RX_DP<34>")
	)
	(segment
		(start 288.88563 -275.570188)
		(end 288.99993 -275.684488)
		(width 0.1143)
		(layer "In7.Cu")
		(net "P5E_PEX2_STN2_RX_DP<34>")
	)
	(segment
		(start 319.831212 -39.731442)
		(end 321.144646 -49.45253)
		(width 0.1651)
		(layer "In7.Cu")
		(net "P5E_PEX2_STN2_RX_DP<34>")
	)
	(segment
		(start 319.986406 -36.781486)
		(end 319.800478 -37.779198)
		(width 0.1651)
		(layer "In7.Cu")
		(net "P5E_PEX2_STN2_RX_DP<34>")
	)
	(segment
		(start 319.830958 -39.714678)
		(end 319.830704 -39.714678)
		(width 0.1651)
		(layer "In7.Cu")
		(net "P5E_PEX2_STN2_RX_DP<34>")
	)
	(segment
		(start 415.35731 -146.223736)
		(end 415.645854 -146.51228)
		(width 0.13462)
		(layer "F.Cu")
		(net "P5E_PEX3_STN0_RX_DN<10>")
	)
	(segment
		(start 416.476688 -146.355054)
		(end 416.95751 -146.355054)
		(width 0.13462)
		(layer "F.Cu")
		(net "P5E_PEX3_STN0_RX_DN<10>")
	)
	(segment
		(start 415.645854 -146.51228)
		(end 416.319462 -146.51228)
		(width 0.13462)
		(layer "F.Cu")
		(net "P5E_PEX3_STN0_RX_DN<10>")
	)
	(segment
		(start 416.319462 -146.51228)
		(end 416.476688 -146.355054)
		(width 0.13462)
		(layer "F.Cu")
		(net "P5E_PEX3_STN0_RX_DN<10>")
	)
	(segment
		(start 428.127668 -268.182852)
		(end 427.56582 -271.041114)
		(width 0.1651)
		(layer "In5.Cu")
		(net "P5E_PEX3_STN0_RX_DN<10>")
	)
	(segment
		(start 427.623478 -275.379688)
		(end 427.785276 -275.379688)
		(width 0.1143)
		(layer "In5.Cu")
		(net "P5E_PEX3_STN0_RX_DN<10>")
	)
	(segment
		(start 428.092108 -260.494272)
		(end 428.127668 -268.182852)
		(width 0.1651)
		(layer "In5.Cu")
		(net "P5E_PEX3_STN0_RX_DN<10>")
	)
	(segment
		(start 415.64814 -146.514566)
		(end 416.245802 -146.514566)
		(width 0.1651)
		(layer "In5.Cu")
		(net "P5E_PEX3_STN0_RX_DN<10>")
	)
	(segment
		(start 423.463974 -156.471112)
		(end 424.578272 -161.011616)
		(width 0.1651)
		(layer "In5.Cu")
		(net "P5E_PEX3_STN0_RX_DN<10>")
	)
	(segment
		(start 427.5201 -271.645126)
		(end 427.5201 -275.27631)
		(width 0.1143)
		(layer "In5.Cu")
		(net "P5E_PEX3_STN0_RX_DN<10>")
	)
	(segment
		(start 427.56582 -271.041114)
		(end 427.56582 -271.570958)
		(width 0.1651)
		(layer "In5.Cu")
		(net "P5E_PEX3_STN0_RX_DN<10>")
	)
	(segment
		(start 420.487348 -152.90165)
		(end 422.172384 -155.166822)
		(width 0.1651)
		(layer "In5.Cu")
		(net "P5E_PEX3_STN0_RX_DN<10>")
	)
	(segment
		(start 427.56582 -271.599406)
		(end 427.5201 -271.645126)
		(width 0.1143)
		(layer "In5.Cu")
		(net "P5E_PEX3_STN0_RX_DN<10>")
	)
	(segment
		(start 422.172384 -155.166822)
		(end 423.129964 -155.949396)
		(width 0.1651)
		(layer "In5.Cu")
		(net "P5E_PEX3_STN0_RX_DN<10>")
	)
	(segment
		(start 416.245802 -146.514566)
		(end 417.918646 -148.18741)
		(width 0.1651)
		(layer "In5.Cu")
		(net "P5E_PEX3_STN0_RX_DN<10>")
	)
	(segment
		(start 417.918646 -148.18741)
		(end 419.56228 -150.631906)
		(width 0.1651)
		(layer "In5.Cu")
		(net "P5E_PEX3_STN0_RX_DN<10>")
	)
	(segment
		(start 419.56228 -150.631906)
		(end 420.487348 -152.90165)
		(width 0.1651)
		(layer "In5.Cu")
		(net "P5E_PEX3_STN0_RX_DN<10>")
	)
	(segment
		(start 427.899576 -275.265388)
		(end 427.899576 -274.999958)
		(width 0.1143)
		(layer "In5.Cu")
		(net "P5E_PEX3_STN0_RX_DN<10>")
	)
	(segment
		(start 427.785276 -275.379688)
		(end 427.899576 -275.265388)
		(width 0.1143)
		(layer "In5.Cu")
		(net "P5E_PEX3_STN0_RX_DN<10>")
	)
	(segment
		(start 415.35731 -146.223736)
		(end 415.64814 -146.514566)
		(width 0.1651)
		(layer "In5.Cu")
		(net "P5E_PEX3_STN0_RX_DN<10>")
	)
	(segment
		(start 427.5201 -275.27631)
		(end 427.623478 -275.379688)
		(width 0.1143)
		(layer "In5.Cu")
		(net "P5E_PEX3_STN0_RX_DN<10>")
	)
	(segment
		(start 423.129964 -155.949396)
		(end 423.463974 -156.471112)
		(width 0.1651)
		(layer "In5.Cu")
		(net "P5E_PEX3_STN0_RX_DN<10>")
	)
	(segment
		(start 424.578272 -161.011616)
		(end 428.092108 -260.494272)
		(width 0.1651)
		(layer "In5.Cu")
		(net "P5E_PEX3_STN0_RX_DN<10>")
	)
	(segment
		(start 427.56582 -271.570958)
		(end 427.56582 -271.599406)
		(width 0.1143)
		(layer "In5.Cu")
		(net "P5E_PEX3_STN0_RX_DN<10>")
	)
	(segment
		(start 397.90497 -358.725978)
		(end 397.90497 -342.006174)
		(width 0.1651)
		(layer "In5.Cu")
		(net "P5E_PEX3_STN5_RX_DP<83>")
	)
	(segment
		(start 409.279598 -318.355472)
		(end 409.505404 -318.129666)
		(width 0.1143)
		(layer "In5.Cu")
		(net "P5E_PEX3_STN5_RX_DP<83>")
	)
	(segment
		(start 382.089914 -397.59001)
		(end 382.089914 -397.97609)
		(width 0.1651)
		(layer "In5.Cu")
		(net "P5E_PEX3_STN5_RX_DP<83>")
	)
	(segment
		(start 398.055592 -363.230922)
		(end 397.90497 -358.725978)
		(width 0.1651)
		(layer "In5.Cu")
		(net "P5E_PEX3_STN5_RX_DP<83>")
	)
	(segment
		(start 398.020286 -364.4519)
		(end 398.093946 -364.373414)
		(width 0.1651)
		(layer "In5.Cu")
		(net "P5E_PEX3_STN5_RX_DP<83>")
	)
	(segment
		(start 409.233878 -319.91173)
		(end 409.233878 -319.883282)
		(width 0.1143)
		(layer "In5.Cu")
		(net "P5E_PEX3_STN5_RX_DP<83>")
	)
	(segment
		(start 396.2273 -388.629906)
		(end 397.397478 -387.676644)
		(width 0.1651)
		(layer "In5.Cu")
		(net "P5E_PEX3_STN5_RX_DP<83>")
	)
	(segment
		(start 382.216914 -398.10309)
		(end 382.633474 -398.10309)
		(width 0.1651)
		(layer "In5.Cu")
		(net "P5E_PEX3_STN5_RX_DP<83>")
	)
	(segment
		(start 398.201388 -367.575084)
		(end 398.116044 -365.02086)
		(width 0.1651)
		(layer "In5.Cu")
		(net "P5E_PEX3_STN5_RX_DP<83>")
	)
	(segment
		(start 409.233878 -319.883282)
		(end 409.279598 -319.837562)
		(width 0.1143)
		(layer "In5.Cu")
		(net "P5E_PEX3_STN5_RX_DP<83>")
	)
	(segment
		(start 409.233878 -322.712334)
		(end 409.233878 -319.91173)
		(width 0.1651)
		(layer "In5.Cu")
		(net "P5E_PEX3_STN5_RX_DP<83>")
	)
	(segment
		(start 398.223232 -386.000752)
		(end 398.44091 -370.53012)
		(width 0.1651)
		(layer "In5.Cu")
		(net "P5E_PEX3_STN5_RX_DP<83>")
	)
	(segment
		(start 398.44091 -370.53012)
		(end 398.201388 -367.575084)
		(width 0.1651)
		(layer "In5.Cu")
		(net "P5E_PEX3_STN5_RX_DP<83>")
	)
	(segment
		(start 397.998442 -363.804962)
		(end 397.981932 -363.309662)
		(width 0.1651)
		(layer "In5.Cu")
		(net "P5E_PEX3_STN5_RX_DP<83>")
	)
	(segment
		(start 409.279598 -319.837562)
		(end 409.279598 -318.355472)
		(width 0.1143)
		(layer "In5.Cu")
		(net "P5E_PEX3_STN5_RX_DP<83>")
	)
	(segment
		(start 383.57556 -394.398754)
		(end 385.156456 -393.215622)
		(width 0.1651)
		(layer "In5.Cu")
		(net "P5E_PEX3_STN5_RX_DP<83>")
	)
	(segment
		(start 409.849828 -318.015366)
		(end 409.849828 -317.749936)
		(width 0.1143)
		(layer "In5.Cu")
		(net "P5E_PEX3_STN5_RX_DP<83>")
	)
	(segment
		(start 408.697684 -325.256144)
		(end 409.233878 -322.712334)
		(width 0.1651)
		(layer "In5.Cu")
		(net "P5E_PEX3_STN5_RX_DP<83>")
	)
	(segment
		(start 407.782014 -327.33234)
		(end 408.697684 -325.256144)
		(width 0.1651)
		(layer "In5.Cu")
		(net "P5E_PEX3_STN5_RX_DP<83>")
	)
	(segment
		(start 397.90497 -342.006174)
		(end 398.251426 -340.763352)
		(width 0.1651)
		(layer "In5.Cu")
		(net "P5E_PEX3_STN5_RX_DP<83>")
	)
	(segment
		(start 382.089914 -397.97609)
		(end 382.216914 -398.10309)
		(width 0.1651)
		(layer "In5.Cu")
		(net "P5E_PEX3_STN5_RX_DP<83>")
	)
	(segment
		(start 397.397478 -387.676644)
		(end 397.953484 -386.856986)
		(width 0.1651)
		(layer "In5.Cu")
		(net "P5E_PEX3_STN5_RX_DP<83>")
	)
	(segment
		(start 398.03705 -364.9472)
		(end 398.020286 -364.4519)
		(width 0.1651)
		(layer "In5.Cu")
		(net "P5E_PEX3_STN5_RX_DP<83>")
	)
	(segment
		(start 382.633474 -398.10309)
		(end 382.96596 -397.770604)
		(width 0.1651)
		(layer "In5.Cu")
		(net "P5E_PEX3_STN5_RX_DP<83>")
	)
	(segment
		(start 398.116044 -365.02086)
		(end 398.03705 -364.9472)
		(width 0.1651)
		(layer "In5.Cu")
		(net "P5E_PEX3_STN5_RX_DP<83>")
	)
	(segment
		(start 409.505404 -318.129666)
		(end 409.735528 -318.129666)
		(width 0.1143)
		(layer "In5.Cu")
		(net "P5E_PEX3_STN5_RX_DP<83>")
	)
	(segment
		(start 398.093946 -364.373414)
		(end 398.077436 -363.878622)
		(width 0.1651)
		(layer "In5.Cu")
		(net "P5E_PEX3_STN5_RX_DP<83>")
	)
	(segment
		(start 382.96596 -395.236192)
		(end 383.57556 -394.398754)
		(width 0.1651)
		(layer "In5.Cu")
		(net "P5E_PEX3_STN5_RX_DP<83>")
	)
	(segment
		(start 397.953484 -386.856986)
		(end 398.223232 -386.000752)
		(width 0.1651)
		(layer "In5.Cu")
		(net "P5E_PEX3_STN5_RX_DP<83>")
	)
	(segment
		(start 398.077436 -363.878622)
		(end 397.998442 -363.804962)
		(width 0.1651)
		(layer "In5.Cu")
		(net "P5E_PEX3_STN5_RX_DP<83>")
	)
	(segment
		(start 397.981932 -363.309662)
		(end 398.055592 -363.230922)
		(width 0.1651)
		(layer "In5.Cu")
		(net "P5E_PEX3_STN5_RX_DP<83>")
	)
	(segment
		(start 398.251426 -340.763352)
		(end 407.782014 -327.33234)
		(width 0.1651)
		(layer "In5.Cu")
		(net "P5E_PEX3_STN5_RX_DP<83>")
	)
	(segment
		(start 409.735528 -318.129666)
		(end 409.849828 -318.015366)
		(width 0.1143)
		(layer "In5.Cu")
		(net "P5E_PEX3_STN5_RX_DP<83>")
	)
	(segment
		(start 382.96596 -397.770604)
		(end 382.96596 -395.236192)
		(width 0.1651)
		(layer "In5.Cu")
		(net "P5E_PEX3_STN5_RX_DP<83>")
	)
	(segment
		(start 385.156456 -393.215622)
		(end 396.2273 -388.629906)
		(width 0.1651)
		(layer "In5.Cu")
		(net "P5E_PEX3_STN5_RX_DP<83>")
	)
	(segment
		(start 281.144726 -143.000984)
		(end 281.144726 -146.392646)
		(width 0.13208)
		(layer "F.Cu")
		(net "RST_NIC4_PERST0_R_N")
	)
	(segment
		(start 278.242268 -140.765022)
		(end 278.908764 -140.765022)
		(width 0.13208)
		(layer "F.Cu")
		(net "RST_NIC4_PERST0_R_N")
	)
	(segment
		(start 278.908764 -140.765022)
		(end 281.144726 -143.000984)
		(width 0.13208)
		(layer "F.Cu")
		(net "RST_NIC4_PERST0_R_N")
	)
	(segment
		(start 283.248354 -165.902894)
		(end 283.248354 -165.130226)
		(width 0.13208)
		(layer "F.Cu")
		(net "RST_NIC4_PERST0_R_N")
	)
	(segment
		(start 281.144726 -146.392646)
		(end 281.491944 -146.739864)
		(width 0.13208)
		(layer "F.Cu")
		(net "RST_NIC4_PERST0_R_N")
	)
	(via
		(at 283.248354 -165.130226)
		(size 0.508)
		(drill 0.254)
		(layers "F.Cu" "B.Cu")
		(net "RST_NIC4_PERST0_R_N")
	)
	(via
		(at 281.491944 -146.739864)
		(size 0.508)
		(drill 0.254)
		(layers "F.Cu" "B.Cu")
		(net "RST_NIC4_PERST0_R_N")
	)
	(segment
		(start 281.491944 -146.739864)
		(end 282.660344 -147.908264)
		(width 0.15494)
		(layer "In7.Cu")
		(net "RST_NIC4_PERST0_R_N")
	)
	(segment
		(start 282.660344 -147.908264)
		(end 282.660344 -164.559996)
		(width 0.15494)
		(layer "In7.Cu")
		(net "RST_NIC4_PERST0_R_N")
	)
	(segment
		(start 282.660344 -164.559996)
		(end 283.230574 -165.130226)
		(width 0.15494)
		(layer "In7.Cu")
		(net "RST_NIC4_PERST0_R_N")
	)
	(segment
		(start 283.230574 -165.130226)
		(end 283.248354 -165.130226)
		(width 0.15494)
		(layer "In7.Cu")
		(net "RST_NIC4_PERST0_R_N")
	)
	(segment
		(start 51.130454 -112.644936)
		(end 51.293268 -112.482122)
		(width 0.13462)
		(layer "F.Cu")
		(net "P5E_PEX0_STN1_RX_DN<23>")
	)
	(segment
		(start 51.948334 -112.482122)
		(end 52.24272 -112.776508)
		(width 0.13462)
		(layer "F.Cu")
		(net "P5E_PEX0_STN1_RX_DN<23>")
	)
	(segment
		(start 50.64252 -112.644936)
		(end 51.130454 -112.644936)
		(width 0.13462)
		(layer "F.Cu")
		(net "P5E_PEX0_STN1_RX_DN<23>")
	)
	(segment
		(start 51.293268 -112.482122)
		(end 51.948334 -112.482122)
		(width 0.13462)
		(layer "F.Cu")
		(net "P5E_PEX0_STN1_RX_DN<23>")
	)
	(segment
		(start 50.193448 -112.94745)
		(end 49.735232 -113.134902)
		(width 0.1651)
		(layer "In5.Cu")
		(net "P5E_PEX0_STN1_RX_DN<23>")
	)
	(segment
		(start 43.073574 -122.341894)
		(end 42.966386 -122.825256)
		(width 0.1651)
		(layer "In5.Cu")
		(net "P5E_PEX0_STN1_RX_DN<23>")
	)
	(segment
		(start 42.280332 -125.912626)
		(end 41.722802 -128.4224)
		(width 0.1651)
		(layer "In5.Cu")
		(net "P5E_PEX0_STN1_RX_DN<23>")
	)
	(segment
		(start 42.544746 -124.722382)
		(end 42.437558 -125.205744)
		(width 0.1651)
		(layer "In5.Cu")
		(net "P5E_PEX0_STN1_RX_DN<23>")
	)
	(segment
		(start 44.086018 -119.486426)
		(end 43.87723 -119.935498)
		(width 0.1651)
		(layer "In5.Cu")
		(net "P5E_PEX0_STN1_RX_DN<23>")
	)
	(segment
		(start 50.342546 -113.009934)
		(end 50.193448 -112.94745)
		(width 0.1651)
		(layer "In5.Cu")
		(net "P5E_PEX0_STN1_RX_DN<23>")
	)
	(segment
		(start 42.945558 -123.445524)
		(end 42.80916 -123.532138)
		(width 0.1651)
		(layer "In5.Cu")
		(net "P5E_PEX0_STN1_RX_DN<23>")
	)
	(segment
		(start 65.920112 -275.27631)
		(end 66.02349 -275.379688)
		(width 0.1143)
		(layer "In5.Cu")
		(net "P5E_PEX0_STN1_RX_DN<23>")
	)
	(segment
		(start 40.253158 -137.487406)
		(end 38.245796 -141.115288)
		(width 0.1651)
		(layer "In5.Cu")
		(net "P5E_PEX0_STN1_RX_DN<23>")
	)
	(segment
		(start 43.932602 -120.087136)
		(end 43.72356 -120.536716)
		(width 0.1651)
		(layer "In5.Cu")
		(net "P5E_PEX0_STN1_RX_DN<23>")
	)
	(segment
		(start 52.24272 -112.776508)
		(end 51.95189 -112.485678)
		(width 0.1651)
		(layer "In5.Cu")
		(net "P5E_PEX0_STN1_RX_DN<23>")
	)
	(segment
		(start 45.085254 -117.338856)
		(end 44.39158 -118.829836)
		(width 0.1651)
		(layer "In5.Cu")
		(net "P5E_PEX0_STN1_RX_DN<23>")
	)
	(segment
		(start 38.245796 -141.115288)
		(end 36.477194 -145.148046)
		(width 0.1651)
		(layer "In5.Cu")
		(net "P5E_PEX0_STN1_RX_DN<23>")
	)
	(segment
		(start 65.965832 -271.802352)
		(end 65.920112 -271.848072)
		(width 0.1143)
		(layer "In5.Cu")
		(net "P5E_PEX0_STN1_RX_DN<23>")
	)
	(segment
		(start 41.722802 -128.4224)
		(end 40.253158 -137.487406)
		(width 0.1651)
		(layer "In5.Cu")
		(net "P5E_PEX0_STN1_RX_DN<23>")
	)
	(segment
		(start 49.21377 -113.471452)
		(end 49.064926 -113.408968)
		(width 0.1651)
		(layer "In5.Cu")
		(net "P5E_PEX0_STN1_RX_DN<23>")
	)
	(segment
		(start 42.437558 -125.205744)
		(end 42.524172 -125.342142)
		(width 0.1651)
		(layer "In5.Cu")
		(net "P5E_PEX0_STN1_RX_DN<23>")
	)
	(segment
		(start 42.80916 -123.532138)
		(end 42.701972 -124.0155)
		(width 0.1651)
		(layer "In5.Cu")
		(net "P5E_PEX0_STN1_RX_DN<23>")
	)
	(segment
		(start 50.801016 -112.822482)
		(end 50.342546 -113.009934)
		(width 0.1651)
		(layer "In5.Cu")
		(net "P5E_PEX0_STN1_RX_DN<23>")
	)
	(segment
		(start 44.23791 -119.431054)
		(end 44.086018 -119.486426)
		(width 0.1651)
		(layer "In5.Cu")
		(net "P5E_PEX0_STN1_RX_DN<23>")
	)
	(segment
		(start 43.571668 -120.592088)
		(end 43.362372 -121.04243)
		(width 0.1651)
		(layer "In5.Cu")
		(net "P5E_PEX0_STN1_RX_DN<23>")
	)
	(segment
		(start 42.681144 -124.635768)
		(end 42.544746 -124.722382)
		(width 0.1651)
		(layer "In5.Cu")
		(net "P5E_PEX0_STN1_RX_DN<23>")
	)
	(segment
		(start 43.87723 -119.935498)
		(end 43.932602 -120.087136)
		(width 0.1651)
		(layer "In5.Cu")
		(net "P5E_PEX0_STN1_RX_DN<23>")
	)
	(segment
		(start 42.524172 -125.342142)
		(end 42.41673 -125.826012)
		(width 0.1651)
		(layer "In5.Cu")
		(net "P5E_PEX0_STN1_RX_DN<23>")
	)
	(segment
		(start 43.210226 -122.25528)
		(end 43.073574 -122.341894)
		(width 0.1651)
		(layer "In5.Cu")
		(net "P5E_PEX0_STN1_RX_DN<23>")
	)
	(segment
		(start 35.362642 -151.225504)
		(end 35.823906 -158.30169)
		(width 0.1651)
		(layer "In5.Cu")
		(net "P5E_PEX0_STN1_RX_DN<23>")
	)
	(segment
		(start 51.32197 -112.485678)
		(end 50.863754 -112.67313)
		(width 0.1651)
		(layer "In5.Cu")
		(net "P5E_PEX0_STN1_RX_DN<23>")
	)
	(segment
		(start 49.672494 -113.284)
		(end 49.21377 -113.471452)
		(width 0.1651)
		(layer "In5.Cu")
		(net "P5E_PEX0_STN1_RX_DN<23>")
	)
	(segment
		(start 43.053 -122.961654)
		(end 42.945558 -123.445524)
		(width 0.1651)
		(layer "In5.Cu")
		(net "P5E_PEX0_STN1_RX_DN<23>")
	)
	(segment
		(start 50.863754 -112.67313)
		(end 50.801016 -112.822482)
		(width 0.1651)
		(layer "In5.Cu")
		(net "P5E_PEX0_STN1_RX_DN<23>")
	)
	(segment
		(start 42.41673 -125.826012)
		(end 42.280332 -125.912626)
		(width 0.1651)
		(layer "In5.Cu")
		(net "P5E_PEX0_STN1_RX_DN<23>")
	)
	(segment
		(start 46.451012 -114.872008)
		(end 45.736256 -116.408708)
		(width 0.1651)
		(layer "In5.Cu")
		(net "P5E_PEX0_STN1_RX_DN<23>")
	)
	(segment
		(start 47.17415 -114.182144)
		(end 46.451012 -114.872008)
		(width 0.1651)
		(layer "In5.Cu")
		(net "P5E_PEX0_STN1_RX_DN<23>")
	)
	(segment
		(start 66.185288 -275.379688)
		(end 66.299588 -275.265388)
		(width 0.1143)
		(layer "In5.Cu")
		(net "P5E_PEX0_STN1_RX_DN<23>")
	)
	(segment
		(start 42.966386 -122.825256)
		(end 43.053 -122.961654)
		(width 0.1651)
		(layer "In5.Cu")
		(net "P5E_PEX0_STN1_RX_DN<23>")
	)
	(segment
		(start 49.735232 -113.134902)
		(end 49.672494 -113.284)
		(width 0.1651)
		(layer "In5.Cu")
		(net "P5E_PEX0_STN1_RX_DN<23>")
	)
	(segment
		(start 51.95189 -112.485678)
		(end 51.32197 -112.485678)
		(width 0.1651)
		(layer "In5.Cu")
		(net "P5E_PEX0_STN1_RX_DN<23>")
	)
	(segment
		(start 65.920112 -271.848072)
		(end 65.920112 -275.27631)
		(width 0.1143)
		(layer "In5.Cu")
		(net "P5E_PEX0_STN1_RX_DN<23>")
	)
	(segment
		(start 65.965832 -268.570202)
		(end 65.965832 -271.773904)
		(width 0.1651)
		(layer "In5.Cu")
		(net "P5E_PEX0_STN1_RX_DN<23>")
	)
	(segment
		(start 66.299588 -275.265388)
		(end 66.299588 -274.999958)
		(width 0.1143)
		(layer "In5.Cu")
		(net "P5E_PEX0_STN1_RX_DN<23>")
	)
	(segment
		(start 65.965832 -271.773904)
		(end 65.965832 -271.802352)
		(width 0.1143)
		(layer "In5.Cu")
		(net "P5E_PEX0_STN1_RX_DN<23>")
	)
	(segment
		(start 45.736256 -116.408708)
		(end 45.085254 -117.338856)
		(width 0.1651)
		(layer "In5.Cu")
		(net "P5E_PEX0_STN1_RX_DN<23>")
	)
	(segment
		(start 66.02349 -275.379688)
		(end 66.185288 -275.379688)
		(width 0.1143)
		(layer "In5.Cu")
		(net "P5E_PEX0_STN1_RX_DN<23>")
	)
	(segment
		(start 36.477194 -145.148046)
		(end 35.362642 -151.225504)
		(width 0.1651)
		(layer "In5.Cu")
		(net "P5E_PEX0_STN1_RX_DN<23>")
	)
	(segment
		(start 42.701972 -124.0155)
		(end 42.788586 -124.151898)
		(width 0.1651)
		(layer "In5.Cu")
		(net "P5E_PEX0_STN1_RX_DN<23>")
	)
	(segment
		(start 43.362372 -121.04243)
		(end 43.2308 -121.635012)
		(width 0.1651)
		(layer "In5.Cu")
		(net "P5E_PEX0_STN1_RX_DN<23>")
	)
	(segment
		(start 35.823906 -158.30169)
		(end 36.80587 -164.031168)
		(width 0.1651)
		(layer "In5.Cu")
		(net "P5E_PEX0_STN1_RX_DN<23>")
	)
	(segment
		(start 44.39158 -118.829836)
		(end 44.446952 -118.981728)
		(width 0.1651)
		(layer "In5.Cu")
		(net "P5E_PEX0_STN1_RX_DN<23>")
	)
	(segment
		(start 36.80587 -164.031168)
		(end 65.965832 -268.570202)
		(width 0.1651)
		(layer "In5.Cu")
		(net "P5E_PEX0_STN1_RX_DN<23>")
	)
	(segment
		(start 49.064926 -113.408968)
		(end 47.17415 -114.182144)
		(width 0.1651)
		(layer "In5.Cu")
		(net "P5E_PEX0_STN1_RX_DN<23>")
	)
	(segment
		(start 44.446952 -118.981728)
		(end 44.23791 -119.431054)
		(width 0.1651)
		(layer "In5.Cu")
		(net "P5E_PEX0_STN1_RX_DN<23>")
	)
	(segment
		(start 43.2308 -121.635012)
		(end 43.317668 -121.77141)
		(width 0.1651)
		(layer "In5.Cu")
		(net "P5E_PEX0_STN1_RX_DN<23>")
	)
	(segment
		(start 42.788586 -124.151898)
		(end 42.681144 -124.635768)
		(width 0.1651)
		(layer "In5.Cu")
		(net "P5E_PEX0_STN1_RX_DN<23>")
	)
	(segment
		(start 43.317668 -121.77141)
		(end 43.210226 -122.25528)
		(width 0.1651)
		(layer "In5.Cu")
		(net "P5E_PEX0_STN1_RX_DN<23>")
	)
	(segment
		(start 43.72356 -120.536716)
		(end 43.571668 -120.592088)
		(width 0.1651)
		(layer "In5.Cu")
		(net "P5E_PEX0_STN1_RX_DN<23>")
	)
	(segment
		(start 167.393112 -107.082082)
		(end 169.901616 -107.082082)
		(width 0.13462)
		(layer "F.Cu")
		(net "P5E_PEX1_STN1_RX_DN<20>")
	)
	(segment
		(start 167.230298 -107.244896)
		(end 167.393112 -107.082082)
		(width 0.13462)
		(layer "F.Cu")
		(net "P5E_PEX1_STN1_RX_DN<20>")
	)
	(segment
		(start 169.902124 -107.081574)
		(end 170.196764 -107.376214)
		(width 0.13462)
		(layer "F.Cu")
		(net "P5E_PEX1_STN1_RX_DN<20>")
	)
	(segment
		(start 169.901616 -107.082082)
		(end 169.902124 -107.081574)
		(width 0.13462)
		(layer "F.Cu")
		(net "P5E_PEX1_STN1_RX_DN<20>")
	)
	(segment
		(start 166.742364 -107.244896)
		(end 167.230298 -107.244896)
		(width 0.13462)
		(layer "F.Cu")
		(net "P5E_PEX1_STN1_RX_DN<20>")
	)
	(segment
		(start 157.21076 -114.80038)
		(end 155.456382 -122.331226)
		(width 0.1651)
		(layer "In5.Cu")
		(net "P5E_PEX1_STN1_RX_DN<20>")
	)
	(segment
		(start 158.00832 -113.39322)
		(end 157.21076 -114.80038)
		(width 0.1651)
		(layer "In5.Cu")
		(net "P5E_PEX1_STN1_RX_DN<20>")
	)
	(segment
		(start 170.196764 -107.376214)
		(end 169.905934 -107.085384)
		(width 0.1651)
		(layer "In5.Cu")
		(net "P5E_PEX1_STN1_RX_DN<20>")
	)
	(segment
		(start 158.826708 -112.602518)
		(end 158.00832 -113.39322)
		(width 0.1651)
		(layer "In5.Cu")
		(net "P5E_PEX1_STN1_RX_DN<20>")
	)
	(segment
		(start 154.69997 -123.195842)
		(end 152.96896 -123.863354)
		(width 0.1651)
		(layer "In5.Cu")
		(net "P5E_PEX1_STN1_RX_DN<20>")
	)
	(segment
		(start 167.323008 -107.318048)
		(end 167.275764 -107.472734)
		(width 0.1651)
		(layer "In5.Cu")
		(net "P5E_PEX1_STN1_RX_DN<20>")
	)
	(segment
		(start 179.21605 -271.554448)
		(end 179.17033 -271.600168)
		(width 0.1143)
		(layer "In5.Cu")
		(net "P5E_PEX1_STN1_RX_DN<20>")
	)
	(segment
		(start 179.273708 -273.479514)
		(end 179.435506 -273.479514)
		(width 0.1143)
		(layer "In5.Cu")
		(net "P5E_PEX1_STN1_RX_DN<20>")
	)
	(segment
		(start 162.970718 -109.764576)
		(end 162.53333 -109.997748)
		(width 0.1651)
		(layer "In5.Cu")
		(net "P5E_PEX1_STN1_RX_DN<20>")
	)
	(segment
		(start 167.760142 -107.085384)
		(end 167.323008 -107.318048)
		(width 0.1651)
		(layer "In5.Cu")
		(net "P5E_PEX1_STN1_RX_DN<20>")
	)
	(segment
		(start 163.017962 -109.610144)
		(end 162.970718 -109.764576)
		(width 0.1651)
		(layer "In5.Cu")
		(net "P5E_PEX1_STN1_RX_DN<20>")
	)
	(segment
		(start 161.94151 -110.183168)
		(end 161.894266 -110.337854)
		(width 0.1651)
		(layer "In5.Cu")
		(net "P5E_PEX1_STN1_RX_DN<20>")
	)
	(segment
		(start 179.435506 -273.479514)
		(end 179.549806 -273.365214)
		(width 0.1143)
		(layer "In5.Cu")
		(net "P5E_PEX1_STN1_RX_DN<20>")
	)
	(segment
		(start 148.998432 -158.717488)
		(end 150.01875 -164.663882)
		(width 0.1651)
		(layer "In5.Cu")
		(net "P5E_PEX1_STN1_RX_DN<20>")
	)
	(segment
		(start 150.01875 -164.663882)
		(end 179.21605 -269.31239)
		(width 0.1651)
		(layer "In5.Cu")
		(net "P5E_PEX1_STN1_RX_DN<20>")
	)
	(segment
		(start 166.24681 -107.891072)
		(end 166.199566 -108.045758)
		(width 0.1651)
		(layer "In5.Cu")
		(net "P5E_PEX1_STN1_RX_DN<20>")
	)
	(segment
		(start 159.347408 -112.099344)
		(end 159.344614 -112.260888)
		(width 0.1651)
		(layer "In5.Cu")
		(net "P5E_PEX1_STN1_RX_DN<20>")
	)
	(segment
		(start 148.47951 -150.512018)
		(end 148.998432 -158.717488)
		(width 0.1651)
		(layer "In5.Cu")
		(net "P5E_PEX1_STN1_RX_DN<20>")
	)
	(segment
		(start 164.531294 -108.804456)
		(end 164.09416 -109.03712)
		(width 0.1651)
		(layer "In5.Cu")
		(net "P5E_PEX1_STN1_RX_DN<20>")
	)
	(segment
		(start 179.21605 -269.31239)
		(end 179.21605 -271.526)
		(width 0.1651)
		(layer "In5.Cu")
		(net "P5E_PEX1_STN1_RX_DN<20>")
	)
	(segment
		(start 162.378644 -109.950504)
		(end 161.94151 -110.183168)
		(width 0.1651)
		(layer "In5.Cu")
		(net "P5E_PEX1_STN1_RX_DN<20>")
	)
	(segment
		(start 162.53333 -109.997748)
		(end 162.378644 -109.950504)
		(width 0.1651)
		(layer "In5.Cu")
		(net "P5E_PEX1_STN1_RX_DN<20>")
	)
	(segment
		(start 160.221422 -111.413544)
		(end 159.86506 -111.757968)
		(width 0.1651)
		(layer "In5.Cu")
		(net "P5E_PEX1_STN1_RX_DN<20>")
	)
	(segment
		(start 160.580324 -110.90783)
		(end 160.224216 -111.252)
		(width 0.1651)
		(layer "In5.Cu")
		(net "P5E_PEX1_STN1_RX_DN<20>")
	)
	(segment
		(start 161.894266 -110.337854)
		(end 161.456878 -110.570772)
		(width 0.1651)
		(layer "In5.Cu")
		(net "P5E_PEX1_STN1_RX_DN<20>")
	)
	(segment
		(start 159.703516 -111.755174)
		(end 159.347408 -112.099344)
		(width 0.1651)
		(layer "In5.Cu")
		(net "P5E_PEX1_STN1_RX_DN<20>")
	)
	(segment
		(start 179.21605 -271.526)
		(end 179.21605 -271.554448)
		(width 0.1143)
		(layer "In5.Cu")
		(net "P5E_PEX1_STN1_RX_DN<20>")
	)
	(segment
		(start 164.046916 -109.191806)
		(end 163.609528 -109.424724)
		(width 0.1651)
		(layer "In5.Cu")
		(net "P5E_PEX1_STN1_RX_DN<20>")
	)
	(segment
		(start 179.17033 -271.600168)
		(end 179.17033 -273.376136)
		(width 0.1143)
		(layer "In5.Cu")
		(net "P5E_PEX1_STN1_RX_DN<20>")
	)
	(segment
		(start 179.17033 -273.376136)
		(end 179.273708 -273.479514)
		(width 0.1143)
		(layer "In5.Cu")
		(net "P5E_PEX1_STN1_RX_DN<20>")
	)
	(segment
		(start 165.762178 -108.278676)
		(end 165.607746 -108.231432)
		(width 0.1651)
		(layer "In5.Cu")
		(net "P5E_PEX1_STN1_RX_DN<20>")
	)
	(segment
		(start 166.838376 -107.705652)
		(end 166.683944 -107.658408)
		(width 0.1651)
		(layer "In5.Cu")
		(net "P5E_PEX1_STN1_RX_DN<20>")
	)
	(segment
		(start 166.683944 -107.658408)
		(end 166.24681 -107.891072)
		(width 0.1651)
		(layer "In5.Cu")
		(net "P5E_PEX1_STN1_RX_DN<20>")
	)
	(segment
		(start 161.456878 -110.570772)
		(end 161.302192 -110.523528)
		(width 0.1651)
		(layer "In5.Cu")
		(net "P5E_PEX1_STN1_RX_DN<20>")
	)
	(segment
		(start 159.344614 -112.260888)
		(end 158.988252 -112.605312)
		(width 0.1651)
		(layer "In5.Cu")
		(net "P5E_PEX1_STN1_RX_DN<20>")
	)
	(segment
		(start 150.114 -129.549398)
		(end 148.47951 -150.512018)
		(width 0.1651)
		(layer "In5.Cu")
		(net "P5E_PEX1_STN1_RX_DN<20>")
	)
	(segment
		(start 167.275764 -107.472734)
		(end 166.838376 -107.705652)
		(width 0.1651)
		(layer "In5.Cu")
		(net "P5E_PEX1_STN1_RX_DN<20>")
	)
	(segment
		(start 165.607746 -108.231432)
		(end 165.170612 -108.464096)
		(width 0.1651)
		(layer "In5.Cu")
		(net "P5E_PEX1_STN1_RX_DN<20>")
	)
	(segment
		(start 155.456382 -122.331226)
		(end 154.69997 -123.195842)
		(width 0.1651)
		(layer "In5.Cu")
		(net "P5E_PEX1_STN1_RX_DN<20>")
	)
	(segment
		(start 163.609528 -109.424724)
		(end 163.455096 -109.37748)
		(width 0.1651)
		(layer "In5.Cu")
		(net "P5E_PEX1_STN1_RX_DN<20>")
	)
	(segment
		(start 164.68598 -108.8517)
		(end 164.531294 -108.804456)
		(width 0.1651)
		(layer "In5.Cu")
		(net "P5E_PEX1_STN1_RX_DN<20>")
	)
	(segment
		(start 164.09416 -109.03712)
		(end 164.046916 -109.191806)
		(width 0.1651)
		(layer "In5.Cu")
		(net "P5E_PEX1_STN1_RX_DN<20>")
	)
	(segment
		(start 163.455096 -109.37748)
		(end 163.017962 -109.610144)
		(width 0.1651)
		(layer "In5.Cu")
		(net "P5E_PEX1_STN1_RX_DN<20>")
	)
	(segment
		(start 158.988252 -112.605312)
		(end 158.826708 -112.602518)
		(width 0.1651)
		(layer "In5.Cu")
		(net "P5E_PEX1_STN1_RX_DN<20>")
	)
	(segment
		(start 169.905934 -107.085384)
		(end 167.760142 -107.085384)
		(width 0.1651)
		(layer "In5.Cu")
		(net "P5E_PEX1_STN1_RX_DN<20>")
	)
	(segment
		(start 179.549806 -273.365214)
		(end 179.549806 -273.099784)
		(width 0.1143)
		(layer "In5.Cu")
		(net "P5E_PEX1_STN1_RX_DN<20>")
	)
	(segment
		(start 152.96896 -123.863354)
		(end 150.114 -129.549398)
		(width 0.1651)
		(layer "In5.Cu")
		(net "P5E_PEX1_STN1_RX_DN<20>")
	)
	(segment
		(start 161.302192 -110.523528)
		(end 160.580324 -110.90783)
		(width 0.1651)
		(layer "In5.Cu")
		(net "P5E_PEX1_STN1_RX_DN<20>")
	)
	(segment
		(start 160.224216 -111.252)
		(end 160.221422 -111.413544)
		(width 0.1651)
		(layer "In5.Cu")
		(net "P5E_PEX1_STN1_RX_DN<20>")
	)
	(segment
		(start 159.86506 -111.757968)
		(end 159.703516 -111.755174)
		(width 0.1651)
		(layer "In5.Cu")
		(net "P5E_PEX1_STN1_RX_DN<20>")
	)
	(segment
		(start 166.199566 -108.045758)
		(end 165.762178 -108.278676)
		(width 0.1651)
		(layer "In5.Cu")
		(net "P5E_PEX1_STN1_RX_DN<20>")
	)
	(segment
		(start 165.170612 -108.464096)
		(end 165.123368 -108.618782)
		(width 0.1651)
		(layer "In5.Cu")
		(net "P5E_PEX1_STN1_RX_DN<20>")
	)
	(segment
		(start 165.123368 -108.618782)
		(end 164.68598 -108.8517)
		(width 0.1651)
		(layer "In5.Cu")
		(net "P5E_PEX1_STN1_RX_DN<20>")
	)
	(segment
		(start 252.041406 -30.35808)
		(end 248.135902 -30.35808)
		(width 0.13462)
		(layer "F.Cu")
		(net "P5E_PEX2_STN2_TX_C_DN<45>")
	)
	(segment
		(start 252.367796 -30.03169)
		(end 252.041406 -30.35808)
		(width 0.13462)
		(layer "F.Cu")
		(net "P5E_PEX2_STN2_TX_C_DN<45>")
	)
	(segment
		(start 247.968008 -30.190186)
		(end 247.464834 -30.190186)
		(width 0.13462)
		(layer "F.Cu")
		(net "P5E_PEX2_STN2_TX_C_DN<45>")
	)
	(segment
		(start 248.135902 -30.35808)
		(end 247.968008 -30.190186)
		(width 0.13462)
		(layer "F.Cu")
		(net "P5E_PEX2_STN2_TX_C_DN<45>")
	)
	(segment
		(start 413.801814 -151.92248)
		(end 416.312604 -151.92248)
		(width 0.13462)
		(layer "F.Cu")
		(net "P5E_PEX3_STN0_RX_DN<13>")
	)
	(segment
		(start 416.312604 -151.92248)
		(end 416.47999 -151.755094)
		(width 0.13462)
		(layer "F.Cu")
		(net "P5E_PEX3_STN0_RX_DN<13>")
	)
	(segment
		(start 416.47999 -151.755094)
		(end 416.95751 -151.755094)
		(width 0.13462)
		(layer "F.Cu")
		(net "P5E_PEX3_STN0_RX_DN<13>")
	)
	(segment
		(start 413.50311 -151.623776)
		(end 413.801814 -151.92248)
		(width 0.13462)
		(layer "F.Cu")
		(net "P5E_PEX3_STN0_RX_DN<13>")
	)
	(segment
		(start 421.601646 -161.295334)
		(end 425.157646 -260.64464)
		(width 0.1651)
		(layer "In5.Cu")
		(net "P5E_PEX3_STN0_RX_DN<13>")
	)
	(segment
		(start 424.71594 -271.526)
		(end 424.71594 -271.554448)
		(width 0.1143)
		(layer "In5.Cu")
		(net "P5E_PEX3_STN0_RX_DN<13>")
	)
	(segment
		(start 416.114992 -151.914606)
		(end 417.15944 -152.959054)
		(width 0.1651)
		(layer "In5.Cu")
		(net "P5E_PEX3_STN0_RX_DN<13>")
	)
	(segment
		(start 420.57574 -158.828232)
		(end 421.601646 -161.295334)
		(width 0.1651)
		(layer "In5.Cu")
		(net "P5E_PEX3_STN0_RX_DN<13>")
	)
	(segment
		(start 424.67022 -273.376136)
		(end 424.773598 -273.479514)
		(width 0.1143)
		(layer "In5.Cu")
		(net "P5E_PEX3_STN0_RX_DN<13>")
	)
	(segment
		(start 425.23283 -267.869924)
		(end 424.71594 -270.540226)
		(width 0.1651)
		(layer "In5.Cu")
		(net "P5E_PEX3_STN0_RX_DN<13>")
	)
	(segment
		(start 424.71594 -271.554448)
		(end 424.67022 -271.600168)
		(width 0.1143)
		(layer "In5.Cu")
		(net "P5E_PEX3_STN0_RX_DN<13>")
	)
	(segment
		(start 425.157646 -260.64464)
		(end 425.23283 -267.869924)
		(width 0.1651)
		(layer "In5.Cu")
		(net "P5E_PEX3_STN0_RX_DN<13>")
	)
	(segment
		(start 425.049696 -273.365214)
		(end 425.049696 -273.099784)
		(width 0.1143)
		(layer "In5.Cu")
		(net "P5E_PEX3_STN0_RX_DN<13>")
	)
	(segment
		(start 413.79394 -151.914606)
		(end 416.114992 -151.914606)
		(width 0.1651)
		(layer "In5.Cu")
		(net "P5E_PEX3_STN0_RX_DN<13>")
	)
	(segment
		(start 413.50311 -151.623776)
		(end 413.79394 -151.914606)
		(width 0.1651)
		(layer "In5.Cu")
		(net "P5E_PEX3_STN0_RX_DN<13>")
	)
	(segment
		(start 424.71594 -270.540226)
		(end 424.71594 -271.526)
		(width 0.1651)
		(layer "In5.Cu")
		(net "P5E_PEX3_STN0_RX_DN<13>")
	)
	(segment
		(start 420.565072 -158.80207)
		(end 420.575994 -158.828232)
		(width 0.1651)
		(layer "In5.Cu")
		(net "P5E_PEX3_STN0_RX_DN<13>")
	)
	(segment
		(start 420.575994 -158.828232)
		(end 420.57574 -158.828232)
		(width 0.1651)
		(layer "In5.Cu")
		(net "P5E_PEX3_STN0_RX_DN<13>")
	)
	(segment
		(start 424.935396 -273.479514)
		(end 425.049696 -273.365214)
		(width 0.1143)
		(layer "In5.Cu")
		(net "P5E_PEX3_STN0_RX_DN<13>")
	)
	(segment
		(start 418.031422 -155.050998)
		(end 420.565072 -158.80207)
		(width 0.1651)
		(layer "In5.Cu")
		(net "P5E_PEX3_STN0_RX_DN<13>")
	)
	(segment
		(start 424.67022 -271.600168)
		(end 424.67022 -273.376136)
		(width 0.1143)
		(layer "In5.Cu")
		(net "P5E_PEX3_STN0_RX_DN<13>")
	)
	(segment
		(start 424.773598 -273.479514)
		(end 424.935396 -273.479514)
		(width 0.1143)
		(layer "In5.Cu")
		(net "P5E_PEX3_STN0_RX_DN<13>")
	)
	(segment
		(start 417.15944 -152.959054)
		(end 418.031422 -155.050998)
		(width 0.1651)
		(layer "In5.Cu")
		(net "P5E_PEX3_STN0_RX_DN<13>")
	)
	(segment
		(start 397.402304 -390.527286)
		(end 399.034254 -389.192516)
		(width 0.1651)
		(layer "In5.Cu")
		(net "P5E_PEX3_STN5_RX_DN<85>")
	)
	(segment
		(start 411.750002 -318.434466)
		(end 411.750002 -318.699896)
		(width 0.1143)
		(layer "In5.Cu")
		(net "P5E_PEX3_STN5_RX_DN<85>")
	)
	(segment
		(start 411.415992 -319.916048)
		(end 411.415992 -319.8876)
		(width 0.1143)
		(layer "In5.Cu")
		(net "P5E_PEX3_STN5_RX_DN<85>")
	)
	(segment
		(start 388.031736 -394.684758)
		(end 388.711948 -394.126212)
		(width 0.1651)
		(layer "In5.Cu")
		(net "P5E_PEX3_STN5_RX_DN<85>")
	)
	(segment
		(start 405.15032 -340.00948)
		(end 410.902658 -326.140318)
		(width 0.1651)
		(layer "In5.Cu")
		(net "P5E_PEX3_STN5_RX_DN<85>")
	)
	(segment
		(start 404.514812 -357.543608)
		(end 404.59152 -342.32088)
		(width 0.1651)
		(layer "In5.Cu")
		(net "P5E_PEX3_STN5_RX_DN<85>")
	)
	(segment
		(start 387.647942 -397.887444)
		(end 387.647942 -395.258544)
		(width 0.1651)
		(layer "In5.Cu")
		(net "P5E_PEX3_STN5_RX_DN<85>")
	)
	(segment
		(start 387.150356 -398.38503)
		(end 387.647942 -397.887444)
		(width 0.1651)
		(layer "In5.Cu")
		(net "P5E_PEX3_STN5_RX_DN<85>")
	)
	(segment
		(start 399.034254 -389.192516)
		(end 399.978372 -387.78942)
		(width 0.1651)
		(layer "In5.Cu")
		(net "P5E_PEX3_STN5_RX_DN<85>")
	)
	(segment
		(start 411.415992 -323.56298)
		(end 411.415992 -319.916048)
		(width 0.1651)
		(layer "In5.Cu")
		(net "P5E_PEX3_STN5_RX_DN<85>")
	)
	(segment
		(start 402.181568 -365.930942)
		(end 404.514812 -357.543608)
		(width 0.1651)
		(layer "In5.Cu")
		(net "P5E_PEX3_STN5_RX_DN<85>")
	)
	(segment
		(start 387.647942 -395.258544)
		(end 388.031736 -394.684758)
		(width 0.1651)
		(layer "In5.Cu")
		(net "P5E_PEX3_STN5_RX_DN<85>")
	)
	(segment
		(start 400.82216 -373.16918)
		(end 402.181568 -365.930942)
		(width 0.1651)
		(layer "In5.Cu")
		(net "P5E_PEX3_STN5_RX_DN<85>")
	)
	(segment
		(start 404.59152 -342.32088)
		(end 405.15032 -340.00948)
		(width 0.1651)
		(layer "In5.Cu")
		(net "P5E_PEX3_STN5_RX_DN<85>")
	)
	(segment
		(start 386.489956 -398.51203)
		(end 386.616956 -398.38503)
		(width 0.1651)
		(layer "In5.Cu")
		(net "P5E_PEX3_STN5_RX_DN<85>")
	)
	(segment
		(start 386.489956 -398.890236)
		(end 386.489956 -398.51203)
		(width 0.1651)
		(layer "In5.Cu")
		(net "P5E_PEX3_STN5_RX_DN<85>")
	)
	(segment
		(start 411.484572 -318.320166)
		(end 411.635702 -318.320166)
		(width 0.1143)
		(layer "In5.Cu")
		(net "P5E_PEX3_STN5_RX_DN<85>")
	)
	(segment
		(start 400.60245 -375.365264)
		(end 400.82216 -373.16918)
		(width 0.1651)
		(layer "In5.Cu")
		(net "P5E_PEX3_STN5_RX_DN<85>")
	)
	(segment
		(start 411.415992 -319.8876)
		(end 411.370272 -319.84188)
		(width 0.1143)
		(layer "In5.Cu")
		(net "P5E_PEX3_STN5_RX_DN<85>")
	)
	(segment
		(start 411.370272 -319.84188)
		(end 411.370272 -318.434466)
		(width 0.1143)
		(layer "In5.Cu")
		(net "P5E_PEX3_STN5_RX_DN<85>")
	)
	(segment
		(start 411.635702 -318.320166)
		(end 411.750002 -318.434466)
		(width 0.1143)
		(layer "In5.Cu")
		(net "P5E_PEX3_STN5_RX_DN<85>")
	)
	(segment
		(start 410.902658 -326.140318)
		(end 411.415992 -323.56298)
		(width 0.1651)
		(layer "In5.Cu")
		(net "P5E_PEX3_STN5_RX_DN<85>")
	)
	(segment
		(start 400.45259 -386.273548)
		(end 400.60245 -375.365264)
		(width 0.1651)
		(layer "In5.Cu")
		(net "P5E_PEX3_STN5_RX_DN<85>")
	)
	(segment
		(start 388.711948 -394.126212)
		(end 397.402304 -390.527286)
		(width 0.1651)
		(layer "In5.Cu")
		(net "P5E_PEX3_STN5_RX_DN<85>")
	)
	(segment
		(start 386.616956 -398.38503)
		(end 387.150356 -398.38503)
		(width 0.1651)
		(layer "In5.Cu")
		(net "P5E_PEX3_STN5_RX_DN<85>")
	)
	(segment
		(start 399.978372 -387.78942)
		(end 400.45259 -386.273548)
		(width 0.1651)
		(layer "In5.Cu")
		(net "P5E_PEX3_STN5_RX_DN<85>")
	)
	(segment
		(start 411.370272 -318.434466)
		(end 411.484572 -318.320166)
		(width 0.1143)
		(layer "In5.Cu")
		(net "P5E_PEX3_STN5_RX_DN<85>")
	)
	(segment
		(start 274.177506 -152.719278)
		(end 272.59661 -152.719278)
		(width 0.13208)
		(layer "F.Cu")
		(net "NCSI_NIC4_RXD1")
	)
	(segment
		(start 272.172684 -152.295352)
		(end 271.199864 -152.295352)
		(width 0.13208)
		(layer "F.Cu")
		(net "NCSI_NIC4_RXD1")
	)
	(segment
		(start 272.59661 -152.719278)
		(end 272.172684 -152.295352)
		(width 0.13208)
		(layer "F.Cu")
		(net "NCSI_NIC4_RXD1")
	)
	(segment
		(start 278.242268 -154.159966)
		(end 275.618194 -154.159966)
		(width 0.13208)
		(layer "F.Cu")
		(net "NCSI_NIC4_RXD1")
	)
	(segment
		(start 275.618194 -154.159966)
		(end 274.177506 -152.719278)
		(width 0.13208)
		(layer "F.Cu")
		(net "NCSI_NIC4_RXD1")
	)
	(via
		(at 272.59661 -152.719278)
		(size 0.762)
		(drill 0.381)
		(layers "F.Cu" "B.Cu")
		(net "NCSI_NIC4_RXD1")
	)
	(segment
		(start 51.130454 -108.445046)
		(end 50.64252 -108.445046)
		(width 0.13462)
		(layer "F.Cu")
		(net "P5E_PEX0_STN1_RX_DP<21>")
	)
	(segment
		(start 51.947826 -108.60786)
		(end 51.293268 -108.60786)
		(width 0.13462)
		(layer "F.Cu")
		(net "P5E_PEX0_STN1_RX_DP<21>")
	)
	(segment
		(start 52.24272 -108.312966)
		(end 51.947826 -108.60786)
		(width 0.13462)
		(layer "F.Cu")
		(net "P5E_PEX0_STN1_RX_DP<21>")
	)
	(segment
		(start 52.24272 -108.312712)
		(end 52.24272 -108.312966)
		(width 0.13462)
		(layer "F.Cu")
		(net "P5E_PEX0_STN1_RX_DP<21>")
	)
	(segment
		(start 51.293268 -108.60786)
		(end 51.130454 -108.445046)
		(width 0.13462)
		(layer "F.Cu")
		(net "P5E_PEX0_STN1_RX_DP<21>")
	)
	(segment
		(start 63.783972 -269.183104)
		(end 63.783972 -271.773904)
		(width 0.1651)
		(layer "In5.Cu")
		(net "P5E_PEX0_STN1_RX_DP<21>")
	)
	(segment
		(start 35.086544 -139.663932)
		(end 33.091374 -150.66772)
		(width 0.1651)
		(layer "In5.Cu")
		(net "P5E_PEX0_STN1_RX_DP<21>")
	)
	(segment
		(start 64.285368 -275.569934)
		(end 64.399668 -275.684234)
		(width 0.1143)
		(layer "In5.Cu")
		(net "P5E_PEX0_STN1_RX_DP<21>")
	)
	(segment
		(start 33.091374 -150.66772)
		(end 33.093406 -150.701756)
		(width 0.1651)
		(layer "In5.Cu")
		(net "P5E_PEX0_STN1_RX_DP<21>")
	)
	(segment
		(start 51.519328 -108.603542)
		(end 51.481228 -108.641642)
		(width 0.1651)
		(layer "In5.Cu")
		(net "P5E_PEX0_STN1_RX_DP<21>")
	)
	(segment
		(start 33.093406 -150.701756)
		(end 33.09366 -150.701756)
		(width 0.1651)
		(layer "In5.Cu")
		(net "P5E_PEX0_STN1_RX_DP<21>")
	)
	(segment
		(start 51.481228 -108.641642)
		(end 42.552874 -113.706656)
		(width 0.1651)
		(layer "In5.Cu")
		(net "P5E_PEX0_STN1_RX_DP<21>")
	)
	(segment
		(start 42.552874 -113.706656)
		(end 42.44594 -113.810542)
		(width 0.1651)
		(layer "In5.Cu")
		(net "P5E_PEX0_STN1_RX_DP<21>")
	)
	(segment
		(start 51.95189 -108.603542)
		(end 51.519328 -108.603542)
		(width 0.1651)
		(layer "In5.Cu")
		(net "P5E_PEX0_STN1_RX_DP<21>")
	)
	(segment
		(start 52.24272 -108.312712)
		(end 51.95189 -108.603542)
		(width 0.1651)
		(layer "In5.Cu")
		(net "P5E_PEX0_STN1_RX_DP<21>")
	)
	(segment
		(start 63.783972 -271.773904)
		(end 63.783972 -271.802352)
		(width 0.1143)
		(layer "In5.Cu")
		(net "P5E_PEX0_STN1_RX_DP<21>")
	)
	(segment
		(start 64.044576 -275.569934)
		(end 64.285368 -275.569934)
		(width 0.1143)
		(layer "In5.Cu")
		(net "P5E_PEX0_STN1_RX_DP<21>")
	)
	(segment
		(start 41.745154 -115.056158)
		(end 39.63289 -124.282962)
		(width 0.1651)
		(layer "In5.Cu")
		(net "P5E_PEX0_STN1_RX_DP<21>")
	)
	(segment
		(start 63.829692 -275.35505)
		(end 64.044576 -275.569934)
		(width 0.1143)
		(layer "In5.Cu")
		(net "P5E_PEX0_STN1_RX_DP<21>")
	)
	(segment
		(start 63.783972 -271.802352)
		(end 63.829692 -271.848072)
		(width 0.1143)
		(layer "In5.Cu")
		(net "P5E_PEX0_STN1_RX_DP<21>")
	)
	(segment
		(start 36.270946 -136.383268)
		(end 35.086544 -139.663932)
		(width 0.1651)
		(layer "In5.Cu")
		(net "P5E_PEX0_STN1_RX_DP<21>")
	)
	(segment
		(start 64.399668 -275.684234)
		(end 64.399668 -275.949664)
		(width 0.1143)
		(layer "In5.Cu")
		(net "P5E_PEX0_STN1_RX_DP<21>")
	)
	(segment
		(start 34.635948 -164.671756)
		(end 63.783972 -269.183104)
		(width 0.1651)
		(layer "In5.Cu")
		(net "P5E_PEX0_STN1_RX_DP<21>")
	)
	(segment
		(start 39.63289 -124.282962)
		(end 36.270946 -132.111496)
		(width 0.1651)
		(layer "In5.Cu")
		(net "P5E_PEX0_STN1_RX_DP<21>")
	)
	(segment
		(start 33.09366 -150.701756)
		(end 33.579054 -158.54426)
		(width 0.1651)
		(layer "In5.Cu")
		(net "P5E_PEX0_STN1_RX_DP<21>")
	)
	(segment
		(start 63.829692 -271.848072)
		(end 63.829692 -275.35505)
		(width 0.1143)
		(layer "In5.Cu")
		(net "P5E_PEX0_STN1_RX_DP<21>")
	)
	(segment
		(start 42.44594 -113.810542)
		(end 41.745154 -115.056158)
		(width 0.1651)
		(layer "In5.Cu")
		(net "P5E_PEX0_STN1_RX_DP<21>")
	)
	(segment
		(start 33.579054 -158.54426)
		(end 34.635948 -164.671756)
		(width 0.1651)
		(layer "In5.Cu")
		(net "P5E_PEX0_STN1_RX_DP<21>")
	)
	(segment
		(start 36.270946 -132.111496)
		(end 36.270946 -136.383268)
		(width 0.1651)
		(layer "In5.Cu")
		(net "P5E_PEX0_STN1_RX_DP<21>")
	)
	(segment
		(start 93.030802 -356.831646)
		(end 93.350842 -356.511606)
		(width 0.13462)
		(layer "F.Cu")
		(net "P5E_PEX0_STN6_TX_C_DN<96>")
	)
	(segment
		(start 93.030802 -357.46309)
		(end 93.030802 -356.831646)
		(width 0.13462)
		(layer "F.Cu")
		(net "P5E_PEX0_STN6_TX_C_DN<96>")
	)
	(segment
		(start 93.325442 -357.75773)
		(end 93.030802 -357.46309)
		(width 0.13462)
		(layer "F.Cu")
		(net "P5E_PEX0_STN6_TX_C_DN<96>")
	)
	(segment
		(start 93.034612 -358.977184)
		(end 93.034612 -358.04856)
		(width 0.1651)
		(layer "In13.Cu")
		(net "P5E_PEX0_STN6_TX_C_DN<96>")
	)
	(segment
		(start 87.30996 -384.590036)
		(end 87.30996 -384.20802)
		(width 0.1651)
		(layer "In13.Cu")
		(net "P5E_PEX0_STN6_TX_C_DN<96>")
	)
	(segment
		(start 87.30996 -384.20802)
		(end 87.43696 -384.08102)
		(width 0.1651)
		(layer "In13.Cu")
		(net "P5E_PEX0_STN6_TX_C_DN<96>")
	)
	(segment
		(start 88.484202 -368.597942)
		(end 93.034612 -358.977184)
		(width 0.1651)
		(layer "In13.Cu")
		(net "P5E_PEX0_STN6_TX_C_DN<96>")
	)
	(segment
		(start 87.43696 -384.08102)
		(end 88.081104 -384.08102)
		(width 0.1651)
		(layer "In13.Cu")
		(net "P5E_PEX0_STN6_TX_C_DN<96>")
	)
	(segment
		(start 88.484202 -383.677922)
		(end 88.484202 -368.597942)
		(width 0.1651)
		(layer "In13.Cu")
		(net "P5E_PEX0_STN6_TX_C_DN<96>")
	)
	(segment
		(start 93.034612 -358.04856)
		(end 93.325442 -357.75773)
		(width 0.1651)
		(layer "In13.Cu")
		(net "P5E_PEX0_STN6_TX_C_DN<96>")
	)
	(segment
		(start 88.081104 -384.08102)
		(end 88.484202 -383.677922)
		(width 0.1651)
		(layer "In13.Cu")
		(net "P5E_PEX0_STN6_TX_C_DN<96>")
	)
	(segment
		(start 161.654236 -125.355096)
		(end 161.491422 -125.192282)
		(width 0.13462)
		(layer "F.Cu")
		(net "P5E_PEX1_STN1_TX_C_DP<27>")
	)
	(segment
		(start 161.491422 -125.192282)
		(end 155.974796 -125.192282)
		(width 0.13462)
		(layer "F.Cu")
		(net "P5E_PEX1_STN1_TX_C_DP<27>")
	)
	(segment
		(start 155.974796 -125.192282)
		(end 155.647136 -125.519942)
		(width 0.13462)
		(layer "F.Cu")
		(net "P5E_PEX1_STN1_TX_C_DP<27>")
	)
	(segment
		(start 162.14217 -125.355096)
		(end 161.654236 -125.355096)
		(width 0.13462)
		(layer "F.Cu")
		(net "P5E_PEX1_STN1_TX_C_DP<27>")
	)
	(segment
		(start 320.864738 -33.790128)
		(end 320.387218 -33.790128)
		(width 0.13462)
		(layer "F.Cu")
		(net "P5E_PEX2_STN2_RX_DN<35>")
	)
	(segment
		(start 317.70447 -33.952942)
		(end 317.410338 -33.65881)
		(width 0.13462)
		(layer "F.Cu")
		(net "P5E_PEX2_STN2_RX_DN<35>")
	)
	(segment
		(start 320.224404 -33.952942)
		(end 317.70447 -33.952942)
		(width 0.13462)
		(layer "F.Cu")
		(net "P5E_PEX2_STN2_RX_DN<35>")
	)
	(segment
		(start 320.387218 -33.790128)
		(end 320.224404 -33.952942)
		(width 0.13462)
		(layer "F.Cu")
		(net "P5E_PEX2_STN2_RX_DN<35>")
	)
	(segment
		(start 287.669986 -271.41932)
		(end 287.669986 -273.328638)
		(width 0.1143)
		(layer "In7.Cu")
		(net "P5E_PEX2_STN2_RX_DN<35>")
	)
	(segment
		(start 287.715706 -270.511524)
		(end 287.715706 -271.345152)
		(width 0.1651)
		(layer "In7.Cu")
		(net "P5E_PEX2_STN2_RX_DN<35>")
	)
	(segment
		(start 319.13195 -39.583614)
		(end 320.47053 -49.490884)
		(width 0.1651)
		(layer "In7.Cu")
		(net "P5E_PEX2_STN2_RX_DN<35>")
	)
	(segment
		(start 287.669986 -273.328638)
		(end 287.820862 -273.479514)
		(width 0.1143)
		(layer "In7.Cu")
		(net "P5E_PEX2_STN2_RX_DN<35>")
	)
	(segment
		(start 317.410338 -33.65881)
		(end 317.701168 -33.94964)
		(width 0.1651)
		(layer "In7.Cu")
		(net "P5E_PEX2_STN2_RX_DN<35>")
	)
	(segment
		(start 309.304182 -116.369084)
		(end 308.98719 -143.682974)
		(width 0.1651)
		(layer "In7.Cu")
		(net "P5E_PEX2_STN2_RX_DN<35>")
	)
	(segment
		(start 308.98719 -143.682974)
		(end 307.606954 -154.40914)
		(width 0.1651)
		(layer "In7.Cu")
		(net "P5E_PEX2_STN2_RX_DN<35>")
	)
	(segment
		(start 307.606954 -154.40914)
		(end 288.040572 -266.758166)
		(width 0.1651)
		(layer "In7.Cu")
		(net "P5E_PEX2_STN2_RX_DN<35>")
	)
	(segment
		(start 287.935416 -273.479514)
		(end 288.049716 -273.365214)
		(width 0.1143)
		(layer "In7.Cu")
		(net "P5E_PEX2_STN2_RX_DN<35>")
	)
	(segment
		(start 319.06083 -34.714688)
		(end 319.13195 -39.583614)
		(width 0.1651)
		(layer "In7.Cu")
		(net "P5E_PEX2_STN2_RX_DN<35>")
	)
	(segment
		(start 318.295782 -33.94964)
		(end 319.06083 -34.714688)
		(width 0.1651)
		(layer "In7.Cu")
		(net "P5E_PEX2_STN2_RX_DN<35>")
	)
	(segment
		(start 287.715706 -271.3736)
		(end 287.669986 -271.41932)
		(width 0.1143)
		(layer "In7.Cu")
		(net "P5E_PEX2_STN2_RX_DN<35>")
	)
	(segment
		(start 317.701168 -33.94964)
		(end 318.295782 -33.94964)
		(width 0.1651)
		(layer "In7.Cu")
		(net "P5E_PEX2_STN2_RX_DN<35>")
	)
	(segment
		(start 288.040572 -266.758166)
		(end 287.715706 -270.511524)
		(width 0.1651)
		(layer "In7.Cu")
		(net "P5E_PEX2_STN2_RX_DN<35>")
	)
	(segment
		(start 287.715706 -271.345152)
		(end 287.715706 -271.3736)
		(width 0.1143)
		(layer "In7.Cu")
		(net "P5E_PEX2_STN2_RX_DN<35>")
	)
	(segment
		(start 320.47053 -49.490884)
		(end 320.290952 -60.99048)
		(width 0.1651)
		(layer "In7.Cu")
		(net "P5E_PEX2_STN2_RX_DN<35>")
	)
	(segment
		(start 288.049716 -273.365214)
		(end 288.049716 -273.099784)
		(width 0.1143)
		(layer "In7.Cu")
		(net "P5E_PEX2_STN2_RX_DN<35>")
	)
	(segment
		(start 320.290952 -60.99048)
		(end 309.304182 -116.369084)
		(width 0.1651)
		(layer "In7.Cu")
		(net "P5E_PEX2_STN2_RX_DN<35>")
	)
	(segment
		(start 287.820862 -273.479514)
		(end 287.935416 -273.479514)
		(width 0.1143)
		(layer "In7.Cu")
		(net "P5E_PEX2_STN2_RX_DN<35>")
	)
	(segment
		(start 415.65195 -143.1925)
		(end 416.315906 -143.1925)
		(width 0.13462)
		(layer "F.Cu")
		(net "P5E_PEX3_STN0_RX_DP<8>")
	)
	(segment
		(start 416.315906 -143.1925)
		(end 416.478466 -143.35506)
		(width 0.13462)
		(layer "F.Cu")
		(net "P5E_PEX3_STN0_RX_DP<8>")
	)
	(segment
		(start 415.35731 -143.48714)
		(end 415.65195 -143.1925)
		(width 0.13462)
		(layer "F.Cu")
		(net "P5E_PEX3_STN0_RX_DP<8>")
	)
	(segment
		(start 416.478466 -143.35506)
		(end 416.95751 -143.35506)
		(width 0.13462)
		(layer "F.Cu")
		(net "P5E_PEX3_STN0_RX_DP<8>")
	)
	(segment
		(start 424.706796 -154.825954)
		(end 426.198284 -160.044384)
		(width 0.1651)
		(layer "In5.Cu")
		(net "P5E_PEX3_STN0_RX_DP<8>")
	)
	(segment
		(start 418.843206 -146.38782)
		(end 419.001194 -146.42211)
		(width 0.1651)
		(layer "In5.Cu")
		(net "P5E_PEX3_STN0_RX_DP<8>")
	)
	(segment
		(start 416.524186 -143.810482)
		(end 416.936174 -144.086072)
		(width 0.1651)
		(layer "In5.Cu")
		(net "P5E_PEX3_STN0_RX_DP<8>")
	)
	(segment
		(start 418.57549 -145.970752)
		(end 418.843206 -146.38782)
		(width 0.1651)
		(layer "In5.Cu")
		(net "P5E_PEX3_STN0_RX_DP<8>")
	)
	(segment
		(start 420.318946 -148.473922)
		(end 420.586408 -148.890482)
		(width 0.1651)
		(layer "In5.Cu")
		(net "P5E_PEX3_STN0_RX_DP<8>")
	)
	(segment
		(start 419.66007 -147.448016)
		(end 419.927532 -147.864576)
		(width 0.1651)
		(layer "In5.Cu")
		(net "P5E_PEX3_STN0_RX_DP<8>")
	)
	(segment
		(start 419.001194 -146.42211)
		(end 419.268656 -146.83867)
		(width 0.1651)
		(layer "In5.Cu")
		(net "P5E_PEX3_STN0_RX_DP<8>")
	)
	(segment
		(start 419.234366 -146.996658)
		(end 419.502082 -147.413726)
		(width 0.1651)
		(layer "In5.Cu")
		(net "P5E_PEX3_STN0_RX_DP<8>")
	)
	(segment
		(start 419.502082 -147.413726)
		(end 419.66007 -147.448016)
		(width 0.1651)
		(layer "In5.Cu")
		(net "P5E_PEX3_STN0_RX_DP<8>")
	)
	(segment
		(start 419.927532 -147.864576)
		(end 419.893242 -148.022564)
		(width 0.1651)
		(layer "In5.Cu")
		(net "P5E_PEX3_STN0_RX_DP<8>")
	)
	(segment
		(start 430.61001 -271.552162)
		(end 430.61001 -272.075402)
		(width 0.1651)
		(layer "In5.Cu")
		(net "P5E_PEX3_STN0_RX_DP<8>")
	)
	(segment
		(start 430.179734 -274.885404)
		(end 430.065434 -274.999704)
		(width 0.1143)
		(layer "In5.Cu")
		(net "P5E_PEX3_STN0_RX_DP<8>")
	)
	(segment
		(start 416.49269 -143.651986)
		(end 416.524186 -143.810482)
		(width 0.1651)
		(layer "In5.Cu")
		(net "P5E_PEX3_STN0_RX_DP<8>")
	)
	(segment
		(start 419.893242 -148.022564)
		(end 420.160958 -148.439632)
		(width 0.1651)
		(layer "In5.Cu")
		(net "P5E_PEX3_STN0_RX_DP<8>")
	)
	(segment
		(start 423.363644 -153.018744)
		(end 424.706796 -154.825954)
		(width 0.1651)
		(layer "In5.Cu")
		(net "P5E_PEX3_STN0_RX_DP<8>")
	)
	(segment
		(start 420.95039 -149.457156)
		(end 421.311832 -150.020528)
		(width 0.1651)
		(layer "In5.Cu")
		(net "P5E_PEX3_STN0_RX_DP<8>")
	)
	(segment
		(start 420.827454 -149.430486)
		(end 420.95039 -149.457156)
		(width 0.1651)
		(layer "In5.Cu")
		(net "P5E_PEX3_STN0_RX_DP<8>")
	)
	(segment
		(start 418.60978 -145.812764)
		(end 418.57549 -145.970752)
		(width 0.1651)
		(layer "In5.Cu")
		(net "P5E_PEX3_STN0_RX_DP<8>")
	)
	(segment
		(start 429.903636 -265.22934)
		(end 430.563274 -270.778986)
		(width 0.1651)
		(layer "In5.Cu")
		(net "P5E_PEX3_STN0_RX_DP<8>")
	)
	(segment
		(start 419.268656 -146.83867)
		(end 419.234366 -146.996658)
		(width 0.1651)
		(layer "In5.Cu")
		(net "P5E_PEX3_STN0_RX_DP<8>")
	)
	(segment
		(start 415.35731 -143.48714)
		(end 415.64814 -143.19631)
		(width 0.1651)
		(layer "In5.Cu")
		(net "P5E_PEX3_STN0_RX_DP<8>")
	)
	(segment
		(start 417.770818 -144.506188)
		(end 418.60978 -145.812764)
		(width 0.1651)
		(layer "In5.Cu")
		(net "P5E_PEX3_STN0_RX_DP<8>")
	)
	(segment
		(start 420.586408 -148.890482)
		(end 420.559738 -149.013418)
		(width 0.1651)
		(layer "In5.Cu")
		(net "P5E_PEX3_STN0_RX_DP<8>")
	)
	(segment
		(start 430.61001 -272.10385)
		(end 430.65573 -272.14957)
		(width 0.1143)
		(layer "In5.Cu")
		(net "P5E_PEX3_STN0_RX_DP<8>")
	)
	(segment
		(start 430.179734 -273.755612)
		(end 430.179734 -274.885404)
		(width 0.1143)
		(layer "In5.Cu")
		(net "P5E_PEX3_STN0_RX_DP<8>")
	)
	(segment
		(start 430.61001 -272.075402)
		(end 430.61001 -272.10385)
		(width 0.1143)
		(layer "In5.Cu")
		(net "P5E_PEX3_STN0_RX_DP<8>")
	)
	(segment
		(start 430.065434 -274.999704)
		(end 429.800004 -274.999704)
		(width 0.1143)
		(layer "In5.Cu")
		(net "P5E_PEX3_STN0_RX_DP<8>")
	)
	(segment
		(start 421.870632 -151.590248)
		(end 423.363644 -153.018744)
		(width 0.1651)
		(layer "In5.Cu")
		(net "P5E_PEX3_STN0_RX_DP<8>")
	)
	(segment
		(start 420.160958 -148.439632)
		(end 420.318946 -148.473922)
		(width 0.1651)
		(layer "In5.Cu")
		(net "P5E_PEX3_STN0_RX_DP<8>")
	)
	(segment
		(start 415.64814 -143.19631)
		(end 415.8107 -143.19631)
		(width 0.1651)
		(layer "In5.Cu")
		(net "P5E_PEX3_STN0_RX_DP<8>")
	)
	(segment
		(start 416.936174 -144.086072)
		(end 417.09467 -144.054322)
		(width 0.1651)
		(layer "In5.Cu")
		(net "P5E_PEX3_STN0_RX_DP<8>")
	)
	(segment
		(start 421.311832 -150.020528)
		(end 421.870632 -151.590248)
		(width 0.1651)
		(layer "In5.Cu")
		(net "P5E_PEX3_STN0_RX_DP<8>")
	)
	(segment
		(start 430.65573 -272.14957)
		(end 430.65573 -273.279616)
		(width 0.1143)
		(layer "In5.Cu")
		(net "P5E_PEX3_STN0_RX_DP<8>")
	)
	(segment
		(start 417.09467 -144.054322)
		(end 417.770818 -144.506188)
		(width 0.1651)
		(layer "In5.Cu")
		(net "P5E_PEX3_STN0_RX_DP<8>")
	)
	(segment
		(start 415.8107 -143.19631)
		(end 416.49269 -143.651986)
		(width 0.1651)
		(layer "In5.Cu")
		(net "P5E_PEX3_STN0_RX_DP<8>")
	)
	(segment
		(start 430.563274 -270.778986)
		(end 430.61001 -271.552162)
		(width 0.1651)
		(layer "In5.Cu")
		(net "P5E_PEX3_STN0_RX_DP<8>")
	)
	(segment
		(start 430.65573 -273.279616)
		(end 430.179734 -273.755612)
		(width 0.1143)
		(layer "In5.Cu")
		(net "P5E_PEX3_STN0_RX_DP<8>")
	)
	(segment
		(start 426.198284 -160.044384)
		(end 426.291502 -160.636966)
		(width 0.1651)
		(layer "In5.Cu")
		(net "P5E_PEX3_STN0_RX_DP<8>")
	)
	(segment
		(start 420.559738 -149.013418)
		(end 420.827454 -149.430486)
		(width 0.1651)
		(layer "In5.Cu")
		(net "P5E_PEX3_STN0_RX_DP<8>")
	)
	(segment
		(start 426.291502 -160.636966)
		(end 429.903636 -265.22934)
		(width 0.1651)
		(layer "In5.Cu")
		(net "P5E_PEX3_STN0_RX_DP<8>")
	)
	(segment
		(start 402.572728 -356.832154)
		(end 402.572728 -357.462582)
		(width 0.13462)
		(layer "F.Cu")
		(net "P5E_PEX3_STN5_TX_C_DP<95>")
	)
	(segment
		(start 402.572728 -357.462582)
		(end 402.27758 -357.75773)
		(width 0.13462)
		(layer "F.Cu")
		(net "P5E_PEX3_STN5_TX_C_DP<95>")
	)
	(segment
		(start 402.25218 -356.511606)
		(end 402.572728 -356.832154)
		(width 0.13462)
		(layer "F.Cu")
		(net "P5E_PEX3_STN5_TX_C_DP<95>")
	)
	(segment
		(start 402.114512 -359.418128)
		(end 394.250672 -366.491266)
		(width 0.1651)
		(layer "In13.Cu")
		(net "P5E_PEX3_STN5_TX_C_DP<95>")
	)
	(segment
		(start 390.889998 -379.772164)
		(end 390.889998 -379.390148)
		(width 0.1651)
		(layer "In13.Cu")
		(net "P5E_PEX3_STN5_TX_C_DP<95>")
	)
	(segment
		(start 391.73404 -379.612398)
		(end 391.447274 -379.899164)
		(width 0.1651)
		(layer "In13.Cu")
		(net "P5E_PEX3_STN5_TX_C_DP<95>")
	)
	(segment
		(start 402.27758 -357.75773)
		(end 402.56841 -358.04856)
		(width 0.1651)
		(layer "In13.Cu")
		(net "P5E_PEX3_STN5_TX_C_DP<95>")
	)
	(segment
		(start 402.56841 -358.04856)
		(end 402.56841 -358.400096)
		(width 0.1651)
		(layer "In13.Cu")
		(net "P5E_PEX3_STN5_TX_C_DP<95>")
	)
	(segment
		(start 394.250672 -366.491266)
		(end 394.142976 -366.485678)
		(width 0.1651)
		(layer "In13.Cu")
		(net "P5E_PEX3_STN5_TX_C_DP<95>")
	)
	(segment
		(start 391.016998 -379.899164)
		(end 390.889998 -379.772164)
		(width 0.1651)
		(layer "In13.Cu")
		(net "P5E_PEX3_STN5_TX_C_DP<95>")
	)
	(segment
		(start 391.447274 -379.899164)
		(end 391.016998 -379.899164)
		(width 0.1651)
		(layer "In13.Cu")
		(net "P5E_PEX3_STN5_TX_C_DP<95>")
	)
	(segment
		(start 394.142976 -366.485678)
		(end 393.774422 -366.817148)
		(width 0.1651)
		(layer "In13.Cu")
		(net "P5E_PEX3_STN5_TX_C_DP<95>")
	)
	(segment
		(start 391.73404 -369.80241)
		(end 391.73404 -379.612398)
		(width 0.1651)
		(layer "In13.Cu")
		(net "P5E_PEX3_STN5_TX_C_DP<95>")
	)
	(segment
		(start 393.774422 -366.817148)
		(end 393.768834 -366.924844)
		(width 0.1651)
		(layer "In13.Cu")
		(net "P5E_PEX3_STN5_TX_C_DP<95>")
	)
	(segment
		(start 402.56841 -358.400096)
		(end 402.114512 -359.418128)
		(width 0.1651)
		(layer "In13.Cu")
		(net "P5E_PEX3_STN5_TX_C_DP<95>")
	)
	(segment
		(start 392.512804 -368.054382)
		(end 391.73404 -369.80241)
		(width 0.1651)
		(layer "In13.Cu")
		(net "P5E_PEX3_STN5_TX_C_DP<95>")
	)
	(segment
		(start 393.768834 -366.924844)
		(end 392.512804 -368.054382)
		(width 0.1651)
		(layer "In13.Cu")
		(net "P5E_PEX3_STN5_TX_C_DP<95>")
	)
	(segment
		(start 73.257664 -97.039938)
		(end 75.107546 -97.039938)
		(width 0.13208)
		(layer "F.Cu")
		(net "PWRGD_NIC1_PWR_GOOD")
	)
	(via
		(at 75.107546 -97.039938)
		(size 0.508)
		(drill 0.254)
		(layers "F.Cu" "B.Cu")
		(net "PWRGD_NIC1_PWR_GOOD")
	)
	(segment
		(start 71.35495 -96.79305)
		(end 71.755 -96.393)
		(width 0.13208)
		(layer "B.Cu")
		(net "PWRGD_NIC1_PWR_GOOD")
	)
	(segment
		(start 74.460608 -96.393)
		(end 75.107546 -97.039938)
		(width 0.13208)
		(layer "B.Cu")
		(net "PWRGD_NIC1_PWR_GOOD")
	)
	(segment
		(start 71.35495 -97.663)
		(end 71.35495 -96.79305)
		(width 0.13208)
		(layer "B.Cu")
		(net "PWRGD_NIC1_PWR_GOOD")
	)
	(segment
		(start 71.755 -96.393)
		(end 74.460608 -96.393)
		(width 0.13208)
		(layer "B.Cu")
		(net "PWRGD_NIC1_PWR_GOOD")
	)
	(segment
		(start 70.50405 -97.663)
		(end 71.35495 -97.663)
		(width 0.13208)
		(layer "B.Cu")
		(net "PWRGD_NIC1_PWR_GOOD")
	)
	(segment
		(start 275.20392 -156.481526)
		(end 275.725382 -155.960064)
		(width 0.13208)
		(layer "F.Cu")
		(net "NIC4_DATA_OUT")
	)
	(segment
		(start 275.725382 -155.960064)
		(end 278.242268 -155.960064)
		(width 0.13208)
		(layer "F.Cu")
		(net "NIC4_DATA_OUT")
	)
	(segment
		(start 271.721326 -156.481526)
		(end 272.39341 -156.481526)
		(width 0.13208)
		(layer "F.Cu")
		(net "NIC4_DATA_OUT")
	)
	(segment
		(start 271.207992 -156.3624)
		(end 271.6022 -156.3624)
		(width 0.13208)
		(layer "F.Cu")
		(net "NIC4_DATA_OUT")
	)
	(segment
		(start 271.6022 -156.3624)
		(end 271.721326 -156.481526)
		(width 0.13208)
		(layer "F.Cu")
		(net "NIC4_DATA_OUT")
	)
	(segment
		(start 272.39341 -156.481526)
		(end 275.20392 -156.481526)
		(width 0.13208)
		(layer "F.Cu")
		(net "NIC4_DATA_OUT")
	)
	(via
		(at 272.39341 -156.481526)
		(size 0.762)
		(drill 0.381)
		(layers "F.Cu" "B.Cu")
		(net "NIC4_DATA_OUT")
	)
	(segment
		(start 51.293268 -105.007918)
		(end 51.130454 -104.845104)
		(width 0.13462)
		(layer "F.Cu")
		(net "P5E_PEX0_STN1_RX_DP<19>")
	)
	(segment
		(start 52.24272 -104.713024)
		(end 51.947826 -105.007918)
		(width 0.13462)
		(layer "F.Cu")
		(net "P5E_PEX0_STN1_RX_DP<19>")
	)
	(segment
		(start 51.947826 -105.007918)
		(end 51.293268 -105.007918)
		(width 0.13462)
		(layer "F.Cu")
		(net "P5E_PEX0_STN1_RX_DP<19>")
	)
	(segment
		(start 51.130454 -104.845104)
		(end 50.64252 -104.845104)
		(width 0.13462)
		(layer "F.Cu")
		(net "P5E_PEX0_STN1_RX_DP<19>")
	)
	(segment
		(start 52.24272 -104.71277)
		(end 52.24272 -104.713024)
		(width 0.13462)
		(layer "F.Cu")
		(net "P5E_PEX0_STN1_RX_DP<19>")
	)
	(segment
		(start 51.40325 -105.0036)
		(end 45.034454 -108.444538)
		(width 0.1651)
		(layer "In5.Cu")
		(net "P5E_PEX0_STN1_RX_DP<19>")
	)
	(segment
		(start 31.384748 -154.627072)
		(end 31.516066 -156.689806)
		(width 0.1651)
		(layer "In5.Cu")
		(net "P5E_PEX0_STN1_RX_DP<19>")
	)
	(segment
		(start 61.883798 -271.773904)
		(end 61.883798 -271.802352)
		(width 0.1143)
		(layer "In5.Cu")
		(net "P5E_PEX0_STN1_RX_DP<19>")
	)
	(segment
		(start 31.516066 -156.69006)
		(end 31.648654 -158.768034)
		(width 0.1651)
		(layer "In5.Cu")
		(net "P5E_PEX0_STN1_RX_DP<19>")
	)
	(segment
		(start 61.929518 -275.355304)
		(end 62.144402 -275.570188)
		(width 0.1143)
		(layer "In5.Cu")
		(net "P5E_PEX0_STN1_RX_DP<19>")
	)
	(segment
		(start 34.149284 -121.856246)
		(end 33.40354 -122.76328)
		(width 0.1651)
		(layer "In5.Cu")
		(net "P5E_PEX0_STN1_RX_DP<19>")
	)
	(segment
		(start 31.516066 -156.689806)
		(end 31.515812 -156.689806)
		(width 0.1651)
		(layer "In5.Cu")
		(net "P5E_PEX0_STN1_RX_DP<19>")
	)
	(segment
		(start 51.95189 -105.0036)
		(end 51.40325 -105.0036)
		(width 0.1651)
		(layer "In5.Cu")
		(net "P5E_PEX0_STN1_RX_DP<19>")
	)
	(segment
		(start 32.723836 -126.351538)
		(end 31.120588 -150.48357)
		(width 0.1651)
		(layer "In5.Cu")
		(net "P5E_PEX0_STN1_RX_DP<19>")
	)
	(segment
		(start 62.385194 -275.570188)
		(end 62.499494 -275.684488)
		(width 0.1143)
		(layer "In5.Cu")
		(net "P5E_PEX0_STN1_RX_DP<19>")
	)
	(segment
		(start 61.883798 -271.802352)
		(end 61.929518 -271.848072)
		(width 0.1143)
		(layer "In5.Cu")
		(net "P5E_PEX0_STN1_RX_DP<19>")
	)
	(segment
		(start 31.384494 -154.627072)
		(end 31.384748 -154.627072)
		(width 0.1651)
		(layer "In5.Cu")
		(net "P5E_PEX0_STN1_RX_DP<19>")
	)
	(segment
		(start 45.034454 -108.444538)
		(end 40.658034 -112.68202)
		(width 0.1651)
		(layer "In5.Cu")
		(net "P5E_PEX0_STN1_RX_DP<19>")
	)
	(segment
		(start 32.749998 -165.18255)
		(end 61.883798 -269.528544)
		(width 0.1651)
		(layer "In5.Cu")
		(net "P5E_PEX0_STN1_RX_DP<19>")
	)
	(segment
		(start 31.515812 -156.689806)
		(end 31.516066 -156.69006)
		(width 0.1651)
		(layer "In5.Cu")
		(net "P5E_PEX0_STN1_RX_DP<19>")
	)
	(segment
		(start 31.648654 -158.768034)
		(end 32.749998 -165.18255)
		(width 0.1651)
		(layer "In5.Cu")
		(net "P5E_PEX0_STN1_RX_DP<19>")
	)
	(segment
		(start 61.929518 -271.848072)
		(end 61.929518 -275.355304)
		(width 0.1143)
		(layer "In5.Cu")
		(net "P5E_PEX0_STN1_RX_DP<19>")
	)
	(segment
		(start 62.499494 -275.684488)
		(end 62.499494 -275.949918)
		(width 0.1143)
		(layer "In5.Cu")
		(net "P5E_PEX0_STN1_RX_DP<19>")
	)
	(segment
		(start 62.144402 -275.570188)
		(end 62.385194 -275.570188)
		(width 0.1143)
		(layer "In5.Cu")
		(net "P5E_PEX0_STN1_RX_DP<19>")
	)
	(segment
		(start 37.496496 -119.163592)
		(end 36.185094 -120.760236)
		(width 0.1651)
		(layer "In5.Cu")
		(net "P5E_PEX0_STN1_RX_DP<19>")
	)
	(segment
		(start 31.120588 -150.48357)
		(end 31.384494 -154.627072)
		(width 0.1651)
		(layer "In5.Cu")
		(net "P5E_PEX0_STN1_RX_DP<19>")
	)
	(segment
		(start 61.883798 -269.528544)
		(end 61.883798 -271.773904)
		(width 0.1651)
		(layer "In5.Cu")
		(net "P5E_PEX0_STN1_RX_DP<19>")
	)
	(segment
		(start 40.658034 -112.68202)
		(end 37.496496 -119.163592)
		(width 0.1651)
		(layer "In5.Cu")
		(net "P5E_PEX0_STN1_RX_DP<19>")
	)
	(segment
		(start 33.40354 -122.76328)
		(end 32.723836 -126.351538)
		(width 0.1651)
		(layer "In5.Cu")
		(net "P5E_PEX0_STN1_RX_DP<19>")
	)
	(segment
		(start 52.24272 -104.71277)
		(end 51.95189 -105.0036)
		(width 0.1651)
		(layer "In5.Cu")
		(net "P5E_PEX0_STN1_RX_DP<19>")
	)
	(segment
		(start 36.185094 -120.760236)
		(end 34.149284 -121.856246)
		(width 0.1651)
		(layer "In5.Cu")
		(net "P5E_PEX0_STN1_RX_DP<19>")
	)
	(segment
		(start 161.654236 -108.445046)
		(end 162.14217 -108.445046)
		(width 0.13462)
		(layer "F.Cu")
		(net "P5E_PEX1_STN1_TX_C_DN<21>")
	)
	(segment
		(start 153.317448 -108.60786)
		(end 161.491422 -108.60786)
		(width 0.13462)
		(layer "F.Cu")
		(net "P5E_PEX1_STN1_TX_C_DN<21>")
	)
	(segment
		(start 153.005028 -108.29544)
		(end 153.317448 -108.60786)
		(width 0.13462)
		(layer "F.Cu")
		(net "P5E_PEX1_STN1_TX_C_DN<21>")
	)
	(segment
		(start 161.491422 -108.60786)
		(end 161.654236 -108.445046)
		(width 0.13462)
		(layer "F.Cu")
		(net "P5E_PEX1_STN1_TX_C_DN<21>")
	)
	(segment
		(start 293.5605 -28.55468)
		(end 293.26459 -28.25877)
		(width 0.13462)
		(layer "F.Cu")
		(net "P5E_PEX2_STN2_RX_DN<36>")
	)
	(segment
		(start 294.219376 -28.55468)
		(end 293.5605 -28.55468)
		(width 0.13462)
		(layer "F.Cu")
		(net "P5E_PEX2_STN2_RX_DN<36>")
	)
	(segment
		(start 294.383968 -28.390088)
		(end 294.219376 -28.55468)
		(width 0.13462)
		(layer "F.Cu")
		(net "P5E_PEX2_STN2_RX_DN<36>")
	)
	(segment
		(start 294.86479 -28.390088)
		(end 294.383968 -28.390088)
		(width 0.13462)
		(layer "F.Cu")
		(net "P5E_PEX2_STN2_RX_DN<36>")
	)
	(segment
		(start 286.719772 -275.275802)
		(end 286.823658 -275.379688)
		(width 0.1143)
		(layer "In7.Cu")
		(net "P5E_PEX2_STN2_RX_DN<36>")
	)
	(segment
		(start 293.26459 -28.25877)
		(end 293.557706 -28.551886)
		(width 0.1651)
		(layer "In7.Cu")
		(net "P5E_PEX2_STN2_RX_DN<36>")
	)
	(segment
		(start 297.483022 -48.834802)
		(end 297.283632 -68.374514)
		(width 0.1651)
		(layer "In7.Cu")
		(net "P5E_PEX2_STN2_RX_DN<36>")
	)
	(segment
		(start 286.765492 -271.421352)
		(end 286.719772 -271.467072)
		(width 0.1143)
		(layer "In7.Cu")
		(net "P5E_PEX2_STN2_RX_DN<36>")
	)
	(segment
		(start 293.557706 -28.551886)
		(end 293.563548 -28.5496)
		(width 0.1651)
		(layer "In7.Cu")
		(net "P5E_PEX2_STN2_RX_DN<36>")
	)
	(segment
		(start 286.719772 -271.467072)
		(end 286.719772 -275.275802)
		(width 0.1143)
		(layer "In7.Cu")
		(net "P5E_PEX2_STN2_RX_DN<36>")
	)
	(segment
		(start 286.985456 -275.379688)
		(end 287.099756 -275.265388)
		(width 0.1143)
		(layer "In7.Cu")
		(net "P5E_PEX2_STN2_RX_DN<36>")
	)
	(segment
		(start 286.899604 -264.972038)
		(end 286.765492 -266.499848)
		(width 0.1651)
		(layer "In7.Cu")
		(net "P5E_PEX2_STN2_RX_DN<36>")
	)
	(segment
		(start 294.00373 -28.5496)
		(end 296.902632 -31.448502)
		(width 0.1651)
		(layer "In7.Cu")
		(net "P5E_PEX2_STN2_RX_DN<36>")
	)
	(segment
		(start 299.50664 -39.169594)
		(end 297.483022 -48.834802)
		(width 0.1651)
		(layer "In7.Cu")
		(net "P5E_PEX2_STN2_RX_DN<36>")
	)
	(segment
		(start 293.563548 -28.5496)
		(end 294.00373 -28.5496)
		(width 0.1651)
		(layer "In7.Cu")
		(net "P5E_PEX2_STN2_RX_DN<36>")
	)
	(segment
		(start 299.531278 -37.688012)
		(end 299.50664 -39.169594)
		(width 0.1651)
		(layer "In7.Cu")
		(net "P5E_PEX2_STN2_RX_DN<36>")
	)
	(segment
		(start 286.765492 -271.392904)
		(end 286.765492 -271.421352)
		(width 0.1143)
		(layer "In7.Cu")
		(net "P5E_PEX2_STN2_RX_DN<36>")
	)
	(segment
		(start 297.283632 -68.374514)
		(end 286.899604 -264.972038)
		(width 0.1651)
		(layer "In7.Cu")
		(net "P5E_PEX2_STN2_RX_DN<36>")
	)
	(segment
		(start 287.099756 -275.265388)
		(end 287.099756 -274.999958)
		(width 0.1143)
		(layer "In7.Cu")
		(net "P5E_PEX2_STN2_RX_DN<36>")
	)
	(segment
		(start 286.823658 -275.379688)
		(end 286.985456 -275.379688)
		(width 0.1143)
		(layer "In7.Cu")
		(net "P5E_PEX2_STN2_RX_DN<36>")
	)
	(segment
		(start 296.902632 -31.448502)
		(end 299.531278 -37.688012)
		(width 0.1651)
		(layer "In7.Cu")
		(net "P5E_PEX2_STN2_RX_DN<36>")
	)
	(segment
		(start 286.765492 -266.499848)
		(end 286.765492 -271.392904)
		(width 0.1651)
		(layer "In7.Cu")
		(net "P5E_PEX2_STN2_RX_DN<36>")
	)
	(segment
		(start 416.31489 -135.88492)
		(end 416.47491 -136.04494)
		(width 0.13462)
		(layer "F.Cu")
		(net "P5E_PEX3_STN0_RX_DP<7>")
	)
	(segment
		(start 416.47491 -136.04494)
		(end 416.95751 -136.04494)
		(width 0.13462)
		(layer "F.Cu")
		(net "P5E_PEX3_STN0_RX_DP<7>")
	)
	(segment
		(start 413.50311 -136.177274)
		(end 413.795464 -135.88492)
		(width 0.13462)
		(layer "F.Cu")
		(net "P5E_PEX3_STN0_RX_DP<7>")
	)
	(segment
		(start 413.795464 -135.88492)
		(end 416.31489 -135.88492)
		(width 0.13462)
		(layer "F.Cu")
		(net "P5E_PEX3_STN0_RX_DP<7>")
	)
	(segment
		(start 430.852834 -264.857484)
		(end 431.506376 -269.468854)
		(width 0.1651)
		(layer "In5.Cu")
		(net "P5E_PEX3_STN0_RX_DP<7>")
	)
	(segment
		(start 422.02481 -140.697204)
		(end 422.896284 -141.568678)
		(width 0.1651)
		(layer "In5.Cu")
		(net "P5E_PEX3_STN0_RX_DP<7>")
	)
	(segment
		(start 432.7779 -276.331172)
		(end 432.691286 -280.407364)
		(width 0.1651)
		(layer "In5.Cu")
		(net "P5E_PEX3_STN0_RX_DP<7>")
	)
	(segment
		(start 432.691286 -280.407364)
		(end 432.460654 -280.94559)
		(width 0.1651)
		(layer "In5.Cu")
		(net "P5E_PEX3_STN0_RX_DP<7>")
	)
	(segment
		(start 422.896284 -141.568678)
		(end 423.040302 -141.814042)
		(width 0.1651)
		(layer "In5.Cu")
		(net "P5E_PEX3_STN0_RX_DP<7>")
	)
	(segment
		(start 420.801546 -138.50239)
		(end 420.927276 -138.503406)
		(width 0.1651)
		(layer "In5.Cu")
		(net "P5E_PEX3_STN0_RX_DP<7>")
	)
	(segment
		(start 420.106602 -137.671302)
		(end 420.454328 -138.023854)
		(width 0.1651)
		(layer "In5.Cu")
		(net "P5E_PEX3_STN0_RX_DP<7>")
	)
	(segment
		(start 417.045648 -136.426448)
		(end 417.504372 -136.612884)
		(width 0.1651)
		(layer "In5.Cu")
		(net "P5E_PEX3_STN0_RX_DP<7>")
	)
	(segment
		(start 418.63391 -137.07237)
		(end 418.682678 -137.188194)
		(width 0.1651)
		(layer "In5.Cu")
		(net "P5E_PEX3_STN0_RX_DP<7>")
	)
	(segment
		(start 432.250088 -281.033982)
		(end 432.22164 -281.033982)
		(width 0.1143)
		(layer "In5.Cu")
		(net "P5E_PEX3_STN0_RX_DP<7>")
	)
	(segment
		(start 423.708576 -145.2626)
		(end 423.845482 -145.348706)
		(width 0.1651)
		(layer "In5.Cu")
		(net "P5E_PEX3_STN0_RX_DP<7>")
	)
	(segment
		(start 423.327576 -143.590518)
		(end 423.437558 -144.073626)
		(width 0.1651)
		(layer "In5.Cu")
		(net "P5E_PEX3_STN0_RX_DP<7>")
	)
	(segment
		(start 419.257734 -137.326116)
		(end 420.106602 -137.671302)
		(width 0.1651)
		(layer "In5.Cu")
		(net "P5E_PEX3_STN0_RX_DP<7>")
	)
	(segment
		(start 418.175186 -136.885934)
		(end 418.63391 -137.07237)
		(width 0.1651)
		(layer "In5.Cu")
		(net "P5E_PEX3_STN0_RX_DP<7>")
	)
	(segment
		(start 420.927276 -138.503406)
		(end 421.34409 -138.926062)
		(width 0.1651)
		(layer "In5.Cu")
		(net "P5E_PEX3_STN0_RX_DP<7>")
	)
	(segment
		(start 423.437558 -144.073626)
		(end 423.574718 -144.159732)
		(width 0.1651)
		(layer "In5.Cu")
		(net "P5E_PEX3_STN0_RX_DP<7>")
	)
	(segment
		(start 420.453312 -138.149584)
		(end 420.801546 -138.50239)
		(width 0.1651)
		(layer "In5.Cu")
		(net "P5E_PEX3_STN0_RX_DP<7>")
	)
	(segment
		(start 427.298866 -160.51276)
		(end 430.852834 -264.857484)
		(width 0.1651)
		(layer "In5.Cu")
		(net "P5E_PEX3_STN0_RX_DP<7>")
	)
	(segment
		(start 424.116246 -146.53768)
		(end 427.298612 -160.511744)
		(width 0.1651)
		(layer "In5.Cu")
		(net "P5E_PEX3_STN0_RX_DP<7>")
	)
	(segment
		(start 421.705532 -139.540996)
		(end 421.705532 -139.926568)
		(width 0.1651)
		(layer "In5.Cu")
		(net "P5E_PEX3_STN0_RX_DP<7>")
	)
	(segment
		(start 432.372008 -281.033982)
		(end 432.250088 -281.033982)
		(width 0.1651)
		(layer "In5.Cu")
		(net "P5E_PEX3_STN0_RX_DP<7>")
	)
	(segment
		(start 416.374834 -136.153398)
		(end 416.437572 -136.30275)
		(width 0.1651)
		(layer "In5.Cu")
		(net "P5E_PEX3_STN0_RX_DP<7>")
	)
	(segment
		(start 423.684192 -144.64157)
		(end 423.684446 -144.642586)
		(width 0.1651)
		(layer "In5.Cu")
		(net "P5E_PEX3_STN0_RX_DP<7>")
	)
	(segment
		(start 432.460654 -280.94559)
		(end 432.372008 -281.033982)
		(width 0.1651)
		(layer "In5.Cu")
		(net "P5E_PEX3_STN0_RX_DP<7>")
	)
	(segment
		(start 415.71799 -135.886444)
		(end 416.374834 -136.153652)
		(width 0.1651)
		(layer "In5.Cu")
		(net "P5E_PEX3_STN0_RX_DP<7>")
	)
	(segment
		(start 423.598594 -144.779492)
		(end 423.708576 -145.2626)
		(width 0.1651)
		(layer "In5.Cu")
		(net "P5E_PEX3_STN0_RX_DP<7>")
	)
	(segment
		(start 423.954956 -145.830544)
		(end 423.95521 -145.83156)
		(width 0.1651)
		(layer "In5.Cu")
		(net "P5E_PEX3_STN0_RX_DP<7>")
	)
	(segment
		(start 421.705532 -139.926568)
		(end 422.02481 -140.697204)
		(width 0.1651)
		(layer "In5.Cu")
		(net "P5E_PEX3_STN0_RX_DP<7>")
	)
	(segment
		(start 413.79394 -135.886444)
		(end 415.71799 -135.886444)
		(width 0.1651)
		(layer "In5.Cu")
		(net "P5E_PEX3_STN0_RX_DP<7>")
	)
	(segment
		(start 432.22164 -281.033982)
		(end 432.17592 -281.079702)
		(width 0.1143)
		(layer "In5.Cu")
		(net "P5E_PEX3_STN0_RX_DP<7>")
	)
	(segment
		(start 430.179734 -281.29484)
		(end 430.179734 -281.535632)
		(width 0.1143)
		(layer "In5.Cu")
		(net "P5E_PEX3_STN0_RX_DP<7>")
	)
	(segment
		(start 421.34409 -138.926062)
		(end 421.705532 -139.540996)
		(width 0.1651)
		(layer "In5.Cu")
		(net "P5E_PEX3_STN0_RX_DP<7>")
	)
	(segment
		(start 418.026088 -136.948672)
		(end 418.175186 -136.885934)
		(width 0.1651)
		(layer "In5.Cu")
		(net "P5E_PEX3_STN0_RX_DP<7>")
	)
	(segment
		(start 420.454328 -138.023854)
		(end 420.453312 -138.149584)
		(width 0.1651)
		(layer "In5.Cu")
		(net "P5E_PEX3_STN0_RX_DP<7>")
	)
	(segment
		(start 423.869358 -145.968466)
		(end 423.97934 -146.451574)
		(width 0.1651)
		(layer "In5.Cu")
		(net "P5E_PEX3_STN0_RX_DP<7>")
	)
	(segment
		(start 416.437572 -136.30275)
		(end 416.896804 -136.489186)
		(width 0.1651)
		(layer "In5.Cu")
		(net "P5E_PEX3_STN0_RX_DP<7>")
	)
	(segment
		(start 413.50311 -136.177274)
		(end 413.79394 -135.886444)
		(width 0.1651)
		(layer "In5.Cu")
		(net "P5E_PEX3_STN0_RX_DP<7>")
	)
	(segment
		(start 431.506376 -269.468854)
		(end 432.7779 -276.331172)
		(width 0.1651)
		(layer "In5.Cu")
		(net "P5E_PEX3_STN0_RX_DP<7>")
	)
	(segment
		(start 418.682678 -137.188194)
		(end 419.14191 -137.375138)
		(width 0.1651)
		(layer "In5.Cu")
		(net "P5E_PEX3_STN0_RX_DP<7>")
	)
	(segment
		(start 427.298612 -160.511744)
		(end 427.298866 -160.51276)
		(width 0.1651)
		(layer "In5.Cu")
		(net "P5E_PEX3_STN0_RX_DP<7>")
	)
	(segment
		(start 423.845482 -145.348706)
		(end 423.954956 -145.830544)
		(width 0.1651)
		(layer "In5.Cu")
		(net "P5E_PEX3_STN0_RX_DP<7>")
	)
	(segment
		(start 419.14191 -137.375138)
		(end 419.257734 -137.326116)
		(width 0.1651)
		(layer "In5.Cu")
		(net "P5E_PEX3_STN0_RX_DP<7>")
	)
	(segment
		(start 430.065434 -281.649932)
		(end 429.800004 -281.649932)
		(width 0.1143)
		(layer "In5.Cu")
		(net "P5E_PEX3_STN0_RX_DP<7>")
	)
	(segment
		(start 423.97934 -146.451574)
		(end 424.116246 -146.53768)
		(width 0.1651)
		(layer "In5.Cu")
		(net "P5E_PEX3_STN0_RX_DP<7>")
	)
	(segment
		(start 423.574718 -144.159732)
		(end 423.684192 -144.64157)
		(width 0.1651)
		(layer "In5.Cu")
		(net "P5E_PEX3_STN0_RX_DP<7>")
	)
	(segment
		(start 423.95521 -145.83156)
		(end 423.869358 -145.968466)
		(width 0.1651)
		(layer "In5.Cu")
		(net "P5E_PEX3_STN0_RX_DP<7>")
	)
	(segment
		(start 417.56711 -136.761982)
		(end 418.026088 -136.948672)
		(width 0.1651)
		(layer "In5.Cu")
		(net "P5E_PEX3_STN0_RX_DP<7>")
	)
	(segment
		(start 423.413682 -143.453612)
		(end 423.327576 -143.590518)
		(width 0.1651)
		(layer "In5.Cu")
		(net "P5E_PEX3_STN0_RX_DP<7>")
	)
	(segment
		(start 417.504372 -136.612884)
		(end 417.56711 -136.761982)
		(width 0.1651)
		(layer "In5.Cu")
		(net "P5E_PEX3_STN0_RX_DP<7>")
	)
	(segment
		(start 423.684446 -144.642586)
		(end 423.598594 -144.779492)
		(width 0.1651)
		(layer "In5.Cu")
		(net "P5E_PEX3_STN0_RX_DP<7>")
	)
	(segment
		(start 423.040302 -141.814042)
		(end 423.413682 -143.453612)
		(width 0.1651)
		(layer "In5.Cu")
		(net "P5E_PEX3_STN0_RX_DP<7>")
	)
	(segment
		(start 432.17592 -281.079702)
		(end 430.394872 -281.079702)
		(width 0.1143)
		(layer "In5.Cu")
		(net "P5E_PEX3_STN0_RX_DP<7>")
	)
	(segment
		(start 430.179734 -281.535632)
		(end 430.065434 -281.649932)
		(width 0.1143)
		(layer "In5.Cu")
		(net "P5E_PEX3_STN0_RX_DP<7>")
	)
	(segment
		(start 430.394872 -281.079702)
		(end 430.179734 -281.29484)
		(width 0.1143)
		(layer "In5.Cu")
		(net "P5E_PEX3_STN0_RX_DP<7>")
	)
	(segment
		(start 416.374834 -136.153652)
		(end 416.374834 -136.153398)
		(width 0.1651)
		(layer "In5.Cu")
		(net "P5E_PEX3_STN0_RX_DP<7>")
	)
	(segment
		(start 416.896804 -136.489186)
		(end 417.045648 -136.426448)
		(width 0.1651)
		(layer "In5.Cu")
		(net "P5E_PEX3_STN0_RX_DP<7>")
	)
	(segment
		(start 390.596374 -394.30325)
		(end 391.147046 -393.850622)
		(width 0.1651)
		(layer "In5.Cu")
		(net "P5E_PEX3_STN5_RX_DP<86>")
	)
	(segment
		(start 412.585662 -316.229492)
		(end 412.699962 -316.115192)
		(width 0.1143)
		(layer "In5.Cu")
		(net "P5E_PEX3_STN5_RX_DP<86>")
	)
	(segment
		(start 403.755606 -363.066076)
		(end 403.864572 -363.00283)
		(width 0.1651)
		(layer "In5.Cu")
		(net "P5E_PEX3_STN5_RX_DP<86>")
	)
	(segment
		(start 397.982948 -391.019792)
		(end 399.437606 -389.825738)
		(width 0.1651)
		(layer "In5.Cu")
		(net "P5E_PEX3_STN5_RX_DP<86>")
	)
	(segment
		(start 411.480254 -326.72528)
		(end 412.084012 -323.69506)
		(width 0.1651)
		(layer "In5.Cu")
		(net "P5E_PEX3_STN5_RX_DP<86>")
	)
	(segment
		(start 412.355538 -316.229492)
		(end 412.585662 -316.229492)
		(width 0.1143)
		(layer "In5.Cu")
		(net "P5E_PEX3_STN5_RX_DP<86>")
	)
	(segment
		(start 389.23341 -397.003016)
		(end 389.565896 -396.67053)
		(width 0.1651)
		(layer "In5.Cu")
		(net "P5E_PEX3_STN5_RX_DP<86>")
	)
	(segment
		(start 400.577558 -388.119874)
		(end 401.21967 -386.208778)
		(width 0.1651)
		(layer "In5.Cu")
		(net "P5E_PEX3_STN5_RX_DP<86>")
	)
	(segment
		(start 402.55698 -367.950242)
		(end 403.393656 -364.783624)
		(width 0.1651)
		(layer "In5.Cu")
		(net "P5E_PEX3_STN5_RX_DP<86>")
	)
	(segment
		(start 388.81685 -397.003016)
		(end 389.23341 -397.003016)
		(width 0.1651)
		(layer "In5.Cu")
		(net "P5E_PEX3_STN5_RX_DP<86>")
	)
	(segment
		(start 412.084012 -319.941448)
		(end 412.084012 -319.913)
		(width 0.1143)
		(layer "In5.Cu")
		(net "P5E_PEX3_STN5_RX_DP<86>")
	)
	(segment
		(start 403.393656 -364.783624)
		(end 403.33041 -364.674912)
		(width 0.1651)
		(layer "In5.Cu")
		(net "P5E_PEX3_STN5_RX_DP<86>")
	)
	(segment
		(start 401.21967 -386.208778)
		(end 401.386294 -375.639838)
		(width 0.1651)
		(layer "In5.Cu")
		(net "P5E_PEX3_STN5_RX_DP<86>")
	)
	(segment
		(start 403.629114 -363.54512)
		(end 403.755606 -363.066076)
		(width 0.1651)
		(layer "In5.Cu")
		(net "P5E_PEX3_STN5_RX_DP<86>")
	)
	(segment
		(start 403.69236 -363.653832)
		(end 403.629114 -363.54512)
		(width 0.1651)
		(layer "In5.Cu")
		(net "P5E_PEX3_STN5_RX_DP<86>")
	)
	(segment
		(start 403.565868 -364.132622)
		(end 403.69236 -363.653832)
		(width 0.1651)
		(layer "In5.Cu")
		(net "P5E_PEX3_STN5_RX_DP<86>")
	)
	(segment
		(start 399.437606 -389.825738)
		(end 400.577558 -388.119874)
		(width 0.1651)
		(layer "In5.Cu")
		(net "P5E_PEX3_STN5_RX_DP<86>")
	)
	(segment
		(start 389.565896 -396.67053)
		(end 389.565896 -395.845284)
		(width 0.1651)
		(layer "In5.Cu")
		(net "P5E_PEX3_STN5_RX_DP<86>")
	)
	(segment
		(start 389.565896 -395.845284)
		(end 390.596374 -394.30325)
		(width 0.1651)
		(layer "In5.Cu")
		(net "P5E_PEX3_STN5_RX_DP<86>")
	)
	(segment
		(start 403.456902 -364.195868)
		(end 403.565868 -364.132622)
		(width 0.1651)
		(layer "In5.Cu")
		(net "P5E_PEX3_STN5_RX_DP<86>")
	)
	(segment
		(start 403.864318 -363.00283)
		(end 405.205438 -357.92791)
		(width 0.1651)
		(layer "In5.Cu")
		(net "P5E_PEX3_STN5_RX_DP<86>")
	)
	(segment
		(start 391.147046 -393.850622)
		(end 397.982948 -391.019792)
		(width 0.1651)
		(layer "In5.Cu")
		(net "P5E_PEX3_STN5_RX_DP<86>")
	)
	(segment
		(start 405.205438 -357.92791)
		(end 405.282654 -342.654382)
		(width 0.1651)
		(layer "In5.Cu")
		(net "P5E_PEX3_STN5_RX_DP<86>")
	)
	(segment
		(start 403.864572 -363.00283)
		(end 403.864318 -363.00283)
		(width 0.1651)
		(layer "In5.Cu")
		(net "P5E_PEX3_STN5_RX_DP<86>")
	)
	(segment
		(start 401.386294 -375.639838)
		(end 402.55698 -367.950242)
		(width 0.1651)
		(layer "In5.Cu")
		(net "P5E_PEX3_STN5_RX_DP<86>")
	)
	(segment
		(start 412.129732 -319.86728)
		(end 412.129732 -316.455298)
		(width 0.1143)
		(layer "In5.Cu")
		(net "P5E_PEX3_STN5_RX_DP<86>")
	)
	(segment
		(start 405.282654 -342.654382)
		(end 405.854408 -340.289642)
		(width 0.1651)
		(layer "In5.Cu")
		(net "P5E_PEX3_STN5_RX_DP<86>")
	)
	(segment
		(start 412.129732 -316.455298)
		(end 412.355538 -316.229492)
		(width 0.1143)
		(layer "In5.Cu")
		(net "P5E_PEX3_STN5_RX_DP<86>")
	)
	(segment
		(start 412.699962 -316.115192)
		(end 412.699962 -315.849762)
		(width 0.1143)
		(layer "In5.Cu")
		(net "P5E_PEX3_STN5_RX_DP<86>")
	)
	(segment
		(start 412.084012 -323.69506)
		(end 412.084012 -319.941448)
		(width 0.1651)
		(layer "In5.Cu")
		(net "P5E_PEX3_STN5_RX_DP<86>")
	)
	(segment
		(start 403.33041 -364.674912)
		(end 403.456902 -364.195868)
		(width 0.1651)
		(layer "In5.Cu")
		(net "P5E_PEX3_STN5_RX_DP<86>")
	)
	(segment
		(start 388.68985 -396.49019)
		(end 388.68985 -396.876016)
		(width 0.1651)
		(layer "In5.Cu")
		(net "P5E_PEX3_STN5_RX_DP<86>")
	)
	(segment
		(start 412.084012 -319.913)
		(end 412.129732 -319.86728)
		(width 0.1143)
		(layer "In5.Cu")
		(net "P5E_PEX3_STN5_RX_DP<86>")
	)
	(segment
		(start 405.854408 -340.289642)
		(end 411.480254 -326.72528)
		(width 0.1651)
		(layer "In5.Cu")
		(net "P5E_PEX3_STN5_RX_DP<86>")
	)
	(segment
		(start 388.68985 -396.876016)
		(end 388.81685 -397.003016)
		(width 0.1651)
		(layer "In5.Cu")
		(net "P5E_PEX3_STN5_RX_DP<86>")
	)
	(segment
		(start 58.595006 -98.734372)
		(end 58.595006 -99.06254)
		(width 0.13208)
		(layer "F.Cu")
		(net "NIC1_RBT_ARB_OUT")
	)
	(segment
		(start 58.72226 -99.189794)
		(end 62.923166 -99.189794)
		(width 0.13208)
		(layer "F.Cu")
		(net "NIC1_RBT_ARB_OUT")
	)
	(segment
		(start 62.923166 -99.189794)
		(end 63.173356 -99.439984)
		(width 0.13208)
		(layer "F.Cu")
		(net "NIC1_RBT_ARB_OUT")
	)
	(segment
		(start 64.309244 -99.439984)
		(end 68.65747 -99.439984)
		(width 0.13208)
		(layer "F.Cu")
		(net "NIC1_RBT_ARB_OUT")
	)
	(segment
		(start 63.173356 -99.439984)
		(end 64.309244 -99.439984)
		(width 0.13208)
		(layer "F.Cu")
		(net "NIC1_RBT_ARB_OUT")
	)
	(segment
		(start 58.595006 -99.06254)
		(end 58.72226 -99.189794)
		(width 0.13208)
		(layer "F.Cu")
		(net "NIC1_RBT_ARB_OUT")
	)
	(via
		(at 64.309244 -99.439984)
		(size 0.762)
		(drill 0.381)
		(layers "F.Cu" "B.Cu")
		(net "NIC1_RBT_ARB_OUT")
	)
	(segment
		(start 271.207992 -163.061396)
		(end 271.207992 -162.044126)
		(width 0.13208)
		(layer "F.Cu")
		(net "PWRGD_NIC4_PWR_GOOD")
	)
	(segment
		(start 274.010374 -161.501074)
		(end 277.151338 -158.36011)
		(width 0.13208)
		(layer "F.Cu")
		(net "PWRGD_NIC4_PWR_GOOD")
	)
	(segment
		(start 271.207992 -162.044126)
		(end 272.470372 -162.044126)
		(width 0.13208)
		(layer "F.Cu")
		(net "PWRGD_NIC4_PWR_GOOD")
	)
	(segment
		(start 272.472912 -162.046666)
		(end 273.018504 -161.501074)
		(width 0.13208)
		(layer "F.Cu")
		(net "PWRGD_NIC4_PWR_GOOD")
	)
	(segment
		(start 273.018504 -161.501074)
		(end 274.010374 -161.501074)
		(width 0.13208)
		(layer "F.Cu")
		(net "PWRGD_NIC4_PWR_GOOD")
	)
	(segment
		(start 277.151338 -158.36011)
		(end 278.242268 -158.36011)
		(width 0.13208)
		(layer "F.Cu")
		(net "PWRGD_NIC4_PWR_GOOD")
	)
	(segment
		(start 272.470372 -162.044126)
		(end 272.472912 -162.046666)
		(width 0.13208)
		(layer "F.Cu")
		(net "PWRGD_NIC4_PWR_GOOD")
	)
	(via
		(at 272.472912 -162.046666)
		(size 0.762)
		(drill 0.381)
		(layers "F.Cu" "B.Cu")
		(net "PWRGD_NIC4_PWR_GOOD")
	)
	(segment
		(start 39.547292 -107.403138)
		(end 39.868348 -107.082082)
		(width 0.13462)
		(layer "F.Cu")
		(net "P5E_PEX0_STN1_TX_C_DN<20>")
	)
	(segment
		(start 45.391578 -107.082082)
		(end 45.554392 -107.244896)
		(width 0.13462)
		(layer "F.Cu")
		(net "P5E_PEX0_STN1_TX_C_DN<20>")
	)
	(segment
		(start 45.554392 -107.244896)
		(end 46.042326 -107.244896)
		(width 0.13462)
		(layer "F.Cu")
		(net "P5E_PEX0_STN1_TX_C_DN<20>")
	)
	(segment
		(start 39.868348 -107.082082)
		(end 45.391578 -107.082082)
		(width 0.13462)
		(layer "F.Cu")
		(net "P5E_PEX0_STN1_TX_C_DN<20>")
	)
	(segment
		(start 167.393112 -134.3279)
		(end 169.901616 -134.3279)
		(width 0.13462)
		(layer "F.Cu")
		(net "P5E_PEX1_STN1_RX_DP<30>")
	)
	(segment
		(start 166.742364 -134.165086)
		(end 167.230298 -134.165086)
		(width 0.13462)
		(layer "F.Cu")
		(net "P5E_PEX1_STN1_RX_DP<30>")
	)
	(segment
		(start 169.901616 -134.3279)
		(end 170.196764 -134.032752)
		(width 0.13462)
		(layer "F.Cu")
		(net "P5E_PEX1_STN1_RX_DP<30>")
	)
	(segment
		(start 167.230298 -134.165086)
		(end 167.393112 -134.3279)
		(width 0.13462)
		(layer "F.Cu")
		(net "P5E_PEX1_STN1_RX_DP<30>")
	)
	(segment
		(start 158.799022 -148.044154)
		(end 159.113474 -147.389596)
		(width 0.1651)
		(layer "In5.Cu")
		(net "P5E_PEX1_STN1_RX_DP<30>")
	)
	(segment
		(start 159.70377 -146.99361)
		(end 160.06572 -146.8882)
		(width 0.1651)
		(layer "In5.Cu")
		(net "P5E_PEX1_STN1_RX_DP<30>")
	)
	(segment
		(start 188.43371 -267.270738)
		(end 160.09239 -160.767776)
		(width 0.1651)
		(layer "In5.Cu")
		(net "P5E_PEX1_STN1_RX_DP<30>")
	)
	(segment
		(start 188.433202 -271.397222)
		(end 188.43371 -271.396714)
		(width 0.1651)
		(layer "In5.Cu")
		(net "P5E_PEX1_STN1_RX_DP<30>")
	)
	(segment
		(start 165.83914 -137.06983)
		(end 165.866064 -137.042906)
		(width 0.1651)
		(layer "In5.Cu")
		(net "P5E_PEX1_STN1_RX_DP<30>")
	)
	(segment
		(start 164.097462 -144.077182)
		(end 165.00348 -143.171164)
		(width 0.1651)
		(layer "In5.Cu")
		(net "P5E_PEX1_STN1_RX_DP<30>")
	)
	(segment
		(start 162.331654 -145.741136)
		(end 162.651694 -145.262854)
		(width 0.1651)
		(layer "In5.Cu")
		(net "P5E_PEX1_STN1_RX_DP<30>")
	)
	(segment
		(start 188.43371 -271.396714)
		(end 188.43371 -267.270738)
		(width 0.1651)
		(layer "In5.Cu")
		(net "P5E_PEX1_STN1_RX_DP<30>")
	)
	(segment
		(start 159.515556 -147.087844)
		(end 159.70377 -146.99361)
		(width 0.1651)
		(layer "In5.Cu")
		(net "P5E_PEX1_STN1_RX_DP<30>")
	)
	(segment
		(start 167.079168 -134.697216)
		(end 167.981376 -134.323582)
		(width 0.1651)
		(layer "In5.Cu")
		(net "P5E_PEX1_STN1_RX_DP<30>")
	)
	(segment
		(start 160.544256 -146.8882)
		(end 161.637218 -146.435572)
		(width 0.1651)
		(layer "In5.Cu")
		(net "P5E_PEX1_STN1_RX_DP<30>")
	)
	(segment
		(start 188.47943 -271.600168)
		(end 188.43371 -271.554448)
		(width 0.1143)
		(layer "In5.Cu")
		(net "P5E_PEX1_STN1_RX_DP<30>")
	)
	(segment
		(start 189.04966 -274.049744)
		(end 189.04966 -273.784568)
		(width 0.1143)
		(layer "In5.Cu")
		(net "P5E_PEX1_STN1_RX_DP<30>")
	)
	(segment
		(start 188.43371 -271.526)
		(end 188.43371 -271.398238)
		(width 0.1651)
		(layer "In5.Cu")
		(net "P5E_PEX1_STN1_RX_DP<30>")
	)
	(segment
		(start 188.433202 -271.39773)
		(end 188.433202 -271.397222)
		(width 0.1651)
		(layer "In5.Cu")
		(net "P5E_PEX1_STN1_RX_DP<30>")
	)
	(segment
		(start 159.113474 -147.389596)
		(end 159.515556 -147.087844)
		(width 0.1651)
		(layer "In5.Cu")
		(net "P5E_PEX1_STN1_RX_DP<30>")
	)
	(segment
		(start 188.47943 -273.45513)
		(end 188.47943 -271.600168)
		(width 0.1143)
		(layer "In5.Cu")
		(net "P5E_PEX1_STN1_RX_DP<30>")
	)
	(segment
		(start 166.8907 -134.87654)
		(end 167.079168 -134.697216)
		(width 0.1651)
		(layer "In5.Cu")
		(net "P5E_PEX1_STN1_RX_DP<30>")
	)
	(segment
		(start 165.00348 -143.171164)
		(end 165.83914 -141.153642)
		(width 0.1651)
		(layer "In5.Cu")
		(net "P5E_PEX1_STN1_RX_DP<30>")
	)
	(segment
		(start 167.981376 -134.323582)
		(end 169.905934 -134.323582)
		(width 0.1651)
		(layer "In5.Cu")
		(net "P5E_PEX1_STN1_RX_DP<30>")
	)
	(segment
		(start 169.905934 -134.323582)
		(end 170.196764 -134.032752)
		(width 0.1651)
		(layer "In5.Cu")
		(net "P5E_PEX1_STN1_RX_DP<30>")
	)
	(segment
		(start 160.09239 -160.767776)
		(end 159.376364 -156.747972)
		(width 0.1651)
		(layer "In5.Cu")
		(net "P5E_PEX1_STN1_RX_DP<30>")
	)
	(segment
		(start 188.694314 -273.670014)
		(end 188.47943 -273.45513)
		(width 0.1143)
		(layer "In5.Cu")
		(net "P5E_PEX1_STN1_RX_DP<30>")
	)
	(segment
		(start 188.935106 -273.670014)
		(end 188.694314 -273.670014)
		(width 0.1143)
		(layer "In5.Cu")
		(net "P5E_PEX1_STN1_RX_DP<30>")
	)
	(segment
		(start 162.651694 -145.262854)
		(end 164.097462 -144.077182)
		(width 0.1651)
		(layer "In5.Cu")
		(net "P5E_PEX1_STN1_RX_DP<30>")
	)
	(segment
		(start 188.43371 -271.554448)
		(end 188.43371 -271.526)
		(width 0.1143)
		(layer "In5.Cu")
		(net "P5E_PEX1_STN1_RX_DP<30>")
	)
	(segment
		(start 165.83914 -141.153642)
		(end 165.83914 -137.06983)
		(width 0.1651)
		(layer "In5.Cu")
		(net "P5E_PEX1_STN1_RX_DP<30>")
	)
	(segment
		(start 188.43371 -271.398238)
		(end 188.433202 -271.39773)
		(width 0.1651)
		(layer "In5.Cu")
		(net "P5E_PEX1_STN1_RX_DP<30>")
	)
	(segment
		(start 165.866064 -137.042906)
		(end 166.8907 -134.87654)
		(width 0.1651)
		(layer "In5.Cu")
		(net "P5E_PEX1_STN1_RX_DP<30>")
	)
	(segment
		(start 161.637218 -146.435572)
		(end 162.331654 -145.741136)
		(width 0.1651)
		(layer "In5.Cu")
		(net "P5E_PEX1_STN1_RX_DP<30>")
	)
	(segment
		(start 189.04966 -273.784568)
		(end 188.935106 -273.670014)
		(width 0.1143)
		(layer "In5.Cu")
		(net "P5E_PEX1_STN1_RX_DP<30>")
	)
	(segment
		(start 160.06572 -146.8882)
		(end 160.544256 -146.8882)
		(width 0.1651)
		(layer "In5.Cu")
		(net "P5E_PEX1_STN1_RX_DP<30>")
	)
	(segment
		(start 159.376364 -156.747972)
		(end 158.799022 -148.044154)
		(width 0.1651)
		(layer "In5.Cu")
		(net "P5E_PEX1_STN1_RX_DP<30>")
	)
	(segment
		(start 294.86479 -28.99029)
		(end 294.385746 -28.99029)
		(width 0.13462)
		(layer "F.Cu")
		(net "P5E_PEX2_STN2_RX_DP<36>")
	)
	(segment
		(start 294.385746 -28.99029)
		(end 294.224456 -28.829)
		(width 0.13462)
		(layer "F.Cu")
		(net "P5E_PEX2_STN2_RX_DP<36>")
	)
	(segment
		(start 294.224456 -28.829)
		(end 293.55796 -28.829)
		(width 0.13462)
		(layer "F.Cu")
		(net "P5E_PEX2_STN2_RX_DP<36>")
	)
	(segment
		(start 293.55796 -28.829)
		(end 293.26459 -29.12237)
		(width 0.13462)
		(layer "F.Cu")
		(net "P5E_PEX2_STN2_RX_DP<36>")
	)
	(segment
		(start 294.86479 -28.990036)
		(end 294.86479 -28.99029)
		(width 0.13462)
		(layer "F.Cu")
		(net "P5E_PEX2_STN2_RX_DP<36>")
	)
	(segment
		(start 293.5097 -28.87726)
		(end 293.619936 -28.83154)
		(width 0.1651)
		(layer "In7.Cu")
		(net "P5E_PEX2_STN2_RX_DP<36>")
	)
	(segment
		(start 286.529272 -271.467072)
		(end 286.529272 -275.354796)
		(width 0.1143)
		(layer "In7.Cu")
		(net "P5E_PEX2_STN2_RX_DP<36>")
	)
	(segment
		(start 294.583104 -29.671518)
		(end 294.933624 -30.022038)
		(width 0.1651)
		(layer "In7.Cu")
		(net "P5E_PEX2_STN2_RX_DP<36>")
	)
	(segment
		(start 286.744664 -275.570188)
		(end 286.985456 -275.570188)
		(width 0.1143)
		(layer "In7.Cu")
		(net "P5E_PEX2_STN2_RX_DP<36>")
	)
	(segment
		(start 295.4274 -30.37205)
		(end 295.4274 -30.515814)
		(width 0.1651)
		(layer "In7.Cu")
		(net "P5E_PEX2_STN2_RX_DP<36>")
	)
	(segment
		(start 293.88689 -28.83154)
		(end 294.583104 -29.527754)
		(width 0.1651)
		(layer "In7.Cu")
		(net "P5E_PEX2_STN2_RX_DP<36>")
	)
	(segment
		(start 295.4274 -30.515814)
		(end 295.77792 -30.866334)
		(width 0.1651)
		(layer "In7.Cu")
		(net "P5E_PEX2_STN2_RX_DP<36>")
	)
	(segment
		(start 286.483552 -271.392904)
		(end 286.483552 -271.421352)
		(width 0.1143)
		(layer "In7.Cu")
		(net "P5E_PEX2_STN2_RX_DP<36>")
	)
	(segment
		(start 294.933624 -30.022038)
		(end 295.077388 -30.022038)
		(width 0.1651)
		(layer "In7.Cu")
		(net "P5E_PEX2_STN2_RX_DP<36>")
	)
	(segment
		(start 286.529272 -275.354796)
		(end 286.744664 -275.570188)
		(width 0.1143)
		(layer "In7.Cu")
		(net "P5E_PEX2_STN2_RX_DP<36>")
	)
	(segment
		(start 294.583104 -29.527754)
		(end 294.583104 -29.671518)
		(width 0.1651)
		(layer "In7.Cu")
		(net "P5E_PEX2_STN2_RX_DP<36>")
	)
	(segment
		(start 293.26459 -29.12237)
		(end 293.5097 -28.87726)
		(width 0.1651)
		(layer "In7.Cu")
		(net "P5E_PEX2_STN2_RX_DP<36>")
	)
	(segment
		(start 299.224954 -39.138098)
		(end 297.201336 -48.804068)
		(width 0.1651)
		(layer "In7.Cu")
		(net "P5E_PEX2_STN2_RX_DP<36>")
	)
	(segment
		(start 296.664126 -31.608776)
		(end 299.248322 -37.742622)
		(width 0.1651)
		(layer "In7.Cu")
		(net "P5E_PEX2_STN2_RX_DP<36>")
	)
	(segment
		(start 297.001692 -68.365624)
		(end 286.618172 -264.952226)
		(width 0.1651)
		(layer "In7.Cu")
		(net "P5E_PEX2_STN2_RX_DP<36>")
	)
	(segment
		(start 286.483552 -271.421352)
		(end 286.529272 -271.467072)
		(width 0.1143)
		(layer "In7.Cu")
		(net "P5E_PEX2_STN2_RX_DP<36>")
	)
	(segment
		(start 295.77792 -30.866334)
		(end 295.921684 -30.866334)
		(width 0.1651)
		(layer "In7.Cu")
		(net "P5E_PEX2_STN2_RX_DP<36>")
	)
	(segment
		(start 295.921684 -30.866334)
		(end 296.664126 -31.608776)
		(width 0.1651)
		(layer "In7.Cu")
		(net "P5E_PEX2_STN2_RX_DP<36>")
	)
	(segment
		(start 286.483552 -266.487402)
		(end 286.483552 -271.392904)
		(width 0.1651)
		(layer "In7.Cu")
		(net "P5E_PEX2_STN2_RX_DP<36>")
	)
	(segment
		(start 293.619936 -28.83154)
		(end 293.88689 -28.83154)
		(width 0.1651)
		(layer "In7.Cu")
		(net "P5E_PEX2_STN2_RX_DP<36>")
	)
	(segment
		(start 297.201336 -48.804068)
		(end 297.001692 -68.365624)
		(width 0.1651)
		(layer "In7.Cu")
		(net "P5E_PEX2_STN2_RX_DP<36>")
	)
	(segment
		(start 286.985456 -275.570188)
		(end 287.099756 -275.684488)
		(width 0.1143)
		(layer "In7.Cu")
		(net "P5E_PEX2_STN2_RX_DP<36>")
	)
	(segment
		(start 286.618172 -264.952226)
		(end 286.483552 -266.487402)
		(width 0.1651)
		(layer "In7.Cu")
		(net "P5E_PEX2_STN2_RX_DP<36>")
	)
	(segment
		(start 299.248322 -37.742622)
		(end 299.224954 -39.138098)
		(width 0.1651)
		(layer "In7.Cu")
		(net "P5E_PEX2_STN2_RX_DP<36>")
	)
	(segment
		(start 295.077388 -30.022038)
		(end 295.4274 -30.37205)
		(width 0.1651)
		(layer "In7.Cu")
		(net "P5E_PEX2_STN2_RX_DP<36>")
	)
	(segment
		(start 287.099756 -275.684488)
		(end 287.099756 -275.949918)
		(width 0.1143)
		(layer "In7.Cu")
		(net "P5E_PEX2_STN2_RX_DP<36>")
	)
	(segment
		(start 422.210992 -142.90548)
		(end 422.060624 -142.755112)
		(width 0.13462)
		(layer "F.Cu")
		(net "P5E_PEX3_STN0_TX_C_DN<8>")
	)
	(segment
		(start 428.052738 -142.590266)
		(end 427.737524 -142.90548)
		(width 0.13462)
		(layer "F.Cu")
		(net "P5E_PEX3_STN0_TX_C_DN<8>")
	)
	(segment
		(start 427.737524 -142.90548)
		(end 422.210992 -142.90548)
		(width 0.13462)
		(layer "F.Cu")
		(net "P5E_PEX3_STN0_TX_C_DN<8>")
	)
	(segment
		(start 422.060624 -142.755112)
		(end 421.557704 -142.755112)
		(width 0.13462)
		(layer "F.Cu")
		(net "P5E_PEX3_STN0_TX_C_DN<8>")
	)
	(segment
		(start 418.399976 -316.534292)
		(end 418.399976 -316.799722)
		(width 0.1143)
		(layer "In15.Cu")
		(net "P5E_PEX3_STN5_RX_DN<92>")
	)
	(segment
		(start 384.964178 -371.281198)
		(end 385.416044 -370.829332)
		(width 0.1651)
		(layer "In15.Cu")
		(net "P5E_PEX3_STN5_RX_DN<92>")
	)
	(segment
		(start 401.904962 -338.258658)
		(end 416.484054 -324.58787)
		(width 0.1651)
		(layer "In15.Cu")
		(net "P5E_PEX3_STN5_RX_DN<92>")
	)
	(segment
		(start 418.065966 -319.941448)
		(end 418.020246 -319.895728)
		(width 0.1143)
		(layer "In15.Cu")
		(net "P5E_PEX3_STN5_RX_DN<92>")
	)
	(segment
		(start 418.285676 -316.419992)
		(end 418.399976 -316.534292)
		(width 0.1143)
		(layer "In15.Cu")
		(net "P5E_PEX3_STN5_RX_DN<92>")
	)
	(segment
		(start 385.416044 -370.829332)
		(end 385.416044 -369.631214)
		(width 0.1651)
		(layer "In15.Cu")
		(net "P5E_PEX3_STN5_RX_DN<92>")
	)
	(segment
		(start 385.887468 -368.591084)
		(end 397.610838 -359.196386)
		(width 0.1651)
		(layer "In15.Cu")
		(net "P5E_PEX3_STN5_RX_DN<92>")
	)
	(segment
		(start 418.123878 -316.419992)
		(end 418.285676 -316.419992)
		(width 0.1143)
		(layer "In15.Cu")
		(net "P5E_PEX3_STN5_RX_DN<92>")
	)
	(segment
		(start 384.290062 -371.408198)
		(end 384.417062 -371.281198)
		(width 0.1651)
		(layer "In15.Cu")
		(net "P5E_PEX3_STN5_RX_DN<92>")
	)
	(segment
		(start 398.503394 -341.448898)
		(end 401.904962 -338.258912)
		(width 0.1651)
		(layer "In15.Cu")
		(net "P5E_PEX3_STN5_RX_DN<92>")
	)
	(segment
		(start 398.18691 -342.173814)
		(end 398.503394 -341.448898)
		(width 0.1651)
		(layer "In15.Cu")
		(net "P5E_PEX3_STN5_RX_DN<92>")
	)
	(segment
		(start 418.020246 -319.895728)
		(end 418.020246 -316.523624)
		(width 0.1143)
		(layer "In15.Cu")
		(net "P5E_PEX3_STN5_RX_DN<92>")
	)
	(segment
		(start 416.484054 -324.58787)
		(end 418.065966 -322.300346)
		(width 0.1651)
		(layer "In15.Cu")
		(net "P5E_PEX3_STN5_RX_DN<92>")
	)
	(segment
		(start 384.290062 -371.790214)
		(end 384.290062 -371.408198)
		(width 0.1651)
		(layer "In15.Cu")
		(net "P5E_PEX3_STN5_RX_DN<92>")
	)
	(segment
		(start 418.020246 -316.523624)
		(end 418.123878 -316.419992)
		(width 0.1143)
		(layer "In15.Cu")
		(net "P5E_PEX3_STN5_RX_DN<92>")
	)
	(segment
		(start 418.065966 -319.969896)
		(end 418.065966 -319.941448)
		(width 0.1143)
		(layer "In15.Cu")
		(net "P5E_PEX3_STN5_RX_DN<92>")
	)
	(segment
		(start 384.417062 -371.281198)
		(end 384.964178 -371.281198)
		(width 0.1651)
		(layer "In15.Cu")
		(net "P5E_PEX3_STN5_RX_DN<92>")
	)
	(segment
		(start 418.065966 -322.300346)
		(end 418.065966 -319.969896)
		(width 0.1651)
		(layer "In15.Cu")
		(net "P5E_PEX3_STN5_RX_DN<92>")
	)
	(segment
		(start 397.610838 -359.196386)
		(end 398.18691 -357.996236)
		(width 0.1651)
		(layer "In15.Cu")
		(net "P5E_PEX3_STN5_RX_DN<92>")
	)
	(segment
		(start 401.904962 -338.258912)
		(end 401.904962 -338.258658)
		(width 0.1651)
		(layer "In15.Cu")
		(net "P5E_PEX3_STN5_RX_DN<92>")
	)
	(segment
		(start 398.18691 -357.996236)
		(end 398.18691 -342.173814)
		(width 0.1651)
		(layer "In15.Cu")
		(net "P5E_PEX3_STN5_RX_DN<92>")
	)
	(segment
		(start 385.416044 -369.631214)
		(end 385.887468 -368.591084)
		(width 0.1651)
		(layer "In15.Cu")
		(net "P5E_PEX3_STN5_RX_DN<92>")
	)
	(segment
		(start 46.042326 -99.445064)
		(end 45.554392 -99.445064)
		(width 0.13462)
		(layer "F.Cu")
		(net "P5E_PEX0_STN1_TX_C_DP<16>")
	)
	(segment
		(start 45.554392 -99.445064)
		(end 45.391578 -99.607878)
		(width 0.13462)
		(layer "F.Cu")
		(net "P5E_PEX0_STN1_TX_C_DP<16>")
	)
	(segment
		(start 39.866316 -99.607878)
		(end 39.547292 -99.288854)
		(width 0.13462)
		(layer "F.Cu")
		(net "P5E_PEX0_STN1_TX_C_DP<16>")
	)
	(segment
		(start 45.391578 -99.607878)
		(end 39.866316 -99.607878)
		(width 0.13462)
		(layer "F.Cu")
		(net "P5E_PEX0_STN1_TX_C_DP<16>")
	)
	(segment
		(start 92.461842 -357.75773)
		(end 92.756482 -357.46309)
		(width 0.13462)
		(layer "F.Cu")
		(net "P5E_PEX0_STN6_TX_C_DP<96>")
	)
	(segment
		(start 92.756482 -357.46309)
		(end 92.756482 -356.831646)
		(width 0.13462)
		(layer "F.Cu")
		(net "P5E_PEX0_STN6_TX_C_DP<96>")
	)
	(segment
		(start 92.756482 -356.831646)
		(end 92.436442 -356.511606)
		(width 0.13462)
		(layer "F.Cu")
		(net "P5E_PEX0_STN6_TX_C_DP<96>")
	)
	(segment
		(start 89.231978 -366.089946)
		(end 89.286334 -366.242092)
		(width 0.1651)
		(layer "In13.Cu")
		(net "P5E_PEX0_STN6_TX_C_DP<96>")
	)
	(segment
		(start 87.43696 -383.79908)
		(end 87.30996 -383.67208)
		(width 0.1651)
		(layer "In13.Cu")
		(net "P5E_PEX0_STN6_TX_C_DP<96>")
	)
	(segment
		(start 89.596214 -365.587534)
		(end 89.444068 -365.64189)
		(width 0.1651)
		(layer "In13.Cu")
		(net "P5E_PEX0_STN6_TX_C_DP<96>")
	)
	(segment
		(start 87.964264 -383.79908)
		(end 87.43696 -383.79908)
		(width 0.1651)
		(layer "In13.Cu")
		(net "P5E_PEX0_STN6_TX_C_DP<96>")
	)
	(segment
		(start 92.752672 -358.04856)
		(end 92.752672 -358.913684)
		(width 0.1651)
		(layer "In13.Cu")
		(net "P5E_PEX0_STN6_TX_C_DP<96>")
	)
	(segment
		(start 92.752672 -358.913684)
		(end 89.596214 -365.587534)
		(width 0.1651)
		(layer "In13.Cu")
		(net "P5E_PEX0_STN6_TX_C_DP<96>")
	)
	(segment
		(start 92.461842 -357.75773)
		(end 92.752672 -358.04856)
		(width 0.1651)
		(layer "In13.Cu")
		(net "P5E_PEX0_STN6_TX_C_DP<96>")
	)
	(segment
		(start 88.202262 -368.534442)
		(end 88.202262 -383.561082)
		(width 0.1651)
		(layer "In13.Cu")
		(net "P5E_PEX0_STN6_TX_C_DP<96>")
	)
	(segment
		(start 89.444068 -365.64189)
		(end 89.231978 -366.089946)
		(width 0.1651)
		(layer "In13.Cu")
		(net "P5E_PEX0_STN6_TX_C_DP<96>")
	)
	(segment
		(start 88.202262 -383.561082)
		(end 87.964264 -383.79908)
		(width 0.1651)
		(layer "In13.Cu")
		(net "P5E_PEX0_STN6_TX_C_DP<96>")
	)
	(segment
		(start 87.30996 -383.67208)
		(end 87.30996 -383.290064)
		(width 0.1651)
		(layer "In13.Cu")
		(net "P5E_PEX0_STN6_TX_C_DP<96>")
	)
	(segment
		(start 89.286334 -366.242092)
		(end 88.202262 -368.534442)
		(width 0.1651)
		(layer "In13.Cu")
		(net "P5E_PEX0_STN6_TX_C_DP<96>")
	)
	(segment
		(start 161.491422 -134.3279)
		(end 153.324052 -134.3279)
		(width 0.13462)
		(layer "F.Cu")
		(net "P5E_PEX1_STN1_TX_C_DP<30>")
	)
	(segment
		(start 161.654236 -134.165086)
		(end 161.491422 -134.3279)
		(width 0.13462)
		(layer "F.Cu")
		(net "P5E_PEX1_STN1_TX_C_DP<30>")
	)
	(segment
		(start 153.324052 -134.3279)
		(end 153.005028 -134.008876)
		(width 0.13462)
		(layer "F.Cu")
		(net "P5E_PEX1_STN1_TX_C_DP<30>")
	)
	(segment
		(start 162.14217 -134.165086)
		(end 161.654236 -134.165086)
		(width 0.13462)
		(layer "F.Cu")
		(net "P5E_PEX1_STN1_TX_C_DP<30>")
	)
	(segment
		(start 294.225218 -32.14878)
		(end 293.554658 -32.14878)
		(width 0.13462)
		(layer "F.Cu")
		(net "P5E_PEX2_STN2_RX_DN<38>")
	)
	(segment
		(start 294.86479 -31.99003)
		(end 294.383968 -31.99003)
		(width 0.13462)
		(layer "F.Cu")
		(net "P5E_PEX2_STN2_RX_DN<38>")
	)
	(segment
		(start 294.383968 -31.99003)
		(end 294.225218 -32.14878)
		(width 0.13462)
		(layer "F.Cu")
		(net "P5E_PEX2_STN2_RX_DN<38>")
	)
	(segment
		(start 293.554658 -32.14878)
		(end 293.26459 -31.858712)
		(width 0.13462)
		(layer "F.Cu")
		(net "P5E_PEX2_STN2_RX_DN<38>")
	)
	(segment
		(start 284.819852 -271.467072)
		(end 284.865572 -271.421352)
		(width 0.1143)
		(layer "In7.Cu")
		(net "P5E_PEX2_STN2_RX_DN<38>")
	)
	(segment
		(start 294.129968 -32.149542)
		(end 293.55542 -32.149542)
		(width 0.1651)
		(layer "In7.Cu")
		(net "P5E_PEX2_STN2_RX_DN<38>")
	)
	(segment
		(start 284.865572 -271.421352)
		(end 284.865572 -271.392904)
		(width 0.1143)
		(layer "In7.Cu")
		(net "P5E_PEX2_STN2_RX_DN<38>")
	)
	(segment
		(start 284.923738 -275.379688)
		(end 284.819852 -275.275802)
		(width 0.1143)
		(layer "In7.Cu")
		(net "P5E_PEX2_STN2_RX_DN<38>")
	)
	(segment
		(start 285.199836 -275.265388)
		(end 285.085536 -275.379688)
		(width 0.1143)
		(layer "In7.Cu")
		(net "P5E_PEX2_STN2_RX_DN<38>")
	)
	(segment
		(start 293.55542 -32.149542)
		(end 293.26459 -31.858712)
		(width 0.1651)
		(layer "In7.Cu")
		(net "P5E_PEX2_STN2_RX_DN<38>")
	)
	(segment
		(start 294.607234 -35.04819)
		(end 294.644318 -32.663638)
		(width 0.1651)
		(layer "In7.Cu")
		(net "P5E_PEX2_STN2_RX_DN<38>")
	)
	(segment
		(start 295.322752 -61.011308)
		(end 295.495726 -49.94275)
		(width 0.1651)
		(layer "In7.Cu")
		(net "P5E_PEX2_STN2_RX_DN<38>")
	)
	(segment
		(start 294.11295 -39.71036)
		(end 294.08374 -37.856414)
		(width 0.1651)
		(layer "In7.Cu")
		(net "P5E_PEX2_STN2_RX_DN<38>")
	)
	(segment
		(start 295.495726 -49.94275)
		(end 294.11295 -39.71036)
		(width 0.1651)
		(layer "In7.Cu")
		(net "P5E_PEX2_STN2_RX_DN<38>")
	)
	(segment
		(start 294.08374 -37.856414)
		(end 294.607234 -35.04819)
		(width 0.1651)
		(layer "In7.Cu")
		(net "P5E_PEX2_STN2_RX_DN<38>")
	)
	(segment
		(start 285.085536 -275.379688)
		(end 284.923738 -275.379688)
		(width 0.1143)
		(layer "In7.Cu")
		(net "P5E_PEX2_STN2_RX_DN<38>")
	)
	(segment
		(start 284.865572 -265.778234)
		(end 284.94863 -264.832084)
		(width 0.1651)
		(layer "In7.Cu")
		(net "P5E_PEX2_STN2_RX_DN<38>")
	)
	(segment
		(start 285.199836 -274.999958)
		(end 285.199836 -275.265388)
		(width 0.1143)
		(layer "In7.Cu")
		(net "P5E_PEX2_STN2_RX_DN<38>")
	)
	(segment
		(start 284.865572 -271.392904)
		(end 284.865572 -265.778234)
		(width 0.1651)
		(layer "In7.Cu")
		(net "P5E_PEX2_STN2_RX_DN<38>")
	)
	(segment
		(start 284.94863 -264.832084)
		(end 295.349676 -67.914266)
		(width 0.1651)
		(layer "In7.Cu")
		(net "P5E_PEX2_STN2_RX_DN<38>")
	)
	(segment
		(start 284.819852 -275.275802)
		(end 284.819852 -271.467072)
		(width 0.1143)
		(layer "In7.Cu")
		(net "P5E_PEX2_STN2_RX_DN<38>")
	)
	(segment
		(start 294.644318 -32.663638)
		(end 294.129968 -32.149542)
		(width 0.1651)
		(layer "In7.Cu")
		(net "P5E_PEX2_STN2_RX_DN<38>")
	)
	(segment
		(start 295.349676 -67.914266)
		(end 295.322752 -61.011308)
		(width 0.1651)
		(layer "In7.Cu")
		(net "P5E_PEX2_STN2_RX_DN<38>")
	)
	(segment
		(start 428.052738 -150.70455)
		(end 427.741588 -150.3934)
		(width 0.13462)
		(layer "F.Cu")
		(net "P5E_PEX3_STN0_TX_C_DN<12>")
	)
	(segment
		(start 422.057068 -150.554944)
		(end 421.557704 -150.554944)
		(width 0.13462)
		(layer "F.Cu")
		(net "P5E_PEX3_STN0_TX_C_DN<12>")
	)
	(segment
		(start 422.218612 -150.3934)
		(end 422.057068 -150.554944)
		(width 0.13462)
		(layer "F.Cu")
		(net "P5E_PEX3_STN0_TX_C_DN<12>")
	)
	(segment
		(start 427.741588 -150.3934)
		(end 422.218612 -150.3934)
		(width 0.13462)
		(layer "F.Cu")
		(net "P5E_PEX3_STN0_TX_C_DN<12>")
	)
	(segment
		(start 396.298928 -385.400296)
		(end 396.374366 -370.40439)
		(width 0.1651)
		(layer "In5.Cu")
		(net "P5E_PEX3_STN5_RX_DP<81>")
	)
	(segment
		(start 379.257052 -394.360908)
		(end 383.378964 -391.88263)
		(width 0.1651)
		(layer "In5.Cu")
		(net "P5E_PEX3_STN5_RX_DP<81>")
	)
	(segment
		(start 407.333958 -319.8876)
		(end 407.379678 -319.84188)
		(width 0.1143)
		(layer "In5.Cu")
		(net "P5E_PEX3_STN5_RX_DP<81>")
	)
	(segment
		(start 394.260324 -364.53318)
		(end 394.072872 -364.074202)
		(width 0.1651)
		(layer "In5.Cu")
		(net "P5E_PEX3_STN5_RX_DP<81>")
	)
	(segment
		(start 396.374366 -370.40439)
		(end 396.080996 -368.793268)
		(width 0.1651)
		(layer "In5.Cu")
		(net "P5E_PEX3_STN5_RX_DP<81>")
	)
	(segment
		(start 396.22476 -385.604766)
		(end 396.298928 -385.400296)
		(width 0.1651)
		(layer "In5.Cu")
		(net "P5E_PEX3_STN5_RX_DP<81>")
	)
	(segment
		(start 407.835608 -318.129666)
		(end 407.949908 -318.015366)
		(width 0.1143)
		(layer "In5.Cu")
		(net "P5E_PEX3_STN5_RX_DP<81>")
	)
	(segment
		(start 394.114528 -363.974888)
		(end 391.68705 -358.026716)
		(width 0.1651)
		(layer "In5.Cu")
		(net "P5E_PEX3_STN5_RX_DP<81>")
	)
	(segment
		(start 407.379678 -319.84188)
		(end 407.379678 -318.355472)
		(width 0.1143)
		(layer "In5.Cu")
		(net "P5E_PEX3_STN5_RX_DP<81>")
	)
	(segment
		(start 391.68705 -341.980774)
		(end 392.243818 -341.03056)
		(width 0.1651)
		(layer "In5.Cu")
		(net "P5E_PEX3_STN5_RX_DP<81>")
	)
	(segment
		(start 377.689872 -397.97609)
		(end 377.816872 -398.10309)
		(width 0.1651)
		(layer "In5.Cu")
		(net "P5E_PEX3_STN5_RX_DP<81>")
	)
	(segment
		(start 378.565918 -395.296136)
		(end 379.257052 -394.360908)
		(width 0.1651)
		(layer "In5.Cu")
		(net "P5E_PEX3_STN5_RX_DP<81>")
	)
	(segment
		(start 407.333958 -322.112132)
		(end 407.333958 -319.916048)
		(width 0.1651)
		(layer "In5.Cu")
		(net "P5E_PEX3_STN5_RX_DP<81>")
	)
	(segment
		(start 377.816872 -398.10309)
		(end 378.233432 -398.10309)
		(width 0.1651)
		(layer "In5.Cu")
		(net "P5E_PEX3_STN5_RX_DP<81>")
	)
	(segment
		(start 407.333958 -319.916048)
		(end 407.333958 -319.8876)
		(width 0.1143)
		(layer "In5.Cu")
		(net "P5E_PEX3_STN5_RX_DP<81>")
	)
	(segment
		(start 394.359638 -364.574836)
		(end 394.260324 -364.53318)
		(width 0.1651)
		(layer "In5.Cu")
		(net "P5E_PEX3_STN5_RX_DP<81>")
	)
	(segment
		(start 394.546328 -365.033306)
		(end 394.359384 -364.574836)
		(width 0.1651)
		(layer "In5.Cu")
		(net "P5E_PEX3_STN5_RX_DP<81>")
	)
	(segment
		(start 394.072872 -364.074202)
		(end 394.114528 -363.974888)
		(width 0.1651)
		(layer "In5.Cu")
		(net "P5E_PEX3_STN5_RX_DP<81>")
	)
	(segment
		(start 394.692124 -365.591344)
		(end 394.504672 -365.13262)
		(width 0.1651)
		(layer "In5.Cu")
		(net "P5E_PEX3_STN5_RX_DP<81>")
	)
	(segment
		(start 407.379678 -318.355472)
		(end 407.605484 -318.129666)
		(width 0.1143)
		(layer "In5.Cu")
		(net "P5E_PEX3_STN5_RX_DP<81>")
	)
	(segment
		(start 407.605484 -318.129666)
		(end 407.835608 -318.129666)
		(width 0.1143)
		(layer "In5.Cu")
		(net "P5E_PEX3_STN5_RX_DP<81>")
	)
	(segment
		(start 396.080996 -368.793268)
		(end 396.08125 -368.793268)
		(width 0.1651)
		(layer "In5.Cu")
		(net "P5E_PEX3_STN5_RX_DP<81>")
	)
	(segment
		(start 377.689872 -397.59001)
		(end 377.689872 -397.97609)
		(width 0.1651)
		(layer "In5.Cu")
		(net "P5E_PEX3_STN5_RX_DP<81>")
	)
	(segment
		(start 383.378964 -391.88263)
		(end 395.098524 -386.913628)
		(width 0.1651)
		(layer "In5.Cu")
		(net "P5E_PEX3_STN5_RX_DP<81>")
	)
	(segment
		(start 378.233432 -398.10309)
		(end 378.565918 -397.770604)
		(width 0.1651)
		(layer "In5.Cu")
		(net "P5E_PEX3_STN5_RX_DP<81>")
	)
	(segment
		(start 407.949908 -318.015366)
		(end 407.949908 -317.749936)
		(width 0.1143)
		(layer "In5.Cu")
		(net "P5E_PEX3_STN5_RX_DP<81>")
	)
	(segment
		(start 396.08125 -368.793268)
		(end 394.791438 -365.633254)
		(width 0.1651)
		(layer "In5.Cu")
		(net "P5E_PEX3_STN5_RX_DP<81>")
	)
	(segment
		(start 394.504672 -365.13262)
		(end 394.546328 -365.033306)
		(width 0.1651)
		(layer "In5.Cu")
		(net "P5E_PEX3_STN5_RX_DP<81>")
	)
	(segment
		(start 394.791438 -365.633254)
		(end 394.692124 -365.591344)
		(width 0.1651)
		(layer "In5.Cu")
		(net "P5E_PEX3_STN5_RX_DP<81>")
	)
	(segment
		(start 405.846788 -326.494394)
		(end 406.901396 -324.136004)
		(width 0.1651)
		(layer "In5.Cu")
		(net "P5E_PEX3_STN5_RX_DP<81>")
	)
	(segment
		(start 394.359384 -364.574836)
		(end 394.359638 -364.574836)
		(width 0.1651)
		(layer "In5.Cu")
		(net "P5E_PEX3_STN5_RX_DP<81>")
	)
	(segment
		(start 396.22476 -385.60502)
		(end 396.22476 -385.604766)
		(width 0.1651)
		(layer "In5.Cu")
		(net "P5E_PEX3_STN5_RX_DP<81>")
	)
	(segment
		(start 392.243818 -341.03056)
		(end 405.846788 -326.494394)
		(width 0.1651)
		(layer "In5.Cu")
		(net "P5E_PEX3_STN5_RX_DP<81>")
	)
	(segment
		(start 391.68705 -358.026716)
		(end 391.68705 -341.980774)
		(width 0.1651)
		(layer "In5.Cu")
		(net "P5E_PEX3_STN5_RX_DP<81>")
	)
	(segment
		(start 396.001748 -386.219446)
		(end 396.22476 -385.60502)
		(width 0.1651)
		(layer "In5.Cu")
		(net "P5E_PEX3_STN5_RX_DP<81>")
	)
	(segment
		(start 406.901396 -324.136004)
		(end 407.333958 -322.112132)
		(width 0.1651)
		(layer "In5.Cu")
		(net "P5E_PEX3_STN5_RX_DP<81>")
	)
	(segment
		(start 395.772386 -386.437378)
		(end 396.001748 -386.219446)
		(width 0.1651)
		(layer "In5.Cu")
		(net "P5E_PEX3_STN5_RX_DP<81>")
	)
	(segment
		(start 395.098524 -386.913628)
		(end 395.772386 -386.437378)
		(width 0.1651)
		(layer "In5.Cu")
		(net "P5E_PEX3_STN5_RX_DP<81>")
	)
	(segment
		(start 378.565918 -397.770604)
		(end 378.565918 -395.296136)
		(width 0.1651)
		(layer "In5.Cu")
		(net "P5E_PEX3_STN5_RX_DP<81>")
	)
	(segment
		(start 73.257664 -99.439984)
		(end 75.692 -99.439984)
		(width 0.13208)
		(layer "F.Cu")
		(net "NIC1_DATA_OUT")
	)
	(via
		(at 75.692 -99.439984)
		(size 0.508)
		(drill 0.254)
		(layers "F.Cu" "B.Cu")
		(net "NIC1_DATA_OUT")
	)
	(segment
		(start 75.723496 -99.439984)
		(end 75.692 -99.439984)
		(width 0.13208)
		(layer "B.Cu")
		(net "NIC1_DATA_OUT")
	)
	(segment
		(start 77.141832 -98.021648)
		(end 75.723496 -99.439984)
		(width 0.13208)
		(layer "B.Cu")
		(net "NIC1_DATA_OUT")
	)
	(segment
		(start 50.64252 -131.165092)
		(end 51.130454 -131.165092)
		(width 0.13462)
		(layer "F.Cu")
		(net "P5E_PEX0_STN1_RX_DN<28>")
	)
	(segment
		(start 53.80228 -131.00177)
		(end 54.09692 -131.29641)
		(width 0.13462)
		(layer "F.Cu")
		(net "P5E_PEX0_STN1_RX_DN<28>")
	)
	(segment
		(start 51.293268 -131.002278)
		(end 53.801772 -131.002278)
		(width 0.13462)
		(layer "F.Cu")
		(net "P5E_PEX0_STN1_RX_DN<28>")
	)
	(segment
		(start 51.130454 -131.165092)
		(end 51.293268 -131.002278)
		(width 0.13462)
		(layer "F.Cu")
		(net "P5E_PEX0_STN1_RX_DN<28>")
	)
	(segment
		(start 53.801772 -131.002278)
		(end 53.80228 -131.00177)
		(width 0.13462)
		(layer "F.Cu")
		(net "P5E_PEX0_STN1_RX_DN<28>")
	)
	(segment
		(start 48.380142 -135.576564)
		(end 47.996602 -136.502648)
		(width 0.1651)
		(layer "In5.Cu")
		(net "P5E_PEX0_STN1_RX_DN<28>")
	)
	(segment
		(start 47.775622 -140.883132)
		(end 46.845474 -141.813026)
		(width 0.1651)
		(layer "In5.Cu")
		(net "P5E_PEX0_STN1_RX_DN<28>")
	)
	(segment
		(start 41.212262 -147.079716)
		(end 41.044114 -147.684744)
		(width 0.1651)
		(layer "In5.Cu")
		(net "P5E_PEX0_STN1_RX_DN<28>")
	)
	(segment
		(start 42.59072 -145.218658)
		(end 42.614596 -145.378424)
		(width 0.1651)
		(layer "In5.Cu")
		(net "P5E_PEX0_STN1_RX_DN<28>")
	)
	(segment
		(start 49.313338 -133.323584)
		(end 49.123854 -133.781038)
		(width 0.1651)
		(layer "In5.Cu")
		(net "P5E_PEX0_STN1_RX_DN<28>")
	)
	(segment
		(start 49.123854 -133.781038)
		(end 49.18583 -133.93039)
		(width 0.1651)
		(layer "In5.Cu")
		(net "P5E_PEX0_STN1_RX_DN<28>")
	)
	(segment
		(start 50.128424 -132.330698)
		(end 50.144426 -132.49148)
		(width 0.1651)
		(layer "In5.Cu")
		(net "P5E_PEX0_STN1_RX_DN<28>")
	)
	(segment
		(start 48.996346 -134.388352)
		(end 48.84674 -134.450074)
		(width 0.1651)
		(layer "In5.Cu")
		(net "P5E_PEX0_STN1_RX_DN<28>")
	)
	(segment
		(start 45.555916 -142.812262)
		(end 45.39742 -142.780766)
		(width 0.1651)
		(layer "In5.Cu")
		(net "P5E_PEX0_STN1_RX_DN<28>")
	)
	(segment
		(start 70.715886 -271.802352)
		(end 70.670166 -271.848072)
		(width 0.1143)
		(layer "In5.Cu")
		(net "P5E_PEX0_STN1_RX_DN<28>")
	)
	(segment
		(start 47.996602 -136.502648)
		(end 47.996602 -140.348462)
		(width 0.1651)
		(layer "In5.Cu")
		(net "P5E_PEX0_STN1_RX_DN<28>")
	)
	(segment
		(start 50.917856 -131.54914)
		(end 50.603404 -131.932172)
		(width 0.1651)
		(layer "In5.Cu")
		(net "P5E_PEX0_STN1_RX_DN<28>")
	)
	(segment
		(start 42.88536 -144.82064)
		(end 42.59072 -145.218658)
		(width 0.1651)
		(layer "In5.Cu")
		(net "P5E_PEX0_STN1_RX_DN<28>")
	)
	(segment
		(start 70.715886 -271.773904)
		(end 70.715886 -271.802352)
		(width 0.1143)
		(layer "In5.Cu")
		(net "P5E_PEX0_STN1_RX_DN<28>")
	)
	(segment
		(start 53.162708 -131.11988)
		(end 52.667408 -131.11988)
		(width 0.1651)
		(layer "In5.Cu")
		(net "P5E_PEX0_STN1_RX_DN<28>")
	)
	(segment
		(start 43.971972 -143.733266)
		(end 42.88536 -144.82064)
		(width 0.1651)
		(layer "In5.Cu")
		(net "P5E_PEX0_STN1_RX_DN<28>")
	)
	(segment
		(start 42.159682 -145.800572)
		(end 41.212262 -147.079716)
		(width 0.1651)
		(layer "In5.Cu")
		(net "P5E_PEX0_STN1_RX_DN<28>")
	)
	(segment
		(start 70.773544 -273.479514)
		(end 70.935342 -273.479514)
		(width 0.1143)
		(layer "In5.Cu")
		(net "P5E_PEX0_STN1_RX_DN<28>")
	)
	(segment
		(start 50.442622 -131.94792)
		(end 50.128424 -132.330698)
		(width 0.1651)
		(layer "In5.Cu")
		(net "P5E_PEX0_STN1_RX_DN<28>")
	)
	(segment
		(start 42.614596 -145.378424)
		(end 42.319448 -145.776696)
		(width 0.1651)
		(layer "In5.Cu")
		(net "P5E_PEX0_STN1_RX_DN<28>")
	)
	(segment
		(start 48.529748 -135.514842)
		(end 48.380142 -135.576564)
		(width 0.1651)
		(layer "In5.Cu")
		(net "P5E_PEX0_STN1_RX_DN<28>")
	)
	(segment
		(start 42.319448 -145.776696)
		(end 42.159682 -145.800572)
		(width 0.1651)
		(layer "In5.Cu")
		(net "P5E_PEX0_STN1_RX_DN<28>")
	)
	(segment
		(start 70.670166 -271.848072)
		(end 70.670166 -273.376136)
		(width 0.1143)
		(layer "In5.Cu")
		(net "P5E_PEX0_STN1_RX_DN<28>")
	)
	(segment
		(start 48.84674 -134.450074)
		(end 48.657256 -134.907528)
		(width 0.1651)
		(layer "In5.Cu")
		(net "P5E_PEX0_STN1_RX_DN<28>")
	)
	(segment
		(start 44.542202 -143.48968)
		(end 44.383706 -143.458184)
		(width 0.1651)
		(layer "In5.Cu")
		(net "P5E_PEX0_STN1_RX_DN<28>")
	)
	(segment
		(start 42.391838 -161.14268)
		(end 70.715886 -267.605256)
		(width 0.1651)
		(layer "In5.Cu")
		(net "P5E_PEX0_STN1_RX_DN<28>")
	)
	(segment
		(start 49.18583 -133.93039)
		(end 48.996346 -134.388352)
		(width 0.1651)
		(layer "In5.Cu")
		(net "P5E_PEX0_STN1_RX_DN<28>")
	)
	(segment
		(start 51.216306 -131.00558)
		(end 50.902108 -131.388358)
		(width 0.1651)
		(layer "In5.Cu")
		(net "P5E_PEX0_STN1_RX_DN<28>")
	)
	(segment
		(start 45.967904 -142.536926)
		(end 45.555916 -142.812262)
		(width 0.1651)
		(layer "In5.Cu")
		(net "P5E_PEX0_STN1_RX_DN<28>")
	)
	(segment
		(start 45.9994 -142.37843)
		(end 45.967904 -142.536926)
		(width 0.1651)
		(layer "In5.Cu")
		(net "P5E_PEX0_STN1_RX_DN<28>")
	)
	(segment
		(start 49.668938 -132.890514)
		(end 49.313338 -133.323584)
		(width 0.1651)
		(layer "In5.Cu")
		(net "P5E_PEX0_STN1_RX_DN<28>")
	)
	(segment
		(start 48.657256 -134.907528)
		(end 48.719232 -135.05688)
		(width 0.1651)
		(layer "In5.Cu")
		(net "P5E_PEX0_STN1_RX_DN<28>")
	)
	(segment
		(start 53.80609 -131.00558)
		(end 53.277008 -131.00558)
		(width 0.1651)
		(layer "In5.Cu")
		(net "P5E_PEX0_STN1_RX_DN<28>")
	)
	(segment
		(start 45.39742 -142.780766)
		(end 44.985686 -143.055848)
		(width 0.1651)
		(layer "In5.Cu")
		(net "P5E_PEX0_STN1_RX_DN<28>")
	)
	(segment
		(start 48.719232 -135.05688)
		(end 48.529748 -135.514842)
		(width 0.1651)
		(layer "In5.Cu")
		(net "P5E_PEX0_STN1_RX_DN<28>")
	)
	(segment
		(start 49.82972 -132.874512)
		(end 49.668938 -132.890514)
		(width 0.1651)
		(layer "In5.Cu")
		(net "P5E_PEX0_STN1_RX_DN<28>")
	)
	(segment
		(start 54.09692 -131.29641)
		(end 53.80609 -131.00558)
		(width 0.1651)
		(layer "In5.Cu")
		(net "P5E_PEX0_STN1_RX_DN<28>")
	)
	(segment
		(start 47.996602 -140.348462)
		(end 47.775622 -140.883132)
		(width 0.1651)
		(layer "In5.Cu")
		(net "P5E_PEX0_STN1_RX_DN<28>")
	)
	(segment
		(start 41.044114 -147.684744)
		(end 41.638474 -156.892244)
		(width 0.1651)
		(layer "In5.Cu")
		(net "P5E_PEX0_STN1_RX_DN<28>")
	)
	(segment
		(start 44.95419 -143.214344)
		(end 44.542202 -143.48968)
		(width 0.1651)
		(layer "In5.Cu")
		(net "P5E_PEX0_STN1_RX_DN<28>")
	)
	(segment
		(start 53.277008 -131.00558)
		(end 53.162708 -131.11988)
		(width 0.1651)
		(layer "In5.Cu")
		(net "P5E_PEX0_STN1_RX_DN<28>")
	)
	(segment
		(start 70.670166 -273.376136)
		(end 70.773544 -273.479514)
		(width 0.1143)
		(layer "In5.Cu")
		(net "P5E_PEX0_STN1_RX_DN<28>")
	)
	(segment
		(start 71.049642 -273.365214)
		(end 71.049642 -273.099784)
		(width 0.1143)
		(layer "In5.Cu")
		(net "P5E_PEX0_STN1_RX_DN<28>")
	)
	(segment
		(start 70.935342 -273.479514)
		(end 71.049642 -273.365214)
		(width 0.1143)
		(layer "In5.Cu")
		(net "P5E_PEX0_STN1_RX_DN<28>")
	)
	(segment
		(start 44.383706 -143.458184)
		(end 43.971972 -143.733266)
		(width 0.1651)
		(layer "In5.Cu")
		(net "P5E_PEX0_STN1_RX_DN<28>")
	)
	(segment
		(start 46.845474 -141.813026)
		(end 45.9994 -142.37843)
		(width 0.1651)
		(layer "In5.Cu")
		(net "P5E_PEX0_STN1_RX_DN<28>")
	)
	(segment
		(start 52.667408 -131.11988)
		(end 52.553108 -131.00558)
		(width 0.1651)
		(layer "In5.Cu")
		(net "P5E_PEX0_STN1_RX_DN<28>")
	)
	(segment
		(start 50.902108 -131.388358)
		(end 50.917856 -131.54914)
		(width 0.1651)
		(layer "In5.Cu")
		(net "P5E_PEX0_STN1_RX_DN<28>")
	)
	(segment
		(start 41.638474 -156.892244)
		(end 42.391838 -161.14268)
		(width 0.1651)
		(layer "In5.Cu")
		(net "P5E_PEX0_STN1_RX_DN<28>")
	)
	(segment
		(start 50.144426 -132.49148)
		(end 49.82972 -132.874512)
		(width 0.1651)
		(layer "In5.Cu")
		(net "P5E_PEX0_STN1_RX_DN<28>")
	)
	(segment
		(start 50.603404 -131.932172)
		(end 50.442622 -131.94792)
		(width 0.1651)
		(layer "In5.Cu")
		(net "P5E_PEX0_STN1_RX_DN<28>")
	)
	(segment
		(start 44.985686 -143.055848)
		(end 44.95419 -143.214344)
		(width 0.1651)
		(layer "In5.Cu")
		(net "P5E_PEX0_STN1_RX_DN<28>")
	)
	(segment
		(start 52.553108 -131.00558)
		(end 51.216306 -131.00558)
		(width 0.1651)
		(layer "In5.Cu")
		(net "P5E_PEX0_STN1_RX_DN<28>")
	)
	(segment
		(start 70.715886 -267.605256)
		(end 70.715886 -271.773904)
		(width 0.1651)
		(layer "In5.Cu")
		(net "P5E_PEX0_STN1_RX_DN<28>")
	)
	(segment
		(start 70.454774 -390.748012)
		(end 70.394322 -390.601708)
		(width 0.1651)
		(layer "In5.Cu")
		(net "P5E_PEX0_STN6_RX_DP<109>")
	)
	(segment
		(start 76.915264 -394.902436)
		(end 76.80706 -394.740638)
		(width 0.1651)
		(layer "In5.Cu")
		(net "P5E_PEX0_STN6_RX_DP<109>")
	)
	(segment
		(start 77.202284 -400.661124)
		(end 77.202284 -395.849094)
		(width 0.1651)
		(layer "In5.Cu")
		(net "P5E_PEX0_STN6_RX_DP<109>")
	)
	(segment
		(start 76.964286 -400.899122)
		(end 77.202284 -400.661124)
		(width 0.1651)
		(layer "In5.Cu")
		(net "P5E_PEX0_STN6_RX_DP<109>")
	)
	(segment
		(start 76.436982 -400.899122)
		(end 76.964286 -400.899122)
		(width 0.1651)
		(layer "In5.Cu")
		(net "P5E_PEX0_STN6_RX_DP<109>")
	)
	(segment
		(start 44.82973 -319.921128)
		(end 44.82973 -316.455298)
		(width 0.1143)
		(layer "In5.Cu")
		(net "P5E_PEX0_STN6_RX_DP<109>")
	)
	(segment
		(start 72.145144 -391.327132)
		(end 71.999094 -391.387584)
		(width 0.1651)
		(layer "In5.Cu")
		(net "P5E_PEX0_STN6_RX_DP<109>")
	)
	(segment
		(start 59.066938 -355.402896)
		(end 58.236358 -352.087688)
		(width 0.1651)
		(layer "In5.Cu")
		(net "P5E_PEX0_STN6_RX_DP<109>")
	)
	(segment
		(start 64.033908 -368.27841)
		(end 59.066938 -355.402896)
		(width 0.1651)
		(layer "In5.Cu")
		(net "P5E_PEX0_STN6_RX_DP<109>")
	)
	(segment
		(start 76.309982 -400.390106)
		(end 76.309982 -400.772122)
		(width 0.1651)
		(layer "In5.Cu")
		(net "P5E_PEX0_STN6_RX_DP<109>")
	)
	(segment
		(start 76.309982 -400.772122)
		(end 76.436982 -400.899122)
		(width 0.1651)
		(layer "In5.Cu")
		(net "P5E_PEX0_STN6_RX_DP<109>")
	)
	(segment
		(start 44.82973 -316.455298)
		(end 45.055536 -316.229492)
		(width 0.1143)
		(layer "In5.Cu")
		(net "P5E_PEX0_STN6_RX_DP<109>")
	)
	(segment
		(start 45.28566 -316.229492)
		(end 45.39996 -316.115192)
		(width 0.1143)
		(layer "In5.Cu")
		(net "P5E_PEX0_STN6_RX_DP<109>")
	)
	(segment
		(start 71.492618 -391.056622)
		(end 71.046848 -390.872218)
		(width 0.1651)
		(layer "In5.Cu")
		(net "P5E_PEX0_STN6_RX_DP<109>")
	)
	(segment
		(start 76.80706 -394.740638)
		(end 73.159112 -391.746994)
		(width 0.1651)
		(layer "In5.Cu")
		(net "P5E_PEX0_STN6_RX_DP<109>")
	)
	(segment
		(start 71.55307 -391.202926)
		(end 71.492618 -391.056622)
		(width 0.1651)
		(layer "In5.Cu")
		(net "P5E_PEX0_STN6_RX_DP<109>")
	)
	(segment
		(start 44.78401 -319.995296)
		(end 44.78401 -319.966848)
		(width 0.1143)
		(layer "In5.Cu")
		(net "P5E_PEX0_STN6_RX_DP<109>")
	)
	(segment
		(start 45.055536 -316.229492)
		(end 45.28566 -316.229492)
		(width 0.1143)
		(layer "In5.Cu")
		(net "P5E_PEX0_STN6_RX_DP<109>")
	)
	(segment
		(start 73.159112 -391.746994)
		(end 72.145144 -391.327132)
		(width 0.1651)
		(layer "In5.Cu")
		(net "P5E_PEX0_STN6_RX_DP<109>")
	)
	(segment
		(start 77.202284 -395.849094)
		(end 76.915264 -394.902436)
		(width 0.1651)
		(layer "In5.Cu")
		(net "P5E_PEX0_STN6_RX_DP<109>")
	)
	(segment
		(start 54.01818 -337.387184)
		(end 45.516546 -324.66407)
		(width 0.1651)
		(layer "In5.Cu")
		(net "P5E_PEX0_STN6_RX_DP<109>")
	)
	(segment
		(start 66.749168 -387.845808)
		(end 65.715642 -385.350766)
		(width 0.1651)
		(layer "In5.Cu")
		(net "P5E_PEX0_STN6_RX_DP<109>")
	)
	(segment
		(start 58.236358 -352.087688)
		(end 57.442862 -345.656154)
		(width 0.1651)
		(layer "In5.Cu")
		(net "P5E_PEX0_STN6_RX_DP<109>")
	)
	(segment
		(start 45.39996 -316.115192)
		(end 45.39996 -315.849762)
		(width 0.1143)
		(layer "In5.Cu")
		(net "P5E_PEX0_STN6_RX_DP<109>")
	)
	(segment
		(start 71.999094 -391.387584)
		(end 71.55307 -391.202926)
		(width 0.1651)
		(layer "In5.Cu")
		(net "P5E_PEX0_STN6_RX_DP<109>")
	)
	(segment
		(start 71.046848 -390.872218)
		(end 70.900798 -390.93267)
		(width 0.1651)
		(layer "In5.Cu")
		(net "P5E_PEX0_STN6_RX_DP<109>")
	)
	(segment
		(start 44.78401 -319.966848)
		(end 44.82973 -319.921128)
		(width 0.1143)
		(layer "In5.Cu")
		(net "P5E_PEX0_STN6_RX_DP<109>")
	)
	(segment
		(start 70.394322 -390.601708)
		(end 70.394068 -390.601708)
		(width 0.1651)
		(layer "In5.Cu")
		(net "P5E_PEX0_STN6_RX_DP<109>")
	)
	(segment
		(start 45.516546 -324.66407)
		(end 44.78401 -322.895722)
		(width 0.1651)
		(layer "In5.Cu")
		(net "P5E_PEX0_STN6_RX_DP<109>")
	)
	(segment
		(start 57.442862 -345.656154)
		(end 54.01818 -337.387184)
		(width 0.1651)
		(layer "In5.Cu")
		(net "P5E_PEX0_STN6_RX_DP<109>")
	)
	(segment
		(start 70.900798 -390.93267)
		(end 70.454774 -390.748012)
		(width 0.1651)
		(layer "In5.Cu")
		(net "P5E_PEX0_STN6_RX_DP<109>")
	)
	(segment
		(start 68.876418 -389.973058)
		(end 66.749168 -387.845808)
		(width 0.1651)
		(layer "In5.Cu")
		(net "P5E_PEX0_STN6_RX_DP<109>")
	)
	(segment
		(start 70.394068 -390.601708)
		(end 68.876418 -389.973058)
		(width 0.1651)
		(layer "In5.Cu")
		(net "P5E_PEX0_STN6_RX_DP<109>")
	)
	(segment
		(start 44.78401 -322.895722)
		(end 44.78401 -319.995296)
		(width 0.1651)
		(layer "In5.Cu")
		(net "P5E_PEX0_STN6_RX_DP<109>")
	)
	(segment
		(start 65.715642 -385.350766)
		(end 64.033908 -368.27841)
		(width 0.1651)
		(layer "In5.Cu")
		(net "P5E_PEX0_STN6_RX_DP<109>")
	)
	(segment
		(start 169.901616 -99.607878)
		(end 170.196764 -99.31273)
		(width 0.13462)
		(layer "F.Cu")
		(net "P5E_PEX1_STN1_RX_DP<16>")
	)
	(segment
		(start 167.393112 -99.607878)
		(end 169.901616 -99.607878)
		(width 0.13462)
		(layer "F.Cu")
		(net "P5E_PEX1_STN1_RX_DP<16>")
	)
	(segment
		(start 167.230298 -99.445064)
		(end 167.393112 -99.607878)
		(width 0.13462)
		(layer "F.Cu")
		(net "P5E_PEX1_STN1_RX_DP<16>")
	)
	(segment
		(start 166.742364 -99.445064)
		(end 167.230298 -99.445064)
		(width 0.13462)
		(layer "F.Cu")
		(net "P5E_PEX1_STN1_RX_DP<16>")
	)
	(segment
		(start 144.114266 -149.937724)
		(end 144.78889 -159.572198)
		(width 0.1651)
		(layer "In5.Cu")
		(net "P5E_PEX1_STN1_RX_DP<16>")
	)
	(segment
		(start 175.749712 -273.78406)
		(end 175.749712 -274.04949)
		(width 0.1143)
		(layer "In5.Cu")
		(net "P5E_PEX1_STN1_RX_DP<16>")
	)
	(segment
		(start 170.196764 -99.31273)
		(end 169.905934 -99.60356)
		(width 0.1651)
		(layer "In5.Cu")
		(net "P5E_PEX1_STN1_RX_DP<16>")
	)
	(segment
		(start 147.121118 -119.642636)
		(end 145.498058 -126.35865)
		(width 0.1651)
		(layer "In5.Cu")
		(net "P5E_PEX1_STN1_RX_DP<16>")
	)
	(segment
		(start 155.132532 -107.761532)
		(end 152.689306 -109.382306)
		(width 0.1651)
		(layer "In5.Cu")
		(net "P5E_PEX1_STN1_RX_DP<16>")
	)
	(segment
		(start 150.395178 -110.640876)
		(end 149.921722 -111.125508)
		(width 0.1651)
		(layer "In5.Cu")
		(net "P5E_PEX1_STN1_RX_DP<16>")
	)
	(segment
		(start 175.635412 -273.66976)
		(end 175.749712 -273.78406)
		(width 0.1143)
		(layer "In5.Cu")
		(net "P5E_PEX1_STN1_RX_DP<16>")
	)
	(segment
		(start 169.905934 -99.60356)
		(end 167.992044 -99.60356)
		(width 0.1651)
		(layer "In5.Cu")
		(net "P5E_PEX1_STN1_RX_DP<16>")
	)
	(segment
		(start 161.007044 -103.095806)
		(end 155.132532 -107.761532)
		(width 0.1651)
		(layer "In5.Cu")
		(net "P5E_PEX1_STN1_RX_DP<16>")
	)
	(segment
		(start 175.134016 -270.105124)
		(end 175.134016 -271.525746)
		(width 0.1651)
		(layer "In5.Cu")
		(net "P5E_PEX1_STN1_RX_DP<16>")
	)
	(segment
		(start 144.78889 -159.572198)
		(end 146.044412 -166.070534)
		(width 0.1651)
		(layer "In5.Cu")
		(net "P5E_PEX1_STN1_RX_DP<16>")
	)
	(segment
		(start 175.179736 -271.599914)
		(end 175.179736 -273.454876)
		(width 0.1143)
		(layer "In5.Cu")
		(net "P5E_PEX1_STN1_RX_DP<16>")
	)
	(segment
		(start 146.044412 -166.070534)
		(end 175.134016 -270.105124)
		(width 0.1651)
		(layer "In5.Cu")
		(net "P5E_PEX1_STN1_RX_DP<16>")
	)
	(segment
		(start 175.134016 -271.525746)
		(end 175.134016 -271.554194)
		(width 0.1143)
		(layer "In5.Cu")
		(net "P5E_PEX1_STN1_RX_DP<16>")
	)
	(segment
		(start 149.921722 -111.125508)
		(end 147.121118 -119.642636)
		(width 0.1651)
		(layer "In5.Cu")
		(net "P5E_PEX1_STN1_RX_DP<16>")
	)
	(segment
		(start 152.033732 -109.97438)
		(end 150.395178 -110.640876)
		(width 0.1651)
		(layer "In5.Cu")
		(net "P5E_PEX1_STN1_RX_DP<16>")
	)
	(segment
		(start 167.992044 -99.60356)
		(end 161.007044 -103.095806)
		(width 0.1651)
		(layer "In5.Cu")
		(net "P5E_PEX1_STN1_RX_DP<16>")
	)
	(segment
		(start 152.689306 -109.382306)
		(end 152.033732 -109.97438)
		(width 0.1651)
		(layer "In5.Cu")
		(net "P5E_PEX1_STN1_RX_DP<16>")
	)
	(segment
		(start 175.179736 -273.454876)
		(end 175.39462 -273.66976)
		(width 0.1143)
		(layer "In5.Cu")
		(net "P5E_PEX1_STN1_RX_DP<16>")
	)
	(segment
		(start 175.134016 -271.554194)
		(end 175.179736 -271.599914)
		(width 0.1143)
		(layer "In5.Cu")
		(net "P5E_PEX1_STN1_RX_DP<16>")
	)
	(segment
		(start 145.498058 -126.35865)
		(end 144.114266 -149.937724)
		(width 0.1651)
		(layer "In5.Cu")
		(net "P5E_PEX1_STN1_RX_DP<16>")
	)
	(segment
		(start 175.39462 -273.66976)
		(end 175.635412 -273.66976)
		(width 0.1143)
		(layer "In5.Cu")
		(net "P5E_PEX1_STN1_RX_DP<16>")
	)
	(segment
		(start 291.704522 -33.952942)
		(end 291.41039 -33.65881)
		(width 0.13462)
		(layer "F.Cu")
		(net "P5E_PEX2_STN2_RX_DN<39>")
	)
	(segment
		(start 294.38727 -33.790128)
		(end 294.224456 -33.952942)
		(width 0.13462)
		(layer "F.Cu")
		(net "P5E_PEX2_STN2_RX_DN<39>")
	)
	(segment
		(start 294.86479 -33.790128)
		(end 294.38727 -33.790128)
		(width 0.13462)
		(layer "F.Cu")
		(net "P5E_PEX2_STN2_RX_DN<39>")
	)
	(segment
		(start 294.224456 -33.952942)
		(end 291.704522 -33.952942)
		(width 0.13462)
		(layer "F.Cu")
		(net "P5E_PEX2_STN2_RX_DN<39>")
	)
	(segment
		(start 283.870146 -271.549368)
		(end 283.915866 -271.503648)
		(width 0.1143)
		(layer "In7.Cu")
		(net "P5E_PEX2_STN2_RX_DN<39>")
	)
	(segment
		(start 283.915866 -271.4752)
		(end 283.915866 -266.275058)
		(width 0.1651)
		(layer "In7.Cu")
		(net "P5E_PEX2_STN2_RX_DN<39>")
	)
	(segment
		(start 293.156386 -39.76497)
		(end 293.08806 -35.355276)
		(width 0.1651)
		(layer "In7.Cu")
		(net "P5E_PEX2_STN2_RX_DN<39>")
	)
	(segment
		(start 284.021022 -273.479514)
		(end 283.870146 -273.328638)
		(width 0.1143)
		(layer "In7.Cu")
		(net "P5E_PEX2_STN2_RX_DN<39>")
	)
	(segment
		(start 283.870146 -273.328638)
		(end 283.870146 -271.549368)
		(width 0.1143)
		(layer "In7.Cu")
		(net "P5E_PEX2_STN2_RX_DN<39>")
	)
	(segment
		(start 284.135576 -273.479514)
		(end 284.021022 -273.479514)
		(width 0.1143)
		(layer "In7.Cu")
		(net "P5E_PEX2_STN2_RX_DN<39>")
	)
	(segment
		(start 284.249876 -273.099784)
		(end 284.249876 -273.365214)
		(width 0.1143)
		(layer "In7.Cu")
		(net "P5E_PEX2_STN2_RX_DN<39>")
	)
	(segment
		(start 294.355012 -60.99683)
		(end 294.527986 -49.915572)
		(width 0.1651)
		(layer "In7.Cu")
		(net "P5E_PEX2_STN2_RX_DN<39>")
	)
	(segment
		(start 292.05174 -33.94964)
		(end 291.70122 -33.94964)
		(width 0.1651)
		(layer "In7.Cu")
		(net "P5E_PEX2_STN2_RX_DN<39>")
	)
	(segment
		(start 293.08806 -34.98596)
		(end 292.05174 -33.94964)
		(width 0.1651)
		(layer "In7.Cu")
		(net "P5E_PEX2_STN2_RX_DN<39>")
	)
	(segment
		(start 293.08806 -35.355276)
		(end 293.08806 -34.98596)
		(width 0.1651)
		(layer "In7.Cu")
		(net "P5E_PEX2_STN2_RX_DN<39>")
	)
	(segment
		(start 291.70122 -33.94964)
		(end 291.41039 -33.65881)
		(width 0.1651)
		(layer "In7.Cu")
		(net "P5E_PEX2_STN2_RX_DN<39>")
	)
	(segment
		(start 294.527986 -49.915572)
		(end 293.156386 -39.76497)
		(width 0.1651)
		(layer "In7.Cu")
		(net "P5E_PEX2_STN2_RX_DN<39>")
	)
	(segment
		(start 283.915866 -266.275058)
		(end 294.38092 -68.13804)
		(width 0.1651)
		(layer "In7.Cu")
		(net "P5E_PEX2_STN2_RX_DN<39>")
	)
	(segment
		(start 283.915866 -271.503648)
		(end 283.915866 -271.4752)
		(width 0.1143)
		(layer "In7.Cu")
		(net "P5E_PEX2_STN2_RX_DN<39>")
	)
	(segment
		(start 284.249876 -273.365214)
		(end 284.135576 -273.479514)
		(width 0.1143)
		(layer "In7.Cu")
		(net "P5E_PEX2_STN2_RX_DN<39>")
	)
	(segment
		(start 294.38092 -68.13804)
		(end 294.355012 -60.99683)
		(width 0.1651)
		(layer "In7.Cu")
		(net "P5E_PEX2_STN2_RX_DN<39>")
	)
	(segment
		(start 422.224708 -150.11908)
		(end 422.060624 -149.954996)
		(width 0.13462)
		(layer "F.Cu")
		(net "P5E_PEX3_STN0_TX_C_DP<12>")
	)
	(segment
		(start 428.052738 -149.79015)
		(end 427.723808 -150.11908)
		(width 0.13462)
		(layer "F.Cu")
		(net "P5E_PEX3_STN0_TX_C_DP<12>")
	)
	(segment
		(start 427.723808 -150.11908)
		(end 422.224708 -150.11908)
		(width 0.13462)
		(layer "F.Cu")
		(net "P5E_PEX3_STN0_TX_C_DP<12>")
	)
	(segment
		(start 422.060624 -149.954996)
		(end 421.557704 -149.954996)
		(width 0.13462)
		(layer "F.Cu")
		(net "P5E_PEX3_STN0_TX_C_DP<12>")
	)
	(segment
		(start 396.354808 -350.685862)
		(end 396.354808 -351.31629)
		(width 0.13462)
		(layer "F.Cu")
		(net "P5E_PEX3_STN5_TX_C_DP<84>")
	)
	(segment
		(start 396.354808 -351.31629)
		(end 396.05966 -351.611438)
		(width 0.13462)
		(layer "F.Cu")
		(net "P5E_PEX3_STN5_TX_C_DP<84>")
	)
	(segment
		(start 396.03426 -350.365314)
		(end 396.354808 -350.685862)
		(width 0.13462)
		(layer "F.Cu")
		(net "P5E_PEX3_STN5_TX_C_DP<84>")
	)
	(segment
		(start 396.05966 -351.611438)
		(end 396.35049 -351.902268)
		(width 0.1651)
		(layer "In7.Cu")
		(net "P5E_PEX3_STN5_TX_C_DP<84>")
	)
	(segment
		(start 397.175736 -363.981746)
		(end 398.78762 -367.50498)
		(width 0.1651)
		(layer "In7.Cu")
		(net "P5E_PEX3_STN5_TX_C_DP<84>")
	)
	(segment
		(start 396.409418 -362.306616)
		(end 396.365476 -362.424472)
		(width 0.1651)
		(layer "In7.Cu")
		(net "P5E_PEX3_STN5_TX_C_DP<84>")
	)
	(segment
		(start 396.895574 -363.369352)
		(end 396.851632 -363.487208)
		(width 0.1651)
		(layer "In7.Cu")
		(net "P5E_PEX3_STN5_TX_C_DP<84>")
	)
	(segment
		(start 396.571724 -362.875322)
		(end 396.68958 -362.91901)
		(width 0.1651)
		(layer "In7.Cu")
		(net "P5E_PEX3_STN5_TX_C_DP<84>")
	)
	(segment
		(start 395.87932 -361.361736)
		(end 396.085568 -361.812586)
		(width 0.1651)
		(layer "In7.Cu")
		(net "P5E_PEX3_STN5_TX_C_DP<84>")
	)
	(segment
		(start 394.79601 -358.78008)
		(end 395.923262 -361.24388)
		(width 0.1651)
		(layer "In7.Cu")
		(net "P5E_PEX3_STN5_TX_C_DP<84>")
	)
	(segment
		(start 396.203424 -361.856274)
		(end 396.409418 -362.306616)
		(width 0.1651)
		(layer "In7.Cu")
		(net "P5E_PEX3_STN5_TX_C_DP<84>")
	)
	(segment
		(start 385.134104 -404.512272)
		(end 384.847338 -404.799038)
		(width 0.1651)
		(layer "In7.Cu")
		(net "P5E_PEX3_STN5_TX_C_DP<84>")
	)
	(segment
		(start 385.134104 -395.48054)
		(end 385.134104 -404.512272)
		(width 0.1651)
		(layer "In7.Cu")
		(net "P5E_PEX3_STN5_TX_C_DP<84>")
	)
	(segment
		(start 396.085568 -361.812586)
		(end 396.203424 -361.856274)
		(width 0.1651)
		(layer "In7.Cu")
		(net "P5E_PEX3_STN5_TX_C_DP<84>")
	)
	(segment
		(start 396.851632 -363.487208)
		(end 397.05788 -363.937804)
		(width 0.1651)
		(layer "In7.Cu")
		(net "P5E_PEX3_STN5_TX_C_DP<84>")
	)
	(segment
		(start 394.79601 -353.910646)
		(end 394.79601 -358.78008)
		(width 0.1651)
		(layer "In7.Cu")
		(net "P5E_PEX3_STN5_TX_C_DP<84>")
	)
	(segment
		(start 397.959072 -388.75081)
		(end 387.57733 -393.132818)
		(width 0.1651)
		(layer "In7.Cu")
		(net "P5E_PEX3_STN5_TX_C_DP<84>")
	)
	(segment
		(start 397.05788 -363.937804)
		(end 397.175736 -363.981746)
		(width 0.1651)
		(layer "In7.Cu")
		(net "P5E_PEX3_STN5_TX_C_DP<84>")
	)
	(segment
		(start 396.68958 -362.91901)
		(end 396.895574 -363.369352)
		(width 0.1651)
		(layer "In7.Cu")
		(net "P5E_PEX3_STN5_TX_C_DP<84>")
	)
	(segment
		(start 395.923262 -361.24388)
		(end 395.87932 -361.361736)
		(width 0.1651)
		(layer "In7.Cu")
		(net "P5E_PEX3_STN5_TX_C_DP<84>")
	)
	(segment
		(start 398.78762 -367.50498)
		(end 399.25752 -369.71224)
		(width 0.1651)
		(layer "In7.Cu")
		(net "P5E_PEX3_STN5_TX_C_DP<84>")
	)
	(segment
		(start 387.57733 -393.132818)
		(end 385.134104 -395.48054)
		(width 0.1651)
		(layer "In7.Cu")
		(net "P5E_PEX3_STN5_TX_C_DP<84>")
	)
	(segment
		(start 398.977612 -386.931154)
		(end 397.959072 -388.75081)
		(width 0.1651)
		(layer "In7.Cu")
		(net "P5E_PEX3_STN5_TX_C_DP<84>")
	)
	(segment
		(start 396.35049 -351.902268)
		(end 396.35049 -352.356166)
		(width 0.1651)
		(layer "In7.Cu")
		(net "P5E_PEX3_STN5_TX_C_DP<84>")
	)
	(segment
		(start 384.290062 -404.672038)
		(end 384.290062 -404.290022)
		(width 0.1651)
		(layer "In7.Cu")
		(net "P5E_PEX3_STN5_TX_C_DP<84>")
	)
	(segment
		(start 399.25752 -369.71224)
		(end 398.977612 -386.931154)
		(width 0.1651)
		(layer "In7.Cu")
		(net "P5E_PEX3_STN5_TX_C_DP<84>")
	)
	(segment
		(start 396.35049 -352.356166)
		(end 394.79601 -353.910646)
		(width 0.1651)
		(layer "In7.Cu")
		(net "P5E_PEX3_STN5_TX_C_DP<84>")
	)
	(segment
		(start 384.847338 -404.799038)
		(end 384.417062 -404.799038)
		(width 0.1651)
		(layer "In7.Cu")
		(net "P5E_PEX3_STN5_TX_C_DP<84>")
	)
	(segment
		(start 384.417062 -404.799038)
		(end 384.290062 -404.672038)
		(width 0.1651)
		(layer "In7.Cu")
		(net "P5E_PEX3_STN5_TX_C_DP<84>")
	)
	(segment
		(start 396.365476 -362.424472)
		(end 396.571724 -362.875322)
		(width 0.1651)
		(layer "In7.Cu")
		(net "P5E_PEX3_STN5_TX_C_DP<84>")
	)
	(segment
		(start 65.04178 -102.798372)
		(end 61.569092 -102.798372)
		(width 0.13208)
		(layer "F.Cu")
		(net "NCSI_NIC1_TXD1")
	)
	(segment
		(start 61.569092 -102.798372)
		(end 59.395106 -102.798372)
		(width 0.13208)
		(layer "F.Cu")
		(net "NCSI_NIC1_TXD1")
	)
	(segment
		(start 66.60007 -101.240082)
		(end 65.04178 -102.798372)
		(width 0.13208)
		(layer "F.Cu")
		(net "NCSI_NIC1_TXD1")
	)
	(segment
		(start 68.65747 -101.240082)
		(end 66.60007 -101.240082)
		(width 0.13208)
		(layer "F.Cu")
		(net "NCSI_NIC1_TXD1")
	)
	(via
		(at 61.569092 -102.798372)
		(size 0.762)
		(drill 0.381)
		(layers "F.Cu" "B.Cu")
		(net "NCSI_NIC1_TXD1")
	)
	(segment
		(start 51.948334 -132.802122)
		(end 52.24272 -133.096508)
		(width 0.13462)
		(layer "F.Cu")
		(net "P5E_PEX0_STN1_RX_DN<29>")
	)
	(segment
		(start 51.130454 -132.964936)
		(end 51.293268 -132.802122)
		(width 0.13462)
		(layer "F.Cu")
		(net "P5E_PEX0_STN1_RX_DN<29>")
	)
	(segment
		(start 51.293268 -132.802122)
		(end 51.948334 -132.802122)
		(width 0.13462)
		(layer "F.Cu")
		(net "P5E_PEX0_STN1_RX_DN<29>")
	)
	(segment
		(start 50.64252 -132.964936)
		(end 51.130454 -132.964936)
		(width 0.13462)
		(layer "F.Cu")
		(net "P5E_PEX0_STN1_RX_DN<29>")
	)
	(segment
		(start 48.951642 -140.76934)
		(end 48.554894 -141.727428)
		(width 0.1651)
		(layer "In5.Cu")
		(net "P5E_PEX0_STN1_RX_DN<29>")
	)
	(segment
		(start 49.607724 -135.409178)
		(end 49.41824 -135.866632)
		(width 0.1651)
		(layer "In5.Cu")
		(net "P5E_PEX0_STN1_RX_DN<29>")
	)
	(segment
		(start 44.766738 -145.912586)
		(end 44.692824 -146.056604)
		(width 0.1651)
		(layer "In5.Cu")
		(net "P5E_PEX0_STN1_RX_DN<29>")
	)
	(segment
		(start 49.065942 -138.94054)
		(end 48.951642 -139.05484)
		(width 0.1651)
		(layer "In5.Cu")
		(net "P5E_PEX0_STN1_RX_DN<29>")
	)
	(segment
		(start 71.620126 -275.276056)
		(end 71.723504 -275.379434)
		(width 0.1143)
		(layer "In5.Cu")
		(net "P5E_PEX0_STN1_RX_DN<29>")
	)
	(segment
		(start 42.639234 -146.783806)
		(end 42.451782 -147.013168)
		(width 0.1651)
		(layer "In5.Cu")
		(net "P5E_PEX0_STN1_RX_DN<29>")
	)
	(segment
		(start 71.620126 -271.848072)
		(end 71.620126 -275.276056)
		(width 0.1143)
		(layer "In5.Cu")
		(net "P5E_PEX0_STN1_RX_DN<29>")
	)
	(segment
		(start 47.695104 -143.25092)
		(end 47.686976 -143.412464)
		(width 0.1651)
		(layer "In5.Cu")
		(net "P5E_PEX0_STN1_RX_DN<29>")
	)
	(segment
		(start 47.319692 -143.745204)
		(end 47.158402 -143.73733)
		(width 0.1651)
		(layer "In5.Cu")
		(net "P5E_PEX0_STN1_RX_DN<29>")
	)
	(segment
		(start 48.951642 -140.27404)
		(end 48.951642 -140.76934)
		(width 0.1651)
		(layer "In5.Cu")
		(net "P5E_PEX0_STN1_RX_DN<29>")
	)
	(segment
		(start 49.480216 -136.015984)
		(end 49.290732 -136.473692)
		(width 0.1651)
		(layer "In5.Cu")
		(net "P5E_PEX0_STN1_RX_DN<29>")
	)
	(segment
		(start 48.278034 -142.396464)
		(end 48.06188 -142.918434)
		(width 0.1651)
		(layer "In5.Cu")
		(net "P5E_PEX0_STN1_RX_DN<29>")
	)
	(segment
		(start 42.59072 -156.74721)
		(end 43.316144 -160.843468)
		(width 0.1651)
		(layer "In5.Cu")
		(net "P5E_PEX0_STN1_RX_DN<29>")
	)
	(segment
		(start 49.94656 -134.889494)
		(end 49.757076 -135.347202)
		(width 0.1651)
		(layer "In5.Cu")
		(net "P5E_PEX0_STN1_RX_DN<29>")
	)
	(segment
		(start 43.316144 -160.843468)
		(end 71.665846 -267.461238)
		(width 0.1651)
		(layer "In5.Cu")
		(net "P5E_PEX0_STN1_RX_DN<29>")
	)
	(segment
		(start 49.41824 -135.866632)
		(end 49.480216 -136.015984)
		(width 0.1651)
		(layer "In5.Cu")
		(net "P5E_PEX0_STN1_RX_DN<29>")
	)
	(segment
		(start 51.95189 -132.805678)
		(end 51.734974 -132.805678)
		(width 0.1651)
		(layer "In5.Cu")
		(net "P5E_PEX0_STN1_RX_DN<29>")
	)
	(segment
		(start 51.056286 -133.498844)
		(end 50.696368 -133.839712)
		(width 0.1651)
		(layer "In5.Cu")
		(net "P5E_PEX0_STN1_RX_DN<29>")
	)
	(segment
		(start 49.065942 -139.66444)
		(end 49.065942 -140.15974)
		(width 0.1651)
		(layer "In5.Cu")
		(net "P5E_PEX0_STN1_RX_DN<29>")
	)
	(segment
		(start 71.665846 -267.461238)
		(end 71.665846 -271.773904)
		(width 0.1651)
		(layer "In5.Cu")
		(net "P5E_PEX0_STN1_RX_DN<29>")
	)
	(segment
		(start 49.065942 -138.44524)
		(end 49.065942 -138.94054)
		(width 0.1651)
		(layer "In5.Cu")
		(net "P5E_PEX0_STN1_RX_DN<29>")
	)
	(segment
		(start 44.077128 -146.13382)
		(end 43.004232 -146.477736)
		(width 0.1651)
		(layer "In5.Cu")
		(net "P5E_PEX0_STN1_RX_DN<29>")
	)
	(segment
		(start 50.081688 -134.2644)
		(end 49.884838 -134.740142)
		(width 0.1651)
		(layer "In5.Cu")
		(net "P5E_PEX0_STN1_RX_DN<29>")
	)
	(segment
		(start 44.220892 -146.207734)
		(end 44.077128 -146.13382)
		(width 0.1651)
		(layer "In5.Cu")
		(net "P5E_PEX0_STN1_RX_DN<29>")
	)
	(segment
		(start 48.951642 -136.993122)
		(end 48.951642 -138.33094)
		(width 0.1651)
		(layer "In5.Cu")
		(net "P5E_PEX0_STN1_RX_DN<29>")
	)
	(segment
		(start 48.61687 -141.87678)
		(end 48.427386 -142.334742)
		(width 0.1651)
		(layer "In5.Cu")
		(net "P5E_PEX0_STN1_RX_DN<29>")
	)
	(segment
		(start 51.734974 -132.805678)
		(end 51.526694 -132.892038)
		(width 0.1651)
		(layer "In5.Cu")
		(net "P5E_PEX0_STN1_RX_DN<29>")
	)
	(segment
		(start 71.885302 -275.379434)
		(end 71.999602 -275.265134)
		(width 0.1143)
		(layer "In5.Cu")
		(net "P5E_PEX0_STN1_RX_DN<29>")
	)
	(segment
		(start 48.06188 -142.918434)
		(end 47.695104 -143.25092)
		(width 0.1651)
		(layer "In5.Cu")
		(net "P5E_PEX0_STN1_RX_DN<29>")
	)
	(segment
		(start 44.692824 -146.056604)
		(end 44.220892 -146.207734)
		(width 0.1651)
		(layer "In5.Cu")
		(net "P5E_PEX0_STN1_RX_DN<29>")
	)
	(segment
		(start 71.665846 -271.773904)
		(end 71.665846 -271.802352)
		(width 0.1143)
		(layer "In5.Cu")
		(net "P5E_PEX0_STN1_RX_DN<29>")
	)
	(segment
		(start 52.24272 -133.096508)
		(end 51.95189 -132.805678)
		(width 0.1651)
		(layer "In5.Cu")
		(net "P5E_PEX0_STN1_RX_DN<29>")
	)
	(segment
		(start 48.951642 -139.55014)
		(end 49.065942 -139.66444)
		(width 0.1651)
		(layer "In5.Cu")
		(net "P5E_PEX0_STN1_RX_DN<29>")
	)
	(segment
		(start 49.065942 -140.15974)
		(end 48.951642 -140.27404)
		(width 0.1651)
		(layer "In5.Cu")
		(net "P5E_PEX0_STN1_RX_DN<29>")
	)
	(segment
		(start 48.427386 -142.334742)
		(end 48.278034 -142.396464)
		(width 0.1651)
		(layer "In5.Cu")
		(net "P5E_PEX0_STN1_RX_DN<29>")
	)
	(segment
		(start 45.238162 -145.761456)
		(end 44.766738 -145.912586)
		(width 0.1651)
		(layer "In5.Cu")
		(net "P5E_PEX0_STN1_RX_DN<29>")
	)
	(segment
		(start 42.01033 -147.823936)
		(end 42.59072 -156.74721)
		(width 0.1651)
		(layer "In5.Cu")
		(net "P5E_PEX0_STN1_RX_DN<29>")
	)
	(segment
		(start 49.884838 -134.740142)
		(end 49.94656 -134.889494)
		(width 0.1651)
		(layer "In5.Cu")
		(net "P5E_PEX0_STN1_RX_DN<29>")
	)
	(segment
		(start 71.723504 -275.379434)
		(end 71.885302 -275.379434)
		(width 0.1143)
		(layer "In5.Cu")
		(net "P5E_PEX0_STN1_RX_DN<29>")
	)
	(segment
		(start 49.757076 -135.347202)
		(end 49.607724 -135.409178)
		(width 0.1651)
		(layer "In5.Cu")
		(net "P5E_PEX0_STN1_RX_DN<29>")
	)
	(segment
		(start 42.451782 -147.013168)
		(end 42.01033 -147.823936)
		(width 0.1651)
		(layer "In5.Cu")
		(net "P5E_PEX0_STN1_RX_DN<29>")
	)
	(segment
		(start 48.554894 -141.727428)
		(end 48.61687 -141.87678)
		(width 0.1651)
		(layer "In5.Cu")
		(net "P5E_PEX0_STN1_RX_DN<29>")
	)
	(segment
		(start 50.696368 -133.839712)
		(end 50.534824 -133.83514)
		(width 0.1651)
		(layer "In5.Cu")
		(net "P5E_PEX0_STN1_RX_DN<29>")
	)
	(segment
		(start 46.13783 -144.662144)
		(end 45.734986 -145.264632)
		(width 0.1651)
		(layer "In5.Cu")
		(net "P5E_PEX0_STN1_RX_DN<29>")
	)
	(segment
		(start 49.141126 -136.535668)
		(end 48.951642 -136.993122)
		(width 0.1651)
		(layer "In5.Cu")
		(net "P5E_PEX0_STN1_RX_DN<29>")
	)
	(segment
		(start 48.951642 -138.33094)
		(end 49.065942 -138.44524)
		(width 0.1651)
		(layer "In5.Cu")
		(net "P5E_PEX0_STN1_RX_DN<29>")
	)
	(segment
		(start 50.534824 -133.83514)
		(end 50.081688 -134.2644)
		(width 0.1651)
		(layer "In5.Cu")
		(net "P5E_PEX0_STN1_RX_DN<29>")
	)
	(segment
		(start 45.734986 -145.264632)
		(end 45.238162 -145.761456)
		(width 0.1651)
		(layer "In5.Cu")
		(net "P5E_PEX0_STN1_RX_DN<29>")
	)
	(segment
		(start 47.158402 -143.73733)
		(end 46.13783 -144.662144)
		(width 0.1651)
		(layer "In5.Cu")
		(net "P5E_PEX0_STN1_RX_DN<29>")
	)
	(segment
		(start 49.290732 -136.473692)
		(end 49.141126 -136.535668)
		(width 0.1651)
		(layer "In5.Cu")
		(net "P5E_PEX0_STN1_RX_DN<29>")
	)
	(segment
		(start 51.457352 -132.96138)
		(end 51.060604 -133.337046)
		(width 0.1651)
		(layer "In5.Cu")
		(net "P5E_PEX0_STN1_RX_DN<29>")
	)
	(segment
		(start 47.686976 -143.412464)
		(end 47.319692 -143.745204)
		(width 0.1651)
		(layer "In5.Cu")
		(net "P5E_PEX0_STN1_RX_DN<29>")
	)
	(segment
		(start 51.060604 -133.337046)
		(end 51.056286 -133.498844)
		(width 0.1651)
		(layer "In5.Cu")
		(net "P5E_PEX0_STN1_RX_DN<29>")
	)
	(segment
		(start 51.526694 -132.892038)
		(end 51.457352 -132.96138)
		(width 0.1651)
		(layer "In5.Cu")
		(net "P5E_PEX0_STN1_RX_DN<29>")
	)
	(segment
		(start 71.665846 -271.802352)
		(end 71.620126 -271.848072)
		(width 0.1143)
		(layer "In5.Cu")
		(net "P5E_PEX0_STN1_RX_DN<29>")
	)
	(segment
		(start 43.004232 -146.477736)
		(end 42.639234 -146.783806)
		(width 0.1651)
		(layer "In5.Cu")
		(net "P5E_PEX0_STN1_RX_DN<29>")
	)
	(segment
		(start 48.951642 -139.05484)
		(end 48.951642 -139.55014)
		(width 0.1651)
		(layer "In5.Cu")
		(net "P5E_PEX0_STN1_RX_DN<29>")
	)
	(segment
		(start 71.999602 -275.265134)
		(end 71.999602 -274.999704)
		(width 0.1143)
		(layer "In5.Cu")
		(net "P5E_PEX0_STN1_RX_DN<29>")
	)
	(segment
		(start 75.28433 -401.82927)
		(end 75.28433 -396.657068)
		(width 0.1651)
		(layer "In5.Cu")
		(net "P5E_PEX0_STN6_RX_DN<110>")
	)
	(segment
		(start 63.37173 -368.432842)
		(end 58.423556 -355.605842)
		(width 0.1651)
		(layer "In5.Cu")
		(net "P5E_PEX0_STN6_RX_DN<110>")
	)
	(segment
		(start 74.539856 -394.85951)
		(end 73.658222 -393.977876)
		(width 0.1651)
		(layer "In5.Cu")
		(net "P5E_PEX0_STN6_RX_DN<110>")
	)
	(segment
		(start 44.184316 -318.320166)
		(end 44.335446 -318.320166)
		(width 0.1143)
		(layer "In5.Cu")
		(net "P5E_PEX0_STN6_RX_DN<110>")
	)
	(segment
		(start 53.421788 -337.70697)
		(end 45.761402 -326.24268)
		(width 0.1651)
		(layer "In5.Cu")
		(net "P5E_PEX0_STN6_RX_DN<110>")
	)
	(segment
		(start 75.28433 -396.657068)
		(end 74.539856 -394.85951)
		(width 0.1651)
		(layer "In5.Cu")
		(net "P5E_PEX0_STN6_RX_DN<110>")
	)
	(segment
		(start 44.449746 -318.434466)
		(end 44.449746 -318.699896)
		(width 0.1143)
		(layer "In5.Cu")
		(net "P5E_PEX0_STN6_RX_DN<110>")
	)
	(segment
		(start 57.573418 -352.211894)
		(end 56.785764 -345.829382)
		(width 0.1651)
		(layer "In5.Cu")
		(net "P5E_PEX0_STN6_RX_DN<110>")
	)
	(segment
		(start 44.070016 -318.434466)
		(end 44.184316 -318.320166)
		(width 0.1143)
		(layer "In5.Cu")
		(net "P5E_PEX0_STN6_RX_DN<110>")
	)
	(segment
		(start 74.109834 -402.790152)
		(end 74.109834 -402.408136)
		(width 0.1651)
		(layer "In5.Cu")
		(net "P5E_PEX0_STN6_RX_DN<110>")
	)
	(segment
		(start 44.9199 -324.983094)
		(end 44.115736 -323.041772)
		(width 0.1651)
		(layer "In5.Cu")
		(net "P5E_PEX0_STN6_RX_DN<110>")
	)
	(segment
		(start 74.236834 -402.281136)
		(end 74.832464 -402.281136)
		(width 0.1651)
		(layer "In5.Cu")
		(net "P5E_PEX0_STN6_RX_DN<110>")
	)
	(segment
		(start 44.335446 -318.320166)
		(end 44.449746 -318.434466)
		(width 0.1143)
		(layer "In5.Cu")
		(net "P5E_PEX0_STN6_RX_DN<110>")
	)
	(segment
		(start 58.423556 -355.605842)
		(end 57.573418 -352.211894)
		(width 0.1651)
		(layer "In5.Cu")
		(net "P5E_PEX0_STN6_RX_DN<110>")
	)
	(segment
		(start 73.658222 -393.977876)
		(end 68.447412 -390.496044)
		(width 0.1651)
		(layer "In5.Cu")
		(net "P5E_PEX0_STN6_RX_DN<110>")
	)
	(segment
		(start 66.12255 -388.171182)
		(end 65.065148 -385.618228)
		(width 0.1651)
		(layer "In5.Cu")
		(net "P5E_PEX0_STN6_RX_DN<110>")
	)
	(segment
		(start 74.832464 -402.281136)
		(end 75.28433 -401.82927)
		(width 0.1651)
		(layer "In5.Cu")
		(net "P5E_PEX0_STN6_RX_DN<110>")
	)
	(segment
		(start 45.761402 -326.24268)
		(end 45.761148 -326.242426)
		(width 0.1651)
		(layer "In5.Cu")
		(net "P5E_PEX0_STN6_RX_DN<110>")
	)
	(segment
		(start 68.447412 -390.496044)
		(end 66.12255 -388.171182)
		(width 0.1651)
		(layer "In5.Cu")
		(net "P5E_PEX0_STN6_RX_DN<110>")
	)
	(segment
		(start 65.065148 -385.618228)
		(end 63.37173 -368.432842)
		(width 0.1651)
		(layer "In5.Cu")
		(net "P5E_PEX0_STN6_RX_DN<110>")
	)
	(segment
		(start 44.115736 -323.041772)
		(end 44.115736 -319.995296)
		(width 0.1651)
		(layer "In5.Cu")
		(net "P5E_PEX0_STN6_RX_DN<110>")
	)
	(segment
		(start 45.761148 -326.242426)
		(end 44.9199 -324.983094)
		(width 0.1651)
		(layer "In5.Cu")
		(net "P5E_PEX0_STN6_RX_DN<110>")
	)
	(segment
		(start 44.115736 -319.966848)
		(end 44.070016 -319.921128)
		(width 0.1143)
		(layer "In5.Cu")
		(net "P5E_PEX0_STN6_RX_DN<110>")
	)
	(segment
		(start 74.109834 -402.408136)
		(end 74.236834 -402.281136)
		(width 0.1651)
		(layer "In5.Cu")
		(net "P5E_PEX0_STN6_RX_DN<110>")
	)
	(segment
		(start 56.785764 -345.829382)
		(end 53.421788 -337.70697)
		(width 0.1651)
		(layer "In5.Cu")
		(net "P5E_PEX0_STN6_RX_DN<110>")
	)
	(segment
		(start 44.115736 -319.995296)
		(end 44.115736 -319.966848)
		(width 0.1143)
		(layer "In5.Cu")
		(net "P5E_PEX0_STN6_RX_DN<110>")
	)
	(segment
		(start 44.070016 -319.921128)
		(end 44.070016 -318.434466)
		(width 0.1143)
		(layer "In5.Cu")
		(net "P5E_PEX0_STN6_RX_DN<110>")
	)
	(segment
		(start 300.125384 -28.829)
		(end 299.964348 -28.990036)
		(width 0.13462)
		(layer "F.Cu")
		(net "P5E_PEX2_STN2_TX_C_DP<36>")
	)
	(segment
		(start 299.964348 -28.990036)
		(end 299.46473 -28.990036)
		(width 0.13462)
		(layer "F.Cu")
		(net "P5E_PEX2_STN2_TX_C_DP<36>")
	)
	(segment
		(start 301.725584 -29.139642)
		(end 301.414942 -28.829)
		(width 0.13462)
		(layer "F.Cu")
		(net "P5E_PEX2_STN2_TX_C_DP<36>")
	)
	(segment
		(start 301.414942 -28.829)
		(end 300.125384 -28.829)
		(width 0.13462)
		(layer "F.Cu")
		(net "P5E_PEX2_STN2_TX_C_DP<36>")
	)
	(segment
		(start 413.802322 -132.27812)
		(end 413.50311 -132.577332)
		(width 0.13462)
		(layer "F.Cu")
		(net "P5E_PEX3_STN0_RX_DP<5>")
	)
	(segment
		(start 416.308032 -132.27812)
		(end 413.802322 -132.27812)
		(width 0.13462)
		(layer "F.Cu")
		(net "P5E_PEX3_STN0_RX_DP<5>")
	)
	(segment
		(start 416.95751 -132.444998)
		(end 416.47491 -132.444998)
		(width 0.13462)
		(layer "F.Cu")
		(net "P5E_PEX3_STN0_RX_DP<5>")
	)
	(segment
		(start 416.47491 -132.444998)
		(end 416.308032 -132.27812)
		(width 0.13462)
		(layer "F.Cu")
		(net "P5E_PEX3_STN0_RX_DP<5>")
	)
	(segment
		(start 432.550062 -233.359452)
		(end 431.513488 -222.619316)
		(width 0.1651)
		(layer "In5.Cu")
		(net "P5E_PEX3_STN0_RX_DP<5>")
	)
	(segment
		(start 423.190162 -136.29767)
		(end 422.366186 -135.702548)
		(width 0.1651)
		(layer "In5.Cu")
		(net "P5E_PEX3_STN0_RX_DP<5>")
	)
	(segment
		(start 429.800004 -283.549852)
		(end 430.065434 -283.549852)
		(width 0.1143)
		(layer "In5.Cu")
		(net "P5E_PEX3_STN0_RX_DP<5>")
	)
	(segment
		(start 432.143408 -282.979622)
		(end 432.189128 -282.933902)
		(width 0.1143)
		(layer "In5.Cu")
		(net "P5E_PEX3_STN0_RX_DP<5>")
	)
	(segment
		(start 423.777156 -136.72185)
		(end 423.617644 -136.747504)
		(width 0.1651)
		(layer "In5.Cu")
		(net "P5E_PEX3_STN0_RX_DP<5>")
	)
	(segment
		(start 429.301402 -160.728406)
		(end 427.920658 -151.400002)
		(width 0.1651)
		(layer "In5.Cu")
		(net "P5E_PEX3_STN0_RX_DP<5>")
	)
	(segment
		(start 418.668454 -133.974586)
		(end 418.6174 -133.82117)
		(width 0.1651)
		(layer "In5.Cu")
		(net "P5E_PEX3_STN0_RX_DP<5>")
	)
	(segment
		(start 417.578794 -133.42747)
		(end 417.52774 -133.274054)
		(width 0.1651)
		(layer "In5.Cu")
		(net "P5E_PEX3_STN0_RX_DP<5>")
	)
	(segment
		(start 418.021516 -133.649974)
		(end 417.578794 -133.42747)
		(width 0.1651)
		(layer "In5.Cu")
		(net "P5E_PEX3_STN0_RX_DP<5>")
	)
	(segment
		(start 418.6174 -133.82117)
		(end 418.174932 -133.599174)
		(width 0.1651)
		(layer "In5.Cu")
		(net "P5E_PEX3_STN0_RX_DP<5>")
	)
	(segment
		(start 425.6659 -138.618976)
		(end 424.998896 -137.604246)
		(width 0.1651)
		(layer "In5.Cu")
		(net "P5E_PEX3_STN0_RX_DP<5>")
	)
	(segment
		(start 422.366186 -135.702548)
		(end 421.444674 -135.240014)
		(width 0.1651)
		(layer "In5.Cu")
		(net "P5E_PEX3_STN0_RX_DP<5>")
	)
	(segment
		(start 426.53966 -142.071598)
		(end 425.93133 -139.23772)
		(width 0.1651)
		(layer "In5.Cu")
		(net "P5E_PEX3_STN0_RX_DP<5>")
	)
	(segment
		(start 424.998896 -137.604246)
		(end 423.777156 -136.72185)
		(width 0.1651)
		(layer "In5.Cu")
		(net "P5E_PEX3_STN0_RX_DP<5>")
	)
	(segment
		(start 432.189128 -282.933902)
		(end 432.217576 -282.933902)
		(width 0.1143)
		(layer "In5.Cu")
		(net "P5E_PEX3_STN0_RX_DP<5>")
	)
	(segment
		(start 421.444674 -135.240014)
		(end 421.291258 -135.291068)
		(width 0.1651)
		(layer "In5.Cu")
		(net "P5E_PEX3_STN0_RX_DP<5>")
	)
	(segment
		(start 430.065434 -283.549852)
		(end 430.179734 -283.435552)
		(width 0.1143)
		(layer "In5.Cu")
		(net "P5E_PEX3_STN0_RX_DP<5>")
	)
	(segment
		(start 420.20109 -134.743952)
		(end 419.758368 -134.521448)
		(width 0.1651)
		(layer "In5.Cu")
		(net "P5E_PEX3_STN0_RX_DP<5>")
	)
	(segment
		(start 442.748924 -272.229834)
		(end 442.80074 -270.270224)
		(width 0.1651)
		(layer "In5.Cu")
		(net "P5E_PEX3_STN0_RX_DP<5>")
	)
	(segment
		(start 416.43808 -132.726938)
		(end 416.437826 -132.727192)
		(width 0.1651)
		(layer "In5.Cu")
		(net "P5E_PEX3_STN0_RX_DP<5>")
	)
	(segment
		(start 430.179734 -283.435552)
		(end 430.179734 -283.19476)
		(width 0.1143)
		(layer "In5.Cu")
		(net "P5E_PEX3_STN0_RX_DP<5>")
	)
	(segment
		(start 423.215816 -136.457182)
		(end 423.190162 -136.29767)
		(width 0.1651)
		(layer "In5.Cu")
		(net "P5E_PEX3_STN0_RX_DP<5>")
	)
	(segment
		(start 427.920658 -151.400002)
		(end 427.920404 -151.399748)
		(width 0.1651)
		(layer "In5.Cu")
		(net "P5E_PEX3_STN0_RX_DP<5>")
	)
	(segment
		(start 431.513488 -222.619316)
		(end 429.301402 -160.728406)
		(width 0.1651)
		(layer "In5.Cu")
		(net "P5E_PEX3_STN0_RX_DP<5>")
	)
	(segment
		(start 413.79394 -132.286502)
		(end 413.50311 -132.577332)
		(width 0.1651)
		(layer "In5.Cu")
		(net "P5E_PEX3_STN0_RX_DP<5>")
	)
	(segment
		(start 419.707314 -134.368032)
		(end 419.264846 -134.146036)
		(width 0.1651)
		(layer "In5.Cu")
		(net "P5E_PEX3_STN0_RX_DP<5>")
	)
	(segment
		(start 419.758368 -134.521448)
		(end 419.707314 -134.368032)
		(width 0.1651)
		(layer "In5.Cu")
		(net "P5E_PEX3_STN0_RX_DP<5>")
	)
	(segment
		(start 416.48888 -132.880354)
		(end 416.43808 -132.726938)
		(width 0.1651)
		(layer "In5.Cu")
		(net "P5E_PEX3_STN0_RX_DP<5>")
	)
	(segment
		(start 423.617644 -136.747504)
		(end 423.215816 -136.457182)
		(width 0.1651)
		(layer "In5.Cu")
		(net "P5E_PEX3_STN0_RX_DP<5>")
	)
	(segment
		(start 415.560002 -132.286502)
		(end 413.79394 -132.286502)
		(width 0.1651)
		(layer "In5.Cu")
		(net "P5E_PEX3_STN0_RX_DP<5>")
	)
	(segment
		(start 419.264846 -134.146036)
		(end 419.11143 -134.19709)
		(width 0.1651)
		(layer "In5.Cu")
		(net "P5E_PEX3_STN0_RX_DP<5>")
	)
	(segment
		(start 420.35476 -134.693152)
		(end 420.20109 -134.743952)
		(width 0.1651)
		(layer "In5.Cu")
		(net "P5E_PEX3_STN0_RX_DP<5>")
	)
	(segment
		(start 427.920404 -151.399748)
		(end 427.920404 -151.39924)
		(width 0.1651)
		(layer "In5.Cu")
		(net "P5E_PEX3_STN0_RX_DP<5>")
	)
	(segment
		(start 427.920404 -151.39924)
		(end 426.53966 -142.071598)
		(width 0.1651)
		(layer "In5.Cu")
		(net "P5E_PEX3_STN0_RX_DP<5>")
	)
	(segment
		(start 433.696618 -282.388056)
		(end 441.046108 -275.243798)
		(width 0.1651)
		(layer "In5.Cu")
		(net "P5E_PEX3_STN0_RX_DP<5>")
	)
	(segment
		(start 430.179734 -283.19476)
		(end 430.394872 -282.979622)
		(width 0.1143)
		(layer "In5.Cu")
		(net "P5E_PEX3_STN0_RX_DP<5>")
	)
	(segment
		(start 425.93133 -139.23772)
		(end 425.6659 -138.618976)
		(width 0.1651)
		(layer "In5.Cu")
		(net "P5E_PEX3_STN0_RX_DP<5>")
	)
	(segment
		(start 417.085272 -133.052058)
		(end 416.931856 -133.102858)
		(width 0.1651)
		(layer "In5.Cu")
		(net "P5E_PEX3_STN0_RX_DP<5>")
	)
	(segment
		(start 442.80074 -270.270224)
		(end 435.175406 -244.204744)
		(width 0.1651)
		(layer "In5.Cu")
		(net "P5E_PEX3_STN0_RX_DP<5>")
	)
	(segment
		(start 435.175406 -244.204744)
		(end 432.550062 -233.359452)
		(width 0.1651)
		(layer "In5.Cu")
		(net "P5E_PEX3_STN0_RX_DP<5>")
	)
	(segment
		(start 417.52774 -133.274054)
		(end 417.085272 -133.052058)
		(width 0.1651)
		(layer "In5.Cu")
		(net "P5E_PEX3_STN0_RX_DP<5>")
	)
	(segment
		(start 416.931856 -133.102858)
		(end 416.48888 -132.880354)
		(width 0.1651)
		(layer "In5.Cu")
		(net "P5E_PEX3_STN0_RX_DP<5>")
	)
	(segment
		(start 419.11143 -134.19709)
		(end 418.668454 -133.974586)
		(width 0.1651)
		(layer "In5.Cu")
		(net "P5E_PEX3_STN0_RX_DP<5>")
	)
	(segment
		(start 420.848282 -135.068564)
		(end 420.797228 -134.915148)
		(width 0.1651)
		(layer "In5.Cu")
		(net "P5E_PEX3_STN0_RX_DP<5>")
	)
	(segment
		(start 432.8668 -282.933902)
		(end 433.696618 -282.388056)
		(width 0.1651)
		(layer "In5.Cu")
		(net "P5E_PEX3_STN0_RX_DP<5>")
	)
	(segment
		(start 421.291258 -135.291068)
		(end 420.848282 -135.068564)
		(width 0.1651)
		(layer "In5.Cu")
		(net "P5E_PEX3_STN0_RX_DP<5>")
	)
	(segment
		(start 430.394872 -282.979622)
		(end 432.143408 -282.979622)
		(width 0.1143)
		(layer "In5.Cu")
		(net "P5E_PEX3_STN0_RX_DP<5>")
	)
	(segment
		(start 441.046108 -275.243798)
		(end 442.748924 -272.229834)
		(width 0.1651)
		(layer "In5.Cu")
		(net "P5E_PEX3_STN0_RX_DP<5>")
	)
	(segment
		(start 420.797228 -134.915148)
		(end 420.35476 -134.693152)
		(width 0.1651)
		(layer "In5.Cu")
		(net "P5E_PEX3_STN0_RX_DP<5>")
	)
	(segment
		(start 432.217576 -282.933902)
		(end 432.8668 -282.933902)
		(width 0.1651)
		(layer "In5.Cu")
		(net "P5E_PEX3_STN0_RX_DP<5>")
	)
	(segment
		(start 416.437826 -132.727192)
		(end 415.560002 -132.286502)
		(width 0.1651)
		(layer "In5.Cu")
		(net "P5E_PEX3_STN0_RX_DP<5>")
	)
	(segment
		(start 418.174932 -133.599174)
		(end 418.021516 -133.649974)
		(width 0.1651)
		(layer "In5.Cu")
		(net "P5E_PEX3_STN0_RX_DP<5>")
	)
	(segment
		(start 64.216026 -101.782372)
		(end 64.94907 -101.782372)
		(width 0.13208)
		(layer "F.Cu")
		(net "NCSI_NIC1_TX_EN")
	)
	(segment
		(start 59.395106 -101.782372)
		(end 64.216026 -101.782372)
		(width 0.13208)
		(layer "F.Cu")
		(net "NCSI_NIC1_TX_EN")
	)
	(segment
		(start 66.091308 -100.640134)
		(end 68.65747 -100.640134)
		(width 0.13208)
		(layer "F.Cu")
		(net "NCSI_NIC1_TX_EN")
	)
	(segment
		(start 64.94907 -101.782372)
		(end 66.091308 -100.640134)
		(width 0.13208)
		(layer "F.Cu")
		(net "NCSI_NIC1_TX_EN")
	)
	(via
		(at 64.216026 -101.782372)
		(size 0.762)
		(drill 0.381)
		(layers "F.Cu" "B.Cu")
		(net "NCSI_NIC1_TX_EN")
	)
	(segment
		(start 50.64252 -121.7549)
		(end 51.130454 -121.7549)
		(width 0.13462)
		(layer "F.Cu")
		(net "P5E_PEX0_STN1_RX_DN<25>")
	)
	(segment
		(start 51.293268 -121.592086)
		(end 51.948334 -121.592086)
		(width 0.13462)
		(layer "F.Cu")
		(net "P5E_PEX0_STN1_RX_DN<25>")
	)
	(segment
		(start 51.948334 -121.592086)
		(end 52.24272 -121.886472)
		(width 0.13462)
		(layer "F.Cu")
		(net "P5E_PEX0_STN1_RX_DN<25>")
	)
	(segment
		(start 51.130454 -121.7549)
		(end 51.293268 -121.592086)
		(width 0.13462)
		(layer "F.Cu")
		(net "P5E_PEX0_STN1_RX_DN<25>")
	)
	(segment
		(start 68.085208 -275.379434)
		(end 68.199508 -275.265134)
		(width 0.1143)
		(layer "In5.Cu")
		(net "P5E_PEX0_STN1_RX_DN<25>")
	)
	(segment
		(start 48.869854 -123.405138)
		(end 48.86198 -123.566682)
		(width 0.1651)
		(layer "In5.Cu")
		(net "P5E_PEX0_STN1_RX_DN<25>")
	)
	(segment
		(start 38.135052 -147.294346)
		(end 38.744144 -157.221936)
		(width 0.1651)
		(layer "In5.Cu")
		(net "P5E_PEX0_STN1_RX_DN<25>")
	)
	(segment
		(start 67.865752 -268.037056)
		(end 67.865752 -271.773904)
		(width 0.1651)
		(layer "In5.Cu")
		(net "P5E_PEX0_STN1_RX_DN<25>")
	)
	(segment
		(start 48.86198 -123.566682)
		(end 48.49495 -123.899676)
		(width 0.1651)
		(layer "In5.Cu")
		(net "P5E_PEX0_STN1_RX_DN<25>")
	)
	(segment
		(start 39.680896 -162.364166)
		(end 67.865752 -268.037056)
		(width 0.1651)
		(layer "In5.Cu")
		(net "P5E_PEX0_STN1_RX_DN<25>")
	)
	(segment
		(start 67.865752 -271.802352)
		(end 67.820032 -271.848072)
		(width 0.1143)
		(layer "In5.Cu")
		(net "P5E_PEX0_STN1_RX_DN<25>")
	)
	(segment
		(start 48.49495 -123.899676)
		(end 48.333406 -123.892056)
		(width 0.1651)
		(layer "In5.Cu")
		(net "P5E_PEX0_STN1_RX_DN<25>")
	)
	(segment
		(start 48.333406 -123.892056)
		(end 47.966884 -124.224796)
		(width 0.1651)
		(layer "In5.Cu")
		(net "P5E_PEX0_STN1_RX_DN<25>")
	)
	(segment
		(start 51.78679 -121.595642)
		(end 51.271932 -121.800874)
		(width 0.1651)
		(layer "In5.Cu")
		(net "P5E_PEX0_STN1_RX_DN<25>")
	)
	(segment
		(start 41.220898 -141.405356)
		(end 41.299384 -141.54658)
		(width 0.1651)
		(layer "In5.Cu")
		(net "P5E_PEX0_STN1_RX_DN<25>")
	)
	(segment
		(start 68.199508 -275.265134)
		(end 68.199508 -274.999704)
		(width 0.1143)
		(layer "In5.Cu")
		(net "P5E_PEX0_STN1_RX_DN<25>")
	)
	(segment
		(start 67.820032 -271.848072)
		(end 67.820032 -275.276056)
		(width 0.1143)
		(layer "In5.Cu")
		(net "P5E_PEX0_STN1_RX_DN<25>")
	)
	(segment
		(start 44.931838 -127.526542)
		(end 44.62272 -127.914146)
		(width 0.1651)
		(layer "In5.Cu")
		(net "P5E_PEX0_STN1_RX_DN<25>")
	)
	(segment
		(start 44.62272 -127.914146)
		(end 44.461938 -127.93218)
		(width 0.1651)
		(layer "In5.Cu")
		(net "P5E_PEX0_STN1_RX_DN<25>")
	)
	(segment
		(start 44.913804 -127.366014)
		(end 44.931838 -127.526542)
		(width 0.1651)
		(layer "In5.Cu")
		(net "P5E_PEX0_STN1_RX_DN<25>")
	)
	(segment
		(start 52.24272 -121.886472)
		(end 51.95189 -121.595642)
		(width 0.1651)
		(layer "In5.Cu")
		(net "P5E_PEX0_STN1_RX_DN<25>")
	)
	(segment
		(start 38.744144 -157.221936)
		(end 39.680896 -162.364166)
		(width 0.1651)
		(layer "In5.Cu")
		(net "P5E_PEX0_STN1_RX_DN<25>")
	)
	(segment
		(start 47.05604 -125.205998)
		(end 46.68901 -125.538992)
		(width 0.1651)
		(layer "In5.Cu")
		(net "P5E_PEX0_STN1_RX_DN<25>")
	)
	(segment
		(start 43.924728 -128.605788)
		(end 43.764708 -128.970024)
		(width 0.1651)
		(layer "In5.Cu")
		(net "P5E_PEX0_STN1_RX_DN<25>")
	)
	(segment
		(start 46.527466 -125.531372)
		(end 45.98289 -126.025656)
		(width 0.1651)
		(layer "In5.Cu")
		(net "P5E_PEX0_STN1_RX_DN<25>")
	)
	(segment
		(start 49.39792 -123.080018)
		(end 49.236376 -123.072398)
		(width 0.1651)
		(layer "In5.Cu")
		(net "P5E_PEX0_STN1_RX_DN<25>")
	)
	(segment
		(start 47.966884 -124.224796)
		(end 47.95901 -124.38634)
		(width 0.1651)
		(layer "In5.Cu")
		(net "P5E_PEX0_STN1_RX_DN<25>")
	)
	(segment
		(start 41.021508 -142.10157)
		(end 40.831516 -142.766034)
		(width 0.1651)
		(layer "In5.Cu")
		(net "P5E_PEX0_STN1_RX_DN<25>")
	)
	(segment
		(start 49.772824 -122.58548)
		(end 49.76495 -122.747024)
		(width 0.1651)
		(layer "In5.Cu")
		(net "P5E_PEX0_STN1_RX_DN<25>")
	)
	(segment
		(start 51.208178 -121.949718)
		(end 50.747676 -122.133106)
		(width 0.1651)
		(layer "In5.Cu")
		(net "P5E_PEX0_STN1_RX_DN<25>")
	)
	(segment
		(start 46.68901 -125.538992)
		(end 46.527466 -125.531372)
		(width 0.1651)
		(layer "In5.Cu")
		(net "P5E_PEX0_STN1_RX_DN<25>")
	)
	(segment
		(start 45.692314 -126.57328)
		(end 45.383196 -126.960884)
		(width 0.1651)
		(layer "In5.Cu")
		(net "P5E_PEX0_STN1_RX_DN<25>")
	)
	(segment
		(start 45.674026 -126.412752)
		(end 45.692314 -126.57328)
		(width 0.1651)
		(layer "In5.Cu")
		(net "P5E_PEX0_STN1_RX_DN<25>")
	)
	(segment
		(start 47.95901 -124.38634)
		(end 47.59198 -124.719334)
		(width 0.1651)
		(layer "In5.Cu")
		(net "P5E_PEX0_STN1_RX_DN<25>")
	)
	(segment
		(start 40.831516 -142.766034)
		(end 38.54577 -145.714212)
		(width 0.1651)
		(layer "In5.Cu")
		(net "P5E_PEX0_STN1_RX_DN<25>")
	)
	(segment
		(start 45.98289 -126.025656)
		(end 45.674026 -126.412752)
		(width 0.1651)
		(layer "In5.Cu")
		(net "P5E_PEX0_STN1_RX_DN<25>")
	)
	(segment
		(start 67.865752 -271.773904)
		(end 67.865752 -271.802352)
		(width 0.1143)
		(layer "In5.Cu")
		(net "P5E_PEX0_STN1_RX_DN<25>")
	)
	(segment
		(start 41.16324 -142.023084)
		(end 41.021508 -142.10157)
		(width 0.1651)
		(layer "In5.Cu")
		(net "P5E_PEX0_STN1_RX_DN<25>")
	)
	(segment
		(start 38.54577 -145.714212)
		(end 38.135052 -147.294346)
		(width 0.1651)
		(layer "In5.Cu")
		(net "P5E_PEX0_STN1_RX_DN<25>")
	)
	(segment
		(start 50.747676 -122.133106)
		(end 50.59934 -122.069352)
		(width 0.1651)
		(layer "In5.Cu")
		(net "P5E_PEX0_STN1_RX_DN<25>")
	)
	(segment
		(start 44.461938 -127.93218)
		(end 43.924728 -128.605788)
		(width 0.1651)
		(layer "In5.Cu")
		(net "P5E_PEX0_STN1_RX_DN<25>")
	)
	(segment
		(start 47.59198 -124.719334)
		(end 47.430436 -124.711714)
		(width 0.1651)
		(layer "In5.Cu")
		(net "P5E_PEX0_STN1_RX_DN<25>")
	)
	(segment
		(start 47.063914 -125.044454)
		(end 47.05604 -125.205998)
		(width 0.1651)
		(layer "In5.Cu")
		(net "P5E_PEX0_STN1_RX_DN<25>")
	)
	(segment
		(start 43.764708 -128.970024)
		(end 42.19702 -137.99439)
		(width 0.1651)
		(layer "In5.Cu")
		(net "P5E_PEX0_STN1_RX_DN<25>")
	)
	(segment
		(start 50.59934 -122.069352)
		(end 50.139346 -122.25274)
		(width 0.1651)
		(layer "In5.Cu")
		(net "P5E_PEX0_STN1_RX_DN<25>")
	)
	(segment
		(start 47.430436 -124.711714)
		(end 47.063914 -125.044454)
		(width 0.1651)
		(layer "In5.Cu")
		(net "P5E_PEX0_STN1_RX_DN<25>")
	)
	(segment
		(start 42.19702 -137.99439)
		(end 41.220898 -141.405356)
		(width 0.1651)
		(layer "In5.Cu")
		(net "P5E_PEX0_STN1_RX_DN<25>")
	)
	(segment
		(start 67.820032 -275.276056)
		(end 67.92341 -275.379434)
		(width 0.1143)
		(layer "In5.Cu")
		(net "P5E_PEX0_STN1_RX_DN<25>")
	)
	(segment
		(start 51.271932 -121.800874)
		(end 51.208178 -121.949718)
		(width 0.1651)
		(layer "In5.Cu")
		(net "P5E_PEX0_STN1_RX_DN<25>")
	)
	(segment
		(start 51.95189 -121.595642)
		(end 51.78679 -121.595642)
		(width 0.1651)
		(layer "In5.Cu")
		(net "P5E_PEX0_STN1_RX_DN<25>")
	)
	(segment
		(start 41.299384 -141.54658)
		(end 41.16324 -142.023084)
		(width 0.1651)
		(layer "In5.Cu")
		(net "P5E_PEX0_STN1_RX_DN<25>")
	)
	(segment
		(start 45.222414 -126.978918)
		(end 44.913804 -127.366014)
		(width 0.1651)
		(layer "In5.Cu")
		(net "P5E_PEX0_STN1_RX_DN<25>")
	)
	(segment
		(start 50.139346 -122.25274)
		(end 49.772824 -122.58548)
		(width 0.1651)
		(layer "In5.Cu")
		(net "P5E_PEX0_STN1_RX_DN<25>")
	)
	(segment
		(start 49.76495 -122.747024)
		(end 49.39792 -123.080018)
		(width 0.1651)
		(layer "In5.Cu")
		(net "P5E_PEX0_STN1_RX_DN<25>")
	)
	(segment
		(start 49.236376 -123.072398)
		(end 48.869854 -123.405138)
		(width 0.1651)
		(layer "In5.Cu")
		(net "P5E_PEX0_STN1_RX_DN<25>")
	)
	(segment
		(start 67.92341 -275.379434)
		(end 68.085208 -275.379434)
		(width 0.1143)
		(layer "In5.Cu")
		(net "P5E_PEX0_STN1_RX_DN<25>")
	)
	(segment
		(start 45.383196 -126.960884)
		(end 45.222414 -126.978918)
		(width 0.1651)
		(layer "In5.Cu")
		(net "P5E_PEX0_STN1_RX_DN<25>")
	)
	(segment
		(start 57.133998 -319.944496)
		(end 57.133998 -319.916048)
		(width 0.1143)
		(layer "In9.Cu")
		(net "P5E_PEX0_STN6_RX_DP<96>")
	)
	(segment
		(start 81.921604 -363.40034)
		(end 77.392276 -360.373676)
		(width 0.1651)
		(layer "In9.Cu")
		(net "P5E_PEX0_STN6_RX_DP<96>")
	)
	(segment
		(start 75.653392 -341.58174)
		(end 75.205844 -340.501224)
		(width 0.1651)
		(layer "In9.Cu")
		(net "P5E_PEX0_STN6_RX_DP<96>")
	)
	(segment
		(start 57.686702 -324.376542)
		(end 57.133998 -323.04228)
		(width 0.1651)
		(layer "In9.Cu")
		(net "P5E_PEX0_STN6_RX_DP<96>")
	)
	(segment
		(start 57.179718 -319.870328)
		(end 57.179718 -318.406272)
		(width 0.1143)
		(layer "In9.Cu")
		(net "P5E_PEX0_STN6_RX_DP<96>")
	)
	(segment
		(start 82.524092 -363.80293)
		(end 82.365342 -363.834426)
		(width 0.1651)
		(layer "In9.Cu")
		(net "P5E_PEX0_STN6_RX_DP<96>")
	)
	(segment
		(start 57.661048 -318.129666)
		(end 57.749948 -318.040766)
		(width 0.1143)
		(layer "In9.Cu")
		(net "P5E_PEX0_STN6_RX_DP<96>")
	)
	(segment
		(start 81.953354 -363.558836)
		(end 81.921858 -363.40034)
		(width 0.1651)
		(layer "In9.Cu")
		(net "P5E_PEX0_STN6_RX_DP<96>")
	)
	(segment
		(start 87.880952 -375.999248)
		(end 88.202516 -375.677684)
		(width 0.1651)
		(layer "In9.Cu")
		(net "P5E_PEX0_STN6_RX_DP<96>")
	)
	(segment
		(start 77.392276 -360.373676)
		(end 75.653392 -358.634792)
		(width 0.1651)
		(layer "In9.Cu")
		(net "P5E_PEX0_STN6_RX_DP<96>")
	)
	(segment
		(start 57.749948 -318.040766)
		(end 57.749948 -317.749936)
		(width 0.1143)
		(layer "In9.Cu")
		(net "P5E_PEX0_STN6_RX_DP<96>")
	)
	(segment
		(start 87.30996 -375.490232)
		(end 87.30996 -375.872248)
		(width 0.1651)
		(layer "In9.Cu")
		(net "P5E_PEX0_STN6_RX_DP<96>")
	)
	(segment
		(start 75.205844 -340.501224)
		(end 68.10248 -333.39786)
		(width 0.1651)
		(layer "In9.Cu")
		(net "P5E_PEX0_STN6_RX_DP<96>")
	)
	(segment
		(start 88.202516 -375.677684)
		(end 88.202516 -368.547142)
		(width 0.1651)
		(layer "In9.Cu")
		(net "P5E_PEX0_STN6_RX_DP<96>")
	)
	(segment
		(start 75.653392 -358.634792)
		(end 75.653392 -341.58174)
		(width 0.1651)
		(layer "In9.Cu")
		(net "P5E_PEX0_STN6_RX_DP<96>")
	)
	(segment
		(start 82.365342 -363.834426)
		(end 81.953354 -363.558836)
		(width 0.1651)
		(layer "In9.Cu")
		(net "P5E_PEX0_STN6_RX_DP<96>")
	)
	(segment
		(start 87.658448 -367.233708)
		(end 82.524092 -363.80293)
		(width 0.1651)
		(layer "In9.Cu")
		(net "P5E_PEX0_STN6_RX_DP<96>")
	)
	(segment
		(start 88.202516 -368.547142)
		(end 87.658448 -367.233708)
		(width 0.1651)
		(layer "In9.Cu")
		(net "P5E_PEX0_STN6_RX_DP<96>")
	)
	(segment
		(start 81.921858 -363.40034)
		(end 81.921604 -363.40034)
		(width 0.1651)
		(layer "In9.Cu")
		(net "P5E_PEX0_STN6_RX_DP<96>")
	)
	(segment
		(start 87.43696 -375.999248)
		(end 87.880952 -375.999248)
		(width 0.1651)
		(layer "In9.Cu")
		(net "P5E_PEX0_STN6_RX_DP<96>")
	)
	(segment
		(start 57.179718 -318.406272)
		(end 57.456324 -318.129666)
		(width 0.1143)
		(layer "In9.Cu")
		(net "P5E_PEX0_STN6_RX_DP<96>")
	)
	(segment
		(start 87.30996 -375.872248)
		(end 87.43696 -375.999248)
		(width 0.1651)
		(layer "In9.Cu")
		(net "P5E_PEX0_STN6_RX_DP<96>")
	)
	(segment
		(start 68.10248 -333.39786)
		(end 63.899796 -330.589636)
		(width 0.1651)
		(layer "In9.Cu")
		(net "P5E_PEX0_STN6_RX_DP<96>")
	)
	(segment
		(start 57.133998 -319.916048)
		(end 57.179718 -319.870328)
		(width 0.1143)
		(layer "In9.Cu")
		(net "P5E_PEX0_STN6_RX_DP<96>")
	)
	(segment
		(start 63.899796 -330.589636)
		(end 57.686702 -324.376542)
		(width 0.1651)
		(layer "In9.Cu")
		(net "P5E_PEX0_STN6_RX_DP<96>")
	)
	(segment
		(start 57.456324 -318.129666)
		(end 57.661048 -318.129666)
		(width 0.1143)
		(layer "In9.Cu")
		(net "P5E_PEX0_STN6_RX_DP<96>")
	)
	(segment
		(start 57.133998 -323.04228)
		(end 57.133998 -319.944496)
		(width 0.1651)
		(layer "In9.Cu")
		(net "P5E_PEX0_STN6_RX_DP<96>")
	)
	(segment
		(start 239.705642 -34.227262)
		(end 239.410494 -34.52241)
		(width 0.13462)
		(layer "F.Cu")
		(net "P5E_PEX2_STN2_RX_DP<47>")
	)
	(segment
		(start 242.21948 -34.227262)
		(end 239.705642 -34.227262)
		(width 0.13462)
		(layer "F.Cu")
		(net "P5E_PEX2_STN2_RX_DP<47>")
	)
	(segment
		(start 242.382294 -34.390076)
		(end 242.21948 -34.227262)
		(width 0.13462)
		(layer "F.Cu")
		(net "P5E_PEX2_STN2_RX_DP<47>")
	)
	(segment
		(start 242.864894 -34.390076)
		(end 242.382294 -34.390076)
		(width 0.13462)
		(layer "F.Cu")
		(net "P5E_PEX2_STN2_RX_DP<47>")
	)
	(segment
		(start 276.033738 -271.345152)
		(end 276.033738 -270.490188)
		(width 0.1651)
		(layer "In7.Cu")
		(net "P5E_PEX2_STN2_RX_DP<47>")
	)
	(segment
		(start 275.053298 -263.595612)
		(end 275.053298 -262.326374)
		(width 0.1651)
		(layer "In7.Cu")
		(net "P5E_PEX2_STN2_RX_DP<47>")
	)
	(segment
		(start 242.067588 -57.253632)
		(end 242.182904 -49.871376)
		(width 0.1651)
		(layer "In7.Cu")
		(net "P5E_PEX2_STN2_RX_DP<47>")
	)
	(segment
		(start 275.469858 -267.071856)
		(end 275.053298 -263.595612)
		(width 0.1651)
		(layer "In7.Cu")
		(net "P5E_PEX2_STN2_RX_DP<47>")
	)
	(segment
		(start 240.838736 -37.47135)
		(end 240.806224 -35.357562)
		(width 0.1651)
		(layer "In7.Cu")
		(net "P5E_PEX2_STN2_RX_DP<47>")
	)
	(segment
		(start 276.34184 -273.670014)
		(end 276.079458 -273.407632)
		(width 0.1143)
		(layer "In7.Cu")
		(net "P5E_PEX2_STN2_RX_DP<47>")
	)
	(segment
		(start 276.033738 -270.490188)
		(end 276.033484 -270.489934)
		(width 0.1651)
		(layer "In7.Cu")
		(net "P5E_PEX2_STN2_RX_DP<47>")
	)
	(segment
		(start 269.115286 -215.029288)
		(end 269.115032 -215.029288)
		(width 0.1651)
		(layer "In7.Cu")
		(net "P5E_PEX2_STN2_RX_DP<47>")
	)
	(segment
		(start 240.868454 -39.36365)
		(end 240.765076 -39.263574)
		(width 0.1651)
		(layer "In7.Cu")
		(net "P5E_PEX2_STN2_RX_DP<47>")
	)
	(segment
		(start 240.849658 -38.170104)
		(end 240.74628 -38.070028)
		(width 0.1651)
		(layer "In7.Cu")
		(net "P5E_PEX2_STN2_RX_DP<47>")
	)
	(segment
		(start 276.535388 -273.670014)
		(end 276.34184 -273.670014)
		(width 0.1143)
		(layer "In7.Cu")
		(net "P5E_PEX2_STN2_RX_DP<47>")
	)
	(segment
		(start 240.74628 -38.070028)
		(end 240.73866 -37.574474)
		(width 0.1651)
		(layer "In7.Cu")
		(net "P5E_PEX2_STN2_RX_DP<47>")
	)
	(segment
		(start 255.8161 -144.698974)
		(end 252.564138 -119.974106)
		(width 0.1651)
		(layer "In7.Cu")
		(net "P5E_PEX2_STN2_RX_DP<47>")
	)
	(segment
		(start 275.11883 -255.62306)
		(end 273.548602 -238.473234)
		(width 0.1651)
		(layer "In7.Cu")
		(net "P5E_PEX2_STN2_RX_DP<47>")
	)
	(segment
		(start 276.033738 -271.3736)
		(end 276.033738 -271.345152)
		(width 0.1143)
		(layer "In7.Cu")
		(net "P5E_PEX2_STN2_RX_DP<47>")
	)
	(segment
		(start 269.115032 -215.029288)
		(end 264.682224 -191.58585)
		(width 0.1651)
		(layer "In7.Cu")
		(net "P5E_PEX2_STN2_RX_DP<47>")
	)
	(segment
		(start 276.079458 -271.41932)
		(end 276.033738 -271.3736)
		(width 0.1143)
		(layer "In7.Cu")
		(net "P5E_PEX2_STN2_RX_DP<47>")
	)
	(segment
		(start 273.548602 -238.473234)
		(end 269.115286 -215.029288)
		(width 0.1651)
		(layer "In7.Cu")
		(net "P5E_PEX2_STN2_RX_DP<47>")
	)
	(segment
		(start 242.182904 -49.871376)
		(end 240.881916 -40.241982)
		(width 0.1651)
		(layer "In7.Cu")
		(net "P5E_PEX2_STN2_RX_DP<47>")
	)
	(segment
		(start 276.649688 -274.049744)
		(end 276.649688 -273.784314)
		(width 0.1143)
		(layer "In7.Cu")
		(net "P5E_PEX2_STN2_RX_DP<47>")
	)
	(segment
		(start 239.935004 -34.23158)
		(end 239.701324 -34.23158)
		(width 0.1651)
		(layer "In7.Cu")
		(net "P5E_PEX2_STN2_RX_DP<47>")
	)
	(segment
		(start 247.366536 -102.82682)
		(end 247.366282 -102.826058)
		(width 0.1651)
		(layer "In7.Cu")
		(net "P5E_PEX2_STN2_RX_DP<47>")
	)
	(segment
		(start 252.564138 -119.974106)
		(end 247.366536 -102.82682)
		(width 0.1651)
		(layer "In7.Cu")
		(net "P5E_PEX2_STN2_RX_DP<47>")
	)
	(segment
		(start 242.339368 -62.60719)
		(end 242.339368 -60.256166)
		(width 0.1651)
		(layer "In7.Cu")
		(net "P5E_PEX2_STN2_RX_DP<47>")
	)
	(segment
		(start 247.366282 -102.826058)
		(end 242.149376 -85.615018)
		(width 0.1651)
		(layer "In7.Cu")
		(net "P5E_PEX2_STN2_RX_DP<47>")
	)
	(segment
		(start 240.73866 -37.574474)
		(end 240.838736 -37.47135)
		(width 0.1651)
		(layer "In7.Cu")
		(net "P5E_PEX2_STN2_RX_DP<47>")
	)
	(segment
		(start 240.757456 -38.768274)
		(end 240.857278 -38.66515)
		(width 0.1651)
		(layer "In7.Cu")
		(net "P5E_PEX2_STN2_RX_DP<47>")
	)
	(segment
		(start 240.765076 -39.263574)
		(end 240.757456 -38.768274)
		(width 0.1651)
		(layer "In7.Cu")
		(net "P5E_PEX2_STN2_RX_DP<47>")
	)
	(segment
		(start 276.649688 -273.784314)
		(end 276.535388 -273.670014)
		(width 0.1143)
		(layer "In7.Cu")
		(net "P5E_PEX2_STN2_RX_DP<47>")
	)
	(segment
		(start 240.881916 -40.241982)
		(end 240.868454 -39.36365)
		(width 0.1651)
		(layer "In7.Cu")
		(net "P5E_PEX2_STN2_RX_DP<47>")
	)
	(segment
		(start 276.033484 -270.489934)
		(end 275.839174 -268.869414)
		(width 0.1651)
		(layer "In7.Cu")
		(net "P5E_PEX2_STN2_RX_DP<47>")
	)
	(segment
		(start 275.839174 -268.869414)
		(end 275.469858 -267.071856)
		(width 0.1651)
		(layer "In7.Cu")
		(net "P5E_PEX2_STN2_RX_DP<47>")
	)
	(segment
		(start 275.053298 -262.326374)
		(end 275.11883 -255.62306)
		(width 0.1651)
		(layer "In7.Cu")
		(net "P5E_PEX2_STN2_RX_DP<47>")
	)
	(segment
		(start 239.701324 -34.23158)
		(end 239.410494 -34.52241)
		(width 0.1651)
		(layer "In7.Cu")
		(net "P5E_PEX2_STN2_RX_DP<47>")
	)
	(segment
		(start 240.806224 -35.357562)
		(end 240.806224 -35.1028)
		(width 0.1651)
		(layer "In7.Cu")
		(net "P5E_PEX2_STN2_RX_DP<47>")
	)
	(segment
		(start 242.339368 -60.256166)
		(end 242.067588 -57.253632)
		(width 0.1651)
		(layer "In7.Cu")
		(net "P5E_PEX2_STN2_RX_DP<47>")
	)
	(segment
		(start 276.079458 -273.407632)
		(end 276.079458 -271.41932)
		(width 0.1143)
		(layer "In7.Cu")
		(net "P5E_PEX2_STN2_RX_DP<47>")
	)
	(segment
		(start 240.806224 -35.1028)
		(end 239.935004 -34.23158)
		(width 0.1651)
		(layer "In7.Cu")
		(net "P5E_PEX2_STN2_RX_DP<47>")
	)
	(segment
		(start 264.68197 -191.58585)
		(end 255.8161 -144.698974)
		(width 0.1651)
		(layer "In7.Cu")
		(net "P5E_PEX2_STN2_RX_DP<47>")
	)
	(segment
		(start 240.857278 -38.66515)
		(end 240.849658 -38.170104)
		(width 0.1651)
		(layer "In7.Cu")
		(net "P5E_PEX2_STN2_RX_DP<47>")
	)
	(segment
		(start 264.682224 -191.58585)
		(end 264.68197 -191.58585)
		(width 0.1651)
		(layer "In7.Cu")
		(net "P5E_PEX2_STN2_RX_DP<47>")
	)
	(segment
		(start 242.149376 -85.615018)
		(end 242.339368 -62.60719)
		(width 0.1651)
		(layer "In7.Cu")
		(net "P5E_PEX2_STN2_RX_DP<47>")
	)
	(segment
		(start 422.231312 -153.7208)
		(end 422.06545 -153.554938)
		(width 0.13462)
		(layer "F.Cu")
		(net "P5E_PEX3_STN0_TX_C_DP<14>")
	)
	(segment
		(start 428.052738 -153.390346)
		(end 427.722284 -153.7208)
		(width 0.13462)
		(layer "F.Cu")
		(net "P5E_PEX3_STN0_TX_C_DP<14>")
	)
	(segment
		(start 422.06545 -153.554938)
		(end 421.557704 -153.554938)
		(width 0.13462)
		(layer "F.Cu")
		(net "P5E_PEX3_STN0_TX_C_DP<14>")
	)
	(segment
		(start 427.722284 -153.7208)
		(end 422.231312 -153.7208)
		(width 0.13462)
		(layer "F.Cu")
		(net "P5E_PEX3_STN0_TX_C_DP<14>")
	)
	(segment
		(start 386.489956 -371.590062)
		(end 386.489956 -371.972078)
		(width 0.1651)
		(layer "In15.Cu")
		(net "P5E_PEX3_STN5_RX_DP<93>")
	)
	(segment
		(start 403.668484 -338.586572)
		(end 404.015702 -338.233004)
		(width 0.1651)
		(layer "In15.Cu")
		(net "P5E_PEX3_STN5_RX_DP<93>")
	)
	(segment
		(start 402.850604 -339.546184)
		(end 402.849334 -339.420454)
		(width 0.1651)
		(layer "In15.Cu")
		(net "P5E_PEX3_STN5_RX_DP<93>")
	)
	(segment
		(start 403.6695 -338.712302)
		(end 403.668484 -338.586572)
		(width 0.1651)
		(layer "In15.Cu")
		(net "P5E_PEX3_STN5_RX_DP<93>")
	)
	(segment
		(start 386.489956 -371.972078)
		(end 386.616956 -372.099078)
		(width 0.1651)
		(layer "In15.Cu")
		(net "P5E_PEX3_STN5_RX_DP<93>")
	)
	(segment
		(start 402.849334 -339.420454)
		(end 403.196806 -339.066886)
		(width 0.1651)
		(layer "In15.Cu")
		(net "P5E_PEX3_STN5_RX_DP<93>")
	)
	(segment
		(start 403.196806 -339.066886)
		(end 403.322536 -339.065616)
		(width 0.1651)
		(layer "In15.Cu")
		(net "P5E_PEX3_STN5_RX_DP<93>")
	)
	(segment
		(start 400.457416 -359.12933)
		(end 401.01393 -358.013762)
		(width 0.1651)
		(layer "In15.Cu")
		(net "P5E_PEX3_STN5_RX_DP<93>")
	)
	(segment
		(start 386.616956 -372.099078)
		(end 387.047232 -372.099078)
		(width 0.1651)
		(layer "In15.Cu")
		(net "P5E_PEX3_STN5_RX_DP<93>")
	)
	(segment
		(start 403.322536 -339.065616)
		(end 403.6695 -338.712302)
		(width 0.1651)
		(layer "In15.Cu")
		(net "P5E_PEX3_STN5_RX_DP<93>")
	)
	(segment
		(start 418.994844 -318.129666)
		(end 419.235636 -318.129666)
		(width 0.1143)
		(layer "In15.Cu")
		(net "P5E_PEX3_STN5_RX_DP<93>")
	)
	(segment
		(start 404.488396 -337.878674)
		(end 404.48738 -337.752944)
		(width 0.1651)
		(layer "In15.Cu")
		(net "P5E_PEX3_STN5_RX_DP<93>")
	)
	(segment
		(start 418.779706 -319.895728)
		(end 418.779706 -318.344804)
		(width 0.1143)
		(layer "In15.Cu")
		(net "P5E_PEX3_STN5_RX_DP<93>")
	)
	(segment
		(start 404.48738 -337.752944)
		(end 404.834598 -337.399376)
		(width 0.1651)
		(layer "In15.Cu")
		(net "P5E_PEX3_STN5_RX_DP<93>")
	)
	(segment
		(start 418.733986 -319.969896)
		(end 418.733986 -319.941448)
		(width 0.1143)
		(layer "In15.Cu")
		(net "P5E_PEX3_STN5_RX_DP<93>")
	)
	(segment
		(start 401.01393 -358.013762)
		(end 401.01393 -342.114886)
		(width 0.1651)
		(layer "In15.Cu")
		(net "P5E_PEX3_STN5_RX_DP<93>")
	)
	(segment
		(start 418.733986 -322.590668)
		(end 418.733986 -319.969896)
		(width 0.1651)
		(layer "In15.Cu")
		(net "P5E_PEX3_STN5_RX_DP<93>")
	)
	(segment
		(start 419.349936 -318.015366)
		(end 419.349936 -317.749936)
		(width 0.1143)
		(layer "In15.Cu")
		(net "P5E_PEX3_STN5_RX_DP<93>")
	)
	(segment
		(start 401.01393 -342.114886)
		(end 401.522946 -340.897718)
		(width 0.1651)
		(layer "In15.Cu")
		(net "P5E_PEX3_STN5_RX_DP<93>")
	)
	(segment
		(start 418.779706 -318.344804)
		(end 418.994844 -318.129666)
		(width 0.1143)
		(layer "In15.Cu")
		(net "P5E_PEX3_STN5_RX_DP<93>")
	)
	(segment
		(start 404.960328 -337.39836)
		(end 417.141152 -324.997572)
		(width 0.1651)
		(layer "In15.Cu")
		(net "P5E_PEX3_STN5_RX_DP<93>")
	)
	(segment
		(start 387.333998 -369.49507)
		(end 387.63575 -368.790982)
		(width 0.1651)
		(layer "In15.Cu")
		(net "P5E_PEX3_STN5_RX_DP<93>")
	)
	(segment
		(start 404.834598 -337.399376)
		(end 404.960328 -337.39836)
		(width 0.1651)
		(layer "In15.Cu")
		(net "P5E_PEX3_STN5_RX_DP<93>")
	)
	(segment
		(start 419.235636 -318.129666)
		(end 419.349936 -318.015366)
		(width 0.1143)
		(layer "In15.Cu")
		(net "P5E_PEX3_STN5_RX_DP<93>")
	)
	(segment
		(start 404.015702 -338.233004)
		(end 404.141432 -338.231988)
		(width 0.1651)
		(layer "In15.Cu")
		(net "P5E_PEX3_STN5_RX_DP<93>")
	)
	(segment
		(start 404.141432 -338.231988)
		(end 404.488396 -337.878674)
		(width 0.1651)
		(layer "In15.Cu")
		(net "P5E_PEX3_STN5_RX_DP<93>")
	)
	(segment
		(start 387.63575 -368.790982)
		(end 400.457416 -359.12933)
		(width 0.1651)
		(layer "In15.Cu")
		(net "P5E_PEX3_STN5_RX_DP<93>")
	)
	(segment
		(start 401.522946 -340.897718)
		(end 402.850604 -339.546184)
		(width 0.1651)
		(layer "In15.Cu")
		(net "P5E_PEX3_STN5_RX_DP<93>")
	)
	(segment
		(start 418.733986 -319.941448)
		(end 418.779706 -319.895728)
		(width 0.1143)
		(layer "In15.Cu")
		(net "P5E_PEX3_STN5_RX_DP<93>")
	)
	(segment
		(start 387.047232 -372.099078)
		(end 387.333998 -371.812312)
		(width 0.1651)
		(layer "In15.Cu")
		(net "P5E_PEX3_STN5_RX_DP<93>")
	)
	(segment
		(start 417.141152 -324.997572)
		(end 418.733986 -322.590668)
		(width 0.1651)
		(layer "In15.Cu")
		(net "P5E_PEX3_STN5_RX_DP<93>")
	)
	(segment
		(start 387.333998 -371.812312)
		(end 387.333998 -369.49507)
		(width 0.1651)
		(layer "In15.Cu")
		(net "P5E_PEX3_STN5_RX_DP<93>")
	)
	(segment
		(start 50.64252 -134.765034)
		(end 51.130454 -134.765034)
		(width 0.13462)
		(layer "F.Cu")
		(net "P5E_PEX0_STN1_RX_DN<30>")
	)
	(segment
		(start 51.293268 -134.60222)
		(end 53.801772 -134.60222)
		(width 0.13462)
		(layer "F.Cu")
		(net "P5E_PEX0_STN1_RX_DN<30>")
	)
	(segment
		(start 51.130454 -134.765034)
		(end 51.293268 -134.60222)
		(width 0.13462)
		(layer "F.Cu")
		(net "P5E_PEX0_STN1_RX_DN<30>")
	)
	(segment
		(start 53.80228 -134.601712)
		(end 54.09692 -134.896352)
		(width 0.13462)
		(layer "F.Cu")
		(net "P5E_PEX0_STN1_RX_DN<30>")
	)
	(segment
		(start 53.801772 -134.60222)
		(end 53.80228 -134.601712)
		(width 0.13462)
		(layer "F.Cu")
		(net "P5E_PEX0_STN1_RX_DN<30>")
	)
	(segment
		(start 50.135536 -140.600176)
		(end 50.021236 -140.714476)
		(width 0.1651)
		(layer "In5.Cu")
		(net "P5E_PEX0_STN1_RX_DN<30>")
	)
	(segment
		(start 43.230546 -151.792686)
		(end 43.340782 -151.889206)
		(width 0.1651)
		(layer "In5.Cu")
		(net "P5E_PEX0_STN1_RX_DN<30>")
	)
	(segment
		(start 43.340782 -151.889206)
		(end 43.375072 -152.40508)
		(width 0.1651)
		(layer "In5.Cu")
		(net "P5E_PEX0_STN1_RX_DN<30>")
	)
	(segment
		(start 72.949562 -273.365214)
		(end 72.949562 -273.099784)
		(width 0.1143)
		(layer "In5.Cu")
		(net "P5E_PEX0_STN1_RX_DN<30>")
	)
	(segment
		(start 72.835262 -273.479514)
		(end 72.949562 -273.365214)
		(width 0.1143)
		(layer "In5.Cu")
		(net "P5E_PEX0_STN1_RX_DN<30>")
	)
	(segment
		(start 45.69714 -146.674586)
		(end 44.500546 -147.17014)
		(width 0.1651)
		(layer "In5.Cu")
		(net "P5E_PEX0_STN1_RX_DN<30>")
	)
	(segment
		(start 50.86604 -135.644382)
		(end 50.65395 -136.092438)
		(width 0.1651)
		(layer "In5.Cu")
		(net "P5E_PEX0_STN1_RX_DN<30>")
	)
	(segment
		(start 43.503596 -154.767026)
		(end 43.433492 -154.847036)
		(width 0.1651)
		(layer "In5.Cu")
		(net "P5E_PEX0_STN1_RX_DN<30>")
	)
	(segment
		(start 43.311318 -153.009346)
		(end 43.40606 -153.09215)
		(width 0.1651)
		(layer "In5.Cu")
		(net "P5E_PEX0_STN1_RX_DN<30>")
	)
	(segment
		(start 50.021236 -137.163302)
		(end 50.021236 -138.771376)
		(width 0.1651)
		(layer "In5.Cu")
		(net "P5E_PEX0_STN1_RX_DN<30>")
	)
	(segment
		(start 48.187102 -144.286478)
		(end 46.763178 -145.454624)
		(width 0.1651)
		(layer "In5.Cu")
		(net "P5E_PEX0_STN1_RX_DN<30>")
	)
	(segment
		(start 72.673464 -273.479514)
		(end 72.835262 -273.479514)
		(width 0.1143)
		(layer "In5.Cu")
		(net "P5E_PEX0_STN1_RX_DN<30>")
	)
	(segment
		(start 44.500546 -147.17014)
		(end 44.006262 -147.17014)
		(width 0.1651)
		(layer "In5.Cu")
		(net "P5E_PEX0_STN1_RX_DN<30>")
	)
	(segment
		(start 50.65395 -136.092438)
		(end 50.501804 -136.147048)
		(width 0.1651)
		(layer "In5.Cu")
		(net "P5E_PEX0_STN1_RX_DN<30>")
	)
	(segment
		(start 53.042566 -134.719822)
		(end 52.547266 -134.719822)
		(width 0.1651)
		(layer "In5.Cu")
		(net "P5E_PEX0_STN1_RX_DN<30>")
	)
	(segment
		(start 52.432966 -134.605522)
		(end 51.937666 -134.605522)
		(width 0.1651)
		(layer "In5.Cu")
		(net "P5E_PEX0_STN1_RX_DN<30>")
	)
	(segment
		(start 52.547266 -134.719822)
		(end 52.432966 -134.605522)
		(width 0.1651)
		(layer "In5.Cu")
		(net "P5E_PEX0_STN1_RX_DN<30>")
	)
	(segment
		(start 53.803804 -134.603236)
		(end 53.797708 -134.605522)
		(width 0.1651)
		(layer "In5.Cu")
		(net "P5E_PEX0_STN1_RX_DN<30>")
	)
	(segment
		(start 43.40606 -153.09215)
		(end 43.438826 -153.586688)
		(width 0.1651)
		(layer "In5.Cu")
		(net "P5E_PEX0_STN1_RX_DN<30>")
	)
	(segment
		(start 49.764442 -142.128494)
		(end 49.574958 -142.586202)
		(width 0.1651)
		(layer "In5.Cu")
		(net "P5E_PEX0_STN1_RX_DN<30>")
	)
	(segment
		(start 43.433492 -154.847036)
		(end 43.556936 -156.713936)
		(width 0.1651)
		(layer "In5.Cu")
		(net "P5E_PEX0_STN1_RX_DN<30>")
	)
	(segment
		(start 49.574958 -142.586202)
		(end 49.425352 -142.648178)
		(width 0.1651)
		(layer "In5.Cu")
		(net "P5E_PEX0_STN1_RX_DN<30>")
	)
	(segment
		(start 44.268136 -160.706816)
		(end 72.615806 -267.233654)
		(width 0.1651)
		(layer "In5.Cu")
		(net "P5E_PEX0_STN1_RX_DN<30>")
	)
	(segment
		(start 43.356022 -153.681176)
		(end 43.388534 -154.175206)
		(width 0.1651)
		(layer "In5.Cu")
		(net "P5E_PEX0_STN1_RX_DN<30>")
	)
	(segment
		(start 54.09692 -134.896352)
		(end 53.803804 -134.603236)
		(width 0.1651)
		(layer "In5.Cu")
		(net "P5E_PEX0_STN1_RX_DN<30>")
	)
	(segment
		(start 50.135536 -140.104876)
		(end 50.135536 -140.600176)
		(width 0.1651)
		(layer "In5.Cu")
		(net "P5E_PEX0_STN1_RX_DN<30>")
	)
	(segment
		(start 43.56481 -147.328636)
		(end 43.238166 -147.574)
		(width 0.1651)
		(layer "In5.Cu")
		(net "P5E_PEX0_STN1_RX_DN<30>")
	)
	(segment
		(start 72.615806 -271.554448)
		(end 72.570086 -271.600168)
		(width 0.1143)
		(layer "In5.Cu")
		(net "P5E_PEX0_STN1_RX_DN<30>")
	)
	(segment
		(start 51.135788 -134.937754)
		(end 51.023266 -135.044688)
		(width 0.1651)
		(layer "In5.Cu")
		(net "P5E_PEX0_STN1_RX_DN<30>")
	)
	(segment
		(start 53.797708 -134.605522)
		(end 53.156866 -134.605522)
		(width 0.1651)
		(layer "In5.Cu")
		(net "P5E_PEX0_STN1_RX_DN<30>")
	)
	(segment
		(start 72.570086 -271.600168)
		(end 72.570086 -273.376136)
		(width 0.1143)
		(layer "In5.Cu")
		(net "P5E_PEX0_STN1_RX_DN<30>")
	)
	(segment
		(start 43.304206 -151.17699)
		(end 43.19778 -151.298656)
		(width 0.1651)
		(layer "In5.Cu")
		(net "P5E_PEX0_STN1_RX_DN<30>")
	)
	(segment
		(start 72.615806 -271.526)
		(end 72.615806 -271.554448)
		(width 0.1143)
		(layer "In5.Cu")
		(net "P5E_PEX0_STN1_RX_DN<30>")
	)
	(segment
		(start 72.570086 -273.376136)
		(end 72.673464 -273.479514)
		(width 0.1143)
		(layer "In5.Cu")
		(net "P5E_PEX0_STN1_RX_DN<30>")
	)
	(segment
		(start 50.021236 -139.990576)
		(end 50.135536 -140.104876)
		(width 0.1651)
		(layer "In5.Cu")
		(net "P5E_PEX0_STN1_RX_DN<30>")
	)
	(segment
		(start 51.023266 -135.044688)
		(end 50.811684 -135.492236)
		(width 0.1651)
		(layer "In5.Cu")
		(net "P5E_PEX0_STN1_RX_DN<30>")
	)
	(segment
		(start 50.021236 -139.495276)
		(end 50.021236 -139.990576)
		(width 0.1651)
		(layer "In5.Cu")
		(net "P5E_PEX0_STN1_RX_DN<30>")
	)
	(segment
		(start 43.438826 -153.586688)
		(end 43.356022 -153.681176)
		(width 0.1651)
		(layer "In5.Cu")
		(net "P5E_PEX0_STN1_RX_DN<30>")
	)
	(segment
		(start 46.763178 -145.454624)
		(end 46.450758 -145.920968)
		(width 0.1651)
		(layer "In5.Cu")
		(net "P5E_PEX0_STN1_RX_DN<30>")
	)
	(segment
		(start 53.156866 -134.605522)
		(end 53.042566 -134.719822)
		(width 0.1651)
		(layer "In5.Cu")
		(net "P5E_PEX0_STN1_RX_DN<30>")
	)
	(segment
		(start 43.707304 -147.257262)
		(end 43.56481 -147.328636)
		(width 0.1651)
		(layer "In5.Cu")
		(net "P5E_PEX0_STN1_RX_DN<30>")
	)
	(segment
		(start 50.021236 -140.714476)
		(end 50.021236 -141.209776)
		(width 0.1651)
		(layer "In5.Cu")
		(net "P5E_PEX0_STN1_RX_DN<30>")
	)
	(segment
		(start 50.135536 -138.885676)
		(end 50.135536 -139.380976)
		(width 0.1651)
		(layer "In5.Cu")
		(net "P5E_PEX0_STN1_RX_DN<30>")
	)
	(segment
		(start 49.425352 -142.648178)
		(end 49.425352 -142.648432)
		(width 0.1651)
		(layer "In5.Cu")
		(net "P5E_PEX0_STN1_RX_DN<30>")
	)
	(segment
		(start 51.937666 -134.605522)
		(end 51.135788 -134.937754)
		(width 0.1651)
		(layer "In5.Cu")
		(net "P5E_PEX0_STN1_RX_DN<30>")
	)
	(segment
		(start 49.425352 -142.648432)
		(end 49.14265 -143.33093)
		(width 0.1651)
		(layer "In5.Cu")
		(net "P5E_PEX0_STN1_RX_DN<30>")
	)
	(segment
		(start 43.149774 -150.576026)
		(end 43.14952 -150.576026)
		(width 0.1651)
		(layer "In5.Cu")
		(net "P5E_PEX0_STN1_RX_DN<30>")
	)
	(segment
		(start 49.70272 -141.979142)
		(end 49.764442 -142.128494)
		(width 0.1651)
		(layer "In5.Cu")
		(net "P5E_PEX0_STN1_RX_DN<30>")
	)
	(segment
		(start 43.238166 -147.574)
		(end 42.985436 -148.099526)
		(width 0.1651)
		(layer "In5.Cu")
		(net "P5E_PEX0_STN1_RX_DN<30>")
	)
	(segment
		(start 50.501804 -136.147302)
		(end 50.021236 -137.163302)
		(width 0.1651)
		(layer "In5.Cu")
		(net "P5E_PEX0_STN1_RX_DN<30>")
	)
	(segment
		(start 50.135536 -139.380976)
		(end 50.021236 -139.495276)
		(width 0.1651)
		(layer "In5.Cu")
		(net "P5E_PEX0_STN1_RX_DN<30>")
	)
	(segment
		(start 43.556936 -156.713936)
		(end 44.268136 -160.706816)
		(width 0.1651)
		(layer "In5.Cu")
		(net "P5E_PEX0_STN1_RX_DN<30>")
	)
	(segment
		(start 50.501804 -136.147048)
		(end 50.501804 -136.147302)
		(width 0.1651)
		(layer "In5.Cu")
		(net "P5E_PEX0_STN1_RX_DN<30>")
	)
	(segment
		(start 43.27144 -150.682452)
		(end 43.304206 -151.17699)
		(width 0.1651)
		(layer "In5.Cu")
		(net "P5E_PEX0_STN1_RX_DN<30>")
	)
	(segment
		(start 42.985436 -148.099526)
		(end 43.149774 -150.576026)
		(width 0.1651)
		(layer "In5.Cu")
		(net "P5E_PEX0_STN1_RX_DN<30>")
	)
	(segment
		(start 50.811684 -135.492236)
		(end 50.86604 -135.644382)
		(width 0.1651)
		(layer "In5.Cu")
		(net "P5E_PEX0_STN1_RX_DN<30>")
	)
	(segment
		(start 46.450758 -145.920968)
		(end 45.69714 -146.674586)
		(width 0.1651)
		(layer "In5.Cu")
		(net "P5E_PEX0_STN1_RX_DN<30>")
	)
	(segment
		(start 44.006262 -147.17014)
		(end 43.707304 -147.257262)
		(width 0.1651)
		(layer "In5.Cu")
		(net "P5E_PEX0_STN1_RX_DN<30>")
	)
	(segment
		(start 50.021236 -138.771376)
		(end 50.135536 -138.885676)
		(width 0.1651)
		(layer "In5.Cu")
		(net "P5E_PEX0_STN1_RX_DN<30>")
	)
	(segment
		(start 43.469052 -154.245564)
		(end 43.503596 -154.767026)
		(width 0.1651)
		(layer "In5.Cu")
		(net "P5E_PEX0_STN1_RX_DN<30>")
	)
	(segment
		(start 43.278552 -152.515316)
		(end 43.311318 -153.009346)
		(width 0.1651)
		(layer "In5.Cu")
		(net "P5E_PEX0_STN1_RX_DN<30>")
	)
	(segment
		(start 50.021236 -141.209776)
		(end 49.70272 -141.979142)
		(width 0.1651)
		(layer "In5.Cu")
		(net "P5E_PEX0_STN1_RX_DN<30>")
	)
	(segment
		(start 43.375072 -152.40508)
		(end 43.278552 -152.515316)
		(width 0.1651)
		(layer "In5.Cu")
		(net "P5E_PEX0_STN1_RX_DN<30>")
	)
	(segment
		(start 72.615806 -267.233654)
		(end 72.615806 -271.526)
		(width 0.1651)
		(layer "In5.Cu")
		(net "P5E_PEX0_STN1_RX_DN<30>")
	)
	(segment
		(start 43.14952 -150.576026)
		(end 43.27144 -150.682452)
		(width 0.1651)
		(layer "In5.Cu")
		(net "P5E_PEX0_STN1_RX_DN<30>")
	)
	(segment
		(start 49.14265 -143.33093)
		(end 48.187102 -144.286478)
		(width 0.1651)
		(layer "In5.Cu")
		(net "P5E_PEX0_STN1_RX_DN<30>")
	)
	(segment
		(start 43.19778 -151.298656)
		(end 43.230546 -151.792686)
		(width 0.1651)
		(layer "In5.Cu")
		(net "P5E_PEX0_STN1_RX_DN<30>")
	)
	(segment
		(start 43.388534 -154.175206)
		(end 43.469052 -154.245564)
		(width 0.1651)
		(layer "In5.Cu")
		(net "P5E_PEX0_STN1_RX_DN<30>")
	)
	(segment
		(start 51.670204 -319.870328)
		(end 51.670204 -318.485266)
		(width 0.1143)
		(layer "In9.Cu")
		(net "P5E_PEX0_STN6_RX_DN<102>")
	)
	(segment
		(start 51.961034 -318.320166)
		(end 52.049934 -318.409066)
		(width 0.1143)
		(layer "In9.Cu")
		(net "P5E_PEX0_STN6_RX_DN<102>")
	)
	(segment
		(start 75.28433 -369.346226)
		(end 74.795888 -368.167158)
		(width 0.1651)
		(layer "In9.Cu")
		(net "P5E_PEX0_STN6_RX_DN<102>")
	)
	(segment
		(start 74.109834 -376.408188)
		(end 74.236834 -376.281188)
		(width 0.1651)
		(layer "In9.Cu")
		(net "P5E_PEX0_STN6_RX_DN<102>")
	)
	(segment
		(start 74.109834 -376.790204)
		(end 74.109834 -376.408188)
		(width 0.1651)
		(layer "In9.Cu")
		(net "P5E_PEX0_STN6_RX_DN<102>")
	)
	(segment
		(start 59.807348 -354.273104)
		(end 58.248296 -346.435426)
		(width 0.1651)
		(layer "In9.Cu")
		(net "P5E_PEX0_STN6_RX_DN<102>")
	)
	(segment
		(start 74.236834 -376.281188)
		(end 74.797666 -376.281188)
		(width 0.1651)
		(layer "In9.Cu")
		(net "P5E_PEX0_STN6_RX_DN<102>")
	)
	(segment
		(start 58.248296 -346.435426)
		(end 51.715924 -324.902322)
		(width 0.1651)
		(layer "In9.Cu")
		(net "P5E_PEX0_STN6_RX_DN<102>")
	)
	(segment
		(start 74.795888 -368.167158)
		(end 65.317878 -361.833922)
		(width 0.1651)
		(layer "In9.Cu")
		(net "P5E_PEX0_STN6_RX_DN<102>")
	)
	(segment
		(start 52.049934 -318.409066)
		(end 52.049934 -318.699896)
		(width 0.1143)
		(layer "In9.Cu")
		(net "P5E_PEX0_STN6_RX_DN<102>")
	)
	(segment
		(start 51.715924 -319.944496)
		(end 51.715924 -319.916048)
		(width 0.1143)
		(layer "In9.Cu")
		(net "P5E_PEX0_STN6_RX_DN<102>")
	)
	(segment
		(start 62.038484 -359.659428)
		(end 59.807348 -354.273104)
		(width 0.1651)
		(layer "In9.Cu")
		(net "P5E_PEX0_STN6_RX_DN<102>")
	)
	(segment
		(start 75.28433 -375.794524)
		(end 75.28433 -369.346226)
		(width 0.1651)
		(layer "In9.Cu")
		(net "P5E_PEX0_STN6_RX_DN<102>")
	)
	(segment
		(start 65.317878 -361.833922)
		(end 63.431928 -361.052872)
		(width 0.1651)
		(layer "In9.Cu")
		(net "P5E_PEX0_STN6_RX_DN<102>")
	)
	(segment
		(start 74.797666 -376.281188)
		(end 75.28433 -375.794524)
		(width 0.1651)
		(layer "In9.Cu")
		(net "P5E_PEX0_STN6_RX_DN<102>")
	)
	(segment
		(start 63.431928 -361.052872)
		(end 62.038484 -359.659428)
		(width 0.1651)
		(layer "In9.Cu")
		(net "P5E_PEX0_STN6_RX_DN<102>")
	)
	(segment
		(start 51.670204 -318.485266)
		(end 51.835304 -318.320166)
		(width 0.1143)
		(layer "In9.Cu")
		(net "P5E_PEX0_STN6_RX_DN<102>")
	)
	(segment
		(start 51.715924 -324.902322)
		(end 51.715924 -319.944496)
		(width 0.1651)
		(layer "In9.Cu")
		(net "P5E_PEX0_STN6_RX_DN<102>")
	)
	(segment
		(start 51.715924 -319.916048)
		(end 51.670204 -319.870328)
		(width 0.1143)
		(layer "In9.Cu")
		(net "P5E_PEX0_STN6_RX_DN<102>")
	)
	(segment
		(start 51.835304 -318.320166)
		(end 51.961034 -318.320166)
		(width 0.1143)
		(layer "In9.Cu")
		(net "P5E_PEX0_STN6_RX_DN<102>")
	)
	(segment
		(start 294.86479 -30.790134)
		(end 294.38219 -30.790134)
		(width 0.13462)
		(layer "F.Cu")
		(net "P5E_PEX2_STN2_RX_DP<37>")
	)
	(segment
		(start 294.38219 -30.790134)
		(end 294.219376 -30.62732)
		(width 0.13462)
		(layer "F.Cu")
		(net "P5E_PEX2_STN2_RX_DP<37>")
	)
	(segment
		(start 291.705538 -30.62732)
		(end 291.41039 -30.922468)
		(width 0.13462)
		(layer "F.Cu")
		(net "P5E_PEX2_STN2_RX_DP<37>")
	)
	(segment
		(start 294.219376 -30.62732)
		(end 291.705538 -30.62732)
		(width 0.13462)
		(layer "F.Cu")
		(net "P5E_PEX2_STN2_RX_DP<37>")
	)
	(segment
		(start 293.872158 -30.631638)
		(end 293.376858 -30.631638)
		(width 0.1651)
		(layer "In7.Cu")
		(net "P5E_PEX2_STN2_RX_DP<37>")
	)
	(segment
		(start 294.852852 -39.991792)
		(end 294.80256 -39.321486)
		(width 0.1651)
		(layer "In7.Cu")
		(net "P5E_PEX2_STN2_RX_DP<37>")
	)
	(segment
		(start 285.841948 -273.670014)
		(end 285.579566 -273.407632)
		(width 0.1143)
		(layer "In7.Cu")
		(net "P5E_PEX2_STN2_RX_DP<37>")
	)
	(segment
		(start 296.222674 -50.12817)
		(end 294.852852 -39.991792)
		(width 0.1651)
		(layer "In7.Cu")
		(net "P5E_PEX2_STN2_RX_DP<37>")
	)
	(segment
		(start 291.70122 -30.631638)
		(end 291.41039 -30.922468)
		(width 0.1651)
		(layer "In7.Cu")
		(net "P5E_PEX2_STN2_RX_DP<37>")
	)
	(segment
		(start 285.579566 -273.407632)
		(end 285.579566 -271.41932)
		(width 0.1143)
		(layer "In7.Cu")
		(net "P5E_PEX2_STN2_RX_DP<37>")
	)
	(segment
		(start 285.533846 -266.379706)
		(end 285.66491 -264.886186)
		(width 0.1651)
		(layer "In7.Cu")
		(net "P5E_PEX2_STN2_RX_DP<37>")
	)
	(segment
		(start 286.149796 -274.049744)
		(end 286.149796 -273.784314)
		(width 0.1143)
		(layer "In7.Cu")
		(net "P5E_PEX2_STN2_RX_DP<37>")
	)
	(segment
		(start 286.035496 -273.670014)
		(end 285.841948 -273.670014)
		(width 0.1143)
		(layer "In7.Cu")
		(net "P5E_PEX2_STN2_RX_DP<37>")
	)
	(segment
		(start 294.48506 -31.388304)
		(end 294.48506 -31.24454)
		(width 0.1651)
		(layer "In7.Cu")
		(net "P5E_PEX2_STN2_RX_DP<37>")
	)
	(segment
		(start 285.533846 -271.3736)
		(end 285.533846 -271.345152)
		(width 0.1143)
		(layer "In7.Cu")
		(net "P5E_PEX2_STN2_RX_DP<37>")
	)
	(segment
		(start 285.66491 -264.886186)
		(end 296.038524 -68.490084)
		(width 0.1651)
		(layer "In7.Cu")
		(net "P5E_PEX2_STN2_RX_DP<37>")
	)
	(segment
		(start 285.579566 -271.41932)
		(end 285.533846 -271.3736)
		(width 0.1143)
		(layer "In7.Cu")
		(net "P5E_PEX2_STN2_RX_DP<37>")
	)
	(segment
		(start 294.83558 -31.738824)
		(end 294.48506 -31.388304)
		(width 0.1651)
		(layer "In7.Cu")
		(net "P5E_PEX2_STN2_RX_DP<37>")
	)
	(segment
		(start 294.80256 -39.321486)
		(end 294.780716 -37.940234)
		(width 0.1651)
		(layer "In7.Cu")
		(net "P5E_PEX2_STN2_RX_DP<37>")
	)
	(segment
		(start 293.376858 -30.631638)
		(end 293.275258 -30.733238)
		(width 0.1651)
		(layer "In7.Cu")
		(net "P5E_PEX2_STN2_RX_DP<37>")
	)
	(segment
		(start 295.329356 -32.088836)
		(end 294.979344 -31.738824)
		(width 0.1651)
		(layer "In7.Cu")
		(net "P5E_PEX2_STN2_RX_DP<37>")
	)
	(segment
		(start 292.779958 -30.733238)
		(end 292.678358 -30.631638)
		(width 0.1651)
		(layer "In7.Cu")
		(net "P5E_PEX2_STN2_RX_DP<37>")
	)
	(segment
		(start 295.305988 -34.981642)
		(end 295.329356 -32.088836)
		(width 0.1651)
		(layer "In7.Cu")
		(net "P5E_PEX2_STN2_RX_DP<37>")
	)
	(segment
		(start 293.275258 -30.733238)
		(end 292.779958 -30.733238)
		(width 0.1651)
		(layer "In7.Cu")
		(net "P5E_PEX2_STN2_RX_DP<37>")
	)
	(segment
		(start 292.678358 -30.631638)
		(end 291.70122 -30.631638)
		(width 0.1651)
		(layer "In7.Cu")
		(net "P5E_PEX2_STN2_RX_DP<37>")
	)
	(segment
		(start 294.780716 -37.940234)
		(end 295.305988 -34.981642)
		(width 0.1651)
		(layer "In7.Cu")
		(net "P5E_PEX2_STN2_RX_DP<37>")
	)
	(segment
		(start 286.149796 -273.784314)
		(end 286.035496 -273.670014)
		(width 0.1143)
		(layer "In7.Cu")
		(net "P5E_PEX2_STN2_RX_DP<37>")
	)
	(segment
		(start 294.48506 -31.24454)
		(end 293.872158 -30.631638)
		(width 0.1651)
		(layer "In7.Cu")
		(net "P5E_PEX2_STN2_RX_DP<37>")
	)
	(segment
		(start 296.038524 -68.490084)
		(end 296.222674 -50.12817)
		(width 0.1651)
		(layer "In7.Cu")
		(net "P5E_PEX2_STN2_RX_DP<37>")
	)
	(segment
		(start 285.533846 -271.345152)
		(end 285.533846 -266.379706)
		(width 0.1651)
		(layer "In7.Cu")
		(net "P5E_PEX2_STN2_RX_DP<37>")
	)
	(segment
		(start 294.979344 -31.738824)
		(end 294.83558 -31.738824)
		(width 0.1651)
		(layer "In7.Cu")
		(net "P5E_PEX2_STN2_RX_DP<37>")
	)
	(segment
		(start 413.788352 -124.38888)
		(end 413.50311 -124.103638)
		(width 0.13462)
		(layer "F.Cu")
		(net "P5E_PEX3_STN0_RX_DN<3>")
	)
	(segment
		(start 416.326066 -124.38888)
		(end 413.788352 -124.38888)
		(width 0.13462)
		(layer "F.Cu")
		(net "P5E_PEX3_STN0_RX_DN<3>")
	)
	(segment
		(start 416.95751 -124.234956)
		(end 416.47999 -124.234956)
		(width 0.13462)
		(layer "F.Cu")
		(net "P5E_PEX3_STN0_RX_DN<3>")
	)
	(segment
		(start 416.47999 -124.234956)
		(end 416.326066 -124.38888)
		(width 0.13462)
		(layer "F.Cu")
		(net "P5E_PEX3_STN0_RX_DN<3>")
	)
	(segment
		(start 434.772054 -284.422596)
		(end 442.778642 -276.661626)
		(width 0.1651)
		(layer "In5.Cu")
		(net "P5E_PEX3_STN0_RX_DN<3>")
	)
	(segment
		(start 421.994838 -127.04318)
		(end 421.116252 -126.186438)
		(width 0.1651)
		(layer "In5.Cu")
		(net "P5E_PEX3_STN0_RX_DN<3>")
	)
	(segment
		(start 430.484534 -285.449772)
		(end 430.370234 -285.335472)
		(width 0.1143)
		(layer "In5.Cu")
		(net "P5E_PEX3_STN0_RX_DN<3>")
	)
	(segment
		(start 430.585118 -139.15898)
		(end 428.347378 -137.67562)
		(width 0.1651)
		(layer "In5.Cu")
		(net "P5E_PEX3_STN0_RX_DN<3>")
	)
	(segment
		(start 434.7718 -232.197402)
		(end 435.426612 -168.402254)
		(width 0.1651)
		(layer "In5.Cu")
		(net "P5E_PEX3_STN0_RX_DN<3>")
	)
	(segment
		(start 428.347378 -137.67562)
		(end 421.994838 -127.04318)
		(width 0.1651)
		(layer "In5.Cu")
		(net "P5E_PEX3_STN0_RX_DN<3>")
	)
	(segment
		(start 415.581846 -124.394468)
		(end 413.79394 -124.394468)
		(width 0.1651)
		(layer "In5.Cu")
		(net "P5E_PEX3_STN0_RX_DN<3>")
	)
	(segment
		(start 444.924434 -272.856706)
		(end 445.037972 -269.543276)
		(width 0.1651)
		(layer "In5.Cu")
		(net "P5E_PEX3_STN0_RX_DN<3>")
	)
	(segment
		(start 434.564028 -147.200366)
		(end 434.564282 -147.200366)
		(width 0.1651)
		(layer "In5.Cu")
		(net "P5E_PEX3_STN0_RX_DN<3>")
	)
	(segment
		(start 432.250088 -285.115762)
		(end 433.576476 -285.115762)
		(width 0.1651)
		(layer "In5.Cu")
		(net "P5E_PEX3_STN0_RX_DN<3>")
	)
	(segment
		(start 442.778642 -276.661626)
		(end 444.924434 -272.856706)
		(width 0.1651)
		(layer "In5.Cu")
		(net "P5E_PEX3_STN0_RX_DN<3>")
	)
	(segment
		(start 432.17592 -285.070042)
		(end 432.22164 -285.115762)
		(width 0.1143)
		(layer "In5.Cu")
		(net "P5E_PEX3_STN0_RX_DN<3>")
	)
	(segment
		(start 430.370234 -285.173674)
		(end 430.473866 -285.070042)
		(width 0.1143)
		(layer "In5.Cu")
		(net "P5E_PEX3_STN0_RX_DN<3>")
	)
	(segment
		(start 435.426612 -168.402254)
		(end 434.963824 -150.027132)
		(width 0.1651)
		(layer "In5.Cu")
		(net "P5E_PEX3_STN0_RX_DN<3>")
	)
	(segment
		(start 434.963824 -150.027132)
		(end 434.564028 -147.200366)
		(width 0.1651)
		(layer "In5.Cu")
		(net "P5E_PEX3_STN0_RX_DN<3>")
	)
	(segment
		(start 421.116252 -126.186438)
		(end 417.867846 -124.836428)
		(width 0.1651)
		(layer "In5.Cu")
		(net "P5E_PEX3_STN0_RX_DN<3>")
	)
	(segment
		(start 432.22164 -285.115762)
		(end 432.250088 -285.115762)
		(width 0.1143)
		(layer "In5.Cu")
		(net "P5E_PEX3_STN0_RX_DN<3>")
	)
	(segment
		(start 430.749964 -285.449772)
		(end 430.484534 -285.449772)
		(width 0.1143)
		(layer "In5.Cu")
		(net "P5E_PEX3_STN0_RX_DN<3>")
	)
	(segment
		(start 413.79394 -124.394468)
		(end 413.50311 -124.103638)
		(width 0.1651)
		(layer "In5.Cu")
		(net "P5E_PEX3_STN0_RX_DN<3>")
	)
	(segment
		(start 434.156104 -144.316196)
		(end 430.922938 -140.10386)
		(width 0.1651)
		(layer "In5.Cu")
		(net "P5E_PEX3_STN0_RX_DN<3>")
	)
	(segment
		(start 430.370234 -285.335472)
		(end 430.370234 -285.173674)
		(width 0.1143)
		(layer "In5.Cu")
		(net "P5E_PEX3_STN0_RX_DN<3>")
	)
	(segment
		(start 433.576476 -285.115762)
		(end 434.772054 -284.422596)
		(width 0.1651)
		(layer "In5.Cu")
		(net "P5E_PEX3_STN0_RX_DN<3>")
	)
	(segment
		(start 430.922938 -140.10386)
		(end 430.585118 -139.15898)
		(width 0.1651)
		(layer "In5.Cu")
		(net "P5E_PEX3_STN0_RX_DN<3>")
	)
	(segment
		(start 434.564282 -147.200366)
		(end 434.156104 -144.316196)
		(width 0.1651)
		(layer "In5.Cu")
		(net "P5E_PEX3_STN0_RX_DN<3>")
	)
	(segment
		(start 417.867846 -124.836428)
		(end 415.581846 -124.394468)
		(width 0.1651)
		(layer "In5.Cu")
		(net "P5E_PEX3_STN0_RX_DN<3>")
	)
	(segment
		(start 436.493666 -240.289334)
		(end 434.7718 -232.197402)
		(width 0.1651)
		(layer "In5.Cu")
		(net "P5E_PEX3_STN0_RX_DN<3>")
	)
	(segment
		(start 430.473866 -285.070042)
		(end 432.17592 -285.070042)
		(width 0.1143)
		(layer "In5.Cu")
		(net "P5E_PEX3_STN0_RX_DN<3>")
	)
	(segment
		(start 445.037972 -269.543276)
		(end 436.493666 -240.289334)
		(width 0.1651)
		(layer "In5.Cu")
		(net "P5E_PEX3_STN0_RX_DN<3>")
	)
	(segment
		(start 383.416048 -368.62004)
		(end 394.200634 -359.310686)
		(width 0.1651)
		(layer "In15.Cu")
		(net "P5E_PEX3_STN5_RX_DP<91>")
	)
	(segment
		(start 382.933956 -371.812312)
		(end 382.933956 -369.771168)
		(width 0.1651)
		(layer "In15.Cu")
		(net "P5E_PEX3_STN5_RX_DP<91>")
	)
	(segment
		(start 416.834066 -319.941448)
		(end 416.879786 -319.895728)
		(width 0.1143)
		(layer "In15.Cu")
		(net "P5E_PEX3_STN5_RX_DP<91>")
	)
	(segment
		(start 398.453102 -338.462366)
		(end 398.462246 -338.33689)
		(width 0.1651)
		(layer "In15.Cu")
		(net "P5E_PEX3_STN5_RX_DP<91>")
	)
	(segment
		(start 396.686786 -339.99297)
		(end 396.68704 -339.99297)
		(width 0.1651)
		(layer "In15.Cu")
		(net "P5E_PEX3_STN5_RX_DP<91>")
	)
	(segment
		(start 416.879786 -318.344804)
		(end 417.094924 -318.129666)
		(width 0.1143)
		(layer "In15.Cu")
		(net "P5E_PEX3_STN5_RX_DP<91>")
	)
	(segment
		(start 397.07058 -339.542882)
		(end 397.195802 -339.551772)
		(width 0.1651)
		(layer "In15.Cu")
		(net "P5E_PEX3_STN5_RX_DP<91>")
	)
	(segment
		(start 394.79601 -358.010206)
		(end 394.79601 -342.114886)
		(width 0.1651)
		(layer "In15.Cu")
		(net "P5E_PEX3_STN5_RX_DP<91>")
	)
	(segment
		(start 398.836642 -338.012278)
		(end 398.962118 -338.021168)
		(width 0.1651)
		(layer "In15.Cu")
		(net "P5E_PEX3_STN5_RX_DP<91>")
	)
	(segment
		(start 398.962118 -338.021168)
		(end 415.568384 -323.63283)
		(width 0.1651)
		(layer "In15.Cu")
		(net "P5E_PEX3_STN5_RX_DP<91>")
	)
	(segment
		(start 416.834066 -319.969896)
		(end 416.834066 -319.941448)
		(width 0.1143)
		(layer "In15.Cu")
		(net "P5E_PEX3_STN5_RX_DP<91>")
	)
	(segment
		(start 417.335716 -318.129666)
		(end 417.450016 -318.015366)
		(width 0.1143)
		(layer "In15.Cu")
		(net "P5E_PEX3_STN5_RX_DP<91>")
	)
	(segment
		(start 397.953484 -338.77758)
		(end 398.07896 -338.78647)
		(width 0.1651)
		(layer "In15.Cu")
		(net "P5E_PEX3_STN5_RX_DP<91>")
	)
	(segment
		(start 382.933956 -369.771168)
		(end 383.416048 -368.62004)
		(width 0.1651)
		(layer "In15.Cu")
		(net "P5E_PEX3_STN5_RX_DP<91>")
	)
	(segment
		(start 396.68704 -339.99297)
		(end 396.69593 -339.867494)
		(width 0.1651)
		(layer "In15.Cu")
		(net "P5E_PEX3_STN5_RX_DP<91>")
	)
	(segment
		(start 394.200634 -359.310686)
		(end 394.79601 -358.010206)
		(width 0.1651)
		(layer "In15.Cu")
		(net "P5E_PEX3_STN5_RX_DP<91>")
	)
	(segment
		(start 398.07896 -338.78647)
		(end 398.453102 -338.462366)
		(width 0.1651)
		(layer "In15.Cu")
		(net "P5E_PEX3_STN5_RX_DP<91>")
	)
	(segment
		(start 397.569944 -339.227668)
		(end 397.579088 -339.102192)
		(width 0.1651)
		(layer "In15.Cu")
		(net "P5E_PEX3_STN5_RX_DP<91>")
	)
	(segment
		(start 382.64719 -372.099078)
		(end 382.933956 -371.812312)
		(width 0.1651)
		(layer "In15.Cu")
		(net "P5E_PEX3_STN5_RX_DP<91>")
	)
	(segment
		(start 398.462246 -338.33689)
		(end 398.836642 -338.012278)
		(width 0.1651)
		(layer "In15.Cu")
		(net "P5E_PEX3_STN5_RX_DP<91>")
	)
	(segment
		(start 415.568384 -323.63283)
		(end 416.834066 -321.877436)
		(width 0.1651)
		(layer "In15.Cu")
		(net "P5E_PEX3_STN5_RX_DP<91>")
	)
	(segment
		(start 382.216914 -372.099078)
		(end 382.64719 -372.099078)
		(width 0.1651)
		(layer "In15.Cu")
		(net "P5E_PEX3_STN5_RX_DP<91>")
	)
	(segment
		(start 397.195802 -339.551772)
		(end 397.569944 -339.227668)
		(width 0.1651)
		(layer "In15.Cu")
		(net "P5E_PEX3_STN5_RX_DP<91>")
	)
	(segment
		(start 417.450016 -318.015366)
		(end 417.450016 -317.749936)
		(width 0.1143)
		(layer "In15.Cu")
		(net "P5E_PEX3_STN5_RX_DP<91>")
	)
	(segment
		(start 416.834066 -321.877436)
		(end 416.834066 -319.969896)
		(width 0.1651)
		(layer "In15.Cu")
		(net "P5E_PEX3_STN5_RX_DP<91>")
	)
	(segment
		(start 416.879786 -319.895728)
		(end 416.879786 -318.344804)
		(width 0.1143)
		(layer "In15.Cu")
		(net "P5E_PEX3_STN5_RX_DP<91>")
	)
	(segment
		(start 382.089914 -371.972078)
		(end 382.216914 -372.099078)
		(width 0.1651)
		(layer "In15.Cu")
		(net "P5E_PEX3_STN5_RX_DP<91>")
	)
	(segment
		(start 396.69593 -339.867494)
		(end 397.07058 -339.542882)
		(width 0.1651)
		(layer "In15.Cu")
		(net "P5E_PEX3_STN5_RX_DP<91>")
	)
	(segment
		(start 382.089914 -371.590062)
		(end 382.089914 -371.972078)
		(width 0.1651)
		(layer "In15.Cu")
		(net "P5E_PEX3_STN5_RX_DP<91>")
	)
	(segment
		(start 397.579088 -339.102192)
		(end 397.953484 -338.77758)
		(width 0.1651)
		(layer "In15.Cu")
		(net "P5E_PEX3_STN5_RX_DP<91>")
	)
	(segment
		(start 417.094924 -318.129666)
		(end 417.335716 -318.129666)
		(width 0.1143)
		(layer "In15.Cu")
		(net "P5E_PEX3_STN5_RX_DP<91>")
	)
	(segment
		(start 394.79601 -342.114886)
		(end 395.073378 -341.390986)
		(width 0.1651)
		(layer "In15.Cu")
		(net "P5E_PEX3_STN5_RX_DP<91>")
	)
	(segment
		(start 395.073378 -341.390986)
		(end 396.686786 -339.99297)
		(width 0.1651)
		(layer "In15.Cu")
		(net "P5E_PEX3_STN5_RX_DP<91>")
	)
	(segment
		(start 70.746366 -111.884206)
		(end 70.746366 -112.143286)
		(width 0.13208)
		(layer "F.Cu")
		(net "NIC1_BIF1_N")
	)
	(segment
		(start 72.03821 -113.43513)
		(end 73.257664 -113.43513)
		(width 0.13208)
		(layer "F.Cu")
		(net "NIC1_BIF1_N")
	)
	(segment
		(start 70.746366 -112.143286)
		(end 72.03821 -113.43513)
		(width 0.13208)
		(layer "F.Cu")
		(net "NIC1_BIF1_N")
	)
	(via
		(at 70.746366 -111.884206)
		(size 0.508)
		(drill 0.254)
		(layers "F.Cu" "B.Cu")
		(net "NIC1_BIF1_N")
	)
	(segment
		(start 68.981574 -109.70895)
		(end 68.981574 -109.133132)
		(width 0.13208)
		(layer "B.Cu")
		(net "NIC1_BIF1_N")
	)
	(segment
		(start 66.503296 -108.485432)
		(end 66.028316 -108.960412)
		(width 0.13208)
		(layer "B.Cu")
		(net "NIC1_BIF1_N")
	)
	(segment
		(start 62.975236 -109.198156)
		(end 62.975236 -109.481366)
		(width 0.13208)
		(layer "B.Cu")
		(net "NIC1_BIF1_N")
	)
	(segment
		(start 66.028316 -108.960412)
		(end 63.21298 -108.960412)
		(width 0.13208)
		(layer "B.Cu")
		(net "NIC1_BIF1_N")
	)
	(segment
		(start 63.21298 -108.960412)
		(end 62.975236 -109.198156)
		(width 0.13208)
		(layer "B.Cu")
		(net "NIC1_BIF1_N")
	)
	(segment
		(start 68.333874 -108.485432)
		(end 66.503296 -108.485432)
		(width 0.13208)
		(layer "B.Cu")
		(net "NIC1_BIF1_N")
	)
	(segment
		(start 70.746366 -111.884206)
		(end 70.746366 -111.473742)
		(width 0.13208)
		(layer "B.Cu")
		(net "NIC1_BIF1_N")
	)
	(segment
		(start 70.746366 -111.473742)
		(end 68.981574 -109.70895)
		(width 0.13208)
		(layer "B.Cu")
		(net "NIC1_BIF1_N")
	)
	(segment
		(start 62.975236 -109.481366)
		(end 61.997336 -109.481366)
		(width 0.13208)
		(layer "B.Cu")
		(net "NIC1_BIF1_N")
	)
	(segment
		(start 68.981574 -109.133132)
		(end 68.333874 -108.485432)
		(width 0.13208)
		(layer "B.Cu")
		(net "NIC1_BIF1_N")
	)
	(segment
		(start 53.801772 -99.607878)
		(end 54.09692 -99.31273)
		(width 0.13462)
		(layer "F.Cu")
		(net "P5E_PEX0_STN1_RX_DP<16>")
	)
	(segment
		(start 50.64252 -99.445064)
		(end 51.130454 -99.445064)
		(width 0.13462)
		(layer "F.Cu")
		(net "P5E_PEX0_STN1_RX_DP<16>")
	)
	(segment
		(start 51.130454 -99.445064)
		(end 51.293268 -99.607878)
		(width 0.13462)
		(layer "F.Cu")
		(net "P5E_PEX0_STN1_RX_DP<16>")
	)
	(segment
		(start 51.293268 -99.607878)
		(end 53.801772 -99.607878)
		(width 0.13462)
		(layer "F.Cu")
		(net "P5E_PEX0_STN1_RX_DP<16>")
	)
	(segment
		(start 33.821624 -111.125508)
		(end 31.02102 -119.642636)
		(width 0.1651)
		(layer "In5.Cu")
		(net "P5E_PEX0_STN1_RX_DP<16>")
	)
	(segment
		(start 34.29508 -110.640876)
		(end 33.821624 -111.125508)
		(width 0.1651)
		(layer "In5.Cu")
		(net "P5E_PEX0_STN1_RX_DP<16>")
	)
	(segment
		(start 59.033918 -270.105124)
		(end 59.033918 -271.726152)
		(width 0.1651)
		(layer "In5.Cu")
		(net "P5E_PEX0_STN1_RX_DP<16>")
	)
	(segment
		(start 28.014168 -149.937724)
		(end 28.015184 -149.955758)
		(width 0.1651)
		(layer "In5.Cu")
		(net "P5E_PEX0_STN1_RX_DP<16>")
	)
	(segment
		(start 35.933634 -109.97438)
		(end 34.29508 -110.640876)
		(width 0.1651)
		(layer "In5.Cu")
		(net "P5E_PEX0_STN1_RX_DP<16>")
	)
	(segment
		(start 59.649614 -273.78406)
		(end 59.649614 -274.04949)
		(width 0.1143)
		(layer "In5.Cu")
		(net "P5E_PEX0_STN1_RX_DP<16>")
	)
	(segment
		(start 59.079638 -273.454876)
		(end 59.294522 -273.66976)
		(width 0.1143)
		(layer "In5.Cu")
		(net "P5E_PEX0_STN1_RX_DP<16>")
	)
	(segment
		(start 28.688792 -159.572198)
		(end 29.944314 -166.070534)
		(width 0.1651)
		(layer "In5.Cu")
		(net "P5E_PEX0_STN1_RX_DP<16>")
	)
	(segment
		(start 28.015438 -149.955758)
		(end 28.688792 -159.572198)
		(width 0.1651)
		(layer "In5.Cu")
		(net "P5E_PEX0_STN1_RX_DP<16>")
	)
	(segment
		(start 59.079638 -271.80032)
		(end 59.079638 -273.454876)
		(width 0.1143)
		(layer "In5.Cu")
		(net "P5E_PEX0_STN1_RX_DP<16>")
	)
	(segment
		(start 31.02102 -119.642636)
		(end 29.39796 -126.35865)
		(width 0.1651)
		(layer "In5.Cu")
		(net "P5E_PEX0_STN1_RX_DP<16>")
	)
	(segment
		(start 54.09692 -99.31273)
		(end 53.80609 -99.60356)
		(width 0.1651)
		(layer "In5.Cu")
		(net "P5E_PEX0_STN1_RX_DP<16>")
	)
	(segment
		(start 53.80609 -99.60356)
		(end 51.891946 -99.60356)
		(width 0.1651)
		(layer "In5.Cu")
		(net "P5E_PEX0_STN1_RX_DP<16>")
	)
	(segment
		(start 29.944314 -166.070534)
		(end 59.033918 -270.105124)
		(width 0.1651)
		(layer "In5.Cu")
		(net "P5E_PEX0_STN1_RX_DP<16>")
	)
	(segment
		(start 59.033918 -271.7546)
		(end 59.079638 -271.80032)
		(width 0.1143)
		(layer "In5.Cu")
		(net "P5E_PEX0_STN1_RX_DP<16>")
	)
	(segment
		(start 29.39796 -126.35865)
		(end 28.014168 -149.937724)
		(width 0.1651)
		(layer "In5.Cu")
		(net "P5E_PEX0_STN1_RX_DP<16>")
	)
	(segment
		(start 59.294522 -273.66976)
		(end 59.535314 -273.66976)
		(width 0.1143)
		(layer "In5.Cu")
		(net "P5E_PEX0_STN1_RX_DP<16>")
	)
	(segment
		(start 28.015184 -149.955758)
		(end 28.015438 -149.955758)
		(width 0.1651)
		(layer "In5.Cu")
		(net "P5E_PEX0_STN1_RX_DP<16>")
	)
	(segment
		(start 39.032434 -107.761532)
		(end 36.589208 -109.382306)
		(width 0.1651)
		(layer "In5.Cu")
		(net "P5E_PEX0_STN1_RX_DP<16>")
	)
	(segment
		(start 51.891946 -99.60356)
		(end 44.906946 -103.095806)
		(width 0.1651)
		(layer "In5.Cu")
		(net "P5E_PEX0_STN1_RX_DP<16>")
	)
	(segment
		(start 59.033918 -271.726152)
		(end 59.033918 -271.7546)
		(width 0.1143)
		(layer "In5.Cu")
		(net "P5E_PEX0_STN1_RX_DP<16>")
	)
	(segment
		(start 59.535314 -273.66976)
		(end 59.649614 -273.78406)
		(width 0.1143)
		(layer "In5.Cu")
		(net "P5E_PEX0_STN1_RX_DP<16>")
	)
	(segment
		(start 36.589208 -109.382306)
		(end 35.933634 -109.97438)
		(width 0.1651)
		(layer "In5.Cu")
		(net "P5E_PEX0_STN1_RX_DP<16>")
	)
	(segment
		(start 44.906946 -103.095806)
		(end 39.032434 -107.761532)
		(width 0.1651)
		(layer "In5.Cu")
		(net "P5E_PEX0_STN1_RX_DP<16>")
	)
	(segment
		(start 65.050162 -351.316798)
		(end 65.050162 -350.685354)
		(width 0.13462)
		(layer "F.Cu")
		(net "P5E_PEX0_STN6_TX_C_DN<110>")
	)
	(segment
		(start 65.050162 -350.685354)
		(end 65.370202 -350.365314)
		(width 0.13462)
		(layer "F.Cu")
		(net "P5E_PEX0_STN6_TX_C_DN<110>")
	)
	(segment
		(start 65.344802 -351.611438)
		(end 65.050162 -351.316798)
		(width 0.13462)
		(layer "F.Cu")
		(net "P5E_PEX0_STN6_TX_C_DN<110>")
	)
	(segment
		(start 74.236834 -410.080968)
		(end 74.109834 -410.207968)
		(width 0.1651)
		(layer "In13.Cu")
		(net "P5E_PEX0_STN6_TX_C_DN<110>")
	)
	(segment
		(start 64.607694 -382.137158)
		(end 64.607694 -384.203956)
		(width 0.1651)
		(layer "In13.Cu")
		(net "P5E_PEX0_STN6_TX_C_DN<110>")
	)
	(segment
		(start 75.28433 -396.178786)
		(end 75.28433 -409.677616)
		(width 0.1651)
		(layer "In13.Cu")
		(net "P5E_PEX0_STN6_TX_C_DN<110>")
	)
	(segment
		(start 65.344802 -351.611438)
		(end 65.053972 -351.902268)
		(width 0.1651)
		(layer "In13.Cu")
		(net "P5E_PEX0_STN6_TX_C_DN<110>")
	)
	(segment
		(start 74.109834 -410.207968)
		(end 74.109834 -410.589984)
		(width 0.1651)
		(layer "In13.Cu")
		(net "P5E_PEX0_STN6_TX_C_DN<110>")
	)
	(segment
		(start 74.880978 -410.080968)
		(end 74.236834 -410.080968)
		(width 0.1651)
		(layer "In13.Cu")
		(net "P5E_PEX0_STN6_TX_C_DN<110>")
	)
	(segment
		(start 74.351388 -394.433298)
		(end 74.649584 -394.991082)
		(width 0.1651)
		(layer "In13.Cu")
		(net "P5E_PEX0_STN6_TX_C_DN<110>")
	)
	(segment
		(start 74.649584 -394.991082)
		(end 74.752708 -395.022578)
		(width 0.1651)
		(layer "In13.Cu")
		(net "P5E_PEX0_STN6_TX_C_DN<110>")
	)
	(segment
		(start 66.376042 -388.473442)
		(end 68.27647 -390.37387)
		(width 0.1651)
		(layer "In13.Cu")
		(net "P5E_PEX0_STN6_TX_C_DN<110>")
	)
	(segment
		(start 63.499492 -359.127044)
		(end 63.906908 -363.261148)
		(width 0.1651)
		(layer "In13.Cu")
		(net "P5E_PEX0_STN6_TX_C_DN<110>")
	)
	(segment
		(start 63.499492 -354.089208)
		(end 63.499492 -359.127044)
		(width 0.1651)
		(layer "In13.Cu")
		(net "P5E_PEX0_STN6_TX_C_DN<110>")
	)
	(segment
		(start 63.906908 -363.261148)
		(end 64.607694 -382.137158)
		(width 0.1651)
		(layer "In13.Cu")
		(net "P5E_PEX0_STN6_TX_C_DN<110>")
	)
	(segment
		(start 74.752708 -395.022578)
		(end 74.986388 -395.459458)
		(width 0.1651)
		(layer "In13.Cu")
		(net "P5E_PEX0_STN6_TX_C_DN<110>")
	)
	(segment
		(start 65.053972 -352.534728)
		(end 63.499492 -354.089208)
		(width 0.1651)
		(layer "In13.Cu")
		(net "P5E_PEX0_STN6_TX_C_DN<110>")
	)
	(segment
		(start 64.607694 -384.203956)
		(end 66.376042 -388.473442)
		(width 0.1651)
		(layer "In13.Cu")
		(net "P5E_PEX0_STN6_TX_C_DN<110>")
	)
	(segment
		(start 75.28433 -409.677616)
		(end 74.880978 -410.080968)
		(width 0.1651)
		(layer "In13.Cu")
		(net "P5E_PEX0_STN6_TX_C_DN<110>")
	)
	(segment
		(start 68.27647 -390.37387)
		(end 74.351388 -394.433298)
		(width 0.1651)
		(layer "In13.Cu")
		(net "P5E_PEX0_STN6_TX_C_DN<110>")
	)
	(segment
		(start 74.986388 -395.459458)
		(end 74.955146 -395.562582)
		(width 0.1651)
		(layer "In13.Cu")
		(net "P5E_PEX0_STN6_TX_C_DN<110>")
	)
	(segment
		(start 74.955146 -395.562582)
		(end 75.28433 -396.178786)
		(width 0.1651)
		(layer "In13.Cu")
		(net "P5E_PEX0_STN6_TX_C_DN<110>")
	)
	(segment
		(start 65.053972 -351.902268)
		(end 65.053972 -352.534728)
		(width 0.1651)
		(layer "In13.Cu")
		(net "P5E_PEX0_STN6_TX_C_DN<110>")
	)
	(segment
		(start 249.415046 -28.829)
		(end 248.125488 -28.829)
		(width 0.13462)
		(layer "F.Cu")
		(net "P5E_PEX2_STN2_TX_C_DP<44>")
	)
	(segment
		(start 249.725688 -29.139642)
		(end 249.415046 -28.829)
		(width 0.13462)
		(layer "F.Cu")
		(net "P5E_PEX2_STN2_TX_C_DP<44>")
	)
	(segment
		(start 248.125488 -28.829)
		(end 247.964452 -28.990036)
		(width 0.13462)
		(layer "F.Cu")
		(net "P5E_PEX2_STN2_TX_C_DP<44>")
	)
	(segment
		(start 247.964452 -28.990036)
		(end 247.464834 -28.990036)
		(width 0.13462)
		(layer "F.Cu")
		(net "P5E_PEX2_STN2_TX_C_DP<44>")
	)
	(segment
		(start 73.257664 -100.039932)
		(end 74.258932 -100.039932)
		(width 0.13208)
		(layer "F.Cu")
		(net "NIC1_CLK")
	)
	(via
		(at 74.258932 -100.039932)
		(size 0.508)
		(drill 0.254)
		(layers "F.Cu" "B.Cu")
		(net "NIC1_CLK")
	)
	(segment
		(start 76.139548 -100.039932)
		(end 74.258932 -100.039932)
		(width 0.13208)
		(layer "B.Cu")
		(net "NIC1_CLK")
	)
	(segment
		(start 77.141832 -99.037648)
		(end 76.139548 -100.039932)
		(width 0.13208)
		(layer "B.Cu")
		(net "NIC1_CLK")
	)
	(segment
		(start 51.293522 -136.402064)
		(end 51.948334 -136.402064)
		(width 0.13462)
		(layer "F.Cu")
		(net "P5E_PEX0_STN1_RX_DN<31>")
	)
	(segment
		(start 51.948334 -136.402064)
		(end 52.24272 -136.69645)
		(width 0.13462)
		(layer "F.Cu")
		(net "P5E_PEX0_STN1_RX_DN<31>")
	)
	(segment
		(start 50.64252 -136.565132)
		(end 51.130454 -136.565132)
		(width 0.13462)
		(layer "F.Cu")
		(net "P5E_PEX0_STN1_RX_DN<31>")
	)
	(segment
		(start 51.130454 -136.565132)
		(end 51.293522 -136.402064)
		(width 0.13462)
		(layer "F.Cu")
		(net "P5E_PEX0_STN1_RX_DN<31>")
	)
	(segment
		(start 45.87748 -151.096726)
		(end 45.982128 -151.219916)
		(width 0.1651)
		(layer "In5.Cu")
		(net "P5E_PEX0_STN1_RX_DN<31>")
	)
	(segment
		(start 51.16957 -137.66165)
		(end 51.28387 -137.77595)
		(width 0.1651)
		(layer "In5.Cu")
		(net "P5E_PEX0_STN1_RX_DN<31>")
	)
	(segment
		(start 51.16957 -140.18895)
		(end 51.16957 -141.285976)
		(width 0.1651)
		(layer "In5.Cu")
		(net "P5E_PEX0_STN1_RX_DN<31>")
	)
	(segment
		(start 49.03597 -145.231358)
		(end 48.683164 -145.578576)
		(width 0.1651)
		(layer "In5.Cu")
		(net "P5E_PEX0_STN1_RX_DN<31>")
	)
	(segment
		(start 50.977546 -141.755368)
		(end 51.04003 -141.904466)
		(width 0.1651)
		(layer "In5.Cu")
		(net "P5E_PEX0_STN1_RX_DN<31>")
	)
	(segment
		(start 51.28387 -140.07465)
		(end 51.16957 -140.18895)
		(width 0.1651)
		(layer "In5.Cu")
		(net "P5E_PEX0_STN1_RX_DN<31>")
	)
	(segment
		(start 48.32858 -146.087846)
		(end 48.167036 -146.08683)
		(width 0.1651)
		(layer "In5.Cu")
		(net "P5E_PEX0_STN1_RX_DN<31>")
	)
	(segment
		(start 51.28387 -138.27125)
		(end 51.16957 -138.38555)
		(width 0.1651)
		(layer "In5.Cu")
		(net "P5E_PEX0_STN1_RX_DN<31>")
	)
	(segment
		(start 51.16957 -138.38555)
		(end 51.16957 -139.46505)
		(width 0.1651)
		(layer "In5.Cu")
		(net "P5E_PEX0_STN1_RX_DN<31>")
	)
	(segment
		(start 45.818298 -151.818594)
		(end 45.778166 -152.312116)
		(width 0.1651)
		(layer "In5.Cu")
		(net "P5E_PEX0_STN1_RX_DN<31>")
	)
	(segment
		(start 49.550828 -144.885156)
		(end 49.197768 -145.232628)
		(width 0.1651)
		(layer "In5.Cu")
		(net "P5E_PEX0_STN1_RX_DN<31>")
	)
	(segment
		(start 49.905158 -144.37614)
		(end 49.552352 -144.723358)
		(width 0.1651)
		(layer "In5.Cu")
		(net "P5E_PEX0_STN1_RX_DN<31>")
	)
	(segment
		(start 51.16957 -139.46505)
		(end 51.28387 -139.57935)
		(width 0.1651)
		(layer "In5.Cu")
		(net "P5E_PEX0_STN1_RX_DN<31>")
	)
	(segment
		(start 73.623424 -275.379688)
		(end 73.785222 -275.379688)
		(width 0.1143)
		(layer "In5.Cu")
		(net "P5E_PEX0_STN1_RX_DN<31>")
	)
	(segment
		(start 51.691794 -136.40562)
		(end 51.251358 -136.846056)
		(width 0.1651)
		(layer "In5.Cu")
		(net "P5E_PEX0_STN1_RX_DN<31>")
	)
	(segment
		(start 45.882814 -152.435306)
		(end 45.842428 -152.929336)
		(width 0.1651)
		(layer "In5.Cu")
		(net "P5E_PEX0_STN1_RX_DN<31>")
	)
	(segment
		(start 73.565766 -271.802352)
		(end 73.520046 -271.848072)
		(width 0.1143)
		(layer "In5.Cu")
		(net "P5E_PEX0_STN1_RX_DN<31>")
	)
	(segment
		(start 49.197768 -145.232628)
		(end 49.03597 -145.231358)
		(width 0.1651)
		(layer "In5.Cu")
		(net "P5E_PEX0_STN1_RX_DN<31>")
	)
	(segment
		(start 48.68164 -145.740374)
		(end 48.32858 -146.087846)
		(width 0.1651)
		(layer "In5.Cu")
		(net "P5E_PEX0_STN1_RX_DN<31>")
	)
	(segment
		(start 52.24272 -136.69645)
		(end 51.95189 -136.40562)
		(width 0.1651)
		(layer "In5.Cu")
		(net "P5E_PEX0_STN1_RX_DN<31>")
	)
	(segment
		(start 48.683164 -145.578576)
		(end 48.68164 -145.740374)
		(width 0.1651)
		(layer "In5.Cu")
		(net "P5E_PEX0_STN1_RX_DN<31>")
	)
	(segment
		(start 51.28387 -137.77595)
		(end 51.28387 -138.27125)
		(width 0.1651)
		(layer "In5.Cu")
		(net "P5E_PEX0_STN1_RX_DN<31>")
	)
	(segment
		(start 73.785222 -275.379688)
		(end 73.899522 -275.265388)
		(width 0.1143)
		(layer "In5.Cu")
		(net "P5E_PEX0_STN1_RX_DN<31>")
	)
	(segment
		(start 46.530768 -147.32)
		(end 46.107858 -148.271484)
		(width 0.1651)
		(layer "In5.Cu")
		(net "P5E_PEX0_STN1_RX_DN<31>")
	)
	(segment
		(start 51.04003 -141.904466)
		(end 50.852578 -142.36319)
		(width 0.1651)
		(layer "In5.Cu")
		(net "P5E_PEX0_STN1_RX_DN<31>")
	)
	(segment
		(start 45.778166 -152.312116)
		(end 45.882814 -152.435306)
		(width 0.1651)
		(layer "In5.Cu")
		(net "P5E_PEX0_STN1_RX_DN<31>")
	)
	(segment
		(start 51.16957 -141.285976)
		(end 50.977546 -141.755368)
		(width 0.1651)
		(layer "In5.Cu")
		(net "P5E_PEX0_STN1_RX_DN<31>")
	)
	(segment
		(start 45.982128 -151.219916)
		(end 45.941742 -151.713946)
		(width 0.1651)
		(layer "In5.Cu")
		(net "P5E_PEX0_STN1_RX_DN<31>")
	)
	(segment
		(start 51.16957 -137.043668)
		(end 51.16957 -137.66165)
		(width 0.1651)
		(layer "In5.Cu")
		(net "P5E_PEX0_STN1_RX_DN<31>")
	)
	(segment
		(start 73.520046 -275.27631)
		(end 73.623424 -275.379688)
		(width 0.1143)
		(layer "In5.Cu")
		(net "P5E_PEX0_STN1_RX_DN<31>")
	)
	(segment
		(start 45.941742 -151.713946)
		(end 45.818298 -151.818594)
		(width 0.1651)
		(layer "In5.Cu")
		(net "P5E_PEX0_STN1_RX_DN<31>")
	)
	(segment
		(start 50.852578 -142.36319)
		(end 50.703226 -142.425674)
		(width 0.1651)
		(layer "In5.Cu")
		(net "P5E_PEX0_STN1_RX_DN<31>")
	)
	(segment
		(start 48.167036 -146.08683)
		(end 47.422054 -146.819874)
		(width 0.1651)
		(layer "In5.Cu")
		(net "P5E_PEX0_STN1_RX_DN<31>")
	)
	(segment
		(start 45.193458 -159.47898)
		(end 45.232574 -160.37052)
		(width 0.1651)
		(layer "In5.Cu")
		(net "P5E_PEX0_STN1_RX_DN<31>")
	)
	(segment
		(start 47.422054 -146.819874)
		(end 46.765718 -147.088606)
		(width 0.1651)
		(layer "In5.Cu")
		(net "P5E_PEX0_STN1_RX_DN<31>")
	)
	(segment
		(start 51.251358 -136.846056)
		(end 51.16957 -137.043668)
		(width 0.1651)
		(layer "In5.Cu")
		(net "P5E_PEX0_STN1_RX_DN<31>")
	)
	(segment
		(start 46.107858 -148.271484)
		(end 45.87748 -151.096726)
		(width 0.1651)
		(layer "In5.Cu")
		(net "P5E_PEX0_STN1_RX_DN<31>")
	)
	(segment
		(start 45.842428 -152.929336)
		(end 45.718984 -153.033984)
		(width 0.1651)
		(layer "In5.Cu")
		(net "P5E_PEX0_STN1_RX_DN<31>")
	)
	(segment
		(start 51.28387 -139.57935)
		(end 51.28387 -140.07465)
		(width 0.1651)
		(layer "In5.Cu")
		(net "P5E_PEX0_STN1_RX_DN<31>")
	)
	(segment
		(start 50.390806 -143.491712)
		(end 50.241454 -143.554196)
		(width 0.1651)
		(layer "In5.Cu")
		(net "P5E_PEX0_STN1_RX_DN<31>")
	)
	(segment
		(start 45.718984 -153.033984)
		(end 45.193458 -159.47898)
		(width 0.1651)
		(layer "In5.Cu")
		(net "P5E_PEX0_STN1_RX_DN<31>")
	)
	(segment
		(start 45.232574 -160.37052)
		(end 73.497948 -266.542774)
		(width 0.1651)
		(layer "In5.Cu")
		(net "P5E_PEX0_STN1_RX_DN<31>")
	)
	(segment
		(start 50.241454 -143.554196)
		(end 49.905158 -144.37614)
		(width 0.1651)
		(layer "In5.Cu")
		(net "P5E_PEX0_STN1_RX_DN<31>")
	)
	(segment
		(start 73.565766 -267.061188)
		(end 73.565766 -271.773904)
		(width 0.1651)
		(layer "In5.Cu")
		(net "P5E_PEX0_STN1_RX_DN<31>")
	)
	(segment
		(start 50.578258 -143.032988)
		(end 50.390806 -143.491712)
		(width 0.1651)
		(layer "In5.Cu")
		(net "P5E_PEX0_STN1_RX_DN<31>")
	)
	(segment
		(start 51.95189 -136.40562)
		(end 51.691794 -136.40562)
		(width 0.1651)
		(layer "In5.Cu")
		(net "P5E_PEX0_STN1_RX_DN<31>")
	)
	(segment
		(start 46.765718 -147.088606)
		(end 46.530768 -147.32)
		(width 0.1651)
		(layer "In5.Cu")
		(net "P5E_PEX0_STN1_RX_DN<31>")
	)
	(segment
		(start 73.497948 -266.542774)
		(end 73.565766 -267.061188)
		(width 0.1651)
		(layer "In5.Cu")
		(net "P5E_PEX0_STN1_RX_DN<31>")
	)
	(segment
		(start 50.703226 -142.425674)
		(end 50.515774 -142.88389)
		(width 0.1651)
		(layer "In5.Cu")
		(net "P5E_PEX0_STN1_RX_DN<31>")
	)
	(segment
		(start 73.520046 -271.848072)
		(end 73.520046 -275.27631)
		(width 0.1143)
		(layer "In5.Cu")
		(net "P5E_PEX0_STN1_RX_DN<31>")
	)
	(segment
		(start 49.552352 -144.723358)
		(end 49.550828 -144.885156)
		(width 0.1651)
		(layer "In5.Cu")
		(net "P5E_PEX0_STN1_RX_DN<31>")
	)
	(segment
		(start 50.515774 -142.88389)
		(end 50.578258 -143.032988)
		(width 0.1651)
		(layer "In5.Cu")
		(net "P5E_PEX0_STN1_RX_DN<31>")
	)
	(segment
		(start 73.565766 -271.773904)
		(end 73.565766 -271.802352)
		(width 0.1143)
		(layer "In5.Cu")
		(net "P5E_PEX0_STN1_RX_DN<31>")
	)
	(segment
		(start 73.899522 -275.265388)
		(end 73.899522 -274.999958)
		(width 0.1143)
		(layer "In5.Cu")
		(net "P5E_PEX0_STN1_RX_DN<31>")
	)
	(segment
		(start 71.90994 -375.308114)
		(end 72.03694 -375.181114)
		(width 0.1651)
		(layer "In9.Cu")
		(net "P5E_PEX0_STN6_RX_DN<103>")
	)
	(segment
		(start 50.885344 -316.419992)
		(end 51.011074 -316.419992)
		(width 0.1143)
		(layer "In9.Cu")
		(net "P5E_PEX0_STN6_RX_DN<103>")
	)
	(segment
		(start 50.720244 -319.91808)
		(end 50.720244 -316.585092)
		(width 0.1143)
		(layer "In9.Cu")
		(net "P5E_PEX0_STN6_RX_DN<103>")
	)
	(segment
		(start 58.840116 -354.532438)
		(end 57.272428 -346.65031)
		(width 0.1651)
		(layer "In9.Cu")
		(net "P5E_PEX0_STN6_RX_DN<103>")
	)
	(segment
		(start 71.90994 -375.69013)
		(end 71.90994 -375.308114)
		(width 0.1651)
		(layer "In9.Cu")
		(net "P5E_PEX0_STN6_RX_DN<103>")
	)
	(segment
		(start 63.071248 -362.042964)
		(end 61.158882 -360.130598)
		(width 0.1651)
		(layer "In9.Cu")
		(net "P5E_PEX0_STN6_RX_DN<103>")
	)
	(segment
		(start 51.099974 -316.508892)
		(end 51.099974 -316.799722)
		(width 0.1143)
		(layer "In9.Cu")
		(net "P5E_PEX0_STN6_RX_DN<103>")
	)
	(segment
		(start 72.54494 -375.181114)
		(end 73.084182 -374.641872)
		(width 0.1651)
		(layer "In9.Cu")
		(net "P5E_PEX0_STN6_RX_DN<103>")
	)
	(segment
		(start 50.765964 -325.201534)
		(end 50.765964 -319.992248)
		(width 0.1651)
		(layer "In9.Cu")
		(net "P5E_PEX0_STN6_RX_DN<103>")
	)
	(segment
		(start 61.158882 -360.130598)
		(end 58.840116 -354.532438)
		(width 0.1651)
		(layer "In9.Cu")
		(net "P5E_PEX0_STN6_RX_DN<103>")
	)
	(segment
		(start 73.084182 -369.267994)
		(end 72.651112 -368.22253)
		(width 0.1651)
		(layer "In9.Cu")
		(net "P5E_PEX0_STN6_RX_DN<103>")
	)
	(segment
		(start 50.765964 -319.9638)
		(end 50.720244 -319.91808)
		(width 0.1143)
		(layer "In9.Cu")
		(net "P5E_PEX0_STN6_RX_DN<103>")
	)
	(segment
		(start 72.651112 -368.22253)
		(end 63.944246 -362.40466)
		(width 0.1651)
		(layer "In9.Cu")
		(net "P5E_PEX0_STN6_RX_DN<103>")
	)
	(segment
		(start 73.084182 -374.641872)
		(end 73.084182 -369.267994)
		(width 0.1651)
		(layer "In9.Cu")
		(net "P5E_PEX0_STN6_RX_DN<103>")
	)
	(segment
		(start 51.011074 -316.419992)
		(end 51.099974 -316.508892)
		(width 0.1143)
		(layer "In9.Cu")
		(net "P5E_PEX0_STN6_RX_DN<103>")
	)
	(segment
		(start 72.03694 -375.181114)
		(end 72.54494 -375.181114)
		(width 0.1651)
		(layer "In9.Cu")
		(net "P5E_PEX0_STN6_RX_DN<103>")
	)
	(segment
		(start 63.944246 -362.40466)
		(end 63.071248 -362.042964)
		(width 0.1651)
		(layer "In9.Cu")
		(net "P5E_PEX0_STN6_RX_DN<103>")
	)
	(segment
		(start 50.765964 -319.992248)
		(end 50.765964 -319.9638)
		(width 0.1143)
		(layer "In9.Cu")
		(net "P5E_PEX0_STN6_RX_DN<103>")
	)
	(segment
		(start 50.720244 -316.585092)
		(end 50.885344 -316.419992)
		(width 0.1143)
		(layer "In9.Cu")
		(net "P5E_PEX0_STN6_RX_DN<103>")
	)
	(segment
		(start 57.272428 -346.65031)
		(end 50.765964 -325.201534)
		(width 0.1651)
		(layer "In9.Cu")
		(net "P5E_PEX0_STN6_RX_DN<103>")
	)
	(segment
		(start 319.560448 -28.55468)
		(end 319.264538 -28.25877)
		(width 0.13462)
		(layer "F.Cu")
		(net "P5E_PEX2_STN2_RX_DN<32>")
	)
	(segment
		(start 320.383916 -28.390088)
		(end 320.219324 -28.55468)
		(width 0.13462)
		(layer "F.Cu")
		(net "P5E_PEX2_STN2_RX_DN<32>")
	)
	(segment
		(start 320.219324 -28.55468)
		(end 319.560448 -28.55468)
		(width 0.13462)
		(layer "F.Cu")
		(net "P5E_PEX2_STN2_RX_DN<32>")
	)
	(segment
		(start 320.864738 -28.390088)
		(end 320.383916 -28.390088)
		(width 0.13462)
		(layer "F.Cu")
		(net "P5E_PEX2_STN2_RX_DN<32>")
	)
	(segment
		(start 325.33971 -39.96563)
		(end 323.360542 -49.41951)
		(width 0.1651)
		(layer "In7.Cu")
		(net "P5E_PEX2_STN2_RX_DN<32>")
	)
	(segment
		(start 290.623752 -275.379688)
		(end 290.78555 -275.379688)
		(width 0.1143)
		(layer "In7.Cu")
		(net "P5E_PEX2_STN2_RX_DN<32>")
	)
	(segment
		(start 290.565586 -271.421352)
		(end 290.519866 -271.467072)
		(width 0.1143)
		(layer "In7.Cu")
		(net "P5E_PEX2_STN2_RX_DN<32>")
	)
	(segment
		(start 325.444104 -37.481256)
		(end 325.55434 -38.052248)
		(width 0.1651)
		(layer "In7.Cu")
		(net "P5E_PEX2_STN2_RX_DN<32>")
	)
	(segment
		(start 312.16854 -116.656866)
		(end 311.852056 -144.057878)
		(width 0.1651)
		(layer "In7.Cu")
		(net "P5E_PEX2_STN2_RX_DN<32>")
	)
	(segment
		(start 323.1769 -61.172852)
		(end 312.16854 -116.656866)
		(width 0.1651)
		(layer "In7.Cu")
		(net "P5E_PEX2_STN2_RX_DN<32>")
	)
	(segment
		(start 323.360542 -49.41951)
		(end 323.1769 -61.172852)
		(width 0.1651)
		(layer "In7.Cu")
		(net "P5E_PEX2_STN2_RX_DN<32>")
	)
	(segment
		(start 290.742624 -269.42669)
		(end 290.565586 -270.191992)
		(width 0.1651)
		(layer "In7.Cu")
		(net "P5E_PEX2_STN2_RX_DN<32>")
	)
	(segment
		(start 290.976304 -266.734544)
		(end 290.97605 -266.734544)
		(width 0.1651)
		(layer "In7.Cu")
		(net "P5E_PEX2_STN2_RX_DN<32>")
	)
	(segment
		(start 319.555368 -28.5496)
		(end 320.210942 -28.5496)
		(width 0.1651)
		(layer "In7.Cu")
		(net "P5E_PEX2_STN2_RX_DN<32>")
	)
	(segment
		(start 325.55434 -38.052248)
		(end 325.33971 -39.96563)
		(width 0.1651)
		(layer "In7.Cu")
		(net "P5E_PEX2_STN2_RX_DN<32>")
	)
	(segment
		(start 290.89985 -275.265388)
		(end 290.89985 -274.999958)
		(width 0.1143)
		(layer "In7.Cu")
		(net "P5E_PEX2_STN2_RX_DN<32>")
	)
	(segment
		(start 290.78555 -275.379688)
		(end 290.89985 -275.265388)
		(width 0.1143)
		(layer "In7.Cu")
		(net "P5E_PEX2_STN2_RX_DN<32>")
	)
	(segment
		(start 319.264538 -28.25877)
		(end 319.555368 -28.5496)
		(width 0.1651)
		(layer "In7.Cu")
		(net "P5E_PEX2_STN2_RX_DN<32>")
	)
	(segment
		(start 322.751704 -31.090362)
		(end 325.444104 -37.481256)
		(width 0.1651)
		(layer "In7.Cu")
		(net "P5E_PEX2_STN2_RX_DN<32>")
	)
	(segment
		(start 290.97605 -266.734544)
		(end 290.742624 -269.42669)
		(width 0.1651)
		(layer "In7.Cu")
		(net "P5E_PEX2_STN2_RX_DN<32>")
	)
	(segment
		(start 310.46293 -154.841448)
		(end 290.976304 -266.734544)
		(width 0.1651)
		(layer "In7.Cu")
		(net "P5E_PEX2_STN2_RX_DN<32>")
	)
	(segment
		(start 290.565586 -271.392904)
		(end 290.565586 -271.421352)
		(width 0.1143)
		(layer "In7.Cu")
		(net "P5E_PEX2_STN2_RX_DN<32>")
	)
	(segment
		(start 311.852056 -144.057878)
		(end 310.46293 -154.841448)
		(width 0.1651)
		(layer "In7.Cu")
		(net "P5E_PEX2_STN2_RX_DN<32>")
	)
	(segment
		(start 290.519866 -275.275802)
		(end 290.623752 -275.379688)
		(width 0.1143)
		(layer "In7.Cu")
		(net "P5E_PEX2_STN2_RX_DN<32>")
	)
	(segment
		(start 290.565586 -270.191992)
		(end 290.565586 -271.392904)
		(width 0.1651)
		(layer "In7.Cu")
		(net "P5E_PEX2_STN2_RX_DN<32>")
	)
	(segment
		(start 290.519866 -271.467072)
		(end 290.519866 -275.275802)
		(width 0.1143)
		(layer "In7.Cu")
		(net "P5E_PEX2_STN2_RX_DN<32>")
	)
	(segment
		(start 320.210942 -28.5496)
		(end 322.751704 -31.090362)
		(width 0.1651)
		(layer "In7.Cu")
		(net "P5E_PEX2_STN2_RX_DN<32>")
	)
	(segment
		(start 396.629128 -345.171014)
		(end 396.92326 -345.465146)
		(width 0.13462)
		(layer "F.Cu")
		(net "P5E_PEX3_STN5_TX_C_DN<91>")
	)
	(segment
		(start 396.629128 -344.538554)
		(end 396.629128 -345.171014)
		(width 0.13462)
		(layer "F.Cu")
		(net "P5E_PEX3_STN5_TX_C_DN<91>")
	)
	(segment
		(start 396.94866 -344.219022)
		(end 396.629128 -344.538554)
		(width 0.13462)
		(layer "F.Cu")
		(net "P5E_PEX3_STN5_TX_C_DN<91>")
	)
	(segment
		(start 383.883916 -368.308382)
		(end 394.37564 -359.634536)
		(width 0.1651)
		(layer "In13.Cu")
		(net "P5E_PEX3_STN5_TX_C_DN<91>")
	)
	(segment
		(start 382.089914 -380.69012)
		(end 382.089914 -380.308104)
		(width 0.1651)
		(layer "In13.Cu")
		(net "P5E_PEX3_STN5_TX_C_DN<91>")
	)
	(segment
		(start 382.089914 -380.308104)
		(end 382.216914 -380.181104)
		(width 0.1651)
		(layer "In13.Cu")
		(net "P5E_PEX3_STN5_TX_C_DN<91>")
	)
	(segment
		(start 395.07795 -358.142794)
		(end 395.07795 -347.881194)
		(width 0.1651)
		(layer "In13.Cu")
		(net "P5E_PEX3_STN5_TX_C_DN<91>")
	)
	(segment
		(start 396.63243 -346.326714)
		(end 396.63243 -345.755976)
		(width 0.1651)
		(layer "In13.Cu")
		(net "P5E_PEX3_STN5_TX_C_DN<91>")
	)
	(segment
		(start 395.07795 -347.881194)
		(end 396.63243 -346.326714)
		(width 0.1651)
		(layer "In13.Cu")
		(net "P5E_PEX3_STN5_TX_C_DN<91>")
	)
	(segment
		(start 383.215896 -369.727226)
		(end 383.883916 -368.308382)
		(width 0.1651)
		(layer "In13.Cu")
		(net "P5E_PEX3_STN5_TX_C_DN<91>")
	)
	(segment
		(start 382.76403 -380.181104)
		(end 383.215896 -379.729238)
		(width 0.1651)
		(layer "In13.Cu")
		(net "P5E_PEX3_STN5_TX_C_DN<91>")
	)
	(segment
		(start 383.215896 -379.729238)
		(end 383.215896 -369.727226)
		(width 0.1651)
		(layer "In13.Cu")
		(net "P5E_PEX3_STN5_TX_C_DN<91>")
	)
	(segment
		(start 394.37564 -359.634536)
		(end 395.07795 -358.142794)
		(width 0.1651)
		(layer "In13.Cu")
		(net "P5E_PEX3_STN5_TX_C_DN<91>")
	)
	(segment
		(start 396.63243 -345.755976)
		(end 396.92326 -345.465146)
		(width 0.1651)
		(layer "In13.Cu")
		(net "P5E_PEX3_STN5_TX_C_DN<91>")
	)
	(segment
		(start 382.216914 -380.181104)
		(end 382.76403 -380.181104)
		(width 0.1651)
		(layer "In13.Cu")
		(net "P5E_PEX3_STN5_TX_C_DN<91>")
	)
	(segment
		(start 80.13954 -138.661648)
		(end 80.13954 -137.645648)
		(width 0.13208)
		(layer "F.Cu")
		(net "PRSNTB0_NIC1_N")
	)
	(segment
		(start 73.257664 -137.24509)
		(end 78.90891 -137.24509)
		(width 0.13208)
		(layer "F.Cu")
		(net "PRSNTB0_NIC1_N")
	)
	(segment
		(start 80.13954 -137.645648)
		(end 79.738982 -137.24509)
		(width 0.13208)
		(layer "F.Cu")
		(net "PRSNTB0_NIC1_N")
	)
	(segment
		(start 79.738982 -137.24509)
		(end 78.90891 -137.24509)
		(width 0.13208)
		(layer "F.Cu")
		(net "PRSNTB0_NIC1_N")
	)
	(via
		(at 78.90891 -137.24509)
		(size 0.762)
		(drill 0.381)
		(layers "F.Cu" "B.Cu")
		(net "PRSNTB0_NIC1_N")
	)
	(segment
		(start 46.042326 -119.355108)
		(end 45.554392 -119.355108)
		(width 0.13462)
		(layer "F.Cu")
		(net "P5E_PEX0_STN1_TX_C_DP<24>")
	)
	(segment
		(start 45.391578 -119.517922)
		(end 37.224208 -119.517922)
		(width 0.13462)
		(layer "F.Cu")
		(net "P5E_PEX0_STN1_TX_C_DP<24>")
	)
	(segment
		(start 37.224208 -119.517922)
		(end 36.905184 -119.198898)
		(width 0.13462)
		(layer "F.Cu")
		(net "P5E_PEX0_STN1_TX_C_DP<24>")
	)
	(segment
		(start 45.554392 -119.355108)
		(end 45.391578 -119.517922)
		(width 0.13462)
		(layer "F.Cu")
		(net "P5E_PEX0_STN1_TX_C_DP<24>")
	)
	(segment
		(start 72.802242 -395.61262)
		(end 72.471788 -394.814806)
		(width 0.1651)
		(layer "In5.Cu")
		(net "P5E_PEX0_STN6_RX_DP<111>")
	)
	(segment
		(start 57.241694 -355.980492)
		(end 56.353964 -352.43643)
		(width 0.1651)
		(layer "In5.Cu")
		(net "P5E_PEX0_STN6_RX_DP<111>")
	)
	(segment
		(start 55.578248 -346.147898)
		(end 52.558442 -338.85759)
		(width 0.1651)
		(layer "In5.Cu")
		(net "P5E_PEX0_STN6_RX_DP<111>")
	)
	(segment
		(start 72.03694 -400.899122)
		(end 72.564244 -400.899122)
		(width 0.1651)
		(layer "In5.Cu")
		(net "P5E_PEX0_STN6_RX_DP<111>")
	)
	(segment
		(start 48.648366 -333.00543)
		(end 48.493172 -332.974442)
		(width 0.1651)
		(layer "In5.Cu")
		(net "P5E_PEX0_STN6_RX_DP<111>")
	)
	(segment
		(start 42.929556 -319.921128)
		(end 42.929556 -316.455298)
		(width 0.1143)
		(layer "In5.Cu")
		(net "P5E_PEX0_STN6_RX_DP<111>")
	)
	(segment
		(start 65.042542 -388.840726)
		(end 63.712598 -385.63042)
		(width 0.1651)
		(layer "In5.Cu")
		(net "P5E_PEX0_STN6_RX_DP<111>")
	)
	(segment
		(start 72.564244 -400.899122)
		(end 72.802242 -400.661124)
		(width 0.1651)
		(layer "In5.Cu")
		(net "P5E_PEX0_STN6_RX_DP<111>")
	)
	(segment
		(start 71.90994 -400.390106)
		(end 71.90994 -400.772122)
		(width 0.1651)
		(layer "In5.Cu")
		(net "P5E_PEX0_STN6_RX_DP<111>")
	)
	(segment
		(start 44.058332 -326.136)
		(end 42.883836 -323.300852)
		(width 0.1651)
		(layer "In5.Cu")
		(net "P5E_PEX0_STN6_RX_DP<111>")
	)
	(segment
		(start 47.595028 -331.42936)
		(end 47.595028 -331.429106)
		(width 0.1651)
		(layer "In5.Cu")
		(net "P5E_PEX0_STN6_RX_DP<111>")
	)
	(segment
		(start 63.712598 -385.63042)
		(end 62.011814 -368.345212)
		(width 0.1651)
		(layer "In5.Cu")
		(net "P5E_PEX0_STN6_RX_DP<111>")
	)
	(segment
		(start 72.044306 -394.387324)
		(end 67.659504 -391.457688)
		(width 0.1651)
		(layer "In5.Cu")
		(net "P5E_PEX0_STN6_RX_DP<111>")
	)
	(segment
		(start 47.987712 -332.016862)
		(end 47.832772 -331.985874)
		(width 0.1651)
		(layer "In5.Cu")
		(net "P5E_PEX0_STN6_RX_DP<111>")
	)
	(segment
		(start 48.224948 -332.573122)
		(end 48.255682 -332.417928)
		(width 0.1651)
		(layer "In5.Cu")
		(net "P5E_PEX0_STN6_RX_DP<111>")
	)
	(segment
		(start 42.883836 -319.995296)
		(end 42.883836 -319.966848)
		(width 0.1143)
		(layer "In5.Cu")
		(net "P5E_PEX0_STN6_RX_DP<111>")
	)
	(segment
		(start 47.595028 -331.429106)
		(end 44.058332 -326.136)
		(width 0.1651)
		(layer "In5.Cu")
		(net "P5E_PEX0_STN6_RX_DP<111>")
	)
	(segment
		(start 62.011814 -368.345212)
		(end 57.241694 -355.980492)
		(width 0.1651)
		(layer "In5.Cu")
		(net "P5E_PEX0_STN6_RX_DP<111>")
	)
	(segment
		(start 47.832772 -331.985874)
		(end 47.564294 -331.5843)
		(width 0.1651)
		(layer "In5.Cu")
		(net "P5E_PEX0_STN6_RX_DP<111>")
	)
	(segment
		(start 42.883836 -319.966848)
		(end 42.929556 -319.921128)
		(width 0.1143)
		(layer "In5.Cu")
		(net "P5E_PEX0_STN6_RX_DP<111>")
	)
	(segment
		(start 48.648112 -333.00543)
		(end 48.648366 -333.00543)
		(width 0.1651)
		(layer "In5.Cu")
		(net "P5E_PEX0_STN6_RX_DP<111>")
	)
	(segment
		(start 72.802242 -400.661124)
		(end 72.802242 -395.61262)
		(width 0.1651)
		(layer "In5.Cu")
		(net "P5E_PEX0_STN6_RX_DP<111>")
	)
	(segment
		(start 47.564294 -331.5843)
		(end 47.595028 -331.42936)
		(width 0.1651)
		(layer "In5.Cu")
		(net "P5E_PEX0_STN6_RX_DP<111>")
	)
	(segment
		(start 48.493172 -332.974442)
		(end 48.224948 -332.573122)
		(width 0.1651)
		(layer "In5.Cu")
		(net "P5E_PEX0_STN6_RX_DP<111>")
	)
	(segment
		(start 56.353964 -352.43643)
		(end 55.578248 -346.147898)
		(width 0.1651)
		(layer "In5.Cu")
		(net "P5E_PEX0_STN6_RX_DP<111>")
	)
	(segment
		(start 43.385486 -316.229492)
		(end 43.499786 -316.115192)
		(width 0.1143)
		(layer "In5.Cu")
		(net "P5E_PEX0_STN6_RX_DP<111>")
	)
	(segment
		(start 42.883836 -323.300852)
		(end 42.883836 -319.995296)
		(width 0.1651)
		(layer "In5.Cu")
		(net "P5E_PEX0_STN6_RX_DP<111>")
	)
	(segment
		(start 48.255682 -332.417928)
		(end 47.987712 -332.016862)
		(width 0.1651)
		(layer "In5.Cu")
		(net "P5E_PEX0_STN6_RX_DP<111>")
	)
	(segment
		(start 52.558442 -338.85759)
		(end 48.648112 -333.00543)
		(width 0.1651)
		(layer "In5.Cu")
		(net "P5E_PEX0_STN6_RX_DP<111>")
	)
	(segment
		(start 67.659504 -391.457688)
		(end 65.042542 -388.840726)
		(width 0.1651)
		(layer "In5.Cu")
		(net "P5E_PEX0_STN6_RX_DP<111>")
	)
	(segment
		(start 71.90994 -400.772122)
		(end 72.03694 -400.899122)
		(width 0.1651)
		(layer "In5.Cu")
		(net "P5E_PEX0_STN6_RX_DP<111>")
	)
	(segment
		(start 72.471788 -394.814806)
		(end 72.044306 -394.387324)
		(width 0.1651)
		(layer "In5.Cu")
		(net "P5E_PEX0_STN6_RX_DP<111>")
	)
	(segment
		(start 43.499786 -316.115192)
		(end 43.499786 -315.849762)
		(width 0.1143)
		(layer "In5.Cu")
		(net "P5E_PEX0_STN6_RX_DP<111>")
	)
	(segment
		(start 43.155362 -316.229492)
		(end 43.385486 -316.229492)
		(width 0.1143)
		(layer "In5.Cu")
		(net "P5E_PEX0_STN6_RX_DP<111>")
	)
	(segment
		(start 42.929556 -316.455298)
		(end 43.155362 -316.229492)
		(width 0.1143)
		(layer "In5.Cu")
		(net "P5E_PEX0_STN6_RX_DP<111>")
	)
	(segment
		(start 252.367796 -33.631886)
		(end 252.047502 -33.95218)
		(width 0.13462)
		(layer "F.Cu")
		(net "P5E_PEX2_STN2_TX_C_DN<47>")
	)
	(segment
		(start 252.047502 -33.95218)
		(end 248.13387 -33.95218)
		(width 0.13462)
		(layer "F.Cu")
		(net "P5E_PEX2_STN2_TX_C_DN<47>")
	)
	(segment
		(start 248.13387 -33.95218)
		(end 247.971818 -33.790128)
		(width 0.13462)
		(layer "F.Cu")
		(net "P5E_PEX2_STN2_TX_C_DN<47>")
	)
	(segment
		(start 247.971818 -33.790128)
		(end 247.464834 -33.790128)
		(width 0.13462)
		(layer "F.Cu")
		(net "P5E_PEX2_STN2_TX_C_DN<47>")
	)
	(segment
		(start 376.61596 -370.829332)
		(end 376.61596 -369.492276)
		(width 0.1651)
		(layer "In15.Cu")
		(net "P5E_PEX3_STN5_RX_DN<88>")
	)
	(segment
		(start 376.164094 -371.281198)
		(end 376.61596 -370.829332)
		(width 0.1651)
		(layer "In15.Cu")
		(net "P5E_PEX3_STN5_RX_DN<88>")
	)
	(segment
		(start 414.220152 -319.921128)
		(end 414.220152 -316.523624)
		(width 0.1143)
		(layer "In15.Cu")
		(net "P5E_PEX3_STN5_RX_DN<88>")
	)
	(segment
		(start 414.264602 -320.85915)
		(end 414.265872 -320.85788)
		(width 0.1651)
		(layer "In15.Cu")
		(net "P5E_PEX3_STN5_RX_DN<88>")
	)
	(segment
		(start 385.75107 -342.170766)
		(end 386.065268 -341.409274)
		(width 0.1651)
		(layer "In15.Cu")
		(net "P5E_PEX3_STN5_RX_DN<88>")
	)
	(segment
		(start 376.61596 -369.492276)
		(end 377.104402 -368.328194)
		(width 0.1651)
		(layer "In15.Cu")
		(net "P5E_PEX3_STN5_RX_DN<88>")
	)
	(segment
		(start 375.489978 -371.408198)
		(end 375.616978 -371.281198)
		(width 0.1651)
		(layer "In15.Cu")
		(net "P5E_PEX3_STN5_RX_DN<88>")
	)
	(segment
		(start 385.343146 -359.220262)
		(end 385.75107 -358.160828)
		(width 0.1651)
		(layer "In15.Cu")
		(net "P5E_PEX3_STN5_RX_DN<88>")
	)
	(segment
		(start 414.265872 -319.966848)
		(end 414.220152 -319.921128)
		(width 0.1143)
		(layer "In15.Cu")
		(net "P5E_PEX3_STN5_RX_DN<88>")
	)
	(segment
		(start 414.220152 -316.523624)
		(end 414.323784 -316.419992)
		(width 0.1143)
		(layer "In15.Cu")
		(net "P5E_PEX3_STN5_RX_DN<88>")
	)
	(segment
		(start 375.489978 -371.790214)
		(end 375.489978 -371.408198)
		(width 0.1651)
		(layer "In15.Cu")
		(net "P5E_PEX3_STN5_RX_DN<88>")
	)
	(segment
		(start 414.265872 -320.85788)
		(end 414.265872 -319.995296)
		(width 0.1651)
		(layer "In15.Cu")
		(net "P5E_PEX3_STN5_RX_DN<88>")
	)
	(segment
		(start 414.323784 -316.419992)
		(end 414.485582 -316.419992)
		(width 0.1143)
		(layer "In15.Cu")
		(net "P5E_PEX3_STN5_RX_DN<88>")
	)
	(segment
		(start 414.599882 -316.534292)
		(end 414.599882 -316.799722)
		(width 0.1143)
		(layer "In15.Cu")
		(net "P5E_PEX3_STN5_RX_DN<88>")
	)
	(segment
		(start 414.485582 -316.419992)
		(end 414.599882 -316.534292)
		(width 0.1143)
		(layer "In15.Cu")
		(net "P5E_PEX3_STN5_RX_DN<88>")
	)
	(segment
		(start 375.616978 -371.281198)
		(end 376.164094 -371.281198)
		(width 0.1651)
		(layer "In15.Cu")
		(net "P5E_PEX3_STN5_RX_DN<88>")
	)
	(segment
		(start 377.104402 -368.328194)
		(end 385.343146 -359.220262)
		(width 0.1651)
		(layer "In15.Cu")
		(net "P5E_PEX3_STN5_RX_DN<88>")
	)
	(segment
		(start 385.75107 -358.160828)
		(end 385.75107 -342.170766)
		(width 0.1651)
		(layer "In15.Cu")
		(net "P5E_PEX3_STN5_RX_DN<88>")
	)
	(segment
		(start 386.065268 -341.409274)
		(end 414.264602 -320.85915)
		(width 0.1651)
		(layer "In15.Cu")
		(net "P5E_PEX3_STN5_RX_DN<88>")
	)
	(segment
		(start 414.265872 -319.995296)
		(end 414.265872 -319.966848)
		(width 0.1143)
		(layer "In15.Cu")
		(net "P5E_PEX3_STN5_RX_DN<88>")
	)
	(segment
		(start 39.547292 -111.003334)
		(end 39.868348 -110.682278)
		(width 0.13462)
		(layer "F.Cu")
		(net "P5E_PEX0_STN1_TX_C_DN<22>")
	)
	(segment
		(start 45.391578 -110.682278)
		(end 45.554392 -110.845092)
		(width 0.13462)
		(layer "F.Cu")
		(net "P5E_PEX0_STN1_TX_C_DN<22>")
	)
	(segment
		(start 39.868348 -110.682278)
		(end 45.391578 -110.682278)
		(width 0.13462)
		(layer "F.Cu")
		(net "P5E_PEX0_STN1_TX_C_DN<22>")
	)
	(segment
		(start 45.554392 -110.845092)
		(end 46.042326 -110.845092)
		(width 0.13462)
		(layer "F.Cu")
		(net "P5E_PEX0_STN1_TX_C_DN<22>")
	)
	(segment
		(start 68.26758 -390.714992)
		(end 65.883536 -388.330948)
		(width 0.1651)
		(layer "In5.Cu")
		(net "P5E_PEX0_STN6_RX_DP<110>")
	)
	(segment
		(start 43.833796 -323.097906)
		(end 43.833796 -319.995296)
		(width 0.1651)
		(layer "In5.Cu")
		(net "P5E_PEX0_STN6_RX_DP<110>")
	)
	(segment
		(start 46.42485 -327.943972)
		(end 46.156626 -327.542652)
		(width 0.1651)
		(layer "In5.Cu")
		(net "P5E_PEX0_STN6_RX_DP<110>")
	)
	(segment
		(start 53.171852 -337.840574)
		(end 46.57979 -327.97496)
		(width 0.1651)
		(layer "In5.Cu")
		(net "P5E_PEX0_STN6_RX_DP<110>")
	)
	(segment
		(start 44.105322 -318.129666)
		(end 44.335446 -318.129666)
		(width 0.1143)
		(layer "In5.Cu")
		(net "P5E_PEX0_STN6_RX_DP<110>")
	)
	(segment
		(start 45.91939 -326.986392)
		(end 45.764196 -326.955658)
		(width 0.1651)
		(layer "In5.Cu")
		(net "P5E_PEX0_STN6_RX_DP<110>")
	)
	(segment
		(start 58.154062 -355.691186)
		(end 57.295542 -352.26371)
		(width 0.1651)
		(layer "In5.Cu")
		(net "P5E_PEX0_STN6_RX_DP<110>")
	)
	(segment
		(start 46.580044 -327.97496)
		(end 46.42485 -327.943972)
		(width 0.1651)
		(layer "In5.Cu")
		(net "P5E_PEX0_STN6_RX_DP<110>")
	)
	(segment
		(start 75.00239 -396.713202)
		(end 74.300842 -395.019276)
		(width 0.1651)
		(layer "In5.Cu")
		(net "P5E_PEX0_STN6_RX_DP<110>")
	)
	(segment
		(start 45.526706 -326.399144)
		(end 44.669964 -325.116698)
		(width 0.1651)
		(layer "In5.Cu")
		(net "P5E_PEX0_STN6_RX_DP<110>")
	)
	(segment
		(start 44.335446 -318.129666)
		(end 44.449746 -318.015366)
		(width 0.1143)
		(layer "In5.Cu")
		(net "P5E_PEX0_STN6_RX_DP<110>")
	)
	(segment
		(start 56.510428 -345.902026)
		(end 53.171852 -337.840574)
		(width 0.1651)
		(layer "In5.Cu")
		(net "P5E_PEX0_STN6_RX_DP<110>")
	)
	(segment
		(start 65.883536 -388.330948)
		(end 64.788542 -385.68757)
		(width 0.1651)
		(layer "In5.Cu")
		(net "P5E_PEX0_STN6_RX_DP<110>")
	)
	(segment
		(start 74.109834 -401.49018)
		(end 74.109834 -401.872196)
		(width 0.1651)
		(layer "In5.Cu")
		(net "P5E_PEX0_STN6_RX_DP<110>")
	)
	(segment
		(start 46.18736 -327.387458)
		(end 45.91939 -326.986392)
		(width 0.1651)
		(layer "In5.Cu")
		(net "P5E_PEX0_STN6_RX_DP<110>")
	)
	(segment
		(start 44.449746 -318.015366)
		(end 44.449746 -317.749936)
		(width 0.1143)
		(layer "In5.Cu")
		(net "P5E_PEX0_STN6_RX_DP<110>")
	)
	(segment
		(start 57.295542 -352.26371)
		(end 56.510428 -345.902026)
		(width 0.1651)
		(layer "In5.Cu")
		(net "P5E_PEX0_STN6_RX_DP<110>")
	)
	(segment
		(start 75.00239 -401.71243)
		(end 75.00239 -396.713202)
		(width 0.1651)
		(layer "In5.Cu")
		(net "P5E_PEX0_STN6_RX_DP<110>")
	)
	(segment
		(start 64.788542 -385.68757)
		(end 63.09487 -368.498628)
		(width 0.1651)
		(layer "In5.Cu")
		(net "P5E_PEX0_STN6_RX_DP<110>")
	)
	(segment
		(start 46.57979 -327.97496)
		(end 46.580044 -327.97496)
		(width 0.1651)
		(layer "In5.Cu")
		(net "P5E_PEX0_STN6_RX_DP<110>")
	)
	(segment
		(start 43.879516 -319.921128)
		(end 43.879516 -318.355472)
		(width 0.1143)
		(layer "In5.Cu")
		(net "P5E_PEX0_STN6_RX_DP<110>")
	)
	(segment
		(start 43.833796 -319.995296)
		(end 43.833796 -319.966848)
		(width 0.1143)
		(layer "In5.Cu")
		(net "P5E_PEX0_STN6_RX_DP<110>")
	)
	(segment
		(start 73.47839 -394.196824)
		(end 68.26758 -390.714992)
		(width 0.1651)
		(layer "In5.Cu")
		(net "P5E_PEX0_STN6_RX_DP<110>")
	)
	(segment
		(start 63.09487 -368.498628)
		(end 58.154062 -355.691186)
		(width 0.1651)
		(layer "In5.Cu")
		(net "P5E_PEX0_STN6_RX_DP<110>")
	)
	(segment
		(start 43.833796 -319.966848)
		(end 43.879516 -319.921128)
		(width 0.1143)
		(layer "In5.Cu")
		(net "P5E_PEX0_STN6_RX_DP<110>")
	)
	(segment
		(start 45.764196 -326.955658)
		(end 45.495972 -326.554084)
		(width 0.1651)
		(layer "In5.Cu")
		(net "P5E_PEX0_STN6_RX_DP<110>")
	)
	(segment
		(start 44.669964 -325.116698)
		(end 43.833796 -323.097906)
		(width 0.1651)
		(layer "In5.Cu")
		(net "P5E_PEX0_STN6_RX_DP<110>")
	)
	(segment
		(start 74.300842 -395.019276)
		(end 73.47839 -394.196824)
		(width 0.1651)
		(layer "In5.Cu")
		(net "P5E_PEX0_STN6_RX_DP<110>")
	)
	(segment
		(start 74.715624 -401.999196)
		(end 75.00239 -401.71243)
		(width 0.1651)
		(layer "In5.Cu")
		(net "P5E_PEX0_STN6_RX_DP<110>")
	)
	(segment
		(start 74.109834 -401.872196)
		(end 74.236834 -401.999196)
		(width 0.1651)
		(layer "In5.Cu")
		(net "P5E_PEX0_STN6_RX_DP<110>")
	)
	(segment
		(start 43.879516 -318.355472)
		(end 44.105322 -318.129666)
		(width 0.1143)
		(layer "In5.Cu")
		(net "P5E_PEX0_STN6_RX_DP<110>")
	)
	(segment
		(start 45.495972 -326.554084)
		(end 45.526706 -326.399144)
		(width 0.1651)
		(layer "In5.Cu")
		(net "P5E_PEX0_STN6_RX_DP<110>")
	)
	(segment
		(start 74.236834 -401.999196)
		(end 74.715624 -401.999196)
		(width 0.1651)
		(layer "In5.Cu")
		(net "P5E_PEX0_STN6_RX_DP<110>")
	)
	(segment
		(start 46.156626 -327.542652)
		(end 46.18736 -327.387458)
		(width 0.1651)
		(layer "In5.Cu")
		(net "P5E_PEX0_STN6_RX_DP<110>")
	)
	(segment
		(start 278.367744 -30.03169)
		(end 278.041354 -30.35808)
		(width 0.13462)
		(layer "F.Cu")
		(net "P5E_PEX2_STN2_TX_C_DN<41>")
	)
	(segment
		(start 274.13585 -30.35808)
		(end 273.967956 -30.190186)
		(width 0.13462)
		(layer "F.Cu")
		(net "P5E_PEX2_STN2_TX_C_DN<41>")
	)
	(segment
		(start 278.041354 -30.35808)
		(end 274.13585 -30.35808)
		(width 0.13462)
		(layer "F.Cu")
		(net "P5E_PEX2_STN2_TX_C_DN<41>")
	)
	(segment
		(start 273.967956 -30.190186)
		(end 273.464782 -30.190186)
		(width 0.13462)
		(layer "F.Cu")
		(net "P5E_PEX2_STN2_TX_C_DN<41>")
	)
	(segment
		(start 396.354808 -357.462582)
		(end 396.05966 -357.75773)
		(width 0.13462)
		(layer "F.Cu")
		(net "P5E_PEX3_STN5_TX_C_DP<92>")
	)
	(segment
		(start 396.03426 -356.511606)
		(end 396.354808 -356.832154)
		(width 0.13462)
		(layer "F.Cu")
		(net "P5E_PEX3_STN5_TX_C_DP<92>")
	)
	(segment
		(start 396.354808 -356.832154)
		(end 396.354808 -357.462582)
		(width 0.13462)
		(layer "F.Cu")
		(net "P5E_PEX3_STN5_TX_C_DP<92>")
	)
	(segment
		(start 389.405368 -365.060992)
		(end 395.886686 -359.414318)
		(width 0.1651)
		(layer "In13.Cu")
		(net "P5E_PEX3_STN5_TX_C_DP<92>")
	)
	(segment
		(start 388.398766 -365.819944)
		(end 388.524242 -365.82858)
		(width 0.1651)
		(layer "In13.Cu")
		(net "P5E_PEX3_STN5_TX_C_DP<92>")
	)
	(segment
		(start 387.13537 -367.038382)
		(end 387.144006 -366.91316)
		(width 0.1651)
		(layer "In13.Cu")
		(net "P5E_PEX3_STN5_TX_C_DP<92>")
	)
	(segment
		(start 388.897622 -365.50346)
		(end 388.906258 -365.377984)
		(width 0.1651)
		(layer "In13.Cu")
		(net "P5E_PEX3_STN5_TX_C_DP<92>")
	)
	(segment
		(start 387.51764 -366.587532)
		(end 387.643116 -366.596168)
		(width 0.1651)
		(layer "In13.Cu")
		(net "P5E_PEX3_STN5_TX_C_DP<92>")
	)
	(segment
		(start 387.144006 -366.91316)
		(end 387.51764 -366.587532)
		(width 0.1651)
		(layer "In13.Cu")
		(net "P5E_PEX3_STN5_TX_C_DP<92>")
	)
	(segment
		(start 385.134104 -369.780058)
		(end 385.886452 -368.126518)
		(width 0.1651)
		(layer "In13.Cu")
		(net "P5E_PEX3_STN5_TX_C_DP<92>")
	)
	(segment
		(start 384.290062 -378.67209)
		(end 384.417062 -378.79909)
		(width 0.1651)
		(layer "In13.Cu")
		(net "P5E_PEX3_STN5_TX_C_DP<92>")
	)
	(segment
		(start 384.290062 -378.290074)
		(end 384.290062 -378.67209)
		(width 0.1651)
		(layer "In13.Cu")
		(net "P5E_PEX3_STN5_TX_C_DP<92>")
	)
	(segment
		(start 385.886452 -368.126518)
		(end 387.13537 -367.038382)
		(width 0.1651)
		(layer "In13.Cu")
		(net "P5E_PEX3_STN5_TX_C_DP<92>")
	)
	(segment
		(start 384.847338 -378.79909)
		(end 385.134104 -378.512324)
		(width 0.1651)
		(layer "In13.Cu")
		(net "P5E_PEX3_STN5_TX_C_DP<92>")
	)
	(segment
		(start 388.025132 -366.145572)
		(end 388.398766 -365.819944)
		(width 0.1651)
		(layer "In13.Cu")
		(net "P5E_PEX3_STN5_TX_C_DP<92>")
	)
	(segment
		(start 387.643116 -366.596168)
		(end 388.016496 -366.271048)
		(width 0.1651)
		(layer "In13.Cu")
		(net "P5E_PEX3_STN5_TX_C_DP<92>")
	)
	(segment
		(start 396.35049 -358.395524)
		(end 396.35049 -358.04856)
		(width 0.1651)
		(layer "In13.Cu")
		(net "P5E_PEX3_STN5_TX_C_DP<92>")
	)
	(segment
		(start 385.134104 -378.512324)
		(end 385.134104 -369.780058)
		(width 0.1651)
		(layer "In13.Cu")
		(net "P5E_PEX3_STN5_TX_C_DP<92>")
	)
	(segment
		(start 396.35049 -358.04856)
		(end 396.05966 -357.75773)
		(width 0.1651)
		(layer "In13.Cu")
		(net "P5E_PEX3_STN5_TX_C_DP<92>")
	)
	(segment
		(start 389.279892 -365.052356)
		(end 389.405368 -365.060992)
		(width 0.1651)
		(layer "In13.Cu")
		(net "P5E_PEX3_STN5_TX_C_DP<92>")
	)
	(segment
		(start 384.417062 -378.79909)
		(end 384.847338 -378.79909)
		(width 0.1651)
		(layer "In13.Cu")
		(net "P5E_PEX3_STN5_TX_C_DP<92>")
	)
	(segment
		(start 388.524242 -365.82858)
		(end 388.897622 -365.50346)
		(width 0.1651)
		(layer "In13.Cu")
		(net "P5E_PEX3_STN5_TX_C_DP<92>")
	)
	(segment
		(start 388.906258 -365.377984)
		(end 389.279892 -365.052356)
		(width 0.1651)
		(layer "In13.Cu")
		(net "P5E_PEX3_STN5_TX_C_DP<92>")
	)
	(segment
		(start 388.016496 -366.271048)
		(end 388.025132 -366.145572)
		(width 0.1651)
		(layer "In13.Cu")
		(net "P5E_PEX3_STN5_TX_C_DP<92>")
	)
	(segment
		(start 395.886686 -359.414318)
		(end 396.35049 -358.395524)
		(width 0.1651)
		(layer "In13.Cu")
		(net "P5E_PEX3_STN5_TX_C_DP<92>")
	)
	(segment
		(start 72.428862 -114.290094)
		(end 71.548752 -114.290094)
		(width 0.13208)
		(layer "F.Cu")
		(net "RST_NIC1_PERST0_R_N")
	)
	(segment
		(start 72.773794 -114.635026)
		(end 72.428862 -114.290094)
		(width 0.13208)
		(layer "F.Cu")
		(net "RST_NIC1_PERST0_R_N")
	)
	(segment
		(start 81.639664 -87.749126)
		(end 81.639664 -88.39581)
		(width 0.13208)
		(layer "F.Cu")
		(net "RST_NIC1_PERST0_R_N")
	)
	(segment
		(start 73.257664 -114.635026)
		(end 72.773794 -114.635026)
		(width 0.13208)
		(layer "F.Cu")
		(net "RST_NIC1_PERST0_R_N")
	)
	(segment
		(start 71.548752 -114.290094)
		(end 71.17588 -113.917222)
		(width 0.13208)
		(layer "F.Cu")
		(net "RST_NIC1_PERST0_R_N")
	)
	(via
		(at 81.639664 -88.39581)
		(size 0.508)
		(drill 0.254)
		(layers "F.Cu" "B.Cu")
		(net "RST_NIC1_PERST0_R_N")
	)
	(via
		(at 71.17588 -113.917222)
		(size 0.508)
		(drill 0.254)
		(layers "F.Cu" "B.Cu")
		(net "RST_NIC1_PERST0_R_N")
	)
	(segment
		(start 81.639664 -88.39581)
		(end 81.152492 -88.882982)
		(width 0.15494)
		(layer "In11.Cu")
		(net "RST_NIC1_PERST0_R_N")
	)
	(segment
		(start 73.703942 -105.429812)
		(end 73.703942 -112.14608)
		(width 0.15494)
		(layer "In11.Cu")
		(net "RST_NIC1_PERST0_R_N")
	)
	(segment
		(start 72.893936 -104.619806)
		(end 73.703942 -105.429812)
		(width 0.15494)
		(layer "In11.Cu")
		(net "RST_NIC1_PERST0_R_N")
	)
	(segment
		(start 81.152492 -88.882982)
		(end 77.161136 -88.882982)
		(width 0.15494)
		(layer "In11.Cu")
		(net "RST_NIC1_PERST0_R_N")
	)
	(segment
		(start 72.893936 -98.06559)
		(end 72.893936 -104.619806)
		(width 0.15494)
		(layer "In11.Cu")
		(net "RST_NIC1_PERST0_R_N")
	)
	(segment
		(start 73.703942 -112.14608)
		(end 72.289162 -113.56086)
		(width 0.15494)
		(layer "In11.Cu")
		(net "RST_NIC1_PERST0_R_N")
	)
	(segment
		(start 74.694542 -96.264984)
		(end 72.893936 -98.06559)
		(width 0.15494)
		(layer "In11.Cu")
		(net "RST_NIC1_PERST0_R_N")
	)
	(segment
		(start 72.289162 -113.56086)
		(end 71.532242 -113.56086)
		(width 0.15494)
		(layer "In11.Cu")
		(net "RST_NIC1_PERST0_R_N")
	)
	(segment
		(start 74.694542 -91.349576)
		(end 74.694542 -96.264984)
		(width 0.15494)
		(layer "In11.Cu")
		(net "RST_NIC1_PERST0_R_N")
	)
	(segment
		(start 77.161136 -88.882982)
		(end 74.694542 -91.349576)
		(width 0.15494)
		(layer "In11.Cu")
		(net "RST_NIC1_PERST0_R_N")
	)
	(segment
		(start 71.532242 -113.56086)
		(end 71.17588 -113.917222)
		(width 0.15494)
		(layer "In11.Cu")
		(net "RST_NIC1_PERST0_R_N")
	)
	(segment
		(start 50.64252 -101.84511)
		(end 51.130454 -101.84511)
		(width 0.13462)
		(layer "F.Cu")
		(net "P5E_PEX0_STN1_RX_DN<17>")
	)
	(segment
		(start 51.293522 -101.682042)
		(end 51.948334 -101.682042)
		(width 0.13462)
		(layer "F.Cu")
		(net "P5E_PEX0_STN1_RX_DN<17>")
	)
	(segment
		(start 51.130454 -101.84511)
		(end 51.293522 -101.682042)
		(width 0.13462)
		(layer "F.Cu")
		(net "P5E_PEX0_STN1_RX_DN<17>")
	)
	(segment
		(start 51.948334 -101.682042)
		(end 52.24272 -101.976428)
		(width 0.13462)
		(layer "F.Cu")
		(net "P5E_PEX0_STN1_RX_DN<17>")
	)
	(segment
		(start 42.555922 -107.931204)
		(end 42.717466 -107.927902)
		(width 0.1651)
		(layer "In5.Cu")
		(net "P5E_PEX0_STN1_RX_DN<17>")
	)
	(segment
		(start 60.599574 -274.999704)
		(end 60.599574 -275.265134)
		(width 0.1143)
		(layer "In5.Cu")
		(net "P5E_PEX0_STN1_RX_DN<17>")
	)
	(segment
		(start 45.819822 -105.094278)
		(end 46.250098 -104.84866)
		(width 0.1651)
		(layer "In5.Cu")
		(net "P5E_PEX0_STN1_RX_DN<17>")
	)
	(segment
		(start 49.600612 -102.936802)
		(end 50.031142 -102.691184)
		(width 0.1651)
		(layer "In5.Cu")
		(net "P5E_PEX0_STN1_RX_DN<17>")
	)
	(segment
		(start 31.075122 -165.351968)
		(end 29.88564 -158.838138)
		(width 0.1651)
		(layer "In5.Cu")
		(net "P5E_PEX0_STN1_RX_DN<17>")
	)
	(segment
		(start 29.88564 -158.838138)
		(end 29.31795 -150.180294)
		(width 0.1651)
		(layer "In5.Cu")
		(net "P5E_PEX0_STN1_RX_DN<17>")
	)
	(segment
		(start 43.561508 -107.047792)
		(end 43.904408 -106.689906)
		(width 0.1651)
		(layer "In5.Cu")
		(net "P5E_PEX0_STN1_RX_DN<17>")
	)
	(segment
		(start 60.599574 -275.265134)
		(end 60.485274 -275.379434)
		(width 0.1143)
		(layer "In5.Cu")
		(net "P5E_PEX0_STN1_RX_DN<17>")
	)
	(segment
		(start 29.31795 -150.180294)
		(end 30.741112 -126.612142)
		(width 0.1651)
		(layer "In5.Cu")
		(net "P5E_PEX0_STN1_RX_DN<17>")
	)
	(segment
		(start 32.231584 -119.95023)
		(end 33.566862 -117.307614)
		(width 0.1651)
		(layer "In5.Cu")
		(net "P5E_PEX0_STN1_RX_DN<17>")
	)
	(segment
		(start 60.323476 -275.379434)
		(end 60.220098 -275.276056)
		(width 0.1143)
		(layer "In5.Cu")
		(net "P5E_PEX0_STN1_RX_DN<17>")
	)
	(segment
		(start 60.265818 -271.802352)
		(end 60.265818 -271.773904)
		(width 0.1143)
		(layer "In5.Cu")
		(net "P5E_PEX0_STN1_RX_DN<17>")
	)
	(segment
		(start 43.39971 -107.051094)
		(end 43.561508 -107.047792)
		(width 0.1651)
		(layer "In5.Cu")
		(net "P5E_PEX0_STN1_RX_DN<17>")
	)
	(segment
		(start 46.29277 -104.692704)
		(end 47.326804 -104.102662)
		(width 0.1651)
		(layer "In5.Cu")
		(net "P5E_PEX0_STN1_RX_DN<17>")
	)
	(segment
		(start 43.057064 -107.408472)
		(end 43.39971 -107.051094)
		(width 0.1651)
		(layer "In5.Cu")
		(net "P5E_PEX0_STN1_RX_DN<17>")
	)
	(segment
		(start 51.95189 -101.685598)
		(end 52.24272 -101.976428)
		(width 0.1651)
		(layer "In5.Cu")
		(net "P5E_PEX0_STN1_RX_DN<17>")
	)
	(segment
		(start 43.901106 -106.528362)
		(end 44.897548 -105.488994)
		(width 0.1651)
		(layer "In5.Cu")
		(net "P5E_PEX0_STN1_RX_DN<17>")
	)
	(segment
		(start 51.563016 -101.685598)
		(end 51.95189 -101.685598)
		(width 0.1651)
		(layer "In5.Cu")
		(net "P5E_PEX0_STN1_RX_DN<17>")
	)
	(segment
		(start 42.717466 -107.927902)
		(end 43.060366 -107.570016)
		(width 0.1651)
		(layer "In5.Cu")
		(net "P5E_PEX0_STN1_RX_DN<17>")
	)
	(segment
		(start 46.250098 -104.84866)
		(end 46.29277 -104.692704)
		(width 0.1651)
		(layer "In5.Cu")
		(net "P5E_PEX0_STN1_RX_DN<17>")
	)
	(segment
		(start 47.91329 -103.899716)
		(end 47.955962 -103.74376)
		(width 0.1651)
		(layer "In5.Cu")
		(net "P5E_PEX0_STN1_RX_DN<17>")
	)
	(segment
		(start 43.904408 -106.689906)
		(end 43.901106 -106.528362)
		(width 0.1651)
		(layer "In5.Cu")
		(net "P5E_PEX0_STN1_RX_DN<17>")
	)
	(segment
		(start 49.44491 -102.89413)
		(end 49.600612 -102.936802)
		(width 0.1651)
		(layer "In5.Cu")
		(net "P5E_PEX0_STN1_RX_DN<17>")
	)
	(segment
		(start 30.741112 -126.612142)
		(end 32.231584 -119.95023)
		(width 0.1651)
		(layer "In5.Cu")
		(net "P5E_PEX0_STN1_RX_DN<17>")
	)
	(segment
		(start 42.216578 -108.450126)
		(end 42.213276 -108.288582)
		(width 0.1651)
		(layer "In5.Cu")
		(net "P5E_PEX0_STN1_RX_DN<17>")
	)
	(segment
		(start 44.897548 -105.488994)
		(end 45.663866 -105.051606)
		(width 0.1651)
		(layer "In5.Cu")
		(net "P5E_PEX0_STN1_RX_DN<17>")
	)
	(segment
		(start 45.663866 -105.051606)
		(end 45.819822 -105.094278)
		(width 0.1651)
		(layer "In5.Cu")
		(net "P5E_PEX0_STN1_RX_DN<17>")
	)
	(segment
		(start 60.220098 -271.848072)
		(end 60.265818 -271.802352)
		(width 0.1143)
		(layer "In5.Cu")
		(net "P5E_PEX0_STN1_RX_DN<17>")
	)
	(segment
		(start 50.073814 -102.535228)
		(end 50.503836 -102.289864)
		(width 0.1651)
		(layer "In5.Cu")
		(net "P5E_PEX0_STN1_RX_DN<17>")
	)
	(segment
		(start 50.503836 -102.289864)
		(end 50.659792 -102.332536)
		(width 0.1651)
		(layer "In5.Cu")
		(net "P5E_PEX0_STN1_RX_DN<17>")
	)
	(segment
		(start 47.955962 -103.74376)
		(end 48.385984 -103.498396)
		(width 0.1651)
		(layer "In5.Cu")
		(net "P5E_PEX0_STN1_RX_DN<17>")
	)
	(segment
		(start 42.213276 -108.288582)
		(end 42.555922 -107.931204)
		(width 0.1651)
		(layer "In5.Cu")
		(net "P5E_PEX0_STN1_RX_DN<17>")
	)
	(segment
		(start 60.220098 -275.276056)
		(end 60.220098 -271.848072)
		(width 0.1143)
		(layer "In5.Cu")
		(net "P5E_PEX0_STN1_RX_DN<17>")
	)
	(segment
		(start 47.48276 -104.145334)
		(end 47.91329 -103.899716)
		(width 0.1651)
		(layer "In5.Cu")
		(net "P5E_PEX0_STN1_RX_DN<17>")
	)
	(segment
		(start 50.659792 -102.332536)
		(end 51.090322 -102.086918)
		(width 0.1651)
		(layer "In5.Cu")
		(net "P5E_PEX0_STN1_RX_DN<17>")
	)
	(segment
		(start 50.031142 -102.691184)
		(end 50.073814 -102.535228)
		(width 0.1651)
		(layer "In5.Cu")
		(net "P5E_PEX0_STN1_RX_DN<17>")
	)
	(segment
		(start 51.090322 -102.086918)
		(end 51.132994 -101.930962)
		(width 0.1651)
		(layer "In5.Cu")
		(net "P5E_PEX0_STN1_RX_DN<17>")
	)
	(segment
		(start 48.541686 -103.541068)
		(end 48.972216 -103.29545)
		(width 0.1651)
		(layer "In5.Cu")
		(net "P5E_PEX0_STN1_RX_DN<17>")
	)
	(segment
		(start 60.265818 -271.773904)
		(end 60.265818 -269.900654)
		(width 0.1651)
		(layer "In5.Cu")
		(net "P5E_PEX0_STN1_RX_DN<17>")
	)
	(segment
		(start 47.326804 -104.102662)
		(end 47.48276 -104.145334)
		(width 0.1651)
		(layer "In5.Cu")
		(net "P5E_PEX0_STN1_RX_DN<17>")
	)
	(segment
		(start 60.485274 -275.379434)
		(end 60.323476 -275.379434)
		(width 0.1143)
		(layer "In5.Cu")
		(net "P5E_PEX0_STN1_RX_DN<17>")
	)
	(segment
		(start 41.873678 -108.808012)
		(end 42.216578 -108.450126)
		(width 0.1651)
		(layer "In5.Cu")
		(net "P5E_PEX0_STN1_RX_DN<17>")
	)
	(segment
		(start 49.014888 -103.139494)
		(end 49.44491 -102.89413)
		(width 0.1651)
		(layer "In5.Cu")
		(net "P5E_PEX0_STN1_RX_DN<17>")
	)
	(segment
		(start 48.972216 -103.29545)
		(end 49.014888 -103.139494)
		(width 0.1651)
		(layer "In5.Cu")
		(net "P5E_PEX0_STN1_RX_DN<17>")
	)
	(segment
		(start 48.385984 -103.498396)
		(end 48.541686 -103.541068)
		(width 0.1651)
		(layer "In5.Cu")
		(net "P5E_PEX0_STN1_RX_DN<17>")
	)
	(segment
		(start 43.060366 -107.570016)
		(end 43.057064 -107.408472)
		(width 0.1651)
		(layer "In5.Cu")
		(net "P5E_PEX0_STN1_RX_DN<17>")
	)
	(segment
		(start 60.265818 -269.900654)
		(end 31.075122 -165.351968)
		(width 0.1651)
		(layer "In5.Cu")
		(net "P5E_PEX0_STN1_RX_DN<17>")
	)
	(segment
		(start 33.566862 -117.307614)
		(end 41.712134 -108.811314)
		(width 0.1651)
		(layer "In5.Cu")
		(net "P5E_PEX0_STN1_RX_DN<17>")
	)
	(segment
		(start 41.712134 -108.811314)
		(end 41.873678 -108.808012)
		(width 0.1651)
		(layer "In5.Cu")
		(net "P5E_PEX0_STN1_RX_DN<17>")
	)
	(segment
		(start 51.132994 -101.930962)
		(end 51.563016 -101.685598)
		(width 0.1651)
		(layer "In5.Cu")
		(net "P5E_PEX0_STN1_RX_DN<17>")
	)
	(segment
		(start 242.385596 -32.589978)
		(end 242.218718 -32.4231)
		(width 0.13462)
		(layer "F.Cu")
		(net "P5E_PEX2_STN2_RX_DP<46>")
	)
	(segment
		(start 241.563906 -32.4231)
		(end 241.264694 -32.722312)
		(width 0.13462)
		(layer "F.Cu")
		(net "P5E_PEX2_STN2_RX_DP<46>")
	)
	(segment
		(start 242.218718 -32.4231)
		(end 241.563906 -32.4231)
		(width 0.13462)
		(layer "F.Cu")
		(net "P5E_PEX2_STN2_RX_DP<46>")
	)
	(segment
		(start 242.864894 -32.589978)
		(end 242.385596 -32.589978)
		(width 0.13462)
		(layer "F.Cu")
		(net "P5E_PEX2_STN2_RX_DP<46>")
	)
	(segment
		(start 241.264694 -32.722312)
		(end 241.555524 -32.431482)
		(width 0.1651)
		(layer "In7.Cu")
		(net "P5E_PEX2_STN2_RX_DP<46>")
	)
	(segment
		(start 242.236244 -34.231834)
		(end 242.336066 -34.334958)
		(width 0.1651)
		(layer "In7.Cu")
		(net "P5E_PEX2_STN2_RX_DP<46>")
	)
	(segment
		(start 243.111528 -85.491066)
		(end 248.311416 -102.64521)
		(width 0.1651)
		(layer "In7.Cu")
		(net "P5E_PEX2_STN2_RX_DP<46>")
	)
	(segment
		(start 277.485602 -275.570188)
		(end 277.599902 -275.684488)
		(width 0.1143)
		(layer "In7.Cu")
		(net "P5E_PEX2_STN2_RX_DP<46>")
	)
	(segment
		(start 243.30406 -60.306966)
		(end 243.30406 -61.823346)
		(width 0.1651)
		(layer "In7.Cu")
		(net "P5E_PEX2_STN2_RX_DP<46>")
	)
	(segment
		(start 276.983698 -271.392904)
		(end 276.983698 -271.421352)
		(width 0.1143)
		(layer "In7.Cu")
		(net "P5E_PEX2_STN2_RX_DP<46>")
	)
	(segment
		(start 276.008338 -263.536684)
		(end 276.983698 -270.404336)
		(width 0.1651)
		(layer "In7.Cu")
		(net "P5E_PEX2_STN2_RX_DP<46>")
	)
	(segment
		(start 248.311416 -102.64521)
		(end 248.311416 -102.645718)
		(width 0.1651)
		(layer "In7.Cu")
		(net "P5E_PEX2_STN2_RX_DP<46>")
	)
	(segment
		(start 274.49653 -238.34217)
		(end 274.893278 -242.68049)
		(width 0.1651)
		(layer "In7.Cu")
		(net "P5E_PEX2_STN2_RX_DP<46>")
	)
	(segment
		(start 241.801396 -37.832538)
		(end 241.83848 -40.16883)
		(width 0.1651)
		(layer "In7.Cu")
		(net "P5E_PEX2_STN2_RX_DP<46>")
	)
	(segment
		(start 274.893278 -242.68049)
		(end 274.893532 -242.68049)
		(width 0.1651)
		(layer "In7.Cu")
		(net "P5E_PEX2_STN2_RX_DP<46>")
	)
	(segment
		(start 248.323354 -102.685088)
		(end 248.323608 -102.68585)
		(width 0.1651)
		(layer "In7.Cu")
		(net "P5E_PEX2_STN2_RX_DP<46>")
	)
	(segment
		(start 243.023644 -57.21223)
		(end 243.30406 -60.306966)
		(width 0.1651)
		(layer "In7.Cu")
		(net "P5E_PEX2_STN2_RX_DP<46>")
	)
	(segment
		(start 241.83848 -40.16883)
		(end 243.139468 -49.798986)
		(width 0.1651)
		(layer "In7.Cu")
		(net "P5E_PEX2_STN2_RX_DP<46>")
	)
	(segment
		(start 241.555524 -32.431482)
		(end 242.013232 -32.431482)
		(width 0.1651)
		(layer "In7.Cu")
		(net "P5E_PEX2_STN2_RX_DP<46>")
	)
	(segment
		(start 248.323608 -102.68585)
		(end 253.515876 -119.815864)
		(width 0.1651)
		(layer "In7.Cu")
		(net "P5E_PEX2_STN2_RX_DP<46>")
	)
	(segment
		(start 242.336066 -34.334958)
		(end 242.325652 -35.019996)
		(width 0.1651)
		(layer "In7.Cu")
		(net "P5E_PEX2_STN2_RX_DP<46>")
	)
	(segment
		(start 242.013232 -36.140898)
		(end 242.094512 -36.259516)
		(width 0.1651)
		(layer "In7.Cu")
		(net "P5E_PEX2_STN2_RX_DP<46>")
	)
	(segment
		(start 248.311416 -102.645718)
		(end 248.323354 -102.685088)
		(width 0.1651)
		(layer "In7.Cu")
		(net "P5E_PEX2_STN2_RX_DP<46>")
	)
	(segment
		(start 242.347242 -33.636458)
		(end 242.243864 -33.73628)
		(width 0.1651)
		(layer "In7.Cu")
		(net "P5E_PEX2_STN2_RX_DP<46>")
	)
	(segment
		(start 277.029418 -275.354796)
		(end 277.24481 -275.570188)
		(width 0.1143)
		(layer "In7.Cu")
		(net "P5E_PEX2_STN2_RX_DP<46>")
	)
	(segment
		(start 276.0853 -255.697482)
		(end 276.008338 -263.536684)
		(width 0.1651)
		(layer "In7.Cu")
		(net "P5E_PEX2_STN2_RX_DP<46>")
	)
	(segment
		(start 253.515876 -119.815864)
		(end 256.789174 -144.702276)
		(width 0.1651)
		(layer "In7.Cu")
		(net "P5E_PEX2_STN2_RX_DP<46>")
	)
	(segment
		(start 242.325652 -35.019996)
		(end 242.222782 -35.572446)
		(width 0.1651)
		(layer "In7.Cu")
		(net "P5E_PEX2_STN2_RX_DP<46>")
	)
	(segment
		(start 276.983698 -270.404336)
		(end 276.983698 -271.392904)
		(width 0.1651)
		(layer "In7.Cu")
		(net "P5E_PEX2_STN2_RX_DP<46>")
	)
	(segment
		(start 277.24481 -275.570188)
		(end 277.485602 -275.570188)
		(width 0.1143)
		(layer "In7.Cu")
		(net "P5E_PEX2_STN2_RX_DP<46>")
	)
	(segment
		(start 242.013232 -32.431482)
		(end 242.36045 -32.7787)
		(width 0.1651)
		(layer "In7.Cu")
		(net "P5E_PEX2_STN2_RX_DP<46>")
	)
	(segment
		(start 243.139468 -49.798986)
		(end 243.023644 -57.21223)
		(width 0.1651)
		(layer "In7.Cu")
		(net "P5E_PEX2_STN2_RX_DP<46>")
	)
	(segment
		(start 276.983698 -271.421352)
		(end 277.029418 -271.467072)
		(width 0.1143)
		(layer "In7.Cu")
		(net "P5E_PEX2_STN2_RX_DP<46>")
	)
	(segment
		(start 242.222782 -35.572446)
		(end 242.10391 -35.653726)
		(width 0.1651)
		(layer "In7.Cu")
		(net "P5E_PEX2_STN2_RX_DP<46>")
	)
	(segment
		(start 274.893532 -242.68049)
		(end 276.0853 -255.697482)
		(width 0.1651)
		(layer "In7.Cu")
		(net "P5E_PEX2_STN2_RX_DP<46>")
	)
	(segment
		(start 243.30406 -61.823346)
		(end 243.111528 -85.491066)
		(width 0.1651)
		(layer "In7.Cu")
		(net "P5E_PEX2_STN2_RX_DP<46>")
	)
	(segment
		(start 242.36045 -32.7787)
		(end 242.347242 -33.636458)
		(width 0.1651)
		(layer "In7.Cu")
		(net "P5E_PEX2_STN2_RX_DP<46>")
	)
	(segment
		(start 242.094512 -36.259516)
		(end 241.801396 -37.832538)
		(width 0.1651)
		(layer "In7.Cu")
		(net "P5E_PEX2_STN2_RX_DP<46>")
	)
	(segment
		(start 277.029418 -271.467072)
		(end 277.029418 -275.354796)
		(width 0.1143)
		(layer "In7.Cu")
		(net "P5E_PEX2_STN2_RX_DP<46>")
	)
	(segment
		(start 256.789174 -144.702276)
		(end 274.49653 -238.34217)
		(width 0.1651)
		(layer "In7.Cu")
		(net "P5E_PEX2_STN2_RX_DP<46>")
	)
	(segment
		(start 242.10391 -35.653726)
		(end 242.013232 -36.140898)
		(width 0.1651)
		(layer "In7.Cu")
		(net "P5E_PEX2_STN2_RX_DP<46>")
	)
	(segment
		(start 242.243864 -33.73628)
		(end 242.236244 -34.231834)
		(width 0.1651)
		(layer "In7.Cu")
		(net "P5E_PEX2_STN2_RX_DP<46>")
	)
	(segment
		(start 277.599902 -275.684488)
		(end 277.599902 -275.949918)
		(width 0.1143)
		(layer "In7.Cu")
		(net "P5E_PEX2_STN2_RX_DP<46>")
	)
	(segment
		(start 390.411208 -344.538554)
		(end 390.411208 -345.171014)
		(width 0.13462)
		(layer "F.Cu")
		(net "P5E_PEX3_STN5_TX_C_DN<88>")
	)
	(segment
		(start 390.411208 -345.171014)
		(end 390.70534 -345.465146)
		(width 0.13462)
		(layer "F.Cu")
		(net "P5E_PEX3_STN5_TX_C_DN<88>")
	)
	(segment
		(start 390.73074 -344.219022)
		(end 390.411208 -344.538554)
		(width 0.13462)
		(layer "F.Cu")
		(net "P5E_PEX3_STN5_TX_C_DN<88>")
	)
	(segment
		(start 376.61596 -369.829588)
		(end 377.369578 -368.257836)
		(width 0.1651)
		(layer "In13.Cu")
		(net "P5E_PEX3_STN5_TX_C_DN<88>")
	)
	(segment
		(start 388.86003 -358.04094)
		(end 388.86003 -347.881194)
		(width 0.1651)
		(layer "In13.Cu")
		(net "P5E_PEX3_STN5_TX_C_DN<88>")
	)
	(segment
		(start 388.08914 -359.648506)
		(end 388.86003 -358.04094)
		(width 0.1651)
		(layer "In13.Cu")
		(net "P5E_PEX3_STN5_TX_C_DN<88>")
	)
	(segment
		(start 376.61596 -378.629164)
		(end 376.61596 -369.829588)
		(width 0.1651)
		(layer "In13.Cu")
		(net "P5E_PEX3_STN5_TX_C_DN<88>")
	)
	(segment
		(start 376.164094 -379.08103)
		(end 376.61596 -378.629164)
		(width 0.1651)
		(layer "In13.Cu")
		(net "P5E_PEX3_STN5_TX_C_DN<88>")
	)
	(segment
		(start 388.86003 -347.881194)
		(end 390.41451 -346.326714)
		(width 0.1651)
		(layer "In13.Cu")
		(net "P5E_PEX3_STN5_TX_C_DN<88>")
	)
	(segment
		(start 375.489978 -379.20803)
		(end 375.616978 -379.08103)
		(width 0.1651)
		(layer "In13.Cu")
		(net "P5E_PEX3_STN5_TX_C_DN<88>")
	)
	(segment
		(start 375.616978 -379.08103)
		(end 376.164094 -379.08103)
		(width 0.1651)
		(layer "In13.Cu")
		(net "P5E_PEX3_STN5_TX_C_DN<88>")
	)
	(segment
		(start 375.489978 -379.590046)
		(end 375.489978 -379.20803)
		(width 0.1651)
		(layer "In13.Cu")
		(net "P5E_PEX3_STN5_TX_C_DN<88>")
	)
	(segment
		(start 390.41451 -345.755976)
		(end 390.70534 -345.465146)
		(width 0.1651)
		(layer "In13.Cu")
		(net "P5E_PEX3_STN5_TX_C_DN<88>")
	)
	(segment
		(start 377.369578 -368.257836)
		(end 388.08914 -359.648506)
		(width 0.1651)
		(layer "In13.Cu")
		(net "P5E_PEX3_STN5_TX_C_DN<88>")
	)
	(segment
		(start 390.41451 -346.326714)
		(end 390.41451 -345.755976)
		(width 0.1651)
		(layer "In13.Cu")
		(net "P5E_PEX3_STN5_TX_C_DN<88>")
	)
	(segment
		(start 61.42355 -96.702372)
		(end 59.395106 -96.702372)
		(width 0.13208)
		(layer "F.Cu")
		(net "RST_NIC1_PERST2_R_N")
	)
	(segment
		(start 67.706748 -97.039938)
		(end 67.369182 -96.702372)
		(width 0.13208)
		(layer "F.Cu")
		(net "RST_NIC1_PERST2_R_N")
	)
	(segment
		(start 68.65747 -97.039938)
		(end 67.706748 -97.039938)
		(width 0.13208)
		(layer "F.Cu")
		(net "RST_NIC1_PERST2_R_N")
	)
	(segment
		(start 67.369182 -96.702372)
		(end 61.42355 -96.702372)
		(width 0.13208)
		(layer "F.Cu")
		(net "RST_NIC1_PERST2_R_N")
	)
	(via
		(at 61.42355 -96.702372)
		(size 0.762)
		(drill 0.381)
		(layers "F.Cu" "B.Cu")
		(net "RST_NIC1_PERST2_R_N")
	)
	(segment
		(start 50.64252 -100.045012)
		(end 51.130454 -100.045012)
		(width 0.13462)
		(layer "F.Cu")
		(net "P5E_PEX0_STN1_RX_DN<16>")
	)
	(segment
		(start 53.801772 -99.882198)
		(end 53.80228 -99.88169)
		(width 0.13462)
		(layer "F.Cu")
		(net "P5E_PEX0_STN1_RX_DN<16>")
	)
	(segment
		(start 51.130454 -100.045012)
		(end 51.293268 -99.882198)
		(width 0.13462)
		(layer "F.Cu")
		(net "P5E_PEX0_STN1_RX_DN<16>")
	)
	(segment
		(start 51.293268 -99.882198)
		(end 53.801772 -99.882198)
		(width 0.13462)
		(layer "F.Cu")
		(net "P5E_PEX0_STN1_RX_DN<16>")
	)
	(segment
		(start 53.80228 -99.88169)
		(end 54.09692 -100.17633)
		(width 0.13462)
		(layer "F.Cu")
		(net "P5E_PEX0_STN1_RX_DN<16>")
	)
	(segment
		(start 50.797206 -100.466144)
		(end 50.746152 -100.61956)
		(width 0.1651)
		(layer "In5.Cu")
		(net "P5E_PEX0_STN1_RX_DN<16>")
	)
	(segment
		(start 43.932094 -104.37622)
		(end 43.771566 -104.357932)
		(width 0.1651)
		(layer "In5.Cu")
		(net "P5E_PEX0_STN1_RX_DN<16>")
	)
	(segment
		(start 49.655476 -101.164898)
		(end 49.212246 -101.38664)
		(width 0.1651)
		(layer "In5.Cu")
		(net "P5E_PEX0_STN1_RX_DN<16>")
	)
	(segment
		(start 50.302922 -100.841302)
		(end 50.149506 -100.790248)
		(width 0.1651)
		(layer "In5.Cu")
		(net "P5E_PEX0_STN1_RX_DN<16>")
	)
	(segment
		(start 29.678122 -126.400306)
		(end 28.29687 -149.9362)
		(width 0.1651)
		(layer "In5.Cu")
		(net "P5E_PEX0_STN1_RX_DN<16>")
	)
	(segment
		(start 47.968154 -101.880924)
		(end 47.525178 -102.102158)
		(width 0.1651)
		(layer "In5.Cu")
		(net "P5E_PEX0_STN1_RX_DN<16>")
	)
	(segment
		(start 49.212246 -101.38664)
		(end 49.05883 -101.335586)
		(width 0.1651)
		(layer "In5.Cu")
		(net "P5E_PEX0_STN1_RX_DN<16>")
	)
	(segment
		(start 59.315858 -271.7546)
		(end 59.270138 -271.80032)
		(width 0.1143)
		(layer "In5.Cu")
		(net "P5E_PEX0_STN1_RX_DN<16>")
	)
	(segment
		(start 34.455862 -110.87989)
		(end 34.069274 -111.275876)
		(width 0.1651)
		(layer "In5.Cu")
		(net "P5E_PEX0_STN1_RX_DN<16>")
	)
	(segment
		(start 47.474124 -102.255574)
		(end 47.030894 -102.477316)
		(width 0.1651)
		(layer "In5.Cu")
		(net "P5E_PEX0_STN1_RX_DN<16>")
	)
	(segment
		(start 46.877478 -102.426262)
		(end 46.434502 -102.647496)
		(width 0.1651)
		(layer "In5.Cu")
		(net "P5E_PEX0_STN1_RX_DN<16>")
	)
	(segment
		(start 59.270138 -271.80032)
		(end 59.270138 -273.375882)
		(width 0.1143)
		(layer "In5.Cu")
		(net "P5E_PEX0_STN1_RX_DN<16>")
	)
	(segment
		(start 31.292546 -119.720106)
		(end 29.678122 -126.400306)
		(width 0.1651)
		(layer "In5.Cu")
		(net "P5E_PEX0_STN1_RX_DN<16>")
	)
	(segment
		(start 46.434502 -102.647496)
		(end 46.383448 -102.800912)
		(width 0.1651)
		(layer "In5.Cu")
		(net "P5E_PEX0_STN1_RX_DN<16>")
	)
	(segment
		(start 42.410634 -105.584752)
		(end 42.022522 -105.893108)
		(width 0.1651)
		(layer "In5.Cu")
		(net "P5E_PEX0_STN1_RX_DN<16>")
	)
	(segment
		(start 44.320206 -104.068118)
		(end 43.932094 -104.37622)
		(width 0.1651)
		(layer "In5.Cu")
		(net "P5E_PEX0_STN1_RX_DN<16>")
	)
	(segment
		(start 28.29687 -149.9362)
		(end 28.968954 -159.535368)
		(width 0.1651)
		(layer "In5.Cu")
		(net "P5E_PEX0_STN1_RX_DN<16>")
	)
	(segment
		(start 41.861994 -105.87482)
		(end 39.198296 -107.989878)
		(width 0.1651)
		(layer "In5.Cu")
		(net "P5E_PEX0_STN1_RX_DN<16>")
	)
	(segment
		(start 59.373516 -273.47926)
		(end 59.535314 -273.47926)
		(width 0.1143)
		(layer "In5.Cu")
		(net "P5E_PEX0_STN1_RX_DN<16>")
	)
	(segment
		(start 50.149506 -100.790248)
		(end 49.70653 -101.011482)
		(width 0.1651)
		(layer "In5.Cu")
		(net "P5E_PEX0_STN1_RX_DN<16>")
	)
	(segment
		(start 36.08578 -110.21695)
		(end 34.455862 -110.87989)
		(width 0.1651)
		(layer "In5.Cu")
		(net "P5E_PEX0_STN1_RX_DN<16>")
	)
	(segment
		(start 45.940218 -103.022654)
		(end 45.786802 -102.9716)
		(width 0.1651)
		(layer "In5.Cu")
		(net "P5E_PEX0_STN1_RX_DN<16>")
	)
	(segment
		(start 50.746152 -100.61956)
		(end 50.302922 -100.841302)
		(width 0.1651)
		(layer "In5.Cu")
		(net "P5E_PEX0_STN1_RX_DN<16>")
	)
	(segment
		(start 44.338748 -103.907336)
		(end 44.320206 -104.068118)
		(width 0.1651)
		(layer "In5.Cu")
		(net "P5E_PEX0_STN1_RX_DN<16>")
	)
	(segment
		(start 53.80609 -99.8855)
		(end 51.958748 -99.8855)
		(width 0.1651)
		(layer "In5.Cu")
		(net "P5E_PEX0_STN1_RX_DN<16>")
	)
	(segment
		(start 42.977308 -105.134664)
		(end 42.81678 -105.116376)
		(width 0.1651)
		(layer "In5.Cu")
		(net "P5E_PEX0_STN1_RX_DN<16>")
	)
	(segment
		(start 59.649614 -273.36496)
		(end 59.649614 -273.09953)
		(width 0.1143)
		(layer "In5.Cu")
		(net "P5E_PEX0_STN1_RX_DN<16>")
	)
	(segment
		(start 30.219142 -166.005764)
		(end 59.315858 -270.066262)
		(width 0.1651)
		(layer "In5.Cu")
		(net "P5E_PEX0_STN1_RX_DN<16>")
	)
	(segment
		(start 42.428922 -105.424224)
		(end 42.410634 -105.584752)
		(width 0.1651)
		(layer "In5.Cu")
		(net "P5E_PEX0_STN1_RX_DN<16>")
	)
	(segment
		(start 48.5648 -101.710236)
		(end 48.12157 -101.931978)
		(width 0.1651)
		(layer "In5.Cu")
		(net "P5E_PEX0_STN1_RX_DN<16>")
	)
	(segment
		(start 48.615854 -101.55682)
		(end 48.5648 -101.710236)
		(width 0.1651)
		(layer "In5.Cu")
		(net "P5E_PEX0_STN1_RX_DN<16>")
	)
	(segment
		(start 51.958748 -99.8855)
		(end 50.797206 -100.466144)
		(width 0.1651)
		(layer "In5.Cu")
		(net "P5E_PEX0_STN1_RX_DN<16>")
	)
	(segment
		(start 47.525178 -102.102158)
		(end 47.474124 -102.255574)
		(width 0.1651)
		(layer "In5.Cu")
		(net "P5E_PEX0_STN1_RX_DN<16>")
	)
	(segment
		(start 34.069274 -111.275876)
		(end 31.292546 -119.720106)
		(width 0.1651)
		(layer "In5.Cu")
		(net "P5E_PEX0_STN1_RX_DN<16>")
	)
	(segment
		(start 59.535314 -273.47926)
		(end 59.649614 -273.36496)
		(width 0.1143)
		(layer "In5.Cu")
		(net "P5E_PEX0_STN1_RX_DN<16>")
	)
	(segment
		(start 45.786802 -102.9716)
		(end 45.059346 -103.335074)
		(width 0.1651)
		(layer "In5.Cu")
		(net "P5E_PEX0_STN1_RX_DN<16>")
	)
	(segment
		(start 42.022522 -105.893108)
		(end 41.861994 -105.87482)
		(width 0.1651)
		(layer "In5.Cu")
		(net "P5E_PEX0_STN1_RX_DN<16>")
	)
	(segment
		(start 39.198296 -107.989878)
		(end 36.76269 -109.605572)
		(width 0.1651)
		(layer "In5.Cu")
		(net "P5E_PEX0_STN1_RX_DN<16>")
	)
	(segment
		(start 54.09692 -100.17633)
		(end 53.80609 -99.8855)
		(width 0.1651)
		(layer "In5.Cu")
		(net "P5E_PEX0_STN1_RX_DN<16>")
	)
	(segment
		(start 48.12157 -101.931978)
		(end 47.968154 -101.880924)
		(width 0.1651)
		(layer "In5.Cu")
		(net "P5E_PEX0_STN1_RX_DN<16>")
	)
	(segment
		(start 59.315858 -270.066262)
		(end 59.315858 -271.726152)
		(width 0.1651)
		(layer "In5.Cu")
		(net "P5E_PEX0_STN1_RX_DN<16>")
	)
	(segment
		(start 43.771566 -104.357932)
		(end 43.383962 -104.66578)
		(width 0.1651)
		(layer "In5.Cu")
		(net "P5E_PEX0_STN1_RX_DN<16>")
	)
	(segment
		(start 59.315858 -271.726152)
		(end 59.315858 -271.7546)
		(width 0.1143)
		(layer "In5.Cu")
		(net "P5E_PEX0_STN1_RX_DN<16>")
	)
	(segment
		(start 28.968954 -159.535368)
		(end 30.219142 -166.005764)
		(width 0.1651)
		(layer "In5.Cu")
		(net "P5E_PEX0_STN1_RX_DN<16>")
	)
	(segment
		(start 45.059346 -103.335074)
		(end 44.338748 -103.907336)
		(width 0.1651)
		(layer "In5.Cu")
		(net "P5E_PEX0_STN1_RX_DN<16>")
	)
	(segment
		(start 59.270138 -273.375882)
		(end 59.373516 -273.47926)
		(width 0.1143)
		(layer "In5.Cu")
		(net "P5E_PEX0_STN1_RX_DN<16>")
	)
	(segment
		(start 46.383448 -102.800912)
		(end 45.940218 -103.022654)
		(width 0.1651)
		(layer "In5.Cu")
		(net "P5E_PEX0_STN1_RX_DN<16>")
	)
	(segment
		(start 43.36542 -104.826562)
		(end 42.977308 -105.134664)
		(width 0.1651)
		(layer "In5.Cu")
		(net "P5E_PEX0_STN1_RX_DN<16>")
	)
	(segment
		(start 36.76269 -109.605572)
		(end 36.08578 -110.21695)
		(width 0.1651)
		(layer "In5.Cu")
		(net "P5E_PEX0_STN1_RX_DN<16>")
	)
	(segment
		(start 43.383962 -104.66578)
		(end 43.36542 -104.826562)
		(width 0.1651)
		(layer "In5.Cu")
		(net "P5E_PEX0_STN1_RX_DN<16>")
	)
	(segment
		(start 49.70653 -101.011482)
		(end 49.655476 -101.164898)
		(width 0.1651)
		(layer "In5.Cu")
		(net "P5E_PEX0_STN1_RX_DN<16>")
	)
	(segment
		(start 49.05883 -101.335586)
		(end 48.615854 -101.55682)
		(width 0.1651)
		(layer "In5.Cu")
		(net "P5E_PEX0_STN1_RX_DN<16>")
	)
	(segment
		(start 42.81678 -105.116376)
		(end 42.428922 -105.424224)
		(width 0.1651)
		(layer "In5.Cu")
		(net "P5E_PEX0_STN1_RX_DN<16>")
	)
	(segment
		(start 47.030894 -102.477316)
		(end 46.877478 -102.426262)
		(width 0.1651)
		(layer "In5.Cu")
		(net "P5E_PEX0_STN1_RX_DN<16>")
	)
	(segment
		(start 268.224508 -28.829)
		(end 267.558012 -28.829)
		(width 0.13462)
		(layer "F.Cu")
		(net "P5E_PEX2_STN2_RX_DP<40>")
	)
	(segment
		(start 268.864842 -28.99029)
		(end 268.385798 -28.99029)
		(width 0.13462)
		(layer "F.Cu")
		(net "P5E_PEX2_STN2_RX_DP<40>")
	)
	(segment
		(start 267.558012 -28.829)
		(end 267.264642 -29.12237)
		(width 0.13462)
		(layer "F.Cu")
		(net "P5E_PEX2_STN2_RX_DP<40>")
	)
	(segment
		(start 268.864842 -28.990036)
		(end 268.864842 -28.99029)
		(width 0.13462)
		(layer "F.Cu")
		(net "P5E_PEX2_STN2_RX_DP<40>")
	)
	(segment
		(start 268.385798 -28.99029)
		(end 268.224508 -28.829)
		(width 0.13462)
		(layer "F.Cu")
		(net "P5E_PEX2_STN2_RX_DP<40>")
	)
	(segment
		(start 271.386554 -65.14846)
		(end 274.530312 -104.315514)
		(width 0.1651)
		(layer "In7.Cu")
		(net "P5E_PEX2_STN2_RX_DP<40>")
	)
	(segment
		(start 282.683712 -271.392904)
		(end 282.683712 -271.421352)
		(width 0.1143)
		(layer "In7.Cu")
		(net "P5E_PEX2_STN2_RX_DP<40>")
	)
	(segment
		(start 283.185616 -275.570188)
		(end 283.299916 -275.684488)
		(width 0.1143)
		(layer "In7.Cu")
		(net "P5E_PEX2_STN2_RX_DP<40>")
	)
	(segment
		(start 282.361894 -264.871962)
		(end 282.683712 -268.137132)
		(width 0.1651)
		(layer "In7.Cu")
		(net "P5E_PEX2_STN2_RX_DP<40>")
	)
	(segment
		(start 269.448026 -30.536388)
		(end 269.798546 -30.886908)
		(width 0.1651)
		(layer "In7.Cu")
		(net "P5E_PEX2_STN2_RX_DP<40>")
	)
	(segment
		(start 269.448026 -30.392624)
		(end 269.448026 -30.536388)
		(width 0.1651)
		(layer "In7.Cu")
		(net "P5E_PEX2_STN2_RX_DP<40>")
	)
	(segment
		(start 269.798546 -30.886908)
		(end 269.94231 -30.886908)
		(width 0.1651)
		(layer "In7.Cu")
		(net "P5E_PEX2_STN2_RX_DP<40>")
	)
	(segment
		(start 270.664178 -31.608776)
		(end 273.248374 -37.742622)
		(width 0.1651)
		(layer "In7.Cu")
		(net "P5E_PEX2_STN2_RX_DP<40>")
	)
	(segment
		(start 268.95425 -30.042612)
		(end 269.098014 -30.042612)
		(width 0.1651)
		(layer "In7.Cu")
		(net "P5E_PEX2_STN2_RX_DP<40>")
	)
	(segment
		(start 267.52296 -28.864052)
		(end 267.601446 -28.83154)
		(width 0.1651)
		(layer "In7.Cu")
		(net "P5E_PEX2_STN2_RX_DP<40>")
	)
	(segment
		(start 273.248374 -37.742622)
		(end 273.234912 -38.545262)
		(width 0.1651)
		(layer "In7.Cu")
		(net "P5E_PEX2_STN2_RX_DP<40>")
	)
	(segment
		(start 270.988282 -55.19547)
		(end 271.386554 -65.14846)
		(width 0.1651)
		(layer "In7.Cu")
		(net "P5E_PEX2_STN2_RX_DP<40>")
	)
	(segment
		(start 268.60373 -29.548328)
		(end 268.60373 -29.692092)
		(width 0.1651)
		(layer "In7.Cu")
		(net "P5E_PEX2_STN2_RX_DP<40>")
	)
	(segment
		(start 267.886942 -28.83154)
		(end 268.60373 -29.548328)
		(width 0.1651)
		(layer "In7.Cu")
		(net "P5E_PEX2_STN2_RX_DP<40>")
	)
	(segment
		(start 282.729432 -275.354796)
		(end 282.944824 -275.570188)
		(width 0.1143)
		(layer "In7.Cu")
		(net "P5E_PEX2_STN2_RX_DP<40>")
	)
	(segment
		(start 282.648406 -250.016518)
		(end 282.361894 -264.871962)
		(width 0.1651)
		(layer "In7.Cu")
		(net "P5E_PEX2_STN2_RX_DP<40>")
	)
	(segment
		(start 273.234912 -38.545262)
		(end 271.088104 -48.798226)
		(width 0.1651)
		(layer "In7.Cu")
		(net "P5E_PEX2_STN2_RX_DP<40>")
	)
	(segment
		(start 269.098014 -30.042612)
		(end 269.448026 -30.392624)
		(width 0.1651)
		(layer "In7.Cu")
		(net "P5E_PEX2_STN2_RX_DP<40>")
	)
	(segment
		(start 282.683712 -268.137132)
		(end 282.683712 -271.392904)
		(width 0.1651)
		(layer "In7.Cu")
		(net "P5E_PEX2_STN2_RX_DP<40>")
	)
	(segment
		(start 267.264642 -29.12237)
		(end 267.52296 -28.864052)
		(width 0.1651)
		(layer "In7.Cu")
		(net "P5E_PEX2_STN2_RX_DP<40>")
	)
	(segment
		(start 274.992592 -119.567198)
		(end 274.686776 -147.947888)
		(width 0.1651)
		(layer "In7.Cu")
		(net "P5E_PEX2_STN2_RX_DP<40>")
	)
	(segment
		(start 269.94231 -30.886908)
		(end 270.664178 -31.608776)
		(width 0.1651)
		(layer "In7.Cu")
		(net "P5E_PEX2_STN2_RX_DP<40>")
	)
	(segment
		(start 274.686776 -147.947888)
		(end 282.648406 -250.016518)
		(width 0.1651)
		(layer "In7.Cu")
		(net "P5E_PEX2_STN2_RX_DP<40>")
	)
	(segment
		(start 274.530312 -104.315514)
		(end 274.992592 -119.567198)
		(width 0.1651)
		(layer "In7.Cu")
		(net "P5E_PEX2_STN2_RX_DP<40>")
	)
	(segment
		(start 282.729432 -271.467072)
		(end 282.729432 -275.354796)
		(width 0.1143)
		(layer "In7.Cu")
		(net "P5E_PEX2_STN2_RX_DP<40>")
	)
	(segment
		(start 267.601446 -28.83154)
		(end 267.886942 -28.83154)
		(width 0.1651)
		(layer "In7.Cu")
		(net "P5E_PEX2_STN2_RX_DP<40>")
	)
	(segment
		(start 268.60373 -29.692092)
		(end 268.95425 -30.042612)
		(width 0.1651)
		(layer "In7.Cu")
		(net "P5E_PEX2_STN2_RX_DP<40>")
	)
	(segment
		(start 283.299916 -275.684488)
		(end 283.299916 -275.949918)
		(width 0.1143)
		(layer "In7.Cu")
		(net "P5E_PEX2_STN2_RX_DP<40>")
	)
	(segment
		(start 271.088104 -48.798226)
		(end 270.988282 -55.19547)
		(width 0.1651)
		(layer "In7.Cu")
		(net "P5E_PEX2_STN2_RX_DP<40>")
	)
	(segment
		(start 282.944824 -275.570188)
		(end 283.185616 -275.570188)
		(width 0.1143)
		(layer "In7.Cu")
		(net "P5E_PEX2_STN2_RX_DP<40>")
	)
	(segment
		(start 282.683712 -271.421352)
		(end 282.729432 -271.467072)
		(width 0.1143)
		(layer "In7.Cu")
		(net "P5E_PEX2_STN2_RX_DP<40>")
	)
	(segment
		(start 342.490044 -401.49018)
		(end 342.490044 -401.872196)
		(width 0.1651)
		(layer "In5.Cu")
		(net "P5E_PEX2_STN6_RX_DP<106>")
	)
	(segment
		(start 338.777834 -391.86231)
		(end 338.675218 -391.894822)
		(width 0.1651)
		(layer "In5.Cu")
		(net "P5E_PEX2_STN6_RX_DP<106>")
	)
	(segment
		(start 279.833832 -319.966848)
		(end 279.833832 -319.9384)
		(width 0.1143)
		(layer "In5.Cu")
		(net "P5E_PEX2_STN6_RX_DP<106>")
	)
	(segment
		(start 342.490044 -401.872196)
		(end 342.617044 -401.999196)
		(width 0.1651)
		(layer "In5.Cu")
		(net "P5E_PEX2_STN6_RX_DP<106>")
	)
	(segment
		(start 338.235544 -391.66546)
		(end 338.203286 -391.562844)
		(width 0.1651)
		(layer "In5.Cu")
		(net "P5E_PEX2_STN6_RX_DP<106>")
	)
	(segment
		(start 342.02624 -393.992354)
		(end 341.879682 -394.020802)
		(width 0.1651)
		(layer "In5.Cu")
		(net "P5E_PEX2_STN6_RX_DP<106>")
	)
	(segment
		(start 328.554842 -386.160518)
		(end 327.957434 -384.662172)
		(width 0.1651)
		(layer "In5.Cu")
		(net "P5E_PEX2_STN6_RX_DP<106>")
	)
	(segment
		(start 328.840846 -386.77088)
		(end 328.554842 -386.160518)
		(width 0.1651)
		(layer "In5.Cu")
		(net "P5E_PEX2_STN6_RX_DP<106>")
	)
	(segment
		(start 319.38849 -340.694772)
		(end 280.816558 -322.673218)
		(width 0.1651)
		(layer "In5.Cu")
		(net "P5E_PEX2_STN6_RX_DP<106>")
	)
	(segment
		(start 279.879552 -319.89268)
		(end 279.879552 -318.355472)
		(width 0.1143)
		(layer "In5.Cu")
		(net "P5E_PEX2_STN6_RX_DP<106>")
	)
	(segment
		(start 279.879552 -318.355472)
		(end 280.105358 -318.129666)
		(width 0.1143)
		(layer "In5.Cu")
		(net "P5E_PEX2_STN6_RX_DP<106>")
	)
	(segment
		(start 342.617044 -401.999196)
		(end 343.04732 -401.999196)
		(width 0.1651)
		(layer "In5.Cu")
		(net "P5E_PEX2_STN6_RX_DP<106>")
	)
	(segment
		(start 324.10527 -373.049546)
		(end 320.566034 -358.505506)
		(width 0.1651)
		(layer "In5.Cu")
		(net "P5E_PEX2_STN6_RX_DP<106>")
	)
	(segment
		(start 340.524846 -393.083288)
		(end 340.50097 -392.959844)
		(width 0.1651)
		(layer "In5.Cu")
		(net "P5E_PEX2_STN6_RX_DP<106>")
	)
	(segment
		(start 280.335482 -318.129666)
		(end 280.449782 -318.015366)
		(width 0.1143)
		(layer "In5.Cu")
		(net "P5E_PEX2_STN6_RX_DP<106>")
	)
	(segment
		(start 280.449782 -318.015366)
		(end 280.449782 -317.749936)
		(width 0.1143)
		(layer "In5.Cu")
		(net "P5E_PEX2_STN6_RX_DP<106>")
	)
	(segment
		(start 343.334086 -395.738858)
		(end 342.731598 -394.46962)
		(width 0.1651)
		(layer "In5.Cu")
		(net "P5E_PEX2_STN6_RX_DP<106>")
	)
	(segment
		(start 342.731598 -394.46962)
		(end 342.02624 -393.992354)
		(width 0.1651)
		(layer "In5.Cu")
		(net "P5E_PEX2_STN6_RX_DP<106>")
	)
	(segment
		(start 335.958942 -390.39292)
		(end 329.835002 -387.877304)
		(width 0.1651)
		(layer "In5.Cu")
		(net "P5E_PEX2_STN6_RX_DP<106>")
	)
	(segment
		(start 320.566034 -341.872316)
		(end 319.38849 -340.694772)
		(width 0.1651)
		(layer "In5.Cu")
		(net "P5E_PEX2_STN6_RX_DP<106>")
	)
	(segment
		(start 329.133454 -387.1849)
		(end 328.840846 -386.77088)
		(width 0.1651)
		(layer "In5.Cu")
		(net "P5E_PEX2_STN6_RX_DP<106>")
	)
	(segment
		(start 341.058754 -393.337542)
		(end 340.93531 -393.361164)
		(width 0.1651)
		(layer "In5.Cu")
		(net "P5E_PEX2_STN6_RX_DP<106>")
	)
	(segment
		(start 340.93531 -393.361164)
		(end 340.524846 -393.083288)
		(width 0.1651)
		(layer "In5.Cu")
		(net "P5E_PEX2_STN6_RX_DP<106>")
	)
	(segment
		(start 341.46871 -393.61491)
		(end 341.058754 -393.337542)
		(width 0.1651)
		(layer "In5.Cu")
		(net "P5E_PEX2_STN6_RX_DP<106>")
	)
	(segment
		(start 279.833832 -321.342512)
		(end 279.833832 -319.966848)
		(width 0.1651)
		(layer "In5.Cu")
		(net "P5E_PEX2_STN6_RX_DP<106>")
	)
	(segment
		(start 343.334086 -401.71243)
		(end 343.334086 -395.738858)
		(width 0.1651)
		(layer "In5.Cu")
		(net "P5E_PEX2_STN6_RX_DP<106>")
	)
	(segment
		(start 329.835002 -387.877304)
		(end 329.133454 -387.1849)
		(width 0.1651)
		(layer "In5.Cu")
		(net "P5E_PEX2_STN6_RX_DP<106>")
	)
	(segment
		(start 280.816558 -322.673218)
		(end 280.20772 -322.246244)
		(width 0.1651)
		(layer "In5.Cu")
		(net "P5E_PEX2_STN6_RX_DP<106>")
	)
	(segment
		(start 338.203286 -391.562844)
		(end 335.958942 -390.39292)
		(width 0.1651)
		(layer "In5.Cu")
		(net "P5E_PEX2_STN6_RX_DP<106>")
	)
	(segment
		(start 280.105358 -318.129666)
		(end 280.335482 -318.129666)
		(width 0.1143)
		(layer "In5.Cu")
		(net "P5E_PEX2_STN6_RX_DP<106>")
	)
	(segment
		(start 320.566034 -358.505506)
		(end 320.566034 -341.872316)
		(width 0.1651)
		(layer "In5.Cu")
		(net "P5E_PEX2_STN6_RX_DP<106>")
	)
	(segment
		(start 341.49665 -393.761468)
		(end 341.46871 -393.61491)
		(width 0.1651)
		(layer "In5.Cu")
		(net "P5E_PEX2_STN6_RX_DP<106>")
	)
	(segment
		(start 343.04732 -401.999196)
		(end 343.334086 -401.71243)
		(width 0.1651)
		(layer "In5.Cu")
		(net "P5E_PEX2_STN6_RX_DP<106>")
	)
	(segment
		(start 341.879682 -394.020802)
		(end 341.49665 -393.761468)
		(width 0.1651)
		(layer "In5.Cu")
		(net "P5E_PEX2_STN6_RX_DP<106>")
	)
	(segment
		(start 340.50097 -392.959844)
		(end 339.217 -392.091164)
		(width 0.1651)
		(layer "In5.Cu")
		(net "P5E_PEX2_STN6_RX_DP<106>")
	)
	(segment
		(start 279.833832 -319.9384)
		(end 279.879552 -319.89268)
		(width 0.1143)
		(layer "In5.Cu")
		(net "P5E_PEX2_STN6_RX_DP<106>")
	)
	(segment
		(start 338.675218 -391.894822)
		(end 338.235544 -391.66546)
		(width 0.1651)
		(layer "In5.Cu")
		(net "P5E_PEX2_STN6_RX_DP<106>")
	)
	(segment
		(start 280.20772 -322.246244)
		(end 279.833832 -321.342512)
		(width 0.1651)
		(layer "In5.Cu")
		(net "P5E_PEX2_STN6_RX_DP<106>")
	)
	(segment
		(start 339.217 -392.091164)
		(end 338.777834 -391.86231)
		(width 0.1651)
		(layer "In5.Cu")
		(net "P5E_PEX2_STN6_RX_DP<106>")
	)
	(segment
		(start 327.957434 -384.662172)
		(end 324.10527 -373.049546)
		(width 0.1651)
		(layer "In5.Cu")
		(net "P5E_PEX2_STN6_RX_DP<106>")
	)
	(segment
		(start 392.752326 -338.121498)
		(end 393.146788 -337.82127)
		(width 0.1651)
		(layer "In15.Cu")
		(net "P5E_PEX3_STN5_RX_DP<89>")
	)
	(segment
		(start 392.735562 -338.245958)
		(end 392.752326 -338.121498)
		(width 0.1651)
		(layer "In15.Cu")
		(net "P5E_PEX3_STN5_RX_DP<89>")
	)
	(segment
		(start 388.57809 -342.114886)
		(end 388.92099 -341.147146)
		(width 0.1651)
		(layer "In15.Cu")
		(net "P5E_PEX3_STN5_RX_DP<89>")
	)
	(segment
		(start 377.816872 -372.099078)
		(end 378.247148 -372.099078)
		(width 0.1651)
		(layer "In15.Cu")
		(net "P5E_PEX3_STN5_RX_DP<89>")
	)
	(segment
		(start 392.21664 -338.52866)
		(end 392.341354 -338.545678)
		(width 0.1651)
		(layer "In15.Cu")
		(net "P5E_PEX3_STN5_RX_DP<89>")
	)
	(segment
		(start 391.286746 -339.236304)
		(end 391.411206 -339.253068)
		(width 0.1651)
		(layer "In15.Cu")
		(net "P5E_PEX3_STN5_RX_DP<89>")
	)
	(segment
		(start 378.247148 -372.099078)
		(end 378.533914 -371.812312)
		(width 0.1651)
		(layer "In15.Cu")
		(net "P5E_PEX3_STN5_RX_DP<89>")
	)
	(segment
		(start 391.411206 -339.253068)
		(end 391.805414 -338.953348)
		(width 0.1651)
		(layer "In15.Cu")
		(net "P5E_PEX3_STN5_RX_DP<89>")
	)
	(segment
		(start 391.805414 -338.953348)
		(end 391.822178 -338.828888)
		(width 0.1651)
		(layer "In15.Cu")
		(net "P5E_PEX3_STN5_RX_DP<89>")
	)
	(segment
		(start 390.892284 -339.536278)
		(end 391.286746 -339.236304)
		(width 0.1651)
		(layer "In15.Cu")
		(net "P5E_PEX3_STN5_RX_DP<89>")
	)
	(segment
		(start 379.028452 -368.565684)
		(end 388.29361 -358.672384)
		(width 0.1651)
		(layer "In15.Cu")
		(net "P5E_PEX3_STN5_RX_DP<89>")
	)
	(segment
		(start 377.689872 -371.590062)
		(end 377.689872 -371.972078)
		(width 0.1651)
		(layer "In15.Cu")
		(net "P5E_PEX3_STN5_RX_DP<89>")
	)
	(segment
		(start 378.533914 -371.812312)
		(end 378.533914 -369.818412)
		(width 0.1651)
		(layer "In15.Cu")
		(net "P5E_PEX3_STN5_RX_DP<89>")
	)
	(segment
		(start 377.689872 -371.972078)
		(end 377.816872 -372.099078)
		(width 0.1651)
		(layer "In15.Cu")
		(net "P5E_PEX3_STN5_RX_DP<89>")
	)
	(segment
		(start 388.29361 -358.672384)
		(end 388.57809 -357.952802)
		(width 0.1651)
		(layer "In15.Cu")
		(net "P5E_PEX3_STN5_RX_DP<89>")
	)
	(segment
		(start 392.341354 -338.545678)
		(end 392.735562 -338.245958)
		(width 0.1651)
		(layer "In15.Cu")
		(net "P5E_PEX3_STN5_RX_DP<89>")
	)
	(segment
		(start 393.146788 -337.82127)
		(end 393.271502 -337.838288)
		(width 0.1651)
		(layer "In15.Cu")
		(net "P5E_PEX3_STN5_RX_DP<89>")
	)
	(segment
		(start 414.979612 -319.921128)
		(end 414.979612 -318.344804)
		(width 0.1143)
		(layer "In15.Cu")
		(net "P5E_PEX3_STN5_RX_DP<89>")
	)
	(segment
		(start 414.933892 -319.995296)
		(end 414.933892 -319.966848)
		(width 0.1143)
		(layer "In15.Cu")
		(net "P5E_PEX3_STN5_RX_DP<89>")
	)
	(segment
		(start 391.822178 -338.828888)
		(end 392.21664 -338.52866)
		(width 0.1651)
		(layer "In15.Cu")
		(net "P5E_PEX3_STN5_RX_DP<89>")
	)
	(segment
		(start 390.875266 -339.660738)
		(end 390.892284 -339.536278)
		(width 0.1651)
		(layer "In15.Cu")
		(net "P5E_PEX3_STN5_RX_DP<89>")
	)
	(segment
		(start 393.271502 -337.838288)
		(end 414.507172 -321.687444)
		(width 0.1651)
		(layer "In15.Cu")
		(net "P5E_PEX3_STN5_RX_DP<89>")
	)
	(segment
		(start 414.933892 -319.966848)
		(end 414.979612 -319.921128)
		(width 0.1143)
		(layer "In15.Cu")
		(net "P5E_PEX3_STN5_RX_DP<89>")
	)
	(segment
		(start 414.933892 -321.133978)
		(end 414.933892 -319.995296)
		(width 0.1651)
		(layer "In15.Cu")
		(net "P5E_PEX3_STN5_RX_DP<89>")
	)
	(segment
		(start 388.92099 -341.147146)
		(end 390.875266 -339.660738)
		(width 0.1651)
		(layer "In15.Cu")
		(net "P5E_PEX3_STN5_RX_DP<89>")
	)
	(segment
		(start 388.57809 -357.952802)
		(end 388.57809 -342.114886)
		(width 0.1651)
		(layer "In15.Cu")
		(net "P5E_PEX3_STN5_RX_DP<89>")
	)
	(segment
		(start 415.435542 -318.129666)
		(end 415.549842 -318.015366)
		(width 0.1143)
		(layer "In15.Cu")
		(net "P5E_PEX3_STN5_RX_DP<89>")
	)
	(segment
		(start 415.19475 -318.129666)
		(end 415.435542 -318.129666)
		(width 0.1143)
		(layer "In15.Cu")
		(net "P5E_PEX3_STN5_RX_DP<89>")
	)
	(segment
		(start 414.507172 -321.687444)
		(end 414.933892 -321.133978)
		(width 0.1651)
		(layer "In15.Cu")
		(net "P5E_PEX3_STN5_RX_DP<89>")
	)
	(segment
		(start 378.533914 -369.818412)
		(end 379.028452 -368.565684)
		(width 0.1651)
		(layer "In15.Cu")
		(net "P5E_PEX3_STN5_RX_DP<89>")
	)
	(segment
		(start 415.549842 -318.015366)
		(end 415.549842 -317.749936)
		(width 0.1143)
		(layer "In15.Cu")
		(net "P5E_PEX3_STN5_RX_DP<89>")
	)
	(segment
		(start 414.979612 -318.344804)
		(end 415.19475 -318.129666)
		(width 0.1143)
		(layer "In15.Cu")
		(net "P5E_PEX3_STN5_RX_DP<89>")
	)
	(segment
		(start 73.257664 -158.35503)
		(end 76.709524 -158.35503)
		(width 0.13208)
		(layer "F.Cu")
		(net "PRSNTB3_NIC1_N")
	)
	(segment
		(start 78.932024 -158.219648)
		(end 80.13954 -158.219648)
		(width 0.13208)
		(layer "F.Cu")
		(net "PRSNTB3_NIC1_N")
	)
	(segment
		(start 80.13954 -159.235648)
		(end 80.13954 -158.219648)
		(width 0.13208)
		(layer "F.Cu")
		(net "PRSNTB3_NIC1_N")
	)
	(segment
		(start 76.844906 -158.219648)
		(end 78.932024 -158.219648)
		(width 0.13208)
		(layer "F.Cu")
		(net "PRSNTB3_NIC1_N")
	)
	(segment
		(start 76.709524 -158.35503)
		(end 76.844906 -158.219648)
		(width 0.13208)
		(layer "F.Cu")
		(net "PRSNTB3_NIC1_N")
	)
	(via
		(at 78.932024 -158.219648)
		(size 0.762)
		(drill 0.381)
		(layers "F.Cu" "B.Cu")
		(net "PRSNTB3_NIC1_N")
	)
	(segment
		(start 46.042326 -124.755148)
		(end 45.554392 -124.755148)
		(width 0.13462)
		(layer "F.Cu")
		(net "P5E_PEX0_STN1_TX_C_DN<27>")
	)
	(segment
		(start 45.391578 -124.917962)
		(end 39.859712 -124.917962)
		(width 0.13462)
		(layer "F.Cu")
		(net "P5E_PEX0_STN1_TX_C_DN<27>")
	)
	(segment
		(start 45.554392 -124.755148)
		(end 45.391578 -124.917962)
		(width 0.13462)
		(layer "F.Cu")
		(net "P5E_PEX0_STN1_TX_C_DN<27>")
	)
	(segment
		(start 39.859712 -124.917962)
		(end 39.547292 -124.605542)
		(width 0.13462)
		(layer "F.Cu")
		(net "P5E_PEX0_STN1_TX_C_DN<27>")
	)
	(segment
		(start 320.224404 -30.353)
		(end 317.70447 -30.353)
		(width 0.13462)
		(layer "F.Cu")
		(net "P5E_PEX2_STN2_RX_DN<33>")
	)
	(segment
		(start 317.70447 -30.353)
		(end 317.410338 -30.058868)
		(width 0.13462)
		(layer "F.Cu")
		(net "P5E_PEX2_STN2_RX_DN<33>")
	)
	(segment
		(start 320.864738 -30.190186)
		(end 320.387218 -30.190186)
		(width 0.13462)
		(layer "F.Cu")
		(net "P5E_PEX2_STN2_RX_DN<33>")
	)
	(segment
		(start 320.387218 -30.190186)
		(end 320.224404 -30.353)
		(width 0.13462)
		(layer "F.Cu")
		(net "P5E_PEX2_STN2_RX_DN<33>")
	)
	(segment
		(start 309.518304 -154.698446)
		(end 289.953192 -267.040868)
		(width 0.1651)
		(layer "In7.Cu")
		(net "P5E_PEX2_STN2_RX_DN<33>")
	)
	(segment
		(start 322.222876 -61.072268)
		(end 311.214262 -116.557552)
		(width 0.1651)
		(layer "In7.Cu")
		(net "P5E_PEX2_STN2_RX_DN<33>")
	)
	(segment
		(start 289.721036 -273.479514)
		(end 289.83559 -273.479514)
		(width 0.1143)
		(layer "In7.Cu")
		(net "P5E_PEX2_STN2_RX_DN<33>")
	)
	(segment
		(start 321.507358 -32.239712)
		(end 321.793616 -33.002982)
		(width 0.1651)
		(layer "In7.Cu")
		(net "P5E_PEX2_STN2_RX_DN<33>")
	)
	(segment
		(start 289.57016 -271.41932)
		(end 289.57016 -273.328638)
		(width 0.1143)
		(layer "In7.Cu")
		(net "P5E_PEX2_STN2_RX_DN<33>")
	)
	(segment
		(start 320.290698 -30.349698)
		(end 321.507358 -32.239712)
		(width 0.1651)
		(layer "In7.Cu")
		(net "P5E_PEX2_STN2_RX_DN<33>")
	)
	(segment
		(start 289.61588 -270.929862)
		(end 289.61588 -271.345152)
		(width 0.1651)
		(layer "In7.Cu")
		(net "P5E_PEX2_STN2_RX_DN<33>")
	)
	(segment
		(start 321.089528 -39.636954)
		(end 322.405756 -49.3776)
		(width 0.1651)
		(layer "In7.Cu")
		(net "P5E_PEX2_STN2_RX_DN<33>")
	)
	(segment
		(start 321.793616 -33.002982)
		(end 321.78498 -34.102294)
		(width 0.1651)
		(layer "In7.Cu")
		(net "P5E_PEX2_STN2_RX_DN<33>")
	)
	(segment
		(start 289.61588 -271.345152)
		(end 289.61588 -271.3736)
		(width 0.1143)
		(layer "In7.Cu")
		(net "P5E_PEX2_STN2_RX_DN<33>")
	)
	(segment
		(start 311.214262 -116.557552)
		(end 310.89727 -143.990568)
		(width 0.1651)
		(layer "In7.Cu")
		(net "P5E_PEX2_STN2_RX_DN<33>")
	)
	(segment
		(start 289.953192 -267.040868)
		(end 289.61588 -270.929862)
		(width 0.1651)
		(layer "In7.Cu")
		(net "P5E_PEX2_STN2_RX_DN<33>")
	)
	(segment
		(start 289.94989 -273.365214)
		(end 289.94989 -273.099784)
		(width 0.1143)
		(layer "In7.Cu")
		(net "P5E_PEX2_STN2_RX_DN<33>")
	)
	(segment
		(start 310.89727 -143.990568)
		(end 309.518304 -154.698446)
		(width 0.1651)
		(layer "In7.Cu")
		(net "P5E_PEX2_STN2_RX_DN<33>")
	)
	(segment
		(start 317.701168 -30.349698)
		(end 320.290698 -30.349698)
		(width 0.1651)
		(layer "In7.Cu")
		(net "P5E_PEX2_STN2_RX_DN<33>")
	)
	(segment
		(start 321.78498 -34.102294)
		(end 321.065906 -38.15207)
		(width 0.1651)
		(layer "In7.Cu")
		(net "P5E_PEX2_STN2_RX_DN<33>")
	)
	(segment
		(start 317.410338 -30.058868)
		(end 317.701168 -30.349698)
		(width 0.1651)
		(layer "In7.Cu")
		(net "P5E_PEX2_STN2_RX_DN<33>")
	)
	(segment
		(start 321.065906 -38.15207)
		(end 321.089528 -39.636954)
		(width 0.1651)
		(layer "In7.Cu")
		(net "P5E_PEX2_STN2_RX_DN<33>")
	)
	(segment
		(start 289.61588 -271.3736)
		(end 289.57016 -271.41932)
		(width 0.1143)
		(layer "In7.Cu")
		(net "P5E_PEX2_STN2_RX_DN<33>")
	)
	(segment
		(start 289.57016 -273.328638)
		(end 289.721036 -273.479514)
		(width 0.1143)
		(layer "In7.Cu")
		(net "P5E_PEX2_STN2_RX_DN<33>")
	)
	(segment
		(start 322.405756 -49.3776)
		(end 322.222876 -61.072268)
		(width 0.1651)
		(layer "In7.Cu")
		(net "P5E_PEX2_STN2_RX_DN<33>")
	)
	(segment
		(start 289.83559 -273.479514)
		(end 289.94989 -273.365214)
		(width 0.1143)
		(layer "In7.Cu")
		(net "P5E_PEX2_STN2_RX_DN<33>")
	)
	(segment
		(start 344.59164 -392.713464)
		(end 345.003374 -392.9888)
		(width 0.1651)
		(layer "In5.Cu")
		(net "P5E_PEX2_STN6_RX_DP<104>")
	)
	(segment
		(start 345.003374 -392.988546)
		(end 345.031314 -393.129516)
		(width 0.1651)
		(layer "In5.Cu")
		(net "P5E_PEX2_STN6_RX_DP<104>")
	)
	(segment
		(start 325.907908 -341.038434)
		(end 326.783954 -341.91448)
		(width 0.1651)
		(layer "In5.Cu")
		(net "P5E_PEX2_STN6_RX_DP<104>")
	)
	(segment
		(start 282.349702 -318.015366)
		(end 282.235402 -318.129666)
		(width 0.1143)
		(layer "In5.Cu")
		(net "P5E_PEX2_STN6_RX_DP<104>")
	)
	(segment
		(start 345.003374 -392.9888)
		(end 345.003374 -392.988546)
		(width 0.1651)
		(layer "In5.Cu")
		(net "P5E_PEX2_STN6_RX_DP<104>")
	)
	(segment
		(start 326.783954 -359.166668)
		(end 329.912218 -384.35026)
		(width 0.1651)
		(layer "In5.Cu")
		(net "P5E_PEX2_STN6_RX_DP<104>")
	)
	(segment
		(start 345.584272 -393.377166)
		(end 346.073984 -393.704572)
		(width 0.1651)
		(layer "In5.Cu")
		(net "P5E_PEX2_STN6_RX_DP<104>")
	)
	(segment
		(start 282.235402 -318.129666)
		(end 282.005278 -318.129666)
		(width 0.1143)
		(layer "In5.Cu")
		(net "P5E_PEX2_STN6_RX_DP<104>")
	)
	(segment
		(start 281.733752 -320.392806)
		(end 282.60675 -321.265804)
		(width 0.1651)
		(layer "In5.Cu")
		(net "P5E_PEX2_STN6_RX_DP<104>")
	)
	(segment
		(start 282.349702 -317.749936)
		(end 282.349702 -318.015366)
		(width 0.1143)
		(layer "In5.Cu")
		(net "P5E_PEX2_STN6_RX_DP<104>")
	)
	(segment
		(start 281.779472 -319.84188)
		(end 281.733752 -319.8876)
		(width 0.1143)
		(layer "In5.Cu")
		(net "P5E_PEX2_STN6_RX_DP<104>")
	)
	(segment
		(start 281.733752 -319.8876)
		(end 281.733752 -319.916048)
		(width 0.1143)
		(layer "In5.Cu")
		(net "P5E_PEX2_STN6_RX_DP<104>")
	)
	(segment
		(start 347.520768 -395.18844)
		(end 347.734128 -395.679168)
		(width 0.1651)
		(layer "In5.Cu")
		(net "P5E_PEX2_STN6_RX_DP<104>")
	)
	(segment
		(start 281.733752 -319.916048)
		(end 281.733752 -320.392806)
		(width 0.1651)
		(layer "In5.Cu")
		(net "P5E_PEX2_STN6_RX_DP<104>")
	)
	(segment
		(start 281.779472 -318.355472)
		(end 281.779472 -319.84188)
		(width 0.1143)
		(layer "In5.Cu")
		(net "P5E_PEX2_STN6_RX_DP<104>")
	)
	(segment
		(start 345.031314 -393.129516)
		(end 345.443302 -393.405106)
		(width 0.1651)
		(layer "In5.Cu")
		(net "P5E_PEX2_STN6_RX_DP<104>")
	)
	(segment
		(start 344.038936 -392.465814)
		(end 344.450924 -392.741404)
		(width 0.1651)
		(layer "In5.Cu")
		(net "P5E_PEX2_STN6_RX_DP<104>")
	)
	(segment
		(start 326.783954 -341.91448)
		(end 326.783954 -359.166668)
		(width 0.1651)
		(layer "In5.Cu")
		(net "P5E_PEX2_STN6_RX_DP<104>")
	)
	(segment
		(start 346.890086 -401.872196)
		(end 346.890086 -401.49018)
		(width 0.1651)
		(layer "In5.Cu")
		(net "P5E_PEX2_STN6_RX_DP<104>")
	)
	(segment
		(start 344.450924 -392.741404)
		(end 344.59164 -392.713464)
		(width 0.1651)
		(layer "In5.Cu")
		(net "P5E_PEX2_STN6_RX_DP<104>")
	)
	(segment
		(start 346.859606 -394.637514)
		(end 346.985336 -394.639292)
		(width 0.1651)
		(layer "In5.Cu")
		(net "P5E_PEX2_STN6_RX_DP<104>")
	)
	(segment
		(start 346.073984 -393.704572)
		(end 346.515182 -394.156946)
		(width 0.1651)
		(layer "In5.Cu")
		(net "P5E_PEX2_STN6_RX_DP<104>")
	)
	(segment
		(start 342.780874 -391.502646)
		(end 344.010742 -392.324844)
		(width 0.1651)
		(layer "In5.Cu")
		(net "P5E_PEX2_STN6_RX_DP<104>")
	)
	(segment
		(start 282.60675 -321.265804)
		(end 325.907908 -341.038434)
		(width 0.1651)
		(layer "In5.Cu")
		(net "P5E_PEX2_STN6_RX_DP<104>")
	)
	(segment
		(start 330.62799 -385.912106)
		(end 330.950824 -386.246624)
		(width 0.1651)
		(layer "In5.Cu")
		(net "P5E_PEX2_STN6_RX_DP<104>")
	)
	(segment
		(start 345.443302 -393.405106)
		(end 345.584272 -393.377166)
		(width 0.1651)
		(layer "In5.Cu")
		(net "P5E_PEX2_STN6_RX_DP<104>")
	)
	(segment
		(start 347.734128 -401.71243)
		(end 347.447362 -401.999196)
		(width 0.1651)
		(layer "In5.Cu")
		(net "P5E_PEX2_STN6_RX_DP<104>")
	)
	(segment
		(start 346.515182 -394.156946)
		(end 346.513404 -394.282676)
		(width 0.1651)
		(layer "In5.Cu")
		(net "P5E_PEX2_STN6_RX_DP<104>")
	)
	(segment
		(start 282.005278 -318.129666)
		(end 281.779472 -318.355472)
		(width 0.1143)
		(layer "In5.Cu")
		(net "P5E_PEX2_STN6_RX_DP<104>")
	)
	(segment
		(start 330.950824 -386.246624)
		(end 336.643472 -388.54634)
		(width 0.1651)
		(layer "In5.Cu")
		(net "P5E_PEX2_STN6_RX_DP<104>")
	)
	(segment
		(start 347.017086 -401.999196)
		(end 346.890086 -401.872196)
		(width 0.1651)
		(layer "In5.Cu")
		(net "P5E_PEX2_STN6_RX_DP<104>")
	)
	(segment
		(start 346.513404 -394.282676)
		(end 346.859606 -394.637514)
		(width 0.1651)
		(layer "In5.Cu")
		(net "P5E_PEX2_STN6_RX_DP<104>")
	)
	(segment
		(start 344.010742 -392.324844)
		(end 344.038936 -392.465814)
		(width 0.1651)
		(layer "In5.Cu")
		(net "P5E_PEX2_STN6_RX_DP<104>")
	)
	(segment
		(start 347.447362 -401.999196)
		(end 347.017086 -401.999196)
		(width 0.1651)
		(layer "In5.Cu")
		(net "P5E_PEX2_STN6_RX_DP<104>")
	)
	(segment
		(start 347.734128 -395.679168)
		(end 347.734128 -401.71243)
		(width 0.1651)
		(layer "In5.Cu")
		(net "P5E_PEX2_STN6_RX_DP<104>")
	)
	(segment
		(start 346.985336 -394.639292)
		(end 347.520768 -395.18844)
		(width 0.1651)
		(layer "In5.Cu")
		(net "P5E_PEX2_STN6_RX_DP<104>")
	)
	(segment
		(start 336.643472 -388.54634)
		(end 342.780874 -391.502646)
		(width 0.1651)
		(layer "In5.Cu")
		(net "P5E_PEX2_STN6_RX_DP<104>")
	)
	(segment
		(start 329.912218 -384.35026)
		(end 330.62799 -385.912106)
		(width 0.1651)
		(layer "In5.Cu")
		(net "P5E_PEX2_STN6_RX_DP<104>")
	)
	(segment
		(start 391.293858 -394.095224)
		(end 398.129506 -391.264394)
		(width 0.1651)
		(layer "In5.Cu")
		(net "P5E_PEX3_STN5_RX_DN<86>")
	)
	(segment
		(start 412.365952 -323.723)
		(end 412.365952 -319.941448)
		(width 0.1651)
		(layer "In5.Cu")
		(net "P5E_PEX3_STN5_RX_DN<86>")
	)
	(segment
		(start 405.487378 -357.965248)
		(end 405.564594 -342.688672)
		(width 0.1651)
		(layer "In5.Cu")
		(net "P5E_PEX3_STN5_RX_DN<86>")
	)
	(segment
		(start 388.68985 -397.411956)
		(end 388.81685 -397.284956)
		(width 0.1651)
		(layer "In5.Cu")
		(net "P5E_PEX3_STN5_RX_DN<86>")
	)
	(segment
		(start 401.66798 -375.66346)
		(end 402.833586 -368.007646)
		(width 0.1651)
		(layer "In5.Cu")
		(net "P5E_PEX3_STN5_RX_DN<86>")
	)
	(segment
		(start 401.501102 -386.257038)
		(end 401.66798 -375.66346)
		(width 0.1651)
		(layer "In5.Cu")
		(net "P5E_PEX3_STN5_RX_DN<86>")
	)
	(segment
		(start 412.320232 -319.86728)
		(end 412.320232 -316.534292)
		(width 0.1143)
		(layer "In5.Cu")
		(net "P5E_PEX3_STN5_RX_DN<86>")
	)
	(segment
		(start 412.365952 -319.941448)
		(end 412.365952 -319.913)
		(width 0.1143)
		(layer "In5.Cu")
		(net "P5E_PEX3_STN5_RX_DN<86>")
	)
	(segment
		(start 412.434532 -316.419992)
		(end 412.585662 -316.419992)
		(width 0.1143)
		(layer "In5.Cu")
		(net "P5E_PEX3_STN5_RX_DN<86>")
	)
	(segment
		(start 412.699962 -316.534292)
		(end 412.699962 -316.799722)
		(width 0.1143)
		(layer "In5.Cu")
		(net "P5E_PEX3_STN5_RX_DN<86>")
	)
	(segment
		(start 411.751526 -326.807576)
		(end 412.365952 -323.723)
		(width 0.1651)
		(layer "In5.Cu")
		(net "P5E_PEX3_STN5_RX_DN<86>")
	)
	(segment
		(start 389.847836 -395.930882)
		(end 390.807702 -394.494512)
		(width 0.1651)
		(layer "In5.Cu")
		(net "P5E_PEX3_STN5_RX_DN<86>")
	)
	(segment
		(start 402.833586 -368.007646)
		(end 405.487378 -357.965248)
		(width 0.1651)
		(layer "In5.Cu")
		(net "P5E_PEX3_STN5_RX_DN<86>")
	)
	(segment
		(start 389.35025 -397.284956)
		(end 389.847836 -396.78737)
		(width 0.1651)
		(layer "In5.Cu")
		(net "P5E_PEX3_STN5_RX_DN<86>")
	)
	(segment
		(start 412.365952 -319.913)
		(end 412.320232 -319.86728)
		(width 0.1143)
		(layer "In5.Cu")
		(net "P5E_PEX3_STN5_RX_DN<86>")
	)
	(segment
		(start 389.847836 -396.78737)
		(end 389.847836 -395.930882)
		(width 0.1651)
		(layer "In5.Cu")
		(net "P5E_PEX3_STN5_RX_DN<86>")
	)
	(segment
		(start 390.807702 -394.494512)
		(end 391.293858 -394.095224)
		(width 0.1651)
		(layer "In5.Cu")
		(net "P5E_PEX3_STN5_RX_DN<86>")
	)
	(segment
		(start 412.320232 -316.534292)
		(end 412.434532 -316.419992)
		(width 0.1143)
		(layer "In5.Cu")
		(net "P5E_PEX3_STN5_RX_DN<86>")
	)
	(segment
		(start 412.585662 -316.419992)
		(end 412.699962 -316.534292)
		(width 0.1143)
		(layer "In5.Cu")
		(net "P5E_PEX3_STN5_RX_DN<86>")
	)
	(segment
		(start 388.68985 -397.790162)
		(end 388.68985 -397.411956)
		(width 0.1651)
		(layer "In5.Cu")
		(net "P5E_PEX3_STN5_RX_DN<86>")
	)
	(segment
		(start 400.832828 -388.24535)
		(end 401.501102 -386.257038)
		(width 0.1651)
		(layer "In5.Cu")
		(net "P5E_PEX3_STN5_RX_DN<86>")
	)
	(segment
		(start 405.564594 -342.688672)
		(end 406.123394 -340.377272)
		(width 0.1651)
		(layer "In5.Cu")
		(net "P5E_PEX3_STN5_RX_DN<86>")
	)
	(segment
		(start 388.81685 -397.284956)
		(end 389.35025 -397.284956)
		(width 0.1651)
		(layer "In5.Cu")
		(net "P5E_PEX3_STN5_RX_DN<86>")
	)
	(segment
		(start 406.123394 -340.377272)
		(end 411.751526 -326.807576)
		(width 0.1651)
		(layer "In5.Cu")
		(net "P5E_PEX3_STN5_RX_DN<86>")
	)
	(segment
		(start 399.648934 -390.017254)
		(end 400.832828 -388.24535)
		(width 0.1651)
		(layer "In5.Cu")
		(net "P5E_PEX3_STN5_RX_DN<86>")
	)
	(segment
		(start 398.129506 -391.264394)
		(end 399.648934 -390.017254)
		(width 0.1651)
		(layer "In5.Cu")
		(net "P5E_PEX3_STN5_RX_DN<86>")
	)
	(segment
		(start 397.116046 -167.166544)
		(end 397.116046 -168.490392)
		(width 0.13208)
		(layer "F.Cu")
		(net "RST_HP_NIC6_N")
	)
	(segment
		(start 396.502382 -166.55288)
		(end 397.116046 -167.166544)
		(width 0.13208)
		(layer "F.Cu")
		(net "RST_HP_NIC6_N")
	)
	(segment
		(start 397.543528 -168.917874)
		(end 397.543528 -169.710862)
		(width 0.13208)
		(layer "F.Cu")
		(net "RST_HP_NIC6_N")
	)
	(segment
		(start 395.759178 -166.55288)
		(end 396.502382 -166.55288)
		(width 0.13208)
		(layer "F.Cu")
		(net "RST_HP_NIC6_N")
	)
	(segment
		(start 397.116046 -168.490392)
		(end 397.543528 -168.917874)
		(width 0.13208)
		(layer "F.Cu")
		(net "RST_HP_NIC6_N")
	)
	(segment
		(start 397.543528 -169.710862)
		(end 397.543528 -170.77944)
		(width 0.13208)
		(layer "F.Cu")
		(net "RST_HP_NIC6_N")
	)
	(via
		(at 397.543528 -169.710862)
		(size 0.508)
		(drill 0.254)
		(layers "F.Cu" "B.Cu")
		(net "RST_HP_NIC6_N")
	)
	(segment
		(start 96.569784 -25.031954)
		(end 95.926402 -25.031954)
		(width 0.4572)
		(layer "F.Cu")
		(net "P3V3_SSD3")
	)
	(segment
		(start 100.75672 -10.145522)
		(end 100.75672 -9.535922)
		(width 0.508)
		(layer "F.Cu")
		(net "P3V3_SSD3")
	)
	(segment
		(start 86.178898 -59.978036)
		(end 86.178898 -60.633356)
		(width 0.381)
		(layer "F.Cu")
		(net "P3V3_SSD3")
	)
	(segment
		(start 70.846696 -37.47516)
		(end 70.141084 -37.47516)
		(width 0.4572)
		(layer "F.Cu")
		(net "P3V3_SSD3")
	)
	(segment
		(start 94.475046 -25.031954)
		(end 95.926402 -25.031954)
		(width 0.381)
		(layer "F.Cu")
		(net "P3V3_SSD3")
	)
	(segment
		(start 93.264736 -24.790146)
		(end 94.233238 -24.790146)
		(width 0.381)
		(layer "F.Cu")
		(net "P3V3_SSD3")
	)
	(segment
		(start 83.96859 -30.971236)
		(end 83.96859 -32.512762)
		(width 0.381)
		(layer "F.Cu")
		(net "P3V3_SSD3")
	)
	(segment
		(start 97.471484 -25.742392)
		(end 97.471484 -26.360882)
		(width 0.4572)
		(layer "F.Cu")
		(net "P3V3_SSD3")
	)
	(segment
		(start 98.072448 -8.577072)
		(end 98.136964 -8.641588)
		(width 0.381)
		(layer "F.Cu")
		(net "P3V3_SSD3")
	)
	(segment
		(start 83.394042 -30.396688)
		(end 83.96859 -30.971236)
		(width 0.381)
		(layer "F.Cu")
		(net "P3V3_SSD3")
	)
	(segment
		(start 97.437448 -8.577072)
		(end 98.072448 -8.577072)
		(width 0.381)
		(layer "F.Cu")
		(net "P3V3_SSD3")
	)
	(segment
		(start 83.96859 -32.512762)
		(end 83.694016 -32.787336)
		(width 0.381)
		(layer "F.Cu")
		(net "P3V3_SSD3")
	)
	(segment
		(start 85.371686 -24.807418)
		(end 84.753196 -24.807418)
		(width 0.4572)
		(layer "F.Cu")
		(net "P3V3_SSD3")
	)
	(segment
		(start 103.80472 -9.53262)
		(end 103.80472 -10.145522)
		(width 0.508)
		(layer "F.Cu")
		(net "P3V3_SSD3")
	)
	(segment
		(start 99.753928 -27.492198)
		(end 99.232974 -26.971244)
		(width 0.381)
		(layer "F.Cu")
		(net "P3V3_SSD3")
	)
	(segment
		(start 99.8855 -27.492198)
		(end 99.753928 -27.492198)
		(width 0.381)
		(layer "F.Cu")
		(net "P3V3_SSD3")
	)
	(segment
		(start 94.233238 -24.790146)
		(end 94.475046 -25.031954)
		(width 0.381)
		(layer "F.Cu")
		(net "P3V3_SSD3")
	)
	(segment
		(start 98.136964 -8.641588)
		(end 99.776534 -8.641588)
		(width 0.381)
		(layer "F.Cu")
		(net "P3V3_SSD3")
	)
	(segment
		(start 83.694016 -32.787336)
		(end 83.694016 -34.248852)
		(width 0.381)
		(layer "F.Cu")
		(net "P3V3_SSD3")
	)
	(via
		(at 86.178898 -60.633356)
		(size 0.508)
		(drill 0.254)
		(layers "F.Cu" "B.Cu")
		(net "P3V3_SSD3")
	)
	(via
		(at 84.514436 -53.469286)
		(size 0.508)
		(drill 0.254)
		(layers "F.Cu" "B.Cu")
		(net "P3V3_SSD3")
	)
	(via
		(at 86.398862 -49.574704)
		(size 0.508)
		(drill 0.254)
		(layers "F.Cu" "B.Cu")
		(net "P3V3_SSD3")
	)
	(via
		(at 84.964778 -52.528724)
		(size 0.508)
		(drill 0.254)
		(layers "F.Cu" "B.Cu")
		(net "P3V3_SSD3")
	)
	(via
		(at 99.232974 -26.971244)
		(size 0.508)
		(drill 0.254)
		(layers "F.Cu" "B.Cu")
		(net "P3V3_SSD3")
	)
	(via
		(at 85.514434 -50.608992)
		(size 0.508)
		(drill 0.254)
		(layers "F.Cu" "B.Cu")
		(net "P3V3_SSD3")
	)
	(via
		(at 86.276434 -51.320192)
		(size 0.508)
		(drill 0.254)
		(layers "F.Cu" "B.Cu")
		(net "P3V3_SSD3")
	)
	(via
		(at 85.599778 -52.528724)
		(size 0.508)
		(drill 0.254)
		(layers "F.Cu" "B.Cu")
		(net "P3V3_SSD3")
	)
	(via
		(at 97.471484 -26.360882)
		(size 0.508)
		(drill 0.254)
		(layers "F.Cu" "B.Cu")
		(net "P3V3_SSD3")
	)
	(via
		(at 100.75672 -9.535922)
		(size 0.508)
		(drill 0.254)
		(layers "F.Cu" "B.Cu")
		(net "P3V3_SSD3")
	)
	(via
		(at 96.569784 -25.031954)
		(size 0.508)
		(drill 0.254)
		(layers "F.Cu" "B.Cu")
		(net "P3V3_SSD3")
	)
	(via
		(at 97.437448 -8.577072)
		(size 0.508)
		(drill 0.254)
		(layers "F.Cu" "B.Cu")
		(net "P3V3_SSD3")
	)
	(via
		(at 85.149436 -53.469286)
		(size 0.508)
		(drill 0.254)
		(layers "F.Cu" "B.Cu")
		(net "P3V3_SSD3")
	)
	(via
		(at 84.753196 -24.807418)
		(size 0.508)
		(drill 0.254)
		(layers "F.Cu" "B.Cu")
		(net "P3V3_SSD3")
	)
	(via
		(at 85.128862 -49.574704)
		(size 0.508)
		(drill 0.254)
		(layers "F.Cu" "B.Cu")
		(net "P3V3_SSD3")
	)
	(via
		(at 86.276434 -50.608992)
		(size 0.508)
		(drill 0.254)
		(layers "F.Cu" "B.Cu")
		(net "P3V3_SSD3")
	)
	(via
		(at 84.493862 -49.574704)
		(size 0.508)
		(drill 0.254)
		(layers "F.Cu" "B.Cu")
		(net "P3V3_SSD3")
	)
	(via
		(at 82.310478 -29.614876)
		(size 0.508)
		(drill 0.254)
		(layers "F.Cu" "B.Cu")
		(net "P3V3_SSD3")
	)
	(via
		(at 70.141084 -37.47516)
		(size 0.508)
		(drill 0.254)
		(layers "F.Cu" "B.Cu")
		(net "P3V3_SSD3")
	)
	(via
		(at 85.763862 -49.574704)
		(size 0.508)
		(drill 0.254)
		(layers "F.Cu" "B.Cu")
		(net "P3V3_SSD3")
	)
	(via
		(at 85.514434 -51.243992)
		(size 0.508)
		(drill 0.254)
		(layers "F.Cu" "B.Cu")
		(net "P3V3_SSD3")
	)
	(via
		(at 103.80472 -9.53262)
		(size 0.508)
		(drill 0.254)
		(layers "F.Cu" "B.Cu")
		(net "P3V3_SSD3")
	)
	(via
		(at 82.310478 -30.376876)
		(size 0.508)
		(drill 0.254)
		(layers "F.Cu" "B.Cu")
		(net "P3V3_SSD3")
	)
	(segment
		(start 79.76362 -37.872924)
		(end 73.053956 -37.872924)
		(width 0.508)
		(layer "In9.Cu")
		(net "P3V3_SSD3")
	)
	(segment
		(start 73.053956 -37.872924)
		(end 72.604122 -38.322758)
		(width 0.508)
		(layer "In9.Cu")
		(net "P3V3_SSD3")
	)
	(segment
		(start 72.604122 -38.322758)
		(end 70.988682 -38.322758)
		(width 0.508)
		(layer "In9.Cu")
		(net "P3V3_SSD3")
	)
	(segment
		(start 70.988682 -38.322758)
		(end 70.141084 -37.47516)
		(width 0.508)
		(layer "In9.Cu")
		(net "P3V3_SSD3")
	)
	(segment
		(start 51.293268 -134.3279)
		(end 53.801772 -134.3279)
		(width 0.13462)
		(layer "F.Cu")
		(net "P5E_PEX0_STN1_RX_DP<30>")
	)
	(segment
		(start 53.801772 -134.3279)
		(end 54.09692 -134.032752)
		(width 0.13462)
		(layer "F.Cu")
		(net "P5E_PEX0_STN1_RX_DP<30>")
	)
	(segment
		(start 51.130454 -134.165086)
		(end 51.293268 -134.3279)
		(width 0.13462)
		(layer "F.Cu")
		(net "P5E_PEX0_STN1_RX_DP<30>")
	)
	(segment
		(start 50.64252 -134.165086)
		(end 51.130454 -134.165086)
		(width 0.13462)
		(layer "F.Cu")
		(net "P5E_PEX0_STN1_RX_DP<30>")
	)
	(segment
		(start 53.80609 -134.323582)
		(end 51.881532 -134.323582)
		(width 0.1651)
		(layer "In5.Cu")
		(net "P5E_PEX0_STN1_RX_DP<30>")
	)
	(segment
		(start 43.992546 -160.767776)
		(end 72.333866 -267.270738)
		(width 0.1651)
		(layer "In5.Cu")
		(net "P5E_PEX0_STN1_RX_DP<30>")
	)
	(segment
		(start 42.699178 -148.044154)
		(end 43.27652 -156.747972)
		(width 0.1651)
		(layer "In5.Cu")
		(net "P5E_PEX0_STN1_RX_DP<30>")
	)
	(segment
		(start 72.333358 -271.39773)
		(end 72.333866 -271.398238)
		(width 0.1651)
		(layer "In5.Cu")
		(net "P5E_PEX0_STN1_RX_DP<30>")
	)
	(segment
		(start 72.835262 -273.670014)
		(end 72.949562 -273.784314)
		(width 0.1143)
		(layer "In5.Cu")
		(net "P5E_PEX0_STN1_RX_DP<30>")
	)
	(segment
		(start 72.333866 -271.398238)
		(end 72.333866 -271.526)
		(width 0.1651)
		(layer "In5.Cu")
		(net "P5E_PEX0_STN1_RX_DP<30>")
	)
	(segment
		(start 49.739296 -141.153642)
		(end 48.903636 -143.171164)
		(width 0.1651)
		(layer "In5.Cu")
		(net "P5E_PEX0_STN1_RX_DP<30>")
	)
	(segment
		(start 49.739296 -137.06983)
		(end 49.739296 -141.153642)
		(width 0.1651)
		(layer "In5.Cu")
		(net "P5E_PEX0_STN1_RX_DP<30>")
	)
	(segment
		(start 46.55185 -145.262854)
		(end 46.23181 -145.741136)
		(width 0.1651)
		(layer "In5.Cu")
		(net "P5E_PEX0_STN1_RX_DP<30>")
	)
	(segment
		(start 45.537374 -146.435572)
		(end 44.444412 -146.8882)
		(width 0.1651)
		(layer "In5.Cu")
		(net "P5E_PEX0_STN1_RX_DP<30>")
	)
	(segment
		(start 44.444412 -146.8882)
		(end 43.965876 -146.8882)
		(width 0.1651)
		(layer "In5.Cu")
		(net "P5E_PEX0_STN1_RX_DP<30>")
	)
	(segment
		(start 48.903636 -143.171164)
		(end 47.997618 -144.077182)
		(width 0.1651)
		(layer "In5.Cu")
		(net "P5E_PEX0_STN1_RX_DP<30>")
	)
	(segment
		(start 43.603926 -146.99361)
		(end 43.415712 -147.087844)
		(width 0.1651)
		(layer "In5.Cu")
		(net "P5E_PEX0_STN1_RX_DP<30>")
	)
	(segment
		(start 72.333866 -271.526)
		(end 72.333866 -271.554448)
		(width 0.1143)
		(layer "In5.Cu")
		(net "P5E_PEX0_STN1_RX_DP<30>")
	)
	(segment
		(start 72.333866 -271.554448)
		(end 72.379586 -271.600168)
		(width 0.1143)
		(layer "In5.Cu")
		(net "P5E_PEX0_STN1_RX_DP<30>")
	)
	(segment
		(start 72.379586 -271.600168)
		(end 72.379586 -273.45513)
		(width 0.1143)
		(layer "In5.Cu")
		(net "P5E_PEX0_STN1_RX_DP<30>")
	)
	(segment
		(start 43.01363 -147.389596)
		(end 42.699178 -148.044154)
		(width 0.1651)
		(layer "In5.Cu")
		(net "P5E_PEX0_STN1_RX_DP<30>")
	)
	(segment
		(start 51.881532 -134.323582)
		(end 50.979324 -134.697216)
		(width 0.1651)
		(layer "In5.Cu")
		(net "P5E_PEX0_STN1_RX_DP<30>")
	)
	(segment
		(start 43.415712 -147.087844)
		(end 43.01363 -147.389596)
		(width 0.1651)
		(layer "In5.Cu")
		(net "P5E_PEX0_STN1_RX_DP<30>")
	)
	(segment
		(start 50.790856 -134.87654)
		(end 49.76622 -137.042906)
		(width 0.1651)
		(layer "In5.Cu")
		(net "P5E_PEX0_STN1_RX_DP<30>")
	)
	(segment
		(start 72.949562 -273.784314)
		(end 72.949562 -274.049744)
		(width 0.1143)
		(layer "In5.Cu")
		(net "P5E_PEX0_STN1_RX_DP<30>")
	)
	(segment
		(start 72.333358 -271.397222)
		(end 72.333358 -271.39773)
		(width 0.1651)
		(layer "In5.Cu")
		(net "P5E_PEX0_STN1_RX_DP<30>")
	)
	(segment
		(start 54.09692 -134.032752)
		(end 53.80609 -134.323582)
		(width 0.1651)
		(layer "In5.Cu")
		(net "P5E_PEX0_STN1_RX_DP<30>")
	)
	(segment
		(start 46.23181 -145.741136)
		(end 45.537374 -146.435572)
		(width 0.1651)
		(layer "In5.Cu")
		(net "P5E_PEX0_STN1_RX_DP<30>")
	)
	(segment
		(start 43.965876 -146.8882)
		(end 43.603926 -146.99361)
		(width 0.1651)
		(layer "In5.Cu")
		(net "P5E_PEX0_STN1_RX_DP<30>")
	)
	(segment
		(start 43.27652 -156.747972)
		(end 43.992546 -160.767776)
		(width 0.1651)
		(layer "In5.Cu")
		(net "P5E_PEX0_STN1_RX_DP<30>")
	)
	(segment
		(start 72.379586 -273.45513)
		(end 72.59447 -273.670014)
		(width 0.1143)
		(layer "In5.Cu")
		(net "P5E_PEX0_STN1_RX_DP<30>")
	)
	(segment
		(start 49.76622 -137.042906)
		(end 49.739296 -137.06983)
		(width 0.1651)
		(layer "In5.Cu")
		(net "P5E_PEX0_STN1_RX_DP<30>")
	)
	(segment
		(start 72.59447 -273.670014)
		(end 72.835262 -273.670014)
		(width 0.1143)
		(layer "In5.Cu")
		(net "P5E_PEX0_STN1_RX_DP<30>")
	)
	(segment
		(start 50.979324 -134.697216)
		(end 50.790856 -134.87654)
		(width 0.1651)
		(layer "In5.Cu")
		(net "P5E_PEX0_STN1_RX_DP<30>")
	)
	(segment
		(start 72.333866 -267.270738)
		(end 72.333866 -271.396714)
		(width 0.1651)
		(layer "In5.Cu")
		(net "P5E_PEX0_STN1_RX_DP<30>")
	)
	(segment
		(start 47.997618 -144.077182)
		(end 46.55185 -145.262854)
		(width 0.1651)
		(layer "In5.Cu")
		(net "P5E_PEX0_STN1_RX_DP<30>")
	)
	(segment
		(start 72.333866 -271.396714)
		(end 72.333358 -271.397222)
		(width 0.1651)
		(layer "In5.Cu")
		(net "P5E_PEX0_STN1_RX_DP<30>")
	)
	(segment
		(start 80.320642 -357.46309)
		(end 80.320642 -356.831646)
		(width 0.13462)
		(layer "F.Cu")
		(net "P5E_PEX0_STN6_TX_C_DP<102>")
	)
	(segment
		(start 80.320642 -356.831646)
		(end 80.000602 -356.511606)
		(width 0.13462)
		(layer "F.Cu")
		(net "P5E_PEX0_STN6_TX_C_DP<102>")
	)
	(segment
		(start 80.026002 -357.75773)
		(end 80.320642 -357.46309)
		(width 0.13462)
		(layer "F.Cu")
		(net "P5E_PEX0_STN6_TX_C_DP<102>")
	)
	(segment
		(start 75.00239 -383.560828)
		(end 74.764138 -383.79908)
		(width 0.1651)
		(layer "In13.Cu")
		(net "P5E_PEX0_STN6_TX_C_DP<102>")
	)
	(segment
		(start 74.109834 -383.67208)
		(end 74.109834 -383.290064)
		(width 0.1651)
		(layer "In13.Cu")
		(net "P5E_PEX0_STN6_TX_C_DP<102>")
	)
	(segment
		(start 77.185774 -364.698026)
		(end 77.064616 -364.731554)
		(width 0.1651)
		(layer "In13.Cu")
		(net "P5E_PEX0_STN6_TX_C_DP<102>")
	)
	(segment
		(start 75.00239 -368.551714)
		(end 75.00239 -383.560828)
		(width 0.1651)
		(layer "In13.Cu")
		(net "P5E_PEX0_STN6_TX_C_DP<102>")
	)
	(segment
		(start 80.316832 -358.04856)
		(end 80.316832 -359.17124)
		(width 0.1651)
		(layer "In13.Cu")
		(net "P5E_PEX0_STN6_TX_C_DP<102>")
	)
	(segment
		(start 77.429868 -364.267242)
		(end 77.185774 -364.698026)
		(width 0.1651)
		(layer "In13.Cu")
		(net "P5E_PEX0_STN6_TX_C_DP<102>")
	)
	(segment
		(start 80.026002 -357.75773)
		(end 80.316832 -358.04856)
		(width 0.1651)
		(layer "In13.Cu")
		(net "P5E_PEX0_STN6_TX_C_DP<102>")
	)
	(segment
		(start 76.853796 -365.28375)
		(end 75.00239 -368.551714)
		(width 0.1651)
		(layer "In13.Cu")
		(net "P5E_PEX0_STN6_TX_C_DP<102>")
	)
	(segment
		(start 77.645514 -363.732064)
		(end 77.401166 -364.163356)
		(width 0.1651)
		(layer "In13.Cu")
		(net "P5E_PEX0_STN6_TX_C_DP<102>")
	)
	(segment
		(start 77.7494 -363.703362)
		(end 77.645514 -363.732064)
		(width 0.1651)
		(layer "In13.Cu")
		(net "P5E_PEX0_STN6_TX_C_DP<102>")
	)
	(segment
		(start 74.236834 -383.79908)
		(end 74.109834 -383.67208)
		(width 0.1651)
		(layer "In13.Cu")
		(net "P5E_PEX0_STN6_TX_C_DP<102>")
	)
	(segment
		(start 74.764138 -383.79908)
		(end 74.236834 -383.79908)
		(width 0.1651)
		(layer "In13.Cu")
		(net "P5E_PEX0_STN6_TX_C_DP<102>")
	)
	(segment
		(start 76.820268 -365.162592)
		(end 76.853796 -365.28375)
		(width 0.1651)
		(layer "In13.Cu")
		(net "P5E_PEX0_STN6_TX_C_DP<102>")
	)
	(segment
		(start 77.401166 -364.163356)
		(end 77.429868 -364.267242)
		(width 0.1651)
		(layer "In13.Cu")
		(net "P5E_PEX0_STN6_TX_C_DP<102>")
	)
	(segment
		(start 80.316832 -359.17124)
		(end 77.7494 -363.703362)
		(width 0.1651)
		(layer "In13.Cu")
		(net "P5E_PEX0_STN6_TX_C_DP<102>")
	)
	(segment
		(start 77.064616 -364.731554)
		(end 76.820268 -365.162592)
		(width 0.1651)
		(layer "In13.Cu")
		(net "P5E_PEX0_STN6_TX_C_DP<102>")
	)
	(segment
		(start 299.967904 -30.190186)
		(end 299.46473 -30.190186)
		(width 0.13462)
		(layer "F.Cu")
		(net "P5E_PEX2_STN2_TX_C_DN<37>")
	)
	(segment
		(start 304.041302 -30.35808)
		(end 300.135798 -30.35808)
		(width 0.13462)
		(layer "F.Cu")
		(net "P5E_PEX2_STN2_TX_C_DN<37>")
	)
	(segment
		(start 304.367692 -30.03169)
		(end 304.041302 -30.35808)
		(width 0.13462)
		(layer "F.Cu")
		(net "P5E_PEX2_STN2_TX_C_DN<37>")
	)
	(segment
		(start 300.135798 -30.35808)
		(end 299.967904 -30.190186)
		(width 0.13462)
		(layer "F.Cu")
		(net "P5E_PEX2_STN2_TX_C_DN<37>")
	)
	(segment
		(start 275.319998 -319.96888)
		(end 275.319998 -316.534292)
		(width 0.1143)
		(layer "In5.Cu")
		(net "P5E_PEX2_STN6_RX_DN<111>")
	)
	(segment
		(start 275.365718 -320.043048)
		(end 275.365718 -320.0146)
		(width 0.1143)
		(layer "In5.Cu")
		(net "P5E_PEX2_STN6_RX_DN<111>")
	)
	(segment
		(start 275.365718 -322.907152)
		(end 275.365718 -320.043048)
		(width 0.1651)
		(layer "In5.Cu")
		(net "P5E_PEX2_STN6_RX_DN<111>")
	)
	(segment
		(start 278.665432 -326.798178)
		(end 276.847554 -325.5137)
		(width 0.1651)
		(layer "In5.Cu")
		(net "P5E_PEX2_STN6_RX_DN<111>")
	)
	(segment
		(start 332.40218 -394.5128)
		(end 331.789024 -393.89304)
		(width 0.1651)
		(layer "In5.Cu")
		(net "P5E_PEX2_STN6_RX_DN<111>")
	)
	(segment
		(start 276.847554 -325.5137)
		(end 276.010624 -324.466458)
		(width 0.1651)
		(layer "In5.Cu")
		(net "P5E_PEX2_STN6_RX_DN<111>")
	)
	(segment
		(start 302.597566 -339.696044)
		(end 278.665432 -326.798178)
		(width 0.1651)
		(layer "In5.Cu")
		(net "P5E_PEX2_STN6_RX_DN<111>")
	)
	(segment
		(start 329.061572 -392.749024)
		(end 327.536048 -392.108944)
		(width 0.1651)
		(layer "In5.Cu")
		(net "P5E_PEX2_STN6_RX_DN<111>")
	)
	(segment
		(start 324.91426 -389.482076)
		(end 302.859186 -340.092792)
		(width 0.1651)
		(layer "In5.Cu")
		(net "P5E_PEX2_STN6_RX_DN<111>")
	)
	(segment
		(start 275.434298 -316.419992)
		(end 275.585428 -316.419992)
		(width 0.1143)
		(layer "In5.Cu")
		(net "P5E_PEX2_STN6_RX_DN<111>")
	)
	(segment
		(start 329.061826 -392.749024)
		(end 329.061572 -392.749024)
		(width 0.1651)
		(layer "In5.Cu")
		(net "P5E_PEX2_STN6_RX_DN<111>")
	)
	(segment
		(start 332.616048 -395.027912)
		(end 332.40218 -394.5128)
		(width 0.1651)
		(layer "In5.Cu")
		(net "P5E_PEX2_STN6_RX_DN<111>")
	)
	(segment
		(start 327.536048 -392.108944)
		(end 324.91426 -389.482076)
		(width 0.1651)
		(layer "In5.Cu")
		(net "P5E_PEX2_STN6_RX_DN<111>")
	)
	(segment
		(start 275.365718 -320.0146)
		(end 275.319998 -319.96888)
		(width 0.1143)
		(layer "In5.Cu")
		(net "P5E_PEX2_STN6_RX_DN<111>")
	)
	(segment
		(start 331.617066 -401.181062)
		(end 332.164182 -401.181062)
		(width 0.1651)
		(layer "In5.Cu")
		(net "P5E_PEX2_STN6_RX_DN<111>")
	)
	(segment
		(start 331.490066 -401.690078)
		(end 331.490066 -401.308062)
		(width 0.1651)
		(layer "In5.Cu")
		(net "P5E_PEX2_STN6_RX_DN<111>")
	)
	(segment
		(start 276.010624 -324.466458)
		(end 275.365718 -322.907152)
		(width 0.1651)
		(layer "In5.Cu")
		(net "P5E_PEX2_STN6_RX_DN<111>")
	)
	(segment
		(start 275.699728 -316.534292)
		(end 275.699728 -316.799722)
		(width 0.1143)
		(layer "In5.Cu")
		(net "P5E_PEX2_STN6_RX_DN<111>")
	)
	(segment
		(start 331.490066 -401.308062)
		(end 331.617066 -401.181062)
		(width 0.1651)
		(layer "In5.Cu")
		(net "P5E_PEX2_STN6_RX_DN<111>")
	)
	(segment
		(start 275.319998 -316.534292)
		(end 275.434298 -316.419992)
		(width 0.1143)
		(layer "In5.Cu")
		(net "P5E_PEX2_STN6_RX_DN<111>")
	)
	(segment
		(start 331.789024 -393.89304)
		(end 329.061826 -392.749024)
		(width 0.1651)
		(layer "In5.Cu")
		(net "P5E_PEX2_STN6_RX_DN<111>")
	)
	(segment
		(start 275.585428 -316.419992)
		(end 275.699728 -316.534292)
		(width 0.1143)
		(layer "In5.Cu")
		(net "P5E_PEX2_STN6_RX_DN<111>")
	)
	(segment
		(start 332.616048 -400.729196)
		(end 332.616048 -395.027912)
		(width 0.1651)
		(layer "In5.Cu")
		(net "P5E_PEX2_STN6_RX_DN<111>")
	)
	(segment
		(start 302.859186 -340.092792)
		(end 302.597566 -339.696044)
		(width 0.1651)
		(layer "In5.Cu")
		(net "P5E_PEX2_STN6_RX_DN<111>")
	)
	(segment
		(start 332.164182 -401.181062)
		(end 332.616048 -400.729196)
		(width 0.1651)
		(layer "In5.Cu")
		(net "P5E_PEX2_STN6_RX_DN<111>")
	)
	(segment
		(start 402.847048 -344.538554)
		(end 402.847048 -345.171014)
		(width 0.13462)
		(layer "F.Cu")
		(net "P5E_PEX3_STN5_TX_C_DN<94>")
	)
	(segment
		(start 402.847048 -345.171014)
		(end 403.14118 -345.465146)
		(width 0.13462)
		(layer "F.Cu")
		(net "P5E_PEX3_STN5_TX_C_DN<94>")
	)
	(segment
		(start 403.16658 -344.219022)
		(end 402.847048 -344.538554)
		(width 0.13462)
		(layer "F.Cu")
		(net "P5E_PEX3_STN5_TX_C_DN<94>")
	)
	(segment
		(start 400.436842 -359.846372)
		(end 401.29587 -357.994458)
		(width 0.1651)
		(layer "In13.Cu")
		(net "P5E_PEX3_STN5_TX_C_DN<94>")
	)
	(segment
		(start 389.815832 -369.84559)
		(end 390.590024 -368.17681)
		(width 0.1651)
		(layer "In13.Cu")
		(net "P5E_PEX3_STN5_TX_C_DN<94>")
	)
	(segment
		(start 401.29587 -347.881194)
		(end 402.85035 -346.326714)
		(width 0.1651)
		(layer "In13.Cu")
		(net "P5E_PEX3_STN5_TX_C_DN<94>")
	)
	(segment
		(start 402.85035 -345.755976)
		(end 403.14118 -345.465146)
		(width 0.1651)
		(layer "In13.Cu")
		(net "P5E_PEX3_STN5_TX_C_DN<94>")
	)
	(segment
		(start 390.590024 -368.17681)
		(end 400.436842 -359.846372)
		(width 0.1651)
		(layer "In13.Cu")
		(net "P5E_PEX3_STN5_TX_C_DN<94>")
	)
	(segment
		(start 389.363966 -379.08103)
		(end 389.815832 -378.629164)
		(width 0.1651)
		(layer "In13.Cu")
		(net "P5E_PEX3_STN5_TX_C_DN<94>")
	)
	(segment
		(start 389.815832 -378.629164)
		(end 389.815832 -369.84559)
		(width 0.1651)
		(layer "In13.Cu")
		(net "P5E_PEX3_STN5_TX_C_DN<94>")
	)
	(segment
		(start 388.81685 -379.08103)
		(end 389.363966 -379.08103)
		(width 0.1651)
		(layer "In13.Cu")
		(net "P5E_PEX3_STN5_TX_C_DN<94>")
	)
	(segment
		(start 402.85035 -346.326714)
		(end 402.85035 -345.755976)
		(width 0.1651)
		(layer "In13.Cu")
		(net "P5E_PEX3_STN5_TX_C_DN<94>")
	)
	(segment
		(start 388.68985 -379.590046)
		(end 388.68985 -379.20803)
		(width 0.1651)
		(layer "In13.Cu")
		(net "P5E_PEX3_STN5_TX_C_DN<94>")
	)
	(segment
		(start 401.29587 -357.994458)
		(end 401.29587 -347.881194)
		(width 0.1651)
		(layer "In13.Cu")
		(net "P5E_PEX3_STN5_TX_C_DN<94>")
	)
	(segment
		(start 388.68985 -379.20803)
		(end 388.81685 -379.08103)
		(width 0.1651)
		(layer "In13.Cu")
		(net "P5E_PEX3_STN5_TX_C_DN<94>")
	)
	(segment
		(start 66.478912 -137.24509)
		(end 68.65747 -137.24509)
		(width 0.13208)
		(layer "F.Cu")
		(net "PRSNTB1_NIC1_N")
	)
	(segment
		(start 63.87084 -138.864848)
		(end 63.87084 -137.848848)
		(width 0.13208)
		(layer "F.Cu")
		(net "PRSNTB1_NIC1_N")
	)
	(segment
		(start 65.875154 -137.848848)
		(end 66.478912 -137.24509)
		(width 0.13208)
		(layer "F.Cu")
		(net "PRSNTB1_NIC1_N")
	)
	(segment
		(start 65.047114 -137.848848)
		(end 65.875154 -137.848848)
		(width 0.13208)
		(layer "F.Cu")
		(net "PRSNTB1_NIC1_N")
	)
	(segment
		(start 63.87084 -137.848848)
		(end 65.047114 -137.848848)
		(width 0.13208)
		(layer "F.Cu")
		(net "PRSNTB1_NIC1_N")
	)
	(via
		(at 65.047114 -137.848848)
		(size 0.762)
		(drill 0.381)
		(layers "F.Cu" "B.Cu")
		(net "PRSNTB1_NIC1_N")
	)
	(segment
		(start 400.289268 -175.238156)
		(end 400.289268 -176.478438)
		(width 0.13208)
		(layer "F.Cu")
		(net "HP_NIC6_PWRGD_R")
	)
	(segment
		(start 400.925792 -173.681898)
		(end 400.925792 -174.225712)
		(width 0.13208)
		(layer "F.Cu")
		(net "HP_NIC6_PWRGD_R")
	)
	(segment
		(start 400.925792 -174.225712)
		(end 400.345148 -174.806356)
		(width 0.13208)
		(layer "F.Cu")
		(net "HP_NIC6_PWRGD_R")
	)
	(segment
		(start 400.345148 -175.182276)
		(end 400.289268 -175.238156)
		(width 0.13208)
		(layer "F.Cu")
		(net "HP_NIC6_PWRGD_R")
	)
	(segment
		(start 400.345148 -174.806356)
		(end 400.345148 -175.182276)
		(width 0.13208)
		(layer "F.Cu")
		(net "HP_NIC6_PWRGD_R")
	)
	(segment
		(start 400.473418 -173.229524)
		(end 400.925792 -173.681898)
		(width 0.13208)
		(layer "F.Cu")
		(net "HP_NIC6_PWRGD_R")
	)
	(segment
		(start 399.443448 -173.229524)
		(end 400.473418 -173.229524)
		(width 0.13208)
		(layer "F.Cu")
		(net "HP_NIC6_PWRGD_R")
	)
	(via
		(at 400.925792 -173.681898)
		(size 0.762)
		(drill 0.381)
		(layers "F.Cu" "B.Cu")
		(net "HP_NIC6_PWRGD_R")
	)
	(segment
		(start 44.846748 -37.47516)
		(end 44.141136 -37.47516)
		(width 0.4572)
		(layer "F.Cu")
		(net "P3V3_SSD2")
	)
	(segment
		(start 67.264788 -24.790146)
		(end 68.23329 -24.790146)
		(width 0.381)
		(layer "F.Cu")
		(net "P3V3_SSD2")
	)
	(segment
		(start 69.926454 -25.031954)
		(end 70.569836 -25.031954)
		(width 0.4572)
		(layer "F.Cu")
		(net "P3V3_SSD2")
	)
	(segment
		(start 77.560424 -14.799818)
		(end 77.560424 -16.439388)
		(width 0.381)
		(layer "F.Cu")
		(net "P3V3_SSD2")
	)
	(segment
		(start 77.62494 -14.735302)
		(end 77.560424 -14.799818)
		(width 0.381)
		(layer "F.Cu")
		(net "P3V3_SSD2")
	)
	(segment
		(start 77.62494 -14.100302)
		(end 77.62494 -14.735302)
		(width 0.381)
		(layer "F.Cu")
		(net "P3V3_SSD2")
	)
	(segment
		(start 59.371738 -24.807418)
		(end 58.753248 -24.807418)
		(width 0.4572)
		(layer "F.Cu")
		(net "P3V3_SSD2")
	)
	(segment
		(start 68.475098 -25.031954)
		(end 69.926454 -25.031954)
		(width 0.381)
		(layer "F.Cu")
		(net "P3V3_SSD2")
	)
	(segment
		(start 57.968642 -32.512762)
		(end 57.968642 -30.971236)
		(width 0.381)
		(layer "F.Cu")
		(net "P3V3_SSD2")
	)
	(segment
		(start 60.17895 -59.978036)
		(end 60.17895 -60.633356)
		(width 0.381)
		(layer "F.Cu")
		(net "P3V3_SSD2")
	)
	(segment
		(start 76.05649 -17.419574)
		(end 76.66609 -17.419574)
		(width 0.508)
		(layer "F.Cu")
		(net "P3V3_SSD2")
	)
	(segment
		(start 68.23329 -24.790146)
		(end 68.475098 -25.031954)
		(width 0.381)
		(layer "F.Cu")
		(net "P3V3_SSD2")
	)
	(segment
		(start 76.669392 -20.467574)
		(end 76.05649 -20.467574)
		(width 0.508)
		(layer "F.Cu")
		(net "P3V3_SSD2")
	)
	(segment
		(start 57.968642 -30.971236)
		(end 57.394094 -30.396688)
		(width 0.381)
		(layer "F.Cu")
		(net "P3V3_SSD2")
	)
	(segment
		(start 71.471536 -25.742392)
		(end 71.471536 -26.360882)
		(width 0.4572)
		(layer "F.Cu")
		(net "P3V3_SSD2")
	)
	(segment
		(start 73.885552 -27.492198)
		(end 73.75398 -27.492198)
		(width 0.381)
		(layer "F.Cu")
		(net "P3V3_SSD2")
	)
	(segment
		(start 73.75398 -27.492198)
		(end 73.233026 -26.971244)
		(width 0.381)
		(layer "F.Cu")
		(net "P3V3_SSD2")
	)
	(segment
		(start 57.694068 -32.787336)
		(end 57.968642 -32.512762)
		(width 0.381)
		(layer "F.Cu")
		(net "P3V3_SSD2")
	)
	(segment
		(start 57.694068 -34.248852)
		(end 57.694068 -32.787336)
		(width 0.381)
		(layer "F.Cu")
		(net "P3V3_SSD2")
	)
	(via
		(at 59.128914 -49.574704)
		(size 0.508)
		(drill 0.254)
		(layers "F.Cu" "B.Cu")
		(net "P3V3_SSD2")
	)
	(via
		(at 60.276486 -50.608992)
		(size 0.508)
		(drill 0.254)
		(layers "F.Cu" "B.Cu")
		(net "P3V3_SSD2")
	)
	(via
		(at 58.753248 -24.807418)
		(size 0.508)
		(drill 0.254)
		(layers "F.Cu" "B.Cu")
		(net "P3V3_SSD2")
	)
	(via
		(at 56.31053 -30.376876)
		(size 0.508)
		(drill 0.254)
		(layers "F.Cu" "B.Cu")
		(net "P3V3_SSD2")
	)
	(via
		(at 58.96483 -52.528724)
		(size 0.508)
		(drill 0.254)
		(layers "F.Cu" "B.Cu")
		(net "P3V3_SSD2")
	)
	(via
		(at 59.149488 -53.469286)
		(size 0.508)
		(drill 0.254)
		(layers "F.Cu" "B.Cu")
		(net "P3V3_SSD2")
	)
	(via
		(at 56.31053 -29.614876)
		(size 0.508)
		(drill 0.254)
		(layers "F.Cu" "B.Cu")
		(net "P3V3_SSD2")
	)
	(via
		(at 60.398914 -49.574704)
		(size 0.508)
		(drill 0.254)
		(layers "F.Cu" "B.Cu")
		(net "P3V3_SSD2")
	)
	(via
		(at 70.569836 -25.031954)
		(size 0.508)
		(drill 0.254)
		(layers "F.Cu" "B.Cu")
		(net "P3V3_SSD2")
	)
	(via
		(at 59.514486 -50.608992)
		(size 0.508)
		(drill 0.254)
		(layers "F.Cu" "B.Cu")
		(net "P3V3_SSD2")
	)
	(via
		(at 60.17895 -60.633356)
		(size 0.508)
		(drill 0.254)
		(layers "F.Cu" "B.Cu")
		(net "P3V3_SSD2")
	)
	(via
		(at 60.276486 -51.320192)
		(size 0.508)
		(drill 0.254)
		(layers "F.Cu" "B.Cu")
		(net "P3V3_SSD2")
	)
	(via
		(at 58.493914 -49.574704)
		(size 0.508)
		(drill 0.254)
		(layers "F.Cu" "B.Cu")
		(net "P3V3_SSD2")
	)
	(via
		(at 59.514486 -51.243992)
		(size 0.508)
		(drill 0.254)
		(layers "F.Cu" "B.Cu")
		(net "P3V3_SSD2")
	)
	(via
		(at 77.62494 -14.100302)
		(size 0.508)
		(drill 0.254)
		(layers "F.Cu" "B.Cu")
		(net "P3V3_SSD2")
	)
	(via
		(at 76.66609 -17.419574)
		(size 0.508)
		(drill 0.254)
		(layers "F.Cu" "B.Cu")
		(net "P3V3_SSD2")
	)
	(via
		(at 58.514488 -53.469286)
		(size 0.508)
		(drill 0.254)
		(layers "F.Cu" "B.Cu")
		(net "P3V3_SSD2")
	)
	(via
		(at 59.59983 -52.528724)
		(size 0.508)
		(drill 0.254)
		(layers "F.Cu" "B.Cu")
		(net "P3V3_SSD2")
	)
	(via
		(at 76.669392 -20.467574)
		(size 0.508)
		(drill 0.254)
		(layers "F.Cu" "B.Cu")
		(net "P3V3_SSD2")
	)
	(via
		(at 71.471536 -26.360882)
		(size 0.508)
		(drill 0.254)
		(layers "F.Cu" "B.Cu")
		(net "P3V3_SSD2")
	)
	(via
		(at 73.233026 -26.971244)
		(size 0.508)
		(drill 0.254)
		(layers "F.Cu" "B.Cu")
		(net "P3V3_SSD2")
	)
	(via
		(at 44.141136 -37.47516)
		(size 0.508)
		(drill 0.254)
		(layers "F.Cu" "B.Cu")
		(net "P3V3_SSD2")
	)
	(via
		(at 59.763914 -49.574704)
		(size 0.508)
		(drill 0.254)
		(layers "F.Cu" "B.Cu")
		(net "P3V3_SSD2")
	)
	(segment
		(start 46.604174 -38.322758)
		(end 44.988734 -38.322758)
		(width 0.508)
		(layer "In9.Cu")
		(net "P3V3_SSD2")
	)
	(segment
		(start 44.988734 -38.322758)
		(end 44.141136 -37.47516)
		(width 0.508)
		(layer "In9.Cu")
		(net "P3V3_SSD2")
	)
	(segment
		(start 53.763672 -37.872924)
		(end 47.054008 -37.872924)
		(width 0.508)
		(layer "In9.Cu")
		(net "P3V3_SSD2")
	)
	(segment
		(start 47.054008 -37.872924)
		(end 46.604174 -38.322758)
		(width 0.508)
		(layer "In9.Cu")
		(net "P3V3_SSD2")
	)
	(segment
		(start 51.293268 -105.282238)
		(end 51.130454 -105.445052)
		(width 0.13462)
		(layer "F.Cu")
		(net "P5E_PEX0_STN1_RX_DN<19>")
	)
	(segment
		(start 52.24272 -105.57637)
		(end 51.948588 -105.282238)
		(width 0.13462)
		(layer "F.Cu")
		(net "P5E_PEX0_STN1_RX_DN<19>")
	)
	(segment
		(start 51.948588 -105.282238)
		(end 51.293268 -105.282238)
		(width 0.13462)
		(layer "F.Cu")
		(net "P5E_PEX0_STN1_RX_DN<19>")
	)
	(segment
		(start 51.130454 -105.445052)
		(end 50.64252 -105.445052)
		(width 0.13462)
		(layer "F.Cu")
		(net "P5E_PEX0_STN1_RX_DN<19>")
	)
	(segment
		(start 49.32934 -106.444796)
		(end 48.89373 -106.68)
		(width 0.1651)
		(layer "In5.Cu")
		(net "P5E_PEX0_STN1_RX_DN<19>")
	)
	(segment
		(start 62.385194 -275.379688)
		(end 62.499494 -275.265388)
		(width 0.1143)
		(layer "In5.Cu")
		(net "P5E_PEX0_STN1_RX_DN<19>")
	)
	(segment
		(start 43.931332 -110.06455)
		(end 43.769788 -110.06201)
		(width 0.1651)
		(layer "In5.Cu")
		(net "P5E_PEX0_STN1_RX_DN<19>")
	)
	(segment
		(start 49.920144 -106.255312)
		(end 49.484026 -106.491024)
		(width 0.1651)
		(layer "In5.Cu")
		(net "P5E_PEX0_STN1_RX_DN<19>")
	)
	(segment
		(start 50.992786 -105.675684)
		(end 50.556668 -105.911396)
		(width 0.1651)
		(layer "In5.Cu")
		(net "P5E_PEX0_STN1_RX_DN<19>")
	)
	(segment
		(start 42.535348 -111.416084)
		(end 42.17924 -111.761016)
		(width 0.1651)
		(layer "In5.Cu")
		(net "P5E_PEX0_STN1_RX_DN<19>")
	)
	(segment
		(start 51.474624 -105.28554)
		(end 51.039014 -105.520744)
		(width 0.1651)
		(layer "In5.Cu")
		(net "P5E_PEX0_STN1_RX_DN<19>")
	)
	(segment
		(start 42.537888 -111.25454)
		(end 42.535348 -111.416084)
		(width 0.1651)
		(layer "In5.Cu")
		(net "P5E_PEX0_STN1_RX_DN<19>")
	)
	(segment
		(start 44.28744 -109.719618)
		(end 43.931332 -110.06455)
		(width 0.1651)
		(layer "In5.Cu")
		(net "P5E_PEX0_STN1_RX_DN<19>")
	)
	(segment
		(start 48.411384 -107.070652)
		(end 48.256698 -107.024424)
		(width 0.1651)
		(layer "In5.Cu")
		(net "P5E_PEX0_STN1_RX_DN<19>")
	)
	(segment
		(start 62.120018 -271.848072)
		(end 62.120018 -275.27631)
		(width 0.1143)
		(layer "In5.Cu")
		(net "P5E_PEX0_STN1_RX_DN<19>")
	)
	(segment
		(start 46.265846 -108.229908)
		(end 46.11116 -108.18368)
		(width 0.1651)
		(layer "In5.Cu")
		(net "P5E_PEX0_STN1_RX_DN<19>")
	)
	(segment
		(start 62.223396 -275.379688)
		(end 62.385194 -275.379688)
		(width 0.1143)
		(layer "In5.Cu")
		(net "P5E_PEX0_STN1_RX_DN<19>")
	)
	(segment
		(start 48.847502 -106.83494)
		(end 48.411384 -107.070652)
		(width 0.1651)
		(layer "In5.Cu")
		(net "P5E_PEX0_STN1_RX_DN<19>")
	)
	(segment
		(start 33.004252 -126.387352)
		(end 32.204152 -138.435842)
		(width 0.1651)
		(layer "In5.Cu")
		(net "P5E_PEX0_STN1_RX_DN<19>")
	)
	(segment
		(start 34.33191 -122.078242)
		(end 33.667192 -122.886724)
		(width 0.1651)
		(layer "In5.Cu")
		(net "P5E_PEX0_STN1_RX_DN<19>")
	)
	(segment
		(start 46.748192 -107.839256)
		(end 46.701964 -107.994196)
		(width 0.1651)
		(layer "In5.Cu")
		(net "P5E_PEX0_STN1_RX_DN<19>")
	)
	(segment
		(start 46.701964 -107.994196)
		(end 46.265846 -108.229908)
		(width 0.1651)
		(layer "In5.Cu")
		(net "P5E_PEX0_STN1_RX_DN<19>")
	)
	(segment
		(start 51.039014 -105.520744)
		(end 50.992786 -105.675684)
		(width 0.1651)
		(layer "In5.Cu")
		(net "P5E_PEX0_STN1_RX_DN<19>")
	)
	(segment
		(start 33.025588 -165.120574)
		(end 62.165738 -269.489682)
		(width 0.1651)
		(layer "In5.Cu")
		(net "P5E_PEX0_STN1_RX_DN<19>")
	)
	(segment
		(start 42.893742 -110.910116)
		(end 42.537888 -111.25454)
		(width 0.1651)
		(layer "In5.Cu")
		(net "P5E_PEX0_STN1_RX_DN<19>")
	)
	(segment
		(start 47.338742 -107.65028)
		(end 47.183802 -107.604052)
		(width 0.1651)
		(layer "In5.Cu")
		(net "P5E_PEX0_STN1_RX_DN<19>")
	)
	(segment
		(start 31.40329 -150.483824)
		(end 31.92907 -158.735014)
		(width 0.1651)
		(layer "In5.Cu")
		(net "P5E_PEX0_STN1_RX_DN<19>")
	)
	(segment
		(start 48.256698 -107.024424)
		(end 47.821088 -107.259628)
		(width 0.1651)
		(layer "In5.Cu")
		(net "P5E_PEX0_STN1_RX_DN<19>")
	)
	(segment
		(start 62.120018 -275.27631)
		(end 62.223396 -275.379688)
		(width 0.1143)
		(layer "In5.Cu")
		(net "P5E_PEX0_STN1_RX_DN<19>")
	)
	(segment
		(start 49.966372 -106.100372)
		(end 49.920144 -106.255312)
		(width 0.1651)
		(layer "In5.Cu")
		(net "P5E_PEX0_STN1_RX_DN<19>")
	)
	(segment
		(start 46.11116 -108.18368)
		(end 45.202856 -108.674408)
		(width 0.1651)
		(layer "In5.Cu")
		(net "P5E_PEX0_STN1_RX_DN<19>")
	)
	(segment
		(start 32.203644 -138.436096)
		(end 31.40329 -150.483824)
		(width 0.1651)
		(layer "In5.Cu")
		(net "P5E_PEX0_STN1_RX_DN<19>")
	)
	(segment
		(start 45.202856 -108.674408)
		(end 44.28998 -109.558074)
		(width 0.1651)
		(layer "In5.Cu")
		(net "P5E_PEX0_STN1_RX_DN<19>")
	)
	(segment
		(start 52.24272 -105.57637)
		(end 51.95189 -105.28554)
		(width 0.1651)
		(layer "In5.Cu")
		(net "P5E_PEX0_STN1_RX_DN<19>")
	)
	(segment
		(start 44.28998 -109.558074)
		(end 44.28744 -109.719618)
		(width 0.1651)
		(layer "In5.Cu")
		(net "P5E_PEX0_STN1_RX_DN<19>")
	)
	(segment
		(start 32.204152 -138.435842)
		(end 32.203644 -138.436096)
		(width 0.1651)
		(layer "In5.Cu")
		(net "P5E_PEX0_STN1_RX_DN<19>")
	)
	(segment
		(start 50.401982 -105.865168)
		(end 49.966372 -106.100372)
		(width 0.1651)
		(layer "In5.Cu")
		(net "P5E_PEX0_STN1_RX_DN<19>")
	)
	(segment
		(start 49.484026 -106.491024)
		(end 49.32934 -106.444796)
		(width 0.1651)
		(layer "In5.Cu")
		(net "P5E_PEX0_STN1_RX_DN<19>")
	)
	(segment
		(start 48.89373 -106.68)
		(end 48.847502 -106.83494)
		(width 0.1651)
		(layer "In5.Cu")
		(net "P5E_PEX0_STN1_RX_DN<19>")
	)
	(segment
		(start 42.17924 -111.761016)
		(end 42.017696 -111.758222)
		(width 0.1651)
		(layer "In5.Cu")
		(net "P5E_PEX0_STN1_RX_DN<19>")
	)
	(segment
		(start 31.92907 -158.735014)
		(end 33.025588 -165.120574)
		(width 0.1651)
		(layer "In5.Cu")
		(net "P5E_PEX0_STN1_RX_DN<19>")
	)
	(segment
		(start 62.165738 -269.489682)
		(end 62.165738 -271.773904)
		(width 0.1651)
		(layer "In5.Cu")
		(net "P5E_PEX0_STN1_RX_DN<19>")
	)
	(segment
		(start 43.055286 -110.91291)
		(end 42.893742 -110.910116)
		(width 0.1651)
		(layer "In5.Cu")
		(net "P5E_PEX0_STN1_RX_DN<19>")
	)
	(segment
		(start 36.36772 -120.982232)
		(end 34.33191 -122.078242)
		(width 0.1651)
		(layer "In5.Cu")
		(net "P5E_PEX0_STN1_RX_DN<19>")
	)
	(segment
		(start 50.556668 -105.911396)
		(end 50.401982 -105.865168)
		(width 0.1651)
		(layer "In5.Cu")
		(net "P5E_PEX0_STN1_RX_DN<19>")
	)
	(segment
		(start 43.413934 -110.406434)
		(end 43.411394 -110.567978)
		(width 0.1651)
		(layer "In5.Cu")
		(net "P5E_PEX0_STN1_RX_DN<19>")
	)
	(segment
		(start 62.165738 -271.802352)
		(end 62.120018 -271.848072)
		(width 0.1143)
		(layer "In5.Cu")
		(net "P5E_PEX0_STN1_RX_DN<19>")
	)
	(segment
		(start 62.499494 -275.265388)
		(end 62.499494 -274.999958)
		(width 0.1143)
		(layer "In5.Cu")
		(net "P5E_PEX0_STN1_RX_DN<19>")
	)
	(segment
		(start 47.183802 -107.604052)
		(end 46.748192 -107.839256)
		(width 0.1651)
		(layer "In5.Cu")
		(net "P5E_PEX0_STN1_RX_DN<19>")
	)
	(segment
		(start 37.73551 -119.317008)
		(end 36.36772 -120.982232)
		(width 0.1651)
		(layer "In5.Cu")
		(net "P5E_PEX0_STN1_RX_DN<19>")
	)
	(segment
		(start 47.77486 -107.414568)
		(end 47.338742 -107.65028)
		(width 0.1651)
		(layer "In5.Cu")
		(net "P5E_PEX0_STN1_RX_DN<19>")
	)
	(segment
		(start 43.411394 -110.567978)
		(end 43.055286 -110.91291)
		(width 0.1651)
		(layer "In5.Cu")
		(net "P5E_PEX0_STN1_RX_DN<19>")
	)
	(segment
		(start 40.889936 -112.850168)
		(end 37.73551 -119.317008)
		(width 0.1651)
		(layer "In5.Cu")
		(net "P5E_PEX0_STN1_RX_DN<19>")
	)
	(segment
		(start 62.165738 -271.773904)
		(end 62.165738 -271.802352)
		(width 0.1143)
		(layer "In5.Cu")
		(net "P5E_PEX0_STN1_RX_DN<19>")
	)
	(segment
		(start 42.017696 -111.758222)
		(end 40.889936 -112.850168)
		(width 0.1651)
		(layer "In5.Cu")
		(net "P5E_PEX0_STN1_RX_DN<19>")
	)
	(segment
		(start 47.821088 -107.259628)
		(end 47.77486 -107.414568)
		(width 0.1651)
		(layer "In5.Cu")
		(net "P5E_PEX0_STN1_RX_DN<19>")
	)
	(segment
		(start 51.95189 -105.28554)
		(end 51.474624 -105.28554)
		(width 0.1651)
		(layer "In5.Cu")
		(net "P5E_PEX0_STN1_RX_DN<19>")
	)
	(segment
		(start 33.667192 -122.886724)
		(end 33.004252 -126.387352)
		(width 0.1651)
		(layer "In5.Cu")
		(net "P5E_PEX0_STN1_RX_DN<19>")
	)
	(segment
		(start 43.769788 -110.06201)
		(end 43.413934 -110.406434)
		(width 0.1651)
		(layer "In5.Cu")
		(net "P5E_PEX0_STN1_RX_DN<19>")
	)
	(segment
		(start 317.705486 -34.227262)
		(end 317.410338 -34.52241)
		(width 0.13462)
		(layer "F.Cu")
		(net "P5E_PEX2_STN2_RX_DP<35>")
	)
	(segment
		(start 320.864738 -34.390076)
		(end 320.382138 -34.390076)
		(width 0.13462)
		(layer "F.Cu")
		(net "P5E_PEX2_STN2_RX_DP<35>")
	)
	(segment
		(start 320.382138 -34.390076)
		(end 320.219324 -34.227262)
		(width 0.13462)
		(layer "F.Cu")
		(net "P5E_PEX2_STN2_RX_DP<35>")
	)
	(segment
		(start 320.219324 -34.227262)
		(end 317.705486 -34.227262)
		(width 0.13462)
		(layer "F.Cu")
		(net "P5E_PEX2_STN2_RX_DP<35>")
	)
	(segment
		(start 317.612268 -34.32048)
		(end 317.826898 -34.23158)
		(width 0.1651)
		(layer "In7.Cu")
		(net "P5E_PEX2_STN2_RX_DP<35>")
	)
	(segment
		(start 288.049716 -273.784314)
		(end 288.049716 -274.049744)
		(width 0.1143)
		(layer "In7.Cu")
		(net "P5E_PEX2_STN2_RX_DP<35>")
	)
	(segment
		(start 287.760664 -266.721844)
		(end 287.433766 -270.499332)
		(width 0.1651)
		(layer "In7.Cu")
		(net "P5E_PEX2_STN2_RX_DP<35>")
	)
	(segment
		(start 318.813688 -37.11575)
		(end 318.8208 -37.610796)
		(width 0.1651)
		(layer "In7.Cu")
		(net "P5E_PEX2_STN2_RX_DP<35>")
	)
	(segment
		(start 308.70525 -143.663162)
		(end 307.328062 -154.366976)
		(width 0.1651)
		(layer "In7.Cu")
		(net "P5E_PEX2_STN2_RX_DP<35>")
	)
	(segment
		(start 287.741868 -273.670014)
		(end 287.935416 -273.670014)
		(width 0.1143)
		(layer "In7.Cu")
		(net "P5E_PEX2_STN2_RX_DP<35>")
	)
	(segment
		(start 317.410338 -34.52241)
		(end 317.612268 -34.32048)
		(width 0.1651)
		(layer "In7.Cu")
		(net "P5E_PEX2_STN2_RX_DP<35>")
	)
	(segment
		(start 287.433766 -270.499332)
		(end 287.433766 -271.345152)
		(width 0.1651)
		(layer "In7.Cu")
		(net "P5E_PEX2_STN2_RX_DP<35>")
	)
	(segment
		(start 307.328062 -154.366976)
		(end 287.760664 -266.721844)
		(width 0.1651)
		(layer "In7.Cu")
		(net "P5E_PEX2_STN2_RX_DP<35>")
	)
	(segment
		(start 287.433766 -271.345152)
		(end 287.433766 -271.3736)
		(width 0.1143)
		(layer "In7.Cu")
		(net "P5E_PEX2_STN2_RX_DP<35>")
	)
	(segment
		(start 317.826898 -34.23158)
		(end 318.178942 -34.23158)
		(width 0.1651)
		(layer "In7.Cu")
		(net "P5E_PEX2_STN2_RX_DP<35>")
	)
	(segment
		(start 287.935416 -273.670014)
		(end 288.049716 -273.784314)
		(width 0.1143)
		(layer "In7.Cu")
		(net "P5E_PEX2_STN2_RX_DP<35>")
	)
	(segment
		(start 309.022496 -116.339874)
		(end 308.70525 -143.663162)
		(width 0.1651)
		(layer "In7.Cu")
		(net "P5E_PEX2_STN2_RX_DP<35>")
	)
	(segment
		(start 318.80302 -36.391596)
		(end 318.690244 -36.507674)
		(width 0.1651)
		(layer "In7.Cu")
		(net "P5E_PEX2_STN2_RX_DP<35>")
	)
	(segment
		(start 287.479486 -273.407632)
		(end 287.741868 -273.670014)
		(width 0.1143)
		(layer "In7.Cu")
		(net "P5E_PEX2_STN2_RX_DP<35>")
	)
	(segment
		(start 287.433766 -271.3736)
		(end 287.479486 -271.41932)
		(width 0.1143)
		(layer "In7.Cu")
		(net "P5E_PEX2_STN2_RX_DP<35>")
	)
	(segment
		(start 287.479486 -271.41932)
		(end 287.479486 -273.407632)
		(width 0.1143)
		(layer "In7.Cu")
		(net "P5E_PEX2_STN2_RX_DP<35>")
	)
	(segment
		(start 318.690244 -36.507674)
		(end 318.69761 -37.002974)
		(width 0.1651)
		(layer "In7.Cu")
		(net "P5E_PEX2_STN2_RX_DP<35>")
	)
	(segment
		(start 318.715644 -38.222174)
		(end 318.831722 -38.33495)
		(width 0.1651)
		(layer "In7.Cu")
		(net "P5E_PEX2_STN2_RX_DP<35>")
	)
	(segment
		(start 318.8208 -37.610796)
		(end 318.708278 -37.72662)
		(width 0.1651)
		(layer "In7.Cu")
		(net "P5E_PEX2_STN2_RX_DP<35>")
	)
	(segment
		(start 318.831722 -38.33495)
		(end 318.850264 -39.604696)
		(width 0.1651)
		(layer "In7.Cu")
		(net "P5E_PEX2_STN2_RX_DP<35>")
	)
	(segment
		(start 318.178942 -34.23158)
		(end 318.780414 -34.833306)
		(width 0.1651)
		(layer "In7.Cu")
		(net "P5E_PEX2_STN2_RX_DP<35>")
	)
	(segment
		(start 318.69761 -37.002974)
		(end 318.813688 -37.11575)
		(width 0.1651)
		(layer "In7.Cu")
		(net "P5E_PEX2_STN2_RX_DP<35>")
	)
	(segment
		(start 320.009266 -60.960508)
		(end 309.022496 -116.339874)
		(width 0.1651)
		(layer "In7.Cu")
		(net "P5E_PEX2_STN2_RX_DP<35>")
	)
	(segment
		(start 318.850264 -39.604696)
		(end 320.188082 -49.507648)
		(width 0.1651)
		(layer "In7.Cu")
		(net "P5E_PEX2_STN2_RX_DP<35>")
	)
	(segment
		(start 320.188082 -49.507648)
		(end 320.009266 -60.960508)
		(width 0.1651)
		(layer "In7.Cu")
		(net "P5E_PEX2_STN2_RX_DP<35>")
	)
	(segment
		(start 318.780414 -34.833306)
		(end 318.80302 -36.391596)
		(width 0.1651)
		(layer "In7.Cu")
		(net "P5E_PEX2_STN2_RX_DP<35>")
	)
	(segment
		(start 318.708278 -37.72662)
		(end 318.715644 -38.222174)
		(width 0.1651)
		(layer "In7.Cu")
		(net "P5E_PEX2_STN2_RX_DP<35>")
	)
	(segment
		(start 291.808916 -328.6633)
		(end 292.255956 -328.876406)
		(width 0.1651)
		(layer "In5.Cu")
		(net "P5E_PEX2_STN6_RX_DN<107>")
	)
	(segment
		(start 279.165812 -320.0146)
		(end 279.165812 -320.043048)
		(width 0.1143)
		(layer "In5.Cu")
		(net "P5E_PEX2_STN6_RX_DN<107>")
	)
	(segment
		(start 291.767006 -328.544682)
		(end 291.808916 -328.6633)
		(width 0.1651)
		(layer "In5.Cu")
		(net "P5E_PEX2_STN6_RX_DN<107>")
	)
	(segment
		(start 335.637632 -391.008362)
		(end 337.04022 -391.8077)
		(width 0.1651)
		(layer "In5.Cu")
		(net "P5E_PEX2_STN6_RX_DN<107>")
	)
	(segment
		(start 292.863778 -329.166474)
		(end 292.864032 -329.16622)
		(width 0.1651)
		(layer "In5.Cu")
		(net "P5E_PEX2_STN6_RX_DN<107>")
	)
	(segment
		(start 340.964266 -401.181062)
		(end 340.41715 -401.181062)
		(width 0.1651)
		(layer "In5.Cu")
		(net "P5E_PEX2_STN6_RX_DN<107>")
	)
	(segment
		(start 324.719442 -377.808236)
		(end 325.121778 -378.932186)
		(width 0.1651)
		(layer "In5.Cu")
		(net "P5E_PEX2_STN6_RX_DN<107>")
	)
	(segment
		(start 337.04784 -391.811764)
		(end 340.83117 -394.278612)
		(width 0.1651)
		(layer "In5.Cu")
		(net "P5E_PEX2_STN6_RX_DN<107>")
	)
	(segment
		(start 324.719188 -377.807474)
		(end 324.719442 -377.808236)
		(width 0.1651)
		(layer "In5.Cu")
		(net "P5E_PEX2_STN6_RX_DN<107>")
	)
	(segment
		(start 325.122286 -378.932948)
		(end 327.069196 -384.372104)
		(width 0.1651)
		(layer "In5.Cu")
		(net "P5E_PEX2_STN6_RX_DN<107>")
	)
	(segment
		(start 279.499822 -316.799722)
		(end 279.499822 -316.534292)
		(width 0.1143)
		(layer "In5.Cu")
		(net "P5E_PEX2_STN6_RX_DN<107>")
	)
	(segment
		(start 317.024258 -341.108284)
		(end 317.739014 -341.82304)
		(width 0.1651)
		(layer "In5.Cu")
		(net "P5E_PEX2_STN6_RX_DN<107>")
	)
	(segment
		(start 279.385522 -316.419992)
		(end 279.234392 -316.419992)
		(width 0.1143)
		(layer "In5.Cu")
		(net "P5E_PEX2_STN6_RX_DN<107>")
	)
	(segment
		(start 292.821614 -329.047856)
		(end 292.863778 -329.166474)
		(width 0.1651)
		(layer "In5.Cu")
		(net "P5E_PEX2_STN6_RX_DN<107>")
	)
	(segment
		(start 279.120092 -319.96888)
		(end 279.165812 -320.0146)
		(width 0.1143)
		(layer "In5.Cu")
		(net "P5E_PEX2_STN6_RX_DN<107>")
	)
	(segment
		(start 292.255956 -328.876406)
		(end 292.37432 -328.834496)
		(width 0.1651)
		(layer "In5.Cu")
		(net "P5E_PEX2_STN6_RX_DN<107>")
	)
	(segment
		(start 279.165812 -320.043048)
		(end 279.165812 -321.77101)
		(width 0.1651)
		(layer "In5.Cu")
		(net "P5E_PEX2_STN6_RX_DN<107>")
	)
	(segment
		(start 279.509982 -322.604892)
		(end 280.34869 -323.197728)
		(width 0.1651)
		(layer "In5.Cu")
		(net "P5E_PEX2_STN6_RX_DN<107>")
	)
	(segment
		(start 341.21852 -394.69568)
		(end 341.416132 -395.19225)
		(width 0.1651)
		(layer "In5.Cu")
		(net "P5E_PEX2_STN6_RX_DN<107>")
	)
	(segment
		(start 279.165812 -321.77101)
		(end 279.509982 -322.604892)
		(width 0.1651)
		(layer "In5.Cu")
		(net "P5E_PEX2_STN6_RX_DN<107>")
	)
	(segment
		(start 291.319712 -328.331322)
		(end 291.767006 -328.544682)
		(width 0.1651)
		(layer "In5.Cu")
		(net "P5E_PEX2_STN6_RX_DN<107>")
	)
	(segment
		(start 279.499822 -316.534292)
		(end 279.385522 -316.419992)
		(width 0.1143)
		(layer "In5.Cu")
		(net "P5E_PEX2_STN6_RX_DN<107>")
	)
	(segment
		(start 317.739014 -358.309164)
		(end 324.719188 -377.807474)
		(width 0.1651)
		(layer "In5.Cu")
		(net "P5E_PEX2_STN6_RX_DN<107>")
	)
	(segment
		(start 292.864032 -329.16622)
		(end 313.180476 -338.855304)
		(width 0.1651)
		(layer "In5.Cu")
		(net "P5E_PEX2_STN6_RX_DN<107>")
	)
	(segment
		(start 292.37432 -328.834496)
		(end 292.821614 -329.047856)
		(width 0.1651)
		(layer "In5.Cu")
		(net "P5E_PEX2_STN6_RX_DN<107>")
	)
	(segment
		(start 327.069196 -384.372104)
		(end 328.00036 -386.583936)
		(width 0.1651)
		(layer "In5.Cu")
		(net "P5E_PEX2_STN6_RX_DN<107>")
	)
	(segment
		(start 317.739014 -341.82304)
		(end 317.739014 -358.309164)
		(width 0.1651)
		(layer "In5.Cu")
		(net "P5E_PEX2_STN6_RX_DN<107>")
	)
	(segment
		(start 340.83117 -394.278612)
		(end 341.21852 -394.69568)
		(width 0.1651)
		(layer "In5.Cu")
		(net "P5E_PEX2_STN6_RX_DN<107>")
	)
	(segment
		(start 328.00036 -386.583936)
		(end 328.437748 -387.481572)
		(width 0.1651)
		(layer "In5.Cu")
		(net "P5E_PEX2_STN6_RX_DN<107>")
	)
	(segment
		(start 313.180476 -338.855304)
		(end 317.024258 -341.108284)
		(width 0.1651)
		(layer "In5.Cu")
		(net "P5E_PEX2_STN6_RX_DN<107>")
	)
	(segment
		(start 341.416132 -395.19225)
		(end 341.416132 -400.729196)
		(width 0.1651)
		(layer "In5.Cu")
		(net "P5E_PEX2_STN6_RX_DN<107>")
	)
	(segment
		(start 325.122032 -378.932186)
		(end 325.122286 -378.932948)
		(width 0.1651)
		(layer "In5.Cu")
		(net "P5E_PEX2_STN6_RX_DN<107>")
	)
	(segment
		(start 329.370436 -388.421626)
		(end 335.637632 -391.008362)
		(width 0.1651)
		(layer "In5.Cu")
		(net "P5E_PEX2_STN6_RX_DN<107>")
	)
	(segment
		(start 279.234392 -316.419992)
		(end 279.120092 -316.534292)
		(width 0.1143)
		(layer "In5.Cu")
		(net "P5E_PEX2_STN6_RX_DN<107>")
	)
	(segment
		(start 291.201094 -328.373232)
		(end 291.319712 -328.331322)
		(width 0.1651)
		(layer "In5.Cu")
		(net "P5E_PEX2_STN6_RX_DN<107>")
	)
	(segment
		(start 341.416132 -400.729196)
		(end 340.964266 -401.181062)
		(width 0.1651)
		(layer "In5.Cu")
		(net "P5E_PEX2_STN6_RX_DN<107>")
	)
	(segment
		(start 337.04022 -391.8077)
		(end 337.04784 -391.811764)
		(width 0.1651)
		(layer "In5.Cu")
		(net "P5E_PEX2_STN6_RX_DN<107>")
	)
	(segment
		(start 340.29015 -401.308062)
		(end 340.29015 -401.690078)
		(width 0.1651)
		(layer "In5.Cu")
		(net "P5E_PEX2_STN6_RX_DN<107>")
	)
	(segment
		(start 325.121778 -378.932186)
		(end 325.122032 -378.932186)
		(width 0.1651)
		(layer "In5.Cu")
		(net "P5E_PEX2_STN6_RX_DN<107>")
	)
	(segment
		(start 280.34869 -323.197728)
		(end 291.201094 -328.373232)
		(width 0.1651)
		(layer "In5.Cu")
		(net "P5E_PEX2_STN6_RX_DN<107>")
	)
	(segment
		(start 340.41715 -401.181062)
		(end 340.29015 -401.308062)
		(width 0.1651)
		(layer "In5.Cu")
		(net "P5E_PEX2_STN6_RX_DN<107>")
	)
	(segment
		(start 279.120092 -316.534292)
		(end 279.120092 -319.96888)
		(width 0.1143)
		(layer "In5.Cu")
		(net "P5E_PEX2_STN6_RX_DN<107>")
	)
	(segment
		(start 328.437748 -387.481572)
		(end 329.370436 -388.421626)
		(width 0.1651)
		(layer "In5.Cu")
		(net "P5E_PEX2_STN6_RX_DN<107>")
	)
	(segment
		(start 399.738088 -357.463598)
		(end 400.03222 -357.75773)
		(width 0.13462)
		(layer "F.Cu")
		(net "P5E_PEX3_STN5_TX_C_DN<86>")
	)
	(segment
		(start 399.738088 -356.831138)
		(end 399.738088 -357.463598)
		(width 0.13462)
		(layer "F.Cu")
		(net "P5E_PEX3_STN5_TX_C_DN<86>")
	)
	(segment
		(start 400.05762 -356.511606)
		(end 399.738088 -356.831138)
		(width 0.13462)
		(layer "F.Cu")
		(net "P5E_PEX3_STN5_TX_C_DN<86>")
	)
	(segment
		(start 388.68985 -405.207978)
		(end 388.81685 -405.080978)
		(width 0.1651)
		(layer "In7.Cu")
		(net "P5E_PEX3_STN5_TX_C_DN<86>")
	)
	(segment
		(start 391.746486 -393.915392)
		(end 399.575782 -390.548622)
		(width 0.1651)
		(layer "In7.Cu")
		(net "P5E_PEX3_STN5_TX_C_DN<86>")
	)
	(segment
		(start 388.68985 -405.589994)
		(end 388.68985 -405.207978)
		(width 0.1651)
		(layer "In7.Cu")
		(net "P5E_PEX3_STN5_TX_C_DN<86>")
	)
	(segment
		(start 401.471892 -369.314476)
		(end 399.74139 -358.837738)
		(width 0.1651)
		(layer "In7.Cu")
		(net "P5E_PEX3_STN5_TX_C_DN<86>")
	)
	(segment
		(start 401.385278 -387.434582)
		(end 401.471892 -369.314476)
		(width 0.1651)
		(layer "In7.Cu")
		(net "P5E_PEX3_STN5_TX_C_DN<86>")
	)
	(segment
		(start 390.125966 -395.506448)
		(end 391.746486 -393.915392)
		(width 0.1651)
		(layer "In7.Cu")
		(net "P5E_PEX3_STN5_TX_C_DN<86>")
	)
	(segment
		(start 399.74139 -358.837738)
		(end 399.74139 -358.04856)
		(width 0.1651)
		(layer "In7.Cu")
		(net "P5E_PEX3_STN5_TX_C_DN<86>")
	)
	(segment
		(start 389.363966 -405.080978)
		(end 389.815832 -404.629112)
		(width 0.1651)
		(layer "In7.Cu")
		(net "P5E_PEX3_STN5_TX_C_DN<86>")
	)
	(segment
		(start 389.815832 -404.629112)
		(end 389.815832 -396.43812)
		(width 0.1651)
		(layer "In7.Cu")
		(net "P5E_PEX3_STN5_TX_C_DN<86>")
	)
	(segment
		(start 399.74139 -358.04856)
		(end 400.03222 -357.75773)
		(width 0.1651)
		(layer "In7.Cu")
		(net "P5E_PEX3_STN5_TX_C_DN<86>")
	)
	(segment
		(start 389.815832 -396.43812)
		(end 390.125966 -395.506448)
		(width 0.1651)
		(layer "In7.Cu")
		(net "P5E_PEX3_STN5_TX_C_DN<86>")
	)
	(segment
		(start 388.81685 -405.080978)
		(end 389.363966 -405.080978)
		(width 0.1651)
		(layer "In7.Cu")
		(net "P5E_PEX3_STN5_TX_C_DN<86>")
	)
	(segment
		(start 399.575782 -390.548622)
		(end 401.385278 -387.434582)
		(width 0.1651)
		(layer "In7.Cu")
		(net "P5E_PEX3_STN5_TX_C_DN<86>")
	)
	(segment
		(start 73.257664 -97.64014)
		(end 74.30008 -97.64014)
		(width 0.13208)
		(layer "F.Cu")
		(net "NIC1_MAIN_PWR_EN_R")
	)
	(via
		(at 73.279 -98.552)
		(size 0.6604)
		(drill 0.3302)
		(layers "F.Cu" "B.Cu")
		(net "NIC1_MAIN_PWR_EN_R")
	)
	(via
		(at 74.30008 -97.64014)
		(size 0.508)
		(drill 0.254)
		(layers "F.Cu" "B.Cu")
		(net "NIC1_MAIN_PWR_EN_R")
	)
	(segment
		(start 73.279 -98.552)
		(end 73.66 -98.171)
		(width 0.13208)
		(layer "B.Cu")
		(net "NIC1_MAIN_PWR_EN_R")
	)
	(segment
		(start 73.76922 -98.171)
		(end 74.30008 -97.64014)
		(width 0.13208)
		(layer "B.Cu")
		(net "NIC1_MAIN_PWR_EN_R")
	)
	(segment
		(start 72.15505 -98.552)
		(end 73.279 -98.552)
		(width 0.13208)
		(layer "B.Cu")
		(net "NIC1_MAIN_PWR_EN_R")
	)
	(segment
		(start 73.66 -98.171)
		(end 73.76922 -98.171)
		(width 0.13208)
		(layer "B.Cu")
		(net "NIC1_MAIN_PWR_EN_R")
	)
	(segment
		(start 51.293268 -124.917962)
		(end 51.130454 -124.755148)
		(width 0.13462)
		(layer "F.Cu")
		(net "P5E_PEX0_STN1_RX_DP<27>")
	)
	(segment
		(start 52.24272 -124.622814)
		(end 52.24272 -124.623068)
		(width 0.13462)
		(layer "F.Cu")
		(net "P5E_PEX0_STN1_RX_DP<27>")
	)
	(segment
		(start 51.947826 -124.917962)
		(end 51.293268 -124.917962)
		(width 0.13462)
		(layer "F.Cu")
		(net "P5E_PEX0_STN1_RX_DP<27>")
	)
	(segment
		(start 52.24272 -124.623068)
		(end 51.947826 -124.917962)
		(width 0.13462)
		(layer "F.Cu")
		(net "P5E_PEX0_STN1_RX_DP<27>")
	)
	(segment
		(start 51.130454 -124.755148)
		(end 50.64252 -124.755148)
		(width 0.13462)
		(layer "F.Cu")
		(net "P5E_PEX0_STN1_RX_DP<27>")
	)
	(segment
		(start 39.79926 -147.60702)
		(end 40.408352 -157.041342)
		(width 0.1651)
		(layer "In5.Cu")
		(net "P5E_PEX0_STN1_RX_DP<27>")
	)
	(segment
		(start 69.483732 -267.785596)
		(end 69.483732 -271.773904)
		(width 0.1651)
		(layer "In5.Cu")
		(net "P5E_PEX0_STN1_RX_DP<27>")
	)
	(segment
		(start 50.969418 -125.45314)
		(end 50.49139 -126.607316)
		(width 0.1651)
		(layer "In5.Cu")
		(net "P5E_PEX0_STN1_RX_DP<27>")
	)
	(segment
		(start 42.020744 -143.910304)
		(end 40.066214 -146.533108)
		(width 0.1651)
		(layer "In5.Cu")
		(net "P5E_PEX0_STN1_RX_DP<27>")
	)
	(segment
		(start 69.483732 -271.773904)
		(end 69.483732 -271.802352)
		(width 0.1143)
		(layer "In5.Cu")
		(net "P5E_PEX0_STN1_RX_DP<27>")
	)
	(segment
		(start 48.221138 -132.492242)
		(end 47.692564 -133.614922)
		(width 0.1651)
		(layer "In5.Cu")
		(net "P5E_PEX0_STN1_RX_DP<27>")
	)
	(segment
		(start 52.24272 -124.622814)
		(end 51.95189 -124.913644)
		(width 0.1651)
		(layer "In5.Cu")
		(net "P5E_PEX0_STN1_RX_DP<27>")
	)
	(segment
		(start 39.799006 -147.60702)
		(end 39.79926 -147.60702)
		(width 0.1651)
		(layer "In5.Cu")
		(net "P5E_PEX0_STN1_RX_DP<27>")
	)
	(segment
		(start 69.483732 -271.802352)
		(end 69.529452 -271.848072)
		(width 0.1143)
		(layer "In5.Cu")
		(net "P5E_PEX0_STN1_RX_DP<27>")
	)
	(segment
		(start 41.183306 -161.41446)
		(end 69.483732 -267.785596)
		(width 0.1651)
		(layer "In5.Cu")
		(net "P5E_PEX0_STN1_RX_DP<27>")
	)
	(segment
		(start 49.506378 -130.590798)
		(end 48.221138 -132.492242)
		(width 0.1651)
		(layer "In5.Cu")
		(net "P5E_PEX0_STN1_RX_DP<27>")
	)
	(segment
		(start 43.001438 -142.94231)
		(end 42.020744 -143.910304)
		(width 0.1651)
		(layer "In5.Cu")
		(net "P5E_PEX0_STN1_RX_DP<27>")
	)
	(segment
		(start 50.49139 -126.607316)
		(end 50.49139 -128.23317)
		(width 0.1651)
		(layer "In5.Cu")
		(net "P5E_PEX0_STN1_RX_DP<27>")
	)
	(segment
		(start 70.099428 -275.684488)
		(end 70.099428 -275.949918)
		(width 0.1143)
		(layer "In5.Cu")
		(net "P5E_PEX0_STN1_RX_DP<27>")
	)
	(segment
		(start 45.192442 -140.950442)
		(end 43.001438 -142.94231)
		(width 0.1651)
		(layer "In5.Cu")
		(net "P5E_PEX0_STN1_RX_DP<27>")
	)
	(segment
		(start 69.985128 -275.570188)
		(end 70.099428 -275.684488)
		(width 0.1143)
		(layer "In5.Cu")
		(net "P5E_PEX0_STN1_RX_DP<27>")
	)
	(segment
		(start 51.95189 -124.913644)
		(end 51.508914 -124.913644)
		(width 0.1651)
		(layer "In5.Cu")
		(net "P5E_PEX0_STN1_RX_DP<27>")
	)
	(segment
		(start 45.34408 -140.451078)
		(end 45.344334 -140.451078)
		(width 0.1651)
		(layer "In5.Cu")
		(net "P5E_PEX0_STN1_RX_DP<27>")
	)
	(segment
		(start 39.796212 -147.561554)
		(end 39.799006 -147.60702)
		(width 0.1651)
		(layer "In5.Cu")
		(net "P5E_PEX0_STN1_RX_DP<27>")
	)
	(segment
		(start 47.69231 -133.61543)
		(end 46.928278 -135.238236)
		(width 0.1651)
		(layer "In5.Cu")
		(net "P5E_PEX0_STN1_RX_DP<27>")
	)
	(segment
		(start 50.49139 -128.23317)
		(end 50.04308 -129.306066)
		(width 0.1651)
		(layer "In5.Cu")
		(net "P5E_PEX0_STN1_RX_DP<27>")
	)
	(segment
		(start 40.408352 -157.041342)
		(end 41.183306 -161.41446)
		(width 0.1651)
		(layer "In5.Cu")
		(net "P5E_PEX0_STN1_RX_DP<27>")
	)
	(segment
		(start 69.529452 -275.355304)
		(end 69.744336 -275.570188)
		(width 0.1143)
		(layer "In5.Cu")
		(net "P5E_PEX0_STN1_RX_DP<27>")
	)
	(segment
		(start 50.042826 -129.306574)
		(end 49.506378 -130.590798)
		(width 0.1651)
		(layer "In5.Cu")
		(net "P5E_PEX0_STN1_RX_DP<27>")
	)
	(segment
		(start 40.066214 -146.533108)
		(end 39.796212 -147.561554)
		(width 0.1651)
		(layer "In5.Cu")
		(net "P5E_PEX0_STN1_RX_DP<27>")
	)
	(segment
		(start 51.508914 -124.913644)
		(end 50.969418 -125.45314)
		(width 0.1651)
		(layer "In5.Cu")
		(net "P5E_PEX0_STN1_RX_DP<27>")
	)
	(segment
		(start 45.344334 -140.451078)
		(end 45.192442 -140.950442)
		(width 0.1651)
		(layer "In5.Cu")
		(net "P5E_PEX0_STN1_RX_DP<27>")
	)
	(segment
		(start 47.692564 -133.614922)
		(end 47.69231 -133.61543)
		(width 0.1651)
		(layer "In5.Cu")
		(net "P5E_PEX0_STN1_RX_DP<27>")
	)
	(segment
		(start 50.04308 -129.306066)
		(end 50.042826 -129.306574)
		(width 0.1651)
		(layer "In5.Cu")
		(net "P5E_PEX0_STN1_RX_DP<27>")
	)
	(segment
		(start 69.529452 -271.848072)
		(end 69.529452 -275.355304)
		(width 0.1143)
		(layer "In5.Cu")
		(net "P5E_PEX0_STN1_RX_DP<27>")
	)
	(segment
		(start 69.744336 -275.570188)
		(end 69.985128 -275.570188)
		(width 0.1143)
		(layer "In5.Cu")
		(net "P5E_PEX0_STN1_RX_DP<27>")
	)
	(segment
		(start 46.928278 -135.238236)
		(end 45.34408 -140.451078)
		(width 0.1651)
		(layer "In5.Cu")
		(net "P5E_PEX0_STN1_RX_DP<27>")
	)
	(segment
		(start 304.367692 -30.94609)
		(end 304.054002 -30.6324)
		(width 0.13462)
		(layer "F.Cu")
		(net "P5E_PEX2_STN2_TX_C_DP<37>")
	)
	(segment
		(start 299.965364 -30.790134)
		(end 299.46473 -30.790134)
		(width 0.13462)
		(layer "F.Cu")
		(net "P5E_PEX2_STN2_TX_C_DP<37>")
	)
	(segment
		(start 304.054002 -30.6324)
		(end 300.123098 -30.6324)
		(width 0.13462)
		(layer "F.Cu")
		(net "P5E_PEX2_STN2_TX_C_DP<37>")
	)
	(segment
		(start 300.123098 -30.6324)
		(end 299.965364 -30.790134)
		(width 0.13462)
		(layer "F.Cu")
		(net "P5E_PEX2_STN2_TX_C_DP<37>")
	)
	(segment
		(start 342.490044 -376.408188)
		(end 342.617044 -376.281188)
		(width 0.1651)
		(layer "In9.Cu")
		(net "P5E_PEX2_STN6_RX_DN<98>")
	)
	(segment
		(start 323.505322 -341.2363)
		(end 295.23436 -330.258674)
		(width 0.1651)
		(layer "In9.Cu")
		(net "P5E_PEX2_STN6_RX_DN<98>")
	)
	(segment
		(start 343.616026 -369.34902)
		(end 343.23782 -368.40414)
		(width 0.1651)
		(layer "In9.Cu")
		(net "P5E_PEX2_STN6_RX_DN<98>")
	)
	(segment
		(start 287.974278 -324.395338)
		(end 287.71596 -323.771006)
		(width 0.1651)
		(layer "In9.Cu")
		(net "P5E_PEX2_STN6_RX_DN<98>")
	)
	(segment
		(start 324.35546 -358.902)
		(end 323.956934 -358.503474)
		(width 0.1651)
		(layer "In9.Cu")
		(net "P5E_PEX2_STN6_RX_DN<98>")
	)
	(segment
		(start 287.71596 -323.771006)
		(end 287.715706 -323.770752)
		(width 0.1651)
		(layer "In9.Cu")
		(net "P5E_PEX2_STN6_RX_DN<98>")
	)
	(segment
		(start 343.616026 -375.829322)
		(end 343.616026 -369.34902)
		(width 0.1651)
		(layer "In9.Cu")
		(net "P5E_PEX2_STN6_RX_DN<98>")
	)
	(segment
		(start 342.490044 -376.790204)
		(end 342.490044 -376.408188)
		(width 0.1651)
		(layer "In9.Cu")
		(net "P5E_PEX2_STN6_RX_DN<98>")
	)
	(segment
		(start 343.23782 -368.40414)
		(end 338.2899 -364.91672)
		(width 0.1651)
		(layer "In9.Cu")
		(net "P5E_PEX2_STN6_RX_DN<98>")
	)
	(segment
		(start 323.956934 -342.28024)
		(end 323.505322 -341.2363)
		(width 0.1651)
		(layer "In9.Cu")
		(net "P5E_PEX2_STN6_RX_DN<98>")
	)
	(segment
		(start 323.956934 -358.503474)
		(end 323.956934 -342.28024)
		(width 0.1651)
		(layer "In9.Cu")
		(net "P5E_PEX2_STN6_RX_DN<98>")
	)
	(segment
		(start 287.669986 -319.84188)
		(end 287.669986 -318.434212)
		(width 0.1143)
		(layer "In9.Cu")
		(net "P5E_PEX2_STN6_RX_DN<98>")
	)
	(segment
		(start 287.784032 -318.320166)
		(end 287.960816 -318.320166)
		(width 0.1143)
		(layer "In9.Cu")
		(net "P5E_PEX2_STN6_RX_DN<98>")
	)
	(segment
		(start 295.23436 -330.258674)
		(end 291.218366 -327.639426)
		(width 0.1651)
		(layer "In9.Cu")
		(net "P5E_PEX2_STN6_RX_DN<98>")
	)
	(segment
		(start 288.049716 -318.409066)
		(end 288.049716 -318.699896)
		(width 0.1143)
		(layer "In9.Cu")
		(net "P5E_PEX2_STN6_RX_DN<98>")
	)
	(segment
		(start 287.960816 -318.320166)
		(end 288.049716 -318.409066)
		(width 0.1143)
		(layer "In9.Cu")
		(net "P5E_PEX2_STN6_RX_DN<98>")
	)
	(segment
		(start 287.715706 -323.770752)
		(end 287.715706 -319.916048)
		(width 0.1651)
		(layer "In9.Cu")
		(net "P5E_PEX2_STN6_RX_DN<98>")
	)
	(segment
		(start 342.617044 -376.281188)
		(end 343.16416 -376.281188)
		(width 0.1651)
		(layer "In9.Cu")
		(net "P5E_PEX2_STN6_RX_DN<98>")
	)
	(segment
		(start 287.669986 -318.434212)
		(end 287.784032 -318.320166)
		(width 0.1143)
		(layer "In9.Cu")
		(net "P5E_PEX2_STN6_RX_DN<98>")
	)
	(segment
		(start 287.715706 -319.8876)
		(end 287.669986 -319.84188)
		(width 0.1143)
		(layer "In9.Cu")
		(net "P5E_PEX2_STN6_RX_DN<98>")
	)
	(segment
		(start 291.218366 -327.639426)
		(end 287.974278 -324.395338)
		(width 0.1651)
		(layer "In9.Cu")
		(net "P5E_PEX2_STN6_RX_DN<98>")
	)
	(segment
		(start 338.2899 -364.91672)
		(end 324.35546 -358.902)
		(width 0.1651)
		(layer "In9.Cu")
		(net "P5E_PEX2_STN6_RX_DN<98>")
	)
	(segment
		(start 343.16416 -376.281188)
		(end 343.616026 -375.829322)
		(width 0.1651)
		(layer "In9.Cu")
		(net "P5E_PEX2_STN6_RX_DN<98>")
	)
	(segment
		(start 287.715706 -319.916048)
		(end 287.715706 -319.8876)
		(width 0.1143)
		(layer "In9.Cu")
		(net "P5E_PEX2_STN6_RX_DN<98>")
	)
	(segment
		(start 389.81634 -350.365314)
		(end 390.136888 -350.685862)
		(width 0.13462)
		(layer "F.Cu")
		(net "P5E_PEX3_STN5_TX_C_DP<81>")
	)
	(segment
		(start 390.136888 -350.685862)
		(end 390.136888 -351.31629)
		(width 0.13462)
		(layer "F.Cu")
		(net "P5E_PEX3_STN5_TX_C_DP<81>")
	)
	(segment
		(start 390.136888 -351.31629)
		(end 389.84174 -351.611438)
		(width 0.13462)
		(layer "F.Cu")
		(net "P5E_PEX3_STN5_TX_C_DP<81>")
	)
	(segment
		(start 396.26032 -369.84178)
		(end 396.06728 -385.87426)
		(width 0.1651)
		(layer "In7.Cu")
		(net "P5E_PEX3_STN5_TX_C_DP<81>")
	)
	(segment
		(start 395.8463 -386.39496)
		(end 383.45872 -391.35558)
		(width 0.1651)
		(layer "In7.Cu")
		(net "P5E_PEX3_STN5_TX_C_DP<81>")
	)
	(segment
		(start 388.57809 -353.910646)
		(end 388.57809 -358.38892)
		(width 0.1651)
		(layer "In7.Cu")
		(net "P5E_PEX3_STN5_TX_C_DP<81>")
	)
	(segment
		(start 390.13257 -352.356166)
		(end 388.57809 -353.910646)
		(width 0.1651)
		(layer "In7.Cu")
		(net "P5E_PEX3_STN5_TX_C_DP<81>")
	)
	(segment
		(start 393.400534 -365.17961)
		(end 393.691872 -365.580422)
		(width 0.1651)
		(layer "In7.Cu")
		(net "P5E_PEX3_STN5_TX_C_DP<81>")
	)
	(segment
		(start 393.420092 -365.055404)
		(end 393.400534 -365.17961)
		(width 0.1651)
		(layer "In7.Cu")
		(net "P5E_PEX3_STN5_TX_C_DP<81>")
	)
	(segment
		(start 388.57809 -358.38892)
		(end 393.420092 -365.055404)
		(width 0.1651)
		(layer "In7.Cu")
		(net "P5E_PEX3_STN5_TX_C_DP<81>")
	)
	(segment
		(start 396.06728 -385.87426)
		(end 395.8463 -386.39496)
		(width 0.1651)
		(layer "In7.Cu")
		(net "P5E_PEX3_STN5_TX_C_DP<81>")
	)
	(segment
		(start 390.13257 -351.902268)
		(end 390.13257 -352.356166)
		(width 0.1651)
		(layer "In7.Cu")
		(net "P5E_PEX3_STN5_TX_C_DP<81>")
	)
	(segment
		(start 378.533914 -405.612346)
		(end 378.247148 -405.899112)
		(width 0.1651)
		(layer "In7.Cu")
		(net "P5E_PEX3_STN5_TX_C_DP<81>")
	)
	(segment
		(start 383.45872 -391.35558)
		(end 378.817378 -394.595604)
		(width 0.1651)
		(layer "In7.Cu")
		(net "P5E_PEX3_STN5_TX_C_DP<81>")
	)
	(segment
		(start 395.75486 -368.26952)
		(end 396.26032 -369.84178)
		(width 0.1651)
		(layer "In7.Cu")
		(net "P5E_PEX3_STN5_TX_C_DP<81>")
	)
	(segment
		(start 377.816872 -405.899112)
		(end 377.689872 -405.772112)
		(width 0.1651)
		(layer "In7.Cu")
		(net "P5E_PEX3_STN5_TX_C_DP<81>")
	)
	(segment
		(start 378.817378 -394.595604)
		(end 378.533914 -396.0622)
		(width 0.1651)
		(layer "In7.Cu")
		(net "P5E_PEX3_STN5_TX_C_DP<81>")
	)
	(segment
		(start 378.533914 -396.0622)
		(end 378.533914 -405.612346)
		(width 0.1651)
		(layer "In7.Cu")
		(net "P5E_PEX3_STN5_TX_C_DP<81>")
	)
	(segment
		(start 377.689872 -405.772112)
		(end 377.689872 -405.390096)
		(width 0.1651)
		(layer "In7.Cu")
		(net "P5E_PEX3_STN5_TX_C_DP<81>")
	)
	(segment
		(start 389.84174 -351.611438)
		(end 390.13257 -351.902268)
		(width 0.1651)
		(layer "In7.Cu")
		(net "P5E_PEX3_STN5_TX_C_DP<81>")
	)
	(segment
		(start 378.247148 -405.899112)
		(end 377.816872 -405.899112)
		(width 0.1651)
		(layer "In7.Cu")
		(net "P5E_PEX3_STN5_TX_C_DP<81>")
	)
	(segment
		(start 393.691872 -365.580422)
		(end 393.816078 -365.600234)
		(width 0.1651)
		(layer "In7.Cu")
		(net "P5E_PEX3_STN5_TX_C_DP<81>")
	)
	(segment
		(start 393.816078 -365.600234)
		(end 395.75486 -368.26952)
		(width 0.1651)
		(layer "In7.Cu")
		(net "P5E_PEX3_STN5_TX_C_DP<81>")
	)
	(segment
		(start 75.276964 -98.840036)
		(end 75.946 -98.171)
		(width 0.13208)
		(layer "F.Cu")
		(net "NIC1_DATA_IN")
	)
	(segment
		(start 73.257664 -98.840036)
		(end 75.276964 -98.840036)
		(width 0.13208)
		(layer "F.Cu")
		(net "NIC1_DATA_IN")
	)
	(via
		(at 75.946 -98.171)
		(size 0.508)
		(drill 0.254)
		(layers "F.Cu" "B.Cu")
		(net "NIC1_DATA_IN")
	)
	(segment
		(start 77.141832 -97.005648)
		(end 75.97648 -98.171)
		(width 0.13208)
		(layer "B.Cu")
		(net "NIC1_DATA_IN")
	)
	(segment
		(start 75.97648 -98.171)
		(end 75.946 -98.171)
		(width 0.13208)
		(layer "B.Cu")
		(net "NIC1_DATA_IN")
	)
	(segment
		(start 39.868348 -103.48214)
		(end 45.391578 -103.48214)
		(width 0.13462)
		(layer "F.Cu")
		(net "P5E_PEX0_STN1_TX_C_DN<18>")
	)
	(segment
		(start 45.391578 -103.48214)
		(end 45.554392 -103.644954)
		(width 0.13462)
		(layer "F.Cu")
		(net "P5E_PEX0_STN1_TX_C_DN<18>")
	)
	(segment
		(start 39.547292 -103.803196)
		(end 39.868348 -103.48214)
		(width 0.13462)
		(layer "F.Cu")
		(net "P5E_PEX0_STN1_TX_C_DN<18>")
	)
	(segment
		(start 45.554392 -103.644954)
		(end 46.042326 -103.644954)
		(width 0.13462)
		(layer "F.Cu")
		(net "P5E_PEX0_STN1_TX_C_DN<18>")
	)
	(segment
		(start 80.594962 -345.170506)
		(end 80.594962 -344.539062)
		(width 0.13462)
		(layer "F.Cu")
		(net "P5E_PEX0_STN6_TX_C_DN<103>")
	)
	(segment
		(start 80.594962 -344.539062)
		(end 80.915002 -344.219022)
		(width 0.13462)
		(layer "F.Cu")
		(net "P5E_PEX0_STN6_TX_C_DN<103>")
	)
	(segment
		(start 80.889602 -345.465146)
		(end 80.594962 -345.170506)
		(width 0.13462)
		(layer "F.Cu")
		(net "P5E_PEX0_STN6_TX_C_DN<103>")
	)
	(segment
		(start 71.90994 -383.490216)
		(end 71.90994 -383.1082)
		(width 0.1651)
		(layer "In13.Cu")
		(net "P5E_PEX0_STN6_TX_C_DN<103>")
	)
	(segment
		(start 73.084182 -382.540764)
		(end 73.084182 -369.033044)
		(width 0.1651)
		(layer "In13.Cu")
		(net "P5E_PEX0_STN6_TX_C_DN<103>")
	)
	(segment
		(start 73.084182 -369.033044)
		(end 79.044292 -358.512618)
		(width 0.1651)
		(layer "In13.Cu")
		(net "P5E_PEX0_STN6_TX_C_DN<103>")
	)
	(segment
		(start 79.044292 -347.983048)
		(end 80.598772 -346.428568)
		(width 0.1651)
		(layer "In13.Cu")
		(net "P5E_PEX0_STN6_TX_C_DN<103>")
	)
	(segment
		(start 72.03694 -382.9812)
		(end 72.643746 -382.9812)
		(width 0.1651)
		(layer "In13.Cu")
		(net "P5E_PEX0_STN6_TX_C_DN<103>")
	)
	(segment
		(start 71.90994 -383.1082)
		(end 72.03694 -382.9812)
		(width 0.1651)
		(layer "In13.Cu")
		(net "P5E_PEX0_STN6_TX_C_DN<103>")
	)
	(segment
		(start 72.643746 -382.9812)
		(end 73.084182 -382.540764)
		(width 0.1651)
		(layer "In13.Cu")
		(net "P5E_PEX0_STN6_TX_C_DN<103>")
	)
	(segment
		(start 79.044292 -358.512618)
		(end 79.044292 -347.983048)
		(width 0.1651)
		(layer "In13.Cu")
		(net "P5E_PEX0_STN6_TX_C_DN<103>")
	)
	(segment
		(start 80.598772 -346.428568)
		(end 80.598772 -345.755976)
		(width 0.1651)
		(layer "In13.Cu")
		(net "P5E_PEX0_STN6_TX_C_DN<103>")
	)
	(segment
		(start 80.598772 -345.755976)
		(end 80.889602 -345.465146)
		(width 0.1651)
		(layer "In13.Cu")
		(net "P5E_PEX0_STN6_TX_C_DN<103>")
	)
	(segment
		(start 274.12315 -30.6324)
		(end 273.965416 -30.790134)
		(width 0.13462)
		(layer "F.Cu")
		(net "P5E_PEX2_STN2_TX_C_DP<41>")
	)
	(segment
		(start 278.054054 -30.6324)
		(end 274.12315 -30.6324)
		(width 0.13462)
		(layer "F.Cu")
		(net "P5E_PEX2_STN2_TX_C_DP<41>")
	)
	(segment
		(start 278.367744 -30.94609)
		(end 278.054054 -30.6324)
		(width 0.13462)
		(layer "F.Cu")
		(net "P5E_PEX2_STN2_TX_C_DP<41>")
	)
	(segment
		(start 273.965416 -30.790134)
		(end 273.464782 -30.790134)
		(width 0.13462)
		(layer "F.Cu")
		(net "P5E_PEX2_STN2_TX_C_DP<41>")
	)
	(segment
		(start 319.015364 -356.831646)
		(end 318.695324 -356.511606)
		(width 0.13462)
		(layer "F.Cu")
		(net "P5E_PEX2_STN6_TX_C_DP<108>")
	)
	(segment
		(start 318.720724 -357.75773)
		(end 319.015364 -357.46309)
		(width 0.13462)
		(layer "F.Cu")
		(net "P5E_PEX2_STN6_TX_C_DP<108>")
	)
	(segment
		(start 319.015364 -357.46309)
		(end 319.015364 -356.831646)
		(width 0.13462)
		(layer "F.Cu")
		(net "P5E_PEX2_STN6_TX_C_DP<108>")
	)
	(segment
		(start 335.01203 -392.021822)
		(end 329.952604 -390.247632)
		(width 0.1651)
		(layer "In13.Cu")
		(net "P5E_PEX2_STN6_TX_C_DP<108>")
	)
	(segment
		(start 338.647278 -409.799028)
		(end 338.934044 -409.512262)
		(width 0.1651)
		(layer "In13.Cu")
		(net "P5E_PEX2_STN6_TX_C_DP<108>")
	)
	(segment
		(start 337.631786 -393.816586)
		(end 335.01203 -392.021822)
		(width 0.1651)
		(layer "In13.Cu")
		(net "P5E_PEX2_STN6_TX_C_DP<108>")
	)
	(segment
		(start 338.934044 -395.7447)
		(end 338.762848 -395.140434)
		(width 0.1651)
		(layer "In13.Cu")
		(net "P5E_PEX2_STN6_TX_C_DP<108>")
	)
	(segment
		(start 338.934044 -409.512262)
		(end 338.934044 -395.7447)
		(width 0.1651)
		(layer "In13.Cu")
		(net "P5E_PEX2_STN6_TX_C_DP<108>")
	)
	(segment
		(start 338.762848 -395.140434)
		(end 337.631786 -393.816586)
		(width 0.1651)
		(layer "In13.Cu")
		(net "P5E_PEX2_STN6_TX_C_DP<108>")
	)
	(segment
		(start 326.605392 -387.491224)
		(end 319.020952 -358.99725)
		(width 0.1651)
		(layer "In13.Cu")
		(net "P5E_PEX2_STN6_TX_C_DP<108>")
	)
	(segment
		(start 338.090002 -409.290012)
		(end 338.090002 -409.672028)
		(width 0.1651)
		(layer "In13.Cu")
		(net "P5E_PEX2_STN6_TX_C_DP<108>")
	)
	(segment
		(start 319.020952 -358.99725)
		(end 319.011554 -358.987852)
		(width 0.1651)
		(layer "In13.Cu")
		(net "P5E_PEX2_STN6_TX_C_DP<108>")
	)
	(segment
		(start 338.217002 -409.799028)
		(end 338.647278 -409.799028)
		(width 0.1651)
		(layer "In13.Cu")
		(net "P5E_PEX2_STN6_TX_C_DP<108>")
	)
	(segment
		(start 338.090002 -409.672028)
		(end 338.217002 -409.799028)
		(width 0.1651)
		(layer "In13.Cu")
		(net "P5E_PEX2_STN6_TX_C_DP<108>")
	)
	(segment
		(start 319.011554 -358.987852)
		(end 319.011554 -358.04856)
		(width 0.1651)
		(layer "In13.Cu")
		(net "P5E_PEX2_STN6_TX_C_DP<108>")
	)
	(segment
		(start 319.011554 -358.04856)
		(end 318.720724 -357.75773)
		(width 0.1651)
		(layer "In13.Cu")
		(net "P5E_PEX2_STN6_TX_C_DP<108>")
	)
	(segment
		(start 329.952604 -390.247632)
		(end 326.605392 -387.491224)
		(width 0.1651)
		(layer "In13.Cu")
		(net "P5E_PEX2_STN6_TX_C_DP<108>")
	)
	(segment
		(start 396.94866 -350.365314)
		(end 396.629128 -350.684846)
		(width 0.13462)
		(layer "F.Cu")
		(net "P5E_PEX3_STN5_TX_C_DN<84>")
	)
	(segment
		(start 396.629128 -351.317306)
		(end 396.92326 -351.611438)
		(width 0.13462)
		(layer "F.Cu")
		(net "P5E_PEX3_STN5_TX_C_DN<84>")
	)
	(segment
		(start 396.629128 -350.684846)
		(end 396.629128 -351.317306)
		(width 0.13462)
		(layer "F.Cu")
		(net "P5E_PEX3_STN5_TX_C_DN<84>")
	)
	(segment
		(start 396.63243 -352.473006)
		(end 396.63243 -351.902268)
		(width 0.1651)
		(layer "In7.Cu")
		(net "P5E_PEX3_STN5_TX_C_DN<84>")
	)
	(segment
		(start 399.057114 -367.415826)
		(end 395.07795 -358.718612)
		(width 0.1651)
		(layer "In7.Cu")
		(net "P5E_PEX3_STN5_TX_C_DN<84>")
	)
	(segment
		(start 399.539968 -369.684808)
		(end 399.057114 -367.415826)
		(width 0.1651)
		(layer "In7.Cu")
		(net "P5E_PEX3_STN5_TX_C_DN<84>")
	)
	(segment
		(start 385.416044 -395.600682)
		(end 387.735064 -393.37234)
		(width 0.1651)
		(layer "In7.Cu")
		(net "P5E_PEX3_STN5_TX_C_DN<84>")
	)
	(segment
		(start 384.290062 -405.207978)
		(end 384.417062 -405.080978)
		(width 0.1651)
		(layer "In7.Cu")
		(net "P5E_PEX3_STN5_TX_C_DN<84>")
	)
	(segment
		(start 399.258536 -387.006846)
		(end 399.539968 -369.684808)
		(width 0.1651)
		(layer "In7.Cu")
		(net "P5E_PEX3_STN5_TX_C_DN<84>")
	)
	(segment
		(start 385.416044 -404.629112)
		(end 385.416044 -395.600682)
		(width 0.1651)
		(layer "In7.Cu")
		(net "P5E_PEX3_STN5_TX_C_DN<84>")
	)
	(segment
		(start 396.63243 -351.902268)
		(end 396.92326 -351.611438)
		(width 0.1651)
		(layer "In7.Cu")
		(net "P5E_PEX3_STN5_TX_C_DN<84>")
	)
	(segment
		(start 398.157954 -388.97306)
		(end 399.258536 -387.006846)
		(width 0.1651)
		(layer "In7.Cu")
		(net "P5E_PEX3_STN5_TX_C_DN<84>")
	)
	(segment
		(start 384.964178 -405.080978)
		(end 385.416044 -404.629112)
		(width 0.1651)
		(layer "In7.Cu")
		(net "P5E_PEX3_STN5_TX_C_DN<84>")
	)
	(segment
		(start 387.735064 -393.37234)
		(end 398.157954 -388.97306)
		(width 0.1651)
		(layer "In7.Cu")
		(net "P5E_PEX3_STN5_TX_C_DN<84>")
	)
	(segment
		(start 384.290062 -405.589994)
		(end 384.290062 -405.207978)
		(width 0.1651)
		(layer "In7.Cu")
		(net "P5E_PEX3_STN5_TX_C_DN<84>")
	)
	(segment
		(start 384.417062 -405.080978)
		(end 384.964178 -405.080978)
		(width 0.1651)
		(layer "In7.Cu")
		(net "P5E_PEX3_STN5_TX_C_DN<84>")
	)
	(segment
		(start 395.07795 -354.027486)
		(end 396.63243 -352.473006)
		(width 0.1651)
		(layer "In7.Cu")
		(net "P5E_PEX3_STN5_TX_C_DN<84>")
	)
	(segment
		(start 395.07795 -358.718612)
		(end 395.07795 -354.027486)
		(width 0.1651)
		(layer "In7.Cu")
		(net "P5E_PEX3_STN5_TX_C_DN<84>")
	)
	(segment
		(start 61.620146 -104.840024)
		(end 61.610494 -104.830372)
		(width 0.13208)
		(layer "F.Cu")
		(net "CLK_50M_NIC1_RBT_REF")
	)
	(segment
		(start 68.65747 -104.840024)
		(end 61.620146 -104.840024)
		(width 0.13208)
		(layer "F.Cu")
		(net "CLK_50M_NIC1_RBT_REF")
	)
	(segment
		(start 61.610494 -104.830372)
		(end 59.395106 -104.830372)
		(width 0.13208)
		(layer "F.Cu")
		(net "CLK_50M_NIC1_RBT_REF")
	)
	(via
		(at 61.610494 -104.830372)
		(size 0.762)
		(drill 0.381)
		(layers "F.Cu" "B.Cu")
		(net "CLK_50M_NIC1_RBT_REF")
	)
	(segment
		(start 45.554392 -112.044988)
		(end 46.042326 -112.044988)
		(width 0.13462)
		(layer "F.Cu")
		(net "P5E_PEX0_STN1_TX_C_DN<23>")
	)
	(segment
		(start 36.905184 -111.895382)
		(end 37.217604 -112.207802)
		(width 0.13462)
		(layer "F.Cu")
		(net "P5E_PEX0_STN1_TX_C_DN<23>")
	)
	(segment
		(start 37.217604 -112.207802)
		(end 45.391578 -112.207802)
		(width 0.13462)
		(layer "F.Cu")
		(net "P5E_PEX0_STN1_TX_C_DN<23>")
	)
	(segment
		(start 45.391578 -112.207802)
		(end 45.554392 -112.044988)
		(width 0.13462)
		(layer "F.Cu")
		(net "P5E_PEX0_STN1_TX_C_DN<23>")
	)
	(segment
		(start 89.647522 -350.685354)
		(end 89.327482 -350.365314)
		(width 0.13462)
		(layer "F.Cu")
		(net "P5E_PEX0_STN6_TX_C_DP<98>")
	)
	(segment
		(start 89.647522 -351.316798)
		(end 89.647522 -350.685354)
		(width 0.13462)
		(layer "F.Cu")
		(net "P5E_PEX0_STN6_TX_C_DP<98>")
	)
	(segment
		(start 89.352882 -351.611438)
		(end 89.647522 -351.316798)
		(width 0.13462)
		(layer "F.Cu")
		(net "P5E_PEX0_STN6_TX_C_DP<98>")
	)
	(segment
		(start 89.643712 -351.902268)
		(end 89.352882 -351.611438)
		(width 0.1651)
		(layer "In13.Cu")
		(net "P5E_PEX0_STN6_TX_C_DP<98>")
	)
	(segment
		(start 85.13953 -365.678466)
		(end 85.097112 -365.560102)
		(width 0.1651)
		(layer "In13.Cu")
		(net "P5E_PEX0_STN6_TX_C_DP<98>")
	)
	(segment
		(start 82.909918 -383.67208)
		(end 83.036918 -383.79908)
		(width 0.1651)
		(layer "In13.Cu")
		(net "P5E_PEX0_STN6_TX_C_DP<98>")
	)
	(segment
		(start 85.097112 -365.560102)
		(end 85.309202 -365.112046)
		(width 0.1651)
		(layer "In13.Cu")
		(net "P5E_PEX0_STN6_TX_C_DP<98>")
	)
	(segment
		(start 84.927948 -366.126014)
		(end 85.13953 -365.678466)
		(width 0.1651)
		(layer "In13.Cu")
		(net "P5E_PEX0_STN6_TX_C_DP<98>")
	)
	(segment
		(start 88.089232 -359.442004)
		(end 88.089232 -353.972368)
		(width 0.1651)
		(layer "In13.Cu")
		(net "P5E_PEX0_STN6_TX_C_DP<98>")
	)
	(segment
		(start 88.089232 -353.972368)
		(end 89.643712 -352.417888)
		(width 0.1651)
		(layer "In13.Cu")
		(net "P5E_PEX0_STN6_TX_C_DP<98>")
	)
	(segment
		(start 82.909918 -383.290064)
		(end 82.909918 -383.67208)
		(width 0.1651)
		(layer "In13.Cu")
		(net "P5E_PEX0_STN6_TX_C_DP<98>")
	)
	(segment
		(start 84.639912 -366.734852)
		(end 84.597494 -366.616488)
		(width 0.1651)
		(layer "In13.Cu")
		(net "P5E_PEX0_STN6_TX_C_DP<98>")
	)
	(segment
		(start 85.309202 -365.112046)
		(end 85.427566 -365.069628)
		(width 0.1651)
		(layer "In13.Cu")
		(net "P5E_PEX0_STN6_TX_C_DP<98>")
	)
	(segment
		(start 83.80222 -383.561082)
		(end 83.80222 -368.50574)
		(width 0.1651)
		(layer "In13.Cu")
		(net "P5E_PEX0_STN6_TX_C_DP<98>")
	)
	(segment
		(start 85.427566 -365.069628)
		(end 88.089232 -359.442004)
		(width 0.1651)
		(layer "In13.Cu")
		(net "P5E_PEX0_STN6_TX_C_DP<98>")
	)
	(segment
		(start 84.809584 -366.168432)
		(end 84.927948 -366.126014)
		(width 0.1651)
		(layer "In13.Cu")
		(net "P5E_PEX0_STN6_TX_C_DP<98>")
	)
	(segment
		(start 83.036918 -383.79908)
		(end 83.564222 -383.79908)
		(width 0.1651)
		(layer "In13.Cu")
		(net "P5E_PEX0_STN6_TX_C_DP<98>")
	)
	(segment
		(start 89.643712 -352.417888)
		(end 89.643712 -351.902268)
		(width 0.1651)
		(layer "In13.Cu")
		(net "P5E_PEX0_STN6_TX_C_DP<98>")
	)
	(segment
		(start 84.597494 -366.616488)
		(end 84.809584 -366.168432)
		(width 0.1651)
		(layer "In13.Cu")
		(net "P5E_PEX0_STN6_TX_C_DP<98>")
	)
	(segment
		(start 83.80222 -368.50574)
		(end 84.639912 -366.734852)
		(width 0.1651)
		(layer "In13.Cu")
		(net "P5E_PEX0_STN6_TX_C_DP<98>")
	)
	(segment
		(start 83.564222 -383.79908)
		(end 83.80222 -383.561082)
		(width 0.1651)
		(layer "In13.Cu")
		(net "P5E_PEX0_STN6_TX_C_DP<98>")
	)
	(segment
		(start 273.967956 -28.390088)
		(end 273.464782 -28.390088)
		(width 0.13462)
		(layer "F.Cu")
		(net "P5E_PEX2_STN2_TX_C_DN<40>")
	)
	(segment
		(start 274.132548 -28.55468)
		(end 273.967956 -28.390088)
		(width 0.13462)
		(layer "F.Cu")
		(net "P5E_PEX2_STN2_TX_C_DN<40>")
	)
	(segment
		(start 275.725636 -28.225242)
		(end 275.396198 -28.55468)
		(width 0.13462)
		(layer "F.Cu")
		(net "P5E_PEX2_STN2_TX_C_DN<40>")
	)
	(segment
		(start 275.396198 -28.55468)
		(end 274.132548 -28.55468)
		(width 0.13462)
		(layer "F.Cu")
		(net "P5E_PEX2_STN2_TX_C_DN<40>")
	)
	(segment
		(start 322.124324 -350.685354)
		(end 322.124324 -351.316798)
		(width 0.13462)
		(layer "F.Cu")
		(net "P5E_PEX2_STN6_TX_C_DP<107>")
	)
	(segment
		(start 322.124324 -351.316798)
		(end 321.829684 -351.611438)
		(width 0.13462)
		(layer "F.Cu")
		(net "P5E_PEX2_STN6_TX_C_DP<107>")
	)
	(segment
		(start 321.804284 -350.365314)
		(end 322.124324 -350.685354)
		(width 0.13462)
		(layer "F.Cu")
		(net "P5E_PEX2_STN6_TX_C_DP<107>")
	)
	(segment
		(start 338.210906 -392.549126)
		(end 338.608162 -392.844782)
		(width 0.1651)
		(layer "In13.Cu")
		(net "P5E_PEX2_STN6_TX_C_DP<107>")
	)
	(segment
		(start 341.134192 -395.04112)
		(end 341.134192 -408.412442)
		(width 0.1651)
		(layer "In13.Cu")
		(net "P5E_PEX2_STN6_TX_C_DP<107>")
	)
	(segment
		(start 337.67141 -392.274044)
		(end 338.06892 -392.569954)
		(width 0.1651)
		(layer "In13.Cu")
		(net "P5E_PEX2_STN6_TX_C_DP<107>")
	)
	(segment
		(start 320.566034 -353.910646)
		(end 320.566034 -358.93629)
		(width 0.1651)
		(layer "In13.Cu")
		(net "P5E_PEX2_STN6_TX_C_DP<107>")
	)
	(segment
		(start 339.16874 -393.262104)
		(end 339.565996 -393.55776)
		(width 0.1651)
		(layer "In13.Cu")
		(net "P5E_PEX2_STN6_TX_C_DP<107>")
	)
	(segment
		(start 341.134192 -408.412442)
		(end 340.847426 -408.699208)
		(width 0.1651)
		(layer "In13.Cu")
		(net "P5E_PEX2_STN6_TX_C_DP<107>")
	)
	(segment
		(start 337.650582 -392.131804)
		(end 337.67141 -392.274044)
		(width 0.1651)
		(layer "In13.Cu")
		(net "P5E_PEX2_STN6_TX_C_DP<107>")
	)
	(segment
		(start 339.586824 -393.7)
		(end 339.984334 -393.99591)
		(width 0.1651)
		(layer "In13.Cu")
		(net "P5E_PEX2_STN6_TX_C_DP<107>")
	)
	(segment
		(start 340.126574 -393.975082)
		(end 340.842346 -394.507974)
		(width 0.1651)
		(layer "In13.Cu")
		(net "P5E_PEX2_STN6_TX_C_DP<107>")
	)
	(segment
		(start 321.829684 -351.611438)
		(end 322.120514 -351.902268)
		(width 0.1651)
		(layer "In13.Cu")
		(net "P5E_PEX2_STN6_TX_C_DP<107>")
	)
	(segment
		(start 322.120514 -352.356166)
		(end 320.566034 -353.910646)
		(width 0.1651)
		(layer "In13.Cu")
		(net "P5E_PEX2_STN6_TX_C_DP<107>")
	)
	(segment
		(start 320.566034 -358.93629)
		(end 327.448926 -386.906516)
		(width 0.1651)
		(layer "In13.Cu")
		(net "P5E_PEX2_STN6_TX_C_DP<107>")
	)
	(segment
		(start 340.29015 -408.572208)
		(end 340.29015 -408.190192)
		(width 0.1651)
		(layer "In13.Cu")
		(net "P5E_PEX2_STN6_TX_C_DP<107>")
	)
	(segment
		(start 322.120514 -351.902268)
		(end 322.120514 -352.356166)
		(width 0.1651)
		(layer "In13.Cu")
		(net "P5E_PEX2_STN6_TX_C_DP<107>")
	)
	(segment
		(start 339.565996 -393.55776)
		(end 339.586824 -393.7)
		(width 0.1651)
		(layer "In13.Cu")
		(net "P5E_PEX2_STN6_TX_C_DP<107>")
	)
	(segment
		(start 327.448926 -386.906516)
		(end 330.326238 -389.179308)
		(width 0.1651)
		(layer "In13.Cu")
		(net "P5E_PEX2_STN6_TX_C_DP<107>")
	)
	(segment
		(start 339.984334 -393.99591)
		(end 340.126574 -393.975082)
		(width 0.1651)
		(layer "In13.Cu")
		(net "P5E_PEX2_STN6_TX_C_DP<107>")
	)
	(segment
		(start 338.608162 -392.844782)
		(end 338.62899 -392.987022)
		(width 0.1651)
		(layer "In13.Cu")
		(net "P5E_PEX2_STN6_TX_C_DP<107>")
	)
	(segment
		(start 340.41715 -408.699208)
		(end 340.29015 -408.572208)
		(width 0.1651)
		(layer "In13.Cu")
		(net "P5E_PEX2_STN6_TX_C_DP<107>")
	)
	(segment
		(start 339.026754 -393.282932)
		(end 339.16874 -393.262104)
		(width 0.1651)
		(layer "In13.Cu")
		(net "P5E_PEX2_STN6_TX_C_DP<107>")
	)
	(segment
		(start 338.06892 -392.569954)
		(end 338.210906 -392.549126)
		(width 0.1651)
		(layer "In13.Cu")
		(net "P5E_PEX2_STN6_TX_C_DP<107>")
	)
	(segment
		(start 340.847426 -408.699208)
		(end 340.41715 -408.699208)
		(width 0.1651)
		(layer "In13.Cu")
		(net "P5E_PEX2_STN6_TX_C_DP<107>")
	)
	(segment
		(start 340.842346 -394.507974)
		(end 341.134192 -395.04112)
		(width 0.1651)
		(layer "In13.Cu")
		(net "P5E_PEX2_STN6_TX_C_DP<107>")
	)
	(segment
		(start 336.79003 -391.491216)
		(end 337.650582 -392.131804)
		(width 0.1651)
		(layer "In13.Cu")
		(net "P5E_PEX2_STN6_TX_C_DP<107>")
	)
	(segment
		(start 330.326238 -389.179308)
		(end 336.79003 -391.491216)
		(width 0.1651)
		(layer "In13.Cu")
		(net "P5E_PEX2_STN6_TX_C_DP<107>")
	)
	(segment
		(start 338.62899 -392.987022)
		(end 339.026754 -393.282932)
		(width 0.1651)
		(layer "In13.Cu")
		(net "P5E_PEX2_STN6_TX_C_DP<107>")
	)
	(segment
		(start 400.05762 -344.219022)
		(end 399.738088 -344.538554)
		(width 0.13462)
		(layer "F.Cu")
		(net "P5E_PEX3_STN5_TX_C_DN<85>")
	)
	(segment
		(start 399.738088 -345.171014)
		(end 400.03222 -345.465146)
		(width 0.13462)
		(layer "F.Cu")
		(net "P5E_PEX3_STN5_TX_C_DN<85>")
	)
	(segment
		(start 399.738088 -344.538554)
		(end 399.738088 -345.171014)
		(width 0.13462)
		(layer "F.Cu")
		(net "P5E_PEX3_STN5_TX_C_DN<85>")
	)
	(segment
		(start 399.74139 -345.755976)
		(end 400.03222 -345.465146)
		(width 0.1651)
		(layer "In7.Cu")
		(net "P5E_PEX3_STN5_TX_C_DN<85>")
	)
	(segment
		(start 386.616956 -406.181052)
		(end 387.164072 -406.181052)
		(width 0.1651)
		(layer "In7.Cu")
		(net "P5E_PEX3_STN5_TX_C_DN<85>")
	)
	(segment
		(start 386.489956 -406.690068)
		(end 386.489956 -406.308052)
		(width 0.1651)
		(layer "In7.Cu")
		(net "P5E_PEX3_STN5_TX_C_DN<85>")
	)
	(segment
		(start 400.384772 -387.12775)
		(end 400.51482 -369.566952)
		(width 0.1651)
		(layer "In7.Cu")
		(net "P5E_PEX3_STN5_TX_C_DN<85>")
	)
	(segment
		(start 388.637272 -394.034518)
		(end 398.905222 -389.758682)
		(width 0.1651)
		(layer "In7.Cu")
		(net "P5E_PEX3_STN5_TX_C_DN<85>")
	)
	(segment
		(start 387.615938 -395.087094)
		(end 388.637272 -394.034518)
		(width 0.1651)
		(layer "In7.Cu")
		(net "P5E_PEX3_STN5_TX_C_DN<85>")
	)
	(segment
		(start 400.515074 -369.53571)
		(end 398.18691 -358.837738)
		(width 0.1651)
		(layer "In7.Cu")
		(net "P5E_PEX3_STN5_TX_C_DN<85>")
	)
	(segment
		(start 398.18691 -358.837738)
		(end 398.18691 -347.881194)
		(width 0.1651)
		(layer "In7.Cu")
		(net "P5E_PEX3_STN5_TX_C_DN<85>")
	)
	(segment
		(start 386.489956 -406.308052)
		(end 386.616956 -406.181052)
		(width 0.1651)
		(layer "In7.Cu")
		(net "P5E_PEX3_STN5_TX_C_DN<85>")
	)
	(segment
		(start 387.615938 -405.729186)
		(end 387.615938 -395.087094)
		(width 0.1651)
		(layer "In7.Cu")
		(net "P5E_PEX3_STN5_TX_C_DN<85>")
	)
	(segment
		(start 387.164072 -406.181052)
		(end 387.615938 -405.729186)
		(width 0.1651)
		(layer "In7.Cu")
		(net "P5E_PEX3_STN5_TX_C_DN<85>")
	)
	(segment
		(start 398.905222 -389.758682)
		(end 400.384772 -387.12775)
		(width 0.1651)
		(layer "In7.Cu")
		(net "P5E_PEX3_STN5_TX_C_DN<85>")
	)
	(segment
		(start 400.51482 -369.566952)
		(end 400.515074 -369.53571)
		(width 0.1651)
		(layer "In7.Cu")
		(net "P5E_PEX3_STN5_TX_C_DN<85>")
	)
	(segment
		(start 399.74139 -346.326714)
		(end 399.74139 -345.755976)
		(width 0.1651)
		(layer "In7.Cu")
		(net "P5E_PEX3_STN5_TX_C_DN<85>")
	)
	(segment
		(start 398.18691 -347.881194)
		(end 399.74139 -346.326714)
		(width 0.1651)
		(layer "In7.Cu")
		(net "P5E_PEX3_STN5_TX_C_DN<85>")
	)
	(segment
		(start 73.257664 -98.240088)
		(end 74.733912 -98.240088)
		(width 0.13208)
		(layer "F.Cu")
		(net "NIC1_LD_N")
	)
	(segment
		(start 74.733912 -98.240088)
		(end 75.946 -97.028)
		(width 0.13208)
		(layer "F.Cu")
		(net "NIC1_LD_N")
	)
	(segment
		(start 75.946 -97.028)
		(end 75.946 -95.989648)
		(width 0.13208)
		(layer "F.Cu")
		(net "NIC1_LD_N")
	)
	(via
		(at 75.946 -95.989648)
		(size 0.508)
		(drill 0.254)
		(layers "F.Cu" "B.Cu")
		(net "NIC1_LD_N")
	)
	(segment
		(start 75.946 -95.989648)
		(end 77.141832 -95.989648)
		(width 0.13208)
		(layer "B.Cu")
		(net "NIC1_LD_N")
	)
	(segment
		(start 45.391578 -130.727958)
		(end 37.224208 -130.727958)
		(width 0.13462)
		(layer "F.Cu")
		(net "P5E_PEX0_STN1_TX_C_DP<28>")
	)
	(segment
		(start 37.224208 -130.727958)
		(end 36.905184 -130.408934)
		(width 0.13462)
		(layer "F.Cu")
		(net "P5E_PEX0_STN1_TX_C_DP<28>")
	)
	(segment
		(start 45.554392 -130.565144)
		(end 45.391578 -130.727958)
		(width 0.13462)
		(layer "F.Cu")
		(net "P5E_PEX0_STN1_TX_C_DP<28>")
	)
	(segment
		(start 46.042326 -130.565144)
		(end 45.554392 -130.565144)
		(width 0.13462)
		(layer "F.Cu")
		(net "P5E_PEX0_STN1_TX_C_DP<28>")
	)
	(segment
		(start 327.725532 -28.225242)
		(end 327.396094 -28.55468)
		(width 0.13462)
		(layer "F.Cu")
		(net "P5E_PEX2_STN2_TX_C_DN<32>")
	)
	(segment
		(start 327.396094 -28.55468)
		(end 326.132444 -28.55468)
		(width 0.13462)
		(layer "F.Cu")
		(net "P5E_PEX2_STN2_TX_C_DN<32>")
	)
	(segment
		(start 325.967852 -28.390088)
		(end 325.464678 -28.390088)
		(width 0.13462)
		(layer "F.Cu")
		(net "P5E_PEX2_STN2_TX_C_DN<32>")
	)
	(segment
		(start 326.132444 -28.55468)
		(end 325.967852 -28.390088)
		(width 0.13462)
		(layer "F.Cu")
		(net "P5E_PEX2_STN2_TX_C_DN<32>")
	)
	(segment
		(start 328.936604 -350.365314)
		(end 328.616564 -350.685354)
		(width 0.13462)
		(layer "F.Cu")
		(net "P5E_PEX2_STN6_TX_C_DN<104>")
	)
	(segment
		(start 328.616564 -351.316798)
		(end 328.911204 -351.611438)
		(width 0.13462)
		(layer "F.Cu")
		(net "P5E_PEX2_STN6_TX_C_DN<104>")
	)
	(segment
		(start 328.616564 -350.685354)
		(end 328.616564 -351.316798)
		(width 0.13462)
		(layer "F.Cu")
		(net "P5E_PEX2_STN6_TX_C_DN<104>")
	)
	(segment
		(start 328.620374 -352.473006)
		(end 328.620374 -351.902268)
		(width 0.1651)
		(layer "In13.Cu")
		(net "P5E_PEX2_STN6_TX_C_DN<104>")
	)
	(segment
		(start 331.794612 -386.212334)
		(end 330.452984 -385.150868)
		(width 0.1651)
		(layer "In13.Cu")
		(net "P5E_PEX2_STN6_TX_C_DN<104>")
	)
	(segment
		(start 348.016068 -395.680692)
		(end 347.822774 -395.165834)
		(width 0.1651)
		(layer "In13.Cu")
		(net "P5E_PEX2_STN6_TX_C_DN<104>")
	)
	(segment
		(start 327.065894 -358.902)
		(end 327.065894 -354.027486)
		(width 0.1651)
		(layer "In13.Cu")
		(net "P5E_PEX2_STN6_TX_C_DN<104>")
	)
	(segment
		(start 347.564202 -410.080968)
		(end 348.016068 -409.629102)
		(width 0.1651)
		(layer "In13.Cu")
		(net "P5E_PEX2_STN6_TX_C_DN<104>")
	)
	(segment
		(start 346.890086 -410.589984)
		(end 346.890086 -410.207968)
		(width 0.1651)
		(layer "In13.Cu")
		(net "P5E_PEX2_STN6_TX_C_DN<104>")
	)
	(segment
		(start 327.065894 -354.027486)
		(end 328.620374 -352.473006)
		(width 0.1651)
		(layer "In13.Cu")
		(net "P5E_PEX2_STN6_TX_C_DN<104>")
	)
	(segment
		(start 346.890086 -410.207968)
		(end 347.017086 -410.080968)
		(width 0.1651)
		(layer "In13.Cu")
		(net "P5E_PEX2_STN6_TX_C_DN<104>")
	)
	(segment
		(start 347.017086 -410.080968)
		(end 347.564202 -410.080968)
		(width 0.1651)
		(layer "In13.Cu")
		(net "P5E_PEX2_STN6_TX_C_DN<104>")
	)
	(segment
		(start 347.822774 -395.165834)
		(end 346.00642 -393.34694)
		(width 0.1651)
		(layer "In13.Cu")
		(net "P5E_PEX2_STN6_TX_C_DN<104>")
	)
	(segment
		(start 348.016068 -409.629102)
		(end 348.016068 -395.680692)
		(width 0.1651)
		(layer "In13.Cu")
		(net "P5E_PEX2_STN6_TX_C_DN<104>")
	)
	(segment
		(start 338.362544 -388.544562)
		(end 331.794612 -386.212334)
		(width 0.1651)
		(layer "In13.Cu")
		(net "P5E_PEX2_STN6_TX_C_DN<104>")
	)
	(segment
		(start 328.620374 -351.902268)
		(end 328.911204 -351.611438)
		(width 0.1651)
		(layer "In13.Cu")
		(net "P5E_PEX2_STN6_TX_C_DN<104>")
	)
	(segment
		(start 346.00642 -393.34694)
		(end 338.362544 -388.544562)
		(width 0.1651)
		(layer "In13.Cu")
		(net "P5E_PEX2_STN6_TX_C_DN<104>")
	)
	(segment
		(start 330.452984 -385.150868)
		(end 327.065894 -358.902)
		(width 0.1651)
		(layer "In13.Cu")
		(net "P5E_PEX2_STN6_TX_C_DN<104>")
	)
	(segment
		(start 396.354808 -345.169998)
		(end 396.05966 -345.465146)
		(width 0.13462)
		(layer "F.Cu")
		(net "P5E_PEX3_STN5_TX_C_DP<91>")
	)
	(segment
		(start 396.354808 -344.53957)
		(end 396.354808 -345.169998)
		(width 0.13462)
		(layer "F.Cu")
		(net "P5E_PEX3_STN5_TX_C_DP<91>")
	)
	(segment
		(start 396.03426 -344.219022)
		(end 396.354808 -344.53957)
		(width 0.13462)
		(layer "F.Cu")
		(net "P5E_PEX3_STN5_TX_C_DP<91>")
	)
	(segment
		(start 396.35049 -346.209874)
		(end 396.35049 -345.755976)
		(width 0.1651)
		(layer "In13.Cu")
		(net "P5E_PEX3_STN5_TX_C_DP<91>")
	)
	(segment
		(start 382.933956 -369.66398)
		(end 383.65557 -368.131344)
		(width 0.1651)
		(layer "In13.Cu")
		(net "P5E_PEX3_STN5_TX_C_DP<91>")
	)
	(segment
		(start 394.147294 -359.457498)
		(end 394.79601 -358.079548)
		(width 0.1651)
		(layer "In13.Cu")
		(net "P5E_PEX3_STN5_TX_C_DP<91>")
	)
	(segment
		(start 382.216914 -379.899164)
		(end 382.64719 -379.899164)
		(width 0.1651)
		(layer "In13.Cu")
		(net "P5E_PEX3_STN5_TX_C_DP<91>")
	)
	(segment
		(start 394.79601 -358.079548)
		(end 394.79601 -347.764354)
		(width 0.1651)
		(layer "In13.Cu")
		(net "P5E_PEX3_STN5_TX_C_DP<91>")
	)
	(segment
		(start 385.431792 -366.547654)
		(end 385.813808 -366.231678)
		(width 0.1651)
		(layer "In13.Cu")
		(net "P5E_PEX3_STN5_TX_C_DP<91>")
	)
	(segment
		(start 382.64719 -379.899164)
		(end 382.933956 -379.612398)
		(width 0.1651)
		(layer "In13.Cu")
		(net "P5E_PEX3_STN5_TX_C_DP<91>")
	)
	(segment
		(start 382.089914 -379.390148)
		(end 382.089914 -379.772164)
		(width 0.1651)
		(layer "In13.Cu")
		(net "P5E_PEX3_STN5_TX_C_DP<91>")
	)
	(segment
		(start 382.089914 -379.772164)
		(end 382.216914 -379.899164)
		(width 0.1651)
		(layer "In13.Cu")
		(net "P5E_PEX3_STN5_TX_C_DP<91>")
	)
	(segment
		(start 396.35049 -345.755976)
		(end 396.05966 -345.465146)
		(width 0.1651)
		(layer "In13.Cu")
		(net "P5E_PEX3_STN5_TX_C_DP<91>")
	)
	(segment
		(start 385.813808 -366.231678)
		(end 385.938776 -366.243616)
		(width 0.1651)
		(layer "In13.Cu")
		(net "P5E_PEX3_STN5_TX_C_DP<91>")
	)
	(segment
		(start 385.419854 -366.672622)
		(end 385.431792 -366.547654)
		(width 0.1651)
		(layer "In13.Cu")
		(net "P5E_PEX3_STN5_TX_C_DP<91>")
	)
	(segment
		(start 383.65557 -368.131344)
		(end 385.419854 -366.672622)
		(width 0.1651)
		(layer "In13.Cu")
		(net "P5E_PEX3_STN5_TX_C_DP<91>")
	)
	(segment
		(start 385.938776 -366.243616)
		(end 394.147294 -359.457498)
		(width 0.1651)
		(layer "In13.Cu")
		(net "P5E_PEX3_STN5_TX_C_DP<91>")
	)
	(segment
		(start 394.79601 -347.764354)
		(end 396.35049 -346.209874)
		(width 0.1651)
		(layer "In13.Cu")
		(net "P5E_PEX3_STN5_TX_C_DP<91>")
	)
	(segment
		(start 382.933956 -379.612398)
		(end 382.933956 -369.66398)
		(width 0.1651)
		(layer "In13.Cu")
		(net "P5E_PEX3_STN5_TX_C_DP<91>")
	)
	(segment
		(start 80.623664 -87.749126)
		(end 80.623664 -88.033352)
		(width 0.13208)
		(layer "F.Cu")
		(net "RST_NIC1_PERST1_R_N")
	)
	(segment
		(start 80.623664 -88.033352)
		(end 80.281018 -88.375998)
		(width 0.13208)
		(layer "F.Cu")
		(net "RST_NIC1_PERST1_R_N")
	)
	(segment
		(start 68.65747 -115.234974)
		(end 67.363594 -115.234974)
		(width 0.13208)
		(layer "F.Cu")
		(net "RST_NIC1_PERST1_R_N")
	)
	(segment
		(start 67.363594 -115.234974)
		(end 67.312794 -115.285774)
		(width 0.13208)
		(layer "F.Cu")
		(net "RST_NIC1_PERST1_R_N")
	)
	(via
		(at 67.312794 -115.285774)
		(size 0.508)
		(drill 0.254)
		(layers "F.Cu" "B.Cu")
		(net "RST_NIC1_PERST1_R_N")
	)
	(via
		(at 80.281018 -88.375998)
		(size 0.508)
		(drill 0.254)
		(layers "F.Cu" "B.Cu")
		(net "RST_NIC1_PERST1_R_N")
	)
	(segment
		(start 76.695808 -88.375998)
		(end 74.007218 -91.064588)
		(width 0.15494)
		(layer "In11.Cu")
		(net "RST_NIC1_PERST1_R_N")
	)
	(segment
		(start 67.881246 -115.285774)
		(end 67.312794 -115.285774)
		(width 0.15494)
		(layer "In11.Cu")
		(net "RST_NIC1_PERST1_R_N")
	)
	(segment
		(start 74.007218 -95.98025)
		(end 72.206612 -97.780856)
		(width 0.15494)
		(layer "In11.Cu")
		(net "RST_NIC1_PERST1_R_N")
	)
	(segment
		(start 72.416416 -108.7882)
		(end 71.173848 -108.7882)
		(width 0.15494)
		(layer "In11.Cu")
		(net "RST_NIC1_PERST1_R_N")
	)
	(segment
		(start 73.12787 -106.150156)
		(end 73.12787 -108.076746)
		(width 0.15494)
		(layer "In11.Cu")
		(net "RST_NIC1_PERST1_R_N")
	)
	(segment
		(start 80.281018 -88.375998)
		(end 76.695808 -88.375998)
		(width 0.15494)
		(layer "In11.Cu")
		(net "RST_NIC1_PERST1_R_N")
	)
	(segment
		(start 74.007218 -91.064588)
		(end 74.007218 -95.98025)
		(width 0.15494)
		(layer "In11.Cu")
		(net "RST_NIC1_PERST1_R_N")
	)
	(segment
		(start 73.12787 -108.076746)
		(end 72.416416 -108.7882)
		(width 0.15494)
		(layer "In11.Cu")
		(net "RST_NIC1_PERST1_R_N")
	)
	(segment
		(start 72.206612 -97.780856)
		(end 72.206612 -105.228898)
		(width 0.15494)
		(layer "In11.Cu")
		(net "RST_NIC1_PERST1_R_N")
	)
	(segment
		(start 68.896484 -114.270536)
		(end 67.881246 -115.285774)
		(width 0.15494)
		(layer "In11.Cu")
		(net "RST_NIC1_PERST1_R_N")
	)
	(segment
		(start 68.896484 -111.065564)
		(end 68.896484 -114.270536)
		(width 0.15494)
		(layer "In11.Cu")
		(net "RST_NIC1_PERST1_R_N")
	)
	(segment
		(start 71.173848 -108.7882)
		(end 68.896484 -111.065564)
		(width 0.15494)
		(layer "In11.Cu")
		(net "RST_NIC1_PERST1_R_N")
	)
	(segment
		(start 72.206612 -105.228898)
		(end 73.12787 -106.150156)
		(width 0.15494)
		(layer "In11.Cu")
		(net "RST_NIC1_PERST1_R_N")
	)
	(segment
		(start 53.801772 -107.082082)
		(end 53.80228 -107.081574)
		(width 0.13462)
		(layer "F.Cu")
		(net "P5E_PEX0_STN1_RX_DN<20>")
	)
	(segment
		(start 51.293268 -107.082082)
		(end 53.801772 -107.082082)
		(width 0.13462)
		(layer "F.Cu")
		(net "P5E_PEX0_STN1_RX_DN<20>")
	)
	(segment
		(start 50.64252 -107.244896)
		(end 51.130454 -107.244896)
		(width 0.13462)
		(layer "F.Cu")
		(net "P5E_PEX0_STN1_RX_DN<20>")
	)
	(segment
		(start 51.130454 -107.244896)
		(end 51.293268 -107.082082)
		(width 0.13462)
		(layer "F.Cu")
		(net "P5E_PEX0_STN1_RX_DN<20>")
	)
	(segment
		(start 53.80228 -107.081574)
		(end 54.09692 -107.376214)
		(width 0.13462)
		(layer "F.Cu")
		(net "P5E_PEX0_STN1_RX_DN<20>")
	)
	(segment
		(start 43.244516 -112.260888)
		(end 42.888154 -112.605312)
		(width 0.1651)
		(layer "In5.Cu")
		(net "P5E_PEX0_STN1_RX_DN<20>")
	)
	(segment
		(start 50.583846 -107.658408)
		(end 50.146712 -107.891072)
		(width 0.1651)
		(layer "In5.Cu")
		(net "P5E_PEX0_STN1_RX_DN<20>")
	)
	(segment
		(start 47.946818 -109.191806)
		(end 47.50943 -109.424724)
		(width 0.1651)
		(layer "In5.Cu")
		(net "P5E_PEX0_STN1_RX_DN<20>")
	)
	(segment
		(start 50.738278 -107.705652)
		(end 50.583846 -107.658408)
		(width 0.1651)
		(layer "In5.Cu")
		(net "P5E_PEX0_STN1_RX_DN<20>")
	)
	(segment
		(start 46.87062 -109.764576)
		(end 46.433232 -109.997748)
		(width 0.1651)
		(layer "In5.Cu")
		(net "P5E_PEX0_STN1_RX_DN<20>")
	)
	(segment
		(start 46.433232 -109.997748)
		(end 46.278546 -109.950504)
		(width 0.1651)
		(layer "In5.Cu")
		(net "P5E_PEX0_STN1_RX_DN<20>")
	)
	(segment
		(start 49.070514 -108.464096)
		(end 49.02327 -108.618782)
		(width 0.1651)
		(layer "In5.Cu")
		(net "P5E_PEX0_STN1_RX_DN<20>")
	)
	(segment
		(start 63.115952 -271.802352)
		(end 63.070232 -271.848072)
		(width 0.1143)
		(layer "In5.Cu")
		(net "P5E_PEX0_STN1_RX_DN<20>")
	)
	(segment
		(start 45.35678 -110.570772)
		(end 45.202094 -110.523528)
		(width 0.1651)
		(layer "In5.Cu")
		(net "P5E_PEX0_STN1_RX_DN<20>")
	)
	(segment
		(start 32.379412 -150.512018)
		(end 32.898334 -158.717488)
		(width 0.1651)
		(layer "In5.Cu")
		(net "P5E_PEX0_STN1_RX_DN<20>")
	)
	(segment
		(start 44.124118 -111.252)
		(end 44.121324 -111.413544)
		(width 0.1651)
		(layer "In5.Cu")
		(net "P5E_PEX0_STN1_RX_DN<20>")
	)
	(segment
		(start 53.80609 -107.085384)
		(end 51.660044 -107.085384)
		(width 0.1651)
		(layer "In5.Cu")
		(net "P5E_PEX0_STN1_RX_DN<20>")
	)
	(segment
		(start 38.599872 -123.195842)
		(end 36.868862 -123.863354)
		(width 0.1651)
		(layer "In5.Cu")
		(net "P5E_PEX0_STN1_RX_DN<20>")
	)
	(segment
		(start 47.994062 -109.03712)
		(end 47.946818 -109.191806)
		(width 0.1651)
		(layer "In5.Cu")
		(net "P5E_PEX0_STN1_RX_DN<20>")
	)
	(segment
		(start 63.115952 -271.773904)
		(end 63.115952 -271.802352)
		(width 0.1143)
		(layer "In5.Cu")
		(net "P5E_PEX0_STN1_RX_DN<20>")
	)
	(segment
		(start 41.110662 -114.80038)
		(end 39.356284 -122.331226)
		(width 0.1651)
		(layer "In5.Cu")
		(net "P5E_PEX0_STN1_RX_DN<20>")
	)
	(segment
		(start 63.115952 -269.31239)
		(end 63.115952 -271.773904)
		(width 0.1651)
		(layer "In5.Cu")
		(net "P5E_PEX0_STN1_RX_DN<20>")
	)
	(segment
		(start 44.480226 -110.90783)
		(end 44.124118 -111.252)
		(width 0.1651)
		(layer "In5.Cu")
		(net "P5E_PEX0_STN1_RX_DN<20>")
	)
	(segment
		(start 51.22291 -107.318048)
		(end 51.175666 -107.472734)
		(width 0.1651)
		(layer "In5.Cu")
		(net "P5E_PEX0_STN1_RX_DN<20>")
	)
	(segment
		(start 51.175666 -107.472734)
		(end 50.738278 -107.705652)
		(width 0.1651)
		(layer "In5.Cu")
		(net "P5E_PEX0_STN1_RX_DN<20>")
	)
	(segment
		(start 34.013902 -129.549398)
		(end 32.379412 -150.512018)
		(width 0.1651)
		(layer "In5.Cu")
		(net "P5E_PEX0_STN1_RX_DN<20>")
	)
	(segment
		(start 63.335408 -273.479514)
		(end 63.449708 -273.365214)
		(width 0.1143)
		(layer "In5.Cu")
		(net "P5E_PEX0_STN1_RX_DN<20>")
	)
	(segment
		(start 41.908222 -113.39322)
		(end 41.110662 -114.80038)
		(width 0.1651)
		(layer "In5.Cu")
		(net "P5E_PEX0_STN1_RX_DN<20>")
	)
	(segment
		(start 32.898334 -158.717488)
		(end 33.918652 -164.663882)
		(width 0.1651)
		(layer "In5.Cu")
		(net "P5E_PEX0_STN1_RX_DN<20>")
	)
	(segment
		(start 47.50943 -109.424724)
		(end 47.354998 -109.37748)
		(width 0.1651)
		(layer "In5.Cu")
		(net "P5E_PEX0_STN1_RX_DN<20>")
	)
	(segment
		(start 43.764962 -111.757968)
		(end 43.603418 -111.755174)
		(width 0.1651)
		(layer "In5.Cu")
		(net "P5E_PEX0_STN1_RX_DN<20>")
	)
	(segment
		(start 51.660044 -107.085384)
		(end 51.22291 -107.318048)
		(width 0.1651)
		(layer "In5.Cu")
		(net "P5E_PEX0_STN1_RX_DN<20>")
	)
	(segment
		(start 36.868862 -123.863354)
		(end 34.013902 -129.549398)
		(width 0.1651)
		(layer "In5.Cu")
		(net "P5E_PEX0_STN1_RX_DN<20>")
	)
	(segment
		(start 49.66208 -108.278676)
		(end 49.507648 -108.231432)
		(width 0.1651)
		(layer "In5.Cu")
		(net "P5E_PEX0_STN1_RX_DN<20>")
	)
	(segment
		(start 46.278546 -109.950504)
		(end 45.841412 -110.183168)
		(width 0.1651)
		(layer "In5.Cu")
		(net "P5E_PEX0_STN1_RX_DN<20>")
	)
	(segment
		(start 43.603418 -111.755174)
		(end 43.24731 -112.099344)
		(width 0.1651)
		(layer "In5.Cu")
		(net "P5E_PEX0_STN1_RX_DN<20>")
	)
	(segment
		(start 42.888154 -112.605312)
		(end 42.72661 -112.602518)
		(width 0.1651)
		(layer "In5.Cu")
		(net "P5E_PEX0_STN1_RX_DN<20>")
	)
	(segment
		(start 42.72661 -112.602518)
		(end 41.908222 -113.39322)
		(width 0.1651)
		(layer "In5.Cu")
		(net "P5E_PEX0_STN1_RX_DN<20>")
	)
	(segment
		(start 33.918652 -164.663882)
		(end 63.115952 -269.31239)
		(width 0.1651)
		(layer "In5.Cu")
		(net "P5E_PEX0_STN1_RX_DN<20>")
	)
	(segment
		(start 46.917864 -109.610144)
		(end 46.87062 -109.764576)
		(width 0.1651)
		(layer "In5.Cu")
		(net "P5E_PEX0_STN1_RX_DN<20>")
	)
	(segment
		(start 39.356284 -122.331226)
		(end 38.599872 -123.195842)
		(width 0.1651)
		(layer "In5.Cu")
		(net "P5E_PEX0_STN1_RX_DN<20>")
	)
	(segment
		(start 45.841412 -110.183168)
		(end 45.794168 -110.337854)
		(width 0.1651)
		(layer "In5.Cu")
		(net "P5E_PEX0_STN1_RX_DN<20>")
	)
	(segment
		(start 45.202094 -110.523528)
		(end 44.480226 -110.90783)
		(width 0.1651)
		(layer "In5.Cu")
		(net "P5E_PEX0_STN1_RX_DN<20>")
	)
	(segment
		(start 63.070232 -271.848072)
		(end 63.070232 -273.376136)
		(width 0.1143)
		(layer "In5.Cu")
		(net "P5E_PEX0_STN1_RX_DN<20>")
	)
	(segment
		(start 50.099468 -108.045758)
		(end 49.66208 -108.278676)
		(width 0.1651)
		(layer "In5.Cu")
		(net "P5E_PEX0_STN1_RX_DN<20>")
	)
	(segment
		(start 54.09692 -107.376214)
		(end 53.80609 -107.085384)
		(width 0.1651)
		(layer "In5.Cu")
		(net "P5E_PEX0_STN1_RX_DN<20>")
	)
	(segment
		(start 63.070232 -273.376136)
		(end 63.17361 -273.479514)
		(width 0.1143)
		(layer "In5.Cu")
		(net "P5E_PEX0_STN1_RX_DN<20>")
	)
	(segment
		(start 47.354998 -109.37748)
		(end 46.917864 -109.610144)
		(width 0.1651)
		(layer "In5.Cu")
		(net "P5E_PEX0_STN1_RX_DN<20>")
	)
	(segment
		(start 44.121324 -111.413544)
		(end 43.764962 -111.757968)
		(width 0.1651)
		(layer "In5.Cu")
		(net "P5E_PEX0_STN1_RX_DN<20>")
	)
	(segment
		(start 50.146712 -107.891072)
		(end 50.099468 -108.045758)
		(width 0.1651)
		(layer "In5.Cu")
		(net "P5E_PEX0_STN1_RX_DN<20>")
	)
	(segment
		(start 45.794168 -110.337854)
		(end 45.35678 -110.570772)
		(width 0.1651)
		(layer "In5.Cu")
		(net "P5E_PEX0_STN1_RX_DN<20>")
	)
	(segment
		(start 63.449708 -273.365214)
		(end 63.449708 -273.099784)
		(width 0.1143)
		(layer "In5.Cu")
		(net "P5E_PEX0_STN1_RX_DN<20>")
	)
	(segment
		(start 49.507648 -108.231432)
		(end 49.070514 -108.464096)
		(width 0.1651)
		(layer "In5.Cu")
		(net "P5E_PEX0_STN1_RX_DN<20>")
	)
	(segment
		(start 49.02327 -108.618782)
		(end 48.585882 -108.8517)
		(width 0.1651)
		(layer "In5.Cu")
		(net "P5E_PEX0_STN1_RX_DN<20>")
	)
	(segment
		(start 63.17361 -273.479514)
		(end 63.335408 -273.479514)
		(width 0.1143)
		(layer "In5.Cu")
		(net "P5E_PEX0_STN1_RX_DN<20>")
	)
	(segment
		(start 43.24731 -112.099344)
		(end 43.244516 -112.260888)
		(width 0.1651)
		(layer "In5.Cu")
		(net "P5E_PEX0_STN1_RX_DN<20>")
	)
	(segment
		(start 48.585882 -108.8517)
		(end 48.431196 -108.804456)
		(width 0.1651)
		(layer "In5.Cu")
		(net "P5E_PEX0_STN1_RX_DN<20>")
	)
	(segment
		(start 48.431196 -108.804456)
		(end 47.994062 -109.03712)
		(width 0.1651)
		(layer "In5.Cu")
		(net "P5E_PEX0_STN1_RX_DN<20>")
	)
	(segment
		(start 53.379624 -319.819528)
		(end 53.379624 -318.406272)
		(width 0.1143)
		(layer "In9.Cu")
		(net "P5E_PEX0_STN6_RX_DP<100>")
	)
	(segment
		(start 73.920096 -364.850426)
		(end 68.569078 -361.275122)
		(width 0.1651)
		(layer "In9.Cu")
		(net "P5E_PEX0_STN6_RX_DP<100>")
	)
	(segment
		(start 79.137256 -368.613436)
		(end 78.302358 -367.778538)
		(width 0.1651)
		(layer "In9.Cu")
		(net "P5E_PEX0_STN6_RX_DP<100>")
	)
	(segment
		(start 62.322202 -338.67471)
		(end 54.200044 -326.519286)
		(width 0.1651)
		(layer "In9.Cu")
		(net "P5E_PEX0_STN6_RX_DP<100>")
	)
	(segment
		(start 63.585598 -358.903778)
		(end 63.217552 -358.015286)
		(width 0.1651)
		(layer "In9.Cu")
		(net "P5E_PEX0_STN6_RX_DP<100>")
	)
	(segment
		(start 73.951592 -365.008922)
		(end 73.920096 -364.850426)
		(width 0.1651)
		(layer "In9.Cu")
		(net "P5E_PEX0_STN6_RX_DP<100>")
	)
	(segment
		(start 53.333904 -324.428104)
		(end 53.333904 -319.893696)
		(width 0.1651)
		(layer "In9.Cu")
		(net "P5E_PEX0_STN6_RX_DP<100>")
	)
	(segment
		(start 78.509876 -375.872248)
		(end 78.636876 -375.999248)
		(width 0.1651)
		(layer "In9.Cu")
		(net "P5E_PEX0_STN6_RX_DP<100>")
	)
	(segment
		(start 68.569078 -361.275122)
		(end 64.1096 -359.42778)
		(width 0.1651)
		(layer "In9.Cu")
		(net "P5E_PEX0_STN6_RX_DP<100>")
	)
	(segment
		(start 79.080868 -375.999248)
		(end 79.402432 -375.677684)
		(width 0.1651)
		(layer "In9.Cu")
		(net "P5E_PEX0_STN6_RX_DP<100>")
	)
	(segment
		(start 53.333904 -319.865248)
		(end 53.379624 -319.819528)
		(width 0.1143)
		(layer "In9.Cu")
		(net "P5E_PEX0_STN6_RX_DP<100>")
	)
	(segment
		(start 78.302358 -367.778538)
		(end 74.522076 -365.252762)
		(width 0.1651)
		(layer "In9.Cu")
		(net "P5E_PEX0_STN6_RX_DP<100>")
	)
	(segment
		(start 64.1096 -359.42778)
		(end 63.585598 -358.903778)
		(width 0.1651)
		(layer "In9.Cu")
		(net "P5E_PEX0_STN6_RX_DP<100>")
	)
	(segment
		(start 53.949854 -318.040766)
		(end 53.949854 -317.749936)
		(width 0.1143)
		(layer "In9.Cu")
		(net "P5E_PEX0_STN6_RX_DP<100>")
	)
	(segment
		(start 74.522076 -365.252762)
		(end 74.36358 -365.284258)
		(width 0.1651)
		(layer "In9.Cu")
		(net "P5E_PEX0_STN6_RX_DP<100>")
	)
	(segment
		(start 78.636876 -375.999248)
		(end 79.080868 -375.999248)
		(width 0.1651)
		(layer "In9.Cu")
		(net "P5E_PEX0_STN6_RX_DP<100>")
	)
	(segment
		(start 63.217552 -358.015286)
		(end 63.217552 -341.62619)
		(width 0.1651)
		(layer "In9.Cu")
		(net "P5E_PEX0_STN6_RX_DP<100>")
	)
	(segment
		(start 79.402432 -375.677684)
		(end 79.402432 -369.253516)
		(width 0.1651)
		(layer "In9.Cu")
		(net "P5E_PEX0_STN6_RX_DP<100>")
	)
	(segment
		(start 53.65623 -318.129666)
		(end 53.860954 -318.129666)
		(width 0.1143)
		(layer "In9.Cu")
		(net "P5E_PEX0_STN6_RX_DP<100>")
	)
	(segment
		(start 53.860954 -318.129666)
		(end 53.949854 -318.040766)
		(width 0.1143)
		(layer "In9.Cu")
		(net "P5E_PEX0_STN6_RX_DP<100>")
	)
	(segment
		(start 63.217552 -341.62619)
		(end 62.322202 -338.67471)
		(width 0.1651)
		(layer "In9.Cu")
		(net "P5E_PEX0_STN6_RX_DP<100>")
	)
	(segment
		(start 74.36358 -365.284258)
		(end 73.951592 -365.008922)
		(width 0.1651)
		(layer "In9.Cu")
		(net "P5E_PEX0_STN6_RX_DP<100>")
	)
	(segment
		(start 54.200044 -326.519286)
		(end 53.333904 -324.428104)
		(width 0.1651)
		(layer "In9.Cu")
		(net "P5E_PEX0_STN6_RX_DP<100>")
	)
	(segment
		(start 53.379624 -318.406272)
		(end 53.65623 -318.129666)
		(width 0.1143)
		(layer "In9.Cu")
		(net "P5E_PEX0_STN6_RX_DP<100>")
	)
	(segment
		(start 79.402432 -369.253516)
		(end 79.137256 -368.613436)
		(width 0.1651)
		(layer "In9.Cu")
		(net "P5E_PEX0_STN6_RX_DP<100>")
	)
	(segment
		(start 53.333904 -319.893696)
		(end 53.333904 -319.865248)
		(width 0.1143)
		(layer "In9.Cu")
		(net "P5E_PEX0_STN6_RX_DP<100>")
	)
	(segment
		(start 78.509876 -375.490232)
		(end 78.509876 -375.872248)
		(width 0.1651)
		(layer "In9.Cu")
		(net "P5E_PEX0_STN6_RX_DP<100>")
	)
	(segment
		(start 273.9644 -28.990036)
		(end 273.464782 -28.990036)
		(width 0.13462)
		(layer "F.Cu")
		(net "P5E_PEX2_STN2_TX_C_DP<40>")
	)
	(segment
		(start 275.725636 -29.139642)
		(end 275.414994 -28.829)
		(width 0.13462)
		(layer "F.Cu")
		(net "P5E_PEX2_STN2_TX_C_DP<40>")
	)
	(segment
		(start 275.414994 -28.829)
		(end 274.125436 -28.829)
		(width 0.13462)
		(layer "F.Cu")
		(net "P5E_PEX2_STN2_TX_C_DP<40>")
	)
	(segment
		(start 274.125436 -28.829)
		(end 273.9644 -28.990036)
		(width 0.13462)
		(layer "F.Cu")
		(net "P5E_PEX2_STN2_TX_C_DP<40>")
	)
	(segment
		(start 323.674994 -342.33866)
		(end 323.293232 -341.456518)
		(width 0.1651)
		(layer "In9.Cu")
		(net "P5E_PEX2_STN6_RX_DP<98>")
	)
	(segment
		(start 324.19417 -359.13949)
		(end 323.674994 -358.620314)
		(width 0.1651)
		(layer "In9.Cu")
		(net "P5E_PEX2_STN6_RX_DP<98>")
	)
	(segment
		(start 341.417148 -367.465864)
		(end 341.012526 -367.180622)
		(width 0.1651)
		(layer "In9.Cu")
		(net "P5E_PEX2_STN6_RX_DP<98>")
	)
	(segment
		(start 340.501224 -366.913414)
		(end 340.482682 -366.807242)
		(width 0.1651)
		(layer "In9.Cu")
		(net "P5E_PEX2_STN6_RX_DP<98>")
	)
	(segment
		(start 295.10482 -330.510896)
		(end 291.039804 -327.859644)
		(width 0.1651)
		(layer "In9.Cu")
		(net "P5E_PEX2_STN6_RX_DP<98>")
	)
	(segment
		(start 341.840566 -367.857786)
		(end 341.43569 -367.572036)
		(width 0.1651)
		(layer "In9.Cu")
		(net "P5E_PEX2_STN6_RX_DP<98>")
	)
	(segment
		(start 341.43569 -367.572036)
		(end 341.417148 -367.465864)
		(width 0.1651)
		(layer "In9.Cu")
		(net "P5E_PEX2_STN6_RX_DP<98>")
	)
	(segment
		(start 340.906354 -367.19891)
		(end 340.501224 -366.913414)
		(width 0.1651)
		(layer "In9.Cu")
		(net "P5E_PEX2_STN6_RX_DP<98>")
	)
	(segment
		(start 291.039804 -327.859644)
		(end 287.735264 -324.555104)
		(width 0.1651)
		(layer "In9.Cu")
		(net "P5E_PEX2_STN6_RX_DP<98>")
	)
	(segment
		(start 287.705038 -318.129666)
		(end 287.960816 -318.129666)
		(width 0.1143)
		(layer "In9.Cu")
		(net "P5E_PEX2_STN6_RX_DP<98>")
	)
	(segment
		(start 343.04732 -375.999248)
		(end 343.334086 -375.712482)
		(width 0.1651)
		(layer "In9.Cu")
		(net "P5E_PEX2_STN6_RX_DP<98>")
	)
	(segment
		(start 288.049716 -318.040766)
		(end 288.049716 -317.749936)
		(width 0.1143)
		(layer "In9.Cu")
		(net "P5E_PEX2_STN6_RX_DP<98>")
	)
	(segment
		(start 287.479486 -318.355218)
		(end 287.705038 -318.129666)
		(width 0.1143)
		(layer "In9.Cu")
		(net "P5E_PEX2_STN6_RX_DP<98>")
	)
	(segment
		(start 323.674994 -358.620314)
		(end 323.674994 -342.33866)
		(width 0.1651)
		(layer "In9.Cu")
		(net "P5E_PEX2_STN6_RX_DP<98>")
	)
	(segment
		(start 342.490044 -375.872248)
		(end 342.617044 -375.999248)
		(width 0.1651)
		(layer "In9.Cu")
		(net "P5E_PEX2_STN6_RX_DP<98>")
	)
	(segment
		(start 287.960816 -318.129666)
		(end 288.049716 -318.040766)
		(width 0.1143)
		(layer "In9.Cu")
		(net "P5E_PEX2_STN6_RX_DP<98>")
	)
	(segment
		(start 287.433766 -319.916048)
		(end 287.433766 -319.8876)
		(width 0.1143)
		(layer "In9.Cu")
		(net "P5E_PEX2_STN6_RX_DP<98>")
	)
	(segment
		(start 340.482682 -366.807242)
		(end 338.15147 -365.164116)
		(width 0.1651)
		(layer "In9.Cu")
		(net "P5E_PEX2_STN6_RX_DP<98>")
	)
	(segment
		(start 343.334086 -369.403376)
		(end 343.006934 -368.586512)
		(width 0.1651)
		(layer "In9.Cu")
		(net "P5E_PEX2_STN6_RX_DP<98>")
	)
	(segment
		(start 287.433766 -323.82714)
		(end 287.433766 -319.916048)
		(width 0.1651)
		(layer "In9.Cu")
		(net "P5E_PEX2_STN6_RX_DP<98>")
	)
	(segment
		(start 343.334086 -375.712482)
		(end 343.334086 -369.403376)
		(width 0.1651)
		(layer "In9.Cu")
		(net "P5E_PEX2_STN6_RX_DP<98>")
	)
	(segment
		(start 342.490044 -375.490232)
		(end 342.490044 -375.872248)
		(width 0.1651)
		(layer "In9.Cu")
		(net "P5E_PEX2_STN6_RX_DP<98>")
	)
	(segment
		(start 341.012526 -367.180622)
		(end 340.906354 -367.19891)
		(width 0.1651)
		(layer "In9.Cu")
		(net "P5E_PEX2_STN6_RX_DP<98>")
	)
	(segment
		(start 287.433766 -319.8876)
		(end 287.479486 -319.84188)
		(width 0.1143)
		(layer "In9.Cu")
		(net "P5E_PEX2_STN6_RX_DP<98>")
	)
	(segment
		(start 287.479486 -319.84188)
		(end 287.479486 -318.355218)
		(width 0.1143)
		(layer "In9.Cu")
		(net "P5E_PEX2_STN6_RX_DP<98>")
	)
	(segment
		(start 323.293232 -341.456518)
		(end 295.10482 -330.510896)
		(width 0.1651)
		(layer "In9.Cu")
		(net "P5E_PEX2_STN6_RX_DP<98>")
	)
	(segment
		(start 341.946738 -367.839244)
		(end 341.840566 -367.857786)
		(width 0.1651)
		(layer "In9.Cu")
		(net "P5E_PEX2_STN6_RX_DP<98>")
	)
	(segment
		(start 287.735264 -324.555104)
		(end 287.433766 -323.82714)
		(width 0.1651)
		(layer "In9.Cu")
		(net "P5E_PEX2_STN6_RX_DP<98>")
	)
	(segment
		(start 342.617044 -375.999248)
		(end 343.04732 -375.999248)
		(width 0.1651)
		(layer "In9.Cu")
		(net "P5E_PEX2_STN6_RX_DP<98>")
	)
	(segment
		(start 343.006934 -368.586512)
		(end 341.946738 -367.839244)
		(width 0.1651)
		(layer "In9.Cu")
		(net "P5E_PEX2_STN6_RX_DP<98>")
	)
	(segment
		(start 338.15147 -365.164116)
		(end 324.19417 -359.13949)
		(width 0.1651)
		(layer "In9.Cu")
		(net "P5E_PEX2_STN6_RX_DP<98>")
	)
	(segment
		(start 399.463768 -357.462582)
		(end 399.463768 -356.832154)
		(width 0.13462)
		(layer "F.Cu")
		(net "P5E_PEX3_STN5_TX_C_DP<86>")
	)
	(segment
		(start 399.16862 -357.75773)
		(end 399.463768 -357.462582)
		(width 0.13462)
		(layer "F.Cu")
		(net "P5E_PEX3_STN5_TX_C_DP<86>")
	)
	(segment
		(start 399.463768 -356.832154)
		(end 399.14322 -356.511606)
		(width 0.13462)
		(layer "F.Cu")
		(net "P5E_PEX3_STN5_TX_C_DP<86>")
	)
	(segment
		(start 399.378678 -390.326118)
		(end 391.635234 -393.656312)
		(width 0.1651)
		(layer "In7.Cu")
		(net "P5E_PEX3_STN5_TX_C_DP<86>")
	)
	(segment
		(start 389.533892 -404.512272)
		(end 389.247126 -404.799038)
		(width 0.1651)
		(layer "In7.Cu")
		(net "P5E_PEX3_STN5_TX_C_DP<86>")
	)
	(segment
		(start 401.103592 -387.357874)
		(end 399.378678 -390.326118)
		(width 0.1651)
		(layer "In7.Cu")
		(net "P5E_PEX3_STN5_TX_C_DP<86>")
	)
	(segment
		(start 399.894044 -362.037376)
		(end 399.974816 -362.526326)
		(width 0.1651)
		(layer "In7.Cu")
		(net "P5E_PEX3_STN5_TX_C_DP<86>")
	)
	(segment
		(start 401.189698 -369.336828)
		(end 401.103592 -387.357874)
		(width 0.1651)
		(layer "In7.Cu")
		(net "P5E_PEX3_STN5_TX_C_DP<86>")
	)
	(segment
		(start 400.165316 -363.679232)
		(end 400.267678 -363.752384)
		(width 0.1651)
		(layer "In7.Cu")
		(net "P5E_PEX3_STN5_TX_C_DP<86>")
	)
	(segment
		(start 399.886678 -361.446572)
		(end 399.967196 -361.935014)
		(width 0.1651)
		(layer "In7.Cu")
		(net "P5E_PEX3_STN5_TX_C_DP<86>")
	)
	(segment
		(start 399.45945 -358.861106)
		(end 399.776696 -360.782108)
		(width 0.1651)
		(layer "In7.Cu")
		(net "P5E_PEX3_STN5_TX_C_DP<86>")
	)
	(segment
		(start 399.45945 -358.04856)
		(end 399.45945 -358.861106)
		(width 0.1651)
		(layer "In7.Cu")
		(net "P5E_PEX3_STN5_TX_C_DP<86>")
	)
	(segment
		(start 400.084544 -363.190282)
		(end 400.165316 -363.679232)
		(width 0.1651)
		(layer "In7.Cu")
		(net "P5E_PEX3_STN5_TX_C_DP<86>")
	)
	(segment
		(start 399.776696 -360.782108)
		(end 399.70329 -360.884216)
		(width 0.1651)
		(layer "In7.Cu")
		(net "P5E_PEX3_STN5_TX_C_DP<86>")
	)
	(segment
		(start 389.247126 -404.799038)
		(end 388.81685 -404.799038)
		(width 0.1651)
		(layer "In7.Cu")
		(net "P5E_PEX3_STN5_TX_C_DP<86>")
	)
	(segment
		(start 399.70329 -360.884216)
		(end 399.784062 -361.373166)
		(width 0.1651)
		(layer "In7.Cu")
		(net "P5E_PEX3_STN5_TX_C_DP<86>")
	)
	(segment
		(start 389.533892 -396.3924)
		(end 389.533892 -404.512272)
		(width 0.1651)
		(layer "In7.Cu")
		(net "P5E_PEX3_STN5_TX_C_DP<86>")
	)
	(segment
		(start 399.16862 -357.75773)
		(end 399.45945 -358.04856)
		(width 0.1651)
		(layer "In7.Cu")
		(net "P5E_PEX3_STN5_TX_C_DP<86>")
	)
	(segment
		(start 399.784062 -361.373166)
		(end 399.886678 -361.446572)
		(width 0.1651)
		(layer "In7.Cu")
		(net "P5E_PEX3_STN5_TX_C_DP<86>")
	)
	(segment
		(start 391.635234 -393.656058)
		(end 391.586466 -393.67714)
		(width 0.1651)
		(layer "In7.Cu")
		(net "P5E_PEX3_STN5_TX_C_DP<86>")
	)
	(segment
		(start 388.81685 -404.799038)
		(end 388.68985 -404.672038)
		(width 0.1651)
		(layer "In7.Cu")
		(net "P5E_PEX3_STN5_TX_C_DP<86>")
	)
	(segment
		(start 400.157696 -363.08792)
		(end 400.084544 -363.190282)
		(width 0.1651)
		(layer "In7.Cu")
		(net "P5E_PEX3_STN5_TX_C_DP<86>")
	)
	(segment
		(start 391.635234 -393.656312)
		(end 391.635234 -393.656058)
		(width 0.1651)
		(layer "In7.Cu")
		(net "P5E_PEX3_STN5_TX_C_DP<86>")
	)
	(segment
		(start 388.68985 -404.672038)
		(end 388.68985 -404.290022)
		(width 0.1651)
		(layer "In7.Cu")
		(net "P5E_PEX3_STN5_TX_C_DP<86>")
	)
	(segment
		(start 400.267678 -363.752384)
		(end 401.189698 -369.336828)
		(width 0.1651)
		(layer "In7.Cu")
		(net "P5E_PEX3_STN5_TX_C_DP<86>")
	)
	(segment
		(start 399.967196 -361.935014)
		(end 399.894044 -362.037376)
		(width 0.1651)
		(layer "In7.Cu")
		(net "P5E_PEX3_STN5_TX_C_DP<86>")
	)
	(segment
		(start 400.077178 -362.599478)
		(end 400.157696 -363.08792)
		(width 0.1651)
		(layer "In7.Cu")
		(net "P5E_PEX3_STN5_TX_C_DP<86>")
	)
	(segment
		(start 389.879586 -395.352778)
		(end 389.533892 -396.3924)
		(width 0.1651)
		(layer "In7.Cu")
		(net "P5E_PEX3_STN5_TX_C_DP<86>")
	)
	(segment
		(start 391.586466 -393.67714)
		(end 389.879586 -395.352778)
		(width 0.1651)
		(layer "In7.Cu")
		(net "P5E_PEX3_STN5_TX_C_DP<86>")
	)
	(segment
		(start 399.974816 -362.526326)
		(end 400.077178 -362.599478)
		(width 0.1651)
		(layer "In7.Cu")
		(net "P5E_PEX3_STN5_TX_C_DP<86>")
	)
	(segment
		(start 66.901822 -101.84003)
		(end 68.65747 -101.84003)
		(width 0.13208)
		(layer "F.Cu")
		(net "NCSI_NIC1_TXD0")
	)
	(segment
		(start 66.135758 -102.606094)
		(end 66.901822 -101.84003)
		(width 0.13208)
		(layer "F.Cu")
		(net "NCSI_NIC1_TXD0")
	)
	(segment
		(start 64.93129 -103.814372)
		(end 66.135758 -102.609904)
		(width 0.13208)
		(layer "F.Cu")
		(net "NCSI_NIC1_TXD0")
	)
	(segment
		(start 66.135758 -102.609904)
		(end 66.135758 -102.606094)
		(width 0.13208)
		(layer "F.Cu")
		(net "NCSI_NIC1_TXD0")
	)
	(segment
		(start 63.906654 -103.814372)
		(end 64.93129 -103.814372)
		(width 0.13208)
		(layer "F.Cu")
		(net "NCSI_NIC1_TXD0")
	)
	(segment
		(start 59.395106 -103.814372)
		(end 63.906654 -103.814372)
		(width 0.13208)
		(layer "F.Cu")
		(net "NCSI_NIC1_TXD0")
	)
	(via
		(at 63.906654 -103.814372)
		(size 0.762)
		(drill 0.381)
		(layers "F.Cu" "B.Cu")
		(net "NCSI_NIC1_TXD0")
	)
	(segment
		(start 50.64252 -110.245144)
		(end 51.130454 -110.245144)
		(width 0.13462)
		(layer "F.Cu")
		(net "P5E_PEX0_STN1_RX_DP<22>")
	)
	(segment
		(start 53.801772 -110.407958)
		(end 54.09692 -110.11281)
		(width 0.13462)
		(layer "F.Cu")
		(net "P5E_PEX0_STN1_RX_DP<22>")
	)
	(segment
		(start 51.130454 -110.245144)
		(end 51.293268 -110.407958)
		(width 0.13462)
		(layer "F.Cu")
		(net "P5E_PEX0_STN1_RX_DP<22>")
	)
	(segment
		(start 51.293268 -110.407958)
		(end 53.801772 -110.407958)
		(width 0.13462)
		(layer "F.Cu")
		(net "P5E_PEX0_STN1_RX_DP<22>")
	)
	(segment
		(start 34.081974 -150.991316)
		(end 34.076132 -151.024336)
		(width 0.1651)
		(layer "In5.Cu")
		(net "P5E_PEX0_STN1_RX_DP<22>")
	)
	(segment
		(start 65.349628 -273.784314)
		(end 65.349628 -274.049744)
		(width 0.1143)
		(layer "In5.Cu")
		(net "P5E_PEX0_STN1_RX_DP<22>")
	)
	(segment
		(start 34.534856 -158.40456)
		(end 35.62477 -164.482018)
		(width 0.1651)
		(layer "In5.Cu")
		(net "P5E_PEX0_STN1_RX_DP<22>")
	)
	(segment
		(start 64.994536 -273.670014)
		(end 65.235328 -273.670014)
		(width 0.1143)
		(layer "In5.Cu")
		(net "P5E_PEX0_STN1_RX_DP<22>")
	)
	(segment
		(start 39.008812 -136.92378)
		(end 37.0713 -140.590016)
		(width 0.1651)
		(layer "In5.Cu")
		(net "P5E_PEX0_STN1_RX_DP<22>")
	)
	(segment
		(start 42.601134 -115.598956)
		(end 39.008812 -136.92378)
		(width 0.1651)
		(layer "In5.Cu")
		(net "P5E_PEX0_STN1_RX_DP<22>")
	)
	(segment
		(start 43.24731 -114.534442)
		(end 42.916602 -114.922554)
		(width 0.1651)
		(layer "In5.Cu")
		(net "P5E_PEX0_STN1_RX_DP<22>")
	)
	(segment
		(start 54.09692 -110.11281)
		(end 53.80609 -110.40364)
		(width 0.1651)
		(layer "In5.Cu")
		(net "P5E_PEX0_STN1_RX_DP<22>")
	)
	(segment
		(start 44.488608 -114.177826)
		(end 44.323254 -114.24666)
		(width 0.1651)
		(layer "In5.Cu")
		(net "P5E_PEX0_STN1_RX_DP<22>")
	)
	(segment
		(start 65.235328 -273.670014)
		(end 65.349628 -273.784314)
		(width 0.1143)
		(layer "In5.Cu")
		(net "P5E_PEX0_STN1_RX_DP<22>")
	)
	(segment
		(start 53.80609 -110.40364)
		(end 51.787298 -110.40364)
		(width 0.1651)
		(layer "In5.Cu")
		(net "P5E_PEX0_STN1_RX_DP<22>")
	)
	(segment
		(start 34.076132 -151.024336)
		(end 34.534856 -158.40456)
		(width 0.1651)
		(layer "In5.Cu")
		(net "P5E_PEX0_STN1_RX_DP<22>")
	)
	(segment
		(start 64.779652 -271.848072)
		(end 64.779652 -273.45513)
		(width 0.1143)
		(layer "In5.Cu")
		(net "P5E_PEX0_STN1_RX_DP<22>")
	)
	(segment
		(start 37.0713 -140.590016)
		(end 35.18408 -144.791938)
		(width 0.1651)
		(layer "In5.Cu")
		(net "P5E_PEX0_STN1_RX_DP<22>")
	)
	(segment
		(start 64.733932 -268.825472)
		(end 64.733932 -271.773904)
		(width 0.1651)
		(layer "In5.Cu")
		(net "P5E_PEX0_STN1_RX_DP<22>")
	)
	(segment
		(start 44.323254 -114.24666)
		(end 43.871642 -114.24666)
		(width 0.1651)
		(layer "In5.Cu")
		(net "P5E_PEX0_STN1_RX_DP<22>")
	)
	(segment
		(start 35.62477 -164.482018)
		(end 64.733932 -268.825472)
		(width 0.1651)
		(layer "In5.Cu")
		(net "P5E_PEX0_STN1_RX_DP<22>")
	)
	(segment
		(start 35.18408 -144.791938)
		(end 34.082228 -150.991316)
		(width 0.1651)
		(layer "In5.Cu")
		(net "P5E_PEX0_STN1_RX_DP<22>")
	)
	(segment
		(start 42.916602 -114.922554)
		(end 42.601134 -115.598956)
		(width 0.1651)
		(layer "In5.Cu")
		(net "P5E_PEX0_STN1_RX_DP<22>")
	)
	(segment
		(start 64.733932 -271.802352)
		(end 64.779652 -271.848072)
		(width 0.1143)
		(layer "In5.Cu")
		(net "P5E_PEX0_STN1_RX_DP<22>")
	)
	(segment
		(start 43.871642 -114.24666)
		(end 43.24731 -114.534442)
		(width 0.1651)
		(layer "In5.Cu")
		(net "P5E_PEX0_STN1_RX_DP<22>")
	)
	(segment
		(start 64.779652 -273.45513)
		(end 64.994536 -273.670014)
		(width 0.1143)
		(layer "In5.Cu")
		(net "P5E_PEX0_STN1_RX_DP<22>")
	)
	(segment
		(start 51.787298 -110.40364)
		(end 47.584614 -112.114584)
		(width 0.1651)
		(layer "In5.Cu")
		(net "P5E_PEX0_STN1_RX_DP<22>")
	)
	(segment
		(start 64.733932 -271.773904)
		(end 64.733932 -271.802352)
		(width 0.1143)
		(layer "In5.Cu")
		(net "P5E_PEX0_STN1_RX_DP<22>")
	)
	(segment
		(start 34.082228 -150.991316)
		(end 34.081974 -150.991316)
		(width 0.1651)
		(layer "In5.Cu")
		(net "P5E_PEX0_STN1_RX_DP<22>")
	)
	(segment
		(start 47.584614 -112.114584)
		(end 44.488608 -114.177826)
		(width 0.1651)
		(layer "In5.Cu")
		(net "P5E_PEX0_STN1_RX_DP<22>")
	)
	(segment
		(start 86.538562 -356.831646)
		(end 86.218522 -356.511606)
		(width 0.13462)
		(layer "F.Cu")
		(net "P5E_PEX0_STN6_TX_C_DP<99>")
	)
	(segment
		(start 86.243922 -357.75773)
		(end 86.538562 -357.46309)
		(width 0.13462)
		(layer "F.Cu")
		(net "P5E_PEX0_STN6_TX_C_DP<99>")
	)
	(segment
		(start 86.538562 -357.46309)
		(end 86.538562 -356.831646)
		(width 0.13462)
		(layer "F.Cu")
		(net "P5E_PEX0_STN6_TX_C_DP<99>")
	)
	(segment
		(start 83.21675 -366.060736)
		(end 81.602326 -369.474242)
		(width 0.1651)
		(layer "In13.Cu")
		(net "P5E_PEX0_STN6_TX_C_DP<99>")
	)
	(segment
		(start 83.174332 -365.942372)
		(end 83.21675 -366.060736)
		(width 0.1651)
		(layer "In13.Cu")
		(net "P5E_PEX0_STN6_TX_C_DP<99>")
	)
	(segment
		(start 81.32699 -382.69926)
		(end 80.837024 -382.69926)
		(width 0.1651)
		(layer "In13.Cu")
		(net "P5E_PEX0_STN6_TX_C_DP<99>")
	)
	(segment
		(start 83.386422 -365.494316)
		(end 83.174332 -365.942372)
		(width 0.1651)
		(layer "In13.Cu")
		(net "P5E_PEX0_STN6_TX_C_DP<99>")
	)
	(segment
		(start 86.243922 -357.75773)
		(end 86.534752 -358.04856)
		(width 0.1651)
		(layer "In13.Cu")
		(net "P5E_PEX0_STN6_TX_C_DP<99>")
	)
	(segment
		(start 84.504022 -363.339126)
		(end 84.385658 -363.381544)
		(width 0.1651)
		(layer "In13.Cu")
		(net "P5E_PEX0_STN6_TX_C_DP<99>")
	)
	(segment
		(start 83.88604 -364.43793)
		(end 83.674204 -364.885986)
		(width 0.1651)
		(layer "In13.Cu")
		(net "P5E_PEX0_STN6_TX_C_DP<99>")
	)
	(segment
		(start 81.602326 -382.423924)
		(end 81.32699 -382.69926)
		(width 0.1651)
		(layer "In13.Cu")
		(net "P5E_PEX0_STN6_TX_C_DP<99>")
	)
	(segment
		(start 86.534752 -358.04856)
		(end 86.534752 -359.045764)
		(width 0.1651)
		(layer "In13.Cu")
		(net "P5E_PEX0_STN6_TX_C_DP<99>")
	)
	(segment
		(start 84.385658 -363.381544)
		(end 84.173822 -363.8296)
		(width 0.1651)
		(layer "In13.Cu")
		(net "P5E_PEX0_STN6_TX_C_DP<99>")
	)
	(segment
		(start 86.534752 -359.045764)
		(end 84.504022 -363.339126)
		(width 0.1651)
		(layer "In13.Cu")
		(net "P5E_PEX0_STN6_TX_C_DP<99>")
	)
	(segment
		(start 84.215986 -363.947964)
		(end 84.004404 -364.395512)
		(width 0.1651)
		(layer "In13.Cu")
		(net "P5E_PEX0_STN6_TX_C_DP<99>")
	)
	(segment
		(start 83.674204 -364.885986)
		(end 83.716368 -365.00435)
		(width 0.1651)
		(layer "In13.Cu")
		(net "P5E_PEX0_STN6_TX_C_DP<99>")
	)
	(segment
		(start 80.710024 -382.57226)
		(end 80.710024 -382.18999)
		(width 0.1651)
		(layer "In13.Cu")
		(net "P5E_PEX0_STN6_TX_C_DP<99>")
	)
	(segment
		(start 81.602326 -369.474242)
		(end 81.602326 -382.423924)
		(width 0.1651)
		(layer "In13.Cu")
		(net "P5E_PEX0_STN6_TX_C_DP<99>")
	)
	(segment
		(start 84.173822 -363.8296)
		(end 84.215986 -363.947964)
		(width 0.1651)
		(layer "In13.Cu")
		(net "P5E_PEX0_STN6_TX_C_DP<99>")
	)
	(segment
		(start 83.716368 -365.00435)
		(end 83.504786 -365.451898)
		(width 0.1651)
		(layer "In13.Cu")
		(net "P5E_PEX0_STN6_TX_C_DP<99>")
	)
	(segment
		(start 83.504786 -365.451898)
		(end 83.386422 -365.494316)
		(width 0.1651)
		(layer "In13.Cu")
		(net "P5E_PEX0_STN6_TX_C_DP<99>")
	)
	(segment
		(start 80.837024 -382.69926)
		(end 80.710024 -382.57226)
		(width 0.1651)
		(layer "In13.Cu")
		(net "P5E_PEX0_STN6_TX_C_DP<99>")
	)
	(segment
		(start 84.004404 -364.395512)
		(end 83.88604 -364.43793)
		(width 0.1651)
		(layer "In13.Cu")
		(net "P5E_PEX0_STN6_TX_C_DP<99>")
	)
	(segment
		(start 242.864894 -28.99029)
		(end 242.38585 -28.99029)
		(width 0.13462)
		(layer "F.Cu")
		(net "P5E_PEX2_STN2_RX_DP<44>")
	)
	(segment
		(start 242.864894 -28.990036)
		(end 242.864894 -28.99029)
		(width 0.13462)
		(layer "F.Cu")
		(net "P5E_PEX2_STN2_RX_DP<44>")
	)
	(segment
		(start 242.22456 -28.829)
		(end 241.558064 -28.829)
		(width 0.13462)
		(layer "F.Cu")
		(net "P5E_PEX2_STN2_RX_DP<44>")
	)
	(segment
		(start 242.38585 -28.99029)
		(end 242.22456 -28.829)
		(width 0.13462)
		(layer "F.Cu")
		(net "P5E_PEX2_STN2_RX_DP<44>")
	)
	(segment
		(start 241.558064 -28.829)
		(end 241.264694 -29.12237)
		(width 0.13462)
		(layer "F.Cu")
		(net "P5E_PEX2_STN2_RX_DP<44>")
	)
	(segment
		(start 241.510058 -28.877006)
		(end 241.619786 -28.83154)
		(width 0.1651)
		(layer "In7.Cu")
		(net "P5E_PEX2_STN2_RX_DP<44>")
	)
	(segment
		(start 276.40153 -238.07547)
		(end 278.007572 -255.61925)
		(width 0.1651)
		(layer "In7.Cu")
		(net "P5E_PEX2_STN2_RX_DP<44>")
	)
	(segment
		(start 277.93061 -263.48055)
		(end 278.883618 -269.523718)
		(width 0.1651)
		(layer "In7.Cu")
		(net "P5E_PEX2_STN2_RX_DP<44>")
	)
	(segment
		(start 245.224808 -61.849762)
		(end 245.035324 -85.214206)
		(width 0.1651)
		(layer "In7.Cu")
		(net "P5E_PEX2_STN2_RX_DP<44>")
	)
	(segment
		(start 279.499822 -275.684488)
		(end 279.499822 -275.949918)
		(width 0.1143)
		(layer "In7.Cu")
		(net "P5E_PEX2_STN2_RX_DP<44>")
	)
	(segment
		(start 278.883618 -271.392904)
		(end 278.883618 -271.421352)
		(width 0.1143)
		(layer "In7.Cu")
		(net "P5E_PEX2_STN2_RX_DP<44>")
	)
	(segment
		(start 279.14473 -275.570188)
		(end 279.385522 -275.570188)
		(width 0.1143)
		(layer "In7.Cu")
		(net "P5E_PEX2_STN2_RX_DP<44>")
	)
	(segment
		(start 278.929338 -271.467072)
		(end 278.929338 -275.354796)
		(width 0.1143)
		(layer "In7.Cu")
		(net "P5E_PEX2_STN2_RX_DP<44>")
	)
	(segment
		(start 247.225058 -39.137844)
		(end 245.079012 -49.388014)
		(width 0.1651)
		(layer "In7.Cu")
		(net "P5E_PEX2_STN2_RX_DP<44>")
	)
	(segment
		(start 245.289578 -33.354772)
		(end 245.422674 -33.408874)
		(width 0.1651)
		(layer "In7.Cu")
		(net "P5E_PEX2_STN2_RX_DP<44>")
	)
	(segment
		(start 244.90426 -32.178498)
		(end 245.151148 -32.764984)
		(width 0.1651)
		(layer "In7.Cu")
		(net "P5E_PEX2_STN2_RX_DP<44>")
	)
	(segment
		(start 245.079012 -49.388014)
		(end 244.95506 -57.335674)
		(width 0.1651)
		(layer "In7.Cu")
		(net "P5E_PEX2_STN2_RX_DP<44>")
	)
	(segment
		(start 241.619786 -28.83154)
		(end 241.886994 -28.83154)
		(width 0.1651)
		(layer "In7.Cu")
		(net "P5E_PEX2_STN2_RX_DP<44>")
	)
	(segment
		(start 245.560596 -33.998154)
		(end 245.753128 -34.454846)
		(width 0.1651)
		(layer "In7.Cu")
		(net "P5E_PEX2_STN2_RX_DP<44>")
	)
	(segment
		(start 245.886224 -34.509202)
		(end 247.248426 -37.742622)
		(width 0.1651)
		(layer "In7.Cu")
		(net "P5E_PEX2_STN2_RX_DP<44>")
	)
	(segment
		(start 247.248426 -37.742622)
		(end 247.225058 -39.137844)
		(width 0.1651)
		(layer "In7.Cu")
		(net "P5E_PEX2_STN2_RX_DP<44>")
	)
	(segment
		(start 278.929338 -275.354796)
		(end 279.14473 -275.570188)
		(width 0.1143)
		(layer "In7.Cu")
		(net "P5E_PEX2_STN2_RX_DP<44>")
	)
	(segment
		(start 243.360194 -30.634432)
		(end 244.90426 -32.178498)
		(width 0.1651)
		(layer "In7.Cu")
		(net "P5E_PEX2_STN2_RX_DP<44>")
	)
	(segment
		(start 241.886994 -28.83154)
		(end 242.695984 -29.64053)
		(width 0.1651)
		(layer "In7.Cu")
		(net "P5E_PEX2_STN2_RX_DP<44>")
	)
	(segment
		(start 278.883618 -271.421352)
		(end 278.929338 -271.467072)
		(width 0.1143)
		(layer "In7.Cu")
		(net "P5E_PEX2_STN2_RX_DP<44>")
	)
	(segment
		(start 244.95506 -57.335674)
		(end 245.224808 -60.073794)
		(width 0.1651)
		(layer "In7.Cu")
		(net "P5E_PEX2_STN2_RX_DP<44>")
	)
	(segment
		(start 255.400048 -119.40921)
		(end 258.687062 -144.398238)
		(width 0.1651)
		(layer "In7.Cu")
		(net "P5E_PEX2_STN2_RX_DP<44>")
	)
	(segment
		(start 245.614952 -33.865312)
		(end 245.560596 -33.998154)
		(width 0.1651)
		(layer "In7.Cu")
		(net "P5E_PEX2_STN2_RX_DP<44>")
	)
	(segment
		(start 241.264694 -29.12237)
		(end 241.510058 -28.877006)
		(width 0.1651)
		(layer "In7.Cu")
		(net "P5E_PEX2_STN2_RX_DP<44>")
	)
	(segment
		(start 245.753128 -34.454846)
		(end 245.886224 -34.509202)
		(width 0.1651)
		(layer "In7.Cu")
		(net "P5E_PEX2_STN2_RX_DP<44>")
	)
	(segment
		(start 245.422674 -33.408874)
		(end 245.614952 -33.865312)
		(width 0.1651)
		(layer "In7.Cu")
		(net "P5E_PEX2_STN2_RX_DP<44>")
	)
	(segment
		(start 278.007572 -255.61925)
		(end 277.93061 -263.48055)
		(width 0.1651)
		(layer "In7.Cu")
		(net "P5E_PEX2_STN2_RX_DP<44>")
	)
	(segment
		(start 245.224808 -60.073794)
		(end 245.224808 -61.849762)
		(width 0.1651)
		(layer "In7.Cu")
		(net "P5E_PEX2_STN2_RX_DP<44>")
	)
	(segment
		(start 245.097046 -32.89808)
		(end 245.289578 -33.354772)
		(width 0.1651)
		(layer "In7.Cu")
		(net "P5E_PEX2_STN2_RX_DP<44>")
	)
	(segment
		(start 279.385522 -275.570188)
		(end 279.499822 -275.684488)
		(width 0.1143)
		(layer "In7.Cu")
		(net "P5E_PEX2_STN2_RX_DP<44>")
	)
	(segment
		(start 258.687062 -144.398238)
		(end 276.40153 -238.07547)
		(width 0.1651)
		(layer "In7.Cu")
		(net "P5E_PEX2_STN2_RX_DP<44>")
	)
	(segment
		(start 242.695984 -29.64053)
		(end 243.360194 -30.634432)
		(width 0.1651)
		(layer "In7.Cu")
		(net "P5E_PEX2_STN2_RX_DP<44>")
	)
	(segment
		(start 278.883618 -269.523718)
		(end 278.883618 -271.392904)
		(width 0.1651)
		(layer "In7.Cu")
		(net "P5E_PEX2_STN2_RX_DP<44>")
	)
	(segment
		(start 245.151148 -32.764984)
		(end 245.097046 -32.89808)
		(width 0.1651)
		(layer "In7.Cu")
		(net "P5E_PEX2_STN2_RX_DP<44>")
	)
	(segment
		(start 245.035324 -85.214206)
		(end 255.400048 -119.40921)
		(width 0.1651)
		(layer "In7.Cu")
		(net "P5E_PEX2_STN2_RX_DP<44>")
	)
	(segment
		(start 287.099756 -316.140592)
		(end 287.099756 -315.849762)
		(width 0.1143)
		(layer "In9.Cu")
		(net "P5E_PEX2_STN6_RX_DP<99>")
	)
	(segment
		(start 286.755078 -316.229492)
		(end 287.010856 -316.229492)
		(width 0.1143)
		(layer "In9.Cu")
		(net "P5E_PEX2_STN6_RX_DP<99>")
	)
	(segment
		(start 320.566034 -342.411558)
		(end 320.190114 -341.482934)
		(width 0.1651)
		(layer "In9.Cu")
		(net "P5E_PEX2_STN6_RX_DP<99>")
	)
	(segment
		(start 339.292438 -367.538762)
		(end 338.878418 -367.267236)
		(width 0.1651)
		(layer "In9.Cu")
		(net "P5E_PEX2_STN6_RX_DP<99>")
	)
	(segment
		(start 331.29093 -363.36986)
		(end 321.366896 -359.35285)
		(width 0.1651)
		(layer "In9.Cu")
		(net "P5E_PEX2_STN6_RX_DP<99>")
	)
	(segment
		(start 295.234106 -331.76083)
		(end 290.392612 -328.599546)
		(width 0.1651)
		(layer "In9.Cu")
		(net "P5E_PEX2_STN6_RX_DP<99>")
	)
	(segment
		(start 333.45247 -364.326932)
		(end 333.410306 -364.227872)
		(width 0.1651)
		(layer "In9.Cu")
		(net "P5E_PEX2_STN6_RX_DP<99>")
	)
	(segment
		(start 333.911702 -364.513114)
		(end 333.45247 -364.326932)
		(width 0.1651)
		(layer "In9.Cu")
		(net "P5E_PEX2_STN6_RX_DP<99>")
	)
	(segment
		(start 331.333094 -363.469174)
		(end 331.29093 -363.36986)
		(width 0.1651)
		(layer "In9.Cu")
		(net "P5E_PEX2_STN6_RX_DP<99>")
	)
	(segment
		(start 337.922616 -366.640364)
		(end 337.816952 -366.662208)
		(width 0.1651)
		(layer "In9.Cu")
		(net "P5E_PEX2_STN6_RX_DP<99>")
	)
	(segment
		(start 337.816952 -366.662208)
		(end 337.402678 -366.390428)
		(width 0.1651)
		(layer "In9.Cu")
		(net "P5E_PEX2_STN6_RX_DP<99>")
	)
	(segment
		(start 286.483806 -324.201282)
		(end 286.483806 -319.916048)
		(width 0.1651)
		(layer "In9.Cu")
		(net "P5E_PEX2_STN6_RX_DP<99>")
	)
	(segment
		(start 286.829754 -325.036434)
		(end 286.483806 -324.201282)
		(width 0.1651)
		(layer "In9.Cu")
		(net "P5E_PEX2_STN6_RX_DP<99>")
	)
	(segment
		(start 334.011016 -364.47095)
		(end 333.911702 -364.513114)
		(width 0.1651)
		(layer "In9.Cu")
		(net "P5E_PEX2_STN6_RX_DP<99>")
	)
	(segment
		(start 290.392612 -328.599546)
		(end 286.829754 -325.036434)
		(width 0.1651)
		(layer "In9.Cu")
		(net "P5E_PEX2_STN6_RX_DP<99>")
	)
	(segment
		(start 339.72881 -367.915952)
		(end 339.314536 -367.644172)
		(width 0.1651)
		(layer "In9.Cu")
		(net "P5E_PEX2_STN6_RX_DP<99>")
	)
	(segment
		(start 332.852014 -364.084108)
		(end 332.392782 -363.89818)
		(width 0.1651)
		(layer "In9.Cu")
		(net "P5E_PEX2_STN6_RX_DP<99>")
	)
	(segment
		(start 339.314536 -367.644172)
		(end 339.292438 -367.538762)
		(width 0.1651)
		(layer "In9.Cu")
		(net "P5E_PEX2_STN6_RX_DP<99>")
	)
	(segment
		(start 341.134192 -369.004342)
		(end 340.92896 -368.611912)
		(width 0.1651)
		(layer "In9.Cu")
		(net "P5E_PEX2_STN6_RX_DP<99>")
	)
	(segment
		(start 338.878418 -367.267236)
		(end 338.772754 -367.28908)
		(width 0.1651)
		(layer "In9.Cu")
		(net "P5E_PEX2_STN6_RX_DP<99>")
	)
	(segment
		(start 321.366896 -359.35285)
		(end 320.566034 -358.551734)
		(width 0.1651)
		(layer "In9.Cu")
		(net "P5E_PEX2_STN6_RX_DP<99>")
	)
	(segment
		(start 286.483806 -319.8876)
		(end 286.529526 -319.84188)
		(width 0.1143)
		(layer "In9.Cu")
		(net "P5E_PEX2_STN6_RX_DP<99>")
	)
	(segment
		(start 339.83422 -367.894108)
		(end 339.72881 -367.915952)
		(width 0.1651)
		(layer "In9.Cu")
		(net "P5E_PEX2_STN6_RX_DP<99>")
	)
	(segment
		(start 338.35848 -367.0173)
		(end 338.336636 -366.91189)
		(width 0.1651)
		(layer "In9.Cu")
		(net "P5E_PEX2_STN6_RX_DP<99>")
	)
	(segment
		(start 286.529526 -319.84188)
		(end 286.529526 -316.455044)
		(width 0.1143)
		(layer "In9.Cu")
		(net "P5E_PEX2_STN6_RX_DP<99>")
	)
	(segment
		(start 286.529526 -316.455044)
		(end 286.755078 -316.229492)
		(width 0.1143)
		(layer "In9.Cu")
		(net "P5E_PEX2_STN6_RX_DP<99>")
	)
	(segment
		(start 337.38058 -366.285018)
		(end 335.587848 -365.109252)
		(width 0.1651)
		(layer "In9.Cu")
		(net "P5E_PEX2_STN6_RX_DP<99>")
	)
	(segment
		(start 286.483806 -319.916048)
		(end 286.483806 -319.8876)
		(width 0.1143)
		(layer "In9.Cu")
		(net "P5E_PEX2_STN6_RX_DP<99>")
	)
	(segment
		(start 333.410306 -364.227872)
		(end 332.951328 -364.042198)
		(width 0.1651)
		(layer "In9.Cu")
		(net "P5E_PEX2_STN6_RX_DP<99>")
	)
	(segment
		(start 320.566034 -358.551734)
		(end 320.566034 -342.411558)
		(width 0.1651)
		(layer "In9.Cu")
		(net "P5E_PEX2_STN6_RX_DP<99>")
	)
	(segment
		(start 338.336636 -366.91189)
		(end 337.922616 -366.640364)
		(width 0.1651)
		(layer "In9.Cu")
		(net "P5E_PEX2_STN6_RX_DP<99>")
	)
	(segment
		(start 338.772754 -367.28908)
		(end 338.35848 -367.0173)
		(width 0.1651)
		(layer "In9.Cu")
		(net "P5E_PEX2_STN6_RX_DP<99>")
	)
	(segment
		(start 340.92896 -368.611912)
		(end 339.83422 -367.894108)
		(width 0.1651)
		(layer "In9.Cu")
		(net "P5E_PEX2_STN6_RX_DP<99>")
	)
	(segment
		(start 340.847426 -374.899174)
		(end 341.134192 -374.612408)
		(width 0.1651)
		(layer "In9.Cu")
		(net "P5E_PEX2_STN6_RX_DP<99>")
	)
	(segment
		(start 337.402678 -366.390428)
		(end 337.38058 -366.285018)
		(width 0.1651)
		(layer "In9.Cu")
		(net "P5E_PEX2_STN6_RX_DP<99>")
	)
	(segment
		(start 335.587848 -365.109252)
		(end 334.011016 -364.47095)
		(width 0.1651)
		(layer "In9.Cu")
		(net "P5E_PEX2_STN6_RX_DP<99>")
	)
	(segment
		(start 331.792326 -363.655102)
		(end 331.333094 -363.469174)
		(width 0.1651)
		(layer "In9.Cu")
		(net "P5E_PEX2_STN6_RX_DP<99>")
	)
	(segment
		(start 341.134192 -374.612408)
		(end 341.134192 -369.004342)
		(width 0.1651)
		(layer "In9.Cu")
		(net "P5E_PEX2_STN6_RX_DP<99>")
	)
	(segment
		(start 287.010856 -316.229492)
		(end 287.099756 -316.140592)
		(width 0.1143)
		(layer "In9.Cu")
		(net "P5E_PEX2_STN6_RX_DP<99>")
	)
	(segment
		(start 332.350618 -363.798866)
		(end 331.89164 -363.613192)
		(width 0.1651)
		(layer "In9.Cu")
		(net "P5E_PEX2_STN6_RX_DP<99>")
	)
	(segment
		(start 340.41715 -374.899174)
		(end 340.847426 -374.899174)
		(width 0.1651)
		(layer "In9.Cu")
		(net "P5E_PEX2_STN6_RX_DP<99>")
	)
	(segment
		(start 332.951328 -364.042198)
		(end 332.852014 -364.084108)
		(width 0.1651)
		(layer "In9.Cu")
		(net "P5E_PEX2_STN6_RX_DP<99>")
	)
	(segment
		(start 320.190114 -341.482934)
		(end 295.234106 -331.76083)
		(width 0.1651)
		(layer "In9.Cu")
		(net "P5E_PEX2_STN6_RX_DP<99>")
	)
	(segment
		(start 340.29015 -374.772174)
		(end 340.41715 -374.899174)
		(width 0.1651)
		(layer "In9.Cu")
		(net "P5E_PEX2_STN6_RX_DP<99>")
	)
	(segment
		(start 332.392782 -363.89818)
		(end 332.350618 -363.798866)
		(width 0.1651)
		(layer "In9.Cu")
		(net "P5E_PEX2_STN6_RX_DP<99>")
	)
	(segment
		(start 340.29015 -374.390158)
		(end 340.29015 -374.772174)
		(width 0.1651)
		(layer "In9.Cu")
		(net "P5E_PEX2_STN6_RX_DP<99>")
	)
	(segment
		(start 331.89164 -363.613192)
		(end 331.792326 -363.655102)
		(width 0.1651)
		(layer "In9.Cu")
		(net "P5E_PEX2_STN6_RX_DP<99>")
	)
	(segment
		(start 393.824714 -339.490304)
		(end 393.985242 -339.508338)
		(width 0.1651)
		(layer "In15.Cu")
		(net "P5E_PEX3_STN5_RX_DP<90>")
	)
	(segment
		(start 392.136122 -340.98484)
		(end 393.41933 -339.960204)
		(width 0.1651)
		(layer "In15.Cu")
		(net "P5E_PEX3_STN5_RX_DP<90>")
	)
	(segment
		(start 379.89002 -370.872258)
		(end 380.01702 -370.999258)
		(width 0.1651)
		(layer "In15.Cu")
		(net "P5E_PEX3_STN5_RX_DP<90>")
	)
	(segment
		(start 393.437364 -339.799676)
		(end 393.824714 -339.490304)
		(width 0.1651)
		(layer "In15.Cu")
		(net "P5E_PEX3_STN5_RX_DP<90>")
	)
	(segment
		(start 380.734062 -370.712492)
		(end 380.734062 -369.555522)
		(width 0.1651)
		(layer "In15.Cu")
		(net "P5E_PEX3_STN5_RX_DP<90>")
	)
	(segment
		(start 393.985242 -339.508338)
		(end 394.372084 -339.199474)
		(width 0.1651)
		(layer "In15.Cu")
		(net "P5E_PEX3_STN5_RX_DP<90>")
	)
	(segment
		(start 394.777468 -338.729574)
		(end 394.937996 -338.747354)
		(width 0.1651)
		(layer "In15.Cu")
		(net "P5E_PEX3_STN5_RX_DP<90>")
	)
	(segment
		(start 414.900872 -322.807076)
		(end 415.883852 -321.5005)
		(width 0.1651)
		(layer "In15.Cu")
		(net "P5E_PEX3_STN5_RX_DP<90>")
	)
	(segment
		(start 416.14471 -316.229492)
		(end 416.385502 -316.229492)
		(width 0.1143)
		(layer "In15.Cu")
		(net "P5E_PEX3_STN5_RX_DP<90>")
	)
	(segment
		(start 415.883852 -321.5005)
		(end 415.883852 -319.969896)
		(width 0.1651)
		(layer "In15.Cu")
		(net "P5E_PEX3_STN5_RX_DP<90>")
	)
	(segment
		(start 415.883852 -319.941448)
		(end 415.929572 -319.895728)
		(width 0.1143)
		(layer "In15.Cu")
		(net "P5E_PEX3_STN5_RX_DP<90>")
	)
	(segment
		(start 395.851634 -338.017866)
		(end 414.900872 -322.807076)
		(width 0.1651)
		(layer "In15.Cu")
		(net "P5E_PEX3_STN5_RX_DP<90>")
	)
	(segment
		(start 379.89002 -370.489988)
		(end 379.89002 -370.872258)
		(width 0.1651)
		(layer "In15.Cu")
		(net "P5E_PEX3_STN5_RX_DP<90>")
	)
	(segment
		(start 416.385502 -316.229492)
		(end 416.499802 -316.115192)
		(width 0.1143)
		(layer "In15.Cu")
		(net "P5E_PEX3_STN5_RX_DP<90>")
	)
	(segment
		(start 416.499802 -316.115192)
		(end 416.499802 -315.849762)
		(width 0.1143)
		(layer "In15.Cu")
		(net "P5E_PEX3_STN5_RX_DP<90>")
	)
	(segment
		(start 395.324838 -338.43849)
		(end 395.338808 -338.313522)
		(width 0.1651)
		(layer "In15.Cu")
		(net "P5E_PEX3_STN5_RX_DP<90>")
	)
	(segment
		(start 394.390118 -339.038692)
		(end 394.777468 -338.729574)
		(width 0.1651)
		(layer "In15.Cu")
		(net "P5E_PEX3_STN5_RX_DP<90>")
	)
	(segment
		(start 415.929572 -316.44463)
		(end 416.14471 -316.229492)
		(width 0.1143)
		(layer "In15.Cu")
		(net "P5E_PEX3_STN5_RX_DP<90>")
	)
	(segment
		(start 395.851888 -338.01812)
		(end 395.851634 -338.017866)
		(width 0.1651)
		(layer "In15.Cu")
		(net "P5E_PEX3_STN5_RX_DP<90>")
	)
	(segment
		(start 393.41933 -339.960204)
		(end 393.437364 -339.799676)
		(width 0.1651)
		(layer "In15.Cu")
		(net "P5E_PEX3_STN5_RX_DP<90>")
	)
	(segment
		(start 380.447296 -370.999258)
		(end 380.734062 -370.712492)
		(width 0.1651)
		(layer "In15.Cu")
		(net "P5E_PEX3_STN5_RX_DP<90>")
	)
	(segment
		(start 381.48006 -367.986564)
		(end 391.165842 -359.14584)
		(width 0.1651)
		(layer "In15.Cu")
		(net "P5E_PEX3_STN5_RX_DP<90>")
	)
	(segment
		(start 395.851126 -338.01812)
		(end 395.851888 -338.01812)
		(width 0.1651)
		(layer "In15.Cu")
		(net "P5E_PEX3_STN5_RX_DP<90>")
	)
	(segment
		(start 394.937996 -338.747354)
		(end 395.324838 -338.43849)
		(width 0.1651)
		(layer "In15.Cu")
		(net "P5E_PEX3_STN5_RX_DP<90>")
	)
	(segment
		(start 391.165842 -359.14584)
		(end 391.68705 -357.965248)
		(width 0.1651)
		(layer "In15.Cu")
		(net "P5E_PEX3_STN5_RX_DP<90>")
	)
	(segment
		(start 380.734062 -369.555522)
		(end 381.48006 -367.986564)
		(width 0.1651)
		(layer "In15.Cu")
		(net "P5E_PEX3_STN5_RX_DP<90>")
	)
	(segment
		(start 395.338808 -338.313522)
		(end 395.726158 -338.00415)
		(width 0.1651)
		(layer "In15.Cu")
		(net "P5E_PEX3_STN5_RX_DP<90>")
	)
	(segment
		(start 394.372084 -339.199474)
		(end 394.390118 -339.038692)
		(width 0.1651)
		(layer "In15.Cu")
		(net "P5E_PEX3_STN5_RX_DP<90>")
	)
	(segment
		(start 391.68705 -342.114886)
		(end 392.136122 -340.98484)
		(width 0.1651)
		(layer "In15.Cu")
		(net "P5E_PEX3_STN5_RX_DP<90>")
	)
	(segment
		(start 415.929572 -319.895728)
		(end 415.929572 -316.44463)
		(width 0.1143)
		(layer "In15.Cu")
		(net "P5E_PEX3_STN5_RX_DP<90>")
	)
	(segment
		(start 415.883852 -319.969896)
		(end 415.883852 -319.941448)
		(width 0.1143)
		(layer "In15.Cu")
		(net "P5E_PEX3_STN5_RX_DP<90>")
	)
	(segment
		(start 391.68705 -357.965248)
		(end 391.68705 -342.114886)
		(width 0.1651)
		(layer "In15.Cu")
		(net "P5E_PEX3_STN5_RX_DP<90>")
	)
	(segment
		(start 395.726158 -338.00415)
		(end 395.851126 -338.01812)
		(width 0.1651)
		(layer "In15.Cu")
		(net "P5E_PEX3_STN5_RX_DP<90>")
	)
	(segment
		(start 380.01702 -370.999258)
		(end 380.447296 -370.999258)
		(width 0.1651)
		(layer "In15.Cu")
		(net "P5E_PEX3_STN5_RX_DP<90>")
	)
	(segment
		(start 73.257664 -101.240082)
		(end 74.676 -101.240082)
		(width 0.13208)
		(layer "F.Cu")
		(net "NCSI_NIC1_RXD1")
	)
	(via
		(at 74.676 -101.240082)
		(size 0.508)
		(drill 0.254)
		(layers "F.Cu" "B.Cu")
		(net "NCSI_NIC1_RXD1")
	)
	(segment
		(start 77.141832 -102.088696)
		(end 75.92695 -102.088696)
		(width 0.13208)
		(layer "B.Cu")
		(net "NCSI_NIC1_RXD1")
	)
	(segment
		(start 75.078336 -101.240082)
		(end 74.676 -101.240082)
		(width 0.13208)
		(layer "B.Cu")
		(net "NCSI_NIC1_RXD1")
	)
	(segment
		(start 75.92695 -102.088696)
		(end 75.078336 -101.240082)
		(width 0.13208)
		(layer "B.Cu")
		(net "NCSI_NIC1_RXD1")
	)
	(segment
		(start 329.671426 -24.910542)
		(end 329.671426 -24.942292)
		(width 0.13208)
		(layer "F.Cu")
		(net "DUALPORT_N_SSD11")
	)
	(segment
		(start 329.249532 -24.488648)
		(end 329.671426 -24.910542)
		(width 0.13208)
		(layer "F.Cu")
		(net "DUALPORT_N_SSD11")
	)
	(segment
		(start 330.687426 -24.942292)
		(end 329.671426 -24.942292)
		(width 0.13208)
		(layer "F.Cu")
		(net "DUALPORT_N_SSD11")
	)
	(segment
		(start 325.464678 -23.589996)
		(end 326.666352 -23.589996)
		(width 0.13208)
		(layer "F.Cu")
		(net "DUALPORT_N_SSD11")
	)
	(segment
		(start 327.020428 -24.488648)
		(end 329.249532 -24.488648)
		(width 0.13208)
		(layer "F.Cu")
		(net "DUALPORT_N_SSD11")
	)
	(segment
		(start 326.666352 -23.589996)
		(end 326.666352 -24.134572)
		(width 0.13208)
		(layer "F.Cu")
		(net "DUALPORT_N_SSD11")
	)
	(segment
		(start 326.666352 -24.134572)
		(end 327.020428 -24.488648)
		(width 0.13208)
		(layer "F.Cu")
		(net "DUALPORT_N_SSD11")
	)
	(via
		(at 326.666352 -23.589996)
		(size 0.508)
		(drill 0.254)
		(layers "F.Cu" "B.Cu")
		(net "DUALPORT_N_SSD11")
	)
	(segment
		(start 46.042326 -119.955056)
		(end 45.554392 -119.955056)
		(width 0.13462)
		(layer "F.Cu")
		(net "P5E_PEX0_STN1_TX_C_DN<24>")
	)
	(segment
		(start 45.391578 -119.792242)
		(end 37.22624 -119.792242)
		(width 0.13462)
		(layer "F.Cu")
		(net "P5E_PEX0_STN1_TX_C_DN<24>")
	)
	(segment
		(start 37.22624 -119.792242)
		(end 36.905184 -120.113298)
		(width 0.13462)
		(layer "F.Cu")
		(net "P5E_PEX0_STN1_TX_C_DN<24>")
	)
	(segment
		(start 45.554392 -119.955056)
		(end 45.391578 -119.792242)
		(width 0.13462)
		(layer "F.Cu")
		(net "P5E_PEX0_STN1_TX_C_DN<24>")
	)
	(segment
		(start 326.131174 -34.2265)
		(end 325.967598 -34.390076)
		(width 0.13462)
		(layer "F.Cu")
		(net "P5E_PEX2_STN2_TX_C_DP<35>")
	)
	(segment
		(start 330.047854 -34.2265)
		(end 326.131174 -34.2265)
		(width 0.13462)
		(layer "F.Cu")
		(net "P5E_PEX2_STN2_TX_C_DP<35>")
	)
	(segment
		(start 325.967598 -34.390076)
		(end 325.464678 -34.390076)
		(width 0.13462)
		(layer "F.Cu")
		(net "P5E_PEX2_STN2_TX_C_DP<35>")
	)
	(segment
		(start 330.36764 -34.546286)
		(end 330.047854 -34.2265)
		(width 0.13462)
		(layer "F.Cu")
		(net "P5E_PEX2_STN2_TX_C_DP<35>")
	)
	(segment
		(start 341.052404 -350.685354)
		(end 341.052404 -351.316798)
		(width 0.13462)
		(layer "F.Cu")
		(net "P5E_PEX2_STN6_TX_C_DN<98>")
	)
	(segment
		(start 341.052404 -351.316798)
		(end 341.347044 -351.611438)
		(width 0.13462)
		(layer "F.Cu")
		(net "P5E_PEX2_STN6_TX_C_DN<98>")
	)
	(segment
		(start 341.372444 -350.365314)
		(end 341.052404 -350.685354)
		(width 0.13462)
		(layer "F.Cu")
		(net "P5E_PEX2_STN6_TX_C_DN<98>")
	)
	(segment
		(start 343.616026 -383.629154)
		(end 343.16416 -384.08102)
		(width 0.1651)
		(layer "In13.Cu")
		(net "P5E_PEX2_STN6_TX_C_DN<98>")
	)
	(segment
		(start 341.056214 -352.473006)
		(end 339.501734 -354.027486)
		(width 0.1651)
		(layer "In13.Cu")
		(net "P5E_PEX2_STN6_TX_C_DN<98>")
	)
	(segment
		(start 339.501734 -358.902)
		(end 343.616026 -368.89436)
		(width 0.1651)
		(layer "In13.Cu")
		(net "P5E_PEX2_STN6_TX_C_DN<98>")
	)
	(segment
		(start 341.347044 -351.611438)
		(end 341.056214 -351.902268)
		(width 0.1651)
		(layer "In13.Cu")
		(net "P5E_PEX2_STN6_TX_C_DN<98>")
	)
	(segment
		(start 343.16416 -384.08102)
		(end 342.617044 -384.08102)
		(width 0.1651)
		(layer "In13.Cu")
		(net "P5E_PEX2_STN6_TX_C_DN<98>")
	)
	(segment
		(start 343.616026 -368.89436)
		(end 343.616026 -383.629154)
		(width 0.1651)
		(layer "In13.Cu")
		(net "P5E_PEX2_STN6_TX_C_DN<98>")
	)
	(segment
		(start 341.056214 -351.902268)
		(end 341.056214 -352.473006)
		(width 0.1651)
		(layer "In13.Cu")
		(net "P5E_PEX2_STN6_TX_C_DN<98>")
	)
	(segment
		(start 342.617044 -384.08102)
		(end 342.490044 -384.20802)
		(width 0.1651)
		(layer "In13.Cu")
		(net "P5E_PEX2_STN6_TX_C_DN<98>")
	)
	(segment
		(start 339.501734 -354.027486)
		(end 339.501734 -358.902)
		(width 0.1651)
		(layer "In13.Cu")
		(net "P5E_PEX2_STN6_TX_C_DN<98>")
	)
	(segment
		(start 342.490044 -384.20802)
		(end 342.490044 -384.590036)
		(width 0.1651)
		(layer "In13.Cu")
		(net "P5E_PEX2_STN6_TX_C_DN<98>")
	)
	(segment
		(start 419.729666 -316.44463)
		(end 419.944804 -316.229492)
		(width 0.1143)
		(layer "In15.Cu")
		(net "P5E_PEX3_STN5_RX_DP<94>")
	)
	(segment
		(start 408.988514 -338.220304)
		(end 409.27782 -337.817968)
		(width 0.1651)
		(layer "In15.Cu")
		(net "P5E_PEX3_STN5_RX_DP<94>")
	)
	(segment
		(start 409.437332 -337.791806)
		(end 409.726384 -337.389724)
		(width 0.1651)
		(layer "In15.Cu")
		(net "P5E_PEX3_STN5_RX_DP<94>")
	)
	(segment
		(start 404.302468 -357.605076)
		(end 406.925272 -341.608918)
		(width 0.1651)
		(layer "In15.Cu")
		(net "P5E_PEX3_STN5_RX_DP<94>")
	)
	(segment
		(start 409.989528 -336.827876)
		(end 410.14904 -336.801714)
		(width 0.1651)
		(layer "In15.Cu")
		(net "P5E_PEX3_STN5_RX_DP<94>")
	)
	(segment
		(start 410.14904 -336.801714)
		(end 410.438092 -336.399632)
		(width 0.1651)
		(layer "In15.Cu")
		(net "P5E_PEX3_STN5_RX_DP<94>")
	)
	(segment
		(start 388.81685 -370.999258)
		(end 389.247126 -370.999258)
		(width 0.1651)
		(layer "In15.Cu")
		(net "P5E_PEX3_STN5_RX_DP<94>")
	)
	(segment
		(start 419.683946 -319.969896)
		(end 419.683946 -319.941448)
		(width 0.1143)
		(layer "In15.Cu")
		(net "P5E_PEX3_STN5_RX_DP<94>")
	)
	(segment
		(start 410.701236 -335.837784)
		(end 410.860748 -335.811622)
		(width 0.1651)
		(layer "In15.Cu")
		(net "P5E_PEX3_STN5_RX_DP<94>")
	)
	(segment
		(start 418.7952 -324.773798)
		(end 419.683946 -323.177154)
		(width 0.1651)
		(layer "In15.Cu")
		(net "P5E_PEX3_STN5_RX_DP<94>")
	)
	(segment
		(start 409.726384 -337.389724)
		(end 409.700222 -337.230212)
		(width 0.1651)
		(layer "In15.Cu")
		(net "P5E_PEX3_STN5_RX_DP<94>")
	)
	(segment
		(start 419.729666 -319.895728)
		(end 419.729666 -316.44463)
		(width 0.1143)
		(layer "In15.Cu")
		(net "P5E_PEX3_STN5_RX_DP<94>")
	)
	(segment
		(start 409.27782 -337.817968)
		(end 409.437332 -337.791806)
		(width 0.1651)
		(layer "In15.Cu")
		(net "P5E_PEX3_STN5_RX_DP<94>")
	)
	(segment
		(start 410.860748 -335.811622)
		(end 410.861002 -335.811622)
		(width 0.1651)
		(layer "In15.Cu")
		(net "P5E_PEX3_STN5_RX_DP<94>")
	)
	(segment
		(start 420.299896 -316.115192)
		(end 420.299896 -315.849762)
		(width 0.1143)
		(layer "In15.Cu")
		(net "P5E_PEX3_STN5_RX_DP<94>")
	)
	(segment
		(start 420.185596 -316.229492)
		(end 420.299896 -316.115192)
		(width 0.1143)
		(layer "In15.Cu")
		(net "P5E_PEX3_STN5_RX_DP<94>")
	)
	(segment
		(start 388.68985 -370.872258)
		(end 388.81685 -370.999258)
		(width 0.1651)
		(layer "In15.Cu")
		(net "P5E_PEX3_STN5_RX_DP<94>")
	)
	(segment
		(start 410.438092 -336.399632)
		(end 410.41193 -336.24012)
		(width 0.1651)
		(layer "In15.Cu")
		(net "P5E_PEX3_STN5_RX_DP<94>")
	)
	(segment
		(start 389.533892 -370.712492)
		(end 389.533892 -369.5827)
		(width 0.1651)
		(layer "In15.Cu")
		(net "P5E_PEX3_STN5_RX_DP<94>")
	)
	(segment
		(start 410.861002 -335.811622)
		(end 418.7952 -324.773798)
		(width 0.1651)
		(layer "In15.Cu")
		(net "P5E_PEX3_STN5_RX_DP<94>")
	)
	(segment
		(start 409.700222 -337.230212)
		(end 409.989528 -336.827876)
		(width 0.1651)
		(layer "In15.Cu")
		(net "P5E_PEX3_STN5_RX_DP<94>")
	)
	(segment
		(start 419.683946 -319.941448)
		(end 419.729666 -319.895728)
		(width 0.1143)
		(layer "In15.Cu")
		(net "P5E_PEX3_STN5_RX_DP<94>")
	)
	(segment
		(start 410.41193 -336.24012)
		(end 410.701236 -335.837784)
		(width 0.1651)
		(layer "In15.Cu")
		(net "P5E_PEX3_STN5_RX_DP<94>")
	)
	(segment
		(start 389.247126 -370.999258)
		(end 389.533892 -370.712492)
		(width 0.1651)
		(layer "In15.Cu")
		(net "P5E_PEX3_STN5_RX_DP<94>")
	)
	(segment
		(start 388.68985 -370.489988)
		(end 388.68985 -370.872258)
		(width 0.1651)
		(layer "In15.Cu")
		(net "P5E_PEX3_STN5_RX_DP<94>")
	)
	(segment
		(start 403.862032 -358.650286)
		(end 404.302468 -357.605076)
		(width 0.1651)
		(layer "In15.Cu")
		(net "P5E_PEX3_STN5_RX_DP<94>")
	)
	(segment
		(start 407.824178 -340.035896)
		(end 409.014676 -338.379816)
		(width 0.1651)
		(layer "In15.Cu")
		(net "P5E_PEX3_STN5_RX_DP<94>")
	)
	(segment
		(start 419.683946 -323.177154)
		(end 419.683946 -319.969896)
		(width 0.1651)
		(layer "In15.Cu")
		(net "P5E_PEX3_STN5_RX_DP<94>")
	)
	(segment
		(start 389.533892 -369.5827)
		(end 390.038336 -368.393218)
		(width 0.1651)
		(layer "In15.Cu")
		(net "P5E_PEX3_STN5_RX_DP<94>")
	)
	(segment
		(start 419.944804 -316.229492)
		(end 420.185596 -316.229492)
		(width 0.1143)
		(layer "In15.Cu")
		(net "P5E_PEX3_STN5_RX_DP<94>")
	)
	(segment
		(start 409.014676 -338.379816)
		(end 408.988514 -338.220304)
		(width 0.1651)
		(layer "In15.Cu")
		(net "P5E_PEX3_STN5_RX_DP<94>")
	)
	(segment
		(start 406.925272 -341.608918)
		(end 407.824178 -340.035896)
		(width 0.1651)
		(layer "In15.Cu")
		(net "P5E_PEX3_STN5_RX_DP<94>")
	)
	(segment
		(start 390.038336 -368.393218)
		(end 403.862032 -358.650286)
		(width 0.1651)
		(layer "In15.Cu")
		(net "P5E_PEX3_STN5_RX_DP<94>")
	)
	(segment
		(start 74.737976 -104.840024)
		(end 75.692 -103.886)
		(width 0.13208)
		(layer "F.Cu")
		(net "NCSI_NIC1_CRS_DV")
	)
	(segment
		(start 73.257664 -104.840024)
		(end 74.737976 -104.840024)
		(width 0.13208)
		(layer "F.Cu")
		(net "NCSI_NIC1_CRS_DV")
	)
	(via
		(at 75.692 -103.886)
		(size 0.508)
		(drill 0.254)
		(layers "F.Cu" "B.Cu")
		(net "NCSI_NIC1_CRS_DV")
	)
	(segment
		(start 76.434696 -104.120696)
		(end 76.2 -103.886)
		(width 0.13208)
		(layer "B.Cu")
		(net "NCSI_NIC1_CRS_DV")
	)
	(segment
		(start 77.141832 -104.120696)
		(end 76.434696 -104.120696)
		(width 0.13208)
		(layer "B.Cu")
		(net "NCSI_NIC1_CRS_DV")
	)
	(segment
		(start 76.2 -103.886)
		(end 75.692 -103.886)
		(width 0.13208)
		(layer "B.Cu")
		(net "NCSI_NIC1_CRS_DV")
	)
	(segment
		(start 294.86479 -24.790146)
		(end 293.219378 -24.790146)
		(width 0.13208)
		(layer "F.Cu")
		(net "PU_CLKREQ10")
	)
	(segment
		(start 293.219378 -24.790146)
		(end 293.202106 -24.807418)
		(width 0.13208)
		(layer "F.Cu")
		(net "PU_CLKREQ10")
	)
	(segment
		(start 292.37178 -24.807418)
		(end 293.202106 -24.807418)
		(width 0.13208)
		(layer "F.Cu")
		(net "PU_CLKREQ10")
	)
	(via
		(at 293.202106 -24.807418)
		(size 0.508)
		(drill 0.254)
		(layers "F.Cu" "B.Cu")
		(net "PU_CLKREQ10")
	)
	(segment
		(start 45.554392 -134.765034)
		(end 45.391578 -134.60222)
		(width 0.13462)
		(layer "F.Cu")
		(net "P5E_PEX0_STN1_TX_C_DN<30>")
	)
	(segment
		(start 46.042326 -134.765034)
		(end 45.554392 -134.765034)
		(width 0.13462)
		(layer "F.Cu")
		(net "P5E_PEX0_STN1_TX_C_DN<30>")
	)
	(segment
		(start 45.391578 -134.60222)
		(end 37.22624 -134.60222)
		(width 0.13462)
		(layer "F.Cu")
		(net "P5E_PEX0_STN1_TX_C_DN<30>")
	)
	(segment
		(start 37.22624 -134.60222)
		(end 36.905184 -134.923276)
		(width 0.13462)
		(layer "F.Cu")
		(net "P5E_PEX0_STN1_TX_C_DN<30>")
	)
	(segment
		(start 57.415938 -319.916048)
		(end 57.370218 -319.870328)
		(width 0.1143)
		(layer "In9.Cu")
		(net "P5E_PEX0_STN6_RX_DN<96>")
	)
	(segment
		(start 64.079628 -330.370688)
		(end 57.925716 -324.216776)
		(width 0.1651)
		(layer "In9.Cu")
		(net "P5E_PEX0_STN6_RX_DN<96>")
	)
	(segment
		(start 87.30996 -376.790204)
		(end 87.30996 -376.408188)
		(width 0.1651)
		(layer "In9.Cu")
		(net "P5E_PEX0_STN6_RX_DN<96>")
	)
	(segment
		(start 88.484456 -375.794524)
		(end 88.484456 -368.491008)
		(width 0.1651)
		(layer "In9.Cu")
		(net "P5E_PEX0_STN6_RX_DN<96>")
	)
	(segment
		(start 75.935332 -341.525606)
		(end 75.444858 -340.341458)
		(width 0.1651)
		(layer "In9.Cu")
		(net "P5E_PEX0_STN6_RX_DN<96>")
	)
	(segment
		(start 57.661048 -318.320166)
		(end 57.749948 -318.409066)
		(width 0.1143)
		(layer "In9.Cu")
		(net "P5E_PEX0_STN6_RX_DN<96>")
	)
	(segment
		(start 57.925716 -324.216776)
		(end 57.415938 -322.986146)
		(width 0.1651)
		(layer "In9.Cu")
		(net "P5E_PEX0_STN6_RX_DN<96>")
	)
	(segment
		(start 57.415938 -322.986146)
		(end 57.415938 -319.944496)
		(width 0.1651)
		(layer "In9.Cu")
		(net "P5E_PEX0_STN6_RX_DN<96>")
	)
	(segment
		(start 75.444858 -340.341458)
		(end 68.282312 -333.178912)
		(width 0.1651)
		(layer "In9.Cu")
		(net "P5E_PEX0_STN6_RX_DN<96>")
	)
	(segment
		(start 77.572108 -360.154728)
		(end 75.935332 -358.517952)
		(width 0.1651)
		(layer "In9.Cu")
		(net "P5E_PEX0_STN6_RX_DN<96>")
	)
	(segment
		(start 87.30996 -376.408188)
		(end 87.43696 -376.281188)
		(width 0.1651)
		(layer "In9.Cu")
		(net "P5E_PEX0_STN6_RX_DN<96>")
	)
	(segment
		(start 57.370218 -318.485266)
		(end 57.535318 -318.320166)
		(width 0.1143)
		(layer "In9.Cu")
		(net "P5E_PEX0_STN6_RX_DN<96>")
	)
	(segment
		(start 75.935332 -358.517952)
		(end 75.935332 -341.525606)
		(width 0.1651)
		(layer "In9.Cu")
		(net "P5E_PEX0_STN6_RX_DN<96>")
	)
	(segment
		(start 57.370218 -319.870328)
		(end 57.370218 -318.485266)
		(width 0.1143)
		(layer "In9.Cu")
		(net "P5E_PEX0_STN6_RX_DN<96>")
	)
	(segment
		(start 57.535318 -318.320166)
		(end 57.661048 -318.320166)
		(width 0.1143)
		(layer "In9.Cu")
		(net "P5E_PEX0_STN6_RX_DN<96>")
	)
	(segment
		(start 87.997792 -376.281188)
		(end 88.484456 -375.794524)
		(width 0.1651)
		(layer "In9.Cu")
		(net "P5E_PEX0_STN6_RX_DN<96>")
	)
	(segment
		(start 88.484456 -368.491008)
		(end 87.886286 -367.046764)
		(width 0.1651)
		(layer "In9.Cu")
		(net "P5E_PEX0_STN6_RX_DN<96>")
	)
	(segment
		(start 57.415938 -319.944496)
		(end 57.415938 -319.916048)
		(width 0.1143)
		(layer "In9.Cu")
		(net "P5E_PEX0_STN6_RX_DN<96>")
	)
	(segment
		(start 87.43696 -376.281188)
		(end 87.997792 -376.281188)
		(width 0.1651)
		(layer "In9.Cu")
		(net "P5E_PEX0_STN6_RX_DN<96>")
	)
	(segment
		(start 68.282312 -333.178912)
		(end 64.079628 -330.370688)
		(width 0.1651)
		(layer "In9.Cu")
		(net "P5E_PEX0_STN6_RX_DN<96>")
	)
	(segment
		(start 57.749948 -318.409066)
		(end 57.749948 -318.699896)
		(width 0.1143)
		(layer "In9.Cu")
		(net "P5E_PEX0_STN6_RX_DN<96>")
	)
	(segment
		(start 87.886286 -367.046764)
		(end 77.572108 -360.154728)
		(width 0.1651)
		(layer "In9.Cu")
		(net "P5E_PEX0_STN6_RX_DN<96>")
	)
	(segment
		(start 265.70559 -30.62732)
		(end 265.410442 -30.922468)
		(width 0.13462)
		(layer "F.Cu")
		(net "P5E_PEX2_STN2_RX_DP<41>")
	)
	(segment
		(start 268.382242 -30.790134)
		(end 268.219428 -30.62732)
		(width 0.13462)
		(layer "F.Cu")
		(net "P5E_PEX2_STN2_RX_DP<41>")
	)
	(segment
		(start 268.219428 -30.62732)
		(end 265.70559 -30.62732)
		(width 0.13462)
		(layer "F.Cu")
		(net "P5E_PEX2_STN2_RX_DP<41>")
	)
	(segment
		(start 268.864842 -30.790134)
		(end 268.382242 -30.790134)
		(width 0.13462)
		(layer "F.Cu")
		(net "P5E_PEX2_STN2_RX_DP<41>")
	)
	(segment
		(start 268.835632 -31.738824)
		(end 268.979396 -31.738824)
		(width 0.1651)
		(layer "In7.Cu")
		(net "P5E_PEX2_STN2_RX_DP<41>")
	)
	(segment
		(start 265.410442 -30.922468)
		(end 265.701272 -30.631638)
		(width 0.1651)
		(layer "In7.Cu")
		(net "P5E_PEX2_STN2_RX_DP<41>")
	)
	(segment
		(start 282.041854 -273.670014)
		(end 282.235402 -273.670014)
		(width 0.1143)
		(layer "In7.Cu")
		(net "P5E_PEX2_STN2_RX_DP<41>")
	)
	(segment
		(start 281.733752 -271.345152)
		(end 281.733752 -271.3736)
		(width 0.1143)
		(layer "In7.Cu")
		(net "P5E_PEX2_STN2_RX_DP<41>")
	)
	(segment
		(start 268.780768 -37.940234)
		(end 268.807692 -39.641272)
		(width 0.1651)
		(layer "In7.Cu")
		(net "P5E_PEX2_STN2_RX_DP<41>")
	)
	(segment
		(start 266.674092 -30.631638)
		(end 266.775692 -30.733238)
		(width 0.1651)
		(layer "In7.Cu")
		(net "P5E_PEX2_STN2_RX_DP<41>")
	)
	(segment
		(start 267.372592 -30.631638)
		(end 267.87221 -30.631638)
		(width 0.1651)
		(layer "In7.Cu")
		(net "P5E_PEX2_STN2_RX_DP<41>")
	)
	(segment
		(start 282.235402 -273.670014)
		(end 282.349702 -273.784314)
		(width 0.1143)
		(layer "In7.Cu")
		(net "P5E_PEX2_STN2_RX_DP<41>")
	)
	(segment
		(start 270.123412 -49.394364)
		(end 270.024098 -55.75808)
		(width 0.1651)
		(layer "In7.Cu")
		(net "P5E_PEX2_STN2_RX_DP<41>")
	)
	(segment
		(start 281.779472 -271.41932)
		(end 281.779472 -273.407632)
		(width 0.1143)
		(layer "In7.Cu")
		(net "P5E_PEX2_STN2_RX_DP<41>")
	)
	(segment
		(start 267.87221 -30.631638)
		(end 268.485112 -31.24454)
		(width 0.1651)
		(layer "In7.Cu")
		(net "P5E_PEX2_STN2_RX_DP<41>")
	)
	(segment
		(start 267.270992 -30.733238)
		(end 267.372592 -30.631638)
		(width 0.1651)
		(layer "In7.Cu")
		(net "P5E_PEX2_STN2_RX_DP<41>")
	)
	(segment
		(start 274.037044 -119.576596)
		(end 273.730974 -147.979892)
		(width 0.1651)
		(layer "In7.Cu")
		(net "P5E_PEX2_STN2_RX_DP<41>")
	)
	(segment
		(start 268.979396 -31.738824)
		(end 269.329408 -32.088836)
		(width 0.1651)
		(layer "In7.Cu")
		(net "P5E_PEX2_STN2_RX_DP<41>")
	)
	(segment
		(start 281.779472 -273.407632)
		(end 282.041854 -273.670014)
		(width 0.1143)
		(layer "In7.Cu")
		(net "P5E_PEX2_STN2_RX_DP<41>")
	)
	(segment
		(start 268.807692 -39.641272)
		(end 268.807438 -39.641272)
		(width 0.1651)
		(layer "In7.Cu")
		(net "P5E_PEX2_STN2_RX_DP<41>")
	)
	(segment
		(start 282.349702 -273.784314)
		(end 282.349702 -274.049744)
		(width 0.1143)
		(layer "In7.Cu")
		(net "P5E_PEX2_STN2_RX_DP<41>")
	)
	(segment
		(start 268.485112 -31.24454)
		(end 268.485112 -31.388304)
		(width 0.1651)
		(layer "In7.Cu")
		(net "P5E_PEX2_STN2_RX_DP<41>")
	)
	(segment
		(start 270.024098 -55.75808)
		(end 270.38427 -64.756792)
		(width 0.1651)
		(layer "In7.Cu")
		(net "P5E_PEX2_STN2_RX_DP<41>")
	)
	(segment
		(start 268.807438 -39.641272)
		(end 268.807946 -39.658036)
		(width 0.1651)
		(layer "In7.Cu")
		(net "P5E_PEX2_STN2_RX_DP<41>")
	)
	(segment
		(start 273.730974 -147.979892)
		(end 281.68727 -249.979434)
		(width 0.1651)
		(layer "In7.Cu")
		(net "P5E_PEX2_STN2_RX_DP<41>")
	)
	(segment
		(start 281.68727 -249.979434)
		(end 281.482292 -260.60146)
		(width 0.1651)
		(layer "In7.Cu")
		(net "P5E_PEX2_STN2_RX_DP<41>")
	)
	(segment
		(start 281.733752 -271.3736)
		(end 281.779472 -271.41932)
		(width 0.1143)
		(layer "In7.Cu")
		(net "P5E_PEX2_STN2_RX_DP<41>")
	)
	(segment
		(start 281.733752 -267.683234)
		(end 281.733752 -271.345152)
		(width 0.1651)
		(layer "In7.Cu")
		(net "P5E_PEX2_STN2_RX_DP<41>")
	)
	(segment
		(start 269.329408 -32.088836)
		(end 269.30604 -34.981642)
		(width 0.1651)
		(layer "In7.Cu")
		(net "P5E_PEX2_STN2_RX_DP<41>")
	)
	(segment
		(start 266.775692 -30.733238)
		(end 267.270992 -30.733238)
		(width 0.1651)
		(layer "In7.Cu")
		(net "P5E_PEX2_STN2_RX_DP<41>")
	)
	(segment
		(start 268.807946 -39.658036)
		(end 270.123412 -49.394364)
		(width 0.1651)
		(layer "In7.Cu")
		(net "P5E_PEX2_STN2_RX_DP<41>")
	)
	(segment
		(start 273.583908 -104.61879)
		(end 274.037044 -119.576596)
		(width 0.1651)
		(layer "In7.Cu")
		(net "P5E_PEX2_STN2_RX_DP<41>")
	)
	(segment
		(start 265.701272 -30.631638)
		(end 266.674092 -30.631638)
		(width 0.1651)
		(layer "In7.Cu")
		(net "P5E_PEX2_STN2_RX_DP<41>")
	)
	(segment
		(start 281.333956 -263.623806)
		(end 281.733752 -267.683234)
		(width 0.1651)
		(layer "In7.Cu")
		(net "P5E_PEX2_STN2_RX_DP<41>")
	)
	(segment
		(start 281.482292 -260.60146)
		(end 281.333956 -263.623806)
		(width 0.1651)
		(layer "In7.Cu")
		(net "P5E_PEX2_STN2_RX_DP<41>")
	)
	(segment
		(start 268.485112 -31.388304)
		(end 268.835632 -31.738824)
		(width 0.1651)
		(layer "In7.Cu")
		(net "P5E_PEX2_STN2_RX_DP<41>")
	)
	(segment
		(start 270.38427 -64.756792)
		(end 273.583908 -104.61879)
		(width 0.1651)
		(layer "In7.Cu")
		(net "P5E_PEX2_STN2_RX_DP<41>")
	)
	(segment
		(start 269.30604 -34.981642)
		(end 268.780768 -37.940234)
		(width 0.1651)
		(layer "In7.Cu")
		(net "P5E_PEX2_STN2_RX_DP<41>")
	)
	(segment
		(start 337.943444 -345.170506)
		(end 338.238084 -345.465146)
		(width 0.13462)
		(layer "F.Cu")
		(net "P5E_PEX2_STN6_TX_C_DN<100>")
	)
	(segment
		(start 337.943444 -344.539062)
		(end 337.943444 -345.170506)
		(width 0.13462)
		(layer "F.Cu")
		(net "P5E_PEX2_STN6_TX_C_DN<100>")
	)
	(segment
		(start 338.263484 -344.219022)
		(end 337.943444 -344.539062)
		(width 0.13462)
		(layer "F.Cu")
		(net "P5E_PEX2_STN6_TX_C_DN<100>")
	)
	(segment
		(start 339.215984 -368.8715)
		(end 339.215984 -383.629154)
		(width 0.1651)
		(layer "In13.Cu")
		(net "P5E_PEX2_STN6_TX_C_DN<100>")
	)
	(segment
		(start 336.392774 -347.881194)
		(end 336.392774 -358.88422)
		(width 0.1651)
		(layer "In13.Cu")
		(net "P5E_PEX2_STN6_TX_C_DN<100>")
	)
	(segment
		(start 338.238084 -345.465146)
		(end 337.947254 -345.755976)
		(width 0.1651)
		(layer "In13.Cu")
		(net "P5E_PEX2_STN6_TX_C_DN<100>")
	)
	(segment
		(start 337.947254 -346.326714)
		(end 336.392774 -347.881194)
		(width 0.1651)
		(layer "In13.Cu")
		(net "P5E_PEX2_STN6_TX_C_DN<100>")
	)
	(segment
		(start 336.392774 -358.88422)
		(end 339.215984 -368.8715)
		(width 0.1651)
		(layer "In13.Cu")
		(net "P5E_PEX2_STN6_TX_C_DN<100>")
	)
	(segment
		(start 338.217002 -384.08102)
		(end 338.090002 -384.20802)
		(width 0.1651)
		(layer "In13.Cu")
		(net "P5E_PEX2_STN6_TX_C_DN<100>")
	)
	(segment
		(start 338.090002 -384.20802)
		(end 338.090002 -384.590036)
		(width 0.1651)
		(layer "In13.Cu")
		(net "P5E_PEX2_STN6_TX_C_DN<100>")
	)
	(segment
		(start 337.947254 -345.755976)
		(end 337.947254 -346.326714)
		(width 0.1651)
		(layer "In13.Cu")
		(net "P5E_PEX2_STN6_TX_C_DN<100>")
	)
	(segment
		(start 338.764118 -384.08102)
		(end 338.217002 -384.08102)
		(width 0.1651)
		(layer "In13.Cu")
		(net "P5E_PEX2_STN6_TX_C_DN<100>")
	)
	(segment
		(start 339.215984 -383.629154)
		(end 338.764118 -384.08102)
		(width 0.1651)
		(layer "In13.Cu")
		(net "P5E_PEX2_STN6_TX_C_DN<100>")
	)
	(segment
		(start 415.170112 -318.423798)
		(end 415.273744 -318.320166)
		(width 0.1143)
		(layer "In15.Cu")
		(net "P5E_PEX3_STN5_RX_DN<89>")
	)
	(segment
		(start 414.707832 -321.889374)
		(end 415.215832 -321.230244)
		(width 0.1651)
		(layer "In15.Cu")
		(net "P5E_PEX3_STN5_RX_DN<89>")
	)
	(segment
		(start 378.815854 -369.87226)
		(end 379.271276 -368.719354)
		(width 0.1651)
		(layer "In15.Cu")
		(net "P5E_PEX3_STN5_RX_DN<89>")
	)
	(segment
		(start 389.158734 -341.320628)
		(end 414.707832 -321.889374)
		(width 0.1651)
		(layer "In15.Cu")
		(net "P5E_PEX3_STN5_RX_DN<89>")
	)
	(segment
		(start 377.689872 -372.890034)
		(end 377.689872 -372.508018)
		(width 0.1651)
		(layer "In15.Cu")
		(net "P5E_PEX3_STN5_RX_DN<89>")
	)
	(segment
		(start 415.170112 -319.921128)
		(end 415.170112 -318.423798)
		(width 0.1143)
		(layer "In15.Cu")
		(net "P5E_PEX3_STN5_RX_DN<89>")
	)
	(segment
		(start 378.815854 -371.929152)
		(end 378.815854 -369.87226)
		(width 0.1651)
		(layer "In15.Cu")
		(net "P5E_PEX3_STN5_RX_DN<89>")
	)
	(segment
		(start 415.215832 -321.230244)
		(end 415.215832 -319.995296)
		(width 0.1651)
		(layer "In15.Cu")
		(net "P5E_PEX3_STN5_RX_DN<89>")
	)
	(segment
		(start 379.271276 -368.719354)
		(end 388.53618 -358.826054)
		(width 0.1651)
		(layer "In15.Cu")
		(net "P5E_PEX3_STN5_RX_DN<89>")
	)
	(segment
		(start 415.549842 -318.434466)
		(end 415.549842 -318.699896)
		(width 0.1143)
		(layer "In15.Cu")
		(net "P5E_PEX3_STN5_RX_DN<89>")
	)
	(segment
		(start 388.86003 -342.1634)
		(end 389.158734 -341.320628)
		(width 0.1651)
		(layer "In15.Cu")
		(net "P5E_PEX3_STN5_RX_DN<89>")
	)
	(segment
		(start 388.53618 -358.826054)
		(end 388.86003 -358.00665)
		(width 0.1651)
		(layer "In15.Cu")
		(net "P5E_PEX3_STN5_RX_DN<89>")
	)
	(segment
		(start 415.273744 -318.320166)
		(end 415.435542 -318.320166)
		(width 0.1143)
		(layer "In15.Cu")
		(net "P5E_PEX3_STN5_RX_DN<89>")
	)
	(segment
		(start 388.86003 -358.00665)
		(end 388.86003 -342.1634)
		(width 0.1651)
		(layer "In15.Cu")
		(net "P5E_PEX3_STN5_RX_DN<89>")
	)
	(segment
		(start 415.215832 -319.995296)
		(end 415.215832 -319.966848)
		(width 0.1143)
		(layer "In15.Cu")
		(net "P5E_PEX3_STN5_RX_DN<89>")
	)
	(segment
		(start 377.816872 -372.381018)
		(end 378.363988 -372.381018)
		(width 0.1651)
		(layer "In15.Cu")
		(net "P5E_PEX3_STN5_RX_DN<89>")
	)
	(segment
		(start 377.689872 -372.508018)
		(end 377.816872 -372.381018)
		(width 0.1651)
		(layer "In15.Cu")
		(net "P5E_PEX3_STN5_RX_DN<89>")
	)
	(segment
		(start 378.363988 -372.381018)
		(end 378.815854 -371.929152)
		(width 0.1651)
		(layer "In15.Cu")
		(net "P5E_PEX3_STN5_RX_DN<89>")
	)
	(segment
		(start 415.215832 -319.966848)
		(end 415.170112 -319.921128)
		(width 0.1143)
		(layer "In15.Cu")
		(net "P5E_PEX3_STN5_RX_DN<89>")
	)
	(segment
		(start 415.435542 -318.320166)
		(end 415.549842 -318.434466)
		(width 0.1143)
		(layer "In15.Cu")
		(net "P5E_PEX3_STN5_RX_DN<89>")
	)
	(segment
		(start 72.186292 -115.977416)
		(end 72.654668 -115.977416)
		(width 0.13208)
		(layer "F.Cu")
		(net "NIC1_AUX_PWR_EN_R")
	)
	(segment
		(start 72.654668 -115.977416)
		(end 72.797162 -115.834922)
		(width 0.13208)
		(layer "F.Cu")
		(net "NIC1_AUX_PWR_EN_R")
	)
	(segment
		(start 72.797162 -115.834922)
		(end 73.257664 -115.834922)
		(width 0.13208)
		(layer "F.Cu")
		(net "NIC1_AUX_PWR_EN_R")
	)
	(segment
		(start 71.68642 -116.477288)
		(end 72.186292 -115.977416)
		(width 0.13208)
		(layer "F.Cu")
		(net "NIC1_AUX_PWR_EN_R")
	)
	(via
		(at 71.68642 -116.477288)
		(size 0.508)
		(drill 0.254)
		(layers "F.Cu" "B.Cu")
		(net "NIC1_AUX_PWR_EN_R")
	)
	(segment
		(start 69.999352 -114.713512)
		(end 69.999352 -115.348512)
		(width 0.13208)
		(layer "B.Cu")
		(net "NIC1_AUX_PWR_EN_R")
	)
	(segment
		(start 71.68642 -116.477288)
		(end 71.68642 -117.66169)
		(width 0.13208)
		(layer "B.Cu")
		(net "NIC1_AUX_PWR_EN_R")
	)
	(segment
		(start 71.128128 -116.477288)
		(end 71.68642 -116.477288)
		(width 0.13208)
		(layer "B.Cu")
		(net "NIC1_AUX_PWR_EN_R")
	)
	(segment
		(start 69.999352 -115.348512)
		(end 71.128128 -116.477288)
		(width 0.13208)
		(layer "B.Cu")
		(net "NIC1_AUX_PWR_EN_R")
	)
	(segment
		(start 318.371728 -24.807418)
		(end 319.202054 -24.807418)
		(width 0.13208)
		(layer "F.Cu")
		(net "PU_CLKREQ11")
	)
	(segment
		(start 319.219326 -24.790146)
		(end 319.202054 -24.807418)
		(width 0.13208)
		(layer "F.Cu")
		(net "PU_CLKREQ11")
	)
	(segment
		(start 320.864738 -24.790146)
		(end 319.219326 -24.790146)
		(width 0.13208)
		(layer "F.Cu")
		(net "PU_CLKREQ11")
	)
	(via
		(at 319.202054 -24.807418)
		(size 0.508)
		(drill 0.254)
		(layers "F.Cu" "B.Cu")
		(net "PU_CLKREQ11")
	)
	(segment
		(start 37.22624 -123.392184)
		(end 36.905184 -123.71324)
		(width 0.13462)
		(layer "F.Cu")
		(net "P5E_PEX0_STN1_TX_C_DN<26>")
	)
	(segment
		(start 45.554392 -123.554998)
		(end 45.391578 -123.392184)
		(width 0.13462)
		(layer "F.Cu")
		(net "P5E_PEX0_STN1_TX_C_DN<26>")
	)
	(segment
		(start 46.042326 -123.554998)
		(end 45.554392 -123.554998)
		(width 0.13462)
		(layer "F.Cu")
		(net "P5E_PEX0_STN1_TX_C_DN<26>")
	)
	(segment
		(start 45.391578 -123.392184)
		(end 37.22624 -123.392184)
		(width 0.13462)
		(layer "F.Cu")
		(net "P5E_PEX0_STN1_TX_C_DN<26>")
	)
	(segment
		(start 241.554762 -32.14878)
		(end 241.264694 -31.858712)
		(width 0.13462)
		(layer "F.Cu")
		(net "P5E_PEX2_STN2_RX_DN<46>")
	)
	(segment
		(start 242.384072 -31.99003)
		(end 242.225322 -32.14878)
		(width 0.13462)
		(layer "F.Cu")
		(net "P5E_PEX2_STN2_RX_DN<46>")
	)
	(segment
		(start 242.225322 -32.14878)
		(end 241.554762 -32.14878)
		(width 0.13462)
		(layer "F.Cu")
		(net "P5E_PEX2_STN2_RX_DN<46>")
	)
	(segment
		(start 242.864894 -31.99003)
		(end 242.384072 -31.99003)
		(width 0.13462)
		(layer "F.Cu")
		(net "P5E_PEX2_STN2_RX_DN<46>")
	)
	(segment
		(start 274.776184 -238.303054)
		(end 276.367494 -255.686052)
		(width 0.1651)
		(layer "In7.Cu")
		(net "P5E_PEX2_STN2_RX_DN<46>")
	)
	(segment
		(start 277.485602 -275.379688)
		(end 277.599902 -275.265388)
		(width 0.1143)
		(layer "In7.Cu")
		(net "P5E_PEX2_STN2_RX_DN<46>")
	)
	(segment
		(start 277.265638 -270.38427)
		(end 277.265638 -271.392904)
		(width 0.1651)
		(layer "In7.Cu")
		(net "P5E_PEX2_STN2_RX_DN<46>")
	)
	(segment
		(start 248.581418 -102.56393)
		(end 248.593356 -102.6033)
		(width 0.1651)
		(layer "In7.Cu")
		(net "P5E_PEX2_STN2_RX_DN<46>")
	)
	(segment
		(start 242.607338 -35.04819)
		(end 242.083844 -37.856414)
		(width 0.1651)
		(layer "In7.Cu")
		(net "P5E_PEX2_STN2_RX_DN<46>")
	)
	(segment
		(start 277.219918 -271.467072)
		(end 277.219918 -275.275802)
		(width 0.1143)
		(layer "In7.Cu")
		(net "P5E_PEX2_STN2_RX_DN<46>")
	)
	(segment
		(start 253.792482 -119.756174)
		(end 257.067812 -144.657572)
		(width 0.1651)
		(layer "In7.Cu")
		(net "P5E_PEX2_STN2_RX_DN<46>")
	)
	(segment
		(start 243.586 -61.824616)
		(end 243.393976 -85.450426)
		(width 0.1651)
		(layer "In7.Cu")
		(net "P5E_PEX2_STN2_RX_DN<46>")
	)
	(segment
		(start 243.586 -60.294012)
		(end 243.586 -61.824616)
		(width 0.1651)
		(layer "In7.Cu")
		(net "P5E_PEX2_STN2_RX_DN<46>")
	)
	(segment
		(start 242.083844 -37.856414)
		(end 242.120166 -40.147748)
		(width 0.1651)
		(layer "In7.Cu")
		(net "P5E_PEX2_STN2_RX_DN<46>")
	)
	(segment
		(start 243.393976 -85.450426)
		(end 248.581164 -102.563168)
		(width 0.1651)
		(layer "In7.Cu")
		(net "P5E_PEX2_STN2_RX_DN<46>")
	)
	(segment
		(start 243.305838 -57.201562)
		(end 243.586 -60.294012)
		(width 0.1651)
		(layer "In7.Cu")
		(net "P5E_PEX2_STN2_RX_DN<46>")
	)
	(segment
		(start 248.581164 -102.563168)
		(end 248.581418 -102.56393)
		(width 0.1651)
		(layer "In7.Cu")
		(net "P5E_PEX2_STN2_RX_DN<46>")
	)
	(segment
		(start 277.265638 -271.421352)
		(end 277.219918 -271.467072)
		(width 0.1143)
		(layer "In7.Cu")
		(net "P5E_PEX2_STN2_RX_DN<46>")
	)
	(segment
		(start 248.593356 -102.603808)
		(end 253.792482 -119.756174)
		(width 0.1651)
		(layer "In7.Cu")
		(net "P5E_PEX2_STN2_RX_DN<46>")
	)
	(segment
		(start 242.120166 -40.147748)
		(end 243.421916 -49.782222)
		(width 0.1651)
		(layer "In7.Cu")
		(net "P5E_PEX2_STN2_RX_DN<46>")
	)
	(segment
		(start 277.219918 -275.275802)
		(end 277.323804 -275.379688)
		(width 0.1143)
		(layer "In7.Cu")
		(net "P5E_PEX2_STN2_RX_DN<46>")
	)
	(segment
		(start 248.593356 -102.6033)
		(end 248.593356 -102.603808)
		(width 0.1651)
		(layer "In7.Cu")
		(net "P5E_PEX2_STN2_RX_DN<46>")
	)
	(segment
		(start 277.599902 -275.265388)
		(end 277.599902 -274.999958)
		(width 0.1143)
		(layer "In7.Cu")
		(net "P5E_PEX2_STN2_RX_DN<46>")
	)
	(segment
		(start 277.265638 -271.392904)
		(end 277.265638 -271.421352)
		(width 0.1143)
		(layer "In7.Cu")
		(net "P5E_PEX2_STN2_RX_DN<46>")
	)
	(segment
		(start 241.555524 -32.149542)
		(end 242.130072 -32.149542)
		(width 0.1651)
		(layer "In7.Cu")
		(net "P5E_PEX2_STN2_RX_DN<46>")
	)
	(segment
		(start 257.067812 -144.657572)
		(end 274.776184 -238.303054)
		(width 0.1651)
		(layer "In7.Cu")
		(net "P5E_PEX2_STN2_RX_DN<46>")
	)
	(segment
		(start 242.644422 -32.663638)
		(end 242.607338 -35.04819)
		(width 0.1651)
		(layer "In7.Cu")
		(net "P5E_PEX2_STN2_RX_DN<46>")
	)
	(segment
		(start 241.264694 -31.858712)
		(end 241.555524 -32.149542)
		(width 0.1651)
		(layer "In7.Cu")
		(net "P5E_PEX2_STN2_RX_DN<46>")
	)
	(segment
		(start 276.367494 -255.686052)
		(end 276.290532 -263.518142)
		(width 0.1651)
		(layer "In7.Cu")
		(net "P5E_PEX2_STN2_RX_DN<46>")
	)
	(segment
		(start 277.323804 -275.379688)
		(end 277.485602 -275.379688)
		(width 0.1143)
		(layer "In7.Cu")
		(net "P5E_PEX2_STN2_RX_DN<46>")
	)
	(segment
		(start 276.290532 -263.518142)
		(end 277.265638 -270.38427)
		(width 0.1651)
		(layer "In7.Cu")
		(net "P5E_PEX2_STN2_RX_DN<46>")
	)
	(segment
		(start 242.130072 -32.149542)
		(end 242.644422 -32.663638)
		(width 0.1651)
		(layer "In7.Cu")
		(net "P5E_PEX2_STN2_RX_DN<46>")
	)
	(segment
		(start 243.421916 -49.782222)
		(end 243.305838 -57.201562)
		(width 0.1651)
		(layer "In7.Cu")
		(net "P5E_PEX2_STN2_RX_DN<46>")
	)
	(segment
		(start 340.778084 -350.685354)
		(end 340.778084 -351.316798)
		(width 0.13462)
		(layer "F.Cu")
		(net "P5E_PEX2_STN6_TX_C_DP<98>")
	)
	(segment
		(start 340.458044 -350.365314)
		(end 340.778084 -350.685354)
		(width 0.13462)
		(layer "F.Cu")
		(net "P5E_PEX2_STN6_TX_C_DP<98>")
	)
	(segment
		(start 340.778084 -351.316798)
		(end 340.483444 -351.611438)
		(width 0.13462)
		(layer "F.Cu")
		(net "P5E_PEX2_STN6_TX_C_DP<98>")
	)
	(segment
		(start 341.003382 -363.590332)
		(end 340.81466 -363.131862)
		(width 0.1651)
		(layer "In13.Cu")
		(net "P5E_PEX2_STN6_TX_C_DP<98>")
	)
	(segment
		(start 340.774274 -351.902268)
		(end 340.483444 -351.611438)
		(width 0.1651)
		(layer "In13.Cu")
		(net "P5E_PEX2_STN6_TX_C_DP<98>")
	)
	(segment
		(start 343.334086 -383.512314)
		(end 343.334086 -368.95024)
		(width 0.1651)
		(layer "In13.Cu")
		(net "P5E_PEX2_STN6_TX_C_DP<98>")
	)
	(segment
		(start 339.219794 -353.910646)
		(end 340.774274 -352.356166)
		(width 0.1651)
		(layer "In13.Cu")
		(net "P5E_PEX2_STN6_TX_C_DP<98>")
	)
	(segment
		(start 341.617046 -364.779814)
		(end 341.467694 -364.717838)
		(width 0.1651)
		(layer "In13.Cu")
		(net "P5E_PEX2_STN6_TX_C_DP<98>")
	)
	(segment
		(start 342.081358 -365.907574)
		(end 341.931752 -365.845344)
		(width 0.1651)
		(layer "In13.Cu")
		(net "P5E_PEX2_STN6_TX_C_DP<98>")
	)
	(segment
		(start 341.743284 -365.387128)
		(end 341.805514 -365.237776)
		(width 0.1651)
		(layer "In13.Cu")
		(net "P5E_PEX2_STN6_TX_C_DP<98>")
	)
	(segment
		(start 342.490044 -383.67208)
		(end 342.617044 -383.79908)
		(width 0.1651)
		(layer "In13.Cu")
		(net "P5E_PEX2_STN6_TX_C_DP<98>")
	)
	(segment
		(start 340.774274 -352.356166)
		(end 340.774274 -351.902268)
		(width 0.1651)
		(layer "In13.Cu")
		(net "P5E_PEX2_STN6_TX_C_DP<98>")
	)
	(segment
		(start 341.931752 -365.845344)
		(end 341.743284 -365.387128)
		(width 0.1651)
		(layer "In13.Cu")
		(net "P5E_PEX2_STN6_TX_C_DP<98>")
	)
	(segment
		(start 340.87689 -362.982764)
		(end 339.219794 -358.95788)
		(width 0.1651)
		(layer "In13.Cu")
		(net "P5E_PEX2_STN6_TX_C_DP<98>")
	)
	(segment
		(start 341.341202 -364.11027)
		(end 341.152734 -363.652308)
		(width 0.1651)
		(layer "In13.Cu")
		(net "P5E_PEX2_STN6_TX_C_DP<98>")
	)
	(segment
		(start 341.467694 -364.717838)
		(end 341.278972 -364.259368)
		(width 0.1651)
		(layer "In13.Cu")
		(net "P5E_PEX2_STN6_TX_C_DP<98>")
	)
	(segment
		(start 341.278972 -364.259368)
		(end 341.341202 -364.11027)
		(width 0.1651)
		(layer "In13.Cu")
		(net "P5E_PEX2_STN6_TX_C_DP<98>")
	)
	(segment
		(start 343.334086 -368.95024)
		(end 342.081358 -365.907574)
		(width 0.1651)
		(layer "In13.Cu")
		(net "P5E_PEX2_STN6_TX_C_DP<98>")
	)
	(segment
		(start 341.805514 -365.237776)
		(end 341.617046 -364.779814)
		(width 0.1651)
		(layer "In13.Cu")
		(net "P5E_PEX2_STN6_TX_C_DP<98>")
	)
	(segment
		(start 342.490044 -383.290064)
		(end 342.490044 -383.67208)
		(width 0.1651)
		(layer "In13.Cu")
		(net "P5E_PEX2_STN6_TX_C_DP<98>")
	)
	(segment
		(start 343.04732 -383.79908)
		(end 343.334086 -383.512314)
		(width 0.1651)
		(layer "In13.Cu")
		(net "P5E_PEX2_STN6_TX_C_DP<98>")
	)
	(segment
		(start 341.152734 -363.652308)
		(end 341.003382 -363.590332)
		(width 0.1651)
		(layer "In13.Cu")
		(net "P5E_PEX2_STN6_TX_C_DP<98>")
	)
	(segment
		(start 340.81466 -363.131862)
		(end 340.87689 -362.982764)
		(width 0.1651)
		(layer "In13.Cu")
		(net "P5E_PEX2_STN6_TX_C_DP<98>")
	)
	(segment
		(start 342.617044 -383.79908)
		(end 343.04732 -383.79908)
		(width 0.1651)
		(layer "In13.Cu")
		(net "P5E_PEX2_STN6_TX_C_DP<98>")
	)
	(segment
		(start 339.219794 -358.95788)
		(end 339.219794 -353.910646)
		(width 0.1651)
		(layer "In13.Cu")
		(net "P5E_PEX2_STN6_TX_C_DP<98>")
	)
	(segment
		(start 393.245848 -350.685862)
		(end 393.245848 -351.31629)
		(width 0.13462)
		(layer "F.Cu")
		(net "P5E_PEX3_STN5_TX_C_DP<90>")
	)
	(segment
		(start 392.9253 -350.365314)
		(end 393.245848 -350.685862)
		(width 0.13462)
		(layer "F.Cu")
		(net "P5E_PEX3_STN5_TX_C_DP<90>")
	)
	(segment
		(start 393.245848 -351.31629)
		(end 392.9507 -351.611438)
		(width 0.13462)
		(layer "F.Cu")
		(net "P5E_PEX3_STN5_TX_C_DP<90>")
	)
	(segment
		(start 380.734062 -378.512324)
		(end 380.447296 -378.79909)
		(width 0.1651)
		(layer "In13.Cu")
		(net "P5E_PEX3_STN5_TX_C_DP<90>")
	)
	(segment
		(start 381.49149 -368.02695)
		(end 380.734062 -369.715034)
		(width 0.1651)
		(layer "In13.Cu")
		(net "P5E_PEX3_STN5_TX_C_DP<90>")
	)
	(segment
		(start 383.161794 -366.422178)
		(end 382.791462 -366.751616)
		(width 0.1651)
		(layer "In13.Cu")
		(net "P5E_PEX3_STN5_TX_C_DP<90>")
	)
	(segment
		(start 380.447296 -378.79909)
		(end 380.01702 -378.79909)
		(width 0.1651)
		(layer "In13.Cu")
		(net "P5E_PEX3_STN5_TX_C_DP<90>")
	)
	(segment
		(start 384.530346 -365.323628)
		(end 384.160522 -365.652812)
		(width 0.1651)
		(layer "In13.Cu")
		(net "P5E_PEX3_STN5_TX_C_DP<90>")
	)
	(segment
		(start 385.033774 -364.87608)
		(end 384.908044 -364.868714)
		(width 0.1651)
		(layer "In13.Cu")
		(net "P5E_PEX3_STN5_TX_C_DP<90>")
	)
	(segment
		(start 380.734062 -369.715034)
		(end 380.734062 -378.512324)
		(width 0.1651)
		(layer "In13.Cu")
		(net "P5E_PEX3_STN5_TX_C_DP<90>")
	)
	(segment
		(start 393.24153 -352.356166)
		(end 391.68705 -353.910646)
		(width 0.1651)
		(layer "In13.Cu")
		(net "P5E_PEX3_STN5_TX_C_DP<90>")
	)
	(segment
		(start 382.784096 -366.877092)
		(end 381.49149 -368.02695)
		(width 0.1651)
		(layer "In13.Cu")
		(net "P5E_PEX3_STN5_TX_C_DP<90>")
	)
	(segment
		(start 392.9507 -351.611438)
		(end 393.24153 -351.902268)
		(width 0.1651)
		(layer "In13.Cu")
		(net "P5E_PEX3_STN5_TX_C_DP<90>")
	)
	(segment
		(start 391.68705 -353.910646)
		(end 391.68705 -358.004618)
		(width 0.1651)
		(layer "In13.Cu")
		(net "P5E_PEX3_STN5_TX_C_DP<90>")
	)
	(segment
		(start 391.68705 -358.004618)
		(end 390.97458 -359.59161)
		(width 0.1651)
		(layer "In13.Cu")
		(net "P5E_PEX3_STN5_TX_C_DP<90>")
	)
	(segment
		(start 383.66446 -365.974884)
		(end 383.657094 -366.10036)
		(width 0.1651)
		(layer "In13.Cu")
		(net "P5E_PEX3_STN5_TX_C_DP<90>")
	)
	(segment
		(start 384.034792 -365.645446)
		(end 383.66446 -365.974884)
		(width 0.1651)
		(layer "In13.Cu")
		(net "P5E_PEX3_STN5_TX_C_DP<90>")
	)
	(segment
		(start 380.01702 -378.79909)
		(end 379.89002 -378.67209)
		(width 0.1651)
		(layer "In13.Cu")
		(net "P5E_PEX3_STN5_TX_C_DP<90>")
	)
	(segment
		(start 384.160522 -365.652812)
		(end 384.034792 -365.645446)
		(width 0.1651)
		(layer "In13.Cu")
		(net "P5E_PEX3_STN5_TX_C_DP<90>")
	)
	(segment
		(start 379.89002 -378.67209)
		(end 379.89002 -378.290074)
		(width 0.1651)
		(layer "In13.Cu")
		(net "P5E_PEX3_STN5_TX_C_DP<90>")
	)
	(segment
		(start 382.791462 -366.751616)
		(end 382.784096 -366.877092)
		(width 0.1651)
		(layer "In13.Cu")
		(net "P5E_PEX3_STN5_TX_C_DP<90>")
	)
	(segment
		(start 384.537712 -365.198152)
		(end 384.530346 -365.323628)
		(width 0.1651)
		(layer "In13.Cu")
		(net "P5E_PEX3_STN5_TX_C_DP<90>")
	)
	(segment
		(start 383.657094 -366.10036)
		(end 383.28727 -366.429544)
		(width 0.1651)
		(layer "In13.Cu")
		(net "P5E_PEX3_STN5_TX_C_DP<90>")
	)
	(segment
		(start 383.28727 -366.429544)
		(end 383.161794 -366.422178)
		(width 0.1651)
		(layer "In13.Cu")
		(net "P5E_PEX3_STN5_TX_C_DP<90>")
	)
	(segment
		(start 393.24153 -351.902268)
		(end 393.24153 -352.356166)
		(width 0.1651)
		(layer "In13.Cu")
		(net "P5E_PEX3_STN5_TX_C_DP<90>")
	)
	(segment
		(start 384.908044 -364.868714)
		(end 384.537712 -365.198152)
		(width 0.1651)
		(layer "In13.Cu")
		(net "P5E_PEX3_STN5_TX_C_DP<90>")
	)
	(segment
		(start 390.97458 -359.59161)
		(end 385.033774 -364.87608)
		(width 0.1651)
		(layer "In13.Cu")
		(net "P5E_PEX3_STN5_TX_C_DP<90>")
	)
	(segment
		(start 65.467738 -116.550186)
		(end 65.570354 -116.44757)
		(width 0.13208)
		(layer "F.Cu")
		(net "PRSNTB2_NIC1_N")
	)
	(segment
		(start 64.07785 -117.566186)
		(end 64.07785 -116.550186)
		(width 0.13208)
		(layer "F.Cu")
		(net "PRSNTB2_NIC1_N")
	)
	(segment
		(start 66.53911 -116.44757)
		(end 67.151758 -115.834922)
		(width 0.13208)
		(layer "F.Cu")
		(net "PRSNTB2_NIC1_N")
	)
	(segment
		(start 65.570354 -116.44757)
		(end 66.53911 -116.44757)
		(width 0.13208)
		(layer "F.Cu")
		(net "PRSNTB2_NIC1_N")
	)
	(segment
		(start 67.151758 -115.834922)
		(end 68.65747 -115.834922)
		(width 0.13208)
		(layer "F.Cu")
		(net "PRSNTB2_NIC1_N")
	)
	(segment
		(start 64.07785 -116.550186)
		(end 65.467738 -116.550186)
		(width 0.13208)
		(layer "F.Cu")
		(net "PRSNTB2_NIC1_N")
	)
	(via
		(at 66.53911 -116.44757)
		(size 0.508)
		(drill 0.254)
		(layers "F.Cu" "B.Cu")
		(net "PRSNTB2_NIC1_N")
	)
	(segment
		(start 303.671478 -24.942292)
		(end 303.671478 -24.910542)
		(width 0.13208)
		(layer "F.Cu")
		(net "DUALPORT_N_SSD10")
	)
	(segment
		(start 300.666404 -24.134572)
		(end 300.666404 -23.589996)
		(width 0.13208)
		(layer "F.Cu")
		(net "DUALPORT_N_SSD10")
	)
	(segment
		(start 303.671478 -24.910542)
		(end 303.249584 -24.488648)
		(width 0.13208)
		(layer "F.Cu")
		(net "DUALPORT_N_SSD10")
	)
	(segment
		(start 303.249584 -24.488648)
		(end 301.02048 -24.488648)
		(width 0.13208)
		(layer "F.Cu")
		(net "DUALPORT_N_SSD10")
	)
	(segment
		(start 301.02048 -24.488648)
		(end 300.666404 -24.134572)
		(width 0.13208)
		(layer "F.Cu")
		(net "DUALPORT_N_SSD10")
	)
	(segment
		(start 304.687478 -24.942292)
		(end 303.671478 -24.942292)
		(width 0.13208)
		(layer "F.Cu")
		(net "DUALPORT_N_SSD10")
	)
	(segment
		(start 300.666404 -23.589996)
		(end 299.46473 -23.589996)
		(width 0.13208)
		(layer "F.Cu")
		(net "DUALPORT_N_SSD10")
	)
	(via
		(at 300.666404 -23.589996)
		(size 0.508)
		(drill 0.254)
		(layers "F.Cu" "B.Cu")
		(net "DUALPORT_N_SSD10")
	)
	(segment
		(start 45.554392 -125.355096)
		(end 45.391578 -125.192282)
		(width 0.13462)
		(layer "F.Cu")
		(net "P5E_PEX0_STN1_TX_C_DP<27>")
	)
	(segment
		(start 45.391578 -125.192282)
		(end 39.874952 -125.192282)
		(width 0.13462)
		(layer "F.Cu")
		(net "P5E_PEX0_STN1_TX_C_DP<27>")
	)
	(segment
		(start 46.042326 -125.355096)
		(end 45.554392 -125.355096)
		(width 0.13462)
		(layer "F.Cu")
		(net "P5E_PEX0_STN1_TX_C_DP<27>")
	)
	(segment
		(start 39.874952 -125.192282)
		(end 39.547292 -125.519942)
		(width 0.13462)
		(layer "F.Cu")
		(net "P5E_PEX0_STN1_TX_C_DP<27>")
	)
	(segment
		(start 61.666882 -344.539062)
		(end 61.346842 -344.219022)
		(width 0.13462)
		(layer "F.Cu")
		(net "P5E_PEX0_STN6_TX_C_DP<111>")
	)
	(segment
		(start 61.666882 -345.170506)
		(end 61.666882 -344.539062)
		(width 0.13462)
		(layer "F.Cu")
		(net "P5E_PEX0_STN6_TX_C_DP<111>")
	)
	(segment
		(start 61.372242 -345.465146)
		(end 61.666882 -345.170506)
		(width 0.13462)
		(layer "F.Cu")
		(net "P5E_PEX0_STN6_TX_C_DP<111>")
	)
	(segment
		(start 61.663072 -345.755976)
		(end 61.372242 -345.465146)
		(width 0.1651)
		(layer "In13.Cu")
		(net "P5E_PEX0_STN6_TX_C_DP<111>")
	)
	(segment
		(start 72.506332 -394.75664)
		(end 71.87057 -394.331698)
		(width 0.1651)
		(layer "In13.Cu")
		(net "P5E_PEX0_STN6_TX_C_DP<111>")
	)
	(segment
		(start 60.108592 -347.866208)
		(end 61.663072 -346.311728)
		(width 0.1651)
		(layer "In13.Cu")
		(net "P5E_PEX0_STN6_TX_C_DP<111>")
	)
	(segment
		(start 71.90994 -408.572208)
		(end 72.03694 -408.699208)
		(width 0.1651)
		(layer "In13.Cu")
		(net "P5E_PEX0_STN6_TX_C_DP<111>")
	)
	(segment
		(start 71.90994 -408.190192)
		(end 71.90994 -408.572208)
		(width 0.1651)
		(layer "In13.Cu")
		(net "P5E_PEX0_STN6_TX_C_DP<111>")
	)
	(segment
		(start 72.802242 -408.382978)
		(end 72.802242 -395.309852)
		(width 0.1651)
		(layer "In13.Cu")
		(net "P5E_PEX0_STN6_TX_C_DP<111>")
	)
	(segment
		(start 71.299832 -394.087858)
		(end 71.268336 -393.929362)
		(width 0.1651)
		(layer "In13.Cu")
		(net "P5E_PEX0_STN6_TX_C_DP<111>")
	)
	(segment
		(start 70.254622 -393.25169)
		(end 67.476624 -391.395204)
		(width 0.1651)
		(layer "In13.Cu")
		(net "P5E_PEX0_STN6_TX_C_DP<111>")
	)
	(segment
		(start 71.712074 -394.363194)
		(end 71.299832 -394.087858)
		(width 0.1651)
		(layer "In13.Cu")
		(net "P5E_PEX0_STN6_TX_C_DP<111>")
	)
	(segment
		(start 72.802242 -395.309852)
		(end 72.506332 -394.75664)
		(width 0.1651)
		(layer "In13.Cu")
		(net "P5E_PEX0_STN6_TX_C_DP<111>")
	)
	(segment
		(start 63.375286 -384.47853)
		(end 61.402468 -361.649518)
		(width 0.1651)
		(layer "In13.Cu")
		(net "P5E_PEX0_STN6_TX_C_DP<111>")
	)
	(segment
		(start 72.03694 -408.699208)
		(end 72.486012 -408.699208)
		(width 0.1651)
		(layer "In13.Cu")
		(net "P5E_PEX0_STN6_TX_C_DP<111>")
	)
	(segment
		(start 61.402468 -361.649518)
		(end 60.108592 -352.553524)
		(width 0.1651)
		(layer "In13.Cu")
		(net "P5E_PEX0_STN6_TX_C_DP<111>")
	)
	(segment
		(start 71.268336 -393.929362)
		(end 70.856602 -393.65428)
		(width 0.1651)
		(layer "In13.Cu")
		(net "P5E_PEX0_STN6_TX_C_DP<111>")
	)
	(segment
		(start 70.286118 -393.410186)
		(end 70.254622 -393.25169)
		(width 0.1651)
		(layer "In13.Cu")
		(net "P5E_PEX0_STN6_TX_C_DP<111>")
	)
	(segment
		(start 61.663072 -346.311728)
		(end 61.663072 -345.755976)
		(width 0.1651)
		(layer "In13.Cu")
		(net "P5E_PEX0_STN6_TX_C_DP<111>")
	)
	(segment
		(start 70.698106 -393.685776)
		(end 70.286118 -393.410186)
		(width 0.1651)
		(layer "In13.Cu")
		(net "P5E_PEX0_STN6_TX_C_DP<111>")
	)
	(segment
		(start 67.476624 -391.395204)
		(end 65.366392 -389.284972)
		(width 0.1651)
		(layer "In13.Cu")
		(net "P5E_PEX0_STN6_TX_C_DP<111>")
	)
	(segment
		(start 60.108592 -352.553524)
		(end 60.108592 -347.866208)
		(width 0.1651)
		(layer "In13.Cu")
		(net "P5E_PEX0_STN6_TX_C_DP<111>")
	)
	(segment
		(start 65.366392 -389.284972)
		(end 63.375286 -384.47853)
		(width 0.1651)
		(layer "In13.Cu")
		(net "P5E_PEX0_STN6_TX_C_DP<111>")
	)
	(segment
		(start 72.486012 -408.699208)
		(end 72.802242 -408.382978)
		(width 0.1651)
		(layer "In13.Cu")
		(net "P5E_PEX0_STN6_TX_C_DP<111>")
	)
	(segment
		(start 70.856602 -393.65428)
		(end 70.698106 -393.685776)
		(width 0.1651)
		(layer "In13.Cu")
		(net "P5E_PEX0_STN6_TX_C_DP<111>")
	)
	(segment
		(start 71.87057 -394.331698)
		(end 71.712074 -394.363194)
		(width 0.1651)
		(layer "In13.Cu")
		(net "P5E_PEX0_STN6_TX_C_DP<111>")
	)
	(segment
		(start 242.864894 -33.790128)
		(end 242.387374 -33.790128)
		(width 0.13462)
		(layer "F.Cu")
		(net "P5E_PEX2_STN2_RX_DN<47>")
	)
	(segment
		(start 242.22456 -33.952942)
		(end 239.704626 -33.952942)
		(width 0.13462)
		(layer "F.Cu")
		(net "P5E_PEX2_STN2_RX_DN<47>")
	)
	(segment
		(start 239.704626 -33.952942)
		(end 239.410494 -33.65881)
		(width 0.13462)
		(layer "F.Cu")
		(net "P5E_PEX2_STN2_RX_DN<47>")
	)
	(segment
		(start 242.387374 -33.790128)
		(end 242.22456 -33.952942)
		(width 0.13462)
		(layer "F.Cu")
		(net "P5E_PEX2_STN2_RX_DN<47>")
	)
	(segment
		(start 256.094738 -144.65427)
		(end 252.840744 -119.914416)
		(width 0.1651)
		(layer "In7.Cu")
		(net "P5E_PEX2_STN2_RX_DN<47>")
	)
	(segment
		(start 275.748496 -267.026644)
		(end 275.335238 -263.578594)
		(width 0.1651)
		(layer "In7.Cu")
		(net "P5E_PEX2_STN2_RX_DN<47>")
	)
	(segment
		(start 273.828256 -238.434118)
		(end 256.094738 -144.65427)
		(width 0.1651)
		(layer "In7.Cu")
		(net "P5E_PEX2_STN2_RX_DN<47>")
	)
	(segment
		(start 239.701324 -33.94964)
		(end 239.410494 -33.65881)
		(width 0.1651)
		(layer "In7.Cu")
		(net "P5E_PEX2_STN2_RX_DN<47>")
	)
	(segment
		(start 252.840744 -119.914416)
		(end 247.636538 -102.745032)
		(width 0.1651)
		(layer "In7.Cu")
		(net "P5E_PEX2_STN2_RX_DN<47>")
	)
	(segment
		(start 242.465352 -49.854612)
		(end 241.163602 -40.2209)
		(width 0.1651)
		(layer "In7.Cu")
		(net "P5E_PEX2_STN2_RX_DN<47>")
	)
	(segment
		(start 275.335238 -262.327898)
		(end 275.401024 -255.61163)
		(width 0.1651)
		(layer "In7.Cu")
		(net "P5E_PEX2_STN2_RX_DN<47>")
	)
	(segment
		(start 241.088164 -34.98596)
		(end 240.051844 -33.94964)
		(width 0.1651)
		(layer "In7.Cu")
		(net "P5E_PEX2_STN2_RX_DN<47>")
	)
	(segment
		(start 276.420834 -273.479514)
		(end 276.269958 -273.328638)
		(width 0.1143)
		(layer "In7.Cu")
		(net "P5E_PEX2_STN2_RX_DN<47>")
	)
	(segment
		(start 242.349782 -57.243218)
		(end 242.465352 -49.854612)
		(width 0.1651)
		(layer "In7.Cu")
		(net "P5E_PEX2_STN2_RX_DN<47>")
	)
	(segment
		(start 276.315678 -270.472916)
		(end 276.117812 -268.824202)
		(width 0.1651)
		(layer "In7.Cu")
		(net "P5E_PEX2_STN2_RX_DN<47>")
	)
	(segment
		(start 276.315678 -271.3736)
		(end 276.315678 -271.345152)
		(width 0.1143)
		(layer "In7.Cu")
		(net "P5E_PEX2_STN2_RX_DN<47>")
	)
	(segment
		(start 276.117812 -268.824202)
		(end 275.748496 -267.026644)
		(width 0.1651)
		(layer "In7.Cu")
		(net "P5E_PEX2_STN2_RX_DN<47>")
	)
	(segment
		(start 242.621308 -60.243212)
		(end 242.349782 -57.243218)
		(width 0.1651)
		(layer "In7.Cu")
		(net "P5E_PEX2_STN2_RX_DN<47>")
	)
	(segment
		(start 247.636538 -102.745032)
		(end 247.636284 -102.744524)
		(width 0.1651)
		(layer "In7.Cu")
		(net "P5E_PEX2_STN2_RX_DN<47>")
	)
	(segment
		(start 275.401024 -255.61163)
		(end 273.828256 -238.434118)
		(width 0.1651)
		(layer "In7.Cu")
		(net "P5E_PEX2_STN2_RX_DN<47>")
	)
	(segment
		(start 275.335238 -263.578594)
		(end 275.335238 -262.327898)
		(width 0.1651)
		(layer "In7.Cu")
		(net "P5E_PEX2_STN2_RX_DN<47>")
	)
	(segment
		(start 242.621308 -62.60846)
		(end 242.621308 -60.243212)
		(width 0.1651)
		(layer "In7.Cu")
		(net "P5E_PEX2_STN2_RX_DN<47>")
	)
	(segment
		(start 242.431824 -85.574378)
		(end 242.621308 -62.60846)
		(width 0.1651)
		(layer "In7.Cu")
		(net "P5E_PEX2_STN2_RX_DN<47>")
	)
	(segment
		(start 276.649688 -273.365214)
		(end 276.535388 -273.479514)
		(width 0.1143)
		(layer "In7.Cu")
		(net "P5E_PEX2_STN2_RX_DN<47>")
	)
	(segment
		(start 276.315678 -271.345152)
		(end 276.315678 -270.472916)
		(width 0.1651)
		(layer "In7.Cu")
		(net "P5E_PEX2_STN2_RX_DN<47>")
	)
	(segment
		(start 241.163602 -40.2209)
		(end 241.088164 -35.355276)
		(width 0.1651)
		(layer "In7.Cu")
		(net "P5E_PEX2_STN2_RX_DN<47>")
	)
	(segment
		(start 276.535388 -273.479514)
		(end 276.420834 -273.479514)
		(width 0.1143)
		(layer "In7.Cu")
		(net "P5E_PEX2_STN2_RX_DN<47>")
	)
	(segment
		(start 276.269958 -271.41932)
		(end 276.315678 -271.3736)
		(width 0.1143)
		(layer "In7.Cu")
		(net "P5E_PEX2_STN2_RX_DN<47>")
	)
	(segment
		(start 276.649688 -273.099784)
		(end 276.649688 -273.365214)
		(width 0.1143)
		(layer "In7.Cu")
		(net "P5E_PEX2_STN2_RX_DN<47>")
	)
	(segment
		(start 276.269958 -273.328638)
		(end 276.269958 -271.41932)
		(width 0.1143)
		(layer "In7.Cu")
		(net "P5E_PEX2_STN2_RX_DN<47>")
	)
	(segment
		(start 240.051844 -33.94964)
		(end 239.701324 -33.94964)
		(width 0.1651)
		(layer "In7.Cu")
		(net "P5E_PEX2_STN2_RX_DN<47>")
	)
	(segment
		(start 241.088164 -35.355276)
		(end 241.088164 -34.98596)
		(width 0.1651)
		(layer "In7.Cu")
		(net "P5E_PEX2_STN2_RX_DN<47>")
	)
	(segment
		(start 247.636284 -102.744524)
		(end 242.431824 -85.574378)
		(width 0.1651)
		(layer "In7.Cu")
		(net "P5E_PEX2_STN2_RX_DN<47>")
	)
	(segment
		(start 313.391804 -344.219022)
		(end 313.071764 -344.539062)
		(width 0.13462)
		(layer "F.Cu")
		(net "P5E_PEX2_STN6_TX_C_DN<111>")
	)
	(segment
		(start 313.071764 -345.170506)
		(end 313.366404 -345.465146)
		(width 0.13462)
		(layer "F.Cu")
		(net "P5E_PEX2_STN6_TX_C_DN<111>")
	)
	(segment
		(start 313.071764 -344.539062)
		(end 313.071764 -345.170506)
		(width 0.13462)
		(layer "F.Cu")
		(net "P5E_PEX2_STN6_TX_C_DN<111>")
	)
	(segment
		(start 313.075574 -346.209874)
		(end 313.075574 -345.755976)
		(width 0.1651)
		(layer "In13.Cu")
		(net "P5E_PEX2_STN6_TX_C_DN<111>")
	)
	(segment
		(start 328.584052 -392.681206)
		(end 324.38594 -389.224774)
		(width 0.1651)
		(layer "In13.Cu")
		(net "P5E_PEX2_STN6_TX_C_DN<111>")
	)
	(segment
		(start 331.80274 -394.047472)
		(end 328.58456 -392.681714)
		(width 0.1651)
		(layer "In13.Cu")
		(net "P5E_PEX2_STN6_TX_C_DN<111>")
	)
	(segment
		(start 328.584814 -392.68146)
		(end 328.584052 -392.681206)
		(width 0.1651)
		(layer "In13.Cu")
		(net "P5E_PEX2_STN6_TX_C_DN<111>")
	)
	(segment
		(start 328.58456 -392.681714)
		(end 328.584814 -392.68146)
		(width 0.1651)
		(layer "In13.Cu")
		(net "P5E_PEX2_STN6_TX_C_DN<111>")
	)
	(segment
		(start 313.29884 -358.11333)
		(end 313.29884 -353.85502)
		(width 0.1651)
		(layer "In13.Cu")
		(net "P5E_PEX2_STN6_TX_C_DN<111>")
	)
	(segment
		(start 331.490066 -409.490164)
		(end 331.490066 -409.108148)
		(width 0.1651)
		(layer "In13.Cu")
		(net "P5E_PEX2_STN6_TX_C_DN<111>")
	)
	(segment
		(start 314.630054 -352.523806)
		(end 314.630054 -347.764354)
		(width 0.1651)
		(layer "In13.Cu")
		(net "P5E_PEX2_STN6_TX_C_DN<111>")
	)
	(segment
		(start 313.29884 -353.85502)
		(end 314.630054 -352.523806)
		(width 0.1651)
		(layer "In13.Cu")
		(net "P5E_PEX2_STN6_TX_C_DN<111>")
	)
	(segment
		(start 314.630054 -347.764354)
		(end 313.075574 -346.209874)
		(width 0.1651)
		(layer "In13.Cu")
		(net "P5E_PEX2_STN6_TX_C_DN<111>")
	)
	(segment
		(start 313.075574 -345.755976)
		(end 313.366404 -345.465146)
		(width 0.1651)
		(layer "In13.Cu")
		(net "P5E_PEX2_STN6_TX_C_DN<111>")
	)
	(segment
		(start 332.616048 -408.529282)
		(end 332.616048 -394.86078)
		(width 0.1651)
		(layer "In13.Cu")
		(net "P5E_PEX2_STN6_TX_C_DN<111>")
	)
	(segment
		(start 332.164182 -408.981148)
		(end 332.616048 -408.529282)
		(width 0.1651)
		(layer "In13.Cu")
		(net "P5E_PEX2_STN6_TX_C_DN<111>")
	)
	(segment
		(start 331.490066 -409.108148)
		(end 331.617066 -408.981148)
		(width 0.1651)
		(layer "In13.Cu")
		(net "P5E_PEX2_STN6_TX_C_DN<111>")
	)
	(segment
		(start 332.616048 -394.86078)
		(end 331.80274 -394.047472)
		(width 0.1651)
		(layer "In13.Cu")
		(net "P5E_PEX2_STN6_TX_C_DN<111>")
	)
	(segment
		(start 324.38594 -389.224774)
		(end 313.29884 -358.11333)
		(width 0.1651)
		(layer "In13.Cu")
		(net "P5E_PEX2_STN6_TX_C_DN<111>")
	)
	(segment
		(start 331.617066 -408.981148)
		(end 332.164182 -408.981148)
		(width 0.1651)
		(layer "In13.Cu")
		(net "P5E_PEX2_STN6_TX_C_DN<111>")
	)
	(segment
		(start 391.009378 -337.31581)
		(end 391.169144 -337.340956)
		(width 0.1651)
		(layer "In15.Cu")
		(net "P5E_PEX3_STN5_RX_DP<88>")
	)
	(segment
		(start 414.599882 -316.115192)
		(end 414.599882 -315.849762)
		(width 0.1143)
		(layer "In15.Cu")
		(net "P5E_PEX3_STN5_RX_DP<88>")
	)
	(segment
		(start 375.616978 -370.999258)
		(end 376.047254 -370.999258)
		(width 0.1651)
		(layer "In15.Cu")
		(net "P5E_PEX3_STN5_RX_DP<88>")
	)
	(segment
		(start 385.46913 -342.114632)
		(end 385.83489 -341.228172)
		(width 0.1651)
		(layer "In15.Cu")
		(net "P5E_PEX3_STN5_RX_DP<88>")
	)
	(segment
		(start 414.24479 -316.229492)
		(end 414.485582 -316.229492)
		(width 0.1143)
		(layer "In15.Cu")
		(net "P5E_PEX3_STN5_RX_DP<88>")
	)
	(segment
		(start 385.83489 -341.228172)
		(end 389.598408 -338.48548)
		(width 0.1651)
		(layer "In15.Cu")
		(net "P5E_PEX3_STN5_RX_DP<88>")
	)
	(segment
		(start 414.029652 -319.921128)
		(end 414.029652 -316.44463)
		(width 0.1143)
		(layer "In15.Cu")
		(net "P5E_PEX3_STN5_RX_DP<88>")
	)
	(segment
		(start 391.994898 -336.597752)
		(end 392.15441 -336.622898)
		(width 0.1651)
		(layer "In15.Cu")
		(net "P5E_PEX3_STN5_RX_DP<88>")
	)
	(segment
		(start 390.183624 -338.059014)
		(end 390.583674 -337.767422)
		(width 0.1651)
		(layer "In15.Cu")
		(net "P5E_PEX3_STN5_RX_DP<88>")
	)
	(segment
		(start 376.862848 -368.174524)
		(end 385.098798 -359.069894)
		(width 0.1651)
		(layer "In15.Cu")
		(net "P5E_PEX3_STN5_RX_DP<88>")
	)
	(segment
		(start 389.598408 -338.48548)
		(end 389.623554 -338.325714)
		(width 0.1651)
		(layer "In15.Cu")
		(net "P5E_PEX3_STN5_RX_DP<88>")
	)
	(segment
		(start 413.983932 -319.966848)
		(end 414.029652 -319.921128)
		(width 0.1143)
		(layer "In15.Cu")
		(net "P5E_PEX3_STN5_RX_DP<88>")
	)
	(segment
		(start 414.485582 -316.229492)
		(end 414.599882 -316.115192)
		(width 0.1143)
		(layer "In15.Cu")
		(net "P5E_PEX3_STN5_RX_DP<88>")
	)
	(segment
		(start 413.983932 -320.714624)
		(end 413.983932 -319.995296)
		(width 0.1651)
		(layer "In15.Cu")
		(net "P5E_PEX3_STN5_RX_DP<88>")
	)
	(segment
		(start 376.33402 -370.712492)
		(end 376.33402 -369.43538)
		(width 0.1651)
		(layer "In15.Cu")
		(net "P5E_PEX3_STN5_RX_DP<88>")
	)
	(segment
		(start 376.047254 -370.999258)
		(end 376.33402 -370.712492)
		(width 0.1651)
		(layer "In15.Cu")
		(net "P5E_PEX3_STN5_RX_DP<88>")
	)
	(segment
		(start 390.583674 -337.767422)
		(end 390.60882 -337.607656)
		(width 0.1651)
		(layer "In15.Cu")
		(net "P5E_PEX3_STN5_RX_DP<88>")
	)
	(segment
		(start 375.489978 -370.489988)
		(end 375.489978 -370.872258)
		(width 0.1651)
		(layer "In15.Cu")
		(net "P5E_PEX3_STN5_RX_DP<88>")
	)
	(segment
		(start 414.029652 -316.44463)
		(end 414.24479 -316.229492)
		(width 0.1143)
		(layer "In15.Cu")
		(net "P5E_PEX3_STN5_RX_DP<88>")
	)
	(segment
		(start 389.623554 -338.325714)
		(end 390.024112 -338.033868)
		(width 0.1651)
		(layer "In15.Cu")
		(net "P5E_PEX3_STN5_RX_DP<88>")
	)
	(segment
		(start 390.60882 -337.607656)
		(end 391.009378 -337.31581)
		(width 0.1651)
		(layer "In15.Cu")
		(net "P5E_PEX3_STN5_RX_DP<88>")
	)
	(segment
		(start 391.169144 -337.340956)
		(end 391.569194 -337.049364)
		(width 0.1651)
		(layer "In15.Cu")
		(net "P5E_PEX3_STN5_RX_DP<88>")
	)
	(segment
		(start 391.569194 -337.049364)
		(end 391.59434 -336.889598)
		(width 0.1651)
		(layer "In15.Cu")
		(net "P5E_PEX3_STN5_RX_DP<88>")
	)
	(segment
		(start 375.489978 -370.872258)
		(end 375.616978 -370.999258)
		(width 0.1651)
		(layer "In15.Cu")
		(net "P5E_PEX3_STN5_RX_DP<88>")
	)
	(segment
		(start 385.46913 -358.10825)
		(end 385.46913 -342.114632)
		(width 0.1651)
		(layer "In15.Cu")
		(net "P5E_PEX3_STN5_RX_DP<88>")
	)
	(segment
		(start 385.098798 -359.069894)
		(end 385.46913 -358.10825)
		(width 0.1651)
		(layer "In15.Cu")
		(net "P5E_PEX3_STN5_RX_DP<88>")
	)
	(segment
		(start 390.024112 -338.033868)
		(end 390.183624 -338.059014)
		(width 0.1651)
		(layer "In15.Cu")
		(net "P5E_PEX3_STN5_RX_DP<88>")
	)
	(segment
		(start 376.33402 -369.43538)
		(end 376.862848 -368.174524)
		(width 0.1651)
		(layer "In15.Cu")
		(net "P5E_PEX3_STN5_RX_DP<88>")
	)
	(segment
		(start 391.59434 -336.889598)
		(end 391.994898 -336.597752)
		(width 0.1651)
		(layer "In15.Cu")
		(net "P5E_PEX3_STN5_RX_DP<88>")
	)
	(segment
		(start 413.983932 -319.995296)
		(end 413.983932 -319.966848)
		(width 0.1143)
		(layer "In15.Cu")
		(net "P5E_PEX3_STN5_RX_DP<88>")
	)
	(segment
		(start 392.15441 -336.622898)
		(end 413.983932 -320.714624)
		(width 0.1651)
		(layer "In15.Cu")
		(net "P5E_PEX3_STN5_RX_DP<88>")
	)
	(segment
		(start 73.257664 -100.640134)
		(end 75.538838 -100.640134)
		(width 0.13208)
		(layer "F.Cu")
		(net "NIC1_SLOT_ID0")
	)
	(segment
		(start 75.538838 -100.640134)
		(end 75.968352 -101.069648)
		(width 0.13208)
		(layer "F.Cu")
		(net "NIC1_SLOT_ID0")
	)
	(via
		(at 75.968352 -101.069648)
		(size 0.508)
		(drill 0.254)
		(layers "F.Cu" "B.Cu")
		(net "NIC1_SLOT_ID0")
	)
	(segment
		(start 77.141832 -101.069648)
		(end 75.968352 -101.069648)
		(width 0.13208)
		(layer "B.Cu")
		(net "NIC1_SLOT_ID0")
	)
	(segment
		(start 77.141832 -100.056696)
		(end 77.141832 -101.069648)
		(width 0.13208)
		(layer "B.Cu")
		(net "NIC1_SLOT_ID0")
	)
	(segment
		(start 309.824882 -14.100302)
		(end 309.824882 -14.735302)
		(width 0.381)
		(layer "F.Cu")
		(net "P3V3_SSD10")
	)
	(segment
		(start 289.89401 -32.787336)
		(end 289.89401 -34.248852)
		(width 0.381)
		(layer "F.Cu")
		(net "P3V3_SSD10")
	)
	(segment
		(start 308.869334 -20.467574)
		(end 308.256432 -20.467574)
		(width 0.508)
		(layer "F.Cu")
		(net "P3V3_SSD10")
	)
	(segment
		(start 306.085494 -27.492198)
		(end 305.953922 -27.492198)
		(width 0.381)
		(layer "F.Cu")
		(net "P3V3_SSD10")
	)
	(segment
		(start 309.824882 -14.735302)
		(end 309.760366 -14.799818)
		(width 0.381)
		(layer "F.Cu")
		(net "P3V3_SSD10")
	)
	(segment
		(start 300.67504 -25.031954)
		(end 302.126396 -25.031954)
		(width 0.381)
		(layer "F.Cu")
		(net "P3V3_SSD10")
	)
	(segment
		(start 292.378892 -59.978036)
		(end 292.378892 -60.633356)
		(width 0.381)
		(layer "F.Cu")
		(net "P3V3_SSD10")
	)
	(segment
		(start 309.760366 -14.799818)
		(end 309.760366 -16.439388)
		(width 0.381)
		(layer "F.Cu")
		(net "P3V3_SSD10")
	)
	(segment
		(start 308.256432 -17.419574)
		(end 308.866032 -17.419574)
		(width 0.508)
		(layer "F.Cu")
		(net "P3V3_SSD10")
	)
	(segment
		(start 302.126396 -25.031954)
		(end 302.769778 -25.031954)
		(width 0.4572)
		(layer "F.Cu")
		(net "P3V3_SSD10")
	)
	(segment
		(start 290.168584 -32.512762)
		(end 289.89401 -32.787336)
		(width 0.381)
		(layer "F.Cu")
		(net "P3V3_SSD10")
	)
	(segment
		(start 291.57168 -24.807418)
		(end 290.95319 -24.807418)
		(width 0.4572)
		(layer "F.Cu")
		(net "P3V3_SSD10")
	)
	(segment
		(start 277.04669 -37.47516)
		(end 276.341078 -37.47516)
		(width 0.4572)
		(layer "F.Cu")
		(net "P3V3_SSD10")
	)
	(segment
		(start 300.433232 -24.790146)
		(end 300.67504 -25.031954)
		(width 0.381)
		(layer "F.Cu")
		(net "P3V3_SSD10")
	)
	(segment
		(start 289.594036 -30.396688)
		(end 290.168584 -30.971236)
		(width 0.381)
		(layer "F.Cu")
		(net "P3V3_SSD10")
	)
	(segment
		(start 299.46473 -24.790146)
		(end 300.433232 -24.790146)
		(width 0.381)
		(layer "F.Cu")
		(net "P3V3_SSD10")
	)
	(segment
		(start 303.671478 -25.742392)
		(end 303.671478 -26.360882)
		(width 0.4572)
		(layer "F.Cu")
		(net "P3V3_SSD10")
	)
	(segment
		(start 305.953922 -27.492198)
		(end 305.432968 -26.971244)
		(width 0.381)
		(layer "F.Cu")
		(net "P3V3_SSD10")
	)
	(segment
		(start 290.168584 -30.971236)
		(end 290.168584 -32.512762)
		(width 0.381)
		(layer "F.Cu")
		(net "P3V3_SSD10")
	)
	(via
		(at 291.328856 -49.574704)
		(size 0.508)
		(drill 0.254)
		(layers "F.Cu" "B.Cu")
		(net "P3V3_SSD10")
	)
	(via
		(at 290.71443 -53.469286)
		(size 0.508)
		(drill 0.254)
		(layers "F.Cu" "B.Cu")
		(net "P3V3_SSD10")
	)
	(via
		(at 276.341078 -37.47516)
		(size 0.508)
		(drill 0.254)
		(layers "F.Cu" "B.Cu")
		(net "P3V3_SSD10")
	)
	(via
		(at 292.378892 -60.633356)
		(size 0.508)
		(drill 0.254)
		(layers "F.Cu" "B.Cu")
		(net "P3V3_SSD10")
	)
	(via
		(at 302.769778 -25.031954)
		(size 0.508)
		(drill 0.254)
		(layers "F.Cu" "B.Cu")
		(net "P3V3_SSD10")
	)
	(via
		(at 288.510472 -29.614876)
		(size 0.508)
		(drill 0.254)
		(layers "F.Cu" "B.Cu")
		(net "P3V3_SSD10")
	)
	(via
		(at 292.476428 -51.320192)
		(size 0.508)
		(drill 0.254)
		(layers "F.Cu" "B.Cu")
		(net "P3V3_SSD10")
	)
	(via
		(at 308.869334 -20.467574)
		(size 0.508)
		(drill 0.254)
		(layers "F.Cu" "B.Cu")
		(net "P3V3_SSD10")
	)
	(via
		(at 305.432968 -26.971244)
		(size 0.508)
		(drill 0.254)
		(layers "F.Cu" "B.Cu")
		(net "P3V3_SSD10")
	)
	(via
		(at 290.693856 -50.478182)
		(size 0.6604)
		(drill 0.3302)
		(layers "F.Cu" "B.Cu")
		(net "P3V3_SSD10")
	)
	(via
		(at 291.963856 -49.574704)
		(size 0.508)
		(drill 0.254)
		(layers "F.Cu" "B.Cu")
		(net "P3V3_SSD10")
	)
	(via
		(at 308.866032 -17.419574)
		(size 0.508)
		(drill 0.254)
		(layers "F.Cu" "B.Cu")
		(net "P3V3_SSD10")
	)
	(via
		(at 291.714428 -50.608992)
		(size 0.508)
		(drill 0.254)
		(layers "F.Cu" "B.Cu")
		(net "P3V3_SSD10")
	)
	(via
		(at 288.510472 -30.376876)
		(size 0.508)
		(drill 0.254)
		(layers "F.Cu" "B.Cu")
		(net "P3V3_SSD10")
	)
	(via
		(at 291.164772 -52.528724)
		(size 0.508)
		(drill 0.254)
		(layers "F.Cu" "B.Cu")
		(net "P3V3_SSD10")
	)
	(via
		(at 291.34943 -53.469286)
		(size 0.508)
		(drill 0.254)
		(layers "F.Cu" "B.Cu")
		(net "P3V3_SSD10")
	)
	(via
		(at 309.824882 -14.100302)
		(size 0.508)
		(drill 0.254)
		(layers "F.Cu" "B.Cu")
		(net "P3V3_SSD10")
	)
	(via
		(at 290.693856 -49.574704)
		(size 0.508)
		(drill 0.254)
		(layers "F.Cu" "B.Cu")
		(net "P3V3_SSD10")
	)
	(via
		(at 291.799772 -52.528724)
		(size 0.508)
		(drill 0.254)
		(layers "F.Cu" "B.Cu")
		(net "P3V3_SSD10")
	)
	(via
		(at 292.476428 -50.608992)
		(size 0.508)
		(drill 0.254)
		(layers "F.Cu" "B.Cu")
		(net "P3V3_SSD10")
	)
	(via
		(at 291.714428 -51.243992)
		(size 0.508)
		(drill 0.254)
		(layers "F.Cu" "B.Cu")
		(net "P3V3_SSD10")
	)
	(via
		(at 303.671478 -26.360882)
		(size 0.508)
		(drill 0.254)
		(layers "F.Cu" "B.Cu")
		(net "P3V3_SSD10")
	)
	(via
		(at 290.95319 -24.807418)
		(size 0.508)
		(drill 0.254)
		(layers "F.Cu" "B.Cu")
		(net "P3V3_SSD10")
	)
	(via
		(at 292.598856 -49.574704)
		(size 0.508)
		(drill 0.254)
		(layers "F.Cu" "B.Cu")
		(net "P3V3_SSD10")
	)
	(segment
		(start 277.188676 -38.322758)
		(end 276.341078 -37.47516)
		(width 0.508)
		(layer "In9.Cu")
		(net "P3V3_SSD10")
	)
	(segment
		(start 279.25395 -37.872924)
		(end 278.804116 -38.322758)
		(width 0.508)
		(layer "In9.Cu")
		(net "P3V3_SSD10")
	)
	(segment
		(start 278.804116 -38.322758)
		(end 277.188676 -38.322758)
		(width 0.508)
		(layer "In9.Cu")
		(net "P3V3_SSD10")
	)
	(segment
		(start 285.963614 -37.872924)
		(end 279.25395 -37.872924)
		(width 0.508)
		(layer "In9.Cu")
		(net "P3V3_SSD10")
	)
	(segment
		(start 51.948588 -108.88218)
		(end 51.293268 -108.88218)
		(width 0.13462)
		(layer "F.Cu")
		(net "P5E_PEX0_STN1_RX_DN<21>")
	)
	(segment
		(start 52.24272 -109.176312)
		(end 51.948588 -108.88218)
		(width 0.13462)
		(layer "F.Cu")
		(net "P5E_PEX0_STN1_RX_DN<21>")
	)
	(segment
		(start 51.293268 -108.88218)
		(end 51.130454 -109.044994)
		(width 0.13462)
		(layer "F.Cu")
		(net "P5E_PEX0_STN1_RX_DN<21>")
	)
	(segment
		(start 51.130454 -109.044994)
		(end 50.64252 -109.044994)
		(width 0.13462)
		(layer "F.Cu")
		(net "P5E_PEX0_STN1_RX_DN<21>")
	)
	(segment
		(start 38.961822 -126.85014)
		(end 38.766496 -127.305562)
		(width 0.1651)
		(layer "In5.Cu")
		(net "P5E_PEX0_STN1_RX_DN<21>")
	)
	(segment
		(start 38.420802 -127.82042)
		(end 38.480746 -127.970534)
		(width 0.1651)
		(layer "In5.Cu")
		(net "P5E_PEX0_STN1_RX_DN<21>")
	)
	(segment
		(start 38.135052 -128.4859)
		(end 37.939726 -128.940814)
		(width 0.1651)
		(layer "In5.Cu")
		(net "P5E_PEX0_STN1_RX_DN<21>")
	)
	(segment
		(start 64.020192 -271.848072)
		(end 64.020192 -275.276056)
		(width 0.1143)
		(layer "In5.Cu")
		(net "P5E_PEX0_STN1_RX_DN<21>")
	)
	(segment
		(start 42.671746 -113.984532)
		(end 42.011092 -115.159028)
		(width 0.1651)
		(layer "In5.Cu")
		(net "P5E_PEX0_STN1_RX_DN<21>")
	)
	(segment
		(start 33.375092 -150.684484)
		(end 33.859724 -158.511494)
		(width 0.1651)
		(layer "In5.Cu")
		(net "P5E_PEX0_STN1_RX_DN<21>")
	)
	(segment
		(start 64.285368 -275.379434)
		(end 64.399668 -275.265134)
		(width 0.1143)
		(layer "In5.Cu")
		(net "P5E_PEX0_STN1_RX_DN<21>")
	)
	(segment
		(start 33.859724 -158.511494)
		(end 34.911538 -164.60978)
		(width 0.1651)
		(layer "In5.Cu")
		(net "P5E_PEX0_STN1_RX_DN<21>")
	)
	(segment
		(start 51.620166 -108.887006)
		(end 51.092862 -109.186218)
		(width 0.1651)
		(layer "In5.Cu")
		(net "P5E_PEX0_STN1_RX_DN<21>")
	)
	(segment
		(start 64.065912 -271.773904)
		(end 64.065912 -271.802352)
		(width 0.1143)
		(layer "In5.Cu")
		(net "P5E_PEX0_STN1_RX_DN<21>")
	)
	(segment
		(start 51.61915 -108.885482)
		(end 51.620166 -108.886498)
		(width 0.1651)
		(layer "In5.Cu")
		(net "P5E_PEX0_STN1_RX_DN<21>")
	)
	(segment
		(start 51.620166 -108.886498)
		(end 51.620166 -108.887006)
		(width 0.1651)
		(layer "In5.Cu")
		(net "P5E_PEX0_STN1_RX_DN<21>")
	)
	(segment
		(start 42.723562 -113.93424)
		(end 42.671746 -113.984532)
		(width 0.1651)
		(layer "In5.Cu")
		(net "P5E_PEX0_STN1_RX_DN<21>")
	)
	(segment
		(start 64.065912 -271.802352)
		(end 64.020192 -271.848072)
		(width 0.1143)
		(layer "In5.Cu")
		(net "P5E_PEX0_STN1_RX_DN<21>")
	)
	(segment
		(start 49.402492 -110.145322)
		(end 48.758094 -110.510828)
		(width 0.1651)
		(layer "In5.Cu")
		(net "P5E_PEX0_STN1_RX_DN<21>")
	)
	(segment
		(start 38.28542 -128.425956)
		(end 38.135052 -128.4859)
		(width 0.1651)
		(layer "In5.Cu")
		(net "P5E_PEX0_STN1_RX_DN<21>")
	)
	(segment
		(start 52.24272 -109.176312)
		(end 51.95189 -108.885482)
		(width 0.1651)
		(layer "In5.Cu")
		(net "P5E_PEX0_STN1_RX_DN<21>")
	)
	(segment
		(start 64.020192 -275.276056)
		(end 64.12357 -275.379434)
		(width 0.1143)
		(layer "In5.Cu")
		(net "P5E_PEX0_STN1_RX_DN<21>")
	)
	(segment
		(start 34.911538 -164.60978)
		(end 64.065912 -269.144496)
		(width 0.1651)
		(layer "In5.Cu")
		(net "P5E_PEX0_STN1_RX_DN<21>")
	)
	(segment
		(start 50.032158 -109.787944)
		(end 49.989232 -109.943646)
		(width 0.1651)
		(layer "In5.Cu")
		(net "P5E_PEX0_STN1_RX_DN<21>")
	)
	(segment
		(start 51.95189 -108.885482)
		(end 51.61915 -108.885482)
		(width 0.1651)
		(layer "In5.Cu")
		(net "P5E_PEX0_STN1_RX_DN<21>")
	)
	(segment
		(start 47.067724 -111.469932)
		(end 42.723562 -113.93424)
		(width 0.1651)
		(layer "In5.Cu")
		(net "P5E_PEX0_STN1_RX_DN<21>")
	)
	(segment
		(start 42.011092 -115.159028)
		(end 39.90213 -124.370846)
		(width 0.1651)
		(layer "In5.Cu")
		(net "P5E_PEX0_STN1_RX_DN<21>")
	)
	(segment
		(start 64.12357 -275.379434)
		(end 64.285368 -275.379434)
		(width 0.1143)
		(layer "In5.Cu")
		(net "P5E_PEX0_STN1_RX_DN<21>")
	)
	(segment
		(start 37.323014 -130.666744)
		(end 37.172646 -130.726688)
		(width 0.1651)
		(layer "In5.Cu")
		(net "P5E_PEX0_STN1_RX_DN<21>")
	)
	(segment
		(start 37.99967 -129.090928)
		(end 37.80409 -129.54635)
		(width 0.1651)
		(layer "In5.Cu")
		(net "P5E_PEX0_STN1_RX_DN<21>")
	)
	(segment
		(start 37.939726 -128.940814)
		(end 37.99967 -129.090928)
		(width 0.1651)
		(layer "In5.Cu")
		(net "P5E_PEX0_STN1_RX_DN<21>")
	)
	(segment
		(start 49.558194 -110.188248)
		(end 49.402492 -110.145322)
		(width 0.1651)
		(layer "In5.Cu")
		(net "P5E_PEX0_STN1_RX_DN<21>")
	)
	(segment
		(start 48.758094 -110.510828)
		(end 48.715168 -110.66653)
		(width 0.1651)
		(layer "In5.Cu")
		(net "P5E_PEX0_STN1_RX_DN<21>")
	)
	(segment
		(start 37.172646 -130.726688)
		(end 36.552886 -132.169662)
		(width 0.1651)
		(layer "In5.Cu")
		(net "P5E_PEX0_STN1_RX_DN<21>")
	)
	(segment
		(start 38.901878 -126.700026)
		(end 38.961822 -126.85014)
		(width 0.1651)
		(layer "In5.Cu")
		(net "P5E_PEX0_STN1_RX_DN<21>")
	)
	(segment
		(start 64.065912 -269.144496)
		(end 64.065912 -271.773904)
		(width 0.1651)
		(layer "In5.Cu")
		(net "P5E_PEX0_STN1_RX_DN<21>")
	)
	(segment
		(start 37.51834 -130.211322)
		(end 37.323014 -130.666744)
		(width 0.1651)
		(layer "In5.Cu")
		(net "P5E_PEX0_STN1_RX_DN<21>")
	)
	(segment
		(start 48.28413 -110.911132)
		(end 48.128428 -110.868206)
		(width 0.1651)
		(layer "In5.Cu")
		(net "P5E_PEX0_STN1_RX_DN<21>")
	)
	(segment
		(start 50.618644 -109.586522)
		(end 50.462942 -109.543596)
		(width 0.1651)
		(layer "In5.Cu")
		(net "P5E_PEX0_STN1_RX_DN<21>")
	)
	(segment
		(start 37.80409 -129.54635)
		(end 37.653722 -129.606294)
		(width 0.1651)
		(layer "In5.Cu")
		(net "P5E_PEX0_STN1_RX_DN<21>")
	)
	(segment
		(start 38.480746 -127.970534)
		(end 38.28542 -128.425956)
		(width 0.1651)
		(layer "In5.Cu")
		(net "P5E_PEX0_STN1_RX_DN<21>")
	)
	(segment
		(start 48.715168 -110.66653)
		(end 48.28413 -110.911132)
		(width 0.1651)
		(layer "In5.Cu")
		(net "P5E_PEX0_STN1_RX_DN<21>")
	)
	(segment
		(start 36.552886 -136.432798)
		(end 35.359848 -139.737338)
		(width 0.1651)
		(layer "In5.Cu")
		(net "P5E_PEX0_STN1_RX_DN<21>")
	)
	(segment
		(start 35.359848 -139.737338)
		(end 33.375092 -150.684484)
		(width 0.1651)
		(layer "In5.Cu")
		(net "P5E_PEX0_STN1_RX_DN<21>")
	)
	(segment
		(start 50.462942 -109.543596)
		(end 50.032158 -109.787944)
		(width 0.1651)
		(layer "In5.Cu")
		(net "P5E_PEX0_STN1_RX_DN<21>")
	)
	(segment
		(start 49.989232 -109.943646)
		(end 49.558194 -110.188248)
		(width 0.1651)
		(layer "In5.Cu")
		(net "P5E_PEX0_STN1_RX_DN<21>")
	)
	(segment
		(start 36.552886 -132.169662)
		(end 36.552886 -136.432798)
		(width 0.1651)
		(layer "In5.Cu")
		(net "P5E_PEX0_STN1_RX_DN<21>")
	)
	(segment
		(start 47.654718 -111.268256)
		(end 47.22368 -111.512858)
		(width 0.1651)
		(layer "In5.Cu")
		(net "P5E_PEX0_STN1_RX_DN<21>")
	)
	(segment
		(start 38.616128 -127.365506)
		(end 38.420802 -127.82042)
		(width 0.1651)
		(layer "In5.Cu")
		(net "P5E_PEX0_STN1_RX_DN<21>")
	)
	(segment
		(start 47.22368 -111.512858)
		(end 47.067724 -111.469932)
		(width 0.1651)
		(layer "In5.Cu")
		(net "P5E_PEX0_STN1_RX_DN<21>")
	)
	(segment
		(start 37.653722 -129.606294)
		(end 37.458396 -130.061208)
		(width 0.1651)
		(layer "In5.Cu")
		(net "P5E_PEX0_STN1_RX_DN<21>")
	)
	(segment
		(start 47.697644 -111.112554)
		(end 47.654718 -111.268256)
		(width 0.1651)
		(layer "In5.Cu")
		(net "P5E_PEX0_STN1_RX_DN<21>")
	)
	(segment
		(start 38.766496 -127.305562)
		(end 38.616128 -127.365506)
		(width 0.1651)
		(layer "In5.Cu")
		(net "P5E_PEX0_STN1_RX_DN<21>")
	)
	(segment
		(start 64.399668 -275.265134)
		(end 64.399668 -274.999704)
		(width 0.1143)
		(layer "In5.Cu")
		(net "P5E_PEX0_STN1_RX_DN<21>")
	)
	(segment
		(start 51.092862 -109.186218)
		(end 51.049936 -109.34192)
		(width 0.1651)
		(layer "In5.Cu")
		(net "P5E_PEX0_STN1_RX_DN<21>")
	)
	(segment
		(start 51.049936 -109.34192)
		(end 50.618644 -109.586522)
		(width 0.1651)
		(layer "In5.Cu")
		(net "P5E_PEX0_STN1_RX_DN<21>")
	)
	(segment
		(start 37.458396 -130.061208)
		(end 37.51834 -130.211322)
		(width 0.1651)
		(layer "In5.Cu")
		(net "P5E_PEX0_STN1_RX_DN<21>")
	)
	(segment
		(start 39.90213 -124.370846)
		(end 38.901878 -126.700026)
		(width 0.1651)
		(layer "In5.Cu")
		(net "P5E_PEX0_STN1_RX_DN<21>")
	)
	(segment
		(start 48.128428 -110.868206)
		(end 47.697644 -111.112554)
		(width 0.1651)
		(layer "In5.Cu")
		(net "P5E_PEX0_STN1_RX_DN<21>")
	)
	(segment
		(start 71.90994 -374.390158)
		(end 71.90994 -374.772174)
		(width 0.1651)
		(layer "In9.Cu")
		(net "P5E_PEX0_STN6_RX_DP<103>")
	)
	(segment
		(start 51.099974 -316.140592)
		(end 51.099974 -315.849762)
		(width 0.1143)
		(layer "In9.Cu")
		(net "P5E_PEX0_STN6_RX_DP<103>")
	)
	(segment
		(start 68.932044 -366.213898)
		(end 68.900294 -366.055402)
		(width 0.1651)
		(layer "In9.Cu")
		(net "P5E_PEX0_STN6_RX_DP<103>")
	)
	(segment
		(start 68.900294 -366.055402)
		(end 68.48856 -365.78032)
		(width 0.1651)
		(layer "In9.Cu")
		(net "P5E_PEX0_STN6_RX_DP<103>")
	)
	(segment
		(start 56.998362 -346.71889)
		(end 50.484024 -325.243444)
		(width 0.1651)
		(layer "In9.Cu")
		(net "P5E_PEX0_STN6_RX_DP<103>")
	)
	(segment
		(start 58.568844 -354.614734)
		(end 56.998362 -346.71889)
		(width 0.1651)
		(layer "In9.Cu")
		(net "P5E_PEX0_STN6_RX_DP<103>")
	)
	(segment
		(start 72.802242 -369.324128)
		(end 72.423274 -368.409474)
		(width 0.1651)
		(layer "In9.Cu")
		(net "P5E_PEX0_STN6_RX_DP<103>")
	)
	(segment
		(start 69.945758 -366.89157)
		(end 69.914262 -366.73282)
		(width 0.1651)
		(layer "In9.Cu")
		(net "P5E_PEX0_STN6_RX_DP<103>")
	)
	(segment
		(start 69.914262 -366.73282)
		(end 69.502528 -366.457738)
		(width 0.1651)
		(layer "In9.Cu")
		(net "P5E_PEX0_STN6_RX_DP<103>")
	)
	(segment
		(start 69.344032 -366.489234)
		(end 68.932044 -366.213898)
		(width 0.1651)
		(layer "In9.Cu")
		(net "P5E_PEX0_STN6_RX_DP<103>")
	)
	(segment
		(start 71.90994 -374.772174)
		(end 72.03694 -374.899174)
		(width 0.1651)
		(layer "In9.Cu")
		(net "P5E_PEX0_STN6_RX_DP<103>")
	)
	(segment
		(start 70.516496 -367.13541)
		(end 70.357746 -367.166906)
		(width 0.1651)
		(layer "In9.Cu")
		(net "P5E_PEX0_STN6_RX_DP<103>")
	)
	(segment
		(start 50.529744 -319.91808)
		(end 50.529744 -316.506098)
		(width 0.1143)
		(layer "In9.Cu")
		(net "P5E_PEX0_STN6_RX_DP<103>")
	)
	(segment
		(start 50.484024 -319.992248)
		(end 50.484024 -319.9638)
		(width 0.1143)
		(layer "In9.Cu")
		(net "P5E_PEX0_STN6_RX_DP<103>")
	)
	(segment
		(start 69.502528 -366.457738)
		(end 69.344032 -366.489234)
		(width 0.1651)
		(layer "In9.Cu")
		(net "P5E_PEX0_STN6_RX_DP<103>")
	)
	(segment
		(start 70.357746 -367.166906)
		(end 69.945758 -366.89157)
		(width 0.1651)
		(layer "In9.Cu")
		(net "P5E_PEX0_STN6_RX_DP<103>")
	)
	(segment
		(start 50.484024 -325.243444)
		(end 50.484024 -319.992248)
		(width 0.1651)
		(layer "In9.Cu")
		(net "P5E_PEX0_STN6_RX_DP<103>")
	)
	(segment
		(start 67.918076 -365.53648)
		(end 67.886326 -365.377984)
		(width 0.1651)
		(layer "In9.Cu")
		(net "P5E_PEX0_STN6_RX_DP<103>")
	)
	(segment
		(start 67.886326 -365.377984)
		(end 63.810642 -362.654596)
		(width 0.1651)
		(layer "In9.Cu")
		(net "P5E_PEX0_STN6_RX_DP<103>")
	)
	(segment
		(start 72.423274 -368.409474)
		(end 70.516496 -367.13541)
		(width 0.1651)
		(layer "In9.Cu")
		(net "P5E_PEX0_STN6_RX_DP<103>")
	)
	(segment
		(start 63.810642 -362.654596)
		(end 62.911482 -362.281978)
		(width 0.1651)
		(layer "In9.Cu")
		(net "P5E_PEX0_STN6_RX_DP<103>")
	)
	(segment
		(start 72.4281 -374.899174)
		(end 72.802242 -374.525032)
		(width 0.1651)
		(layer "In9.Cu")
		(net "P5E_PEX0_STN6_RX_DP<103>")
	)
	(segment
		(start 72.802242 -374.525032)
		(end 72.802242 -369.324128)
		(width 0.1651)
		(layer "In9.Cu")
		(net "P5E_PEX0_STN6_RX_DP<103>")
	)
	(segment
		(start 50.484024 -319.9638)
		(end 50.529744 -319.91808)
		(width 0.1143)
		(layer "In9.Cu")
		(net "P5E_PEX0_STN6_RX_DP<103>")
	)
	(segment
		(start 68.48856 -365.78032)
		(end 68.330064 -365.811816)
		(width 0.1651)
		(layer "In9.Cu")
		(net "P5E_PEX0_STN6_RX_DP<103>")
	)
	(segment
		(start 50.529744 -316.506098)
		(end 50.80635 -316.229492)
		(width 0.1143)
		(layer "In9.Cu")
		(net "P5E_PEX0_STN6_RX_DP<103>")
	)
	(segment
		(start 72.03694 -374.899174)
		(end 72.4281 -374.899174)
		(width 0.1651)
		(layer "In9.Cu")
		(net "P5E_PEX0_STN6_RX_DP<103>")
	)
	(segment
		(start 60.919868 -360.290364)
		(end 58.568844 -354.614734)
		(width 0.1651)
		(layer "In9.Cu")
		(net "P5E_PEX0_STN6_RX_DP<103>")
	)
	(segment
		(start 50.80635 -316.229492)
		(end 51.011074 -316.229492)
		(width 0.1143)
		(layer "In9.Cu")
		(net "P5E_PEX0_STN6_RX_DP<103>")
	)
	(segment
		(start 62.911482 -362.281978)
		(end 60.919868 -360.290364)
		(width 0.1651)
		(layer "In9.Cu")
		(net "P5E_PEX0_STN6_RX_DP<103>")
	)
	(segment
		(start 51.011074 -316.229492)
		(end 51.099974 -316.140592)
		(width 0.1143)
		(layer "In9.Cu")
		(net "P5E_PEX0_STN6_RX_DP<103>")
	)
	(segment
		(start 68.330064 -365.811816)
		(end 67.918076 -365.53648)
		(width 0.1651)
		(layer "In9.Cu")
		(net "P5E_PEX0_STN6_RX_DP<103>")
	)
	(segment
		(start 304.367692 -33.631886)
		(end 304.047398 -33.95218)
		(width 0.13462)
		(layer "F.Cu")
		(net "P5E_PEX2_STN2_TX_C_DN<39>")
	)
	(segment
		(start 304.047398 -33.95218)
		(end 300.133766 -33.95218)
		(width 0.13462)
		(layer "F.Cu")
		(net "P5E_PEX2_STN2_TX_C_DN<39>")
	)
	(segment
		(start 300.133766 -33.95218)
		(end 299.971714 -33.790128)
		(width 0.13462)
		(layer "F.Cu")
		(net "P5E_PEX2_STN2_TX_C_DN<39>")
	)
	(segment
		(start 299.971714 -33.790128)
		(end 299.46473 -33.790128)
		(width 0.13462)
		(layer "F.Cu")
		(net "P5E_PEX2_STN2_TX_C_DN<39>")
	)
	(segment
		(start 331.131164 -356.511606)
		(end 331.451204 -356.831646)
		(width 0.13462)
		(layer "F.Cu")
		(net "P5E_PEX2_STN6_TX_C_DP<102>")
	)
	(segment
		(start 331.451204 -356.831646)
		(end 331.451204 -357.46309)
		(width 0.13462)
		(layer "F.Cu")
		(net "P5E_PEX2_STN6_TX_C_DP<102>")
	)
	(segment
		(start 331.451204 -357.46309)
		(end 331.156564 -357.75773)
		(width 0.13462)
		(layer "F.Cu")
		(net "P5E_PEX2_STN6_TX_C_DP<102>")
	)
	(segment
		(start 333.90586 -367.247424)
		(end 334.049116 -367.322608)
		(width 0.1651)
		(layer "In13.Cu")
		(net "P5E_PEX2_STN6_TX_C_DP<102>")
	)
	(segment
		(start 333.83347 -366.63122)
		(end 333.75854 -366.774222)
		(width 0.1651)
		(layer "In13.Cu")
		(net "P5E_PEX2_STN6_TX_C_DP<102>")
	)
	(segment
		(start 334.247236 -383.79908)
		(end 333.81696 -383.79908)
		(width 0.1651)
		(layer "In13.Cu")
		(net "P5E_PEX2_STN6_TX_C_DP<102>")
	)
	(segment
		(start 331.447394 -358.972866)
		(end 333.470758 -365.467138)
		(width 0.1651)
		(layer "In13.Cu")
		(net "P5E_PEX2_STN6_TX_C_DP<102>")
	)
	(segment
		(start 333.75854 -366.774222)
		(end 333.90586 -367.247424)
		(width 0.1651)
		(layer "In13.Cu")
		(net "P5E_PEX2_STN6_TX_C_DP<102>")
	)
	(segment
		(start 333.81696 -383.79908)
		(end 333.68996 -383.67208)
		(width 0.1651)
		(layer "In13.Cu")
		(net "P5E_PEX2_STN6_TX_C_DP<102>")
	)
	(segment
		(start 333.68996 -383.67208)
		(end 333.68996 -383.290064)
		(width 0.1651)
		(layer "In13.Cu")
		(net "P5E_PEX2_STN6_TX_C_DP<102>")
	)
	(segment
		(start 334.534002 -383.512314)
		(end 334.247236 -383.79908)
		(width 0.1651)
		(layer "In13.Cu")
		(net "P5E_PEX2_STN6_TX_C_DP<102>")
	)
	(segment
		(start 333.470758 -365.467138)
		(end 333.395574 -365.61014)
		(width 0.1651)
		(layer "In13.Cu")
		(net "P5E_PEX2_STN6_TX_C_DP<102>")
	)
	(segment
		(start 333.395574 -365.61014)
		(end 333.542894 -366.083342)
		(width 0.1651)
		(layer "In13.Cu")
		(net "P5E_PEX2_STN6_TX_C_DP<102>")
	)
	(segment
		(start 333.542894 -366.083342)
		(end 333.68615 -366.158526)
		(width 0.1651)
		(layer "In13.Cu")
		(net "P5E_PEX2_STN6_TX_C_DP<102>")
	)
	(segment
		(start 333.68615 -366.158526)
		(end 333.83347 -366.63122)
		(width 0.1651)
		(layer "In13.Cu")
		(net "P5E_PEX2_STN6_TX_C_DP<102>")
	)
	(segment
		(start 331.156564 -357.75773)
		(end 331.447394 -358.04856)
		(width 0.1651)
		(layer "In13.Cu")
		(net "P5E_PEX2_STN6_TX_C_DP<102>")
	)
	(segment
		(start 334.534002 -368.878866)
		(end 334.534002 -383.512314)
		(width 0.1651)
		(layer "In13.Cu")
		(net "P5E_PEX2_STN6_TX_C_DP<102>")
	)
	(segment
		(start 331.447394 -358.04856)
		(end 331.447394 -358.972866)
		(width 0.1651)
		(layer "In13.Cu")
		(net "P5E_PEX2_STN6_TX_C_DP<102>")
	)
	(segment
		(start 334.049116 -367.322608)
		(end 334.534002 -368.878866)
		(width 0.1651)
		(layer "In13.Cu")
		(net "P5E_PEX2_STN6_TX_C_DP<102>")
	)
	(segment
		(start 408.520138 -319.84188)
		(end 408.520138 -316.534292)
		(width 0.1143)
		(layer "In5.Cu")
		(net "P5E_PEX3_STN5_RX_DN<82>")
	)
	(segment
		(start 381.048006 -396.48638)
		(end 382.4224 -394.27912)
		(width 0.1651)
		(layer "In5.Cu")
		(net "P5E_PEX3_STN5_RX_DN<82>")
	)
	(segment
		(start 406.899618 -327.17994)
		(end 408.001216 -324.960234)
		(width 0.1651)
		(layer "In5.Cu")
		(net "P5E_PEX3_STN5_RX_DN<82>")
	)
	(segment
		(start 408.785568 -316.419992)
		(end 408.899868 -316.534292)
		(width 0.1143)
		(layer "In5.Cu")
		(net "P5E_PEX3_STN5_RX_DN<82>")
	)
	(segment
		(start 382.4224 -394.27912)
		(end 384.619754 -392.709146)
		(width 0.1651)
		(layer "In5.Cu")
		(net "P5E_PEX3_STN5_RX_DN<82>")
	)
	(segment
		(start 380.01702 -397.284956)
		(end 380.55042 -397.284956)
		(width 0.1651)
		(layer "In5.Cu")
		(net "P5E_PEX3_STN5_RX_DN<82>")
	)
	(segment
		(start 396.91564 -387.154674)
		(end 397.267938 -386.632196)
		(width 0.1651)
		(layer "In5.Cu")
		(net "P5E_PEX3_STN5_RX_DN<82>")
	)
	(segment
		(start 397.42999 -368.64163)
		(end 395.07795 -358.721152)
		(width 0.1651)
		(layer "In5.Cu")
		(net "P5E_PEX3_STN5_RX_DN<82>")
	)
	(segment
		(start 395.07795 -358.721152)
		(end 395.07795 -342.034114)
		(width 0.1651)
		(layer "In5.Cu")
		(net "P5E_PEX3_STN5_RX_DN<82>")
	)
	(segment
		(start 395.07795 -342.034114)
		(end 395.378686 -341.102442)
		(width 0.1651)
		(layer "In5.Cu")
		(net "P5E_PEX3_STN5_RX_DN<82>")
	)
	(segment
		(start 408.565858 -319.916048)
		(end 408.565858 -319.8876)
		(width 0.1143)
		(layer "In5.Cu")
		(net "P5E_PEX3_STN5_RX_DN<82>")
	)
	(segment
		(start 379.89002 -397.790162)
		(end 379.89002 -397.411956)
		(width 0.1651)
		(layer "In5.Cu")
		(net "P5E_PEX3_STN5_RX_DN<82>")
	)
	(segment
		(start 381.048006 -396.78737)
		(end 381.048006 -396.48638)
		(width 0.1651)
		(layer "In5.Cu")
		(net "P5E_PEX3_STN5_RX_DN<82>")
	)
	(segment
		(start 395.378686 -341.102442)
		(end 406.899618 -327.17994)
		(width 0.1651)
		(layer "In5.Cu")
		(net "P5E_PEX3_STN5_RX_DN<82>")
	)
	(segment
		(start 395.73708 -388.10438)
		(end 396.91564 -387.154674)
		(width 0.1651)
		(layer "In5.Cu")
		(net "P5E_PEX3_STN5_RX_DN<82>")
	)
	(segment
		(start 408.634438 -316.419992)
		(end 408.785568 -316.419992)
		(width 0.1143)
		(layer "In5.Cu")
		(net "P5E_PEX3_STN5_RX_DN<82>")
	)
	(segment
		(start 408.565858 -322.552314)
		(end 408.565858 -319.916048)
		(width 0.1651)
		(layer "In5.Cu")
		(net "P5E_PEX3_STN5_RX_DN<82>")
	)
	(segment
		(start 384.619754 -392.709146)
		(end 395.73708 -388.10438)
		(width 0.1651)
		(layer "In5.Cu")
		(net "P5E_PEX3_STN5_RX_DN<82>")
	)
	(segment
		(start 380.55042 -397.284956)
		(end 381.048006 -396.78737)
		(width 0.1651)
		(layer "In5.Cu")
		(net "P5E_PEX3_STN5_RX_DN<82>")
	)
	(segment
		(start 408.001216 -324.960234)
		(end 408.565858 -322.552314)
		(width 0.1651)
		(layer "In5.Cu")
		(net "P5E_PEX3_STN5_RX_DN<82>")
	)
	(segment
		(start 397.547592 -385.731512)
		(end 397.678148 -370.879624)
		(width 0.1651)
		(layer "In5.Cu")
		(net "P5E_PEX3_STN5_RX_DN<82>")
	)
	(segment
		(start 408.899868 -316.534292)
		(end 408.899868 -316.799722)
		(width 0.1143)
		(layer "In5.Cu")
		(net "P5E_PEX3_STN5_RX_DN<82>")
	)
	(segment
		(start 397.678148 -370.879624)
		(end 397.42999 -368.64163)
		(width 0.1651)
		(layer "In5.Cu")
		(net "P5E_PEX3_STN5_RX_DN<82>")
	)
	(segment
		(start 408.520138 -316.534292)
		(end 408.634438 -316.419992)
		(width 0.1143)
		(layer "In5.Cu")
		(net "P5E_PEX3_STN5_RX_DN<82>")
	)
	(segment
		(start 379.89002 -397.411956)
		(end 380.01702 -397.284956)
		(width 0.1651)
		(layer "In5.Cu")
		(net "P5E_PEX3_STN5_RX_DN<82>")
	)
	(segment
		(start 397.267938 -386.632196)
		(end 397.547592 -385.731512)
		(width 0.1651)
		(layer "In5.Cu")
		(net "P5E_PEX3_STN5_RX_DN<82>")
	)
	(segment
		(start 408.565858 -319.8876)
		(end 408.520138 -319.84188)
		(width 0.1143)
		(layer "In5.Cu")
		(net "P5E_PEX3_STN5_RX_DN<82>")
	)
	(segment
		(start 70.811136 -110.530132)
		(end 71.241412 -110.960408)
		(width 0.13208)
		(layer "F.Cu")
		(net "NIC1_BIF0_N")
	)
	(segment
		(start 71.241412 -112.235742)
		(end 72.04583 -113.04016)
		(width 0.13208)
		(layer "F.Cu")
		(net "NIC1_BIF0_N")
	)
	(segment
		(start 72.806306 -112.834928)
		(end 73.257664 -112.834928)
		(width 0.13208)
		(layer "F.Cu")
		(net "NIC1_BIF0_N")
	)
	(segment
		(start 71.241412 -110.960408)
		(end 71.241412 -112.235742)
		(width 0.13208)
		(layer "F.Cu")
		(net "NIC1_BIF0_N")
	)
	(segment
		(start 72.601074 -113.04016)
		(end 72.806306 -112.834928)
		(width 0.13208)
		(layer "F.Cu")
		(net "NIC1_BIF0_N")
	)
	(segment
		(start 72.04583 -113.04016)
		(end 72.601074 -113.04016)
		(width 0.13208)
		(layer "F.Cu")
		(net "NIC1_BIF0_N")
	)
	(via
		(at 70.811136 -110.530132)
		(size 0.508)
		(drill 0.254)
		(layers "F.Cu" "B.Cu")
		(net "NIC1_BIF0_N")
	)
	(segment
		(start 66.375534 -108.197142)
		(end 66.029586 -107.851194)
		(width 0.13208)
		(layer "B.Cu")
		(net "NIC1_BIF0_N")
	)
	(segment
		(start 63.119 -107.851194)
		(end 62.983364 -107.98683)
		(width 0.13208)
		(layer "B.Cu")
		(net "NIC1_BIF0_N")
	)
	(segment
		(start 62.000384 -108.462318)
		(end 61.997336 -108.465366)
		(width 0.13208)
		(layer "B.Cu")
		(net "NIC1_BIF0_N")
	)
	(segment
		(start 68.478146 -108.197142)
		(end 66.375534 -108.197142)
		(width 0.13208)
		(layer "B.Cu")
		(net "NIC1_BIF0_N")
	)
	(segment
		(start 70.811136 -110.530132)
		(end 68.478146 -108.197142)
		(width 0.13208)
		(layer "B.Cu")
		(net "NIC1_BIF0_N")
	)
	(segment
		(start 62.983364 -107.98683)
		(end 62.983364 -108.462318)
		(width 0.13208)
		(layer "B.Cu")
		(net "NIC1_BIF0_N")
	)
	(segment
		(start 62.983364 -108.462318)
		(end 62.000384 -108.462318)
		(width 0.13208)
		(layer "B.Cu")
		(net "NIC1_BIF0_N")
	)
	(segment
		(start 66.029586 -107.851194)
		(end 63.119 -107.851194)
		(width 0.13208)
		(layer "B.Cu")
		(net "NIC1_BIF0_N")
	)
	(segment
		(start 395.373352 -139.029186)
		(end 395.373352 -138.564112)
		(width 0.13208)
		(layer "F.Cu")
		(net "NIC6_AUX_PWR_EN_R")
	)
	(segment
		(start 394.837412 -139.565126)
		(end 395.373352 -139.029186)
		(width 0.13208)
		(layer "F.Cu")
		(net "NIC6_AUX_PWR_EN_R")
	)
	(segment
		(start 394.342366 -139.565126)
		(end 394.837412 -139.565126)
		(width 0.13208)
		(layer "F.Cu")
		(net "NIC6_AUX_PWR_EN_R")
	)
	(via
		(at 395.373352 -138.564112)
		(size 0.508)
		(drill 0.254)
		(layers "F.Cu" "B.Cu")
		(net "NIC6_AUX_PWR_EN_R")
	)
	(segment
		(start 401.38604 -137.668)
		(end 402.26488 -138.54684)
		(width 0.13208)
		(layer "B.Cu")
		(net "NIC6_AUX_PWR_EN_R")
	)
	(segment
		(start 395.373352 -138.564112)
		(end 395.790928 -138.564112)
		(width 0.13208)
		(layer "B.Cu")
		(net "NIC6_AUX_PWR_EN_R")
	)
	(segment
		(start 396.766034 -138.421618)
		(end 396.766034 -137.795)
		(width 0.13208)
		(layer "B.Cu")
		(net "NIC6_AUX_PWR_EN_R")
	)
	(segment
		(start 395.933422 -138.421618)
		(end 396.766034 -138.421618)
		(width 0.13208)
		(layer "B.Cu")
		(net "NIC6_AUX_PWR_EN_R")
	)
	(segment
		(start 395.790928 -138.564112)
		(end 395.933422 -138.421618)
		(width 0.13208)
		(layer "B.Cu")
		(net "NIC6_AUX_PWR_EN_R")
	)
	(segment
		(start 396.893034 -137.668)
		(end 401.38604 -137.668)
		(width 0.13208)
		(layer "B.Cu")
		(net "NIC6_AUX_PWR_EN_R")
	)
	(segment
		(start 402.26488 -138.54684)
		(end 402.26488 -140.181076)
		(width 0.13208)
		(layer "B.Cu")
		(net "NIC6_AUX_PWR_EN_R")
	)
	(segment
		(start 396.766034 -137.795)
		(end 396.893034 -137.668)
		(width 0.13208)
		(layer "B.Cu")
		(net "NIC6_AUX_PWR_EN_R")
	)
	(segment
		(start 330.336906 -8.641588)
		(end 331.976476 -8.641588)
		(width 0.381)
		(layer "F.Cu")
		(net "P3V3_SSD11")
	)
	(segment
		(start 331.95387 -27.492198)
		(end 331.432916 -26.971244)
		(width 0.381)
		(layer "F.Cu")
		(net "P3V3_SSD11")
	)
	(segment
		(start 332.956662 -10.145522)
		(end 332.956662 -9.535922)
		(width 0.508)
		(layer "F.Cu")
		(net "P3V3_SSD11")
	)
	(segment
		(start 329.671426 -25.742392)
		(end 329.671426 -26.360882)
		(width 0.4572)
		(layer "F.Cu")
		(net "P3V3_SSD11")
	)
	(segment
		(start 328.126344 -25.031954)
		(end 328.769726 -25.031954)
		(width 0.4572)
		(layer "F.Cu")
		(net "P3V3_SSD11")
	)
	(segment
		(start 329.63739 -8.577072)
		(end 330.27239 -8.577072)
		(width 0.381)
		(layer "F.Cu")
		(net "P3V3_SSD11")
	)
	(segment
		(start 303.046638 -37.47516)
		(end 302.341026 -37.47516)
		(width 0.4572)
		(layer "F.Cu")
		(net "P3V3_SSD11")
	)
	(segment
		(start 326.43318 -24.790146)
		(end 326.674988 -25.031954)
		(width 0.381)
		(layer "F.Cu")
		(net "P3V3_SSD11")
	)
	(segment
		(start 330.27239 -8.577072)
		(end 330.336906 -8.641588)
		(width 0.381)
		(layer "F.Cu")
		(net "P3V3_SSD11")
	)
	(segment
		(start 316.168532 -32.512762)
		(end 316.168532 -30.971236)
		(width 0.381)
		(layer "F.Cu")
		(net "P3V3_SSD11")
	)
	(segment
		(start 317.571628 -24.807418)
		(end 316.953138 -24.807418)
		(width 0.4572)
		(layer "F.Cu")
		(net "P3V3_SSD11")
	)
	(segment
		(start 332.085442 -27.492198)
		(end 331.95387 -27.492198)
		(width 0.381)
		(layer "F.Cu")
		(net "P3V3_SSD11")
	)
	(segment
		(start 318.37884 -59.978036)
		(end 318.37884 -60.633356)
		(width 0.381)
		(layer "F.Cu")
		(net "P3V3_SSD11")
	)
	(segment
		(start 326.674988 -25.031954)
		(end 328.126344 -25.031954)
		(width 0.381)
		(layer "F.Cu")
		(net "P3V3_SSD11")
	)
	(segment
		(start 325.464678 -24.790146)
		(end 326.43318 -24.790146)
		(width 0.381)
		(layer "F.Cu")
		(net "P3V3_SSD11")
	)
	(segment
		(start 315.893958 -32.787336)
		(end 316.168532 -32.512762)
		(width 0.381)
		(layer "F.Cu")
		(net "P3V3_SSD11")
	)
	(segment
		(start 336.004662 -9.53262)
		(end 336.004662 -10.145522)
		(width 0.508)
		(layer "F.Cu")
		(net "P3V3_SSD11")
	)
	(segment
		(start 316.168532 -30.971236)
		(end 315.593984 -30.396688)
		(width 0.381)
		(layer "F.Cu")
		(net "P3V3_SSD11")
	)
	(segment
		(start 315.893958 -34.248852)
		(end 315.893958 -32.787336)
		(width 0.381)
		(layer "F.Cu")
		(net "P3V3_SSD11")
	)
	(via
		(at 317.714376 -50.608992)
		(size 0.508)
		(drill 0.254)
		(layers "F.Cu" "B.Cu")
		(net "P3V3_SSD11")
	)
	(via
		(at 331.432916 -26.971244)
		(size 0.508)
		(drill 0.254)
		(layers "F.Cu" "B.Cu")
		(net "P3V3_SSD11")
	)
	(via
		(at 317.714376 -51.243992)
		(size 0.508)
		(drill 0.254)
		(layers "F.Cu" "B.Cu")
		(net "P3V3_SSD11")
	)
	(via
		(at 316.693804 -50.478182)
		(size 0.6604)
		(drill 0.3302)
		(layers "F.Cu" "B.Cu")
		(net "P3V3_SSD11")
	)
	(via
		(at 317.963804 -49.574704)
		(size 0.508)
		(drill 0.254)
		(layers "F.Cu" "B.Cu")
		(net "P3V3_SSD11")
	)
	(via
		(at 328.769726 -25.031954)
		(size 0.508)
		(drill 0.254)
		(layers "F.Cu" "B.Cu")
		(net "P3V3_SSD11")
	)
	(via
		(at 336.004662 -9.53262)
		(size 0.508)
		(drill 0.254)
		(layers "F.Cu" "B.Cu")
		(net "P3V3_SSD11")
	)
	(via
		(at 317.328804 -49.574704)
		(size 0.508)
		(drill 0.254)
		(layers "F.Cu" "B.Cu")
		(net "P3V3_SSD11")
	)
	(via
		(at 316.693804 -49.574704)
		(size 0.508)
		(drill 0.254)
		(layers "F.Cu" "B.Cu")
		(net "P3V3_SSD11")
	)
	(via
		(at 317.79972 -52.528724)
		(size 0.508)
		(drill 0.254)
		(layers "F.Cu" "B.Cu")
		(net "P3V3_SSD11")
	)
	(via
		(at 317.349378 -53.469286)
		(size 0.508)
		(drill 0.254)
		(layers "F.Cu" "B.Cu")
		(net "P3V3_SSD11")
	)
	(via
		(at 329.671426 -26.360882)
		(size 0.508)
		(drill 0.254)
		(layers "F.Cu" "B.Cu")
		(net "P3V3_SSD11")
	)
	(via
		(at 316.953138 -24.807418)
		(size 0.508)
		(drill 0.254)
		(layers "F.Cu" "B.Cu")
		(net "P3V3_SSD11")
	)
	(via
		(at 314.51042 -29.614876)
		(size 0.508)
		(drill 0.254)
		(layers "F.Cu" "B.Cu")
		(net "P3V3_SSD11")
	)
	(via
		(at 318.37884 -60.633356)
		(size 0.508)
		(drill 0.254)
		(layers "F.Cu" "B.Cu")
		(net "P3V3_SSD11")
	)
	(via
		(at 317.16472 -52.528724)
		(size 0.508)
		(drill 0.254)
		(layers "F.Cu" "B.Cu")
		(net "P3V3_SSD11")
	)
	(via
		(at 318.598804 -49.574704)
		(size 0.508)
		(drill 0.254)
		(layers "F.Cu" "B.Cu")
		(net "P3V3_SSD11")
	)
	(via
		(at 318.476376 -50.608992)
		(size 0.508)
		(drill 0.254)
		(layers "F.Cu" "B.Cu")
		(net "P3V3_SSD11")
	)
	(via
		(at 318.476376 -51.320192)
		(size 0.508)
		(drill 0.254)
		(layers "F.Cu" "B.Cu")
		(net "P3V3_SSD11")
	)
	(via
		(at 302.341026 -37.47516)
		(size 0.508)
		(drill 0.254)
		(layers "F.Cu" "B.Cu")
		(net "P3V3_SSD11")
	)
	(via
		(at 329.63739 -8.577072)
		(size 0.508)
		(drill 0.254)
		(layers "F.Cu" "B.Cu")
		(net "P3V3_SSD11")
	)
	(via
		(at 316.714378 -53.469286)
		(size 0.508)
		(drill 0.254)
		(layers "F.Cu" "B.Cu")
		(net "P3V3_SSD11")
	)
	(via
		(at 314.51042 -30.376876)
		(size 0.508)
		(drill 0.254)
		(layers "F.Cu" "B.Cu")
		(net "P3V3_SSD11")
	)
	(via
		(at 332.956662 -9.535922)
		(size 0.508)
		(drill 0.254)
		(layers "F.Cu" "B.Cu")
		(net "P3V3_SSD11")
	)
	(segment
		(start 305.253898 -37.872924)
		(end 304.804064 -38.322758)
		(width 0.508)
		(layer "In9.Cu")
		(net "P3V3_SSD11")
	)
	(segment
		(start 304.804064 -38.322758)
		(end 303.188624 -38.322758)
		(width 0.508)
		(layer "In9.Cu")
		(net "P3V3_SSD11")
	)
	(segment
		(start 303.188624 -38.322758)
		(end 302.341026 -37.47516)
		(width 0.508)
		(layer "In9.Cu")
		(net "P3V3_SSD11")
	)
	(segment
		(start 311.963562 -37.872924)
		(end 305.253898 -37.872924)
		(width 0.508)
		(layer "In9.Cu")
		(net "P3V3_SSD11")
	)
	(segment
		(start 45.554392 -110.245144)
		(end 46.042326 -110.245144)
		(width 0.13462)
		(layer "F.Cu")
		(net "P5E_PEX0_STN1_TX_C_DP<22>")
	)
	(segment
		(start 39.547292 -110.088934)
		(end 39.866316 -110.407958)
		(width 0.13462)
		(layer "F.Cu")
		(net "P5E_PEX0_STN1_TX_C_DP<22>")
	)
	(segment
		(start 39.866316 -110.407958)
		(end 45.391578 -110.407958)
		(width 0.13462)
		(layer "F.Cu")
		(net "P5E_PEX0_STN1_TX_C_DP<22>")
	)
	(segment
		(start 45.391578 -110.407958)
		(end 45.554392 -110.245144)
		(width 0.13462)
		(layer "F.Cu")
		(net "P5E_PEX0_STN1_TX_C_DP<22>")
	)
	(segment
		(start 56.20766 -325.34479)
		(end 55.515764 -323.674994)
		(width 0.1651)
		(layer "In9.Cu")
		(net "P5E_PEX0_STN6_RX_DN<98>")
	)
	(segment
		(start 55.470044 -319.819528)
		(end 55.470044 -318.485266)
		(width 0.1143)
		(layer "In9.Cu")
		(net "P5E_PEX0_STN6_RX_DN<98>")
	)
	(segment
		(start 55.515764 -323.674994)
		(end 55.515764 -319.893696)
		(width 0.1651)
		(layer "In9.Cu")
		(net "P5E_PEX0_STN6_RX_DN<98>")
	)
	(segment
		(start 65.039748 -335.0895)
		(end 56.20766 -325.34479)
		(width 0.1651)
		(layer "In9.Cu")
		(net "P5E_PEX0_STN6_RX_DN<98>")
	)
	(segment
		(start 55.635144 -318.320166)
		(end 55.760874 -318.320166)
		(width 0.1143)
		(layer "In9.Cu")
		(net "P5E_PEX0_STN6_RX_DN<98>")
	)
	(segment
		(start 83.370674 -367.814352)
		(end 70.70725 -359.35285)
		(width 0.1651)
		(layer "In9.Cu")
		(net "P5E_PEX0_STN6_RX_DN<98>")
	)
	(segment
		(start 84.08416 -375.794778)
		(end 84.08416 -369.536472)
		(width 0.1651)
		(layer "In9.Cu")
		(net "P5E_PEX0_STN6_RX_DN<98>")
	)
	(segment
		(start 67.0306 -337.515454)
		(end 65.039748 -335.0895)
		(width 0.1651)
		(layer "In9.Cu")
		(net "P5E_PEX0_STN6_RX_DN<98>")
	)
	(segment
		(start 82.909918 -376.790204)
		(end 82.909918 -376.408188)
		(width 0.1651)
		(layer "In9.Cu")
		(net "P5E_PEX0_STN6_RX_DN<98>")
	)
	(segment
		(start 55.515764 -319.893696)
		(end 55.515764 -319.865248)
		(width 0.1143)
		(layer "In9.Cu")
		(net "P5E_PEX0_STN6_RX_DN<98>")
	)
	(segment
		(start 70.011544 -358.657144)
		(end 69.717412 -357.94696)
		(width 0.1651)
		(layer "In9.Cu")
		(net "P5E_PEX0_STN6_RX_DN<98>")
	)
	(segment
		(start 55.515764 -319.865248)
		(end 55.470044 -319.819528)
		(width 0.1143)
		(layer "In9.Cu")
		(net "P5E_PEX0_STN6_RX_DN<98>")
	)
	(segment
		(start 69.541644 -341.273384)
		(end 67.0306 -337.515454)
		(width 0.1651)
		(layer "In9.Cu")
		(net "P5E_PEX0_STN6_RX_DN<98>")
	)
	(segment
		(start 55.849774 -318.409066)
		(end 55.849774 -318.699896)
		(width 0.1143)
		(layer "In9.Cu")
		(net "P5E_PEX0_STN6_RX_DN<98>")
	)
	(segment
		(start 69.717412 -357.94696)
		(end 69.717412 -341.852504)
		(width 0.1651)
		(layer "In9.Cu")
		(net "P5E_PEX0_STN6_RX_DN<98>")
	)
	(segment
		(start 55.470044 -318.485266)
		(end 55.635144 -318.320166)
		(width 0.1143)
		(layer "In9.Cu")
		(net "P5E_PEX0_STN6_RX_DN<98>")
	)
	(segment
		(start 84.08416 -369.536472)
		(end 83.370674 -367.814352)
		(width 0.1651)
		(layer "In9.Cu")
		(net "P5E_PEX0_STN6_RX_DN<98>")
	)
	(segment
		(start 82.909918 -376.408188)
		(end 83.036918 -376.281188)
		(width 0.1651)
		(layer "In9.Cu")
		(net "P5E_PEX0_STN6_RX_DN<98>")
	)
	(segment
		(start 55.760874 -318.320166)
		(end 55.849774 -318.409066)
		(width 0.1143)
		(layer "In9.Cu")
		(net "P5E_PEX0_STN6_RX_DN<98>")
	)
	(segment
		(start 70.70725 -359.35285)
		(end 70.011544 -358.657144)
		(width 0.1651)
		(layer "In9.Cu")
		(net "P5E_PEX0_STN6_RX_DN<98>")
	)
	(segment
		(start 83.59775 -376.281188)
		(end 84.08416 -375.794778)
		(width 0.1651)
		(layer "In9.Cu")
		(net "P5E_PEX0_STN6_RX_DN<98>")
	)
	(segment
		(start 83.036918 -376.281188)
		(end 83.59775 -376.281188)
		(width 0.1651)
		(layer "In9.Cu")
		(net "P5E_PEX0_STN6_RX_DN<98>")
	)
	(segment
		(start 69.717412 -341.852504)
		(end 69.541644 -341.273384)
		(width 0.1651)
		(layer "In9.Cu")
		(net "P5E_PEX0_STN6_RX_DN<98>")
	)
	(segment
		(start 325.971662 -33.790128)
		(end 325.464678 -33.790128)
		(width 0.13462)
		(layer "F.Cu")
		(net "P5E_PEX2_STN2_TX_C_DN<35>")
	)
	(segment
		(start 330.36764 -33.631886)
		(end 330.047346 -33.95218)
		(width 0.13462)
		(layer "F.Cu")
		(net "P5E_PEX2_STN2_TX_C_DN<35>")
	)
	(segment
		(start 326.133714 -33.95218)
		(end 325.971662 -33.790128)
		(width 0.13462)
		(layer "F.Cu")
		(net "P5E_PEX2_STN2_TX_C_DN<35>")
	)
	(segment
		(start 330.047346 -33.95218)
		(end 326.133714 -33.95218)
		(width 0.13462)
		(layer "F.Cu")
		(net "P5E_PEX2_STN2_TX_C_DN<35>")
	)
	(segment
		(start 298.371768 -330.310998)
		(end 297.908472 -330.134468)
		(width 0.1651)
		(layer "In9.Cu")
		(net "P5E_PEX2_STN6_RX_DN<97>")
	)
	(segment
		(start 291.968936 -326.980296)
		(end 288.79292 -323.804026)
		(width 0.1651)
		(layer "In9.Cu")
		(net "P5E_PEX2_STN6_RX_DN<97>")
	)
	(segment
		(start 288.99993 -316.508892)
		(end 288.99993 -316.799722)
		(width 0.1143)
		(layer "In9.Cu")
		(net "P5E_PEX2_STN6_RX_DN<97>")
	)
	(segment
		(start 345.544902 -368.449606)
		(end 341.370412 -365.543846)
		(width 0.1651)
		(layer "In9.Cu")
		(net "P5E_PEX2_STN6_RX_DN<97>")
	)
	(segment
		(start 288.91103 -316.419992)
		(end 288.99993 -316.508892)
		(width 0.1143)
		(layer "In9.Cu")
		(net "P5E_PEX2_STN6_RX_DN<97>")
	)
	(segment
		(start 327.065894 -342.24976)
		(end 326.555354 -341.126572)
		(width 0.1651)
		(layer "In9.Cu")
		(net "P5E_PEX2_STN6_RX_DN<97>")
	)
	(segment
		(start 326.555354 -341.126572)
		(end 298.41571 -330.409296)
		(width 0.1651)
		(layer "In9.Cu")
		(net "P5E_PEX2_STN6_RX_DN<97>")
	)
	(segment
		(start 288.66592 -323.497702)
		(end 288.66592 -319.916048)
		(width 0.1651)
		(layer "In9.Cu")
		(net "P5E_PEX2_STN6_RX_DN<97>")
	)
	(segment
		(start 288.734246 -316.419992)
		(end 288.91103 -316.419992)
		(width 0.1143)
		(layer "In9.Cu")
		(net "P5E_PEX2_STN6_RX_DN<97>")
	)
	(segment
		(start 298.41571 -330.409296)
		(end 298.371768 -330.310998)
		(width 0.1651)
		(layer "In9.Cu")
		(net "P5E_PEX2_STN6_RX_DN<97>")
	)
	(segment
		(start 288.6202 -316.534038)
		(end 288.734246 -316.419992)
		(width 0.1143)
		(layer "In9.Cu")
		(net "P5E_PEX2_STN6_RX_DN<97>")
	)
	(segment
		(start 288.66592 -319.916048)
		(end 288.66592 -319.8876)
		(width 0.1143)
		(layer "In9.Cu")
		(net "P5E_PEX2_STN6_RX_DN<97>")
	)
	(segment
		(start 295.619424 -329.344274)
		(end 291.968936 -326.980296)
		(width 0.1651)
		(layer "In9.Cu")
		(net "P5E_PEX2_STN6_RX_DN<97>")
	)
	(segment
		(start 288.6202 -319.84188)
		(end 288.6202 -316.534038)
		(width 0.1143)
		(layer "In9.Cu")
		(net "P5E_PEX2_STN6_RX_DN<97>")
	)
	(segment
		(start 345.81592 -368.96802)
		(end 345.544902 -368.449606)
		(width 0.1651)
		(layer "In9.Cu")
		(net "P5E_PEX2_STN6_RX_DN<97>")
	)
	(segment
		(start 327.390506 -358.800146)
		(end 327.065894 -358.475534)
		(width 0.1651)
		(layer "In9.Cu")
		(net "P5E_PEX2_STN6_RX_DN<97>")
	)
	(segment
		(start 341.370412 -365.5441)
		(end 339.563964 -364.286546)
		(width 0.1651)
		(layer "In9.Cu")
		(net "P5E_PEX2_STN6_RX_DN<97>")
	)
	(segment
		(start 297.810174 -330.178664)
		(end 295.619424 -329.344274)
		(width 0.1651)
		(layer "In9.Cu")
		(net "P5E_PEX2_STN6_RX_DN<97>")
	)
	(segment
		(start 288.66592 -319.8876)
		(end 288.6202 -319.84188)
		(width 0.1143)
		(layer "In9.Cu")
		(net "P5E_PEX2_STN6_RX_DN<97>")
	)
	(segment
		(start 344.816938 -375.181114)
		(end 345.364054 -375.181114)
		(width 0.1651)
		(layer "In9.Cu")
		(net "P5E_PEX2_STN6_RX_DN<97>")
	)
	(segment
		(start 339.563964 -364.286546)
		(end 327.390506 -358.800146)
		(width 0.1651)
		(layer "In9.Cu")
		(net "P5E_PEX2_STN6_RX_DN<97>")
	)
	(segment
		(start 344.689938 -375.69013)
		(end 344.689938 -375.308114)
		(width 0.1651)
		(layer "In9.Cu")
		(net "P5E_PEX2_STN6_RX_DN<97>")
	)
	(segment
		(start 327.065894 -358.475534)
		(end 327.065894 -342.24976)
		(width 0.1651)
		(layer "In9.Cu")
		(net "P5E_PEX2_STN6_RX_DN<97>")
	)
	(segment
		(start 345.81592 -374.729248)
		(end 345.81592 -368.96802)
		(width 0.1651)
		(layer "In9.Cu")
		(net "P5E_PEX2_STN6_RX_DN<97>")
	)
	(segment
		(start 297.908472 -330.134468)
		(end 297.810174 -330.178664)
		(width 0.1651)
		(layer "In9.Cu")
		(net "P5E_PEX2_STN6_RX_DN<97>")
	)
	(segment
		(start 341.370412 -365.543846)
		(end 341.370412 -365.5441)
		(width 0.1651)
		(layer "In9.Cu")
		(net "P5E_PEX2_STN6_RX_DN<97>")
	)
	(segment
		(start 345.364054 -375.181114)
		(end 345.81592 -374.729248)
		(width 0.1651)
		(layer "In9.Cu")
		(net "P5E_PEX2_STN6_RX_DN<97>")
	)
	(segment
		(start 344.689938 -375.308114)
		(end 344.816938 -375.181114)
		(width 0.1651)
		(layer "In9.Cu")
		(net "P5E_PEX2_STN6_RX_DN<97>")
	)
	(segment
		(start 288.79292 -323.804026)
		(end 288.66592 -323.497702)
		(width 0.1651)
		(layer "In9.Cu")
		(net "P5E_PEX2_STN6_RX_DN<97>")
	)
	(segment
		(start 402.25218 -350.365314)
		(end 402.572728 -350.685862)
		(width 0.13462)
		(layer "F.Cu")
		(net "P5E_PEX3_STN5_TX_C_DP<87>")
	)
	(segment
		(start 402.572728 -350.685862)
		(end 402.572728 -351.31629)
		(width 0.13462)
		(layer "F.Cu")
		(net "P5E_PEX3_STN5_TX_C_DP<87>")
	)
	(segment
		(start 402.572728 -351.31629)
		(end 402.27758 -351.611438)
		(width 0.13462)
		(layer "F.Cu")
		(net "P5E_PEX3_STN5_TX_C_DP<87>")
	)
	(segment
		(start 402.180298 -369.099846)
		(end 401.494752 -363.058202)
		(width 0.1651)
		(layer "In7.Cu")
		(net "P5E_PEX3_STN5_TX_C_DP<87>")
	)
	(segment
		(start 390.889998 -405.390096)
		(end 390.889998 -405.772112)
		(width 0.1651)
		(layer "In7.Cu")
		(net "P5E_PEX3_STN5_TX_C_DP<87>")
	)
	(segment
		(start 401.494752 -363.058202)
		(end 401.3962 -362.97997)
		(width 0.1651)
		(layer "In7.Cu")
		(net "P5E_PEX3_STN5_TX_C_DP<87>")
	)
	(segment
		(start 400.08429 -391.15238)
		(end 402.091144 -387.698742)
		(width 0.1651)
		(layer "In7.Cu")
		(net "P5E_PEX3_STN5_TX_C_DP<87>")
	)
	(segment
		(start 391.73404 -405.612346)
		(end 391.73404 -395.010386)
		(width 0.1651)
		(layer "In7.Cu")
		(net "P5E_PEX3_STN5_TX_C_DP<87>")
	)
	(segment
		(start 391.447274 -405.899112)
		(end 391.73404 -405.612346)
		(width 0.1651)
		(layer "In7.Cu")
		(net "P5E_PEX3_STN5_TX_C_DP<87>")
	)
	(segment
		(start 390.889998 -405.772112)
		(end 391.016998 -405.899112)
		(width 0.1651)
		(layer "In7.Cu")
		(net "P5E_PEX3_STN5_TX_C_DP<87>")
	)
	(segment
		(start 401.362926 -361.897168)
		(end 401.264374 -361.818936)
		(width 0.1651)
		(layer "In7.Cu")
		(net "P5E_PEX3_STN5_TX_C_DP<87>")
	)
	(segment
		(start 402.56841 -352.40595)
		(end 402.56841 -351.902268)
		(width 0.1651)
		(layer "In7.Cu")
		(net "P5E_PEX3_STN5_TX_C_DP<87>")
	)
	(segment
		(start 401.286726 -361.228132)
		(end 401.01393 -358.824022)
		(width 0.1651)
		(layer "In7.Cu")
		(net "P5E_PEX3_STN5_TX_C_DP<87>")
	)
	(segment
		(start 401.01393 -353.96043)
		(end 402.56841 -352.40595)
		(width 0.1651)
		(layer "In7.Cu")
		(net "P5E_PEX3_STN5_TX_C_DP<87>")
	)
	(segment
		(start 402.56841 -351.902268)
		(end 402.27758 -351.611438)
		(width 0.1651)
		(layer "In7.Cu")
		(net "P5E_PEX3_STN5_TX_C_DP<87>")
	)
	(segment
		(start 401.264374 -361.818936)
		(end 401.208494 -361.32643)
		(width 0.1651)
		(layer "In7.Cu")
		(net "P5E_PEX3_STN5_TX_C_DP<87>")
	)
	(segment
		(start 391.016998 -405.899112)
		(end 391.447274 -405.899112)
		(width 0.1651)
		(layer "In7.Cu")
		(net "P5E_PEX3_STN5_TX_C_DP<87>")
	)
	(segment
		(start 402.091144 -387.698742)
		(end 402.180298 -369.099846)
		(width 0.1651)
		(layer "In7.Cu")
		(net "P5E_PEX3_STN5_TX_C_DP<87>")
	)
	(segment
		(start 392.364976 -394.421106)
		(end 392.419332 -394.422884)
		(width 0.1651)
		(layer "In7.Cu")
		(net "P5E_PEX3_STN5_TX_C_DP<87>")
	)
	(segment
		(start 391.73404 -395.010386)
		(end 392.364976 -394.421106)
		(width 0.1651)
		(layer "In7.Cu")
		(net "P5E_PEX3_STN5_TX_C_DP<87>")
	)
	(segment
		(start 401.208494 -361.32643)
		(end 401.286726 -361.228132)
		(width 0.1651)
		(layer "In7.Cu")
		(net "P5E_PEX3_STN5_TX_C_DP<87>")
	)
	(segment
		(start 401.418552 -362.389166)
		(end 401.362926 -361.897168)
		(width 0.1651)
		(layer "In7.Cu")
		(net "P5E_PEX3_STN5_TX_C_DP<87>")
	)
	(segment
		(start 401.34032 -362.487464)
		(end 401.418552 -362.389166)
		(width 0.1651)
		(layer "In7.Cu")
		(net "P5E_PEX3_STN5_TX_C_DP<87>")
	)
	(segment
		(start 392.419332 -394.422884)
		(end 400.08429 -391.15238)
		(width 0.1651)
		(layer "In7.Cu")
		(net "P5E_PEX3_STN5_TX_C_DP<87>")
	)
	(segment
		(start 401.01393 -358.824022)
		(end 401.01393 -353.96043)
		(width 0.1651)
		(layer "In7.Cu")
		(net "P5E_PEX3_STN5_TX_C_DP<87>")
	)
	(segment
		(start 401.3962 -362.97997)
		(end 401.34032 -362.487464)
		(width 0.1651)
		(layer "In7.Cu")
		(net "P5E_PEX3_STN5_TX_C_DP<87>")
	)
	(segment
		(start 71.975472 -113.834672)
		(end 71.130414 -112.989614)
		(width 0.13208)
		(layer "F.Cu")
		(net "NIC1_BIF2_N")
	)
	(segment
		(start 72.990202 -114.035078)
		(end 72.506332 -113.834672)
		(width 0.13208)
		(layer "F.Cu")
		(net "NIC1_BIF2_N")
	)
	(segment
		(start 73.257664 -114.035078)
		(end 72.990202 -114.035078)
		(width 0.13208)
		(layer "F.Cu")
		(net "NIC1_BIF2_N")
	)
	(segment
		(start 71.130414 -112.989614)
		(end 70.822058 -112.989614)
		(width 0.13208)
		(layer "F.Cu")
		(net "NIC1_BIF2_N")
	)
	(segment
		(start 72.506332 -113.834672)
		(end 71.975472 -113.834672)
		(width 0.13208)
		(layer "F.Cu")
		(net "NIC1_BIF2_N")
	)
	(via
		(at 65.531746 -109.982762)
		(size 0.6604)
		(drill 0.3302)
		(layers "F.Cu" "B.Cu")
		(net "NIC1_BIF2_N")
	)
	(via
		(at 70.822058 -112.989614)
		(size 0.508)
		(drill 0.254)
		(layers "F.Cu" "B.Cu")
		(net "NIC1_BIF2_N")
	)
	(segment
		(start 65.978278 -109.982762)
		(end 65.531746 -109.982762)
		(width 0.13208)
		(layer "B.Cu")
		(net "NIC1_BIF2_N")
	)
	(segment
		(start 61.997336 -110.497366)
		(end 62.975236 -110.497366)
		(width 0.13208)
		(layer "B.Cu")
		(net "NIC1_BIF2_N")
	)
	(segment
		(start 65.531746 -109.982762)
		(end 63.191644 -109.982762)
		(width 0.13208)
		(layer "B.Cu")
		(net "NIC1_BIF2_N")
	)
	(segment
		(start 67.191128 -108.769912)
		(end 65.978278 -109.982762)
		(width 0.13208)
		(layer "B.Cu")
		(net "NIC1_BIF2_N")
	)
	(segment
		(start 63.191644 -109.982762)
		(end 62.975236 -110.19917)
		(width 0.13208)
		(layer "B.Cu")
		(net "NIC1_BIF2_N")
	)
	(segment
		(start 70.240144 -112.105948)
		(end 68.563998 -110.429802)
		(width 0.13208)
		(layer "B.Cu")
		(net "NIC1_BIF2_N")
	)
	(segment
		(start 68.563998 -109.219492)
		(end 68.114418 -108.769912)
		(width 0.13208)
		(layer "B.Cu")
		(net "NIC1_BIF2_N")
	)
	(segment
		(start 68.563998 -110.429802)
		(end 68.563998 -109.219492)
		(width 0.13208)
		(layer "B.Cu")
		(net "NIC1_BIF2_N")
	)
	(segment
		(start 62.975236 -110.19917)
		(end 62.975236 -110.497366)
		(width 0.13208)
		(layer "B.Cu")
		(net "NIC1_BIF2_N")
	)
	(segment
		(start 70.822058 -112.989614)
		(end 70.453758 -112.621314)
		(width 0.13208)
		(layer "B.Cu")
		(net "NIC1_BIF2_N")
	)
	(segment
		(start 70.453758 -112.621314)
		(end 70.240144 -112.105948)
		(width 0.13208)
		(layer "B.Cu")
		(net "NIC1_BIF2_N")
	)
	(segment
		(start 68.114418 -108.769912)
		(end 67.191128 -108.769912)
		(width 0.13208)
		(layer "B.Cu")
		(net "NIC1_BIF2_N")
	)
	(segment
		(start 52.24272 -125.486414)
		(end 51.948588 -125.192282)
		(width 0.13462)
		(layer "F.Cu")
		(net "P5E_PEX0_STN1_RX_DN<27>")
	)
	(segment
		(start 51.130454 -125.355096)
		(end 50.64252 -125.355096)
		(width 0.13462)
		(layer "F.Cu")
		(net "P5E_PEX0_STN1_RX_DN<27>")
	)
	(segment
		(start 51.293268 -125.192282)
		(end 51.130454 -125.355096)
		(width 0.13462)
		(layer "F.Cu")
		(net "P5E_PEX0_STN1_RX_DN<27>")
	)
	(segment
		(start 51.948588 -125.192282)
		(end 51.293268 -125.192282)
		(width 0.13462)
		(layer "F.Cu")
		(net "P5E_PEX0_STN1_RX_DN<27>")
	)
	(segment
		(start 46.289214 -138.311636)
		(end 46.145196 -138.785346)
		(width 0.1651)
		(layer "In5.Cu")
		(net "P5E_PEX0_STN1_RX_DN<27>")
	)
	(segment
		(start 47.73676 -134.183374)
		(end 47.79137 -134.33552)
		(width 0.1651)
		(layer "In5.Cu")
		(net "P5E_PEX0_STN1_RX_DN<27>")
	)
	(segment
		(start 69.765672 -271.802352)
		(end 69.719952 -271.848072)
		(width 0.1143)
		(layer "In5.Cu")
		(net "P5E_PEX0_STN1_RX_DN<27>")
	)
	(segment
		(start 42.234104 -144.095978)
		(end 40.325294 -146.657822)
		(width 0.1651)
		(layer "In5.Cu")
		(net "P5E_PEX0_STN1_RX_DN<27>")
	)
	(segment
		(start 69.765672 -267.748512)
		(end 69.765672 -271.773904)
		(width 0.1651)
		(layer "In5.Cu")
		(net "P5E_PEX0_STN1_RX_DN<27>")
	)
	(segment
		(start 51.625754 -125.195584)
		(end 51.208432 -125.612906)
		(width 0.1651)
		(layer "In5.Cu")
		(net "P5E_PEX0_STN1_RX_DN<27>")
	)
	(segment
		(start 70.099428 -275.265388)
		(end 70.099428 -274.999958)
		(width 0.1143)
		(layer "In5.Cu")
		(net "P5E_PEX0_STN1_RX_DN<27>")
	)
	(segment
		(start 49.509426 -131.294378)
		(end 49.231804 -131.705096)
		(width 0.1651)
		(layer "In5.Cu")
		(net "P5E_PEX0_STN1_RX_DN<27>")
	)
	(segment
		(start 48.256444 -133.080252)
		(end 48.311054 -133.232144)
		(width 0.1651)
		(layer "In5.Cu")
		(net "P5E_PEX0_STN1_RX_DN<27>")
	)
	(segment
		(start 49.073054 -131.73583)
		(end 48.467264 -132.632196)
		(width 0.1651)
		(layer "In5.Cu")
		(net "P5E_PEX0_STN1_RX_DN<27>")
	)
	(segment
		(start 45.440092 -141.106652)
		(end 43.195494 -143.147034)
		(width 0.1651)
		(layer "In5.Cu")
		(net "P5E_PEX0_STN1_RX_DN<27>")
	)
	(segment
		(start 50.303176 -129.415032)
		(end 49.755806 -130.725418)
		(width 0.1651)
		(layer "In5.Cu")
		(net "P5E_PEX0_STN1_RX_DN<27>")
	)
	(segment
		(start 41.458896 -161.3535)
		(end 69.765672 -267.748512)
		(width 0.1651)
		(layer "In5.Cu")
		(net "P5E_PEX0_STN1_RX_DN<27>")
	)
	(segment
		(start 47.94758 -133.735318)
		(end 47.73676 -134.183374)
		(width 0.1651)
		(layer "In5.Cu")
		(net "P5E_PEX0_STN1_RX_DN<27>")
	)
	(segment
		(start 45.867066 -140.094716)
		(end 45.723048 -140.56868)
		(width 0.1651)
		(layer "In5.Cu")
		(net "P5E_PEX0_STN1_RX_DN<27>")
	)
	(segment
		(start 47.79137 -134.33552)
		(end 47.580296 -134.78383)
		(width 0.1651)
		(layer "In5.Cu")
		(net "P5E_PEX0_STN1_RX_DN<27>")
	)
	(segment
		(start 46.575726 -137.761472)
		(end 46.431962 -138.235436)
		(width 0.1651)
		(layer "In5.Cu")
		(net "P5E_PEX0_STN1_RX_DN<27>")
	)
	(segment
		(start 46.930564 -136.594596)
		(end 46.786546 -137.068814)
		(width 0.1651)
		(layer "In5.Cu")
		(net "P5E_PEX0_STN1_RX_DN<27>")
	)
	(segment
		(start 50.453036 -129.353564)
		(end 50.303176 -129.415032)
		(width 0.1651)
		(layer "In5.Cu")
		(net "P5E_PEX0_STN1_RX_DN<27>")
	)
	(segment
		(start 69.985128 -275.379688)
		(end 70.099428 -275.265388)
		(width 0.1143)
		(layer "In5.Cu")
		(net "P5E_PEX0_STN1_RX_DN<27>")
	)
	(segment
		(start 51.208432 -125.612906)
		(end 50.77333 -126.66345)
		(width 0.1651)
		(layer "In5.Cu")
		(net "P5E_PEX0_STN1_RX_DN<27>")
	)
	(segment
		(start 49.478692 -131.135628)
		(end 49.509426 -131.294378)
		(width 0.1651)
		(layer "In5.Cu")
		(net "P5E_PEX0_STN1_RX_DN<27>")
	)
	(segment
		(start 50.77333 -126.66345)
		(end 50.77333 -128.289812)
		(width 0.1651)
		(layer "In5.Cu")
		(net "P5E_PEX0_STN1_RX_DN<27>")
	)
	(segment
		(start 45.934376 -139.478258)
		(end 45.934884 -139.478258)
		(width 0.1651)
		(layer "In5.Cu")
		(net "P5E_PEX0_STN1_RX_DN<27>")
	)
	(segment
		(start 48.099726 -133.680708)
		(end 47.94758 -133.735318)
		(width 0.1651)
		(layer "In5.Cu")
		(net "P5E_PEX0_STN1_RX_DN<27>")
	)
	(segment
		(start 46.28896 -138.311636)
		(end 46.289214 -138.311636)
		(width 0.1651)
		(layer "In5.Cu")
		(net "P5E_PEX0_STN1_RX_DN<27>")
	)
	(segment
		(start 50.582576 -128.746758)
		(end 50.644044 -128.89611)
		(width 0.1651)
		(layer "In5.Cu")
		(net "P5E_PEX0_STN1_RX_DN<27>")
	)
	(segment
		(start 48.467264 -132.632196)
		(end 48.256444 -133.080252)
		(width 0.1651)
		(layer "In5.Cu")
		(net "P5E_PEX0_STN1_RX_DN<27>")
	)
	(segment
		(start 50.644044 -128.89611)
		(end 50.453036 -129.353564)
		(width 0.1651)
		(layer "In5.Cu")
		(net "P5E_PEX0_STN1_RX_DN<27>")
	)
	(segment
		(start 40.325294 -146.657822)
		(end 40.080692 -147.588986)
		(width 0.1651)
		(layer "In5.Cu")
		(net "P5E_PEX0_STN1_RX_DN<27>")
	)
	(segment
		(start 47.580296 -134.78383)
		(end 47.42815 -134.83844)
		(width 0.1651)
		(layer "In5.Cu")
		(net "P5E_PEX0_STN1_RX_DN<27>")
	)
	(segment
		(start 46.431962 -138.235436)
		(end 46.28896 -138.311636)
		(width 0.1651)
		(layer "In5.Cu")
		(net "P5E_PEX0_STN1_RX_DN<27>")
	)
	(segment
		(start 49.755806 -130.725418)
		(end 49.478692 -131.135628)
		(width 0.1651)
		(layer "In5.Cu")
		(net "P5E_PEX0_STN1_RX_DN<27>")
	)
	(segment
		(start 45.934884 -139.478258)
		(end 45.790866 -139.951968)
		(width 0.1651)
		(layer "In5.Cu")
		(net "P5E_PEX0_STN1_RX_DN<27>")
	)
	(segment
		(start 46.221396 -138.928094)
		(end 46.077378 -139.402312)
		(width 0.1651)
		(layer "In5.Cu")
		(net "P5E_PEX0_STN1_RX_DN<27>")
	)
	(segment
		(start 46.854364 -136.452102)
		(end 46.930564 -136.594596)
		(width 0.1651)
		(layer "In5.Cu")
		(net "P5E_PEX0_STN1_RX_DN<27>")
	)
	(segment
		(start 52.24272 -125.486414)
		(end 51.95189 -125.195584)
		(width 0.1651)
		(layer "In5.Cu")
		(net "P5E_PEX0_STN1_RX_DN<27>")
	)
	(segment
		(start 40.688768 -157.00756)
		(end 41.458896 -161.3535)
		(width 0.1651)
		(layer "In5.Cu")
		(net "P5E_PEX0_STN1_RX_DN<27>")
	)
	(segment
		(start 50.77333 -128.289812)
		(end 50.582576 -128.746758)
		(width 0.1651)
		(layer "In5.Cu")
		(net "P5E_PEX0_STN1_RX_DN<27>")
	)
	(segment
		(start 43.195494 -143.147034)
		(end 42.234104 -144.095978)
		(width 0.1651)
		(layer "In5.Cu")
		(net "P5E_PEX0_STN1_RX_DN<27>")
	)
	(segment
		(start 69.719952 -275.27631)
		(end 69.82333 -275.379688)
		(width 0.1143)
		(layer "In5.Cu")
		(net "P5E_PEX0_STN1_RX_DN<27>")
	)
	(segment
		(start 49.231804 -131.705096)
		(end 49.073054 -131.73583)
		(width 0.1651)
		(layer "In5.Cu")
		(net "P5E_PEX0_STN1_RX_DN<27>")
	)
	(segment
		(start 69.719952 -271.848072)
		(end 69.719952 -275.27631)
		(width 0.1143)
		(layer "In5.Cu")
		(net "P5E_PEX0_STN1_RX_DN<27>")
	)
	(segment
		(start 45.790866 -139.951968)
		(end 45.867066 -140.094716)
		(width 0.1651)
		(layer "In5.Cu")
		(net "P5E_PEX0_STN1_RX_DN<27>")
	)
	(segment
		(start 45.5803 -140.64488)
		(end 45.440092 -141.106652)
		(width 0.1651)
		(layer "In5.Cu")
		(net "P5E_PEX0_STN1_RX_DN<27>")
	)
	(segment
		(start 46.643544 -137.145014)
		(end 46.49978 -137.618724)
		(width 0.1651)
		(layer "In5.Cu")
		(net "P5E_PEX0_STN1_RX_DN<27>")
	)
	(segment
		(start 46.077378 -139.402312)
		(end 45.934376 -139.478258)
		(width 0.1651)
		(layer "In5.Cu")
		(net "P5E_PEX0_STN1_RX_DN<27>")
	)
	(segment
		(start 69.765672 -271.773904)
		(end 69.765672 -271.802352)
		(width 0.1143)
		(layer "In5.Cu")
		(net "P5E_PEX0_STN1_RX_DN<27>")
	)
	(segment
		(start 46.145196 -138.785346)
		(end 46.221396 -138.928094)
		(width 0.1651)
		(layer "In5.Cu")
		(net "P5E_PEX0_STN1_RX_DN<27>")
	)
	(segment
		(start 69.82333 -275.379688)
		(end 69.985128 -275.379688)
		(width 0.1143)
		(layer "In5.Cu")
		(net "P5E_PEX0_STN1_RX_DN<27>")
	)
	(segment
		(start 51.95189 -125.195584)
		(end 51.625754 -125.195584)
		(width 0.1651)
		(layer "In5.Cu")
		(net "P5E_PEX0_STN1_RX_DN<27>")
	)
	(segment
		(start 46.786546 -137.068814)
		(end 46.643544 -137.145014)
		(width 0.1651)
		(layer "In5.Cu")
		(net "P5E_PEX0_STN1_RX_DN<27>")
	)
	(segment
		(start 45.723048 -140.56868)
		(end 45.5803 -140.64488)
		(width 0.1651)
		(layer "In5.Cu")
		(net "P5E_PEX0_STN1_RX_DN<27>")
	)
	(segment
		(start 46.49978 -137.618724)
		(end 46.575726 -137.761472)
		(width 0.1651)
		(layer "In5.Cu")
		(net "P5E_PEX0_STN1_RX_DN<27>")
	)
	(segment
		(start 47.42815 -134.83844)
		(end 47.192184 -135.339836)
		(width 0.1651)
		(layer "In5.Cu")
		(net "P5E_PEX0_STN1_RX_DN<27>")
	)
	(segment
		(start 48.311054 -133.232144)
		(end 48.099726 -133.680708)
		(width 0.1651)
		(layer "In5.Cu")
		(net "P5E_PEX0_STN1_RX_DN<27>")
	)
	(segment
		(start 47.192184 -135.339836)
		(end 46.854364 -136.452102)
		(width 0.1651)
		(layer "In5.Cu")
		(net "P5E_PEX0_STN1_RX_DN<27>")
	)
	(segment
		(start 40.080692 -147.588986)
		(end 40.688768 -157.00756)
		(width 0.1651)
		(layer "In5.Cu")
		(net "P5E_PEX0_STN1_RX_DN<27>")
	)
	(segment
		(start 86.538562 -345.170506)
		(end 86.538562 -344.539062)
		(width 0.13462)
		(layer "F.Cu")
		(net "P5E_PEX0_STN6_TX_C_DP<100>")
	)
	(segment
		(start 86.243922 -345.465146)
		(end 86.538562 -345.170506)
		(width 0.13462)
		(layer "F.Cu")
		(net "P5E_PEX0_STN6_TX_C_DP<100>")
	)
	(segment
		(start 86.538562 -344.539062)
		(end 86.218522 -344.219022)
		(width 0.13462)
		(layer "F.Cu")
		(net "P5E_PEX0_STN6_TX_C_DP<100>")
	)
	(segment
		(start 79.16418 -383.79908)
		(end 79.402432 -383.560828)
		(width 0.1651)
		(layer "In13.Cu")
		(net "P5E_PEX0_STN6_TX_C_DP<100>")
	)
	(segment
		(start 78.509876 -383.67208)
		(end 78.636876 -383.79908)
		(width 0.1651)
		(layer "In13.Cu")
		(net "P5E_PEX0_STN6_TX_C_DP<100>")
	)
	(segment
		(start 83.449922 -360.684572)
		(end 84.980272 -358.394254)
		(width 0.1651)
		(layer "In13.Cu")
		(net "P5E_PEX0_STN6_TX_C_DP<100>")
	)
	(segment
		(start 78.636876 -383.79908)
		(end 79.16418 -383.79908)
		(width 0.1651)
		(layer "In13.Cu")
		(net "P5E_PEX0_STN6_TX_C_DP<100>")
	)
	(segment
		(start 80.820006 -366.03686)
		(end 81.032096 -365.589058)
		(width 0.1651)
		(layer "In13.Cu")
		(net "P5E_PEX0_STN6_TX_C_DP<100>")
	)
	(segment
		(start 81.650078 -364.490254)
		(end 83.449922 -360.684572)
		(width 0.1651)
		(layer "In13.Cu")
		(net "P5E_PEX0_STN6_TX_C_DP<100>")
	)
	(segment
		(start 80.862424 -366.155478)
		(end 80.820006 -366.03686)
		(width 0.1651)
		(layer "In13.Cu")
		(net "P5E_PEX0_STN6_TX_C_DP<100>")
	)
	(segment
		(start 84.980272 -358.394254)
		(end 84.980272 -347.866208)
		(width 0.1651)
		(layer "In13.Cu")
		(net "P5E_PEX0_STN6_TX_C_DP<100>")
	)
	(segment
		(start 81.362042 -365.099092)
		(end 81.319624 -364.980728)
		(width 0.1651)
		(layer "In13.Cu")
		(net "P5E_PEX0_STN6_TX_C_DP<100>")
	)
	(segment
		(start 81.032096 -365.589058)
		(end 81.15046 -365.54664)
		(width 0.1651)
		(layer "In13.Cu")
		(net "P5E_PEX0_STN6_TX_C_DP<100>")
	)
	(segment
		(start 79.402432 -369.242594)
		(end 80.862424 -366.155478)
		(width 0.1651)
		(layer "In13.Cu")
		(net "P5E_PEX0_STN6_TX_C_DP<100>")
	)
	(segment
		(start 81.319624 -364.980728)
		(end 81.531714 -364.532672)
		(width 0.1651)
		(layer "In13.Cu")
		(net "P5E_PEX0_STN6_TX_C_DP<100>")
	)
	(segment
		(start 79.402432 -383.560828)
		(end 79.402432 -369.242594)
		(width 0.1651)
		(layer "In13.Cu")
		(net "P5E_PEX0_STN6_TX_C_DP<100>")
	)
	(segment
		(start 86.534752 -346.311728)
		(end 86.534752 -345.755976)
		(width 0.1651)
		(layer "In13.Cu")
		(net "P5E_PEX0_STN6_TX_C_DP<100>")
	)
	(segment
		(start 81.15046 -365.54664)
		(end 81.362042 -365.099092)
		(width 0.1651)
		(layer "In13.Cu")
		(net "P5E_PEX0_STN6_TX_C_DP<100>")
	)
	(segment
		(start 81.531714 -364.532672)
		(end 81.650078 -364.490254)
		(width 0.1651)
		(layer "In13.Cu")
		(net "P5E_PEX0_STN6_TX_C_DP<100>")
	)
	(segment
		(start 78.509876 -383.290064)
		(end 78.509876 -383.67208)
		(width 0.1651)
		(layer "In13.Cu")
		(net "P5E_PEX0_STN6_TX_C_DP<100>")
	)
	(segment
		(start 86.534752 -345.755976)
		(end 86.243922 -345.465146)
		(width 0.1651)
		(layer "In13.Cu")
		(net "P5E_PEX0_STN6_TX_C_DP<100>")
	)
	(segment
		(start 84.980272 -347.866208)
		(end 86.534752 -346.311728)
		(width 0.1651)
		(layer "In13.Cu")
		(net "P5E_PEX0_STN6_TX_C_DP<100>")
	)
	(segment
		(start 249.414792 -32.13608)
		(end 248.114058 -32.13608)
		(width 0.13462)
		(layer "F.Cu")
		(net "P5E_PEX2_STN2_TX_C_DN<46>")
	)
	(segment
		(start 247.968008 -31.99003)
		(end 247.464834 -31.99003)
		(width 0.13462)
		(layer "F.Cu")
		(net "P5E_PEX2_STN2_TX_C_DN<46>")
	)
	(segment
		(start 249.725688 -31.825184)
		(end 249.414792 -32.13608)
		(width 0.13462)
		(layer "F.Cu")
		(net "P5E_PEX2_STN2_TX_C_DN<46>")
	)
	(segment
		(start 248.114058 -32.13608)
		(end 247.968008 -31.99003)
		(width 0.13462)
		(layer "F.Cu")
		(net "P5E_PEX2_STN2_TX_C_DN<46>")
	)
	(segment
		(start 285.702502 -329.395582)
		(end 285.701994 -329.251818)
		(width 0.1651)
		(layer "In9.Cu")
		(net "P5E_PEX2_STN6_RX_DN<103>")
	)
	(segment
		(start 285.701994 -329.251818)
		(end 285.349696 -328.903076)
		(width 0.1651)
		(layer "In9.Cu")
		(net "P5E_PEX2_STN6_RX_DN<103>")
	)
	(segment
		(start 285.349696 -328.903076)
		(end 285.205932 -328.903838)
		(width 0.1651)
		(layer "In9.Cu")
		(net "P5E_PEX2_STN6_RX_DN<103>")
	)
	(segment
		(start 300.676818 -341.363808)
		(end 286.376364 -330.06284)
		(width 0.1651)
		(layer "In9.Cu")
		(net "P5E_PEX2_STN6_RX_DN<103>")
	)
	(segment
		(start 315.075316 -361.562142)
		(end 313.514486 -359.972864)
		(width 0.1651)
		(layer "In9.Cu")
		(net "P5E_PEX2_STN6_RX_DN<103>")
	)
	(segment
		(start 332.616048 -369.18392)
		(end 332.12024 -368.2492)
		(width 0.1651)
		(layer "In9.Cu")
		(net "P5E_PEX2_STN6_RX_DN<103>")
	)
	(segment
		(start 283.299916 -316.508892)
		(end 283.299916 -316.799722)
		(width 0.1143)
		(layer "In9.Cu")
		(net "P5E_PEX2_STN6_RX_DN<103>")
	)
	(segment
		(start 286.376364 -330.06284)
		(end 285.702502 -329.395582)
		(width 0.1651)
		(layer "In9.Cu")
		(net "P5E_PEX2_STN6_RX_DN<103>")
	)
	(segment
		(start 284.2895 -327.996042)
		(end 283.63164 -327.0123)
		(width 0.1651)
		(layer "In9.Cu")
		(net "P5E_PEX2_STN6_RX_DN<103>")
	)
	(segment
		(start 285.205932 -328.903838)
		(end 284.2895 -327.996042)
		(width 0.1651)
		(layer "In9.Cu")
		(net "P5E_PEX2_STN6_RX_DN<103>")
	)
	(segment
		(start 283.63164 -327.0123)
		(end 282.965906 -325.405242)
		(width 0.1651)
		(layer "In9.Cu")
		(net "P5E_PEX2_STN6_RX_DN<103>")
	)
	(segment
		(start 283.034232 -316.419992)
		(end 283.211016 -316.419992)
		(width 0.1143)
		(layer "In9.Cu")
		(net "P5E_PEX2_STN6_RX_DN<103>")
	)
	(segment
		(start 282.920186 -319.84188)
		(end 282.920186 -316.534038)
		(width 0.1143)
		(layer "In9.Cu")
		(net "P5E_PEX2_STN6_RX_DN<103>")
	)
	(segment
		(start 331.617066 -375.181114)
		(end 332.164182 -375.181114)
		(width 0.1651)
		(layer "In9.Cu")
		(net "P5E_PEX2_STN6_RX_DN<103>")
	)
	(segment
		(start 282.965906 -325.405242)
		(end 282.965906 -319.916048)
		(width 0.1651)
		(layer "In9.Cu")
		(net "P5E_PEX2_STN6_RX_DN<103>")
	)
	(segment
		(start 282.920186 -316.534038)
		(end 283.034232 -316.419992)
		(width 0.1143)
		(layer "In9.Cu")
		(net "P5E_PEX2_STN6_RX_DN<103>")
	)
	(segment
		(start 282.965906 -319.916048)
		(end 282.965906 -319.8876)
		(width 0.1143)
		(layer "In9.Cu")
		(net "P5E_PEX2_STN6_RX_DN<103>")
	)
	(segment
		(start 313.514486 -359.972864)
		(end 300.676818 -341.363808)
		(width 0.1651)
		(layer "In9.Cu")
		(net "P5E_PEX2_STN6_RX_DN<103>")
	)
	(segment
		(start 332.164182 -375.181114)
		(end 332.616048 -374.729248)
		(width 0.1651)
		(layer "In9.Cu")
		(net "P5E_PEX2_STN6_RX_DN<103>")
	)
	(segment
		(start 331.651356 -367.907316)
		(end 315.075316 -361.562142)
		(width 0.1651)
		(layer "In9.Cu")
		(net "P5E_PEX2_STN6_RX_DN<103>")
	)
	(segment
		(start 332.616048 -374.729248)
		(end 332.616048 -369.18392)
		(width 0.1651)
		(layer "In9.Cu")
		(net "P5E_PEX2_STN6_RX_DN<103>")
	)
	(segment
		(start 283.211016 -316.419992)
		(end 283.299916 -316.508892)
		(width 0.1143)
		(layer "In9.Cu")
		(net "P5E_PEX2_STN6_RX_DN<103>")
	)
	(segment
		(start 331.490066 -375.69013)
		(end 331.490066 -375.308114)
		(width 0.1651)
		(layer "In9.Cu")
		(net "P5E_PEX2_STN6_RX_DN<103>")
	)
	(segment
		(start 331.490066 -375.308114)
		(end 331.617066 -375.181114)
		(width 0.1651)
		(layer "In9.Cu")
		(net "P5E_PEX2_STN6_RX_DN<103>")
	)
	(segment
		(start 282.965906 -319.8876)
		(end 282.920186 -319.84188)
		(width 0.1143)
		(layer "In9.Cu")
		(net "P5E_PEX2_STN6_RX_DN<103>")
	)
	(segment
		(start 332.12024 -368.2492)
		(end 331.651356 -367.907316)
		(width 0.1651)
		(layer "In9.Cu")
		(net "P5E_PEX2_STN6_RX_DN<103>")
	)
	(segment
		(start 390.73074 -356.511606)
		(end 390.411208 -356.831138)
		(width 0.13462)
		(layer "F.Cu")
		(net "P5E_PEX3_STN5_TX_C_DN<89>")
	)
	(segment
		(start 390.411208 -356.831138)
		(end 390.411208 -357.463598)
		(width 0.13462)
		(layer "F.Cu")
		(net "P5E_PEX3_STN5_TX_C_DN<89>")
	)
	(segment
		(start 390.411208 -357.463598)
		(end 390.70534 -357.75773)
		(width 0.13462)
		(layer "F.Cu")
		(net "P5E_PEX3_STN5_TX_C_DN<89>")
	)
	(segment
		(start 377.816872 -380.181104)
		(end 378.363988 -380.181104)
		(width 0.1651)
		(layer "In13.Cu")
		(net "P5E_PEX3_STN5_TX_C_DN<89>")
	)
	(segment
		(start 390.41451 -358.4575)
		(end 390.41451 -358.04856)
		(width 0.1651)
		(layer "In13.Cu")
		(net "P5E_PEX3_STN5_TX_C_DN<89>")
	)
	(segment
		(start 390.41451 -358.04856)
		(end 390.70534 -357.75773)
		(width 0.1651)
		(layer "In13.Cu")
		(net "P5E_PEX3_STN5_TX_C_DN<89>")
	)
	(segment
		(start 377.689872 -380.308104)
		(end 377.816872 -380.181104)
		(width 0.1651)
		(layer "In13.Cu")
		(net "P5E_PEX3_STN5_TX_C_DN<89>")
	)
	(segment
		(start 389.888984 -359.58145)
		(end 390.41451 -358.4575)
		(width 0.1651)
		(layer "In13.Cu")
		(net "P5E_PEX3_STN5_TX_C_DN<89>")
	)
	(segment
		(start 377.689872 -380.69012)
		(end 377.689872 -380.308104)
		(width 0.1651)
		(layer "In13.Cu")
		(net "P5E_PEX3_STN5_TX_C_DN<89>")
	)
	(segment
		(start 378.815854 -379.729238)
		(end 378.815854 -369.71351)
		(width 0.1651)
		(layer "In13.Cu")
		(net "P5E_PEX3_STN5_TX_C_DN<89>")
	)
	(segment
		(start 379.491748 -368.26825)
		(end 389.888984 -359.58145)
		(width 0.1651)
		(layer "In13.Cu")
		(net "P5E_PEX3_STN5_TX_C_DN<89>")
	)
	(segment
		(start 378.815854 -369.71351)
		(end 379.491748 -368.26825)
		(width 0.1651)
		(layer "In13.Cu")
		(net "P5E_PEX3_STN5_TX_C_DN<89>")
	)
	(segment
		(start 378.363988 -380.181104)
		(end 378.815854 -379.729238)
		(width 0.1651)
		(layer "In13.Cu")
		(net "P5E_PEX3_STN5_TX_C_DN<89>")
	)
	(segment
		(start 73.257664 -101.84003)
		(end 74.53503 -101.84003)
		(width 0.13208)
		(layer "F.Cu")
		(net "NCSI_NIC1_RXD0")
	)
	(segment
		(start 74.53503 -101.84003)
		(end 75.184 -102.489)
		(width 0.13208)
		(layer "F.Cu")
		(net "NCSI_NIC1_RXD0")
	)
	(via
		(at 75.184 -102.489)
		(size 0.508)
		(drill 0.254)
		(layers "F.Cu" "B.Cu")
		(net "NCSI_NIC1_RXD0")
	)
	(segment
		(start 75.799696 -103.104696)
		(end 75.184 -102.489)
		(width 0.13208)
		(layer "B.Cu")
		(net "NCSI_NIC1_RXD0")
	)
	(segment
		(start 77.141832 -103.104696)
		(end 75.799696 -103.104696)
		(width 0.13208)
		(layer "B.Cu")
		(net "NCSI_NIC1_RXD0")
	)
	(segment
		(start 45.554392 -108.445046)
		(end 46.042326 -108.445046)
		(width 0.13462)
		(layer "F.Cu")
		(net "P5E_PEX0_STN1_TX_C_DN<21>")
	)
	(segment
		(start 37.217604 -108.60786)
		(end 45.391578 -108.60786)
		(width 0.13462)
		(layer "F.Cu")
		(net "P5E_PEX0_STN1_TX_C_DN<21>")
	)
	(segment
		(start 45.391578 -108.60786)
		(end 45.554392 -108.445046)
		(width 0.13462)
		(layer "F.Cu")
		(net "P5E_PEX0_STN1_TX_C_DN<21>")
	)
	(segment
		(start 36.905184 -108.29544)
		(end 37.217604 -108.60786)
		(width 0.13462)
		(layer "F.Cu")
		(net "P5E_PEX0_STN1_TX_C_DN<21>")
	)
	(segment
		(start 62.580012 -338.55279)
		(end 63.499492 -341.58428)
		(width 0.1651)
		(layer "In9.Cu")
		(net "P5E_PEX0_STN6_RX_DN<100>")
	)
	(segment
		(start 53.615844 -319.865248)
		(end 53.615844 -319.893696)
		(width 0.1143)
		(layer "In9.Cu")
		(net "P5E_PEX0_STN6_RX_DN<100>")
	)
	(segment
		(start 78.509876 -376.408188)
		(end 78.509876 -376.790204)
		(width 0.1651)
		(layer "In9.Cu")
		(net "P5E_PEX0_STN6_RX_DN<100>")
	)
	(segment
		(start 78.636876 -376.281188)
		(end 78.509876 -376.408188)
		(width 0.1651)
		(layer "In9.Cu")
		(net "P5E_PEX0_STN6_RX_DN<100>")
	)
	(segment
		(start 53.570124 -318.485266)
		(end 53.570124 -319.819528)
		(width 0.1143)
		(layer "In9.Cu")
		(net "P5E_PEX0_STN6_RX_DN<100>")
	)
	(segment
		(start 53.949854 -318.699896)
		(end 53.949854 -318.409066)
		(width 0.1143)
		(layer "In9.Cu")
		(net "P5E_PEX0_STN6_RX_DN<100>")
	)
	(segment
		(start 79.684372 -369.197382)
		(end 79.684372 -375.794524)
		(width 0.1651)
		(layer "In9.Cu")
		(net "P5E_PEX0_STN6_RX_DN<100>")
	)
	(segment
		(start 53.860954 -318.320166)
		(end 53.735224 -318.320166)
		(width 0.1143)
		(layer "In9.Cu")
		(net "P5E_PEX0_STN6_RX_DN<100>")
	)
	(segment
		(start 68.702682 -361.025186)
		(end 78.48219 -367.55959)
		(width 0.1651)
		(layer "In9.Cu")
		(net "P5E_PEX0_STN6_RX_DN<100>")
	)
	(segment
		(start 79.37627 -368.45367)
		(end 79.684372 -369.197382)
		(width 0.1651)
		(layer "In9.Cu")
		(net "P5E_PEX0_STN6_RX_DN<100>")
	)
	(segment
		(start 53.615844 -319.893696)
		(end 53.615844 -324.37197)
		(width 0.1651)
		(layer "In9.Cu")
		(net "P5E_PEX0_STN6_RX_DN<100>")
	)
	(segment
		(start 64.269366 -359.188766)
		(end 68.702682 -361.025186)
		(width 0.1651)
		(layer "In9.Cu")
		(net "P5E_PEX0_STN6_RX_DN<100>")
	)
	(segment
		(start 53.615844 -324.37197)
		(end 54.44998 -326.385682)
		(width 0.1651)
		(layer "In9.Cu")
		(net "P5E_PEX0_STN6_RX_DN<100>")
	)
	(segment
		(start 78.48219 -367.55959)
		(end 79.37627 -368.45367)
		(width 0.1651)
		(layer "In9.Cu")
		(net "P5E_PEX0_STN6_RX_DN<100>")
	)
	(segment
		(start 63.499492 -357.959152)
		(end 63.824612 -358.744012)
		(width 0.1651)
		(layer "In9.Cu")
		(net "P5E_PEX0_STN6_RX_DN<100>")
	)
	(segment
		(start 54.44998 -326.385682)
		(end 62.580012 -338.55279)
		(width 0.1651)
		(layer "In9.Cu")
		(net "P5E_PEX0_STN6_RX_DN<100>")
	)
	(segment
		(start 53.570124 -319.819528)
		(end 53.615844 -319.865248)
		(width 0.1143)
		(layer "In9.Cu")
		(net "P5E_PEX0_STN6_RX_DN<100>")
	)
	(segment
		(start 63.824612 -358.744012)
		(end 64.269366 -359.188766)
		(width 0.1651)
		(layer "In9.Cu")
		(net "P5E_PEX0_STN6_RX_DN<100>")
	)
	(segment
		(start 63.499492 -341.58428)
		(end 63.499492 -357.959152)
		(width 0.1651)
		(layer "In9.Cu")
		(net "P5E_PEX0_STN6_RX_DN<100>")
	)
	(segment
		(start 79.684372 -375.794524)
		(end 79.197708 -376.281188)
		(width 0.1651)
		(layer "In9.Cu")
		(net "P5E_PEX0_STN6_RX_DN<100>")
	)
	(segment
		(start 53.735224 -318.320166)
		(end 53.570124 -318.485266)
		(width 0.1143)
		(layer "In9.Cu")
		(net "P5E_PEX0_STN6_RX_DN<100>")
	)
	(segment
		(start 53.949854 -318.409066)
		(end 53.860954 -318.320166)
		(width 0.1143)
		(layer "In9.Cu")
		(net "P5E_PEX0_STN6_RX_DN<100>")
	)
	(segment
		(start 79.197708 -376.281188)
		(end 78.636876 -376.281188)
		(width 0.1651)
		(layer "In9.Cu")
		(net "P5E_PEX0_STN6_RX_DN<100>")
	)
	(segment
		(start 268.219428 -28.55468)
		(end 267.560552 -28.55468)
		(width 0.13462)
		(layer "F.Cu")
		(net "P5E_PEX2_STN2_RX_DN<40>")
	)
	(segment
		(start 268.864842 -28.390088)
		(end 268.38402 -28.390088)
		(width 0.13462)
		(layer "F.Cu")
		(net "P5E_PEX2_STN2_RX_DN<40>")
	)
	(segment
		(start 268.38402 -28.390088)
		(end 268.219428 -28.55468)
		(width 0.13462)
		(layer "F.Cu")
		(net "P5E_PEX2_STN2_RX_DN<40>")
	)
	(segment
		(start 267.560552 -28.55468)
		(end 267.264642 -28.25877)
		(width 0.13462)
		(layer "F.Cu")
		(net "P5E_PEX2_STN2_RX_DN<40>")
	)
	(segment
		(start 283.185616 -275.379688)
		(end 283.299916 -275.265388)
		(width 0.1143)
		(layer "In7.Cu")
		(net "P5E_PEX2_STN2_RX_DN<40>")
	)
	(segment
		(start 282.965652 -271.392904)
		(end 282.965652 -271.421352)
		(width 0.1143)
		(layer "In7.Cu")
		(net "P5E_PEX2_STN2_RX_DN<40>")
	)
	(segment
		(start 282.919932 -275.275802)
		(end 283.023818 -275.379688)
		(width 0.1143)
		(layer "In7.Cu")
		(net "P5E_PEX2_STN2_RX_DN<40>")
	)
	(segment
		(start 271.36979 -48.829722)
		(end 271.270476 -55.191914)
		(width 0.1651)
		(layer "In7.Cu")
		(net "P5E_PEX2_STN2_RX_DN<40>")
	)
	(segment
		(start 271.270476 -55.191914)
		(end 271.66824 -65.131442)
		(width 0.1651)
		(layer "In7.Cu")
		(net "P5E_PEX2_STN2_RX_DN<40>")
	)
	(segment
		(start 282.965652 -268.123162)
		(end 282.965652 -271.392904)
		(width 0.1651)
		(layer "In7.Cu")
		(net "P5E_PEX2_STN2_RX_DN<40>")
	)
	(segment
		(start 267.555472 -28.5496)
		(end 268.003782 -28.5496)
		(width 0.1651)
		(layer "In7.Cu")
		(net "P5E_PEX2_STN2_RX_DN<40>")
	)
	(segment
		(start 282.919932 -271.467072)
		(end 282.919932 -275.275802)
		(width 0.1143)
		(layer "In7.Cu")
		(net "P5E_PEX2_STN2_RX_DN<40>")
	)
	(segment
		(start 267.264642 -28.25877)
		(end 267.555472 -28.5496)
		(width 0.1651)
		(layer "In7.Cu")
		(net "P5E_PEX2_STN2_RX_DN<40>")
	)
	(segment
		(start 283.299916 -275.265388)
		(end 283.299916 -274.999958)
		(width 0.1143)
		(layer "In7.Cu")
		(net "P5E_PEX2_STN2_RX_DN<40>")
	)
	(segment
		(start 273.53133 -37.688012)
		(end 273.516598 -38.576758)
		(width 0.1651)
		(layer "In7.Cu")
		(net "P5E_PEX2_STN2_RX_DN<40>")
	)
	(segment
		(start 274.811998 -104.30002)
		(end 275.274786 -119.564404)
		(width 0.1651)
		(layer "In7.Cu")
		(net "P5E_PEX2_STN2_RX_DN<40>")
	)
	(segment
		(start 282.965652 -271.421352)
		(end 282.919932 -271.467072)
		(width 0.1143)
		(layer "In7.Cu")
		(net "P5E_PEX2_STN2_RX_DN<40>")
	)
	(segment
		(start 275.274786 -119.564404)
		(end 274.96897 -147.93849)
		(width 0.1651)
		(layer "In7.Cu")
		(net "P5E_PEX2_STN2_RX_DN<40>")
	)
	(segment
		(start 271.66824 -65.131442)
		(end 274.811998 -104.30002)
		(width 0.1651)
		(layer "In7.Cu")
		(net "P5E_PEX2_STN2_RX_DN<40>")
	)
	(segment
		(start 283.023818 -275.379688)
		(end 283.185616 -275.379688)
		(width 0.1143)
		(layer "In7.Cu")
		(net "P5E_PEX2_STN2_RX_DN<40>")
	)
	(segment
		(start 274.96897 -147.93849)
		(end 282.9306 -250.008136)
		(width 0.1651)
		(layer "In7.Cu")
		(net "P5E_PEX2_STN2_RX_DN<40>")
	)
	(segment
		(start 282.9306 -250.008136)
		(end 282.644342 -264.860786)
		(width 0.1651)
		(layer "In7.Cu")
		(net "P5E_PEX2_STN2_RX_DN<40>")
	)
	(segment
		(start 268.003782 -28.5496)
		(end 270.902684 -31.448502)
		(width 0.1651)
		(layer "In7.Cu")
		(net "P5E_PEX2_STN2_RX_DN<40>")
	)
	(segment
		(start 273.516598 -38.576758)
		(end 271.36979 -48.829722)
		(width 0.1651)
		(layer "In7.Cu")
		(net "P5E_PEX2_STN2_RX_DN<40>")
	)
	(segment
		(start 282.644342 -264.860786)
		(end 282.965652 -268.123162)
		(width 0.1651)
		(layer "In7.Cu")
		(net "P5E_PEX2_STN2_RX_DN<40>")
	)
	(segment
		(start 270.902684 -31.448502)
		(end 273.53133 -37.688012)
		(width 0.1651)
		(layer "In7.Cu")
		(net "P5E_PEX2_STN2_RX_DN<40>")
	)
	(segment
		(start 285.579312 -318.355218)
		(end 285.804864 -318.129666)
		(width 0.1143)
		(layer "In9.Cu")
		(net "P5E_PEX2_STN6_RX_DP<100>")
	)
	(segment
		(start 338.49183 -368.309652)
		(end 337.521804 -367.681002)
		(width 0.1651)
		(layer "In9.Cu")
		(net "P5E_PEX2_STN6_RX_DP<100>")
	)
	(segment
		(start 285.804864 -318.129666)
		(end 286.060642 -318.129666)
		(width 0.1143)
		(layer "In9.Cu")
		(net "P5E_PEX2_STN6_RX_DP<100>")
	)
	(segment
		(start 317.457074 -342.303608)
		(end 317.063374 -341.47887)
		(width 0.1651)
		(layer "In9.Cu")
		(net "P5E_PEX2_STN6_RX_DP<100>")
	)
	(segment
		(start 285.966154 -325.534274)
		(end 285.533592 -324.49008)
		(width 0.1651)
		(layer "In9.Cu")
		(net "P5E_PEX2_STN6_RX_DP<100>")
	)
	(segment
		(start 337.000596 -367.433606)
		(end 336.97799 -367.32845)
		(width 0.1651)
		(layer "In9.Cu")
		(net "P5E_PEX2_STN6_RX_DP<100>")
	)
	(segment
		(start 317.063374 -341.47887)
		(end 295.217342 -332.903068)
		(width 0.1651)
		(layer "In9.Cu")
		(net "P5E_PEX2_STN6_RX_DP<100>")
	)
	(segment
		(start 335.06791 -366.0902)
		(end 318.260476 -359.29189)
		(width 0.1651)
		(layer "In9.Cu")
		(net "P5E_PEX2_STN6_RX_DP<100>")
	)
	(segment
		(start 338.934044 -368.967766)
		(end 338.49183 -368.309652)
		(width 0.1651)
		(layer "In9.Cu")
		(net "P5E_PEX2_STN6_RX_DP<100>")
	)
	(segment
		(start 285.533592 -324.49008)
		(end 285.533592 -319.916048)
		(width 0.1651)
		(layer "In9.Cu")
		(net "P5E_PEX2_STN6_RX_DP<100>")
	)
	(segment
		(start 336.562446 -367.05921)
		(end 336.457036 -367.081562)
		(width 0.1651)
		(layer "In9.Cu")
		(net "P5E_PEX2_STN6_RX_DP<100>")
	)
	(segment
		(start 336.97799 -367.32845)
		(end 336.562446 -367.05921)
		(width 0.1651)
		(layer "In9.Cu")
		(net "P5E_PEX2_STN6_RX_DP<100>")
	)
	(segment
		(start 318.260476 -359.29189)
		(end 317.457074 -358.488234)
		(width 0.1651)
		(layer "In9.Cu")
		(net "P5E_PEX2_STN6_RX_DP<100>")
	)
	(segment
		(start 338.090002 -375.490232)
		(end 338.090002 -375.872248)
		(width 0.1651)
		(layer "In9.Cu")
		(net "P5E_PEX2_STN6_RX_DP<100>")
	)
	(segment
		(start 317.457074 -358.488234)
		(end 317.457074 -342.303608)
		(width 0.1651)
		(layer "In9.Cu")
		(net "P5E_PEX2_STN6_RX_DP<100>")
	)
	(segment
		(start 338.217002 -375.999248)
		(end 338.647278 -375.999248)
		(width 0.1651)
		(layer "In9.Cu")
		(net "P5E_PEX2_STN6_RX_DP<100>")
	)
	(segment
		(start 286.060642 -318.129666)
		(end 286.149796 -318.040512)
		(width 0.1143)
		(layer "In9.Cu")
		(net "P5E_PEX2_STN6_RX_DP<100>")
	)
	(segment
		(start 338.647278 -375.999248)
		(end 338.934044 -375.712482)
		(width 0.1651)
		(layer "In9.Cu")
		(net "P5E_PEX2_STN6_RX_DP<100>")
	)
	(segment
		(start 337.416394 -367.703354)
		(end 337.000596 -367.433606)
		(width 0.1651)
		(layer "In9.Cu")
		(net "P5E_PEX2_STN6_RX_DP<100>")
	)
	(segment
		(start 336.018886 -366.706658)
		(end 335.06791 -366.0902)
		(width 0.1651)
		(layer "In9.Cu")
		(net "P5E_PEX2_STN6_RX_DP<100>")
	)
	(segment
		(start 337.521804 -367.681002)
		(end 337.416394 -367.703354)
		(width 0.1651)
		(layer "In9.Cu")
		(net "P5E_PEX2_STN6_RX_DP<100>")
	)
	(segment
		(start 336.041238 -366.812068)
		(end 336.018886 -366.706658)
		(width 0.1651)
		(layer "In9.Cu")
		(net "P5E_PEX2_STN6_RX_DP<100>")
	)
	(segment
		(start 338.934044 -375.712482)
		(end 338.934044 -368.967766)
		(width 0.1651)
		(layer "In9.Cu")
		(net "P5E_PEX2_STN6_RX_DP<100>")
	)
	(segment
		(start 295.217342 -332.903068)
		(end 289.763454 -329.331574)
		(width 0.1651)
		(layer "In9.Cu")
		(net "P5E_PEX2_STN6_RX_DP<100>")
	)
	(segment
		(start 285.533592 -319.8876)
		(end 285.579312 -319.84188)
		(width 0.1143)
		(layer "In9.Cu")
		(net "P5E_PEX2_STN6_RX_DP<100>")
	)
	(segment
		(start 336.457036 -367.081562)
		(end 336.041238 -366.812068)
		(width 0.1651)
		(layer "In9.Cu")
		(net "P5E_PEX2_STN6_RX_DP<100>")
	)
	(segment
		(start 285.579312 -319.84188)
		(end 285.579312 -318.355218)
		(width 0.1143)
		(layer "In9.Cu")
		(net "P5E_PEX2_STN6_RX_DP<100>")
	)
	(segment
		(start 289.763454 -329.331574)
		(end 285.966154 -325.534274)
		(width 0.1651)
		(layer "In9.Cu")
		(net "P5E_PEX2_STN6_RX_DP<100>")
	)
	(segment
		(start 285.533592 -319.916048)
		(end 285.533592 -319.8876)
		(width 0.1143)
		(layer "In9.Cu")
		(net "P5E_PEX2_STN6_RX_DP<100>")
	)
	(segment
		(start 338.090002 -375.872248)
		(end 338.217002 -375.999248)
		(width 0.1651)
		(layer "In9.Cu")
		(net "P5E_PEX2_STN6_RX_DP<100>")
	)
	(segment
		(start 286.149796 -318.040512)
		(end 286.149796 -317.749936)
		(width 0.1143)
		(layer "In9.Cu")
		(net "P5E_PEX2_STN6_RX_DP<100>")
	)
	(segment
		(start 51.130708 -135.96493)
		(end 51.293522 -136.127744)
		(width 0.13462)
		(layer "F.Cu")
		(net "P5E_PEX0_STN1_RX_DP<31>")
	)
	(segment
		(start 51.293522 -136.127744)
		(end 51.947826 -136.127744)
		(width 0.13462)
		(layer "F.Cu")
		(net "P5E_PEX0_STN1_RX_DP<31>")
	)
	(segment
		(start 51.947826 -136.127744)
		(end 52.24272 -135.83285)
		(width 0.13462)
		(layer "F.Cu")
		(net "P5E_PEX0_STN1_RX_DP<31>")
	)
	(segment
		(start 50.64252 -135.96493)
		(end 51.130708 -135.96493)
		(width 0.13462)
		(layer "F.Cu")
		(net "P5E_PEX0_STN1_RX_DP<31>")
	)
	(segment
		(start 46.607476 -146.848576)
		(end 46.294802 -147.156424)
		(width 0.1651)
		(layer "In5.Cu")
		(net "P5E_PEX0_STN1_RX_DP<31>")
	)
	(segment
		(start 44.911772 -159.491172)
		(end 44.952158 -160.413446)
		(width 0.1651)
		(layer "In5.Cu")
		(net "P5E_PEX0_STN1_RX_DP<31>")
	)
	(segment
		(start 50.88763 -141.23035)
		(end 49.66589 -144.215612)
		(width 0.1651)
		(layer "In5.Cu")
		(net "P5E_PEX0_STN1_RX_DP<31>")
	)
	(segment
		(start 47.263812 -146.579844)
		(end 46.607476 -146.848576)
		(width 0.1651)
		(layer "In5.Cu")
		(net "P5E_PEX0_STN1_RX_DP<31>")
	)
	(segment
		(start 44.952158 -160.413446)
		(end 73.22058 -266.597638)
		(width 0.1651)
		(layer "In5.Cu")
		(net "P5E_PEX0_STN1_RX_DP<31>")
	)
	(segment
		(start 73.22058 -266.597638)
		(end 73.283826 -267.07973)
		(width 0.1651)
		(layer "In5.Cu")
		(net "P5E_PEX0_STN1_RX_DP<31>")
	)
	(segment
		(start 46.294802 -147.156424)
		(end 45.830744 -148.199094)
		(width 0.1651)
		(layer "In5.Cu")
		(net "P5E_PEX0_STN1_RX_DP<31>")
	)
	(segment
		(start 50.88763 -136.987534)
		(end 50.88763 -141.23035)
		(width 0.1651)
		(layer "In5.Cu")
		(net "P5E_PEX0_STN1_RX_DP<31>")
	)
	(segment
		(start 51.95189 -136.12368)
		(end 51.574954 -136.12368)
		(width 0.1651)
		(layer "In5.Cu")
		(net "P5E_PEX0_STN1_RX_DP<31>")
	)
	(segment
		(start 45.830744 -148.199094)
		(end 45.83049 -148.200872)
		(width 0.1651)
		(layer "In5.Cu")
		(net "P5E_PEX0_STN1_RX_DP<31>")
	)
	(segment
		(start 73.329546 -271.848072)
		(end 73.329546 -275.355304)
		(width 0.1143)
		(layer "In5.Cu")
		(net "P5E_PEX0_STN1_RX_DP<31>")
	)
	(segment
		(start 73.283826 -271.802352)
		(end 73.329546 -271.848072)
		(width 0.1143)
		(layer "In5.Cu")
		(net "P5E_PEX0_STN1_RX_DP<31>")
	)
	(segment
		(start 45.43806 -153.01214)
		(end 45.437552 -153.01214)
		(width 0.1651)
		(layer "In5.Cu")
		(net "P5E_PEX0_STN1_RX_DP<31>")
	)
	(segment
		(start 52.24272 -135.83285)
		(end 51.95189 -136.12368)
		(width 0.1651)
		(layer "In5.Cu")
		(net "P5E_PEX0_STN1_RX_DP<31>")
	)
	(segment
		(start 51.012344 -136.68629)
		(end 50.88763 -136.987534)
		(width 0.1651)
		(layer "In5.Cu")
		(net "P5E_PEX0_STN1_RX_DP<31>")
	)
	(segment
		(start 73.54443 -275.570188)
		(end 73.785222 -275.570188)
		(width 0.1143)
		(layer "In5.Cu")
		(net "P5E_PEX0_STN1_RX_DP<31>")
	)
	(segment
		(start 45.83049 -148.200872)
		(end 45.43806 -153.01214)
		(width 0.1651)
		(layer "In5.Cu")
		(net "P5E_PEX0_STN1_RX_DP<31>")
	)
	(segment
		(start 51.574954 -136.12368)
		(end 51.012344 -136.68629)
		(width 0.1651)
		(layer "In5.Cu")
		(net "P5E_PEX0_STN1_RX_DP<31>")
	)
	(segment
		(start 44.91101 -159.473646)
		(end 44.911518 -159.491172)
		(width 0.1651)
		(layer "In5.Cu")
		(net "P5E_PEX0_STN1_RX_DP<31>")
	)
	(segment
		(start 45.437552 -153.01214)
		(end 44.91101 -159.473646)
		(width 0.1651)
		(layer "In5.Cu")
		(net "P5E_PEX0_STN1_RX_DP<31>")
	)
	(segment
		(start 73.785222 -275.570188)
		(end 73.899522 -275.684488)
		(width 0.1143)
		(layer "In5.Cu")
		(net "P5E_PEX0_STN1_RX_DP<31>")
	)
	(segment
		(start 44.911518 -159.491172)
		(end 44.911772 -159.491172)
		(width 0.1651)
		(layer "In5.Cu")
		(net "P5E_PEX0_STN1_RX_DP<31>")
	)
	(segment
		(start 49.66589 -144.215612)
		(end 47.263812 -146.579844)
		(width 0.1651)
		(layer "In5.Cu")
		(net "P5E_PEX0_STN1_RX_DP<31>")
	)
	(segment
		(start 73.329546 -275.355304)
		(end 73.54443 -275.570188)
		(width 0.1143)
		(layer "In5.Cu")
		(net "P5E_PEX0_STN1_RX_DP<31>")
	)
	(segment
		(start 73.283826 -271.773904)
		(end 73.283826 -271.802352)
		(width 0.1143)
		(layer "In5.Cu")
		(net "P5E_PEX0_STN1_RX_DP<31>")
	)
	(segment
		(start 73.283826 -267.07973)
		(end 73.283826 -271.773904)
		(width 0.1651)
		(layer "In5.Cu")
		(net "P5E_PEX0_STN1_RX_DP<31>")
	)
	(segment
		(start 73.899522 -275.684488)
		(end 73.899522 -275.949918)
		(width 0.1143)
		(layer "In5.Cu")
		(net "P5E_PEX0_STN1_RX_DP<31>")
	)
	(segment
		(start 63.881508 -360.15168)
		(end 62.869572 -359.139744)
		(width 0.1651)
		(layer "In9.Cu")
		(net "P5E_PEX0_STN6_RX_DN<101>")
	)
	(segment
		(start 60.717176 -353.943412)
		(end 59.124596 -345.93657)
		(width 0.1651)
		(layer "In9.Cu")
		(net "P5E_PEX0_STN6_RX_DN<101>")
	)
	(segment
		(start 76.436982 -375.181114)
		(end 76.944982 -375.181114)
		(width 0.1651)
		(layer "In9.Cu")
		(net "P5E_PEX0_STN6_RX_DN<101>")
	)
	(segment
		(start 52.999894 -316.508892)
		(end 52.999894 -316.799722)
		(width 0.1143)
		(layer "In9.Cu")
		(net "P5E_PEX0_STN6_RX_DN<101>")
	)
	(segment
		(start 62.869572 -359.139744)
		(end 60.717176 -353.943412)
		(width 0.1651)
		(layer "In9.Cu")
		(net "P5E_PEX0_STN6_RX_DN<101>")
	)
	(segment
		(start 52.665884 -319.865248)
		(end 52.620164 -319.819528)
		(width 0.1143)
		(layer "In9.Cu")
		(net "P5E_PEX0_STN6_RX_DN<101>")
	)
	(segment
		(start 77.484224 -369.470432)
		(end 76.908152 -368.079528)
		(width 0.1651)
		(layer "In9.Cu")
		(net "P5E_PEX0_STN6_RX_DN<101>")
	)
	(segment
		(start 52.665884 -319.893696)
		(end 52.665884 -319.865248)
		(width 0.1143)
		(layer "In9.Cu")
		(net "P5E_PEX0_STN6_RX_DN<101>")
	)
	(segment
		(start 76.309982 -375.69013)
		(end 76.309982 -375.308114)
		(width 0.1651)
		(layer "In9.Cu")
		(net "P5E_PEX0_STN6_RX_DN<101>")
	)
	(segment
		(start 76.944982 -375.181114)
		(end 77.484224 -374.641872)
		(width 0.1651)
		(layer "In9.Cu")
		(net "P5E_PEX0_STN6_RX_DN<101>")
	)
	(segment
		(start 66.938652 -361.41787)
		(end 63.881508 -360.15168)
		(width 0.1651)
		(layer "In9.Cu")
		(net "P5E_PEX0_STN6_RX_DN<101>")
	)
	(segment
		(start 52.620164 -319.819528)
		(end 52.620164 -316.585092)
		(width 0.1143)
		(layer "In9.Cu")
		(net "P5E_PEX0_STN6_RX_DN<101>")
	)
	(segment
		(start 76.908152 -368.079528)
		(end 66.938652 -361.41787)
		(width 0.1651)
		(layer "In9.Cu")
		(net "P5E_PEX0_STN6_RX_DN<101>")
	)
	(segment
		(start 52.620164 -316.585092)
		(end 52.785264 -316.419992)
		(width 0.1143)
		(layer "In9.Cu")
		(net "P5E_PEX0_STN6_RX_DN<101>")
	)
	(segment
		(start 52.665884 -324.645528)
		(end 52.665884 -319.893696)
		(width 0.1651)
		(layer "In9.Cu")
		(net "P5E_PEX0_STN6_RX_DN<101>")
	)
	(segment
		(start 52.785264 -316.419992)
		(end 52.910994 -316.419992)
		(width 0.1143)
		(layer "In9.Cu")
		(net "P5E_PEX0_STN6_RX_DN<101>")
	)
	(segment
		(start 52.910994 -316.419992)
		(end 52.999894 -316.508892)
		(width 0.1143)
		(layer "In9.Cu")
		(net "P5E_PEX0_STN6_RX_DN<101>")
	)
	(segment
		(start 59.124596 -345.93657)
		(end 52.665884 -324.645528)
		(width 0.1651)
		(layer "In9.Cu")
		(net "P5E_PEX0_STN6_RX_DN<101>")
	)
	(segment
		(start 76.309982 -375.308114)
		(end 76.436982 -375.181114)
		(width 0.1651)
		(layer "In9.Cu")
		(net "P5E_PEX0_STN6_RX_DN<101>")
	)
	(segment
		(start 77.484224 -374.641872)
		(end 77.484224 -369.470432)
		(width 0.1651)
		(layer "In9.Cu")
		(net "P5E_PEX0_STN6_RX_DN<101>")
	)
	(segment
		(start 325.964296 -32.589978)
		(end 325.464678 -32.589978)
		(width 0.13462)
		(layer "F.Cu")
		(net "P5E_PEX2_STN2_TX_C_DP<34>")
	)
	(segment
		(start 327.396348 -32.4104)
		(end 326.143874 -32.4104)
		(width 0.13462)
		(layer "F.Cu")
		(net "P5E_PEX2_STN2_TX_C_DP<34>")
	)
	(segment
		(start 326.143874 -32.4104)
		(end 325.964296 -32.589978)
		(width 0.13462)
		(layer "F.Cu")
		(net "P5E_PEX2_STN2_TX_C_DP<34>")
	)
	(segment
		(start 327.725532 -32.739584)
		(end 327.396348 -32.4104)
		(width 0.13462)
		(layer "F.Cu")
		(net "P5E_PEX2_STN2_TX_C_DP<34>")
	)
	(segment
		(start 345.25966 -367.120678)
		(end 345.238324 -366.978692)
		(width 0.1651)
		(layer "In9.Cu")
		(net "P5E_PEX2_STN6_RX_DP<96>")
	)
	(segment
		(start 345.65844 -367.415064)
		(end 345.25966 -367.120678)
		(width 0.1651)
		(layer "In9.Cu")
		(net "P5E_PEX2_STN6_RX_DP<96>")
	)
	(segment
		(start 289.605212 -318.129666)
		(end 289.86099 -318.129666)
		(width 0.1143)
		(layer "In9.Cu")
		(net "P5E_PEX2_STN6_RX_DP<96>")
	)
	(segment
		(start 346.890086 -375.872248)
		(end 347.017086 -375.999248)
		(width 0.1651)
		(layer "In9.Cu")
		(net "P5E_PEX2_STN6_RX_DP<96>")
	)
	(segment
		(start 289.37966 -318.355218)
		(end 289.605212 -318.129666)
		(width 0.1143)
		(layer "In9.Cu")
		(net "P5E_PEX2_STN6_RX_DP<96>")
	)
	(segment
		(start 344.839798 -366.684814)
		(end 344.697558 -366.70615)
		(width 0.1651)
		(layer "In9.Cu")
		(net "P5E_PEX2_STN6_RX_DP<96>")
	)
	(segment
		(start 289.37966 -319.84188)
		(end 289.37966 -318.355218)
		(width 0.1143)
		(layer "In9.Cu")
		(net "P5E_PEX2_STN6_RX_DP<96>")
	)
	(segment
		(start 289.33394 -323.134736)
		(end 289.33394 -319.916048)
		(width 0.1651)
		(layer "In9.Cu")
		(net "P5E_PEX2_STN6_RX_DP<96>")
	)
	(segment
		(start 344.697558 -366.70615)
		(end 344.298778 -366.412018)
		(width 0.1651)
		(layer "In9.Cu")
		(net "P5E_PEX2_STN6_RX_DP<96>")
	)
	(segment
		(start 329.239372 -341.051134)
		(end 296.041064 -328.718164)
		(width 0.1651)
		(layer "In9.Cu")
		(net "P5E_PEX2_STN6_RX_DP<96>")
	)
	(segment
		(start 347.502734 -368.64925)
		(end 345.80068 -367.393728)
		(width 0.1651)
		(layer "In9.Cu")
		(net "P5E_PEX2_STN6_RX_DP<96>")
	)
	(segment
		(start 345.80068 -367.393728)
		(end 345.65844 -367.415064)
		(width 0.1651)
		(layer "In9.Cu")
		(net "P5E_PEX2_STN6_RX_DP<96>")
	)
	(segment
		(start 289.86099 -318.129666)
		(end 289.94989 -318.040766)
		(width 0.1143)
		(layer "In9.Cu")
		(net "P5E_PEX2_STN6_RX_DP<96>")
	)
	(segment
		(start 329.892914 -358.627934)
		(end 329.892914 -342.198452)
		(width 0.1651)
		(layer "In9.Cu")
		(net "P5E_PEX2_STN6_RX_DP<96>")
	)
	(segment
		(start 296.041064 -328.718164)
		(end 292.354254 -326.352154)
		(width 0.1651)
		(layer "In9.Cu")
		(net "P5E_PEX2_STN6_RX_DP<96>")
	)
	(segment
		(start 330.298552 -359.033572)
		(end 329.892914 -358.627934)
		(width 0.1651)
		(layer "In9.Cu")
		(net "P5E_PEX2_STN6_RX_DP<96>")
	)
	(segment
		(start 344.277442 -366.270032)
		(end 342.324436 -364.829344)
		(width 0.1651)
		(layer "In9.Cu")
		(net "P5E_PEX2_STN6_RX_DP<96>")
	)
	(segment
		(start 347.734128 -369.044474)
		(end 347.502734 -368.64925)
		(width 0.1651)
		(layer "In9.Cu")
		(net "P5E_PEX2_STN6_RX_DP<96>")
	)
	(segment
		(start 345.238324 -366.978692)
		(end 344.839798 -366.684814)
		(width 0.1651)
		(layer "In9.Cu")
		(net "P5E_PEX2_STN6_RX_DP<96>")
	)
	(segment
		(start 329.892914 -342.198452)
		(end 329.239372 -341.051134)
		(width 0.1651)
		(layer "In9.Cu")
		(net "P5E_PEX2_STN6_RX_DP<96>")
	)
	(segment
		(start 289.33394 -319.916048)
		(end 289.33394 -319.8876)
		(width 0.1143)
		(layer "In9.Cu")
		(net "P5E_PEX2_STN6_RX_DP<96>")
	)
	(segment
		(start 289.33394 -319.8876)
		(end 289.37966 -319.84188)
		(width 0.1143)
		(layer "In9.Cu")
		(net "P5E_PEX2_STN6_RX_DP<96>")
	)
	(segment
		(start 347.017086 -375.999248)
		(end 347.447362 -375.999248)
		(width 0.1651)
		(layer "In9.Cu")
		(net "P5E_PEX2_STN6_RX_DP<96>")
	)
	(segment
		(start 292.354254 -326.352154)
		(end 289.473386 -323.471286)
		(width 0.1651)
		(layer "In9.Cu")
		(net "P5E_PEX2_STN6_RX_DP<96>")
	)
	(segment
		(start 342.324436 -364.829344)
		(end 330.298552 -359.033572)
		(width 0.1651)
		(layer "In9.Cu")
		(net "P5E_PEX2_STN6_RX_DP<96>")
	)
	(segment
		(start 344.298778 -366.412018)
		(end 344.277442 -366.270032)
		(width 0.1651)
		(layer "In9.Cu")
		(net "P5E_PEX2_STN6_RX_DP<96>")
	)
	(segment
		(start 289.473386 -323.471286)
		(end 289.33394 -323.134736)
		(width 0.1651)
		(layer "In9.Cu")
		(net "P5E_PEX2_STN6_RX_DP<96>")
	)
	(segment
		(start 346.890086 -375.490232)
		(end 346.890086 -375.872248)
		(width 0.1651)
		(layer "In9.Cu")
		(net "P5E_PEX2_STN6_RX_DP<96>")
	)
	(segment
		(start 289.94989 -318.040766)
		(end 289.94989 -317.749936)
		(width 0.1143)
		(layer "In9.Cu")
		(net "P5E_PEX2_STN6_RX_DP<96>")
	)
	(segment
		(start 347.734128 -375.712482)
		(end 347.734128 -369.044474)
		(width 0.1651)
		(layer "In9.Cu")
		(net "P5E_PEX2_STN6_RX_DP<96>")
	)
	(segment
		(start 347.447362 -375.999248)
		(end 347.734128 -375.712482)
		(width 0.1651)
		(layer "In9.Cu")
		(net "P5E_PEX2_STN6_RX_DP<96>")
	)
	(segment
		(start 394.342366 -140.765022)
		(end 394.979906 -140.765022)
		(width 0.13208)
		(layer "F.Cu")
		(net "RST_NIC6_PERST0_R_N")
	)
	(segment
		(start 399.259552 -164.94252)
		(end 399.259552 -165.813994)
		(width 0.13208)
		(layer "F.Cu")
		(net "RST_NIC6_PERST0_R_N")
	)
	(segment
		(start 397.27759 -146.425412)
		(end 397.592042 -146.739864)
		(width 0.13208)
		(layer "F.Cu")
		(net "RST_NIC6_PERST0_R_N")
	)
	(segment
		(start 397.27759 -143.062706)
		(end 397.27759 -146.425412)
		(width 0.13208)
		(layer "F.Cu")
		(net "RST_NIC6_PERST0_R_N")
	)
	(segment
		(start 394.979906 -140.765022)
		(end 397.27759 -143.062706)
		(width 0.13208)
		(layer "F.Cu")
		(net "RST_NIC6_PERST0_R_N")
	)
	(segment
		(start 399.259552 -165.813994)
		(end 399.348452 -165.902894)
		(width 0.13208)
		(layer "F.Cu")
		(net "RST_NIC6_PERST0_R_N")
	)
	(via
		(at 397.592042 -146.739864)
		(size 0.508)
		(drill 0.254)
		(layers "F.Cu" "B.Cu")
		(net "RST_NIC6_PERST0_R_N")
	)
	(via
		(at 399.259552 -164.94252)
		(size 0.508)
		(drill 0.254)
		(layers "F.Cu" "B.Cu")
		(net "RST_NIC6_PERST0_R_N")
	)
	(segment
		(start 398.760442 -160.819846)
		(end 399.259552 -161.318956)
		(width 0.15494)
		(layer "In7.Cu")
		(net "RST_NIC6_PERST0_R_N")
	)
	(segment
		(start 398.760442 -147.908264)
		(end 398.760442 -160.819846)
		(width 0.15494)
		(layer "In7.Cu")
		(net "RST_NIC6_PERST0_R_N")
	)
	(segment
		(start 399.259552 -161.318956)
		(end 399.259552 -164.94252)
		(width 0.15494)
		(layer "In7.Cu")
		(net "RST_NIC6_PERST0_R_N")
	)
	(segment
		(start 397.592042 -146.739864)
		(end 398.760442 -147.908264)
		(width 0.15494)
		(layer "In7.Cu")
		(net "RST_NIC6_PERST0_R_N")
	)
	(segment
		(start 45.554392 -131.165092)
		(end 45.391578 -131.002278)
		(width 0.13462)
		(layer "F.Cu")
		(net "P5E_PEX0_STN1_TX_C_DN<28>")
	)
	(segment
		(start 45.391578 -131.002278)
		(end 37.22624 -131.002278)
		(width 0.13462)
		(layer "F.Cu")
		(net "P5E_PEX0_STN1_TX_C_DN<28>")
	)
	(segment
		(start 46.042326 -131.165092)
		(end 45.554392 -131.165092)
		(width 0.13462)
		(layer "F.Cu")
		(net "P5E_PEX0_STN1_TX_C_DN<28>")
	)
	(segment
		(start 37.22624 -131.002278)
		(end 36.905184 -131.323334)
		(width 0.13462)
		(layer "F.Cu")
		(net "P5E_PEX0_STN1_TX_C_DN<28>")
	)
	(segment
		(start 64.775842 -350.685354)
		(end 64.455802 -350.365314)
		(width 0.13462)
		(layer "F.Cu")
		(net "P5E_PEX0_STN6_TX_C_DP<110>")
	)
	(segment
		(start 64.481202 -351.611438)
		(end 64.775842 -351.316798)
		(width 0.13462)
		(layer "F.Cu")
		(net "P5E_PEX0_STN6_TX_C_DP<110>")
	)
	(segment
		(start 64.775842 -351.316798)
		(end 64.775842 -350.685354)
		(width 0.13462)
		(layer "F.Cu")
		(net "P5E_PEX0_STN6_TX_C_DP<110>")
	)
	(segment
		(start 75.00239 -409.560776)
		(end 75.00239 -396.249652)
		(width 0.1651)
		(layer "In13.Cu")
		(net "P5E_PEX0_STN6_TX_C_DP<110>")
	)
	(segment
		(start 63.217552 -353.972368)
		(end 64.772032 -352.417888)
		(width 0.1651)
		(layer "In13.Cu")
		(net "P5E_PEX0_STN6_TX_C_DP<110>")
	)
	(segment
		(start 74.236834 -409.799028)
		(end 74.764138 -409.799028)
		(width 0.1651)
		(layer "In13.Cu")
		(net "P5E_PEX0_STN6_TX_C_DP<110>")
	)
	(segment
		(start 64.772032 -352.417888)
		(end 64.772032 -351.902268)
		(width 0.1651)
		(layer "In13.Cu")
		(net "P5E_PEX0_STN6_TX_C_DP<110>")
	)
	(segment
		(start 68.096638 -390.592818)
		(end 66.137028 -388.633208)
		(width 0.1651)
		(layer "In13.Cu")
		(net "P5E_PEX0_STN6_TX_C_DP<110>")
	)
	(segment
		(start 64.325754 -384.26009)
		(end 64.325754 -382.142492)
		(width 0.1651)
		(layer "In13.Cu")
		(net "P5E_PEX0_STN6_TX_C_DP<110>")
	)
	(segment
		(start 63.625476 -363.280198)
		(end 63.217552 -359.141014)
		(width 0.1651)
		(layer "In13.Cu")
		(net "P5E_PEX0_STN6_TX_C_DP<110>")
	)
	(segment
		(start 64.325754 -382.142492)
		(end 63.625476 -363.280198)
		(width 0.1651)
		(layer "In13.Cu")
		(net "P5E_PEX0_STN6_TX_C_DP<110>")
	)
	(segment
		(start 63.217552 -359.141014)
		(end 63.217552 -353.972368)
		(width 0.1651)
		(layer "In13.Cu")
		(net "P5E_PEX0_STN6_TX_C_DP<110>")
	)
	(segment
		(start 74.135742 -394.628624)
		(end 68.096638 -390.592818)
		(width 0.1651)
		(layer "In13.Cu")
		(net "P5E_PEX0_STN6_TX_C_DP<110>")
	)
	(segment
		(start 66.137028 -388.633208)
		(end 64.325754 -384.26009)
		(width 0.1651)
		(layer "In13.Cu")
		(net "P5E_PEX0_STN6_TX_C_DP<110>")
	)
	(segment
		(start 75.00239 -396.249652)
		(end 74.135742 -394.628624)
		(width 0.1651)
		(layer "In13.Cu")
		(net "P5E_PEX0_STN6_TX_C_DP<110>")
	)
	(segment
		(start 64.772032 -351.902268)
		(end 64.481202 -351.611438)
		(width 0.1651)
		(layer "In13.Cu")
		(net "P5E_PEX0_STN6_TX_C_DP<110>")
	)
	(segment
		(start 74.764138 -409.799028)
		(end 75.00239 -409.560776)
		(width 0.1651)
		(layer "In13.Cu")
		(net "P5E_PEX0_STN6_TX_C_DP<110>")
	)
	(segment
		(start 74.109834 -409.672028)
		(end 74.236834 -409.799028)
		(width 0.1651)
		(layer "In13.Cu")
		(net "P5E_PEX0_STN6_TX_C_DP<110>")
	)
	(segment
		(start 74.109834 -409.290012)
		(end 74.109834 -409.672028)
		(width 0.1651)
		(layer "In13.Cu")
		(net "P5E_PEX0_STN6_TX_C_DP<110>")
	)
	(segment
		(start 291.704522 -30.353)
		(end 291.41039 -30.058868)
		(width 0.13462)
		(layer "F.Cu")
		(net "P5E_PEX2_STN2_RX_DN<37>")
	)
	(segment
		(start 294.38727 -30.190186)
		(end 294.224456 -30.353)
		(width 0.13462)
		(layer "F.Cu")
		(net "P5E_PEX2_STN2_RX_DN<37>")
	)
	(segment
		(start 294.224456 -30.353)
		(end 291.704522 -30.353)
		(width 0.13462)
		(layer "F.Cu")
		(net "P5E_PEX2_STN2_RX_DN<37>")
	)
	(segment
		(start 294.86479 -30.190186)
		(end 294.38727 -30.190186)
		(width 0.13462)
		(layer "F.Cu")
		(net "P5E_PEX2_STN2_RX_DN<37>")
	)
	(segment
		(start 293.988998 -30.349698)
		(end 291.70122 -30.349698)
		(width 0.1651)
		(layer "In7.Cu")
		(net "P5E_PEX2_STN2_RX_DN<37>")
	)
	(segment
		(start 286.035496 -273.479514)
		(end 285.920942 -273.479514)
		(width 0.1143)
		(layer "In7.Cu")
		(net "P5E_PEX2_STN2_RX_DN<37>")
	)
	(segment
		(start 296.320464 -68.498974)
		(end 296.504868 -50.110644)
		(width 0.1651)
		(layer "In7.Cu")
		(net "P5E_PEX2_STN2_RX_DN<37>")
	)
	(segment
		(start 296.504868 -50.110644)
		(end 295.133522 -39.962328)
		(width 0.1651)
		(layer "In7.Cu")
		(net "P5E_PEX2_STN2_RX_DN<37>")
	)
	(segment
		(start 295.0845 -39.308786)
		(end 295.063164 -37.96284)
		(width 0.1651)
		(layer "In7.Cu")
		(net "P5E_PEX2_STN2_RX_DN<37>")
	)
	(segment
		(start 285.815786 -271.345152)
		(end 285.815786 -266.392152)
		(width 0.1651)
		(layer "In7.Cu")
		(net "P5E_PEX2_STN2_RX_DN<37>")
	)
	(segment
		(start 295.063164 -37.96284)
		(end 295.587928 -35.00755)
		(width 0.1651)
		(layer "In7.Cu")
		(net "P5E_PEX2_STN2_RX_DN<37>")
	)
	(segment
		(start 285.946342 -264.905998)
		(end 296.320464 -68.498974)
		(width 0.1651)
		(layer "In7.Cu")
		(net "P5E_PEX2_STN2_RX_DN<37>")
	)
	(segment
		(start 295.133522 -39.962328)
		(end 295.0845 -39.308786)
		(width 0.1651)
		(layer "In7.Cu")
		(net "P5E_PEX2_STN2_RX_DN<37>")
	)
	(segment
		(start 286.149796 -273.365214)
		(end 286.035496 -273.479514)
		(width 0.1143)
		(layer "In7.Cu")
		(net "P5E_PEX2_STN2_RX_DN<37>")
	)
	(segment
		(start 286.149796 -273.099784)
		(end 286.149796 -273.365214)
		(width 0.1143)
		(layer "In7.Cu")
		(net "P5E_PEX2_STN2_RX_DN<37>")
	)
	(segment
		(start 285.920942 -273.479514)
		(end 285.770066 -273.328638)
		(width 0.1143)
		(layer "In7.Cu")
		(net "P5E_PEX2_STN2_RX_DN<37>")
	)
	(segment
		(start 295.612312 -31.973012)
		(end 293.988998 -30.349698)
		(width 0.1651)
		(layer "In7.Cu")
		(net "P5E_PEX2_STN2_RX_DN<37>")
	)
	(segment
		(start 285.815786 -266.392152)
		(end 285.946342 -264.905998)
		(width 0.1651)
		(layer "In7.Cu")
		(net "P5E_PEX2_STN2_RX_DN<37>")
	)
	(segment
		(start 295.587928 -35.00755)
		(end 295.612312 -31.973012)
		(width 0.1651)
		(layer "In7.Cu")
		(net "P5E_PEX2_STN2_RX_DN<37>")
	)
	(segment
		(start 285.815786 -271.3736)
		(end 285.815786 -271.345152)
		(width 0.1143)
		(layer "In7.Cu")
		(net "P5E_PEX2_STN2_RX_DN<37>")
	)
	(segment
		(start 285.770066 -273.328638)
		(end 285.770066 -271.41932)
		(width 0.1143)
		(layer "In7.Cu")
		(net "P5E_PEX2_STN2_RX_DN<37>")
	)
	(segment
		(start 285.770066 -271.41932)
		(end 285.815786 -271.3736)
		(width 0.1143)
		(layer "In7.Cu")
		(net "P5E_PEX2_STN2_RX_DN<37>")
	)
	(segment
		(start 291.70122 -30.349698)
		(end 291.41039 -30.058868)
		(width 0.1651)
		(layer "In7.Cu")
		(net "P5E_PEX2_STN2_RX_DN<37>")
	)
	(segment
		(start 319.609724 -344.219022)
		(end 319.289684 -344.539062)
		(width 0.13462)
		(layer "F.Cu")
		(net "P5E_PEX2_STN6_TX_C_DN<109>")
	)
	(segment
		(start 319.289684 -345.170506)
		(end 319.584324 -345.465146)
		(width 0.13462)
		(layer "F.Cu")
		(net "P5E_PEX2_STN6_TX_C_DN<109>")
	)
	(segment
		(start 319.289684 -344.539062)
		(end 319.289684 -345.170506)
		(width 0.13462)
		(layer "F.Cu")
		(net "P5E_PEX2_STN6_TX_C_DN<109>")
	)
	(segment
		(start 317.739014 -347.881194)
		(end 319.293494 -346.326714)
		(width 0.1651)
		(layer "In13.Cu")
		(net "P5E_PEX2_STN6_TX_C_DN<109>")
	)
	(segment
		(start 319.293494 -346.326714)
		(end 319.293494 -345.755976)
		(width 0.1651)
		(layer "In13.Cu")
		(net "P5E_PEX2_STN6_TX_C_DN<109>")
	)
	(segment
		(start 334.487012 -392.722354)
		(end 329.84821 -391.061194)
		(width 0.1651)
		(layer "In13.Cu")
		(net "P5E_PEX2_STN6_TX_C_DN<109>")
	)
	(segment
		(start 337.01609 -408.529282)
		(end 337.01609 -394.898372)
		(width 0.1651)
		(layer "In13.Cu")
		(net "P5E_PEX2_STN6_TX_C_DN<109>")
	)
	(segment
		(start 336.671158 -394.399516)
		(end 334.487012 -392.722354)
		(width 0.1651)
		(layer "In13.Cu")
		(net "P5E_PEX2_STN6_TX_C_DN<109>")
	)
	(segment
		(start 319.293494 -345.755976)
		(end 319.584324 -345.465146)
		(width 0.1651)
		(layer "In13.Cu")
		(net "P5E_PEX2_STN6_TX_C_DN<109>")
	)
	(segment
		(start 335.890108 -409.490164)
		(end 335.890108 -409.108148)
		(width 0.1651)
		(layer "In13.Cu")
		(net "P5E_PEX2_STN6_TX_C_DN<109>")
	)
	(segment
		(start 336.017108 -408.981148)
		(end 336.564224 -408.981148)
		(width 0.1651)
		(layer "In13.Cu")
		(net "P5E_PEX2_STN6_TX_C_DN<109>")
	)
	(segment
		(start 326.017382 -387.957822)
		(end 317.739014 -358.90708)
		(width 0.1651)
		(layer "In13.Cu")
		(net "P5E_PEX2_STN6_TX_C_DN<109>")
	)
	(segment
		(start 317.739014 -358.90708)
		(end 317.739014 -347.881194)
		(width 0.1651)
		(layer "In13.Cu")
		(net "P5E_PEX2_STN6_TX_C_DN<109>")
	)
	(segment
		(start 337.01609 -394.898372)
		(end 336.671158 -394.399516)
		(width 0.1651)
		(layer "In13.Cu")
		(net "P5E_PEX2_STN6_TX_C_DN<109>")
	)
	(segment
		(start 329.84821 -391.061194)
		(end 326.017382 -387.957822)
		(width 0.1651)
		(layer "In13.Cu")
		(net "P5E_PEX2_STN6_TX_C_DN<109>")
	)
	(segment
		(start 336.564224 -408.981148)
		(end 337.01609 -408.529282)
		(width 0.1651)
		(layer "In13.Cu")
		(net "P5E_PEX2_STN6_TX_C_DN<109>")
	)
	(segment
		(start 335.890108 -409.108148)
		(end 336.017108 -408.981148)
		(width 0.1651)
		(layer "In13.Cu")
		(net "P5E_PEX2_STN6_TX_C_DN<109>")
	)
	(segment
		(start 387.890766 -158.3944)
		(end 387.30809 -158.3944)
		(width 0.13208)
		(layer "F.Cu")
		(net "NIC6_LD_N")
	)
	(segment
		(start 394.342366 -157.15996)
		(end 392.653012 -157.15996)
		(width 0.13208)
		(layer "F.Cu")
		(net "NIC6_LD_N")
	)
	(segment
		(start 388.487666 -158.9913)
		(end 387.890766 -158.3944)
		(width 0.13208)
		(layer "F.Cu")
		(net "NIC6_LD_N")
	)
	(segment
		(start 390.821672 -158.9913)
		(end 388.487666 -158.9913)
		(width 0.13208)
		(layer "F.Cu")
		(net "NIC6_LD_N")
	)
	(segment
		(start 392.653012 -157.15996)
		(end 390.821672 -158.9913)
		(width 0.13208)
		(layer "F.Cu")
		(net "NIC6_LD_N")
	)
	(via
		(at 388.487666 -158.9913)
		(size 0.762)
		(drill 0.381)
		(layers "F.Cu" "B.Cu")
		(net "NIC6_LD_N")
	)
	(segment
		(start 39.866316 -106.807762)
		(end 45.391578 -106.807762)
		(width 0.13462)
		(layer "F.Cu")
		(net "P5E_PEX0_STN1_TX_C_DP<20>")
	)
	(segment
		(start 45.554392 -106.644948)
		(end 46.042326 -106.644948)
		(width 0.13462)
		(layer "F.Cu")
		(net "P5E_PEX0_STN1_TX_C_DP<20>")
	)
	(segment
		(start 45.391578 -106.807762)
		(end 45.554392 -106.644948)
		(width 0.13462)
		(layer "F.Cu")
		(net "P5E_PEX0_STN1_TX_C_DP<20>")
	)
	(segment
		(start 39.547292 -106.488738)
		(end 39.866316 -106.807762)
		(width 0.13462)
		(layer "F.Cu")
		(net "P5E_PEX0_STN1_TX_C_DP<20>")
	)
	(segment
		(start 80.026002 -345.465146)
		(end 80.320642 -345.170506)
		(width 0.13462)
		(layer "F.Cu")
		(net "P5E_PEX0_STN6_TX_C_DP<103>")
	)
	(segment
		(start 80.320642 -344.539062)
		(end 80.000602 -344.219022)
		(width 0.13462)
		(layer "F.Cu")
		(net "P5E_PEX0_STN6_TX_C_DP<103>")
	)
	(segment
		(start 80.320642 -345.170506)
		(end 80.320642 -344.539062)
		(width 0.13462)
		(layer "F.Cu")
		(net "P5E_PEX0_STN6_TX_C_DP<103>")
	)
	(segment
		(start 76.289916 -362.802932)
		(end 76.045822 -363.233716)
		(width 0.1651)
		(layer "In13.Cu")
		(net "P5E_PEX0_STN6_TX_C_DP<103>")
	)
	(segment
		(start 71.90994 -382.57226)
		(end 71.90994 -382.18999)
		(width 0.1651)
		(layer "In13.Cu")
		(net "P5E_PEX0_STN6_TX_C_DP<103>")
	)
	(segment
		(start 75.680316 -363.698536)
		(end 75.713844 -363.819694)
		(width 0.1651)
		(layer "In13.Cu")
		(net "P5E_PEX0_STN6_TX_C_DP<103>")
	)
	(segment
		(start 80.026002 -345.465146)
		(end 80.316832 -345.755976)
		(width 0.1651)
		(layer "In13.Cu")
		(net "P5E_PEX0_STN6_TX_C_DP<103>")
	)
	(segment
		(start 72.802242 -368.958622)
		(end 72.802242 -382.423924)
		(width 0.1651)
		(layer "In13.Cu")
		(net "P5E_PEX0_STN6_TX_C_DP<103>")
	)
	(segment
		(start 80.316832 -345.755976)
		(end 80.316832 -346.311728)
		(width 0.1651)
		(layer "In13.Cu")
		(net "P5E_PEX0_STN6_TX_C_DP<103>")
	)
	(segment
		(start 76.500736 -362.250482)
		(end 76.256388 -362.681774)
		(width 0.1651)
		(layer "In13.Cu")
		(net "P5E_PEX0_STN6_TX_C_DP<103>")
	)
	(segment
		(start 76.045822 -363.233716)
		(end 75.924664 -363.267244)
		(width 0.1651)
		(layer "In13.Cu")
		(net "P5E_PEX0_STN6_TX_C_DP<103>")
	)
	(segment
		(start 75.46975 -364.250478)
		(end 75.348338 -364.284006)
		(width 0.1651)
		(layer "In13.Cu")
		(net "P5E_PEX0_STN6_TX_C_DP<103>")
	)
	(segment
		(start 75.924664 -363.267244)
		(end 75.680316 -363.698536)
		(width 0.1651)
		(layer "In13.Cu")
		(net "P5E_PEX0_STN6_TX_C_DP<103>")
	)
	(segment
		(start 76.621894 -362.216954)
		(end 76.500736 -362.250482)
		(width 0.1651)
		(layer "In13.Cu")
		(net "P5E_PEX0_STN6_TX_C_DP<103>")
	)
	(segment
		(start 75.137518 -364.836202)
		(end 72.802242 -368.958622)
		(width 0.1651)
		(layer "In13.Cu")
		(net "P5E_PEX0_STN6_TX_C_DP<103>")
	)
	(segment
		(start 75.348338 -364.284006)
		(end 75.10399 -364.715044)
		(width 0.1651)
		(layer "In13.Cu")
		(net "P5E_PEX0_STN6_TX_C_DP<103>")
	)
	(segment
		(start 72.03694 -382.69926)
		(end 71.90994 -382.57226)
		(width 0.1651)
		(layer "In13.Cu")
		(net "P5E_PEX0_STN6_TX_C_DP<103>")
	)
	(segment
		(start 75.10399 -364.715044)
		(end 75.137518 -364.836202)
		(width 0.1651)
		(layer "In13.Cu")
		(net "P5E_PEX0_STN6_TX_C_DP<103>")
	)
	(segment
		(start 78.762352 -358.438196)
		(end 76.621894 -362.216954)
		(width 0.1651)
		(layer "In13.Cu")
		(net "P5E_PEX0_STN6_TX_C_DP<103>")
	)
	(segment
		(start 72.526906 -382.69926)
		(end 72.03694 -382.69926)
		(width 0.1651)
		(layer "In13.Cu")
		(net "P5E_PEX0_STN6_TX_C_DP<103>")
	)
	(segment
		(start 80.316832 -346.311728)
		(end 78.762352 -347.866208)
		(width 0.1651)
		(layer "In13.Cu")
		(net "P5E_PEX0_STN6_TX_C_DP<103>")
	)
	(segment
		(start 75.713844 -363.819694)
		(end 75.46975 -364.250478)
		(width 0.1651)
		(layer "In13.Cu")
		(net "P5E_PEX0_STN6_TX_C_DP<103>")
	)
	(segment
		(start 76.256388 -362.681774)
		(end 76.289916 -362.802932)
		(width 0.1651)
		(layer "In13.Cu")
		(net "P5E_PEX0_STN6_TX_C_DP<103>")
	)
	(segment
		(start 72.802242 -382.423924)
		(end 72.526906 -382.69926)
		(width 0.1651)
		(layer "In13.Cu")
		(net "P5E_PEX0_STN6_TX_C_DP<103>")
	)
	(segment
		(start 78.762352 -347.866208)
		(end 78.762352 -358.438196)
		(width 0.1651)
		(layer "In13.Cu")
		(net "P5E_PEX0_STN6_TX_C_DP<103>")
	)
	(segment
		(start 274.133818 -33.95218)
		(end 273.971766 -33.790128)
		(width 0.13462)
		(layer "F.Cu")
		(net "P5E_PEX2_STN2_TX_C_DN<43>")
	)
	(segment
		(start 273.971766 -33.790128)
		(end 273.464782 -33.790128)
		(width 0.13462)
		(layer "F.Cu")
		(net "P5E_PEX2_STN2_TX_C_DN<43>")
	)
	(segment
		(start 278.367744 -33.631886)
		(end 278.04745 -33.95218)
		(width 0.13462)
		(layer "F.Cu")
		(net "P5E_PEX2_STN2_TX_C_DN<43>")
	)
	(segment
		(start 278.04745 -33.95218)
		(end 274.133818 -33.95218)
		(width 0.13462)
		(layer "F.Cu")
		(net "P5E_PEX2_STN2_TX_C_DN<43>")
	)
	(segment
		(start 308.448456 -334.106012)
		(end 308.44871 -334.106012)
		(width 0.1651)
		(layer "In5.Cu")
		(net "P5E_PEX2_STN6_RX_DN<105>")
	)
	(segment
		(start 281.134312 -316.419992)
		(end 281.020012 -316.534292)
		(width 0.1143)
		(layer "In5.Cu")
		(net "P5E_PEX2_STN6_RX_DN<105>")
	)
	(segment
		(start 345.81592 -400.729196)
		(end 345.364054 -401.181062)
		(width 0.1651)
		(layer "In5.Cu")
		(net "P5E_PEX2_STN6_RX_DN<105>")
	)
	(segment
		(start 293.941246 -327.327768)
		(end 308.448456 -334.106012)
		(width 0.1651)
		(layer "In5.Cu")
		(net "P5E_PEX2_STN6_RX_DN<105>")
	)
	(segment
		(start 327.58634 -376.649488)
		(end 328.240644 -379.885448)
		(width 0.1651)
		(layer "In5.Cu")
		(net "P5E_PEX2_STN6_RX_DN<105>")
	)
	(segment
		(start 344.816938 -401.181062)
		(end 344.689938 -401.308062)
		(width 0.1651)
		(layer "In5.Cu")
		(net "P5E_PEX2_STN6_RX_DN<105>")
	)
	(segment
		(start 345.81592 -394.916406)
		(end 345.81592 -400.729196)
		(width 0.1651)
		(layer "In5.Cu")
		(net "P5E_PEX2_STN6_RX_DN<105>")
	)
	(segment
		(start 281.065732 -319.966848)
		(end 281.065732 -320.97218)
		(width 0.1651)
		(layer "In5.Cu")
		(net "P5E_PEX2_STN6_RX_DN<105>")
	)
	(segment
		(start 323.956934 -358.70007)
		(end 327.58634 -376.648218)
		(width 0.1651)
		(layer "In5.Cu")
		(net "P5E_PEX2_STN6_RX_DN<105>")
	)
	(segment
		(start 329.833224 -385.963414)
		(end 330.138532 -386.416804)
		(width 0.1651)
		(layer "In5.Cu")
		(net "P5E_PEX2_STN6_RX_DN<105>")
	)
	(segment
		(start 293.892224 -327.19264)
		(end 293.941246 -327.327768)
		(width 0.1651)
		(layer "In5.Cu")
		(net "P5E_PEX2_STN6_RX_DN<105>")
	)
	(segment
		(start 335.945734 -389.01751)
		(end 339.55736 -390.7155)
		(width 0.1651)
		(layer "In5.Cu")
		(net "P5E_PEX2_STN6_RX_DN<105>")
	)
	(segment
		(start 281.065732 -319.9384)
		(end 281.065732 -319.966848)
		(width 0.1143)
		(layer "In5.Cu")
		(net "P5E_PEX2_STN6_RX_DN<105>")
	)
	(segment
		(start 292.361366 -326.477376)
		(end 292.810438 -326.687434)
		(width 0.1651)
		(layer "In5.Cu")
		(net "P5E_PEX2_STN6_RX_DN<105>")
	)
	(segment
		(start 345.141804 -394.089636)
		(end 345.578176 -394.458444)
		(width 0.1651)
		(layer "In5.Cu")
		(net "P5E_PEX2_STN6_RX_DN<105>")
	)
	(segment
		(start 292.810438 -326.687434)
		(end 292.85946 -326.822308)
		(width 0.1651)
		(layer "In5.Cu")
		(net "P5E_PEX2_STN6_RX_DN<105>")
	)
	(segment
		(start 339.55736 -390.7155)
		(end 341.95766 -391.93216)
		(width 0.1651)
		(layer "In5.Cu")
		(net "P5E_PEX2_STN6_RX_DN<105>")
	)
	(segment
		(start 328.240644 -379.885702)
		(end 329.10399 -384.155188)
		(width 0.1651)
		(layer "In5.Cu")
		(net "P5E_PEX2_STN6_RX_DN<105>")
	)
	(segment
		(start 281.065732 -320.97218)
		(end 281.299412 -321.420998)
		(width 0.1651)
		(layer "In5.Cu")
		(net "P5E_PEX2_STN6_RX_DN<105>")
	)
	(segment
		(start 345.364054 -401.181062)
		(end 344.816938 -401.181062)
		(width 0.1651)
		(layer "In5.Cu")
		(net "P5E_PEX2_STN6_RX_DN<105>")
	)
	(segment
		(start 330.57592 -386.839968)
		(end 335.945734 -389.01751)
		(width 0.1651)
		(layer "In5.Cu")
		(net "P5E_PEX2_STN6_RX_DN<105>")
	)
	(segment
		(start 345.578176 -394.458444)
		(end 345.81592 -394.916406)
		(width 0.1651)
		(layer "In5.Cu")
		(net "P5E_PEX2_STN6_RX_DN<105>")
	)
	(segment
		(start 329.10399 -384.155188)
		(end 329.833224 -385.963414)
		(width 0.1651)
		(layer "In5.Cu")
		(net "P5E_PEX2_STN6_RX_DN<105>")
	)
	(segment
		(start 308.44871 -334.106012)
		(end 323.001132 -340.905338)
		(width 0.1651)
		(layer "In5.Cu")
		(net "P5E_PEX2_STN6_RX_DN<105>")
	)
	(segment
		(start 281.399742 -316.534292)
		(end 281.285442 -316.419992)
		(width 0.1143)
		(layer "In5.Cu")
		(net "P5E_PEX2_STN6_RX_DN<105>")
	)
	(segment
		(start 292.226492 -326.526398)
		(end 292.361366 -326.477376)
		(width 0.1651)
		(layer "In5.Cu")
		(net "P5E_PEX2_STN6_RX_DN<105>")
	)
	(segment
		(start 344.689938 -401.308062)
		(end 344.689938 -401.690078)
		(width 0.1651)
		(layer "In5.Cu")
		(net "P5E_PEX2_STN6_RX_DN<105>")
	)
	(segment
		(start 293.443152 -326.982836)
		(end 293.892224 -327.19264)
		(width 0.1651)
		(layer "In5.Cu")
		(net "P5E_PEX2_STN6_RX_DN<105>")
	)
	(segment
		(start 330.138532 -386.416804)
		(end 330.57592 -386.839968)
		(width 0.1651)
		(layer "In5.Cu")
		(net "P5E_PEX2_STN6_RX_DN<105>")
	)
	(segment
		(start 323.001132 -340.905338)
		(end 323.956934 -341.86114)
		(width 0.1651)
		(layer "In5.Cu")
		(net "P5E_PEX2_STN6_RX_DN<105>")
	)
	(segment
		(start 281.399742 -316.799722)
		(end 281.399742 -316.534292)
		(width 0.1143)
		(layer "In5.Cu")
		(net "P5E_PEX2_STN6_RX_DN<105>")
	)
	(segment
		(start 328.240644 -379.885448)
		(end 328.240644 -379.885702)
		(width 0.1651)
		(layer "In5.Cu")
		(net "P5E_PEX2_STN6_RX_DN<105>")
	)
	(segment
		(start 292.85946 -326.822308)
		(end 293.308024 -327.031858)
		(width 0.1651)
		(layer "In5.Cu")
		(net "P5E_PEX2_STN6_RX_DN<105>")
	)
	(segment
		(start 323.956934 -341.86114)
		(end 323.956934 -358.70007)
		(width 0.1651)
		(layer "In5.Cu")
		(net "P5E_PEX2_STN6_RX_DN<105>")
	)
	(segment
		(start 341.95766 -391.93216)
		(end 345.141804 -394.089636)
		(width 0.1651)
		(layer "In5.Cu")
		(net "P5E_PEX2_STN6_RX_DN<105>")
	)
	(segment
		(start 281.020012 -316.534292)
		(end 281.020012 -319.89268)
		(width 0.1143)
		(layer "In5.Cu")
		(net "P5E_PEX2_STN6_RX_DN<105>")
	)
	(segment
		(start 327.58634 -376.648218)
		(end 327.58634 -376.649488)
		(width 0.1651)
		(layer "In5.Cu")
		(net "P5E_PEX2_STN6_RX_DN<105>")
	)
	(segment
		(start 281.285442 -316.419992)
		(end 281.134312 -316.419992)
		(width 0.1143)
		(layer "In5.Cu")
		(net "P5E_PEX2_STN6_RX_DN<105>")
	)
	(segment
		(start 281.299412 -321.420998)
		(end 292.226492 -326.526398)
		(width 0.1651)
		(layer "In5.Cu")
		(net "P5E_PEX2_STN6_RX_DN<105>")
	)
	(segment
		(start 293.308024 -327.031858)
		(end 293.443152 -326.982836)
		(width 0.1651)
		(layer "In5.Cu")
		(net "P5E_PEX2_STN6_RX_DN<105>")
	)
	(segment
		(start 281.020012 -319.89268)
		(end 281.065732 -319.9384)
		(width 0.1143)
		(layer "In5.Cu")
		(net "P5E_PEX2_STN6_RX_DN<105>")
	)
	(segment
		(start 390.807194 -142.56512)
		(end 394.342366 -142.56512)
		(width 0.13208)
		(layer "F.Cu")
		(net "NIC6_BIF0_N")
	)
	(segment
		(start 386.854192 -143.401796)
		(end 388.629906 -143.401796)
		(width 0.13208)
		(layer "F.Cu")
		(net "NIC6_BIF0_N")
	)
	(segment
		(start 386.69087 -142.892018)
		(end 386.69087 -143.238474)
		(width 0.13208)
		(layer "F.Cu")
		(net "NIC6_BIF0_N")
	)
	(segment
		(start 386.687822 -142.88897)
		(end 385.704842 -142.88897)
		(width 0.13208)
		(layer "F.Cu")
		(net "NIC6_BIF0_N")
	)
	(segment
		(start 386.69087 -143.238474)
		(end 386.854192 -143.401796)
		(width 0.13208)
		(layer "F.Cu")
		(net "NIC6_BIF0_N")
	)
	(segment
		(start 388.629906 -143.401796)
		(end 388.681468 -143.350234)
		(width 0.13208)
		(layer "F.Cu")
		(net "NIC6_BIF0_N")
	)
	(segment
		(start 388.681468 -143.350234)
		(end 390.02208 -143.350234)
		(width 0.13208)
		(layer "F.Cu")
		(net "NIC6_BIF0_N")
	)
	(segment
		(start 386.69087 -142.892018)
		(end 386.687822 -142.88897)
		(width 0.13208)
		(layer "F.Cu")
		(net "NIC6_BIF0_N")
	)
	(segment
		(start 390.02208 -143.350234)
		(end 390.807194 -142.56512)
		(width 0.13208)
		(layer "F.Cu")
		(net "NIC6_BIF0_N")
	)
	(via
		(at 388.681468 -143.350234)
		(size 0.762)
		(drill 0.381)
		(layers "F.Cu" "B.Cu")
		(net "NIC6_BIF0_N")
	)
	(segment
		(start 45.554392 -132.364988)
		(end 45.391578 -132.527802)
		(width 0.13462)
		(layer "F.Cu")
		(net "P5E_PEX0_STN1_TX_C_DN<29>")
	)
	(segment
		(start 39.859712 -132.527802)
		(end 39.547292 -132.215382)
		(width 0.13462)
		(layer "F.Cu")
		(net "P5E_PEX0_STN1_TX_C_DN<29>")
	)
	(segment
		(start 45.391578 -132.527802)
		(end 39.859712 -132.527802)
		(width 0.13462)
		(layer "F.Cu")
		(net "P5E_PEX0_STN1_TX_C_DN<29>")
	)
	(segment
		(start 46.042326 -132.364988)
		(end 45.554392 -132.364988)
		(width 0.13462)
		(layer "F.Cu")
		(net "P5E_PEX0_STN1_TX_C_DN<29>")
	)
	(segment
		(start 89.921842 -350.685354)
		(end 90.241882 -350.365314)
		(width 0.13462)
		(layer "F.Cu")
		(net "P5E_PEX0_STN6_TX_C_DN<98>")
	)
	(segment
		(start 89.921842 -351.316798)
		(end 89.921842 -350.685354)
		(width 0.13462)
		(layer "F.Cu")
		(net "P5E_PEX0_STN6_TX_C_DN<98>")
	)
	(segment
		(start 90.216482 -351.611438)
		(end 89.921842 -351.316798)
		(width 0.13462)
		(layer "F.Cu")
		(net "P5E_PEX0_STN6_TX_C_DN<98>")
	)
	(segment
		(start 82.909918 -384.590036)
		(end 82.909918 -384.20802)
		(width 0.1651)
		(layer "In13.Cu")
		(net "P5E_PEX0_STN6_TX_C_DN<98>")
	)
	(segment
		(start 89.925652 -351.902268)
		(end 90.216482 -351.611438)
		(width 0.1651)
		(layer "In13.Cu")
		(net "P5E_PEX0_STN6_TX_C_DN<98>")
	)
	(segment
		(start 88.371172 -359.505504)
		(end 88.371172 -354.089208)
		(width 0.1651)
		(layer "In13.Cu")
		(net "P5E_PEX0_STN6_TX_C_DN<98>")
	)
	(segment
		(start 83.681062 -384.08102)
		(end 84.08416 -383.677922)
		(width 0.1651)
		(layer "In13.Cu")
		(net "P5E_PEX0_STN6_TX_C_DN<98>")
	)
	(segment
		(start 84.08416 -368.56924)
		(end 88.371172 -359.505504)
		(width 0.1651)
		(layer "In13.Cu")
		(net "P5E_PEX0_STN6_TX_C_DN<98>")
	)
	(segment
		(start 84.08416 -383.677922)
		(end 84.08416 -368.56924)
		(width 0.1651)
		(layer "In13.Cu")
		(net "P5E_PEX0_STN6_TX_C_DN<98>")
	)
	(segment
		(start 83.036918 -384.08102)
		(end 83.681062 -384.08102)
		(width 0.1651)
		(layer "In13.Cu")
		(net "P5E_PEX0_STN6_TX_C_DN<98>")
	)
	(segment
		(start 82.909918 -384.20802)
		(end 83.036918 -384.08102)
		(width 0.1651)
		(layer "In13.Cu")
		(net "P5E_PEX0_STN6_TX_C_DN<98>")
	)
	(segment
		(start 88.371172 -354.089208)
		(end 89.925652 -352.534728)
		(width 0.1651)
		(layer "In13.Cu")
		(net "P5E_PEX0_STN6_TX_C_DN<98>")
	)
	(segment
		(start 89.925652 -352.534728)
		(end 89.925652 -351.902268)
		(width 0.1651)
		(layer "In13.Cu")
		(net "P5E_PEX0_STN6_TX_C_DN<98>")
	)
	(segment
		(start 327.725532 -31.825184)
		(end 327.414636 -32.13608)
		(width 0.13462)
		(layer "F.Cu")
		(net "P5E_PEX2_STN2_TX_C_DN<34>")
	)
	(segment
		(start 326.113902 -32.13608)
		(end 325.967852 -31.99003)
		(width 0.13462)
		(layer "F.Cu")
		(net "P5E_PEX2_STN2_TX_C_DN<34>")
	)
	(segment
		(start 325.967852 -31.99003)
		(end 325.464678 -31.99003)
		(width 0.13462)
		(layer "F.Cu")
		(net "P5E_PEX2_STN2_TX_C_DN<34>")
	)
	(segment
		(start 327.414636 -32.13608)
		(end 326.113902 -32.13608)
		(width 0.13462)
		(layer "F.Cu")
		(net "P5E_PEX2_STN2_TX_C_DN<34>")
	)
	(segment
		(start 339.230716 -393.571984)
		(end 338.815934 -393.301474)
		(width 0.1651)
		(layer "In5.Cu")
		(net "P5E_PEX2_STN6_RX_DP<107>")
	)
	(segment
		(start 338.710524 -393.323826)
		(end 338.295234 -393.053062)
		(width 0.1651)
		(layer "In5.Cu")
		(net "P5E_PEX2_STN6_RX_DP<107>")
	)
	(segment
		(start 338.295234 -393.053062)
		(end 338.273136 -392.947652)
		(width 0.1651)
		(layer "In5.Cu")
		(net "P5E_PEX2_STN6_RX_DP<107>")
	)
	(segment
		(start 279.499822 -316.115192)
		(end 279.499822 -315.849762)
		(width 0.1143)
		(layer "In5.Cu")
		(net "P5E_PEX2_STN6_RX_DP<107>")
	)
	(segment
		(start 278.929592 -319.96888)
		(end 278.929592 -316.455298)
		(width 0.1143)
		(layer "In5.Cu")
		(net "P5E_PEX2_STN6_RX_DP<107>")
	)
	(segment
		(start 339.252814 -393.677394)
		(end 339.230716 -393.571984)
		(width 0.1651)
		(layer "In5.Cu")
		(net "P5E_PEX2_STN6_RX_DP<107>")
	)
	(segment
		(start 337.315556 -392.32332)
		(end 336.900774 -392.05281)
		(width 0.1651)
		(layer "In5.Cu")
		(net "P5E_PEX2_STN6_RX_DP<107>")
	)
	(segment
		(start 338.815934 -393.301474)
		(end 338.710524 -393.323826)
		(width 0.1651)
		(layer "In5.Cu")
		(net "P5E_PEX2_STN6_RX_DP<107>")
	)
	(segment
		(start 280.205434 -323.442076)
		(end 279.280366 -322.788026)
		(width 0.1651)
		(layer "In5.Cu")
		(net "P5E_PEX2_STN6_RX_DP<107>")
	)
	(segment
		(start 340.29015 -400.390106)
		(end 340.29015 -400.772122)
		(width 0.1651)
		(layer "In5.Cu")
		(net "P5E_PEX2_STN6_RX_DP<107>")
	)
	(segment
		(start 278.883872 -321.827144)
		(end 278.883872 -320.043048)
		(width 0.1651)
		(layer "In5.Cu")
		(net "P5E_PEX2_STN6_RX_DP<107>")
	)
	(segment
		(start 316.850522 -341.333328)
		(end 313.048396 -339.104732)
		(width 0.1651)
		(layer "In5.Cu")
		(net "P5E_PEX2_STN6_RX_DP<107>")
	)
	(segment
		(start 340.847426 -400.899122)
		(end 341.134192 -400.612356)
		(width 0.1651)
		(layer "In5.Cu")
		(net "P5E_PEX2_STN6_RX_DP<107>")
	)
	(segment
		(start 329.210162 -388.66064)
		(end 328.204576 -387.64718)
		(width 0.1651)
		(layer "In5.Cu")
		(net "P5E_PEX2_STN6_RX_DP<107>")
	)
	(segment
		(start 313.048396 -339.104732)
		(end 280.205434 -323.442076)
		(width 0.1651)
		(layer "In5.Cu")
		(net "P5E_PEX2_STN6_RX_DP<107>")
	)
	(segment
		(start 279.155398 -316.229492)
		(end 279.385522 -316.229492)
		(width 0.1143)
		(layer "In5.Cu")
		(net "P5E_PEX2_STN6_RX_DP<107>")
	)
	(segment
		(start 328.204576 -387.64718)
		(end 327.743312 -386.700522)
		(width 0.1651)
		(layer "In5.Cu")
		(net "P5E_PEX2_STN6_RX_DP<107>")
	)
	(segment
		(start 339.668104 -393.948158)
		(end 339.252814 -393.677394)
		(width 0.1651)
		(layer "In5.Cu")
		(net "P5E_PEX2_STN6_RX_DP<107>")
	)
	(segment
		(start 324.620636 -378.369068)
		(end 324.453758 -377.902978)
		(width 0.1651)
		(layer "In5.Cu")
		(net "P5E_PEX2_STN6_RX_DP<107>")
	)
	(segment
		(start 324.156832 -377.374912)
		(end 324.218046 -377.244864)
		(width 0.1651)
		(layer "In5.Cu")
		(net "P5E_PEX2_STN6_RX_DP<107>")
	)
	(segment
		(start 278.883872 -320.0146)
		(end 278.929592 -319.96888)
		(width 0.1143)
		(layer "In5.Cu")
		(net "P5E_PEX2_STN6_RX_DP<107>")
	)
	(segment
		(start 324.856094 -379.026928)
		(end 324.726046 -378.96546)
		(width 0.1651)
		(layer "In5.Cu")
		(net "P5E_PEX2_STN6_RX_DP<107>")
	)
	(segment
		(start 338.273136 -392.947652)
		(end 337.858354 -392.677142)
		(width 0.1651)
		(layer "In5.Cu")
		(net "P5E_PEX2_STN6_RX_DP<107>")
	)
	(segment
		(start 340.97595 -394.848842)
		(end 340.648036 -394.496036)
		(width 0.1651)
		(layer "In5.Cu")
		(net "P5E_PEX2_STN6_RX_DP<107>")
	)
	(segment
		(start 324.559168 -378.498862)
		(end 324.620636 -378.369068)
		(width 0.1651)
		(layer "In5.Cu")
		(net "P5E_PEX2_STN6_RX_DP<107>")
	)
	(segment
		(start 336.900774 -392.05281)
		(end 335.513426 -391.262362)
		(width 0.1651)
		(layer "In5.Cu")
		(net "P5E_PEX2_STN6_RX_DP<107>")
	)
	(segment
		(start 337.858354 -392.677142)
		(end 337.752944 -392.699494)
		(width 0.1651)
		(layer "In5.Cu")
		(net "P5E_PEX2_STN6_RX_DP<107>")
	)
	(segment
		(start 327.743312 -386.700522)
		(end 326.806306 -384.474466)
		(width 0.1651)
		(layer "In5.Cu")
		(net "P5E_PEX2_STN6_RX_DP<107>")
	)
	(segment
		(start 340.29015 -400.772122)
		(end 340.41715 -400.899122)
		(width 0.1651)
		(layer "In5.Cu")
		(net "P5E_PEX2_STN6_RX_DP<107>")
	)
	(segment
		(start 324.32371 -377.84151)
		(end 324.156832 -377.374912)
		(width 0.1651)
		(layer "In5.Cu")
		(net "P5E_PEX2_STN6_RX_DP<107>")
	)
	(segment
		(start 337.752944 -392.699494)
		(end 337.337654 -392.42873)
		(width 0.1651)
		(layer "In5.Cu")
		(net "P5E_PEX2_STN6_RX_DP<107>")
	)
	(segment
		(start 324.726046 -378.96546)
		(end 324.559168 -378.498862)
		(width 0.1651)
		(layer "In5.Cu")
		(net "P5E_PEX2_STN6_RX_DP<107>")
	)
	(segment
		(start 317.457074 -341.93988)
		(end 316.850522 -341.333328)
		(width 0.1651)
		(layer "In5.Cu")
		(net "P5E_PEX2_STN6_RX_DP<107>")
	)
	(segment
		(start 326.806306 -384.474466)
		(end 324.856348 -379.02769)
		(width 0.1651)
		(layer "In5.Cu")
		(net "P5E_PEX2_STN6_RX_DP<107>")
	)
	(segment
		(start 340.648036 -394.496036)
		(end 339.773514 -393.925806)
		(width 0.1651)
		(layer "In5.Cu")
		(net "P5E_PEX2_STN6_RX_DP<107>")
	)
	(segment
		(start 279.385522 -316.229492)
		(end 279.499822 -316.115192)
		(width 0.1143)
		(layer "In5.Cu")
		(net "P5E_PEX2_STN6_RX_DP<107>")
	)
	(segment
		(start 341.134192 -395.246352)
		(end 340.97595 -394.848842)
		(width 0.1651)
		(layer "In5.Cu")
		(net "P5E_PEX2_STN6_RX_DP<107>")
	)
	(segment
		(start 324.218046 -377.244864)
		(end 317.457074 -358.358186)
		(width 0.1651)
		(layer "In5.Cu")
		(net "P5E_PEX2_STN6_RX_DP<107>")
	)
	(segment
		(start 339.773514 -393.925806)
		(end 339.668104 -393.948158)
		(width 0.1651)
		(layer "In5.Cu")
		(net "P5E_PEX2_STN6_RX_DP<107>")
	)
	(segment
		(start 278.883872 -320.043048)
		(end 278.883872 -320.0146)
		(width 0.1143)
		(layer "In5.Cu")
		(net "P5E_PEX2_STN6_RX_DP<107>")
	)
	(segment
		(start 278.929592 -316.455298)
		(end 279.155398 -316.229492)
		(width 0.1143)
		(layer "In5.Cu")
		(net "P5E_PEX2_STN6_RX_DP<107>")
	)
	(segment
		(start 335.513426 -391.262362)
		(end 329.210162 -388.66064)
		(width 0.1651)
		(layer "In5.Cu")
		(net "P5E_PEX2_STN6_RX_DP<107>")
	)
	(segment
		(start 337.337654 -392.42873)
		(end 337.315556 -392.32332)
		(width 0.1651)
		(layer "In5.Cu")
		(net "P5E_PEX2_STN6_RX_DP<107>")
	)
	(segment
		(start 340.41715 -400.899122)
		(end 340.847426 -400.899122)
		(width 0.1651)
		(layer "In5.Cu")
		(net "P5E_PEX2_STN6_RX_DP<107>")
	)
	(segment
		(start 324.453758 -377.902978)
		(end 324.32371 -377.84151)
		(width 0.1651)
		(layer "In5.Cu")
		(net "P5E_PEX2_STN6_RX_DP<107>")
	)
	(segment
		(start 341.134192 -400.612356)
		(end 341.134192 -395.246352)
		(width 0.1651)
		(layer "In5.Cu")
		(net "P5E_PEX2_STN6_RX_DP<107>")
	)
	(segment
		(start 317.457074 -358.358186)
		(end 317.457074 -341.93988)
		(width 0.1651)
		(layer "In5.Cu")
		(net "P5E_PEX2_STN6_RX_DP<107>")
	)
	(segment
		(start 279.280366 -322.788026)
		(end 278.883872 -321.827144)
		(width 0.1651)
		(layer "In5.Cu")
		(net "P5E_PEX2_STN6_RX_DP<107>")
	)
	(segment
		(start 324.856348 -379.02769)
		(end 324.856094 -379.026928)
		(width 0.1651)
		(layer "In5.Cu")
		(net "P5E_PEX2_STN6_RX_DP<107>")
	)
	(segment
		(start 398.94256 -155.960064)
		(end 399.70837 -155.960064)
		(width 0.13208)
		(layer "F.Cu")
		(net "NIC6_RBT_ARB_OUT")
	)
	(segment
		(start 400.030442 -156.282136)
		(end 401.147534 -156.282136)
		(width 0.13208)
		(layer "F.Cu")
		(net "NIC6_RBT_ARB_OUT")
	)
	(segment
		(start 401.147534 -156.282136)
		(end 401.409916 -156.544518)
		(width 0.13208)
		(layer "F.Cu")
		(net "NIC6_RBT_ARB_OUT")
	)
	(segment
		(start 399.70837 -155.960064)
		(end 400.030442 -156.282136)
		(width 0.13208)
		(layer "F.Cu")
		(net "NIC6_RBT_ARB_OUT")
	)
	(via
		(at 401.409916 -156.544518)
		(size 0.508)
		(drill 0.254)
		(layers "F.Cu" "B.Cu")
		(net "NIC6_RBT_ARB_OUT")
	)
	(segment
		(start 397.45539 -157.0736)
		(end 397.45539 -156.718)
		(width 0.13208)
		(layer "B.Cu")
		(net "NIC6_RBT_ARB_OUT")
	)
	(segment
		(start 399.154904 -156.282136)
		(end 401.147534 -156.282136)
		(width 0.13208)
		(layer "B.Cu")
		(net "NIC6_RBT_ARB_OUT")
	)
	(segment
		(start 397.45539 -156.718)
		(end 397.58239 -156.591)
		(width 0.13208)
		(layer "B.Cu")
		(net "NIC6_RBT_ARB_OUT")
	)
	(segment
		(start 398.84604 -156.591)
		(end 399.154904 -156.282136)
		(width 0.13208)
		(layer "B.Cu")
		(net "NIC6_RBT_ARB_OUT")
	)
	(segment
		(start 397.58239 -156.591)
		(end 398.84604 -156.591)
		(width 0.13208)
		(layer "B.Cu")
		(net "NIC6_RBT_ARB_OUT")
	)
	(segment
		(start 401.147534 -156.282136)
		(end 401.409916 -156.544518)
		(width 0.13208)
		(layer "B.Cu")
		(net "NIC6_RBT_ARB_OUT")
	)
	(segment
		(start 51.947826 -112.207802)
		(end 52.24272 -111.912908)
		(width 0.13462)
		(layer "F.Cu")
		(net "P5E_PEX0_STN1_RX_DP<23>")
	)
	(segment
		(start 50.64252 -112.044988)
		(end 51.130454 -112.044988)
		(width 0.13462)
		(layer "F.Cu")
		(net "P5E_PEX0_STN1_RX_DP<23>")
	)
	(segment
		(start 51.130454 -112.044988)
		(end 51.293268 -112.207802)
		(width 0.13462)
		(layer "F.Cu")
		(net "P5E_PEX0_STN1_RX_DP<23>")
	)
	(segment
		(start 51.293268 -112.207802)
		(end 51.947826 -112.207802)
		(width 0.13462)
		(layer "F.Cu")
		(net "P5E_PEX0_STN1_RX_DP<23>")
	)
	(segment
		(start 65.683892 -271.802352)
		(end 65.729612 -271.848072)
		(width 0.1143)
		(layer "In5.Cu")
		(net "P5E_PEX0_STN1_RX_DP<23>")
	)
	(segment
		(start 43.09364 -120.951244)
		(end 41.445688 -128.369314)
		(width 0.1651)
		(layer "In5.Cu")
		(net "P5E_PEX0_STN1_RX_DP<23>")
	)
	(segment
		(start 65.683892 -268.60881)
		(end 65.683892 -271.773904)
		(width 0.1651)
		(layer "In5.Cu")
		(net "P5E_PEX0_STN1_RX_DP<23>")
	)
	(segment
		(start 65.944496 -275.570188)
		(end 66.185288 -275.570188)
		(width 0.1143)
		(layer "In5.Cu")
		(net "P5E_PEX0_STN1_RX_DP<23>")
	)
	(segment
		(start 41.445688 -128.369314)
		(end 39.982648 -137.393934)
		(width 0.1651)
		(layer "In5.Cu")
		(net "P5E_PEX0_STN1_RX_DP<23>")
	)
	(segment
		(start 65.729612 -271.848072)
		(end 65.729612 -275.355304)
		(width 0.1143)
		(layer "In5.Cu")
		(net "P5E_PEX0_STN1_RX_DP<23>")
	)
	(segment
		(start 51.95189 -112.203738)
		(end 51.266344 -112.203738)
		(width 0.1651)
		(layer "In5.Cu")
		(net "P5E_PEX0_STN1_RX_DP<23>")
	)
	(segment
		(start 46.61789 -114.322606)
		(end 46.61789 -114.32286)
		(width 0.1651)
		(layer "In5.Cu")
		(net "P5E_PEX0_STN1_RX_DP<23>")
	)
	(segment
		(start 47.01794 -113.941098)
		(end 46.61789 -114.322606)
		(width 0.1651)
		(layer "In5.Cu")
		(net "P5E_PEX0_STN1_RX_DP<23>")
	)
	(segment
		(start 36.205668 -145.064734)
		(end 35.64255 -148.135594)
		(width 0.1651)
		(layer "In5.Cu")
		(net "P5E_PEX0_STN1_RX_DP<23>")
	)
	(segment
		(start 46.217586 -114.704622)
		(end 45.490892 -116.26723)
		(width 0.1651)
		(layer "In5.Cu")
		(net "P5E_PEX0_STN1_RX_DP<23>")
	)
	(segment
		(start 35.54349 -158.33471)
		(end 36.53028 -164.093144)
		(width 0.1651)
		(layer "In5.Cu")
		(net "P5E_PEX0_STN1_RX_DP<23>")
	)
	(segment
		(start 45.490892 -116.26723)
		(end 44.83989 -117.197378)
		(width 0.1651)
		(layer "In5.Cu")
		(net "P5E_PEX0_STN1_RX_DP<23>")
	)
	(segment
		(start 65.729612 -275.355304)
		(end 65.944496 -275.570188)
		(width 0.1143)
		(layer "In5.Cu")
		(net "P5E_PEX0_STN1_RX_DP<23>")
	)
	(segment
		(start 66.299588 -275.684488)
		(end 66.299588 -275.949918)
		(width 0.1143)
		(layer "In5.Cu")
		(net "P5E_PEX0_STN1_RX_DP<23>")
	)
	(segment
		(start 36.53028 -164.093144)
		(end 65.683892 -268.60881)
		(width 0.1651)
		(layer "In5.Cu")
		(net "P5E_PEX0_STN1_RX_DP<23>")
	)
	(segment
		(start 51.266344 -112.203738)
		(end 47.01794 -113.941098)
		(width 0.1651)
		(layer "In5.Cu")
		(net "P5E_PEX0_STN1_RX_DP<23>")
	)
	(segment
		(start 35.078924 -151.208994)
		(end 35.311842 -154.781758)
		(width 0.1651)
		(layer "In5.Cu")
		(net "P5E_PEX0_STN1_RX_DP<23>")
	)
	(segment
		(start 35.64255 -148.135848)
		(end 35.078924 -151.208994)
		(width 0.1651)
		(layer "In5.Cu")
		(net "P5E_PEX0_STN1_RX_DP<23>")
	)
	(segment
		(start 66.185288 -275.570188)
		(end 66.299588 -275.684488)
		(width 0.1143)
		(layer "In5.Cu")
		(net "P5E_PEX0_STN1_RX_DP<23>")
	)
	(segment
		(start 39.982648 -137.393934)
		(end 37.992812 -140.990066)
		(width 0.1651)
		(layer "In5.Cu")
		(net "P5E_PEX0_STN1_RX_DP<23>")
	)
	(segment
		(start 65.683892 -271.773904)
		(end 65.683892 -271.802352)
		(width 0.1143)
		(layer "In5.Cu")
		(net "P5E_PEX0_STN1_RX_DP<23>")
	)
	(segment
		(start 37.992812 -140.990066)
		(end 36.205668 -145.064734)
		(width 0.1651)
		(layer "In5.Cu")
		(net "P5E_PEX0_STN1_RX_DP<23>")
	)
	(segment
		(start 44.83989 -117.197378)
		(end 43.09364 -120.951244)
		(width 0.1651)
		(layer "In5.Cu")
		(net "P5E_PEX0_STN1_RX_DP<23>")
	)
	(segment
		(start 35.64255 -148.135594)
		(end 35.64255 -148.135848)
		(width 0.1651)
		(layer "In5.Cu")
		(net "P5E_PEX0_STN1_RX_DP<23>")
	)
	(segment
		(start 52.24272 -111.912908)
		(end 51.95189 -112.203738)
		(width 0.1651)
		(layer "In5.Cu")
		(net "P5E_PEX0_STN1_RX_DP<23>")
	)
	(segment
		(start 46.61789 -114.32286)
		(end 46.217586 -114.704622)
		(width 0.1651)
		(layer "In5.Cu")
		(net "P5E_PEX0_STN1_RX_DP<23>")
	)
	(segment
		(start 35.311842 -154.781758)
		(end 35.54349 -158.33471)
		(width 0.1651)
		(layer "In5.Cu")
		(net "P5E_PEX0_STN1_RX_DP<23>")
	)
	(segment
		(start 268.224508 -33.952942)
		(end 265.704574 -33.952942)
		(width 0.13462)
		(layer "F.Cu")
		(net "P5E_PEX2_STN2_RX_DN<43>")
	)
	(segment
		(start 268.387322 -33.790128)
		(end 268.224508 -33.952942)
		(width 0.13462)
		(layer "F.Cu")
		(net "P5E_PEX2_STN2_RX_DN<43>")
	)
	(segment
		(start 265.704574 -33.952942)
		(end 265.410442 -33.65881)
		(width 0.13462)
		(layer "F.Cu")
		(net "P5E_PEX2_STN2_RX_DN<43>")
	)
	(segment
		(start 268.864842 -33.790128)
		(end 268.387322 -33.790128)
		(width 0.13462)
		(layer "F.Cu")
		(net "P5E_PEX2_STN2_RX_DN<43>")
	)
	(segment
		(start 272.408142 -119.592598)
		(end 271.9705 -105.13822)
		(width 0.1651)
		(layer "In7.Cu")
		(net "P5E_PEX2_STN2_RX_DN<43>")
	)
	(segment
		(start 267.088112 -34.98596)
		(end 266.051792 -33.94964)
		(width 0.1651)
		(layer "In7.Cu")
		(net "P5E_PEX2_STN2_RX_DN<43>")
	)
	(segment
		(start 279.657302 -263.216136)
		(end 279.657302 -262.822944)
		(width 0.1651)
		(layer "In7.Cu")
		(net "P5E_PEX2_STN2_RX_DN<43>")
	)
	(segment
		(start 279.934924 -248.471436)
		(end 271.535652 -141.670024)
		(width 0.1651)
		(layer "In7.Cu")
		(net "P5E_PEX2_STN2_RX_DN<43>")
	)
	(segment
		(start 265.701272 -33.94964)
		(end 265.410442 -33.65881)
		(width 0.1651)
		(layer "In7.Cu")
		(net "P5E_PEX2_STN2_RX_DN<43>")
	)
	(segment
		(start 267.088112 -35.355276)
		(end 267.088112 -34.98596)
		(width 0.1651)
		(layer "In7.Cu")
		(net "P5E_PEX2_STN2_RX_DN<43>")
	)
	(segment
		(start 266.051792 -33.94964)
		(end 265.701272 -33.94964)
		(width 0.1651)
		(layer "In7.Cu")
		(net "P5E_PEX2_STN2_RX_DN<43>")
	)
	(segment
		(start 280.449782 -273.099784)
		(end 280.449782 -273.365214)
		(width 0.1143)
		(layer "In7.Cu")
		(net "P5E_PEX2_STN2_RX_DN<43>")
	)
	(segment
		(start 271.569434 -138.51128)
		(end 272.274538 -131.985766)
		(width 0.1651)
		(layer "In7.Cu")
		(net "P5E_PEX2_STN2_RX_DN<43>")
	)
	(segment
		(start 280.115772 -271.3736)
		(end 280.115772 -271.345152)
		(width 0.1143)
		(layer "In7.Cu")
		(net "P5E_PEX2_STN2_RX_DN<43>")
	)
	(segment
		(start 280.220928 -273.479514)
		(end 280.070052 -273.328638)
		(width 0.1143)
		(layer "In7.Cu")
		(net "P5E_PEX2_STN2_RX_DN<43>")
	)
	(segment
		(start 267.156438 -39.76497)
		(end 267.088112 -35.355276)
		(width 0.1651)
		(layer "In7.Cu")
		(net "P5E_PEX2_STN2_RX_DN<43>")
	)
	(segment
		(start 271.535652 -141.670024)
		(end 271.569434 -138.51128)
		(width 0.1651)
		(layer "In7.Cu")
		(net "P5E_PEX2_STN2_RX_DN<43>")
	)
	(segment
		(start 268.768322 -65.250314)
		(end 268.377162 -55.479696)
		(width 0.1651)
		(layer "In7.Cu")
		(net "P5E_PEX2_STN2_RX_DN<43>")
	)
	(segment
		(start 279.657302 -262.822944)
		(end 279.934924 -248.471436)
		(width 0.1651)
		(layer "In7.Cu")
		(net "P5E_PEX2_STN2_RX_DN<43>")
	)
	(segment
		(start 280.070052 -273.328638)
		(end 280.070052 -271.41932)
		(width 0.1143)
		(layer "In7.Cu")
		(net "P5E_PEX2_STN2_RX_DN<43>")
	)
	(segment
		(start 280.115772 -267.871956)
		(end 279.657302 -263.216136)
		(width 0.1651)
		(layer "In7.Cu")
		(net "P5E_PEX2_STN2_RX_DN<43>")
	)
	(segment
		(start 271.9705 -105.13822)
		(end 268.768322 -65.250314)
		(width 0.1651)
		(layer "In7.Cu")
		(net "P5E_PEX2_STN2_RX_DN<43>")
	)
	(segment
		(start 280.115772 -271.345152)
		(end 280.115772 -267.871956)
		(width 0.1651)
		(layer "In7.Cu")
		(net "P5E_PEX2_STN2_RX_DN<43>")
	)
	(segment
		(start 280.449782 -273.365214)
		(end 280.335482 -273.479514)
		(width 0.1143)
		(layer "In7.Cu")
		(net "P5E_PEX2_STN2_RX_DN<43>")
	)
	(segment
		(start 280.070052 -271.41932)
		(end 280.115772 -271.3736)
		(width 0.1143)
		(layer "In7.Cu")
		(net "P5E_PEX2_STN2_RX_DN<43>")
	)
	(segment
		(start 268.377162 -55.479696)
		(end 268.470888 -49.492662)
		(width 0.1651)
		(layer "In7.Cu")
		(net "P5E_PEX2_STN2_RX_DN<43>")
	)
	(segment
		(start 272.274538 -131.985766)
		(end 272.408142 -119.592598)
		(width 0.1651)
		(layer "In7.Cu")
		(net "P5E_PEX2_STN2_RX_DN<43>")
	)
	(segment
		(start 280.335482 -273.479514)
		(end 280.220928 -273.479514)
		(width 0.1143)
		(layer "In7.Cu")
		(net "P5E_PEX2_STN2_RX_DN<43>")
	)
	(segment
		(start 268.470888 -49.492662)
		(end 267.156438 -39.76497)
		(width 0.1651)
		(layer "In7.Cu")
		(net "P5E_PEX2_STN2_RX_DN<43>")
	)
	(segment
		(start 325.507604 -356.831646)
		(end 325.507604 -357.46309)
		(width 0.13462)
		(layer "F.Cu")
		(net "P5E_PEX2_STN6_TX_C_DN<105>")
	)
	(segment
		(start 325.507604 -357.46309)
		(end 325.802244 -357.75773)
		(width 0.13462)
		(layer "F.Cu")
		(net "P5E_PEX2_STN6_TX_C_DN<105>")
	)
	(segment
		(start 325.827644 -356.511606)
		(end 325.507604 -356.831646)
		(width 0.13462)
		(layer "F.Cu")
		(net "P5E_PEX2_STN6_TX_C_DN<105>")
	)
	(segment
		(start 345.81592 -395.460982)
		(end 345.590876 -394.737336)
		(width 0.1651)
		(layer "In13.Cu")
		(net "P5E_PEX2_STN6_TX_C_DN<105>")
	)
	(segment
		(start 325.511414 -358.04856)
		(end 325.802244 -357.75773)
		(width 0.1651)
		(layer "In13.Cu")
		(net "P5E_PEX2_STN6_TX_C_DN<105>")
	)
	(segment
		(start 329.545188 -385.686808)
		(end 325.511668 -358.92994)
		(width 0.1651)
		(layer "In13.Cu")
		(net "P5E_PEX2_STN6_TX_C_DN<105>")
	)
	(segment
		(start 344.689938 -409.490164)
		(end 344.689938 -409.108148)
		(width 0.1651)
		(layer "In13.Cu")
		(net "P5E_PEX2_STN6_TX_C_DN<105>")
	)
	(segment
		(start 325.511668 -358.92994)
		(end 325.511414 -358.929686)
		(width 0.1651)
		(layer "In13.Cu")
		(net "P5E_PEX2_STN6_TX_C_DN<105>")
	)
	(segment
		(start 345.364054 -408.981148)
		(end 345.81592 -408.529282)
		(width 0.1651)
		(layer "In13.Cu")
		(net "P5E_PEX2_STN6_TX_C_DN<105>")
	)
	(segment
		(start 345.196668 -394.213842)
		(end 338.071714 -389.53694)
		(width 0.1651)
		(layer "In13.Cu")
		(net "P5E_PEX2_STN6_TX_C_DN<105>")
	)
	(segment
		(start 344.816938 -408.981148)
		(end 345.364054 -408.981148)
		(width 0.1651)
		(layer "In13.Cu")
		(net "P5E_PEX2_STN6_TX_C_DN<105>")
	)
	(segment
		(start 331.451458 -387.20141)
		(end 329.545188 -385.686808)
		(width 0.1651)
		(layer "In13.Cu")
		(net "P5E_PEX2_STN6_TX_C_DN<105>")
	)
	(segment
		(start 345.81592 -408.529282)
		(end 345.81592 -395.460982)
		(width 0.1651)
		(layer "In13.Cu")
		(net "P5E_PEX2_STN6_TX_C_DN<105>")
	)
	(segment
		(start 345.590876 -394.737336)
		(end 345.196668 -394.213842)
		(width 0.1651)
		(layer "In13.Cu")
		(net "P5E_PEX2_STN6_TX_C_DN<105>")
	)
	(segment
		(start 344.689938 -409.108148)
		(end 344.816938 -408.981148)
		(width 0.1651)
		(layer "In13.Cu")
		(net "P5E_PEX2_STN6_TX_C_DN<105>")
	)
	(segment
		(start 325.511414 -358.929686)
		(end 325.511414 -358.04856)
		(width 0.1651)
		(layer "In13.Cu")
		(net "P5E_PEX2_STN6_TX_C_DN<105>")
	)
	(segment
		(start 338.071714 -389.53694)
		(end 331.451458 -387.20141)
		(width 0.1651)
		(layer "In13.Cu")
		(net "P5E_PEX2_STN6_TX_C_DN<105>")
	)
	(segment
		(start 393.69111 -112.19688)
		(end 393.843002 -112.044988)
		(width 0.13462)
		(layer "F.Cu")
		(net "P5E_PEX3_STN1_TX_C_DN<23>")
	)
	(segment
		(start 385.205224 -111.895382)
		(end 385.506722 -112.19688)
		(width 0.13462)
		(layer "F.Cu")
		(net "P5E_PEX3_STN1_TX_C_DN<23>")
	)
	(segment
		(start 385.506722 -112.19688)
		(end 393.69111 -112.19688)
		(width 0.13462)
		(layer "F.Cu")
		(net "P5E_PEX3_STN1_TX_C_DN<23>")
	)
	(segment
		(start 393.843002 -112.044988)
		(end 394.342366 -112.044988)
		(width 0.13462)
		(layer "F.Cu")
		(net "P5E_PEX3_STN1_TX_C_DN<23>")
	)
	(segment
		(start 387.299962 -154.327352)
		(end 387.299962 -153.322528)
		(width 0.13208)
		(layer "F.Cu")
		(net "NIC6_SLOT_ID0")
	)
	(segment
		(start 388.48792 -153.97226)
		(end 390.44372 -153.97226)
		(width 0.13208)
		(layer "F.Cu")
		(net "NIC6_SLOT_ID0")
	)
	(segment
		(start 387.30809 -153.3144)
		(end 387.83006 -153.3144)
		(width 0.13208)
		(layer "F.Cu")
		(net "NIC6_SLOT_ID0")
	)
	(segment
		(start 387.299962 -153.322528)
		(end 387.30809 -153.3144)
		(width 0.13208)
		(layer "F.Cu")
		(net "NIC6_SLOT_ID0")
	)
	(segment
		(start 391.231374 -154.759914)
		(end 394.342366 -154.759914)
		(width 0.13208)
		(layer "F.Cu")
		(net "NIC6_SLOT_ID0")
	)
	(segment
		(start 387.83006 -153.3144)
		(end 388.48792 -153.97226)
		(width 0.13208)
		(layer "F.Cu")
		(net "NIC6_SLOT_ID0")
	)
	(segment
		(start 390.44372 -153.97226)
		(end 391.231374 -154.759914)
		(width 0.13208)
		(layer "F.Cu")
		(net "NIC6_SLOT_ID0")
	)
	(via
		(at 388.48792 -153.97226)
		(size 0.762)
		(drill 0.381)
		(layers "F.Cu" "B.Cu")
		(net "NIC6_SLOT_ID0")
	)
	(segment
		(start 37.232844 -108.88218)
		(end 45.391578 -108.88218)
		(width 0.13462)
		(layer "F.Cu")
		(net "P5E_PEX0_STN1_TX_C_DP<21>")
	)
	(segment
		(start 36.905184 -109.20984)
		(end 37.232844 -108.88218)
		(width 0.13462)
		(layer "F.Cu")
		(net "P5E_PEX0_STN1_TX_C_DP<21>")
	)
	(segment
		(start 45.391578 -108.88218)
		(end 45.554392 -109.044994)
		(width 0.13462)
		(layer "F.Cu")
		(net "P5E_PEX0_STN1_TX_C_DP<21>")
	)
	(segment
		(start 45.554392 -109.044994)
		(end 46.042326 -109.044994)
		(width 0.13462)
		(layer "F.Cu")
		(net "P5E_PEX0_STN1_TX_C_DP<21>")
	)
	(segment
		(start 83.703922 -351.316798)
		(end 83.703922 -350.685354)
		(width 0.13462)
		(layer "F.Cu")
		(net "P5E_PEX0_STN6_TX_C_DN<101>")
	)
	(segment
		(start 83.703922 -350.685354)
		(end 84.023962 -350.365314)
		(width 0.13462)
		(layer "F.Cu")
		(net "P5E_PEX0_STN6_TX_C_DN<101>")
	)
	(segment
		(start 83.998562 -351.611438)
		(end 83.703922 -351.316798)
		(width 0.13462)
		(layer "F.Cu")
		(net "P5E_PEX0_STN6_TX_C_DN<101>")
	)
	(segment
		(start 83.707732 -352.534728)
		(end 83.707732 -351.902268)
		(width 0.1651)
		(layer "In13.Cu")
		(net "P5E_PEX0_STN6_TX_C_DN<101>")
	)
	(segment
		(start 77.484224 -382.540764)
		(end 77.484224 -368.874802)
		(width 0.1651)
		(layer "In13.Cu")
		(net "P5E_PEX0_STN6_TX_C_DN<101>")
	)
	(segment
		(start 77.043788 -382.9812)
		(end 77.484224 -382.540764)
		(width 0.1651)
		(layer "In13.Cu")
		(net "P5E_PEX0_STN6_TX_C_DN<101>")
	)
	(segment
		(start 76.309982 -383.490216)
		(end 76.309982 -383.1082)
		(width 0.1651)
		(layer "In13.Cu")
		(net "P5E_PEX0_STN6_TX_C_DN<101>")
	)
	(segment
		(start 76.309982 -383.1082)
		(end 76.436982 -382.9812)
		(width 0.1651)
		(layer "In13.Cu")
		(net "P5E_PEX0_STN6_TX_C_DN<101>")
	)
	(segment
		(start 76.436982 -382.9812)
		(end 77.043788 -382.9812)
		(width 0.1651)
		(layer "In13.Cu")
		(net "P5E_PEX0_STN6_TX_C_DN<101>")
	)
	(segment
		(start 82.153252 -359.0036)
		(end 82.153252 -354.089208)
		(width 0.1651)
		(layer "In13.Cu")
		(net "P5E_PEX0_STN6_TX_C_DN<101>")
	)
	(segment
		(start 77.484224 -368.874802)
		(end 82.153252 -359.0036)
		(width 0.1651)
		(layer "In13.Cu")
		(net "P5E_PEX0_STN6_TX_C_DN<101>")
	)
	(segment
		(start 83.707732 -351.902268)
		(end 83.998562 -351.611438)
		(width 0.1651)
		(layer "In13.Cu")
		(net "P5E_PEX0_STN6_TX_C_DN<101>")
	)
	(segment
		(start 82.153252 -354.089208)
		(end 83.707732 -352.534728)
		(width 0.1651)
		(layer "In13.Cu")
		(net "P5E_PEX0_STN6_TX_C_DN<101>")
	)
	(segment
		(start 294.219376 -34.227262)
		(end 291.705538 -34.227262)
		(width 0.13462)
		(layer "F.Cu")
		(net "P5E_PEX2_STN2_RX_DP<39>")
	)
	(segment
		(start 294.86479 -34.390076)
		(end 294.38219 -34.390076)
		(width 0.13462)
		(layer "F.Cu")
		(net "P5E_PEX2_STN2_RX_DP<39>")
	)
	(segment
		(start 294.38219 -34.390076)
		(end 294.219376 -34.227262)
		(width 0.13462)
		(layer "F.Cu")
		(net "P5E_PEX2_STN2_RX_DP<39>")
	)
	(segment
		(start 291.705538 -34.227262)
		(end 291.41039 -34.52241)
		(width 0.13462)
		(layer "F.Cu")
		(net "P5E_PEX2_STN2_RX_DP<39>")
	)
	(segment
		(start 291.9349 -34.23158)
		(end 291.70122 -34.23158)
		(width 0.1651)
		(layer "In7.Cu")
		(net "P5E_PEX2_STN2_RX_DP<39>")
	)
	(segment
		(start 284.249876 -274.049744)
		(end 284.249876 -273.784314)
		(width 0.1143)
		(layer "In7.Cu")
		(net "P5E_PEX2_STN2_RX_DP<39>")
	)
	(segment
		(start 292.864286 -39.111174)
		(end 292.760908 -39.011352)
		(width 0.1651)
		(layer "In7.Cu")
		(net "P5E_PEX2_STN2_RX_DP<39>")
	)
	(segment
		(start 292.753288 -38.515798)
		(end 292.853364 -38.412674)
		(width 0.1651)
		(layer "In7.Cu")
		(net "P5E_PEX2_STN2_RX_DP<39>")
	)
	(segment
		(start 292.853364 -38.412674)
		(end 292.845744 -37.917628)
		(width 0.1651)
		(layer "In7.Cu")
		(net "P5E_PEX2_STN2_RX_DP<39>")
	)
	(segment
		(start 284.249876 -273.784314)
		(end 284.135576 -273.670014)
		(width 0.1143)
		(layer "In7.Cu")
		(net "P5E_PEX2_STN2_RX_DP<39>")
	)
	(segment
		(start 283.942028 -273.670014)
		(end 283.679646 -273.407632)
		(width 0.1143)
		(layer "In7.Cu")
		(net "P5E_PEX2_STN2_RX_DP<39>")
	)
	(segment
		(start 294.098726 -68.131182)
		(end 294.072818 -60.995052)
		(width 0.1651)
		(layer "In7.Cu")
		(net "P5E_PEX2_STN2_RX_DP<39>")
	)
	(segment
		(start 283.633926 -271.4752)
		(end 283.633926 -266.267438)
		(width 0.1651)
		(layer "In7.Cu")
		(net "P5E_PEX2_STN2_RX_DP<39>")
	)
	(segment
		(start 292.80612 -35.357562)
		(end 292.80612 -35.1028)
		(width 0.1651)
		(layer "In7.Cu")
		(net "P5E_PEX2_STN2_RX_DP<39>")
	)
	(segment
		(start 292.742366 -37.817552)
		(end 292.734746 -37.321998)
		(width 0.1651)
		(layer "In7.Cu")
		(net "P5E_PEX2_STN2_RX_DP<39>")
	)
	(segment
		(start 292.734746 -37.321998)
		(end 292.834822 -37.218874)
		(width 0.1651)
		(layer "In7.Cu")
		(net "P5E_PEX2_STN2_RX_DP<39>")
	)
	(segment
		(start 283.679646 -271.549368)
		(end 283.633926 -271.503648)
		(width 0.1143)
		(layer "In7.Cu")
		(net "P5E_PEX2_STN2_RX_DP<39>")
	)
	(segment
		(start 292.760908 -39.011352)
		(end 292.753288 -38.515798)
		(width 0.1651)
		(layer "In7.Cu")
		(net "P5E_PEX2_STN2_RX_DP<39>")
	)
	(segment
		(start 291.70122 -34.23158)
		(end 291.41039 -34.52241)
		(width 0.1651)
		(layer "In7.Cu")
		(net "P5E_PEX2_STN2_RX_DP<39>")
	)
	(segment
		(start 292.8747 -39.786052)
		(end 292.864286 -39.111174)
		(width 0.1651)
		(layer "In7.Cu")
		(net "P5E_PEX2_STN2_RX_DP<39>")
	)
	(segment
		(start 283.633926 -266.267438)
		(end 294.098726 -68.131182)
		(width 0.1651)
		(layer "In7.Cu")
		(net "P5E_PEX2_STN2_RX_DP<39>")
	)
	(segment
		(start 284.135576 -273.670014)
		(end 283.942028 -273.670014)
		(width 0.1143)
		(layer "In7.Cu")
		(net "P5E_PEX2_STN2_RX_DP<39>")
	)
	(segment
		(start 292.80612 -35.1028)
		(end 291.9349 -34.23158)
		(width 0.1651)
		(layer "In7.Cu")
		(net "P5E_PEX2_STN2_RX_DP<39>")
	)
	(segment
		(start 294.245538 -49.932336)
		(end 292.8747 -39.786052)
		(width 0.1651)
		(layer "In7.Cu")
		(net "P5E_PEX2_STN2_RX_DP<39>")
	)
	(segment
		(start 294.072818 -60.995052)
		(end 294.245538 -49.932336)
		(width 0.1651)
		(layer "In7.Cu")
		(net "P5E_PEX2_STN2_RX_DP<39>")
	)
	(segment
		(start 292.845744 -37.917628)
		(end 292.742366 -37.817552)
		(width 0.1651)
		(layer "In7.Cu")
		(net "P5E_PEX2_STN2_RX_DP<39>")
	)
	(segment
		(start 292.834822 -37.218874)
		(end 292.80612 -35.357562)
		(width 0.1651)
		(layer "In7.Cu")
		(net "P5E_PEX2_STN2_RX_DP<39>")
	)
	(segment
		(start 283.633926 -271.503648)
		(end 283.633926 -271.4752)
		(width 0.1143)
		(layer "In7.Cu")
		(net "P5E_PEX2_STN2_RX_DP<39>")
	)
	(segment
		(start 283.679646 -273.407632)
		(end 283.679646 -271.549368)
		(width 0.1143)
		(layer "In7.Cu")
		(net "P5E_PEX2_STN2_RX_DP<39>")
	)
	(segment
		(start 343.567004 -344.219022)
		(end 343.887044 -344.539062)
		(width 0.13462)
		(layer "F.Cu")
		(net "P5E_PEX2_STN6_TX_C_DP<97>")
	)
	(segment
		(start 343.887044 -344.539062)
		(end 343.887044 -345.170506)
		(width 0.13462)
		(layer "F.Cu")
		(net "P5E_PEX2_STN6_TX_C_DP<97>")
	)
	(segment
		(start 343.887044 -345.170506)
		(end 343.592404 -345.465146)
		(width 0.13462)
		(layer "F.Cu")
		(net "P5E_PEX2_STN6_TX_C_DP<97>")
	)
	(segment
		(start 345.53398 -368.845338)
		(end 344.71356 -366.324642)
		(width 0.1651)
		(layer "In13.Cu")
		(net "P5E_PEX2_STN6_TX_C_DP<97>")
	)
	(segment
		(start 343.883234 -346.209874)
		(end 343.883234 -345.755976)
		(width 0.1651)
		(layer "In13.Cu")
		(net "P5E_PEX2_STN6_TX_C_DP<97>")
	)
	(segment
		(start 344.191844 -365.09198)
		(end 344.038428 -364.620556)
		(width 0.1651)
		(layer "In13.Cu")
		(net "P5E_PEX2_STN6_TX_C_DP<97>")
	)
	(segment
		(start 344.038428 -364.620556)
		(end 344.111834 -364.476538)
		(width 0.1651)
		(layer "In13.Cu")
		(net "P5E_PEX2_STN6_TX_C_DP<97>")
	)
	(segment
		(start 345.247214 -382.69926)
		(end 345.53398 -382.412494)
		(width 0.1651)
		(layer "In13.Cu")
		(net "P5E_PEX2_STN6_TX_C_DP<97>")
	)
	(segment
		(start 344.689938 -382.561084)
		(end 344.828114 -382.69926)
		(width 0.1651)
		(layer "In13.Cu")
		(net "P5E_PEX2_STN6_TX_C_DP<97>")
	)
	(segment
		(start 345.53398 -382.412494)
		(end 345.53398 -368.845338)
		(width 0.1651)
		(layer "In13.Cu")
		(net "P5E_PEX2_STN6_TX_C_DP<97>")
	)
	(segment
		(start 343.436956 -362.77296)
		(end 343.28354 -362.301536)
		(width 0.1651)
		(layer "In13.Cu")
		(net "P5E_PEX2_STN6_TX_C_DP<97>")
	)
	(segment
		(start 342.328754 -358.997758)
		(end 342.328754 -347.764354)
		(width 0.1651)
		(layer "In13.Cu")
		(net "P5E_PEX2_STN6_TX_C_DP<97>")
	)
	(segment
		(start 343.581228 -362.846112)
		(end 343.436956 -362.77296)
		(width 0.1651)
		(layer "In13.Cu")
		(net "P5E_PEX2_STN6_TX_C_DP<97>")
	)
	(segment
		(start 344.111834 -364.476538)
		(end 343.958672 -364.005622)
		(width 0.1651)
		(layer "In13.Cu")
		(net "P5E_PEX2_STN6_TX_C_DP<97>")
	)
	(segment
		(start 343.8144 -363.93247)
		(end 343.660984 -363.461046)
		(width 0.1651)
		(layer "In13.Cu")
		(net "P5E_PEX2_STN6_TX_C_DP<97>")
	)
	(segment
		(start 344.336116 -365.165132)
		(end 344.191844 -365.09198)
		(width 0.1651)
		(layer "In13.Cu")
		(net "P5E_PEX2_STN6_TX_C_DP<97>")
	)
	(segment
		(start 344.569288 -366.25149)
		(end 344.416126 -365.780066)
		(width 0.1651)
		(layer "In13.Cu")
		(net "P5E_PEX2_STN6_TX_C_DP<97>")
	)
	(segment
		(start 343.73439 -363.317028)
		(end 343.581228 -362.846112)
		(width 0.1651)
		(layer "In13.Cu")
		(net "P5E_PEX2_STN6_TX_C_DP<97>")
	)
	(segment
		(start 343.660984 -363.461046)
		(end 343.73439 -363.317028)
		(width 0.1651)
		(layer "In13.Cu")
		(net "P5E_PEX2_STN6_TX_C_DP<97>")
	)
	(segment
		(start 343.28354 -362.301536)
		(end 343.356946 -362.157518)
		(width 0.1651)
		(layer "In13.Cu")
		(net "P5E_PEX2_STN6_TX_C_DP<97>")
	)
	(segment
		(start 344.828114 -382.69926)
		(end 345.247214 -382.69926)
		(width 0.1651)
		(layer "In13.Cu")
		(net "P5E_PEX2_STN6_TX_C_DP<97>")
	)
	(segment
		(start 344.416126 -365.780066)
		(end 344.489278 -365.636048)
		(width 0.1651)
		(layer "In13.Cu")
		(net "P5E_PEX2_STN6_TX_C_DP<97>")
	)
	(segment
		(start 343.356946 -362.157518)
		(end 342.328754 -358.997758)
		(width 0.1651)
		(layer "In13.Cu")
		(net "P5E_PEX2_STN6_TX_C_DP<97>")
	)
	(segment
		(start 343.958672 -364.005622)
		(end 343.8144 -363.93247)
		(width 0.1651)
		(layer "In13.Cu")
		(net "P5E_PEX2_STN6_TX_C_DP<97>")
	)
	(segment
		(start 343.883234 -345.755976)
		(end 343.592404 -345.465146)
		(width 0.1651)
		(layer "In13.Cu")
		(net "P5E_PEX2_STN6_TX_C_DP<97>")
	)
	(segment
		(start 342.328754 -347.764354)
		(end 343.883234 -346.209874)
		(width 0.1651)
		(layer "In13.Cu")
		(net "P5E_PEX2_STN6_TX_C_DP<97>")
	)
	(segment
		(start 344.71356 -366.324642)
		(end 344.569288 -366.25149)
		(width 0.1651)
		(layer "In13.Cu")
		(net "P5E_PEX2_STN6_TX_C_DP<97>")
	)
	(segment
		(start 344.489278 -365.636048)
		(end 344.336116 -365.165132)
		(width 0.1651)
		(layer "In13.Cu")
		(net "P5E_PEX2_STN6_TX_C_DP<97>")
	)
	(segment
		(start 344.689938 -382.18999)
		(end 344.689938 -382.561084)
		(width 0.1651)
		(layer "In13.Cu")
		(net "P5E_PEX2_STN6_TX_C_DP<97>")
	)
	(segment
		(start 385.5339 -134.5946)
		(end 393.665202 -134.5946)
		(width 0.13462)
		(layer "F.Cu")
		(net "P5E_PEX3_STN1_TX_C_DN<30>")
	)
	(segment
		(start 385.205224 -134.923276)
		(end 385.5339 -134.5946)
		(width 0.13462)
		(layer "F.Cu")
		(net "P5E_PEX3_STN1_TX_C_DN<30>")
	)
	(segment
		(start 393.835636 -134.765034)
		(end 394.342366 -134.765034)
		(width 0.13462)
		(layer "F.Cu")
		(net "P5E_PEX3_STN1_TX_C_DN<30>")
	)
	(segment
		(start 393.665202 -134.5946)
		(end 393.835636 -134.765034)
		(width 0.13462)
		(layer "F.Cu")
		(net "P5E_PEX3_STN1_TX_C_DN<30>")
	)
	(segment
		(start 400.195288 -140.165074)
		(end 398.94256 -140.165074)
		(width 0.13208)
		(layer "F.Cu")
		(net "RST_NIC6_PERST1_R_N")
	)
	(segment
		(start 400.776948 -140.746734)
		(end 400.195288 -140.165074)
		(width 0.13208)
		(layer "F.Cu")
		(net "RST_NIC6_PERST1_R_N")
	)
	(segment
		(start 400.01952 -164.056314)
		(end 400.364452 -164.401246)
		(width 0.13208)
		(layer "F.Cu")
		(net "RST_NIC6_PERST1_R_N")
	)
	(segment
		(start 400.364452 -164.401246)
		(end 400.364452 -165.902894)
		(width 0.13208)
		(layer "F.Cu")
		(net "RST_NIC6_PERST1_R_N")
	)
	(via
		(at 400.01952 -164.056314)
		(size 0.508)
		(drill 0.254)
		(layers "F.Cu" "B.Cu")
		(net "RST_NIC6_PERST1_R_N")
	)
	(via
		(at 400.776948 -140.746734)
		(size 0.508)
		(drill 0.254)
		(layers "F.Cu" "B.Cu")
		(net "RST_NIC6_PERST1_R_N")
	)
	(segment
		(start 399.22577 -160.557972)
		(end 399.22577 -150.63724)
		(width 0.15494)
		(layer "In7.Cu")
		(net "RST_NIC6_PERST1_R_N")
	)
	(segment
		(start 400.01952 -164.056314)
		(end 400.01952 -161.351722)
		(width 0.15494)
		(layer "In7.Cu")
		(net "RST_NIC6_PERST1_R_N")
	)
	(segment
		(start 400.01952 -161.351722)
		(end 399.22577 -160.557972)
		(width 0.15494)
		(layer "In7.Cu")
		(net "RST_NIC6_PERST1_R_N")
	)
	(segment
		(start 399.22577 -150.63724)
		(end 401.573746 -148.289264)
		(width 0.15494)
		(layer "In7.Cu")
		(net "RST_NIC6_PERST1_R_N")
	)
	(segment
		(start 401.573746 -148.289264)
		(end 401.573746 -141.543532)
		(width 0.15494)
		(layer "In7.Cu")
		(net "RST_NIC6_PERST1_R_N")
	)
	(segment
		(start 401.573746 -141.543532)
		(end 400.776948 -140.746734)
		(width 0.15494)
		(layer "In7.Cu")
		(net "RST_NIC6_PERST1_R_N")
	)
	(segment
		(start 51.130454 -103.045006)
		(end 51.293268 -103.20782)
		(width 0.13462)
		(layer "F.Cu")
		(net "P5E_PEX0_STN1_RX_DP<18>")
	)
	(segment
		(start 53.801772 -103.20782)
		(end 54.09692 -102.912672)
		(width 0.13462)
		(layer "F.Cu")
		(net "P5E_PEX0_STN1_RX_DP<18>")
	)
	(segment
		(start 51.293268 -103.20782)
		(end 53.801772 -103.20782)
		(width 0.13462)
		(layer "F.Cu")
		(net "P5E_PEX0_STN1_RX_DP<18>")
	)
	(segment
		(start 50.64252 -103.045006)
		(end 51.130454 -103.045006)
		(width 0.13462)
		(layer "F.Cu")
		(net "P5E_PEX0_STN1_RX_DP<18>")
	)
	(segment
		(start 30.381702 -154.568144)
		(end 30.66161 -158.791148)
		(width 0.1651)
		(layer "In5.Cu")
		(net "P5E_PEX0_STN1_RX_DP<18>")
	)
	(segment
		(start 44.731178 -106.897932)
		(end 33.83788 -118.307358)
		(width 0.1651)
		(layer "In5.Cu")
		(net "P5E_PEX0_STN1_RX_DP<18>")
	)
	(segment
		(start 33.83788 -118.307358)
		(end 32.84347 -120.379236)
		(width 0.1651)
		(layer "In5.Cu")
		(net "P5E_PEX0_STN1_RX_DP<18>")
	)
	(segment
		(start 60.979558 -271.848072)
		(end 60.979558 -273.45513)
		(width 0.1143)
		(layer "In5.Cu")
		(net "P5E_PEX0_STN1_RX_DP<18>")
	)
	(segment
		(start 61.194442 -273.670014)
		(end 61.435234 -273.670014)
		(width 0.1143)
		(layer "In5.Cu")
		(net "P5E_PEX0_STN1_RX_DP<18>")
	)
	(segment
		(start 60.979558 -273.45513)
		(end 61.194442 -273.670014)
		(width 0.1143)
		(layer "In5.Cu")
		(net "P5E_PEX0_STN1_RX_DP<18>")
	)
	(segment
		(start 51.930808 -103.203502)
		(end 44.731178 -106.897932)
		(width 0.1651)
		(layer "In5.Cu")
		(net "P5E_PEX0_STN1_RX_DP<18>")
	)
	(segment
		(start 60.933838 -271.802352)
		(end 60.979558 -271.848072)
		(width 0.1143)
		(layer "In5.Cu")
		(net "P5E_PEX0_STN1_RX_DP<18>")
	)
	(segment
		(start 31.7881 -165.304216)
		(end 60.933838 -269.772892)
		(width 0.1651)
		(layer "In5.Cu")
		(net "P5E_PEX0_STN1_RX_DP<18>")
	)
	(segment
		(start 61.435234 -273.670014)
		(end 61.549534 -273.784314)
		(width 0.1143)
		(layer "In5.Cu")
		(net "P5E_PEX0_STN1_RX_DP<18>")
	)
	(segment
		(start 32.84347 -120.379236)
		(end 31.705804 -126.602744)
		(width 0.1651)
		(layer "In5.Cu")
		(net "P5E_PEX0_STN1_RX_DP<18>")
	)
	(segment
		(start 54.09692 -102.912672)
		(end 53.80609 -103.203502)
		(width 0.1651)
		(layer "In5.Cu")
		(net "P5E_PEX0_STN1_RX_DP<18>")
	)
	(segment
		(start 30.101794 -150.34133)
		(end 30.381702 -154.568144)
		(width 0.1651)
		(layer "In5.Cu")
		(net "P5E_PEX0_STN1_RX_DP<18>")
	)
	(segment
		(start 30.66161 -158.791148)
		(end 31.7881 -165.304216)
		(width 0.1651)
		(layer "In5.Cu")
		(net "P5E_PEX0_STN1_RX_DP<18>")
	)
	(segment
		(start 53.80609 -103.203502)
		(end 51.930808 -103.203502)
		(width 0.1651)
		(layer "In5.Cu")
		(net "P5E_PEX0_STN1_RX_DP<18>")
	)
	(segment
		(start 61.549534 -273.784314)
		(end 61.549534 -274.049744)
		(width 0.1143)
		(layer "In5.Cu")
		(net "P5E_PEX0_STN1_RX_DP<18>")
	)
	(segment
		(start 60.933838 -271.773904)
		(end 60.933838 -271.802352)
		(width 0.1143)
		(layer "In5.Cu")
		(net "P5E_PEX0_STN1_RX_DP<18>")
	)
	(segment
		(start 60.933838 -269.772892)
		(end 60.933838 -271.773904)
		(width 0.1651)
		(layer "In5.Cu")
		(net "P5E_PEX0_STN1_RX_DP<18>")
	)
	(segment
		(start 31.705804 -126.602744)
		(end 30.101794 -150.34133)
		(width 0.1651)
		(layer "In5.Cu")
		(net "P5E_PEX0_STN1_RX_DP<18>")
	)
	(segment
		(start 80.594962 -357.46309)
		(end 80.594962 -356.831646)
		(width 0.13462)
		(layer "F.Cu")
		(net "P5E_PEX0_STN6_TX_C_DN<102>")
	)
	(segment
		(start 80.594962 -356.831646)
		(end 80.915002 -356.511606)
		(width 0.13462)
		(layer "F.Cu")
		(net "P5E_PEX0_STN6_TX_C_DN<102>")
	)
	(segment
		(start 80.889602 -357.75773)
		(end 80.594962 -357.46309)
		(width 0.13462)
		(layer "F.Cu")
		(net "P5E_PEX0_STN6_TX_C_DN<102>")
	)
	(segment
		(start 75.28433 -368.626136)
		(end 80.598772 -359.245662)
		(width 0.1651)
		(layer "In13.Cu")
		(net "P5E_PEX0_STN6_TX_C_DN<102>")
	)
	(segment
		(start 74.880978 -384.08102)
		(end 75.28433 -383.677668)
		(width 0.1651)
		(layer "In13.Cu")
		(net "P5E_PEX0_STN6_TX_C_DN<102>")
	)
	(segment
		(start 80.598772 -358.04856)
		(end 80.889602 -357.75773)
		(width 0.1651)
		(layer "In13.Cu")
		(net "P5E_PEX0_STN6_TX_C_DN<102>")
	)
	(segment
		(start 74.109834 -384.590036)
		(end 74.109834 -384.20802)
		(width 0.1651)
		(layer "In13.Cu")
		(net "P5E_PEX0_STN6_TX_C_DN<102>")
	)
	(segment
		(start 74.109834 -384.20802)
		(end 74.236834 -384.08102)
		(width 0.1651)
		(layer "In13.Cu")
		(net "P5E_PEX0_STN6_TX_C_DN<102>")
	)
	(segment
		(start 80.598772 -359.245662)
		(end 80.598772 -358.04856)
		(width 0.1651)
		(layer "In13.Cu")
		(net "P5E_PEX0_STN6_TX_C_DN<102>")
	)
	(segment
		(start 74.236834 -384.08102)
		(end 74.880978 -384.08102)
		(width 0.1651)
		(layer "In13.Cu")
		(net "P5E_PEX0_STN6_TX_C_DN<102>")
	)
	(segment
		(start 75.28433 -383.677668)
		(end 75.28433 -368.626136)
		(width 0.1651)
		(layer "In13.Cu")
		(net "P5E_PEX0_STN6_TX_C_DN<102>")
	)
	(segment
		(start 252.054106 -30.6324)
		(end 248.123202 -30.6324)
		(width 0.13462)
		(layer "F.Cu")
		(net "P5E_PEX2_STN2_TX_C_DP<45>")
	)
	(segment
		(start 252.367796 -30.94609)
		(end 252.054106 -30.6324)
		(width 0.13462)
		(layer "F.Cu")
		(net "P5E_PEX2_STN2_TX_C_DP<45>")
	)
	(segment
		(start 247.965468 -30.790134)
		(end 247.464834 -30.790134)
		(width 0.13462)
		(layer "F.Cu")
		(net "P5E_PEX2_STN2_TX_C_DP<45>")
	)
	(segment
		(start 248.123202 -30.6324)
		(end 247.965468 -30.790134)
		(width 0.13462)
		(layer "F.Cu")
		(net "P5E_PEX2_STN2_TX_C_DP<45>")
	)
	(segment
		(start 332.045564 -356.511606)
		(end 331.725524 -356.831646)
		(width 0.13462)
		(layer "F.Cu")
		(net "P5E_PEX2_STN6_TX_C_DN<102>")
	)
	(segment
		(start 331.725524 -357.46309)
		(end 332.020164 -357.75773)
		(width 0.13462)
		(layer "F.Cu")
		(net "P5E_PEX2_STN6_TX_C_DN<102>")
	)
	(segment
		(start 331.725524 -356.831646)
		(end 331.725524 -357.46309)
		(width 0.13462)
		(layer "F.Cu")
		(net "P5E_PEX2_STN6_TX_C_DN<102>")
	)
	(segment
		(start 331.729334 -358.04856)
		(end 331.729334 -358.92994)
		(width 0.1651)
		(layer "In13.Cu")
		(net "P5E_PEX2_STN6_TX_C_DN<102>")
	)
	(segment
		(start 333.81696 -384.08102)
		(end 333.68996 -384.20802)
		(width 0.1651)
		(layer "In13.Cu")
		(net "P5E_PEX2_STN6_TX_C_DN<102>")
	)
	(segment
		(start 333.68996 -384.20802)
		(end 333.68996 -384.590036)
		(width 0.1651)
		(layer "In13.Cu")
		(net "P5E_PEX2_STN6_TX_C_DN<102>")
	)
	(segment
		(start 334.364076 -384.08102)
		(end 333.81696 -384.08102)
		(width 0.1651)
		(layer "In13.Cu")
		(net "P5E_PEX2_STN6_TX_C_DN<102>")
	)
	(segment
		(start 332.020164 -357.75773)
		(end 331.729334 -358.04856)
		(width 0.1651)
		(layer "In13.Cu")
		(net "P5E_PEX2_STN6_TX_C_DN<102>")
	)
	(segment
		(start 331.729334 -358.92994)
		(end 334.815942 -368.83594)
		(width 0.1651)
		(layer "In13.Cu")
		(net "P5E_PEX2_STN6_TX_C_DN<102>")
	)
	(segment
		(start 334.815942 -383.629154)
		(end 334.364076 -384.08102)
		(width 0.1651)
		(layer "In13.Cu")
		(net "P5E_PEX2_STN6_TX_C_DN<102>")
	)
	(segment
		(start 334.815942 -368.83594)
		(end 334.815942 -383.629154)
		(width 0.1651)
		(layer "In13.Cu")
		(net "P5E_PEX2_STN6_TX_C_DN<102>")
	)
	(segment
		(start 388.16407 -124.92228)
		(end 393.67587 -124.92228)
		(width 0.13462)
		(layer "F.Cu")
		(net "P5E_PEX3_STN1_TX_C_DN<27>")
	)
	(segment
		(start 387.847332 -124.605542)
		(end 388.16407 -124.92228)
		(width 0.13462)
		(layer "F.Cu")
		(net "P5E_PEX3_STN1_TX_C_DN<27>")
	)
	(segment
		(start 393.843002 -124.755148)
		(end 394.342366 -124.755148)
		(width 0.13462)
		(layer "F.Cu")
		(net "P5E_PEX3_STN1_TX_C_DN<27>")
	)
	(segment
		(start 393.67587 -124.92228)
		(end 393.843002 -124.755148)
		(width 0.13462)
		(layer "F.Cu")
		(net "P5E_PEX3_STN1_TX_C_DN<27>")
	)
	(segment
		(start 388.57301 -162.046666)
		(end 389.118602 -161.501074)
		(width 0.13208)
		(layer "F.Cu")
		(net "PWRGD_NIC6_PWR_GOOD")
	)
	(segment
		(start 388.57047 -162.044126)
		(end 388.57301 -162.046666)
		(width 0.13208)
		(layer "F.Cu")
		(net "PWRGD_NIC6_PWR_GOOD")
	)
	(segment
		(start 389.118602 -161.501074)
		(end 390.110472 -161.501074)
		(width 0.13208)
		(layer "F.Cu")
		(net "PWRGD_NIC6_PWR_GOOD")
	)
	(segment
		(start 387.30809 -162.044126)
		(end 388.57047 -162.044126)
		(width 0.13208)
		(layer "F.Cu")
		(net "PWRGD_NIC6_PWR_GOOD")
	)
	(segment
		(start 393.251436 -158.36011)
		(end 394.342366 -158.36011)
		(width 0.13208)
		(layer "F.Cu")
		(net "PWRGD_NIC6_PWR_GOOD")
	)
	(segment
		(start 387.30809 -163.061396)
		(end 387.30809 -162.044126)
		(width 0.13208)
		(layer "F.Cu")
		(net "PWRGD_NIC6_PWR_GOOD")
	)
	(segment
		(start 390.110472 -161.501074)
		(end 393.251436 -158.36011)
		(width 0.13208)
		(layer "F.Cu")
		(net "PWRGD_NIC6_PWR_GOOD")
	)
	(via
		(at 388.57301 -162.046666)
		(size 0.762)
		(drill 0.381)
		(layers "F.Cu" "B.Cu")
		(net "PWRGD_NIC6_PWR_GOOD")
	)
	(segment
		(start 50.64252 -106.644948)
		(end 51.130454 -106.644948)
		(width 0.13462)
		(layer "F.Cu")
		(net "P5E_PEX0_STN1_RX_DP<20>")
	)
	(segment
		(start 51.293268 -106.807762)
		(end 53.801772 -106.807762)
		(width 0.13462)
		(layer "F.Cu")
		(net "P5E_PEX0_STN1_RX_DP<20>")
	)
	(segment
		(start 53.801772 -106.807762)
		(end 54.09692 -106.512614)
		(width 0.13462)
		(layer "F.Cu")
		(net "P5E_PEX0_STN1_RX_DP<20>")
	)
	(segment
		(start 51.130454 -106.644948)
		(end 51.293268 -106.807762)
		(width 0.13462)
		(layer "F.Cu")
		(net "P5E_PEX0_STN1_RX_DP<20>")
	)
	(segment
		(start 41.682924 -113.218722)
		(end 40.845232 -114.696748)
		(width 0.1651)
		(layer "In5.Cu")
		(net "P5E_PEX0_STN1_RX_DP<20>")
	)
	(segment
		(start 51.589432 -106.803444)
		(end 44.31284 -110.677452)
		(width 0.1651)
		(layer "In5.Cu")
		(net "P5E_PEX0_STN1_RX_DP<20>")
	)
	(segment
		(start 62.879732 -273.45513)
		(end 63.094616 -273.670014)
		(width 0.1143)
		(layer "In5.Cu")
		(net "P5E_PEX0_STN1_RX_DP<20>")
	)
	(segment
		(start 54.09692 -106.512614)
		(end 53.80609 -106.803444)
		(width 0.1651)
		(layer "In5.Cu")
		(net "P5E_PEX0_STN1_RX_DP<20>")
	)
	(segment
		(start 40.845232 -114.696748)
		(end 39.097458 -122.198384)
		(width 0.1651)
		(layer "In5.Cu")
		(net "P5E_PEX0_STN1_RX_DP<20>")
	)
	(segment
		(start 62.879732 -271.848072)
		(end 62.879732 -273.45513)
		(width 0.1143)
		(layer "In5.Cu")
		(net "P5E_PEX0_STN1_RX_DP<20>")
	)
	(segment
		(start 44.31284 -110.677452)
		(end 41.682924 -113.218722)
		(width 0.1651)
		(layer "In5.Cu")
		(net "P5E_PEX0_STN1_RX_DP<20>")
	)
	(segment
		(start 36.61664 -123.736608)
		(end 36.616894 -123.736608)
		(width 0.1651)
		(layer "In5.Cu")
		(net "P5E_PEX0_STN1_RX_DP<20>")
	)
	(segment
		(start 32.09671 -150.509986)
		(end 32.357314 -154.632406)
		(width 0.1651)
		(layer "In5.Cu")
		(net "P5E_PEX0_STN1_RX_DP<20>")
	)
	(segment
		(start 32.617664 -158.750254)
		(end 33.643062 -164.725858)
		(width 0.1651)
		(layer "In5.Cu")
		(net "P5E_PEX0_STN1_RX_DP<20>")
	)
	(segment
		(start 38.433248 -122.95759)
		(end 36.665662 -123.639326)
		(width 0.1651)
		(layer "In5.Cu")
		(net "P5E_PEX0_STN1_RX_DP<20>")
	)
	(segment
		(start 32.357314 -154.632406)
		(end 32.617664 -158.750254)
		(width 0.1651)
		(layer "In5.Cu")
		(net "P5E_PEX0_STN1_RX_DP<20>")
	)
	(segment
		(start 62.834012 -271.802352)
		(end 62.879732 -271.848072)
		(width 0.1143)
		(layer "In5.Cu")
		(net "P5E_PEX0_STN1_RX_DP<20>")
	)
	(segment
		(start 36.616894 -123.736608)
		(end 33.737042 -129.472436)
		(width 0.1651)
		(layer "In5.Cu")
		(net "P5E_PEX0_STN1_RX_DP<20>")
	)
	(segment
		(start 33.737042 -129.472436)
		(end 32.09671 -150.509986)
		(width 0.1651)
		(layer "In5.Cu")
		(net "P5E_PEX0_STN1_RX_DP<20>")
	)
	(segment
		(start 53.80609 -106.803444)
		(end 51.589432 -106.803444)
		(width 0.1651)
		(layer "In5.Cu")
		(net "P5E_PEX0_STN1_RX_DP<20>")
	)
	(segment
		(start 62.834012 -271.773904)
		(end 62.834012 -271.802352)
		(width 0.1143)
		(layer "In5.Cu")
		(net "P5E_PEX0_STN1_RX_DP<20>")
	)
	(segment
		(start 63.094616 -273.670014)
		(end 63.335408 -273.670014)
		(width 0.1143)
		(layer "In5.Cu")
		(net "P5E_PEX0_STN1_RX_DP<20>")
	)
	(segment
		(start 36.665662 -123.639326)
		(end 36.61664 -123.736608)
		(width 0.1651)
		(layer "In5.Cu")
		(net "P5E_PEX0_STN1_RX_DP<20>")
	)
	(segment
		(start 62.834012 -269.350998)
		(end 62.834012 -271.773904)
		(width 0.1651)
		(layer "In5.Cu")
		(net "P5E_PEX0_STN1_RX_DP<20>")
	)
	(segment
		(start 39.097458 -122.198384)
		(end 38.433248 -122.95759)
		(width 0.1651)
		(layer "In5.Cu")
		(net "P5E_PEX0_STN1_RX_DP<20>")
	)
	(segment
		(start 33.643062 -164.725858)
		(end 62.834012 -269.350998)
		(width 0.1651)
		(layer "In5.Cu")
		(net "P5E_PEX0_STN1_RX_DP<20>")
	)
	(segment
		(start 63.335408 -273.670014)
		(end 63.449708 -273.784314)
		(width 0.1143)
		(layer "In5.Cu")
		(net "P5E_PEX0_STN1_RX_DP<20>")
	)
	(segment
		(start 63.449708 -273.784314)
		(end 63.449708 -274.049744)
		(width 0.1143)
		(layer "In5.Cu")
		(net "P5E_PEX0_STN1_RX_DP<20>")
	)
	(segment
		(start 268.385544 -32.589978)
		(end 268.218666 -32.4231)
		(width 0.13462)
		(layer "F.Cu")
		(net "P5E_PEX2_STN2_RX_DP<42>")
	)
	(segment
		(start 268.864842 -32.589978)
		(end 268.385544 -32.589978)
		(width 0.13462)
		(layer "F.Cu")
		(net "P5E_PEX2_STN2_RX_DP<42>")
	)
	(segment
		(start 268.218666 -32.4231)
		(end 267.563854 -32.4231)
		(width 0.13462)
		(layer "F.Cu")
		(net "P5E_PEX2_STN2_RX_DP<42>")
	)
	(segment
		(start 267.563854 -32.4231)
		(end 267.264642 -32.722312)
		(width 0.13462)
		(layer "F.Cu")
		(net "P5E_PEX2_STN2_RX_DP<42>")
	)
	(segment
		(start 269.052548 -55.371238)
		(end 269.14475 -49.45253)
		(width 0.1651)
		(layer "In7.Cu")
		(net "P5E_PEX2_STN2_RX_DP<42>")
	)
	(segment
		(start 268.3256 -35.019996)
		(end 268.337792 -34.232596)
		(width 0.1651)
		(layer "In7.Cu")
		(net "P5E_PEX2_STN2_RX_DP<42>")
	)
	(segment
		(start 280.562558 -258.724654)
		(end 280.731214 -250.005342)
		(width 0.1651)
		(layer "In7.Cu")
		(net "P5E_PEX2_STN2_RX_DP<42>")
	)
	(segment
		(start 281.04465 -275.570188)
		(end 280.829258 -275.354796)
		(width 0.1143)
		(layer "In7.Cu")
		(net "P5E_PEX2_STN2_RX_DP<42>")
	)
	(segment
		(start 272.775172 -148.011896)
		(end 273.081496 -119.585994)
		(width 0.1651)
		(layer "In7.Cu")
		(net "P5E_PEX2_STN2_RX_DP<42>")
	)
	(segment
		(start 268.01318 -32.431482)
		(end 267.555472 -32.431482)
		(width 0.1651)
		(layer "In7.Cu")
		(net "P5E_PEX2_STN2_RX_DP<42>")
	)
	(segment
		(start 281.399742 -275.949918)
		(end 281.399742 -275.684488)
		(width 0.1143)
		(layer "In7.Cu")
		(net "P5E_PEX2_STN2_RX_DP<42>")
	)
	(segment
		(start 268.337792 -34.232596)
		(end 268.237716 -34.129472)
		(width 0.1651)
		(layer "In7.Cu")
		(net "P5E_PEX2_STN2_RX_DP<42>")
	)
	(segment
		(start 269.14475 -49.45253)
		(end 267.831316 -39.731442)
		(width 0.1651)
		(layer "In7.Cu")
		(net "P5E_PEX2_STN2_RX_DP<42>")
	)
	(segment
		(start 281.285442 -275.570188)
		(end 281.04465 -275.570188)
		(width 0.1143)
		(layer "In7.Cu")
		(net "P5E_PEX2_STN2_RX_DP<42>")
	)
	(segment
		(start 268.237716 -34.129472)
		(end 268.245336 -33.633918)
		(width 0.1651)
		(layer "In7.Cu")
		(net "P5E_PEX2_STN2_RX_DP<42>")
	)
	(segment
		(start 280.829258 -275.354796)
		(end 280.829258 -271.467072)
		(width 0.1143)
		(layer "In7.Cu")
		(net "P5E_PEX2_STN2_RX_DP<42>")
	)
	(segment
		(start 280.783538 -271.392904)
		(end 280.783538 -267.781786)
		(width 0.1651)
		(layer "In7.Cu")
		(net "P5E_PEX2_STN2_RX_DP<42>")
	)
	(segment
		(start 280.783538 -267.781786)
		(end 280.339292 -263.273032)
		(width 0.1651)
		(layer "In7.Cu")
		(net "P5E_PEX2_STN2_RX_DP<42>")
	)
	(segment
		(start 268.106652 -36.19373)
		(end 268.025372 -36.075112)
		(width 0.1651)
		(layer "In7.Cu")
		(net "P5E_PEX2_STN2_RX_DP<42>")
	)
	(segment
		(start 280.731214 -250.005342)
		(end 272.775172 -148.011896)
		(width 0.1651)
		(layer "In7.Cu")
		(net "P5E_PEX2_STN2_RX_DP<42>")
	)
	(segment
		(start 268.360398 -32.7787)
		(end 268.01318 -32.431482)
		(width 0.1651)
		(layer "In7.Cu")
		(net "P5E_PEX2_STN2_RX_DP<42>")
	)
	(segment
		(start 281.399742 -275.684488)
		(end 281.285442 -275.570188)
		(width 0.1143)
		(layer "In7.Cu")
		(net "P5E_PEX2_STN2_RX_DP<42>")
	)
	(segment
		(start 267.831316 -39.731442)
		(end 267.801344 -37.832538)
		(width 0.1651)
		(layer "In7.Cu")
		(net "P5E_PEX2_STN2_RX_DP<42>")
	)
	(segment
		(start 267.801344 -37.832538)
		(end 268.106652 -36.19373)
		(width 0.1651)
		(layer "In7.Cu")
		(net "P5E_PEX2_STN2_RX_DP<42>")
	)
	(segment
		(start 280.783538 -271.421352)
		(end 280.783538 -271.392904)
		(width 0.1143)
		(layer "In7.Cu")
		(net "P5E_PEX2_STN2_RX_DP<42>")
	)
	(segment
		(start 272.638774 -104.96804)
		(end 269.444724 -65.176654)
		(width 0.1651)
		(layer "In7.Cu")
		(net "P5E_PEX2_STN2_RX_DP<42>")
	)
	(segment
		(start 269.444724 -65.176654)
		(end 269.052548 -55.371238)
		(width 0.1651)
		(layer "In7.Cu")
		(net "P5E_PEX2_STN2_RX_DP<42>")
	)
	(segment
		(start 280.829258 -271.467072)
		(end 280.783538 -271.421352)
		(width 0.1143)
		(layer "In7.Cu")
		(net "P5E_PEX2_STN2_RX_DP<42>")
	)
	(segment
		(start 280.339292 -263.273032)
		(end 280.562558 -258.724654)
		(width 0.1651)
		(layer "In7.Cu")
		(net "P5E_PEX2_STN2_RX_DP<42>")
	)
	(segment
		(start 273.081496 -119.585994)
		(end 272.638774 -104.96804)
		(width 0.1651)
		(layer "In7.Cu")
		(net "P5E_PEX2_STN2_RX_DP<42>")
	)
	(segment
		(start 268.245336 -33.633918)
		(end 268.348714 -33.533842)
		(width 0.1651)
		(layer "In7.Cu")
		(net "P5E_PEX2_STN2_RX_DP<42>")
	)
	(segment
		(start 268.116304 -35.58794)
		(end 268.234922 -35.50666)
		(width 0.1651)
		(layer "In7.Cu")
		(net "P5E_PEX2_STN2_RX_DP<42>")
	)
	(segment
		(start 267.555472 -32.431482)
		(end 267.264642 -32.722312)
		(width 0.1651)
		(layer "In7.Cu")
		(net "P5E_PEX2_STN2_RX_DP<42>")
	)
	(segment
		(start 268.025372 -36.075112)
		(end 268.116304 -35.58794)
		(width 0.1651)
		(layer "In7.Cu")
		(net "P5E_PEX2_STN2_RX_DP<42>")
	)
	(segment
		(start 268.234922 -35.50666)
		(end 268.3256 -35.019996)
		(width 0.1651)
		(layer "In7.Cu")
		(net "P5E_PEX2_STN2_RX_DP<42>")
	)
	(segment
		(start 268.348714 -33.533842)
		(end 268.360398 -32.7787)
		(width 0.1651)
		(layer "In7.Cu")
		(net "P5E_PEX2_STN2_RX_DP<42>")
	)
	(segment
		(start 337.669124 -357.46309)
		(end 337.374484 -357.75773)
		(width 0.13462)
		(layer "F.Cu")
		(net "P5E_PEX2_STN6_TX_C_DP<99>")
	)
	(segment
		(start 337.669124 -356.831646)
		(end 337.669124 -357.46309)
		(width 0.13462)
		(layer "F.Cu")
		(net "P5E_PEX2_STN6_TX_C_DP<99>")
	)
	(segment
		(start 337.349084 -356.511606)
		(end 337.669124 -356.831646)
		(width 0.13462)
		(layer "F.Cu")
		(net "P5E_PEX2_STN6_TX_C_DP<99>")
	)
	(segment
		(start 340.847426 -382.69926)
		(end 340.41715 -382.69926)
		(width 0.1651)
		(layer "In13.Cu")
		(net "P5E_PEX2_STN6_TX_C_DP<99>")
	)
	(segment
		(start 341.134192 -382.412494)
		(end 340.847426 -382.69926)
		(width 0.1651)
		(layer "In13.Cu")
		(net "P5E_PEX2_STN6_TX_C_DP<99>")
	)
	(segment
		(start 337.374484 -357.75773)
		(end 337.665314 -358.04856)
		(width 0.1651)
		(layer "In13.Cu")
		(net "P5E_PEX2_STN6_TX_C_DP<99>")
	)
	(segment
		(start 339.909658 -365.758222)
		(end 340.0552 -365.82858)
		(width 0.1651)
		(layer "In13.Cu")
		(net "P5E_PEX2_STN6_TX_C_DP<99>")
	)
	(segment
		(start 339.016086 -362.841286)
		(end 338.945728 -362.986574)
		(width 0.1651)
		(layer "In13.Cu")
		(net "P5E_PEX2_STN6_TX_C_DP<99>")
	)
	(segment
		(start 338.54517 -361.834938)
		(end 338.707984 -362.30306)
		(width 0.1651)
		(layer "In13.Cu")
		(net "P5E_PEX2_STN6_TX_C_DP<99>")
	)
	(segment
		(start 340.0552 -365.82858)
		(end 341.134192 -368.931952)
		(width 0.1651)
		(layer "In13.Cu")
		(net "P5E_PEX2_STN6_TX_C_DP<99>")
	)
	(segment
		(start 340.29015 -382.57226)
		(end 340.29015 -382.18999)
		(width 0.1651)
		(layer "In13.Cu")
		(net "P5E_PEX2_STN6_TX_C_DP<99>")
	)
	(segment
		(start 337.665314 -358.04856)
		(end 337.665314 -358.954832)
		(width 0.1651)
		(layer "In13.Cu")
		(net "P5E_PEX2_STN6_TX_C_DP<99>")
	)
	(segment
		(start 341.134192 -368.931952)
		(end 341.134192 -382.412494)
		(width 0.1651)
		(layer "In13.Cu")
		(net "P5E_PEX2_STN6_TX_C_DP<99>")
	)
	(segment
		(start 339.108288 -363.454696)
		(end 339.254084 -363.525308)
		(width 0.1651)
		(layer "In13.Cu")
		(net "P5E_PEX2_STN6_TX_C_DP<99>")
	)
	(segment
		(start 339.817202 -365.144558)
		(end 339.746844 -365.2901)
		(width 0.1651)
		(layer "In13.Cu")
		(net "P5E_PEX2_STN6_TX_C_DP<99>")
	)
	(segment
		(start 337.665314 -358.954832)
		(end 338.615782 -361.68965)
		(width 0.1651)
		(layer "In13.Cu")
		(net "P5E_PEX2_STN6_TX_C_DP<99>")
	)
	(segment
		(start 339.508846 -364.606332)
		(end 339.654642 -364.676944)
		(width 0.1651)
		(layer "In13.Cu")
		(net "P5E_PEX2_STN6_TX_C_DP<99>")
	)
	(segment
		(start 339.254084 -363.525308)
		(end 339.416644 -363.992922)
		(width 0.1651)
		(layer "In13.Cu")
		(net "P5E_PEX2_STN6_TX_C_DP<99>")
	)
	(segment
		(start 339.416644 -363.992922)
		(end 339.346286 -364.13821)
		(width 0.1651)
		(layer "In13.Cu")
		(net "P5E_PEX2_STN6_TX_C_DP<99>")
	)
	(segment
		(start 338.707984 -362.30306)
		(end 338.853526 -362.373672)
		(width 0.1651)
		(layer "In13.Cu")
		(net "P5E_PEX2_STN6_TX_C_DP<99>")
	)
	(segment
		(start 340.41715 -382.69926)
		(end 340.29015 -382.57226)
		(width 0.1651)
		(layer "In13.Cu")
		(net "P5E_PEX2_STN6_TX_C_DP<99>")
	)
	(segment
		(start 338.853526 -362.373672)
		(end 339.016086 -362.841286)
		(width 0.1651)
		(layer "In13.Cu")
		(net "P5E_PEX2_STN6_TX_C_DP<99>")
	)
	(segment
		(start 338.615782 -361.68965)
		(end 338.54517 -361.834938)
		(width 0.1651)
		(layer "In13.Cu")
		(net "P5E_PEX2_STN6_TX_C_DP<99>")
	)
	(segment
		(start 338.945728 -362.986574)
		(end 339.108288 -363.454696)
		(width 0.1651)
		(layer "In13.Cu")
		(net "P5E_PEX2_STN6_TX_C_DP<99>")
	)
	(segment
		(start 339.654642 -364.676944)
		(end 339.817202 -365.144558)
		(width 0.1651)
		(layer "In13.Cu")
		(net "P5E_PEX2_STN6_TX_C_DP<99>")
	)
	(segment
		(start 339.346286 -364.13821)
		(end 339.508846 -364.606332)
		(width 0.1651)
		(layer "In13.Cu")
		(net "P5E_PEX2_STN6_TX_C_DP<99>")
	)
	(segment
		(start 339.746844 -365.2901)
		(end 339.909658 -365.758222)
		(width 0.1651)
		(layer "In13.Cu")
		(net "P5E_PEX2_STN6_TX_C_DP<99>")
	)
	(segment
		(start 393.8397 -99.445064)
		(end 394.342366 -99.445064)
		(width 0.13462)
		(layer "F.Cu")
		(net "P5E_PEX3_STN1_TX_C_DP<16>")
	)
	(segment
		(start 393.686284 -99.59848)
		(end 393.8397 -99.445064)
		(width 0.13462)
		(layer "F.Cu")
		(net "P5E_PEX3_STN1_TX_C_DP<16>")
	)
	(segment
		(start 387.847332 -99.288854)
		(end 388.156958 -99.59848)
		(width 0.13462)
		(layer "F.Cu")
		(net "P5E_PEX3_STN1_TX_C_DP<16>")
	)
	(segment
		(start 388.156958 -99.59848)
		(end 393.686284 -99.59848)
		(width 0.13462)
		(layer "F.Cu")
		(net "P5E_PEX3_STN1_TX_C_DP<16>")
	)
	(segment
		(start 398.94256 -153.560018)
		(end 401.13204 -153.560018)
		(width 0.13208)
		(layer "F.Cu")
		(net "NCSI_NIC6_TXD0")
	)
	(via
		(at 401.13204 -153.560018)
		(size 0.508)
		(drill 0.254)
		(layers "F.Cu" "B.Cu")
		(net "NCSI_NIC6_TXD0")
	)
	(segment
		(start 400.217894 -151.9936)
		(end 401.13204 -152.907746)
		(width 0.13208)
		(layer "B.Cu")
		(net "NCSI_NIC6_TXD0")
	)
	(segment
		(start 398.25549 -151.9936)
		(end 400.217894 -151.9936)
		(width 0.13208)
		(layer "B.Cu")
		(net "NCSI_NIC6_TXD0")
	)
	(segment
		(start 401.13204 -152.907746)
		(end 401.13204 -153.560018)
		(width 0.13208)
		(layer "B.Cu")
		(net "NCSI_NIC6_TXD0")
	)
	(segment
		(start 39.547292 -102.888796)
		(end 39.866316 -103.20782)
		(width 0.13462)
		(layer "F.Cu")
		(net "P5E_PEX0_STN1_TX_C_DP<18>")
	)
	(segment
		(start 45.554392 -103.045006)
		(end 46.042326 -103.045006)
		(width 0.13462)
		(layer "F.Cu")
		(net "P5E_PEX0_STN1_TX_C_DP<18>")
	)
	(segment
		(start 39.866316 -103.20782)
		(end 45.391578 -103.20782)
		(width 0.13462)
		(layer "F.Cu")
		(net "P5E_PEX0_STN1_TX_C_DP<18>")
	)
	(segment
		(start 45.391578 -103.20782)
		(end 45.554392 -103.045006)
		(width 0.13462)
		(layer "F.Cu")
		(net "P5E_PEX0_STN1_TX_C_DP<18>")
	)
	(segment
		(start 242.22456 -30.353)
		(end 239.704626 -30.353)
		(width 0.13462)
		(layer "F.Cu")
		(net "P5E_PEX2_STN2_RX_DN<45>")
	)
	(segment
		(start 242.864894 -30.190186)
		(end 242.387374 -30.190186)
		(width 0.13462)
		(layer "F.Cu")
		(net "P5E_PEX2_STN2_RX_DN<45>")
	)
	(segment
		(start 242.387374 -30.190186)
		(end 242.22456 -30.353)
		(width 0.13462)
		(layer "F.Cu")
		(net "P5E_PEX2_STN2_RX_DN<45>")
	)
	(segment
		(start 239.704626 -30.353)
		(end 239.410494 -30.058868)
		(width 0.13462)
		(layer "F.Cu")
		(net "P5E_PEX2_STN2_RX_DN<45>")
	)
	(segment
		(start 278.170132 -273.328638)
		(end 278.170132 -271.41932)
		(width 0.1143)
		(layer "In7.Cu")
		(net "P5E_PEX2_STN2_RX_DN<45>")
	)
	(segment
		(start 249.54738 -102.432104)
		(end 249.535442 -102.392734)
		(width 0.1651)
		(layer "In7.Cu")
		(net "P5E_PEX2_STN2_RX_DN<45>")
	)
	(segment
		(start 275.730716 -238.16945)
		(end 258.018788 -144.505172)
		(width 0.1651)
		(layer "In7.Cu")
		(net "P5E_PEX2_STN2_RX_DN<45>")
	)
	(segment
		(start 244.548406 -60.132976)
		(end 244.280944 -57.362344)
		(width 0.1651)
		(layer "In7.Cu")
		(net "P5E_PEX2_STN2_RX_DN<45>")
	)
	(segment
		(start 278.170132 -271.41932)
		(end 278.215852 -271.3736)
		(width 0.1143)
		(layer "In7.Cu")
		(net "P5E_PEX2_STN2_RX_DN<45>")
	)
	(segment
		(start 244.280944 -57.362344)
		(end 244.398292 -49.868074)
		(width 0.1651)
		(layer "In7.Cu")
		(net "P5E_PEX2_STN2_RX_DN<45>")
	)
	(segment
		(start 244.548406 -61.48959)
		(end 244.548406 -60.132976)
		(width 0.1651)
		(layer "In7.Cu")
		(net "P5E_PEX2_STN2_RX_DN<45>")
	)
	(segment
		(start 243.063268 -37.96284)
		(end 243.588032 -35.00755)
		(width 0.1651)
		(layer "In7.Cu")
		(net "P5E_PEX2_STN2_RX_DN<45>")
	)
	(segment
		(start 278.215852 -271.345152)
		(end 278.215852 -270.28521)
		(width 0.1651)
		(layer "In7.Cu")
		(net "P5E_PEX2_STN2_RX_DN<45>")
	)
	(segment
		(start 249.535442 -102.392734)
		(end 249.535188 -102.391972)
		(width 0.1651)
		(layer "In7.Cu")
		(net "P5E_PEX2_STN2_RX_DN<45>")
	)
	(segment
		(start 249.535188 -102.391972)
		(end 244.357906 -85.311742)
		(width 0.1651)
		(layer "In7.Cu")
		(net "P5E_PEX2_STN2_RX_DN<45>")
	)
	(segment
		(start 243.099336 -40.256206)
		(end 243.063268 -37.96284)
		(width 0.1651)
		(layer "In7.Cu")
		(net "P5E_PEX2_STN2_RX_DN<45>")
	)
	(segment
		(start 278.215852 -270.28521)
		(end 277.2537 -263.502648)
		(width 0.1651)
		(layer "In7.Cu")
		(net "P5E_PEX2_STN2_RX_DN<45>")
	)
	(segment
		(start 241.989102 -30.349698)
		(end 239.701324 -30.349698)
		(width 0.1651)
		(layer "In7.Cu")
		(net "P5E_PEX2_STN2_RX_DN<45>")
	)
	(segment
		(start 243.588032 -35.00755)
		(end 243.612416 -31.973012)
		(width 0.1651)
		(layer "In7.Cu")
		(net "P5E_PEX2_STN2_RX_DN<45>")
	)
	(segment
		(start 278.435562 -273.479514)
		(end 278.321008 -273.479514)
		(width 0.1143)
		(layer "In7.Cu")
		(net "P5E_PEX2_STN2_RX_DN<45>")
	)
	(segment
		(start 278.215852 -271.3736)
		(end 278.215852 -271.345152)
		(width 0.1143)
		(layer "In7.Cu")
		(net "P5E_PEX2_STN2_RX_DN<45>")
	)
	(segment
		(start 243.612416 -31.973012)
		(end 241.989102 -30.349698)
		(width 0.1651)
		(layer "In7.Cu")
		(net "P5E_PEX2_STN2_RX_DN<45>")
	)
	(segment
		(start 278.321008 -273.479514)
		(end 278.170132 -273.328638)
		(width 0.1143)
		(layer "In7.Cu")
		(net "P5E_PEX2_STN2_RX_DN<45>")
	)
	(segment
		(start 277.2537 -263.502648)
		(end 277.330662 -255.646936)
		(width 0.1651)
		(layer "In7.Cu")
		(net "P5E_PEX2_STN2_RX_DN<45>")
	)
	(segment
		(start 244.398292 -49.868074)
		(end 243.099336 -40.256206)
		(width 0.1651)
		(layer "In7.Cu")
		(net "P5E_PEX2_STN2_RX_DN<45>")
	)
	(segment
		(start 249.54738 -102.432612)
		(end 249.54738 -102.432104)
		(width 0.1651)
		(layer "In7.Cu")
		(net "P5E_PEX2_STN2_RX_DN<45>")
	)
	(segment
		(start 278.549862 -273.099784)
		(end 278.549862 -273.365214)
		(width 0.1143)
		(layer "In7.Cu")
		(net "P5E_PEX2_STN2_RX_DN<45>")
	)
	(segment
		(start 244.357906 -85.311742)
		(end 244.548406 -61.48959)
		(width 0.1651)
		(layer "In7.Cu")
		(net "P5E_PEX2_STN2_RX_DN<45>")
	)
	(segment
		(start 254.7366 -119.552466)
		(end 249.54738 -102.432612)
		(width 0.1651)
		(layer "In7.Cu")
		(net "P5E_PEX2_STN2_RX_DN<45>")
	)
	(segment
		(start 239.701324 -30.349698)
		(end 239.410494 -30.058868)
		(width 0.1651)
		(layer "In7.Cu")
		(net "P5E_PEX2_STN2_RX_DN<45>")
	)
	(segment
		(start 278.549862 -273.365214)
		(end 278.435562 -273.479514)
		(width 0.1143)
		(layer "In7.Cu")
		(net "P5E_PEX2_STN2_RX_DN<45>")
	)
	(segment
		(start 277.330662 -255.646936)
		(end 275.730716 -238.16945)
		(width 0.1651)
		(layer "In7.Cu")
		(net "P5E_PEX2_STN2_RX_DN<45>")
	)
	(segment
		(start 258.018788 -144.505172)
		(end 254.7366 -119.552466)
		(width 0.1651)
		(layer "In7.Cu")
		(net "P5E_PEX2_STN2_RX_DN<45>")
	)
	(segment
		(start 325.507604 -344.539062)
		(end 325.507604 -345.170506)
		(width 0.13462)
		(layer "F.Cu")
		(net "P5E_PEX2_STN6_TX_C_DN<106>")
	)
	(segment
		(start 325.507604 -345.170506)
		(end 325.802244 -345.465146)
		(width 0.13462)
		(layer "F.Cu")
		(net "P5E_PEX2_STN6_TX_C_DN<106>")
	)
	(segment
		(start 325.827644 -344.219022)
		(end 325.507604 -344.539062)
		(width 0.13462)
		(layer "F.Cu")
		(net "P5E_PEX2_STN6_TX_C_DN<106>")
	)
	(segment
		(start 342.490044 -410.238956)
		(end 342.648032 -410.080968)
		(width 0.1651)
		(layer "In13.Cu")
		(net "P5E_PEX2_STN6_TX_C_DN<106>")
	)
	(segment
		(start 323.956934 -358.894634)
		(end 323.956934 -347.881194)
		(width 0.1651)
		(layer "In13.Cu")
		(net "P5E_PEX2_STN6_TX_C_DN<106>")
	)
	(segment
		(start 343.251282 -394.78712)
		(end 337.460844 -390.373108)
		(width 0.1651)
		(layer "In13.Cu")
		(net "P5E_PEX2_STN6_TX_C_DN<106>")
	)
	(segment
		(start 328.614024 -386.19303)
		(end 323.956934 -358.894634)
		(width 0.1651)
		(layer "In13.Cu")
		(net "P5E_PEX2_STN6_TX_C_DN<106>")
	)
	(segment
		(start 342.490044 -410.589984)
		(end 342.490044 -410.238956)
		(width 0.1651)
		(layer "In13.Cu")
		(net "P5E_PEX2_STN6_TX_C_DN<106>")
	)
	(segment
		(start 323.956934 -347.881194)
		(end 325.511414 -346.326714)
		(width 0.1651)
		(layer "In13.Cu")
		(net "P5E_PEX2_STN6_TX_C_DN<106>")
	)
	(segment
		(start 337.460844 -390.373108)
		(end 330.920344 -388.043166)
		(width 0.1651)
		(layer "In13.Cu")
		(net "P5E_PEX2_STN6_TX_C_DN<106>")
	)
	(segment
		(start 343.616026 -409.629102)
		(end 343.616026 -395.395196)
		(width 0.1651)
		(layer "In13.Cu")
		(net "P5E_PEX2_STN6_TX_C_DN<106>")
	)
	(segment
		(start 330.920344 -388.043166)
		(end 328.614024 -386.19303)
		(width 0.1651)
		(layer "In13.Cu")
		(net "P5E_PEX2_STN6_TX_C_DN<106>")
	)
	(segment
		(start 343.16416 -410.080968)
		(end 343.616026 -409.629102)
		(width 0.1651)
		(layer "In13.Cu")
		(net "P5E_PEX2_STN6_TX_C_DN<106>")
	)
	(segment
		(start 342.648032 -410.080968)
		(end 343.16416 -410.080968)
		(width 0.1651)
		(layer "In13.Cu")
		(net "P5E_PEX2_STN6_TX_C_DN<106>")
	)
	(segment
		(start 325.511414 -345.755976)
		(end 325.802244 -345.465146)
		(width 0.1651)
		(layer "In13.Cu")
		(net "P5E_PEX2_STN6_TX_C_DN<106>")
	)
	(segment
		(start 343.616026 -395.395196)
		(end 343.251282 -394.78712)
		(width 0.1651)
		(layer "In13.Cu")
		(net "P5E_PEX2_STN6_TX_C_DN<106>")
	)
	(segment
		(start 325.511414 -346.326714)
		(end 325.511414 -345.755976)
		(width 0.1651)
		(layer "In13.Cu")
		(net "P5E_PEX2_STN6_TX_C_DN<106>")
	)
	(segment
		(start 399.578576 -107.0864)
		(end 399.42008 -107.244896)
		(width 0.13462)
		(layer "F.Cu")
		(net "P5E_PEX3_STN1_RX_DN<20>")
	)
	(segment
		(start 402.107146 -107.0864)
		(end 399.578576 -107.0864)
		(width 0.13462)
		(layer "F.Cu")
		(net "P5E_PEX3_STN1_RX_DN<20>")
	)
	(segment
		(start 399.42008 -107.244896)
		(end 398.94256 -107.244896)
		(width 0.13462)
		(layer "F.Cu")
		(net "P5E_PEX3_STN1_RX_DN<20>")
	)
	(segment
		(start 402.39696 -107.376214)
		(end 402.107146 -107.0864)
		(width 0.13462)
		(layer "F.Cu")
		(net "P5E_PEX3_STN1_RX_DN<20>")
	)
	(segment
		(start 399.475706 -107.472734)
		(end 399.038318 -107.705652)
		(width 0.1651)
		(layer "In5.Cu")
		(net "P5E_PEX3_STN1_RX_DN<20>")
	)
	(segment
		(start 411.370272 -271.600168)
		(end 411.370272 -273.376136)
		(width 0.1143)
		(layer "In5.Cu")
		(net "P5E_PEX3_STN1_RX_DN<20>")
	)
	(segment
		(start 382.313942 -129.549398)
		(end 380.679452 -150.512018)
		(width 0.1651)
		(layer "In5.Cu")
		(net "P5E_PEX3_STN1_RX_DN<20>")
	)
	(segment
		(start 394.733272 -109.997748)
		(end 394.578586 -109.950504)
		(width 0.1651)
		(layer "In5.Cu")
		(net "P5E_PEX3_STN1_RX_DN<20>")
	)
	(segment
		(start 411.415992 -271.526)
		(end 411.415992 -271.554448)
		(width 0.1143)
		(layer "In5.Cu")
		(net "P5E_PEX3_STN1_RX_DN<20>")
	)
	(segment
		(start 396.246858 -109.191806)
		(end 395.80947 -109.424724)
		(width 0.1651)
		(layer "In5.Cu")
		(net "P5E_PEX3_STN1_RX_DN<20>")
	)
	(segment
		(start 392.421364 -111.413544)
		(end 392.065002 -111.757968)
		(width 0.1651)
		(layer "In5.Cu")
		(net "P5E_PEX3_STN1_RX_DN<20>")
	)
	(segment
		(start 397.32331 -108.618782)
		(end 396.885922 -108.8517)
		(width 0.1651)
		(layer "In5.Cu")
		(net "P5E_PEX3_STN1_RX_DN<20>")
	)
	(segment
		(start 392.780266 -110.90783)
		(end 392.424158 -111.252)
		(width 0.1651)
		(layer "In5.Cu")
		(net "P5E_PEX3_STN1_RX_DN<20>")
	)
	(segment
		(start 411.47365 -273.479514)
		(end 411.635448 -273.479514)
		(width 0.1143)
		(layer "In5.Cu")
		(net "P5E_PEX3_STN1_RX_DN<20>")
	)
	(segment
		(start 390.208262 -113.39322)
		(end 389.410702 -114.80038)
		(width 0.1651)
		(layer "In5.Cu")
		(net "P5E_PEX3_STN1_RX_DN<20>")
	)
	(segment
		(start 411.370272 -273.376136)
		(end 411.47365 -273.479514)
		(width 0.1143)
		(layer "In5.Cu")
		(net "P5E_PEX3_STN1_RX_DN<20>")
	)
	(segment
		(start 395.80947 -109.424724)
		(end 395.655038 -109.37748)
		(width 0.1651)
		(layer "In5.Cu")
		(net "P5E_PEX3_STN1_RX_DN<20>")
	)
	(segment
		(start 391.903458 -111.755174)
		(end 391.54735 -112.099344)
		(width 0.1651)
		(layer "In5.Cu")
		(net "P5E_PEX3_STN1_RX_DN<20>")
	)
	(segment
		(start 394.141452 -110.183168)
		(end 394.094208 -110.337854)
		(width 0.1651)
		(layer "In5.Cu")
		(net "P5E_PEX3_STN1_RX_DN<20>")
	)
	(segment
		(start 396.885922 -108.8517)
		(end 396.731236 -108.804456)
		(width 0.1651)
		(layer "In5.Cu")
		(net "P5E_PEX3_STN1_RX_DN<20>")
	)
	(segment
		(start 394.578586 -109.950504)
		(end 394.141452 -110.183168)
		(width 0.1651)
		(layer "In5.Cu")
		(net "P5E_PEX3_STN1_RX_DN<20>")
	)
	(segment
		(start 411.415992 -269.31239)
		(end 411.415992 -271.526)
		(width 0.1651)
		(layer "In5.Cu")
		(net "P5E_PEX3_STN1_RX_DN<20>")
	)
	(segment
		(start 394.094208 -110.337854)
		(end 393.65682 -110.570772)
		(width 0.1651)
		(layer "In5.Cu")
		(net "P5E_PEX3_STN1_RX_DN<20>")
	)
	(segment
		(start 393.65682 -110.570772)
		(end 393.502134 -110.523528)
		(width 0.1651)
		(layer "In5.Cu")
		(net "P5E_PEX3_STN1_RX_DN<20>")
	)
	(segment
		(start 396.294102 -109.03712)
		(end 396.246858 -109.191806)
		(width 0.1651)
		(layer "In5.Cu")
		(net "P5E_PEX3_STN1_RX_DN<20>")
	)
	(segment
		(start 397.96212 -108.278676)
		(end 397.807688 -108.231432)
		(width 0.1651)
		(layer "In5.Cu")
		(net "P5E_PEX3_STN1_RX_DN<20>")
	)
	(segment
		(start 393.502134 -110.523528)
		(end 392.780266 -110.90783)
		(width 0.1651)
		(layer "In5.Cu")
		(net "P5E_PEX3_STN1_RX_DN<20>")
	)
	(segment
		(start 385.168902 -123.863354)
		(end 382.313942 -129.549398)
		(width 0.1651)
		(layer "In5.Cu")
		(net "P5E_PEX3_STN1_RX_DN<20>")
	)
	(segment
		(start 396.731236 -108.804456)
		(end 396.294102 -109.03712)
		(width 0.1651)
		(layer "In5.Cu")
		(net "P5E_PEX3_STN1_RX_DN<20>")
	)
	(segment
		(start 398.883886 -107.658408)
		(end 398.446752 -107.891072)
		(width 0.1651)
		(layer "In5.Cu")
		(net "P5E_PEX3_STN1_RX_DN<20>")
	)
	(segment
		(start 391.544556 -112.260888)
		(end 391.188194 -112.605312)
		(width 0.1651)
		(layer "In5.Cu")
		(net "P5E_PEX3_STN1_RX_DN<20>")
	)
	(segment
		(start 389.410702 -114.80038)
		(end 387.656324 -122.331226)
		(width 0.1651)
		(layer "In5.Cu")
		(net "P5E_PEX3_STN1_RX_DN<20>")
	)
	(segment
		(start 399.960084 -107.085384)
		(end 399.52295 -107.318048)
		(width 0.1651)
		(layer "In5.Cu")
		(net "P5E_PEX3_STN1_RX_DN<20>")
	)
	(segment
		(start 391.02665 -112.602518)
		(end 390.208262 -113.39322)
		(width 0.1651)
		(layer "In5.Cu")
		(net "P5E_PEX3_STN1_RX_DN<20>")
	)
	(segment
		(start 386.899912 -123.195842)
		(end 385.168902 -123.863354)
		(width 0.1651)
		(layer "In5.Cu")
		(net "P5E_PEX3_STN1_RX_DN<20>")
	)
	(segment
		(start 395.217904 -109.610144)
		(end 395.17066 -109.764576)
		(width 0.1651)
		(layer "In5.Cu")
		(net "P5E_PEX3_STN1_RX_DN<20>")
	)
	(segment
		(start 411.635448 -273.479514)
		(end 411.749748 -273.365214)
		(width 0.1143)
		(layer "In5.Cu")
		(net "P5E_PEX3_STN1_RX_DN<20>")
	)
	(segment
		(start 402.10613 -107.085384)
		(end 399.960084 -107.085384)
		(width 0.1651)
		(layer "In5.Cu")
		(net "P5E_PEX3_STN1_RX_DN<20>")
	)
	(segment
		(start 382.218692 -164.663882)
		(end 411.415992 -269.31239)
		(width 0.1651)
		(layer "In5.Cu")
		(net "P5E_PEX3_STN1_RX_DN<20>")
	)
	(segment
		(start 398.399508 -108.045758)
		(end 397.96212 -108.278676)
		(width 0.1651)
		(layer "In5.Cu")
		(net "P5E_PEX3_STN1_RX_DN<20>")
	)
	(segment
		(start 391.188194 -112.605312)
		(end 391.02665 -112.602518)
		(width 0.1651)
		(layer "In5.Cu")
		(net "P5E_PEX3_STN1_RX_DN<20>")
	)
	(segment
		(start 391.54735 -112.099344)
		(end 391.544556 -112.260888)
		(width 0.1651)
		(layer "In5.Cu")
		(net "P5E_PEX3_STN1_RX_DN<20>")
	)
	(segment
		(start 395.655038 -109.37748)
		(end 395.217904 -109.610144)
		(width 0.1651)
		(layer "In5.Cu")
		(net "P5E_PEX3_STN1_RX_DN<20>")
	)
	(segment
		(start 380.679452 -150.512018)
		(end 381.198374 -158.717488)
		(width 0.1651)
		(layer "In5.Cu")
		(net "P5E_PEX3_STN1_RX_DN<20>")
	)
	(segment
		(start 411.415992 -271.554448)
		(end 411.370272 -271.600168)
		(width 0.1143)
		(layer "In5.Cu")
		(net "P5E_PEX3_STN1_RX_DN<20>")
	)
	(segment
		(start 392.424158 -111.252)
		(end 392.421364 -111.413544)
		(width 0.1651)
		(layer "In5.Cu")
		(net "P5E_PEX3_STN1_RX_DN<20>")
	)
	(segment
		(start 402.39696 -107.376214)
		(end 402.10613 -107.085384)
		(width 0.1651)
		(layer "In5.Cu")
		(net "P5E_PEX3_STN1_RX_DN<20>")
	)
	(segment
		(start 411.749748 -273.365214)
		(end 411.749748 -273.099784)
		(width 0.1143)
		(layer "In5.Cu")
		(net "P5E_PEX3_STN1_RX_DN<20>")
	)
	(segment
		(start 397.807688 -108.231432)
		(end 397.370554 -108.464096)
		(width 0.1651)
		(layer "In5.Cu")
		(net "P5E_PEX3_STN1_RX_DN<20>")
	)
	(segment
		(start 395.17066 -109.764576)
		(end 394.733272 -109.997748)
		(width 0.1651)
		(layer "In5.Cu")
		(net "P5E_PEX3_STN1_RX_DN<20>")
	)
	(segment
		(start 399.52295 -107.318048)
		(end 399.475706 -107.472734)
		(width 0.1651)
		(layer "In5.Cu")
		(net "P5E_PEX3_STN1_RX_DN<20>")
	)
	(segment
		(start 387.656324 -122.331226)
		(end 386.899912 -123.195842)
		(width 0.1651)
		(layer "In5.Cu")
		(net "P5E_PEX3_STN1_RX_DN<20>")
	)
	(segment
		(start 399.038318 -107.705652)
		(end 398.883886 -107.658408)
		(width 0.1651)
		(layer "In5.Cu")
		(net "P5E_PEX3_STN1_RX_DN<20>")
	)
	(segment
		(start 392.065002 -111.757968)
		(end 391.903458 -111.755174)
		(width 0.1651)
		(layer "In5.Cu")
		(net "P5E_PEX3_STN1_RX_DN<20>")
	)
	(segment
		(start 381.198374 -158.717488)
		(end 382.218692 -164.663882)
		(width 0.1651)
		(layer "In5.Cu")
		(net "P5E_PEX3_STN1_RX_DN<20>")
	)
	(segment
		(start 398.446752 -107.891072)
		(end 398.399508 -108.045758)
		(width 0.1651)
		(layer "In5.Cu")
		(net "P5E_PEX3_STN1_RX_DN<20>")
	)
	(segment
		(start 397.370554 -108.464096)
		(end 397.32331 -108.618782)
		(width 0.1651)
		(layer "In5.Cu")
		(net "P5E_PEX3_STN1_RX_DN<20>")
	)
	(segment
		(start 403.34819 -139.6492)
		(end 403.77999 -139.6492)
		(width 0.13208)
		(layer "F.Cu")
		(net "PRSNTB2_NIC6_N")
	)
	(segment
		(start 403.77999 -138.6332)
		(end 403.77999 -139.6492)
		(width 0.13208)
		(layer "F.Cu")
		(net "PRSNTB2_NIC6_N")
	)
	(segment
		(start 398.94256 -139.565126)
		(end 402.570188 -139.565126)
		(width 0.13208)
		(layer "F.Cu")
		(net "PRSNTB2_NIC6_N")
	)
	(segment
		(start 403.264116 -139.565126)
		(end 403.34819 -139.6492)
		(width 0.13208)
		(layer "F.Cu")
		(net "PRSNTB2_NIC6_N")
	)
	(segment
		(start 402.570188 -139.565126)
		(end 403.264116 -139.565126)
		(width 0.13208)
		(layer "F.Cu")
		(net "PRSNTB2_NIC6_N")
	)
	(via
		(at 402.570188 -139.565126)
		(size 0.762)
		(drill 0.381)
		(layers "F.Cu" "B.Cu")
		(net "PRSNTB2_NIC6_N")
	)
	(segment
		(start 45.554392 -132.964936)
		(end 45.391578 -132.802122)
		(width 0.13462)
		(layer "F.Cu")
		(net "P5E_PEX0_STN1_TX_C_DP<29>")
	)
	(segment
		(start 45.391578 -132.802122)
		(end 39.874952 -132.802122)
		(width 0.13462)
		(layer "F.Cu")
		(net "P5E_PEX0_STN1_TX_C_DP<29>")
	)
	(segment
		(start 46.042326 -132.964936)
		(end 45.554392 -132.964936)
		(width 0.13462)
		(layer "F.Cu")
		(net "P5E_PEX0_STN1_TX_C_DP<29>")
	)
	(segment
		(start 39.874952 -132.802122)
		(end 39.547292 -133.129782)
		(width 0.13462)
		(layer "F.Cu")
		(net "P5E_PEX0_STN1_TX_C_DP<29>")
	)
	(segment
		(start 83.134962 -351.611438)
		(end 83.429602 -351.316798)
		(width 0.13462)
		(layer "F.Cu")
		(net "P5E_PEX0_STN6_TX_C_DP<101>")
	)
	(segment
		(start 83.429602 -351.316798)
		(end 83.429602 -350.685354)
		(width 0.13462)
		(layer "F.Cu")
		(net "P5E_PEX0_STN6_TX_C_DP<101>")
	)
	(segment
		(start 83.429602 -350.685354)
		(end 83.109562 -350.365314)
		(width 0.13462)
		(layer "F.Cu")
		(net "P5E_PEX0_STN6_TX_C_DP<101>")
	)
	(segment
		(start 83.134962 -351.611438)
		(end 83.425792 -351.902268)
		(width 0.1651)
		(layer "In13.Cu")
		(net "P5E_PEX0_STN6_TX_C_DP<101>")
	)
	(segment
		(start 78.525116 -366.014762)
		(end 77.202284 -368.811302)
		(width 0.1651)
		(layer "In13.Cu")
		(net "P5E_PEX0_STN6_TX_C_DP<101>")
	)
	(segment
		(start 79.31277 -364.349538)
		(end 79.194406 -364.391956)
		(width 0.1651)
		(layer "In13.Cu")
		(net "P5E_PEX0_STN6_TX_C_DP<101>")
	)
	(segment
		(start 79.194406 -364.391956)
		(end 78.982316 -364.840012)
		(width 0.1651)
		(layer "In13.Cu")
		(net "P5E_PEX0_STN6_TX_C_DP<101>")
	)
	(segment
		(start 79.482188 -363.783626)
		(end 79.524352 -363.90199)
		(width 0.1651)
		(layer "In13.Cu")
		(net "P5E_PEX0_STN6_TX_C_DP<101>")
	)
	(segment
		(start 77.202284 -382.423924)
		(end 76.926948 -382.69926)
		(width 0.1651)
		(layer "In13.Cu")
		(net "P5E_PEX0_STN6_TX_C_DP<101>")
	)
	(segment
		(start 76.926948 -382.69926)
		(end 76.436982 -382.69926)
		(width 0.1651)
		(layer "In13.Cu")
		(net "P5E_PEX0_STN6_TX_C_DP<101>")
	)
	(segment
		(start 81.871312 -358.9401)
		(end 79.812388 -363.293152)
		(width 0.1651)
		(layer "In13.Cu")
		(net "P5E_PEX0_STN6_TX_C_DP<101>")
	)
	(segment
		(start 77.202284 -368.811302)
		(end 77.202284 -382.423924)
		(width 0.1651)
		(layer "In13.Cu")
		(net "P5E_PEX0_STN6_TX_C_DP<101>")
	)
	(segment
		(start 76.436982 -382.69926)
		(end 76.309982 -382.57226)
		(width 0.1651)
		(layer "In13.Cu")
		(net "P5E_PEX0_STN6_TX_C_DP<101>")
	)
	(segment
		(start 78.982316 -364.840012)
		(end 79.024734 -364.958376)
		(width 0.1651)
		(layer "In13.Cu")
		(net "P5E_PEX0_STN6_TX_C_DP<101>")
	)
	(segment
		(start 78.482698 -365.896398)
		(end 78.525116 -366.014762)
		(width 0.1651)
		(layer "In13.Cu")
		(net "P5E_PEX0_STN6_TX_C_DP<101>")
	)
	(segment
		(start 78.694788 -365.448342)
		(end 78.482698 -365.896398)
		(width 0.1651)
		(layer "In13.Cu")
		(net "P5E_PEX0_STN6_TX_C_DP<101>")
	)
	(segment
		(start 83.425792 -352.417888)
		(end 81.871312 -353.972368)
		(width 0.1651)
		(layer "In13.Cu")
		(net "P5E_PEX0_STN6_TX_C_DP<101>")
	)
	(segment
		(start 79.524352 -363.90199)
		(end 79.31277 -364.349538)
		(width 0.1651)
		(layer "In13.Cu")
		(net "P5E_PEX0_STN6_TX_C_DP<101>")
	)
	(segment
		(start 76.309982 -382.57226)
		(end 76.309982 -382.18999)
		(width 0.1651)
		(layer "In13.Cu")
		(net "P5E_PEX0_STN6_TX_C_DP<101>")
	)
	(segment
		(start 79.812388 -363.293152)
		(end 79.694024 -363.33557)
		(width 0.1651)
		(layer "In13.Cu")
		(net "P5E_PEX0_STN6_TX_C_DP<101>")
	)
	(segment
		(start 79.694024 -363.33557)
		(end 79.482188 -363.783626)
		(width 0.1651)
		(layer "In13.Cu")
		(net "P5E_PEX0_STN6_TX_C_DP<101>")
	)
	(segment
		(start 79.024734 -364.958376)
		(end 78.813152 -365.405924)
		(width 0.1651)
		(layer "In13.Cu")
		(net "P5E_PEX0_STN6_TX_C_DP<101>")
	)
	(segment
		(start 78.813152 -365.405924)
		(end 78.694788 -365.448342)
		(width 0.1651)
		(layer "In13.Cu")
		(net "P5E_PEX0_STN6_TX_C_DP<101>")
	)
	(segment
		(start 83.425792 -351.902268)
		(end 83.425792 -352.417888)
		(width 0.1651)
		(layer "In13.Cu")
		(net "P5E_PEX0_STN6_TX_C_DP<101>")
	)
	(segment
		(start 81.871312 -353.972368)
		(end 81.871312 -358.9401)
		(width 0.1651)
		(layer "In13.Cu")
		(net "P5E_PEX0_STN6_TX_C_DP<101>")
	)
	(segment
		(start 300.113954 -32.13608)
		(end 299.967904 -31.99003)
		(width 0.13462)
		(layer "F.Cu")
		(net "P5E_PEX2_STN2_TX_C_DN<38>")
	)
	(segment
		(start 301.414688 -32.13608)
		(end 300.113954 -32.13608)
		(width 0.13462)
		(layer "F.Cu")
		(net "P5E_PEX2_STN2_TX_C_DN<38>")
	)
	(segment
		(start 301.725584 -31.825184)
		(end 301.414688 -32.13608)
		(width 0.13462)
		(layer "F.Cu")
		(net "P5E_PEX2_STN2_TX_C_DN<38>")
	)
	(segment
		(start 299.967904 -31.99003)
		(end 299.46473 -31.99003)
		(width 0.13462)
		(layer "F.Cu")
		(net "P5E_PEX2_STN2_TX_C_DN<38>")
	)
	(segment
		(start 343.27846 -393.275312)
		(end 342.86825 -392.997182)
		(width 0.1651)
		(layer "In5.Cu")
		(net "P5E_PEX2_STN6_RX_DP<105>")
	)
	(segment
		(start 327.3044 -376.677936)
		(end 327.3044 -376.676666)
		(width 0.1651)
		(layer "In5.Cu")
		(net "P5E_PEX2_STN6_RX_DP<105>")
	)
	(segment
		(start 343.81186 -393.529312)
		(end 343.401904 -393.25169)
		(width 0.1651)
		(layer "In5.Cu")
		(net "P5E_PEX2_STN6_RX_DP<105>")
	)
	(segment
		(start 339.433662 -390.968992)
		(end 335.832704 -389.276082)
		(width 0.1651)
		(layer "In5.Cu")
		(net "P5E_PEX2_STN6_RX_DP<105>")
	)
	(segment
		(start 345.247214 -400.899122)
		(end 345.53398 -400.612356)
		(width 0.1651)
		(layer "In5.Cu")
		(net "P5E_PEX2_STN6_RX_DP<105>")
	)
	(segment
		(start 280.783792 -321.041268)
		(end 280.783792 -319.966848)
		(width 0.1651)
		(layer "In5.Cu")
		(net "P5E_PEX2_STN6_RX_DP<105>")
	)
	(segment
		(start 323.680582 -358.75595)
		(end 323.674994 -358.750362)
		(width 0.1651)
		(layer "In5.Cu")
		(net "P5E_PEX2_STN6_RX_DP<105>")
	)
	(segment
		(start 344.369136 -393.90701)
		(end 344.245692 -393.930886)
		(width 0.1651)
		(layer "In5.Cu")
		(net "P5E_PEX2_STN6_RX_DP<105>")
	)
	(segment
		(start 329.921108 -386.598922)
		(end 329.58278 -386.096256)
		(width 0.1651)
		(layer "In5.Cu")
		(net "P5E_PEX2_STN6_RX_DP<105>")
	)
	(segment
		(start 340.666832 -391.594086)
		(end 339.433662 -390.968992)
		(width 0.1651)
		(layer "In5.Cu")
		(net "P5E_PEX2_STN6_RX_DP<105>")
	)
	(segment
		(start 344.816938 -400.899122)
		(end 345.247214 -400.899122)
		(width 0.1651)
		(layer "In5.Cu")
		(net "P5E_PEX2_STN6_RX_DP<105>")
	)
	(segment
		(start 344.971116 -394.314934)
		(end 344.369136 -393.90701)
		(width 0.1651)
		(layer "In5.Cu")
		(net "P5E_PEX2_STN6_RX_DP<105>")
	)
	(segment
		(start 342.844374 -392.873738)
		(end 341.81415 -392.175746)
		(width 0.1651)
		(layer "In5.Cu")
		(net "P5E_PEX2_STN6_RX_DP<105>")
	)
	(segment
		(start 345.53398 -394.98524)
		(end 345.353386 -394.638022)
		(width 0.1651)
		(layer "In5.Cu")
		(net "P5E_PEX2_STN6_RX_DP<105>")
	)
	(segment
		(start 327.622408 -378.251212)
		(end 327.3044 -376.677936)
		(width 0.1651)
		(layer "In5.Cu")
		(net "P5E_PEX2_STN6_RX_DP<105>")
	)
	(segment
		(start 345.53398 -400.612356)
		(end 345.53398 -394.98524)
		(width 0.1651)
		(layer "In5.Cu")
		(net "P5E_PEX2_STN6_RX_DP<105>")
	)
	(segment
		(start 328.832718 -384.236468)
		(end 327.987406 -380.05639)
		(width 0.1651)
		(layer "In5.Cu")
		(net "P5E_PEX2_STN6_RX_DP<105>")
	)
	(segment
		(start 330.419202 -387.08076)
		(end 329.921108 -386.598922)
		(width 0.1651)
		(layer "In5.Cu")
		(net "P5E_PEX2_STN6_RX_DP<105>")
	)
	(segment
		(start 280.783792 -319.966848)
		(end 280.783792 -319.9384)
		(width 0.1143)
		(layer "In5.Cu")
		(net "P5E_PEX2_STN6_RX_DP<105>")
	)
	(segment
		(start 280.783792 -319.9384)
		(end 280.829512 -319.89268)
		(width 0.1143)
		(layer "In5.Cu")
		(net "P5E_PEX2_STN6_RX_DP<105>")
	)
	(segment
		(start 327.882504 -379.987048)
		(end 327.784206 -379.501146)
		(width 0.1651)
		(layer "In5.Cu")
		(net "P5E_PEX2_STN6_RX_DP<105>")
	)
	(segment
		(start 343.401904 -393.25169)
		(end 343.27846 -393.275312)
		(width 0.1651)
		(layer "In5.Cu")
		(net "P5E_PEX2_STN6_RX_DP<105>")
	)
	(segment
		(start 327.987406 -380.05639)
		(end 327.882504 -379.987048)
		(width 0.1651)
		(layer "In5.Cu")
		(net "P5E_PEX2_STN6_RX_DP<105>")
	)
	(segment
		(start 340.711536 -391.730738)
		(end 340.666832 -391.594086)
		(width 0.1651)
		(layer "In5.Cu")
		(net "P5E_PEX2_STN6_RX_DP<105>")
	)
	(segment
		(start 281.285442 -316.229492)
		(end 281.399742 -316.115192)
		(width 0.1143)
		(layer "In5.Cu")
		(net "P5E_PEX2_STN6_RX_DP<105>")
	)
	(segment
		(start 341.290148 -391.910062)
		(end 341.153496 -391.954766)
		(width 0.1651)
		(layer "In5.Cu")
		(net "P5E_PEX2_STN6_RX_DP<105>")
	)
	(segment
		(start 327.756012 -378.911104)
		(end 327.65111 -378.841508)
		(width 0.1651)
		(layer "In5.Cu")
		(net "P5E_PEX2_STN6_RX_DP<105>")
	)
	(segment
		(start 345.353386 -394.638022)
		(end 344.971116 -394.314934)
		(width 0.1651)
		(layer "In5.Cu")
		(net "P5E_PEX2_STN6_RX_DP<105>")
	)
	(segment
		(start 280.829512 -316.455298)
		(end 281.055318 -316.229492)
		(width 0.1143)
		(layer "In5.Cu")
		(net "P5E_PEX2_STN6_RX_DP<105>")
	)
	(segment
		(start 327.3044 -376.676666)
		(end 327.29043 -376.608086)
		(width 0.1651)
		(layer "In5.Cu")
		(net "P5E_PEX2_STN6_RX_DP<105>")
	)
	(segment
		(start 343.835482 -393.652756)
		(end 343.81186 -393.529312)
		(width 0.1651)
		(layer "In5.Cu")
		(net "P5E_PEX2_STN6_RX_DP<105>")
	)
	(segment
		(start 327.65111 -378.841508)
		(end 327.552812 -378.35586)
		(width 0.1651)
		(layer "In5.Cu")
		(net "P5E_PEX2_STN6_RX_DP<105>")
	)
	(segment
		(start 341.81415 -392.175746)
		(end 341.290148 -391.910062)
		(width 0.1651)
		(layer "In5.Cu")
		(net "P5E_PEX2_STN6_RX_DP<105>")
	)
	(segment
		(start 281.399742 -316.115192)
		(end 281.399742 -315.849762)
		(width 0.1143)
		(layer "In5.Cu")
		(net "P5E_PEX2_STN6_RX_DP<105>")
	)
	(segment
		(start 327.853802 -379.396498)
		(end 327.755758 -378.911104)
		(width 0.1651)
		(layer "In5.Cu")
		(net "P5E_PEX2_STN6_RX_DP<105>")
	)
	(segment
		(start 342.86825 -392.997182)
		(end 342.844374 -392.873738)
		(width 0.1651)
		(layer "In5.Cu")
		(net "P5E_PEX2_STN6_RX_DP<105>")
	)
	(segment
		(start 327.29043 -376.608086)
		(end 323.680582 -358.75595)
		(width 0.1651)
		(layer "In5.Cu")
		(net "P5E_PEX2_STN6_RX_DP<105>")
	)
	(segment
		(start 344.689938 -400.390106)
		(end 344.689938 -400.772122)
		(width 0.1651)
		(layer "In5.Cu")
		(net "P5E_PEX2_STN6_RX_DP<105>")
	)
	(segment
		(start 281.055318 -316.229492)
		(end 281.285442 -316.229492)
		(width 0.1143)
		(layer "In5.Cu")
		(net "P5E_PEX2_STN6_RX_DP<105>")
	)
	(segment
		(start 344.689938 -400.772122)
		(end 344.816938 -400.899122)
		(width 0.1651)
		(layer "In5.Cu")
		(net "P5E_PEX2_STN6_RX_DP<105>")
	)
	(segment
		(start 280.829512 -319.89268)
		(end 280.829512 -316.455298)
		(width 0.1143)
		(layer "In5.Cu")
		(net "P5E_PEX2_STN6_RX_DP<105>")
	)
	(segment
		(start 344.245692 -393.930886)
		(end 343.835482 -393.652756)
		(width 0.1651)
		(layer "In5.Cu")
		(net "P5E_PEX2_STN6_RX_DP<105>")
	)
	(segment
		(start 322.836794 -341.13978)
		(end 281.093418 -321.63639)
		(width 0.1651)
		(layer "In5.Cu")
		(net "P5E_PEX2_STN6_RX_DP<105>")
	)
	(segment
		(start 329.58278 -386.096256)
		(end 328.832718 -384.236468)
		(width 0.1651)
		(layer "In5.Cu")
		(net "P5E_PEX2_STN6_RX_DP<105>")
	)
	(segment
		(start 327.784206 -379.501146)
		(end 327.853802 -379.396498)
		(width 0.1651)
		(layer "In5.Cu")
		(net "P5E_PEX2_STN6_RX_DP<105>")
	)
	(segment
		(start 327.552812 -378.35586)
		(end 327.622408 -378.251212)
		(width 0.1651)
		(layer "In5.Cu")
		(net "P5E_PEX2_STN6_RX_DP<105>")
	)
	(segment
		(start 281.093418 -321.63639)
		(end 280.783792 -321.041268)
		(width 0.1651)
		(layer "In5.Cu")
		(net "P5E_PEX2_STN6_RX_DP<105>")
	)
	(segment
		(start 341.153496 -391.954766)
		(end 340.711536 -391.730738)
		(width 0.1651)
		(layer "In5.Cu")
		(net "P5E_PEX2_STN6_RX_DP<105>")
	)
	(segment
		(start 323.674994 -341.97798)
		(end 322.836794 -341.13978)
		(width 0.1651)
		(layer "In5.Cu")
		(net "P5E_PEX2_STN6_RX_DP<105>")
	)
	(segment
		(start 323.674994 -358.750362)
		(end 323.674994 -341.97798)
		(width 0.1651)
		(layer "In5.Cu")
		(net "P5E_PEX2_STN6_RX_DP<105>")
	)
	(segment
		(start 335.832704 -389.276082)
		(end 330.419202 -387.08076)
		(width 0.1651)
		(layer "In5.Cu")
		(net "P5E_PEX2_STN6_RX_DP<105>")
	)
	(segment
		(start 327.755758 -378.911104)
		(end 327.756012 -378.911104)
		(width 0.1651)
		(layer "In5.Cu")
		(net "P5E_PEX2_STN6_RX_DP<105>")
	)
	(segment
		(start 402.096732 -134.33298)
		(end 399.593054 -134.33298)
		(width 0.13462)
		(layer "F.Cu")
		(net "P5E_PEX3_STN1_RX_DP<30>")
	)
	(segment
		(start 402.39696 -134.032752)
		(end 402.096732 -134.33298)
		(width 0.13462)
		(layer "F.Cu")
		(net "P5E_PEX3_STN1_RX_DP<30>")
	)
	(segment
		(start 399.593054 -134.33298)
		(end 399.42516 -134.165086)
		(width 0.13462)
		(layer "F.Cu")
		(net "P5E_PEX3_STN1_RX_DP<30>")
	)
	(segment
		(start 399.42516 -134.165086)
		(end 398.94256 -134.165086)
		(width 0.13462)
		(layer "F.Cu")
		(net "P5E_PEX3_STN1_RX_DP<30>")
	)
	(segment
		(start 399.279364 -134.697216)
		(end 399.090896 -134.87654)
		(width 0.1651)
		(layer "In5.Cu")
		(net "P5E_PEX3_STN1_RX_DP<30>")
	)
	(segment
		(start 421.249602 -273.784314)
		(end 421.249602 -274.049744)
		(width 0.1143)
		(layer "In5.Cu")
		(net "P5E_PEX3_STN1_RX_DP<30>")
	)
	(segment
		(start 420.679626 -271.600168)
		(end 420.679626 -273.45513)
		(width 0.1143)
		(layer "In5.Cu")
		(net "P5E_PEX3_STN1_RX_DP<30>")
	)
	(segment
		(start 420.633906 -271.396714)
		(end 420.633398 -271.397222)
		(width 0.1651)
		(layer "In5.Cu")
		(net "P5E_PEX3_STN1_RX_DP<30>")
	)
	(segment
		(start 394.85189 -145.262854)
		(end 394.53185 -145.741136)
		(width 0.1651)
		(layer "In5.Cu")
		(net "P5E_PEX3_STN1_RX_DP<30>")
	)
	(segment
		(start 421.135302 -273.670014)
		(end 421.249602 -273.784314)
		(width 0.1143)
		(layer "In5.Cu")
		(net "P5E_PEX3_STN1_RX_DP<30>")
	)
	(segment
		(start 400.181572 -134.323582)
		(end 399.279364 -134.697216)
		(width 0.1651)
		(layer "In5.Cu")
		(net "P5E_PEX3_STN1_RX_DP<30>")
	)
	(segment
		(start 420.633398 -271.397222)
		(end 420.633398 -271.39773)
		(width 0.1651)
		(layer "In5.Cu")
		(net "P5E_PEX3_STN1_RX_DP<30>")
	)
	(segment
		(start 420.633398 -271.39773)
		(end 420.633906 -271.398238)
		(width 0.1651)
		(layer "In5.Cu")
		(net "P5E_PEX3_STN1_RX_DP<30>")
	)
	(segment
		(start 420.679626 -273.45513)
		(end 420.89451 -273.670014)
		(width 0.1143)
		(layer "In5.Cu")
		(net "P5E_PEX3_STN1_RX_DP<30>")
	)
	(segment
		(start 398.06626 -137.042906)
		(end 398.039336 -137.06983)
		(width 0.1651)
		(layer "In5.Cu")
		(net "P5E_PEX3_STN1_RX_DP<30>")
	)
	(segment
		(start 420.633906 -267.270738)
		(end 420.633906 -271.396714)
		(width 0.1651)
		(layer "In5.Cu")
		(net "P5E_PEX3_STN1_RX_DP<30>")
	)
	(segment
		(start 420.633906 -271.526)
		(end 420.633906 -271.554448)
		(width 0.1143)
		(layer "In5.Cu")
		(net "P5E_PEX3_STN1_RX_DP<30>")
	)
	(segment
		(start 420.633906 -271.398238)
		(end 420.633906 -271.526)
		(width 0.1651)
		(layer "In5.Cu")
		(net "P5E_PEX3_STN1_RX_DP<30>")
	)
	(segment
		(start 420.89451 -273.670014)
		(end 421.135302 -273.670014)
		(width 0.1143)
		(layer "In5.Cu")
		(net "P5E_PEX3_STN1_RX_DP<30>")
	)
	(segment
		(start 392.265916 -146.8882)
		(end 391.903966 -146.99361)
		(width 0.1651)
		(layer "In5.Cu")
		(net "P5E_PEX3_STN1_RX_DP<30>")
	)
	(segment
		(start 390.999218 -148.044154)
		(end 391.57656 -156.747972)
		(width 0.1651)
		(layer "In5.Cu")
		(net "P5E_PEX3_STN1_RX_DP<30>")
	)
	(segment
		(start 391.903966 -146.99361)
		(end 391.715752 -147.087844)
		(width 0.1651)
		(layer "In5.Cu")
		(net "P5E_PEX3_STN1_RX_DP<30>")
	)
	(segment
		(start 391.57656 -156.747972)
		(end 392.292586 -160.767776)
		(width 0.1651)
		(layer "In5.Cu")
		(net "P5E_PEX3_STN1_RX_DP<30>")
	)
	(segment
		(start 402.39696 -134.032752)
		(end 402.10613 -134.323582)
		(width 0.1651)
		(layer "In5.Cu")
		(net "P5E_PEX3_STN1_RX_DP<30>")
	)
	(segment
		(start 393.837414 -146.435572)
		(end 392.744452 -146.8882)
		(width 0.1651)
		(layer "In5.Cu")
		(net "P5E_PEX3_STN1_RX_DP<30>")
	)
	(segment
		(start 391.715752 -147.087844)
		(end 391.31367 -147.389596)
		(width 0.1651)
		(layer "In5.Cu")
		(net "P5E_PEX3_STN1_RX_DP<30>")
	)
	(segment
		(start 392.744452 -146.8882)
		(end 392.265916 -146.8882)
		(width 0.1651)
		(layer "In5.Cu")
		(net "P5E_PEX3_STN1_RX_DP<30>")
	)
	(segment
		(start 402.10613 -134.323582)
		(end 400.181572 -134.323582)
		(width 0.1651)
		(layer "In5.Cu")
		(net "P5E_PEX3_STN1_RX_DP<30>")
	)
	(segment
		(start 396.297658 -144.077182)
		(end 394.85189 -145.262854)
		(width 0.1651)
		(layer "In5.Cu")
		(net "P5E_PEX3_STN1_RX_DP<30>")
	)
	(segment
		(start 398.039336 -137.06983)
		(end 398.039336 -141.153642)
		(width 0.1651)
		(layer "In5.Cu")
		(net "P5E_PEX3_STN1_RX_DP<30>")
	)
	(segment
		(start 397.203676 -143.171164)
		(end 396.297658 -144.077182)
		(width 0.1651)
		(layer "In5.Cu")
		(net "P5E_PEX3_STN1_RX_DP<30>")
	)
	(segment
		(start 420.633906 -271.554448)
		(end 420.679626 -271.600168)
		(width 0.1143)
		(layer "In5.Cu")
		(net "P5E_PEX3_STN1_RX_DP<30>")
	)
	(segment
		(start 392.292586 -160.767776)
		(end 420.633906 -267.270738)
		(width 0.1651)
		(layer "In5.Cu")
		(net "P5E_PEX3_STN1_RX_DP<30>")
	)
	(segment
		(start 398.039336 -141.153642)
		(end 397.203676 -143.171164)
		(width 0.1651)
		(layer "In5.Cu")
		(net "P5E_PEX3_STN1_RX_DP<30>")
	)
	(segment
		(start 394.53185 -145.741136)
		(end 393.837414 -146.435572)
		(width 0.1651)
		(layer "In5.Cu")
		(net "P5E_PEX3_STN1_RX_DP<30>")
	)
	(segment
		(start 391.31367 -147.389596)
		(end 390.999218 -148.044154)
		(width 0.1651)
		(layer "In5.Cu")
		(net "P5E_PEX3_STN1_RX_DP<30>")
	)
	(segment
		(start 399.090896 -134.87654)
		(end 398.06626 -137.042906)
		(width 0.1651)
		(layer "In5.Cu")
		(net "P5E_PEX3_STN1_RX_DP<30>")
	)
	(segment
		(start 87.107522 -345.465146)
		(end 86.812882 -345.170506)
		(width 0.13462)
		(layer "F.Cu")
		(net "P5E_PEX0_STN6_TX_C_DN<100>")
	)
	(segment
		(start 86.812882 -345.170506)
		(end 86.812882 -344.539062)
		(width 0.13462)
		(layer "F.Cu")
		(net "P5E_PEX0_STN6_TX_C_DN<100>")
	)
	(segment
		(start 86.812882 -344.539062)
		(end 87.132922 -344.219022)
		(width 0.13462)
		(layer "F.Cu")
		(net "P5E_PEX0_STN6_TX_C_DN<100>")
	)
	(segment
		(start 79.684372 -383.677668)
		(end 79.684372 -369.306094)
		(width 0.1651)
		(layer "In13.Cu")
		(net "P5E_PEX0_STN6_TX_C_DN<100>")
	)
	(segment
		(start 86.816692 -345.755976)
		(end 87.107522 -345.465146)
		(width 0.1651)
		(layer "In13.Cu")
		(net "P5E_PEX0_STN6_TX_C_DN<100>")
	)
	(segment
		(start 78.636876 -384.08102)
		(end 79.28102 -384.08102)
		(width 0.1651)
		(layer "In13.Cu")
		(net "P5E_PEX0_STN6_TX_C_DN<100>")
	)
	(segment
		(start 85.262212 -347.983048)
		(end 86.816692 -346.428568)
		(width 0.1651)
		(layer "In13.Cu")
		(net "P5E_PEX0_STN6_TX_C_DN<100>")
	)
	(segment
		(start 78.509876 -384.590036)
		(end 78.509876 -384.20802)
		(width 0.1651)
		(layer "In13.Cu")
		(net "P5E_PEX0_STN6_TX_C_DN<100>")
	)
	(segment
		(start 79.28102 -384.08102)
		(end 79.684372 -383.677668)
		(width 0.1651)
		(layer "In13.Cu")
		(net "P5E_PEX0_STN6_TX_C_DN<100>")
	)
	(segment
		(start 79.684372 -369.306094)
		(end 83.696048 -360.824018)
		(width 0.1651)
		(layer "In13.Cu")
		(net "P5E_PEX0_STN6_TX_C_DN<100>")
	)
	(segment
		(start 85.262212 -358.479852)
		(end 85.262212 -347.983048)
		(width 0.1651)
		(layer "In13.Cu")
		(net "P5E_PEX0_STN6_TX_C_DN<100>")
	)
	(segment
		(start 78.509876 -384.20802)
		(end 78.636876 -384.08102)
		(width 0.1651)
		(layer "In13.Cu")
		(net "P5E_PEX0_STN6_TX_C_DN<100>")
	)
	(segment
		(start 83.696048 -360.824018)
		(end 85.262212 -358.479852)
		(width 0.1651)
		(layer "In13.Cu")
		(net "P5E_PEX0_STN6_TX_C_DN<100>")
	)
	(segment
		(start 86.816692 -346.428568)
		(end 86.816692 -345.755976)
		(width 0.1651)
		(layer "In13.Cu")
		(net "P5E_PEX0_STN6_TX_C_DN<100>")
	)
	(segment
		(start 301.396146 -28.55468)
		(end 300.132496 -28.55468)
		(width 0.13462)
		(layer "F.Cu")
		(net "P5E_PEX2_STN2_TX_C_DN<36>")
	)
	(segment
		(start 301.725584 -28.225242)
		(end 301.396146 -28.55468)
		(width 0.13462)
		(layer "F.Cu")
		(net "P5E_PEX2_STN2_TX_C_DN<36>")
	)
	(segment
		(start 300.132496 -28.55468)
		(end 299.967904 -28.390088)
		(width 0.13462)
		(layer "F.Cu")
		(net "P5E_PEX2_STN2_TX_C_DN<36>")
	)
	(segment
		(start 299.967904 -28.390088)
		(end 299.46473 -28.390088)
		(width 0.13462)
		(layer "F.Cu")
		(net "P5E_PEX2_STN2_TX_C_DN<36>")
	)
	(segment
		(start 283.299916 -316.140592)
		(end 283.299916 -315.849762)
		(width 0.1143)
		(layer "In9.Cu")
		(net "P5E_PEX2_STN6_RX_DP<103>")
	)
	(segment
		(start 326.783446 -366.440974)
		(end 326.732138 -366.326166)
		(width 0.1651)
		(layer "In9.Cu")
		(net "P5E_PEX2_STN6_RX_DP<103>")
	)
	(segment
		(start 286.188912 -330.274422)
		(end 284.070806 -328.176382)
		(width 0.1651)
		(layer "In9.Cu")
		(net "P5E_PEX2_STN6_RX_DP<103>")
	)
	(segment
		(start 283.381704 -327.145904)
		(end 282.683966 -325.461376)
		(width 0.1651)
		(layer "In9.Cu")
		(net "P5E_PEX2_STN6_RX_DP<103>")
	)
	(segment
		(start 282.683966 -325.461376)
		(end 282.683966 -319.916048)
		(width 0.1651)
		(layer "In9.Cu")
		(net "P5E_PEX2_STN6_RX_DP<103>")
	)
	(segment
		(start 283.211016 -316.229492)
		(end 283.299916 -316.140592)
		(width 0.1143)
		(layer "In9.Cu")
		(net "P5E_PEX2_STN6_RX_DP<103>")
	)
	(segment
		(start 325.640446 -365.90859)
		(end 325.178166 -365.731552)
		(width 0.1651)
		(layer "In9.Cu")
		(net "P5E_PEX2_STN6_RX_DP<103>")
	)
	(segment
		(start 331.901546 -368.438684)
		(end 331.515466 -368.157252)
		(width 0.1651)
		(layer "In9.Cu")
		(net "P5E_PEX2_STN6_RX_DP<103>")
	)
	(segment
		(start 282.729686 -316.455044)
		(end 282.955238 -316.229492)
		(width 0.1143)
		(layer "In9.Cu")
		(net "P5E_PEX2_STN6_RX_DP<103>")
	)
	(segment
		(start 332.334108 -369.254278)
		(end 331.901546 -368.438684)
		(width 0.1651)
		(layer "In9.Cu")
		(net "P5E_PEX2_STN6_RX_DP<103>")
	)
	(segment
		(start 326.154796 -366.200436)
		(end 325.692008 -366.023144)
		(width 0.1651)
		(layer "In9.Cu")
		(net "P5E_PEX2_STN6_RX_DP<103>")
	)
	(segment
		(start 328.337672 -367.036096)
		(end 327.87463 -366.858804)
		(width 0.1651)
		(layer "In9.Cu")
		(net "P5E_PEX2_STN6_RX_DP<103>")
	)
	(segment
		(start 325.178166 -365.731552)
		(end 325.178166 -365.731298)
		(width 0.1651)
		(layer "In9.Cu")
		(net "P5E_PEX2_STN6_RX_DP<103>")
	)
	(segment
		(start 282.683966 -319.8876)
		(end 282.729686 -319.84188)
		(width 0.1143)
		(layer "In9.Cu")
		(net "P5E_PEX2_STN6_RX_DP<103>")
	)
	(segment
		(start 332.047342 -374.899174)
		(end 332.334108 -374.612408)
		(width 0.1651)
		(layer "In9.Cu")
		(net "P5E_PEX2_STN6_RX_DP<103>")
	)
	(segment
		(start 323.509132 -365.187484)
		(end 323.457824 -365.072676)
		(width 0.1651)
		(layer "In9.Cu")
		(net "P5E_PEX2_STN6_RX_DP<103>")
	)
	(segment
		(start 327.823576 -366.743996)
		(end 327.361042 -366.566958)
		(width 0.1651)
		(layer "In9.Cu")
		(net "P5E_PEX2_STN6_RX_DP<103>")
	)
	(segment
		(start 325.6407 -365.908336)
		(end 325.640446 -365.90859)
		(width 0.1651)
		(layer "In9.Cu")
		(net "P5E_PEX2_STN6_RX_DP<103>")
	)
	(segment
		(start 331.490066 -374.390158)
		(end 331.490066 -374.772174)
		(width 0.1651)
		(layer "In9.Cu")
		(net "P5E_PEX2_STN6_RX_DP<103>")
	)
	(segment
		(start 326.732138 -366.326166)
		(end 326.269604 -366.149128)
		(width 0.1651)
		(layer "In9.Cu")
		(net "P5E_PEX2_STN6_RX_DP<103>")
	)
	(segment
		(start 314.917074 -361.803696)
		(end 313.296046 -360.153204)
		(width 0.1651)
		(layer "In9.Cu")
		(net "P5E_PEX2_STN6_RX_DP<103>")
	)
	(segment
		(start 327.361042 -366.566958)
		(end 327.246234 -366.618266)
		(width 0.1651)
		(layer "In9.Cu")
		(net "P5E_PEX2_STN6_RX_DP<103>")
	)
	(segment
		(start 324.086728 -365.313468)
		(end 323.97192 -365.364776)
		(width 0.1651)
		(layer "In9.Cu")
		(net "P5E_PEX2_STN6_RX_DP<103>")
	)
	(segment
		(start 326.269604 -366.149128)
		(end 326.154796 -366.200436)
		(width 0.1651)
		(layer "In9.Cu")
		(net "P5E_PEX2_STN6_RX_DP<103>")
	)
	(segment
		(start 324.60057 -365.605314)
		(end 324.549262 -365.490506)
		(width 0.1651)
		(layer "In9.Cu")
		(net "P5E_PEX2_STN6_RX_DP<103>")
	)
	(segment
		(start 332.334108 -374.612408)
		(end 332.334108 -369.254278)
		(width 0.1651)
		(layer "In9.Cu")
		(net "P5E_PEX2_STN6_RX_DP<103>")
	)
	(segment
		(start 331.617066 -374.899174)
		(end 332.047342 -374.899174)
		(width 0.1651)
		(layer "In9.Cu")
		(net "P5E_PEX2_STN6_RX_DP<103>")
	)
	(segment
		(start 282.729686 -319.84188)
		(end 282.729686 -316.455044)
		(width 0.1143)
		(layer "In9.Cu")
		(net "P5E_PEX2_STN6_RX_DP<103>")
	)
	(segment
		(start 324.549262 -365.490506)
		(end 324.549262 -365.49076)
		(width 0.1651)
		(layer "In9.Cu")
		(net "P5E_PEX2_STN6_RX_DP<103>")
	)
	(segment
		(start 300.468792 -341.55888)
		(end 286.188912 -330.274422)
		(width 0.1651)
		(layer "In9.Cu")
		(net "P5E_PEX2_STN6_RX_DP<103>")
	)
	(segment
		(start 282.955238 -316.229492)
		(end 283.211016 -316.229492)
		(width 0.1143)
		(layer "In9.Cu")
		(net "P5E_PEX2_STN6_RX_DP<103>")
	)
	(segment
		(start 327.246234 -366.618266)
		(end 326.783446 -366.440974)
		(width 0.1651)
		(layer "In9.Cu")
		(net "P5E_PEX2_STN6_RX_DP<103>")
	)
	(segment
		(start 282.683966 -319.916048)
		(end 282.683966 -319.8876)
		(width 0.1143)
		(layer "In9.Cu")
		(net "P5E_PEX2_STN6_RX_DP<103>")
	)
	(segment
		(start 323.457824 -365.072676)
		(end 323.45757 -365.07293)
		(width 0.1651)
		(layer "In9.Cu")
		(net "P5E_PEX2_STN6_RX_DP<103>")
	)
	(segment
		(start 327.87463 -366.858804)
		(end 327.823576 -366.743996)
		(width 0.1651)
		(layer "In9.Cu")
		(net "P5E_PEX2_STN6_RX_DP<103>")
	)
	(segment
		(start 324.086728 -365.313722)
		(end 324.086728 -365.313468)
		(width 0.1651)
		(layer "In9.Cu")
		(net "P5E_PEX2_STN6_RX_DP<103>")
	)
	(segment
		(start 325.063358 -365.782606)
		(end 324.60057 -365.605314)
		(width 0.1651)
		(layer "In9.Cu")
		(net "P5E_PEX2_STN6_RX_DP<103>")
	)
	(segment
		(start 325.178166 -365.731298)
		(end 325.063358 -365.782606)
		(width 0.1651)
		(layer "In9.Cu")
		(net "P5E_PEX2_STN6_RX_DP<103>")
	)
	(segment
		(start 284.070806 -328.176382)
		(end 283.381704 -327.145904)
		(width 0.1651)
		(layer "In9.Cu")
		(net "P5E_PEX2_STN6_RX_DP<103>")
	)
	(segment
		(start 328.45248 -366.984788)
		(end 328.337672 -367.036096)
		(width 0.1651)
		(layer "In9.Cu")
		(net "P5E_PEX2_STN6_RX_DP<103>")
	)
	(segment
		(start 313.296046 -360.153204)
		(end 300.468792 -341.55888)
		(width 0.1651)
		(layer "In9.Cu")
		(net "P5E_PEX2_STN6_RX_DP<103>")
	)
	(segment
		(start 331.490066 -374.772174)
		(end 331.617066 -374.899174)
		(width 0.1651)
		(layer "In9.Cu")
		(net "P5E_PEX2_STN6_RX_DP<103>")
	)
	(segment
		(start 323.97192 -365.364776)
		(end 323.509132 -365.187484)
		(width 0.1651)
		(layer "In9.Cu")
		(net "P5E_PEX2_STN6_RX_DP<103>")
	)
	(segment
		(start 323.45757 -365.07293)
		(end 314.917074 -361.803696)
		(width 0.1651)
		(layer "In9.Cu")
		(net "P5E_PEX2_STN6_RX_DP<103>")
	)
	(segment
		(start 325.692008 -366.023144)
		(end 325.6407 -365.908336)
		(width 0.1651)
		(layer "In9.Cu")
		(net "P5E_PEX2_STN6_RX_DP<103>")
	)
	(segment
		(start 324.549262 -365.49076)
		(end 324.086728 -365.313722)
		(width 0.1651)
		(layer "In9.Cu")
		(net "P5E_PEX2_STN6_RX_DP<103>")
	)
	(segment
		(start 331.515466 -368.157252)
		(end 328.45248 -366.984788)
		(width 0.1651)
		(layer "In9.Cu")
		(net "P5E_PEX2_STN6_RX_DP<103>")
	)
	(segment
		(start 393.839446 -105.445052)
		(end 394.342366 -105.445052)
		(width 0.13462)
		(layer "F.Cu")
		(net "P5E_PEX3_STN1_TX_C_DP<19>")
	)
	(segment
		(start 385.532122 -105.283)
		(end 393.677394 -105.283)
		(width 0.13462)
		(layer "F.Cu")
		(net "P5E_PEX3_STN1_TX_C_DP<19>")
	)
	(segment
		(start 385.205224 -105.609898)
		(end 385.532122 -105.283)
		(width 0.13462)
		(layer "F.Cu")
		(net "P5E_PEX3_STN1_TX_C_DP<19>")
	)
	(segment
		(start 393.677394 -105.283)
		(end 393.839446 -105.445052)
		(width 0.13462)
		(layer "F.Cu")
		(net "P5E_PEX3_STN1_TX_C_DP<19>")
	)
	(segment
		(start 387.299962 -150.263352)
		(end 388.64032 -150.263352)
		(width 0.13208)
		(layer "F.Cu")
		(net "NCSI_NIC6_CRS_DV")
	)
	(segment
		(start 390.88695 -150.212552)
		(end 391.234422 -150.560024)
		(width 0.13208)
		(layer "F.Cu")
		(net "NCSI_NIC6_CRS_DV")
	)
	(segment
		(start 391.234422 -150.560024)
		(end 394.342366 -150.560024)
		(width 0.13208)
		(layer "F.Cu")
		(net "NCSI_NIC6_CRS_DV")
	)
	(segment
		(start 388.69112 -150.212552)
		(end 390.88695 -150.212552)
		(width 0.13208)
		(layer "F.Cu")
		(net "NCSI_NIC6_CRS_DV")
	)
	(segment
		(start 388.64032 -150.263352)
		(end 388.69112 -150.212552)
		(width 0.13208)
		(layer "F.Cu")
		(net "NCSI_NIC6_CRS_DV")
	)
	(via
		(at 388.69112 -150.212552)
		(size 0.762)
		(drill 0.381)
		(layers "F.Cu" "B.Cu")
		(net "NCSI_NIC6_CRS_DV")
	)
	(segment
		(start 55.965852 -325.497952)
		(end 55.233824 -323.731128)
		(width 0.1651)
		(layer "In9.Cu")
		(net "P5E_PEX0_STN6_RX_DP<98>")
	)
	(segment
		(start 69.283834 -341.395558)
		(end 66.803778 -337.683602)
		(width 0.1651)
		(layer "In9.Cu")
		(net "P5E_PEX0_STN6_RX_DP<98>")
	)
	(segment
		(start 55.233824 -319.893696)
		(end 55.233824 -319.865248)
		(width 0.1143)
		(layer "In9.Cu")
		(net "P5E_PEX0_STN6_RX_DP<98>")
	)
	(segment
		(start 83.48091 -375.999248)
		(end 83.80222 -375.677938)
		(width 0.1651)
		(layer "In9.Cu")
		(net "P5E_PEX0_STN6_RX_DP<98>")
	)
	(segment
		(start 83.142836 -368.001296)
		(end 76.7969 -363.76102)
		(width 0.1651)
		(layer "In9.Cu")
		(net "P5E_PEX0_STN6_RX_DP<98>")
	)
	(segment
		(start 83.80222 -375.677938)
		(end 83.80222 -369.592606)
		(width 0.1651)
		(layer "In9.Cu")
		(net "P5E_PEX0_STN6_RX_DP<98>")
	)
	(segment
		(start 55.233824 -323.731128)
		(end 55.233824 -319.893696)
		(width 0.1651)
		(layer "In9.Cu")
		(net "P5E_PEX0_STN6_RX_DP<98>")
	)
	(segment
		(start 55.760874 -318.129666)
		(end 55.849774 -318.040766)
		(width 0.1143)
		(layer "In9.Cu")
		(net "P5E_PEX0_STN6_RX_DP<98>")
	)
	(segment
		(start 82.909918 -375.872248)
		(end 83.036918 -375.999248)
		(width 0.1651)
		(layer "In9.Cu")
		(net "P5E_PEX0_STN6_RX_DP<98>")
	)
	(segment
		(start 64.826134 -335.27365)
		(end 55.965852 -325.497952)
		(width 0.1651)
		(layer "In9.Cu")
		(net "P5E_PEX0_STN6_RX_DP<98>")
	)
	(segment
		(start 55.279544 -318.406272)
		(end 55.55615 -318.129666)
		(width 0.1143)
		(layer "In9.Cu")
		(net "P5E_PEX0_STN6_RX_DP<98>")
	)
	(segment
		(start 55.233824 -319.865248)
		(end 55.279544 -319.819528)
		(width 0.1143)
		(layer "In9.Cu")
		(net "P5E_PEX0_STN6_RX_DP<98>")
	)
	(segment
		(start 76.226416 -363.51718)
		(end 76.19492 -363.358684)
		(width 0.1651)
		(layer "In9.Cu")
		(net "P5E_PEX0_STN6_RX_DP<98>")
	)
	(segment
		(start 55.279544 -319.819528)
		(end 55.279544 -318.406272)
		(width 0.1143)
		(layer "In9.Cu")
		(net "P5E_PEX0_STN6_RX_DP<98>")
	)
	(segment
		(start 70.527418 -359.571798)
		(end 69.77253 -358.81691)
		(width 0.1651)
		(layer "In9.Cu")
		(net "P5E_PEX0_STN6_RX_DP<98>")
	)
	(segment
		(start 76.19492 -363.358684)
		(end 76.194666 -363.358684)
		(width 0.1651)
		(layer "In9.Cu")
		(net "P5E_PEX0_STN6_RX_DP<98>")
	)
	(segment
		(start 76.638404 -363.792516)
		(end 76.226416 -363.51718)
		(width 0.1651)
		(layer "In9.Cu")
		(net "P5E_PEX0_STN6_RX_DP<98>")
	)
	(segment
		(start 83.80222 -369.592606)
		(end 83.142836 -368.001296)
		(width 0.1651)
		(layer "In9.Cu")
		(net "P5E_PEX0_STN6_RX_DP<98>")
	)
	(segment
		(start 66.803778 -337.683602)
		(end 64.826134 -335.27365)
		(width 0.1651)
		(layer "In9.Cu")
		(net "P5E_PEX0_STN6_RX_DP<98>")
	)
	(segment
		(start 83.036918 -375.999248)
		(end 83.48091 -375.999248)
		(width 0.1651)
		(layer "In9.Cu")
		(net "P5E_PEX0_STN6_RX_DP<98>")
	)
	(segment
		(start 55.849774 -318.040766)
		(end 55.849774 -317.749936)
		(width 0.1143)
		(layer "In9.Cu")
		(net "P5E_PEX0_STN6_RX_DP<98>")
	)
	(segment
		(start 69.435472 -341.894414)
		(end 69.283834 -341.395558)
		(width 0.1651)
		(layer "In9.Cu")
		(net "P5E_PEX0_STN6_RX_DP<98>")
	)
	(segment
		(start 82.909918 -375.490232)
		(end 82.909918 -375.872248)
		(width 0.1651)
		(layer "In9.Cu")
		(net "P5E_PEX0_STN6_RX_DP<98>")
	)
	(segment
		(start 76.7969 -363.76102)
		(end 76.638404 -363.792516)
		(width 0.1651)
		(layer "In9.Cu")
		(net "P5E_PEX0_STN6_RX_DP<98>")
	)
	(segment
		(start 69.77253 -358.81691)
		(end 69.435472 -358.003094)
		(width 0.1651)
		(layer "In9.Cu")
		(net "P5E_PEX0_STN6_RX_DP<98>")
	)
	(segment
		(start 69.435472 -358.003094)
		(end 69.435472 -341.894414)
		(width 0.1651)
		(layer "In9.Cu")
		(net "P5E_PEX0_STN6_RX_DP<98>")
	)
	(segment
		(start 76.194666 -363.358684)
		(end 70.527418 -359.571798)
		(width 0.1651)
		(layer "In9.Cu")
		(net "P5E_PEX0_STN6_RX_DP<98>")
	)
	(segment
		(start 55.55615 -318.129666)
		(end 55.760874 -318.129666)
		(width 0.1143)
		(layer "In9.Cu")
		(net "P5E_PEX0_STN6_RX_DP<98>")
	)
	(segment
		(start 274.114006 -32.13608)
		(end 273.967956 -31.99003)
		(width 0.13462)
		(layer "F.Cu")
		(net "P5E_PEX2_STN2_TX_C_DN<42>")
	)
	(segment
		(start 273.967956 -31.99003)
		(end 273.464782 -31.99003)
		(width 0.13462)
		(layer "F.Cu")
		(net "P5E_PEX2_STN2_TX_C_DN<42>")
	)
	(segment
		(start 275.41474 -32.13608)
		(end 274.114006 -32.13608)
		(width 0.13462)
		(layer "F.Cu")
		(net "P5E_PEX2_STN2_TX_C_DN<42>")
	)
	(segment
		(start 275.725636 -31.825184)
		(end 275.41474 -32.13608)
		(width 0.13462)
		(layer "F.Cu")
		(net "P5E_PEX2_STN2_TX_C_DN<42>")
	)
	(segment
		(start 337.349084 -344.219022)
		(end 337.669124 -344.539062)
		(width 0.13462)
		(layer "F.Cu")
		(net "P5E_PEX2_STN6_TX_C_DP<100>")
	)
	(segment
		(start 337.669124 -345.170506)
		(end 337.374484 -345.465146)
		(width 0.13462)
		(layer "F.Cu")
		(net "P5E_PEX2_STN6_TX_C_DP<100>")
	)
	(segment
		(start 337.669124 -344.539062)
		(end 337.669124 -345.170506)
		(width 0.13462)
		(layer "F.Cu")
		(net "P5E_PEX2_STN6_TX_C_DP<100>")
	)
	(segment
		(start 337.707478 -364.572296)
		(end 337.628484 -364.71352)
		(width 0.1651)
		(layer "In13.Cu")
		(net "P5E_PEX2_STN6_TX_C_DP<100>")
	)
	(segment
		(start 337.665314 -345.755976)
		(end 337.665314 -346.209874)
		(width 0.1651)
		(layer "In13.Cu")
		(net "P5E_PEX2_STN6_TX_C_DP<100>")
	)
	(segment
		(start 337.763358 -365.190278)
		(end 337.904582 -365.269272)
		(width 0.1651)
		(layer "In13.Cu")
		(net "P5E_PEX2_STN6_TX_C_DP<100>")
	)
	(segment
		(start 337.628484 -364.71352)
		(end 337.763358 -365.190278)
		(width 0.1651)
		(layer "In13.Cu")
		(net "P5E_PEX2_STN6_TX_C_DP<100>")
	)
	(segment
		(start 336.110834 -347.764354)
		(end 336.110834 -358.923336)
		(width 0.1651)
		(layer "In13.Cu")
		(net "P5E_PEX2_STN6_TX_C_DP<100>")
	)
	(segment
		(start 338.647278 -383.79908)
		(end 338.217002 -383.79908)
		(width 0.1651)
		(layer "In13.Cu")
		(net "P5E_PEX2_STN6_TX_C_DP<100>")
	)
	(segment
		(start 338.217002 -383.79908)
		(end 338.090002 -383.67208)
		(width 0.1651)
		(layer "In13.Cu")
		(net "P5E_PEX2_STN6_TX_C_DP<100>")
	)
	(segment
		(start 337.904582 -365.269272)
		(end 338.039202 -365.745776)
		(width 0.1651)
		(layer "In13.Cu")
		(net "P5E_PEX2_STN6_TX_C_DP<100>")
	)
	(segment
		(start 338.934044 -368.910616)
		(end 338.934044 -383.512314)
		(width 0.1651)
		(layer "In13.Cu")
		(net "P5E_PEX2_STN6_TX_C_DP<100>")
	)
	(segment
		(start 338.095082 -366.363758)
		(end 338.23656 -366.442752)
		(width 0.1651)
		(layer "In13.Cu")
		(net "P5E_PEX2_STN6_TX_C_DP<100>")
	)
	(segment
		(start 338.039202 -365.745776)
		(end 337.960462 -365.886746)
		(width 0.1651)
		(layer "In13.Cu")
		(net "P5E_PEX2_STN6_TX_C_DP<100>")
	)
	(segment
		(start 337.960462 -365.886746)
		(end 338.095082 -366.363758)
		(width 0.1651)
		(layer "In13.Cu")
		(net "P5E_PEX2_STN6_TX_C_DP<100>")
	)
	(segment
		(start 338.934044 -383.512314)
		(end 338.647278 -383.79908)
		(width 0.1651)
		(layer "In13.Cu")
		(net "P5E_PEX2_STN6_TX_C_DP<100>")
	)
	(segment
		(start 336.110834 -358.923336)
		(end 337.707478 -364.572296)
		(width 0.1651)
		(layer "In13.Cu")
		(net "P5E_PEX2_STN6_TX_C_DP<100>")
	)
	(segment
		(start 338.23656 -366.442752)
		(end 338.934044 -368.910616)
		(width 0.1651)
		(layer "In13.Cu")
		(net "P5E_PEX2_STN6_TX_C_DP<100>")
	)
	(segment
		(start 338.090002 -383.67208)
		(end 338.090002 -383.290064)
		(width 0.1651)
		(layer "In13.Cu")
		(net "P5E_PEX2_STN6_TX_C_DP<100>")
	)
	(segment
		(start 337.374484 -345.465146)
		(end 337.665314 -345.755976)
		(width 0.1651)
		(layer "In13.Cu")
		(net "P5E_PEX2_STN6_TX_C_DP<100>")
	)
	(segment
		(start 337.665314 -346.209874)
		(end 336.110834 -347.764354)
		(width 0.1651)
		(layer "In13.Cu")
		(net "P5E_PEX2_STN6_TX_C_DP<100>")
	)
	(segment
		(start 387.847332 -135.815324)
		(end 388.150608 -136.1186)
		(width 0.13462)
		(layer "F.Cu")
		(net "P5E_PEX3_STN1_TX_C_DN<31>")
	)
	(segment
		(start 388.150608 -136.1186)
		(end 393.689332 -136.1186)
		(width 0.13462)
		(layer "F.Cu")
		(net "P5E_PEX3_STN1_TX_C_DN<31>")
	)
	(segment
		(start 393.843002 -135.96493)
		(end 394.342366 -135.96493)
		(width 0.13462)
		(layer "F.Cu")
		(net "P5E_PEX3_STN1_TX_C_DN<31>")
	)
	(segment
		(start 393.689332 -136.1186)
		(end 393.843002 -135.96493)
		(width 0.13462)
		(layer "F.Cu")
		(net "P5E_PEX3_STN1_TX_C_DN<31>")
	)
	(segment
		(start 67.590162 -357.75773)
		(end 67.884802 -357.46309)
		(width 0.13462)
		(layer "F.Cu")
		(net "P5E_PEX0_STN6_TX_C_DP<108>")
	)
	(segment
		(start 67.884802 -356.831646)
		(end 67.564762 -356.511606)
		(width 0.13462)
		(layer "F.Cu")
		(net "P5E_PEX0_STN6_TX_C_DP<108>")
	)
	(segment
		(start 67.884802 -357.46309)
		(end 67.884802 -356.831646)
		(width 0.13462)
		(layer "F.Cu")
		(net "P5E_PEX0_STN6_TX_C_DP<108>")
	)
	(segment
		(start 67.880992 -361.069382)
		(end 67.880992 -358.04856)
		(width 0.1651)
		(layer "In13.Cu")
		(net "P5E_PEX0_STN6_TX_C_DP<108>")
	)
	(segment
		(start 78.636876 -409.799028)
		(end 79.16418 -409.799028)
		(width 0.1651)
		(layer "In13.Cu")
		(net "P5E_PEX0_STN6_TX_C_DP<108>")
	)
	(segment
		(start 66.408554 -382.168146)
		(end 66.729356 -368.828574)
		(width 0.1651)
		(layer "In13.Cu")
		(net "P5E_PEX0_STN6_TX_C_DP<108>")
	)
	(segment
		(start 66.729356 -368.828574)
		(end 67.880992 -361.069382)
		(width 0.1651)
		(layer "In13.Cu")
		(net "P5E_PEX0_STN6_TX_C_DP<108>")
	)
	(segment
		(start 67.880992 -358.04856)
		(end 67.590162 -357.75773)
		(width 0.1651)
		(layer "In13.Cu")
		(net "P5E_PEX0_STN6_TX_C_DP<108>")
	)
	(segment
		(start 66.408554 -384.166364)
		(end 66.408554 -382.168146)
		(width 0.1651)
		(layer "In13.Cu")
		(net "P5E_PEX0_STN6_TX_C_DP<108>")
	)
	(segment
		(start 67.765168 -387.441948)
		(end 66.408554 -384.166364)
		(width 0.1651)
		(layer "In13.Cu")
		(net "P5E_PEX0_STN6_TX_C_DP<108>")
	)
	(segment
		(start 79.402432 -409.560776)
		(end 79.402432 -395.353032)
		(width 0.1651)
		(layer "In13.Cu")
		(net "P5E_PEX0_STN6_TX_C_DP<108>")
	)
	(segment
		(start 79.16418 -409.799028)
		(end 79.402432 -409.560776)
		(width 0.1651)
		(layer "In13.Cu")
		(net "P5E_PEX0_STN6_TX_C_DP<108>")
	)
	(segment
		(start 78.509876 -409.290012)
		(end 78.509876 -409.672028)
		(width 0.1651)
		(layer "In13.Cu")
		(net "P5E_PEX0_STN6_TX_C_DP<108>")
	)
	(segment
		(start 69.51726 -389.194294)
		(end 67.765168 -387.441948)
		(width 0.1651)
		(layer "In13.Cu")
		(net "P5E_PEX0_STN6_TX_C_DP<108>")
	)
	(segment
		(start 79.402432 -395.353032)
		(end 77.523594 -393.474194)
		(width 0.1651)
		(layer "In13.Cu")
		(net "P5E_PEX0_STN6_TX_C_DP<108>")
	)
	(segment
		(start 78.509876 -409.672028)
		(end 78.636876 -409.799028)
		(width 0.1651)
		(layer "In13.Cu")
		(net "P5E_PEX0_STN6_TX_C_DP<108>")
	)
	(segment
		(start 77.523594 -393.474194)
		(end 69.51726 -389.194294)
		(width 0.1651)
		(layer "In13.Cu")
		(net "P5E_PEX0_STN6_TX_C_DP<108>")
	)
	(segment
		(start 268.22527 -32.14878)
		(end 267.55471 -32.14878)
		(width 0.13462)
		(layer "F.Cu")
		(net "P5E_PEX2_STN2_RX_DN<42>")
	)
	(segment
		(start 268.864842 -31.99003)
		(end 268.38402 -31.99003)
		(width 0.13462)
		(layer "F.Cu")
		(net "P5E_PEX2_STN2_RX_DN<42>")
	)
	(segment
		(start 268.38402 -31.99003)
		(end 268.22527 -32.14878)
		(width 0.13462)
		(layer "F.Cu")
		(net "P5E_PEX2_STN2_RX_DN<42>")
	)
	(segment
		(start 267.55471 -32.14878)
		(end 267.264642 -31.858712)
		(width 0.13462)
		(layer "F.Cu")
		(net "P5E_PEX2_STN2_RX_DN<42>")
	)
	(segment
		(start 268.13002 -32.149542)
		(end 267.555472 -32.149542)
		(width 0.1651)
		(layer "In7.Cu")
		(net "P5E_PEX2_STN2_RX_DN<42>")
	)
	(segment
		(start 273.057366 -148.002498)
		(end 273.36369 -119.5832)
		(width 0.1651)
		(layer "In7.Cu")
		(net "P5E_PEX2_STN2_RX_DN<42>")
	)
	(segment
		(start 281.019758 -275.275802)
		(end 281.019758 -271.467072)
		(width 0.1143)
		(layer "In7.Cu")
		(net "P5E_PEX2_STN2_RX_DN<42>")
	)
	(segment
		(start 281.399742 -274.999958)
		(end 281.399742 -275.265388)
		(width 0.1143)
		(layer "In7.Cu")
		(net "P5E_PEX2_STN2_RX_DN<42>")
	)
	(segment
		(start 281.065478 -267.767816)
		(end 280.621994 -263.266174)
		(width 0.1651)
		(layer "In7.Cu")
		(net "P5E_PEX2_STN2_RX_DN<42>")
	)
	(segment
		(start 269.334742 -55.367682)
		(end 269.427198 -49.435766)
		(width 0.1651)
		(layer "In7.Cu")
		(net "P5E_PEX2_STN2_RX_DN<42>")
	)
	(segment
		(start 272.92046 -104.952546)
		(end 269.72641 -65.159636)
		(width 0.1651)
		(layer "In7.Cu")
		(net "P5E_PEX2_STN2_RX_DN<42>")
	)
	(segment
		(start 269.427198 -49.435766)
		(end 268.113002 -39.71036)
		(width 0.1651)
		(layer "In7.Cu")
		(net "P5E_PEX2_STN2_RX_DN<42>")
	)
	(segment
		(start 269.72641 -65.159636)
		(end 269.334742 -55.367682)
		(width 0.1651)
		(layer "In7.Cu")
		(net "P5E_PEX2_STN2_RX_DN<42>")
	)
	(segment
		(start 280.621994 -263.266174)
		(end 280.844498 -258.734306)
		(width 0.1651)
		(layer "In7.Cu")
		(net "P5E_PEX2_STN2_RX_DN<42>")
	)
	(segment
		(start 281.123644 -275.379688)
		(end 281.019758 -275.275802)
		(width 0.1143)
		(layer "In7.Cu")
		(net "P5E_PEX2_STN2_RX_DN<42>")
	)
	(segment
		(start 267.555472 -32.149542)
		(end 267.264642 -31.858712)
		(width 0.1651)
		(layer "In7.Cu")
		(net "P5E_PEX2_STN2_RX_DN<42>")
	)
	(segment
		(start 281.019758 -271.467072)
		(end 281.065478 -271.421352)
		(width 0.1143)
		(layer "In7.Cu")
		(net "P5E_PEX2_STN2_RX_DN<42>")
	)
	(segment
		(start 268.113002 -39.71036)
		(end 268.083792 -37.856414)
		(width 0.1651)
		(layer "In7.Cu")
		(net "P5E_PEX2_STN2_RX_DN<42>")
	)
	(segment
		(start 281.013408 -249.99696)
		(end 273.057366 -148.002498)
		(width 0.1651)
		(layer "In7.Cu")
		(net "P5E_PEX2_STN2_RX_DN<42>")
	)
	(segment
		(start 281.399742 -275.265388)
		(end 281.285442 -275.379688)
		(width 0.1143)
		(layer "In7.Cu")
		(net "P5E_PEX2_STN2_RX_DN<42>")
	)
	(segment
		(start 281.285442 -275.379688)
		(end 281.123644 -275.379688)
		(width 0.1143)
		(layer "In7.Cu")
		(net "P5E_PEX2_STN2_RX_DN<42>")
	)
	(segment
		(start 281.065478 -271.421352)
		(end 281.065478 -271.392904)
		(width 0.1143)
		(layer "In7.Cu")
		(net "P5E_PEX2_STN2_RX_DN<42>")
	)
	(segment
		(start 273.36369 -119.5832)
		(end 272.92046 -104.952546)
		(width 0.1651)
		(layer "In7.Cu")
		(net "P5E_PEX2_STN2_RX_DN<42>")
	)
	(segment
		(start 268.607286 -35.04819)
		(end 268.64437 -32.663638)
		(width 0.1651)
		(layer "In7.Cu")
		(net "P5E_PEX2_STN2_RX_DN<42>")
	)
	(segment
		(start 268.64437 -32.663638)
		(end 268.13002 -32.149542)
		(width 0.1651)
		(layer "In7.Cu")
		(net "P5E_PEX2_STN2_RX_DN<42>")
	)
	(segment
		(start 280.844498 -258.734306)
		(end 281.013408 -249.99696)
		(width 0.1651)
		(layer "In7.Cu")
		(net "P5E_PEX2_STN2_RX_DN<42>")
	)
	(segment
		(start 281.065478 -271.392904)
		(end 281.065478 -267.767816)
		(width 0.1651)
		(layer "In7.Cu")
		(net "P5E_PEX2_STN2_RX_DN<42>")
	)
	(segment
		(start 268.083792 -37.856414)
		(end 268.607286 -35.04819)
		(width 0.1651)
		(layer "In7.Cu")
		(net "P5E_PEX2_STN2_RX_DN<42>")
	)
	(segment
		(start 287.099756 -316.508892)
		(end 287.099756 -316.799722)
		(width 0.1143)
		(layer "In9.Cu")
		(net "P5E_PEX2_STN6_RX_DN<99>")
	)
	(segment
		(start 320.847974 -342.35644)
		(end 320.406014 -341.26424)
		(width 0.1651)
		(layer "In9.Cu")
		(net "P5E_PEX2_STN6_RX_DN<99>")
	)
	(segment
		(start 286.765746 -319.916048)
		(end 286.765746 -319.8876)
		(width 0.1143)
		(layer "In9.Cu")
		(net "P5E_PEX2_STN6_RX_DN<99>")
	)
	(segment
		(start 286.720026 -319.84188)
		(end 286.720026 -316.534038)
		(width 0.1143)
		(layer "In9.Cu")
		(net "P5E_PEX2_STN6_RX_DN<99>")
	)
	(segment
		(start 341.14486 -368.416332)
		(end 335.71942 -364.8583)
		(width 0.1651)
		(layer "In9.Cu")
		(net "P5E_PEX2_STN6_RX_DN<99>")
	)
	(segment
		(start 320.406014 -341.26424)
		(end 298.125642 -332.584552)
		(width 0.1651)
		(layer "In9.Cu")
		(net "P5E_PEX2_STN6_RX_DN<99>")
	)
	(segment
		(start 287.010856 -316.419992)
		(end 287.099756 -316.508892)
		(width 0.1143)
		(layer "In9.Cu")
		(net "P5E_PEX2_STN6_RX_DN<99>")
	)
	(segment
		(start 341.416132 -374.729248)
		(end 341.416132 -368.935)
		(width 0.1651)
		(layer "In9.Cu")
		(net "P5E_PEX2_STN6_RX_DN<99>")
	)
	(segment
		(start 286.834072 -316.419992)
		(end 287.010856 -316.419992)
		(width 0.1143)
		(layer "In9.Cu")
		(net "P5E_PEX2_STN6_RX_DN<99>")
	)
	(segment
		(start 298.125642 -332.584552)
		(end 298.082208 -332.486)
		(width 0.1651)
		(layer "In9.Cu")
		(net "P5E_PEX2_STN6_RX_DN<99>")
	)
	(segment
		(start 321.5259 -359.11282)
		(end 320.847974 -358.434894)
		(width 0.1651)
		(layer "In9.Cu")
		(net "P5E_PEX2_STN6_RX_DN<99>")
	)
	(segment
		(start 320.847974 -358.434894)
		(end 320.847974 -342.35644)
		(width 0.1651)
		(layer "In9.Cu")
		(net "P5E_PEX2_STN6_RX_DN<99>")
	)
	(segment
		(start 286.765746 -319.8876)
		(end 286.720026 -319.84188)
		(width 0.1143)
		(layer "In9.Cu")
		(net "P5E_PEX2_STN6_RX_DN<99>")
	)
	(segment
		(start 295.3639 -331.508608)
		(end 290.571428 -328.379328)
		(width 0.1651)
		(layer "In9.Cu")
		(net "P5E_PEX2_STN6_RX_DN<99>")
	)
	(segment
		(start 340.29015 -375.69013)
		(end 340.29015 -375.308114)
		(width 0.1651)
		(layer "In9.Cu")
		(net "P5E_PEX2_STN6_RX_DN<99>")
	)
	(segment
		(start 341.416132 -368.935)
		(end 341.14486 -368.416332)
		(width 0.1651)
		(layer "In9.Cu")
		(net "P5E_PEX2_STN6_RX_DN<99>")
	)
	(segment
		(start 298.082208 -332.486)
		(end 297.620436 -332.305914)
		(width 0.1651)
		(layer "In9.Cu")
		(net "P5E_PEX2_STN6_RX_DN<99>")
	)
	(segment
		(start 286.765746 -324.144894)
		(end 286.765746 -319.916048)
		(width 0.1651)
		(layer "In9.Cu")
		(net "P5E_PEX2_STN6_RX_DN<99>")
	)
	(segment
		(start 297.521884 -332.349094)
		(end 295.3639 -331.508608)
		(width 0.1651)
		(layer "In9.Cu")
		(net "P5E_PEX2_STN6_RX_DN<99>")
	)
	(segment
		(start 340.41715 -375.181114)
		(end 340.964266 -375.181114)
		(width 0.1651)
		(layer "In9.Cu")
		(net "P5E_PEX2_STN6_RX_DN<99>")
	)
	(segment
		(start 335.71942 -364.8583)
		(end 321.5259 -359.11282)
		(width 0.1651)
		(layer "In9.Cu")
		(net "P5E_PEX2_STN6_RX_DN<99>")
	)
	(segment
		(start 286.720026 -316.534038)
		(end 286.834072 -316.419992)
		(width 0.1143)
		(layer "In9.Cu")
		(net "P5E_PEX2_STN6_RX_DN<99>")
	)
	(segment
		(start 297.620436 -332.305914)
		(end 297.521884 -332.349094)
		(width 0.1651)
		(layer "In9.Cu")
		(net "P5E_PEX2_STN6_RX_DN<99>")
	)
	(segment
		(start 340.964266 -375.181114)
		(end 341.416132 -374.729248)
		(width 0.1651)
		(layer "In9.Cu")
		(net "P5E_PEX2_STN6_RX_DN<99>")
	)
	(segment
		(start 290.571428 -328.379328)
		(end 287.068768 -324.876668)
		(width 0.1651)
		(layer "In9.Cu")
		(net "P5E_PEX2_STN6_RX_DN<99>")
	)
	(segment
		(start 340.29015 -375.308114)
		(end 340.41715 -375.181114)
		(width 0.1651)
		(layer "In9.Cu")
		(net "P5E_PEX2_STN6_RX_DN<99>")
	)
	(segment
		(start 287.068768 -324.876668)
		(end 286.765746 -324.144894)
		(width 0.1651)
		(layer "In9.Cu")
		(net "P5E_PEX2_STN6_RX_DN<99>")
	)
	(segment
		(start 385.205224 -131.323334)
		(end 385.528058 -131.0005)
		(width 0.13462)
		(layer "F.Cu")
		(net "P5E_PEX3_STN1_TX_C_DN<28>")
	)
	(segment
		(start 385.528058 -131.0005)
		(end 393.671044 -131.0005)
		(width 0.13462)
		(layer "F.Cu")
		(net "P5E_PEX3_STN1_TX_C_DN<28>")
	)
	(segment
		(start 393.835636 -131.165092)
		(end 394.342366 -131.165092)
		(width 0.13462)
		(layer "F.Cu")
		(net "P5E_PEX3_STN1_TX_C_DN<28>")
	)
	(segment
		(start 393.671044 -131.0005)
		(end 393.835636 -131.165092)
		(width 0.13462)
		(layer "F.Cu")
		(net "P5E_PEX3_STN1_TX_C_DN<28>")
	)
	(segment
		(start 398.94256 -154.159966)
		(end 399.98904 -154.159966)
		(width 0.13208)
		(layer "F.Cu")
		(net "NCSI_NIC6_TXD1")
	)
	(via
		(at 399.98904 -154.159966)
		(size 0.508)
		(drill 0.254)
		(layers "F.Cu" "B.Cu")
		(net "NCSI_NIC6_TXD1")
	)
	(segment
		(start 398.838674 -153.0096)
		(end 399.98904 -154.159966)
		(width 0.13208)
		(layer "B.Cu")
		(net "NCSI_NIC6_TXD1")
	)
	(segment
		(start 398.25549 -153.0096)
		(end 398.838674 -153.0096)
		(width 0.13208)
		(layer "B.Cu")
		(net "NCSI_NIC6_TXD1")
	)
	(segment
		(start 51.75631 -318.129666)
		(end 51.961034 -318.129666)
		(width 0.1143)
		(layer "In9.Cu")
		(net "P5E_PEX0_STN6_RX_DP<102>")
	)
	(segment
		(start 65.184274 -362.083858)
		(end 63.272162 -361.291886)
		(width 0.1651)
		(layer "In9.Cu")
		(net "P5E_PEX0_STN6_RX_DP<102>")
	)
	(segment
		(start 51.433984 -319.916048)
		(end 51.479704 -319.870328)
		(width 0.1143)
		(layer "In9.Cu")
		(net "P5E_PEX0_STN6_RX_DP<102>")
	)
	(segment
		(start 72.139048 -366.86871)
		(end 71.72706 -366.59312)
		(width 0.1651)
		(layer "In9.Cu")
		(net "P5E_PEX0_STN6_RX_DP<102>")
	)
	(segment
		(start 75.00239 -369.40236)
		(end 74.56805 -368.354102)
		(width 0.1651)
		(layer "In9.Cu")
		(net "P5E_PEX0_STN6_RX_DP<102>")
	)
	(segment
		(start 59.536076 -354.3554)
		(end 57.97423 -346.504006)
		(width 0.1651)
		(layer "In9.Cu")
		(net "P5E_PEX0_STN6_RX_DP<102>")
	)
	(segment
		(start 74.109834 -375.490232)
		(end 74.109834 -375.872248)
		(width 0.1651)
		(layer "In9.Cu")
		(net "P5E_PEX0_STN6_RX_DP<102>")
	)
	(segment
		(start 57.97423 -346.504006)
		(end 51.433984 -324.944232)
		(width 0.1651)
		(layer "In9.Cu")
		(net "P5E_PEX0_STN6_RX_DP<102>")
	)
	(segment
		(start 74.680826 -375.999248)
		(end 75.00239 -375.677684)
		(width 0.1651)
		(layer "In9.Cu")
		(net "P5E_PEX0_STN6_RX_DP<102>")
	)
	(segment
		(start 51.479704 -318.406272)
		(end 51.75631 -318.129666)
		(width 0.1143)
		(layer "In9.Cu")
		(net "P5E_PEX0_STN6_RX_DP<102>")
	)
	(segment
		(start 51.479704 -319.870328)
		(end 51.479704 -318.406272)
		(width 0.1143)
		(layer "In9.Cu")
		(net "P5E_PEX0_STN6_RX_DP<102>")
	)
	(segment
		(start 61.79947 -359.819194)
		(end 59.536076 -354.3554)
		(width 0.1651)
		(layer "In9.Cu")
		(net "P5E_PEX0_STN6_RX_DP<102>")
	)
	(segment
		(start 75.00239 -375.677684)
		(end 75.00239 -369.40236)
		(width 0.1651)
		(layer "In9.Cu")
		(net "P5E_PEX0_STN6_RX_DP<102>")
	)
	(segment
		(start 72.297798 -366.837214)
		(end 72.139048 -366.86871)
		(width 0.1651)
		(layer "In9.Cu")
		(net "P5E_PEX0_STN6_RX_DP<102>")
	)
	(segment
		(start 74.109834 -375.872248)
		(end 74.236834 -375.999248)
		(width 0.1651)
		(layer "In9.Cu")
		(net "P5E_PEX0_STN6_RX_DP<102>")
	)
	(segment
		(start 51.433984 -319.944496)
		(end 51.433984 -319.916048)
		(width 0.1143)
		(layer "In9.Cu")
		(net "P5E_PEX0_STN6_RX_DP<102>")
	)
	(segment
		(start 74.236834 -375.999248)
		(end 74.680826 -375.999248)
		(width 0.1651)
		(layer "In9.Cu")
		(net "P5E_PEX0_STN6_RX_DP<102>")
	)
	(segment
		(start 71.72706 -366.59312)
		(end 71.695564 -366.434624)
		(width 0.1651)
		(layer "In9.Cu")
		(net "P5E_PEX0_STN6_RX_DP<102>")
	)
	(segment
		(start 71.695564 -366.434624)
		(end 65.184274 -362.083858)
		(width 0.1651)
		(layer "In9.Cu")
		(net "P5E_PEX0_STN6_RX_DP<102>")
	)
	(segment
		(start 51.961034 -318.129666)
		(end 52.049934 -318.040766)
		(width 0.1143)
		(layer "In9.Cu")
		(net "P5E_PEX0_STN6_RX_DP<102>")
	)
	(segment
		(start 74.56805 -368.354102)
		(end 72.297798 -366.837214)
		(width 0.1651)
		(layer "In9.Cu")
		(net "P5E_PEX0_STN6_RX_DP<102>")
	)
	(segment
		(start 52.049934 -318.040766)
		(end 52.049934 -317.749936)
		(width 0.1143)
		(layer "In9.Cu")
		(net "P5E_PEX0_STN6_RX_DP<102>")
	)
	(segment
		(start 51.433984 -324.944232)
		(end 51.433984 -319.944496)
		(width 0.1651)
		(layer "In9.Cu")
		(net "P5E_PEX0_STN6_RX_DP<102>")
	)
	(segment
		(start 63.272162 -361.291886)
		(end 61.79947 -359.819194)
		(width 0.1651)
		(layer "In9.Cu")
		(net "P5E_PEX0_STN6_RX_DP<102>")
	)
	(segment
		(start 268.382242 -34.390076)
		(end 268.219428 -34.227262)
		(width 0.13462)
		(layer "F.Cu")
		(net "P5E_PEX2_STN2_RX_DP<43>")
	)
	(segment
		(start 268.864842 -34.390076)
		(end 268.382242 -34.390076)
		(width 0.13462)
		(layer "F.Cu")
		(net "P5E_PEX2_STN2_RX_DP<43>")
	)
	(segment
		(start 268.219428 -34.227262)
		(end 265.70559 -34.227262)
		(width 0.13462)
		(layer "F.Cu")
		(net "P5E_PEX2_STN2_RX_DP<43>")
	)
	(segment
		(start 265.70559 -34.227262)
		(end 265.410442 -34.52241)
		(width 0.13462)
		(layer "F.Cu")
		(net "P5E_PEX2_STN2_RX_DP<43>")
	)
	(segment
		(start 266.806172 -35.357562)
		(end 266.806172 -35.1028)
		(width 0.1651)
		(layer "In7.Cu")
		(net "P5E_PEX2_STN2_RX_DP<43>")
	)
	(segment
		(start 266.847828 -38.05428)
		(end 266.840208 -37.559234)
		(width 0.1651)
		(layer "In7.Cu")
		(net "P5E_PEX2_STN2_RX_DP<43>")
	)
	(segment
		(start 271.287494 -138.494516)
		(end 271.992598 -131.969002)
		(width 0.1651)
		(layer "In7.Cu")
		(net "P5E_PEX2_STN2_RX_DP<43>")
	)
	(segment
		(start 279.833832 -271.3736)
		(end 279.833832 -271.345152)
		(width 0.1143)
		(layer "In7.Cu")
		(net "P5E_PEX2_STN2_RX_DP<43>")
	)
	(segment
		(start 266.840208 -37.559234)
		(end 266.73683 -37.459158)
		(width 0.1651)
		(layer "In7.Cu")
		(net "P5E_PEX2_STN2_RX_DP<43>")
	)
	(segment
		(start 280.449782 -273.784314)
		(end 280.335482 -273.670014)
		(width 0.1143)
		(layer "In7.Cu")
		(net "P5E_PEX2_STN2_RX_DP<43>")
	)
	(segment
		(start 266.73683 -37.459158)
		(end 266.72921 -36.963604)
		(width 0.1651)
		(layer "In7.Cu")
		(net "P5E_PEX2_STN2_RX_DP<43>")
	)
	(segment
		(start 266.85875 -38.75278)
		(end 266.755372 -38.652704)
		(width 0.1651)
		(layer "In7.Cu")
		(net "P5E_PEX2_STN2_RX_DP<43>")
	)
	(segment
		(start 266.874752 -39.786052)
		(end 266.85875 -38.75278)
		(width 0.1651)
		(layer "In7.Cu")
		(net "P5E_PEX2_STN2_RX_DP<43>")
	)
	(segment
		(start 279.65273 -248.479818)
		(end 271.253458 -141.679676)
		(width 0.1651)
		(layer "In7.Cu")
		(net "P5E_PEX2_STN2_RX_DP<43>")
	)
	(segment
		(start 268.486636 -65.267332)
		(end 268.094968 -55.483252)
		(width 0.1651)
		(layer "In7.Cu")
		(net "P5E_PEX2_STN2_RX_DP<43>")
	)
	(segment
		(start 265.701272 -34.23158)
		(end 265.410442 -34.52241)
		(width 0.1651)
		(layer "In7.Cu")
		(net "P5E_PEX2_STN2_RX_DP<43>")
	)
	(segment
		(start 279.375362 -263.230106)
		(end 279.375362 -262.82015)
		(width 0.1651)
		(layer "In7.Cu")
		(net "P5E_PEX2_STN2_RX_DP<43>")
	)
	(segment
		(start 279.833832 -267.885926)
		(end 279.375362 -263.230106)
		(width 0.1651)
		(layer "In7.Cu")
		(net "P5E_PEX2_STN2_RX_DP<43>")
	)
	(segment
		(start 279.879552 -273.407632)
		(end 279.879552 -271.41932)
		(width 0.1143)
		(layer "In7.Cu")
		(net "P5E_PEX2_STN2_RX_DP<43>")
	)
	(segment
		(start 266.72921 -36.963604)
		(end 266.829286 -36.86048)
		(width 0.1651)
		(layer "In7.Cu")
		(net "P5E_PEX2_STN2_RX_DP<43>")
	)
	(segment
		(start 279.879552 -271.41932)
		(end 279.833832 -271.3736)
		(width 0.1143)
		(layer "In7.Cu")
		(net "P5E_PEX2_STN2_RX_DP<43>")
	)
	(segment
		(start 266.755372 -38.652704)
		(end 266.747752 -38.157404)
		(width 0.1651)
		(layer "In7.Cu")
		(net "P5E_PEX2_STN2_RX_DP<43>")
	)
	(segment
		(start 266.829286 -36.86048)
		(end 266.806172 -35.357562)
		(width 0.1651)
		(layer "In7.Cu")
		(net "P5E_PEX2_STN2_RX_DP<43>")
	)
	(segment
		(start 272.125948 -119.595392)
		(end 271.688814 -105.153714)
		(width 0.1651)
		(layer "In7.Cu")
		(net "P5E_PEX2_STN2_RX_DP<43>")
	)
	(segment
		(start 268.18844 -49.509426)
		(end 266.874752 -39.786052)
		(width 0.1651)
		(layer "In7.Cu")
		(net "P5E_PEX2_STN2_RX_DP<43>")
	)
	(segment
		(start 280.335482 -273.670014)
		(end 280.141934 -273.670014)
		(width 0.1143)
		(layer "In7.Cu")
		(net "P5E_PEX2_STN2_RX_DP<43>")
	)
	(segment
		(start 280.449782 -274.049744)
		(end 280.449782 -273.784314)
		(width 0.1143)
		(layer "In7.Cu")
		(net "P5E_PEX2_STN2_RX_DP<43>")
	)
	(segment
		(start 279.375362 -262.82015)
		(end 279.65273 -248.479818)
		(width 0.1651)
		(layer "In7.Cu")
		(net "P5E_PEX2_STN2_RX_DP<43>")
	)
	(segment
		(start 271.992598 -131.969002)
		(end 272.125948 -119.595392)
		(width 0.1651)
		(layer "In7.Cu")
		(net "P5E_PEX2_STN2_RX_DP<43>")
	)
	(segment
		(start 266.747752 -38.157404)
		(end 266.847828 -38.05428)
		(width 0.1651)
		(layer "In7.Cu")
		(net "P5E_PEX2_STN2_RX_DP<43>")
	)
	(segment
		(start 279.833832 -271.345152)
		(end 279.833832 -267.885926)
		(width 0.1651)
		(layer "In7.Cu")
		(net "P5E_PEX2_STN2_RX_DP<43>")
	)
	(segment
		(start 280.141934 -273.670014)
		(end 279.879552 -273.407632)
		(width 0.1143)
		(layer "In7.Cu")
		(net "P5E_PEX2_STN2_RX_DP<43>")
	)
	(segment
		(start 271.688814 -105.153714)
		(end 268.486636 -65.267332)
		(width 0.1651)
		(layer "In7.Cu")
		(net "P5E_PEX2_STN2_RX_DP<43>")
	)
	(segment
		(start 268.094968 -55.483252)
		(end 268.18844 -49.509426)
		(width 0.1651)
		(layer "In7.Cu")
		(net "P5E_PEX2_STN2_RX_DP<43>")
	)
	(segment
		(start 265.934952 -34.23158)
		(end 265.701272 -34.23158)
		(width 0.1651)
		(layer "In7.Cu")
		(net "P5E_PEX2_STN2_RX_DP<43>")
	)
	(segment
		(start 271.253458 -141.679676)
		(end 271.287494 -138.494516)
		(width 0.1651)
		(layer "In7.Cu")
		(net "P5E_PEX2_STN2_RX_DP<43>")
	)
	(segment
		(start 266.806172 -35.1028)
		(end 265.934952 -34.23158)
		(width 0.1651)
		(layer "In7.Cu")
		(net "P5E_PEX2_STN2_RX_DP<43>")
	)
	(segment
		(start 303.226216 -339.235034)
		(end 278.886412 -326.126856)
		(width 0.1651)
		(layer "In5.Cu")
		(net "P5E_PEX2_STN6_RX_DP<110>")
	)
	(segment
		(start 334.534002 -395.670278)
		(end 334.35544 -395.247114)
		(width 0.1651)
		(layer "In5.Cu")
		(net "P5E_PEX2_STN6_RX_DP<110>")
	)
	(segment
		(start 332.391004 -393.273534)
		(end 331.786992 -393.024106)
		(width 0.1651)
		(layer "In5.Cu")
		(net "P5E_PEX2_STN6_RX_DP<110>")
	)
	(segment
		(start 333.68996 -401.872196)
		(end 333.81696 -401.999196)
		(width 0.1651)
		(layer "In5.Cu")
		(net "P5E_PEX2_STN6_RX_DP<110>")
	)
	(segment
		(start 325.499476 -389.094726)
		(end 303.226216 -339.235034)
		(width 0.1651)
		(layer "In5.Cu")
		(net "P5E_PEX2_STN6_RX_DP<110>")
	)
	(segment
		(start 334.534002 -401.71243)
		(end 334.534002 -395.670278)
		(width 0.1651)
		(layer "In5.Cu")
		(net "P5E_PEX2_STN6_RX_DP<110>")
	)
	(segment
		(start 327.79589 -391.375646)
		(end 325.499476 -389.094726)
		(width 0.1651)
		(layer "In5.Cu")
		(net "P5E_PEX2_STN6_RX_DP<110>")
	)
	(segment
		(start 333.81696 -401.999196)
		(end 334.247236 -401.999196)
		(width 0.1651)
		(layer "In5.Cu")
		(net "P5E_PEX2_STN6_RX_DP<110>")
	)
	(segment
		(start 334.35544 -395.247114)
		(end 334.00619 -394.896086)
		(width 0.1651)
		(layer "In5.Cu")
		(net "P5E_PEX2_STN6_RX_DP<110>")
	)
	(segment
		(start 276.079458 -318.355472)
		(end 276.305264 -318.129666)
		(width 0.1143)
		(layer "In5.Cu")
		(net "P5E_PEX2_STN6_RX_DP<110>")
	)
	(segment
		(start 331.196442 -392.889994)
		(end 331.141324 -392.757152)
		(width 0.1651)
		(layer "In5.Cu")
		(net "P5E_PEX2_STN6_RX_DP<110>")
	)
	(segment
		(start 333.513176 -394.400786)
		(end 332.391004 -393.273534)
		(width 0.1651)
		(layer "In5.Cu")
		(net "P5E_PEX2_STN6_RX_DP<110>")
	)
	(segment
		(start 333.862426 -394.895832)
		(end 333.512922 -394.54455)
		(width 0.1651)
		(layer "In5.Cu")
		(net "P5E_PEX2_STN6_RX_DP<110>")
	)
	(segment
		(start 276.033738 -320.0146)
		(end 276.079458 -319.96888)
		(width 0.1143)
		(layer "In5.Cu")
		(net "P5E_PEX2_STN6_RX_DP<110>")
	)
	(segment
		(start 331.786992 -393.024106)
		(end 331.654404 -393.079224)
		(width 0.1651)
		(layer "In5.Cu")
		(net "P5E_PEX2_STN6_RX_DP<110>")
	)
	(segment
		(start 334.247236 -401.999196)
		(end 334.534002 -401.71243)
		(width 0.1651)
		(layer "In5.Cu")
		(net "P5E_PEX2_STN6_RX_DP<110>")
	)
	(segment
		(start 334.00619 -394.896086)
		(end 333.862426 -394.895832)
		(width 0.1651)
		(layer "In5.Cu")
		(net "P5E_PEX2_STN6_RX_DP<110>")
	)
	(segment
		(start 276.033738 -322.739766)
		(end 276.033738 -320.043048)
		(width 0.1651)
		(layer "In5.Cu")
		(net "P5E_PEX2_STN6_RX_DP<110>")
	)
	(segment
		(start 333.68996 -401.49018)
		(end 333.68996 -401.872196)
		(width 0.1651)
		(layer "In5.Cu")
		(net "P5E_PEX2_STN6_RX_DP<110>")
	)
	(segment
		(start 276.535388 -318.129666)
		(end 276.649688 -318.015366)
		(width 0.1143)
		(layer "In5.Cu")
		(net "P5E_PEX2_STN6_RX_DP<110>")
	)
	(segment
		(start 333.512922 -394.54455)
		(end 333.513176 -394.400786)
		(width 0.1651)
		(layer "In5.Cu")
		(net "P5E_PEX2_STN6_RX_DP<110>")
	)
	(segment
		(start 276.305264 -318.129666)
		(end 276.535388 -318.129666)
		(width 0.1143)
		(layer "In5.Cu")
		(net "P5E_PEX2_STN6_RX_DP<110>")
	)
	(segment
		(start 276.649688 -318.015366)
		(end 276.649688 -317.749936)
		(width 0.1143)
		(layer "In5.Cu")
		(net "P5E_PEX2_STN6_RX_DP<110>")
	)
	(segment
		(start 276.033738 -320.043048)
		(end 276.033738 -320.0146)
		(width 0.1143)
		(layer "In5.Cu")
		(net "P5E_PEX2_STN6_RX_DP<110>")
	)
	(segment
		(start 331.654404 -393.079224)
		(end 331.196442 -392.889994)
		(width 0.1651)
		(layer "In5.Cu")
		(net "P5E_PEX2_STN6_RX_DP<110>")
	)
	(segment
		(start 276.587204 -324.077076)
		(end 276.033738 -322.739766)
		(width 0.1651)
		(layer "In5.Cu")
		(net "P5E_PEX2_STN6_RX_DP<110>")
	)
	(segment
		(start 276.079458 -319.96888)
		(end 276.079458 -318.355472)
		(width 0.1143)
		(layer "In5.Cu")
		(net "P5E_PEX2_STN6_RX_DP<110>")
	)
	(segment
		(start 277.366476 -325.052436)
		(end 276.587204 -324.077076)
		(width 0.1651)
		(layer "In5.Cu")
		(net "P5E_PEX2_STN6_RX_DP<110>")
	)
	(segment
		(start 278.886412 -326.126856)
		(end 277.366476 -325.052436)
		(width 0.1651)
		(layer "In5.Cu")
		(net "P5E_PEX2_STN6_RX_DP<110>")
	)
	(segment
		(start 331.141324 -392.757152)
		(end 327.79589 -391.375646)
		(width 0.1651)
		(layer "In5.Cu")
		(net "P5E_PEX2_STN6_RX_DP<110>")
	)
	(segment
		(start 399.592292 -108.61548)
		(end 399.421858 -108.445046)
		(width 0.13462)
		(layer "F.Cu")
		(net "P5E_PEX3_STN1_RX_DP<21>")
	)
	(segment
		(start 400.54276 -108.312712)
		(end 400.239992 -108.61548)
		(width 0.13462)
		(layer "F.Cu")
		(net "P5E_PEX3_STN1_RX_DP<21>")
	)
	(segment
		(start 399.421858 -108.445046)
		(end 398.94256 -108.445046)
		(width 0.13462)
		(layer "F.Cu")
		(net "P5E_PEX3_STN1_RX_DP<21>")
	)
	(segment
		(start 400.239992 -108.61548)
		(end 399.592292 -108.61548)
		(width 0.13462)
		(layer "F.Cu")
		(net "P5E_PEX3_STN1_RX_DP<21>")
	)
	(segment
		(start 384.570986 -136.383268)
		(end 383.386584 -139.663932)
		(width 0.1651)
		(layer "In5.Cu")
		(net "P5E_PEX3_STN1_RX_DP<21>")
	)
	(segment
		(start 384.570986 -132.111496)
		(end 384.570986 -136.383268)
		(width 0.1651)
		(layer "In5.Cu")
		(net "P5E_PEX3_STN1_RX_DP<21>")
	)
	(segment
		(start 412.084012 -271.599152)
		(end 412.129732 -271.644872)
		(width 0.1143)
		(layer "In5.Cu")
		(net "P5E_PEX3_STN1_RX_DP<21>")
	)
	(segment
		(start 412.585408 -275.569934)
		(end 412.699708 -275.684234)
		(width 0.1143)
		(layer "In5.Cu")
		(net "P5E_PEX3_STN1_RX_DP<21>")
	)
	(segment
		(start 400.25193 -108.603542)
		(end 399.819368 -108.603542)
		(width 0.1651)
		(layer "In5.Cu")
		(net "P5E_PEX3_STN1_RX_DP<21>")
	)
	(segment
		(start 399.781268 -108.641642)
		(end 390.852914 -113.706656)
		(width 0.1651)
		(layer "In5.Cu")
		(net "P5E_PEX3_STN1_RX_DP<21>")
	)
	(segment
		(start 400.54276 -108.312712)
		(end 400.25193 -108.603542)
		(width 0.1651)
		(layer "In5.Cu")
		(net "P5E_PEX3_STN1_RX_DP<21>")
	)
	(segment
		(start 412.129732 -271.644872)
		(end 412.129732 -275.35505)
		(width 0.1143)
		(layer "In5.Cu")
		(net "P5E_PEX3_STN1_RX_DP<21>")
	)
	(segment
		(start 412.699708 -275.684234)
		(end 412.699708 -275.949664)
		(width 0.1143)
		(layer "In5.Cu")
		(net "P5E_PEX3_STN1_RX_DP<21>")
	)
	(segment
		(start 412.344616 -275.569934)
		(end 412.585408 -275.569934)
		(width 0.1143)
		(layer "In5.Cu")
		(net "P5E_PEX3_STN1_RX_DP<21>")
	)
	(segment
		(start 390.74598 -113.810542)
		(end 390.045194 -115.056158)
		(width 0.1651)
		(layer "In5.Cu")
		(net "P5E_PEX3_STN1_RX_DP<21>")
	)
	(segment
		(start 390.045194 -115.056158)
		(end 387.93293 -124.282962)
		(width 0.1651)
		(layer "In5.Cu")
		(net "P5E_PEX3_STN1_RX_DP<21>")
	)
	(segment
		(start 383.386584 -139.663932)
		(end 381.391414 -150.66772)
		(width 0.1651)
		(layer "In5.Cu")
		(net "P5E_PEX3_STN1_RX_DP<21>")
	)
	(segment
		(start 381.391414 -150.66772)
		(end 381.393446 -150.701756)
		(width 0.1651)
		(layer "In5.Cu")
		(net "P5E_PEX3_STN1_RX_DP<21>")
	)
	(segment
		(start 412.084012 -271.570704)
		(end 412.084012 -271.599152)
		(width 0.1143)
		(layer "In5.Cu")
		(net "P5E_PEX3_STN1_RX_DP<21>")
	)
	(segment
		(start 412.084012 -269.183104)
		(end 412.084012 -271.570704)
		(width 0.1651)
		(layer "In5.Cu")
		(net "P5E_PEX3_STN1_RX_DP<21>")
	)
	(segment
		(start 390.852914 -113.706656)
		(end 390.74598 -113.810542)
		(width 0.1651)
		(layer "In5.Cu")
		(net "P5E_PEX3_STN1_RX_DP<21>")
	)
	(segment
		(start 381.879094 -158.54426)
		(end 382.935988 -164.671756)
		(width 0.1651)
		(layer "In5.Cu")
		(net "P5E_PEX3_STN1_RX_DP<21>")
	)
	(segment
		(start 381.3937 -150.701756)
		(end 381.879094 -158.54426)
		(width 0.1651)
		(layer "In5.Cu")
		(net "P5E_PEX3_STN1_RX_DP<21>")
	)
	(segment
		(start 381.393446 -150.701756)
		(end 381.3937 -150.701756)
		(width 0.1651)
		(layer "In5.Cu")
		(net "P5E_PEX3_STN1_RX_DP<21>")
	)
	(segment
		(start 412.129732 -275.35505)
		(end 412.344616 -275.569934)
		(width 0.1143)
		(layer "In5.Cu")
		(net "P5E_PEX3_STN1_RX_DP<21>")
	)
	(segment
		(start 382.935988 -164.671756)
		(end 412.084012 -269.183104)
		(width 0.1651)
		(layer "In5.Cu")
		(net "P5E_PEX3_STN1_RX_DP<21>")
	)
	(segment
		(start 399.819368 -108.603542)
		(end 399.781268 -108.641642)
		(width 0.1651)
		(layer "In5.Cu")
		(net "P5E_PEX3_STN1_RX_DP<21>")
	)
	(segment
		(start 387.93293 -124.282962)
		(end 384.570986 -132.111496)
		(width 0.1651)
		(layer "In5.Cu")
		(net "P5E_PEX3_STN1_RX_DP<21>")
	)
	(segment
		(start 195.414646 -81.76006)
		(end 195.404232 -81.749646)
		(width 0.13208)
		(layer "F.Cu")
		(net "HP_NIC3_PWRGD_R")
	)
	(segment
		(start 196.51345 -83.526376)
		(end 195.414646 -82.427572)
		(width 0.13208)
		(layer "F.Cu")
		(net "HP_NIC3_PWRGD_R")
	)
	(segment
		(start 197.44944 -83.526376)
		(end 196.51345 -83.526376)
		(width 0.13208)
		(layer "F.Cu")
		(net "HP_NIC3_PWRGD_R")
	)
	(segment
		(start 195.414646 -81.76006)
		(end 195.414646 -82.427572)
		(width 0.13208)
		(layer "F.Cu")
		(net "HP_NIC3_PWRGD_R")
	)
	(segment
		(start 195.404232 -81.749646)
		(end 194.157346 -81.749646)
		(width 0.13208)
		(layer "F.Cu")
		(net "HP_NIC3_PWRGD_R")
	)
	(via
		(at 195.414646 -82.427572)
		(size 0.508)
		(drill 0.254)
		(layers "F.Cu" "B.Cu")
		(net "HP_NIC3_PWRGD_R")
	)
	(segment
		(start 73.349358 -363.232192)
		(end 72.93737 -362.956856)
		(width 0.1651)
		(layer "In9.Cu")
		(net "P5E_PEX0_STN6_RX_DP<99>")
	)
	(segment
		(start 74.933556 -364.153196)
		(end 74.521822 -363.878114)
		(width 0.1651)
		(layer "In9.Cu")
		(net "P5E_PEX0_STN6_RX_DP<99>")
	)
	(segment
		(start 80.666336 -367.98377)
		(end 75.535536 -364.555532)
		(width 0.1651)
		(layer "In9.Cu")
		(net "P5E_PEX0_STN6_RX_DP<99>")
	)
	(segment
		(start 66.326512 -357.99776)
		(end 66.326512 -341.227664)
		(width 0.1651)
		(layer "In9.Cu")
		(net "P5E_PEX0_STN6_RX_DP<99>")
	)
	(segment
		(start 72.93737 -362.956856)
		(end 72.90562 -362.79836)
		(width 0.1651)
		(layer "In9.Cu")
		(net "P5E_PEX0_STN6_RX_DP<99>")
	)
	(segment
		(start 54.329584 -316.506098)
		(end 54.60619 -316.229492)
		(width 0.1143)
		(layer "In9.Cu")
		(net "P5E_PEX0_STN6_RX_DP<99>")
	)
	(segment
		(start 54.283864 -319.865248)
		(end 54.329584 -319.819528)
		(width 0.1143)
		(layer "In9.Cu")
		(net "P5E_PEX0_STN6_RX_DP<99>")
	)
	(segment
		(start 80.710024 -374.390158)
		(end 80.710024 -374.772174)
		(width 0.1651)
		(layer "In9.Cu")
		(net "P5E_PEX0_STN6_RX_DP<99>")
	)
	(segment
		(start 80.837024 -374.899174)
		(end 81.228184 -374.899174)
		(width 0.1651)
		(layer "In9.Cu")
		(net "P5E_PEX0_STN6_RX_DP<99>")
	)
	(segment
		(start 54.329584 -319.819528)
		(end 54.329584 -316.506098)
		(width 0.1143)
		(layer "In9.Cu")
		(net "P5E_PEX0_STN6_RX_DP<99>")
	)
	(segment
		(start 74.363326 -363.90961)
		(end 73.951338 -363.634274)
		(width 0.1651)
		(layer "In9.Cu")
		(net "P5E_PEX0_STN6_RX_DP<99>")
	)
	(segment
		(start 73.507854 -363.200696)
		(end 73.349358 -363.232192)
		(width 0.1651)
		(layer "In9.Cu")
		(net "P5E_PEX0_STN6_RX_DP<99>")
	)
	(segment
		(start 54.283864 -319.893696)
		(end 54.283864 -319.865248)
		(width 0.1143)
		(layer "In9.Cu")
		(net "P5E_PEX0_STN6_RX_DP<99>")
	)
	(segment
		(start 75.377294 -364.587282)
		(end 74.965052 -364.311692)
		(width 0.1651)
		(layer "In9.Cu")
		(net "P5E_PEX0_STN6_RX_DP<99>")
	)
	(segment
		(start 74.965052 -364.311692)
		(end 74.933556 -364.153196)
		(width 0.1651)
		(layer "In9.Cu")
		(net "P5E_PEX0_STN6_RX_DP<99>")
	)
	(segment
		(start 80.710024 -374.772174)
		(end 80.837024 -374.899174)
		(width 0.1651)
		(layer "In9.Cu")
		(net "P5E_PEX0_STN6_RX_DP<99>")
	)
	(segment
		(start 74.521822 -363.878114)
		(end 74.363326 -363.90961)
		(width 0.1651)
		(layer "In9.Cu")
		(net "P5E_PEX0_STN6_RX_DP<99>")
	)
	(segment
		(start 73.951338 -363.634274)
		(end 73.919588 -363.475778)
		(width 0.1651)
		(layer "In9.Cu")
		(net "P5E_PEX0_STN6_RX_DP<99>")
	)
	(segment
		(start 55.138066 -326.08266)
		(end 54.283864 -324.020434)
		(width 0.1651)
		(layer "In9.Cu")
		(net "P5E_PEX0_STN6_RX_DP<99>")
	)
	(segment
		(start 73.919588 -363.475778)
		(end 73.507854 -363.200696)
		(width 0.1651)
		(layer "In9.Cu")
		(net "P5E_PEX0_STN6_RX_DP<99>")
	)
	(segment
		(start 66.714116 -358.933496)
		(end 66.326512 -357.99776)
		(width 0.1651)
		(layer "In9.Cu")
		(net "P5E_PEX0_STN6_RX_DP<99>")
	)
	(segment
		(start 54.60619 -316.229492)
		(end 54.810914 -316.229492)
		(width 0.1143)
		(layer "In9.Cu")
		(net "P5E_PEX0_STN6_RX_DP<99>")
	)
	(segment
		(start 75.535536 -364.555532)
		(end 75.377294 -364.587282)
		(width 0.1651)
		(layer "In9.Cu")
		(net "P5E_PEX0_STN6_RX_DP<99>")
	)
	(segment
		(start 81.318862 -368.636296)
		(end 80.666336 -367.98377)
		(width 0.1651)
		(layer "In9.Cu")
		(net "P5E_PEX0_STN6_RX_DP<99>")
	)
	(segment
		(start 66.326512 -341.227664)
		(end 60.890658 -333.092298)
		(width 0.1651)
		(layer "In9.Cu")
		(net "P5E_PEX0_STN6_RX_DP<99>")
	)
	(segment
		(start 81.602326 -374.525032)
		(end 81.602326 -369.320826)
		(width 0.1651)
		(layer "In9.Cu")
		(net "P5E_PEX0_STN6_RX_DP<99>")
	)
	(segment
		(start 68.907152 -360.126534)
		(end 67.199764 -359.419144)
		(width 0.1651)
		(layer "In9.Cu")
		(net "P5E_PEX0_STN6_RX_DP<99>")
	)
	(segment
		(start 81.228184 -374.899174)
		(end 81.602326 -374.525032)
		(width 0.1651)
		(layer "In9.Cu")
		(net "P5E_PEX0_STN6_RX_DP<99>")
	)
	(segment
		(start 54.810914 -316.229492)
		(end 54.899814 -316.140592)
		(width 0.1143)
		(layer "In9.Cu")
		(net "P5E_PEX0_STN6_RX_DP<99>")
	)
	(segment
		(start 60.890658 -333.092298)
		(end 55.138066 -326.08266)
		(width 0.1651)
		(layer "In9.Cu")
		(net "P5E_PEX0_STN6_RX_DP<99>")
	)
	(segment
		(start 54.899814 -316.140592)
		(end 54.899814 -315.849762)
		(width 0.1143)
		(layer "In9.Cu")
		(net "P5E_PEX0_STN6_RX_DP<99>")
	)
	(segment
		(start 67.199764 -359.419144)
		(end 66.714116 -358.933496)
		(width 0.1651)
		(layer "In9.Cu")
		(net "P5E_PEX0_STN6_RX_DP<99>")
	)
	(segment
		(start 72.90562 -362.79836)
		(end 68.907152 -360.126534)
		(width 0.1651)
		(layer "In9.Cu")
		(net "P5E_PEX0_STN6_RX_DP<99>")
	)
	(segment
		(start 54.283864 -324.020434)
		(end 54.283864 -319.893696)
		(width 0.1651)
		(layer "In9.Cu")
		(net "P5E_PEX0_STN6_RX_DP<99>")
	)
	(segment
		(start 81.602326 -369.320826)
		(end 81.318862 -368.636296)
		(width 0.1651)
		(layer "In9.Cu")
		(net "P5E_PEX0_STN6_RX_DP<99>")
	)
	(segment
		(start 278.047958 -34.2265)
		(end 274.131278 -34.2265)
		(width 0.13462)
		(layer "F.Cu")
		(net "P5E_PEX2_STN2_TX_C_DP<43>")
	)
	(segment
		(start 273.967702 -34.390076)
		(end 273.464782 -34.390076)
		(width 0.13462)
		(layer "F.Cu")
		(net "P5E_PEX2_STN2_TX_C_DP<43>")
	)
	(segment
		(start 274.131278 -34.2265)
		(end 273.967702 -34.390076)
		(width 0.13462)
		(layer "F.Cu")
		(net "P5E_PEX2_STN2_TX_C_DP<43>")
	)
	(segment
		(start 278.367744 -34.546286)
		(end 278.047958 -34.2265)
		(width 0.13462)
		(layer "F.Cu")
		(net "P5E_PEX2_STN2_TX_C_DP<43>")
	)
	(segment
		(start 304.658268 -339.786722)
		(end 304.281586 -338.942934)
		(width 0.1651)
		(layer "In5.Cu")
		(net "P5E_PEX2_STN6_RX_DP<109>")
	)
	(segment
		(start 304.60061 -339.937598)
		(end 304.658268 -339.786722)
		(width 0.1651)
		(layer "In5.Cu")
		(net "P5E_PEX2_STN6_RX_DP<109>")
	)
	(segment
		(start 277.029672 -319.96888)
		(end 277.029672 -316.455298)
		(width 0.1143)
		(layer "In5.Cu")
		(net "P5E_PEX2_STN6_RX_DP<109>")
	)
	(segment
		(start 304.953924 -340.447884)
		(end 304.80254 -340.390226)
		(width 0.1651)
		(layer "In5.Cu")
		(net "P5E_PEX2_STN6_RX_DP<109>")
	)
	(segment
		(start 336.73415 -395.075664)
		(end 336.584036 -394.726414)
		(width 0.1651)
		(layer "In5.Cu")
		(net "P5E_PEX2_STN6_RX_DP<109>")
	)
	(segment
		(start 332.46568 -392.21918)
		(end 332.007972 -392.028934)
		(width 0.1651)
		(layer "In5.Cu")
		(net "P5E_PEX2_STN6_RX_DP<109>")
	)
	(segment
		(start 336.206338 -394.354304)
		(end 333.41818 -392.504676)
		(width 0.1651)
		(layer "In5.Cu")
		(net "P5E_PEX2_STN6_RX_DP<109>")
	)
	(segment
		(start 332.007972 -392.028934)
		(end 331.953108 -391.896092)
		(width 0.1651)
		(layer "In5.Cu")
		(net "P5E_PEX2_STN6_RX_DP<109>")
	)
	(segment
		(start 277.029672 -316.455298)
		(end 277.255478 -316.229492)
		(width 0.1143)
		(layer "In5.Cu")
		(net "P5E_PEX2_STN6_RX_DP<109>")
	)
	(segment
		(start 326.520302 -388.737856)
		(end 304.95367 -340.447884)
		(width 0.1651)
		(layer "In5.Cu")
		(net "P5E_PEX2_STN6_RX_DP<109>")
	)
	(segment
		(start 277.485602 -316.229492)
		(end 277.599902 -316.115192)
		(width 0.1143)
		(layer "In5.Cu")
		(net "P5E_PEX2_STN6_RX_DP<109>")
	)
	(segment
		(start 276.983952 -320.043048)
		(end 276.983952 -320.0146)
		(width 0.1143)
		(layer "In5.Cu")
		(net "P5E_PEX2_STN6_RX_DP<109>")
	)
	(segment
		(start 331.953108 -391.896092)
		(end 328.059288 -390.279128)
		(width 0.1651)
		(layer "In5.Cu")
		(net "P5E_PEX2_STN6_RX_DP<109>")
	)
	(segment
		(start 333.41818 -392.504676)
		(end 332.598522 -392.164316)
		(width 0.1651)
		(layer "In5.Cu")
		(net "P5E_PEX2_STN6_RX_DP<109>")
	)
	(segment
		(start 303.76241 -338.383372)
		(end 279.345898 -325.192136)
		(width 0.1651)
		(layer "In5.Cu")
		(net "P5E_PEX2_STN6_RX_DP<109>")
	)
	(segment
		(start 304.95367 -340.447884)
		(end 304.953924 -340.447884)
		(width 0.1651)
		(layer "In5.Cu")
		(net "P5E_PEX2_STN6_RX_DP<109>")
	)
	(segment
		(start 277.61946 -323.970142)
		(end 276.983952 -322.435982)
		(width 0.1651)
		(layer "In5.Cu")
		(net "P5E_PEX2_STN6_RX_DP<109>")
	)
	(segment
		(start 335.890108 -400.390106)
		(end 335.890108 -400.772122)
		(width 0.1651)
		(layer "In5.Cu")
		(net "P5E_PEX2_STN6_RX_DP<109>")
	)
	(segment
		(start 304.80254 -340.390226)
		(end 304.60061 -339.937598)
		(width 0.1651)
		(layer "In5.Cu")
		(net "P5E_PEX2_STN6_RX_DP<109>")
	)
	(segment
		(start 335.890108 -400.772122)
		(end 336.017108 -400.899122)
		(width 0.1651)
		(layer "In5.Cu")
		(net "P5E_PEX2_STN6_RX_DP<109>")
	)
	(segment
		(start 276.983952 -322.435982)
		(end 276.983952 -320.043048)
		(width 0.1651)
		(layer "In5.Cu")
		(net "P5E_PEX2_STN6_RX_DP<109>")
	)
	(segment
		(start 277.255478 -316.229492)
		(end 277.485602 -316.229492)
		(width 0.1143)
		(layer "In5.Cu")
		(net "P5E_PEX2_STN6_RX_DP<109>")
	)
	(segment
		(start 336.447384 -400.899122)
		(end 336.73415 -400.612356)
		(width 0.1651)
		(layer "In5.Cu")
		(net "P5E_PEX2_STN6_RX_DP<109>")
	)
	(segment
		(start 279.345898 -325.192136)
		(end 277.61946 -323.970142)
		(width 0.1651)
		(layer "In5.Cu")
		(net "P5E_PEX2_STN6_RX_DP<109>")
	)
	(segment
		(start 336.73415 -400.612356)
		(end 336.73415 -395.075664)
		(width 0.1651)
		(layer "In5.Cu")
		(net "P5E_PEX2_STN6_RX_DP<109>")
	)
	(segment
		(start 276.983952 -320.0146)
		(end 277.029672 -319.96888)
		(width 0.1143)
		(layer "In5.Cu")
		(net "P5E_PEX2_STN6_RX_DP<109>")
	)
	(segment
		(start 328.059288 -390.279128)
		(end 326.520302 -388.737856)
		(width 0.1651)
		(layer "In5.Cu")
		(net "P5E_PEX2_STN6_RX_DP<109>")
	)
	(segment
		(start 277.599902 -316.115192)
		(end 277.599902 -315.849762)
		(width 0.1143)
		(layer "In5.Cu")
		(net "P5E_PEX2_STN6_RX_DP<109>")
	)
	(segment
		(start 336.584036 -394.726414)
		(end 336.206338 -394.354304)
		(width 0.1651)
		(layer "In5.Cu")
		(net "P5E_PEX2_STN6_RX_DP<109>")
	)
	(segment
		(start 336.017108 -400.899122)
		(end 336.447384 -400.899122)
		(width 0.1651)
		(layer "In5.Cu")
		(net "P5E_PEX2_STN6_RX_DP<109>")
	)
	(segment
		(start 304.281586 -338.942934)
		(end 303.76241 -338.383372)
		(width 0.1651)
		(layer "In5.Cu")
		(net "P5E_PEX2_STN6_RX_DP<109>")
	)
	(segment
		(start 332.598522 -392.164316)
		(end 332.46568 -392.21918)
		(width 0.1651)
		(layer "In5.Cu")
		(net "P5E_PEX2_STN6_RX_DP<109>")
	)
	(segment
		(start 393.685776 -136.39292)
		(end 393.857988 -136.565132)
		(width 0.13462)
		(layer "F.Cu")
		(net "P5E_PEX3_STN1_TX_C_DP<31>")
	)
	(segment
		(start 387.847332 -136.729724)
		(end 388.184136 -136.39292)
		(width 0.13462)
		(layer "F.Cu")
		(net "P5E_PEX3_STN1_TX_C_DP<31>")
	)
	(segment
		(start 388.184136 -136.39292)
		(end 393.685776 -136.39292)
		(width 0.13462)
		(layer "F.Cu")
		(net "P5E_PEX3_STN1_TX_C_DP<31>")
	)
	(segment
		(start 393.857988 -136.565132)
		(end 394.342366 -136.565132)
		(width 0.13462)
		(layer "F.Cu")
		(net "P5E_PEX3_STN1_TX_C_DP<31>")
	)
	(segment
		(start 400.562064 -150.560024)
		(end 401.25904 -151.257)
		(width 0.13208)
		(layer "F.Cu")
		(net "CLK_50M_NIC6_RBT_REF")
	)
	(segment
		(start 398.94256 -150.560024)
		(end 400.562064 -150.560024)
		(width 0.13208)
		(layer "F.Cu")
		(net "CLK_50M_NIC6_RBT_REF")
	)
	(via
		(at 401.25904 -151.257)
		(size 0.508)
		(drill 0.254)
		(layers "F.Cu" "B.Cu")
		(net "CLK_50M_NIC6_RBT_REF")
	)
	(segment
		(start 398.25549 -150.9776)
		(end 398.74444 -150.9776)
		(width 0.13208)
		(layer "B.Cu")
		(net "CLK_50M_NIC6_RBT_REF")
	)
	(segment
		(start 398.74444 -150.9776)
		(end 399.162016 -150.560024)
		(width 0.13208)
		(layer "B.Cu")
		(net "CLK_50M_NIC6_RBT_REF")
	)
	(segment
		(start 400.562064 -150.560024)
		(end 401.25904 -151.257)
		(width 0.13208)
		(layer "B.Cu")
		(net "CLK_50M_NIC6_RBT_REF")
	)
	(segment
		(start 399.162016 -150.560024)
		(end 400.562064 -150.560024)
		(width 0.13208)
		(layer "B.Cu")
		(net "CLK_50M_NIC6_RBT_REF")
	)
	(segment
		(start 43.165776 -319.966848)
		(end 43.120056 -319.921128)
		(width 0.1143)
		(layer "In5.Cu")
		(net "P5E_PEX0_STN6_RX_DN<111>")
	)
	(segment
		(start 43.499786 -316.534292)
		(end 43.499786 -316.799722)
		(width 0.1143)
		(layer "In5.Cu")
		(net "P5E_PEX0_STN6_RX_DN<111>")
	)
	(segment
		(start 57.511188 -355.895148)
		(end 56.63184 -352.384614)
		(width 0.1651)
		(layer "In5.Cu")
		(net "P5E_PEX0_STN6_RX_DN<111>")
	)
	(segment
		(start 56.63184 -352.384614)
		(end 55.853584 -346.075254)
		(width 0.1651)
		(layer "In5.Cu")
		(net "P5E_PEX0_STN6_RX_DN<111>")
	)
	(segment
		(start 72.710802 -394.65504)
		(end 72.224138 -394.168376)
		(width 0.1651)
		(layer "In5.Cu")
		(net "P5E_PEX0_STN6_RX_DN<111>")
	)
	(segment
		(start 65.281556 -388.68096)
		(end 63.989204 -385.561078)
		(width 0.1651)
		(layer "In5.Cu")
		(net "P5E_PEX0_STN6_RX_DN<111>")
	)
	(segment
		(start 72.224138 -394.168376)
		(end 67.839336 -391.23874)
		(width 0.1651)
		(layer "In5.Cu")
		(net "P5E_PEX0_STN6_RX_DN<111>")
	)
	(segment
		(start 43.385486 -316.419992)
		(end 43.499786 -316.534292)
		(width 0.1143)
		(layer "In5.Cu")
		(net "P5E_PEX0_STN6_RX_DN<111>")
	)
	(segment
		(start 73.084182 -400.777964)
		(end 73.084182 -395.556486)
		(width 0.1651)
		(layer "In5.Cu")
		(net "P5E_PEX0_STN6_RX_DN<111>")
	)
	(segment
		(start 52.808378 -338.723986)
		(end 44.308268 -326.002396)
		(width 0.1651)
		(layer "In5.Cu")
		(net "P5E_PEX0_STN6_RX_DN<111>")
	)
	(segment
		(start 44.308268 -326.002396)
		(end 43.165776 -323.244718)
		(width 0.1651)
		(layer "In5.Cu")
		(net "P5E_PEX0_STN6_RX_DN<111>")
	)
	(segment
		(start 72.03694 -401.181062)
		(end 72.681084 -401.181062)
		(width 0.1651)
		(layer "In5.Cu")
		(net "P5E_PEX0_STN6_RX_DN<111>")
	)
	(segment
		(start 43.165776 -323.244718)
		(end 43.165776 -319.995296)
		(width 0.1651)
		(layer "In5.Cu")
		(net "P5E_PEX0_STN6_RX_DN<111>")
	)
	(segment
		(start 71.90994 -401.690078)
		(end 71.90994 -401.308062)
		(width 0.1651)
		(layer "In5.Cu")
		(net "P5E_PEX0_STN6_RX_DN<111>")
	)
	(segment
		(start 43.120056 -319.921128)
		(end 43.120056 -316.534292)
		(width 0.1143)
		(layer "In5.Cu")
		(net "P5E_PEX0_STN6_RX_DN<111>")
	)
	(segment
		(start 72.681084 -401.181062)
		(end 73.084182 -400.777964)
		(width 0.1651)
		(layer "In5.Cu")
		(net "P5E_PEX0_STN6_RX_DN<111>")
	)
	(segment
		(start 63.989204 -385.561078)
		(end 62.288674 -368.279426)
		(width 0.1651)
		(layer "In5.Cu")
		(net "P5E_PEX0_STN6_RX_DN<111>")
	)
	(segment
		(start 43.120056 -316.534292)
		(end 43.234356 -316.419992)
		(width 0.1143)
		(layer "In5.Cu")
		(net "P5E_PEX0_STN6_RX_DN<111>")
	)
	(segment
		(start 67.839336 -391.23874)
		(end 65.281556 -388.68096)
		(width 0.1651)
		(layer "In5.Cu")
		(net "P5E_PEX0_STN6_RX_DN<111>")
	)
	(segment
		(start 62.288674 -368.279426)
		(end 57.511188 -355.895148)
		(width 0.1651)
		(layer "In5.Cu")
		(net "P5E_PEX0_STN6_RX_DN<111>")
	)
	(segment
		(start 43.165776 -319.995296)
		(end 43.165776 -319.966848)
		(width 0.1143)
		(layer "In5.Cu")
		(net "P5E_PEX0_STN6_RX_DN<111>")
	)
	(segment
		(start 43.234356 -316.419992)
		(end 43.385486 -316.419992)
		(width 0.1143)
		(layer "In5.Cu")
		(net "P5E_PEX0_STN6_RX_DN<111>")
	)
	(segment
		(start 55.853584 -346.075254)
		(end 52.808378 -338.723986)
		(width 0.1651)
		(layer "In5.Cu")
		(net "P5E_PEX0_STN6_RX_DN<111>")
	)
	(segment
		(start 71.90994 -401.308062)
		(end 72.03694 -401.181062)
		(width 0.1651)
		(layer "In5.Cu")
		(net "P5E_PEX0_STN6_RX_DN<111>")
	)
	(segment
		(start 73.084182 -395.556486)
		(end 72.710802 -394.65504)
		(width 0.1651)
		(layer "In5.Cu")
		(net "P5E_PEX0_STN6_RX_DN<111>")
	)
	(segment
		(start 294.385492 -32.589978)
		(end 294.218614 -32.4231)
		(width 0.13462)
		(layer "F.Cu")
		(net "P5E_PEX2_STN2_RX_DP<38>")
	)
	(segment
		(start 293.563802 -32.4231)
		(end 293.26459 -32.722312)
		(width 0.13462)
		(layer "F.Cu")
		(net "P5E_PEX2_STN2_RX_DP<38>")
	)
	(segment
		(start 294.86479 -32.589978)
		(end 294.385492 -32.589978)
		(width 0.13462)
		(layer "F.Cu")
		(net "P5E_PEX2_STN2_RX_DP<38>")
	)
	(segment
		(start 294.218614 -32.4231)
		(end 293.563802 -32.4231)
		(width 0.13462)
		(layer "F.Cu")
		(net "P5E_PEX2_STN2_RX_DP<38>")
	)
	(segment
		(start 294.3479 -33.583626)
		(end 294.360346 -32.7787)
		(width 0.1651)
		(layer "In7.Cu")
		(net "P5E_PEX2_STN2_RX_DP<38>")
	)
	(segment
		(start 284.844744 -275.570188)
		(end 284.629352 -275.354796)
		(width 0.1143)
		(layer "In7.Cu")
		(net "P5E_PEX2_STN2_RX_DP<38>")
	)
	(segment
		(start 294.09009 -35.728402)
		(end 294.208708 -35.647122)
		(width 0.1651)
		(layer "In7.Cu")
		(net "P5E_PEX2_STN2_RX_DP<38>")
	)
	(segment
		(start 294.080438 -36.334192)
		(end 293.999158 -36.215574)
		(width 0.1651)
		(layer "In7.Cu")
		(net "P5E_PEX2_STN2_RX_DP<38>")
	)
	(segment
		(start 285.085536 -275.570188)
		(end 284.844744 -275.570188)
		(width 0.1143)
		(layer "In7.Cu")
		(net "P5E_PEX2_STN2_RX_DP<38>")
	)
	(segment
		(start 293.999158 -36.215574)
		(end 294.09009 -35.728402)
		(width 0.1651)
		(layer "In7.Cu")
		(net "P5E_PEX2_STN2_RX_DP<38>")
	)
	(segment
		(start 293.55542 -32.431482)
		(end 293.26459 -32.722312)
		(width 0.1651)
		(layer "In7.Cu")
		(net "P5E_PEX2_STN2_RX_DP<38>")
	)
	(segment
		(start 294.208708 -35.647122)
		(end 294.325548 -35.019996)
		(width 0.1651)
		(layer "In7.Cu")
		(net "P5E_PEX2_STN2_RX_DP<38>")
	)
	(segment
		(start 284.629352 -275.354796)
		(end 284.629352 -271.467072)
		(width 0.1143)
		(layer "In7.Cu")
		(net "P5E_PEX2_STN2_RX_DP<38>")
	)
	(segment
		(start 294.236902 -34.179256)
		(end 294.244522 -33.683702)
		(width 0.1651)
		(layer "In7.Cu")
		(net "P5E_PEX2_STN2_RX_DP<38>")
	)
	(segment
		(start 293.801292 -37.832538)
		(end 294.080438 -36.334192)
		(width 0.1651)
		(layer "In7.Cu")
		(net "P5E_PEX2_STN2_RX_DP<38>")
	)
	(segment
		(start 294.244522 -33.683702)
		(end 294.3479 -33.583626)
		(width 0.1651)
		(layer "In7.Cu")
		(net "P5E_PEX2_STN2_RX_DP<38>")
	)
	(segment
		(start 285.199836 -275.949918)
		(end 285.199836 -275.684488)
		(width 0.1143)
		(layer "In7.Cu")
		(net "P5E_PEX2_STN2_RX_DP<38>")
	)
	(segment
		(start 294.360346 -32.7787)
		(end 294.013128 -32.431482)
		(width 0.1651)
		(layer "In7.Cu")
		(net "P5E_PEX2_STN2_RX_DP<38>")
	)
	(segment
		(start 294.325548 -35.019996)
		(end 294.336978 -34.28238)
		(width 0.1651)
		(layer "In7.Cu")
		(net "P5E_PEX2_STN2_RX_DP<38>")
	)
	(segment
		(start 294.336978 -34.28238)
		(end 294.236902 -34.179256)
		(width 0.1651)
		(layer "In7.Cu")
		(net "P5E_PEX2_STN2_RX_DP<38>")
	)
	(segment
		(start 284.629352 -271.467072)
		(end 284.583632 -271.421352)
		(width 0.1143)
		(layer "In7.Cu")
		(net "P5E_PEX2_STN2_RX_DP<38>")
	)
	(segment
		(start 295.213278 -49.959514)
		(end 293.831264 -39.731442)
		(width 0.1651)
		(layer "In7.Cu")
		(net "P5E_PEX2_STN2_RX_DP<38>")
	)
	(segment
		(start 284.583632 -265.765788)
		(end 284.667198 -264.812272)
		(width 0.1651)
		(layer "In7.Cu")
		(net "P5E_PEX2_STN2_RX_DP<38>")
	)
	(segment
		(start 295.067482 -67.907408)
		(end 295.040558 -61.00953)
		(width 0.1651)
		(layer "In7.Cu")
		(net "P5E_PEX2_STN2_RX_DP<38>")
	)
	(segment
		(start 295.040558 -61.00953)
		(end 295.213278 -49.959514)
		(width 0.1651)
		(layer "In7.Cu")
		(net "P5E_PEX2_STN2_RX_DP<38>")
	)
	(segment
		(start 293.831264 -39.731442)
		(end 293.801292 -37.832538)
		(width 0.1651)
		(layer "In7.Cu")
		(net "P5E_PEX2_STN2_RX_DP<38>")
	)
	(segment
		(start 294.013128 -32.431482)
		(end 293.55542 -32.431482)
		(width 0.1651)
		(layer "In7.Cu")
		(net "P5E_PEX2_STN2_RX_DP<38>")
	)
	(segment
		(start 284.583632 -271.421352)
		(end 284.583632 -271.392904)
		(width 0.1143)
		(layer "In7.Cu")
		(net "P5E_PEX2_STN2_RX_DP<38>")
	)
	(segment
		(start 284.667198 -264.812272)
		(end 295.067482 -67.907408)
		(width 0.1651)
		(layer "In7.Cu")
		(net "P5E_PEX2_STN2_RX_DP<38>")
	)
	(segment
		(start 285.199836 -275.684488)
		(end 285.085536 -275.570188)
		(width 0.1143)
		(layer "In7.Cu")
		(net "P5E_PEX2_STN2_RX_DP<38>")
	)
	(segment
		(start 284.583632 -271.392904)
		(end 284.583632 -265.765788)
		(width 0.1651)
		(layer "In7.Cu")
		(net "P5E_PEX2_STN2_RX_DP<38>")
	)
	(segment
		(start 316.500764 -350.365314)
		(end 316.180724 -350.685354)
		(width 0.13462)
		(layer "F.Cu")
		(net "P5E_PEX2_STN6_TX_C_DN<110>")
	)
	(segment
		(start 316.180724 -351.316798)
		(end 316.475364 -351.611438)
		(width 0.13462)
		(layer "F.Cu")
		(net "P5E_PEX2_STN6_TX_C_DN<110>")
	)
	(segment
		(start 316.180724 -350.685354)
		(end 316.180724 -351.316798)
		(width 0.13462)
		(layer "F.Cu")
		(net "P5E_PEX2_STN6_TX_C_DN<110>")
	)
	(segment
		(start 314.630054 -357.91902)
		(end 314.630054 -354.027486)
		(width 0.1651)
		(layer "In13.Cu")
		(net "P5E_PEX2_STN6_TX_C_DN<110>")
	)
	(segment
		(start 334.364076 -410.080968)
		(end 334.815942 -409.629102)
		(width 0.1651)
		(layer "In13.Cu")
		(net "P5E_PEX2_STN6_TX_C_DN<110>")
	)
	(segment
		(start 329.221338 -391.856722)
		(end 325.180198 -388.56666)
		(width 0.1651)
		(layer "In13.Cu")
		(net "P5E_PEX2_STN6_TX_C_DN<110>")
	)
	(segment
		(start 333.68996 -410.589984)
		(end 333.68996 -410.207968)
		(width 0.1651)
		(layer "In13.Cu")
		(net "P5E_PEX2_STN6_TX_C_DN<110>")
	)
	(segment
		(start 334.815942 -409.629102)
		(end 334.815942 -395.784578)
		(width 0.1651)
		(layer "In13.Cu")
		(net "P5E_PEX2_STN6_TX_C_DN<110>")
	)
	(segment
		(start 334.815942 -395.784578)
		(end 334.552544 -395.23543)
		(width 0.1651)
		(layer "In13.Cu")
		(net "P5E_PEX2_STN6_TX_C_DN<110>")
	)
	(segment
		(start 316.184534 -351.902268)
		(end 316.475364 -351.611438)
		(width 0.1651)
		(layer "In13.Cu")
		(net "P5E_PEX2_STN6_TX_C_DN<110>")
	)
	(segment
		(start 333.68996 -410.207968)
		(end 333.81696 -410.080968)
		(width 0.1651)
		(layer "In13.Cu")
		(net "P5E_PEX2_STN6_TX_C_DN<110>")
	)
	(segment
		(start 332.412594 -393.197842)
		(end 329.221338 -391.856722)
		(width 0.1651)
		(layer "In13.Cu")
		(net "P5E_PEX2_STN6_TX_C_DN<110>")
	)
	(segment
		(start 325.180198 -388.56666)
		(end 314.630054 -357.91902)
		(width 0.1651)
		(layer "In13.Cu")
		(net "P5E_PEX2_STN6_TX_C_DN<110>")
	)
	(segment
		(start 333.81696 -410.080968)
		(end 334.364076 -410.080968)
		(width 0.1651)
		(layer "In13.Cu")
		(net "P5E_PEX2_STN6_TX_C_DN<110>")
	)
	(segment
		(start 316.184534 -352.473006)
		(end 316.184534 -351.902268)
		(width 0.1651)
		(layer "In13.Cu")
		(net "P5E_PEX2_STN6_TX_C_DN<110>")
	)
	(segment
		(start 334.552544 -395.23543)
		(end 332.412594 -393.197842)
		(width 0.1651)
		(layer "In13.Cu")
		(net "P5E_PEX2_STN6_TX_C_DN<110>")
	)
	(segment
		(start 314.630054 -354.027486)
		(end 316.184534 -352.473006)
		(width 0.1651)
		(layer "In13.Cu")
		(net "P5E_PEX2_STN6_TX_C_DN<110>")
	)
	(segment
		(start 400.54276 -121.886472)
		(end 400.246088 -121.5898)
		(width 0.13462)
		(layer "F.Cu")
		(net "P5E_PEX3_STN1_RX_DN<25>")
	)
	(segment
		(start 399.588736 -121.5898)
		(end 399.423636 -121.7549)
		(width 0.13462)
		(layer "F.Cu")
		(net "P5E_PEX3_STN1_RX_DN<25>")
	)
	(segment
		(start 399.423636 -121.7549)
		(end 398.94256 -121.7549)
		(width 0.13462)
		(layer "F.Cu")
		(net "P5E_PEX3_STN1_RX_DN<25>")
	)
	(segment
		(start 400.246088 -121.5898)
		(end 399.588736 -121.5898)
		(width 0.13462)
		(layer "F.Cu")
		(net "P5E_PEX3_STN1_RX_DN<25>")
	)
	(segment
		(start 387.980936 -162.364166)
		(end 416.165792 -268.037056)
		(width 0.1651)
		(layer "In5.Cu")
		(net "P5E_PEX3_STN1_RX_DN<25>")
	)
	(segment
		(start 397.169894 -123.405138)
		(end 397.16202 -123.566682)
		(width 0.1651)
		(layer "In5.Cu")
		(net "P5E_PEX3_STN1_RX_DN<25>")
	)
	(segment
		(start 386.84581 -145.714212)
		(end 386.435092 -147.294346)
		(width 0.1651)
		(layer "In5.Cu")
		(net "P5E_PEX3_STN1_RX_DN<25>")
	)
	(segment
		(start 389.46328 -142.023084)
		(end 389.321548 -142.10157)
		(width 0.1651)
		(layer "In5.Cu")
		(net "P5E_PEX3_STN1_RX_DN<25>")
	)
	(segment
		(start 416.165792 -268.037056)
		(end 416.165792 -271.570704)
		(width 0.1651)
		(layer "In5.Cu")
		(net "P5E_PEX3_STN1_RX_DN<25>")
	)
	(segment
		(start 392.92276 -127.914146)
		(end 392.761978 -127.93218)
		(width 0.1651)
		(layer "In5.Cu")
		(net "P5E_PEX3_STN1_RX_DN<25>")
	)
	(segment
		(start 392.064748 -128.970024)
		(end 390.49706 -137.99439)
		(width 0.1651)
		(layer "In5.Cu")
		(net "P5E_PEX3_STN1_RX_DN<25>")
	)
	(segment
		(start 394.827506 -125.531372)
		(end 394.28293 -126.025656)
		(width 0.1651)
		(layer "In5.Cu")
		(net "P5E_PEX3_STN1_RX_DN<25>")
	)
	(segment
		(start 397.69796 -123.080018)
		(end 397.536416 -123.072398)
		(width 0.1651)
		(layer "In5.Cu")
		(net "P5E_PEX3_STN1_RX_DN<25>")
	)
	(segment
		(start 416.22345 -275.379434)
		(end 416.385248 -275.379434)
		(width 0.1143)
		(layer "In5.Cu")
		(net "P5E_PEX3_STN1_RX_DN<25>")
	)
	(segment
		(start 416.385248 -275.379434)
		(end 416.499548 -275.265134)
		(width 0.1143)
		(layer "In5.Cu")
		(net "P5E_PEX3_STN1_RX_DN<25>")
	)
	(segment
		(start 396.633446 -123.892056)
		(end 396.266924 -124.224796)
		(width 0.1651)
		(layer "In5.Cu")
		(net "P5E_PEX3_STN1_RX_DN<25>")
	)
	(segment
		(start 387.044184 -157.221936)
		(end 387.980936 -162.364166)
		(width 0.1651)
		(layer "In5.Cu")
		(net "P5E_PEX3_STN1_RX_DN<25>")
	)
	(segment
		(start 400.54276 -121.886472)
		(end 400.25193 -121.595642)
		(width 0.1651)
		(layer "In5.Cu")
		(net "P5E_PEX3_STN1_RX_DN<25>")
	)
	(segment
		(start 389.131556 -142.766034)
		(end 386.84581 -145.714212)
		(width 0.1651)
		(layer "In5.Cu")
		(net "P5E_PEX3_STN1_RX_DN<25>")
	)
	(segment
		(start 393.213844 -127.366014)
		(end 393.231878 -127.526542)
		(width 0.1651)
		(layer "In5.Cu")
		(net "P5E_PEX3_STN1_RX_DN<25>")
	)
	(segment
		(start 389.520938 -141.405356)
		(end 389.599424 -141.54658)
		(width 0.1651)
		(layer "In5.Cu")
		(net "P5E_PEX3_STN1_RX_DN<25>")
	)
	(segment
		(start 389.321548 -142.10157)
		(end 389.131556 -142.766034)
		(width 0.1651)
		(layer "In5.Cu")
		(net "P5E_PEX3_STN1_RX_DN<25>")
	)
	(segment
		(start 394.98905 -125.538992)
		(end 394.827506 -125.531372)
		(width 0.1651)
		(layer "In5.Cu")
		(net "P5E_PEX3_STN1_RX_DN<25>")
	)
	(segment
		(start 395.730476 -124.711714)
		(end 395.363954 -125.044454)
		(width 0.1651)
		(layer "In5.Cu")
		(net "P5E_PEX3_STN1_RX_DN<25>")
	)
	(segment
		(start 396.266924 -124.224796)
		(end 396.25905 -124.38634)
		(width 0.1651)
		(layer "In5.Cu")
		(net "P5E_PEX3_STN1_RX_DN<25>")
	)
	(segment
		(start 416.165792 -271.570704)
		(end 416.165792 -271.599152)
		(width 0.1143)
		(layer "In5.Cu")
		(net "P5E_PEX3_STN1_RX_DN<25>")
	)
	(segment
		(start 398.06499 -122.747024)
		(end 397.69796 -123.080018)
		(width 0.1651)
		(layer "In5.Cu")
		(net "P5E_PEX3_STN1_RX_DN<25>")
	)
	(segment
		(start 393.683236 -126.960884)
		(end 393.522454 -126.978918)
		(width 0.1651)
		(layer "In5.Cu")
		(net "P5E_PEX3_STN1_RX_DN<25>")
	)
	(segment
		(start 395.35608 -125.205998)
		(end 394.98905 -125.538992)
		(width 0.1651)
		(layer "In5.Cu")
		(net "P5E_PEX3_STN1_RX_DN<25>")
	)
	(segment
		(start 399.508218 -121.949718)
		(end 399.047716 -122.133106)
		(width 0.1651)
		(layer "In5.Cu")
		(net "P5E_PEX3_STN1_RX_DN<25>")
	)
	(segment
		(start 400.25193 -121.595642)
		(end 400.08683 -121.595642)
		(width 0.1651)
		(layer "In5.Cu")
		(net "P5E_PEX3_STN1_RX_DN<25>")
	)
	(segment
		(start 416.499548 -275.265134)
		(end 416.499548 -274.999704)
		(width 0.1143)
		(layer "In5.Cu")
		(net "P5E_PEX3_STN1_RX_DN<25>")
	)
	(segment
		(start 393.992354 -126.57328)
		(end 393.683236 -126.960884)
		(width 0.1651)
		(layer "In5.Cu")
		(net "P5E_PEX3_STN1_RX_DN<25>")
	)
	(segment
		(start 386.435092 -147.294346)
		(end 387.044184 -157.221936)
		(width 0.1651)
		(layer "In5.Cu")
		(net "P5E_PEX3_STN1_RX_DN<25>")
	)
	(segment
		(start 393.974066 -126.412752)
		(end 393.992354 -126.57328)
		(width 0.1651)
		(layer "In5.Cu")
		(net "P5E_PEX3_STN1_RX_DN<25>")
	)
	(segment
		(start 393.231878 -127.526542)
		(end 392.92276 -127.914146)
		(width 0.1651)
		(layer "In5.Cu")
		(net "P5E_PEX3_STN1_RX_DN<25>")
	)
	(segment
		(start 398.89938 -122.069352)
		(end 398.439386 -122.25274)
		(width 0.1651)
		(layer "In5.Cu")
		(net "P5E_PEX3_STN1_RX_DN<25>")
	)
	(segment
		(start 390.49706 -137.99439)
		(end 389.520938 -141.405356)
		(width 0.1651)
		(layer "In5.Cu")
		(net "P5E_PEX3_STN1_RX_DN<25>")
	)
	(segment
		(start 397.536416 -123.072398)
		(end 397.169894 -123.405138)
		(width 0.1651)
		(layer "In5.Cu")
		(net "P5E_PEX3_STN1_RX_DN<25>")
	)
	(segment
		(start 395.363954 -125.044454)
		(end 395.35608 -125.205998)
		(width 0.1651)
		(layer "In5.Cu")
		(net "P5E_PEX3_STN1_RX_DN<25>")
	)
	(segment
		(start 396.79499 -123.899676)
		(end 396.633446 -123.892056)
		(width 0.1651)
		(layer "In5.Cu")
		(net "P5E_PEX3_STN1_RX_DN<25>")
	)
	(segment
		(start 400.08683 -121.595642)
		(end 399.571972 -121.800874)
		(width 0.1651)
		(layer "In5.Cu")
		(net "P5E_PEX3_STN1_RX_DN<25>")
	)
	(segment
		(start 398.439386 -122.25274)
		(end 398.072864 -122.58548)
		(width 0.1651)
		(layer "In5.Cu")
		(net "P5E_PEX3_STN1_RX_DN<25>")
	)
	(segment
		(start 394.28293 -126.025656)
		(end 393.974066 -126.412752)
		(width 0.1651)
		(layer "In5.Cu")
		(net "P5E_PEX3_STN1_RX_DN<25>")
	)
	(segment
		(start 397.16202 -123.566682)
		(end 396.79499 -123.899676)
		(width 0.1651)
		(layer "In5.Cu")
		(net "P5E_PEX3_STN1_RX_DN<25>")
	)
	(segment
		(start 399.571972 -121.800874)
		(end 399.508218 -121.949718)
		(width 0.1651)
		(layer "In5.Cu")
		(net "P5E_PEX3_STN1_RX_DN<25>")
	)
	(segment
		(start 389.599424 -141.54658)
		(end 389.46328 -142.023084)
		(width 0.1651)
		(layer "In5.Cu")
		(net "P5E_PEX3_STN1_RX_DN<25>")
	)
	(segment
		(start 392.761978 -127.93218)
		(end 392.224768 -128.605788)
		(width 0.1651)
		(layer "In5.Cu")
		(net "P5E_PEX3_STN1_RX_DN<25>")
	)
	(segment
		(start 395.89202 -124.719334)
		(end 395.730476 -124.711714)
		(width 0.1651)
		(layer "In5.Cu")
		(net "P5E_PEX3_STN1_RX_DN<25>")
	)
	(segment
		(start 399.047716 -122.133106)
		(end 398.89938 -122.069352)
		(width 0.1651)
		(layer "In5.Cu")
		(net "P5E_PEX3_STN1_RX_DN<25>")
	)
	(segment
		(start 393.522454 -126.978918)
		(end 393.213844 -127.366014)
		(width 0.1651)
		(layer "In5.Cu")
		(net "P5E_PEX3_STN1_RX_DN<25>")
	)
	(segment
		(start 396.25905 -124.38634)
		(end 395.89202 -124.719334)
		(width 0.1651)
		(layer "In5.Cu")
		(net "P5E_PEX3_STN1_RX_DN<25>")
	)
	(segment
		(start 392.224768 -128.605788)
		(end 392.064748 -128.970024)
		(width 0.1651)
		(layer "In5.Cu")
		(net "P5E_PEX3_STN1_RX_DN<25>")
	)
	(segment
		(start 398.072864 -122.58548)
		(end 398.06499 -122.747024)
		(width 0.1651)
		(layer "In5.Cu")
		(net "P5E_PEX3_STN1_RX_DN<25>")
	)
	(segment
		(start 416.120072 -271.644872)
		(end 416.120072 -275.276056)
		(width 0.1143)
		(layer "In5.Cu")
		(net "P5E_PEX3_STN1_RX_DN<25>")
	)
	(segment
		(start 416.165792 -271.599152)
		(end 416.120072 -271.644872)
		(width 0.1143)
		(layer "In5.Cu")
		(net "P5E_PEX3_STN1_RX_DN<25>")
	)
	(segment
		(start 416.120072 -275.276056)
		(end 416.22345 -275.379434)
		(width 0.1143)
		(layer "In5.Cu")
		(net "P5E_PEX3_STN1_RX_DN<25>")
	)
	(segment
		(start 68.453762 -345.465146)
		(end 68.159122 -345.170506)
		(width 0.13462)
		(layer "F.Cu")
		(net "P5E_PEX0_STN6_TX_C_DN<109>")
	)
	(segment
		(start 68.159122 -345.170506)
		(end 68.159122 -344.539062)
		(width 0.13462)
		(layer "F.Cu")
		(net "P5E_PEX0_STN6_TX_C_DN<109>")
	)
	(segment
		(start 68.159122 -344.539062)
		(end 68.479162 -344.219022)
		(width 0.13462)
		(layer "F.Cu")
		(net "P5E_PEX0_STN6_TX_C_DN<109>")
	)
	(segment
		(start 65.674494 -382.159256)
		(end 66.030094 -367.371376)
		(width 0.1651)
		(layer "In13.Cu")
		(net "P5E_PEX0_STN6_TX_C_DN<109>")
	)
	(segment
		(start 76.309982 -409.490164)
		(end 76.309982 -409.108148)
		(width 0.1651)
		(layer "In13.Cu")
		(net "P5E_PEX0_STN6_TX_C_DN<109>")
	)
	(segment
		(start 66.40195 -363.597698)
		(end 66.608452 -359.38841)
		(width 0.1651)
		(layer "In13.Cu")
		(net "P5E_PEX0_STN6_TX_C_DN<109>")
	)
	(segment
		(start 66.608452 -347.983048)
		(end 68.162932 -346.428568)
		(width 0.1651)
		(layer "In13.Cu")
		(net "P5E_PEX0_STN6_TX_C_DN<109>")
	)
	(segment
		(start 67.212464 -387.912864)
		(end 65.674494 -384.199638)
		(width 0.1651)
		(layer "In13.Cu")
		(net "P5E_PEX0_STN6_TX_C_DN<109>")
	)
	(segment
		(start 76.309982 -409.108148)
		(end 76.436982 -408.981148)
		(width 0.1651)
		(layer "In13.Cu")
		(net "P5E_PEX0_STN6_TX_C_DN<109>")
	)
	(segment
		(start 69.00799 -389.70839)
		(end 67.212464 -387.912864)
		(width 0.1651)
		(layer "In13.Cu")
		(net "P5E_PEX0_STN6_TX_C_DN<109>")
	)
	(segment
		(start 68.162932 -346.428568)
		(end 68.162932 -345.755976)
		(width 0.1651)
		(layer "In13.Cu")
		(net "P5E_PEX0_STN6_TX_C_DN<109>")
	)
	(segment
		(start 76.84643 -394.19403)
		(end 74.633836 -392.715496)
		(width 0.1651)
		(layer "In13.Cu")
		(net "P5E_PEX0_STN6_TX_C_DN<109>")
	)
	(segment
		(start 77.484224 -408.499818)
		(end 77.484224 -394.831824)
		(width 0.1651)
		(layer "In13.Cu")
		(net "P5E_PEX0_STN6_TX_C_DN<109>")
	)
	(segment
		(start 66.608452 -359.38841)
		(end 66.608452 -347.983048)
		(width 0.1651)
		(layer "In13.Cu")
		(net "P5E_PEX0_STN6_TX_C_DN<109>")
	)
	(segment
		(start 77.002894 -408.981148)
		(end 77.484224 -408.499818)
		(width 0.1651)
		(layer "In13.Cu")
		(net "P5E_PEX0_STN6_TX_C_DN<109>")
	)
	(segment
		(start 74.633836 -392.715496)
		(end 69.00799 -389.70839)
		(width 0.1651)
		(layer "In13.Cu")
		(net "P5E_PEX0_STN6_TX_C_DN<109>")
	)
	(segment
		(start 76.436982 -408.981148)
		(end 77.002894 -408.981148)
		(width 0.1651)
		(layer "In13.Cu")
		(net "P5E_PEX0_STN6_TX_C_DN<109>")
	)
	(segment
		(start 66.030094 -367.371376)
		(end 66.40195 -363.597698)
		(width 0.1651)
		(layer "In13.Cu")
		(net "P5E_PEX0_STN6_TX_C_DN<109>")
	)
	(segment
		(start 77.484224 -394.831824)
		(end 76.84643 -394.19403)
		(width 0.1651)
		(layer "In13.Cu")
		(net "P5E_PEX0_STN6_TX_C_DN<109>")
	)
	(segment
		(start 65.674494 -384.199638)
		(end 65.674494 -382.159256)
		(width 0.1651)
		(layer "In13.Cu")
		(net "P5E_PEX0_STN6_TX_C_DN<109>")
	)
	(segment
		(start 68.162932 -345.755976)
		(end 68.453762 -345.465146)
		(width 0.1651)
		(layer "In13.Cu")
		(net "P5E_PEX0_STN6_TX_C_DN<109>")
	)
	(segment
		(start 330.04125 -30.35808)
		(end 326.135746 -30.35808)
		(width 0.13462)
		(layer "F.Cu")
		(net "P5E_PEX2_STN2_TX_C_DN<33>")
	)
	(segment
		(start 326.135746 -30.35808)
		(end 325.967852 -30.190186)
		(width 0.13462)
		(layer "F.Cu")
		(net "P5E_PEX2_STN2_TX_C_DN<33>")
	)
	(segment
		(start 330.36764 -30.03169)
		(end 330.04125 -30.35808)
		(width 0.13462)
		(layer "F.Cu")
		(net "P5E_PEX2_STN2_TX_C_DN<33>")
	)
	(segment
		(start 325.967852 -30.190186)
		(end 325.464678 -30.190186)
		(width 0.13462)
		(layer "F.Cu")
		(net "P5E_PEX2_STN2_TX_C_DN<33>")
	)
	(segment
		(start 328.022204 -350.365314)
		(end 328.342244 -350.685354)
		(width 0.13462)
		(layer "F.Cu")
		(net "P5E_PEX2_STN6_TX_C_DP<104>")
	)
	(segment
		(start 328.342244 -351.316798)
		(end 328.047604 -351.611438)
		(width 0.13462)
		(layer "F.Cu")
		(net "P5E_PEX2_STN6_TX_C_DP<104>")
	)
	(segment
		(start 328.342244 -350.685354)
		(end 328.342244 -351.316798)
		(width 0.13462)
		(layer "F.Cu")
		(net "P5E_PEX2_STN6_TX_C_DP<104>")
	)
	(segment
		(start 328.338434 -352.356166)
		(end 328.338434 -351.902268)
		(width 0.1651)
		(layer "In13.Cu")
		(net "P5E_PEX2_STN6_TX_C_DP<104>")
	)
	(segment
		(start 326.783954 -353.910646)
		(end 328.338434 -352.356166)
		(width 0.1651)
		(layer "In13.Cu")
		(net "P5E_PEX2_STN6_TX_C_DP<104>")
	)
	(segment
		(start 347.017086 -409.799028)
		(end 347.447362 -409.799028)
		(width 0.1651)
		(layer "In13.Cu")
		(net "P5E_PEX2_STN6_TX_C_DP<104>")
	)
	(segment
		(start 346.890086 -409.290012)
		(end 346.890086 -409.672028)
		(width 0.1651)
		(layer "In13.Cu")
		(net "P5E_PEX2_STN6_TX_C_DP<104>")
	)
	(segment
		(start 345.829382 -393.568682)
		(end 338.238846 -388.799832)
		(width 0.1651)
		(layer "In13.Cu")
		(net "P5E_PEX2_STN6_TX_C_DP<104>")
	)
	(segment
		(start 347.734128 -395.732)
		(end 347.580204 -395.322044)
		(width 0.1651)
		(layer "In13.Cu")
		(net "P5E_PEX2_STN6_TX_C_DP<104>")
	)
	(segment
		(start 347.734128 -409.512262)
		(end 347.734128 -395.732)
		(width 0.1651)
		(layer "In13.Cu")
		(net "P5E_PEX2_STN6_TX_C_DP<104>")
	)
	(segment
		(start 331.656182 -386.462524)
		(end 330.187808 -385.300982)
		(width 0.1651)
		(layer "In13.Cu")
		(net "P5E_PEX2_STN6_TX_C_DP<104>")
	)
	(segment
		(start 338.238846 -388.799832)
		(end 331.656182 -386.462524)
		(width 0.1651)
		(layer "In13.Cu")
		(net "P5E_PEX2_STN6_TX_C_DP<104>")
	)
	(segment
		(start 328.338434 -351.902268)
		(end 328.047604 -351.611438)
		(width 0.1651)
		(layer "In13.Cu")
		(net "P5E_PEX2_STN6_TX_C_DP<104>")
	)
	(segment
		(start 330.187808 -385.300982)
		(end 326.783954 -358.920288)
		(width 0.1651)
		(layer "In13.Cu")
		(net "P5E_PEX2_STN6_TX_C_DP<104>")
	)
	(segment
		(start 347.447362 -409.799028)
		(end 347.734128 -409.512262)
		(width 0.1651)
		(layer "In13.Cu")
		(net "P5E_PEX2_STN6_TX_C_DP<104>")
	)
	(segment
		(start 326.783954 -358.920288)
		(end 326.783954 -353.910646)
		(width 0.1651)
		(layer "In13.Cu")
		(net "P5E_PEX2_STN6_TX_C_DP<104>")
	)
	(segment
		(start 347.580204 -395.322044)
		(end 345.829382 -393.568682)
		(width 0.1651)
		(layer "In13.Cu")
		(net "P5E_PEX2_STN6_TX_C_DP<104>")
	)
	(segment
		(start 346.890086 -409.672028)
		(end 347.017086 -409.799028)
		(width 0.1651)
		(layer "In13.Cu")
		(net "P5E_PEX2_STN6_TX_C_DP<104>")
	)
	(segment
		(start 399.421858 -104.845104)
		(end 398.94256 -104.845104)
		(width 0.13462)
		(layer "F.Cu")
		(net "P5E_PEX3_STN1_RX_DP<19>")
	)
	(segment
		(start 400.54276 -104.71277)
		(end 400.25193 -105.0036)
		(width 0.13462)
		(layer "F.Cu")
		(net "P5E_PEX3_STN1_RX_DP<19>")
	)
	(segment
		(start 399.580354 -105.0036)
		(end 399.421858 -104.845104)
		(width 0.13462)
		(layer "F.Cu")
		(net "P5E_PEX3_STN1_RX_DP<19>")
	)
	(segment
		(start 400.25193 -105.0036)
		(end 399.580354 -105.0036)
		(width 0.13462)
		(layer "F.Cu")
		(net "P5E_PEX3_STN1_RX_DP<19>")
	)
	(segment
		(start 381.023876 -126.351538)
		(end 379.420628 -150.48357)
		(width 0.1651)
		(layer "In5.Cu")
		(net "P5E_PEX3_STN1_RX_DP<19>")
	)
	(segment
		(start 410.799534 -275.684488)
		(end 410.799534 -275.949918)
		(width 0.1143)
		(layer "In5.Cu")
		(net "P5E_PEX3_STN1_RX_DP<19>")
	)
	(segment
		(start 399.70329 -105.0036)
		(end 393.334494 -108.444538)
		(width 0.1651)
		(layer "In5.Cu")
		(net "P5E_PEX3_STN1_RX_DP<19>")
	)
	(segment
		(start 379.816106 -156.69006)
		(end 379.948694 -158.768034)
		(width 0.1651)
		(layer "In5.Cu")
		(net "P5E_PEX3_STN1_RX_DP<19>")
	)
	(segment
		(start 381.050038 -165.18255)
		(end 410.183838 -269.528544)
		(width 0.1651)
		(layer "In5.Cu")
		(net "P5E_PEX3_STN1_RX_DP<19>")
	)
	(segment
		(start 410.183838 -271.570958)
		(end 410.183838 -271.599406)
		(width 0.1143)
		(layer "In5.Cu")
		(net "P5E_PEX3_STN1_RX_DP<19>")
	)
	(segment
		(start 379.948694 -158.768034)
		(end 381.050038 -165.18255)
		(width 0.1651)
		(layer "In5.Cu")
		(net "P5E_PEX3_STN1_RX_DP<19>")
	)
	(segment
		(start 379.815852 -156.689806)
		(end 379.816106 -156.69006)
		(width 0.1651)
		(layer "In5.Cu")
		(net "P5E_PEX3_STN1_RX_DP<19>")
	)
	(segment
		(start 410.229558 -275.355304)
		(end 410.444442 -275.570188)
		(width 0.1143)
		(layer "In5.Cu")
		(net "P5E_PEX3_STN1_RX_DP<19>")
	)
	(segment
		(start 382.449324 -121.856246)
		(end 381.70358 -122.76328)
		(width 0.1651)
		(layer "In5.Cu")
		(net "P5E_PEX3_STN1_RX_DP<19>")
	)
	(segment
		(start 410.229558 -271.645126)
		(end 410.229558 -275.355304)
		(width 0.1143)
		(layer "In5.Cu")
		(net "P5E_PEX3_STN1_RX_DP<19>")
	)
	(segment
		(start 388.958074 -112.68202)
		(end 385.796536 -119.163592)
		(width 0.1651)
		(layer "In5.Cu")
		(net "P5E_PEX3_STN1_RX_DP<19>")
	)
	(segment
		(start 379.684788 -154.627072)
		(end 379.816106 -156.689806)
		(width 0.1651)
		(layer "In5.Cu")
		(net "P5E_PEX3_STN1_RX_DP<19>")
	)
	(segment
		(start 384.485134 -120.760236)
		(end 382.449324 -121.856246)
		(width 0.1651)
		(layer "In5.Cu")
		(net "P5E_PEX3_STN1_RX_DP<19>")
	)
	(segment
		(start 410.444442 -275.570188)
		(end 410.685234 -275.570188)
		(width 0.1143)
		(layer "In5.Cu")
		(net "P5E_PEX3_STN1_RX_DP<19>")
	)
	(segment
		(start 393.334494 -108.444538)
		(end 388.958074 -112.68202)
		(width 0.1651)
		(layer "In5.Cu")
		(net "P5E_PEX3_STN1_RX_DP<19>")
	)
	(segment
		(start 381.70358 -122.76328)
		(end 381.023876 -126.351538)
		(width 0.1651)
		(layer "In5.Cu")
		(net "P5E_PEX3_STN1_RX_DP<19>")
	)
	(segment
		(start 410.183838 -269.528544)
		(end 410.183838 -271.570958)
		(width 0.1651)
		(layer "In5.Cu")
		(net "P5E_PEX3_STN1_RX_DP<19>")
	)
	(segment
		(start 379.420628 -150.48357)
		(end 379.684534 -154.627072)
		(width 0.1651)
		(layer "In5.Cu")
		(net "P5E_PEX3_STN1_RX_DP<19>")
	)
	(segment
		(start 410.685234 -275.570188)
		(end 410.799534 -275.684488)
		(width 0.1143)
		(layer "In5.Cu")
		(net "P5E_PEX3_STN1_RX_DP<19>")
	)
	(segment
		(start 400.25193 -105.0036)
		(end 399.70329 -105.0036)
		(width 0.1651)
		(layer "In5.Cu")
		(net "P5E_PEX3_STN1_RX_DP<19>")
	)
	(segment
		(start 400.54276 -104.71277)
		(end 400.25193 -105.0036)
		(width 0.1651)
		(layer "In5.Cu")
		(net "P5E_PEX3_STN1_RX_DP<19>")
	)
	(segment
		(start 379.816106 -156.689806)
		(end 379.815852 -156.689806)
		(width 0.1651)
		(layer "In5.Cu")
		(net "P5E_PEX3_STN1_RX_DP<19>")
	)
	(segment
		(start 410.183838 -271.599406)
		(end 410.229558 -271.645126)
		(width 0.1143)
		(layer "In5.Cu")
		(net "P5E_PEX3_STN1_RX_DP<19>")
	)
	(segment
		(start 379.684534 -154.627072)
		(end 379.684788 -154.627072)
		(width 0.1651)
		(layer "In5.Cu")
		(net "P5E_PEX3_STN1_RX_DP<19>")
	)
	(segment
		(start 385.796536 -119.163592)
		(end 384.485134 -120.760236)
		(width 0.1651)
		(layer "In5.Cu")
		(net "P5E_PEX3_STN1_RX_DP<19>")
	)
	(segment
		(start 401.724876 -117.5512)
		(end 402.552916 -117.5512)
		(width 0.13208)
		(layer "F.Cu")
		(net "PRSNTB1_NIC6_N")
	)
	(segment
		(start 402.552916 -117.5512)
		(end 403.72919 -117.5512)
		(width 0.13208)
		(layer "F.Cu")
		(net "PRSNTB1_NIC6_N")
	)
	(segment
		(start 401.121118 -118.154958)
		(end 401.724876 -117.5512)
		(width 0.13208)
		(layer "F.Cu")
		(net "PRSNTB1_NIC6_N")
	)
	(segment
		(start 403.72919 -116.5352)
		(end 403.72919 -117.5512)
		(width 0.13208)
		(layer "F.Cu")
		(net "PRSNTB1_NIC6_N")
	)
	(segment
		(start 398.94256 -118.154958)
		(end 401.121118 -118.154958)
		(width 0.13208)
		(layer "F.Cu")
		(net "PRSNTB1_NIC6_N")
	)
	(via
		(at 402.552916 -117.5512)
		(size 0.762)
		(drill 0.381)
		(layers "F.Cu" "B.Cu")
		(net "PRSNTB1_NIC6_N")
	)
	(segment
		(start 70.975728 -364.592108)
		(end 70.56374 -364.316772)
		(width 0.1651)
		(layer "In9.Cu")
		(net "P5E_PEX0_STN6_RX_DP<101>")
	)
	(segment
		(start 71.989442 -365.269526)
		(end 71.577454 -364.99419)
		(width 0.1651)
		(layer "In9.Cu")
		(net "P5E_PEX0_STN6_RX_DP<101>")
	)
	(segment
		(start 77.202284 -369.526566)
		(end 76.680314 -368.266472)
		(width 0.1651)
		(layer "In9.Cu")
		(net "P5E_PEX0_STN6_RX_DP<101>")
	)
	(segment
		(start 76.828142 -374.899174)
		(end 77.202284 -374.525032)
		(width 0.1651)
		(layer "In9.Cu")
		(net "P5E_PEX0_STN6_RX_DP<101>")
	)
	(segment
		(start 52.429664 -319.819528)
		(end 52.429664 -316.506098)
		(width 0.1143)
		(layer "In9.Cu")
		(net "P5E_PEX0_STN6_RX_DP<101>")
	)
	(segment
		(start 71.545958 -364.835694)
		(end 71.134224 -364.560612)
		(width 0.1651)
		(layer "In9.Cu")
		(net "P5E_PEX0_STN6_RX_DP<101>")
	)
	(segment
		(start 72.147938 -365.23803)
		(end 71.989442 -365.269526)
		(width 0.1651)
		(layer "In9.Cu")
		(net "P5E_PEX0_STN6_RX_DP<101>")
	)
	(segment
		(start 77.202284 -374.525032)
		(end 77.202284 -369.526566)
		(width 0.1651)
		(layer "In9.Cu")
		(net "P5E_PEX0_STN6_RX_DP<101>")
	)
	(segment
		(start 71.134224 -364.560612)
		(end 70.975728 -364.592108)
		(width 0.1651)
		(layer "In9.Cu")
		(net "P5E_PEX0_STN6_RX_DP<101>")
	)
	(segment
		(start 52.383944 -319.893696)
		(end 52.383944 -319.865248)
		(width 0.1143)
		(layer "In9.Cu")
		(net "P5E_PEX0_STN6_RX_DP<101>")
	)
	(segment
		(start 60.445904 -354.025708)
		(end 58.85053 -346.00515)
		(width 0.1651)
		(layer "In9.Cu")
		(net "P5E_PEX0_STN6_RX_DP<101>")
	)
	(segment
		(start 52.999894 -316.140592)
		(end 52.999894 -315.849762)
		(width 0.1143)
		(layer "In9.Cu")
		(net "P5E_PEX0_STN6_RX_DP<101>")
	)
	(segment
		(start 70.53199 -364.158276)
		(end 66.805048 -361.667806)
		(width 0.1651)
		(layer "In9.Cu")
		(net "P5E_PEX0_STN6_RX_DP<101>")
	)
	(segment
		(start 72.559672 -365.513112)
		(end 72.147938 -365.23803)
		(width 0.1651)
		(layer "In9.Cu")
		(net "P5E_PEX0_STN6_RX_DP<101>")
	)
	(segment
		(start 76.309982 -374.772174)
		(end 76.436982 -374.899174)
		(width 0.1651)
		(layer "In9.Cu")
		(net "P5E_PEX0_STN6_RX_DP<101>")
	)
	(segment
		(start 71.577454 -364.99419)
		(end 71.545958 -364.835694)
		(width 0.1651)
		(layer "In9.Cu")
		(net "P5E_PEX0_STN6_RX_DP<101>")
	)
	(segment
		(start 63.721742 -360.390694)
		(end 62.630558 -359.29951)
		(width 0.1651)
		(layer "In9.Cu")
		(net "P5E_PEX0_STN6_RX_DP<101>")
	)
	(segment
		(start 52.70627 -316.229492)
		(end 52.910994 -316.229492)
		(width 0.1143)
		(layer "In9.Cu")
		(net "P5E_PEX0_STN6_RX_DP<101>")
	)
	(segment
		(start 76.436982 -374.899174)
		(end 76.828142 -374.899174)
		(width 0.1651)
		(layer "In9.Cu")
		(net "P5E_PEX0_STN6_RX_DP<101>")
	)
	(segment
		(start 62.630558 -359.29951)
		(end 60.445904 -354.025708)
		(width 0.1651)
		(layer "In9.Cu")
		(net "P5E_PEX0_STN6_RX_DP<101>")
	)
	(segment
		(start 73.161906 -365.915448)
		(end 73.003156 -365.946944)
		(width 0.1651)
		(layer "In9.Cu")
		(net "P5E_PEX0_STN6_RX_DP<101>")
	)
	(segment
		(start 76.309982 -374.390158)
		(end 76.309982 -374.772174)
		(width 0.1651)
		(layer "In9.Cu")
		(net "P5E_PEX0_STN6_RX_DP<101>")
	)
	(segment
		(start 58.85053 -346.00515)
		(end 52.383944 -324.687438)
		(width 0.1651)
		(layer "In9.Cu")
		(net "P5E_PEX0_STN6_RX_DP<101>")
	)
	(segment
		(start 72.591168 -365.671608)
		(end 72.559672 -365.513112)
		(width 0.1651)
		(layer "In9.Cu")
		(net "P5E_PEX0_STN6_RX_DP<101>")
	)
	(segment
		(start 66.805048 -361.667806)
		(end 63.721742 -360.390694)
		(width 0.1651)
		(layer "In9.Cu")
		(net "P5E_PEX0_STN6_RX_DP<101>")
	)
	(segment
		(start 73.003156 -365.946944)
		(end 72.591168 -365.671608)
		(width 0.1651)
		(layer "In9.Cu")
		(net "P5E_PEX0_STN6_RX_DP<101>")
	)
	(segment
		(start 52.383944 -324.687438)
		(end 52.383944 -319.893696)
		(width 0.1651)
		(layer "In9.Cu")
		(net "P5E_PEX0_STN6_RX_DP<101>")
	)
	(segment
		(start 76.680314 -368.266472)
		(end 73.161906 -365.915448)
		(width 0.1651)
		(layer "In9.Cu")
		(net "P5E_PEX0_STN6_RX_DP<101>")
	)
	(segment
		(start 52.910994 -316.229492)
		(end 52.999894 -316.140592)
		(width 0.1143)
		(layer "In9.Cu")
		(net "P5E_PEX0_STN6_RX_DP<101>")
	)
	(segment
		(start 52.383944 -319.865248)
		(end 52.429664 -319.819528)
		(width 0.1143)
		(layer "In9.Cu")
		(net "P5E_PEX0_STN6_RX_DP<101>")
	)
	(segment
		(start 52.429664 -316.506098)
		(end 52.70627 -316.229492)
		(width 0.1143)
		(layer "In9.Cu")
		(net "P5E_PEX0_STN6_RX_DP<101>")
	)
	(segment
		(start 70.56374 -364.316772)
		(end 70.53199 -364.158276)
		(width 0.1651)
		(layer "In9.Cu")
		(net "P5E_PEX0_STN6_RX_DP<101>")
	)
	(segment
		(start 247.967754 -34.390076)
		(end 247.464834 -34.390076)
		(width 0.13462)
		(layer "F.Cu")
		(net "P5E_PEX2_STN2_TX_C_DP<47>")
	)
	(segment
		(start 252.04801 -34.2265)
		(end 248.13133 -34.2265)
		(width 0.13462)
		(layer "F.Cu")
		(net "P5E_PEX2_STN2_TX_C_DP<47>")
	)
	(segment
		(start 252.367796 -34.546286)
		(end 252.04801 -34.2265)
		(width 0.13462)
		(layer "F.Cu")
		(net "P5E_PEX2_STN2_TX_C_DP<47>")
	)
	(segment
		(start 248.13133 -34.2265)
		(end 247.967754 -34.390076)
		(width 0.13462)
		(layer "F.Cu")
		(net "P5E_PEX2_STN2_TX_C_DP<47>")
	)
	(segment
		(start 333.68996 -402.790152)
		(end 333.68996 -402.408136)
		(width 0.1651)
		(layer "In5.Cu")
		(net "P5E_PEX2_STN6_RX_DN<110>")
	)
	(segment
		(start 334.815942 -401.82927)
		(end 334.815942 -395.613128)
		(width 0.1651)
		(layer "In5.Cu")
		(net "P5E_PEX2_STN6_RX_DN<110>")
	)
	(segment
		(start 276.832568 -323.932296)
		(end 276.315678 -322.683632)
		(width 0.1651)
		(layer "In5.Cu")
		(net "P5E_PEX2_STN6_RX_DN<110>")
	)
	(segment
		(start 334.5942 -395.08684)
		(end 332.551024 -393.03452)
		(width 0.1651)
		(layer "In5.Cu")
		(net "P5E_PEX2_STN6_RX_DN<110>")
	)
	(segment
		(start 276.269958 -319.96888)
		(end 276.269958 -318.434466)
		(width 0.1143)
		(layer "In5.Cu")
		(net "P5E_PEX2_STN6_RX_DN<110>")
	)
	(segment
		(start 279.035256 -325.886572)
		(end 277.561802 -324.845172)
		(width 0.1651)
		(layer "In5.Cu")
		(net "P5E_PEX2_STN6_RX_DN<110>")
	)
	(segment
		(start 334.815942 -395.613128)
		(end 334.5942 -395.08684)
		(width 0.1651)
		(layer "In5.Cu")
		(net "P5E_PEX2_STN6_RX_DN<110>")
	)
	(segment
		(start 325.735442 -388.931658)
		(end 303.444656 -339.032088)
		(width 0.1651)
		(layer "In5.Cu")
		(net "P5E_PEX2_STN6_RX_DN<110>")
	)
	(segment
		(start 333.68996 -402.408136)
		(end 333.81696 -402.281136)
		(width 0.1651)
		(layer "In5.Cu")
		(net "P5E_PEX2_STN6_RX_DN<110>")
	)
	(segment
		(start 331.24902 -392.496802)
		(end 331.24902 -392.496548)
		(width 0.1651)
		(layer "In5.Cu")
		(net "P5E_PEX2_STN6_RX_DN<110>")
	)
	(segment
		(start 276.315678 -322.683632)
		(end 276.315678 -320.043048)
		(width 0.1651)
		(layer "In5.Cu")
		(net "P5E_PEX2_STN6_RX_DN<110>")
	)
	(segment
		(start 277.561802 -324.845172)
		(end 276.832568 -323.932296)
		(width 0.1651)
		(layer "In5.Cu")
		(net "P5E_PEX2_STN6_RX_DN<110>")
	)
	(segment
		(start 333.81696 -402.281136)
		(end 334.364076 -402.281136)
		(width 0.1651)
		(layer "In5.Cu")
		(net "P5E_PEX2_STN6_RX_DN<110>")
	)
	(segment
		(start 334.364076 -402.281136)
		(end 334.815942 -401.82927)
		(width 0.1651)
		(layer "In5.Cu")
		(net "P5E_PEX2_STN6_RX_DN<110>")
	)
	(segment
		(start 332.551024 -393.03452)
		(end 331.24902 -392.496802)
		(width 0.1651)
		(layer "In5.Cu")
		(net "P5E_PEX2_STN6_RX_DN<110>")
	)
	(segment
		(start 276.269958 -318.434466)
		(end 276.384258 -318.320166)
		(width 0.1143)
		(layer "In5.Cu")
		(net "P5E_PEX2_STN6_RX_DN<110>")
	)
	(segment
		(start 276.384258 -318.320166)
		(end 276.535388 -318.320166)
		(width 0.1143)
		(layer "In5.Cu")
		(net "P5E_PEX2_STN6_RX_DN<110>")
	)
	(segment
		(start 327.955148 -391.136378)
		(end 325.735442 -388.931658)
		(width 0.1651)
		(layer "In5.Cu")
		(net "P5E_PEX2_STN6_RX_DN<110>")
	)
	(segment
		(start 276.315678 -320.0146)
		(end 276.269958 -319.96888)
		(width 0.1143)
		(layer "In5.Cu")
		(net "P5E_PEX2_STN6_RX_DN<110>")
	)
	(segment
		(start 331.24902 -392.496548)
		(end 327.955148 -391.136378)
		(width 0.1651)
		(layer "In5.Cu")
		(net "P5E_PEX2_STN6_RX_DN<110>")
	)
	(segment
		(start 276.535388 -318.320166)
		(end 276.649688 -318.434466)
		(width 0.1143)
		(layer "In5.Cu")
		(net "P5E_PEX2_STN6_RX_DN<110>")
	)
	(segment
		(start 276.649688 -318.434466)
		(end 276.649688 -318.699896)
		(width 0.1143)
		(layer "In5.Cu")
		(net "P5E_PEX2_STN6_RX_DN<110>")
	)
	(segment
		(start 276.315678 -320.043048)
		(end 276.315678 -320.0146)
		(width 0.1143)
		(layer "In5.Cu")
		(net "P5E_PEX2_STN6_RX_DN<110>")
	)
	(segment
		(start 303.444656 -339.032088)
		(end 279.035256 -325.886572)
		(width 0.1651)
		(layer "In5.Cu")
		(net "P5E_PEX2_STN6_RX_DN<110>")
	)
	(segment
		(start 385.205224 -119.198898)
		(end 385.518406 -119.51208)
		(width 0.13462)
		(layer "F.Cu")
		(net "P5E_PEX3_STN1_TX_C_DP<24>")
	)
	(segment
		(start 393.682728 -119.51208)
		(end 393.8397 -119.355108)
		(width 0.13462)
		(layer "F.Cu")
		(net "P5E_PEX3_STN1_TX_C_DP<24>")
	)
	(segment
		(start 385.518406 -119.51208)
		(end 393.682728 -119.51208)
		(width 0.13462)
		(layer "F.Cu")
		(net "P5E_PEX3_STN1_TX_C_DP<24>")
	)
	(segment
		(start 393.8397 -119.355108)
		(end 394.342366 -119.355108)
		(width 0.13462)
		(layer "F.Cu")
		(net "P5E_PEX3_STN1_TX_C_DP<24>")
	)
	(segment
		(start 191.72047 -86.247986)
		(end 191.72047 -85.751924)
		(width 0.13208)
		(layer "F.Cu")
		(net "RST_HP_NIC3_N")
	)
	(segment
		(start 191.72047 -85.751924)
		(end 192.046098 -85.426296)
		(width 0.13208)
		(layer "F.Cu")
		(net "RST_HP_NIC3_N")
	)
	(segment
		(start 192.046098 -85.426296)
		(end 194.999356 -85.426296)
		(width 0.13208)
		(layer "F.Cu")
		(net "RST_HP_NIC3_N")
	)
	(segment
		(start 191.83985 -87.599012)
		(end 191.72047 -87.479632)
		(width 0.13208)
		(layer "F.Cu")
		(net "RST_HP_NIC3_N")
	)
	(segment
		(start 191.72047 -87.479632)
		(end 191.72047 -86.247986)
		(width 0.13208)
		(layer "F.Cu")
		(net "RST_HP_NIC3_N")
	)
	(segment
		(start 193.134234 -87.599012)
		(end 191.83985 -87.599012)
		(width 0.13208)
		(layer "F.Cu")
		(net "RST_HP_NIC3_N")
	)
	(via
		(at 191.72047 -86.247986)
		(size 0.508)
		(drill 0.254)
		(layers "F.Cu" "B.Cu")
		(net "RST_HP_NIC3_N")
	)
	(segment
		(start 385.704842 -141.87297)
		(end 386.682742 -141.87297)
		(width 0.13208)
		(layer "F.Cu")
		(net "NIC6_BIF1_N")
	)
	(segment
		(start 388.12724 -142.080234)
		(end 388.681468 -142.080234)
		(width 0.13208)
		(layer "F.Cu")
		(net "NIC6_BIF1_N")
	)
	(segment
		(start 386.875274 -142.34795)
		(end 387.859524 -142.34795)
		(width 0.13208)
		(layer "F.Cu")
		(net "NIC6_BIF1_N")
	)
	(segment
		(start 387.859524 -142.34795)
		(end 388.12724 -142.080234)
		(width 0.13208)
		(layer "F.Cu")
		(net "NIC6_BIF1_N")
	)
	(segment
		(start 389.477758 -141.964918)
		(end 394.342366 -141.964918)
		(width 0.13208)
		(layer "F.Cu")
		(net "NIC6_BIF1_N")
	)
	(segment
		(start 386.682742 -142.155418)
		(end 386.875274 -142.34795)
		(width 0.13208)
		(layer "F.Cu")
		(net "NIC6_BIF1_N")
	)
	(segment
		(start 388.681468 -142.080234)
		(end 389.362442 -142.080234)
		(width 0.13208)
		(layer "F.Cu")
		(net "NIC6_BIF1_N")
	)
	(segment
		(start 386.682742 -141.87297)
		(end 386.682742 -142.155418)
		(width 0.13208)
		(layer "F.Cu")
		(net "NIC6_BIF1_N")
	)
	(segment
		(start 389.362442 -142.080234)
		(end 389.477758 -141.964918)
		(width 0.13208)
		(layer "F.Cu")
		(net "NIC6_BIF1_N")
	)
	(via
		(at 388.681468 -142.080234)
		(size 0.762)
		(drill 0.381)
		(layers "F.Cu" "B.Cu")
		(net "NIC6_BIF1_N")
	)
	(segment
		(start 299.964348 -32.589978)
		(end 299.46473 -32.589978)
		(width 0.13462)
		(layer "F.Cu")
		(net "P5E_PEX2_STN2_TX_C_DP<38>")
	)
	(segment
		(start 301.725584 -32.739584)
		(end 301.3964 -32.4104)
		(width 0.13462)
		(layer "F.Cu")
		(net "P5E_PEX2_STN2_TX_C_DP<38>")
	)
	(segment
		(start 300.143926 -32.4104)
		(end 299.964348 -32.589978)
		(width 0.13462)
		(layer "F.Cu")
		(net "P5E_PEX2_STN2_TX_C_DP<38>")
	)
	(segment
		(start 301.3964 -32.4104)
		(end 300.143926 -32.4104)
		(width 0.13462)
		(layer "F.Cu")
		(net "P5E_PEX2_STN2_TX_C_DP<38>")
	)
	(segment
		(start 344.161364 -357.46309)
		(end 344.456004 -357.75773)
		(width 0.13462)
		(layer "F.Cu")
		(net "P5E_PEX2_STN6_TX_C_DN<96>")
	)
	(segment
		(start 344.481404 -356.511606)
		(end 344.161364 -356.831646)
		(width 0.13462)
		(layer "F.Cu")
		(net "P5E_PEX2_STN6_TX_C_DN<96>")
	)
	(segment
		(start 344.161364 -356.831646)
		(end 344.161364 -357.46309)
		(width 0.13462)
		(layer "F.Cu")
		(net "P5E_PEX2_STN6_TX_C_DN<96>")
	)
	(segment
		(start 344.456004 -357.75773)
		(end 344.165174 -358.04856)
		(width 0.1651)
		(layer "In13.Cu")
		(net "P5E_PEX2_STN6_TX_C_DN<96>")
	)
	(segment
		(start 344.165174 -358.04856)
		(end 344.165174 -358.9401)
		(width 0.1651)
		(layer "In13.Cu")
		(net "P5E_PEX2_STN6_TX_C_DN<96>")
	)
	(segment
		(start 344.165174 -358.9401)
		(end 348.016068 -368.77752)
		(width 0.1651)
		(layer "In13.Cu")
		(net "P5E_PEX2_STN6_TX_C_DN<96>")
	)
	(segment
		(start 346.890086 -384.20802)
		(end 346.890086 -384.590036)
		(width 0.1651)
		(layer "In13.Cu")
		(net "P5E_PEX2_STN6_TX_C_DN<96>")
	)
	(segment
		(start 348.016068 -383.629154)
		(end 347.564202 -384.08102)
		(width 0.1651)
		(layer "In13.Cu")
		(net "P5E_PEX2_STN6_TX_C_DN<96>")
	)
	(segment
		(start 347.564202 -384.08102)
		(end 347.017086 -384.08102)
		(width 0.1651)
		(layer "In13.Cu")
		(net "P5E_PEX2_STN6_TX_C_DN<96>")
	)
	(segment
		(start 348.016068 -368.77752)
		(end 348.016068 -383.629154)
		(width 0.1651)
		(layer "In13.Cu")
		(net "P5E_PEX2_STN6_TX_C_DN<96>")
	)
	(segment
		(start 347.017086 -384.08102)
		(end 346.890086 -384.20802)
		(width 0.1651)
		(layer "In13.Cu")
		(net "P5E_PEX2_STN6_TX_C_DN<96>")
	)
	(segment
		(start 387.847332 -103.803196)
		(end 388.170928 -103.4796)
		(width 0.13462)
		(layer "F.Cu")
		(net "P5E_PEX3_STN1_TX_C_DN<18>")
	)
	(segment
		(start 388.170928 -103.4796)
		(end 393.670282 -103.4796)
		(width 0.13462)
		(layer "F.Cu")
		(net "P5E_PEX3_STN1_TX_C_DN<18>")
	)
	(segment
		(start 393.835636 -103.644954)
		(end 394.342366 -103.644954)
		(width 0.13462)
		(layer "F.Cu")
		(net "P5E_PEX3_STN1_TX_C_DN<18>")
	)
	(segment
		(start 393.670282 -103.4796)
		(end 393.835636 -103.644954)
		(width 0.13462)
		(layer "F.Cu")
		(net "P5E_PEX3_STN1_TX_C_DN<18>")
	)
	(segment
		(start 56.799988 -316.508892)
		(end 56.799988 -316.799722)
		(width 0.1143)
		(layer "In9.Cu")
		(net "P5E_PEX0_STN6_RX_DN<97>")
	)
	(segment
		(start 72.826372 -357.863394)
		(end 72.826372 -342.00211)
		(width 0.1651)
		(layer "In9.Cu")
		(net "P5E_PEX0_STN6_RX_DN<97>")
	)
	(segment
		(start 85.68182 -367.476024)
		(end 74.219054 -359.816654)
		(width 0.1651)
		(layer "In9.Cu")
		(net "P5E_PEX0_STN6_RX_DN<97>")
	)
	(segment
		(start 56.465978 -319.995296)
		(end 56.465978 -319.966848)
		(width 0.1143)
		(layer "In9.Cu")
		(net "P5E_PEX0_STN6_RX_DN<97>")
	)
	(segment
		(start 56.460898 -323.246242)
		(end 56.465978 -323.241162)
		(width 0.1651)
		(layer "In9.Cu")
		(net "P5E_PEX0_STN6_RX_DN<97>")
	)
	(segment
		(start 86.284054 -374.641872)
		(end 86.284054 -368.929666)
		(width 0.1651)
		(layer "In9.Cu")
		(net "P5E_PEX0_STN6_RX_DN<97>")
	)
	(segment
		(start 56.585358 -316.419992)
		(end 56.711088 -316.419992)
		(width 0.1143)
		(layer "In9.Cu")
		(net "P5E_PEX0_STN6_RX_DN<97>")
	)
	(segment
		(start 56.711088 -316.419992)
		(end 56.799988 -316.508892)
		(width 0.1143)
		(layer "In9.Cu")
		(net "P5E_PEX0_STN6_RX_DN<97>")
	)
	(segment
		(start 71.81215 -339.55355)
		(end 57.1373 -324.8787)
		(width 0.1651)
		(layer "In9.Cu")
		(net "P5E_PEX0_STN6_RX_DN<97>")
	)
	(segment
		(start 74.219054 -359.816654)
		(end 73.222612 -358.820212)
		(width 0.1651)
		(layer "In9.Cu")
		(net "P5E_PEX0_STN6_RX_DN<97>")
	)
	(segment
		(start 85.262212 -375.181114)
		(end 85.744812 -375.181114)
		(width 0.1651)
		(layer "In9.Cu")
		(net "P5E_PEX0_STN6_RX_DN<97>")
	)
	(segment
		(start 56.465978 -319.966848)
		(end 56.420258 -319.921128)
		(width 0.1143)
		(layer "In9.Cu")
		(net "P5E_PEX0_STN6_RX_DN<97>")
	)
	(segment
		(start 72.826372 -342.00211)
		(end 71.81215 -339.55355)
		(width 0.1651)
		(layer "In9.Cu")
		(net "P5E_PEX0_STN6_RX_DN<97>")
	)
	(segment
		(start 85.109812 -375.333514)
		(end 85.262212 -375.181114)
		(width 0.1651)
		(layer "In9.Cu")
		(net "P5E_PEX0_STN6_RX_DN<97>")
	)
	(segment
		(start 85.744812 -375.181114)
		(end 86.284054 -374.641872)
		(width 0.1651)
		(layer "In9.Cu")
		(net "P5E_PEX0_STN6_RX_DN<97>")
	)
	(segment
		(start 56.420258 -319.921128)
		(end 56.420258 -316.585092)
		(width 0.1143)
		(layer "In9.Cu")
		(net "P5E_PEX0_STN6_RX_DN<97>")
	)
	(segment
		(start 57.1373 -324.8787)
		(end 56.460898 -323.246242)
		(width 0.1651)
		(layer "In9.Cu")
		(net "P5E_PEX0_STN6_RX_DN<97>")
	)
	(segment
		(start 85.109812 -375.69013)
		(end 85.109812 -375.333514)
		(width 0.1651)
		(layer "In9.Cu")
		(net "P5E_PEX0_STN6_RX_DN<97>")
	)
	(segment
		(start 86.284054 -368.929666)
		(end 85.68182 -367.476024)
		(width 0.1651)
		(layer "In9.Cu")
		(net "P5E_PEX0_STN6_RX_DN<97>")
	)
	(segment
		(start 56.465978 -323.241162)
		(end 56.465978 -319.995296)
		(width 0.1651)
		(layer "In9.Cu")
		(net "P5E_PEX0_STN6_RX_DN<97>")
	)
	(segment
		(start 56.420258 -316.585092)
		(end 56.585358 -316.419992)
		(width 0.1143)
		(layer "In9.Cu")
		(net "P5E_PEX0_STN6_RX_DN<97>")
	)
	(segment
		(start 73.222612 -358.820212)
		(end 72.826372 -357.863394)
		(width 0.1651)
		(layer "In9.Cu")
		(net "P5E_PEX0_STN6_RX_DN<97>")
	)
	(segment
		(start 320.224404 -28.829)
		(end 319.557908 -28.829)
		(width 0.13462)
		(layer "F.Cu")
		(net "P5E_PEX2_STN2_RX_DP<32>")
	)
	(segment
		(start 320.385694 -28.99029)
		(end 320.224404 -28.829)
		(width 0.13462)
		(layer "F.Cu")
		(net "P5E_PEX2_STN2_RX_DP<32>")
	)
	(segment
		(start 320.864738 -28.990036)
		(end 320.864738 -28.99029)
		(width 0.13462)
		(layer "F.Cu")
		(net "P5E_PEX2_STN2_RX_DP<32>")
	)
	(segment
		(start 319.557908 -28.829)
		(end 319.264538 -29.12237)
		(width 0.13462)
		(layer "F.Cu")
		(net "P5E_PEX2_STN2_RX_DP<32>")
	)
	(segment
		(start 320.864738 -28.99029)
		(end 320.385694 -28.99029)
		(width 0.13462)
		(layer "F.Cu")
		(net "P5E_PEX2_STN2_RX_DP<32>")
	)
	(segment
		(start 290.283646 -271.421352)
		(end 290.329366 -271.467072)
		(width 0.1143)
		(layer "In7.Cu")
		(net "P5E_PEX2_STN2_RX_DP<32>")
	)
	(segment
		(start 323.078856 -49.388014)
		(end 322.895214 -61.14288)
		(width 0.1651)
		(layer "In7.Cu")
		(net "P5E_PEX2_STN2_RX_DP<32>")
	)
	(segment
		(start 319.264538 -29.12237)
		(end 319.422526 -28.964382)
		(width 0.1651)
		(layer "In7.Cu")
		(net "P5E_PEX2_STN2_RX_DP<32>")
	)
	(segment
		(start 290.329366 -275.354796)
		(end 290.544758 -275.570188)
		(width 0.1143)
		(layer "In7.Cu")
		(net "P5E_PEX2_STN2_RX_DP<32>")
	)
	(segment
		(start 310.184038 -154.799284)
		(end 290.696142 -266.698222)
		(width 0.1651)
		(layer "In7.Cu")
		(net "P5E_PEX2_STN2_RX_DP<32>")
	)
	(segment
		(start 320.794634 -29.69387)
		(end 320.956432 -29.69387)
		(width 0.1651)
		(layer "In7.Cu")
		(net "P5E_PEX2_STN2_RX_DP<32>")
	)
	(segment
		(start 290.78555 -275.570188)
		(end 290.89985 -275.684488)
		(width 0.1143)
		(layer "In7.Cu")
		(net "P5E_PEX2_STN2_RX_DP<32>")
	)
	(segment
		(start 290.696142 -266.698222)
		(end 290.463224 -269.382494)
		(width 0.1651)
		(layer "In7.Cu")
		(net "P5E_PEX2_STN2_RX_DP<32>")
	)
	(segment
		(start 290.283646 -270.159734)
		(end 290.283646 -271.392904)
		(width 0.1651)
		(layer "In7.Cu")
		(net "P5E_PEX2_STN2_RX_DP<32>")
	)
	(segment
		(start 290.329366 -271.467072)
		(end 290.329366 -275.354796)
		(width 0.1143)
		(layer "In7.Cu")
		(net "P5E_PEX2_STN2_RX_DP<32>")
	)
	(segment
		(start 322.513198 -31.250636)
		(end 325.172832 -37.563552)
		(width 0.1651)
		(layer "In7.Cu")
		(net "P5E_PEX2_STN2_RX_DP<32>")
	)
	(segment
		(start 311.886854 -116.627656)
		(end 311.570116 -144.038066)
		(width 0.1651)
		(layer "In7.Cu")
		(net "P5E_PEX2_STN2_RX_DP<32>")
	)
	(segment
		(start 325.269098 -38.063424)
		(end 325.060818 -39.920926)
		(width 0.1651)
		(layer "In7.Cu")
		(net "P5E_PEX2_STN2_RX_DP<32>")
	)
	(segment
		(start 320.094102 -28.83154)
		(end 320.444114 -29.181552)
		(width 0.1651)
		(layer "In7.Cu")
		(net "P5E_PEX2_STN2_RX_DP<32>")
	)
	(segment
		(start 321.306444 -30.043882)
		(end 321.306444 -30.20568)
		(width 0.1651)
		(layer "In7.Cu")
		(net "P5E_PEX2_STN2_RX_DP<32>")
	)
	(segment
		(start 321.306444 -30.20568)
		(end 321.656964 -30.5562)
		(width 0.1651)
		(layer "In7.Cu")
		(net "P5E_PEX2_STN2_RX_DP<32>")
	)
	(segment
		(start 290.89985 -275.684488)
		(end 290.89985 -275.949918)
		(width 0.1143)
		(layer "In7.Cu")
		(net "P5E_PEX2_STN2_RX_DP<32>")
	)
	(segment
		(start 290.463224 -269.382494)
		(end 290.283646 -270.159734)
		(width 0.1651)
		(layer "In7.Cu")
		(net "P5E_PEX2_STN2_RX_DP<32>")
	)
	(segment
		(start 325.172832 -37.563552)
		(end 325.269098 -38.063424)
		(width 0.1651)
		(layer "In7.Cu")
		(net "P5E_PEX2_STN2_RX_DP<32>")
	)
	(segment
		(start 322.895214 -61.14288)
		(end 311.886854 -116.627656)
		(width 0.1651)
		(layer "In7.Cu")
		(net "P5E_PEX2_STN2_RX_DP<32>")
	)
	(segment
		(start 320.444114 -29.181552)
		(end 320.444114 -29.34335)
		(width 0.1651)
		(layer "In7.Cu")
		(net "P5E_PEX2_STN2_RX_DP<32>")
	)
	(segment
		(start 320.444114 -29.34335)
		(end 320.794634 -29.69387)
		(width 0.1651)
		(layer "In7.Cu")
		(net "P5E_PEX2_STN2_RX_DP<32>")
	)
	(segment
		(start 325.060818 -39.920926)
		(end 323.078856 -49.388014)
		(width 0.1651)
		(layer "In7.Cu")
		(net "P5E_PEX2_STN2_RX_DP<32>")
	)
	(segment
		(start 311.570116 -144.038066)
		(end 310.184038 -154.799284)
		(width 0.1651)
		(layer "In7.Cu")
		(net "P5E_PEX2_STN2_RX_DP<32>")
	)
	(segment
		(start 320.956432 -29.69387)
		(end 321.306444 -30.043882)
		(width 0.1651)
		(layer "In7.Cu")
		(net "P5E_PEX2_STN2_RX_DP<32>")
	)
	(segment
		(start 319.422526 -28.964382)
		(end 319.743328 -28.83154)
		(width 0.1651)
		(layer "In7.Cu")
		(net "P5E_PEX2_STN2_RX_DP<32>")
	)
	(segment
		(start 321.656964 -30.5562)
		(end 321.818762 -30.5562)
		(width 0.1651)
		(layer "In7.Cu")
		(net "P5E_PEX2_STN2_RX_DP<32>")
	)
	(segment
		(start 319.743328 -28.83154)
		(end 320.094102 -28.83154)
		(width 0.1651)
		(layer "In7.Cu")
		(net "P5E_PEX2_STN2_RX_DP<32>")
	)
	(segment
		(start 290.544758 -275.570188)
		(end 290.78555 -275.570188)
		(width 0.1143)
		(layer "In7.Cu")
		(net "P5E_PEX2_STN2_RX_DP<32>")
	)
	(segment
		(start 290.283646 -271.392904)
		(end 290.283646 -271.421352)
		(width 0.1143)
		(layer "In7.Cu")
		(net "P5E_PEX2_STN2_RX_DP<32>")
	)
	(segment
		(start 321.818762 -30.5562)
		(end 322.513198 -31.250636)
		(width 0.1651)
		(layer "In7.Cu")
		(net "P5E_PEX2_STN2_RX_DP<32>")
	)
	(segment
		(start 325.233284 -345.170506)
		(end 324.938644 -345.465146)
		(width 0.13462)
		(layer "F.Cu")
		(net "P5E_PEX2_STN6_TX_C_DP<106>")
	)
	(segment
		(start 324.913244 -344.219022)
		(end 325.233284 -344.539062)
		(width 0.13462)
		(layer "F.Cu")
		(net "P5E_PEX2_STN6_TX_C_DP<106>")
	)
	(segment
		(start 325.233284 -344.539062)
		(end 325.233284 -345.170506)
		(width 0.13462)
		(layer "F.Cu")
		(net "P5E_PEX2_STN6_TX_C_DP<106>")
	)
	(segment
		(start 337.324954 -390.62406)
		(end 330.780898 -388.292848)
		(width 0.1651)
		(layer "In13.Cu")
		(net "P5E_PEX2_STN6_TX_C_DP<106>")
	)
	(segment
		(start 325.229474 -346.209874)
		(end 325.229474 -345.755976)
		(width 0.1651)
		(layer "In13.Cu")
		(net "P5E_PEX2_STN6_TX_C_DP<106>")
	)
	(segment
		(start 328.353928 -386.346192)
		(end 323.674994 -358.91851)
		(width 0.1651)
		(layer "In13.Cu")
		(net "P5E_PEX2_STN6_TX_C_DP<106>")
	)
	(segment
		(start 342.490044 -409.290012)
		(end 342.490044 -409.672028)
		(width 0.1651)
		(layer "In13.Cu")
		(net "P5E_PEX2_STN6_TX_C_DP<106>")
	)
	(segment
		(start 323.674994 -347.764354)
		(end 325.229474 -346.209874)
		(width 0.1651)
		(layer "In13.Cu")
		(net "P5E_PEX2_STN6_TX_C_DP<106>")
	)
	(segment
		(start 330.780898 -388.292848)
		(end 328.353928 -386.346192)
		(width 0.1651)
		(layer "In13.Cu")
		(net "P5E_PEX2_STN6_TX_C_DP<106>")
	)
	(segment
		(start 343.334086 -395.473428)
		(end 343.03716 -394.978636)
		(width 0.1651)
		(layer "In13.Cu")
		(net "P5E_PEX2_STN6_TX_C_DP<106>")
	)
	(segment
		(start 342.617044 -409.799028)
		(end 343.04732 -409.799028)
		(width 0.1651)
		(layer "In13.Cu")
		(net "P5E_PEX2_STN6_TX_C_DP<106>")
	)
	(segment
		(start 323.674994 -358.91851)
		(end 323.674994 -347.764354)
		(width 0.1651)
		(layer "In13.Cu")
		(net "P5E_PEX2_STN6_TX_C_DP<106>")
	)
	(segment
		(start 343.334086 -409.512262)
		(end 343.334086 -395.473428)
		(width 0.1651)
		(layer "In13.Cu")
		(net "P5E_PEX2_STN6_TX_C_DP<106>")
	)
	(segment
		(start 325.229474 -345.755976)
		(end 324.938644 -345.465146)
		(width 0.1651)
		(layer "In13.Cu")
		(net "P5E_PEX2_STN6_TX_C_DP<106>")
	)
	(segment
		(start 342.490044 -409.672028)
		(end 342.617044 -409.799028)
		(width 0.1651)
		(layer "In13.Cu")
		(net "P5E_PEX2_STN6_TX_C_DP<106>")
	)
	(segment
		(start 343.03716 -394.978636)
		(end 337.324954 -390.62406)
		(width 0.1651)
		(layer "In13.Cu")
		(net "P5E_PEX2_STN6_TX_C_DP<106>")
	)
	(segment
		(start 343.04732 -409.799028)
		(end 343.334086 -409.512262)
		(width 0.1651)
		(layer "In13.Cu")
		(net "P5E_PEX2_STN6_TX_C_DP<106>")
	)
	(segment
		(start 386.148326 -101.6762)
		(end 393.66571 -101.6762)
		(width 0.13462)
		(layer "F.Cu")
		(net "P5E_PEX3_STN1_TX_C_DP<17>")
	)
	(segment
		(start 393.66571 -101.6762)
		(end 393.83462 -101.84511)
		(width 0.13462)
		(layer "F.Cu")
		(net "P5E_PEX3_STN1_TX_C_DP<17>")
	)
	(segment
		(start 385.814824 -102.009702)
		(end 386.148326 -101.6762)
		(width 0.13462)
		(layer "F.Cu")
		(net "P5E_PEX3_STN1_TX_C_DP<17>")
	)
	(segment
		(start 393.83462 -101.84511)
		(end 394.342366 -101.84511)
		(width 0.13462)
		(layer "F.Cu")
		(net "P5E_PEX3_STN1_TX_C_DP<17>")
	)
	(segment
		(start 405.287988 -140.300202)
		(end 405.96439 -139.6238)
		(width 0.13208)
		(layer "F.Cu")
		(net "RST_SMB_NIC6_MUX_ISO_R_N")
	)
	(segment
		(start 404.11273 -140.300202)
		(end 405.287988 -140.300202)
		(width 0.13208)
		(layer "F.Cu")
		(net "RST_SMB_NIC6_MUX_ISO_R_N")
	)
	(segment
		(start 403.54504 -140.867892)
		(end 404.11273 -140.300202)
		(width 0.13208)
		(layer "F.Cu")
		(net "RST_SMB_NIC6_MUX_ISO_R_N")
	)
	(segment
		(start 398.94256 -141.36497)
		(end 400.935952 -141.36497)
		(width 0.13208)
		(layer "F.Cu")
		(net "RST_SMB_NIC6_MUX_ISO_R_N")
	)
	(segment
		(start 400.935952 -141.36497)
		(end 401.43303 -140.867892)
		(width 0.13208)
		(layer "F.Cu")
		(net "RST_SMB_NIC6_MUX_ISO_R_N")
	)
	(segment
		(start 401.43303 -140.867892)
		(end 402.575776 -140.867892)
		(width 0.13208)
		(layer "F.Cu")
		(net "RST_SMB_NIC6_MUX_ISO_R_N")
	)
	(segment
		(start 402.575776 -140.867892)
		(end 403.54504 -140.867892)
		(width 0.13208)
		(layer "F.Cu")
		(net "RST_SMB_NIC6_MUX_ISO_R_N")
	)
	(via
		(at 402.575776 -140.867892)
		(size 0.762)
		(drill 0.381)
		(layers "F.Cu" "B.Cu")
		(net "RST_SMB_NIC6_MUX_ISO_R_N")
	)
	(segment
		(start 59.978544 -355.110796)
		(end 59.177428 -351.912682)
		(width 0.1651)
		(layer "In5.Cu")
		(net "P5E_PEX0_STN6_RX_DP<108>")
	)
	(segment
		(start 78.509876 -401.872196)
		(end 78.636876 -401.999196)
		(width 0.1651)
		(layer "In5.Cu")
		(net "P5E_PEX0_STN6_RX_DP<108>")
	)
	(segment
		(start 46.34992 -318.015366)
		(end 46.34992 -317.749936)
		(width 0.1143)
		(layer "In5.Cu")
		(net "P5E_PEX0_STN6_RX_DP<108>")
	)
	(segment
		(start 76.199746 -392.84783)
		(end 76.04252 -392.863324)
		(width 0.1651)
		(layer "In5.Cu")
		(net "P5E_PEX0_STN6_RX_DP<108>")
	)
	(segment
		(start 74.734674 -391.64514)
		(end 74.046842 -391.080752)
		(width 0.1651)
		(layer "In5.Cu")
		(net "P5E_PEX0_STN6_RX_DP<108>")
	)
	(segment
		(start 69.41693 -389.162798)
		(end 67.665346 -387.411214)
		(width 0.1651)
		(layer "In5.Cu")
		(net "P5E_PEX0_STN6_RX_DP<108>")
	)
	(segment
		(start 76.04252 -392.863324)
		(end 75.66914 -392.556746)
		(width 0.1651)
		(layer "In5.Cu")
		(net "P5E_PEX0_STN6_RX_DP<108>")
	)
	(segment
		(start 54.865016 -336.935318)
		(end 46.407324 -324.277736)
		(width 0.1651)
		(layer "In5.Cu")
		(net "P5E_PEX0_STN6_RX_DP<108>")
	)
	(segment
		(start 56.620156 -341.1728)
		(end 54.865016 -336.935318)
		(width 0.1651)
		(layer "In5.Cu")
		(net "P5E_PEX0_STN6_RX_DP<108>")
	)
	(segment
		(start 45.73397 -319.966848)
		(end 45.77969 -319.921128)
		(width 0.1143)
		(layer "In5.Cu")
		(net "P5E_PEX0_STN6_RX_DP<108>")
	)
	(segment
		(start 46.23562 -318.129666)
		(end 46.34992 -318.015366)
		(width 0.1143)
		(layer "In5.Cu")
		(net "P5E_PEX0_STN6_RX_DP<108>")
	)
	(segment
		(start 45.77969 -318.355472)
		(end 46.005496 -318.129666)
		(width 0.1143)
		(layer "In5.Cu")
		(net "P5E_PEX0_STN6_RX_DP<108>")
	)
	(segment
		(start 45.77969 -319.921128)
		(end 45.77969 -318.355472)
		(width 0.1143)
		(layer "In5.Cu")
		(net "P5E_PEX0_STN6_RX_DP<108>")
	)
	(segment
		(start 66.797174 -385.314952)
		(end 65.139062 -368.488468)
		(width 0.1651)
		(layer "In5.Cu")
		(net "P5E_PEX0_STN6_RX_DP<108>")
	)
	(segment
		(start 75.280774 -392.09345)
		(end 75.123548 -392.108944)
		(width 0.1651)
		(layer "In5.Cu")
		(net "P5E_PEX0_STN6_RX_DP<108>")
	)
	(segment
		(start 79.115666 -401.999196)
		(end 79.402432 -401.71243)
		(width 0.1651)
		(layer "In5.Cu")
		(net "P5E_PEX0_STN6_RX_DP<108>")
	)
	(segment
		(start 46.407324 -324.277736)
		(end 45.73397 -322.652136)
		(width 0.1651)
		(layer "In5.Cu")
		(net "P5E_PEX0_STN6_RX_DP<108>")
	)
	(segment
		(start 75.123548 -392.108944)
		(end 74.750168 -391.80262)
		(width 0.1651)
		(layer "In5.Cu")
		(net "P5E_PEX0_STN6_RX_DP<108>")
	)
	(segment
		(start 56.620156 -341.173308)
		(end 56.620156 -341.1728)
		(width 0.1651)
		(layer "In5.Cu")
		(net "P5E_PEX0_STN6_RX_DP<108>")
	)
	(segment
		(start 65.139062 -368.488468)
		(end 59.978544 -355.110796)
		(width 0.1651)
		(layer "In5.Cu")
		(net "P5E_PEX0_STN6_RX_DP<108>")
	)
	(segment
		(start 59.177428 -351.912682)
		(end 58.37555 -345.411298)
		(width 0.1651)
		(layer "In5.Cu")
		(net "P5E_PEX0_STN6_RX_DP<108>")
	)
	(segment
		(start 67.665346 -387.411214)
		(end 66.797174 -385.314952)
		(width 0.1651)
		(layer "In5.Cu")
		(net "P5E_PEX0_STN6_RX_DP<108>")
	)
	(segment
		(start 75.653646 -392.39952)
		(end 75.280774 -392.09345)
		(width 0.1651)
		(layer "In5.Cu")
		(net "P5E_PEX0_STN6_RX_DP<108>")
	)
	(segment
		(start 74.046842 -391.080752)
		(end 69.41693 -389.162798)
		(width 0.1651)
		(layer "In5.Cu")
		(net "P5E_PEX0_STN6_RX_DP<108>")
	)
	(segment
		(start 45.73397 -319.995296)
		(end 45.73397 -319.966848)
		(width 0.1143)
		(layer "In5.Cu")
		(net "P5E_PEX0_STN6_RX_DP<108>")
	)
	(segment
		(start 58.37555 -345.411298)
		(end 56.620156 -341.173308)
		(width 0.1651)
		(layer "In5.Cu")
		(net "P5E_PEX0_STN6_RX_DP<108>")
	)
	(segment
		(start 78.636876 -401.999196)
		(end 79.115666 -401.999196)
		(width 0.1651)
		(layer "In5.Cu")
		(net "P5E_PEX0_STN6_RX_DP<108>")
	)
	(segment
		(start 78.807564 -394.988034)
		(end 76.199746 -392.84783)
		(width 0.1651)
		(layer "In5.Cu")
		(net "P5E_PEX0_STN6_RX_DP<108>")
	)
	(segment
		(start 45.73397 -322.652136)
		(end 45.73397 -319.995296)
		(width 0.1651)
		(layer "In5.Cu")
		(net "P5E_PEX0_STN6_RX_DP<108>")
	)
	(segment
		(start 74.750168 -391.80262)
		(end 74.734674 -391.64514)
		(width 0.1651)
		(layer "In5.Cu")
		(net "P5E_PEX0_STN6_RX_DP<108>")
	)
	(segment
		(start 75.66914 -392.556746)
		(end 75.653646 -392.39952)
		(width 0.1651)
		(layer "In5.Cu")
		(net "P5E_PEX0_STN6_RX_DP<108>")
	)
	(segment
		(start 46.005496 -318.129666)
		(end 46.23562 -318.129666)
		(width 0.1143)
		(layer "In5.Cu")
		(net "P5E_PEX0_STN6_RX_DP<108>")
	)
	(segment
		(start 78.509876 -401.49018)
		(end 78.509876 -401.872196)
		(width 0.1651)
		(layer "In5.Cu")
		(net "P5E_PEX0_STN6_RX_DP<108>")
	)
	(segment
		(start 79.402432 -396.948406)
		(end 78.807564 -394.988034)
		(width 0.1651)
		(layer "In5.Cu")
		(net "P5E_PEX0_STN6_RX_DP<108>")
	)
	(segment
		(start 79.402432 -401.71243)
		(end 79.402432 -396.948406)
		(width 0.1651)
		(layer "In5.Cu")
		(net "P5E_PEX0_STN6_RX_DP<108>")
	)
	(segment
		(start 268.224508 -30.353)
		(end 265.704574 -30.353)
		(width 0.13462)
		(layer "F.Cu")
		(net "P5E_PEX2_STN2_RX_DN<41>")
	)
	(segment
		(start 268.864842 -30.190186)
		(end 268.387322 -30.190186)
		(width 0.13462)
		(layer "F.Cu")
		(net "P5E_PEX2_STN2_RX_DN<41>")
	)
	(segment
		(start 268.387322 -30.190186)
		(end 268.224508 -30.353)
		(width 0.13462)
		(layer "F.Cu")
		(net "P5E_PEX2_STN2_RX_DN<41>")
	)
	(segment
		(start 265.704574 -30.353)
		(end 265.410442 -30.058868)
		(width 0.13462)
		(layer "F.Cu")
		(net "P5E_PEX2_STN2_RX_DN<41>")
	)
	(segment
		(start 267.98905 -30.349698)
		(end 265.701272 -30.349698)
		(width 0.1651)
		(layer "In7.Cu")
		(net "P5E_PEX2_STN2_RX_DN<41>")
	)
	(segment
		(start 282.235402 -273.479514)
		(end 282.120848 -273.479514)
		(width 0.1143)
		(layer "In7.Cu")
		(net "P5E_PEX2_STN2_RX_DN<41>")
	)
	(segment
		(start 282.349702 -273.099784)
		(end 282.349702 -273.365214)
		(width 0.1143)
		(layer "In7.Cu")
		(net "P5E_PEX2_STN2_RX_DN<41>")
	)
	(segment
		(start 281.764232 -260.611112)
		(end 281.969464 -249.971052)
		(width 0.1651)
		(layer "In7.Cu")
		(net "P5E_PEX2_STN2_RX_DN<41>")
	)
	(segment
		(start 281.969972 -271.41932)
		(end 282.015692 -271.3736)
		(width 0.1143)
		(layer "In7.Cu")
		(net "P5E_PEX2_STN2_RX_DN<41>")
	)
	(segment
		(start 282.349702 -273.365214)
		(end 282.235402 -273.479514)
		(width 0.1143)
		(layer "In7.Cu")
		(net "P5E_PEX2_STN2_RX_DN<41>")
	)
	(segment
		(start 273.865594 -104.603296)
		(end 270.665956 -64.739774)
		(width 0.1651)
		(layer "In7.Cu")
		(net "P5E_PEX2_STN2_RX_DN<41>")
	)
	(segment
		(start 281.969464 -249.971052)
		(end 274.013168 -147.970494)
		(width 0.1651)
		(layer "In7.Cu")
		(net "P5E_PEX2_STN2_RX_DN<41>")
	)
	(segment
		(start 282.015692 -271.3736)
		(end 282.015692 -271.345152)
		(width 0.1143)
		(layer "In7.Cu")
		(net "P5E_PEX2_STN2_RX_DN<41>")
	)
	(segment
		(start 281.969972 -273.328638)
		(end 281.969972 -271.41932)
		(width 0.1143)
		(layer "In7.Cu")
		(net "P5E_PEX2_STN2_RX_DN<41>")
	)
	(segment
		(start 274.319238 -119.573802)
		(end 273.865594 -104.603296)
		(width 0.1651)
		(layer "In7.Cu")
		(net "P5E_PEX2_STN2_RX_DN<41>")
	)
	(segment
		(start 270.665956 -64.739774)
		(end 270.306292 -55.754524)
		(width 0.1651)
		(layer "In7.Cu")
		(net "P5E_PEX2_STN2_RX_DN<41>")
	)
	(segment
		(start 269.58798 -35.00755)
		(end 269.612364 -31.973012)
		(width 0.1651)
		(layer "In7.Cu")
		(net "P5E_PEX2_STN2_RX_DN<41>")
	)
	(segment
		(start 270.40586 -49.3776)
		(end 269.089632 -39.636954)
		(width 0.1651)
		(layer "In7.Cu")
		(net "P5E_PEX2_STN2_RX_DN<41>")
	)
	(segment
		(start 265.701272 -30.349698)
		(end 265.410442 -30.058868)
		(width 0.1651)
		(layer "In7.Cu")
		(net "P5E_PEX2_STN2_RX_DN<41>")
	)
	(segment
		(start 282.015692 -267.669264)
		(end 281.616658 -263.616948)
		(width 0.1651)
		(layer "In7.Cu")
		(net "P5E_PEX2_STN2_RX_DN<41>")
	)
	(segment
		(start 269.612364 -31.973012)
		(end 267.98905 -30.349698)
		(width 0.1651)
		(layer "In7.Cu")
		(net "P5E_PEX2_STN2_RX_DN<41>")
	)
	(segment
		(start 269.063216 -37.96284)
		(end 269.58798 -35.00755)
		(width 0.1651)
		(layer "In7.Cu")
		(net "P5E_PEX2_STN2_RX_DN<41>")
	)
	(segment
		(start 269.089632 -39.636954)
		(end 269.063216 -37.96284)
		(width 0.1651)
		(layer "In7.Cu")
		(net "P5E_PEX2_STN2_RX_DN<41>")
	)
	(segment
		(start 282.015692 -271.345152)
		(end 282.015692 -267.669264)
		(width 0.1651)
		(layer "In7.Cu")
		(net "P5E_PEX2_STN2_RX_DN<41>")
	)
	(segment
		(start 274.013168 -147.970494)
		(end 274.319238 -119.573802)
		(width 0.1651)
		(layer "In7.Cu")
		(net "P5E_PEX2_STN2_RX_DN<41>")
	)
	(segment
		(start 282.120848 -273.479514)
		(end 281.969972 -273.328638)
		(width 0.1143)
		(layer "In7.Cu")
		(net "P5E_PEX2_STN2_RX_DN<41>")
	)
	(segment
		(start 270.306292 -55.754524)
		(end 270.40586 -49.3776)
		(width 0.1651)
		(layer "In7.Cu")
		(net "P5E_PEX2_STN2_RX_DN<41>")
	)
	(segment
		(start 281.616658 -263.616948)
		(end 281.764232 -260.611112)
		(width 0.1651)
		(layer "In7.Cu")
		(net "P5E_PEX2_STN2_RX_DN<41>")
	)
	(segment
		(start 331.451204 -344.539062)
		(end 331.451204 -345.170506)
		(width 0.13462)
		(layer "F.Cu")
		(net "P5E_PEX2_STN6_TX_C_DP<103>")
	)
	(segment
		(start 331.451204 -345.170506)
		(end 331.156564 -345.465146)
		(width 0.13462)
		(layer "F.Cu")
		(net "P5E_PEX2_STN6_TX_C_DP<103>")
	)
	(segment
		(start 331.131164 -344.219022)
		(end 331.451204 -344.539062)
		(width 0.13462)
		(layer "F.Cu")
		(net "P5E_PEX2_STN6_TX_C_DP<103>")
	)
	(segment
		(start 331.379068 -365.457994)
		(end 331.462634 -365.319564)
		(width 0.1651)
		(layer "In13.Cu")
		(net "P5E_PEX2_STN6_TX_C_DP<103>")
	)
	(segment
		(start 331.672438 -366.64138)
		(end 331.756004 -366.50295)
		(width 0.1651)
		(layer "In13.Cu")
		(net "P5E_PEX2_STN6_TX_C_DP<103>")
	)
	(segment
		(start 331.490066 -382.57226)
		(end 331.617066 -382.69926)
		(width 0.1651)
		(layer "In13.Cu")
		(net "P5E_PEX2_STN6_TX_C_DP<103>")
	)
	(segment
		(start 331.498194 -365.938816)
		(end 331.379068 -365.457994)
		(width 0.1651)
		(layer "In13.Cu")
		(net "P5E_PEX2_STN6_TX_C_DP<103>")
	)
	(segment
		(start 331.490066 -382.18999)
		(end 331.490066 -382.57226)
		(width 0.1651)
		(layer "In13.Cu")
		(net "P5E_PEX2_STN6_TX_C_DP<103>")
	)
	(segment
		(start 331.636878 -366.022382)
		(end 331.498194 -365.938816)
		(width 0.1651)
		(layer "In13.Cu")
		(net "P5E_PEX2_STN6_TX_C_DP<103>")
	)
	(segment
		(start 331.343508 -364.838996)
		(end 331.204824 -364.75543)
		(width 0.1651)
		(layer "In13.Cu")
		(net "P5E_PEX2_STN6_TX_C_DP<103>")
	)
	(segment
		(start 331.791564 -367.122456)
		(end 331.672438 -366.64138)
		(width 0.1651)
		(layer "In13.Cu")
		(net "P5E_PEX2_STN6_TX_C_DP<103>")
	)
	(segment
		(start 331.085698 -364.274608)
		(end 331.169264 -364.136178)
		(width 0.1651)
		(layer "In13.Cu")
		(net "P5E_PEX2_STN6_TX_C_DP<103>")
	)
	(segment
		(start 331.447394 -346.209874)
		(end 331.447394 -345.755976)
		(width 0.1651)
		(layer "In13.Cu")
		(net "P5E_PEX2_STN6_TX_C_DP<103>")
	)
	(segment
		(start 332.334108 -382.412494)
		(end 332.334108 -368.834924)
		(width 0.1651)
		(layer "In13.Cu")
		(net "P5E_PEX2_STN6_TX_C_DP<103>")
	)
	(segment
		(start 332.334108 -368.834924)
		(end 331.930248 -367.205768)
		(width 0.1651)
		(layer "In13.Cu")
		(net "P5E_PEX2_STN6_TX_C_DP<103>")
	)
	(segment
		(start 331.756004 -366.50295)
		(end 331.636878 -366.022382)
		(width 0.1651)
		(layer "In13.Cu")
		(net "P5E_PEX2_STN6_TX_C_DP<103>")
	)
	(segment
		(start 332.047342 -382.69926)
		(end 332.334108 -382.412494)
		(width 0.1651)
		(layer "In13.Cu")
		(net "P5E_PEX2_STN6_TX_C_DP<103>")
	)
	(segment
		(start 331.462634 -365.319564)
		(end 331.343508 -364.838996)
		(width 0.1651)
		(layer "In13.Cu")
		(net "P5E_PEX2_STN6_TX_C_DP<103>")
	)
	(segment
		(start 331.930248 -367.205768)
		(end 331.791564 -367.122456)
		(width 0.1651)
		(layer "In13.Cu")
		(net "P5E_PEX2_STN6_TX_C_DP<103>")
	)
	(segment
		(start 331.617066 -382.69926)
		(end 332.047342 -382.69926)
		(width 0.1651)
		(layer "In13.Cu")
		(net "P5E_PEX2_STN6_TX_C_DP<103>")
	)
	(segment
		(start 331.169264 -364.136178)
		(end 329.892914 -358.987344)
		(width 0.1651)
		(layer "In13.Cu")
		(net "P5E_PEX2_STN6_TX_C_DP<103>")
	)
	(segment
		(start 331.204824 -364.75543)
		(end 331.085698 -364.274608)
		(width 0.1651)
		(layer "In13.Cu")
		(net "P5E_PEX2_STN6_TX_C_DP<103>")
	)
	(segment
		(start 329.892914 -358.987344)
		(end 329.892914 -347.764354)
		(width 0.1651)
		(layer "In13.Cu")
		(net "P5E_PEX2_STN6_TX_C_DP<103>")
	)
	(segment
		(start 329.892914 -347.764354)
		(end 331.447394 -346.209874)
		(width 0.1651)
		(layer "In13.Cu")
		(net "P5E_PEX2_STN6_TX_C_DP<103>")
	)
	(segment
		(start 331.447394 -345.755976)
		(end 331.156564 -345.465146)
		(width 0.1651)
		(layer "In13.Cu")
		(net "P5E_PEX2_STN6_TX_C_DP<103>")
	)
	(segment
		(start 399.582894 -136.40562)
		(end 399.423382 -136.565132)
		(width 0.13462)
		(layer "F.Cu")
		(net "P5E_PEX3_STN1_RX_DN<31>")
	)
	(segment
		(start 400.25193 -136.40562)
		(end 399.582894 -136.40562)
		(width 0.13462)
		(layer "F.Cu")
		(net "P5E_PEX3_STN1_RX_DN<31>")
	)
	(segment
		(start 399.423382 -136.565132)
		(end 398.94256 -136.565132)
		(width 0.13462)
		(layer "F.Cu")
		(net "P5E_PEX3_STN1_RX_DN<31>")
	)
	(segment
		(start 400.54276 -136.69645)
		(end 400.25193 -136.40562)
		(width 0.13462)
		(layer "F.Cu")
		(net "P5E_PEX3_STN1_RX_DN<31>")
	)
	(segment
		(start 395.065758 -147.088606)
		(end 394.830808 -147.32)
		(width 0.1651)
		(layer "In5.Cu")
		(net "P5E_PEX3_STN1_RX_DN<31>")
	)
	(segment
		(start 396.98168 -145.740374)
		(end 396.62862 -146.087846)
		(width 0.1651)
		(layer "In5.Cu")
		(net "P5E_PEX3_STN1_RX_DN<31>")
	)
	(segment
		(start 399.003266 -142.425674)
		(end 398.815814 -142.88389)
		(width 0.1651)
		(layer "In5.Cu")
		(net "P5E_PEX3_STN1_RX_DN<31>")
	)
	(segment
		(start 399.58391 -138.27125)
		(end 399.46961 -138.38555)
		(width 0.1651)
		(layer "In5.Cu")
		(net "P5E_PEX3_STN1_RX_DN<31>")
	)
	(segment
		(start 421.820086 -275.27631)
		(end 421.923464 -275.379688)
		(width 0.1143)
		(layer "In5.Cu")
		(net "P5E_PEX3_STN1_RX_DN<31>")
	)
	(segment
		(start 398.205198 -144.37614)
		(end 397.852392 -144.723358)
		(width 0.1651)
		(layer "In5.Cu")
		(net "P5E_PEX3_STN1_RX_DN<31>")
	)
	(segment
		(start 397.852392 -144.723358)
		(end 397.850868 -144.885156)
		(width 0.1651)
		(layer "In5.Cu")
		(net "P5E_PEX3_STN1_RX_DN<31>")
	)
	(segment
		(start 394.241782 -151.713946)
		(end 394.118338 -151.818594)
		(width 0.1651)
		(layer "In5.Cu")
		(net "P5E_PEX3_STN1_RX_DN<31>")
	)
	(segment
		(start 400.54276 -136.69645)
		(end 400.25193 -136.40562)
		(width 0.1651)
		(layer "In5.Cu")
		(net "P5E_PEX3_STN1_RX_DN<31>")
	)
	(segment
		(start 398.541494 -143.554196)
		(end 398.205198 -144.37614)
		(width 0.1651)
		(layer "In5.Cu")
		(net "P5E_PEX3_STN1_RX_DN<31>")
	)
	(segment
		(start 396.467076 -146.08683)
		(end 395.722094 -146.819874)
		(width 0.1651)
		(layer "In5.Cu")
		(net "P5E_PEX3_STN1_RX_DN<31>")
	)
	(segment
		(start 421.865806 -271.570958)
		(end 421.865806 -271.599406)
		(width 0.1143)
		(layer "In5.Cu")
		(net "P5E_PEX3_STN1_RX_DN<31>")
	)
	(segment
		(start 422.199562 -275.265388)
		(end 422.199562 -274.999958)
		(width 0.1143)
		(layer "In5.Cu")
		(net "P5E_PEX3_STN1_RX_DN<31>")
	)
	(segment
		(start 399.34007 -141.904466)
		(end 399.152618 -142.36319)
		(width 0.1651)
		(layer "In5.Cu")
		(net "P5E_PEX3_STN1_RX_DN<31>")
	)
	(segment
		(start 399.46961 -141.285976)
		(end 399.277586 -141.755368)
		(width 0.1651)
		(layer "In5.Cu")
		(net "P5E_PEX3_STN1_RX_DN<31>")
	)
	(segment
		(start 399.991834 -136.40562)
		(end 399.551398 -136.846056)
		(width 0.1651)
		(layer "In5.Cu")
		(net "P5E_PEX3_STN1_RX_DN<31>")
	)
	(segment
		(start 399.46961 -137.043668)
		(end 399.46961 -137.66165)
		(width 0.1651)
		(layer "In5.Cu")
		(net "P5E_PEX3_STN1_RX_DN<31>")
	)
	(segment
		(start 394.019024 -153.033984)
		(end 393.493498 -159.47898)
		(width 0.1651)
		(layer "In5.Cu")
		(net "P5E_PEX3_STN1_RX_DN<31>")
	)
	(segment
		(start 395.722094 -146.819874)
		(end 395.065758 -147.088606)
		(width 0.1651)
		(layer "In5.Cu")
		(net "P5E_PEX3_STN1_RX_DN<31>")
	)
	(segment
		(start 399.46961 -139.46505)
		(end 399.58391 -139.57935)
		(width 0.1651)
		(layer "In5.Cu")
		(net "P5E_PEX3_STN1_RX_DN<31>")
	)
	(segment
		(start 394.142468 -152.929336)
		(end 394.019024 -153.033984)
		(width 0.1651)
		(layer "In5.Cu")
		(net "P5E_PEX3_STN1_RX_DN<31>")
	)
	(segment
		(start 399.58391 -137.77595)
		(end 399.58391 -138.27125)
		(width 0.1651)
		(layer "In5.Cu")
		(net "P5E_PEX3_STN1_RX_DN<31>")
	)
	(segment
		(start 399.46961 -140.18895)
		(end 399.46961 -141.285976)
		(width 0.1651)
		(layer "In5.Cu")
		(net "P5E_PEX3_STN1_RX_DN<31>")
	)
	(segment
		(start 394.182854 -152.435306)
		(end 394.142468 -152.929336)
		(width 0.1651)
		(layer "In5.Cu")
		(net "P5E_PEX3_STN1_RX_DN<31>")
	)
	(segment
		(start 394.17752 -151.096726)
		(end 394.282168 -151.219916)
		(width 0.1651)
		(layer "In5.Cu")
		(net "P5E_PEX3_STN1_RX_DN<31>")
	)
	(segment
		(start 393.493498 -159.47898)
		(end 393.532614 -160.37052)
		(width 0.1651)
		(layer "In5.Cu")
		(net "P5E_PEX3_STN1_RX_DN<31>")
	)
	(segment
		(start 399.58391 -139.57935)
		(end 399.58391 -140.07465)
		(width 0.1651)
		(layer "In5.Cu")
		(net "P5E_PEX3_STN1_RX_DN<31>")
	)
	(segment
		(start 398.878298 -143.032988)
		(end 398.690846 -143.491712)
		(width 0.1651)
		(layer "In5.Cu")
		(net "P5E_PEX3_STN1_RX_DN<31>")
	)
	(segment
		(start 399.551398 -136.846056)
		(end 399.46961 -137.043668)
		(width 0.1651)
		(layer "In5.Cu")
		(net "P5E_PEX3_STN1_RX_DN<31>")
	)
	(segment
		(start 394.830808 -147.32)
		(end 394.407898 -148.271484)
		(width 0.1651)
		(layer "In5.Cu")
		(net "P5E_PEX3_STN1_RX_DN<31>")
	)
	(segment
		(start 399.46961 -137.66165)
		(end 399.58391 -137.77595)
		(width 0.1651)
		(layer "In5.Cu")
		(net "P5E_PEX3_STN1_RX_DN<31>")
	)
	(segment
		(start 398.815814 -142.88389)
		(end 398.878298 -143.032988)
		(width 0.1651)
		(layer "In5.Cu")
		(net "P5E_PEX3_STN1_RX_DN<31>")
	)
	(segment
		(start 421.923464 -275.379688)
		(end 422.085262 -275.379688)
		(width 0.1143)
		(layer "In5.Cu")
		(net "P5E_PEX3_STN1_RX_DN<31>")
	)
	(segment
		(start 400.25193 -136.40562)
		(end 399.991834 -136.40562)
		(width 0.1651)
		(layer "In5.Cu")
		(net "P5E_PEX3_STN1_RX_DN<31>")
	)
	(segment
		(start 399.58391 -140.07465)
		(end 399.46961 -140.18895)
		(width 0.1651)
		(layer "In5.Cu")
		(net "P5E_PEX3_STN1_RX_DN<31>")
	)
	(segment
		(start 399.152618 -142.36319)
		(end 399.003266 -142.425674)
		(width 0.1651)
		(layer "In5.Cu")
		(net "P5E_PEX3_STN1_RX_DN<31>")
	)
	(segment
		(start 397.33601 -145.231358)
		(end 396.983204 -145.578576)
		(width 0.1651)
		(layer "In5.Cu")
		(net "P5E_PEX3_STN1_RX_DN<31>")
	)
	(segment
		(start 399.46961 -138.38555)
		(end 399.46961 -139.46505)
		(width 0.1651)
		(layer "In5.Cu")
		(net "P5E_PEX3_STN1_RX_DN<31>")
	)
	(segment
		(start 422.085262 -275.379688)
		(end 422.199562 -275.265388)
		(width 0.1143)
		(layer "In5.Cu")
		(net "P5E_PEX3_STN1_RX_DN<31>")
	)
	(segment
		(start 396.62862 -146.087846)
		(end 396.467076 -146.08683)
		(width 0.1651)
		(layer "In5.Cu")
		(net "P5E_PEX3_STN1_RX_DN<31>")
	)
	(segment
		(start 393.532614 -160.37052)
		(end 421.797988 -266.542774)
		(width 0.1651)
		(layer "In5.Cu")
		(net "P5E_PEX3_STN1_RX_DN<31>")
	)
	(segment
		(start 397.850868 -144.885156)
		(end 397.497808 -145.232628)
		(width 0.1651)
		(layer "In5.Cu")
		(net "P5E_PEX3_STN1_RX_DN<31>")
	)
	(segment
		(start 399.277586 -141.755368)
		(end 399.34007 -141.904466)
		(width 0.1651)
		(layer "In5.Cu")
		(net "P5E_PEX3_STN1_RX_DN<31>")
	)
	(segment
		(start 421.797988 -266.542774)
		(end 421.865806 -267.061188)
		(width 0.1651)
		(layer "In5.Cu")
		(net "P5E_PEX3_STN1_RX_DN<31>")
	)
	(segment
		(start 421.865806 -271.599406)
		(end 421.820086 -271.645126)
		(width 0.1143)
		(layer "In5.Cu")
		(net "P5E_PEX3_STN1_RX_DN<31>")
	)
	(segment
		(start 421.820086 -271.645126)
		(end 421.820086 -275.27631)
		(width 0.1143)
		(layer "In5.Cu")
		(net "P5E_PEX3_STN1_RX_DN<31>")
	)
	(segment
		(start 397.497808 -145.232628)
		(end 397.33601 -145.231358)
		(width 0.1651)
		(layer "In5.Cu")
		(net "P5E_PEX3_STN1_RX_DN<31>")
	)
	(segment
		(start 394.407898 -148.271484)
		(end 394.17752 -151.096726)
		(width 0.1651)
		(layer "In5.Cu")
		(net "P5E_PEX3_STN1_RX_DN<31>")
	)
	(segment
		(start 421.865806 -267.061188)
		(end 421.865806 -271.570958)
		(width 0.1651)
		(layer "In5.Cu")
		(net "P5E_PEX3_STN1_RX_DN<31>")
	)
	(segment
		(start 394.118338 -151.818594)
		(end 394.078206 -152.312116)
		(width 0.1651)
		(layer "In5.Cu")
		(net "P5E_PEX3_STN1_RX_DN<31>")
	)
	(segment
		(start 396.983204 -145.578576)
		(end 396.98168 -145.740374)
		(width 0.1651)
		(layer "In5.Cu")
		(net "P5E_PEX3_STN1_RX_DN<31>")
	)
	(segment
		(start 398.690846 -143.491712)
		(end 398.541494 -143.554196)
		(width 0.1651)
		(layer "In5.Cu")
		(net "P5E_PEX3_STN1_RX_DN<31>")
	)
	(segment
		(start 394.078206 -152.312116)
		(end 394.182854 -152.435306)
		(width 0.1651)
		(layer "In5.Cu")
		(net "P5E_PEX3_STN1_RX_DN<31>")
	)
	(segment
		(start 394.282168 -151.219916)
		(end 394.241782 -151.713946)
		(width 0.1651)
		(layer "In5.Cu")
		(net "P5E_PEX3_STN1_RX_DN<31>")
	)
	(segment
		(start 399.756884 -154.759914)
		(end 399.955258 -154.958288)
		(width 0.13208)
		(layer "F.Cu")
		(net "NCSI_NIC6_TX_EN")
	)
	(segment
		(start 399.955258 -154.958288)
		(end 401.426172 -154.958288)
		(width 0.13208)
		(layer "F.Cu")
		(net "NCSI_NIC6_TX_EN")
	)
	(segment
		(start 398.94256 -154.759914)
		(end 399.756884 -154.759914)
		(width 0.13208)
		(layer "F.Cu")
		(net "NCSI_NIC6_TX_EN")
	)
	(via
		(at 401.426172 -154.958288)
		(size 0.508)
		(drill 0.254)
		(layers "F.Cu" "B.Cu")
		(net "NCSI_NIC6_TX_EN")
	)
	(segment
		(start 398.25549 -154.0256)
		(end 398.82064 -154.0256)
		(width 0.13208)
		(layer "B.Cu")
		(net "NCSI_NIC6_TX_EN")
	)
	(segment
		(start 399.753328 -154.958288)
		(end 401.426172 -154.958288)
		(width 0.13208)
		(layer "B.Cu")
		(net "NCSI_NIC6_TX_EN")
	)
	(segment
		(start 398.82064 -154.0256)
		(end 399.753328 -154.958288)
		(width 0.13208)
		(layer "B.Cu")
		(net "NCSI_NIC6_TX_EN")
	)
	(segment
		(start 62.235842 -345.465146)
		(end 61.941202 -345.170506)
		(width 0.13462)
		(layer "F.Cu")
		(net "P5E_PEX0_STN6_TX_C_DN<111>")
	)
	(segment
		(start 61.941202 -344.539062)
		(end 62.261242 -344.219022)
		(width 0.13462)
		(layer "F.Cu")
		(net "P5E_PEX0_STN6_TX_C_DN<111>")
	)
	(segment
		(start 61.941202 -345.170506)
		(end 61.941202 -344.539062)
		(width 0.13462)
		(layer "F.Cu")
		(net "P5E_PEX0_STN6_TX_C_DN<111>")
	)
	(segment
		(start 61.945012 -346.428568)
		(end 61.945012 -345.755976)
		(width 0.1651)
		(layer "In13.Cu")
		(net "P5E_PEX0_STN6_TX_C_DN<111>")
	)
	(segment
		(start 72.721724 -394.561314)
		(end 67.656456 -391.176256)
		(width 0.1651)
		(layer "In13.Cu")
		(net "P5E_PEX0_STN6_TX_C_DN<111>")
	)
	(segment
		(start 61.945012 -345.755976)
		(end 62.235842 -345.465146)
		(width 0.1651)
		(layer "In13.Cu")
		(net "P5E_PEX0_STN6_TX_C_DN<111>")
	)
	(segment
		(start 72.602852 -408.981148)
		(end 73.084182 -408.499818)
		(width 0.1651)
		(layer "In13.Cu")
		(net "P5E_PEX0_STN6_TX_C_DN<111>")
	)
	(segment
		(start 73.084182 -395.238986)
		(end 72.721978 -394.561314)
		(width 0.1651)
		(layer "In13.Cu")
		(net "P5E_PEX0_STN6_TX_C_DN<111>")
	)
	(segment
		(start 72.03694 -408.981148)
		(end 72.602852 -408.981148)
		(width 0.1651)
		(layer "In13.Cu")
		(net "P5E_PEX0_STN6_TX_C_DN<111>")
	)
	(segment
		(start 72.721978 -394.561314)
		(end 72.721724 -394.561314)
		(width 0.1651)
		(layer "In13.Cu")
		(net "P5E_PEX0_STN6_TX_C_DN<111>")
	)
	(segment
		(start 61.682884 -361.617514)
		(end 60.390532 -352.533458)
		(width 0.1651)
		(layer "In13.Cu")
		(net "P5E_PEX0_STN6_TX_C_DN<111>")
	)
	(segment
		(start 71.90994 -409.490164)
		(end 71.90994 -409.108148)
		(width 0.1651)
		(layer "In13.Cu")
		(net "P5E_PEX0_STN6_TX_C_DN<111>")
	)
	(segment
		(start 60.390532 -352.533458)
		(end 60.390532 -347.983048)
		(width 0.1651)
		(layer "In13.Cu")
		(net "P5E_PEX0_STN6_TX_C_DN<111>")
	)
	(segment
		(start 71.90994 -409.108148)
		(end 72.03694 -408.981148)
		(width 0.1651)
		(layer "In13.Cu")
		(net "P5E_PEX0_STN6_TX_C_DN<111>")
	)
	(segment
		(start 63.652654 -384.410712)
		(end 61.682884 -361.617514)
		(width 0.1651)
		(layer "In13.Cu")
		(net "P5E_PEX0_STN6_TX_C_DN<111>")
	)
	(segment
		(start 67.656456 -391.176256)
		(end 65.605406 -389.125206)
		(width 0.1651)
		(layer "In13.Cu")
		(net "P5E_PEX0_STN6_TX_C_DN<111>")
	)
	(segment
		(start 65.605406 -389.125206)
		(end 63.652654 -384.410712)
		(width 0.1651)
		(layer "In13.Cu")
		(net "P5E_PEX0_STN6_TX_C_DN<111>")
	)
	(segment
		(start 73.084182 -408.499818)
		(end 73.084182 -395.238986)
		(width 0.1651)
		(layer "In13.Cu")
		(net "P5E_PEX0_STN6_TX_C_DN<111>")
	)
	(segment
		(start 60.390532 -347.983048)
		(end 61.945012 -346.428568)
		(width 0.1651)
		(layer "In13.Cu")
		(net "P5E_PEX0_STN6_TX_C_DN<111>")
	)
	(segment
		(start 275.396452 -32.4104)
		(end 274.143978 -32.4104)
		(width 0.13462)
		(layer "F.Cu")
		(net "P5E_PEX2_STN2_TX_C_DP<42>")
	)
	(segment
		(start 275.725636 -32.739584)
		(end 275.396452 -32.4104)
		(width 0.13462)
		(layer "F.Cu")
		(net "P5E_PEX2_STN2_TX_C_DP<42>")
	)
	(segment
		(start 273.9644 -32.589978)
		(end 273.464782 -32.589978)
		(width 0.13462)
		(layer "F.Cu")
		(net "P5E_PEX2_STN2_TX_C_DP<42>")
	)
	(segment
		(start 274.143978 -32.4104)
		(end 273.9644 -32.589978)
		(width 0.13462)
		(layer "F.Cu")
		(net "P5E_PEX2_STN2_TX_C_DP<42>")
	)
	(segment
		(start 334.834484 -350.685354)
		(end 334.834484 -351.316798)
		(width 0.13462)
		(layer "F.Cu")
		(net "P5E_PEX2_STN6_TX_C_DN<101>")
	)
	(segment
		(start 334.834484 -351.316798)
		(end 335.129124 -351.611438)
		(width 0.13462)
		(layer "F.Cu")
		(net "P5E_PEX2_STN6_TX_C_DN<101>")
	)
	(segment
		(start 335.154524 -350.365314)
		(end 334.834484 -350.685354)
		(width 0.13462)
		(layer "F.Cu")
		(net "P5E_PEX2_STN6_TX_C_DN<101>")
	)
	(segment
		(start 337.01609 -368.8715)
		(end 337.01609 -382.529334)
		(width 0.1651)
		(layer "In13.Cu")
		(net "P5E_PEX2_STN6_TX_C_DN<101>")
	)
	(segment
		(start 336.017108 -382.9812)
		(end 335.890108 -383.1082)
		(width 0.1651)
		(layer "In13.Cu")
		(net "P5E_PEX2_STN6_TX_C_DN<101>")
	)
	(segment
		(start 336.564224 -382.9812)
		(end 336.017108 -382.9812)
		(width 0.1651)
		(layer "In13.Cu")
		(net "P5E_PEX2_STN6_TX_C_DN<101>")
	)
	(segment
		(start 333.283814 -354.027486)
		(end 333.283814 -358.902)
		(width 0.1651)
		(layer "In13.Cu")
		(net "P5E_PEX2_STN6_TX_C_DN<101>")
	)
	(segment
		(start 334.838294 -352.473006)
		(end 333.283814 -354.027486)
		(width 0.1651)
		(layer "In13.Cu")
		(net "P5E_PEX2_STN6_TX_C_DN<101>")
	)
	(segment
		(start 335.890108 -383.1082)
		(end 335.890108 -383.490216)
		(width 0.1651)
		(layer "In13.Cu")
		(net "P5E_PEX2_STN6_TX_C_DN<101>")
	)
	(segment
		(start 337.01609 -382.529334)
		(end 336.564224 -382.9812)
		(width 0.1651)
		(layer "In13.Cu")
		(net "P5E_PEX2_STN6_TX_C_DN<101>")
	)
	(segment
		(start 335.129124 -351.611438)
		(end 334.838294 -351.902268)
		(width 0.1651)
		(layer "In13.Cu")
		(net "P5E_PEX2_STN6_TX_C_DN<101>")
	)
	(segment
		(start 334.838294 -351.902268)
		(end 334.838294 -352.473006)
		(width 0.1651)
		(layer "In13.Cu")
		(net "P5E_PEX2_STN6_TX_C_DN<101>")
	)
	(segment
		(start 333.283814 -358.902)
		(end 337.01609 -368.8715)
		(width 0.1651)
		(layer "In13.Cu")
		(net "P5E_PEX2_STN6_TX_C_DN<101>")
	)
	(segment
		(start 387.847332 -100.203254)
		(end 388.177786 -99.8728)
		(width 0.13462)
		(layer "F.Cu")
		(net "P5E_PEX3_STN1_TX_C_DN<16>")
	)
	(segment
		(start 388.177786 -99.8728)
		(end 393.663424 -99.8728)
		(width 0.13462)
		(layer "F.Cu")
		(net "P5E_PEX3_STN1_TX_C_DN<16>")
	)
	(segment
		(start 393.835636 -100.045012)
		(end 394.342366 -100.045012)
		(width 0.13462)
		(layer "F.Cu")
		(net "P5E_PEX3_STN1_TX_C_DN<16>")
	)
	(segment
		(start 393.663424 -99.8728)
		(end 393.835636 -100.045012)
		(width 0.13462)
		(layer "F.Cu")
		(net "P5E_PEX3_STN1_TX_C_DN<16>")
	)
	(segment
		(start 388.691882 -160.245044)
		(end 390.438894 -160.245044)
		(width 0.13208)
		(layer "F.Cu")
		(net "NIC6_MAIN_PWR_EN_R")
	)
	(segment
		(start 387.857238 -159.4104)
		(end 388.691882 -160.245044)
		(width 0.13208)
		(layer "F.Cu")
		(net "NIC6_MAIN_PWR_EN_R")
	)
	(segment
		(start 392.92403 -157.759908)
		(end 394.342366 -157.759908)
		(width 0.13208)
		(layer "F.Cu")
		(net "NIC6_MAIN_PWR_EN_R")
	)
	(segment
		(start 390.438894 -160.245044)
		(end 392.92403 -157.759908)
		(width 0.13208)
		(layer "F.Cu")
		(net "NIC6_MAIN_PWR_EN_R")
	)
	(segment
		(start 387.30809 -159.4104)
		(end 387.857238 -159.4104)
		(width 0.13208)
		(layer "F.Cu")
		(net "NIC6_MAIN_PWR_EN_R")
	)
	(via
		(at 388.691882 -160.245044)
		(size 0.762)
		(drill 0.381)
		(layers "F.Cu" "B.Cu")
		(net "NIC6_MAIN_PWR_EN_R")
	)
	(segment
		(start 54.520084 -319.819528)
		(end 54.565804 -319.865248)
		(width 0.1143)
		(layer "In9.Cu")
		(net "P5E_PEX0_STN6_RX_DN<99>")
	)
	(segment
		(start 81.557876 -368.47653)
		(end 81.884266 -369.264692)
		(width 0.1651)
		(layer "In9.Cu")
		(net "P5E_PEX0_STN6_RX_DN<99>")
	)
	(segment
		(start 66.608452 -341.142066)
		(end 66.608452 -357.941626)
		(width 0.1651)
		(layer "In9.Cu")
		(net "P5E_PEX0_STN6_RX_DN<99>")
	)
	(segment
		(start 54.810914 -316.419992)
		(end 54.685184 -316.419992)
		(width 0.1143)
		(layer "In9.Cu")
		(net "P5E_PEX0_STN6_RX_DN<99>")
	)
	(segment
		(start 66.95313 -358.77373)
		(end 67.35953 -359.18013)
		(width 0.1651)
		(layer "In9.Cu")
		(net "P5E_PEX0_STN6_RX_DN<99>")
	)
	(segment
		(start 54.565804 -319.893696)
		(end 54.565804 -323.9643)
		(width 0.1651)
		(layer "In9.Cu")
		(net "P5E_PEX0_STN6_RX_DN<99>")
	)
	(segment
		(start 66.608452 -357.941626)
		(end 66.95313 -358.77373)
		(width 0.1651)
		(layer "In9.Cu")
		(net "P5E_PEX0_STN6_RX_DN<99>")
	)
	(segment
		(start 54.565804 -323.9643)
		(end 55.382668 -325.936102)
		(width 0.1651)
		(layer "In9.Cu")
		(net "P5E_PEX0_STN6_RX_DN<99>")
	)
	(segment
		(start 80.846168 -367.764822)
		(end 81.557876 -368.47653)
		(width 0.1651)
		(layer "In9.Cu")
		(net "P5E_PEX0_STN6_RX_DN<99>")
	)
	(segment
		(start 54.565804 -319.865248)
		(end 54.565804 -319.893696)
		(width 0.1143)
		(layer "In9.Cu")
		(net "P5E_PEX0_STN6_RX_DN<99>")
	)
	(segment
		(start 81.884266 -369.264692)
		(end 81.884266 -374.641872)
		(width 0.1651)
		(layer "In9.Cu")
		(net "P5E_PEX0_STN6_RX_DN<99>")
	)
	(segment
		(start 54.899814 -316.799722)
		(end 54.899814 -316.508892)
		(width 0.1143)
		(layer "In9.Cu")
		(net "P5E_PEX0_STN6_RX_DN<99>")
	)
	(segment
		(start 80.710024 -375.308114)
		(end 80.710024 -375.69013)
		(width 0.1651)
		(layer "In9.Cu")
		(net "P5E_PEX0_STN6_RX_DN<99>")
	)
	(segment
		(start 54.899814 -316.508892)
		(end 54.810914 -316.419992)
		(width 0.1143)
		(layer "In9.Cu")
		(net "P5E_PEX0_STN6_RX_DN<99>")
	)
	(segment
		(start 81.345024 -375.181114)
		(end 80.837024 -375.181114)
		(width 0.1651)
		(layer "In9.Cu")
		(net "P5E_PEX0_STN6_RX_DN<99>")
	)
	(segment
		(start 80.837024 -375.181114)
		(end 80.710024 -375.308114)
		(width 0.1651)
		(layer "In9.Cu")
		(net "P5E_PEX0_STN6_RX_DN<99>")
	)
	(segment
		(start 54.685184 -316.419992)
		(end 54.520084 -316.585092)
		(width 0.1143)
		(layer "In9.Cu")
		(net "P5E_PEX0_STN6_RX_DN<99>")
	)
	(segment
		(start 67.35953 -359.18013)
		(end 69.040756 -359.876598)
		(width 0.1651)
		(layer "In9.Cu")
		(net "P5E_PEX0_STN6_RX_DN<99>")
	)
	(segment
		(start 61.11748 -332.92415)
		(end 66.608452 -341.142066)
		(width 0.1651)
		(layer "In9.Cu")
		(net "P5E_PEX0_STN6_RX_DN<99>")
	)
	(segment
		(start 54.520084 -316.585092)
		(end 54.520084 -319.819528)
		(width 0.1143)
		(layer "In9.Cu")
		(net "P5E_PEX0_STN6_RX_DN<99>")
	)
	(segment
		(start 81.884266 -374.641872)
		(end 81.345024 -375.181114)
		(width 0.1651)
		(layer "In9.Cu")
		(net "P5E_PEX0_STN6_RX_DN<99>")
	)
	(segment
		(start 55.382668 -325.936102)
		(end 61.11748 -332.92415)
		(width 0.1651)
		(layer "In9.Cu")
		(net "P5E_PEX0_STN6_RX_DN<99>")
	)
	(segment
		(start 69.040756 -359.876598)
		(end 80.846168 -367.764822)
		(width 0.1651)
		(layer "In9.Cu")
		(net "P5E_PEX0_STN6_RX_DN<99>")
	)
	(segment
		(start 327.41489 -28.829)
		(end 326.125332 -28.829)
		(width 0.13462)
		(layer "F.Cu")
		(net "P5E_PEX2_STN2_TX_C_DP<32>")
	)
	(segment
		(start 326.125332 -28.829)
		(end 325.964296 -28.990036)
		(width 0.13462)
		(layer "F.Cu")
		(net "P5E_PEX2_STN2_TX_C_DP<32>")
	)
	(segment
		(start 325.964296 -28.990036)
		(end 325.464678 -28.990036)
		(width 0.13462)
		(layer "F.Cu")
		(net "P5E_PEX2_STN2_TX_C_DP<32>")
	)
	(segment
		(start 327.725532 -29.139642)
		(end 327.41489 -28.829)
		(width 0.13462)
		(layer "F.Cu")
		(net "P5E_PEX2_STN2_TX_C_DP<32>")
	)
	(segment
		(start 342.147398 -366.428528)
		(end 341.740998 -366.145572)
		(width 0.1651)
		(layer "In9.Cu")
		(net "P5E_PEX2_STN6_RX_DP<97>")
	)
	(segment
		(start 326.783954 -358.592374)
		(end 326.783954 -342.310974)
		(width 0.1651)
		(layer "In9.Cu")
		(net "P5E_PEX2_STN6_RX_DP<97>")
	)
	(segment
		(start 288.655252 -316.229492)
		(end 288.91103 -316.229492)
		(width 0.1143)
		(layer "In9.Cu")
		(net "P5E_PEX2_STN6_RX_DP<97>")
	)
	(segment
		(start 337.529932 -363.762798)
		(end 337.491832 -363.66196)
		(width 0.1651)
		(layer "In9.Cu")
		(net "P5E_PEX2_STN6_RX_DP<97>")
	)
	(segment
		(start 342.573102 -366.817656)
		(end 342.166448 -366.534446)
		(width 0.1651)
		(layer "In9.Cu")
		(net "P5E_PEX2_STN6_RX_DP<97>")
	)
	(segment
		(start 343.61755 -367.451894)
		(end 343.511378 -367.47069)
		(width 0.1651)
		(layer "In9.Cu")
		(net "P5E_PEX2_STN6_RX_DP<97>")
	)
	(segment
		(start 337.981798 -363.966506)
		(end 337.529932 -363.762798)
		(width 0.1651)
		(layer "In9.Cu")
		(net "P5E_PEX2_STN6_RX_DP<97>")
	)
	(segment
		(start 342.679274 -366.798606)
		(end 342.573102 -366.817656)
		(width 0.1651)
		(layer "In9.Cu")
		(net "P5E_PEX2_STN6_RX_DP<97>")
	)
	(segment
		(start 295.491154 -329.597258)
		(end 291.790628 -327.200768)
		(width 0.1651)
		(layer "In9.Cu")
		(net "P5E_PEX2_STN6_RX_DP<97>")
	)
	(segment
		(start 338.082636 -363.928406)
		(end 337.981798 -363.966506)
		(width 0.1651)
		(layer "In9.Cu")
		(net "P5E_PEX2_STN6_RX_DP<97>")
	)
	(segment
		(start 345.247214 -374.899174)
		(end 345.53398 -374.612408)
		(width 0.1651)
		(layer "In9.Cu")
		(net "P5E_PEX2_STN6_RX_DP<97>")
	)
	(segment
		(start 337.491832 -363.66196)
		(end 337.040474 -363.458506)
		(width 0.1651)
		(layer "In9.Cu")
		(net "P5E_PEX2_STN6_RX_DP<97>")
	)
	(segment
		(start 335.998312 -362.98886)
		(end 335.897474 -363.027214)
		(width 0.1651)
		(layer "In9.Cu")
		(net "P5E_PEX2_STN6_RX_DP<97>")
	)
	(segment
		(start 342.166448 -366.534446)
		(end 342.147398 -366.428528)
		(width 0.1651)
		(layer "In9.Cu")
		(net "P5E_PEX2_STN6_RX_DP<97>")
	)
	(segment
		(start 345.32697 -368.64163)
		(end 343.61755 -367.451894)
		(width 0.1651)
		(layer "In9.Cu")
		(net "P5E_PEX2_STN6_RX_DP<97>")
	)
	(segment
		(start 341.740998 -366.145572)
		(end 341.634826 -366.164622)
		(width 0.1651)
		(layer "In9.Cu")
		(net "P5E_PEX2_STN6_RX_DP<97>")
	)
	(segment
		(start 343.104724 -367.18748)
		(end 343.085674 -367.081562)
		(width 0.1651)
		(layer "In9.Cu")
		(net "P5E_PEX2_STN6_RX_DP<97>")
	)
	(segment
		(start 345.53398 -374.612408)
		(end 345.53398 -369.037362)
		(width 0.1651)
		(layer "In9.Cu")
		(net "P5E_PEX2_STN6_RX_DP<97>")
	)
	(segment
		(start 291.790628 -327.200768)
		(end 288.553652 -323.963792)
		(width 0.1651)
		(layer "In9.Cu")
		(net "P5E_PEX2_STN6_RX_DP<97>")
	)
	(segment
		(start 288.38398 -323.55409)
		(end 288.38398 -319.916048)
		(width 0.1651)
		(layer "In9.Cu")
		(net "P5E_PEX2_STN6_RX_DP<97>")
	)
	(segment
		(start 288.553652 -323.963792)
		(end 288.38398 -323.55409)
		(width 0.1651)
		(layer "In9.Cu")
		(net "P5E_PEX2_STN6_RX_DP<97>")
	)
	(segment
		(start 339.424264 -364.532926)
		(end 338.082636 -363.928406)
		(width 0.1651)
		(layer "In9.Cu")
		(net "P5E_PEX2_STN6_RX_DP<97>")
	)
	(segment
		(start 335.897474 -363.027214)
		(end 335.445608 -362.823252)
		(width 0.1651)
		(layer "In9.Cu")
		(net "P5E_PEX2_STN6_RX_DP<97>")
	)
	(segment
		(start 288.38398 -319.8876)
		(end 288.4297 -319.84188)
		(width 0.1143)
		(layer "In9.Cu")
		(net "P5E_PEX2_STN6_RX_DP<97>")
	)
	(segment
		(start 344.689938 -374.772174)
		(end 344.816938 -374.899174)
		(width 0.1651)
		(layer "In9.Cu")
		(net "P5E_PEX2_STN6_RX_DP<97>")
	)
	(segment
		(start 337.040474 -363.458506)
		(end 336.939636 -363.49686)
		(width 0.1651)
		(layer "In9.Cu")
		(net "P5E_PEX2_STN6_RX_DP<97>")
	)
	(segment
		(start 343.085674 -367.081562)
		(end 342.679274 -366.798606)
		(width 0.1651)
		(layer "In9.Cu")
		(net "P5E_PEX2_STN6_RX_DP<97>")
	)
	(segment
		(start 341.228172 -365.881412)
		(end 341.209122 -365.775494)
		(width 0.1651)
		(layer "In9.Cu")
		(net "P5E_PEX2_STN6_RX_DP<97>")
	)
	(segment
		(start 288.91103 -316.229492)
		(end 288.99993 -316.140592)
		(width 0.1143)
		(layer "In9.Cu")
		(net "P5E_PEX2_STN6_RX_DP<97>")
	)
	(segment
		(start 344.689938 -374.390158)
		(end 344.689938 -374.772174)
		(width 0.1651)
		(layer "In9.Cu")
		(net "P5E_PEX2_STN6_RX_DP<97>")
	)
	(segment
		(start 288.99993 -316.140592)
		(end 288.99993 -315.849762)
		(width 0.1143)
		(layer "In9.Cu")
		(net "P5E_PEX2_STN6_RX_DP<97>")
	)
	(segment
		(start 335.407508 -362.722668)
		(end 327.227692 -359.036112)
		(width 0.1651)
		(layer "In9.Cu")
		(net "P5E_PEX2_STN6_RX_DP<97>")
	)
	(segment
		(start 336.48777 -363.292898)
		(end 336.44967 -363.192314)
		(width 0.1651)
		(layer "In9.Cu")
		(net "P5E_PEX2_STN6_RX_DP<97>")
	)
	(segment
		(start 326.783954 -342.310974)
		(end 326.346566 -341.348822)
		(width 0.1651)
		(layer "In9.Cu")
		(net "P5E_PEX2_STN6_RX_DP<97>")
	)
	(segment
		(start 288.4297 -316.455044)
		(end 288.655252 -316.229492)
		(width 0.1143)
		(layer "In9.Cu")
		(net "P5E_PEX2_STN6_RX_DP<97>")
	)
	(segment
		(start 345.53398 -369.037362)
		(end 345.32697 -368.64163)
		(width 0.1651)
		(layer "In9.Cu")
		(net "P5E_PEX2_STN6_RX_DP<97>")
	)
	(segment
		(start 343.511378 -367.47069)
		(end 343.104724 -367.18748)
		(width 0.1651)
		(layer "In9.Cu")
		(net "P5E_PEX2_STN6_RX_DP<97>")
	)
	(segment
		(start 336.44967 -363.192314)
		(end 335.998312 -362.98886)
		(width 0.1651)
		(layer "In9.Cu")
		(net "P5E_PEX2_STN6_RX_DP<97>")
	)
	(segment
		(start 344.816938 -374.899174)
		(end 345.247214 -374.899174)
		(width 0.1651)
		(layer "In9.Cu")
		(net "P5E_PEX2_STN6_RX_DP<97>")
	)
	(segment
		(start 335.445608 -362.823252)
		(end 335.407508 -362.722668)
		(width 0.1651)
		(layer "In9.Cu")
		(net "P5E_PEX2_STN6_RX_DP<97>")
	)
	(segment
		(start 288.4297 -319.84188)
		(end 288.4297 -316.455044)
		(width 0.1143)
		(layer "In9.Cu")
		(net "P5E_PEX2_STN6_RX_DP<97>")
	)
	(segment
		(start 327.227692 -359.036112)
		(end 326.783954 -358.592374)
		(width 0.1651)
		(layer "In9.Cu")
		(net "P5E_PEX2_STN6_RX_DP<97>")
	)
	(segment
		(start 341.209122 -365.775494)
		(end 339.424264 -364.532926)
		(width 0.1651)
		(layer "In9.Cu")
		(net "P5E_PEX2_STN6_RX_DP<97>")
	)
	(segment
		(start 326.346566 -341.348822)
		(end 295.491154 -329.597258)
		(width 0.1651)
		(layer "In9.Cu")
		(net "P5E_PEX2_STN6_RX_DP<97>")
	)
	(segment
		(start 288.38398 -319.916048)
		(end 288.38398 -319.8876)
		(width 0.1143)
		(layer "In9.Cu")
		(net "P5E_PEX2_STN6_RX_DP<97>")
	)
	(segment
		(start 336.939636 -363.49686)
		(end 336.48777 -363.292898)
		(width 0.1651)
		(layer "In9.Cu")
		(net "P5E_PEX2_STN6_RX_DP<97>")
	)
	(segment
		(start 341.634826 -366.164622)
		(end 341.228172 -365.881412)
		(width 0.1651)
		(layer "In9.Cu")
		(net "P5E_PEX2_STN6_RX_DP<97>")
	)
	(segment
		(start 402.39696 -106.512614)
		(end 402.097494 -106.81208)
		(width 0.13462)
		(layer "F.Cu")
		(net "P5E_PEX3_STN1_RX_DP<20>")
	)
	(segment
		(start 402.097494 -106.81208)
		(end 399.592292 -106.81208)
		(width 0.13462)
		(layer "F.Cu")
		(net "P5E_PEX3_STN1_RX_DP<20>")
	)
	(segment
		(start 399.42516 -106.644948)
		(end 398.94256 -106.644948)
		(width 0.13462)
		(layer "F.Cu")
		(net "P5E_PEX3_STN1_RX_DP<20>")
	)
	(segment
		(start 399.592292 -106.81208)
		(end 399.42516 -106.644948)
		(width 0.13462)
		(layer "F.Cu")
		(net "P5E_PEX3_STN1_RX_DP<20>")
	)
	(segment
		(start 386.733288 -122.95759)
		(end 384.965702 -123.639326)
		(width 0.1651)
		(layer "In5.Cu")
		(net "P5E_PEX3_STN1_RX_DP<20>")
	)
	(segment
		(start 411.179772 -273.45513)
		(end 411.394656 -273.670014)
		(width 0.1143)
		(layer "In5.Cu")
		(net "P5E_PEX3_STN1_RX_DP<20>")
	)
	(segment
		(start 384.965702 -123.639326)
		(end 384.91668 -123.736608)
		(width 0.1651)
		(layer "In5.Cu")
		(net "P5E_PEX3_STN1_RX_DP<20>")
	)
	(segment
		(start 402.39696 -106.512614)
		(end 402.10613 -106.803444)
		(width 0.1651)
		(layer "In5.Cu")
		(net "P5E_PEX3_STN1_RX_DP<20>")
	)
	(segment
		(start 411.134052 -271.554448)
		(end 411.179772 -271.600168)
		(width 0.1143)
		(layer "In5.Cu")
		(net "P5E_PEX3_STN1_RX_DP<20>")
	)
	(segment
		(start 411.179772 -271.600168)
		(end 411.179772 -273.45513)
		(width 0.1143)
		(layer "In5.Cu")
		(net "P5E_PEX3_STN1_RX_DP<20>")
	)
	(segment
		(start 380.917704 -158.750254)
		(end 381.943102 -164.725858)
		(width 0.1651)
		(layer "In5.Cu")
		(net "P5E_PEX3_STN1_RX_DP<20>")
	)
	(segment
		(start 380.657354 -154.632406)
		(end 380.917704 -158.750254)
		(width 0.1651)
		(layer "In5.Cu")
		(net "P5E_PEX3_STN1_RX_DP<20>")
	)
	(segment
		(start 389.982964 -113.218722)
		(end 389.145272 -114.696748)
		(width 0.1651)
		(layer "In5.Cu")
		(net "P5E_PEX3_STN1_RX_DP<20>")
	)
	(segment
		(start 411.749748 -273.784314)
		(end 411.749748 -274.049744)
		(width 0.1143)
		(layer "In5.Cu")
		(net "P5E_PEX3_STN1_RX_DP<20>")
	)
	(segment
		(start 384.91668 -123.736608)
		(end 384.916934 -123.736608)
		(width 0.1651)
		(layer "In5.Cu")
		(net "P5E_PEX3_STN1_RX_DP<20>")
	)
	(segment
		(start 387.397498 -122.198384)
		(end 386.733288 -122.95759)
		(width 0.1651)
		(layer "In5.Cu")
		(net "P5E_PEX3_STN1_RX_DP<20>")
	)
	(segment
		(start 381.943102 -164.725858)
		(end 411.134052 -269.350998)
		(width 0.1651)
		(layer "In5.Cu")
		(net "P5E_PEX3_STN1_RX_DP<20>")
	)
	(segment
		(start 392.61288 -110.677452)
		(end 389.982964 -113.218722)
		(width 0.1651)
		(layer "In5.Cu")
		(net "P5E_PEX3_STN1_RX_DP<20>")
	)
	(segment
		(start 411.394656 -273.670014)
		(end 411.635448 -273.670014)
		(width 0.1143)
		(layer "In5.Cu")
		(net "P5E_PEX3_STN1_RX_DP<20>")
	)
	(segment
		(start 411.134052 -269.350998)
		(end 411.134052 -271.526)
		(width 0.1651)
		(layer "In5.Cu")
		(net "P5E_PEX3_STN1_RX_DP<20>")
	)
	(segment
		(start 399.889472 -106.803444)
		(end 392.61288 -110.677452)
		(width 0.1651)
		(layer "In5.Cu")
		(net "P5E_PEX3_STN1_RX_DP<20>")
	)
	(segment
		(start 384.916934 -123.736608)
		(end 382.037082 -129.472436)
		(width 0.1651)
		(layer "In5.Cu")
		(net "P5E_PEX3_STN1_RX_DP<20>")
	)
	(segment
		(start 389.145272 -114.696748)
		(end 387.397498 -122.198384)
		(width 0.1651)
		(layer "In5.Cu")
		(net "P5E_PEX3_STN1_RX_DP<20>")
	)
	(segment
		(start 411.134052 -271.526)
		(end 411.134052 -271.554448)
		(width 0.1143)
		(layer "In5.Cu")
		(net "P5E_PEX3_STN1_RX_DP<20>")
	)
	(segment
		(start 382.037082 -129.472436)
		(end 380.39675 -150.509986)
		(width 0.1651)
		(layer "In5.Cu")
		(net "P5E_PEX3_STN1_RX_DP<20>")
	)
	(segment
		(start 380.39675 -150.509986)
		(end 380.657354 -154.632406)
		(width 0.1651)
		(layer "In5.Cu")
		(net "P5E_PEX3_STN1_RX_DP<20>")
	)
	(segment
		(start 402.10613 -106.803444)
		(end 399.889472 -106.803444)
		(width 0.1651)
		(layer "In5.Cu")
		(net "P5E_PEX3_STN1_RX_DP<20>")
	)
	(segment
		(start 411.635448 -273.670014)
		(end 411.749748 -273.784314)
		(width 0.1143)
		(layer "In5.Cu")
		(net "P5E_PEX3_STN1_RX_DP<20>")
	)
	(segment
		(start 402.65604 -157.353)
		(end 403.39899 -157.353)
		(width 0.13208)
		(layer "F.Cu")
		(net "RST_NIC6_PERST3_R_N")
	)
	(segment
		(start 398.94256 -157.759908)
		(end 400.344132 -157.759908)
		(width 0.13208)
		(layer "F.Cu")
		(net "RST_NIC6_PERST3_R_N")
	)
	(segment
		(start 400.75104 -157.353)
		(end 402.65604 -157.353)
		(width 0.13208)
		(layer "F.Cu")
		(net "RST_NIC6_PERST3_R_N")
	)
	(segment
		(start 403.39899 -157.353)
		(end 403.88159 -157.8356)
		(width 0.13208)
		(layer "F.Cu")
		(net "RST_NIC6_PERST3_R_N")
	)
	(segment
		(start 400.344132 -157.759908)
		(end 400.75104 -157.353)
		(width 0.13208)
		(layer "F.Cu")
		(net "RST_NIC6_PERST3_R_N")
	)
	(via
		(at 402.65604 -157.353)
		(size 0.762)
		(drill 0.381)
		(layers "F.Cu" "B.Cu")
		(net "RST_NIC6_PERST3_R_N")
	)
	(segment
		(start 92.756482 -345.170506)
		(end 92.756482 -344.539062)
		(width 0.13462)
		(layer "F.Cu")
		(net "P5E_PEX0_STN6_TX_C_DP<97>")
	)
	(segment
		(start 92.756482 -344.539062)
		(end 92.436442 -344.219022)
		(width 0.13462)
		(layer "F.Cu")
		(net "P5E_PEX0_STN6_TX_C_DP<97>")
	)
	(segment
		(start 92.461842 -345.465146)
		(end 92.756482 -345.170506)
		(width 0.13462)
		(layer "F.Cu")
		(net "P5E_PEX0_STN6_TX_C_DP<97>")
	)
	(segment
		(start 86.002114 -382.423924)
		(end 85.726778 -382.69926)
		(width 0.1651)
		(layer "In13.Cu")
		(net "P5E_PEX0_STN6_TX_C_DP<97>")
	)
	(segment
		(start 91.198192 -358.217978)
		(end 88.453722 -364.020354)
		(width 0.1651)
		(layer "In13.Cu")
		(net "P5E_PEX0_STN6_TX_C_DP<97>")
	)
	(segment
		(start 88.453722 -364.020354)
		(end 88.335358 -364.062772)
		(width 0.1651)
		(layer "In13.Cu")
		(net "P5E_PEX0_STN6_TX_C_DP<97>")
	)
	(segment
		(start 86.002114 -369.203986)
		(end 86.002114 -382.423924)
		(width 0.1651)
		(layer "In13.Cu")
		(net "P5E_PEX0_STN6_TX_C_DP<97>")
	)
	(segment
		(start 87.954104 -365.07674)
		(end 87.83574 -365.119158)
		(width 0.1651)
		(layer "In13.Cu")
		(net "P5E_PEX0_STN6_TX_C_DP<97>")
	)
	(segment
		(start 85.109812 -382.57226)
		(end 85.109812 -382.18999)
		(width 0.1651)
		(layer "In13.Cu")
		(net "P5E_PEX0_STN6_TX_C_DP<97>")
	)
	(segment
		(start 87.623904 -365.567214)
		(end 87.666068 -365.685578)
		(width 0.1651)
		(layer "In13.Cu")
		(net "P5E_PEX0_STN6_TX_C_DP<97>")
	)
	(segment
		(start 92.752672 -345.755976)
		(end 92.752672 -346.311728)
		(width 0.1651)
		(layer "In13.Cu")
		(net "P5E_PEX0_STN6_TX_C_DP<97>")
	)
	(segment
		(start 92.461842 -345.465146)
		(end 92.752672 -345.755976)
		(width 0.1651)
		(layer "In13.Cu")
		(net "P5E_PEX0_STN6_TX_C_DP<97>")
	)
	(segment
		(start 88.335358 -364.062772)
		(end 88.123522 -364.510828)
		(width 0.1651)
		(layer "In13.Cu")
		(net "P5E_PEX0_STN6_TX_C_DP<97>")
	)
	(segment
		(start 87.336122 -366.175544)
		(end 87.124286 -366.6236)
		(width 0.1651)
		(layer "In13.Cu")
		(net "P5E_PEX0_STN6_TX_C_DP<97>")
	)
	(segment
		(start 88.123522 -364.510828)
		(end 88.165686 -364.629192)
		(width 0.1651)
		(layer "In13.Cu")
		(net "P5E_PEX0_STN6_TX_C_DP<97>")
	)
	(segment
		(start 87.454486 -366.133126)
		(end 87.336122 -366.175544)
		(width 0.1651)
		(layer "In13.Cu")
		(net "P5E_PEX0_STN6_TX_C_DP<97>")
	)
	(segment
		(start 88.165686 -364.629192)
		(end 87.954104 -365.07674)
		(width 0.1651)
		(layer "In13.Cu")
		(net "P5E_PEX0_STN6_TX_C_DP<97>")
	)
	(segment
		(start 91.198192 -347.866208)
		(end 91.198192 -358.217978)
		(width 0.1651)
		(layer "In13.Cu")
		(net "P5E_PEX0_STN6_TX_C_DP<97>")
	)
	(segment
		(start 85.236812 -382.69926)
		(end 85.109812 -382.57226)
		(width 0.1651)
		(layer "In13.Cu")
		(net "P5E_PEX0_STN6_TX_C_DP<97>")
	)
	(segment
		(start 87.16645 -366.741964)
		(end 86.002114 -369.203986)
		(width 0.1651)
		(layer "In13.Cu")
		(net "P5E_PEX0_STN6_TX_C_DP<97>")
	)
	(segment
		(start 85.726778 -382.69926)
		(end 85.236812 -382.69926)
		(width 0.1651)
		(layer "In13.Cu")
		(net "P5E_PEX0_STN6_TX_C_DP<97>")
	)
	(segment
		(start 87.124286 -366.6236)
		(end 87.16645 -366.741964)
		(width 0.1651)
		(layer "In13.Cu")
		(net "P5E_PEX0_STN6_TX_C_DP<97>")
	)
	(segment
		(start 92.752672 -346.311728)
		(end 91.198192 -347.866208)
		(width 0.1651)
		(layer "In13.Cu")
		(net "P5E_PEX0_STN6_TX_C_DP<97>")
	)
	(segment
		(start 87.666068 -365.685578)
		(end 87.454486 -366.133126)
		(width 0.1651)
		(layer "In13.Cu")
		(net "P5E_PEX0_STN6_TX_C_DP<97>")
	)
	(segment
		(start 87.83574 -365.119158)
		(end 87.623904 -365.567214)
		(width 0.1651)
		(layer "In13.Cu")
		(net "P5E_PEX0_STN6_TX_C_DP<97>")
	)
	(segment
		(start 178.287426 -30.190186)
		(end 178.124612 -30.353)
		(width 0.13462)
		(layer "F.Cu")
		(net "P5E_PEX1_STN2_RX_DN<37>")
	)
	(segment
		(start 178.124612 -30.353)
		(end 175.604678 -30.353)
		(width 0.13462)
		(layer "F.Cu")
		(net "P5E_PEX1_STN2_RX_DN<37>")
	)
	(segment
		(start 175.604678 -30.353)
		(end 175.310546 -30.058868)
		(width 0.13462)
		(layer "F.Cu")
		(net "P5E_PEX1_STN2_RX_DN<37>")
	)
	(segment
		(start 178.764946 -30.190186)
		(end 178.287426 -30.190186)
		(width 0.13462)
		(layer "F.Cu")
		(net "P5E_PEX1_STN2_RX_DN<37>")
	)
	(segment
		(start 169.715942 -271.345152)
		(end 169.715942 -266.392152)
		(width 0.1651)
		(layer "In7.Cu")
		(net "P5E_PEX1_STN2_RX_DN<37>")
	)
	(segment
		(start 169.715942 -271.3736)
		(end 169.715942 -271.345152)
		(width 0.1143)
		(layer "In7.Cu")
		(net "P5E_PEX1_STN2_RX_DN<37>")
	)
	(segment
		(start 169.935652 -273.479514)
		(end 169.821098 -273.479514)
		(width 0.1143)
		(layer "In7.Cu")
		(net "P5E_PEX1_STN2_RX_DN<37>")
	)
	(segment
		(start 170.049952 -273.099784)
		(end 170.049952 -273.365214)
		(width 0.1143)
		(layer "In7.Cu")
		(net "P5E_PEX1_STN2_RX_DN<37>")
	)
	(segment
		(start 169.846498 -264.905998)
		(end 180.22062 -68.498974)
		(width 0.1651)
		(layer "In7.Cu")
		(net "P5E_PEX1_STN2_RX_DN<37>")
	)
	(segment
		(start 177.889154 -30.349698)
		(end 175.601376 -30.349698)
		(width 0.1651)
		(layer "In7.Cu")
		(net "P5E_PEX1_STN2_RX_DN<37>")
	)
	(segment
		(start 179.512468 -31.973012)
		(end 177.889154 -30.349698)
		(width 0.1651)
		(layer "In7.Cu")
		(net "P5E_PEX1_STN2_RX_DN<37>")
	)
	(segment
		(start 179.033678 -39.962328)
		(end 178.984656 -39.308786)
		(width 0.1651)
		(layer "In7.Cu")
		(net "P5E_PEX1_STN2_RX_DN<37>")
	)
	(segment
		(start 169.715942 -266.392152)
		(end 169.846498 -264.905998)
		(width 0.1651)
		(layer "In7.Cu")
		(net "P5E_PEX1_STN2_RX_DN<37>")
	)
	(segment
		(start 179.488084 -35.00755)
		(end 179.512468 -31.973012)
		(width 0.1651)
		(layer "In7.Cu")
		(net "P5E_PEX1_STN2_RX_DN<37>")
	)
	(segment
		(start 169.821098 -273.479514)
		(end 169.670222 -273.328638)
		(width 0.1143)
		(layer "In7.Cu")
		(net "P5E_PEX1_STN2_RX_DN<37>")
	)
	(segment
		(start 169.670222 -271.41932)
		(end 169.715942 -271.3736)
		(width 0.1143)
		(layer "In7.Cu")
		(net "P5E_PEX1_STN2_RX_DN<37>")
	)
	(segment
		(start 180.22062 -68.498974)
		(end 180.405024 -50.110644)
		(width 0.1651)
		(layer "In7.Cu")
		(net "P5E_PEX1_STN2_RX_DN<37>")
	)
	(segment
		(start 178.96332 -37.96284)
		(end 179.488084 -35.00755)
		(width 0.1651)
		(layer "In7.Cu")
		(net "P5E_PEX1_STN2_RX_DN<37>")
	)
	(segment
		(start 169.670222 -273.328638)
		(end 169.670222 -271.41932)
		(width 0.1143)
		(layer "In7.Cu")
		(net "P5E_PEX1_STN2_RX_DN<37>")
	)
	(segment
		(start 175.601376 -30.349698)
		(end 175.310546 -30.058868)
		(width 0.1651)
		(layer "In7.Cu")
		(net "P5E_PEX1_STN2_RX_DN<37>")
	)
	(segment
		(start 180.405024 -50.110644)
		(end 179.033678 -39.962328)
		(width 0.1651)
		(layer "In7.Cu")
		(net "P5E_PEX1_STN2_RX_DN<37>")
	)
	(segment
		(start 178.984656 -39.308786)
		(end 178.96332 -37.96284)
		(width 0.1651)
		(layer "In7.Cu")
		(net "P5E_PEX1_STN2_RX_DN<37>")
	)
	(segment
		(start 170.049952 -273.365214)
		(end 169.935652 -273.479514)
		(width 0.1143)
		(layer "In7.Cu")
		(net "P5E_PEX1_STN2_RX_DN<37>")
	)
	(segment
		(start 242.21948 -28.55468)
		(end 241.560604 -28.55468)
		(width 0.13462)
		(layer "F.Cu")
		(net "P5E_PEX2_STN2_RX_DN<44>")
	)
	(segment
		(start 241.560604 -28.55468)
		(end 241.264694 -28.25877)
		(width 0.13462)
		(layer "F.Cu")
		(net "P5E_PEX2_STN2_RX_DN<44>")
	)
	(segment
		(start 242.864894 -28.390088)
		(end 242.384072 -28.390088)
		(width 0.13462)
		(layer "F.Cu")
		(net "P5E_PEX2_STN2_RX_DN<44>")
	)
	(segment
		(start 242.384072 -28.390088)
		(end 242.21948 -28.55468)
		(width 0.13462)
		(layer "F.Cu")
		(net "P5E_PEX2_STN2_RX_DN<44>")
	)
	(segment
		(start 245.506748 -61.851032)
		(end 245.317772 -85.173566)
		(width 0.1651)
		(layer "In7.Cu")
		(net "P5E_PEX2_STN2_RX_DN<44>")
	)
	(segment
		(start 245.237254 -57.32399)
		(end 245.506748 -60.059824)
		(width 0.1651)
		(layer "In7.Cu")
		(net "P5E_PEX2_STN2_RX_DN<44>")
	)
	(segment
		(start 247.531382 -37.688012)
		(end 247.506744 -39.16934)
		(width 0.1651)
		(layer "In7.Cu")
		(net "P5E_PEX2_STN2_RX_DN<44>")
	)
	(segment
		(start 242.003834 -28.5496)
		(end 242.914932 -29.460698)
		(width 0.1651)
		(layer "In7.Cu")
		(net "P5E_PEX2_STN2_RX_DN<44>")
	)
	(segment
		(start 279.119838 -275.275802)
		(end 279.223724 -275.379688)
		(width 0.1143)
		(layer "In7.Cu")
		(net "P5E_PEX2_STN2_RX_DN<44>")
	)
	(segment
		(start 279.165558 -271.421352)
		(end 279.119838 -271.467072)
		(width 0.1143)
		(layer "In7.Cu")
		(net "P5E_PEX2_STN2_RX_DN<44>")
	)
	(segment
		(start 279.385522 -275.379688)
		(end 279.499822 -275.265388)
		(width 0.1143)
		(layer "In7.Cu")
		(net "P5E_PEX2_STN2_RX_DN<44>")
	)
	(segment
		(start 255.676654 -119.34952)
		(end 258.9657 -144.353534)
		(width 0.1651)
		(layer "In7.Cu")
		(net "P5E_PEX2_STN2_RX_DN<44>")
	)
	(segment
		(start 278.212804 -263.459722)
		(end 279.165558 -269.50162)
		(width 0.1651)
		(layer "In7.Cu")
		(net "P5E_PEX2_STN2_RX_DN<44>")
	)
	(segment
		(start 243.579142 -30.4546)
		(end 245.142766 -32.018224)
		(width 0.1651)
		(layer "In7.Cu")
		(net "P5E_PEX2_STN2_RX_DN<44>")
	)
	(segment
		(start 241.55781 -28.551886)
		(end 241.563652 -28.5496)
		(width 0.1651)
		(layer "In7.Cu")
		(net "P5E_PEX2_STN2_RX_DN<44>")
	)
	(segment
		(start 245.317772 -85.173566)
		(end 255.676654 -119.34952)
		(width 0.1651)
		(layer "In7.Cu")
		(net "P5E_PEX2_STN2_RX_DN<44>")
	)
	(segment
		(start 279.499822 -275.265388)
		(end 279.499822 -274.999958)
		(width 0.1143)
		(layer "In7.Cu")
		(net "P5E_PEX2_STN2_RX_DN<44>")
	)
	(segment
		(start 279.165558 -271.392904)
		(end 279.165558 -271.421352)
		(width 0.1143)
		(layer "In7.Cu")
		(net "P5E_PEX2_STN2_RX_DN<44>")
	)
	(segment
		(start 245.142766 -32.018224)
		(end 247.531382 -37.688012)
		(width 0.1651)
		(layer "In7.Cu")
		(net "P5E_PEX2_STN2_RX_DN<44>")
	)
	(segment
		(start 278.289766 -255.60782)
		(end 278.212804 -263.459722)
		(width 0.1651)
		(layer "In7.Cu")
		(net "P5E_PEX2_STN2_RX_DN<44>")
	)
	(segment
		(start 258.9657 -144.353534)
		(end 276.681184 -238.036354)
		(width 0.1651)
		(layer "In7.Cu")
		(net "P5E_PEX2_STN2_RX_DN<44>")
	)
	(segment
		(start 279.119838 -271.467072)
		(end 279.119838 -275.275802)
		(width 0.1143)
		(layer "In7.Cu")
		(net "P5E_PEX2_STN2_RX_DN<44>")
	)
	(segment
		(start 241.264694 -28.25877)
		(end 241.55781 -28.551886)
		(width 0.1651)
		(layer "In7.Cu")
		(net "P5E_PEX2_STN2_RX_DN<44>")
	)
	(segment
		(start 242.914932 -29.460698)
		(end 243.579142 -30.4546)
		(width 0.1651)
		(layer "In7.Cu")
		(net "P5E_PEX2_STN2_RX_DN<44>")
	)
	(segment
		(start 276.681184 -238.036354)
		(end 278.289766 -255.60782)
		(width 0.1651)
		(layer "In7.Cu")
		(net "P5E_PEX2_STN2_RX_DN<44>")
	)
	(segment
		(start 279.223724 -275.379688)
		(end 279.385522 -275.379688)
		(width 0.1143)
		(layer "In7.Cu")
		(net "P5E_PEX2_STN2_RX_DN<44>")
	)
	(segment
		(start 241.563652 -28.5496)
		(end 242.003834 -28.5496)
		(width 0.1651)
		(layer "In7.Cu")
		(net "P5E_PEX2_STN2_RX_DN<44>")
	)
	(segment
		(start 245.360698 -49.41951)
		(end 245.237254 -57.32399)
		(width 0.1651)
		(layer "In7.Cu")
		(net "P5E_PEX2_STN2_RX_DN<44>")
	)
	(segment
		(start 279.165558 -269.50162)
		(end 279.165558 -271.392904)
		(width 0.1651)
		(layer "In7.Cu")
		(net "P5E_PEX2_STN2_RX_DN<44>")
	)
	(segment
		(start 247.506744 -39.16934)
		(end 245.360698 -49.41951)
		(width 0.1651)
		(layer "In7.Cu")
		(net "P5E_PEX2_STN2_RX_DN<44>")
	)
	(segment
		(start 245.506748 -60.059824)
		(end 245.506748 -61.851032)
		(width 0.1651)
		(layer "In7.Cu")
		(net "P5E_PEX2_STN2_RX_DN<44>")
	)
	(segment
		(start 319.015364 -345.170506)
		(end 318.720724 -345.465146)
		(width 0.13462)
		(layer "F.Cu")
		(net "P5E_PEX2_STN6_TX_C_DP<109>")
	)
	(segment
		(start 319.015364 -344.539062)
		(end 319.015364 -345.170506)
		(width 0.13462)
		(layer "F.Cu")
		(net "P5E_PEX2_STN6_TX_C_DP<109>")
	)
	(segment
		(start 318.695324 -344.219022)
		(end 319.015364 -344.539062)
		(width 0.13462)
		(layer "F.Cu")
		(net "P5E_PEX2_STN6_TX_C_DP<109>")
	)
	(segment
		(start 318.23533 -361.677966)
		(end 318.370966 -362.154216)
		(width 0.1651)
		(layer "In13.Cu")
		(net "P5E_PEX2_STN6_TX_C_DP<109>")
	)
	(segment
		(start 318.955674 -364.57636)
		(end 319.09131 -365.052864)
		(width 0.1651)
		(layer "In13.Cu")
		(net "P5E_PEX2_STN6_TX_C_DP<109>")
	)
	(segment
		(start 317.457074 -358.946704)
		(end 318.043814 -361.005882)
		(width 0.1651)
		(layer "In13.Cu")
		(net "P5E_PEX2_STN6_TX_C_DP<109>")
	)
	(segment
		(start 329.708002 -391.310622)
		(end 334.350106 -392.973052)
		(width 0.1651)
		(layer "In13.Cu")
		(net "P5E_PEX2_STN6_TX_C_DP<109>")
	)
	(segment
		(start 334.350106 -392.973052)
		(end 336.464148 -394.596366)
		(width 0.1651)
		(layer "In13.Cu")
		(net "P5E_PEX2_STN6_TX_C_DP<109>")
	)
	(segment
		(start 317.457074 -347.764354)
		(end 317.457074 -358.946704)
		(width 0.1651)
		(layer "In13.Cu")
		(net "P5E_PEX2_STN6_TX_C_DP<109>")
	)
	(segment
		(start 319.011554 -345.755976)
		(end 319.011554 -346.209874)
		(width 0.1651)
		(layer "In13.Cu")
		(net "P5E_PEX2_STN6_TX_C_DP<109>")
	)
	(segment
		(start 317.973964 -361.131612)
		(end 318.1096 -361.608116)
		(width 0.1651)
		(layer "In13.Cu")
		(net "P5E_PEX2_STN6_TX_C_DP<109>")
	)
	(segment
		(start 319.217294 -365.122968)
		(end 319.21704 -365.122968)
		(width 0.1651)
		(layer "In13.Cu")
		(net "P5E_PEX2_STN6_TX_C_DP<109>")
	)
	(segment
		(start 318.1096 -361.608116)
		(end 318.23533 -361.677966)
		(width 0.1651)
		(layer "In13.Cu")
		(net "P5E_PEX2_STN6_TX_C_DP<109>")
	)
	(segment
		(start 335.890108 -408.572208)
		(end 335.890108 -408.190192)
		(width 0.1651)
		(layer "In13.Cu")
		(net "P5E_PEX2_STN6_TX_C_DP<109>")
	)
	(segment
		(start 336.017108 -408.699208)
		(end 335.890108 -408.572208)
		(width 0.1651)
		(layer "In13.Cu")
		(net "P5E_PEX2_STN6_TX_C_DP<109>")
	)
	(segment
		(start 336.73415 -394.98651)
		(end 336.73415 -408.412442)
		(width 0.1651)
		(layer "In13.Cu")
		(net "P5E_PEX2_STN6_TX_C_DP<109>")
	)
	(segment
		(start 336.73415 -408.412442)
		(end 336.447384 -408.699208)
		(width 0.1651)
		(layer "In13.Cu")
		(net "P5E_PEX2_STN6_TX_C_DP<109>")
	)
	(segment
		(start 318.562736 -362.8263)
		(end 318.562482 -362.8263)
		(width 0.1651)
		(layer "In13.Cu")
		(net "P5E_PEX2_STN6_TX_C_DP<109>")
	)
	(segment
		(start 319.011554 -346.209874)
		(end 317.457074 -347.764354)
		(width 0.1651)
		(layer "In13.Cu")
		(net "P5E_PEX2_STN6_TX_C_DP<109>")
	)
	(segment
		(start 318.720724 -345.465146)
		(end 319.011554 -345.755976)
		(width 0.1651)
		(layer "In13.Cu")
		(net "P5E_PEX2_STN6_TX_C_DP<109>")
	)
	(segment
		(start 318.889888 -363.974634)
		(end 319.025524 -364.450884)
		(width 0.1651)
		(layer "In13.Cu")
		(net "P5E_PEX2_STN6_TX_C_DP<109>")
	)
	(segment
		(start 318.370966 -362.154216)
		(end 318.301116 -362.279692)
		(width 0.1651)
		(layer "In13.Cu")
		(net "P5E_PEX2_STN6_TX_C_DP<109>")
	)
	(segment
		(start 319.025524 -364.450884)
		(end 318.955674 -364.57636)
		(width 0.1651)
		(layer "In13.Cu")
		(net "P5E_PEX2_STN6_TX_C_DP<109>")
	)
	(segment
		(start 319.09131 -365.052864)
		(end 319.217294 -365.122968)
		(width 0.1651)
		(layer "In13.Cu")
		(net "P5E_PEX2_STN6_TX_C_DP<109>")
	)
	(segment
		(start 318.436752 -362.756196)
		(end 318.562736 -362.8263)
		(width 0.1651)
		(layer "In13.Cu")
		(net "P5E_PEX2_STN6_TX_C_DP<109>")
	)
	(segment
		(start 325.770494 -388.12089)
		(end 329.708002 -391.310622)
		(width 0.1651)
		(layer "In13.Cu")
		(net "P5E_PEX2_STN6_TX_C_DP<109>")
	)
	(segment
		(start 318.301116 -362.279692)
		(end 318.436752 -362.756196)
		(width 0.1651)
		(layer "In13.Cu")
		(net "P5E_PEX2_STN6_TX_C_DP<109>")
	)
	(segment
		(start 336.464148 -394.596366)
		(end 336.73415 -394.98651)
		(width 0.1651)
		(layer "In13.Cu")
		(net "P5E_PEX2_STN6_TX_C_DP<109>")
	)
	(segment
		(start 318.628268 -363.428026)
		(end 318.763904 -363.90453)
		(width 0.1651)
		(layer "In13.Cu")
		(net "P5E_PEX2_STN6_TX_C_DP<109>")
	)
	(segment
		(start 318.698118 -363.30255)
		(end 318.628268 -363.428026)
		(width 0.1651)
		(layer "In13.Cu")
		(net "P5E_PEX2_STN6_TX_C_DP<109>")
	)
	(segment
		(start 318.562482 -362.8263)
		(end 318.698118 -363.30255)
		(width 0.1651)
		(layer "In13.Cu")
		(net "P5E_PEX2_STN6_TX_C_DP<109>")
	)
	(segment
		(start 336.447384 -408.699208)
		(end 336.017108 -408.699208)
		(width 0.1651)
		(layer "In13.Cu")
		(net "P5E_PEX2_STN6_TX_C_DP<109>")
	)
	(segment
		(start 318.763904 -363.90453)
		(end 318.889888 -363.974634)
		(width 0.1651)
		(layer "In13.Cu")
		(net "P5E_PEX2_STN6_TX_C_DP<109>")
	)
	(segment
		(start 319.21704 -365.122968)
		(end 325.770494 -388.12089)
		(width 0.1651)
		(layer "In13.Cu")
		(net "P5E_PEX2_STN6_TX_C_DP<109>")
	)
	(segment
		(start 318.043814 -361.005882)
		(end 317.973964 -361.131612)
		(width 0.1651)
		(layer "In13.Cu")
		(net "P5E_PEX2_STN6_TX_C_DP<109>")
	)
	(segment
		(start 400.243294 -124.92228)
		(end 399.58899 -124.92228)
		(width 0.13462)
		(layer "F.Cu")
		(net "P5E_PEX3_STN1_RX_DP<27>")
	)
	(segment
		(start 399.421858 -124.755148)
		(end 398.94256 -124.755148)
		(width 0.13462)
		(layer "F.Cu")
		(net "P5E_PEX3_STN1_RX_DP<27>")
	)
	(segment
		(start 399.58899 -124.92228)
		(end 399.421858 -124.755148)
		(width 0.13462)
		(layer "F.Cu")
		(net "P5E_PEX3_STN1_RX_DP<27>")
	)
	(segment
		(start 400.54276 -124.622814)
		(end 400.243294 -124.92228)
		(width 0.13462)
		(layer "F.Cu")
		(net "P5E_PEX3_STN1_RX_DP<27>")
	)
	(segment
		(start 398.79143 -126.607316)
		(end 398.79143 -128.23317)
		(width 0.1651)
		(layer "In5.Cu")
		(net "P5E_PEX3_STN1_RX_DP<27>")
	)
	(segment
		(start 395.228318 -135.238236)
		(end 393.64412 -140.451078)
		(width 0.1651)
		(layer "In5.Cu")
		(net "P5E_PEX3_STN1_RX_DP<27>")
	)
	(segment
		(start 400.54276 -124.622814)
		(end 400.25193 -124.913644)
		(width 0.1651)
		(layer "In5.Cu")
		(net "P5E_PEX3_STN1_RX_DP<27>")
	)
	(segment
		(start 388.708392 -157.041342)
		(end 389.483346 -161.41446)
		(width 0.1651)
		(layer "In5.Cu")
		(net "P5E_PEX3_STN1_RX_DP<27>")
	)
	(segment
		(start 399.269458 -125.45314)
		(end 398.79143 -126.607316)
		(width 0.1651)
		(layer "In5.Cu")
		(net "P5E_PEX3_STN1_RX_DP<27>")
	)
	(segment
		(start 417.783772 -271.570958)
		(end 417.783772 -271.599406)
		(width 0.1143)
		(layer "In5.Cu")
		(net "P5E_PEX3_STN1_RX_DP<27>")
	)
	(segment
		(start 393.492482 -140.950442)
		(end 391.301478 -142.94231)
		(width 0.1651)
		(layer "In5.Cu")
		(net "P5E_PEX3_STN1_RX_DP<27>")
	)
	(segment
		(start 418.285168 -275.570188)
		(end 418.399468 -275.684488)
		(width 0.1143)
		(layer "In5.Cu")
		(net "P5E_PEX3_STN1_RX_DP<27>")
	)
	(segment
		(start 395.992604 -133.614922)
		(end 395.99235 -133.61543)
		(width 0.1651)
		(layer "In5.Cu")
		(net "P5E_PEX3_STN1_RX_DP<27>")
	)
	(segment
		(start 388.096252 -147.561554)
		(end 388.099046 -147.60702)
		(width 0.1651)
		(layer "In5.Cu")
		(net "P5E_PEX3_STN1_RX_DP<27>")
	)
	(segment
		(start 389.483346 -161.41446)
		(end 417.783772 -267.785596)
		(width 0.1651)
		(layer "In5.Cu")
		(net "P5E_PEX3_STN1_RX_DP<27>")
	)
	(segment
		(start 393.644374 -140.451078)
		(end 393.492482 -140.950442)
		(width 0.1651)
		(layer "In5.Cu")
		(net "P5E_PEX3_STN1_RX_DP<27>")
	)
	(segment
		(start 418.399468 -275.684488)
		(end 418.399468 -275.949918)
		(width 0.1143)
		(layer "In5.Cu")
		(net "P5E_PEX3_STN1_RX_DP<27>")
	)
	(segment
		(start 417.783772 -271.599406)
		(end 417.829492 -271.645126)
		(width 0.1143)
		(layer "In5.Cu")
		(net "P5E_PEX3_STN1_RX_DP<27>")
	)
	(segment
		(start 417.829492 -271.645126)
		(end 417.829492 -275.355304)
		(width 0.1143)
		(layer "In5.Cu")
		(net "P5E_PEX3_STN1_RX_DP<27>")
	)
	(segment
		(start 388.099046 -147.60702)
		(end 388.0993 -147.60702)
		(width 0.1651)
		(layer "In5.Cu")
		(net "P5E_PEX3_STN1_RX_DP<27>")
	)
	(segment
		(start 388.366254 -146.533108)
		(end 388.096252 -147.561554)
		(width 0.1651)
		(layer "In5.Cu")
		(net "P5E_PEX3_STN1_RX_DP<27>")
	)
	(segment
		(start 399.808954 -124.913644)
		(end 399.269458 -125.45314)
		(width 0.1651)
		(layer "In5.Cu")
		(net "P5E_PEX3_STN1_RX_DP<27>")
	)
	(segment
		(start 397.806418 -130.590798)
		(end 396.521178 -132.492242)
		(width 0.1651)
		(layer "In5.Cu")
		(net "P5E_PEX3_STN1_RX_DP<27>")
	)
	(segment
		(start 393.64412 -140.451078)
		(end 393.644374 -140.451078)
		(width 0.1651)
		(layer "In5.Cu")
		(net "P5E_PEX3_STN1_RX_DP<27>")
	)
	(segment
		(start 417.783772 -267.785596)
		(end 417.783772 -271.570958)
		(width 0.1651)
		(layer "In5.Cu")
		(net "P5E_PEX3_STN1_RX_DP<27>")
	)
	(segment
		(start 388.0993 -147.60702)
		(end 388.708392 -157.041342)
		(width 0.1651)
		(layer "In5.Cu")
		(net "P5E_PEX3_STN1_RX_DP<27>")
	)
	(segment
		(start 396.521178 -132.492242)
		(end 395.992604 -133.614922)
		(width 0.1651)
		(layer "In5.Cu")
		(net "P5E_PEX3_STN1_RX_DP<27>")
	)
	(segment
		(start 391.301478 -142.94231)
		(end 390.320784 -143.910304)
		(width 0.1651)
		(layer "In5.Cu")
		(net "P5E_PEX3_STN1_RX_DP<27>")
	)
	(segment
		(start 400.25193 -124.913644)
		(end 399.808954 -124.913644)
		(width 0.1651)
		(layer "In5.Cu")
		(net "P5E_PEX3_STN1_RX_DP<27>")
	)
	(segment
		(start 417.829492 -275.355304)
		(end 418.044376 -275.570188)
		(width 0.1143)
		(layer "In5.Cu")
		(net "P5E_PEX3_STN1_RX_DP<27>")
	)
	(segment
		(start 398.342866 -129.306574)
		(end 397.806418 -130.590798)
		(width 0.1651)
		(layer "In5.Cu")
		(net "P5E_PEX3_STN1_RX_DP<27>")
	)
	(segment
		(start 390.320784 -143.910304)
		(end 388.366254 -146.533108)
		(width 0.1651)
		(layer "In5.Cu")
		(net "P5E_PEX3_STN1_RX_DP<27>")
	)
	(segment
		(start 398.34312 -129.306066)
		(end 398.342866 -129.306574)
		(width 0.1651)
		(layer "In5.Cu")
		(net "P5E_PEX3_STN1_RX_DP<27>")
	)
	(segment
		(start 418.044376 -275.570188)
		(end 418.285168 -275.570188)
		(width 0.1143)
		(layer "In5.Cu")
		(net "P5E_PEX3_STN1_RX_DP<27>")
	)
	(segment
		(start 395.99235 -133.61543)
		(end 395.228318 -135.238236)
		(width 0.1651)
		(layer "In5.Cu")
		(net "P5E_PEX3_STN1_RX_DP<27>")
	)
	(segment
		(start 398.79143 -128.23317)
		(end 398.34312 -129.306066)
		(width 0.1651)
		(layer "In5.Cu")
		(net "P5E_PEX3_STN1_RX_DP<27>")
	)
	(segment
		(start 398.94256 -155.360116)
		(end 399.812002 -155.360116)
		(width 0.13208)
		(layer "F.Cu")
		(net "NIC6_SLOT_ID1")
	)
	(segment
		(start 399.812002 -155.360116)
		(end 400.050254 -155.598368)
		(width 0.13208)
		(layer "F.Cu")
		(net "NIC6_SLOT_ID1")
	)
	(via
		(at 400.050254 -155.598368)
		(size 0.508)
		(drill 0.254)
		(layers "F.Cu" "B.Cu")
		(net "NIC6_SLOT_ID1")
	)
	(segment
		(start 398.663414 -155.0416)
		(end 399.220182 -155.598368)
		(width 0.13208)
		(layer "B.Cu")
		(net "NIC6_SLOT_ID1")
	)
	(segment
		(start 398.25549 -155.0416)
		(end 398.663414 -155.0416)
		(width 0.13208)
		(layer "B.Cu")
		(net "NIC6_SLOT_ID1")
	)
	(segment
		(start 398.25549 -156.0576)
		(end 398.25549 -155.0416)
		(width 0.13208)
		(layer "B.Cu")
		(net "NIC6_SLOT_ID1")
	)
	(segment
		(start 399.220182 -155.598368)
		(end 400.050254 -155.598368)
		(width 0.13208)
		(layer "B.Cu")
		(net "NIC6_SLOT_ID1")
	)
	(segment
		(start 67.884802 -345.170506)
		(end 67.884802 -344.539062)
		(width 0.13462)
		(layer "F.Cu")
		(net "P5E_PEX0_STN6_TX_C_DP<109>")
	)
	(segment
		(start 67.884802 -344.539062)
		(end 67.564762 -344.219022)
		(width 0.13462)
		(layer "F.Cu")
		(net "P5E_PEX0_STN6_TX_C_DP<109>")
	)
	(segment
		(start 67.590162 -345.465146)
		(end 67.884802 -345.170506)
		(width 0.13462)
		(layer "F.Cu")
		(net "P5E_PEX0_STN6_TX_C_DP<109>")
	)
	(segment
		(start 76.436982 -408.699208)
		(end 76.886054 -408.699208)
		(width 0.1651)
		(layer "In13.Cu")
		(net "P5E_PEX0_STN6_TX_C_DP<109>")
	)
	(segment
		(start 68.838064 -389.937498)
		(end 66.97345 -388.07263)
		(width 0.1651)
		(layer "In13.Cu")
		(net "P5E_PEX0_STN6_TX_C_DP<109>")
	)
	(segment
		(start 76.309982 -408.190192)
		(end 76.309982 -408.572208)
		(width 0.1651)
		(layer "In13.Cu")
		(net "P5E_PEX0_STN6_TX_C_DP<109>")
	)
	(segment
		(start 76.666598 -394.412978)
		(end 75.800458 -393.834366)
		(width 0.1651)
		(layer "In13.Cu")
		(net "P5E_PEX0_STN6_TX_C_DP<109>")
	)
	(segment
		(start 74.488548 -392.957812)
		(end 74.051922 -392.724386)
		(width 0.1651)
		(layer "In13.Cu")
		(net "P5E_PEX0_STN6_TX_C_DP<109>")
	)
	(segment
		(start 67.880992 -346.311728)
		(end 67.880992 -345.755976)
		(width 0.1651)
		(layer "In13.Cu")
		(net "P5E_PEX0_STN6_TX_C_DP<109>")
	)
	(segment
		(start 75.229974 -393.590526)
		(end 75.198478 -393.43203)
		(width 0.1651)
		(layer "In13.Cu")
		(net "P5E_PEX0_STN6_TX_C_DP<109>")
	)
	(segment
		(start 67.880992 -345.755976)
		(end 67.590162 -345.465146)
		(width 0.1651)
		(layer "In13.Cu")
		(net "P5E_PEX0_STN6_TX_C_DP<109>")
	)
	(segment
		(start 77.202284 -408.382978)
		(end 77.202284 -394.948664)
		(width 0.1651)
		(layer "In13.Cu")
		(net "P5E_PEX0_STN6_TX_C_DP<109>")
	)
	(segment
		(start 65.392554 -382.1557)
		(end 65.748408 -367.354104)
		(width 0.1651)
		(layer "In13.Cu")
		(net "P5E_PEX0_STN6_TX_C_DP<109>")
	)
	(segment
		(start 77.202284 -394.948664)
		(end 76.666598 -394.412978)
		(width 0.1651)
		(layer "In13.Cu")
		(net "P5E_PEX0_STN6_TX_C_DP<109>")
	)
	(segment
		(start 75.641962 -393.865862)
		(end 75.229974 -393.590526)
		(width 0.1651)
		(layer "In13.Cu")
		(net "P5E_PEX0_STN6_TX_C_DP<109>")
	)
	(segment
		(start 74.051922 -392.724386)
		(end 73.897236 -392.771376)
		(width 0.1651)
		(layer "In13.Cu")
		(net "P5E_PEX0_STN6_TX_C_DP<109>")
	)
	(segment
		(start 73.413112 -392.38301)
		(end 68.838064 -389.937498)
		(width 0.1651)
		(layer "In13.Cu")
		(net "P5E_PEX0_STN6_TX_C_DP<109>")
	)
	(segment
		(start 66.97345 -388.07263)
		(end 65.392554 -384.255772)
		(width 0.1651)
		(layer "In13.Cu")
		(net "P5E_PEX0_STN6_TX_C_DP<109>")
	)
	(segment
		(start 75.198478 -393.43203)
		(end 74.488548 -392.957812)
		(width 0.1651)
		(layer "In13.Cu")
		(net "P5E_PEX0_STN6_TX_C_DP<109>")
	)
	(segment
		(start 66.326512 -359.381298)
		(end 66.326512 -347.866208)
		(width 0.1651)
		(layer "In13.Cu")
		(net "P5E_PEX0_STN6_TX_C_DP<109>")
	)
	(segment
		(start 73.460102 -392.537696)
		(end 73.413112 -392.38301)
		(width 0.1651)
		(layer "In13.Cu")
		(net "P5E_PEX0_STN6_TX_C_DP<109>")
	)
	(segment
		(start 76.886054 -408.699208)
		(end 77.202284 -408.382978)
		(width 0.1651)
		(layer "In13.Cu")
		(net "P5E_PEX0_STN6_TX_C_DP<109>")
	)
	(segment
		(start 65.748408 -367.354104)
		(end 66.120518 -363.57687)
		(width 0.1651)
		(layer "In13.Cu")
		(net "P5E_PEX0_STN6_TX_C_DP<109>")
	)
	(segment
		(start 76.309982 -408.572208)
		(end 76.436982 -408.699208)
		(width 0.1651)
		(layer "In13.Cu")
		(net "P5E_PEX0_STN6_TX_C_DP<109>")
	)
	(segment
		(start 66.326512 -347.866208)
		(end 67.880992 -346.311728)
		(width 0.1651)
		(layer "In13.Cu")
		(net "P5E_PEX0_STN6_TX_C_DP<109>")
	)
	(segment
		(start 66.120518 -363.57687)
		(end 66.326512 -359.381298)
		(width 0.1651)
		(layer "In13.Cu")
		(net "P5E_PEX0_STN6_TX_C_DP<109>")
	)
	(segment
		(start 75.800458 -393.834366)
		(end 75.641962 -393.865862)
		(width 0.1651)
		(layer "In13.Cu")
		(net "P5E_PEX0_STN6_TX_C_DP<109>")
	)
	(segment
		(start 73.897236 -392.771376)
		(end 73.460102 -392.537696)
		(width 0.1651)
		(layer "In13.Cu")
		(net "P5E_PEX0_STN6_TX_C_DP<109>")
	)
	(segment
		(start 65.392554 -384.255772)
		(end 65.392554 -382.1557)
		(width 0.1651)
		(layer "In13.Cu")
		(net "P5E_PEX0_STN6_TX_C_DP<109>")
	)
	(segment
		(start 178.119532 -30.62732)
		(end 175.605694 -30.62732)
		(width 0.13462)
		(layer "F.Cu")
		(net "P5E_PEX1_STN2_RX_DP<37>")
	)
	(segment
		(start 178.764946 -30.790134)
		(end 178.282346 -30.790134)
		(width 0.13462)
		(layer "F.Cu")
		(net "P5E_PEX1_STN2_RX_DP<37>")
	)
	(segment
		(start 175.605694 -30.62732)
		(end 175.310546 -30.922468)
		(width 0.13462)
		(layer "F.Cu")
		(net "P5E_PEX1_STN2_RX_DP<37>")
	)
	(segment
		(start 178.282346 -30.790134)
		(end 178.119532 -30.62732)
		(width 0.13462)
		(layer "F.Cu")
		(net "P5E_PEX1_STN2_RX_DP<37>")
	)
	(segment
		(start 176.680114 -30.733238)
		(end 176.578514 -30.631638)
		(width 0.1651)
		(layer "In7.Cu")
		(net "P5E_PEX1_STN2_RX_DP<37>")
	)
	(segment
		(start 169.434002 -271.3736)
		(end 169.434002 -271.345152)
		(width 0.1143)
		(layer "In7.Cu")
		(net "P5E_PEX1_STN2_RX_DP<37>")
	)
	(segment
		(start 179.229512 -32.088836)
		(end 178.8795 -31.738824)
		(width 0.1651)
		(layer "In7.Cu")
		(net "P5E_PEX1_STN2_RX_DP<37>")
	)
	(segment
		(start 169.434002 -271.345152)
		(end 169.434002 -266.379706)
		(width 0.1651)
		(layer "In7.Cu")
		(net "P5E_PEX1_STN2_RX_DP<37>")
	)
	(segment
		(start 178.702716 -39.321486)
		(end 178.680872 -37.940234)
		(width 0.1651)
		(layer "In7.Cu")
		(net "P5E_PEX1_STN2_RX_DP<37>")
	)
	(segment
		(start 169.565066 -264.886186)
		(end 179.93868 -68.490084)
		(width 0.1651)
		(layer "In7.Cu")
		(net "P5E_PEX1_STN2_RX_DP<37>")
	)
	(segment
		(start 169.479722 -271.41932)
		(end 169.434002 -271.3736)
		(width 0.1143)
		(layer "In7.Cu")
		(net "P5E_PEX1_STN2_RX_DP<37>")
	)
	(segment
		(start 169.742104 -273.670014)
		(end 169.479722 -273.407632)
		(width 0.1143)
		(layer "In7.Cu")
		(net "P5E_PEX1_STN2_RX_DP<37>")
	)
	(segment
		(start 169.479722 -273.407632)
		(end 169.479722 -271.41932)
		(width 0.1143)
		(layer "In7.Cu")
		(net "P5E_PEX1_STN2_RX_DP<37>")
	)
	(segment
		(start 176.578514 -30.631638)
		(end 175.601376 -30.631638)
		(width 0.1651)
		(layer "In7.Cu")
		(net "P5E_PEX1_STN2_RX_DP<37>")
	)
	(segment
		(start 178.680872 -37.940234)
		(end 179.206144 -34.981642)
		(width 0.1651)
		(layer "In7.Cu")
		(net "P5E_PEX1_STN2_RX_DP<37>")
	)
	(segment
		(start 178.753008 -39.991792)
		(end 178.702716 -39.321486)
		(width 0.1651)
		(layer "In7.Cu")
		(net "P5E_PEX1_STN2_RX_DP<37>")
	)
	(segment
		(start 179.93868 -68.490084)
		(end 180.12283 -50.12817)
		(width 0.1651)
		(layer "In7.Cu")
		(net "P5E_PEX1_STN2_RX_DP<37>")
	)
	(segment
		(start 179.206144 -34.981642)
		(end 179.229512 -32.088836)
		(width 0.1651)
		(layer "In7.Cu")
		(net "P5E_PEX1_STN2_RX_DP<37>")
	)
	(segment
		(start 169.434002 -266.379706)
		(end 169.565066 -264.886186)
		(width 0.1651)
		(layer "In7.Cu")
		(net "P5E_PEX1_STN2_RX_DP<37>")
	)
	(segment
		(start 177.175414 -30.733238)
		(end 176.680114 -30.733238)
		(width 0.1651)
		(layer "In7.Cu")
		(net "P5E_PEX1_STN2_RX_DP<37>")
	)
	(segment
		(start 170.049952 -273.784314)
		(end 169.935652 -273.670014)
		(width 0.1143)
		(layer "In7.Cu")
		(net "P5E_PEX1_STN2_RX_DP<37>")
	)
	(segment
		(start 175.601376 -30.631638)
		(end 175.310546 -30.922468)
		(width 0.1651)
		(layer "In7.Cu")
		(net "P5E_PEX1_STN2_RX_DP<37>")
	)
	(segment
		(start 180.12283 -50.12817)
		(end 178.753008 -39.991792)
		(width 0.1651)
		(layer "In7.Cu")
		(net "P5E_PEX1_STN2_RX_DP<37>")
	)
	(segment
		(start 169.935652 -273.670014)
		(end 169.742104 -273.670014)
		(width 0.1143)
		(layer "In7.Cu")
		(net "P5E_PEX1_STN2_RX_DP<37>")
	)
	(segment
		(start 177.772314 -30.631638)
		(end 177.277014 -30.631638)
		(width 0.1651)
		(layer "In7.Cu")
		(net "P5E_PEX1_STN2_RX_DP<37>")
	)
	(segment
		(start 178.385216 -31.388304)
		(end 178.385216 -31.24454)
		(width 0.1651)
		(layer "In7.Cu")
		(net "P5E_PEX1_STN2_RX_DP<37>")
	)
	(segment
		(start 170.049952 -274.049744)
		(end 170.049952 -273.784314)
		(width 0.1143)
		(layer "In7.Cu")
		(net "P5E_PEX1_STN2_RX_DP<37>")
	)
	(segment
		(start 177.277014 -30.631638)
		(end 177.175414 -30.733238)
		(width 0.1651)
		(layer "In7.Cu")
		(net "P5E_PEX1_STN2_RX_DP<37>")
	)
	(segment
		(start 178.8795 -31.738824)
		(end 178.735736 -31.738824)
		(width 0.1651)
		(layer "In7.Cu")
		(net "P5E_PEX1_STN2_RX_DP<37>")
	)
	(segment
		(start 178.735736 -31.738824)
		(end 178.385216 -31.388304)
		(width 0.1651)
		(layer "In7.Cu")
		(net "P5E_PEX1_STN2_RX_DP<37>")
	)
	(segment
		(start 178.385216 -31.24454)
		(end 177.772314 -30.631638)
		(width 0.1651)
		(layer "In7.Cu")
		(net "P5E_PEX1_STN2_RX_DP<37>")
	)
	(segment
		(start 319.289684 -356.831646)
		(end 319.289684 -357.46309)
		(width 0.13462)
		(layer "F.Cu")
		(net "P5E_PEX2_STN6_TX_C_DN<108>")
	)
	(segment
		(start 319.609724 -356.511606)
		(end 319.289684 -356.831646)
		(width 0.13462)
		(layer "F.Cu")
		(net "P5E_PEX2_STN6_TX_C_DN<108>")
	)
	(segment
		(start 319.289684 -357.46309)
		(end 319.584324 -357.75773)
		(width 0.13462)
		(layer "F.Cu")
		(net "P5E_PEX2_STN6_TX_C_DN<108>")
	)
	(segment
		(start 337.822032 -393.605004)
		(end 335.140554 -391.768076)
		(width 0.1651)
		(layer "In13.Cu")
		(net "P5E_PEX2_STN6_TX_C_DN<108>")
	)
	(segment
		(start 335.140554 -391.768076)
		(end 330.09332 -389.99795)
		(width 0.1651)
		(layer "In13.Cu")
		(net "P5E_PEX2_STN6_TX_C_DN<108>")
	)
	(segment
		(start 330.09332 -389.99795)
		(end 326.85482 -387.33095)
		(width 0.1651)
		(layer "In13.Cu")
		(net "P5E_PEX2_STN6_TX_C_DN<108>")
	)
	(segment
		(start 326.85482 -387.33095)
		(end 319.293494 -358.92486)
		(width 0.1651)
		(layer "In13.Cu")
		(net "P5E_PEX2_STN6_TX_C_DN<108>")
	)
	(segment
		(start 339.017356 -395.00429)
		(end 337.822032 -393.605004)
		(width 0.1651)
		(layer "In13.Cu")
		(net "P5E_PEX2_STN6_TX_C_DN<108>")
	)
	(segment
		(start 338.764118 -410.080968)
		(end 339.215984 -409.629102)
		(width 0.1651)
		(layer "In13.Cu")
		(net "P5E_PEX2_STN6_TX_C_DN<108>")
	)
	(segment
		(start 339.215984 -409.629102)
		(end 339.215984 -395.70533)
		(width 0.1651)
		(layer "In13.Cu")
		(net "P5E_PEX2_STN6_TX_C_DN<108>")
	)
	(segment
		(start 338.228178 -410.080968)
		(end 338.764118 -410.080968)
		(width 0.1651)
		(layer "In13.Cu")
		(net "P5E_PEX2_STN6_TX_C_DN<108>")
	)
	(segment
		(start 338.090002 -410.219144)
		(end 338.228178 -410.080968)
		(width 0.1651)
		(layer "In13.Cu")
		(net "P5E_PEX2_STN6_TX_C_DN<108>")
	)
	(segment
		(start 339.215984 -395.70533)
		(end 339.017356 -395.00429)
		(width 0.1651)
		(layer "In13.Cu")
		(net "P5E_PEX2_STN6_TX_C_DN<108>")
	)
	(segment
		(start 319.293494 -358.04856)
		(end 319.584324 -357.75773)
		(width 0.1651)
		(layer "In13.Cu")
		(net "P5E_PEX2_STN6_TX_C_DN<108>")
	)
	(segment
		(start 319.293494 -358.92486)
		(end 319.293494 -358.04856)
		(width 0.1651)
		(layer "In13.Cu")
		(net "P5E_PEX2_STN6_TX_C_DN<108>")
	)
	(segment
		(start 338.090002 -410.589984)
		(end 338.090002 -410.219144)
		(width 0.1651)
		(layer "In13.Cu")
		(net "P5E_PEX2_STN6_TX_C_DN<108>")
	)
	(segment
		(start 388.170674 -125.1966)
		(end 393.68095 -125.1966)
		(width 0.13462)
		(layer "F.Cu")
		(net "P5E_PEX3_STN1_TX_C_DP<27>")
	)
	(segment
		(start 393.839446 -125.355096)
		(end 394.342366 -125.355096)
		(width 0.13462)
		(layer "F.Cu")
		(net "P5E_PEX3_STN1_TX_C_DP<27>")
	)
	(segment
		(start 387.847332 -125.519942)
		(end 388.170674 -125.1966)
		(width 0.13462)
		(layer "F.Cu")
		(net "P5E_PEX3_STN1_TX_C_DP<27>")
	)
	(segment
		(start 393.68095 -125.1966)
		(end 393.839446 -125.355096)
		(width 0.13462)
		(layer "F.Cu")
		(net "P5E_PEX3_STN1_TX_C_DP<27>")
	)
	(segment
		(start 388.696708 -152.719278)
		(end 390.277604 -152.719278)
		(width 0.13208)
		(layer "F.Cu")
		(net "NCSI_NIC6_RXD1")
	)
	(segment
		(start 387.299962 -152.295352)
		(end 388.272782 -152.295352)
		(width 0.13208)
		(layer "F.Cu")
		(net "NCSI_NIC6_RXD1")
	)
	(segment
		(start 391.718292 -154.159966)
		(end 394.342366 -154.159966)
		(width 0.13208)
		(layer "F.Cu")
		(net "NCSI_NIC6_RXD1")
	)
	(segment
		(start 390.277604 -152.719278)
		(end 391.718292 -154.159966)
		(width 0.13208)
		(layer "F.Cu")
		(net "NCSI_NIC6_RXD1")
	)
	(segment
		(start 388.272782 -152.295352)
		(end 388.696708 -152.719278)
		(width 0.13208)
		(layer "F.Cu")
		(net "NCSI_NIC6_RXD1")
	)
	(via
		(at 388.696708 -152.719278)
		(size 0.762)
		(drill 0.381)
		(layers "F.Cu" "B.Cu")
		(net "NCSI_NIC6_RXD1")
	)
	(segment
		(start 85.453982 -367.662968)
		(end 79.483458 -363.67339)
		(width 0.1651)
		(layer "In9.Cu")
		(net "P5E_PEX0_STN6_RX_DP<97>")
	)
	(segment
		(start 86.002114 -374.525032)
		(end 86.002114 -368.9858)
		(width 0.1651)
		(layer "In9.Cu")
		(net "P5E_PEX0_STN6_RX_DP<97>")
	)
	(segment
		(start 56.898286 -325.038466)
		(end 56.178958 -323.302376)
		(width 0.1651)
		(layer "In9.Cu")
		(net "P5E_PEX0_STN6_RX_DP<97>")
	)
	(segment
		(start 56.711088 -316.229492)
		(end 56.799988 -316.140592)
		(width 0.1143)
		(layer "In9.Cu")
		(net "P5E_PEX0_STN6_RX_DP<97>")
	)
	(segment
		(start 56.229758 -319.921128)
		(end 56.229758 -316.506098)
		(width 0.1143)
		(layer "In9.Cu")
		(net "P5E_PEX0_STN6_RX_DP<97>")
	)
	(segment
		(start 78.310994 -363.027468)
		(end 77.899006 -362.752132)
		(width 0.1651)
		(layer "In9.Cu")
		(net "P5E_PEX0_STN6_RX_DP<97>")
	)
	(segment
		(start 74.039222 -360.035602)
		(end 72.983598 -358.979978)
		(width 0.1651)
		(layer "In9.Cu")
		(net "P5E_PEX0_STN6_RX_DP<97>")
	)
	(segment
		(start 77.455522 -362.318554)
		(end 77.297026 -362.35005)
		(width 0.1651)
		(layer "In9.Cu")
		(net "P5E_PEX0_STN6_RX_DP<97>")
	)
	(segment
		(start 56.229758 -316.506098)
		(end 56.506364 -316.229492)
		(width 0.1143)
		(layer "In9.Cu")
		(net "P5E_PEX0_STN6_RX_DP<97>")
	)
	(segment
		(start 85.236812 -374.899174)
		(end 85.627972 -374.899174)
		(width 0.1651)
		(layer "In9.Cu")
		(net "P5E_PEX0_STN6_RX_DP<97>")
	)
	(segment
		(start 76.853542 -361.916218)
		(end 74.039222 -360.035602)
		(width 0.1651)
		(layer "In9.Cu")
		(net "P5E_PEX0_STN6_RX_DP<97>")
	)
	(segment
		(start 56.506364 -316.229492)
		(end 56.711088 -316.229492)
		(width 0.1143)
		(layer "In9.Cu")
		(net "P5E_PEX0_STN6_RX_DP<97>")
	)
	(segment
		(start 56.184038 -319.995296)
		(end 56.184038 -319.966848)
		(width 0.1143)
		(layer "In9.Cu")
		(net "P5E_PEX0_STN6_RX_DP<97>")
	)
	(segment
		(start 77.297026 -362.35005)
		(end 76.885038 -362.074714)
		(width 0.1651)
		(layer "In9.Cu")
		(net "P5E_PEX0_STN6_RX_DP<97>")
	)
	(segment
		(start 56.178958 -323.302376)
		(end 56.184038 -323.297296)
		(width 0.1651)
		(layer "In9.Cu")
		(net "P5E_PEX0_STN6_RX_DP<97>")
	)
	(segment
		(start 72.544432 -342.058244)
		(end 71.573136 -339.713316)
		(width 0.1651)
		(layer "In9.Cu")
		(net "P5E_PEX0_STN6_RX_DP<97>")
	)
	(segment
		(start 79.324708 -363.704886)
		(end 78.91272 -363.42955)
		(width 0.1651)
		(layer "In9.Cu")
		(net "P5E_PEX0_STN6_RX_DP<97>")
	)
	(segment
		(start 78.881224 -363.271054)
		(end 78.46949 -362.995972)
		(width 0.1651)
		(layer "In9.Cu")
		(net "P5E_PEX0_STN6_RX_DP<97>")
	)
	(segment
		(start 72.983598 -358.979978)
		(end 72.544432 -357.919528)
		(width 0.1651)
		(layer "In9.Cu")
		(net "P5E_PEX0_STN6_RX_DP<97>")
	)
	(segment
		(start 71.573136 -339.713316)
		(end 56.898286 -325.038466)
		(width 0.1651)
		(layer "In9.Cu")
		(net "P5E_PEX0_STN6_RX_DP<97>")
	)
	(segment
		(start 77.899006 -362.752132)
		(end 77.867256 -362.593636)
		(width 0.1651)
		(layer "In9.Cu")
		(net "P5E_PEX0_STN6_RX_DP<97>")
	)
	(segment
		(start 78.91272 -363.42955)
		(end 78.881224 -363.271054)
		(width 0.1651)
		(layer "In9.Cu")
		(net "P5E_PEX0_STN6_RX_DP<97>")
	)
	(segment
		(start 76.885038 -362.074714)
		(end 76.853542 -361.916218)
		(width 0.1651)
		(layer "In9.Cu")
		(net "P5E_PEX0_STN6_RX_DP<97>")
	)
	(segment
		(start 85.627972 -374.899174)
		(end 86.002114 -374.525032)
		(width 0.1651)
		(layer "In9.Cu")
		(net "P5E_PEX0_STN6_RX_DP<97>")
	)
	(segment
		(start 56.184038 -319.966848)
		(end 56.229758 -319.921128)
		(width 0.1143)
		(layer "In9.Cu")
		(net "P5E_PEX0_STN6_RX_DP<97>")
	)
	(segment
		(start 77.867256 -362.593636)
		(end 77.455522 -362.318554)
		(width 0.1651)
		(layer "In9.Cu")
		(net "P5E_PEX0_STN6_RX_DP<97>")
	)
	(segment
		(start 85.109812 -374.772174)
		(end 85.236812 -374.899174)
		(width 0.1651)
		(layer "In9.Cu")
		(net "P5E_PEX0_STN6_RX_DP<97>")
	)
	(segment
		(start 56.184038 -323.297296)
		(end 56.184038 -319.995296)
		(width 0.1651)
		(layer "In9.Cu")
		(net "P5E_PEX0_STN6_RX_DP<97>")
	)
	(segment
		(start 56.799988 -316.140592)
		(end 56.799988 -315.849762)
		(width 0.1143)
		(layer "In9.Cu")
		(net "P5E_PEX0_STN6_RX_DP<97>")
	)
	(segment
		(start 86.002114 -368.9858)
		(end 85.453982 -367.662968)
		(width 0.1651)
		(layer "In9.Cu")
		(net "P5E_PEX0_STN6_RX_DP<97>")
	)
	(segment
		(start 79.483458 -363.67339)
		(end 79.324708 -363.704886)
		(width 0.1651)
		(layer "In9.Cu")
		(net "P5E_PEX0_STN6_RX_DP<97>")
	)
	(segment
		(start 85.109812 -374.390158)
		(end 85.109812 -374.772174)
		(width 0.1651)
		(layer "In9.Cu")
		(net "P5E_PEX0_STN6_RX_DP<97>")
	)
	(segment
		(start 72.544432 -357.919528)
		(end 72.544432 -342.058244)
		(width 0.1651)
		(layer "In9.Cu")
		(net "P5E_PEX0_STN6_RX_DP<97>")
	)
	(segment
		(start 78.46949 -362.995972)
		(end 78.310994 -363.027468)
		(width 0.1651)
		(layer "In9.Cu")
		(net "P5E_PEX0_STN6_RX_DP<97>")
	)
	(segment
		(start 185.62574 -29.139642)
		(end 185.315098 -28.829)
		(width 0.13462)
		(layer "F.Cu")
		(net "P5E_PEX1_STN2_TX_C_DP<36>")
	)
	(segment
		(start 183.864504 -28.990036)
		(end 183.364886 -28.990036)
		(width 0.13462)
		(layer "F.Cu")
		(net "P5E_PEX1_STN2_TX_C_DP<36>")
	)
	(segment
		(start 185.315098 -28.829)
		(end 184.02554 -28.829)
		(width 0.13462)
		(layer "F.Cu")
		(net "P5E_PEX1_STN2_TX_C_DP<36>")
	)
	(segment
		(start 184.02554 -28.829)
		(end 183.864504 -28.990036)
		(width 0.13462)
		(layer "F.Cu")
		(net "P5E_PEX1_STN2_TX_C_DP<36>")
	)
	(segment
		(start 325.233284 -356.831646)
		(end 325.233284 -357.46309)
		(width 0.13462)
		(layer "F.Cu")
		(net "P5E_PEX2_STN6_TX_C_DP<105>")
	)
	(segment
		(start 325.233284 -357.46309)
		(end 324.938644 -357.75773)
		(width 0.13462)
		(layer "F.Cu")
		(net "P5E_PEX2_STN6_TX_C_DP<105>")
	)
	(segment
		(start 324.913244 -356.511606)
		(end 325.233284 -356.831646)
		(width 0.13462)
		(layer "F.Cu")
		(net "P5E_PEX2_STN6_TX_C_DP<105>")
	)
	(segment
		(start 345.53398 -408.412442)
		(end 345.247214 -408.699208)
		(width 0.1651)
		(layer "In13.Cu")
		(net "P5E_PEX2_STN6_TX_C_DP<105>")
	)
	(segment
		(start 342.09101 -392.649456)
		(end 342.505284 -392.92149)
		(width 0.1651)
		(layer "In13.Cu")
		(net "P5E_PEX2_STN6_TX_C_DP<105>")
	)
	(segment
		(start 343.683082 -393.557506)
		(end 345.00058 -394.422376)
		(width 0.1651)
		(layer "In13.Cu")
		(net "P5E_PEX2_STN6_TX_C_DP<105>")
	)
	(segment
		(start 325.232522 -358.97185)
		(end 329.282806 -385.8387)
		(width 0.1651)
		(layer "In13.Cu")
		(net "P5E_PEX2_STN6_TX_C_DP<105>")
	)
	(segment
		(start 331.313028 -387.4516)
		(end 337.945476 -389.791702)
		(width 0.1651)
		(layer "In13.Cu")
		(net "P5E_PEX2_STN6_TX_C_DP<105>")
	)
	(segment
		(start 345.53398 -395.503908)
		(end 345.53398 -408.412442)
		(width 0.1651)
		(layer "In13.Cu")
		(net "P5E_PEX2_STN6_TX_C_DP<105>")
	)
	(segment
		(start 341.644224 -392.219434)
		(end 342.058244 -392.491214)
		(width 0.1651)
		(layer "In13.Cu")
		(net "P5E_PEX2_STN6_TX_C_DP<105>")
	)
	(segment
		(start 325.229474 -358.04856)
		(end 325.229474 -358.968802)
		(width 0.1651)
		(layer "In13.Cu")
		(net "P5E_PEX2_STN6_TX_C_DP<105>")
	)
	(segment
		(start 345.247214 -408.699208)
		(end 344.816938 -408.699208)
		(width 0.1651)
		(layer "In13.Cu")
		(net "P5E_PEX2_STN6_TX_C_DP<105>")
	)
	(segment
		(start 342.505284 -392.92149)
		(end 342.663526 -392.88847)
		(width 0.1651)
		(layer "In13.Cu")
		(net "P5E_PEX2_STN6_TX_C_DP<105>")
	)
	(segment
		(start 342.663526 -392.88847)
		(end 343.077546 -393.16025)
		(width 0.1651)
		(layer "In13.Cu")
		(net "P5E_PEX2_STN6_TX_C_DP<105>")
	)
	(segment
		(start 344.816938 -408.699208)
		(end 344.689938 -408.572208)
		(width 0.1651)
		(layer "In13.Cu")
		(net "P5E_PEX2_STN6_TX_C_DP<105>")
	)
	(segment
		(start 325.229474 -358.968802)
		(end 325.232522 -358.97185)
		(width 0.1651)
		(layer "In13.Cu")
		(net "P5E_PEX2_STN6_TX_C_DP<105>")
	)
	(segment
		(start 341.485982 -392.252454)
		(end 341.644224 -392.219434)
		(width 0.1651)
		(layer "In13.Cu")
		(net "P5E_PEX2_STN6_TX_C_DP<105>")
	)
	(segment
		(start 324.938644 -357.75773)
		(end 325.229474 -358.04856)
		(width 0.1651)
		(layer "In13.Cu")
		(net "P5E_PEX2_STN6_TX_C_DP<105>")
	)
	(segment
		(start 345.00058 -394.422376)
		(end 345.000834 -394.422884)
		(width 0.1651)
		(layer "In13.Cu")
		(net "P5E_PEX2_STN6_TX_C_DP<105>")
	)
	(segment
		(start 343.110312 -393.318492)
		(end 343.524586 -393.590526)
		(width 0.1651)
		(layer "In13.Cu")
		(net "P5E_PEX2_STN6_TX_C_DP<105>")
	)
	(segment
		(start 345.000834 -394.422884)
		(end 345.336114 -394.867892)
		(width 0.1651)
		(layer "In13.Cu")
		(net "P5E_PEX2_STN6_TX_C_DP<105>")
	)
	(segment
		(start 329.282806 -385.8387)
		(end 331.313028 -387.4516)
		(width 0.1651)
		(layer "In13.Cu")
		(net "P5E_PEX2_STN6_TX_C_DP<105>")
	)
	(segment
		(start 341.038942 -391.822178)
		(end 341.071708 -391.98042)
		(width 0.1651)
		(layer "In13.Cu")
		(net "P5E_PEX2_STN6_TX_C_DP<105>")
	)
	(segment
		(start 342.058244 -392.491214)
		(end 342.09101 -392.649456)
		(width 0.1651)
		(layer "In13.Cu")
		(net "P5E_PEX2_STN6_TX_C_DP<105>")
	)
	(segment
		(start 343.077546 -393.16025)
		(end 343.110312 -393.318492)
		(width 0.1651)
		(layer "In13.Cu")
		(net "P5E_PEX2_STN6_TX_C_DP<105>")
	)
	(segment
		(start 343.524586 -393.590526)
		(end 343.683082 -393.557506)
		(width 0.1651)
		(layer "In13.Cu")
		(net "P5E_PEX2_STN6_TX_C_DP<105>")
	)
	(segment
		(start 337.945476 -389.791702)
		(end 341.038942 -391.822178)
		(width 0.1651)
		(layer "In13.Cu")
		(net "P5E_PEX2_STN6_TX_C_DP<105>")
	)
	(segment
		(start 344.689938 -408.572208)
		(end 344.689938 -408.190192)
		(width 0.1651)
		(layer "In13.Cu")
		(net "P5E_PEX2_STN6_TX_C_DP<105>")
	)
	(segment
		(start 341.071708 -391.98042)
		(end 341.485982 -392.252454)
		(width 0.1651)
		(layer "In13.Cu")
		(net "P5E_PEX2_STN6_TX_C_DP<105>")
	)
	(segment
		(start 345.336114 -394.867892)
		(end 345.53398 -395.503908)
		(width 0.1651)
		(layer "In13.Cu")
		(net "P5E_PEX2_STN6_TX_C_DP<105>")
	)
	(segment
		(start 399.423382 -125.355096)
		(end 398.94256 -125.355096)
		(width 0.13462)
		(layer "F.Cu")
		(net "P5E_PEX3_STN1_RX_DN<27>")
	)
	(segment
		(start 400.252946 -125.1966)
		(end 399.581878 -125.1966)
		(width 0.13462)
		(layer "F.Cu")
		(net "P5E_PEX3_STN1_RX_DN<27>")
	)
	(segment
		(start 400.54276 -125.486414)
		(end 400.252946 -125.1966)
		(width 0.13462)
		(layer "F.Cu")
		(net "P5E_PEX3_STN1_RX_DN<27>")
	)
	(segment
		(start 399.581878 -125.1966)
		(end 399.423382 -125.355096)
		(width 0.13462)
		(layer "F.Cu")
		(net "P5E_PEX3_STN1_RX_DN<27>")
	)
	(segment
		(start 394.521436 -138.928094)
		(end 394.377418 -139.402312)
		(width 0.1651)
		(layer "In5.Cu")
		(net "P5E_PEX3_STN1_RX_DN<27>")
	)
	(segment
		(start 418.065712 -267.748512)
		(end 418.065712 -271.570958)
		(width 0.1651)
		(layer "In5.Cu")
		(net "P5E_PEX3_STN1_RX_DN<27>")
	)
	(segment
		(start 418.285168 -275.379688)
		(end 418.399468 -275.265388)
		(width 0.1143)
		(layer "In5.Cu")
		(net "P5E_PEX3_STN1_RX_DN<27>")
	)
	(segment
		(start 391.495534 -143.147034)
		(end 390.534144 -144.095978)
		(width 0.1651)
		(layer "In5.Cu")
		(net "P5E_PEX3_STN1_RX_DN<27>")
	)
	(segment
		(start 396.24762 -133.735318)
		(end 396.0368 -134.183374)
		(width 0.1651)
		(layer "In5.Cu")
		(net "P5E_PEX3_STN1_RX_DN<27>")
	)
	(segment
		(start 393.740132 -141.106652)
		(end 391.495534 -143.147034)
		(width 0.1651)
		(layer "In5.Cu")
		(net "P5E_PEX3_STN1_RX_DN<27>")
	)
	(segment
		(start 418.019992 -275.27631)
		(end 418.12337 -275.379688)
		(width 0.1143)
		(layer "In5.Cu")
		(net "P5E_PEX3_STN1_RX_DN<27>")
	)
	(segment
		(start 400.25193 -125.195584)
		(end 399.925794 -125.195584)
		(width 0.1651)
		(layer "In5.Cu")
		(net "P5E_PEX3_STN1_RX_DN<27>")
	)
	(segment
		(start 394.445236 -138.785346)
		(end 394.521436 -138.928094)
		(width 0.1651)
		(layer "In5.Cu")
		(net "P5E_PEX3_STN1_RX_DN<27>")
	)
	(segment
		(start 395.154404 -136.452102)
		(end 395.230604 -136.594596)
		(width 0.1651)
		(layer "In5.Cu")
		(net "P5E_PEX3_STN1_RX_DN<27>")
	)
	(segment
		(start 390.534144 -144.095978)
		(end 388.625334 -146.657822)
		(width 0.1651)
		(layer "In5.Cu")
		(net "P5E_PEX3_STN1_RX_DN<27>")
	)
	(segment
		(start 394.589254 -138.311636)
		(end 394.445236 -138.785346)
		(width 0.1651)
		(layer "In5.Cu")
		(net "P5E_PEX3_STN1_RX_DN<27>")
	)
	(segment
		(start 395.880336 -134.78383)
		(end 395.72819 -134.83844)
		(width 0.1651)
		(layer "In5.Cu")
		(net "P5E_PEX3_STN1_RX_DN<27>")
	)
	(segment
		(start 399.925794 -125.195584)
		(end 399.508472 -125.612906)
		(width 0.1651)
		(layer "In5.Cu")
		(net "P5E_PEX3_STN1_RX_DN<27>")
	)
	(segment
		(start 395.230604 -136.594596)
		(end 395.086586 -137.068814)
		(width 0.1651)
		(layer "In5.Cu")
		(net "P5E_PEX3_STN1_RX_DN<27>")
	)
	(segment
		(start 418.065712 -271.570958)
		(end 418.065712 -271.599406)
		(width 0.1143)
		(layer "In5.Cu")
		(net "P5E_PEX3_STN1_RX_DN<27>")
	)
	(segment
		(start 397.778732 -131.135628)
		(end 397.809466 -131.294378)
		(width 0.1651)
		(layer "In5.Cu")
		(net "P5E_PEX3_STN1_RX_DN<27>")
	)
	(segment
		(start 395.086586 -137.068814)
		(end 394.943584 -137.145014)
		(width 0.1651)
		(layer "In5.Cu")
		(net "P5E_PEX3_STN1_RX_DN<27>")
	)
	(segment
		(start 397.809466 -131.294378)
		(end 397.531844 -131.705096)
		(width 0.1651)
		(layer "In5.Cu")
		(net "P5E_PEX3_STN1_RX_DN<27>")
	)
	(segment
		(start 418.399468 -275.265388)
		(end 418.399468 -274.999958)
		(width 0.1143)
		(layer "In5.Cu")
		(net "P5E_PEX3_STN1_RX_DN<27>")
	)
	(segment
		(start 394.732002 -138.235436)
		(end 394.589 -138.311636)
		(width 0.1651)
		(layer "In5.Cu")
		(net "P5E_PEX3_STN1_RX_DN<27>")
	)
	(segment
		(start 418.065712 -271.599406)
		(end 418.019992 -271.645126)
		(width 0.1143)
		(layer "In5.Cu")
		(net "P5E_PEX3_STN1_RX_DN<27>")
	)
	(segment
		(start 388.380732 -147.588986)
		(end 388.988808 -157.00756)
		(width 0.1651)
		(layer "In5.Cu")
		(net "P5E_PEX3_STN1_RX_DN<27>")
	)
	(segment
		(start 389.758936 -161.3535)
		(end 418.065712 -267.748512)
		(width 0.1651)
		(layer "In5.Cu")
		(net "P5E_PEX3_STN1_RX_DN<27>")
	)
	(segment
		(start 395.72819 -134.83844)
		(end 395.492224 -135.339836)
		(width 0.1651)
		(layer "In5.Cu")
		(net "P5E_PEX3_STN1_RX_DN<27>")
	)
	(segment
		(start 394.023088 -140.56868)
		(end 393.88034 -140.64488)
		(width 0.1651)
		(layer "In5.Cu")
		(net "P5E_PEX3_STN1_RX_DN<27>")
	)
	(segment
		(start 398.603216 -129.415032)
		(end 398.055846 -130.725418)
		(width 0.1651)
		(layer "In5.Cu")
		(net "P5E_PEX3_STN1_RX_DN<27>")
	)
	(segment
		(start 399.07337 -128.289812)
		(end 398.882616 -128.746758)
		(width 0.1651)
		(layer "In5.Cu")
		(net "P5E_PEX3_STN1_RX_DN<27>")
	)
	(segment
		(start 394.090906 -139.951968)
		(end 394.167106 -140.094716)
		(width 0.1651)
		(layer "In5.Cu")
		(net "P5E_PEX3_STN1_RX_DN<27>")
	)
	(segment
		(start 396.399766 -133.680708)
		(end 396.24762 -133.735318)
		(width 0.1651)
		(layer "In5.Cu")
		(net "P5E_PEX3_STN1_RX_DN<27>")
	)
	(segment
		(start 399.07337 -126.66345)
		(end 399.07337 -128.289812)
		(width 0.1651)
		(layer "In5.Cu")
		(net "P5E_PEX3_STN1_RX_DN<27>")
	)
	(segment
		(start 394.167106 -140.094716)
		(end 394.023088 -140.56868)
		(width 0.1651)
		(layer "In5.Cu")
		(net "P5E_PEX3_STN1_RX_DN<27>")
	)
	(segment
		(start 397.531844 -131.705096)
		(end 397.373094 -131.73583)
		(width 0.1651)
		(layer "In5.Cu")
		(net "P5E_PEX3_STN1_RX_DN<27>")
	)
	(segment
		(start 398.944084 -128.89611)
		(end 398.753076 -129.353564)
		(width 0.1651)
		(layer "In5.Cu")
		(net "P5E_PEX3_STN1_RX_DN<27>")
	)
	(segment
		(start 399.508472 -125.612906)
		(end 399.07337 -126.66345)
		(width 0.1651)
		(layer "In5.Cu")
		(net "P5E_PEX3_STN1_RX_DN<27>")
	)
	(segment
		(start 396.611094 -133.232144)
		(end 396.399766 -133.680708)
		(width 0.1651)
		(layer "In5.Cu")
		(net "P5E_PEX3_STN1_RX_DN<27>")
	)
	(segment
		(start 394.234924 -139.478258)
		(end 394.090906 -139.951968)
		(width 0.1651)
		(layer "In5.Cu")
		(net "P5E_PEX3_STN1_RX_DN<27>")
	)
	(segment
		(start 394.589 -138.311636)
		(end 394.589254 -138.311636)
		(width 0.1651)
		(layer "In5.Cu")
		(net "P5E_PEX3_STN1_RX_DN<27>")
	)
	(segment
		(start 397.373094 -131.73583)
		(end 396.767304 -132.632196)
		(width 0.1651)
		(layer "In5.Cu")
		(net "P5E_PEX3_STN1_RX_DN<27>")
	)
	(segment
		(start 396.767304 -132.632196)
		(end 396.556484 -133.080252)
		(width 0.1651)
		(layer "In5.Cu")
		(net "P5E_PEX3_STN1_RX_DN<27>")
	)
	(segment
		(start 394.875766 -137.761472)
		(end 394.732002 -138.235436)
		(width 0.1651)
		(layer "In5.Cu")
		(net "P5E_PEX3_STN1_RX_DN<27>")
	)
	(segment
		(start 396.09141 -134.33552)
		(end 395.880336 -134.78383)
		(width 0.1651)
		(layer "In5.Cu")
		(net "P5E_PEX3_STN1_RX_DN<27>")
	)
	(segment
		(start 393.88034 -140.64488)
		(end 393.740132 -141.106652)
		(width 0.1651)
		(layer "In5.Cu")
		(net "P5E_PEX3_STN1_RX_DN<27>")
	)
	(segment
		(start 394.943584 -137.145014)
		(end 394.79982 -137.618724)
		(width 0.1651)
		(layer "In5.Cu")
		(net "P5E_PEX3_STN1_RX_DN<27>")
	)
	(segment
		(start 418.12337 -275.379688)
		(end 418.285168 -275.379688)
		(width 0.1143)
		(layer "In5.Cu")
		(net "P5E_PEX3_STN1_RX_DN<27>")
	)
	(segment
		(start 394.377418 -139.402312)
		(end 394.234416 -139.478258)
		(width 0.1651)
		(layer "In5.Cu")
		(net "P5E_PEX3_STN1_RX_DN<27>")
	)
	(segment
		(start 394.79982 -137.618724)
		(end 394.875766 -137.761472)
		(width 0.1651)
		(layer "In5.Cu")
		(net "P5E_PEX3_STN1_RX_DN<27>")
	)
	(segment
		(start 396.556484 -133.080252)
		(end 396.611094 -133.232144)
		(width 0.1651)
		(layer "In5.Cu")
		(net "P5E_PEX3_STN1_RX_DN<27>")
	)
	(segment
		(start 398.753076 -129.353564)
		(end 398.603216 -129.415032)
		(width 0.1651)
		(layer "In5.Cu")
		(net "P5E_PEX3_STN1_RX_DN<27>")
	)
	(segment
		(start 395.492224 -135.339836)
		(end 395.154404 -136.452102)
		(width 0.1651)
		(layer "In5.Cu")
		(net "P5E_PEX3_STN1_RX_DN<27>")
	)
	(segment
		(start 388.625334 -146.657822)
		(end 388.380732 -147.588986)
		(width 0.1651)
		(layer "In5.Cu")
		(net "P5E_PEX3_STN1_RX_DN<27>")
	)
	(segment
		(start 398.055846 -130.725418)
		(end 397.778732 -131.135628)
		(width 0.1651)
		(layer "In5.Cu")
		(net "P5E_PEX3_STN1_RX_DN<27>")
	)
	(segment
		(start 400.54276 -125.486414)
		(end 400.25193 -125.195584)
		(width 0.1651)
		(layer "In5.Cu")
		(net "P5E_PEX3_STN1_RX_DN<27>")
	)
	(segment
		(start 418.019992 -271.645126)
		(end 418.019992 -275.27631)
		(width 0.1143)
		(layer "In5.Cu")
		(net "P5E_PEX3_STN1_RX_DN<27>")
	)
	(segment
		(start 394.234416 -139.478258)
		(end 394.234924 -139.478258)
		(width 0.1651)
		(layer "In5.Cu")
		(net "P5E_PEX3_STN1_RX_DN<27>")
	)
	(segment
		(start 396.0368 -134.183374)
		(end 396.09141 -134.33552)
		(width 0.1651)
		(layer "In5.Cu")
		(net "P5E_PEX3_STN1_RX_DN<27>")
	)
	(segment
		(start 398.882616 -128.746758)
		(end 398.944084 -128.89611)
		(width 0.1651)
		(layer "In5.Cu")
		(net "P5E_PEX3_STN1_RX_DN<27>")
	)
	(segment
		(start 388.988808 -157.00756)
		(end 389.758936 -161.3535)
		(width 0.1651)
		(layer "In5.Cu")
		(net "P5E_PEX3_STN1_RX_DN<27>")
	)
	(segment
		(start 387.30809 -157.3784)
		(end 388.340854 -157.3784)
		(width 0.13208)
		(layer "F.Cu")
		(net "NIC6_DATA_IN")
	)
	(segment
		(start 391.106406 -157.73273)
		(end 392.279124 -156.560012)
		(width 0.13208)
		(layer "F.Cu")
		(net "NIC6_DATA_IN")
	)
	(segment
		(start 388.697724 -157.73527)
		(end 388.700264 -157.73273)
		(width 0.13208)
		(layer "F.Cu")
		(net "NIC6_DATA_IN")
	)
	(segment
		(start 392.279124 -156.560012)
		(end 394.342366 -156.560012)
		(width 0.13208)
		(layer "F.Cu")
		(net "NIC6_DATA_IN")
	)
	(segment
		(start 388.700264 -157.73273)
		(end 391.106406 -157.73273)
		(width 0.13208)
		(layer "F.Cu")
		(net "NIC6_DATA_IN")
	)
	(segment
		(start 388.340854 -157.3784)
		(end 388.697724 -157.73527)
		(width 0.13208)
		(layer "F.Cu")
		(net "NIC6_DATA_IN")
	)
	(via
		(at 388.697724 -157.73527)
		(size 0.762)
		(drill 0.381)
		(layers "F.Cu" "B.Cu")
		(net "NIC6_DATA_IN")
	)
	(segment
		(start 267.202158 -24.807418)
		(end 266.371832 -24.807418)
		(width 0.13208)
		(layer "F.Cu")
		(net "PU_CLKREQ9")
	)
	(segment
		(start 267.21943 -24.790146)
		(end 267.202158 -24.807418)
		(width 0.13208)
		(layer "F.Cu")
		(net "PU_CLKREQ9")
	)
	(segment
		(start 268.864842 -24.790146)
		(end 267.21943 -24.790146)
		(width 0.13208)
		(layer "F.Cu")
		(net "PU_CLKREQ9")
	)
	(via
		(at 267.202158 -24.807418)
		(size 0.508)
		(drill 0.254)
		(layers "F.Cu" "B.Cu")
		(net "PU_CLKREQ9")
	)
	(segment
		(start 58.650886 -345.338654)
		(end 55.114952 -336.801714)
		(width 0.1651)
		(layer "In5.Cu")
		(net "P5E_PEX0_STN6_RX_DN<108>")
	)
	(segment
		(start 78.636876 -402.281136)
		(end 79.232506 -402.281136)
		(width 0.1651)
		(layer "In5.Cu")
		(net "P5E_PEX0_STN6_RX_DN<108>")
	)
	(segment
		(start 79.684372 -396.906496)
		(end 79.052674 -394.824204)
		(width 0.1651)
		(layer "In5.Cu")
		(net "P5E_PEX0_STN6_RX_DN<108>")
	)
	(segment
		(start 46.01591 -319.966848)
		(end 45.97019 -319.921128)
		(width 0.1143)
		(layer "In5.Cu")
		(net "P5E_PEX0_STN6_RX_DN<108>")
	)
	(segment
		(start 46.08449 -318.320166)
		(end 46.23562 -318.320166)
		(width 0.1143)
		(layer "In5.Cu")
		(net "P5E_PEX0_STN6_RX_DN<108>")
	)
	(segment
		(start 69.576696 -388.923784)
		(end 67.90436 -387.251448)
		(width 0.1651)
		(layer "In5.Cu")
		(net "P5E_PEX0_STN6_RX_DN<108>")
	)
	(segment
		(start 67.90436 -387.251448)
		(end 67.07378 -385.24561)
		(width 0.1651)
		(layer "In5.Cu")
		(net "P5E_PEX0_STN6_RX_DN<108>")
	)
	(segment
		(start 78.509876 -402.790152)
		(end 78.509876 -402.408136)
		(width 0.1651)
		(layer "In5.Cu")
		(net "P5E_PEX0_STN6_RX_DN<108>")
	)
	(segment
		(start 79.052674 -394.824204)
		(end 74.1934 -390.83615)
		(width 0.1651)
		(layer "In5.Cu")
		(net "P5E_PEX0_STN6_RX_DN<108>")
	)
	(segment
		(start 45.97019 -319.921128)
		(end 45.97019 -318.434466)
		(width 0.1143)
		(layer "In5.Cu")
		(net "P5E_PEX0_STN6_RX_DN<108>")
	)
	(segment
		(start 67.07378 -385.24561)
		(end 65.415922 -368.422682)
		(width 0.1651)
		(layer "In5.Cu")
		(net "P5E_PEX0_STN6_RX_DN<108>")
	)
	(segment
		(start 79.232506 -402.281136)
		(end 79.684372 -401.82927)
		(width 0.1651)
		(layer "In5.Cu")
		(net "P5E_PEX0_STN6_RX_DN<108>")
	)
	(segment
		(start 74.1934 -390.83615)
		(end 69.576696 -388.923784)
		(width 0.1651)
		(layer "In5.Cu")
		(net "P5E_PEX0_STN6_RX_DN<108>")
	)
	(segment
		(start 65.415922 -368.422682)
		(end 60.248038 -355.025452)
		(width 0.1651)
		(layer "In5.Cu")
		(net "P5E_PEX0_STN6_RX_DN<108>")
	)
	(segment
		(start 46.34992 -318.434466)
		(end 46.34992 -318.699896)
		(width 0.1143)
		(layer "In5.Cu")
		(net "P5E_PEX0_STN6_RX_DN<108>")
	)
	(segment
		(start 46.01591 -319.995296)
		(end 46.01591 -319.966848)
		(width 0.1143)
		(layer "In5.Cu")
		(net "P5E_PEX0_STN6_RX_DN<108>")
	)
	(segment
		(start 78.509876 -402.408136)
		(end 78.636876 -402.281136)
		(width 0.1651)
		(layer "In5.Cu")
		(net "P5E_PEX0_STN6_RX_DN<108>")
	)
	(segment
		(start 59.455304 -351.860866)
		(end 58.650886 -345.338654)
		(width 0.1651)
		(layer "In5.Cu")
		(net "P5E_PEX0_STN6_RX_DN<108>")
	)
	(segment
		(start 46.01591 -322.596002)
		(end 46.01591 -319.995296)
		(width 0.1651)
		(layer "In5.Cu")
		(net "P5E_PEX0_STN6_RX_DN<108>")
	)
	(segment
		(start 45.97019 -318.434466)
		(end 46.08449 -318.320166)
		(width 0.1143)
		(layer "In5.Cu")
		(net "P5E_PEX0_STN6_RX_DN<108>")
	)
	(segment
		(start 46.65726 -324.144132)
		(end 46.01591 -322.596002)
		(width 0.1651)
		(layer "In5.Cu")
		(net "P5E_PEX0_STN6_RX_DN<108>")
	)
	(segment
		(start 60.248038 -355.025452)
		(end 59.455304 -351.860866)
		(width 0.1651)
		(layer "In5.Cu")
		(net "P5E_PEX0_STN6_RX_DN<108>")
	)
	(segment
		(start 55.114952 -336.801714)
		(end 46.65726 -324.144132)
		(width 0.1651)
		(layer "In5.Cu")
		(net "P5E_PEX0_STN6_RX_DN<108>")
	)
	(segment
		(start 79.684372 -401.82927)
		(end 79.684372 -396.906496)
		(width 0.1651)
		(layer "In5.Cu")
		(net "P5E_PEX0_STN6_RX_DN<108>")
	)
	(segment
		(start 46.23562 -318.320166)
		(end 46.34992 -318.434466)
		(width 0.1143)
		(layer "In5.Cu")
		(net "P5E_PEX0_STN6_RX_DN<108>")
	)
	(segment
		(start 132.044186 -32.4104)
		(end 131.864608 -32.589978)
		(width 0.13462)
		(layer "F.Cu")
		(net "P5E_PEX1_STN2_TX_C_DP<46>")
	)
	(segment
		(start 131.864608 -32.589978)
		(end 131.36499 -32.589978)
		(width 0.13462)
		(layer "F.Cu")
		(net "P5E_PEX1_STN2_TX_C_DP<46>")
	)
	(segment
		(start 133.29666 -32.4104)
		(end 132.044186 -32.4104)
		(width 0.13462)
		(layer "F.Cu")
		(net "P5E_PEX1_STN2_TX_C_DP<46>")
	)
	(segment
		(start 133.625844 -32.739584)
		(end 133.29666 -32.4104)
		(width 0.13462)
		(layer "F.Cu")
		(net "P5E_PEX1_STN2_TX_C_DP<46>")
	)
	(segment
		(start 300.596808 -338.661248)
		(end 300.206918 -338.355432)
		(width 0.1651)
		(layer "In9.Cu")
		(net "P5E_PEX2_STN6_RX_DN<101>")
	)
	(segment
		(start 284.934152 -316.419992)
		(end 285.110936 -316.419992)
		(width 0.1143)
		(layer "In9.Cu")
		(net "P5E_PEX2_STN6_RX_DN<101>")
	)
	(segment
		(start 285.110936 -316.419992)
		(end 285.199836 -316.508892)
		(width 0.1143)
		(layer "In9.Cu")
		(net "P5E_PEX2_STN6_RX_DN<101>")
	)
	(segment
		(start 337.01609 -369.28806)
		(end 336.7913 -368.27714)
		(width 0.1651)
		(layer "In9.Cu")
		(net "P5E_PEX2_STN6_RX_DN<101>")
	)
	(segment
		(start 333.83728 -366.4077)
		(end 315.57722 -359.22458)
		(width 0.1651)
		(layer "In9.Cu")
		(net "P5E_PEX2_STN6_RX_DN<101>")
	)
	(segment
		(start 302.191928 -340.02472)
		(end 300.612048 -338.785962)
		(width 0.1651)
		(layer "In9.Cu")
		(net "P5E_PEX2_STN6_RX_DN<101>")
	)
	(segment
		(start 289.522408 -330.091288)
		(end 285.360618 -325.929498)
		(width 0.1651)
		(layer "In9.Cu")
		(net "P5E_PEX2_STN6_RX_DN<101>")
	)
	(segment
		(start 300.08195 -338.370418)
		(end 289.522408 -330.091288)
		(width 0.1651)
		(layer "In9.Cu")
		(net "P5E_PEX2_STN6_RX_DN<101>")
	)
	(segment
		(start 335.890108 -375.69013)
		(end 335.890108 -375.308114)
		(width 0.1651)
		(layer "In9.Cu")
		(net "P5E_PEX2_STN6_RX_DN<101>")
	)
	(segment
		(start 300.206918 -338.355432)
		(end 300.08195 -338.370418)
		(width 0.1651)
		(layer "In9.Cu")
		(net "P5E_PEX2_STN6_RX_DN<101>")
	)
	(segment
		(start 284.865826 -324.734936)
		(end 284.865826 -319.916048)
		(width 0.1651)
		(layer "In9.Cu")
		(net "P5E_PEX2_STN6_RX_DN<101>")
	)
	(segment
		(start 315.57722 -359.22458)
		(end 314.8457 -358.507792)
		(width 0.1651)
		(layer "In9.Cu")
		(net "P5E_PEX2_STN6_RX_DN<101>")
	)
	(segment
		(start 336.017108 -375.181114)
		(end 336.564224 -375.181114)
		(width 0.1651)
		(layer "In9.Cu")
		(net "P5E_PEX2_STN6_RX_DN<101>")
	)
	(segment
		(start 285.199836 -316.508892)
		(end 285.199836 -316.799722)
		(width 0.1143)
		(layer "In9.Cu")
		(net "P5E_PEX2_STN6_RX_DN<101>")
	)
	(segment
		(start 336.7913 -368.27714)
		(end 333.83728 -366.4077)
		(width 0.1651)
		(layer "In9.Cu")
		(net "P5E_PEX2_STN6_RX_DN<101>")
	)
	(segment
		(start 337.01609 -374.729248)
		(end 337.01609 -369.28806)
		(width 0.1651)
		(layer "In9.Cu")
		(net "P5E_PEX2_STN6_RX_DN<101>")
	)
	(segment
		(start 284.820106 -319.84188)
		(end 284.820106 -316.534038)
		(width 0.1143)
		(layer "In9.Cu")
		(net "P5E_PEX2_STN6_RX_DN<101>")
	)
	(segment
		(start 300.612048 -338.785962)
		(end 300.596808 -338.661248)
		(width 0.1651)
		(layer "In9.Cu")
		(net "P5E_PEX2_STN6_RX_DN<101>")
	)
	(segment
		(start 314.8457 -358.507792)
		(end 302.191928 -340.02472)
		(width 0.1651)
		(layer "In9.Cu")
		(net "P5E_PEX2_STN6_RX_DN<101>")
	)
	(segment
		(start 284.865826 -319.916048)
		(end 284.865826 -319.8876)
		(width 0.1143)
		(layer "In9.Cu")
		(net "P5E_PEX2_STN6_RX_DN<101>")
	)
	(segment
		(start 335.890108 -375.308114)
		(end 336.017108 -375.181114)
		(width 0.1651)
		(layer "In9.Cu")
		(net "P5E_PEX2_STN6_RX_DN<101>")
	)
	(segment
		(start 284.820106 -316.534038)
		(end 284.934152 -316.419992)
		(width 0.1143)
		(layer "In9.Cu")
		(net "P5E_PEX2_STN6_RX_DN<101>")
	)
	(segment
		(start 336.564224 -375.181114)
		(end 337.01609 -374.729248)
		(width 0.1651)
		(layer "In9.Cu")
		(net "P5E_PEX2_STN6_RX_DN<101>")
	)
	(segment
		(start 285.360618 -325.929498)
		(end 284.865826 -324.734936)
		(width 0.1651)
		(layer "In9.Cu")
		(net "P5E_PEX2_STN6_RX_DN<101>")
	)
	(segment
		(start 284.865826 -319.8876)
		(end 284.820106 -319.84188)
		(width 0.1143)
		(layer "In9.Cu")
		(net "P5E_PEX2_STN6_RX_DN<101>")
	)
	(segment
		(start 400.54276 -105.57637)
		(end 400.24431 -105.27792)
		(width 0.13462)
		(layer "F.Cu")
		(net "P5E_PEX3_STN1_RX_DN<19>")
	)
	(segment
		(start 400.24431 -105.27792)
		(end 399.590514 -105.27792)
		(width 0.13462)
		(layer "F.Cu")
		(net "P5E_PEX3_STN1_RX_DN<19>")
	)
	(segment
		(start 399.423382 -105.445052)
		(end 398.94256 -105.445052)
		(width 0.13462)
		(layer "F.Cu")
		(net "P5E_PEX3_STN1_RX_DN<19>")
	)
	(segment
		(start 399.590514 -105.27792)
		(end 399.423382 -105.445052)
		(width 0.13462)
		(layer "F.Cu")
		(net "P5E_PEX3_STN1_RX_DN<19>")
	)
	(segment
		(start 379.70333 -150.483824)
		(end 380.22911 -158.735014)
		(width 0.1651)
		(layer "In5.Cu")
		(net "P5E_PEX3_STN1_RX_DN<19>")
	)
	(segment
		(start 393.502896 -108.674408)
		(end 392.59002 -109.558074)
		(width 0.1651)
		(layer "In5.Cu")
		(net "P5E_PEX3_STN1_RX_DN<19>")
	)
	(segment
		(start 400.25193 -105.28554)
		(end 399.774664 -105.28554)
		(width 0.1651)
		(layer "In5.Cu")
		(net "P5E_PEX3_STN1_RX_DN<19>")
	)
	(segment
		(start 396.121128 -107.259628)
		(end 396.0749 -107.414568)
		(width 0.1651)
		(layer "In5.Cu")
		(net "P5E_PEX3_STN1_RX_DN<19>")
	)
	(segment
		(start 390.837928 -111.25454)
		(end 390.835388 -111.416084)
		(width 0.1651)
		(layer "In5.Cu")
		(net "P5E_PEX3_STN1_RX_DN<19>")
	)
	(segment
		(start 391.355326 -110.91291)
		(end 391.193782 -110.910116)
		(width 0.1651)
		(layer "In5.Cu")
		(net "P5E_PEX3_STN1_RX_DN<19>")
	)
	(segment
		(start 410.799534 -275.265388)
		(end 410.799534 -274.999958)
		(width 0.1143)
		(layer "In5.Cu")
		(net "P5E_PEX3_STN1_RX_DN<19>")
	)
	(segment
		(start 391.193782 -110.910116)
		(end 390.837928 -111.25454)
		(width 0.1651)
		(layer "In5.Cu")
		(net "P5E_PEX3_STN1_RX_DN<19>")
	)
	(segment
		(start 391.711434 -110.567978)
		(end 391.355326 -110.91291)
		(width 0.1651)
		(layer "In5.Cu")
		(net "P5E_PEX3_STN1_RX_DN<19>")
	)
	(segment
		(start 392.58748 -109.719618)
		(end 392.231372 -110.06455)
		(width 0.1651)
		(layer "In5.Cu")
		(net "P5E_PEX3_STN1_RX_DN<19>")
	)
	(segment
		(start 398.220184 -106.255312)
		(end 397.784066 -106.491024)
		(width 0.1651)
		(layer "In5.Cu")
		(net "P5E_PEX3_STN1_RX_DN<19>")
	)
	(segment
		(start 410.465778 -269.489682)
		(end 410.465778 -271.570958)
		(width 0.1651)
		(layer "In5.Cu")
		(net "P5E_PEX3_STN1_RX_DN<19>")
	)
	(segment
		(start 397.19377 -106.68)
		(end 397.147542 -106.83494)
		(width 0.1651)
		(layer "In5.Cu")
		(net "P5E_PEX3_STN1_RX_DN<19>")
	)
	(segment
		(start 394.565886 -108.229908)
		(end 394.4112 -108.18368)
		(width 0.1651)
		(layer "In5.Cu")
		(net "P5E_PEX3_STN1_RX_DN<19>")
	)
	(segment
		(start 397.147542 -106.83494)
		(end 396.711424 -107.070652)
		(width 0.1651)
		(layer "In5.Cu")
		(net "P5E_PEX3_STN1_RX_DN<19>")
	)
	(segment
		(start 395.638782 -107.65028)
		(end 395.483842 -107.604052)
		(width 0.1651)
		(layer "In5.Cu")
		(net "P5E_PEX3_STN1_RX_DN<19>")
	)
	(segment
		(start 399.339054 -105.520744)
		(end 399.292826 -105.675684)
		(width 0.1651)
		(layer "In5.Cu")
		(net "P5E_PEX3_STN1_RX_DN<19>")
	)
	(segment
		(start 396.0749 -107.414568)
		(end 395.638782 -107.65028)
		(width 0.1651)
		(layer "In5.Cu")
		(net "P5E_PEX3_STN1_RX_DN<19>")
	)
	(segment
		(start 397.62938 -106.444796)
		(end 397.19377 -106.68)
		(width 0.1651)
		(layer "In5.Cu")
		(net "P5E_PEX3_STN1_RX_DN<19>")
	)
	(segment
		(start 392.231372 -110.06455)
		(end 392.069828 -110.06201)
		(width 0.1651)
		(layer "In5.Cu")
		(net "P5E_PEX3_STN1_RX_DN<19>")
	)
	(segment
		(start 410.465778 -271.599406)
		(end 410.420058 -271.645126)
		(width 0.1143)
		(layer "In5.Cu")
		(net "P5E_PEX3_STN1_RX_DN<19>")
	)
	(segment
		(start 382.63195 -122.078242)
		(end 381.967232 -122.886724)
		(width 0.1651)
		(layer "In5.Cu")
		(net "P5E_PEX3_STN1_RX_DN<19>")
	)
	(segment
		(start 410.420058 -275.27631)
		(end 410.523436 -275.379688)
		(width 0.1143)
		(layer "In5.Cu")
		(net "P5E_PEX3_STN1_RX_DN<19>")
	)
	(segment
		(start 399.774664 -105.28554)
		(end 399.339054 -105.520744)
		(width 0.1651)
		(layer "In5.Cu")
		(net "P5E_PEX3_STN1_RX_DN<19>")
	)
	(segment
		(start 398.702022 -105.865168)
		(end 398.266412 -106.100372)
		(width 0.1651)
		(layer "In5.Cu")
		(net "P5E_PEX3_STN1_RX_DN<19>")
	)
	(segment
		(start 386.03555 -119.317008)
		(end 384.66776 -120.982232)
		(width 0.1651)
		(layer "In5.Cu")
		(net "P5E_PEX3_STN1_RX_DN<19>")
	)
	(segment
		(start 395.048232 -107.839256)
		(end 395.002004 -107.994196)
		(width 0.1651)
		(layer "In5.Cu")
		(net "P5E_PEX3_STN1_RX_DN<19>")
	)
	(segment
		(start 410.685234 -275.379688)
		(end 410.799534 -275.265388)
		(width 0.1143)
		(layer "In5.Cu")
		(net "P5E_PEX3_STN1_RX_DN<19>")
	)
	(segment
		(start 390.835388 -111.416084)
		(end 390.47928 -111.761016)
		(width 0.1651)
		(layer "In5.Cu")
		(net "P5E_PEX3_STN1_RX_DN<19>")
	)
	(segment
		(start 396.556738 -107.024424)
		(end 396.121128 -107.259628)
		(width 0.1651)
		(layer "In5.Cu")
		(net "P5E_PEX3_STN1_RX_DN<19>")
	)
	(segment
		(start 381.325628 -165.120574)
		(end 410.465778 -269.489682)
		(width 0.1651)
		(layer "In5.Cu")
		(net "P5E_PEX3_STN1_RX_DN<19>")
	)
	(segment
		(start 392.59002 -109.558074)
		(end 392.58748 -109.719618)
		(width 0.1651)
		(layer "In5.Cu")
		(net "P5E_PEX3_STN1_RX_DN<19>")
	)
	(segment
		(start 398.266412 -106.100372)
		(end 398.220184 -106.255312)
		(width 0.1651)
		(layer "In5.Cu")
		(net "P5E_PEX3_STN1_RX_DN<19>")
	)
	(segment
		(start 399.292826 -105.675684)
		(end 398.856708 -105.911396)
		(width 0.1651)
		(layer "In5.Cu")
		(net "P5E_PEX3_STN1_RX_DN<19>")
	)
	(segment
		(start 394.4112 -108.18368)
		(end 393.502896 -108.674408)
		(width 0.1651)
		(layer "In5.Cu")
		(net "P5E_PEX3_STN1_RX_DN<19>")
	)
	(segment
		(start 395.483842 -107.604052)
		(end 395.048232 -107.839256)
		(width 0.1651)
		(layer "In5.Cu")
		(net "P5E_PEX3_STN1_RX_DN<19>")
	)
	(segment
		(start 400.54276 -105.57637)
		(end 400.25193 -105.28554)
		(width 0.1651)
		(layer "In5.Cu")
		(net "P5E_PEX3_STN1_RX_DN<19>")
	)
	(segment
		(start 410.465778 -271.570958)
		(end 410.465778 -271.599406)
		(width 0.1143)
		(layer "In5.Cu")
		(net "P5E_PEX3_STN1_RX_DN<19>")
	)
	(segment
		(start 396.711424 -107.070652)
		(end 396.556738 -107.024424)
		(width 0.1651)
		(layer "In5.Cu")
		(net "P5E_PEX3_STN1_RX_DN<19>")
	)
	(segment
		(start 398.856708 -105.911396)
		(end 398.702022 -105.865168)
		(width 0.1651)
		(layer "In5.Cu")
		(net "P5E_PEX3_STN1_RX_DN<19>")
	)
	(segment
		(start 410.523436 -275.379688)
		(end 410.685234 -275.379688)
		(width 0.1143)
		(layer "In5.Cu")
		(net "P5E_PEX3_STN1_RX_DN<19>")
	)
	(segment
		(start 390.317736 -111.758222)
		(end 389.189976 -112.850168)
		(width 0.1651)
		(layer "In5.Cu")
		(net "P5E_PEX3_STN1_RX_DN<19>")
	)
	(segment
		(start 391.713974 -110.406434)
		(end 391.711434 -110.567978)
		(width 0.1651)
		(layer "In5.Cu")
		(net "P5E_PEX3_STN1_RX_DN<19>")
	)
	(segment
		(start 389.189976 -112.850168)
		(end 386.03555 -119.317008)
		(width 0.1651)
		(layer "In5.Cu")
		(net "P5E_PEX3_STN1_RX_DN<19>")
	)
	(segment
		(start 410.420058 -271.645126)
		(end 410.420058 -275.27631)
		(width 0.1143)
		(layer "In5.Cu")
		(net "P5E_PEX3_STN1_RX_DN<19>")
	)
	(segment
		(start 390.47928 -111.761016)
		(end 390.317736 -111.758222)
		(width 0.1651)
		(layer "In5.Cu")
		(net "P5E_PEX3_STN1_RX_DN<19>")
	)
	(segment
		(start 392.069828 -110.06201)
		(end 391.713974 -110.406434)
		(width 0.1651)
		(layer "In5.Cu")
		(net "P5E_PEX3_STN1_RX_DN<19>")
	)
	(segment
		(start 381.967232 -122.886724)
		(end 381.304292 -126.387352)
		(width 0.1651)
		(layer "In5.Cu")
		(net "P5E_PEX3_STN1_RX_DN<19>")
	)
	(segment
		(start 395.002004 -107.994196)
		(end 394.565886 -108.229908)
		(width 0.1651)
		(layer "In5.Cu")
		(net "P5E_PEX3_STN1_RX_DN<19>")
	)
	(segment
		(start 380.503684 -138.436096)
		(end 379.70333 -150.483824)
		(width 0.1651)
		(layer "In5.Cu")
		(net "P5E_PEX3_STN1_RX_DN<19>")
	)
	(segment
		(start 384.66776 -120.982232)
		(end 382.63195 -122.078242)
		(width 0.1651)
		(layer "In5.Cu")
		(net "P5E_PEX3_STN1_RX_DN<19>")
	)
	(segment
		(start 381.304292 -126.387352)
		(end 380.504192 -138.435842)
		(width 0.1651)
		(layer "In5.Cu")
		(net "P5E_PEX3_STN1_RX_DN<19>")
	)
	(segment
		(start 380.22911 -158.735014)
		(end 381.325628 -165.120574)
		(width 0.1651)
		(layer "In5.Cu")
		(net "P5E_PEX3_STN1_RX_DN<19>")
	)
	(segment
		(start 380.504192 -138.435842)
		(end 380.503684 -138.436096)
		(width 0.1651)
		(layer "In5.Cu")
		(net "P5E_PEX3_STN1_RX_DN<19>")
	)
	(segment
		(start 397.784066 -106.491024)
		(end 397.62938 -106.444796)
		(width 0.1651)
		(layer "In5.Cu")
		(net "P5E_PEX3_STN1_RX_DN<19>")
	)
	(segment
		(start 381.084328 -357.463598)
		(end 381.37846 -357.75773)
		(width 0.13462)
		(layer "F.Cu")
		(net "P5E_PEX3_STN6_TX_C_DN<98>")
	)
	(segment
		(start 381.40386 -356.511606)
		(end 381.084328 -356.831138)
		(width 0.13462)
		(layer "F.Cu")
		(net "P5E_PEX3_STN6_TX_C_DN<98>")
	)
	(segment
		(start 381.084328 -356.831138)
		(end 381.084328 -357.463598)
		(width 0.13462)
		(layer "F.Cu")
		(net "P5E_PEX3_STN6_TX_C_DN<98>")
	)
	(segment
		(start 386.489956 -384.20802)
		(end 386.616956 -384.08102)
		(width 0.1651)
		(layer "In7.Cu")
		(net "P5E_PEX3_STN6_TX_C_DN<98>")
	)
	(segment
		(start 381.08763 -358.678988)
		(end 381.08763 -358.04856)
		(width 0.1651)
		(layer "In7.Cu")
		(net "P5E_PEX3_STN6_TX_C_DN<98>")
	)
	(segment
		(start 387.615938 -368.783108)
		(end 381.08763 -358.678988)
		(width 0.1651)
		(layer "In7.Cu")
		(net "P5E_PEX3_STN6_TX_C_DN<98>")
	)
	(segment
		(start 387.615938 -383.629154)
		(end 387.615938 -368.783108)
		(width 0.1651)
		(layer "In7.Cu")
		(net "P5E_PEX3_STN6_TX_C_DN<98>")
	)
	(segment
		(start 386.616956 -384.08102)
		(end 387.164072 -384.08102)
		(width 0.1651)
		(layer "In7.Cu")
		(net "P5E_PEX3_STN6_TX_C_DN<98>")
	)
	(segment
		(start 381.08763 -358.04856)
		(end 381.37846 -357.75773)
		(width 0.1651)
		(layer "In7.Cu")
		(net "P5E_PEX3_STN6_TX_C_DN<98>")
	)
	(segment
		(start 387.164072 -384.08102)
		(end 387.615938 -383.629154)
		(width 0.1651)
		(layer "In7.Cu")
		(net "P5E_PEX3_STN6_TX_C_DN<98>")
	)
	(segment
		(start 386.489956 -384.590036)
		(end 386.489956 -384.20802)
		(width 0.1651)
		(layer "In7.Cu")
		(net "P5E_PEX3_STN6_TX_C_DN<98>")
	)
	(segment
		(start 390.890506 -97.045018)
		(end 394.342366 -97.045018)
		(width 0.13208)
		(layer "F.Cu")
		(net "PRSNTB3_NIC6_N")
	)
	(segment
		(start 390.755124 -97.1804)
		(end 390.890506 -97.045018)
		(width 0.13208)
		(layer "F.Cu")
		(net "PRSNTB3_NIC6_N")
	)
	(segment
		(start 388.668006 -97.1804)
		(end 390.755124 -97.1804)
		(width 0.13208)
		(layer "F.Cu")
		(net "PRSNTB3_NIC6_N")
	)
	(segment
		(start 387.46049 -96.1644)
		(end 387.46049 -97.1804)
		(width 0.13208)
		(layer "F.Cu")
		(net "PRSNTB3_NIC6_N")
	)
	(segment
		(start 387.46049 -97.1804)
		(end 388.668006 -97.1804)
		(width 0.13208)
		(layer "F.Cu")
		(net "PRSNTB3_NIC6_N")
	)
	(via
		(at 388.668006 -97.1804)
		(size 0.762)
		(drill 0.381)
		(layers "F.Cu" "B.Cu")
		(net "PRSNTB3_NIC6_N")
	)
	(segment
		(start 277.249636 -24.488648)
		(end 277.67153 -24.910542)
		(width 0.13208)
		(layer "F.Cu")
		(net "DUALPORT_N_SSD9")
	)
	(segment
		(start 275.020532 -24.488648)
		(end 277.249636 -24.488648)
		(width 0.13208)
		(layer "F.Cu")
		(net "DUALPORT_N_SSD9")
	)
	(segment
		(start 277.67153 -24.910542)
		(end 277.67153 -24.942292)
		(width 0.13208)
		(layer "F.Cu")
		(net "DUALPORT_N_SSD9")
	)
	(segment
		(start 274.666456 -23.589996)
		(end 274.666456 -24.134572)
		(width 0.13208)
		(layer "F.Cu")
		(net "DUALPORT_N_SSD9")
	)
	(segment
		(start 278.68753 -24.942292)
		(end 277.67153 -24.942292)
		(width 0.13208)
		(layer "F.Cu")
		(net "DUALPORT_N_SSD9")
	)
	(segment
		(start 273.464782 -23.589996)
		(end 274.666456 -23.589996)
		(width 0.13208)
		(layer "F.Cu")
		(net "DUALPORT_N_SSD9")
	)
	(segment
		(start 274.666456 -24.134572)
		(end 275.020532 -24.488648)
		(width 0.13208)
		(layer "F.Cu")
		(net "DUALPORT_N_SSD9")
	)
	(via
		(at 274.666456 -23.589996)
		(size 0.508)
		(drill 0.254)
		(layers "F.Cu" "B.Cu")
		(net "DUALPORT_N_SSD9")
	)
	(segment
		(start 131.86791 -34.390076)
		(end 131.36499 -34.390076)
		(width 0.13462)
		(layer "F.Cu")
		(net "P5E_PEX1_STN2_TX_C_DP<47>")
	)
	(segment
		(start 136.267952 -34.546286)
		(end 135.948166 -34.2265)
		(width 0.13462)
		(layer "F.Cu")
		(net "P5E_PEX1_STN2_TX_C_DP<47>")
	)
	(segment
		(start 135.948166 -34.2265)
		(end 132.031486 -34.2265)
		(width 0.13462)
		(layer "F.Cu")
		(net "P5E_PEX1_STN2_TX_C_DP<47>")
	)
	(segment
		(start 132.031486 -34.2265)
		(end 131.86791 -34.390076)
		(width 0.13462)
		(layer "F.Cu")
		(net "P5E_PEX1_STN2_TX_C_DP<47>")
	)
	(segment
		(start 336.586322 -393.41806)
		(end 336.176366 -393.139422)
		(width 0.1651)
		(layer "In5.Cu")
		(net "P5E_PEX2_STN6_RX_DP<108>")
	)
	(segment
		(start 277.979632 -319.921128)
		(end 277.979632 -318.355472)
		(width 0.1143)
		(layer "In5.Cu")
		(net "P5E_PEX2_STN6_RX_DP<108>")
	)
	(segment
		(start 338.647278 -401.999196)
		(end 338.934044 -401.71243)
		(width 0.1651)
		(layer "In5.Cu")
		(net "P5E_PEX2_STN6_RX_DP<108>")
	)
	(segment
		(start 334.58785 -391.93851)
		(end 328.625454 -389.464042)
		(width 0.1651)
		(layer "In5.Cu")
		(net "P5E_PEX2_STN6_RX_DP<108>")
	)
	(segment
		(start 335.73974 -392.720322)
		(end 335.598516 -392.7475)
		(width 0.1651)
		(layer "In5.Cu")
		(net "P5E_PEX2_STN6_RX_DP<108>")
	)
	(segment
		(start 335.598516 -392.7475)
		(end 335.18856 -392.469116)
		(width 0.1651)
		(layer "In5.Cu")
		(net "P5E_PEX2_STN6_RX_DP<108>")
	)
	(segment
		(start 305.463702 -338.618576)
		(end 304.503836 -337.599528)
		(width 0.1651)
		(layer "In5.Cu")
		(net "P5E_PEX2_STN6_RX_DP<108>")
	)
	(segment
		(start 336.727546 -393.390882)
		(end 336.586322 -393.41806)
		(width 0.1651)
		(layer "In5.Cu")
		(net "P5E_PEX2_STN6_RX_DP<108>")
	)
	(segment
		(start 279.33269 -323.997574)
		(end 278.424386 -323.355462)
		(width 0.1651)
		(layer "In5.Cu")
		(net "P5E_PEX2_STN6_RX_DP<108>")
	)
	(segment
		(start 278.424386 -323.355462)
		(end 277.933912 -322.170044)
		(width 0.1651)
		(layer "In5.Cu")
		(net "P5E_PEX2_STN6_RX_DP<108>")
	)
	(segment
		(start 315.202316 -360.894122)
		(end 305.463702 -338.618576)
		(width 0.1651)
		(layer "In5.Cu")
		(net "P5E_PEX2_STN6_RX_DP<108>")
	)
	(segment
		(start 335.161636 -392.327892)
		(end 334.58785 -391.93851)
		(width 0.1651)
		(layer "In5.Cu")
		(net "P5E_PEX2_STN6_RX_DP<108>")
	)
	(segment
		(start 335.18856 -392.469116)
		(end 335.161636 -392.327892)
		(width 0.1651)
		(layer "In5.Cu")
		(net "P5E_PEX2_STN6_RX_DP<108>")
	)
	(segment
		(start 277.933912 -319.995296)
		(end 277.933912 -319.966848)
		(width 0.1143)
		(layer "In5.Cu")
		(net "P5E_PEX2_STN6_RX_DP<108>")
	)
	(segment
		(start 336.176366 -393.139422)
		(end 336.149442 -392.998452)
		(width 0.1651)
		(layer "In5.Cu")
		(net "P5E_PEX2_STN6_RX_DP<108>")
	)
	(segment
		(start 315.76264 -361.71505)
		(end 315.202316 -360.894122)
		(width 0.1651)
		(layer "In5.Cu")
		(net "P5E_PEX2_STN6_RX_DP<108>")
	)
	(segment
		(start 304.503836 -337.599528)
		(end 279.33269 -323.997574)
		(width 0.1651)
		(layer "In5.Cu")
		(net "P5E_PEX2_STN6_RX_DP<108>")
	)
	(segment
		(start 338.934044 -395.669516)
		(end 338.770722 -395.25575)
		(width 0.1651)
		(layer "In5.Cu")
		(net "P5E_PEX2_STN6_RX_DP<108>")
	)
	(segment
		(start 338.770722 -395.25575)
		(end 337.236054 -393.736068)
		(width 0.1651)
		(layer "In5.Cu")
		(net "P5E_PEX2_STN6_RX_DP<108>")
	)
	(segment
		(start 277.933912 -322.170044)
		(end 277.933912 -319.995296)
		(width 0.1651)
		(layer "In5.Cu")
		(net "P5E_PEX2_STN6_RX_DP<108>")
	)
	(segment
		(start 338.934044 -401.71243)
		(end 338.934044 -395.669516)
		(width 0.1651)
		(layer "In5.Cu")
		(net "P5E_PEX2_STN6_RX_DP<108>")
	)
	(segment
		(start 338.217002 -401.999196)
		(end 338.647278 -401.999196)
		(width 0.1651)
		(layer "In5.Cu")
		(net "P5E_PEX2_STN6_RX_DP<108>")
	)
	(segment
		(start 336.149442 -392.998452)
		(end 335.73974 -392.720322)
		(width 0.1651)
		(layer "In5.Cu")
		(net "P5E_PEX2_STN6_RX_DP<108>")
	)
	(segment
		(start 277.979632 -318.355472)
		(end 278.205438 -318.129666)
		(width 0.1143)
		(layer "In5.Cu")
		(net "P5E_PEX2_STN6_RX_DP<108>")
	)
	(segment
		(start 338.090002 -401.872196)
		(end 338.217002 -401.999196)
		(width 0.1651)
		(layer "In5.Cu")
		(net "P5E_PEX2_STN6_RX_DP<108>")
	)
	(segment
		(start 328.625454 -389.464042)
		(end 327.331578 -388.177532)
		(width 0.1651)
		(layer "In5.Cu")
		(net "P5E_PEX2_STN6_RX_DP<108>")
	)
	(segment
		(start 277.933912 -319.966848)
		(end 277.979632 -319.921128)
		(width 0.1143)
		(layer "In5.Cu")
		(net "P5E_PEX2_STN6_RX_DP<108>")
	)
	(segment
		(start 338.090002 -401.49018)
		(end 338.090002 -401.872196)
		(width 0.1651)
		(layer "In5.Cu")
		(net "P5E_PEX2_STN6_RX_DP<108>")
	)
	(segment
		(start 278.435562 -318.129666)
		(end 278.549862 -318.015366)
		(width 0.1143)
		(layer "In5.Cu")
		(net "P5E_PEX2_STN6_RX_DP<108>")
	)
	(segment
		(start 278.549862 -318.015366)
		(end 278.549862 -317.749936)
		(width 0.1143)
		(layer "In5.Cu")
		(net "P5E_PEX2_STN6_RX_DP<108>")
	)
	(segment
		(start 337.236054 -393.736068)
		(end 336.727546 -393.390882)
		(width 0.1651)
		(layer "In5.Cu")
		(net "P5E_PEX2_STN6_RX_DP<108>")
	)
	(segment
		(start 327.331578 -388.177532)
		(end 315.76264 -361.71505)
		(width 0.1651)
		(layer "In5.Cu")
		(net "P5E_PEX2_STN6_RX_DP<108>")
	)
	(segment
		(start 278.205438 -318.129666)
		(end 278.435562 -318.129666)
		(width 0.1143)
		(layer "In5.Cu")
		(net "P5E_PEX2_STN6_RX_DP<108>")
	)
	(segment
		(start 393.674346 -121.5898)
		(end 393.839446 -121.7549)
		(width 0.13462)
		(layer "F.Cu")
		(net "P5E_PEX3_STN1_TX_C_DP<25>")
	)
	(segment
		(start 387.847332 -121.919746)
		(end 388.177278 -121.5898)
		(width 0.13462)
		(layer "F.Cu")
		(net "P5E_PEX3_STN1_TX_C_DP<25>")
	)
	(segment
		(start 393.839446 -121.7549)
		(end 394.342366 -121.7549)
		(width 0.13462)
		(layer "F.Cu")
		(net "P5E_PEX3_STN1_TX_C_DP<25>")
	)
	(segment
		(start 388.177278 -121.5898)
		(end 393.674346 -121.5898)
		(width 0.13462)
		(layer "F.Cu")
		(net "P5E_PEX3_STN1_TX_C_DP<25>")
	)
	(segment
		(start 391.799826 -316.534292)
		(end 391.685526 -316.419992)
		(width 0.1143)
		(layer "In15.Cu")
		(net "P5E_PEX3_STN6_RX_DN<111>")
	)
	(segment
		(start 391.4648 -320.319146)
		(end 390.148318 -321.635628)
		(width 0.1651)
		(layer "In15.Cu")
		(net "P5E_PEX3_STN6_RX_DN<111>")
	)
	(segment
		(start 372.91264 -392.615166)
		(end 375.558304 -393.80922)
		(width 0.1651)
		(layer "In15.Cu")
		(net "P5E_PEX3_STN6_RX_DN<111>")
	)
	(segment
		(start 376.164094 -401.181062)
		(end 375.616978 -401.181062)
		(width 0.1651)
		(layer "In15.Cu")
		(net "P5E_PEX3_STN6_RX_DN<111>")
	)
	(segment
		(start 366.907826 -371.20449)
		(end 367.467896 -385.981448)
		(width 0.1651)
		(layer "In15.Cu")
		(net "P5E_PEX3_STN6_RX_DN<111>")
	)
	(segment
		(start 375.558304 -393.80922)
		(end 376.315478 -394.5382)
		(width 0.1651)
		(layer "In15.Cu")
		(net "P5E_PEX3_STN6_RX_DN<111>")
	)
	(segment
		(start 376.61596 -400.729196)
		(end 376.164094 -401.181062)
		(width 0.1651)
		(layer "In15.Cu")
		(net "P5E_PEX3_STN6_RX_DN<111>")
	)
	(segment
		(start 391.523728 -316.419992)
		(end 391.41908 -316.52464)
		(width 0.1143)
		(layer "In15.Cu")
		(net "P5E_PEX3_STN6_RX_DN<111>")
	)
	(segment
		(start 367.314226 -341.46109)
		(end 367.242344 -341.861648)
		(width 0.1651)
		(layer "In15.Cu")
		(net "P5E_PEX3_STN6_RX_DN<111>")
	)
	(segment
		(start 375.489978 -401.308062)
		(end 375.489978 -401.690078)
		(width 0.1651)
		(layer "In15.Cu")
		(net "P5E_PEX3_STN6_RX_DN<111>")
	)
	(segment
		(start 375.616978 -401.181062)
		(end 375.489978 -401.308062)
		(width 0.1651)
		(layer "In15.Cu")
		(net "P5E_PEX3_STN6_RX_DN<111>")
	)
	(segment
		(start 376.315478 -394.5382)
		(end 376.61596 -395.3256)
		(width 0.1651)
		(layer "In15.Cu")
		(net "P5E_PEX3_STN6_RX_DN<111>")
	)
	(segment
		(start 390.148318 -321.635628)
		(end 368.699796 -339.108288)
		(width 0.1651)
		(layer "In15.Cu")
		(net "P5E_PEX3_STN6_RX_DN<111>")
	)
	(segment
		(start 367.242344 -341.861648)
		(end 366.907826 -371.20449)
		(width 0.1651)
		(layer "In15.Cu")
		(net "P5E_PEX3_STN6_RX_DN<111>")
	)
	(segment
		(start 369.092988 -389.71347)
		(end 372.91264 -392.615166)
		(width 0.1651)
		(layer "In15.Cu")
		(net "P5E_PEX3_STN6_RX_DN<111>")
	)
	(segment
		(start 391.41908 -319.921128)
		(end 391.4648 -319.966848)
		(width 0.1143)
		(layer "In15.Cu")
		(net "P5E_PEX3_STN6_RX_DN<111>")
	)
	(segment
		(start 376.61596 -395.3256)
		(end 376.61596 -400.729196)
		(width 0.1651)
		(layer "In15.Cu")
		(net "P5E_PEX3_STN6_RX_DN<111>")
	)
	(segment
		(start 368.699796 -339.108288)
		(end 367.314226 -341.46109)
		(width 0.1651)
		(layer "In15.Cu")
		(net "P5E_PEX3_STN6_RX_DN<111>")
	)
	(segment
		(start 391.685526 -316.419992)
		(end 391.523728 -316.419992)
		(width 0.1143)
		(layer "In15.Cu")
		(net "P5E_PEX3_STN6_RX_DN<111>")
	)
	(segment
		(start 391.4648 -319.966848)
		(end 391.4648 -319.995296)
		(width 0.1143)
		(layer "In15.Cu")
		(net "P5E_PEX3_STN6_RX_DN<111>")
	)
	(segment
		(start 391.4648 -319.995296)
		(end 391.4648 -320.319146)
		(width 0.1651)
		(layer "In15.Cu")
		(net "P5E_PEX3_STN6_RX_DN<111>")
	)
	(segment
		(start 391.799826 -316.799722)
		(end 391.799826 -316.534292)
		(width 0.1143)
		(layer "In15.Cu")
		(net "P5E_PEX3_STN6_RX_DN<111>")
	)
	(segment
		(start 391.41908 -316.52464)
		(end 391.41908 -319.921128)
		(width 0.1143)
		(layer "In15.Cu")
		(net "P5E_PEX3_STN6_RX_DN<111>")
	)
	(segment
		(start 367.467896 -385.981448)
		(end 369.092988 -389.71347)
		(width 0.1651)
		(layer "In15.Cu")
		(net "P5E_PEX3_STN6_RX_DN<111>")
	)
	(segment
		(start 188.236352 -116.0272)
		(end 188.704728 -116.0272)
		(width 0.13208)
		(layer "F.Cu")
		(net "NIC3_AUX_PWR_EN_R")
	)
	(segment
		(start 188.897006 -115.834922)
		(end 189.357508 -115.834922)
		(width 0.13208)
		(layer "F.Cu")
		(net "NIC3_AUX_PWR_EN_R")
	)
	(segment
		(start 188.704728 -116.0272)
		(end 188.897006 -115.834922)
		(width 0.13208)
		(layer "F.Cu")
		(net "NIC3_AUX_PWR_EN_R")
	)
	(segment
		(start 187.786264 -116.477288)
		(end 188.236352 -116.0272)
		(width 0.13208)
		(layer "F.Cu")
		(net "NIC3_AUX_PWR_EN_R")
	)
	(via
		(at 187.786264 -116.477288)
		(size 0.508)
		(drill 0.254)
		(layers "F.Cu" "B.Cu")
		(net "NIC3_AUX_PWR_EN_R")
	)
	(segment
		(start 187.269628 -116.477288)
		(end 187.786264 -116.477288)
		(width 0.13208)
		(layer "B.Cu")
		(net "NIC3_AUX_PWR_EN_R")
	)
	(segment
		(start 186.099196 -115.306856)
		(end 187.269628 -116.477288)
		(width 0.13208)
		(layer "B.Cu")
		(net "NIC3_AUX_PWR_EN_R")
	)
	(segment
		(start 186.099196 -114.713512)
		(end 186.099196 -115.306856)
		(width 0.13208)
		(layer "B.Cu")
		(net "NIC3_AUX_PWR_EN_R")
	)
	(segment
		(start 187.786264 -116.477288)
		(end 187.786264 -117.66169)
		(width 0.13208)
		(layer "B.Cu")
		(net "NIC3_AUX_PWR_EN_R")
	)
	(segment
		(start 402.24964 -158.8516)
		(end 402.65604 -158.8516)
		(width 0.13208)
		(layer "F.Cu")
		(net "RST_NIC6_PERST2_R_N")
	)
	(segment
		(start 401.75815 -158.36011)
		(end 402.24964 -158.8516)
		(width 0.13208)
		(layer "F.Cu")
		(net "RST_NIC6_PERST2_R_N")
	)
	(segment
		(start 402.65604 -158.8516)
		(end 403.88159 -158.8516)
		(width 0.13208)
		(layer "F.Cu")
		(net "RST_NIC6_PERST2_R_N")
	)
	(segment
		(start 398.94256 -158.36011)
		(end 401.75815 -158.36011)
		(width 0.13208)
		(layer "F.Cu")
		(net "RST_NIC6_PERST2_R_N")
	)
	(via
		(at 402.65604 -158.8516)
		(size 0.762)
		(drill 0.381)
		(layers "F.Cu" "B.Cu")
		(net "RST_NIC6_PERST2_R_N")
	)
	(segment
		(start 240.371884 -24.807418)
		(end 241.20221 -24.807418)
		(width 0.13208)
		(layer "F.Cu")
		(net "PU_CLKREQ8")
	)
	(segment
		(start 241.219482 -24.790146)
		(end 241.20221 -24.807418)
		(width 0.13208)
		(layer "F.Cu")
		(net "PU_CLKREQ8")
	)
	(segment
		(start 242.864894 -24.790146)
		(end 241.219482 -24.790146)
		(width 0.13208)
		(layer "F.Cu")
		(net "PU_CLKREQ8")
	)
	(via
		(at 241.20221 -24.807418)
		(size 0.508)
		(drill 0.254)
		(layers "F.Cu" "B.Cu")
		(net "PU_CLKREQ8")
	)
	(segment
		(start 68.453762 -357.75773)
		(end 68.159122 -357.46309)
		(width 0.13462)
		(layer "F.Cu")
		(net "P5E_PEX0_STN6_TX_C_DN<108>")
	)
	(segment
		(start 68.159122 -357.46309)
		(end 68.159122 -356.831646)
		(width 0.13462)
		(layer "F.Cu")
		(net "P5E_PEX0_STN6_TX_C_DN<108>")
	)
	(segment
		(start 68.159122 -356.831646)
		(end 68.479162 -356.511606)
		(width 0.13462)
		(layer "F.Cu")
		(net "P5E_PEX0_STN6_TX_C_DN<108>")
	)
	(segment
		(start 79.684372 -409.677616)
		(end 79.684372 -395.236192)
		(width 0.1651)
		(layer "In13.Cu")
		(net "P5E_PEX0_STN6_TX_C_DN<108>")
	)
	(segment
		(start 79.684372 -395.236192)
		(end 77.69352 -393.245086)
		(width 0.1651)
		(layer "In13.Cu")
		(net "P5E_PEX0_STN6_TX_C_DN<108>")
	)
	(segment
		(start 78.509876 -410.589984)
		(end 78.509876 -410.207968)
		(width 0.1651)
		(layer "In13.Cu")
		(net "P5E_PEX0_STN6_TX_C_DN<108>")
	)
	(segment
		(start 78.509876 -410.207968)
		(end 78.636876 -410.080968)
		(width 0.1651)
		(layer "In13.Cu")
		(net "P5E_PEX0_STN6_TX_C_DN<108>")
	)
	(segment
		(start 67.011042 -368.852704)
		(end 68.162932 -361.09021)
		(width 0.1651)
		(layer "In13.Cu")
		(net "P5E_PEX0_STN6_TX_C_DN<108>")
	)
	(segment
		(start 69.687186 -388.965186)
		(end 68.004182 -387.282182)
		(width 0.1651)
		(layer "In13.Cu")
		(net "P5E_PEX0_STN6_TX_C_DN<108>")
	)
	(segment
		(start 68.162932 -358.04856)
		(end 68.453762 -357.75773)
		(width 0.1651)
		(layer "In13.Cu")
		(net "P5E_PEX0_STN6_TX_C_DN<108>")
	)
	(segment
		(start 68.004182 -387.282182)
		(end 66.690494 -384.11023)
		(width 0.1651)
		(layer "In13.Cu")
		(net "P5E_PEX0_STN6_TX_C_DN<108>")
	)
	(segment
		(start 77.69352 -393.245086)
		(end 69.687186 -388.965186)
		(width 0.1651)
		(layer "In13.Cu")
		(net "P5E_PEX0_STN6_TX_C_DN<108>")
	)
	(segment
		(start 79.28102 -410.080968)
		(end 79.684372 -409.677616)
		(width 0.1651)
		(layer "In13.Cu")
		(net "P5E_PEX0_STN6_TX_C_DN<108>")
	)
	(segment
		(start 78.636876 -410.080968)
		(end 79.28102 -410.080968)
		(width 0.1651)
		(layer "In13.Cu")
		(net "P5E_PEX0_STN6_TX_C_DN<108>")
	)
	(segment
		(start 66.690494 -382.171702)
		(end 67.011042 -368.852704)
		(width 0.1651)
		(layer "In13.Cu")
		(net "P5E_PEX0_STN6_TX_C_DN<108>")
	)
	(segment
		(start 66.690494 -384.11023)
		(end 66.690494 -382.171702)
		(width 0.1651)
		(layer "In13.Cu")
		(net "P5E_PEX0_STN6_TX_C_DN<108>")
	)
	(segment
		(start 68.162932 -361.09021)
		(end 68.162932 -358.04856)
		(width 0.1651)
		(layer "In13.Cu")
		(net "P5E_PEX0_STN6_TX_C_DN<108>")
	)
	(segment
		(start 209.865468 -30.790134)
		(end 209.364834 -30.790134)
		(width 0.13462)
		(layer "F.Cu")
		(net "P5E_PEX1_STN2_TX_C_DP<33>")
	)
	(segment
		(start 210.023202 -30.6324)
		(end 209.865468 -30.790134)
		(width 0.13462)
		(layer "F.Cu")
		(net "P5E_PEX1_STN2_TX_C_DP<33>")
	)
	(segment
		(start 213.954106 -30.6324)
		(end 210.023202 -30.6324)
		(width 0.13462)
		(layer "F.Cu")
		(net "P5E_PEX1_STN2_TX_C_DP<33>")
	)
	(segment
		(start 214.267796 -30.94609)
		(end 213.954106 -30.6324)
		(width 0.13462)
		(layer "F.Cu")
		(net "P5E_PEX1_STN2_TX_C_DP<33>")
	)
	(segment
		(start 283.915612 -324.966838)
		(end 283.915612 -319.916048)
		(width 0.1651)
		(layer "In9.Cu")
		(net "P5E_PEX2_STN6_RX_DN<102>")
	)
	(segment
		(start 333.045054 -367.219738)
		(end 315.323982 -360.387646)
		(width 0.1651)
		(layer "In9.Cu")
		(net "P5E_PEX2_STN6_RX_DN<102>")
	)
	(segment
		(start 301.394622 -340.662006)
		(end 287.896808 -330.027534)
		(width 0.1651)
		(layer "In9.Cu")
		(net "P5E_PEX2_STN6_RX_DN<102>")
	)
	(segment
		(start 286.311848 -328.337926)
		(end 285.959296 -327.989692)
		(width 0.1651)
		(layer "In9.Cu")
		(net "P5E_PEX2_STN6_RX_DN<102>")
	)
	(segment
		(start 333.68996 -376.408188)
		(end 333.81696 -376.281188)
		(width 0.1651)
		(layer "In9.Cu")
		(net "P5E_PEX2_STN6_RX_DN<102>")
	)
	(segment
		(start 283.869892 -318.434212)
		(end 283.983938 -318.320166)
		(width 0.1143)
		(layer "In9.Cu")
		(net "P5E_PEX2_STN6_RX_DN<102>")
	)
	(segment
		(start 283.869892 -319.84188)
		(end 283.869892 -318.434212)
		(width 0.1143)
		(layer "In9.Cu")
		(net "P5E_PEX2_STN6_RX_DN<102>")
	)
	(segment
		(start 284.160722 -318.320166)
		(end 284.249876 -318.40932)
		(width 0.1143)
		(layer "In9.Cu")
		(net "P5E_PEX2_STN6_RX_DN<102>")
	)
	(segment
		(start 334.815942 -369.1001)
		(end 334.30464 -368.12474)
		(width 0.1651)
		(layer "In9.Cu")
		(net "P5E_PEX2_STN6_RX_DN<102>")
	)
	(segment
		(start 315.323982 -360.387646)
		(end 314.249562 -359.335832)
		(width 0.1651)
		(layer "In9.Cu")
		(net "P5E_PEX2_STN6_RX_DN<102>")
	)
	(segment
		(start 283.915612 -319.8876)
		(end 283.869892 -319.84188)
		(width 0.1143)
		(layer "In9.Cu")
		(net "P5E_PEX2_STN6_RX_DN<102>")
	)
	(segment
		(start 283.983938 -318.320166)
		(end 284.160722 -318.320166)
		(width 0.1143)
		(layer "In9.Cu")
		(net "P5E_PEX2_STN6_RX_DN<102>")
	)
	(segment
		(start 285.833566 -327.990454)
		(end 284.95879 -327.126854)
		(width 0.1651)
		(layer "In9.Cu")
		(net "P5E_PEX2_STN6_RX_DN<102>")
	)
	(segment
		(start 283.915612 -319.916048)
		(end 283.915612 -319.8876)
		(width 0.1143)
		(layer "In9.Cu")
		(net "P5E_PEX2_STN6_RX_DN<102>")
	)
	(segment
		(start 284.95879 -327.126854)
		(end 284.577028 -326.56399)
		(width 0.1651)
		(layer "In9.Cu")
		(net "P5E_PEX2_STN6_RX_DN<102>")
	)
	(segment
		(start 285.959296 -327.989692)
		(end 285.833566 -327.990454)
		(width 0.1651)
		(layer "In9.Cu")
		(net "P5E_PEX2_STN6_RX_DN<102>")
	)
	(segment
		(start 334.815942 -375.829322)
		(end 334.815942 -369.1001)
		(width 0.1651)
		(layer "In9.Cu")
		(net "P5E_PEX2_STN6_RX_DN<102>")
	)
	(segment
		(start 287.896808 -330.027534)
		(end 286.31261 -328.463656)
		(width 0.1651)
		(layer "In9.Cu")
		(net "P5E_PEX2_STN6_RX_DN<102>")
	)
	(segment
		(start 286.31261 -328.463656)
		(end 286.311848 -328.337926)
		(width 0.1651)
		(layer "In9.Cu")
		(net "P5E_PEX2_STN6_RX_DN<102>")
	)
	(segment
		(start 284.249876 -318.40932)
		(end 284.249876 -318.699896)
		(width 0.1143)
		(layer "In9.Cu")
		(net "P5E_PEX2_STN6_RX_DN<102>")
	)
	(segment
		(start 314.249562 -359.335832)
		(end 301.394622 -340.662006)
		(width 0.1651)
		(layer "In9.Cu")
		(net "P5E_PEX2_STN6_RX_DN<102>")
	)
	(segment
		(start 333.68996 -376.790204)
		(end 333.68996 -376.408188)
		(width 0.1651)
		(layer "In9.Cu")
		(net "P5E_PEX2_STN6_RX_DN<102>")
	)
	(segment
		(start 334.364076 -376.281188)
		(end 334.815942 -375.829322)
		(width 0.1651)
		(layer "In9.Cu")
		(net "P5E_PEX2_STN6_RX_DN<102>")
	)
	(segment
		(start 333.81696 -376.281188)
		(end 334.364076 -376.281188)
		(width 0.1651)
		(layer "In9.Cu")
		(net "P5E_PEX2_STN6_RX_DN<102>")
	)
	(segment
		(start 334.30464 -368.12474)
		(end 333.045054 -367.219738)
		(width 0.1651)
		(layer "In9.Cu")
		(net "P5E_PEX2_STN6_RX_DN<102>")
	)
	(segment
		(start 284.577028 -326.56399)
		(end 283.915612 -324.966838)
		(width 0.1651)
		(layer "In9.Cu")
		(net "P5E_PEX2_STN6_RX_DN<102>")
	)
	(segment
		(start 387.847332 -111.003334)
		(end 388.162546 -110.68812)
		(width 0.13462)
		(layer "F.Cu")
		(net "P5E_PEX3_STN1_TX_C_DN<22>")
	)
	(segment
		(start 388.162546 -110.68812)
		(end 393.678664 -110.68812)
		(width 0.13462)
		(layer "F.Cu")
		(net "P5E_PEX3_STN1_TX_C_DN<22>")
	)
	(segment
		(start 393.678664 -110.68812)
		(end 393.835636 -110.845092)
		(width 0.13462)
		(layer "F.Cu")
		(net "P5E_PEX3_STN1_TX_C_DN<22>")
	)
	(segment
		(start 393.835636 -110.845092)
		(end 394.342366 -110.845092)
		(width 0.13462)
		(layer "F.Cu")
		(net "P5E_PEX3_STN1_TX_C_DN<22>")
	)
	(segment
		(start 381.901192 -393.956286)
		(end 376.594878 -390.906)
		(width 0.1651)
		(layer "In15.Cu")
		(net "P5E_PEX3_STN6_RX_DN<108>")
	)
	(segment
		(start 385.64439 -329.299824)
		(end 392.03122 -324.62978)
		(width 0.1651)
		(layer "In15.Cu")
		(net "P5E_PEX3_STN6_RX_DN<108>")
	)
	(segment
		(start 382.614678 -394.7414)
		(end 381.901192 -393.956286)
		(width 0.1651)
		(layer "In15.Cu")
		(net "P5E_PEX3_STN6_RX_DN<108>")
	)
	(segment
		(start 376.594878 -390.906)
		(end 374.209056 -389.863838)
		(width 0.1651)
		(layer "In15.Cu")
		(net "P5E_PEX3_STN6_RX_DN<108>")
	)
	(segment
		(start 394.315696 -321.313556)
		(end 394.315696 -319.995296)
		(width 0.1651)
		(layer "In15.Cu")
		(net "P5E_PEX3_STN6_RX_DN<108>")
	)
	(segment
		(start 383.215896 -401.82927)
		(end 383.215896 -396.24)
		(width 0.1651)
		(layer "In15.Cu")
		(net "P5E_PEX3_STN6_RX_DN<108>")
	)
	(segment
		(start 382.216914 -402.281136)
		(end 382.76403 -402.281136)
		(width 0.1651)
		(layer "In15.Cu")
		(net "P5E_PEX3_STN6_RX_DN<108>")
	)
	(segment
		(start 370.95938 -341.023194)
		(end 385.64439 -329.299824)
		(width 0.1651)
		(layer "In15.Cu")
		(net "P5E_PEX3_STN6_RX_DN<108>")
	)
	(segment
		(start 394.373862 -318.320166)
		(end 394.53566 -318.320166)
		(width 0.1143)
		(layer "In15.Cu")
		(net "P5E_PEX3_STN6_RX_DN<108>")
	)
	(segment
		(start 383.215896 -396.24)
		(end 382.614678 -394.7414)
		(width 0.1651)
		(layer "In15.Cu")
		(net "P5E_PEX3_STN6_RX_DN<108>")
	)
	(segment
		(start 392.03122 -324.62978)
		(end 394.058648 -321.934332)
		(width 0.1651)
		(layer "In15.Cu")
		(net "P5E_PEX3_STN6_RX_DN<108>")
	)
	(segment
		(start 382.76403 -402.281136)
		(end 383.215896 -401.82927)
		(width 0.1651)
		(layer "In15.Cu")
		(net "P5E_PEX3_STN6_RX_DN<108>")
	)
	(segment
		(start 370.016532 -372.485666)
		(end 370.01577 -372.484904)
		(width 0.1651)
		(layer "In15.Cu")
		(net "P5E_PEX3_STN6_RX_DN<108>")
	)
	(segment
		(start 394.315696 -319.966848)
		(end 394.269976 -319.921128)
		(width 0.1143)
		(layer "In15.Cu")
		(net "P5E_PEX3_STN6_RX_DN<108>")
	)
	(segment
		(start 370.044726 -371.969284)
		(end 370.173504 -342.426544)
		(width 0.1651)
		(layer "In15.Cu")
		(net "P5E_PEX3_STN6_RX_DN<108>")
	)
	(segment
		(start 382.089914 -402.790152)
		(end 382.089914 -402.408136)
		(width 0.1651)
		(layer "In15.Cu")
		(net "P5E_PEX3_STN6_RX_DN<108>")
	)
	(segment
		(start 394.269976 -319.921128)
		(end 394.269976 -318.424052)
		(width 0.1143)
		(layer "In15.Cu")
		(net "P5E_PEX3_STN6_RX_DN<108>")
	)
	(segment
		(start 394.315696 -319.995296)
		(end 394.315696 -319.966848)
		(width 0.1143)
		(layer "In15.Cu")
		(net "P5E_PEX3_STN6_RX_DN<108>")
	)
	(segment
		(start 370.01577 -372.484142)
		(end 370.044726 -371.969284)
		(width 0.1651)
		(layer "In15.Cu")
		(net "P5E_PEX3_STN6_RX_DN<108>")
	)
	(segment
		(start 394.53566 -318.320166)
		(end 394.64996 -318.434466)
		(width 0.1143)
		(layer "In15.Cu")
		(net "P5E_PEX3_STN6_RX_DN<108>")
	)
	(segment
		(start 371.466618 -387.854444)
		(end 370.548154 -385.473702)
		(width 0.1651)
		(layer "In15.Cu")
		(net "P5E_PEX3_STN6_RX_DN<108>")
	)
	(segment
		(start 370.209826 -342.247982)
		(end 370.95938 -341.023194)
		(width 0.1651)
		(layer "In15.Cu")
		(net "P5E_PEX3_STN6_RX_DN<108>")
	)
	(segment
		(start 382.089914 -402.408136)
		(end 382.216914 -402.281136)
		(width 0.1651)
		(layer "In15.Cu")
		(net "P5E_PEX3_STN6_RX_DN<108>")
	)
	(segment
		(start 394.058648 -321.934332)
		(end 394.315696 -321.313556)
		(width 0.1651)
		(layer "In15.Cu")
		(net "P5E_PEX3_STN6_RX_DN<108>")
	)
	(segment
		(start 394.64996 -318.434466)
		(end 394.64996 -318.699896)
		(width 0.1143)
		(layer "In15.Cu")
		(net "P5E_PEX3_STN6_RX_DN<108>")
	)
	(segment
		(start 370.548154 -385.473702)
		(end 370.016532 -372.485666)
		(width 0.1651)
		(layer "In15.Cu")
		(net "P5E_PEX3_STN6_RX_DN<108>")
	)
	(segment
		(start 370.01577 -372.484904)
		(end 370.01577 -372.484142)
		(width 0.1651)
		(layer "In15.Cu")
		(net "P5E_PEX3_STN6_RX_DN<108>")
	)
	(segment
		(start 394.269976 -318.424052)
		(end 394.373862 -318.320166)
		(width 0.1143)
		(layer "In15.Cu")
		(net "P5E_PEX3_STN6_RX_DN<108>")
	)
	(segment
		(start 370.173504 -342.426544)
		(end 370.209826 -342.247982)
		(width 0.1651)
		(layer "In15.Cu")
		(net "P5E_PEX3_STN6_RX_DN<108>")
	)
	(segment
		(start 374.209056 -389.863838)
		(end 371.466618 -387.854444)
		(width 0.1651)
		(layer "In15.Cu")
		(net "P5E_PEX3_STN6_RX_DN<108>")
	)
	(segment
		(start 192.809368 -158.35503)
		(end 189.357508 -158.35503)
		(width 0.13208)
		(layer "F.Cu")
		(net "PRSNTB3_NIC3_N")
	)
	(segment
		(start 192.94475 -158.219648)
		(end 192.809368 -158.35503)
		(width 0.13208)
		(layer "F.Cu")
		(net "PRSNTB3_NIC3_N")
	)
	(segment
		(start 195.031868 -158.219648)
		(end 192.94475 -158.219648)
		(width 0.13208)
		(layer "F.Cu")
		(net "PRSNTB3_NIC3_N")
	)
	(segment
		(start 195.031868 -158.219648)
		(end 196.239384 -158.219648)
		(width 0.13208)
		(layer "F.Cu")
		(net "PRSNTB3_NIC3_N")
	)
	(segment
		(start 196.239384 -159.235648)
		(end 196.239384 -158.219648)
		(width 0.13208)
		(layer "F.Cu")
		(net "PRSNTB3_NIC3_N")
	)
	(via
		(at 195.031868 -158.219648)
		(size 0.762)
		(drill 0.381)
		(layers "F.Cu" "B.Cu")
		(net "PRSNTB3_NIC3_N")
	)
	(segment
		(start 391.304018 -156.481526)
		(end 391.82548 -155.960064)
		(width 0.13208)
		(layer "F.Cu")
		(net "NIC6_DATA_OUT")
	)
	(segment
		(start 388.493508 -156.481526)
		(end 391.304018 -156.481526)
		(width 0.13208)
		(layer "F.Cu")
		(net "NIC6_DATA_OUT")
	)
	(segment
		(start 387.82752 -156.481526)
		(end 388.493508 -156.481526)
		(width 0.13208)
		(layer "F.Cu")
		(net "NIC6_DATA_OUT")
	)
	(segment
		(start 387.708394 -156.3624)
		(end 387.82752 -156.481526)
		(width 0.13208)
		(layer "F.Cu")
		(net "NIC6_DATA_OUT")
	)
	(segment
		(start 391.82548 -155.960064)
		(end 394.342366 -155.960064)
		(width 0.13208)
		(layer "F.Cu")
		(net "NIC6_DATA_OUT")
	)
	(segment
		(start 387.30809 -156.3624)
		(end 387.708394 -156.3624)
		(width 0.13208)
		(layer "F.Cu")
		(net "NIC6_DATA_OUT")
	)
	(via
		(at 388.493508 -156.481526)
		(size 0.762)
		(drill 0.381)
		(layers "F.Cu" "B.Cu")
		(net "NIC6_DATA_OUT")
	)
	(segment
		(start 247.464834 -23.589996)
		(end 248.666508 -23.589996)
		(width 0.13208)
		(layer "F.Cu")
		(net "DUALPORT_N_SSD8")
	)
	(segment
		(start 251.671582 -24.910542)
		(end 251.671582 -24.942292)
		(width 0.13208)
		(layer "F.Cu")
		(net "DUALPORT_N_SSD8")
	)
	(segment
		(start 248.666508 -23.589996)
		(end 248.666508 -24.134572)
		(width 0.13208)
		(layer "F.Cu")
		(net "DUALPORT_N_SSD8")
	)
	(segment
		(start 248.666508 -24.134572)
		(end 249.020584 -24.488648)
		(width 0.13208)
		(layer "F.Cu")
		(net "DUALPORT_N_SSD8")
	)
	(segment
		(start 252.687582 -24.942292)
		(end 251.671582 -24.942292)
		(width 0.13208)
		(layer "F.Cu")
		(net "DUALPORT_N_SSD8")
	)
	(segment
		(start 249.020584 -24.488648)
		(end 251.249688 -24.488648)
		(width 0.13208)
		(layer "F.Cu")
		(net "DUALPORT_N_SSD8")
	)
	(segment
		(start 251.249688 -24.488648)
		(end 251.671582 -24.910542)
		(width 0.13208)
		(layer "F.Cu")
		(net "DUALPORT_N_SSD8")
	)
	(via
		(at 248.666508 -23.589996)
		(size 0.508)
		(drill 0.254)
		(layers "F.Cu" "B.Cu")
		(net "DUALPORT_N_SSD8")
	)
	(segment
		(start 86.812882 -357.46309)
		(end 86.812882 -356.831646)
		(width 0.13462)
		(layer "F.Cu")
		(net "P5E_PEX0_STN6_TX_C_DN<99>")
	)
	(segment
		(start 86.812882 -356.831646)
		(end 87.132922 -356.511606)
		(width 0.13462)
		(layer "F.Cu")
		(net "P5E_PEX0_STN6_TX_C_DN<99>")
	)
	(segment
		(start 87.107522 -357.75773)
		(end 86.812882 -357.46309)
		(width 0.13462)
		(layer "F.Cu")
		(net "P5E_PEX0_STN6_TX_C_DN<99>")
	)
	(segment
		(start 81.884266 -369.537742)
		(end 86.816692 -359.109264)
		(width 0.1651)
		(layer "In13.Cu")
		(net "P5E_PEX0_STN6_TX_C_DN<99>")
	)
	(segment
		(start 81.44383 -382.9812)
		(end 81.884266 -382.540764)
		(width 0.1651)
		(layer "In13.Cu")
		(net "P5E_PEX0_STN6_TX_C_DN<99>")
	)
	(segment
		(start 80.837024 -382.9812)
		(end 81.44383 -382.9812)
		(width 0.1651)
		(layer "In13.Cu")
		(net "P5E_PEX0_STN6_TX_C_DN<99>")
	)
	(segment
		(start 80.710024 -383.490216)
		(end 80.710024 -383.1082)
		(width 0.1651)
		(layer "In13.Cu")
		(net "P5E_PEX0_STN6_TX_C_DN<99>")
	)
	(segment
		(start 81.884266 -382.540764)
		(end 81.884266 -369.537742)
		(width 0.1651)
		(layer "In13.Cu")
		(net "P5E_PEX0_STN6_TX_C_DN<99>")
	)
	(segment
		(start 86.816692 -359.109264)
		(end 86.816692 -358.04856)
		(width 0.1651)
		(layer "In13.Cu")
		(net "P5E_PEX0_STN6_TX_C_DN<99>")
	)
	(segment
		(start 86.816692 -358.04856)
		(end 87.107522 -357.75773)
		(width 0.1651)
		(layer "In13.Cu")
		(net "P5E_PEX0_STN6_TX_C_DN<99>")
	)
	(segment
		(start 80.710024 -383.1082)
		(end 80.837024 -382.9812)
		(width 0.1651)
		(layer "In13.Cu")
		(net "P5E_PEX0_STN6_TX_C_DN<99>")
	)
	(segment
		(start 204.125322 -32.14878)
		(end 203.454762 -32.14878)
		(width 0.13462)
		(layer "F.Cu")
		(net "P5E_PEX1_STN2_RX_DN<34>")
	)
	(segment
		(start 204.764894 -31.99003)
		(end 204.284072 -31.99003)
		(width 0.13462)
		(layer "F.Cu")
		(net "P5E_PEX1_STN2_RX_DN<34>")
	)
	(segment
		(start 204.284072 -31.99003)
		(end 204.125322 -32.14878)
		(width 0.13462)
		(layer "F.Cu")
		(net "P5E_PEX1_STN2_RX_DN<34>")
	)
	(segment
		(start 203.454762 -32.14878)
		(end 203.164694 -31.858712)
		(width 0.13462)
		(layer "F.Cu")
		(net "P5E_PEX1_STN2_RX_DN<34>")
	)
	(segment
		(start 194.156838 -116.602764)
		(end 205.1431 -61.227716)
		(width 0.1651)
		(layer "In7.Cu")
		(net "P5E_PEX1_STN2_RX_DN<34>")
	)
	(segment
		(start 203.90104 -32.149542)
		(end 203.455524 -32.149542)
		(width 0.1651)
		(layer "In7.Cu")
		(net "P5E_PEX1_STN2_RX_DN<34>")
	)
	(segment
		(start 172.623988 -275.379688)
		(end 172.520102 -275.275802)
		(width 0.1143)
		(layer "In7.Cu")
		(net "P5E_PEX1_STN2_RX_DN<34>")
	)
	(segment
		(start 192.451736 -154.552142)
		(end 193.842132 -143.750284)
		(width 0.1651)
		(layer "In7.Cu")
		(net "P5E_PEX1_STN2_RX_DN<34>")
	)
	(segment
		(start 204.54239 -32.790892)
		(end 203.90104 -32.149542)
		(width 0.1651)
		(layer "In7.Cu")
		(net "P5E_PEX1_STN2_RX_DN<34>")
	)
	(segment
		(start 204.508354 -34.984944)
		(end 204.54239 -32.790892)
		(width 0.1651)
		(layer "In7.Cu")
		(net "P5E_PEX1_STN2_RX_DN<34>")
	)
	(segment
		(start 204.013054 -39.71036)
		(end 203.983082 -37.803074)
		(width 0.1651)
		(layer "In7.Cu")
		(net "P5E_PEX1_STN2_RX_DN<34>")
	)
	(segment
		(start 172.89272 -266.859512)
		(end 192.451736 -154.552142)
		(width 0.1651)
		(layer "In7.Cu")
		(net "P5E_PEX1_STN2_RX_DN<34>")
	)
	(segment
		(start 203.455524 -32.149542)
		(end 203.164694 -31.858712)
		(width 0.1651)
		(layer "In7.Cu")
		(net "P5E_PEX1_STN2_RX_DN<34>")
	)
	(segment
		(start 203.983082 -37.803074)
		(end 204.508354 -34.984944)
		(width 0.1651)
		(layer "In7.Cu")
		(net "P5E_PEX1_STN2_RX_DN<34>")
	)
	(segment
		(start 172.785786 -275.379688)
		(end 172.623988 -275.379688)
		(width 0.1143)
		(layer "In7.Cu")
		(net "P5E_PEX1_STN2_RX_DN<34>")
	)
	(segment
		(start 205.1431 -61.227716)
		(end 205.32725 -49.435766)
		(width 0.1651)
		(layer "In7.Cu")
		(net "P5E_PEX1_STN2_RX_DN<34>")
	)
	(segment
		(start 172.900086 -274.999958)
		(end 172.900086 -275.265388)
		(width 0.1143)
		(layer "In7.Cu")
		(net "P5E_PEX1_STN2_RX_DN<34>")
	)
	(segment
		(start 172.565822 -270.653256)
		(end 172.89272 -266.859512)
		(width 0.1651)
		(layer "In7.Cu")
		(net "P5E_PEX1_STN2_RX_DN<34>")
	)
	(segment
		(start 172.520102 -271.467072)
		(end 172.565822 -271.421352)
		(width 0.1143)
		(layer "In7.Cu")
		(net "P5E_PEX1_STN2_RX_DN<34>")
	)
	(segment
		(start 172.565822 -271.392904)
		(end 172.565822 -270.653256)
		(width 0.1651)
		(layer "In7.Cu")
		(net "P5E_PEX1_STN2_RX_DN<34>")
	)
	(segment
		(start 205.32725 -49.435766)
		(end 204.013054 -39.71036)
		(width 0.1651)
		(layer "In7.Cu")
		(net "P5E_PEX1_STN2_RX_DN<34>")
	)
	(segment
		(start 172.565822 -271.421352)
		(end 172.565822 -271.392904)
		(width 0.1143)
		(layer "In7.Cu")
		(net "P5E_PEX1_STN2_RX_DN<34>")
	)
	(segment
		(start 172.900086 -275.265388)
		(end 172.785786 -275.379688)
		(width 0.1143)
		(layer "In7.Cu")
		(net "P5E_PEX1_STN2_RX_DN<34>")
	)
	(segment
		(start 172.520102 -275.275802)
		(end 172.520102 -271.467072)
		(width 0.1143)
		(layer "In7.Cu")
		(net "P5E_PEX1_STN2_RX_DN<34>")
	)
	(segment
		(start 193.842132 -143.750284)
		(end 194.156838 -116.602764)
		(width 0.1651)
		(layer "In7.Cu")
		(net "P5E_PEX1_STN2_RX_DN<34>")
	)
	(segment
		(start 300.212506 -150.11908)
		(end 300.37659 -149.954996)
		(width 0.13462)
		(layer "F.Cu")
		(net "P5E_PEX2_STN0_RX_DN<12>")
	)
	(segment
		(start 300.37659 -149.954996)
		(end 300.857412 -149.954996)
		(width 0.13462)
		(layer "F.Cu")
		(net "P5E_PEX2_STN0_RX_DN<12>")
	)
	(segment
		(start 299.552614 -150.11908)
		(end 300.212506 -150.11908)
		(width 0.13462)
		(layer "F.Cu")
		(net "P5E_PEX2_STN0_RX_DN<12>")
	)
	(segment
		(start 299.257212 -149.823678)
		(end 299.552614 -150.11908)
		(width 0.13462)
		(layer "F.Cu")
		(net "P5E_PEX2_STN0_RX_DN<12>")
	)
	(segment
		(start 309.785258 -275.379688)
		(end 309.899558 -275.265388)
		(width 0.1143)
		(layer "In5.Cu")
		(net "P5E_PEX2_STN0_RX_DN<12>")
	)
	(segment
		(start 305.342798 -158.362396)
		(end 306.502308 -161.1503)
		(width 0.1651)
		(layer "In5.Cu")
		(net "P5E_PEX2_STN0_RX_DN<12>")
	)
	(segment
		(start 305.33213 -158.336488)
		(end 305.343052 -158.362396)
		(width 0.1651)
		(layer "In5.Cu")
		(net "P5E_PEX2_STN0_RX_DN<12>")
	)
	(segment
		(start 305.343052 -158.362396)
		(end 305.342798 -158.362396)
		(width 0.1651)
		(layer "In5.Cu")
		(net "P5E_PEX2_STN0_RX_DN<12>")
	)
	(segment
		(start 299.548042 -150.114508)
		(end 300.138338 -150.114508)
		(width 0.1651)
		(layer "In5.Cu")
		(net "P5E_PEX2_STN0_RX_DN<12>")
	)
	(segment
		(start 302.54321 -153.725372)
		(end 302.543718 -153.725626)
		(width 0.1651)
		(layer "In5.Cu")
		(net "P5E_PEX2_STN0_RX_DN<12>")
	)
	(segment
		(start 300.138338 -150.114508)
		(end 301.648876 -151.59863)
		(width 0.1651)
		(layer "In5.Cu")
		(net "P5E_PEX2_STN0_RX_DN<12>")
	)
	(segment
		(start 309.565802 -270.786098)
		(end 309.565802 -271.570958)
		(width 0.1651)
		(layer "In5.Cu")
		(net "P5E_PEX2_STN0_RX_DN<12>")
	)
	(segment
		(start 309.565802 -271.599406)
		(end 309.520082 -271.645126)
		(width 0.1143)
		(layer "In5.Cu")
		(net "P5E_PEX2_STN0_RX_DN<12>")
	)
	(segment
		(start 310.032654 -260.768084)
		(end 310.095392 -268.061186)
		(width 0.1651)
		(layer "In5.Cu")
		(net "P5E_PEX2_STN0_RX_DN<12>")
	)
	(segment
		(start 299.257212 -149.823678)
		(end 299.548042 -150.114508)
		(width 0.1651)
		(layer "In5.Cu")
		(net "P5E_PEX2_STN0_RX_DN<12>")
	)
	(segment
		(start 301.648876 -151.59863)
		(end 302.54321 -153.725372)
		(width 0.1651)
		(layer "In5.Cu")
		(net "P5E_PEX2_STN0_RX_DN<12>")
	)
	(segment
		(start 309.520082 -271.645126)
		(end 309.520082 -275.27631)
		(width 0.1143)
		(layer "In5.Cu")
		(net "P5E_PEX2_STN0_RX_DN<12>")
	)
	(segment
		(start 309.520082 -275.27631)
		(end 309.62346 -275.379688)
		(width 0.1143)
		(layer "In5.Cu")
		(net "P5E_PEX2_STN0_RX_DN<12>")
	)
	(segment
		(start 302.543718 -153.725626)
		(end 303.067466 -154.97175)
		(width 0.1651)
		(layer "In5.Cu")
		(net "P5E_PEX2_STN0_RX_DN<12>")
	)
	(segment
		(start 306.502308 -161.1503)
		(end 310.032654 -260.768084)
		(width 0.1651)
		(layer "In5.Cu")
		(net "P5E_PEX2_STN0_RX_DN<12>")
	)
	(segment
		(start 303.067466 -154.97175)
		(end 305.33213 -158.336488)
		(width 0.1651)
		(layer "In5.Cu")
		(net "P5E_PEX2_STN0_RX_DN<12>")
	)
	(segment
		(start 309.62346 -275.379688)
		(end 309.785258 -275.379688)
		(width 0.1143)
		(layer "In5.Cu")
		(net "P5E_PEX2_STN0_RX_DN<12>")
	)
	(segment
		(start 309.899558 -275.265388)
		(end 309.899558 -274.999958)
		(width 0.1143)
		(layer "In5.Cu")
		(net "P5E_PEX2_STN0_RX_DN<12>")
	)
	(segment
		(start 310.095392 -268.061186)
		(end 309.565802 -270.786098)
		(width 0.1651)
		(layer "In5.Cu")
		(net "P5E_PEX2_STN0_RX_DN<12>")
	)
	(segment
		(start 309.565802 -271.570958)
		(end 309.565802 -271.599406)
		(width 0.1143)
		(layer "In5.Cu")
		(net "P5E_PEX2_STN0_RX_DN<12>")
	)
	(segment
		(start 334.240124 -350.365314)
		(end 334.560164 -350.685354)
		(width 0.13462)
		(layer "F.Cu")
		(net "P5E_PEX2_STN6_TX_C_DP<101>")
	)
	(segment
		(start 334.560164 -351.316798)
		(end 334.265524 -351.611438)
		(width 0.13462)
		(layer "F.Cu")
		(net "P5E_PEX2_STN6_TX_C_DP<101>")
	)
	(segment
		(start 334.560164 -350.685354)
		(end 334.560164 -351.316798)
		(width 0.13462)
		(layer "F.Cu")
		(net "P5E_PEX2_STN6_TX_C_DP<101>")
	)
	(segment
		(start 335.193132 -365.132874)
		(end 335.019396 -364.668562)
		(width 0.1651)
		(layer "In13.Cu")
		(net "P5E_PEX2_STN6_TX_C_DP<101>")
	)
	(segment
		(start 336.73415 -382.412494)
		(end 336.73415 -368.922554)
		(width 0.1651)
		(layer "In13.Cu")
		(net "P5E_PEX2_STN6_TX_C_DP<101>")
	)
	(segment
		(start 334.556354 -351.902268)
		(end 334.265524 -351.611438)
		(width 0.1651)
		(layer "In13.Cu")
		(net "P5E_PEX2_STN6_TX_C_DP<101>")
	)
	(segment
		(start 334.76565 -363.99089)
		(end 334.591914 -363.526578)
		(width 0.1651)
		(layer "In13.Cu")
		(net "P5E_PEX2_STN6_TX_C_DP<101>")
	)
	(segment
		(start 335.620614 -366.274604)
		(end 335.446878 -365.810546)
		(width 0.1651)
		(layer "In13.Cu")
		(net "P5E_PEX2_STN6_TX_C_DP<101>")
	)
	(segment
		(start 335.446878 -365.810546)
		(end 335.513934 -365.66348)
		(width 0.1651)
		(layer "In13.Cu")
		(net "P5E_PEX2_STN6_TX_C_DP<101>")
	)
	(segment
		(start 334.91297 -364.057692)
		(end 334.76565 -363.99089)
		(width 0.1651)
		(layer "In13.Cu")
		(net "P5E_PEX2_STN6_TX_C_DP<101>")
	)
	(segment
		(start 336.447384 -382.69926)
		(end 336.73415 -382.412494)
		(width 0.1651)
		(layer "In13.Cu")
		(net "P5E_PEX2_STN6_TX_C_DP<101>")
	)
	(segment
		(start 335.513934 -365.66348)
		(end 335.340452 -365.199676)
		(width 0.1651)
		(layer "In13.Cu")
		(net "P5E_PEX2_STN6_TX_C_DP<101>")
	)
	(segment
		(start 335.767934 -366.34166)
		(end 335.620614 -366.274604)
		(width 0.1651)
		(layer "In13.Cu")
		(net "P5E_PEX2_STN6_TX_C_DP<101>")
	)
	(segment
		(start 334.591914 -363.526578)
		(end 334.65897 -363.379512)
		(width 0.1651)
		(layer "In13.Cu")
		(net "P5E_PEX2_STN6_TX_C_DP<101>")
	)
	(segment
		(start 336.017108 -382.69926)
		(end 336.447384 -382.69926)
		(width 0.1651)
		(layer "In13.Cu")
		(net "P5E_PEX2_STN6_TX_C_DP<101>")
	)
	(segment
		(start 334.556354 -352.356166)
		(end 334.556354 -351.902268)
		(width 0.1651)
		(layer "In13.Cu")
		(net "P5E_PEX2_STN6_TX_C_DP<101>")
	)
	(segment
		(start 335.019396 -364.668562)
		(end 335.086452 -364.521496)
		(width 0.1651)
		(layer "In13.Cu")
		(net "P5E_PEX2_STN6_TX_C_DP<101>")
	)
	(segment
		(start 335.086452 -364.521496)
		(end 334.91297 -364.057692)
		(width 0.1651)
		(layer "In13.Cu")
		(net "P5E_PEX2_STN6_TX_C_DP<101>")
	)
	(segment
		(start 335.340452 -365.199676)
		(end 335.193132 -365.132874)
		(width 0.1651)
		(layer "In13.Cu")
		(net "P5E_PEX2_STN6_TX_C_DP<101>")
	)
	(segment
		(start 335.890108 -382.57226)
		(end 336.017108 -382.69926)
		(width 0.1651)
		(layer "In13.Cu")
		(net "P5E_PEX2_STN6_TX_C_DP<101>")
	)
	(segment
		(start 333.001874 -353.910646)
		(end 334.556354 -352.356166)
		(width 0.1651)
		(layer "In13.Cu")
		(net "P5E_PEX2_STN6_TX_C_DP<101>")
	)
	(segment
		(start 336.73415 -368.922554)
		(end 335.767934 -366.34166)
		(width 0.1651)
		(layer "In13.Cu")
		(net "P5E_PEX2_STN6_TX_C_DP<101>")
	)
	(segment
		(start 334.65897 -363.379512)
		(end 333.001874 -358.953054)
		(width 0.1651)
		(layer "In13.Cu")
		(net "P5E_PEX2_STN6_TX_C_DP<101>")
	)
	(segment
		(start 335.890108 -382.18999)
		(end 335.890108 -382.57226)
		(width 0.1651)
		(layer "In13.Cu")
		(net "P5E_PEX2_STN6_TX_C_DP<101>")
	)
	(segment
		(start 333.001874 -358.953054)
		(end 333.001874 -353.910646)
		(width 0.1651)
		(layer "In13.Cu")
		(net "P5E_PEX2_STN6_TX_C_DP<101>")
	)
	(segment
		(start 393.8397 -110.245144)
		(end 394.342366 -110.245144)
		(width 0.13462)
		(layer "F.Cu")
		(net "P5E_PEX3_STN1_TX_C_DP<22>")
	)
	(segment
		(start 388.172198 -110.4138)
		(end 393.671044 -110.4138)
		(width 0.13462)
		(layer "F.Cu")
		(net "P5E_PEX3_STN1_TX_C_DP<22>")
	)
	(segment
		(start 393.671044 -110.4138)
		(end 393.8397 -110.245144)
		(width 0.13462)
		(layer "F.Cu")
		(net "P5E_PEX3_STN1_TX_C_DP<22>")
	)
	(segment
		(start 387.847332 -110.088934)
		(end 388.172198 -110.4138)
		(width 0.13462)
		(layer "F.Cu")
		(net "P5E_PEX3_STN1_TX_C_DP<22>")
	)
	(segment
		(start 375.18594 -350.365314)
		(end 374.866408 -350.684846)
		(width 0.13462)
		(layer "F.Cu")
		(net "P5E_PEX3_STN6_TX_C_DN<110>")
	)
	(segment
		(start 374.866408 -351.317306)
		(end 375.16054 -351.611438)
		(width 0.13462)
		(layer "F.Cu")
		(net "P5E_PEX3_STN6_TX_C_DN<110>")
	)
	(segment
		(start 374.866408 -350.684846)
		(end 374.866408 -351.317306)
		(width 0.13462)
		(layer "F.Cu")
		(net "P5E_PEX3_STN6_TX_C_DN<110>")
	)
	(segment
		(start 378.234194 -395.006068)
		(end 378.220986 -395.113002)
		(width 0.1651)
		(layer "In13.Cu")
		(net "P5E_PEX3_STN6_TX_C_DN<110>")
	)
	(segment
		(start 368.612674 -367.177828)
		(end 367.963704 -373.33174)
		(width 0.1651)
		(layer "In13.Cu")
		(net "P5E_PEX3_STN6_TX_C_DN<110>")
	)
	(segment
		(start 378.815854 -396.494)
		(end 378.815854 -409.629102)
		(width 0.1651)
		(layer "In13.Cu")
		(net "P5E_PEX3_STN6_TX_C_DN<110>")
	)
	(segment
		(start 378.815854 -409.629102)
		(end 378.363988 -410.080968)
		(width 0.1651)
		(layer "In13.Cu")
		(net "P5E_PEX3_STN6_TX_C_DN<110>")
	)
	(segment
		(start 377.816872 -410.080968)
		(end 377.689872 -410.207968)
		(width 0.1651)
		(layer "In13.Cu")
		(net "P5E_PEX3_STN6_TX_C_DN<110>")
	)
	(segment
		(start 374.86971 -352.473006)
		(end 373.314468 -354.028248)
		(width 0.1651)
		(layer "In13.Cu")
		(net "P5E_PEX3_STN6_TX_C_DN<110>")
	)
	(segment
		(start 369.856512 -389.064754)
		(end 373.168418 -391.555986)
		(width 0.1651)
		(layer "In13.Cu")
		(net "P5E_PEX3_STN6_TX_C_DN<110>")
	)
	(segment
		(start 373.168418 -391.555986)
		(end 375.680732 -392.684)
		(width 0.1651)
		(layer "In13.Cu")
		(net "P5E_PEX3_STN6_TX_C_DN<110>")
	)
	(segment
		(start 377.356878 -394.0048)
		(end 377.82246 -394.601954)
		(width 0.1651)
		(layer "In13.Cu")
		(net "P5E_PEX3_STN6_TX_C_DN<110>")
	)
	(segment
		(start 373.314468 -354.028248)
		(end 368.612674 -367.177828)
		(width 0.1651)
		(layer "In13.Cu")
		(net "P5E_PEX3_STN6_TX_C_DN<110>")
	)
	(segment
		(start 377.929394 -394.615162)
		(end 378.234194 -395.006068)
		(width 0.1651)
		(layer "In13.Cu")
		(net "P5E_PEX3_STN6_TX_C_DN<110>")
	)
	(segment
		(start 378.525278 -395.5034)
		(end 378.815854 -396.494)
		(width 0.1651)
		(layer "In13.Cu")
		(net "P5E_PEX3_STN6_TX_C_DN<110>")
	)
	(segment
		(start 374.86971 -351.902268)
		(end 374.86971 -352.473006)
		(width 0.1651)
		(layer "In13.Cu")
		(net "P5E_PEX3_STN6_TX_C_DN<110>")
	)
	(segment
		(start 377.689872 -410.207968)
		(end 377.689872 -410.589984)
		(width 0.1651)
		(layer "In13.Cu")
		(net "P5E_PEX3_STN6_TX_C_DN<110>")
	)
	(segment
		(start 377.82246 -394.601954)
		(end 377.929394 -394.615162)
		(width 0.1651)
		(layer "In13.Cu")
		(net "P5E_PEX3_STN6_TX_C_DN<110>")
	)
	(segment
		(start 378.363988 -410.080968)
		(end 377.816872 -410.080968)
		(width 0.1651)
		(layer "In13.Cu")
		(net "P5E_PEX3_STN6_TX_C_DN<110>")
	)
	(segment
		(start 378.220986 -395.113002)
		(end 378.525278 -395.5034)
		(width 0.1651)
		(layer "In13.Cu")
		(net "P5E_PEX3_STN6_TX_C_DN<110>")
	)
	(segment
		(start 375.680732 -392.684)
		(end 377.356878 -394.0048)
		(width 0.1651)
		(layer "In13.Cu")
		(net "P5E_PEX3_STN6_TX_C_DN<110>")
	)
	(segment
		(start 375.16054 -351.611438)
		(end 374.86971 -351.902268)
		(width 0.1651)
		(layer "In13.Cu")
		(net "P5E_PEX3_STN6_TX_C_DN<110>")
	)
	(segment
		(start 367.963704 -373.33174)
		(end 368.511582 -385.8133)
		(width 0.1651)
		(layer "In13.Cu")
		(net "P5E_PEX3_STN6_TX_C_DN<110>")
	)
	(segment
		(start 368.511582 -385.8133)
		(end 369.856512 -389.064754)
		(width 0.1651)
		(layer "In13.Cu")
		(net "P5E_PEX3_STN6_TX_C_DN<110>")
	)
	(segment
		(start 179.02301 -99.189794)
		(end 179.2732 -99.439984)
		(width 0.13208)
		(layer "F.Cu")
		(net "NIC3_RBT_ARB_OUT")
	)
	(segment
		(start 174.915068 -99.189794)
		(end 179.02301 -99.189794)
		(width 0.13208)
		(layer "F.Cu")
		(net "NIC3_RBT_ARB_OUT")
	)
	(segment
		(start 174.69485 -98.734372)
		(end 174.69485 -98.969576)
		(width 0.13208)
		(layer "F.Cu")
		(net "NIC3_RBT_ARB_OUT")
	)
	(segment
		(start 174.69485 -98.969576)
		(end 174.915068 -99.189794)
		(width 0.13208)
		(layer "F.Cu")
		(net "NIC3_RBT_ARB_OUT")
	)
	(segment
		(start 183.75376 -99.439984)
		(end 184.757314 -99.439984)
		(width 0.13208)
		(layer "F.Cu")
		(net "NIC3_RBT_ARB_OUT")
	)
	(segment
		(start 179.2732 -99.439984)
		(end 183.75376 -99.439984)
		(width 0.13208)
		(layer "F.Cu")
		(net "NIC3_RBT_ARB_OUT")
	)
	(via
		(at 183.75376 -99.439984)
		(size 0.508)
		(drill 0.254)
		(layers "F.Cu" "B.Cu")
		(net "NIC3_RBT_ARB_OUT")
	)
	(segment
		(start 390.673082 -155.360116)
		(end 394.342366 -155.360116)
		(width 0.13208)
		(layer "F.Cu")
		(net "NIC6_CLK")
	)
	(segment
		(start 387.30809 -155.3464)
		(end 387.85673 -155.3464)
		(width 0.13208)
		(layer "F.Cu")
		(net "NIC6_CLK")
	)
	(segment
		(start 390.53897 -155.226004)
		(end 390.673082 -155.360116)
		(width 0.13208)
		(layer "F.Cu")
		(net "NIC6_CLK")
	)
	(segment
		(start 387.85673 -155.3464)
		(end 387.977126 -155.226004)
		(width 0.13208)
		(layer "F.Cu")
		(net "NIC6_CLK")
	)
	(segment
		(start 388.698486 -155.226004)
		(end 390.53897 -155.226004)
		(width 0.13208)
		(layer "F.Cu")
		(net "NIC6_CLK")
	)
	(segment
		(start 387.977126 -155.226004)
		(end 388.698486 -155.226004)
		(width 0.13208)
		(layer "F.Cu")
		(net "NIC6_CLK")
	)
	(via
		(at 388.698486 -155.226004)
		(size 0.762)
		(drill 0.381)
		(layers "F.Cu" "B.Cu")
		(net "NIC6_CLK")
	)
	(segment
		(start 93.325442 -345.465146)
		(end 93.030802 -345.170506)
		(width 0.13462)
		(layer "F.Cu")
		(net "P5E_PEX0_STN6_TX_C_DN<97>")
	)
	(segment
		(start 93.030802 -345.170506)
		(end 93.030802 -344.539062)
		(width 0.13462)
		(layer "F.Cu")
		(net "P5E_PEX0_STN6_TX_C_DN<97>")
	)
	(segment
		(start 93.030802 -344.539062)
		(end 93.350842 -344.219022)
		(width 0.13462)
		(layer "F.Cu")
		(net "P5E_PEX0_STN6_TX_C_DN<97>")
	)
	(segment
		(start 85.843618 -382.9812)
		(end 86.284054 -382.540764)
		(width 0.1651)
		(layer "In13.Cu")
		(net "P5E_PEX0_STN6_TX_C_DN<97>")
	)
	(segment
		(start 91.480132 -347.983048)
		(end 93.034612 -346.428568)
		(width 0.1651)
		(layer "In13.Cu")
		(net "P5E_PEX0_STN6_TX_C_DN<97>")
	)
	(segment
		(start 86.284054 -382.540764)
		(end 86.284054 -369.267486)
		(width 0.1651)
		(layer "In13.Cu")
		(net "P5E_PEX0_STN6_TX_C_DN<97>")
	)
	(segment
		(start 85.109812 -383.1082)
		(end 85.236812 -382.9812)
		(width 0.1651)
		(layer "In13.Cu")
		(net "P5E_PEX0_STN6_TX_C_DN<97>")
	)
	(segment
		(start 93.034612 -345.755976)
		(end 93.325442 -345.465146)
		(width 0.1651)
		(layer "In13.Cu")
		(net "P5E_PEX0_STN6_TX_C_DN<97>")
	)
	(segment
		(start 86.284054 -369.267486)
		(end 91.480132 -358.281478)
		(width 0.1651)
		(layer "In13.Cu")
		(net "P5E_PEX0_STN6_TX_C_DN<97>")
	)
	(segment
		(start 85.109812 -383.490216)
		(end 85.109812 -383.1082)
		(width 0.1651)
		(layer "In13.Cu")
		(net "P5E_PEX0_STN6_TX_C_DN<97>")
	)
	(segment
		(start 85.236812 -382.9812)
		(end 85.843618 -382.9812)
		(width 0.1651)
		(layer "In13.Cu")
		(net "P5E_PEX0_STN6_TX_C_DN<97>")
	)
	(segment
		(start 91.480132 -358.281478)
		(end 91.480132 -347.983048)
		(width 0.1651)
		(layer "In13.Cu")
		(net "P5E_PEX0_STN6_TX_C_DN<97>")
	)
	(segment
		(start 93.034612 -346.428568)
		(end 93.034612 -345.755976)
		(width 0.1651)
		(layer "In13.Cu")
		(net "P5E_PEX0_STN6_TX_C_DN<97>")
	)
	(segment
		(start 131.868164 -31.99003)
		(end 131.36499 -31.99003)
		(width 0.13462)
		(layer "F.Cu")
		(net "P5E_PEX1_STN2_TX_C_DN<46>")
	)
	(segment
		(start 133.625844 -31.825184)
		(end 133.314948 -32.13608)
		(width 0.13462)
		(layer "F.Cu")
		(net "P5E_PEX1_STN2_TX_C_DN<46>")
	)
	(segment
		(start 133.314948 -32.13608)
		(end 132.014214 -32.13608)
		(width 0.13462)
		(layer "F.Cu")
		(net "P5E_PEX1_STN2_TX_C_DN<46>")
	)
	(segment
		(start 132.014214 -32.13608)
		(end 131.868164 -31.99003)
		(width 0.13462)
		(layer "F.Cu")
		(net "P5E_PEX1_STN2_TX_C_DN<46>")
	)
	(segment
		(start 305.960526 -142.755112)
		(end 305.457606 -142.755112)
		(width 0.13462)
		(layer "F.Cu")
		(net "P5E_PEX2_STN0_TX_C_DN<8>")
	)
	(segment
		(start 311.95264 -142.590266)
		(end 311.63133 -142.911576)
		(width 0.13462)
		(layer "F.Cu")
		(net "P5E_PEX2_STN0_TX_C_DN<8>")
	)
	(segment
		(start 306.11699 -142.911576)
		(end 305.960526 -142.755112)
		(width 0.13462)
		(layer "F.Cu")
		(net "P5E_PEX2_STN0_TX_C_DN<8>")
	)
	(segment
		(start 311.63133 -142.911576)
		(end 306.11699 -142.911576)
		(width 0.13462)
		(layer "F.Cu")
		(net "P5E_PEX2_STN0_TX_C_DN<8>")
	)
	(segment
		(start 337.01609 -400.729196)
		(end 337.01609 -395.017752)
		(width 0.1651)
		(layer "In5.Cu")
		(net "P5E_PEX2_STN6_RX_DN<109>")
	)
	(segment
		(start 336.3849 -394.13434)
		(end 333.55153 -392.254486)
		(width 0.1651)
		(layer "In5.Cu")
		(net "P5E_PEX2_STN6_RX_DN<109>")
	)
	(segment
		(start 333.55153 -392.254486)
		(end 328.219308 -390.040114)
		(width 0.1651)
		(layer "In5.Cu")
		(net "P5E_PEX2_STN6_RX_DN<109>")
	)
	(segment
		(start 337.01609 -395.017752)
		(end 336.821526 -394.564108)
		(width 0.1651)
		(layer "In5.Cu")
		(net "P5E_PEX2_STN6_RX_DN<109>")
	)
	(segment
		(start 303.93767 -338.157312)
		(end 279.494996 -324.952106)
		(width 0.1651)
		(layer "In5.Cu")
		(net "P5E_PEX2_STN6_RX_DN<109>")
	)
	(segment
		(start 277.220172 -319.96888)
		(end 277.220172 -316.534292)
		(width 0.1143)
		(layer "In5.Cu")
		(net "P5E_PEX2_STN6_RX_DN<109>")
	)
	(segment
		(start 335.890108 -401.308062)
		(end 336.017108 -401.181062)
		(width 0.1651)
		(layer "In5.Cu")
		(net "P5E_PEX2_STN6_RX_DN<109>")
	)
	(segment
		(start 279.494996 -324.952106)
		(end 277.848822 -323.787008)
		(width 0.1651)
		(layer "In5.Cu")
		(net "P5E_PEX2_STN6_RX_DN<109>")
	)
	(segment
		(start 277.848822 -323.787008)
		(end 277.265892 -322.379848)
		(width 0.1651)
		(layer "In5.Cu")
		(net "P5E_PEX2_STN6_RX_DN<109>")
	)
	(segment
		(start 277.485602 -316.419992)
		(end 277.599902 -316.534292)
		(width 0.1143)
		(layer "In5.Cu")
		(net "P5E_PEX2_STN6_RX_DN<109>")
	)
	(segment
		(start 326.756776 -388.575296)
		(end 304.520092 -338.785454)
		(width 0.1651)
		(layer "In5.Cu")
		(net "P5E_PEX2_STN6_RX_DN<109>")
	)
	(segment
		(start 328.219308 -390.040114)
		(end 326.756776 -388.575296)
		(width 0.1651)
		(layer "In5.Cu")
		(net "P5E_PEX2_STN6_RX_DN<109>")
	)
	(segment
		(start 277.334472 -316.419992)
		(end 277.485602 -316.419992)
		(width 0.1143)
		(layer "In5.Cu")
		(net "P5E_PEX2_STN6_RX_DN<109>")
	)
	(segment
		(start 277.265892 -320.0146)
		(end 277.220172 -319.96888)
		(width 0.1143)
		(layer "In5.Cu")
		(net "P5E_PEX2_STN6_RX_DN<109>")
	)
	(segment
		(start 277.220172 -316.534292)
		(end 277.334472 -316.419992)
		(width 0.1143)
		(layer "In5.Cu")
		(net "P5E_PEX2_STN6_RX_DN<109>")
	)
	(segment
		(start 304.520092 -338.785454)
		(end 303.93767 -338.157312)
		(width 0.1651)
		(layer "In5.Cu")
		(net "P5E_PEX2_STN6_RX_DN<109>")
	)
	(segment
		(start 335.890108 -401.690078)
		(end 335.890108 -401.308062)
		(width 0.1651)
		(layer "In5.Cu")
		(net "P5E_PEX2_STN6_RX_DN<109>")
	)
	(segment
		(start 277.265892 -322.379848)
		(end 277.265892 -320.043048)
		(width 0.1651)
		(layer "In5.Cu")
		(net "P5E_PEX2_STN6_RX_DN<109>")
	)
	(segment
		(start 336.564224 -401.181062)
		(end 337.01609 -400.729196)
		(width 0.1651)
		(layer "In5.Cu")
		(net "P5E_PEX2_STN6_RX_DN<109>")
	)
	(segment
		(start 277.599902 -316.534292)
		(end 277.599902 -316.799722)
		(width 0.1143)
		(layer "In5.Cu")
		(net "P5E_PEX2_STN6_RX_DN<109>")
	)
	(segment
		(start 336.017108 -401.181062)
		(end 336.564224 -401.181062)
		(width 0.1651)
		(layer "In5.Cu")
		(net "P5E_PEX2_STN6_RX_DN<109>")
	)
	(segment
		(start 277.265892 -320.043048)
		(end 277.265892 -320.0146)
		(width 0.1143)
		(layer "In5.Cu")
		(net "P5E_PEX2_STN6_RX_DN<109>")
	)
	(segment
		(start 336.821526 -394.564108)
		(end 336.3849 -394.13434)
		(width 0.1651)
		(layer "In5.Cu")
		(net "P5E_PEX2_STN6_RX_DN<109>")
	)
	(segment
		(start 385.516628 -134.32028)
		(end 393.684506 -134.32028)
		(width 0.13462)
		(layer "F.Cu")
		(net "P5E_PEX3_STN1_TX_C_DP<30>")
	)
	(segment
		(start 393.684506 -134.32028)
		(end 393.8397 -134.165086)
		(width 0.13462)
		(layer "F.Cu")
		(net "P5E_PEX3_STN1_TX_C_DP<30>")
	)
	(segment
		(start 385.205224 -134.008876)
		(end 385.516628 -134.32028)
		(width 0.13462)
		(layer "F.Cu")
		(net "P5E_PEX3_STN1_TX_C_DP<30>")
	)
	(segment
		(start 393.8397 -134.165086)
		(end 394.342366 -134.165086)
		(width 0.13462)
		(layer "F.Cu")
		(net "P5E_PEX3_STN1_TX_C_DP<30>")
	)
	(segment
		(start 404.149814 -318.015366)
		(end 404.149814 -317.749936)
		(width 0.1143)
		(layer "In5.Cu")
		(net "P5E_PEX3_STN6_RX_DP<98>")
	)
	(segment
		(start 379.708664 -341.291926)
		(end 401.273772 -324.296278)
		(width 0.1651)
		(layer "In5.Cu")
		(net "P5E_PEX3_STN6_RX_DP<98>")
	)
	(segment
		(start 403.579584 -318.355472)
		(end 403.80539 -318.129666)
		(width 0.1143)
		(layer "In5.Cu")
		(net "P5E_PEX3_STN6_RX_DP<98>")
	)
	(segment
		(start 403.533864 -319.934082)
		(end 403.579584 -319.888362)
		(width 0.1143)
		(layer "In5.Cu")
		(net "P5E_PEX3_STN6_RX_DP<98>")
	)
	(segment
		(start 403.533864 -320.985134)
		(end 403.533864 -319.96253)
		(width 0.1651)
		(layer "In5.Cu")
		(net "P5E_PEX3_STN6_RX_DP<98>")
	)
	(segment
		(start 387.366002 -375.670572)
		(end 387.366002 -368.447066)
		(width 0.1651)
		(layer "In5.Cu")
		(net "P5E_PEX3_STN6_RX_DP<98>")
	)
	(segment
		(start 404.035514 -318.129666)
		(end 404.149814 -318.015366)
		(width 0.1143)
		(layer "In5.Cu")
		(net "P5E_PEX3_STN6_RX_DP<98>")
	)
	(segment
		(start 403.579584 -319.888362)
		(end 403.579584 -318.355472)
		(width 0.1143)
		(layer "In5.Cu")
		(net "P5E_PEX3_STN6_RX_DP<98>")
	)
	(segment
		(start 385.68503 -366.630966)
		(end 385.698746 -366.46993)
		(width 0.1651)
		(layer "In5.Cu")
		(net "P5E_PEX3_STN6_RX_DP<98>")
	)
	(segment
		(start 401.273772 -324.296278)
		(end 403.101048 -321.951858)
		(width 0.1651)
		(layer "In5.Cu")
		(net "P5E_PEX3_STN6_RX_DP<98>")
	)
	(segment
		(start 386.663184 -376.003058)
		(end 387.033516 -376.003058)
		(width 0.1651)
		(layer "In5.Cu")
		(net "P5E_PEX3_STN6_RX_DP<98>")
	)
	(segment
		(start 386.489956 -375.490232)
		(end 386.489956 -375.82983)
		(width 0.1651)
		(layer "In5.Cu")
		(net "P5E_PEX3_STN6_RX_DP<98>")
	)
	(segment
		(start 403.80539 -318.129666)
		(end 404.035514 -318.129666)
		(width 0.1143)
		(layer "In5.Cu")
		(net "P5E_PEX3_STN6_RX_DP<98>")
	)
	(segment
		(start 386.004562 -367.009934)
		(end 385.68503 -366.630966)
		(width 0.1651)
		(layer "In5.Cu")
		(net "P5E_PEX3_STN6_RX_DP<98>")
	)
	(segment
		(start 386.489956 -375.82983)
		(end 386.663184 -376.003058)
		(width 0.1651)
		(layer "In5.Cu")
		(net "P5E_PEX3_STN6_RX_DP<98>")
	)
	(segment
		(start 386.165598 -367.02365)
		(end 386.004562 -367.009934)
		(width 0.1651)
		(layer "In5.Cu")
		(net "P5E_PEX3_STN6_RX_DP<98>")
	)
	(segment
		(start 387.366002 -368.447066)
		(end 386.165598 -367.02365)
		(width 0.1651)
		(layer "In5.Cu")
		(net "P5E_PEX3_STN6_RX_DP<98>")
	)
	(segment
		(start 379.25121 -358.824276)
		(end 379.25121 -342.160098)
		(width 0.1651)
		(layer "In5.Cu")
		(net "P5E_PEX3_STN6_RX_DP<98>")
	)
	(segment
		(start 379.25121 -342.160098)
		(end 379.463554 -341.580978)
		(width 0.1651)
		(layer "In5.Cu")
		(net "P5E_PEX3_STN6_RX_DP<98>")
	)
	(segment
		(start 403.101048 -321.951858)
		(end 403.533864 -320.985134)
		(width 0.1651)
		(layer "In5.Cu")
		(net "P5E_PEX3_STN6_RX_DP<98>")
	)
	(segment
		(start 387.033516 -376.003058)
		(end 387.366002 -375.670572)
		(width 0.1651)
		(layer "In5.Cu")
		(net "P5E_PEX3_STN6_RX_DP<98>")
	)
	(segment
		(start 403.533864 -319.96253)
		(end 403.533864 -319.934082)
		(width 0.1143)
		(layer "In5.Cu")
		(net "P5E_PEX3_STN6_RX_DP<98>")
	)
	(segment
		(start 379.463554 -341.580978)
		(end 379.708664 -341.291926)
		(width 0.1651)
		(layer "In5.Cu")
		(net "P5E_PEX3_STN6_RX_DP<98>")
	)
	(segment
		(start 385.698746 -366.46993)
		(end 379.25121 -358.824276)
		(width 0.1651)
		(layer "In5.Cu")
		(net "P5E_PEX3_STN6_RX_DP<98>")
	)
	(segment
		(start 399.97888 -156.687012)
		(end 399.97888 -157.0736)
		(width 0.13208)
		(layer "F.Cu")
		(net "NIC6_RBT_ARB_IN")
	)
	(segment
		(start 398.94256 -156.560012)
		(end 399.85188 -156.560012)
		(width 0.13208)
		(layer "F.Cu")
		(net "NIC6_RBT_ARB_IN")
	)
	(segment
		(start 399.85188 -156.560012)
		(end 399.97888 -156.687012)
		(width 0.13208)
		(layer "F.Cu")
		(net "NIC6_RBT_ARB_IN")
	)
	(via
		(at 399.97888 -157.0736)
		(size 0.508)
		(drill 0.254)
		(layers "F.Cu" "B.Cu")
		(net "NIC6_RBT_ARB_IN")
	)
	(segment
		(start 398.25549 -157.0736)
		(end 399.97888 -157.0736)
		(width 0.13208)
		(layer "B.Cu")
		(net "NIC6_RBT_ARB_IN")
	)
	(segment
		(start 66.988182 -387.686042)
		(end 65.992248 -385.281424)
		(width 0.1651)
		(layer "In5.Cu")
		(net "P5E_PEX0_STN6_RX_DN<109>")
	)
	(segment
		(start 45.28566 -316.419992)
		(end 45.39996 -316.534292)
		(width 0.1143)
		(layer "In5.Cu")
		(net "P5E_PEX0_STN6_RX_DN<109>")
	)
	(segment
		(start 73.30567 -391.502392)
		(end 69.036184 -389.734044)
		(width 0.1651)
		(layer "In5.Cu")
		(net "P5E_PEX0_STN6_RX_DN<109>")
	)
	(segment
		(start 76.309982 -401.690078)
		(end 76.309982 -401.308062)
		(width 0.1651)
		(layer "In5.Cu")
		(net "P5E_PEX0_STN6_RX_DN<109>")
	)
	(segment
		(start 45.02023 -319.921128)
		(end 45.02023 -316.534292)
		(width 0.1143)
		(layer "In5.Cu")
		(net "P5E_PEX0_STN6_RX_DN<109>")
	)
	(segment
		(start 45.06595 -319.995296)
		(end 45.06595 -319.966848)
		(width 0.1143)
		(layer "In5.Cu")
		(net "P5E_PEX0_STN6_RX_DN<109>")
	)
	(segment
		(start 45.39996 -316.534292)
		(end 45.39996 -316.799722)
		(width 0.1143)
		(layer "In5.Cu")
		(net "P5E_PEX0_STN6_RX_DN<109>")
	)
	(segment
		(start 77.018388 -394.549122)
		(end 73.30567 -391.502392)
		(width 0.1651)
		(layer "In5.Cu")
		(net "P5E_PEX0_STN6_RX_DN<109>")
	)
	(segment
		(start 77.081126 -401.181062)
		(end 77.484224 -400.777964)
		(width 0.1651)
		(layer "In5.Cu")
		(net "P5E_PEX0_STN6_RX_DN<109>")
	)
	(segment
		(start 45.06595 -322.839588)
		(end 45.06595 -319.995296)
		(width 0.1651)
		(layer "In5.Cu")
		(net "P5E_PEX0_STN6_RX_DN<109>")
	)
	(segment
		(start 77.173074 -394.780516)
		(end 77.018388 -394.549122)
		(width 0.1651)
		(layer "In5.Cu")
		(net "P5E_PEX0_STN6_RX_DN<109>")
	)
	(segment
		(start 45.766482 -324.530466)
		(end 45.06595 -322.839588)
		(width 0.1651)
		(layer "In5.Cu")
		(net "P5E_PEX0_STN6_RX_DN<109>")
	)
	(segment
		(start 69.036184 -389.734044)
		(end 66.988182 -387.686042)
		(width 0.1651)
		(layer "In5.Cu")
		(net "P5E_PEX0_STN6_RX_DN<109>")
	)
	(segment
		(start 45.13453 -316.419992)
		(end 45.28566 -316.419992)
		(width 0.1143)
		(layer "In5.Cu")
		(net "P5E_PEX0_STN6_RX_DN<109>")
	)
	(segment
		(start 77.484224 -395.807184)
		(end 77.173074 -394.780516)
		(width 0.1651)
		(layer "In5.Cu")
		(net "P5E_PEX0_STN6_RX_DN<109>")
	)
	(segment
		(start 64.310768 -368.212624)
		(end 59.336432 -355.317552)
		(width 0.1651)
		(layer "In5.Cu")
		(net "P5E_PEX0_STN6_RX_DN<109>")
	)
	(segment
		(start 58.514234 -352.035872)
		(end 57.718198 -345.58351)
		(width 0.1651)
		(layer "In5.Cu")
		(net "P5E_PEX0_STN6_RX_DN<109>")
	)
	(segment
		(start 76.436982 -401.181062)
		(end 77.081126 -401.181062)
		(width 0.1651)
		(layer "In5.Cu")
		(net "P5E_PEX0_STN6_RX_DN<109>")
	)
	(segment
		(start 54.268116 -337.25358)
		(end 45.766482 -324.530466)
		(width 0.1651)
		(layer "In5.Cu")
		(net "P5E_PEX0_STN6_RX_DN<109>")
	)
	(segment
		(start 45.02023 -316.534292)
		(end 45.13453 -316.419992)
		(width 0.1143)
		(layer "In5.Cu")
		(net "P5E_PEX0_STN6_RX_DN<109>")
	)
	(segment
		(start 57.718198 -345.58351)
		(end 54.268116 -337.25358)
		(width 0.1651)
		(layer "In5.Cu")
		(net "P5E_PEX0_STN6_RX_DN<109>")
	)
	(segment
		(start 45.06595 -319.966848)
		(end 45.02023 -319.921128)
		(width 0.1143)
		(layer "In5.Cu")
		(net "P5E_PEX0_STN6_RX_DN<109>")
	)
	(segment
		(start 76.309982 -401.308062)
		(end 76.436982 -401.181062)
		(width 0.1651)
		(layer "In5.Cu")
		(net "P5E_PEX0_STN6_RX_DN<109>")
	)
	(segment
		(start 59.336432 -355.317552)
		(end 58.514234 -352.035872)
		(width 0.1651)
		(layer "In5.Cu")
		(net "P5E_PEX0_STN6_RX_DN<109>")
	)
	(segment
		(start 77.484224 -400.777964)
		(end 77.484224 -395.807184)
		(width 0.1651)
		(layer "In5.Cu")
		(net "P5E_PEX0_STN6_RX_DN<109>")
	)
	(segment
		(start 65.992248 -385.281424)
		(end 64.310768 -368.212624)
		(width 0.1651)
		(layer "In5.Cu")
		(net "P5E_PEX0_STN6_RX_DN<109>")
	)
	(segment
		(start 211.315046 -28.829)
		(end 210.025488 -28.829)
		(width 0.13462)
		(layer "F.Cu")
		(net "P5E_PEX1_STN2_TX_C_DP<32>")
	)
	(segment
		(start 210.025488 -28.829)
		(end 209.864452 -28.990036)
		(width 0.13462)
		(layer "F.Cu")
		(net "P5E_PEX1_STN2_TX_C_DP<32>")
	)
	(segment
		(start 211.625688 -29.139642)
		(end 211.315046 -28.829)
		(width 0.13462)
		(layer "F.Cu")
		(net "P5E_PEX1_STN2_TX_C_DP<32>")
	)
	(segment
		(start 209.864452 -28.990036)
		(end 209.364834 -28.990036)
		(width 0.13462)
		(layer "F.Cu")
		(net "P5E_PEX1_STN2_TX_C_DP<32>")
	)
	(segment
		(start 306.124864 -148.31568)
		(end 305.964336 -148.155152)
		(width 0.13462)
		(layer "F.Cu")
		(net "P5E_PEX2_STN0_TX_C_DN<11>")
	)
	(segment
		(start 305.964336 -148.155152)
		(end 305.457606 -148.155152)
		(width 0.13462)
		(layer "F.Cu")
		(net "P5E_PEX2_STN0_TX_C_DN<11>")
	)
	(segment
		(start 314.594748 -147.99691)
		(end 314.275978 -148.31568)
		(width 0.13462)
		(layer "F.Cu")
		(net "P5E_PEX2_STN0_TX_C_DN<11>")
	)
	(segment
		(start 314.275978 -148.31568)
		(end 306.124864 -148.31568)
		(width 0.13462)
		(layer "F.Cu")
		(net "P5E_PEX2_STN0_TX_C_DN<11>")
	)
	(segment
		(start 343.887044 -356.831646)
		(end 343.887044 -357.46309)
		(width 0.13462)
		(layer "F.Cu")
		(net "P5E_PEX2_STN6_TX_C_DP<96>")
	)
	(segment
		(start 343.567004 -356.511606)
		(end 343.887044 -356.831646)
		(width 0.13462)
		(layer "F.Cu")
		(net "P5E_PEX2_STN6_TX_C_DP<96>")
	)
	(segment
		(start 343.887044 -357.46309)
		(end 343.592404 -357.75773)
		(width 0.13462)
		(layer "F.Cu")
		(net "P5E_PEX2_STN6_TX_C_DP<96>")
	)
	(segment
		(start 346.890086 -383.290064)
		(end 346.890086 -383.67208)
		(width 0.1651)
		(layer "In13.Cu")
		(net "P5E_PEX2_STN6_TX_C_DP<96>")
	)
	(segment
		(start 345.396312 -362.859828)
		(end 343.883234 -358.99344)
		(width 0.1651)
		(layer "In13.Cu")
		(net "P5E_PEX2_STN6_TX_C_DP<96>")
	)
	(segment
		(start 346.276168 -365.106966)
		(end 346.095828 -364.645956)
		(width 0.1651)
		(layer "In13.Cu")
		(net "P5E_PEX2_STN6_TX_C_DP<96>")
	)
	(segment
		(start 345.831668 -363.971586)
		(end 345.651328 -363.510576)
		(width 0.1651)
		(layer "In13.Cu")
		(net "P5E_PEX2_STN6_TX_C_DP<96>")
	)
	(segment
		(start 345.338908 -362.9914)
		(end 345.396312 -362.859828)
		(width 0.1651)
		(layer "In13.Cu")
		(net "P5E_PEX2_STN6_TX_C_DP<96>")
	)
	(segment
		(start 347.017086 -383.79908)
		(end 347.447362 -383.79908)
		(width 0.1651)
		(layer "In13.Cu")
		(net "P5E_PEX2_STN6_TX_C_DP<96>")
	)
	(segment
		(start 347.447362 -383.79908)
		(end 347.734128 -383.512314)
		(width 0.1651)
		(layer "In13.Cu")
		(net "P5E_PEX2_STN6_TX_C_DP<96>")
	)
	(segment
		(start 346.095828 -364.645956)
		(end 345.947492 -364.581186)
		(width 0.1651)
		(layer "In13.Cu")
		(net "P5E_PEX2_STN6_TX_C_DP<96>")
	)
	(segment
		(start 345.651328 -363.510576)
		(end 345.519248 -363.452918)
		(width 0.1651)
		(layer "In13.Cu")
		(net "P5E_PEX2_STN6_TX_C_DP<96>")
	)
	(segment
		(start 346.391992 -365.716312)
		(end 346.211398 -365.255048)
		(width 0.1651)
		(layer "In13.Cu")
		(net "P5E_PEX2_STN6_TX_C_DP<96>")
	)
	(segment
		(start 345.947492 -364.581186)
		(end 345.766898 -364.119668)
		(width 0.1651)
		(layer "In13.Cu")
		(net "P5E_PEX2_STN6_TX_C_DP<96>")
	)
	(segment
		(start 347.734128 -368.83086)
		(end 346.540328 -365.781082)
		(width 0.1651)
		(layer "In13.Cu")
		(net "P5E_PEX2_STN6_TX_C_DP<96>")
	)
	(segment
		(start 345.519248 -363.452918)
		(end 345.338908 -362.9914)
		(width 0.1651)
		(layer "In13.Cu")
		(net "P5E_PEX2_STN6_TX_C_DP<96>")
	)
	(segment
		(start 347.734128 -383.512314)
		(end 347.734128 -368.83086)
		(width 0.1651)
		(layer "In13.Cu")
		(net "P5E_PEX2_STN6_TX_C_DP<96>")
	)
	(segment
		(start 346.540328 -365.781082)
		(end 346.391992 -365.716312)
		(width 0.1651)
		(layer "In13.Cu")
		(net "P5E_PEX2_STN6_TX_C_DP<96>")
	)
	(segment
		(start 346.211398 -365.255048)
		(end 346.276168 -365.106966)
		(width 0.1651)
		(layer "In13.Cu")
		(net "P5E_PEX2_STN6_TX_C_DP<96>")
	)
	(segment
		(start 345.766898 -364.119668)
		(end 345.831668 -363.971586)
		(width 0.1651)
		(layer "In13.Cu")
		(net "P5E_PEX2_STN6_TX_C_DP<96>")
	)
	(segment
		(start 343.883234 -358.99344)
		(end 343.883234 -358.04856)
		(width 0.1651)
		(layer "In13.Cu")
		(net "P5E_PEX2_STN6_TX_C_DP<96>")
	)
	(segment
		(start 346.890086 -383.67208)
		(end 347.017086 -383.79908)
		(width 0.1651)
		(layer "In13.Cu")
		(net "P5E_PEX2_STN6_TX_C_DP<96>")
	)
	(segment
		(start 343.883234 -358.04856)
		(end 343.592404 -357.75773)
		(width 0.1651)
		(layer "In13.Cu")
		(net "P5E_PEX2_STN6_TX_C_DP<96>")
	)
	(segment
		(start 402.09343 -99.8728)
		(end 399.592292 -99.8728)
		(width 0.13462)
		(layer "F.Cu")
		(net "P5E_PEX3_STN1_RX_DN<16>")
	)
	(segment
		(start 402.39696 -100.17633)
		(end 402.09343 -99.8728)
		(width 0.13462)
		(layer "F.Cu")
		(net "P5E_PEX3_STN1_RX_DN<16>")
	)
	(segment
		(start 399.592292 -99.8728)
		(end 399.42008 -100.045012)
		(width 0.13462)
		(layer "F.Cu")
		(net "P5E_PEX3_STN1_RX_DN<16>")
	)
	(segment
		(start 399.42008 -100.045012)
		(end 398.94256 -100.045012)
		(width 0.13462)
		(layer "F.Cu")
		(net "P5E_PEX3_STN1_RX_DN<16>")
	)
	(segment
		(start 378.519182 -166.005764)
		(end 407.615898 -270.066262)
		(width 0.1651)
		(layer "In5.Cu")
		(net "P5E_PEX3_STN1_RX_DN<16>")
	)
	(segment
		(start 396.268194 -101.880924)
		(end 395.825218 -102.102158)
		(width 0.1651)
		(layer "In5.Cu")
		(net "P5E_PEX3_STN1_RX_DN<16>")
	)
	(segment
		(start 376.59691 -149.9362)
		(end 377.268994 -159.535368)
		(width 0.1651)
		(layer "In5.Cu")
		(net "P5E_PEX3_STN1_RX_DN<16>")
	)
	(segment
		(start 392.620246 -104.068118)
		(end 392.232134 -104.37622)
		(width 0.1651)
		(layer "In5.Cu")
		(net "P5E_PEX3_STN1_RX_DN<16>")
	)
	(segment
		(start 402.10613 -99.8855)
		(end 400.258788 -99.8855)
		(width 0.1651)
		(layer "In5.Cu")
		(net "P5E_PEX3_STN1_RX_DN<16>")
	)
	(segment
		(start 391.684002 -104.66578)
		(end 391.66546 -104.826562)
		(width 0.1651)
		(layer "In5.Cu")
		(net "P5E_PEX3_STN1_RX_DN<16>")
	)
	(segment
		(start 398.449546 -100.790248)
		(end 398.00657 -101.011482)
		(width 0.1651)
		(layer "In5.Cu")
		(net "P5E_PEX3_STN1_RX_DN<16>")
	)
	(segment
		(start 379.592586 -119.720106)
		(end 377.978162 -126.400306)
		(width 0.1651)
		(layer "In5.Cu")
		(net "P5E_PEX3_STN1_RX_DN<16>")
	)
	(segment
		(start 392.232134 -104.37622)
		(end 392.071606 -104.357932)
		(width 0.1651)
		(layer "In5.Cu")
		(net "P5E_PEX3_STN1_RX_DN<16>")
	)
	(segment
		(start 395.330934 -102.477316)
		(end 395.177518 -102.426262)
		(width 0.1651)
		(layer "In5.Cu")
		(net "P5E_PEX3_STN1_RX_DN<16>")
	)
	(segment
		(start 400.258788 -99.8855)
		(end 399.097246 -100.466144)
		(width 0.1651)
		(layer "In5.Cu")
		(net "P5E_PEX3_STN1_RX_DN<16>")
	)
	(segment
		(start 394.683488 -102.800912)
		(end 394.240258 -103.022654)
		(width 0.1651)
		(layer "In5.Cu")
		(net "P5E_PEX3_STN1_RX_DN<16>")
	)
	(segment
		(start 384.38582 -110.21695)
		(end 382.755902 -110.87989)
		(width 0.1651)
		(layer "In5.Cu")
		(net "P5E_PEX3_STN1_RX_DN<16>")
	)
	(segment
		(start 377.978162 -126.400306)
		(end 376.59691 -149.9362)
		(width 0.1651)
		(layer "In5.Cu")
		(net "P5E_PEX3_STN1_RX_DN<16>")
	)
	(segment
		(start 390.162034 -105.87482)
		(end 387.498336 -107.989878)
		(width 0.1651)
		(layer "In5.Cu")
		(net "P5E_PEX3_STN1_RX_DN<16>")
	)
	(segment
		(start 407.949654 -273.36496)
		(end 407.949654 -273.09953)
		(width 0.1143)
		(layer "In5.Cu")
		(net "P5E_PEX3_STN1_RX_DN<16>")
	)
	(segment
		(start 391.277348 -105.134664)
		(end 391.11682 -105.116376)
		(width 0.1651)
		(layer "In5.Cu")
		(net "P5E_PEX3_STN1_RX_DN<16>")
	)
	(segment
		(start 397.35887 -101.335586)
		(end 396.915894 -101.55682)
		(width 0.1651)
		(layer "In5.Cu")
		(net "P5E_PEX3_STN1_RX_DN<16>")
	)
	(segment
		(start 407.615898 -271.525746)
		(end 407.615898 -271.554194)
		(width 0.1143)
		(layer "In5.Cu")
		(net "P5E_PEX3_STN1_RX_DN<16>")
	)
	(segment
		(start 397.512286 -101.38664)
		(end 397.35887 -101.335586)
		(width 0.1651)
		(layer "In5.Cu")
		(net "P5E_PEX3_STN1_RX_DN<16>")
	)
	(segment
		(start 398.00657 -101.011482)
		(end 397.955516 -101.164898)
		(width 0.1651)
		(layer "In5.Cu")
		(net "P5E_PEX3_STN1_RX_DN<16>")
	)
	(segment
		(start 391.66546 -104.826562)
		(end 391.277348 -105.134664)
		(width 0.1651)
		(layer "In5.Cu")
		(net "P5E_PEX3_STN1_RX_DN<16>")
	)
	(segment
		(start 407.673556 -273.47926)
		(end 407.835354 -273.47926)
		(width 0.1143)
		(layer "In5.Cu")
		(net "P5E_PEX3_STN1_RX_DN<16>")
	)
	(segment
		(start 392.638788 -103.907336)
		(end 392.620246 -104.068118)
		(width 0.1651)
		(layer "In5.Cu")
		(net "P5E_PEX3_STN1_RX_DN<16>")
	)
	(segment
		(start 395.774164 -102.255574)
		(end 395.330934 -102.477316)
		(width 0.1651)
		(layer "In5.Cu")
		(net "P5E_PEX3_STN1_RX_DN<16>")
	)
	(segment
		(start 394.086842 -102.9716)
		(end 393.359386 -103.335074)
		(width 0.1651)
		(layer "In5.Cu")
		(net "P5E_PEX3_STN1_RX_DN<16>")
	)
	(segment
		(start 393.359386 -103.335074)
		(end 392.638788 -103.907336)
		(width 0.1651)
		(layer "In5.Cu")
		(net "P5E_PEX3_STN1_RX_DN<16>")
	)
	(segment
		(start 396.42161 -101.931978)
		(end 396.268194 -101.880924)
		(width 0.1651)
		(layer "In5.Cu")
		(net "P5E_PEX3_STN1_RX_DN<16>")
	)
	(segment
		(start 399.046192 -100.61956)
		(end 398.602962 -100.841302)
		(width 0.1651)
		(layer "In5.Cu")
		(net "P5E_PEX3_STN1_RX_DN<16>")
	)
	(segment
		(start 407.570178 -273.375882)
		(end 407.673556 -273.47926)
		(width 0.1143)
		(layer "In5.Cu")
		(net "P5E_PEX3_STN1_RX_DN<16>")
	)
	(segment
		(start 390.710674 -105.584752)
		(end 390.322562 -105.893108)
		(width 0.1651)
		(layer "In5.Cu")
		(net "P5E_PEX3_STN1_RX_DN<16>")
	)
	(segment
		(start 390.728962 -105.424224)
		(end 390.710674 -105.584752)
		(width 0.1651)
		(layer "In5.Cu")
		(net "P5E_PEX3_STN1_RX_DN<16>")
	)
	(segment
		(start 396.915894 -101.55682)
		(end 396.86484 -101.710236)
		(width 0.1651)
		(layer "In5.Cu")
		(net "P5E_PEX3_STN1_RX_DN<16>")
	)
	(segment
		(start 392.071606 -104.357932)
		(end 391.684002 -104.66578)
		(width 0.1651)
		(layer "In5.Cu")
		(net "P5E_PEX3_STN1_RX_DN<16>")
	)
	(segment
		(start 407.835354 -273.47926)
		(end 407.949654 -273.36496)
		(width 0.1143)
		(layer "In5.Cu")
		(net "P5E_PEX3_STN1_RX_DN<16>")
	)
	(segment
		(start 382.755902 -110.87989)
		(end 382.369314 -111.275876)
		(width 0.1651)
		(layer "In5.Cu")
		(net "P5E_PEX3_STN1_RX_DN<16>")
	)
	(segment
		(start 395.177518 -102.426262)
		(end 394.734542 -102.647496)
		(width 0.1651)
		(layer "In5.Cu")
		(net "P5E_PEX3_STN1_RX_DN<16>")
	)
	(segment
		(start 394.734542 -102.647496)
		(end 394.683488 -102.800912)
		(width 0.1651)
		(layer "In5.Cu")
		(net "P5E_PEX3_STN1_RX_DN<16>")
	)
	(segment
		(start 377.268994 -159.535368)
		(end 378.519182 -166.005764)
		(width 0.1651)
		(layer "In5.Cu")
		(net "P5E_PEX3_STN1_RX_DN<16>")
	)
	(segment
		(start 395.825218 -102.102158)
		(end 395.774164 -102.255574)
		(width 0.1651)
		(layer "In5.Cu")
		(net "P5E_PEX3_STN1_RX_DN<16>")
	)
	(segment
		(start 407.570178 -271.599914)
		(end 407.570178 -273.375882)
		(width 0.1143)
		(layer "In5.Cu")
		(net "P5E_PEX3_STN1_RX_DN<16>")
	)
	(segment
		(start 407.615898 -271.554194)
		(end 407.570178 -271.599914)
		(width 0.1143)
		(layer "In5.Cu")
		(net "P5E_PEX3_STN1_RX_DN<16>")
	)
	(segment
		(start 398.602962 -100.841302)
		(end 398.449546 -100.790248)
		(width 0.1651)
		(layer "In5.Cu")
		(net "P5E_PEX3_STN1_RX_DN<16>")
	)
	(segment
		(start 402.39696 -100.17633)
		(end 402.10613 -99.8855)
		(width 0.1651)
		(layer "In5.Cu")
		(net "P5E_PEX3_STN1_RX_DN<16>")
	)
	(segment
		(start 394.240258 -103.022654)
		(end 394.086842 -102.9716)
		(width 0.1651)
		(layer "In5.Cu")
		(net "P5E_PEX3_STN1_RX_DN<16>")
	)
	(segment
		(start 382.369314 -111.275876)
		(end 379.592586 -119.720106)
		(width 0.1651)
		(layer "In5.Cu")
		(net "P5E_PEX3_STN1_RX_DN<16>")
	)
	(segment
		(start 399.097246 -100.466144)
		(end 399.046192 -100.61956)
		(width 0.1651)
		(layer "In5.Cu")
		(net "P5E_PEX3_STN1_RX_DN<16>")
	)
	(segment
		(start 390.322562 -105.893108)
		(end 390.162034 -105.87482)
		(width 0.1651)
		(layer "In5.Cu")
		(net "P5E_PEX3_STN1_RX_DN<16>")
	)
	(segment
		(start 396.86484 -101.710236)
		(end 396.42161 -101.931978)
		(width 0.1651)
		(layer "In5.Cu")
		(net "P5E_PEX3_STN1_RX_DN<16>")
	)
	(segment
		(start 407.615898 -270.066262)
		(end 407.615898 -271.525746)
		(width 0.1651)
		(layer "In5.Cu")
		(net "P5E_PEX3_STN1_RX_DN<16>")
	)
	(segment
		(start 387.498336 -107.989878)
		(end 385.06273 -109.605572)
		(width 0.1651)
		(layer "In5.Cu")
		(net "P5E_PEX3_STN1_RX_DN<16>")
	)
	(segment
		(start 397.955516 -101.164898)
		(end 397.512286 -101.38664)
		(width 0.1651)
		(layer "In5.Cu")
		(net "P5E_PEX3_STN1_RX_DN<16>")
	)
	(segment
		(start 391.11682 -105.116376)
		(end 390.728962 -105.424224)
		(width 0.1651)
		(layer "In5.Cu")
		(net "P5E_PEX3_STN1_RX_DN<16>")
	)
	(segment
		(start 385.06273 -109.605572)
		(end 384.38582 -110.21695)
		(width 0.1651)
		(layer "In5.Cu")
		(net "P5E_PEX3_STN1_RX_DN<16>")
	)
	(segment
		(start 375.18594 -344.219022)
		(end 374.866408 -344.538554)
		(width 0.13462)
		(layer "F.Cu")
		(net "P5E_PEX3_STN6_TX_C_DN<102>")
	)
	(segment
		(start 374.866408 -345.171014)
		(end 375.16054 -345.465146)
		(width 0.13462)
		(layer "F.Cu")
		(net "P5E_PEX3_STN6_TX_C_DN<102>")
	)
	(segment
		(start 374.866408 -344.538554)
		(end 374.866408 -345.171014)
		(width 0.13462)
		(layer "F.Cu")
		(net "P5E_PEX3_STN6_TX_C_DN<102>")
	)
	(segment
		(start 374.86971 -346.326714)
		(end 373.31523 -347.881194)
		(width 0.1651)
		(layer "In7.Cu")
		(net "P5E_PEX3_STN6_TX_C_DN<102>")
	)
	(segment
		(start 374.86971 -345.755976)
		(end 374.86971 -346.326714)
		(width 0.1651)
		(layer "In7.Cu")
		(net "P5E_PEX3_STN6_TX_C_DN<102>")
	)
	(segment
		(start 375.16054 -345.465146)
		(end 374.86971 -345.755976)
		(width 0.1651)
		(layer "In7.Cu")
		(net "P5E_PEX3_STN6_TX_C_DN<102>")
	)
	(segment
		(start 378.363988 -384.08102)
		(end 377.816872 -384.08102)
		(width 0.1651)
		(layer "In7.Cu")
		(net "P5E_PEX3_STN6_TX_C_DN<102>")
	)
	(segment
		(start 378.815854 -383.629154)
		(end 378.363988 -384.08102)
		(width 0.1651)
		(layer "In7.Cu")
		(net "P5E_PEX3_STN6_TX_C_DN<102>")
	)
	(segment
		(start 378.815854 -368.73688)
		(end 378.815854 -383.629154)
		(width 0.1651)
		(layer "In7.Cu")
		(net "P5E_PEX3_STN6_TX_C_DN<102>")
	)
	(segment
		(start 377.689872 -384.20802)
		(end 377.689872 -384.590036)
		(width 0.1651)
		(layer "In7.Cu")
		(net "P5E_PEX3_STN6_TX_C_DN<102>")
	)
	(segment
		(start 373.31523 -347.881194)
		(end 373.31523 -358.4067)
		(width 0.1651)
		(layer "In7.Cu")
		(net "P5E_PEX3_STN6_TX_C_DN<102>")
	)
	(segment
		(start 377.816872 -384.08102)
		(end 377.689872 -384.20802)
		(width 0.1651)
		(layer "In7.Cu")
		(net "P5E_PEX3_STN6_TX_C_DN<102>")
	)
	(segment
		(start 373.31523 -358.4067)
		(end 378.815854 -368.73688)
		(width 0.1651)
		(layer "In7.Cu")
		(net "P5E_PEX3_STN6_TX_C_DN<102>")
	)
	(segment
		(start 175.49495 -103.814372)
		(end 181.031134 -103.814372)
		(width 0.13208)
		(layer "F.Cu")
		(net "NCSI_NIC3_TXD0")
	)
	(segment
		(start 182.22468 -102.620826)
		(end 183.005476 -101.84003)
		(width 0.13208)
		(layer "F.Cu")
		(net "NCSI_NIC3_TXD0")
	)
	(segment
		(start 181.031134 -103.814372)
		(end 182.14467 -102.700836)
		(width 0.13208)
		(layer "F.Cu")
		(net "NCSI_NIC3_TXD0")
	)
	(segment
		(start 183.005476 -101.84003)
		(end 184.757314 -101.84003)
		(width 0.13208)
		(layer "F.Cu")
		(net "NCSI_NIC3_TXD0")
	)
	(segment
		(start 182.14467 -102.700836)
		(end 182.22468 -102.700836)
		(width 0.13208)
		(layer "F.Cu")
		(net "NCSI_NIC3_TXD0")
	)
	(segment
		(start 182.22468 -102.700836)
		(end 182.22468 -102.620826)
		(width 0.13208)
		(layer "F.Cu")
		(net "NCSI_NIC3_TXD0")
	)
	(via
		(at 182.22468 -102.700836)
		(size 0.508)
		(drill 0.254)
		(layers "F.Cu" "B.Cu")
		(net "NCSI_NIC3_TXD0")
	)
	(segment
		(start 387.46049 -116.7384)
		(end 387.46049 -117.7544)
		(width 0.13208)
		(layer "F.Cu")
		(net "PRSNTB0_NIC6_N")
	)
	(segment
		(start 387.46049 -117.7544)
		(end 387.861048 -118.154958)
		(width 0.13208)
		(layer "F.Cu")
		(net "PRSNTB0_NIC6_N")
	)
	(segment
		(start 388.69112 -118.154958)
		(end 394.342366 -118.154958)
		(width 0.13208)
		(layer "F.Cu")
		(net "PRSNTB0_NIC6_N")
	)
	(segment
		(start 387.861048 -118.154958)
		(end 388.69112 -118.154958)
		(width 0.13208)
		(layer "F.Cu")
		(net "PRSNTB0_NIC6_N")
	)
	(via
		(at 388.69112 -118.154958)
		(size 0.762)
		(drill 0.381)
		(layers "F.Cu" "B.Cu")
		(net "PRSNTB0_NIC6_N")
	)
	(segment
		(start 152.764998 -28.990036)
		(end 152.764998 -28.99029)
		(width 0.13462)
		(layer "F.Cu")
		(net "P5E_PEX1_STN2_RX_DP<40>")
	)
	(segment
		(start 152.285954 -28.99029)
		(end 152.124664 -28.829)
		(width 0.13462)
		(layer "F.Cu")
		(net "P5E_PEX1_STN2_RX_DP<40>")
	)
	(segment
		(start 152.124664 -28.829)
		(end 151.458168 -28.829)
		(width 0.13462)
		(layer "F.Cu")
		(net "P5E_PEX1_STN2_RX_DP<40>")
	)
	(segment
		(start 151.458168 -28.829)
		(end 151.164798 -29.12237)
		(width 0.13462)
		(layer "F.Cu")
		(net "P5E_PEX1_STN2_RX_DP<40>")
	)
	(segment
		(start 152.764998 -28.99029)
		(end 152.285954 -28.99029)
		(width 0.13462)
		(layer "F.Cu")
		(net "P5E_PEX1_STN2_RX_DP<40>")
	)
	(segment
		(start 166.84498 -275.570188)
		(end 167.085772 -275.570188)
		(width 0.1143)
		(layer "In7.Cu")
		(net "P5E_PEX1_STN2_RX_DP<40>")
	)
	(segment
		(start 167.200072 -275.684488)
		(end 167.200072 -275.949918)
		(width 0.1143)
		(layer "In7.Cu")
		(net "P5E_PEX1_STN2_RX_DP<40>")
	)
	(segment
		(start 151.501602 -28.83154)
		(end 151.787098 -28.83154)
		(width 0.1651)
		(layer "In7.Cu")
		(net "P5E_PEX1_STN2_RX_DP<40>")
	)
	(segment
		(start 166.583868 -271.392904)
		(end 166.583868 -271.421352)
		(width 0.1143)
		(layer "In7.Cu")
		(net "P5E_PEX1_STN2_RX_DP<40>")
	)
	(segment
		(start 152.503886 -29.548328)
		(end 152.503886 -29.692092)
		(width 0.1651)
		(layer "In7.Cu")
		(net "P5E_PEX1_STN2_RX_DP<40>")
	)
	(segment
		(start 157.135068 -38.545262)
		(end 154.98826 -48.798226)
		(width 0.1651)
		(layer "In7.Cu")
		(net "P5E_PEX1_STN2_RX_DP<40>")
	)
	(segment
		(start 166.548562 -250.016518)
		(end 166.26205 -264.871962)
		(width 0.1651)
		(layer "In7.Cu")
		(net "P5E_PEX1_STN2_RX_DP<40>")
	)
	(segment
		(start 153.698702 -30.886908)
		(end 153.842466 -30.886908)
		(width 0.1651)
		(layer "In7.Cu")
		(net "P5E_PEX1_STN2_RX_DP<40>")
	)
	(segment
		(start 158.430468 -104.315514)
		(end 158.892748 -119.567198)
		(width 0.1651)
		(layer "In7.Cu")
		(net "P5E_PEX1_STN2_RX_DP<40>")
	)
	(segment
		(start 166.26205 -264.871962)
		(end 166.583868 -268.137132)
		(width 0.1651)
		(layer "In7.Cu")
		(net "P5E_PEX1_STN2_RX_DP<40>")
	)
	(segment
		(start 166.583868 -271.421352)
		(end 166.629588 -271.467072)
		(width 0.1143)
		(layer "In7.Cu")
		(net "P5E_PEX1_STN2_RX_DP<40>")
	)
	(segment
		(start 151.164798 -29.12237)
		(end 151.423116 -28.864052)
		(width 0.1651)
		(layer "In7.Cu")
		(net "P5E_PEX1_STN2_RX_DP<40>")
	)
	(segment
		(start 158.586932 -147.947888)
		(end 166.548562 -250.016518)
		(width 0.1651)
		(layer "In7.Cu")
		(net "P5E_PEX1_STN2_RX_DP<40>")
	)
	(segment
		(start 152.503886 -29.692092)
		(end 152.854406 -30.042612)
		(width 0.1651)
		(layer "In7.Cu")
		(net "P5E_PEX1_STN2_RX_DP<40>")
	)
	(segment
		(start 167.085772 -275.570188)
		(end 167.200072 -275.684488)
		(width 0.1143)
		(layer "In7.Cu")
		(net "P5E_PEX1_STN2_RX_DP<40>")
	)
	(segment
		(start 166.583868 -268.137132)
		(end 166.583868 -271.392904)
		(width 0.1651)
		(layer "In7.Cu")
		(net "P5E_PEX1_STN2_RX_DP<40>")
	)
	(segment
		(start 154.564334 -31.608776)
		(end 157.14853 -37.742622)
		(width 0.1651)
		(layer "In7.Cu")
		(net "P5E_PEX1_STN2_RX_DP<40>")
	)
	(segment
		(start 152.99817 -30.042612)
		(end 153.348182 -30.392624)
		(width 0.1651)
		(layer "In7.Cu")
		(net "P5E_PEX1_STN2_RX_DP<40>")
	)
	(segment
		(start 151.423116 -28.864052)
		(end 151.501602 -28.83154)
		(width 0.1651)
		(layer "In7.Cu")
		(net "P5E_PEX1_STN2_RX_DP<40>")
	)
	(segment
		(start 152.854406 -30.042612)
		(end 152.99817 -30.042612)
		(width 0.1651)
		(layer "In7.Cu")
		(net "P5E_PEX1_STN2_RX_DP<40>")
	)
	(segment
		(start 157.14853 -37.742622)
		(end 157.135068 -38.545262)
		(width 0.1651)
		(layer "In7.Cu")
		(net "P5E_PEX1_STN2_RX_DP<40>")
	)
	(segment
		(start 155.28671 -65.14846)
		(end 158.430468 -104.315514)
		(width 0.1651)
		(layer "In7.Cu")
		(net "P5E_PEX1_STN2_RX_DP<40>")
	)
	(segment
		(start 153.348182 -30.392624)
		(end 153.348182 -30.536388)
		(width 0.1651)
		(layer "In7.Cu")
		(net "P5E_PEX1_STN2_RX_DP<40>")
	)
	(segment
		(start 154.888438 -55.19547)
		(end 155.28671 -65.14846)
		(width 0.1651)
		(layer "In7.Cu")
		(net "P5E_PEX1_STN2_RX_DP<40>")
	)
	(segment
		(start 154.98826 -48.798226)
		(end 154.888438 -55.19547)
		(width 0.1651)
		(layer "In7.Cu")
		(net "P5E_PEX1_STN2_RX_DP<40>")
	)
	(segment
		(start 166.629588 -271.467072)
		(end 166.629588 -275.354796)
		(width 0.1143)
		(layer "In7.Cu")
		(net "P5E_PEX1_STN2_RX_DP<40>")
	)
	(segment
		(start 153.348182 -30.536388)
		(end 153.698702 -30.886908)
		(width 0.1651)
		(layer "In7.Cu")
		(net "P5E_PEX1_STN2_RX_DP<40>")
	)
	(segment
		(start 151.787098 -28.83154)
		(end 152.503886 -29.548328)
		(width 0.1651)
		(layer "In7.Cu")
		(net "P5E_PEX1_STN2_RX_DP<40>")
	)
	(segment
		(start 158.892748 -119.567198)
		(end 158.586932 -147.947888)
		(width 0.1651)
		(layer "In7.Cu")
		(net "P5E_PEX1_STN2_RX_DP<40>")
	)
	(segment
		(start 153.842466 -30.886908)
		(end 154.564334 -31.608776)
		(width 0.1651)
		(layer "In7.Cu")
		(net "P5E_PEX1_STN2_RX_DP<40>")
	)
	(segment
		(start 166.629588 -275.354796)
		(end 166.84498 -275.570188)
		(width 0.1143)
		(layer "In7.Cu")
		(net "P5E_PEX1_STN2_RX_DP<40>")
	)
	(segment
		(start 300.379892 -124.234956)
		(end 300.225968 -124.38888)
		(width 0.13462)
		(layer "F.Cu")
		(net "P5E_PEX2_STN0_RX_DN<3>")
	)
	(segment
		(start 300.225968 -124.38888)
		(end 297.688254 -124.38888)
		(width 0.13462)
		(layer "F.Cu")
		(net "P5E_PEX2_STN0_RX_DN<3>")
	)
	(segment
		(start 297.688254 -124.38888)
		(end 297.403012 -124.103638)
		(width 0.13462)
		(layer "F.Cu")
		(net "P5E_PEX2_STN0_RX_DN<3>")
	)
	(segment
		(start 300.857412 -124.234956)
		(end 300.379892 -124.234956)
		(width 0.13462)
		(layer "F.Cu")
		(net "P5E_PEX2_STN0_RX_DN<3>")
	)
	(segment
		(start 314.649866 -285.449772)
		(end 314.384436 -285.449772)
		(width 0.1143)
		(layer "In5.Cu")
		(net "P5E_PEX2_STN0_RX_DN<3>")
	)
	(segment
		(start 305.89474 -127.04318)
		(end 305.016154 -126.186438)
		(width 0.1651)
		(layer "In5.Cu")
		(net "P5E_PEX2_STN0_RX_DN<3>")
	)
	(segment
		(start 314.270136 -285.335472)
		(end 314.270136 -285.173674)
		(width 0.1143)
		(layer "In5.Cu")
		(net "P5E_PEX2_STN0_RX_DN<3>")
	)
	(segment
		(start 318.671956 -284.422596)
		(end 326.678544 -276.661626)
		(width 0.1651)
		(layer "In5.Cu")
		(net "P5E_PEX2_STN0_RX_DN<3>")
	)
	(segment
		(start 314.270136 -285.173674)
		(end 314.373768 -285.070042)
		(width 0.1143)
		(layer "In5.Cu")
		(net "P5E_PEX2_STN0_RX_DN<3>")
	)
	(segment
		(start 314.82284 -140.10386)
		(end 314.48502 -139.15898)
		(width 0.1651)
		(layer "In5.Cu")
		(net "P5E_PEX2_STN0_RX_DN<3>")
	)
	(segment
		(start 314.48502 -139.15898)
		(end 312.24728 -137.67562)
		(width 0.1651)
		(layer "In5.Cu")
		(net "P5E_PEX2_STN0_RX_DN<3>")
	)
	(segment
		(start 318.46393 -147.200366)
		(end 318.464184 -147.200366)
		(width 0.1651)
		(layer "In5.Cu")
		(net "P5E_PEX2_STN0_RX_DN<3>")
	)
	(segment
		(start 317.476378 -285.115762)
		(end 318.671956 -284.422596)
		(width 0.1651)
		(layer "In5.Cu")
		(net "P5E_PEX2_STN0_RX_DN<3>")
	)
	(segment
		(start 305.016154 -126.186438)
		(end 301.767748 -124.836428)
		(width 0.1651)
		(layer "In5.Cu")
		(net "P5E_PEX2_STN0_RX_DN<3>")
	)
	(segment
		(start 316.121542 -285.115762)
		(end 316.14999 -285.115762)
		(width 0.1143)
		(layer "In5.Cu")
		(net "P5E_PEX2_STN0_RX_DN<3>")
	)
	(segment
		(start 318.056006 -144.316196)
		(end 314.82284 -140.10386)
		(width 0.1651)
		(layer "In5.Cu")
		(net "P5E_PEX2_STN0_RX_DN<3>")
	)
	(segment
		(start 314.384436 -285.449772)
		(end 314.270136 -285.335472)
		(width 0.1143)
		(layer "In5.Cu")
		(net "P5E_PEX2_STN0_RX_DN<3>")
	)
	(segment
		(start 301.767748 -124.836428)
		(end 299.481748 -124.394468)
		(width 0.1651)
		(layer "In5.Cu")
		(net "P5E_PEX2_STN0_RX_DN<3>")
	)
	(segment
		(start 319.326514 -168.402254)
		(end 318.863726 -150.027132)
		(width 0.1651)
		(layer "In5.Cu")
		(net "P5E_PEX2_STN0_RX_DN<3>")
	)
	(segment
		(start 314.373768 -285.070042)
		(end 316.075822 -285.070042)
		(width 0.1143)
		(layer "In5.Cu")
		(net "P5E_PEX2_STN0_RX_DN<3>")
	)
	(segment
		(start 318.671702 -232.197402)
		(end 319.326514 -168.402254)
		(width 0.1651)
		(layer "In5.Cu")
		(net "P5E_PEX2_STN0_RX_DN<3>")
	)
	(segment
		(start 316.14999 -285.115762)
		(end 317.476378 -285.115762)
		(width 0.1651)
		(layer "In5.Cu")
		(net "P5E_PEX2_STN0_RX_DN<3>")
	)
	(segment
		(start 328.937874 -269.543276)
		(end 320.393568 -240.289334)
		(width 0.1651)
		(layer "In5.Cu")
		(net "P5E_PEX2_STN0_RX_DN<3>")
	)
	(segment
		(start 318.464184 -147.200366)
		(end 318.056006 -144.316196)
		(width 0.1651)
		(layer "In5.Cu")
		(net "P5E_PEX2_STN0_RX_DN<3>")
	)
	(segment
		(start 328.824336 -272.856706)
		(end 328.937874 -269.543276)
		(width 0.1651)
		(layer "In5.Cu")
		(net "P5E_PEX2_STN0_RX_DN<3>")
	)
	(segment
		(start 318.863726 -150.027132)
		(end 318.46393 -147.200366)
		(width 0.1651)
		(layer "In5.Cu")
		(net "P5E_PEX2_STN0_RX_DN<3>")
	)
	(segment
		(start 320.393568 -240.289334)
		(end 318.671702 -232.197402)
		(width 0.1651)
		(layer "In5.Cu")
		(net "P5E_PEX2_STN0_RX_DN<3>")
	)
	(segment
		(start 297.693842 -124.394468)
		(end 297.403012 -124.103638)
		(width 0.1651)
		(layer "In5.Cu")
		(net "P5E_PEX2_STN0_RX_DN<3>")
	)
	(segment
		(start 316.075822 -285.070042)
		(end 316.121542 -285.115762)
		(width 0.1143)
		(layer "In5.Cu")
		(net "P5E_PEX2_STN0_RX_DN<3>")
	)
	(segment
		(start 326.678544 -276.661626)
		(end 328.824336 -272.856706)
		(width 0.1651)
		(layer "In5.Cu")
		(net "P5E_PEX2_STN0_RX_DN<3>")
	)
	(segment
		(start 299.481748 -124.394468)
		(end 297.693842 -124.394468)
		(width 0.1651)
		(layer "In5.Cu")
		(net "P5E_PEX2_STN0_RX_DN<3>")
	)
	(segment
		(start 312.24728 -137.67562)
		(end 305.89474 -127.04318)
		(width 0.1651)
		(layer "In5.Cu")
		(net "P5E_PEX2_STN0_RX_DN<3>")
	)
	(segment
		(start 331.490066 -400.772122)
		(end 331.617066 -400.899122)
		(width 0.1651)
		(layer "In5.Cu")
		(net "P5E_PEX2_STN6_RX_DP<111>")
	)
	(segment
		(start 302.40097 -339.910674)
		(end 278.516588 -327.038462)
		(width 0.1651)
		(layer "In5.Cu")
		(net "P5E_PEX2_STN6_RX_DP<111>")
	)
	(segment
		(start 275.76526 -324.611238)
		(end 275.083778 -322.963286)
		(width 0.1651)
		(layer "In5.Cu")
		(net "P5E_PEX2_STN6_RX_DP<111>")
	)
	(segment
		(start 328.952606 -393.00912)
		(end 327.37552 -392.347704)
		(width 0.1651)
		(layer "In5.Cu")
		(net "P5E_PEX2_STN6_RX_DP<111>")
	)
	(segment
		(start 331.617066 -400.899122)
		(end 332.047342 -400.899122)
		(width 0.1651)
		(layer "In5.Cu")
		(net "P5E_PEX2_STN6_RX_DP<111>")
	)
	(segment
		(start 276.652228 -325.720964)
		(end 275.76526 -324.611238)
		(width 0.1651)
		(layer "In5.Cu")
		(net "P5E_PEX2_STN6_RX_DP<111>")
	)
	(segment
		(start 330.74483 -393.761214)
		(end 330.595224 -393.822428)
		(width 0.1651)
		(layer "In5.Cu")
		(net "P5E_PEX2_STN6_RX_DP<111>")
	)
	(segment
		(start 275.083778 -320.043048)
		(end 275.083778 -320.0146)
		(width 0.1143)
		(layer "In5.Cu")
		(net "P5E_PEX2_STN6_RX_DP<111>")
	)
	(segment
		(start 329.620372 -393.289282)
		(end 329.470766 -393.350496)
		(width 0.1651)
		(layer "In5.Cu")
		(net "P5E_PEX2_STN6_RX_DP<111>")
	)
	(segment
		(start 275.355304 -316.229492)
		(end 275.585428 -316.229492)
		(width 0.1143)
		(layer "In5.Cu")
		(net "P5E_PEX2_STN6_RX_DP<111>")
	)
	(segment
		(start 332.334108 -395.0843)
		(end 332.162658 -394.672058)
		(width 0.1651)
		(layer "In5.Cu")
		(net "P5E_PEX2_STN6_RX_DP<111>")
	)
	(segment
		(start 332.334108 -400.612356)
		(end 332.334108 -395.0843)
		(width 0.1651)
		(layer "In5.Cu")
		(net "P5E_PEX2_STN6_RX_DP<111>")
	)
	(segment
		(start 275.699728 -316.115192)
		(end 275.699728 -315.849762)
		(width 0.1143)
		(layer "In5.Cu")
		(net "P5E_PEX2_STN6_RX_DP<111>")
	)
	(segment
		(start 327.37552 -392.347704)
		(end 324.677786 -389.644636)
		(width 0.1651)
		(layer "In5.Cu")
		(net "P5E_PEX2_STN6_RX_DP<111>")
	)
	(segment
		(start 332.047342 -400.899122)
		(end 332.334108 -400.612356)
		(width 0.1651)
		(layer "In5.Cu")
		(net "P5E_PEX2_STN6_RX_DP<111>")
	)
	(segment
		(start 330.595224 -393.822428)
		(end 330.138278 -393.630658)
		(width 0.1651)
		(layer "In5.Cu")
		(net "P5E_PEX2_STN6_RX_DP<111>")
	)
	(segment
		(start 329.01382 -393.15898)
		(end 328.952606 -393.00912)
		(width 0.1651)
		(layer "In5.Cu")
		(net "P5E_PEX2_STN6_RX_DP<111>")
	)
	(segment
		(start 330.138278 -393.630658)
		(end 330.077064 -393.480798)
		(width 0.1651)
		(layer "In5.Cu")
		(net "P5E_PEX2_STN6_RX_DP<111>")
	)
	(segment
		(start 275.129498 -319.96888)
		(end 275.129498 -316.455298)
		(width 0.1143)
		(layer "In5.Cu")
		(net "P5E_PEX2_STN6_RX_DP<111>")
	)
	(segment
		(start 331.627988 -394.131546)
		(end 330.74483 -393.761214)
		(width 0.1651)
		(layer "In5.Cu")
		(net "P5E_PEX2_STN6_RX_DP<111>")
	)
	(segment
		(start 330.077064 -393.480798)
		(end 329.620372 -393.289282)
		(width 0.1651)
		(layer "In5.Cu")
		(net "P5E_PEX2_STN6_RX_DP<111>")
	)
	(segment
		(start 302.611028 -340.228936)
		(end 302.40097 -339.910674)
		(width 0.1651)
		(layer "In5.Cu")
		(net "P5E_PEX2_STN6_RX_DP<111>")
	)
	(segment
		(start 275.585428 -316.229492)
		(end 275.699728 -316.115192)
		(width 0.1143)
		(layer "In5.Cu")
		(net "P5E_PEX2_STN6_RX_DP<111>")
	)
	(segment
		(start 332.162658 -394.672058)
		(end 331.627988 -394.131546)
		(width 0.1651)
		(layer "In5.Cu")
		(net "P5E_PEX2_STN6_RX_DP<111>")
	)
	(segment
		(start 329.470766 -393.350496)
		(end 329.01382 -393.15898)
		(width 0.1651)
		(layer "In5.Cu")
		(net "P5E_PEX2_STN6_RX_DP<111>")
	)
	(segment
		(start 275.129498 -316.455298)
		(end 275.355304 -316.229492)
		(width 0.1143)
		(layer "In5.Cu")
		(net "P5E_PEX2_STN6_RX_DP<111>")
	)
	(segment
		(start 275.083778 -320.0146)
		(end 275.129498 -319.96888)
		(width 0.1143)
		(layer "In5.Cu")
		(net "P5E_PEX2_STN6_RX_DP<111>")
	)
	(segment
		(start 324.677786 -389.644636)
		(end 302.611028 -340.228936)
		(width 0.1651)
		(layer "In5.Cu")
		(net "P5E_PEX2_STN6_RX_DP<111>")
	)
	(segment
		(start 275.083778 -322.963286)
		(end 275.083778 -320.043048)
		(width 0.1651)
		(layer "In5.Cu")
		(net "P5E_PEX2_STN6_RX_DP<111>")
	)
	(segment
		(start 278.516588 -327.038462)
		(end 276.652228 -325.720964)
		(width 0.1651)
		(layer "In5.Cu")
		(net "P5E_PEX2_STN6_RX_DP<111>")
	)
	(segment
		(start 331.490066 -400.390106)
		(end 331.490066 -400.772122)
		(width 0.1651)
		(layer "In5.Cu")
		(net "P5E_PEX2_STN6_RX_DP<111>")
	)
	(segment
		(start 393.8397 -106.644948)
		(end 394.342366 -106.644948)
		(width 0.13462)
		(layer "F.Cu")
		(net "P5E_PEX3_STN1_TX_C_DP<20>")
	)
	(segment
		(start 388.170674 -106.81208)
		(end 393.672568 -106.81208)
		(width 0.13462)
		(layer "F.Cu")
		(net "P5E_PEX3_STN1_TX_C_DP<20>")
	)
	(segment
		(start 393.672568 -106.81208)
		(end 393.8397 -106.644948)
		(width 0.13462)
		(layer "F.Cu")
		(net "P5E_PEX3_STN1_TX_C_DP<20>")
	)
	(segment
		(start 387.847332 -106.488738)
		(end 388.170674 -106.81208)
		(width 0.13462)
		(layer "F.Cu")
		(net "P5E_PEX3_STN1_TX_C_DP<20>")
	)
	(segment
		(start 371.483128 -344.53957)
		(end 371.483128 -345.169998)
		(width 0.13462)
		(layer "F.Cu")
		(net "P5E_PEX3_STN6_TX_C_DP<111>")
	)
	(segment
		(start 371.16258 -344.219022)
		(end 371.483128 -344.53957)
		(width 0.13462)
		(layer "F.Cu")
		(net "P5E_PEX3_STN6_TX_C_DP<111>")
	)
	(segment
		(start 371.483128 -345.169998)
		(end 371.18798 -345.465146)
		(width 0.13462)
		(layer "F.Cu")
		(net "P5E_PEX3_STN6_TX_C_DP<111>")
	)
	(segment
		(start 369.937792 -347.750638)
		(end 371.47881 -346.209874)
		(width 0.1651)
		(layer "In13.Cu")
		(net "P5E_PEX3_STN6_TX_C_DP<111>")
	)
	(segment
		(start 376.33402 -408.412442)
		(end 376.33402 -395.37767)
		(width 0.1651)
		(layer "In13.Cu")
		(net "P5E_PEX3_STN6_TX_C_DP<111>")
	)
	(segment
		(start 371.37594 -391.802112)
		(end 368.86388 -389.893556)
		(width 0.1651)
		(layer "In13.Cu")
		(net "P5E_PEX3_STN6_TX_C_DP<111>")
	)
	(segment
		(start 376.047254 -408.699208)
		(end 376.33402 -408.412442)
		(width 0.1651)
		(layer "In13.Cu")
		(net "P5E_PEX3_STN6_TX_C_DP<111>")
	)
	(segment
		(start 374.819164 -393.780264)
		(end 374.684798 -393.831064)
		(width 0.1651)
		(layer "In13.Cu")
		(net "P5E_PEX3_STN6_TX_C_DP<111>")
	)
	(segment
		(start 371.47881 -345.755976)
		(end 371.18798 -345.465146)
		(width 0.1651)
		(layer "In13.Cu")
		(net "P5E_PEX3_STN6_TX_C_DP<111>")
	)
	(segment
		(start 372.751604 -392.847322)
		(end 371.932454 -392.225022)
		(width 0.1651)
		(layer "In13.Cu")
		(net "P5E_PEX3_STN6_TX_C_DP<111>")
	)
	(segment
		(start 376.33402 -395.37767)
		(end 376.074432 -394.697712)
		(width 0.1651)
		(layer "In13.Cu")
		(net "P5E_PEX3_STN6_TX_C_DP<111>")
	)
	(segment
		(start 371.47881 -346.209874)
		(end 371.47881 -345.755976)
		(width 0.1651)
		(layer "In13.Cu")
		(net "P5E_PEX3_STN6_TX_C_DP<111>")
	)
	(segment
		(start 375.489978 -408.572208)
		(end 375.616978 -408.699208)
		(width 0.1651)
		(layer "In13.Cu")
		(net "P5E_PEX3_STN6_TX_C_DP<111>")
	)
	(segment
		(start 367.35766 -366.922558)
		(end 369.937792 -347.750638)
		(width 0.1651)
		(layer "In13.Cu")
		(net "P5E_PEX3_STN6_TX_C_DP<111>")
	)
	(segment
		(start 375.489978 -408.190192)
		(end 375.489978 -408.572208)
		(width 0.1651)
		(layer "In13.Cu")
		(net "P5E_PEX3_STN6_TX_C_DP<111>")
	)
	(segment
		(start 374.684798 -393.831064)
		(end 374.233186 -393.627102)
		(width 0.1651)
		(layer "In13.Cu")
		(net "P5E_PEX3_STN6_TX_C_DP<111>")
	)
	(segment
		(start 366.697768 -373.109236)
		(end 367.35766 -366.922558)
		(width 0.1651)
		(layer "In13.Cu")
		(net "P5E_PEX3_STN6_TX_C_DP<111>")
	)
	(segment
		(start 371.790214 -392.24458)
		(end 371.395498 -391.944606)
		(width 0.1651)
		(layer "In13.Cu")
		(net "P5E_PEX3_STN6_TX_C_DP<111>")
	)
	(segment
		(start 375.388378 -394.037058)
		(end 374.819164 -393.780264)
		(width 0.1651)
		(layer "In13.Cu")
		(net "P5E_PEX3_STN6_TX_C_DP<111>")
	)
	(segment
		(start 367.187988 -386.045202)
		(end 366.697768 -373.109236)
		(width 0.1651)
		(layer "In13.Cu")
		(net "P5E_PEX3_STN6_TX_C_DP<111>")
	)
	(segment
		(start 371.932454 -392.225022)
		(end 371.790214 -392.24458)
		(width 0.1651)
		(layer "In13.Cu")
		(net "P5E_PEX3_STN6_TX_C_DP<111>")
	)
	(segment
		(start 368.86388 -389.893556)
		(end 367.187988 -386.045202)
		(width 0.1651)
		(layer "In13.Cu")
		(net "P5E_PEX3_STN6_TX_C_DP<111>")
	)
	(segment
		(start 376.074432 -394.697712)
		(end 375.388378 -394.037058)
		(width 0.1651)
		(layer "In13.Cu")
		(net "P5E_PEX3_STN6_TX_C_DP<111>")
	)
	(segment
		(start 374.182386 -393.492736)
		(end 372.751604 -392.847322)
		(width 0.1651)
		(layer "In13.Cu")
		(net "P5E_PEX3_STN6_TX_C_DP<111>")
	)
	(segment
		(start 374.233186 -393.627102)
		(end 374.182386 -393.492736)
		(width 0.1651)
		(layer "In13.Cu")
		(net "P5E_PEX3_STN6_TX_C_DP<111>")
	)
	(segment
		(start 371.395498 -391.944606)
		(end 371.37594 -391.802112)
		(width 0.1651)
		(layer "In13.Cu")
		(net "P5E_PEX3_STN6_TX_C_DP<111>")
	)
	(segment
		(start 375.616978 -408.699208)
		(end 376.047254 -408.699208)
		(width 0.1651)
		(layer "In13.Cu")
		(net "P5E_PEX3_STN6_TX_C_DP<111>")
	)
	(segment
		(start 189.357508 -101.240082)
		(end 190.775844 -101.240082)
		(width 0.13208)
		(layer "F.Cu")
		(net "NCSI_NIC3_RXD1")
	)
	(via
		(at 190.775844 -101.240082)
		(size 0.508)
		(drill 0.254)
		(layers "F.Cu" "B.Cu")
		(net "NCSI_NIC3_RXD1")
	)
	(segment
		(start 192.026794 -102.088696)
		(end 191.17818 -101.240082)
		(width 0.13208)
		(layer "B.Cu")
		(net "NCSI_NIC3_RXD1")
	)
	(segment
		(start 193.241676 -102.088696)
		(end 192.026794 -102.088696)
		(width 0.13208)
		(layer "B.Cu")
		(net "NCSI_NIC3_RXD1")
	)
	(segment
		(start 191.17818 -101.240082)
		(end 190.775844 -101.240082)
		(width 0.13208)
		(layer "B.Cu")
		(net "NCSI_NIC3_RXD1")
	)
	(segment
		(start 394.342366 -153.560018)
		(end 392.03503 -153.560018)
		(width 0.13208)
		(layer "F.Cu")
		(net "NCSI_NIC6_RXD0")
	)
	(segment
		(start 387.737858 -151.279352)
		(end 387.299962 -151.279352)
		(width 0.13208)
		(layer "F.Cu")
		(net "NCSI_NIC6_RXD0")
	)
	(segment
		(start 387.92404 -151.465534)
		(end 387.737858 -151.279352)
		(width 0.13208)
		(layer "F.Cu")
		(net "NCSI_NIC6_RXD0")
	)
	(segment
		(start 392.03503 -153.560018)
		(end 389.940546 -151.465534)
		(width 0.13208)
		(layer "F.Cu")
		(net "NCSI_NIC6_RXD0")
	)
	(segment
		(start 388.482332 -151.465534)
		(end 387.92404 -151.465534)
		(width 0.13208)
		(layer "F.Cu")
		(net "NCSI_NIC6_RXD0")
	)
	(segment
		(start 389.940546 -151.465534)
		(end 388.482332 -151.465534)
		(width 0.13208)
		(layer "F.Cu")
		(net "NCSI_NIC6_RXD0")
	)
	(via
		(at 388.482332 -151.465534)
		(size 0.762)
		(drill 0.381)
		(layers "F.Cu" "B.Cu")
		(net "NCSI_NIC6_RXD0")
	)
	(segment
		(start 242.864894 -25.390094)
		(end 241.652044 -25.390094)
		(width 0.13208)
		(layer "F.Cu")
		(net "PRSNT_SSD8_N")
	)
	(segment
		(start 241.102134 -25.940004)
		(end 241.102134 -26.266394)
		(width 0.13208)
		(layer "F.Cu")
		(net "PRSNT_SSD8_N")
	)
	(segment
		(start 241.102134 -26.266394)
		(end 240.320576 -26.266394)
		(width 0.13208)
		(layer "F.Cu")
		(net "PRSNT_SSD8_N")
	)
	(segment
		(start 241.652044 -25.390094)
		(end 241.102134 -25.940004)
		(width 0.13208)
		(layer "F.Cu")
		(net "PRSNT_SSD8_N")
	)
	(via
		(at 241.102134 -26.266394)
		(size 0.508)
		(drill 0.254)
		(layers "F.Cu" "B.Cu")
		(net "PRSNT_SSD8_N")
	)
	(segment
		(start 178.119532 -28.55468)
		(end 177.460656 -28.55468)
		(width 0.13462)
		(layer "F.Cu")
		(net "P5E_PEX1_STN2_RX_DN<36>")
	)
	(segment
		(start 178.284124 -28.390088)
		(end 178.119532 -28.55468)
		(width 0.13462)
		(layer "F.Cu")
		(net "P5E_PEX1_STN2_RX_DN<36>")
	)
	(segment
		(start 178.764946 -28.390088)
		(end 178.284124 -28.390088)
		(width 0.13462)
		(layer "F.Cu")
		(net "P5E_PEX1_STN2_RX_DN<36>")
	)
	(segment
		(start 177.460656 -28.55468)
		(end 177.164746 -28.25877)
		(width 0.13462)
		(layer "F.Cu")
		(net "P5E_PEX1_STN2_RX_DN<36>")
	)
	(segment
		(start 170.723814 -275.379688)
		(end 170.885612 -275.379688)
		(width 0.1143)
		(layer "In7.Cu")
		(net "P5E_PEX1_STN2_RX_DN<36>")
	)
	(segment
		(start 183.406796 -39.169594)
		(end 181.383178 -48.834802)
		(width 0.1651)
		(layer "In7.Cu")
		(net "P5E_PEX1_STN2_RX_DN<36>")
	)
	(segment
		(start 170.665648 -266.499848)
		(end 170.665648 -271.392904)
		(width 0.1651)
		(layer "In7.Cu")
		(net "P5E_PEX1_STN2_RX_DN<36>")
	)
	(segment
		(start 170.619928 -275.275802)
		(end 170.723814 -275.379688)
		(width 0.1143)
		(layer "In7.Cu")
		(net "P5E_PEX1_STN2_RX_DN<36>")
	)
	(segment
		(start 170.999912 -275.265388)
		(end 170.999912 -274.999958)
		(width 0.1143)
		(layer "In7.Cu")
		(net "P5E_PEX1_STN2_RX_DN<36>")
	)
	(segment
		(start 170.665648 -271.392904)
		(end 170.665648 -271.421352)
		(width 0.1143)
		(layer "In7.Cu")
		(net "P5E_PEX1_STN2_RX_DN<36>")
	)
	(segment
		(start 180.802788 -31.448502)
		(end 183.431434 -37.688012)
		(width 0.1651)
		(layer "In7.Cu")
		(net "P5E_PEX1_STN2_RX_DN<36>")
	)
	(segment
		(start 170.885612 -275.379688)
		(end 170.999912 -275.265388)
		(width 0.1143)
		(layer "In7.Cu")
		(net "P5E_PEX1_STN2_RX_DN<36>")
	)
	(segment
		(start 170.79976 -264.972038)
		(end 170.665648 -266.499848)
		(width 0.1651)
		(layer "In7.Cu")
		(net "P5E_PEX1_STN2_RX_DN<36>")
	)
	(segment
		(start 177.457862 -28.551886)
		(end 177.463704 -28.5496)
		(width 0.1651)
		(layer "In7.Cu")
		(net "P5E_PEX1_STN2_RX_DN<36>")
	)
	(segment
		(start 170.619928 -271.467072)
		(end 170.619928 -275.275802)
		(width 0.1143)
		(layer "In7.Cu")
		(net "P5E_PEX1_STN2_RX_DN<36>")
	)
	(segment
		(start 170.665648 -271.421352)
		(end 170.619928 -271.467072)
		(width 0.1143)
		(layer "In7.Cu")
		(net "P5E_PEX1_STN2_RX_DN<36>")
	)
	(segment
		(start 181.183788 -68.374514)
		(end 170.79976 -264.972038)
		(width 0.1651)
		(layer "In7.Cu")
		(net "P5E_PEX1_STN2_RX_DN<36>")
	)
	(segment
		(start 177.903886 -28.5496)
		(end 180.802788 -31.448502)
		(width 0.1651)
		(layer "In7.Cu")
		(net "P5E_PEX1_STN2_RX_DN<36>")
	)
	(segment
		(start 183.431434 -37.688012)
		(end 183.406796 -39.169594)
		(width 0.1651)
		(layer "In7.Cu")
		(net "P5E_PEX1_STN2_RX_DN<36>")
	)
	(segment
		(start 177.164746 -28.25877)
		(end 177.457862 -28.551886)
		(width 0.1651)
		(layer "In7.Cu")
		(net "P5E_PEX1_STN2_RX_DN<36>")
	)
	(segment
		(start 177.463704 -28.5496)
		(end 177.903886 -28.5496)
		(width 0.1651)
		(layer "In7.Cu")
		(net "P5E_PEX1_STN2_RX_DN<36>")
	)
	(segment
		(start 181.383178 -48.834802)
		(end 181.183788 -68.374514)
		(width 0.1651)
		(layer "In7.Cu")
		(net "P5E_PEX1_STN2_RX_DN<36>")
	)
	(segment
		(start 306.131976 -124.6632)
		(end 305.960272 -124.834904)
		(width 0.13462)
		(layer "F.Cu")
		(net "P5E_PEX2_STN0_TX_C_DP<3>")
	)
	(segment
		(start 305.960272 -124.834904)
		(end 305.457606 -124.834904)
		(width 0.13462)
		(layer "F.Cu")
		(net "P5E_PEX2_STN0_TX_C_DP<3>")
	)
	(segment
		(start 314.266834 -124.6632)
		(end 306.131976 -124.6632)
		(width 0.13462)
		(layer "F.Cu")
		(net "P5E_PEX2_STN0_TX_C_DP<3>")
	)
	(segment
		(start 314.594748 -124.991114)
		(end 314.266834 -124.6632)
		(width 0.13462)
		(layer "F.Cu")
		(net "P5E_PEX2_STN0_TX_C_DP<3>")
	)
	(segment
		(start 300.244002 -329.897486)
		(end 299.779436 -329.724766)
		(width 0.1651)
		(layer "In9.Cu")
		(net "P5E_PEX2_STN6_RX_DN<96>")
	)
	(segment
		(start 299.779436 -329.724766)
		(end 299.681392 -329.769724)
		(width 0.1651)
		(layer "In9.Cu")
		(net "P5E_PEX2_STN6_RX_DN<96>")
	)
	(segment
		(start 289.684206 -318.320166)
		(end 289.86099 -318.320166)
		(width 0.1143)
		(layer "In9.Cu")
		(net "P5E_PEX2_STN6_RX_DN<96>")
	)
	(segment
		(start 347.017086 -376.281188)
		(end 347.564202 -376.281188)
		(width 0.1651)
		(layer "In9.Cu")
		(net "P5E_PEX2_STN6_RX_DN<96>")
	)
	(segment
		(start 347.564202 -376.281188)
		(end 348.016068 -375.829322)
		(width 0.1651)
		(layer "In9.Cu")
		(net "P5E_PEX2_STN6_RX_DN<96>")
	)
	(segment
		(start 289.94989 -318.409066)
		(end 289.94989 -318.699896)
		(width 0.1143)
		(layer "In9.Cu")
		(net "P5E_PEX2_STN6_RX_DN<96>")
	)
	(segment
		(start 289.61588 -319.8876)
		(end 289.57016 -319.84188)
		(width 0.1143)
		(layer "In9.Cu")
		(net "P5E_PEX2_STN6_RX_DN<96>")
	)
	(segment
		(start 347.716856 -368.456718)
		(end 342.47074 -364.58652)
		(width 0.1651)
		(layer "In9.Cu")
		(net "P5E_PEX2_STN6_RX_DN<96>")
	)
	(segment
		(start 289.61588 -319.916048)
		(end 289.61588 -319.8876)
		(width 0.1143)
		(layer "In9.Cu")
		(net "P5E_PEX2_STN6_RX_DN<96>")
	)
	(segment
		(start 289.57016 -319.84188)
		(end 289.57016 -318.434212)
		(width 0.1143)
		(layer "In9.Cu")
		(net "P5E_PEX2_STN6_RX_DN<96>")
	)
	(segment
		(start 330.174854 -342.123776)
		(end 329.433682 -340.822534)
		(width 0.1651)
		(layer "In9.Cu")
		(net "P5E_PEX2_STN6_RX_DN<96>")
	)
	(segment
		(start 289.86099 -318.320166)
		(end 289.94989 -318.409066)
		(width 0.1143)
		(layer "In9.Cu")
		(net "P5E_PEX2_STN6_RX_DN<96>")
	)
	(segment
		(start 346.890086 -376.790204)
		(end 346.890086 -376.408188)
		(width 0.1651)
		(layer "In9.Cu")
		(net "P5E_PEX2_STN6_RX_DN<96>")
	)
	(segment
		(start 299.681392 -329.76947)
		(end 296.16781 -328.464418)
		(width 0.1651)
		(layer "In9.Cu")
		(net "P5E_PEX2_STN6_RX_DN<96>")
	)
	(segment
		(start 330.174854 -358.511094)
		(end 330.174854 -342.123776)
		(width 0.1651)
		(layer "In9.Cu")
		(net "P5E_PEX2_STN6_RX_DN<96>")
	)
	(segment
		(start 348.016068 -375.829322)
		(end 348.016068 -368.96802)
		(width 0.1651)
		(layer "In9.Cu")
		(net "P5E_PEX2_STN6_RX_DN<96>")
	)
	(segment
		(start 342.47074 -364.58652)
		(end 330.46416 -358.8004)
		(width 0.1651)
		(layer "In9.Cu")
		(net "P5E_PEX2_STN6_RX_DN<96>")
	)
	(segment
		(start 289.57016 -318.434212)
		(end 289.684206 -318.320166)
		(width 0.1143)
		(layer "In9.Cu")
		(net "P5E_PEX2_STN6_RX_DN<96>")
	)
	(segment
		(start 348.016068 -368.96802)
		(end 347.716856 -368.456718)
		(width 0.1651)
		(layer "In9.Cu")
		(net "P5E_PEX2_STN6_RX_DN<96>")
	)
	(segment
		(start 296.16781 -328.464418)
		(end 292.532054 -326.131174)
		(width 0.1651)
		(layer "In9.Cu")
		(net "P5E_PEX2_STN6_RX_DN<96>")
	)
	(segment
		(start 289.61588 -323.078348)
		(end 289.61588 -319.916048)
		(width 0.1651)
		(layer "In9.Cu")
		(net "P5E_PEX2_STN6_RX_DN<96>")
	)
	(segment
		(start 300.28896 -329.995276)
		(end 300.28896 -329.99553)
		(width 0.1651)
		(layer "In9.Cu")
		(net "P5E_PEX2_STN6_RX_DN<96>")
	)
	(segment
		(start 330.46416 -358.8004)
		(end 330.174854 -358.511094)
		(width 0.1651)
		(layer "In9.Cu")
		(net "P5E_PEX2_STN6_RX_DN<96>")
	)
	(segment
		(start 299.681392 -329.769724)
		(end 299.681392 -329.76947)
		(width 0.1651)
		(layer "In9.Cu")
		(net "P5E_PEX2_STN6_RX_DN<96>")
	)
	(segment
		(start 346.890086 -376.408188)
		(end 347.017086 -376.281188)
		(width 0.1651)
		(layer "In9.Cu")
		(net "P5E_PEX2_STN6_RX_DN<96>")
	)
	(segment
		(start 292.532054 -326.131174)
		(end 289.7124 -323.31152)
		(width 0.1651)
		(layer "In9.Cu")
		(net "P5E_PEX2_STN6_RX_DN<96>")
	)
	(segment
		(start 329.433682 -340.822534)
		(end 300.28896 -329.995276)
		(width 0.1651)
		(layer "In9.Cu")
		(net "P5E_PEX2_STN6_RX_DN<96>")
	)
	(segment
		(start 289.7124 -323.31152)
		(end 289.61588 -323.078348)
		(width 0.1651)
		(layer "In9.Cu")
		(net "P5E_PEX2_STN6_RX_DN<96>")
	)
	(segment
		(start 300.28896 -329.99553)
		(end 300.244002 -329.897486)
		(width 0.1651)
		(layer "In9.Cu")
		(net "P5E_PEX2_STN6_RX_DN<96>")
	)
	(segment
		(start 393.843002 -132.364988)
		(end 394.342366 -132.364988)
		(width 0.13462)
		(layer "F.Cu")
		(net "P5E_PEX3_STN1_TX_C_DN<29>")
	)
	(segment
		(start 388.14883 -132.51688)
		(end 393.69111 -132.51688)
		(width 0.13462)
		(layer "F.Cu")
		(net "P5E_PEX3_STN1_TX_C_DN<29>")
	)
	(segment
		(start 387.847332 -132.215382)
		(end 388.14883 -132.51688)
		(width 0.13462)
		(layer "F.Cu")
		(net "P5E_PEX3_STN1_TX_C_DN<29>")
	)
	(segment
		(start 393.69111 -132.51688)
		(end 393.843002 -132.364988)
		(width 0.13462)
		(layer "F.Cu")
		(net "P5E_PEX3_STN1_TX_C_DN<29>")
	)
	(segment
		(start 395.193774 -327.103232)
		(end 397.363696 -323.607176)
		(width 0.1651)
		(layer "In15.Cu")
		(net "P5E_PEX3_STN6_RX_DP<104>")
	)
	(segment
		(start 389.495284 -393.278868)
		(end 388.47903 -392.238484)
		(width 0.1651)
		(layer "In15.Cu")
		(net "P5E_PEX3_STN6_RX_DP<104>")
	)
	(segment
		(start 397.83385 -319.995296)
		(end 397.83385 -319.966848)
		(width 0.1143)
		(layer "In15.Cu")
		(net "P5E_PEX3_STN6_RX_DP<104>")
	)
	(segment
		(start 397.83385 -319.966848)
		(end 397.87957 -319.921128)
		(width 0.1143)
		(layer "In15.Cu")
		(net "P5E_PEX3_STN6_RX_DP<104>")
	)
	(segment
		(start 374.156986 -384.597148)
		(end 373.71401 -373.039132)
		(width 0.1651)
		(layer "In15.Cu")
		(net "P5E_PEX3_STN6_RX_DP<104>")
	)
	(segment
		(start 398.094708 -318.129666)
		(end 398.3355 -318.129666)
		(width 0.1143)
		(layer "In15.Cu")
		(net "P5E_PEX3_STN6_RX_DP<104>")
	)
	(segment
		(start 373.71401 -373.039132)
		(end 373.8753 -371.333776)
		(width 0.1651)
		(layer "In15.Cu")
		(net "P5E_PEX3_STN6_RX_DP<104>")
	)
	(segment
		(start 397.87957 -318.344804)
		(end 398.094708 -318.129666)
		(width 0.1143)
		(layer "In15.Cu")
		(net "P5E_PEX3_STN6_RX_DP<104>")
	)
	(segment
		(start 398.3355 -318.129666)
		(end 398.4498 -318.015366)
		(width 0.1143)
		(layer "In15.Cu")
		(net "P5E_PEX3_STN6_RX_DP<104>")
	)
	(segment
		(start 391.447274 -401.999196)
		(end 391.73404 -401.71243)
		(width 0.1651)
		(layer "In15.Cu")
		(net "P5E_PEX3_STN6_RX_DP<104>")
	)
	(segment
		(start 374.704356 -368.445034)
		(end 381.991108 -359.04297)
		(width 0.1651)
		(layer "In15.Cu")
		(net "P5E_PEX3_STN6_RX_DP<104>")
	)
	(segment
		(start 390.853168 -394.66901)
		(end 390.691624 -394.667232)
		(width 0.1651)
		(layer "In15.Cu")
		(net "P5E_PEX3_STN6_RX_DP<104>")
	)
	(segment
		(start 374.24995 -369.418108)
		(end 374.704356 -368.445034)
		(width 0.1651)
		(layer "In15.Cu")
		(net "P5E_PEX3_STN6_RX_DP<104>")
	)
	(segment
		(start 388.47903 -392.238484)
		(end 387.459982 -391.608564)
		(width 0.1651)
		(layer "In15.Cu")
		(net "P5E_PEX3_STN6_RX_DP<104>")
	)
	(segment
		(start 390.001252 -393.796774)
		(end 389.839708 -393.794996)
		(width 0.1651)
		(layer "In15.Cu")
		(net "P5E_PEX3_STN6_RX_DP<104>")
	)
	(segment
		(start 390.889998 -401.49018)
		(end 390.889998 -401.872196)
		(width 0.1651)
		(layer "In15.Cu")
		(net "P5E_PEX3_STN6_RX_DP<104>")
	)
	(segment
		(start 390.3472 -394.15085)
		(end 390.001252 -393.796774)
		(width 0.1651)
		(layer "In15.Cu")
		(net "P5E_PEX3_STN6_RX_DP<104>")
	)
	(segment
		(start 389.493252 -393.440412)
		(end 389.495284 -393.278868)
		(width 0.1651)
		(layer "In15.Cu")
		(net "P5E_PEX3_STN6_RX_DP<104>")
	)
	(segment
		(start 382.36017 -342.114886)
		(end 382.990598 -340.667086)
		(width 0.1651)
		(layer "In15.Cu")
		(net "P5E_PEX3_STN6_RX_DP<104>")
	)
	(segment
		(start 387.459982 -391.608564)
		(end 376.200924 -386.707634)
		(width 0.1651)
		(layer "In15.Cu")
		(net "P5E_PEX3_STN6_RX_DP<104>")
	)
	(segment
		(start 390.889998 -401.872196)
		(end 391.016998 -401.999196)
		(width 0.1651)
		(layer "In15.Cu")
		(net "P5E_PEX3_STN6_RX_DP<104>")
	)
	(segment
		(start 381.991108 -359.04297)
		(end 382.36017 -357.964994)
		(width 0.1651)
		(layer "In15.Cu")
		(net "P5E_PEX3_STN6_RX_DP<104>")
	)
	(segment
		(start 391.016998 -401.999196)
		(end 391.447274 -401.999196)
		(width 0.1651)
		(layer "In15.Cu")
		(net "P5E_PEX3_STN6_RX_DP<104>")
	)
	(segment
		(start 393.01166 -329.203558)
		(end 395.193774 -327.103232)
		(width 0.1651)
		(layer "In15.Cu")
		(net "P5E_PEX3_STN6_RX_DP<104>")
	)
	(segment
		(start 391.73404 -396.088108)
		(end 391.418826 -395.24813)
		(width 0.1651)
		(layer "In15.Cu")
		(net "P5E_PEX3_STN6_RX_DP<104>")
	)
	(segment
		(start 382.36017 -357.964994)
		(end 382.36017 -342.114886)
		(width 0.1651)
		(layer "In15.Cu")
		(net "P5E_PEX3_STN6_RX_DP<104>")
	)
	(segment
		(start 397.363696 -323.607176)
		(end 397.83385 -322.473066)
		(width 0.1651)
		(layer "In15.Cu")
		(net "P5E_PEX3_STN6_RX_DP<104>")
	)
	(segment
		(start 390.691624 -394.667232)
		(end 390.345422 -394.312648)
		(width 0.1651)
		(layer "In15.Cu")
		(net "P5E_PEX3_STN6_RX_DP<104>")
	)
	(segment
		(start 382.990598 -340.667086)
		(end 393.01166 -329.203558)
		(width 0.1651)
		(layer "In15.Cu")
		(net "P5E_PEX3_STN6_RX_DP<104>")
	)
	(segment
		(start 391.73404 -401.71243)
		(end 391.73404 -396.088108)
		(width 0.1651)
		(layer "In15.Cu")
		(net "P5E_PEX3_STN6_RX_DP<104>")
	)
	(segment
		(start 374.635014 -385.58597)
		(end 374.156986 -384.597148)
		(width 0.1651)
		(layer "In15.Cu")
		(net "P5E_PEX3_STN6_RX_DP<104>")
	)
	(segment
		(start 389.839708 -393.794996)
		(end 389.493252 -393.440412)
		(width 0.1651)
		(layer "In15.Cu")
		(net "P5E_PEX3_STN6_RX_DP<104>")
	)
	(segment
		(start 373.8753 -371.333776)
		(end 374.24995 -369.418108)
		(width 0.1651)
		(layer "In15.Cu")
		(net "P5E_PEX3_STN6_RX_DP<104>")
	)
	(segment
		(start 397.83385 -322.473066)
		(end 397.83385 -319.995296)
		(width 0.1651)
		(layer "In15.Cu")
		(net "P5E_PEX3_STN6_RX_DP<104>")
	)
	(segment
		(start 398.4498 -318.015366)
		(end 398.4498 -317.749936)
		(width 0.1143)
		(layer "In15.Cu")
		(net "P5E_PEX3_STN6_RX_DP<104>")
	)
	(segment
		(start 376.200924 -386.707634)
		(end 374.635014 -385.58597)
		(width 0.1651)
		(layer "In15.Cu")
		(net "P5E_PEX3_STN6_RX_DP<104>")
	)
	(segment
		(start 390.345422 -394.312648)
		(end 390.3472 -394.15085)
		(width 0.1651)
		(layer "In15.Cu")
		(net "P5E_PEX3_STN6_RX_DP<104>")
	)
	(segment
		(start 397.87957 -319.921128)
		(end 397.87957 -318.344804)
		(width 0.1143)
		(layer "In15.Cu")
		(net "P5E_PEX3_STN6_RX_DP<104>")
	)
	(segment
		(start 391.418826 -395.24813)
		(end 390.853168 -394.66901)
		(width 0.1651)
		(layer "In15.Cu")
		(net "P5E_PEX3_STN6_RX_DP<104>")
	)
	(segment
		(start 388.697216 -140.379196)
		(end 389.68299 -141.36497)
		(width 0.13208)
		(layer "F.Cu")
		(net "NIC6_BIF2_N")
	)
	(segment
		(start 385.704842 -140.85697)
		(end 386.682742 -140.85697)
		(width 0.13208)
		(layer "F.Cu")
		(net "NIC6_BIF2_N")
	)
	(segment
		(start 386.809996 -140.379196)
		(end 388.697216 -140.379196)
		(width 0.13208)
		(layer "F.Cu")
		(net "NIC6_BIF2_N")
	)
	(segment
		(start 386.682742 -140.50645)
		(end 386.809996 -140.379196)
		(width 0.13208)
		(layer "F.Cu")
		(net "NIC6_BIF2_N")
	)
	(segment
		(start 386.682742 -140.85697)
		(end 386.682742 -140.50645)
		(width 0.13208)
		(layer "F.Cu")
		(net "NIC6_BIF2_N")
	)
	(segment
		(start 389.68299 -141.36497)
		(end 394.342366 -141.36497)
		(width 0.13208)
		(layer "F.Cu")
		(net "NIC6_BIF2_N")
	)
	(via
		(at 388.697216 -140.379196)
		(size 0.762)
		(drill 0.381)
		(layers "F.Cu" "B.Cu")
		(net "NIC6_BIF2_N")
	)
	(segment
		(start 213.94801 -34.2265)
		(end 210.03133 -34.2265)
		(width 0.13462)
		(layer "F.Cu")
		(net "P5E_PEX1_STN2_TX_C_DP<35>")
	)
	(segment
		(start 210.03133 -34.2265)
		(end 209.867754 -34.390076)
		(width 0.13462)
		(layer "F.Cu")
		(net "P5E_PEX1_STN2_TX_C_DP<35>")
	)
	(segment
		(start 209.867754 -34.390076)
		(end 209.364834 -34.390076)
		(width 0.13462)
		(layer "F.Cu")
		(net "P5E_PEX1_STN2_TX_C_DP<35>")
	)
	(segment
		(start 214.267796 -34.546286)
		(end 213.94801 -34.2265)
		(width 0.13462)
		(layer "F.Cu")
		(net "P5E_PEX1_STN2_TX_C_DP<35>")
	)
	(segment
		(start 305.941984 -118.834916)
		(end 305.457606 -118.834916)
		(width 0.13462)
		(layer "F.Cu")
		(net "P5E_PEX2_STN0_TX_C_DN<0>")
	)
	(segment
		(start 306.098448 -118.99138)
		(end 305.941984 -118.834916)
		(width 0.13462)
		(layer "F.Cu")
		(net "P5E_PEX2_STN0_TX_C_DN<0>")
	)
	(segment
		(start 311.631584 -118.99138)
		(end 306.098448 -118.99138)
		(width 0.13462)
		(layer "F.Cu")
		(net "P5E_PEX2_STN0_TX_C_DN<0>")
	)
	(segment
		(start 311.95264 -118.670324)
		(end 311.631584 -118.99138)
		(width 0.13462)
		(layer "F.Cu")
		(net "P5E_PEX2_STN0_TX_C_DN<0>")
	)
	(segment
		(start 312.797444 -345.170506)
		(end 312.502804 -345.465146)
		(width 0.13462)
		(layer "F.Cu")
		(net "P5E_PEX2_STN6_TX_C_DP<111>")
	)
	(segment
		(start 312.797444 -344.539062)
		(end 312.797444 -345.170506)
		(width 0.13462)
		(layer "F.Cu")
		(net "P5E_PEX2_STN6_TX_C_DP<111>")
	)
	(segment
		(start 312.477404 -344.219022)
		(end 312.797444 -344.539062)
		(width 0.13462)
		(layer "F.Cu")
		(net "P5E_PEX2_STN6_TX_C_DP<111>")
	)
	(segment
		(start 332.334108 -408.412442)
		(end 332.334108 -394.97762)
		(width 0.1651)
		(layer "In13.Cu")
		(net "P5E_PEX2_STN6_TX_C_DP<111>")
	)
	(segment
		(start 332.047342 -408.699208)
		(end 332.334108 -408.412442)
		(width 0.1651)
		(layer "In13.Cu")
		(net "P5E_PEX2_STN6_TX_C_DP<111>")
	)
	(segment
		(start 314.348114 -347.881194)
		(end 312.793634 -346.326714)
		(width 0.1651)
		(layer "In13.Cu")
		(net "P5E_PEX2_STN6_TX_C_DP<111>")
	)
	(segment
		(start 316.14491 -367.20526)
		(end 315.978794 -366.738408)
		(width 0.1651)
		(layer "In13.Cu")
		(net "P5E_PEX2_STN6_TX_C_DP<111>")
	)
	(segment
		(start 328.436478 -392.9253)
		(end 324.146418 -389.392922)
		(width 0.1651)
		(layer "In13.Cu")
		(net "P5E_PEX2_STN6_TX_C_DP<111>")
	)
	(segment
		(start 315.978794 -366.738408)
		(end 316.032642 -366.62487)
		(width 0.1651)
		(layer "In13.Cu")
		(net "P5E_PEX2_STN6_TX_C_DP<111>")
	)
	(segment
		(start 313.0169 -353.73818)
		(end 314.348114 -352.406966)
		(width 0.1651)
		(layer "In13.Cu")
		(net "P5E_PEX2_STN6_TX_C_DP<111>")
	)
	(segment
		(start 315.586364 -365.637826)
		(end 315.640212 -365.524034)
		(width 0.1651)
		(layer "In13.Cu")
		(net "P5E_PEX2_STN6_TX_C_DP<111>")
	)
	(segment
		(start 312.793634 -346.326714)
		(end 312.793634 -345.755976)
		(width 0.1651)
		(layer "In13.Cu")
		(net "P5E_PEX2_STN6_TX_C_DP<111>")
	)
	(segment
		(start 331.617066 -408.699208)
		(end 332.047342 -408.699208)
		(width 0.1651)
		(layer "In13.Cu")
		(net "P5E_PEX2_STN6_TX_C_DP<111>")
	)
	(segment
		(start 314.348114 -352.406966)
		(end 314.348114 -347.881194)
		(width 0.1651)
		(layer "In13.Cu")
		(net "P5E_PEX2_STN6_TX_C_DP<111>")
	)
	(segment
		(start 315.247782 -364.423198)
		(end 315.081666 -363.956854)
		(width 0.1651)
		(layer "In13.Cu")
		(net "P5E_PEX2_STN6_TX_C_DP<111>")
	)
	(segment
		(start 331.490066 -408.190192)
		(end 331.490066 -408.572208)
		(width 0.1651)
		(layer "In13.Cu")
		(net "P5E_PEX2_STN6_TX_C_DP<111>")
	)
	(segment
		(start 331.490066 -408.572208)
		(end 331.617066 -408.699208)
		(width 0.1651)
		(layer "In13.Cu")
		(net "P5E_PEX2_STN6_TX_C_DP<111>")
	)
	(segment
		(start 324.146418 -389.392922)
		(end 316.258702 -367.259108)
		(width 0.1651)
		(layer "In13.Cu")
		(net "P5E_PEX2_STN6_TX_C_DP<111>")
	)
	(segment
		(start 315.360304 -365.003588)
		(end 315.193934 -364.53699)
		(width 0.1651)
		(layer "In13.Cu")
		(net "P5E_PEX2_STN6_TX_C_DP<111>")
	)
	(segment
		(start 316.258702 -367.259108)
		(end 316.258956 -367.259108)
		(width 0.1651)
		(layer "In13.Cu")
		(net "P5E_PEX2_STN6_TX_C_DP<111>")
	)
	(segment
		(start 315.640212 -365.524034)
		(end 315.474096 -365.05769)
		(width 0.1651)
		(layer "In13.Cu")
		(net "P5E_PEX2_STN6_TX_C_DP<111>")
	)
	(segment
		(start 314.967874 -363.902752)
		(end 314.801504 -363.436154)
		(width 0.1651)
		(layer "In13.Cu")
		(net "P5E_PEX2_STN6_TX_C_DP<111>")
	)
	(segment
		(start 315.752734 -366.104424)
		(end 315.586364 -365.637826)
		(width 0.1651)
		(layer "In13.Cu")
		(net "P5E_PEX2_STN6_TX_C_DP<111>")
	)
	(segment
		(start 331.641958 -394.285724)
		(end 328.436732 -392.9253)
		(width 0.1651)
		(layer "In13.Cu")
		(net "P5E_PEX2_STN6_TX_C_DP<111>")
	)
	(segment
		(start 316.032642 -366.62487)
		(end 315.866526 -366.158526)
		(width 0.1651)
		(layer "In13.Cu")
		(net "P5E_PEX2_STN6_TX_C_DP<111>")
	)
	(segment
		(start 314.855606 -363.322362)
		(end 313.0169 -358.162098)
		(width 0.1651)
		(layer "In13.Cu")
		(net "P5E_PEX2_STN6_TX_C_DP<111>")
	)
	(segment
		(start 313.0169 -358.162098)
		(end 313.0169 -353.73818)
		(width 0.1651)
		(layer "In13.Cu")
		(net "P5E_PEX2_STN6_TX_C_DP<111>")
	)
	(segment
		(start 312.793634 -345.755976)
		(end 312.502804 -345.465146)
		(width 0.1651)
		(layer "In13.Cu")
		(net "P5E_PEX2_STN6_TX_C_DP<111>")
	)
	(segment
		(start 315.866526 -366.158526)
		(end 315.752734 -366.104424)
		(width 0.1651)
		(layer "In13.Cu")
		(net "P5E_PEX2_STN6_TX_C_DP<111>")
	)
	(segment
		(start 316.258956 -367.259108)
		(end 316.14491 -367.20526)
		(width 0.1651)
		(layer "In13.Cu")
		(net "P5E_PEX2_STN6_TX_C_DP<111>")
	)
	(segment
		(start 332.334108 -394.97762)
		(end 331.641958 -394.285724)
		(width 0.1651)
		(layer "In13.Cu")
		(net "P5E_PEX2_STN6_TX_C_DP<111>")
	)
	(segment
		(start 314.801504 -363.436154)
		(end 314.855606 -363.322362)
		(width 0.1651)
		(layer "In13.Cu")
		(net "P5E_PEX2_STN6_TX_C_DP<111>")
	)
	(segment
		(start 328.436732 -392.9253)
		(end 328.436478 -392.9253)
		(width 0.1651)
		(layer "In13.Cu")
		(net "P5E_PEX2_STN6_TX_C_DP<111>")
	)
	(segment
		(start 315.193934 -364.53699)
		(end 315.247782 -364.423198)
		(width 0.1651)
		(layer "In13.Cu")
		(net "P5E_PEX2_STN6_TX_C_DP<111>")
	)
	(segment
		(start 315.081666 -363.956854)
		(end 314.967874 -363.902752)
		(width 0.1651)
		(layer "In13.Cu")
		(net "P5E_PEX2_STN6_TX_C_DP<111>")
	)
	(segment
		(start 315.474096 -365.05769)
		(end 315.360304 -365.003588)
		(width 0.1651)
		(layer "In13.Cu")
		(net "P5E_PEX2_STN6_TX_C_DP<111>")
	)
	(segment
		(start 393.835636 -107.244896)
		(end 394.342366 -107.244896)
		(width 0.13462)
		(layer "F.Cu")
		(net "P5E_PEX3_STN1_TX_C_DN<20>")
	)
	(segment
		(start 388.16407 -107.0864)
		(end 393.67714 -107.0864)
		(width 0.13462)
		(layer "F.Cu")
		(net "P5E_PEX3_STN1_TX_C_DN<20>")
	)
	(segment
		(start 393.67714 -107.0864)
		(end 393.835636 -107.244896)
		(width 0.13462)
		(layer "F.Cu")
		(net "P5E_PEX3_STN1_TX_C_DN<20>")
	)
	(segment
		(start 387.847332 -107.403138)
		(end 388.16407 -107.0864)
		(width 0.13462)
		(layer "F.Cu")
		(net "P5E_PEX3_STN1_TX_C_DN<20>")
	)
	(segment
		(start 402.249894 -318.015366)
		(end 402.135594 -318.129666)
		(width 0.1143)
		(layer "In5.Cu")
		(net "P5E_PEX3_STN6_RX_DP<100>")
	)
	(segment
		(start 373.619776 -341.116412)
		(end 373.03329 -341.834724)
		(width 0.1651)
		(layer "In5.Cu")
		(net "P5E_PEX3_STN6_RX_DP<100>")
	)
	(segment
		(start 379.87097 -365.665766)
		(end 379.87097 -365.82731)
		(width 0.1651)
		(layer "In5.Cu")
		(net "P5E_PEX3_STN6_RX_DP<100>")
	)
	(segment
		(start 401.90547 -318.129666)
		(end 401.679664 -318.355472)
		(width 0.1143)
		(layer "In5.Cu")
		(net "P5E_PEX3_STN6_RX_DP<100>")
	)
	(segment
		(start 382.96596 -368.756184)
		(end 382.96596 -375.670572)
		(width 0.1651)
		(layer "In5.Cu")
		(net "P5E_PEX3_STN6_RX_DP<100>")
	)
	(segment
		(start 402.135594 -318.129666)
		(end 401.90547 -318.129666)
		(width 0.1143)
		(layer "In5.Cu")
		(net "P5E_PEX3_STN6_RX_DP<100>")
	)
	(segment
		(start 382.96596 -375.670572)
		(end 382.633474 -376.003058)
		(width 0.1651)
		(layer "In5.Cu")
		(net "P5E_PEX3_STN6_RX_DP<100>")
	)
	(segment
		(start 399.878296 -322.782946)
		(end 373.619776 -341.116412)
		(width 0.1651)
		(layer "In5.Cu")
		(net "P5E_PEX3_STN6_RX_DP<100>")
	)
	(segment
		(start 401.633944 -319.934082)
		(end 401.633944 -319.96253)
		(width 0.1143)
		(layer "In5.Cu")
		(net "P5E_PEX3_STN6_RX_DP<100>")
	)
	(segment
		(start 401.633944 -319.96253)
		(end 401.633944 -320.599308)
		(width 0.1651)
		(layer "In5.Cu")
		(net "P5E_PEX3_STN6_RX_DP<100>")
	)
	(segment
		(start 379.87097 -365.82731)
		(end 380.221744 -366.177576)
		(width 0.1651)
		(layer "In5.Cu")
		(net "P5E_PEX3_STN6_RX_DP<100>")
	)
	(segment
		(start 373.524272 -359.32872)
		(end 379.87097 -365.665766)
		(width 0.1651)
		(layer "In5.Cu")
		(net "P5E_PEX3_STN6_RX_DP<100>")
	)
	(segment
		(start 380.221744 -366.177576)
		(end 380.383288 -366.177576)
		(width 0.1651)
		(layer "In5.Cu")
		(net "P5E_PEX3_STN6_RX_DP<100>")
	)
	(segment
		(start 402.249894 -317.749936)
		(end 402.249894 -318.015366)
		(width 0.1143)
		(layer "In5.Cu")
		(net "P5E_PEX3_STN6_RX_DP<100>")
	)
	(segment
		(start 401.679664 -318.355472)
		(end 401.679664 -319.888362)
		(width 0.1143)
		(layer "In5.Cu")
		(net "P5E_PEX3_STN6_RX_DP<100>")
	)
	(segment
		(start 380.383288 -366.177576)
		(end 382.96596 -368.756184)
		(width 0.1651)
		(layer "In5.Cu")
		(net "P5E_PEX3_STN6_RX_DP<100>")
	)
	(segment
		(start 373.03329 -358.144064)
		(end 373.524272 -359.32872)
		(width 0.1651)
		(layer "In5.Cu")
		(net "P5E_PEX3_STN6_RX_DP<100>")
	)
	(segment
		(start 373.03329 -341.834724)
		(end 373.03329 -358.144064)
		(width 0.1651)
		(layer "In5.Cu")
		(net "P5E_PEX3_STN6_RX_DP<100>")
	)
	(segment
		(start 401.679664 -319.888362)
		(end 401.633944 -319.934082)
		(width 0.1143)
		(layer "In5.Cu")
		(net "P5E_PEX3_STN6_RX_DP<100>")
	)
	(segment
		(start 401.633944 -320.599308)
		(end 399.878296 -322.782946)
		(width 0.1651)
		(layer "In5.Cu")
		(net "P5E_PEX3_STN6_RX_DP<100>")
	)
	(segment
		(start 382.089914 -375.82983)
		(end 382.089914 -375.490232)
		(width 0.1651)
		(layer "In5.Cu")
		(net "P5E_PEX3_STN6_RX_DP<100>")
	)
	(segment
		(start 382.633474 -376.003058)
		(end 382.263142 -376.003058)
		(width 0.1651)
		(layer "In5.Cu")
		(net "P5E_PEX3_STN6_RX_DP<100>")
	)
	(segment
		(start 382.263142 -376.003058)
		(end 382.089914 -375.82983)
		(width 0.1651)
		(layer "In5.Cu")
		(net "P5E_PEX3_STN6_RX_DP<100>")
	)
	(segment
		(start 183.744616 -96.813878)
		(end 183.970676 -97.039938)
		(width 0.13208)
		(layer "F.Cu")
		(net "RST_NIC3_PERST2_R_N")
	)
	(segment
		(start 183.305704 -96.432878)
		(end 183.744616 -96.432878)
		(width 0.13208)
		(layer "F.Cu")
		(net "RST_NIC3_PERST2_R_N")
	)
	(segment
		(start 183.970676 -97.039938)
		(end 184.757314 -97.039938)
		(width 0.13208)
		(layer "F.Cu")
		(net "RST_NIC3_PERST2_R_N")
	)
	(segment
		(start 183.03621 -96.702372)
		(end 183.305704 -96.432878)
		(width 0.13208)
		(layer "F.Cu")
		(net "RST_NIC3_PERST2_R_N")
	)
	(segment
		(start 183.744616 -96.432878)
		(end 183.744616 -96.813878)
		(width 0.13208)
		(layer "F.Cu")
		(net "RST_NIC3_PERST2_R_N")
	)
	(segment
		(start 175.49495 -96.702372)
		(end 183.03621 -96.702372)
		(width 0.13208)
		(layer "F.Cu")
		(net "RST_NIC3_PERST2_R_N")
	)
	(via
		(at 183.744616 -96.432878)
		(size 0.508)
		(drill 0.254)
		(layers "F.Cu" "B.Cu")
		(net "RST_NIC3_PERST2_R_N")
	)
	(segment
		(start 183.86806 -28.390088)
		(end 183.364886 -28.390088)
		(width 0.13462)
		(layer "F.Cu")
		(net "P5E_PEX1_STN2_TX_C_DN<36>")
	)
	(segment
		(start 184.032652 -28.55468)
		(end 183.86806 -28.390088)
		(width 0.13462)
		(layer "F.Cu")
		(net "P5E_PEX1_STN2_TX_C_DN<36>")
	)
	(segment
		(start 185.62574 -28.225242)
		(end 185.296302 -28.55468)
		(width 0.13462)
		(layer "F.Cu")
		(net "P5E_PEX1_STN2_TX_C_DN<36>")
	)
	(segment
		(start 185.296302 -28.55468)
		(end 184.032652 -28.55468)
		(width 0.13462)
		(layer "F.Cu")
		(net "P5E_PEX1_STN2_TX_C_DN<36>")
	)
	(segment
		(start 299.545756 -146.51228)
		(end 300.219364 -146.51228)
		(width 0.13462)
		(layer "F.Cu")
		(net "P5E_PEX2_STN0_RX_DN<10>")
	)
	(segment
		(start 300.219364 -146.51228)
		(end 300.37659 -146.355054)
		(width 0.13462)
		(layer "F.Cu")
		(net "P5E_PEX2_STN0_RX_DN<10>")
	)
	(segment
		(start 300.37659 -146.355054)
		(end 300.857412 -146.355054)
		(width 0.13462)
		(layer "F.Cu")
		(net "P5E_PEX2_STN0_RX_DN<10>")
	)
	(segment
		(start 299.257212 -146.223736)
		(end 299.545756 -146.51228)
		(width 0.13462)
		(layer "F.Cu")
		(net "P5E_PEX2_STN0_RX_DN<10>")
	)
	(segment
		(start 311.465722 -271.041114)
		(end 311.465722 -271.570958)
		(width 0.1651)
		(layer "In5.Cu")
		(net "P5E_PEX2_STN0_RX_DN<10>")
	)
	(segment
		(start 307.029866 -155.949396)
		(end 307.363876 -156.471112)
		(width 0.1651)
		(layer "In5.Cu")
		(net "P5E_PEX2_STN0_RX_DN<10>")
	)
	(segment
		(start 311.799478 -275.265388)
		(end 311.799478 -274.999958)
		(width 0.1143)
		(layer "In5.Cu")
		(net "P5E_PEX2_STN0_RX_DN<10>")
	)
	(segment
		(start 311.465722 -271.570958)
		(end 311.465722 -271.599406)
		(width 0.1143)
		(layer "In5.Cu")
		(net "P5E_PEX2_STN0_RX_DN<10>")
	)
	(segment
		(start 311.99201 -260.494272)
		(end 312.02757 -268.182852)
		(width 0.1651)
		(layer "In5.Cu")
		(net "P5E_PEX2_STN0_RX_DN<10>")
	)
	(segment
		(start 299.257212 -146.223736)
		(end 299.548042 -146.514566)
		(width 0.1651)
		(layer "In5.Cu")
		(net "P5E_PEX2_STN0_RX_DN<10>")
	)
	(segment
		(start 311.420002 -275.27631)
		(end 311.52338 -275.379688)
		(width 0.1143)
		(layer "In5.Cu")
		(net "P5E_PEX2_STN0_RX_DN<10>")
	)
	(segment
		(start 300.145704 -146.514566)
		(end 301.818548 -148.18741)
		(width 0.1651)
		(layer "In5.Cu")
		(net "P5E_PEX2_STN0_RX_DN<10>")
	)
	(segment
		(start 311.52338 -275.379688)
		(end 311.685178 -275.379688)
		(width 0.1143)
		(layer "In5.Cu")
		(net "P5E_PEX2_STN0_RX_DN<10>")
	)
	(segment
		(start 311.465722 -271.599406)
		(end 311.420002 -271.645126)
		(width 0.1143)
		(layer "In5.Cu")
		(net "P5E_PEX2_STN0_RX_DN<10>")
	)
	(segment
		(start 306.072286 -155.166822)
		(end 307.029866 -155.949396)
		(width 0.1651)
		(layer "In5.Cu")
		(net "P5E_PEX2_STN0_RX_DN<10>")
	)
	(segment
		(start 311.420002 -271.645126)
		(end 311.420002 -275.27631)
		(width 0.1143)
		(layer "In5.Cu")
		(net "P5E_PEX2_STN0_RX_DN<10>")
	)
	(segment
		(start 304.38725 -152.90165)
		(end 306.072286 -155.166822)
		(width 0.1651)
		(layer "In5.Cu")
		(net "P5E_PEX2_STN0_RX_DN<10>")
	)
	(segment
		(start 312.02757 -268.182852)
		(end 311.465722 -271.041114)
		(width 0.1651)
		(layer "In5.Cu")
		(net "P5E_PEX2_STN0_RX_DN<10>")
	)
	(segment
		(start 301.818548 -148.18741)
		(end 303.462182 -150.631906)
		(width 0.1651)
		(layer "In5.Cu")
		(net "P5E_PEX2_STN0_RX_DN<10>")
	)
	(segment
		(start 299.548042 -146.514566)
		(end 300.145704 -146.514566)
		(width 0.1651)
		(layer "In5.Cu")
		(net "P5E_PEX2_STN0_RX_DN<10>")
	)
	(segment
		(start 303.462182 -150.631906)
		(end 304.38725 -152.90165)
		(width 0.1651)
		(layer "In5.Cu")
		(net "P5E_PEX2_STN0_RX_DN<10>")
	)
	(segment
		(start 308.478174 -161.011616)
		(end 311.99201 -260.494272)
		(width 0.1651)
		(layer "In5.Cu")
		(net "P5E_PEX2_STN0_RX_DN<10>")
	)
	(segment
		(start 307.363876 -156.471112)
		(end 308.478174 -161.011616)
		(width 0.1651)
		(layer "In5.Cu")
		(net "P5E_PEX2_STN0_RX_DN<10>")
	)
	(segment
		(start 311.685178 -275.379688)
		(end 311.799478 -275.265388)
		(width 0.1143)
		(layer "In5.Cu")
		(net "P5E_PEX2_STN0_RX_DN<10>")
	)
	(segment
		(start 294.568626 -326.33412)
		(end 295.019476 -326.540114)
		(width 0.1651)
		(layer "In5.Cu")
		(net "P5E_PEX2_STN6_RX_DN<104>")
	)
	(segment
		(start 342.903302 -391.248646)
		(end 342.9127 -391.248646)
		(width 0.1651)
		(layer "In5.Cu")
		(net "P5E_PEX2_STN6_RX_DN<104>")
	)
	(segment
		(start 295.019476 -326.540114)
		(end 295.057068 -326.640952)
		(width 0.1651)
		(layer "In5.Cu")
		(net "P5E_PEX2_STN6_RX_DN<104>")
	)
	(segment
		(start 347.017086 -402.281136)
		(end 346.890086 -402.408136)
		(width 0.1651)
		(layer "In5.Cu")
		(net "P5E_PEX2_STN6_RX_DN<104>")
	)
	(segment
		(start 295.057068 -326.640952)
		(end 326.07123 -340.802976)
		(width 0.1651)
		(layer "In5.Cu")
		(net "P5E_PEX2_STN6_RX_DN<104>")
	)
	(segment
		(start 347.75902 -395.02842)
		(end 348.016068 -395.620494)
		(width 0.1651)
		(layer "In5.Cu")
		(net "P5E_PEX2_STN6_RX_DN<104>")
	)
	(segment
		(start 282.770072 -321.030346)
		(end 294.467788 -326.371712)
		(width 0.1651)
		(layer "In5.Cu")
		(net "P5E_PEX2_STN6_RX_DN<104>")
	)
	(segment
		(start 330.186792 -384.272282)
		(end 330.864464 -385.750816)
		(width 0.1651)
		(layer "In5.Cu")
		(net "P5E_PEX2_STN6_RX_DN<104>")
	)
	(segment
		(start 326.07123 -340.802976)
		(end 327.065894 -341.79764)
		(width 0.1651)
		(layer "In5.Cu")
		(net "P5E_PEX2_STN6_RX_DN<104>")
	)
	(segment
		(start 294.467788 -326.371712)
		(end 294.568626 -326.33412)
		(width 0.1651)
		(layer "In5.Cu")
		(net "P5E_PEX2_STN6_RX_DN<104>")
	)
	(segment
		(start 347.564202 -402.281136)
		(end 347.017086 -402.281136)
		(width 0.1651)
		(layer "In5.Cu")
		(net "P5E_PEX2_STN6_RX_DN<104>")
	)
	(segment
		(start 282.015692 -319.8876)
		(end 282.015692 -319.916048)
		(width 0.1143)
		(layer "In5.Cu")
		(net "P5E_PEX2_STN6_RX_DN<104>")
	)
	(segment
		(start 282.015692 -319.916048)
		(end 282.015692 -320.275966)
		(width 0.1651)
		(layer "In5.Cu")
		(net "P5E_PEX2_STN6_RX_DN<104>")
	)
	(segment
		(start 346.25534 -393.48664)
		(end 347.75902 -395.02842)
		(width 0.1651)
		(layer "In5.Cu")
		(net "P5E_PEX2_STN6_RX_DN<104>")
	)
	(segment
		(start 336.757518 -388.288276)
		(end 342.903302 -391.248646)
		(width 0.1651)
		(layer "In5.Cu")
		(net "P5E_PEX2_STN6_RX_DN<104>")
	)
	(segment
		(start 282.235402 -318.320166)
		(end 282.084272 -318.320166)
		(width 0.1143)
		(layer "In5.Cu")
		(net "P5E_PEX2_STN6_RX_DN<104>")
	)
	(segment
		(start 348.016068 -395.620494)
		(end 348.016068 -401.82927)
		(width 0.1651)
		(layer "In5.Cu")
		(net "P5E_PEX2_STN6_RX_DN<104>")
	)
	(segment
		(start 281.969972 -319.84188)
		(end 282.015692 -319.8876)
		(width 0.1143)
		(layer "In5.Cu")
		(net "P5E_PEX2_STN6_RX_DN<104>")
	)
	(segment
		(start 282.084272 -318.320166)
		(end 281.969972 -318.434466)
		(width 0.1143)
		(layer "In5.Cu")
		(net "P5E_PEX2_STN6_RX_DN<104>")
	)
	(segment
		(start 327.065894 -341.79764)
		(end 327.065894 -359.149142)
		(width 0.1651)
		(layer "In5.Cu")
		(net "P5E_PEX2_STN6_RX_DN<104>")
	)
	(segment
		(start 342.9127 -391.248646)
		(end 342.921082 -391.257028)
		(width 0.1651)
		(layer "In5.Cu")
		(net "P5E_PEX2_STN6_RX_DN<104>")
	)
	(segment
		(start 331.112114 -386.00761)
		(end 336.757518 -388.288276)
		(width 0.1651)
		(layer "In5.Cu")
		(net "P5E_PEX2_STN6_RX_DN<104>")
	)
	(segment
		(start 282.015692 -320.275966)
		(end 282.770072 -321.030346)
		(width 0.1651)
		(layer "In5.Cu")
		(net "P5E_PEX2_STN6_RX_DN<104>")
	)
	(segment
		(start 348.016068 -401.82927)
		(end 347.564202 -402.281136)
		(width 0.1651)
		(layer "In5.Cu")
		(net "P5E_PEX2_STN6_RX_DN<104>")
	)
	(segment
		(start 281.969972 -318.434466)
		(end 281.969972 -319.84188)
		(width 0.1143)
		(layer "In5.Cu")
		(net "P5E_PEX2_STN6_RX_DN<104>")
	)
	(segment
		(start 282.349702 -318.434466)
		(end 282.235402 -318.320166)
		(width 0.1143)
		(layer "In5.Cu")
		(net "P5E_PEX2_STN6_RX_DN<104>")
	)
	(segment
		(start 327.065894 -359.149142)
		(end 330.186792 -384.272282)
		(width 0.1651)
		(layer "In5.Cu")
		(net "P5E_PEX2_STN6_RX_DN<104>")
	)
	(segment
		(start 342.921336 -391.257028)
		(end 346.25534 -393.48664)
		(width 0.1651)
		(layer "In5.Cu")
		(net "P5E_PEX2_STN6_RX_DN<104>")
	)
	(segment
		(start 346.890086 -402.408136)
		(end 346.890086 -402.790152)
		(width 0.1651)
		(layer "In5.Cu")
		(net "P5E_PEX2_STN6_RX_DN<104>")
	)
	(segment
		(start 342.921082 -391.257028)
		(end 342.921336 -391.257028)
		(width 0.1651)
		(layer "In5.Cu")
		(net "P5E_PEX2_STN6_RX_DN<104>")
	)
	(segment
		(start 282.349702 -318.699896)
		(end 282.349702 -318.434466)
		(width 0.1143)
		(layer "In5.Cu")
		(net "P5E_PEX2_STN6_RX_DN<104>")
	)
	(segment
		(start 330.864464 -385.750816)
		(end 331.112114 -386.00761)
		(width 0.1651)
		(layer "In5.Cu")
		(net "P5E_PEX2_STN6_RX_DN<104>")
	)
	(segment
		(start 388.185914 -132.7912)
		(end 393.66571 -132.7912)
		(width 0.13462)
		(layer "F.Cu")
		(net "P5E_PEX3_STN1_TX_C_DP<29>")
	)
	(segment
		(start 387.847332 -133.129782)
		(end 388.185914 -132.7912)
		(width 0.13462)
		(layer "F.Cu")
		(net "P5E_PEX3_STN1_TX_C_DP<29>")
	)
	(segment
		(start 393.839446 -132.964936)
		(end 394.342366 -132.964936)
		(width 0.13462)
		(layer "F.Cu")
		(net "P5E_PEX3_STN1_TX_C_DP<29>")
	)
	(segment
		(start 393.66571 -132.7912)
		(end 393.839446 -132.964936)
		(width 0.13462)
		(layer "F.Cu")
		(net "P5E_PEX3_STN1_TX_C_DP<29>")
	)
	(segment
		(start 378.815854 -396.494)
		(end 378.815854 -401.82927)
		(width 0.1651)
		(layer "In15.Cu")
		(net "P5E_PEX3_STN6_RX_DN<110>")
	)
	(segment
		(start 392.370056 -319.921128)
		(end 392.415776 -319.966848)
		(width 0.1143)
		(layer "In15.Cu")
		(net "P5E_PEX3_STN6_RX_DN<110>")
	)
	(segment
		(start 378.525278 -395.5034)
		(end 378.815854 -396.494)
		(width 0.1651)
		(layer "In15.Cu")
		(net "P5E_PEX3_STN6_RX_DN<110>")
	)
	(segment
		(start 367.91265 -372.166896)
		(end 368.511582 -385.8133)
		(width 0.1651)
		(layer "In15.Cu")
		(net "P5E_PEX3_STN6_RX_DN<110>")
	)
	(segment
		(start 392.749786 -318.699896)
		(end 392.749786 -318.434466)
		(width 0.1143)
		(layer "In15.Cu")
		(net "P5E_PEX3_STN6_RX_DN<110>")
	)
	(segment
		(start 377.816872 -402.281136)
		(end 377.689872 -402.408136)
		(width 0.1651)
		(layer "In15.Cu")
		(net "P5E_PEX3_STN6_RX_DN<110>")
	)
	(segment
		(start 392.415776 -320.740024)
		(end 390.374124 -322.781676)
		(width 0.1651)
		(layer "In15.Cu")
		(net "P5E_PEX3_STN6_RX_DN<110>")
	)
	(segment
		(start 392.415776 -319.995296)
		(end 392.415776 -320.740024)
		(width 0.1651)
		(layer "In15.Cu")
		(net "P5E_PEX3_STN6_RX_DN<110>")
	)
	(segment
		(start 368.511582 -385.8133)
		(end 369.856512 -389.064754)
		(width 0.1651)
		(layer "In15.Cu")
		(net "P5E_PEX3_STN6_RX_DN<110>")
	)
	(segment
		(start 368.24158 -341.946484)
		(end 367.91265 -372.166896)
		(width 0.1651)
		(layer "In15.Cu")
		(net "P5E_PEX3_STN6_RX_DN<110>")
	)
	(segment
		(start 378.815854 -401.82927)
		(end 378.363988 -402.281136)
		(width 0.1651)
		(layer "In15.Cu")
		(net "P5E_PEX3_STN6_RX_DN<110>")
	)
	(segment
		(start 369.856512 -389.064754)
		(end 373.168418 -391.555986)
		(width 0.1651)
		(layer "In15.Cu")
		(net "P5E_PEX3_STN6_RX_DN<110>")
	)
	(segment
		(start 378.363988 -402.281136)
		(end 377.816872 -402.281136)
		(width 0.1651)
		(layer "In15.Cu")
		(net "P5E_PEX3_STN6_RX_DN<110>")
	)
	(segment
		(start 368.28222 -341.711026)
		(end 368.24158 -341.946484)
		(width 0.1651)
		(layer "In15.Cu")
		(net "P5E_PEX3_STN6_RX_DN<110>")
	)
	(segment
		(start 392.635486 -318.320166)
		(end 392.473688 -318.320166)
		(width 0.1143)
		(layer "In15.Cu")
		(net "P5E_PEX3_STN6_RX_DN<110>")
	)
	(segment
		(start 375.680732 -392.684)
		(end 377.356878 -394.0048)
		(width 0.1651)
		(layer "In15.Cu")
		(net "P5E_PEX3_STN6_RX_DN<110>")
	)
	(segment
		(start 392.749786 -318.434466)
		(end 392.635486 -318.320166)
		(width 0.1143)
		(layer "In15.Cu")
		(net "P5E_PEX3_STN6_RX_DN<110>")
	)
	(segment
		(start 392.415776 -319.966848)
		(end 392.415776 -319.995296)
		(width 0.1143)
		(layer "In15.Cu")
		(net "P5E_PEX3_STN6_RX_DN<110>")
	)
	(segment
		(start 377.356878 -394.0048)
		(end 378.525278 -395.5034)
		(width 0.1651)
		(layer "In15.Cu")
		(net "P5E_PEX3_STN6_RX_DN<110>")
	)
	(segment
		(start 373.168418 -391.555986)
		(end 375.680732 -392.684)
		(width 0.1651)
		(layer "In15.Cu")
		(net "P5E_PEX3_STN6_RX_DN<110>")
	)
	(segment
		(start 392.370056 -318.423798)
		(end 392.370056 -319.921128)
		(width 0.1143)
		(layer "In15.Cu")
		(net "P5E_PEX3_STN6_RX_DN<110>")
	)
	(segment
		(start 377.689872 -402.408136)
		(end 377.689872 -402.790152)
		(width 0.1651)
		(layer "In15.Cu")
		(net "P5E_PEX3_STN6_RX_DN<110>")
	)
	(segment
		(start 392.473688 -318.320166)
		(end 392.370056 -318.423798)
		(width 0.1143)
		(layer "In15.Cu")
		(net "P5E_PEX3_STN6_RX_DN<110>")
	)
	(segment
		(start 390.374124 -322.781676)
		(end 369.405154 -339.793326)
		(width 0.1651)
		(layer "In15.Cu")
		(net "P5E_PEX3_STN6_RX_DN<110>")
	)
	(segment
		(start 369.405154 -339.793326)
		(end 368.28222 -341.711026)
		(width 0.1651)
		(layer "In15.Cu")
		(net "P5E_PEX3_STN6_RX_DN<110>")
	)
	(segment
		(start 182.079138 -115.283742)
		(end 182.781448 -114.581432)
		(width 0.13208)
		(layer "F.Cu")
		(net "RST_SMB_NIC3_MUX_ISO_R_N")
	)
	(segment
		(start 182.781448 -114.581432)
		(end 183.327802 -114.035078)
		(width 0.13208)
		(layer "F.Cu")
		(net "RST_SMB_NIC3_MUX_ISO_R_N")
	)
	(segment
		(start 183.327802 -114.035078)
		(end 184.757314 -114.035078)
		(width 0.13208)
		(layer "F.Cu")
		(net "RST_SMB_NIC3_MUX_ISO_R_N")
	)
	(segment
		(start 180.177694 -115.283742)
		(end 182.079138 -115.283742)
		(width 0.13208)
		(layer "F.Cu")
		(net "RST_SMB_NIC3_MUX_ISO_R_N")
	)
	(via
		(at 182.781448 -114.581432)
		(size 0.508)
		(drill 0.254)
		(layers "F.Cu" "B.Cu")
		(net "RST_SMB_NIC3_MUX_ISO_R_N")
	)
	(segment
		(start 185.62574 -32.739584)
		(end 185.296556 -32.4104)
		(width 0.13462)
		(layer "F.Cu")
		(net "P5E_PEX1_STN2_TX_C_DP<38>")
	)
	(segment
		(start 184.044082 -32.4104)
		(end 183.864504 -32.589978)
		(width 0.13462)
		(layer "F.Cu")
		(net "P5E_PEX1_STN2_TX_C_DP<38>")
	)
	(segment
		(start 183.864504 -32.589978)
		(end 183.364886 -32.589978)
		(width 0.13462)
		(layer "F.Cu")
		(net "P5E_PEX1_STN2_TX_C_DP<38>")
	)
	(segment
		(start 185.296556 -32.4104)
		(end 184.044082 -32.4104)
		(width 0.13462)
		(layer "F.Cu")
		(net "P5E_PEX1_STN2_TX_C_DP<38>")
	)
	(segment
		(start 305.95697 -146.955002)
		(end 305.457606 -146.955002)
		(width 0.13462)
		(layer "F.Cu")
		(net "P5E_PEX2_STN0_TX_C_DP<10>")
	)
	(segment
		(start 306.125372 -146.7866)
		(end 305.95697 -146.955002)
		(width 0.13462)
		(layer "F.Cu")
		(net "P5E_PEX2_STN0_TX_C_DP<10>")
	)
	(segment
		(start 311.634632 -146.7866)
		(end 306.125372 -146.7866)
		(width 0.13462)
		(layer "F.Cu")
		(net "P5E_PEX2_STN0_TX_C_DP<10>")
	)
	(segment
		(start 311.95264 -147.104608)
		(end 311.634632 -146.7866)
		(width 0.13462)
		(layer "F.Cu")
		(net "P5E_PEX2_STN0_TX_C_DP<10>")
	)
	(segment
		(start 342.617044 -402.281136)
		(end 342.490044 -402.408136)
		(width 0.1651)
		(layer "In5.Cu")
		(net "P5E_PEX2_STN6_RX_DN<106>")
	)
	(segment
		(start 336.077814 -390.136888)
		(end 339.36178 -391.84834)
		(width 0.1651)
		(layer "In5.Cu")
		(net "P5E_PEX2_STN6_RX_DN<106>")
	)
	(segment
		(start 339.36178 -391.84834)
		(end 342.95334 -394.27912)
		(width 0.1651)
		(layer "In5.Cu")
		(net "P5E_PEX2_STN6_RX_DN<106>")
	)
	(segment
		(start 343.616026 -401.82927)
		(end 343.16416 -402.281136)
		(width 0.1651)
		(layer "In5.Cu")
		(net "P5E_PEX2_STN6_RX_DN<106>")
	)
	(segment
		(start 342.490044 -402.408136)
		(end 342.490044 -402.790152)
		(width 0.1651)
		(layer "In5.Cu")
		(net "P5E_PEX2_STN6_RX_DN<106>")
	)
	(segment
		(start 328.813922 -386.04825)
		(end 329.085702 -386.628386)
		(width 0.1651)
		(layer "In5.Cu")
		(net "P5E_PEX2_STN6_RX_DN<106>")
	)
	(segment
		(start 280.115772 -319.966848)
		(end 280.115772 -321.286378)
		(width 0.1651)
		(layer "In5.Cu")
		(net "P5E_PEX2_STN6_RX_DN<106>")
	)
	(segment
		(start 328.22261 -384.565398)
		(end 328.813922 -386.04825)
		(width 0.1651)
		(layer "In5.Cu")
		(net "P5E_PEX2_STN6_RX_DN<106>")
	)
	(segment
		(start 280.184352 -318.320166)
		(end 280.070052 -318.434466)
		(width 0.1143)
		(layer "In5.Cu")
		(net "P5E_PEX2_STN6_RX_DN<106>")
	)
	(segment
		(start 342.95334 -394.27912)
		(end 343.616026 -395.675104)
		(width 0.1651)
		(layer "In5.Cu")
		(net "P5E_PEX2_STN6_RX_DN<106>")
	)
	(segment
		(start 324.376542 -372.971822)
		(end 324.376542 -372.971568)
		(width 0.1651)
		(layer "In5.Cu")
		(net "P5E_PEX2_STN6_RX_DN<106>")
	)
	(segment
		(start 329.993498 -387.637528)
		(end 336.077814 -390.136888)
		(width 0.1651)
		(layer "In5.Cu")
		(net "P5E_PEX2_STN6_RX_DN<106>")
	)
	(segment
		(start 320.847974 -358.47147)
		(end 324.376542 -372.971822)
		(width 0.1651)
		(layer "In5.Cu")
		(net "P5E_PEX2_STN6_RX_DN<106>")
	)
	(segment
		(start 280.070052 -318.434466)
		(end 280.070052 -319.89268)
		(width 0.1143)
		(layer "In5.Cu")
		(net "P5E_PEX2_STN6_RX_DN<106>")
	)
	(segment
		(start 293.001446 -328.05497)
		(end 319.552828 -340.46033)
		(width 0.1651)
		(layer "In5.Cu")
		(net "P5E_PEX2_STN6_RX_DN<106>")
	)
	(segment
		(start 280.070052 -319.89268)
		(end 280.115772 -319.9384)
		(width 0.1143)
		(layer "In5.Cu")
		(net "P5E_PEX2_STN6_RX_DN<106>")
	)
	(segment
		(start 292.964616 -327.953624)
		(end 293.001446 -328.05497)
		(width 0.1651)
		(layer "In5.Cu")
		(net "P5E_PEX2_STN6_RX_DN<106>")
	)
	(segment
		(start 280.115772 -321.286378)
		(end 280.437082 -322.062348)
		(width 0.1651)
		(layer "In5.Cu")
		(net "P5E_PEX2_STN6_RX_DN<106>")
	)
	(segment
		(start 292.414452 -327.780396)
		(end 292.515544 -327.74382)
		(width 0.1651)
		(layer "In5.Cu")
		(net "P5E_PEX2_STN6_RX_DN<106>")
	)
	(segment
		(start 329.349354 -387.001766)
		(end 329.993498 -387.637528)
		(width 0.1651)
		(layer "In5.Cu")
		(net "P5E_PEX2_STN6_RX_DN<106>")
	)
	(segment
		(start 280.115772 -319.9384)
		(end 280.115772 -319.966848)
		(width 0.1143)
		(layer "In5.Cu")
		(net "P5E_PEX2_STN6_RX_DN<106>")
	)
	(segment
		(start 280.95829 -322.428108)
		(end 292.414452 -327.780396)
		(width 0.1651)
		(layer "In5.Cu")
		(net "P5E_PEX2_STN6_RX_DN<106>")
	)
	(segment
		(start 280.437082 -322.062348)
		(end 280.95829 -322.428108)
		(width 0.1651)
		(layer "In5.Cu")
		(net "P5E_PEX2_STN6_RX_DN<106>")
	)
	(segment
		(start 280.449782 -318.434466)
		(end 280.335482 -318.320166)
		(width 0.1143)
		(layer "In5.Cu")
		(net "P5E_PEX2_STN6_RX_DN<106>")
	)
	(segment
		(start 343.16416 -402.281136)
		(end 342.617044 -402.281136)
		(width 0.1651)
		(layer "In5.Cu")
		(net "P5E_PEX2_STN6_RX_DN<106>")
	)
	(segment
		(start 343.616026 -395.675104)
		(end 343.616026 -401.82927)
		(width 0.1651)
		(layer "In5.Cu")
		(net "P5E_PEX2_STN6_RX_DN<106>")
	)
	(segment
		(start 292.515544 -327.74382)
		(end 292.964616 -327.953624)
		(width 0.1651)
		(layer "In5.Cu")
		(net "P5E_PEX2_STN6_RX_DN<106>")
	)
	(segment
		(start 329.085702 -386.628386)
		(end 329.349354 -387.001766)
		(width 0.1651)
		(layer "In5.Cu")
		(net "P5E_PEX2_STN6_RX_DN<106>")
	)
	(segment
		(start 324.376542 -372.971568)
		(end 328.22261 -384.565398)
		(width 0.1651)
		(layer "In5.Cu")
		(net "P5E_PEX2_STN6_RX_DN<106>")
	)
	(segment
		(start 280.449782 -318.699896)
		(end 280.449782 -318.434466)
		(width 0.1143)
		(layer "In5.Cu")
		(net "P5E_PEX2_STN6_RX_DN<106>")
	)
	(segment
		(start 320.847974 -341.755476)
		(end 320.847974 -358.47147)
		(width 0.1651)
		(layer "In5.Cu")
		(net "P5E_PEX2_STN6_RX_DN<106>")
	)
	(segment
		(start 319.552828 -340.46033)
		(end 320.847974 -341.755476)
		(width 0.1651)
		(layer "In5.Cu")
		(net "P5E_PEX2_STN6_RX_DN<106>")
	)
	(segment
		(start 280.335482 -318.320166)
		(end 280.184352 -318.320166)
		(width 0.1143)
		(layer "In5.Cu")
		(net "P5E_PEX2_STN6_RX_DN<106>")
	)
	(segment
		(start 399.42008 -110.845092)
		(end 398.94256 -110.845092)
		(width 0.13462)
		(layer "F.Cu")
		(net "P5E_PEX3_STN1_RX_DN<22>")
	)
	(segment
		(start 402.11375 -110.6932)
		(end 399.571972 -110.6932)
		(width 0.13462)
		(layer "F.Cu")
		(net "P5E_PEX3_STN1_RX_DN<22>")
	)
	(segment
		(start 399.571972 -110.6932)
		(end 399.42008 -110.845092)
		(width 0.13462)
		(layer "F.Cu")
		(net "P5E_PEX3_STN1_RX_DN<22>")
	)
	(segment
		(start 402.39696 -110.97641)
		(end 402.11375 -110.6932)
		(width 0.13462)
		(layer "F.Cu")
		(net "P5E_PEX3_STN1_RX_DN<22>")
	)
	(segment
		(start 413.649668 -273.365214)
		(end 413.649668 -273.099784)
		(width 0.1143)
		(layer "In5.Cu")
		(net "P5E_PEX3_STN1_RX_DN<22>")
	)
	(segment
		(start 396.903702 -112.128046)
		(end 396.754858 -112.065308)
		(width 0.1651)
		(layer "In5.Cu")
		(net "P5E_PEX3_STN1_RX_DN<22>")
	)
	(segment
		(start 413.37357 -273.479514)
		(end 413.535368 -273.479514)
		(width 0.1143)
		(layer "In5.Cu")
		(net "P5E_PEX3_STN1_RX_DN<22>")
	)
	(segment
		(start 391.721848 -114.76482)
		(end 391.456164 -115.076478)
		(width 0.1651)
		(layer "In5.Cu")
		(net "P5E_PEX3_STN1_RX_DN<22>")
	)
	(segment
		(start 383.7559 -144.875758)
		(end 382.65989 -151.040592)
		(width 0.1651)
		(layer "In5.Cu")
		(net "P5E_PEX3_STN1_RX_DN<22>")
	)
	(segment
		(start 394.951712 -113.075466)
		(end 394.919962 -113.233962)
		(width 0.1651)
		(layer "In5.Cu")
		(net "P5E_PEX3_STN1_RX_DN<22>")
	)
	(segment
		(start 413.270192 -271.600168)
		(end 413.270192 -273.376136)
		(width 0.1143)
		(layer "In5.Cu")
		(net "P5E_PEX3_STN1_RX_DN<22>")
	)
	(segment
		(start 385.625086 -140.713968)
		(end 383.7559 -144.875758)
		(width 0.1651)
		(layer "In5.Cu")
		(net "P5E_PEX3_STN1_RX_DN<22>")
	)
	(segment
		(start 390.436862 -120.053862)
		(end 390.530588 -120.185688)
		(width 0.1651)
		(layer "In5.Cu")
		(net "P5E_PEX3_STN1_RX_DN<22>")
	)
	(segment
		(start 401.24761 -110.79988)
		(end 400.75231 -110.79988)
		(width 0.1651)
		(layer "In5.Cu")
		(net "P5E_PEX3_STN1_RX_DN<22>")
	)
	(segment
		(start 402.10613 -110.68558)
		(end 401.36191 -110.68558)
		(width 0.1651)
		(layer "In5.Cu")
		(net "P5E_PEX3_STN1_RX_DN<22>")
	)
	(segment
		(start 398.554702 -111.332264)
		(end 398.491964 -111.481362)
		(width 0.1651)
		(layer "In5.Cu")
		(net "P5E_PEX3_STN1_RX_DN<22>")
	)
	(segment
		(start 397.425418 -111.792258)
		(end 397.36268 -111.941356)
		(width 0.1651)
		(layer "In5.Cu")
		(net "P5E_PEX3_STN1_RX_DN<22>")
	)
	(segment
		(start 399.16227 -111.208312)
		(end 399.013426 -111.145574)
		(width 0.1651)
		(layer "In5.Cu")
		(net "P5E_PEX3_STN1_RX_DN<22>")
	)
	(segment
		(start 390.327896 -121.388124)
		(end 390.2456 -121.87682)
		(width 0.1651)
		(layer "In5.Cu")
		(net "P5E_PEX3_STN1_RX_DN<22>")
	)
	(segment
		(start 391.172954 -115.683538)
		(end 390.436862 -120.053862)
		(width 0.1651)
		(layer "In5.Cu")
		(net "P5E_PEX3_STN1_RX_DN<22>")
	)
	(segment
		(start 387.579362 -137.015474)
		(end 385.625086 -140.713968)
		(width 0.1651)
		(layer "In5.Cu")
		(net "P5E_PEX3_STN1_RX_DN<22>")
	)
	(segment
		(start 390.316212 -120.76811)
		(end 390.23417 -121.256298)
		(width 0.1651)
		(layer "In5.Cu")
		(net "P5E_PEX3_STN1_RX_DN<22>")
	)
	(segment
		(start 382.65989 -151.040592)
		(end 383.115312 -158.370778)
		(width 0.1651)
		(layer "In5.Cu")
		(net "P5E_PEX3_STN1_RX_DN<22>")
	)
	(segment
		(start 399.621248 -111.021368)
		(end 399.16227 -111.208312)
		(width 0.1651)
		(layer "In5.Cu")
		(net "P5E_PEX3_STN1_RX_DN<22>")
	)
	(segment
		(start 391.456164 -115.076478)
		(end 391.172954 -115.683538)
		(width 0.1651)
		(layer "In5.Cu")
		(net "P5E_PEX3_STN1_RX_DN<22>")
	)
	(segment
		(start 413.270192 -273.376136)
		(end 413.37357 -273.479514)
		(width 0.1143)
		(layer "In5.Cu")
		(net "P5E_PEX3_STN1_RX_DN<22>")
	)
	(segment
		(start 398.491964 -111.481362)
		(end 398.032986 -111.668306)
		(width 0.1651)
		(layer "In5.Cu")
		(net "P5E_PEX3_STN1_RX_DN<22>")
	)
	(segment
		(start 396.754858 -112.065308)
		(end 396.017496 -112.365282)
		(width 0.1651)
		(layer "In5.Cu")
		(net "P5E_PEX3_STN1_RX_DN<22>")
	)
	(segment
		(start 383.115312 -158.370778)
		(end 384.200146 -164.419026)
		(width 0.1651)
		(layer "In5.Cu")
		(net "P5E_PEX3_STN1_RX_DN<22>")
	)
	(segment
		(start 396.017496 -112.365282)
		(end 394.951712 -113.075466)
		(width 0.1651)
		(layer "In5.Cu")
		(net "P5E_PEX3_STN1_RX_DN<22>")
	)
	(segment
		(start 394.507466 -113.50879)
		(end 394.34897 -113.47704)
		(width 0.1651)
		(layer "In5.Cu")
		(net "P5E_PEX3_STN1_RX_DN<22>")
	)
	(segment
		(start 413.315912 -268.786864)
		(end 413.315912 -271.526)
		(width 0.1651)
		(layer "In5.Cu")
		(net "P5E_PEX3_STN1_RX_DN<22>")
	)
	(segment
		(start 390.23417 -121.256298)
		(end 390.327896 -121.388124)
		(width 0.1651)
		(layer "In5.Cu")
		(net "P5E_PEX3_STN1_RX_DN<22>")
	)
	(segment
		(start 394.34897 -113.47704)
		(end 393.936982 -113.751614)
		(width 0.1651)
		(layer "In5.Cu")
		(net "P5E_PEX3_STN1_RX_DN<22>")
	)
	(segment
		(start 413.315912 -271.526)
		(end 413.315912 -271.554448)
		(width 0.1143)
		(layer "In5.Cu")
		(net "P5E_PEX3_STN1_RX_DN<22>")
	)
	(segment
		(start 399.68424 -110.87227)
		(end 399.621248 -111.021368)
		(width 0.1651)
		(layer "In5.Cu")
		(net "P5E_PEX3_STN1_RX_DN<22>")
	)
	(segment
		(start 392.233912 -114.5286)
		(end 391.721848 -114.76482)
		(width 0.1651)
		(layer "In5.Cu")
		(net "P5E_PEX3_STN1_RX_DN<22>")
	)
	(segment
		(start 399.013426 -111.145574)
		(end 398.554702 -111.332264)
		(width 0.1651)
		(layer "In5.Cu")
		(net "P5E_PEX3_STN1_RX_DN<22>")
	)
	(segment
		(start 413.535368 -273.479514)
		(end 413.649668 -273.365214)
		(width 0.1143)
		(layer "In5.Cu")
		(net "P5E_PEX3_STN1_RX_DN<22>")
	)
	(segment
		(start 401.36191 -110.68558)
		(end 401.24761 -110.79988)
		(width 0.1651)
		(layer "In5.Cu")
		(net "P5E_PEX3_STN1_RX_DN<22>")
	)
	(segment
		(start 397.884142 -111.605568)
		(end 397.425418 -111.792258)
		(width 0.1651)
		(layer "In5.Cu")
		(net "P5E_PEX3_STN1_RX_DN<22>")
	)
	(segment
		(start 390.113774 -121.970546)
		(end 387.579362 -137.015474)
		(width 0.1651)
		(layer "In5.Cu")
		(net "P5E_PEX3_STN1_RX_DN<22>")
	)
	(segment
		(start 384.200146 -164.419026)
		(end 413.315912 -268.786864)
		(width 0.1651)
		(layer "In5.Cu")
		(net "P5E_PEX3_STN1_RX_DN<22>")
	)
	(segment
		(start 393.936982 -113.751614)
		(end 393.905232 -113.91011)
		(width 0.1651)
		(layer "In5.Cu")
		(net "P5E_PEX3_STN1_RX_DN<22>")
	)
	(segment
		(start 393.905232 -113.91011)
		(end 393.492736 -114.184938)
		(width 0.1651)
		(layer "In5.Cu")
		(net "P5E_PEX3_STN1_RX_DN<22>")
	)
	(segment
		(start 393.33424 -114.153188)
		(end 392.922252 -114.427762)
		(width 0.1651)
		(layer "In5.Cu")
		(net "P5E_PEX3_STN1_RX_DN<22>")
	)
	(segment
		(start 390.2456 -121.87682)
		(end 390.113774 -121.970546)
		(width 0.1651)
		(layer "In5.Cu")
		(net "P5E_PEX3_STN1_RX_DN<22>")
	)
	(segment
		(start 392.922252 -114.427762)
		(end 392.679682 -114.5286)
		(width 0.1651)
		(layer "In5.Cu")
		(net "P5E_PEX3_STN1_RX_DN<22>")
	)
	(segment
		(start 413.315912 -271.554448)
		(end 413.270192 -271.600168)
		(width 0.1143)
		(layer "In5.Cu")
		(net "P5E_PEX3_STN1_RX_DN<22>")
	)
	(segment
		(start 402.39696 -110.97641)
		(end 402.10613 -110.68558)
		(width 0.1651)
		(layer "In5.Cu")
		(net "P5E_PEX3_STN1_RX_DN<22>")
	)
	(segment
		(start 394.919962 -113.233962)
		(end 394.507466 -113.50879)
		(width 0.1651)
		(layer "In5.Cu")
		(net "P5E_PEX3_STN1_RX_DN<22>")
	)
	(segment
		(start 397.36268 -111.941356)
		(end 396.903702 -112.128046)
		(width 0.1651)
		(layer "In5.Cu")
		(net "P5E_PEX3_STN1_RX_DN<22>")
	)
	(segment
		(start 392.679682 -114.5286)
		(end 392.233912 -114.5286)
		(width 0.1651)
		(layer "In5.Cu")
		(net "P5E_PEX3_STN1_RX_DN<22>")
	)
	(segment
		(start 398.032986 -111.668306)
		(end 397.884142 -111.605568)
		(width 0.1651)
		(layer "In5.Cu")
		(net "P5E_PEX3_STN1_RX_DN<22>")
	)
	(segment
		(start 393.492736 -114.184938)
		(end 393.33424 -114.153188)
		(width 0.1651)
		(layer "In5.Cu")
		(net "P5E_PEX3_STN1_RX_DN<22>")
	)
	(segment
		(start 390.530588 -120.185688)
		(end 390.448292 -120.674384)
		(width 0.1651)
		(layer "In5.Cu")
		(net "P5E_PEX3_STN1_RX_DN<22>")
	)
	(segment
		(start 400.75231 -110.79988)
		(end 400.63801 -110.68558)
		(width 0.1651)
		(layer "In5.Cu")
		(net "P5E_PEX3_STN1_RX_DN<22>")
	)
	(segment
		(start 400.63801 -110.68558)
		(end 400.14271 -110.68558)
		(width 0.1651)
		(layer "In5.Cu")
		(net "P5E_PEX3_STN1_RX_DN<22>")
	)
	(segment
		(start 400.14271 -110.68558)
		(end 399.68424 -110.87227)
		(width 0.1651)
		(layer "In5.Cu")
		(net "P5E_PEX3_STN1_RX_DN<22>")
	)
	(segment
		(start 390.448292 -120.674384)
		(end 390.316212 -120.76811)
		(width 0.1651)
		(layer "In5.Cu")
		(net "P5E_PEX3_STN1_RX_DN<22>")
	)
	(segment
		(start 404.152862 -322.642738)
		(end 404.766018 -321.272154)
		(width 0.1651)
		(layer "In5.Cu")
		(net "P5E_PEX3_STN6_RX_DN<97>")
	)
	(segment
		(start 382.64211 -358.721152)
		(end 382.64211 -342.066626)
		(width 0.1651)
		(layer "In5.Cu")
		(net "P5E_PEX3_STN6_RX_DN<97>")
	)
	(segment
		(start 404.720298 -319.888362)
		(end 404.720298 -316.534292)
		(width 0.1143)
		(layer "In5.Cu")
		(net "P5E_PEX3_STN6_RX_DN<97>")
	)
	(segment
		(start 405.100028 -316.534292)
		(end 405.100028 -316.799722)
		(width 0.1143)
		(layer "In5.Cu")
		(net "P5E_PEX3_STN6_RX_DN<97>")
	)
	(segment
		(start 404.766018 -321.272154)
		(end 404.766018 -319.96253)
		(width 0.1651)
		(layer "In5.Cu")
		(net "P5E_PEX3_STN6_RX_DN<97>")
	)
	(segment
		(start 388.68985 -375.358152)
		(end 388.863078 -375.184924)
		(width 0.1651)
		(layer "In5.Cu")
		(net "P5E_PEX3_STN6_RX_DN<97>")
	)
	(segment
		(start 382.64211 -342.066626)
		(end 383.472182 -340.827868)
		(width 0.1651)
		(layer "In5.Cu")
		(net "P5E_PEX3_STN6_RX_DN<97>")
	)
	(segment
		(start 389.847836 -368.640868)
		(end 382.64211 -358.721152)
		(width 0.1651)
		(layer "In5.Cu")
		(net "P5E_PEX3_STN6_RX_DN<97>")
	)
	(segment
		(start 404.766018 -319.96253)
		(end 404.766018 -319.934082)
		(width 0.1143)
		(layer "In5.Cu")
		(net "P5E_PEX3_STN6_RX_DN<97>")
	)
	(segment
		(start 388.68985 -375.69013)
		(end 388.68985 -375.358152)
		(width 0.1651)
		(layer "In5.Cu")
		(net "P5E_PEX3_STN6_RX_DN<97>")
	)
	(segment
		(start 383.472182 -340.827868)
		(end 402.073364 -325.382128)
		(width 0.1651)
		(layer "In5.Cu")
		(net "P5E_PEX3_STN6_RX_DN<97>")
	)
	(segment
		(start 389.847836 -374.687338)
		(end 389.847836 -368.640868)
		(width 0.1651)
		(layer "In5.Cu")
		(net "P5E_PEX3_STN6_RX_DN<97>")
	)
	(segment
		(start 404.720298 -316.534292)
		(end 404.834598 -316.419992)
		(width 0.1143)
		(layer "In5.Cu")
		(net "P5E_PEX3_STN6_RX_DN<97>")
	)
	(segment
		(start 404.834598 -316.419992)
		(end 404.985728 -316.419992)
		(width 0.1143)
		(layer "In5.Cu")
		(net "P5E_PEX3_STN6_RX_DN<97>")
	)
	(segment
		(start 389.35025 -375.184924)
		(end 389.847836 -374.687338)
		(width 0.1651)
		(layer "In5.Cu")
		(net "P5E_PEX3_STN6_RX_DN<97>")
	)
	(segment
		(start 404.985728 -316.419992)
		(end 405.100028 -316.534292)
		(width 0.1143)
		(layer "In5.Cu")
		(net "P5E_PEX3_STN6_RX_DN<97>")
	)
	(segment
		(start 402.073364 -325.382128)
		(end 404.152862 -322.642738)
		(width 0.1651)
		(layer "In5.Cu")
		(net "P5E_PEX3_STN6_RX_DN<97>")
	)
	(segment
		(start 404.766018 -319.934082)
		(end 404.720298 -319.888362)
		(width 0.1143)
		(layer "In5.Cu")
		(net "P5E_PEX3_STN6_RX_DN<97>")
	)
	(segment
		(start 388.863078 -375.184924)
		(end 389.35025 -375.184924)
		(width 0.1651)
		(layer "In5.Cu")
		(net "P5E_PEX3_STN6_RX_DN<97>")
	)
	(segment
		(start 191.376808 -98.840036)
		(end 192.045844 -98.171)
		(width 0.13208)
		(layer "F.Cu")
		(net "NIC3_DATA_IN")
	)
	(segment
		(start 189.357508 -98.840036)
		(end 191.376808 -98.840036)
		(width 0.13208)
		(layer "F.Cu")
		(net "NIC3_DATA_IN")
	)
	(via
		(at 192.045844 -98.171)
		(size 0.508)
		(drill 0.254)
		(layers "F.Cu" "B.Cu")
		(net "NIC3_DATA_IN")
	)
	(segment
		(start 192.076324 -98.171)
		(end 192.045844 -98.171)
		(width 0.13208)
		(layer "B.Cu")
		(net "NIC3_DATA_IN")
	)
	(segment
		(start 193.241676 -97.005648)
		(end 192.076324 -98.171)
		(width 0.13208)
		(layer "B.Cu")
		(net "NIC3_DATA_IN")
	)
	(segment
		(start 36.6649 -28.990036)
		(end 36.6649 -28.99029)
		(width 0.13462)
		(layer "F.Cu")
		(net "P5E_PEX0_STN2_RX_DP<40>")
	)
	(segment
		(start 35.35807 -28.829)
		(end 35.0647 -29.12237)
		(width 0.13462)
		(layer "F.Cu")
		(net "P5E_PEX0_STN2_RX_DP<40>")
	)
	(segment
		(start 36.185856 -28.99029)
		(end 36.024566 -28.829)
		(width 0.13462)
		(layer "F.Cu")
		(net "P5E_PEX0_STN2_RX_DP<40>")
	)
	(segment
		(start 36.6649 -28.99029)
		(end 36.185856 -28.99029)
		(width 0.13462)
		(layer "F.Cu")
		(net "P5E_PEX0_STN2_RX_DP<40>")
	)
	(segment
		(start 36.024566 -28.829)
		(end 35.35807 -28.829)
		(width 0.13462)
		(layer "F.Cu")
		(net "P5E_PEX0_STN2_RX_DP<40>")
	)
	(segment
		(start 35.323018 -28.864052)
		(end 35.401504 -28.83154)
		(width 0.1651)
		(layer "In7.Cu")
		(net "P5E_PEX0_STN2_RX_DP<40>")
	)
	(segment
		(start 50.744882 -275.570188)
		(end 50.985674 -275.570188)
		(width 0.1143)
		(layer "In7.Cu")
		(net "P5E_PEX0_STN2_RX_DP<40>")
	)
	(segment
		(start 42.79265 -119.567198)
		(end 42.486834 -147.947888)
		(width 0.1651)
		(layer "In7.Cu")
		(net "P5E_PEX0_STN2_RX_DP<40>")
	)
	(segment
		(start 42.33037 -104.315514)
		(end 42.79265 -119.567198)
		(width 0.1651)
		(layer "In7.Cu")
		(net "P5E_PEX0_STN2_RX_DP<40>")
	)
	(segment
		(start 50.52949 -275.354796)
		(end 50.744882 -275.570188)
		(width 0.1143)
		(layer "In7.Cu")
		(net "P5E_PEX0_STN2_RX_DP<40>")
	)
	(segment
		(start 36.754308 -30.042612)
		(end 36.898072 -30.042612)
		(width 0.1651)
		(layer "In7.Cu")
		(net "P5E_PEX0_STN2_RX_DP<40>")
	)
	(segment
		(start 41.03497 -38.545262)
		(end 38.888162 -48.798226)
		(width 0.1651)
		(layer "In7.Cu")
		(net "P5E_PEX0_STN2_RX_DP<40>")
	)
	(segment
		(start 37.598604 -30.886908)
		(end 37.742368 -30.886908)
		(width 0.1651)
		(layer "In7.Cu")
		(net "P5E_PEX0_STN2_RX_DP<40>")
	)
	(segment
		(start 39.186612 -65.14846)
		(end 42.33037 -104.315514)
		(width 0.1651)
		(layer "In7.Cu")
		(net "P5E_PEX0_STN2_RX_DP<40>")
	)
	(segment
		(start 50.985674 -275.570188)
		(end 51.099974 -275.684488)
		(width 0.1143)
		(layer "In7.Cu")
		(net "P5E_PEX0_STN2_RX_DP<40>")
	)
	(segment
		(start 50.161952 -264.871962)
		(end 50.48377 -268.137132)
		(width 0.1651)
		(layer "In7.Cu")
		(net "P5E_PEX0_STN2_RX_DP<40>")
	)
	(segment
		(start 50.48377 -271.392904)
		(end 50.48377 -271.421352)
		(width 0.1143)
		(layer "In7.Cu")
		(net "P5E_PEX0_STN2_RX_DP<40>")
	)
	(segment
		(start 38.78834 -55.19547)
		(end 39.186612 -65.14846)
		(width 0.1651)
		(layer "In7.Cu")
		(net "P5E_PEX0_STN2_RX_DP<40>")
	)
	(segment
		(start 50.448464 -250.016518)
		(end 50.161952 -264.871962)
		(width 0.1651)
		(layer "In7.Cu")
		(net "P5E_PEX0_STN2_RX_DP<40>")
	)
	(segment
		(start 35.401504 -28.83154)
		(end 35.687 -28.83154)
		(width 0.1651)
		(layer "In7.Cu")
		(net "P5E_PEX0_STN2_RX_DP<40>")
	)
	(segment
		(start 51.099974 -275.684488)
		(end 51.099974 -275.949918)
		(width 0.1143)
		(layer "In7.Cu")
		(net "P5E_PEX0_STN2_RX_DP<40>")
	)
	(segment
		(start 35.0647 -29.12237)
		(end 35.323018 -28.864052)
		(width 0.1651)
		(layer "In7.Cu")
		(net "P5E_PEX0_STN2_RX_DP<40>")
	)
	(segment
		(start 50.48377 -271.421352)
		(end 50.52949 -271.467072)
		(width 0.1143)
		(layer "In7.Cu")
		(net "P5E_PEX0_STN2_RX_DP<40>")
	)
	(segment
		(start 37.248084 -30.536388)
		(end 37.598604 -30.886908)
		(width 0.1651)
		(layer "In7.Cu")
		(net "P5E_PEX0_STN2_RX_DP<40>")
	)
	(segment
		(start 41.048432 -37.742622)
		(end 41.03497 -38.545262)
		(width 0.1651)
		(layer "In7.Cu")
		(net "P5E_PEX0_STN2_RX_DP<40>")
	)
	(segment
		(start 37.742368 -30.886908)
		(end 38.464236 -31.608776)
		(width 0.1651)
		(layer "In7.Cu")
		(net "P5E_PEX0_STN2_RX_DP<40>")
	)
	(segment
		(start 36.898072 -30.042612)
		(end 37.248084 -30.392624)
		(width 0.1651)
		(layer "In7.Cu")
		(net "P5E_PEX0_STN2_RX_DP<40>")
	)
	(segment
		(start 38.888162 -48.798226)
		(end 38.78834 -55.19547)
		(width 0.1651)
		(layer "In7.Cu")
		(net "P5E_PEX0_STN2_RX_DP<40>")
	)
	(segment
		(start 37.248084 -30.392624)
		(end 37.248084 -30.536388)
		(width 0.1651)
		(layer "In7.Cu")
		(net "P5E_PEX0_STN2_RX_DP<40>")
	)
	(segment
		(start 36.403788 -29.548328)
		(end 36.403788 -29.692092)
		(width 0.1651)
		(layer "In7.Cu")
		(net "P5E_PEX0_STN2_RX_DP<40>")
	)
	(segment
		(start 35.687 -28.83154)
		(end 36.403788 -29.548328)
		(width 0.1651)
		(layer "In7.Cu")
		(net "P5E_PEX0_STN2_RX_DP<40>")
	)
	(segment
		(start 50.52949 -271.467072)
		(end 50.52949 -275.354796)
		(width 0.1143)
		(layer "In7.Cu")
		(net "P5E_PEX0_STN2_RX_DP<40>")
	)
	(segment
		(start 50.48377 -268.137132)
		(end 50.48377 -271.392904)
		(width 0.1651)
		(layer "In7.Cu")
		(net "P5E_PEX0_STN2_RX_DP<40>")
	)
	(segment
		(start 42.486834 -147.947888)
		(end 50.448464 -250.016518)
		(width 0.1651)
		(layer "In7.Cu")
		(net "P5E_PEX0_STN2_RX_DP<40>")
	)
	(segment
		(start 38.464236 -31.608776)
		(end 41.048432 -37.742622)
		(width 0.1651)
		(layer "In7.Cu")
		(net "P5E_PEX0_STN2_RX_DP<40>")
	)
	(segment
		(start 36.403788 -29.692092)
		(end 36.754308 -30.042612)
		(width 0.1651)
		(layer "In7.Cu")
		(net "P5E_PEX0_STN2_RX_DP<40>")
	)
	(segment
		(start 159.625792 -31.825184)
		(end 159.314896 -32.13608)
		(width 0.13462)
		(layer "F.Cu")
		(net "P5E_PEX1_STN2_TX_C_DN<42>")
	)
	(segment
		(start 158.014162 -32.13608)
		(end 157.868112 -31.99003)
		(width 0.13462)
		(layer "F.Cu")
		(net "P5E_PEX1_STN2_TX_C_DN<42>")
	)
	(segment
		(start 159.314896 -32.13608)
		(end 158.014162 -32.13608)
		(width 0.13462)
		(layer "F.Cu")
		(net "P5E_PEX1_STN2_TX_C_DN<42>")
	)
	(segment
		(start 157.868112 -31.99003)
		(end 157.364938 -31.99003)
		(width 0.13462)
		(layer "F.Cu")
		(net "P5E_PEX1_STN2_TX_C_DN<42>")
	)
	(segment
		(start 300.222412 -119.279162)
		(end 299.545248 -119.279162)
		(width 0.13462)
		(layer "F.Cu")
		(net "P5E_PEX2_STN0_RX_DP<0>")
	)
	(segment
		(start 300.378368 -119.435118)
		(end 300.222412 -119.279162)
		(width 0.13462)
		(layer "F.Cu")
		(net "P5E_PEX2_STN0_RX_DP<0>")
	)
	(segment
		(start 299.545248 -119.279162)
		(end 299.257212 -119.567198)
		(width 0.13462)
		(layer "F.Cu")
		(net "P5E_PEX2_STN0_RX_DP<0>")
	)
	(segment
		(start 300.857412 -119.435118)
		(end 300.378368 -119.435118)
		(width 0.13462)
		(layer "F.Cu")
		(net "P5E_PEX2_STN0_RX_DP<0>")
	)
	(segment
		(start 300.484286 -119.465598)
		(end 300.484286 -119.465852)
		(width 0.1651)
		(layer "In5.Cu")
		(net "P5E_PEX2_STN0_RX_DP<0>")
	)
	(segment
		(start 317.388494 -131.045458)
		(end 310.933846 -126.232412)
		(width 0.1651)
		(layer "In5.Cu")
		(net "P5E_PEX2_STN0_RX_DP<0>")
	)
	(segment
		(start 302.79975 -120.547892)
		(end 302.737774 -120.398286)
		(width 0.1651)
		(layer "In5.Cu")
		(net "P5E_PEX2_STN0_RX_DP<0>")
	)
	(segment
		(start 310.41213 -125.954282)
		(end 310.394096 -125.829822)
		(width 0.1651)
		(layer "In5.Cu")
		(net "P5E_PEX2_STN0_RX_DP<0>")
	)
	(segment
		(start 309.060342 -124.835412)
		(end 308.935882 -124.8537)
		(width 0.1651)
		(layer "In5.Cu")
		(net "P5E_PEX2_STN0_RX_DP<0>")
	)
	(segment
		(start 300.026578 -119.276368)
		(end 299.548042 -119.276368)
		(width 0.1651)
		(layer "In5.Cu")
		(net "P5E_PEX2_STN0_RX_DP<0>")
	)
	(segment
		(start 299.548042 -119.276368)
		(end 299.257212 -119.567198)
		(width 0.1651)
		(layer "In5.Cu")
		(net "P5E_PEX2_STN0_RX_DP<0>")
	)
	(segment
		(start 321.357244 -231.903016)
		(end 322.02374 -168.526206)
		(width 0.1651)
		(layer "In5.Cu")
		(net "P5E_PEX2_STN0_RX_DP<0>")
	)
	(segment
		(start 302.130968 -120.271032)
		(end 301.673006 -120.081548)
		(width 0.1651)
		(layer "In5.Cu")
		(net "P5E_PEX2_STN0_RX_DP<0>")
	)
	(segment
		(start 322.893182 -239.28705)
		(end 321.357244 -231.903016)
		(width 0.1651)
		(layer "In5.Cu")
		(net "P5E_PEX2_STN0_RX_DP<0>")
	)
	(segment
		(start 331.409294 -273.645376)
		(end 331.59065 -269.159482)
		(width 0.1651)
		(layer "In5.Cu")
		(net "P5E_PEX2_STN0_RX_DP<0>")
	)
	(segment
		(start 312.179462 -288.185606)
		(end 312.179462 -287.97377)
		(width 0.1143)
		(layer "In5.Cu")
		(net "P5E_PEX2_STN0_RX_DP<0>")
	)
	(segment
		(start 301.610776 -119.931942)
		(end 301.153576 -119.742712)
		(width 0.1651)
		(layer "In5.Cu")
		(net "P5E_PEX2_STN0_RX_DP<0>")
	)
	(segment
		(start 309.997094 -125.533912)
		(end 309.872634 -125.5522)
		(width 0.1651)
		(layer "In5.Cu")
		(net "P5E_PEX2_STN0_RX_DP<0>")
	)
	(segment
		(start 316.050422 -287.729676)
		(end 316.096142 -287.683956)
		(width 0.1143)
		(layer "In5.Cu")
		(net "P5E_PEX2_STN0_RX_DP<0>")
	)
	(segment
		(start 321.17665 -145.627852)
		(end 318.114426 -131.999482)
		(width 0.1651)
		(layer "In5.Cu")
		(net "P5E_PEX2_STN0_RX_DP<0>")
	)
	(segment
		(start 316.096142 -287.683956)
		(end 316.12459 -287.683956)
		(width 0.1143)
		(layer "In5.Cu")
		(net "P5E_PEX2_STN0_RX_DP<0>")
	)
	(segment
		(start 301.004224 -119.804688)
		(end 300.546262 -119.615204)
		(width 0.1651)
		(layer "In5.Cu")
		(net "P5E_PEX2_STN0_RX_DP<0>")
	)
	(segment
		(start 302.28032 -120.209056)
		(end 302.130968 -120.271032)
		(width 0.1651)
		(layer "In5.Cu")
		(net "P5E_PEX2_STN0_RX_DP<0>")
	)
	(segment
		(start 312.423556 -287.729676)
		(end 316.050422 -287.729676)
		(width 0.1143)
		(layer "In5.Cu")
		(net "P5E_PEX2_STN0_RX_DP<0>")
	)
	(segment
		(start 307.58384 -123.734322)
		(end 306.207668 -122.708162)
		(width 0.1651)
		(layer "In5.Cu")
		(net "P5E_PEX2_STN0_RX_DP<0>")
	)
	(segment
		(start 309.475378 -125.255782)
		(end 309.457344 -125.131322)
		(width 0.1651)
		(layer "In5.Cu")
		(net "P5E_PEX2_STN0_RX_DP<0>")
	)
	(segment
		(start 302.737774 -120.398286)
		(end 302.73752 -120.398286)
		(width 0.1651)
		(layer "In5.Cu")
		(net "P5E_PEX2_STN0_RX_DP<0>")
	)
	(segment
		(start 312.179462 -287.97377)
		(end 312.423556 -287.729676)
		(width 0.1143)
		(layer "In5.Cu")
		(net "P5E_PEX2_STN0_RX_DP<0>")
	)
	(segment
		(start 310.809386 -126.2507)
		(end 310.41213 -125.954282)
		(width 0.1651)
		(layer "In5.Cu")
		(net "P5E_PEX2_STN0_RX_DP<0>")
	)
	(segment
		(start 303.407064 -120.6754)
		(end 303.257712 -120.737376)
		(width 0.1651)
		(layer "In5.Cu")
		(net "P5E_PEX2_STN0_RX_DP<0>")
	)
	(segment
		(start 316.12459 -287.683956)
		(end 318.627252 -287.683956)
		(width 0.1651)
		(layer "In5.Cu")
		(net "P5E_PEX2_STN0_RX_DP<0>")
	)
	(segment
		(start 331.59065 -269.159482)
		(end 322.893182 -239.28705)
		(width 0.1651)
		(layer "In5.Cu")
		(net "P5E_PEX2_STN0_RX_DP<0>")
	)
	(segment
		(start 301.61103 -119.931942)
		(end 301.610776 -119.931942)
		(width 0.1651)
		(layer "In5.Cu")
		(net "P5E_PEX2_STN0_RX_DP<0>")
	)
	(segment
		(start 304.709068 -121.214388)
		(end 303.407064 -120.6754)
		(width 0.1651)
		(layer "In5.Cu")
		(net "P5E_PEX2_STN0_RX_DP<0>")
	)
	(segment
		(start 300.546262 -119.615204)
		(end 300.484286 -119.465598)
		(width 0.1651)
		(layer "In5.Cu")
		(net "P5E_PEX2_STN0_RX_DP<0>")
	)
	(segment
		(start 301.153576 -119.742712)
		(end 301.004224 -119.804688)
		(width 0.1651)
		(layer "In5.Cu")
		(net "P5E_PEX2_STN0_RX_DP<0>")
	)
	(segment
		(start 302.73752 -120.398286)
		(end 302.28032 -120.209056)
		(width 0.1651)
		(layer "In5.Cu")
		(net "P5E_PEX2_STN0_RX_DP<0>")
	)
	(segment
		(start 318.114426 -131.999482)
		(end 317.388494 -131.045458)
		(width 0.1651)
		(layer "In5.Cu")
		(net "P5E_PEX2_STN0_RX_DP<0>")
	)
	(segment
		(start 319.75933 -286.969708)
		(end 328.815446 -278.22525)
		(width 0.1651)
		(layer "In5.Cu")
		(net "P5E_PEX2_STN0_RX_DP<0>")
	)
	(segment
		(start 309.872634 -125.5522)
		(end 309.475378 -125.255782)
		(width 0.1651)
		(layer "In5.Cu")
		(net "P5E_PEX2_STN0_RX_DP<0>")
	)
	(segment
		(start 303.257712 -120.737376)
		(end 302.79975 -120.547892)
		(width 0.1651)
		(layer "In5.Cu")
		(net "P5E_PEX2_STN0_RX_DP<0>")
	)
	(segment
		(start 321.57162 -149.84476)
		(end 321.17665 -145.627852)
		(width 0.1651)
		(layer "In5.Cu")
		(net "P5E_PEX2_STN0_RX_DP<0>")
	)
	(segment
		(start 307.999384 -124.154946)
		(end 307.601874 -123.858782)
		(width 0.1651)
		(layer "In5.Cu")
		(net "P5E_PEX2_STN0_RX_DP<0>")
	)
	(segment
		(start 301.673006 -120.081548)
		(end 301.61103 -119.931942)
		(width 0.1651)
		(layer "In5.Cu")
		(net "P5E_PEX2_STN0_RX_DP<0>")
	)
	(segment
		(start 322.02374 -168.526206)
		(end 321.57162 -149.84476)
		(width 0.1651)
		(layer "In5.Cu")
		(net "P5E_PEX2_STN0_RX_DP<0>")
	)
	(segment
		(start 309.457344 -125.131322)
		(end 309.060342 -124.835412)
		(width 0.1651)
		(layer "In5.Cu")
		(net "P5E_PEX2_STN0_RX_DP<0>")
	)
	(segment
		(start 310.933846 -126.232412)
		(end 310.809386 -126.2507)
		(width 0.1651)
		(layer "In5.Cu")
		(net "P5E_PEX2_STN0_RX_DP<0>")
	)
	(segment
		(start 328.815446 -278.22525)
		(end 331.409294 -273.645376)
		(width 0.1651)
		(layer "In5.Cu")
		(net "P5E_PEX2_STN0_RX_DP<0>")
	)
	(segment
		(start 300.484286 -119.465852)
		(end 300.026578 -119.276368)
		(width 0.1651)
		(layer "In5.Cu")
		(net "P5E_PEX2_STN0_RX_DP<0>")
	)
	(segment
		(start 308.12359 -124.136912)
		(end 307.999384 -124.154946)
		(width 0.1651)
		(layer "In5.Cu")
		(net "P5E_PEX2_STN0_RX_DP<0>")
	)
	(segment
		(start 312.065162 -288.299906)
		(end 312.179462 -288.185606)
		(width 0.1143)
		(layer "In5.Cu")
		(net "P5E_PEX2_STN0_RX_DP<0>")
	)
	(segment
		(start 311.799732 -288.299906)
		(end 312.065162 -288.299906)
		(width 0.1143)
		(layer "In5.Cu")
		(net "P5E_PEX2_STN0_RX_DP<0>")
	)
	(segment
		(start 318.627252 -287.683956)
		(end 319.75933 -286.969708)
		(width 0.1651)
		(layer "In5.Cu")
		(net "P5E_PEX2_STN0_RX_DP<0>")
	)
	(segment
		(start 306.207668 -122.708162)
		(end 304.709068 -121.214388)
		(width 0.1651)
		(layer "In5.Cu")
		(net "P5E_PEX2_STN0_RX_DP<0>")
	)
	(segment
		(start 308.935882 -124.8537)
		(end 308.538626 -124.557282)
		(width 0.1651)
		(layer "In5.Cu")
		(net "P5E_PEX2_STN0_RX_DP<0>")
	)
	(segment
		(start 308.520592 -124.432822)
		(end 308.12359 -124.136912)
		(width 0.1651)
		(layer "In5.Cu")
		(net "P5E_PEX2_STN0_RX_DP<0>")
	)
	(segment
		(start 307.601874 -123.858782)
		(end 307.58384 -123.734322)
		(width 0.1651)
		(layer "In5.Cu")
		(net "P5E_PEX2_STN0_RX_DP<0>")
	)
	(segment
		(start 308.538626 -124.557282)
		(end 308.520592 -124.432822)
		(width 0.1651)
		(layer "In5.Cu")
		(net "P5E_PEX2_STN0_RX_DP<0>")
	)
	(segment
		(start 310.394096 -125.829822)
		(end 309.997094 -125.533912)
		(width 0.1651)
		(layer "In5.Cu")
		(net "P5E_PEX2_STN0_RX_DP<0>")
	)
	(segment
		(start 284.160722 -318.129666)
		(end 284.249876 -318.040512)
		(width 0.1143)
		(layer "In9.Cu")
		(net "P5E_PEX2_STN6_RX_DP<102>")
	)
	(segment
		(start 283.633672 -325.022972)
		(end 283.633672 -319.916048)
		(width 0.1651)
		(layer "In9.Cu")
		(net "P5E_PEX2_STN6_RX_DP<102>")
	)
	(segment
		(start 283.679392 -318.355218)
		(end 283.904944 -318.129666)
		(width 0.1143)
		(layer "In9.Cu")
		(net "P5E_PEX2_STN6_RX_DP<102>")
	)
	(segment
		(start 283.679392 -319.84188)
		(end 283.679392 -318.355218)
		(width 0.1143)
		(layer "In9.Cu")
		(net "P5E_PEX2_STN6_RX_DP<102>")
	)
	(segment
		(start 328.77379 -365.984536)
		(end 328.715624 -365.852964)
		(width 0.1651)
		(layer "In9.Cu")
		(net "P5E_PEX2_STN6_RX_DP<102>")
	)
	(segment
		(start 301.186596 -340.857078)
		(end 287.709864 -330.23937)
		(width 0.1651)
		(layer "In9.Cu")
		(net "P5E_PEX2_STN6_RX_DP<102>")
	)
	(segment
		(start 334.534002 -369.169696)
		(end 334.085692 -368.314986)
		(width 0.1651)
		(layer "In9.Cu")
		(net "P5E_PEX2_STN6_RX_DP<102>")
	)
	(segment
		(start 314.032646 -359.518458)
		(end 301.186596 -340.857078)
		(width 0.1651)
		(layer "In9.Cu")
		(net "P5E_PEX2_STN6_RX_DP<102>")
	)
	(segment
		(start 283.904944 -318.129666)
		(end 284.160722 -318.129666)
		(width 0.1143)
		(layer "In9.Cu")
		(net "P5E_PEX2_STN6_RX_DP<102>")
	)
	(segment
		(start 328.715624 -365.852964)
		(end 315.16828 -360.629962)
		(width 0.1651)
		(layer "In9.Cu")
		(net "P5E_PEX2_STN6_RX_DP<102>")
	)
	(segment
		(start 333.68996 -375.872248)
		(end 333.81696 -375.999248)
		(width 0.1651)
		(layer "In9.Cu")
		(net "P5E_PEX2_STN6_RX_DP<102>")
	)
	(segment
		(start 334.085692 -368.314986)
		(end 332.909672 -367.469928)
		(width 0.1651)
		(layer "In9.Cu")
		(net "P5E_PEX2_STN6_RX_DP<102>")
	)
	(segment
		(start 284.327346 -326.69861)
		(end 283.633672 -325.022972)
		(width 0.1651)
		(layer "In9.Cu")
		(net "P5E_PEX2_STN6_RX_DP<102>")
	)
	(segment
		(start 329.236324 -366.16259)
		(end 328.77379 -365.984536)
		(width 0.1651)
		(layer "In9.Cu")
		(net "P5E_PEX2_STN6_RX_DP<102>")
	)
	(segment
		(start 334.534002 -375.712482)
		(end 334.534002 -369.169696)
		(width 0.1651)
		(layer "In9.Cu")
		(net "P5E_PEX2_STN6_RX_DP<102>")
	)
	(segment
		(start 329.829668 -366.282478)
		(end 329.367642 -366.104424)
		(width 0.1651)
		(layer "In9.Cu")
		(net "P5E_PEX2_STN6_RX_DP<102>")
	)
	(segment
		(start 329.888088 -366.41405)
		(end 329.829668 -366.282478)
		(width 0.1651)
		(layer "In9.Cu")
		(net "P5E_PEX2_STN6_RX_DP<102>")
	)
	(segment
		(start 334.247236 -375.999248)
		(end 334.534002 -375.712482)
		(width 0.1651)
		(layer "In9.Cu")
		(net "P5E_PEX2_STN6_RX_DP<102>")
	)
	(segment
		(start 315.16828 -360.629962)
		(end 314.032646 -359.518458)
		(width 0.1651)
		(layer "In9.Cu")
		(net "P5E_PEX2_STN6_RX_DP<102>")
	)
	(segment
		(start 333.68996 -375.490232)
		(end 333.68996 -375.872248)
		(width 0.1651)
		(layer "In9.Cu")
		(net "P5E_PEX2_STN6_RX_DP<102>")
	)
	(segment
		(start 332.909672 -367.469928)
		(end 330.481686 -366.533938)
		(width 0.1651)
		(layer "In9.Cu")
		(net "P5E_PEX2_STN6_RX_DP<102>")
	)
	(segment
		(start 330.481686 -366.533938)
		(end 330.350368 -366.592104)
		(width 0.1651)
		(layer "In9.Cu")
		(net "P5E_PEX2_STN6_RX_DP<102>")
	)
	(segment
		(start 287.709864 -330.23937)
		(end 284.740858 -327.30821)
		(width 0.1651)
		(layer "In9.Cu")
		(net "P5E_PEX2_STN6_RX_DP<102>")
	)
	(segment
		(start 284.740858 -327.30821)
		(end 284.327346 -326.69861)
		(width 0.1651)
		(layer "In9.Cu")
		(net "P5E_PEX2_STN6_RX_DP<102>")
	)
	(segment
		(start 333.81696 -375.999248)
		(end 334.247236 -375.999248)
		(width 0.1651)
		(layer "In9.Cu")
		(net "P5E_PEX2_STN6_RX_DP<102>")
	)
	(segment
		(start 330.350368 -366.592104)
		(end 329.888088 -366.41405)
		(width 0.1651)
		(layer "In9.Cu")
		(net "P5E_PEX2_STN6_RX_DP<102>")
	)
	(segment
		(start 283.633672 -319.8876)
		(end 283.679392 -319.84188)
		(width 0.1143)
		(layer "In9.Cu")
		(net "P5E_PEX2_STN6_RX_DP<102>")
	)
	(segment
		(start 329.367642 -366.104424)
		(end 329.236324 -366.16259)
		(width 0.1651)
		(layer "In9.Cu")
		(net "P5E_PEX2_STN6_RX_DP<102>")
	)
	(segment
		(start 284.249876 -318.040512)
		(end 284.249876 -317.749936)
		(width 0.1143)
		(layer "In9.Cu")
		(net "P5E_PEX2_STN6_RX_DP<102>")
	)
	(segment
		(start 283.633672 -319.916048)
		(end 283.633672 -319.8876)
		(width 0.1143)
		(layer "In9.Cu")
		(net "P5E_PEX2_STN6_RX_DP<102>")
	)
	(segment
		(start 388.163816 -103.20528)
		(end 393.679426 -103.20528)
		(width 0.13462)
		(layer "F.Cu")
		(net "P5E_PEX3_STN1_TX_C_DP<18>")
	)
	(segment
		(start 387.847332 -102.888796)
		(end 388.163816 -103.20528)
		(width 0.13462)
		(layer "F.Cu")
		(net "P5E_PEX3_STN1_TX_C_DP<18>")
	)
	(segment
		(start 393.679426 -103.20528)
		(end 393.8397 -103.045006)
		(width 0.13462)
		(layer "F.Cu")
		(net "P5E_PEX3_STN1_TX_C_DP<18>")
	)
	(segment
		(start 393.8397 -103.045006)
		(end 394.342366 -103.045006)
		(width 0.13462)
		(layer "F.Cu")
		(net "P5E_PEX3_STN1_TX_C_DP<18>")
	)
	(segment
		(start 378.726192 -366.599978)
		(end 378.386594 -366.239044)
		(width 0.1651)
		(layer "In5.Cu")
		(net "P5E_PEX3_STN6_RX_DP<101>")
	)
	(segment
		(start 400.683984 -319.995296)
		(end 400.683984 -319.966848)
		(width 0.1143)
		(layer "In5.Cu")
		(net "P5E_PEX3_STN6_RX_DP<101>")
	)
	(segment
		(start 370.082318 -341.694262)
		(end 370.764562 -340.834218)
		(width 0.1651)
		(layer "In5.Cu")
		(net "P5E_PEX3_STN6_RX_DP<101>")
	)
	(segment
		(start 400.95551 -316.229492)
		(end 401.185634 -316.229492)
		(width 0.1143)
		(layer "In5.Cu")
		(net "P5E_PEX3_STN6_RX_DP<101>")
	)
	(segment
		(start 400.729704 -319.921128)
		(end 400.729704 -316.455298)
		(width 0.1143)
		(layer "In5.Cu")
		(net "P5E_PEX3_STN6_RX_DP<101>")
	)
	(segment
		(start 377.572016 -365.243872)
		(end 377.232672 -364.883446)
		(width 0.1651)
		(layer "In5.Cu")
		(net "P5E_PEX3_STN6_RX_DP<101>")
	)
	(segment
		(start 378.05106 -365.752888)
		(end 377.907296 -365.74857)
		(width 0.1651)
		(layer "In5.Cu")
		(net "P5E_PEX3_STN6_RX_DP<101>")
	)
	(segment
		(start 400.683984 -319.966848)
		(end 400.729704 -319.921128)
		(width 0.1143)
		(layer "In5.Cu")
		(net "P5E_PEX3_STN6_RX_DP<101>")
	)
	(segment
		(start 380.43358 -374.902984)
		(end 380.766066 -374.570498)
		(width 0.1651)
		(layer "In5.Cu")
		(net "P5E_PEX3_STN6_RX_DP<101>")
	)
	(segment
		(start 369.92433 -342.132666)
		(end 369.924584 -342.131904)
		(width 0.1651)
		(layer "In5.Cu")
		(net "P5E_PEX3_STN6_RX_DP<101>")
	)
	(segment
		(start 379.89002 -374.729756)
		(end 380.063248 -374.902984)
		(width 0.1651)
		(layer "In5.Cu")
		(net "P5E_PEX3_STN6_RX_DP<101>")
	)
	(segment
		(start 378.851922 -366.603788)
		(end 378.726192 -366.599978)
		(width 0.1651)
		(layer "In5.Cu")
		(net "P5E_PEX3_STN6_RX_DP<101>")
	)
	(segment
		(start 377.232672 -364.883446)
		(end 377.071128 -364.878366)
		(width 0.1651)
		(layer "In5.Cu")
		(net "P5E_PEX3_STN6_RX_DP<101>")
	)
	(segment
		(start 379.191266 -366.964214)
		(end 378.851922 -366.603788)
		(width 0.1651)
		(layer "In5.Cu")
		(net "P5E_PEX3_STN6_RX_DP<101>")
	)
	(segment
		(start 379.527054 -367.450624)
		(end 379.187456 -367.08969)
		(width 0.1651)
		(layer "In5.Cu")
		(net "P5E_PEX3_STN6_RX_DP<101>")
	)
	(segment
		(start 369.764818 -342.575388)
		(end 369.92433 -342.132666)
		(width 0.1651)
		(layer "In5.Cu")
		(net "P5E_PEX3_STN6_RX_DP<101>")
	)
	(segment
		(start 369.924584 -342.131904)
		(end 370.082318 -341.694262)
		(width 0.1651)
		(layer "In5.Cu")
		(net "P5E_PEX3_STN6_RX_DP<101>")
	)
	(segment
		(start 400.683984 -320.472816)
		(end 400.683984 -319.995296)
		(width 0.1651)
		(layer "In5.Cu")
		(net "P5E_PEX3_STN6_RX_DP<101>")
	)
	(segment
		(start 376.731276 -364.517686)
		(end 376.736102 -364.355888)
		(width 0.1651)
		(layer "In5.Cu")
		(net "P5E_PEX3_STN6_RX_DP<101>")
	)
	(segment
		(start 378.390404 -366.113314)
		(end 378.05106 -365.752888)
		(width 0.1651)
		(layer "In5.Cu")
		(net "P5E_PEX3_STN6_RX_DP<101>")
	)
	(segment
		(start 377.071128 -364.878366)
		(end 376.731276 -364.517686)
		(width 0.1651)
		(layer "In5.Cu")
		(net "P5E_PEX3_STN6_RX_DP<101>")
	)
	(segment
		(start 379.652784 -367.454434)
		(end 379.527054 -367.450624)
		(width 0.1651)
		(layer "In5.Cu")
		(net "P5E_PEX3_STN6_RX_DP<101>")
	)
	(segment
		(start 401.299934 -316.115192)
		(end 401.299934 -315.849762)
		(width 0.1143)
		(layer "In5.Cu")
		(net "P5E_PEX3_STN6_RX_DP<101>")
	)
	(segment
		(start 380.766066 -368.637058)
		(end 379.652784 -367.454434)
		(width 0.1651)
		(layer "In5.Cu")
		(net "P5E_PEX3_STN6_RX_DP<101>")
	)
	(segment
		(start 378.386594 -366.239044)
		(end 378.390404 -366.113314)
		(width 0.1651)
		(layer "In5.Cu")
		(net "P5E_PEX3_STN6_RX_DP<101>")
	)
	(segment
		(start 372.608856 -359.971594)
		(end 369.864894 -351.950274)
		(width 0.1651)
		(layer "In5.Cu")
		(net "P5E_PEX3_STN6_RX_DP<101>")
	)
	(segment
		(start 370.764562 -340.834218)
		(end 398.981422 -322.175378)
		(width 0.1651)
		(layer "In5.Cu")
		(net "P5E_PEX3_STN6_RX_DP<101>")
	)
	(segment
		(start 376.736102 -364.355888)
		(end 372.608856 -359.971594)
		(width 0.1651)
		(layer "In5.Cu")
		(net "P5E_PEX3_STN6_RX_DP<101>")
	)
	(segment
		(start 377.907296 -365.74857)
		(end 377.567698 -365.387636)
		(width 0.1651)
		(layer "In5.Cu")
		(net "P5E_PEX3_STN6_RX_DP<101>")
	)
	(segment
		(start 379.89002 -374.390158)
		(end 379.89002 -374.729756)
		(width 0.1651)
		(layer "In5.Cu")
		(net "P5E_PEX3_STN6_RX_DP<101>")
	)
	(segment
		(start 379.187456 -367.08969)
		(end 379.191266 -366.964214)
		(width 0.1651)
		(layer "In5.Cu")
		(net "P5E_PEX3_STN6_RX_DP<101>")
	)
	(segment
		(start 380.063248 -374.902984)
		(end 380.43358 -374.902984)
		(width 0.1651)
		(layer "In5.Cu")
		(net "P5E_PEX3_STN6_RX_DP<101>")
	)
	(segment
		(start 401.185634 -316.229492)
		(end 401.299934 -316.115192)
		(width 0.1143)
		(layer "In5.Cu")
		(net "P5E_PEX3_STN6_RX_DP<101>")
	)
	(segment
		(start 369.864894 -351.950274)
		(end 369.764818 -342.575388)
		(width 0.1651)
		(layer "In5.Cu")
		(net "P5E_PEX3_STN6_RX_DP<101>")
	)
	(segment
		(start 380.766066 -374.570498)
		(end 380.766066 -368.637058)
		(width 0.1651)
		(layer "In5.Cu")
		(net "P5E_PEX3_STN6_RX_DP<101>")
	)
	(segment
		(start 377.567698 -365.387636)
		(end 377.572016 -365.243872)
		(width 0.1651)
		(layer "In5.Cu")
		(net "P5E_PEX3_STN6_RX_DP<101>")
	)
	(segment
		(start 400.729704 -316.455298)
		(end 400.95551 -316.229492)
		(width 0.1143)
		(layer "In5.Cu")
		(net "P5E_PEX3_STN6_RX_DP<101>")
	)
	(segment
		(start 398.981422 -322.175378)
		(end 400.683984 -320.472816)
		(width 0.1651)
		(layer "In5.Cu")
		(net "P5E_PEX3_STN6_RX_DP<101>")
	)
	(segment
		(start 189.357508 -101.84003)
		(end 190.634874 -101.84003)
		(width 0.13208)
		(layer "F.Cu")
		(net "NCSI_NIC3_RXD0")
	)
	(segment
		(start 190.634874 -101.84003)
		(end 191.283844 -102.489)
		(width 0.13208)
		(layer "F.Cu")
		(net "NCSI_NIC3_RXD0")
	)
	(via
		(at 191.283844 -102.489)
		(size 0.508)
		(drill 0.254)
		(layers "F.Cu" "B.Cu")
		(net "NCSI_NIC3_RXD0")
	)
	(segment
		(start 193.241676 -103.104696)
		(end 191.89954 -103.104696)
		(width 0.13208)
		(layer "B.Cu")
		(net "NCSI_NIC3_RXD0")
	)
	(segment
		(start 191.89954 -103.104696)
		(end 191.283844 -102.489)
		(width 0.13208)
		(layer "B.Cu")
		(net "NCSI_NIC3_RXD0")
	)
	(segment
		(start 126.125478 -32.14878)
		(end 125.454918 -32.14878)
		(width 0.13462)
		(layer "F.Cu")
		(net "P5E_PEX1_STN2_RX_DN<46>")
	)
	(segment
		(start 126.284228 -31.99003)
		(end 126.125478 -32.14878)
		(width 0.13462)
		(layer "F.Cu")
		(net "P5E_PEX1_STN2_RX_DN<46>")
	)
	(segment
		(start 126.76505 -31.99003)
		(end 126.284228 -31.99003)
		(width 0.13462)
		(layer "F.Cu")
		(net "P5E_PEX1_STN2_RX_DN<46>")
	)
	(segment
		(start 125.454918 -32.14878)
		(end 125.16485 -31.858712)
		(width 0.13462)
		(layer "F.Cu")
		(net "P5E_PEX1_STN2_RX_DN<46>")
	)
	(segment
		(start 126.544578 -32.663638)
		(end 126.507494 -35.04819)
		(width 0.1651)
		(layer "In7.Cu")
		(net "P5E_PEX1_STN2_RX_DN<46>")
	)
	(segment
		(start 161.120074 -275.275802)
		(end 161.22396 -275.379688)
		(width 0.1143)
		(layer "In7.Cu")
		(net "P5E_PEX1_STN2_RX_DN<46>")
	)
	(segment
		(start 161.385758 -275.379688)
		(end 161.500058 -275.265388)
		(width 0.1143)
		(layer "In7.Cu")
		(net "P5E_PEX1_STN2_RX_DN<46>")
	)
	(segment
		(start 161.165794 -270.38427)
		(end 161.165794 -271.392904)
		(width 0.1651)
		(layer "In7.Cu")
		(net "P5E_PEX1_STN2_RX_DN<46>")
	)
	(segment
		(start 132.493512 -102.603808)
		(end 137.692638 -119.756174)
		(width 0.1651)
		(layer "In7.Cu")
		(net "P5E_PEX1_STN2_RX_DN<46>")
	)
	(segment
		(start 127.205994 -57.201562)
		(end 127.486156 -60.294012)
		(width 0.1651)
		(layer "In7.Cu")
		(net "P5E_PEX1_STN2_RX_DN<46>")
	)
	(segment
		(start 161.22396 -275.379688)
		(end 161.385758 -275.379688)
		(width 0.1143)
		(layer "In7.Cu")
		(net "P5E_PEX1_STN2_RX_DN<46>")
	)
	(segment
		(start 158.67634 -238.303054)
		(end 160.26765 -255.686052)
		(width 0.1651)
		(layer "In7.Cu")
		(net "P5E_PEX1_STN2_RX_DN<46>")
	)
	(segment
		(start 140.967968 -144.657572)
		(end 158.67634 -238.303054)
		(width 0.1651)
		(layer "In7.Cu")
		(net "P5E_PEX1_STN2_RX_DN<46>")
	)
	(segment
		(start 127.486156 -62.000892)
		(end 127.294132 -85.450426)
		(width 0.1651)
		(layer "In7.Cu")
		(net "P5E_PEX1_STN2_RX_DN<46>")
	)
	(segment
		(start 161.165794 -271.392904)
		(end 161.165794 -271.421352)
		(width 0.1143)
		(layer "In7.Cu")
		(net "P5E_PEX1_STN2_RX_DN<46>")
	)
	(segment
		(start 126.507494 -35.04819)
		(end 125.984 -37.856414)
		(width 0.1651)
		(layer "In7.Cu")
		(net "P5E_PEX1_STN2_RX_DN<46>")
	)
	(segment
		(start 127.294132 -85.450426)
		(end 132.48132 -102.563168)
		(width 0.1651)
		(layer "In7.Cu")
		(net "P5E_PEX1_STN2_RX_DN<46>")
	)
	(segment
		(start 132.48132 -102.563168)
		(end 132.481574 -102.56393)
		(width 0.1651)
		(layer "In7.Cu")
		(net "P5E_PEX1_STN2_RX_DN<46>")
	)
	(segment
		(start 132.481574 -102.56393)
		(end 132.493512 -102.6033)
		(width 0.1651)
		(layer "In7.Cu")
		(net "P5E_PEX1_STN2_RX_DN<46>")
	)
	(segment
		(start 125.16485 -31.858712)
		(end 125.45568 -32.149542)
		(width 0.1651)
		(layer "In7.Cu")
		(net "P5E_PEX1_STN2_RX_DN<46>")
	)
	(segment
		(start 161.500058 -275.265388)
		(end 161.500058 -274.999958)
		(width 0.1143)
		(layer "In7.Cu")
		(net "P5E_PEX1_STN2_RX_DN<46>")
	)
	(segment
		(start 137.692638 -119.756174)
		(end 140.967968 -144.657572)
		(width 0.1651)
		(layer "In7.Cu")
		(net "P5E_PEX1_STN2_RX_DN<46>")
	)
	(segment
		(start 161.120074 -271.467072)
		(end 161.120074 -275.275802)
		(width 0.1143)
		(layer "In7.Cu")
		(net "P5E_PEX1_STN2_RX_DN<46>")
	)
	(segment
		(start 125.984 -37.856414)
		(end 126.020322 -40.147748)
		(width 0.1651)
		(layer "In7.Cu")
		(net "P5E_PEX1_STN2_RX_DN<46>")
	)
	(segment
		(start 160.190688 -263.518142)
		(end 161.165794 -270.38427)
		(width 0.1651)
		(layer "In7.Cu")
		(net "P5E_PEX1_STN2_RX_DN<46>")
	)
	(segment
		(start 132.493512 -102.6033)
		(end 132.493512 -102.603808)
		(width 0.1651)
		(layer "In7.Cu")
		(net "P5E_PEX1_STN2_RX_DN<46>")
	)
	(segment
		(start 160.26765 -255.686052)
		(end 160.190688 -263.518142)
		(width 0.1651)
		(layer "In7.Cu")
		(net "P5E_PEX1_STN2_RX_DN<46>")
	)
	(segment
		(start 127.486156 -60.294012)
		(end 127.486156 -62.000892)
		(width 0.1651)
		(layer "In7.Cu")
		(net "P5E_PEX1_STN2_RX_DN<46>")
	)
	(segment
		(start 127.322072 -49.782222)
		(end 127.205994 -57.201562)
		(width 0.1651)
		(layer "In7.Cu")
		(net "P5E_PEX1_STN2_RX_DN<46>")
	)
	(segment
		(start 126.020322 -40.147748)
		(end 127.322072 -49.782222)
		(width 0.1651)
		(layer "In7.Cu")
		(net "P5E_PEX1_STN2_RX_DN<46>")
	)
	(segment
		(start 161.165794 -271.421352)
		(end 161.120074 -271.467072)
		(width 0.1143)
		(layer "In7.Cu")
		(net "P5E_PEX1_STN2_RX_DN<46>")
	)
	(segment
		(start 125.45568 -32.149542)
		(end 126.030228 -32.149542)
		(width 0.1651)
		(layer "In7.Cu")
		(net "P5E_PEX1_STN2_RX_DN<46>")
	)
	(segment
		(start 126.030228 -32.149542)
		(end 126.544578 -32.663638)
		(width 0.1651)
		(layer "In7.Cu")
		(net "P5E_PEX1_STN2_RX_DN<46>")
	)
	(segment
		(start 299.257212 -122.30354)
		(end 299.551852 -122.59818)
		(width 0.13462)
		(layer "F.Cu")
		(net "P5E_PEX2_STN0_RX_DN<2>")
	)
	(segment
		(start 300.376336 -122.435112)
		(end 300.857412 -122.435112)
		(width 0.13462)
		(layer "F.Cu")
		(net "P5E_PEX2_STN0_RX_DN<2>")
	)
	(segment
		(start 299.551852 -122.59818)
		(end 300.213268 -122.59818)
		(width 0.13462)
		(layer "F.Cu")
		(net "P5E_PEX2_STN0_RX_DN<2>")
	)
	(segment
		(start 300.213268 -122.59818)
		(end 300.376336 -122.435112)
		(width 0.13462)
		(layer "F.Cu")
		(net "P5E_PEX2_STN0_RX_DN<2>")
	)
	(segment
		(start 317.719202 -286.034226)
		(end 317.687706 -286.065722)
		(width 0.1651)
		(layer "In5.Cu")
		(net "P5E_PEX2_STN0_RX_DN<2>")
	)
	(segment
		(start 306.80406 -126.48184)
		(end 311.8485 -134.04088)
		(width 0.1651)
		(layer "In5.Cu")
		(net "P5E_PEX2_STN0_RX_DN<2>")
	)
	(segment
		(start 304.8889 -124.55398)
		(end 306.80406 -126.48184)
		(width 0.1651)
		(layer "In5.Cu")
		(net "P5E_PEX2_STN0_RX_DN<2>")
	)
	(segment
		(start 319.846452 -149.960838)
		(end 320.342514 -168.455086)
		(width 0.1651)
		(layer "In5.Cu")
		(net "P5E_PEX2_STN0_RX_DN<2>")
	)
	(segment
		(start 312.484262 -286.399732)
		(end 312.749692 -286.399732)
		(width 0.1143)
		(layer "In5.Cu")
		(net "P5E_PEX2_STN0_RX_DN<2>")
	)
	(segment
		(start 329.76693 -273.153378)
		(end 327.438512 -277.258272)
		(width 0.1651)
		(layer "In5.Cu")
		(net "P5E_PEX2_STN0_RX_DN<2>")
	)
	(segment
		(start 318.935608 -143.552926)
		(end 319.846452 -149.960838)
		(width 0.1651)
		(layer "In5.Cu")
		(net "P5E_PEX2_STN0_RX_DN<2>")
	)
	(segment
		(start 321.283838 -239.882426)
		(end 329.935332 -269.474696)
		(width 0.1651)
		(layer "In5.Cu")
		(net "P5E_PEX2_STN0_RX_DN<2>")
	)
	(segment
		(start 300.174406 -122.59437)
		(end 304.8889 -124.55398)
		(width 0.1651)
		(layer "In5.Cu")
		(net "P5E_PEX2_STN0_RX_DN<2>")
	)
	(segment
		(start 327.438512 -277.258272)
		(end 319.140332 -285.298642)
		(width 0.1651)
		(layer "In5.Cu")
		(net "P5E_PEX2_STN0_RX_DN<2>")
	)
	(segment
		(start 319.63614 -232.139744)
		(end 321.283838 -239.882426)
		(width 0.1651)
		(layer "In5.Cu")
		(net "P5E_PEX2_STN0_RX_DN<2>")
	)
	(segment
		(start 329.935332 -269.474696)
		(end 329.76693 -273.153378)
		(width 0.1651)
		(layer "In5.Cu")
		(net "P5E_PEX2_STN0_RX_DN<2>")
	)
	(segment
		(start 299.257212 -122.30354)
		(end 299.548042 -122.59437)
		(width 0.1651)
		(layer "In5.Cu")
		(net "P5E_PEX2_STN0_RX_DN<2>")
	)
	(segment
		(start 319.140332 -285.298642)
		(end 317.719202 -286.034226)
		(width 0.1651)
		(layer "In5.Cu")
		(net "P5E_PEX2_STN0_RX_DN<2>")
	)
	(segment
		(start 312.369962 -286.285432)
		(end 312.484262 -286.399732)
		(width 0.1143)
		(layer "In5.Cu")
		(net "P5E_PEX2_STN0_RX_DN<2>")
	)
	(segment
		(start 317.687706 -286.065722)
		(end 316.12459 -286.065722)
		(width 0.1651)
		(layer "In5.Cu")
		(net "P5E_PEX2_STN0_RX_DN<2>")
	)
	(segment
		(start 299.548042 -122.59437)
		(end 300.174406 -122.59437)
		(width 0.1651)
		(layer "In5.Cu")
		(net "P5E_PEX2_STN0_RX_DN<2>")
	)
	(segment
		(start 312.369962 -286.15259)
		(end 312.369962 -286.285432)
		(width 0.1143)
		(layer "In5.Cu")
		(net "P5E_PEX2_STN0_RX_DN<2>")
	)
	(segment
		(start 316.096142 -286.065722)
		(end 316.050422 -286.020002)
		(width 0.1143)
		(layer "In5.Cu")
		(net "P5E_PEX2_STN0_RX_DN<2>")
	)
	(segment
		(start 316.12459 -286.065722)
		(end 316.096142 -286.065722)
		(width 0.1143)
		(layer "In5.Cu")
		(net "P5E_PEX2_STN0_RX_DN<2>")
	)
	(segment
		(start 316.050422 -286.020002)
		(end 312.50255 -286.020002)
		(width 0.1143)
		(layer "In5.Cu")
		(net "P5E_PEX2_STN0_RX_DN<2>")
	)
	(segment
		(start 316.143386 -138.329924)
		(end 318.935608 -143.552926)
		(width 0.1651)
		(layer "In5.Cu")
		(net "P5E_PEX2_STN0_RX_DN<2>")
	)
	(segment
		(start 312.50255 -286.020002)
		(end 312.369962 -286.15259)
		(width 0.1143)
		(layer "In5.Cu")
		(net "P5E_PEX2_STN0_RX_DN<2>")
	)
	(segment
		(start 311.8485 -134.04088)
		(end 316.143386 -138.329924)
		(width 0.1651)
		(layer "In5.Cu")
		(net "P5E_PEX2_STN0_RX_DN<2>")
	)
	(segment
		(start 320.342514 -168.455086)
		(end 319.63614 -232.139744)
		(width 0.1651)
		(layer "In5.Cu")
		(net "P5E_PEX2_STN0_RX_DN<2>")
	)
	(segment
		(start 322.693284 -351.611438)
		(end 322.398644 -351.316798)
		(width 0.13462)
		(layer "F.Cu")
		(net "P5E_PEX2_STN6_TX_C_DN<107>")
	)
	(segment
		(start 322.398644 -350.685354)
		(end 322.718684 -350.365314)
		(width 0.13462)
		(layer "F.Cu")
		(net "P5E_PEX2_STN6_TX_C_DN<107>")
	)
	(segment
		(start 322.398644 -351.316798)
		(end 322.398644 -350.685354)
		(width 0.13462)
		(layer "F.Cu")
		(net "P5E_PEX2_STN6_TX_C_DN<107>")
	)
	(segment
		(start 340.41715 -408.981148)
		(end 340.964266 -408.981148)
		(width 0.1651)
		(layer "In13.Cu")
		(net "P5E_PEX2_STN6_TX_C_DN<107>")
	)
	(segment
		(start 340.964266 -408.981148)
		(end 341.416132 -408.529282)
		(width 0.1651)
		(layer "In13.Cu")
		(net "P5E_PEX2_STN6_TX_C_DN<107>")
	)
	(segment
		(start 320.847974 -354.027486)
		(end 322.402454 -352.473006)
		(width 0.1651)
		(layer "In13.Cu")
		(net "P5E_PEX2_STN6_TX_C_DN<107>")
	)
	(segment
		(start 330.464922 -388.929118)
		(end 327.699624 -386.745226)
		(width 0.1651)
		(layer "In13.Cu")
		(net "P5E_PEX2_STN6_TX_C_DN<107>")
	)
	(segment
		(start 341.060278 -394.31849)
		(end 336.92465 -391.239756)
		(width 0.1651)
		(layer "In13.Cu")
		(net "P5E_PEX2_STN6_TX_C_DN<107>")
	)
	(segment
		(start 340.29015 -409.490164)
		(end 340.29015 -409.108148)
		(width 0.1651)
		(layer "In13.Cu")
		(net "P5E_PEX2_STN6_TX_C_DN<107>")
	)
	(segment
		(start 336.92465 -391.239756)
		(end 330.464922 -388.929118)
		(width 0.1651)
		(layer "In13.Cu")
		(net "P5E_PEX2_STN6_TX_C_DN<107>")
	)
	(segment
		(start 320.847974 -358.902)
		(end 320.847974 -354.027486)
		(width 0.1651)
		(layer "In13.Cu")
		(net "P5E_PEX2_STN6_TX_C_DN<107>")
	)
	(segment
		(start 341.416132 -394.968984)
		(end 341.060278 -394.31849)
		(width 0.1651)
		(layer "In13.Cu")
		(net "P5E_PEX2_STN6_TX_C_DN<107>")
	)
	(segment
		(start 341.416132 -408.529282)
		(end 341.416132 -394.968984)
		(width 0.1651)
		(layer "In13.Cu")
		(net "P5E_PEX2_STN6_TX_C_DN<107>")
	)
	(segment
		(start 322.402454 -351.902268)
		(end 322.693284 -351.611438)
		(width 0.1651)
		(layer "In13.Cu")
		(net "P5E_PEX2_STN6_TX_C_DN<107>")
	)
	(segment
		(start 322.402454 -352.473006)
		(end 322.402454 -351.902268)
		(width 0.1651)
		(layer "In13.Cu")
		(net "P5E_PEX2_STN6_TX_C_DN<107>")
	)
	(segment
		(start 327.699624 -386.745226)
		(end 320.847974 -358.902)
		(width 0.1651)
		(layer "In13.Cu")
		(net "P5E_PEX2_STN6_TX_C_DN<107>")
	)
	(segment
		(start 340.29015 -409.108148)
		(end 340.41715 -408.981148)
		(width 0.1651)
		(layer "In13.Cu")
		(net "P5E_PEX2_STN6_TX_C_DN<107>")
	)
	(segment
		(start 399.42516 -130.565144)
		(end 398.94256 -130.565144)
		(width 0.13462)
		(layer "F.Cu")
		(net "P5E_PEX3_STN1_RX_DP<28>")
	)
	(segment
		(start 402.10359 -130.72618)
		(end 399.586196 -130.72618)
		(width 0.13462)
		(layer "F.Cu")
		(net "P5E_PEX3_STN1_RX_DP<28>")
	)
	(segment
		(start 402.39696 -130.43281)
		(end 402.10359 -130.72618)
		(width 0.13462)
		(layer "F.Cu")
		(net "P5E_PEX3_STN1_RX_DP<28>")
	)
	(segment
		(start 399.586196 -130.72618)
		(end 399.42516 -130.565144)
		(width 0.13462)
		(layer "F.Cu")
		(net "P5E_PEX3_STN1_RX_DP<28>")
	)
	(segment
		(start 418.733986 -267.64234)
		(end 418.733986 -271.526)
		(width 0.1651)
		(layer "In5.Cu")
		(net "P5E_PEX3_STN1_RX_DP<28>")
	)
	(segment
		(start 418.779706 -271.600168)
		(end 418.779706 -273.45513)
		(width 0.1143)
		(layer "In5.Cu")
		(net "P5E_PEX3_STN1_RX_DP<28>")
	)
	(segment
		(start 394.965682 -141.594078)
		(end 392.09218 -143.514318)
		(width 0.1651)
		(layer "In5.Cu")
		(net "P5E_PEX3_STN1_RX_DP<28>")
	)
	(segment
		(start 418.733986 -271.526)
		(end 418.733986 -271.554448)
		(width 0.1143)
		(layer "In5.Cu")
		(net "P5E_PEX3_STN1_RX_DP<28>")
	)
	(segment
		(start 390.971278 -144.635982)
		(end 389.254492 -146.953732)
		(width 0.1651)
		(layer "In5.Cu")
		(net "P5E_PEX3_STN1_RX_DP<28>")
	)
	(segment
		(start 396.464536 -135.360156)
		(end 396.464282 -135.36041)
		(width 0.1651)
		(layer "In5.Cu")
		(net "P5E_PEX3_STN1_RX_DP<28>")
	)
	(segment
		(start 419.349682 -273.784314)
		(end 419.349682 -274.049744)
		(width 0.1143)
		(layer "In5.Cu")
		(net "P5E_PEX3_STN1_RX_DP<28>")
	)
	(segment
		(start 392.09218 -143.514318)
		(end 390.971278 -144.635982)
		(width 0.1651)
		(layer "In5.Cu")
		(net "P5E_PEX3_STN1_RX_DP<28>")
	)
	(segment
		(start 402.10613 -130.72364)
		(end 399.382996 -130.72364)
		(width 0.1651)
		(layer "In5.Cu")
		(net "P5E_PEX3_STN1_RX_DP<28>")
	)
	(segment
		(start 419.235382 -273.670014)
		(end 419.349682 -273.784314)
		(width 0.1143)
		(layer "In5.Cu")
		(net "P5E_PEX3_STN1_RX_DP<28>")
	)
	(segment
		(start 399.382996 -130.72364)
		(end 397.368776 -133.177026)
		(width 0.1651)
		(layer "In5.Cu")
		(net "P5E_PEX3_STN1_RX_DP<28>")
	)
	(segment
		(start 389.254492 -146.953732)
		(end 389.059674 -147.65528)
		(width 0.1651)
		(layer "In5.Cu")
		(net "P5E_PEX3_STN1_RX_DP<28>")
	)
	(segment
		(start 397.368776 -133.177026)
		(end 396.464536 -135.360156)
		(width 0.1651)
		(layer "In5.Cu")
		(net "P5E_PEX3_STN1_RX_DP<28>")
	)
	(segment
		(start 390.416288 -161.20364)
		(end 418.733986 -267.64234)
		(width 0.1651)
		(layer "In5.Cu")
		(net "P5E_PEX3_STN1_RX_DP<28>")
	)
	(segment
		(start 389.059674 -147.65528)
		(end 389.658098 -156.926026)
		(width 0.1651)
		(layer "In5.Cu")
		(net "P5E_PEX3_STN1_RX_DP<28>")
	)
	(segment
		(start 396.014702 -136.446514)
		(end 396.014702 -140.292328)
		(width 0.1651)
		(layer "In5.Cu")
		(net "P5E_PEX3_STN1_RX_DP<28>")
	)
	(segment
		(start 418.733986 -271.554448)
		(end 418.779706 -271.600168)
		(width 0.1143)
		(layer "In5.Cu")
		(net "P5E_PEX3_STN1_RX_DP<28>")
	)
	(segment
		(start 418.779706 -273.45513)
		(end 418.99459 -273.670014)
		(width 0.1143)
		(layer "In5.Cu")
		(net "P5E_PEX3_STN1_RX_DP<28>")
	)
	(segment
		(start 389.658098 -156.926026)
		(end 390.416288 -161.20364)
		(width 0.1651)
		(layer "In5.Cu")
		(net "P5E_PEX3_STN1_RX_DP<28>")
	)
	(segment
		(start 418.99459 -273.670014)
		(end 419.235382 -273.670014)
		(width 0.1143)
		(layer "In5.Cu")
		(net "P5E_PEX3_STN1_RX_DP<28>")
	)
	(segment
		(start 395.836394 -140.723366)
		(end 394.965682 -141.594078)
		(width 0.1651)
		(layer "In5.Cu")
		(net "P5E_PEX3_STN1_RX_DP<28>")
	)
	(segment
		(start 402.39696 -130.43281)
		(end 402.10613 -130.72364)
		(width 0.1651)
		(layer "In5.Cu")
		(net "P5E_PEX3_STN1_RX_DP<28>")
	)
	(segment
		(start 396.014702 -140.292328)
		(end 395.836394 -140.723366)
		(width 0.1651)
		(layer "In5.Cu")
		(net "P5E_PEX3_STN1_RX_DP<28>")
	)
	(segment
		(start 396.464282 -135.36041)
		(end 396.014702 -136.446514)
		(width 0.1651)
		(layer "In5.Cu")
		(net "P5E_PEX3_STN1_RX_DP<28>")
	)
	(segment
		(start 377.975368 -351.317306)
		(end 378.2695 -351.611438)
		(width 0.13462)
		(layer "F.Cu")
		(net "P5E_PEX3_STN6_TX_C_DN<100>")
	)
	(segment
		(start 378.2949 -350.365314)
		(end 377.975368 -350.684846)
		(width 0.13462)
		(layer "F.Cu")
		(net "P5E_PEX3_STN6_TX_C_DN<100>")
	)
	(segment
		(start 377.975368 -350.684846)
		(end 377.975368 -351.317306)
		(width 0.13462)
		(layer "F.Cu")
		(net "P5E_PEX3_STN6_TX_C_DN<100>")
	)
	(segment
		(start 382.76403 -384.08102)
		(end 382.216914 -384.08102)
		(width 0.1651)
		(layer "In7.Cu")
		(net "P5E_PEX3_STN6_TX_C_DN<100>")
	)
	(segment
		(start 376.42419 -354.027486)
		(end 376.42419 -358.43464)
		(width 0.1651)
		(layer "In7.Cu")
		(net "P5E_PEX3_STN6_TX_C_DN<100>")
	)
	(segment
		(start 378.2695 -351.611438)
		(end 377.97867 -351.902268)
		(width 0.1651)
		(layer "In7.Cu")
		(net "P5E_PEX3_STN6_TX_C_DN<100>")
	)
	(segment
		(start 382.216914 -384.08102)
		(end 382.089914 -384.20802)
		(width 0.1651)
		(layer "In7.Cu")
		(net "P5E_PEX3_STN6_TX_C_DN<100>")
	)
	(segment
		(start 377.97867 -351.902268)
		(end 377.97867 -352.473006)
		(width 0.1651)
		(layer "In7.Cu")
		(net "P5E_PEX3_STN6_TX_C_DN<100>")
	)
	(segment
		(start 382.089914 -384.20802)
		(end 382.089914 -384.590036)
		(width 0.1651)
		(layer "In7.Cu")
		(net "P5E_PEX3_STN6_TX_C_DN<100>")
	)
	(segment
		(start 383.215896 -383.629154)
		(end 382.76403 -384.08102)
		(width 0.1651)
		(layer "In7.Cu")
		(net "P5E_PEX3_STN6_TX_C_DN<100>")
	)
	(segment
		(start 376.42419 -358.43464)
		(end 383.215896 -368.81054)
		(width 0.1651)
		(layer "In7.Cu")
		(net "P5E_PEX3_STN6_TX_C_DN<100>")
	)
	(segment
		(start 377.97867 -352.473006)
		(end 376.42419 -354.027486)
		(width 0.1651)
		(layer "In7.Cu")
		(net "P5E_PEX3_STN6_TX_C_DN<100>")
	)
	(segment
		(start 383.215896 -368.81054)
		(end 383.215896 -383.629154)
		(width 0.1651)
		(layer "In7.Cu")
		(net "P5E_PEX3_STN6_TX_C_DN<100>")
	)
	(segment
		(start 10.664952 -32.589978)
		(end 10.185654 -32.589978)
		(width 0.13462)
		(layer "F.Cu")
		(net "P5E_PEX0_STN2_RX_DP<46>")
	)
	(segment
		(start 10.185654 -32.589978)
		(end 10.018776 -32.4231)
		(width 0.13462)
		(layer "F.Cu")
		(net "P5E_PEX0_STN2_RX_DP<46>")
	)
	(segment
		(start 9.363964 -32.4231)
		(end 9.064752 -32.722312)
		(width 0.13462)
		(layer "F.Cu")
		(net "P5E_PEX0_STN2_RX_DP<46>")
	)
	(segment
		(start 10.018776 -32.4231)
		(end 9.363964 -32.4231)
		(width 0.13462)
		(layer "F.Cu")
		(net "P5E_PEX0_STN2_RX_DP<46>")
	)
	(segment
		(start 10.02284 -35.572446)
		(end 9.903968 -35.653726)
		(width 0.1651)
		(layer "In7.Cu")
		(net "P5E_PEX0_STN2_RX_DP<46>")
	)
	(segment
		(start 16.123412 -102.685088)
		(end 16.123666 -102.68585)
		(width 0.1651)
		(layer "In7.Cu")
		(net "P5E_PEX0_STN2_RX_DP<46>")
	)
	(segment
		(start 21.315934 -119.815864)
		(end 24.589232 -144.702276)
		(width 0.1651)
		(layer "In7.Cu")
		(net "P5E_PEX0_STN2_RX_DP<46>")
	)
	(segment
		(start 44.829476 -275.354796)
		(end 45.044868 -275.570188)
		(width 0.1143)
		(layer "In7.Cu")
		(net "P5E_PEX0_STN2_RX_DP<46>")
	)
	(segment
		(start 44.829476 -271.467072)
		(end 44.829476 -275.354796)
		(width 0.1143)
		(layer "In7.Cu")
		(net "P5E_PEX0_STN2_RX_DP<46>")
	)
	(segment
		(start 9.638538 -40.16883)
		(end 10.939526 -49.798986)
		(width 0.1651)
		(layer "In7.Cu")
		(net "P5E_PEX0_STN2_RX_DP<46>")
	)
	(segment
		(start 43.808396 -263.536684)
		(end 44.783756 -270.404336)
		(width 0.1651)
		(layer "In7.Cu")
		(net "P5E_PEX0_STN2_RX_DP<46>")
	)
	(segment
		(start 9.355582 -32.431482)
		(end 9.81329 -32.431482)
		(width 0.1651)
		(layer "In7.Cu")
		(net "P5E_PEX0_STN2_RX_DP<46>")
	)
	(segment
		(start 24.589232 -144.702276)
		(end 42.296588 -238.34217)
		(width 0.1651)
		(layer "In7.Cu")
		(net "P5E_PEX0_STN2_RX_DP<46>")
	)
	(segment
		(start 10.939526 -49.798986)
		(end 10.823702 -57.21223)
		(width 0.1651)
		(layer "In7.Cu")
		(net "P5E_PEX0_STN2_RX_DP<46>")
	)
	(segment
		(start 10.036302 -34.231834)
		(end 10.136124 -34.334958)
		(width 0.1651)
		(layer "In7.Cu")
		(net "P5E_PEX0_STN2_RX_DP<46>")
	)
	(segment
		(start 45.39996 -275.684488)
		(end 45.39996 -275.949918)
		(width 0.1143)
		(layer "In7.Cu")
		(net "P5E_PEX0_STN2_RX_DP<46>")
	)
	(segment
		(start 10.911586 -85.491066)
		(end 16.111474 -102.64521)
		(width 0.1651)
		(layer "In7.Cu")
		(net "P5E_PEX0_STN2_RX_DP<46>")
	)
	(segment
		(start 45.28566 -275.570188)
		(end 45.39996 -275.684488)
		(width 0.1143)
		(layer "In7.Cu")
		(net "P5E_PEX0_STN2_RX_DP<46>")
	)
	(segment
		(start 10.823702 -57.21223)
		(end 11.104118 -60.306966)
		(width 0.1651)
		(layer "In7.Cu")
		(net "P5E_PEX0_STN2_RX_DP<46>")
	)
	(segment
		(start 11.104118 -61.796676)
		(end 10.911586 -85.491066)
		(width 0.1651)
		(layer "In7.Cu")
		(net "P5E_PEX0_STN2_RX_DP<46>")
	)
	(segment
		(start 10.1473 -33.636458)
		(end 10.043922 -33.73628)
		(width 0.1651)
		(layer "In7.Cu")
		(net "P5E_PEX0_STN2_RX_DP<46>")
	)
	(segment
		(start 9.601454 -37.832538)
		(end 9.638538 -40.16883)
		(width 0.1651)
		(layer "In7.Cu")
		(net "P5E_PEX0_STN2_RX_DP<46>")
	)
	(segment
		(start 10.136124 -34.334958)
		(end 10.12571 -35.019996)
		(width 0.1651)
		(layer "In7.Cu")
		(net "P5E_PEX0_STN2_RX_DP<46>")
	)
	(segment
		(start 16.123666 -102.68585)
		(end 21.315934 -119.815864)
		(width 0.1651)
		(layer "In7.Cu")
		(net "P5E_PEX0_STN2_RX_DP<46>")
	)
	(segment
		(start 10.160508 -32.7787)
		(end 10.1473 -33.636458)
		(width 0.1651)
		(layer "In7.Cu")
		(net "P5E_PEX0_STN2_RX_DP<46>")
	)
	(segment
		(start 16.111474 -102.645718)
		(end 16.123412 -102.685088)
		(width 0.1651)
		(layer "In7.Cu")
		(net "P5E_PEX0_STN2_RX_DP<46>")
	)
	(segment
		(start 10.12571 -35.019996)
		(end 10.02284 -35.572446)
		(width 0.1651)
		(layer "In7.Cu")
		(net "P5E_PEX0_STN2_RX_DP<46>")
	)
	(segment
		(start 9.903968 -35.653726)
		(end 9.81329 -36.140898)
		(width 0.1651)
		(layer "In7.Cu")
		(net "P5E_PEX0_STN2_RX_DP<46>")
	)
	(segment
		(start 44.783756 -271.392904)
		(end 44.783756 -271.421352)
		(width 0.1143)
		(layer "In7.Cu")
		(net "P5E_PEX0_STN2_RX_DP<46>")
	)
	(segment
		(start 42.69359 -242.68049)
		(end 43.885358 -255.697482)
		(width 0.1651)
		(layer "In7.Cu")
		(net "P5E_PEX0_STN2_RX_DP<46>")
	)
	(segment
		(start 42.693336 -242.68049)
		(end 42.69359 -242.68049)
		(width 0.1651)
		(layer "In7.Cu")
		(net "P5E_PEX0_STN2_RX_DP<46>")
	)
	(segment
		(start 42.296588 -238.34217)
		(end 42.693336 -242.68049)
		(width 0.1651)
		(layer "In7.Cu")
		(net "P5E_PEX0_STN2_RX_DP<46>")
	)
	(segment
		(start 43.885358 -255.697482)
		(end 43.808396 -263.536684)
		(width 0.1651)
		(layer "In7.Cu")
		(net "P5E_PEX0_STN2_RX_DP<46>")
	)
	(segment
		(start 16.111474 -102.64521)
		(end 16.111474 -102.645718)
		(width 0.1651)
		(layer "In7.Cu")
		(net "P5E_PEX0_STN2_RX_DP<46>")
	)
	(segment
		(start 9.064752 -32.722312)
		(end 9.355582 -32.431482)
		(width 0.1651)
		(layer "In7.Cu")
		(net "P5E_PEX0_STN2_RX_DP<46>")
	)
	(segment
		(start 44.783756 -271.421352)
		(end 44.829476 -271.467072)
		(width 0.1143)
		(layer "In7.Cu")
		(net "P5E_PEX0_STN2_RX_DP<46>")
	)
	(segment
		(start 10.043922 -33.73628)
		(end 10.036302 -34.231834)
		(width 0.1651)
		(layer "In7.Cu")
		(net "P5E_PEX0_STN2_RX_DP<46>")
	)
	(segment
		(start 11.104118 -60.306966)
		(end 11.104118 -61.796676)
		(width 0.1651)
		(layer "In7.Cu")
		(net "P5E_PEX0_STN2_RX_DP<46>")
	)
	(segment
		(start 9.81329 -36.140898)
		(end 9.89457 -36.259516)
		(width 0.1651)
		(layer "In7.Cu")
		(net "P5E_PEX0_STN2_RX_DP<46>")
	)
	(segment
		(start 45.044868 -275.570188)
		(end 45.28566 -275.570188)
		(width 0.1143)
		(layer "In7.Cu")
		(net "P5E_PEX0_STN2_RX_DP<46>")
	)
	(segment
		(start 44.783756 -270.404336)
		(end 44.783756 -271.392904)
		(width 0.1651)
		(layer "In7.Cu")
		(net "P5E_PEX0_STN2_RX_DP<46>")
	)
	(segment
		(start 9.81329 -32.431482)
		(end 10.160508 -32.7787)
		(width 0.1651)
		(layer "In7.Cu")
		(net "P5E_PEX0_STN2_RX_DP<46>")
	)
	(segment
		(start 9.89457 -36.259516)
		(end 9.601454 -37.832538)
		(width 0.1651)
		(layer "In7.Cu")
		(net "P5E_PEX0_STN2_RX_DP<46>")
	)
	(segment
		(start 136.267952 -30.03169)
		(end 135.941562 -30.35808)
		(width 0.13462)
		(layer "F.Cu")
		(net "P5E_PEX1_STN2_TX_C_DN<45>")
	)
	(segment
		(start 131.868164 -30.190186)
		(end 131.36499 -30.190186)
		(width 0.13462)
		(layer "F.Cu")
		(net "P5E_PEX1_STN2_TX_C_DN<45>")
	)
	(segment
		(start 135.941562 -30.35808)
		(end 132.036058 -30.35808)
		(width 0.13462)
		(layer "F.Cu")
		(net "P5E_PEX1_STN2_TX_C_DN<45>")
	)
	(segment
		(start 132.036058 -30.35808)
		(end 131.868164 -30.190186)
		(width 0.13462)
		(layer "F.Cu")
		(net "P5E_PEX1_STN2_TX_C_DN<45>")
	)
	(segment
		(start 314.594748 -152.511252)
		(end 314.280296 -152.1968)
		(width 0.13462)
		(layer "F.Cu")
		(net "P5E_PEX2_STN0_TX_C_DP<13>")
	)
	(segment
		(start 305.960272 -152.355042)
		(end 305.457606 -152.355042)
		(width 0.13462)
		(layer "F.Cu")
		(net "P5E_PEX2_STN0_TX_C_DP<13>")
	)
	(segment
		(start 314.280296 -152.1968)
		(end 306.118514 -152.1968)
		(width 0.13462)
		(layer "F.Cu")
		(net "P5E_PEX2_STN0_TX_C_DP<13>")
	)
	(segment
		(start 306.118514 -152.1968)
		(end 305.960272 -152.355042)
		(width 0.13462)
		(layer "F.Cu")
		(net "P5E_PEX2_STN0_TX_C_DP<13>")
	)
	(segment
		(start 344.161364 -344.539062)
		(end 344.161364 -345.170506)
		(width 0.13462)
		(layer "F.Cu")
		(net "P5E_PEX2_STN6_TX_C_DN<97>")
	)
	(segment
		(start 344.481404 -344.219022)
		(end 344.161364 -344.539062)
		(width 0.13462)
		(layer "F.Cu")
		(net "P5E_PEX2_STN6_TX_C_DN<97>")
	)
	(segment
		(start 344.161364 -345.170506)
		(end 344.456004 -345.465146)
		(width 0.13462)
		(layer "F.Cu")
		(net "P5E_PEX2_STN6_TX_C_DN<97>")
	)
	(segment
		(start 345.81592 -382.529334)
		(end 345.81592 -368.80038)
		(width 0.1651)
		(layer "In13.Cu")
		(net "P5E_PEX2_STN6_TX_C_DN<97>")
	)
	(segment
		(start 345.81592 -368.80038)
		(end 342.610694 -358.9528)
		(width 0.1651)
		(layer "In13.Cu")
		(net "P5E_PEX2_STN6_TX_C_DN<97>")
	)
	(segment
		(start 345.364054 -382.9812)
		(end 345.81592 -382.529334)
		(width 0.1651)
		(layer "In13.Cu")
		(net "P5E_PEX2_STN6_TX_C_DN<97>")
	)
	(segment
		(start 342.610694 -347.881194)
		(end 344.165174 -346.326714)
		(width 0.1651)
		(layer "In13.Cu")
		(net "P5E_PEX2_STN6_TX_C_DN<97>")
	)
	(segment
		(start 344.165174 -345.755976)
		(end 344.456004 -345.465146)
		(width 0.1651)
		(layer "In13.Cu")
		(net "P5E_PEX2_STN6_TX_C_DN<97>")
	)
	(segment
		(start 342.610694 -358.9528)
		(end 342.610694 -347.881194)
		(width 0.1651)
		(layer "In13.Cu")
		(net "P5E_PEX2_STN6_TX_C_DN<97>")
	)
	(segment
		(start 344.689938 -383.490216)
		(end 344.689938 -383.1082)
		(width 0.1651)
		(layer "In13.Cu")
		(net "P5E_PEX2_STN6_TX_C_DN<97>")
	)
	(segment
		(start 344.689938 -383.1082)
		(end 344.816938 -382.9812)
		(width 0.1651)
		(layer "In13.Cu")
		(net "P5E_PEX2_STN6_TX_C_DN<97>")
	)
	(segment
		(start 344.165174 -346.326714)
		(end 344.165174 -345.755976)
		(width 0.1651)
		(layer "In13.Cu")
		(net "P5E_PEX2_STN6_TX_C_DN<97>")
	)
	(segment
		(start 344.816938 -382.9812)
		(end 345.364054 -382.9812)
		(width 0.1651)
		(layer "In13.Cu")
		(net "P5E_PEX2_STN6_TX_C_DN<97>")
	)
	(segment
		(start 399.592292 -101.6762)
		(end 399.423382 -101.84511)
		(width 0.13462)
		(layer "F.Cu")
		(net "P5E_PEX3_STN1_RX_DN<17>")
	)
	(segment
		(start 399.423382 -101.84511)
		(end 398.94256 -101.84511)
		(width 0.13462)
		(layer "F.Cu")
		(net "P5E_PEX3_STN1_RX_DN<17>")
	)
	(segment
		(start 400.242532 -101.6762)
		(end 399.592292 -101.6762)
		(width 0.13462)
		(layer "F.Cu")
		(net "P5E_PEX3_STN1_RX_DN<17>")
	)
	(segment
		(start 400.54276 -101.976428)
		(end 400.242532 -101.6762)
		(width 0.13462)
		(layer "F.Cu")
		(net "P5E_PEX3_STN1_RX_DN<17>")
	)
	(segment
		(start 396.841726 -103.541068)
		(end 396.686024 -103.498396)
		(width 0.1651)
		(layer "In5.Cu")
		(net "P5E_PEX3_STN1_RX_DN<17>")
	)
	(segment
		(start 381.866902 -117.307614)
		(end 380.531624 -119.95023)
		(width 0.1651)
		(layer "In5.Cu")
		(net "P5E_PEX3_STN1_RX_DN<17>")
	)
	(segment
		(start 379.041152 -126.612142)
		(end 377.61799 -150.180294)
		(width 0.1651)
		(layer "In5.Cu")
		(net "P5E_PEX3_STN1_RX_DN<17>")
	)
	(segment
		(start 390.173718 -108.808012)
		(end 390.012174 -108.811314)
		(width 0.1651)
		(layer "In5.Cu")
		(net "P5E_PEX3_STN1_RX_DN<17>")
	)
	(segment
		(start 408.520138 -271.644872)
		(end 408.520138 -275.276056)
		(width 0.1143)
		(layer "In5.Cu")
		(net "P5E_PEX3_STN1_RX_DN<17>")
	)
	(segment
		(start 396.686024 -103.498396)
		(end 396.256002 -103.74376)
		(width 0.1651)
		(layer "In5.Cu")
		(net "P5E_PEX3_STN1_RX_DN<17>")
	)
	(segment
		(start 395.7828 -104.145334)
		(end 395.626844 -104.102662)
		(width 0.1651)
		(layer "In5.Cu")
		(net "P5E_PEX3_STN1_RX_DN<17>")
	)
	(segment
		(start 390.516618 -108.450126)
		(end 390.173718 -108.808012)
		(width 0.1651)
		(layer "In5.Cu")
		(net "P5E_PEX3_STN1_RX_DN<17>")
	)
	(segment
		(start 400.25193 -101.685598)
		(end 399.863056 -101.685598)
		(width 0.1651)
		(layer "In5.Cu")
		(net "P5E_PEX3_STN1_RX_DN<17>")
	)
	(segment
		(start 396.256002 -103.74376)
		(end 396.21333 -103.899716)
		(width 0.1651)
		(layer "In5.Cu")
		(net "P5E_PEX3_STN1_RX_DN<17>")
	)
	(segment
		(start 399.390362 -102.086918)
		(end 398.959832 -102.332536)
		(width 0.1651)
		(layer "In5.Cu")
		(net "P5E_PEX3_STN1_RX_DN<17>")
	)
	(segment
		(start 394.59281 -104.692704)
		(end 394.550138 -104.84866)
		(width 0.1651)
		(layer "In5.Cu")
		(net "P5E_PEX3_STN1_RX_DN<17>")
	)
	(segment
		(start 391.357104 -107.408472)
		(end 391.360406 -107.570016)
		(width 0.1651)
		(layer "In5.Cu")
		(net "P5E_PEX3_STN1_RX_DN<17>")
	)
	(segment
		(start 397.272256 -103.29545)
		(end 396.841726 -103.541068)
		(width 0.1651)
		(layer "In5.Cu")
		(net "P5E_PEX3_STN1_RX_DN<17>")
	)
	(segment
		(start 391.360406 -107.570016)
		(end 391.017506 -107.927902)
		(width 0.1651)
		(layer "In5.Cu")
		(net "P5E_PEX3_STN1_RX_DN<17>")
	)
	(segment
		(start 408.785314 -275.379434)
		(end 408.899614 -275.265134)
		(width 0.1143)
		(layer "In5.Cu")
		(net "P5E_PEX3_STN1_RX_DN<17>")
	)
	(segment
		(start 400.54276 -101.976428)
		(end 400.25193 -101.685598)
		(width 0.1651)
		(layer "In5.Cu")
		(net "P5E_PEX3_STN1_RX_DN<17>")
	)
	(segment
		(start 392.204448 -106.689906)
		(end 391.861548 -107.047792)
		(width 0.1651)
		(layer "In5.Cu")
		(net "P5E_PEX3_STN1_RX_DN<17>")
	)
	(segment
		(start 390.855962 -107.931204)
		(end 390.513316 -108.288582)
		(width 0.1651)
		(layer "In5.Cu")
		(net "P5E_PEX3_STN1_RX_DN<17>")
	)
	(segment
		(start 398.373854 -102.535228)
		(end 398.331182 -102.691184)
		(width 0.1651)
		(layer "In5.Cu")
		(net "P5E_PEX3_STN1_RX_DN<17>")
	)
	(segment
		(start 391.017506 -107.927902)
		(end 390.855962 -107.931204)
		(width 0.1651)
		(layer "In5.Cu")
		(net "P5E_PEX3_STN1_RX_DN<17>")
	)
	(segment
		(start 390.012174 -108.811314)
		(end 381.866902 -117.307614)
		(width 0.1651)
		(layer "In5.Cu")
		(net "P5E_PEX3_STN1_RX_DN<17>")
	)
	(segment
		(start 379.375162 -165.351968)
		(end 408.565858 -269.900654)
		(width 0.1651)
		(layer "In5.Cu")
		(net "P5E_PEX3_STN1_RX_DN<17>")
	)
	(segment
		(start 397.900652 -102.936802)
		(end 397.74495 -102.89413)
		(width 0.1651)
		(layer "In5.Cu")
		(net "P5E_PEX3_STN1_RX_DN<17>")
	)
	(segment
		(start 393.963906 -105.051606)
		(end 393.197588 -105.488994)
		(width 0.1651)
		(layer "In5.Cu")
		(net "P5E_PEX3_STN1_RX_DN<17>")
	)
	(segment
		(start 408.565858 -271.599152)
		(end 408.520138 -271.644872)
		(width 0.1143)
		(layer "In5.Cu")
		(net "P5E_PEX3_STN1_RX_DN<17>")
	)
	(segment
		(start 397.74495 -102.89413)
		(end 397.314928 -103.139494)
		(width 0.1651)
		(layer "In5.Cu")
		(net "P5E_PEX3_STN1_RX_DN<17>")
	)
	(segment
		(start 380.531624 -119.95023)
		(end 379.041152 -126.612142)
		(width 0.1651)
		(layer "In5.Cu")
		(net "P5E_PEX3_STN1_RX_DN<17>")
	)
	(segment
		(start 377.61799 -150.180294)
		(end 378.18568 -158.838138)
		(width 0.1651)
		(layer "In5.Cu")
		(net "P5E_PEX3_STN1_RX_DN<17>")
	)
	(segment
		(start 399.433034 -101.930962)
		(end 399.390362 -102.086918)
		(width 0.1651)
		(layer "In5.Cu")
		(net "P5E_PEX3_STN1_RX_DN<17>")
	)
	(segment
		(start 394.550138 -104.84866)
		(end 394.119862 -105.094278)
		(width 0.1651)
		(layer "In5.Cu")
		(net "P5E_PEX3_STN1_RX_DN<17>")
	)
	(segment
		(start 408.623516 -275.379434)
		(end 408.785314 -275.379434)
		(width 0.1143)
		(layer "In5.Cu")
		(net "P5E_PEX3_STN1_RX_DN<17>")
	)
	(segment
		(start 408.565858 -271.570704)
		(end 408.565858 -271.599152)
		(width 0.1143)
		(layer "In5.Cu")
		(net "P5E_PEX3_STN1_RX_DN<17>")
	)
	(segment
		(start 398.331182 -102.691184)
		(end 397.900652 -102.936802)
		(width 0.1651)
		(layer "In5.Cu")
		(net "P5E_PEX3_STN1_RX_DN<17>")
	)
	(segment
		(start 408.565858 -269.900654)
		(end 408.565858 -271.570704)
		(width 0.1651)
		(layer "In5.Cu")
		(net "P5E_PEX3_STN1_RX_DN<17>")
	)
	(segment
		(start 397.314928 -103.139494)
		(end 397.272256 -103.29545)
		(width 0.1651)
		(layer "In5.Cu")
		(net "P5E_PEX3_STN1_RX_DN<17>")
	)
	(segment
		(start 394.119862 -105.094278)
		(end 393.963906 -105.051606)
		(width 0.1651)
		(layer "In5.Cu")
		(net "P5E_PEX3_STN1_RX_DN<17>")
	)
	(segment
		(start 391.69975 -107.051094)
		(end 391.357104 -107.408472)
		(width 0.1651)
		(layer "In5.Cu")
		(net "P5E_PEX3_STN1_RX_DN<17>")
	)
	(segment
		(start 390.513316 -108.288582)
		(end 390.516618 -108.450126)
		(width 0.1651)
		(layer "In5.Cu")
		(net "P5E_PEX3_STN1_RX_DN<17>")
	)
	(segment
		(start 378.18568 -158.838138)
		(end 379.375162 -165.351968)
		(width 0.1651)
		(layer "In5.Cu")
		(net "P5E_PEX3_STN1_RX_DN<17>")
	)
	(segment
		(start 399.863056 -101.685598)
		(end 399.433034 -101.930962)
		(width 0.1651)
		(layer "In5.Cu")
		(net "P5E_PEX3_STN1_RX_DN<17>")
	)
	(segment
		(start 395.626844 -104.102662)
		(end 394.59281 -104.692704)
		(width 0.1651)
		(layer "In5.Cu")
		(net "P5E_PEX3_STN1_RX_DN<17>")
	)
	(segment
		(start 398.803876 -102.289864)
		(end 398.373854 -102.535228)
		(width 0.1651)
		(layer "In5.Cu")
		(net "P5E_PEX3_STN1_RX_DN<17>")
	)
	(segment
		(start 393.197588 -105.488994)
		(end 392.201146 -106.528362)
		(width 0.1651)
		(layer "In5.Cu")
		(net "P5E_PEX3_STN1_RX_DN<17>")
	)
	(segment
		(start 391.861548 -107.047792)
		(end 391.69975 -107.051094)
		(width 0.1651)
		(layer "In5.Cu")
		(net "P5E_PEX3_STN1_RX_DN<17>")
	)
	(segment
		(start 396.21333 -103.899716)
		(end 395.7828 -104.145334)
		(width 0.1651)
		(layer "In5.Cu")
		(net "P5E_PEX3_STN1_RX_DN<17>")
	)
	(segment
		(start 392.201146 -106.528362)
		(end 392.204448 -106.689906)
		(width 0.1651)
		(layer "In5.Cu")
		(net "P5E_PEX3_STN1_RX_DN<17>")
	)
	(segment
		(start 408.899614 -275.265134)
		(end 408.899614 -274.999704)
		(width 0.1143)
		(layer "In5.Cu")
		(net "P5E_PEX3_STN1_RX_DN<17>")
	)
	(segment
		(start 408.520138 -275.276056)
		(end 408.623516 -275.379434)
		(width 0.1143)
		(layer "In5.Cu")
		(net "P5E_PEX3_STN1_RX_DN<17>")
	)
	(segment
		(start 398.959832 -102.332536)
		(end 398.803876 -102.289864)
		(width 0.1651)
		(layer "In5.Cu")
		(net "P5E_PEX3_STN1_RX_DN<17>")
	)
	(segment
		(start 375.489978 -374.729756)
		(end 375.489978 -374.390158)
		(width 0.1651)
		(layer "In5.Cu")
		(net "P5E_PEX3_STN6_RX_DP<103>")
	)
	(segment
		(start 398.829784 -319.939162)
		(end 398.784064 -319.984882)
		(width 0.1143)
		(layer "In5.Cu")
		(net "P5E_PEX3_STN6_RX_DP<103>")
	)
	(segment
		(start 398.735296 -320.195702)
		(end 397.665448 -320.638678)
		(width 0.1651)
		(layer "In5.Cu")
		(net "P5E_PEX3_STN6_RX_DP<103>")
	)
	(segment
		(start 374.424702 -366.234218)
		(end 374.55348 -366.256316)
		(width 0.1651)
		(layer "In5.Cu")
		(net "P5E_PEX3_STN6_RX_DP<103>")
	)
	(segment
		(start 376.366024 -368.821208)
		(end 376.366024 -374.570498)
		(width 0.1651)
		(layer "In5.Cu")
		(net "P5E_PEX3_STN6_RX_DP<103>")
	)
	(segment
		(start 374.814338 -366.805718)
		(end 375.112534 -367.227358)
		(width 0.1651)
		(layer "In5.Cu")
		(net "P5E_PEX3_STN6_RX_DP<103>")
	)
	(segment
		(start 370.959888 -361.17149)
		(end 372.727728 -363.67339)
		(width 0.1651)
		(layer "In5.Cu")
		(net "P5E_PEX3_STN6_RX_DP<103>")
	)
	(segment
		(start 399.285714 -316.229492)
		(end 399.05559 -316.229492)
		(width 0.1143)
		(layer "In5.Cu")
		(net "P5E_PEX3_STN6_RX_DP<103>")
	)
	(segment
		(start 376.033538 -374.902984)
		(end 375.663206 -374.902984)
		(width 0.1651)
		(layer "In5.Cu")
		(net "P5E_PEX3_STN6_RX_DP<103>")
	)
	(segment
		(start 372.706392 -363.798612)
		(end 373.020844 -364.243366)
		(width 0.1651)
		(layer "In5.Cu")
		(net "P5E_PEX3_STN6_RX_DP<103>")
	)
	(segment
		(start 373.849646 -365.260636)
		(end 374.135396 -365.665004)
		(width 0.1651)
		(layer "In5.Cu")
		(net "P5E_PEX3_STN6_RX_DP<103>")
	)
	(segment
		(start 367.840514 -342.250268)
		(end 367.949226 -352.366326)
		(width 0.1651)
		(layer "In5.Cu")
		(net "P5E_PEX3_STN6_RX_DP<103>")
	)
	(segment
		(start 399.400014 -315.849762)
		(end 399.400014 -316.115192)
		(width 0.1143)
		(layer "In5.Cu")
		(net "P5E_PEX3_STN6_RX_DP<103>")
	)
	(segment
		(start 373.708168 -365.236252)
		(end 373.849646 -365.260636)
		(width 0.1651)
		(layer "In5.Cu")
		(net "P5E_PEX3_STN6_RX_DP<103>")
	)
	(segment
		(start 374.55348 -366.256316)
		(end 374.838976 -366.660684)
		(width 0.1651)
		(layer "In5.Cu")
		(net "P5E_PEX3_STN6_RX_DP<103>")
	)
	(segment
		(start 373.431562 -364.669324)
		(end 373.407432 -364.810802)
		(width 0.1651)
		(layer "In5.Cu")
		(net "P5E_PEX3_STN6_RX_DP<103>")
	)
	(segment
		(start 374.113298 -365.793782)
		(end 374.424702 -366.234218)
		(width 0.1651)
		(layer "In5.Cu")
		(net "P5E_PEX3_STN6_RX_DP<103>")
	)
	(segment
		(start 375.112534 -367.227358)
		(end 375.25706 -367.25225)
		(width 0.1651)
		(layer "In5.Cu")
		(net "P5E_PEX3_STN6_RX_DP<103>")
	)
	(segment
		(start 374.838976 -366.660684)
		(end 374.814338 -366.805718)
		(width 0.1651)
		(layer "In5.Cu")
		(net "P5E_PEX3_STN6_RX_DP<103>")
	)
	(segment
		(start 372.727728 -363.67339)
		(end 372.706392 -363.798612)
		(width 0.1651)
		(layer "In5.Cu")
		(net "P5E_PEX3_STN6_RX_DP<103>")
	)
	(segment
		(start 373.145812 -364.264956)
		(end 373.431562 -364.669324)
		(width 0.1651)
		(layer "In5.Cu")
		(net "P5E_PEX3_STN6_RX_DP<103>")
	)
	(segment
		(start 367.949226 -352.366326)
		(end 370.959888 -361.17149)
		(width 0.1651)
		(layer "In5.Cu")
		(net "P5E_PEX3_STN6_RX_DP<103>")
	)
	(segment
		(start 373.407432 -364.810802)
		(end 373.708168 -365.236252)
		(width 0.1651)
		(layer "In5.Cu")
		(net "P5E_PEX3_STN6_RX_DP<103>")
	)
	(segment
		(start 369.273328 -339.503766)
		(end 368.461544 -340.52637)
		(width 0.1651)
		(layer "In5.Cu")
		(net "P5E_PEX3_STN6_RX_DP<103>")
	)
	(segment
		(start 399.400014 -316.115192)
		(end 399.285714 -316.229492)
		(width 0.1143)
		(layer "In5.Cu")
		(net "P5E_PEX3_STN6_RX_DP<103>")
	)
	(segment
		(start 399.05559 -316.229492)
		(end 398.829784 -316.455298)
		(width 0.1143)
		(layer "In5.Cu")
		(net "P5E_PEX3_STN6_RX_DP<103>")
	)
	(segment
		(start 373.020844 -364.243366)
		(end 373.145812 -364.264956)
		(width 0.1651)
		(layer "In5.Cu")
		(net "P5E_PEX3_STN6_RX_DP<103>")
	)
	(segment
		(start 368.461544 -340.52637)
		(end 367.840514 -342.250268)
		(width 0.1651)
		(layer "In5.Cu")
		(net "P5E_PEX3_STN6_RX_DP<103>")
	)
	(segment
		(start 398.829784 -316.455298)
		(end 398.829784 -319.939162)
		(width 0.1143)
		(layer "In5.Cu")
		(net "P5E_PEX3_STN6_RX_DP<103>")
	)
	(segment
		(start 375.663206 -374.902984)
		(end 375.489978 -374.729756)
		(width 0.1651)
		(layer "In5.Cu")
		(net "P5E_PEX3_STN6_RX_DP<103>")
	)
	(segment
		(start 397.665448 -320.638678)
		(end 369.273328 -339.503766)
		(width 0.1651)
		(layer "In5.Cu")
		(net "P5E_PEX3_STN6_RX_DP<103>")
	)
	(segment
		(start 374.135396 -365.665004)
		(end 374.113298 -365.793782)
		(width 0.1651)
		(layer "In5.Cu")
		(net "P5E_PEX3_STN6_RX_DP<103>")
	)
	(segment
		(start 398.784064 -320.12255)
		(end 398.735296 -320.195702)
		(width 0.1651)
		(layer "In5.Cu")
		(net "P5E_PEX3_STN6_RX_DP<103>")
	)
	(segment
		(start 398.784064 -320.01333)
		(end 398.784064 -320.12255)
		(width 0.1651)
		(layer "In5.Cu")
		(net "P5E_PEX3_STN6_RX_DP<103>")
	)
	(segment
		(start 375.25706 -367.25225)
		(end 376.366024 -368.821208)
		(width 0.1651)
		(layer "In5.Cu")
		(net "P5E_PEX3_STN6_RX_DP<103>")
	)
	(segment
		(start 376.366024 -374.570498)
		(end 376.033538 -374.902984)
		(width 0.1651)
		(layer "In5.Cu")
		(net "P5E_PEX3_STN6_RX_DP<103>")
	)
	(segment
		(start 398.784064 -319.984882)
		(end 398.784064 -320.01333)
		(width 0.1143)
		(layer "In5.Cu")
		(net "P5E_PEX3_STN6_RX_DP<103>")
	)
	(segment
		(start 182.584598 -104.384856)
		(end 183.039766 -104.840024)
		(width 0.13208)
		(layer "F.Cu")
		(net "CLK_50M_NIC3_RBT_REF")
	)
	(segment
		(start 182.14467 -104.384856)
		(end 182.584598 -104.384856)
		(width 0.13208)
		(layer "F.Cu")
		(net "CLK_50M_NIC3_RBT_REF")
	)
	(segment
		(start 183.039766 -104.840024)
		(end 184.757314 -104.840024)
		(width 0.13208)
		(layer "F.Cu")
		(net "CLK_50M_NIC3_RBT_REF")
	)
	(segment
		(start 181.689502 -104.840024)
		(end 182.14467 -104.384856)
		(width 0.13208)
		(layer "F.Cu")
		(net "CLK_50M_NIC3_RBT_REF")
	)
	(segment
		(start 177.710338 -104.830372)
		(end 177.71999 -104.840024)
		(width 0.13208)
		(layer "F.Cu")
		(net "CLK_50M_NIC3_RBT_REF")
	)
	(segment
		(start 175.49495 -104.830372)
		(end 177.710338 -104.830372)
		(width 0.13208)
		(layer "F.Cu")
		(net "CLK_50M_NIC3_RBT_REF")
	)
	(segment
		(start 177.71999 -104.840024)
		(end 181.689502 -104.840024)
		(width 0.13208)
		(layer "F.Cu")
		(net "CLK_50M_NIC3_RBT_REF")
	)
	(via
		(at 182.14467 -104.384856)
		(size 0.508)
		(drill 0.254)
		(layers "F.Cu" "B.Cu")
		(net "CLK_50M_NIC3_RBT_REF")
	)
	(segment
		(start 214.267796 -30.03169)
		(end 213.941406 -30.35808)
		(width 0.13462)
		(layer "F.Cu")
		(net "P5E_PEX1_STN2_TX_C_DN<33>")
	)
	(segment
		(start 210.035902 -30.35808)
		(end 209.868008 -30.190186)
		(width 0.13462)
		(layer "F.Cu")
		(net "P5E_PEX1_STN2_TX_C_DN<33>")
	)
	(segment
		(start 209.868008 -30.190186)
		(end 209.364834 -30.190186)
		(width 0.13462)
		(layer "F.Cu")
		(net "P5E_PEX1_STN2_TX_C_DN<33>")
	)
	(segment
		(start 213.941406 -30.35808)
		(end 210.035902 -30.35808)
		(width 0.13462)
		(layer "F.Cu")
		(net "P5E_PEX1_STN2_TX_C_DN<33>")
	)
	(segment
		(start 297.708574 -155.52928)
		(end 297.403012 -155.223718)
		(width 0.13462)
		(layer "F.Cu")
		(net "P5E_PEX2_STN0_RX_DN<15>")
	)
	(segment
		(start 300.205648 -155.52928)
		(end 297.708574 -155.52928)
		(width 0.13462)
		(layer "F.Cu")
		(net "P5E_PEX2_STN0_RX_DN<15>")
	)
	(segment
		(start 300.857412 -155.355036)
		(end 300.379892 -155.355036)
		(width 0.13462)
		(layer "F.Cu")
		(net "P5E_PEX2_STN0_RX_DN<15>")
	)
	(segment
		(start 300.379892 -155.355036)
		(end 300.205648 -155.52928)
		(width 0.13462)
		(layer "F.Cu")
		(net "P5E_PEX2_STN0_RX_DN<15>")
	)
	(segment
		(start 307.189124 -267.76807)
		(end 307.019198 -261.27202)
		(width 0.1651)
		(layer "In5.Cu")
		(net "P5E_PEX2_STN0_RX_DN<15>")
	)
	(segment
		(start 297.693842 -155.514548)
		(end 297.403012 -155.223718)
		(width 0.1651)
		(layer "In5.Cu")
		(net "P5E_PEX2_STN0_RX_DN<15>")
	)
	(segment
		(start 307.019198 -261.27202)
		(end 300.11116 -162.860482)
		(width 0.1651)
		(layer "In5.Cu")
		(net "P5E_PEX2_STN0_RX_DN<15>")
	)
	(segment
		(start 307.049678 -273.099784)
		(end 307.049678 -273.365214)
		(width 0.1143)
		(layer "In5.Cu")
		(net "P5E_PEX2_STN0_RX_DN<15>")
	)
	(segment
		(start 298.542964 -155.514548)
		(end 297.693842 -155.514548)
		(width 0.1651)
		(layer "In5.Cu")
		(net "P5E_PEX2_STN0_RX_DN<15>")
	)
	(segment
		(start 307.049678 -273.365214)
		(end 306.935378 -273.479514)
		(width 0.1143)
		(layer "In5.Cu")
		(net "P5E_PEX2_STN0_RX_DN<15>")
	)
	(segment
		(start 306.77358 -273.479514)
		(end 306.670202 -273.376136)
		(width 0.1143)
		(layer "In5.Cu")
		(net "P5E_PEX2_STN0_RX_DN<15>")
	)
	(segment
		(start 300.11116 -162.860482)
		(end 300.11116 -162.860736)
		(width 0.1651)
		(layer "In5.Cu")
		(net "P5E_PEX2_STN0_RX_DN<15>")
	)
	(segment
		(start 306.935378 -273.479514)
		(end 306.77358 -273.479514)
		(width 0.1143)
		(layer "In5.Cu")
		(net "P5E_PEX2_STN0_RX_DN<15>")
	)
	(segment
		(start 306.670202 -271.600168)
		(end 306.715922 -271.554448)
		(width 0.1143)
		(layer "In5.Cu")
		(net "P5E_PEX2_STN0_RX_DN<15>")
	)
	(segment
		(start 306.670202 -273.376136)
		(end 306.670202 -271.600168)
		(width 0.1143)
		(layer "In5.Cu")
		(net "P5E_PEX2_STN0_RX_DN<15>")
	)
	(segment
		(start 306.715922 -271.554448)
		(end 306.715922 -271.526)
		(width 0.1143)
		(layer "In5.Cu")
		(net "P5E_PEX2_STN0_RX_DN<15>")
	)
	(segment
		(start 300.11116 -162.860736)
		(end 299.163232 -156.134562)
		(width 0.1651)
		(layer "In5.Cu")
		(net "P5E_PEX2_STN0_RX_DN<15>")
	)
	(segment
		(start 299.163232 -156.134562)
		(end 298.542964 -155.514548)
		(width 0.1651)
		(layer "In5.Cu")
		(net "P5E_PEX2_STN0_RX_DN<15>")
	)
	(segment
		(start 306.715922 -271.526)
		(end 306.715922 -270.231616)
		(width 0.1651)
		(layer "In5.Cu")
		(net "P5E_PEX2_STN0_RX_DN<15>")
	)
	(segment
		(start 306.715922 -270.231616)
		(end 307.189124 -267.76807)
		(width 0.1651)
		(layer "In5.Cu")
		(net "P5E_PEX2_STN0_RX_DN<15>")
	)
	(segment
		(start 331.725524 -345.170506)
		(end 332.020164 -345.465146)
		(width 0.13462)
		(layer "F.Cu")
		(net "P5E_PEX2_STN6_TX_C_DN<103>")
	)
	(segment
		(start 332.045564 -344.219022)
		(end 331.725524 -344.539062)
		(width 0.13462)
		(layer "F.Cu")
		(net "P5E_PEX2_STN6_TX_C_DN<103>")
	)
	(segment
		(start 331.725524 -344.539062)
		(end 331.725524 -345.170506)
		(width 0.13462)
		(layer "F.Cu")
		(net "P5E_PEX2_STN6_TX_C_DN<103>")
	)
	(segment
		(start 330.174854 -358.9528)
		(end 332.616048 -368.80038)
		(width 0.1651)
		(layer "In13.Cu")
		(net "P5E_PEX2_STN6_TX_C_DN<103>")
	)
	(segment
		(start 332.020164 -345.465146)
		(end 331.729334 -345.755976)
		(width 0.1651)
		(layer "In13.Cu")
		(net "P5E_PEX2_STN6_TX_C_DN<103>")
	)
	(segment
		(start 331.729334 -346.326714)
		(end 330.174854 -347.881194)
		(width 0.1651)
		(layer "In13.Cu")
		(net "P5E_PEX2_STN6_TX_C_DN<103>")
	)
	(segment
		(start 332.164182 -382.9812)
		(end 331.617066 -382.9812)
		(width 0.1651)
		(layer "In13.Cu")
		(net "P5E_PEX2_STN6_TX_C_DN<103>")
	)
	(segment
		(start 331.490066 -383.1082)
		(end 331.490066 -383.490216)
		(width 0.1651)
		(layer "In13.Cu")
		(net "P5E_PEX2_STN6_TX_C_DN<103>")
	)
	(segment
		(start 332.616048 -382.529334)
		(end 332.164182 -382.9812)
		(width 0.1651)
		(layer "In13.Cu")
		(net "P5E_PEX2_STN6_TX_C_DN<103>")
	)
	(segment
		(start 331.729334 -345.755976)
		(end 331.729334 -346.326714)
		(width 0.1651)
		(layer "In13.Cu")
		(net "P5E_PEX2_STN6_TX_C_DN<103>")
	)
	(segment
		(start 331.617066 -382.9812)
		(end 331.490066 -383.1082)
		(width 0.1651)
		(layer "In13.Cu")
		(net "P5E_PEX2_STN6_TX_C_DN<103>")
	)
	(segment
		(start 332.616048 -368.80038)
		(end 332.616048 -382.529334)
		(width 0.1651)
		(layer "In13.Cu")
		(net "P5E_PEX2_STN6_TX_C_DN<103>")
	)
	(segment
		(start 330.174854 -347.881194)
		(end 330.174854 -358.9528)
		(width 0.1651)
		(layer "In13.Cu")
		(net "P5E_PEX2_STN6_TX_C_DN<103>")
	)
	(segment
		(start 385.205224 -130.408934)
		(end 385.52247 -130.72618)
		(width 0.13462)
		(layer "F.Cu")
		(net "P5E_PEX3_STN1_TX_C_DP<28>")
	)
	(segment
		(start 393.678664 -130.72618)
		(end 393.8397 -130.565144)
		(width 0.13462)
		(layer "F.Cu")
		(net "P5E_PEX3_STN1_TX_C_DP<28>")
	)
	(segment
		(start 385.52247 -130.72618)
		(end 393.678664 -130.72618)
		(width 0.13462)
		(layer "F.Cu")
		(net "P5E_PEX3_STN1_TX_C_DP<28>")
	)
	(segment
		(start 393.8397 -130.565144)
		(end 394.342366 -130.565144)
		(width 0.13462)
		(layer "F.Cu")
		(net "P5E_PEX3_STN1_TX_C_DP<28>")
	)
	(segment
		(start 399.99793 -318.137286)
		(end 400.228054 -318.137286)
		(width 0.1143)
		(layer "In5.Cu")
		(net "P5E_PEX3_STN6_RX_DP<102>")
	)
	(segment
		(start 378.233432 -376.003058)
		(end 378.565918 -375.670572)
		(width 0.1651)
		(layer "In5.Cu")
		(net "P5E_PEX3_STN6_RX_DP<102>")
	)
	(segment
		(start 377.217686 -367.331498)
		(end 377.233434 -367.170716)
		(width 0.1651)
		(layer "In5.Cu")
		(net "P5E_PEX3_STN6_RX_DP<102>")
	)
	(segment
		(start 368.90198 -352.120962)
		(end 368.798348 -342.416638)
		(width 0.1651)
		(layer "In5.Cu")
		(net "P5E_PEX3_STN6_RX_DP<102>")
	)
	(segment
		(start 377.689872 -375.82983)
		(end 377.8631 -376.003058)
		(width 0.1651)
		(layer "In5.Cu")
		(net "P5E_PEX3_STN6_RX_DP<102>")
	)
	(segment
		(start 377.693174 -367.730278)
		(end 377.532392 -367.71453)
		(width 0.1651)
		(layer "In5.Cu")
		(net "P5E_PEX3_STN6_RX_DP<102>")
	)
	(segment
		(start 371.779292 -360.534204)
		(end 368.90198 -352.120962)
		(width 0.1651)
		(layer "In5.Cu")
		(net "P5E_PEX3_STN6_RX_DP<102>")
	)
	(segment
		(start 399.734024 -320.310002)
		(end 399.734024 -319.995296)
		(width 0.1651)
		(layer "In5.Cu")
		(net "P5E_PEX3_STN6_RX_DP<102>")
	)
	(segment
		(start 399.093182 -320.950844)
		(end 399.734024 -320.310002)
		(width 0.1651)
		(layer "In5.Cu")
		(net "P5E_PEX3_STN6_RX_DP<102>")
	)
	(segment
		(start 399.734024 -319.995296)
		(end 399.734024 -319.966848)
		(width 0.1143)
		(layer "In5.Cu")
		(net "P5E_PEX3_STN6_RX_DP<102>")
	)
	(segment
		(start 399.779744 -319.921128)
		(end 399.779744 -318.355472)
		(width 0.1143)
		(layer "In5.Cu")
		(net "P5E_PEX3_STN6_RX_DP<102>")
	)
	(segment
		(start 378.565918 -368.792252)
		(end 377.693174 -367.730278)
		(width 0.1651)
		(layer "In5.Cu")
		(net "P5E_PEX3_STN6_RX_DP<102>")
	)
	(segment
		(start 369.2398 -341.191088)
		(end 370.073936 -340.139782)
		(width 0.1651)
		(layer "In5.Cu")
		(net "P5E_PEX3_STN6_RX_DP<102>")
	)
	(segment
		(start 378.565918 -375.670572)
		(end 378.565918 -368.792252)
		(width 0.1651)
		(layer "In5.Cu")
		(net "P5E_PEX3_STN6_RX_DP<102>")
	)
	(segment
		(start 370.073936 -340.139782)
		(end 399.093182 -320.950844)
		(width 0.1651)
		(layer "In5.Cu")
		(net "P5E_PEX3_STN6_RX_DP<102>")
	)
	(segment
		(start 399.734024 -319.966848)
		(end 399.779744 -319.921128)
		(width 0.1143)
		(layer "In5.Cu")
		(net "P5E_PEX3_STN6_RX_DP<102>")
	)
	(segment
		(start 400.349974 -318.015366)
		(end 400.349974 -317.749936)
		(width 0.1143)
		(layer "In5.Cu")
		(net "P5E_PEX3_STN6_RX_DP<102>")
	)
	(segment
		(start 400.228054 -318.137286)
		(end 400.349974 -318.015366)
		(width 0.1143)
		(layer "In5.Cu")
		(net "P5E_PEX3_STN6_RX_DP<102>")
	)
	(segment
		(start 377.532392 -367.71453)
		(end 377.217686 -367.331498)
		(width 0.1651)
		(layer "In5.Cu")
		(net "P5E_PEX3_STN6_RX_DP<102>")
	)
	(segment
		(start 399.779744 -318.355472)
		(end 399.99793 -318.137286)
		(width 0.1143)
		(layer "In5.Cu")
		(net "P5E_PEX3_STN6_RX_DP<102>")
	)
	(segment
		(start 377.689872 -375.490232)
		(end 377.689872 -375.82983)
		(width 0.1651)
		(layer "In5.Cu")
		(net "P5E_PEX3_STN6_RX_DP<102>")
	)
	(segment
		(start 377.8631 -376.003058)
		(end 378.233432 -376.003058)
		(width 0.1651)
		(layer "In5.Cu")
		(net "P5E_PEX3_STN6_RX_DP<102>")
	)
	(segment
		(start 377.233434 -367.170716)
		(end 371.779292 -360.534204)
		(width 0.1651)
		(layer "In5.Cu")
		(net "P5E_PEX3_STN6_RX_DP<102>")
	)
	(segment
		(start 368.798348 -342.416638)
		(end 369.2398 -341.191088)
		(width 0.1651)
		(layer "In5.Cu")
		(net "P5E_PEX3_STN6_RX_DP<102>")
	)
	(segment
		(start 183.251602 -115.834922)
		(end 184.757314 -115.834922)
		(width 0.13208)
		(layer "F.Cu")
		(net "PRSNTB2_NIC3_N")
	)
	(segment
		(start 180.177694 -117.566186)
		(end 180.177694 -116.550186)
		(width 0.13208)
		(layer "F.Cu")
		(net "PRSNTB2_NIC3_N")
	)
	(segment
		(start 182.638954 -116.44757)
		(end 183.251602 -115.834922)
		(width 0.13208)
		(layer "F.Cu")
		(net "PRSNTB2_NIC3_N")
	)
	(segment
		(start 181.567582 -116.550186)
		(end 181.670198 -116.44757)
		(width 0.13208)
		(layer "F.Cu")
		(net "PRSNTB2_NIC3_N")
	)
	(segment
		(start 181.670198 -116.44757)
		(end 182.638954 -116.44757)
		(width 0.13208)
		(layer "F.Cu")
		(net "PRSNTB2_NIC3_N")
	)
	(segment
		(start 180.177694 -116.550186)
		(end 181.567582 -116.550186)
		(width 0.13208)
		(layer "F.Cu")
		(net "PRSNTB2_NIC3_N")
	)
	(via
		(at 182.638954 -116.44757)
		(size 0.508)
		(drill 0.254)
		(layers "F.Cu" "B.Cu")
		(net "PRSNTB2_NIC3_N")
	)
	(segment
		(start 177.458116 -28.829)
		(end 177.164746 -29.12237)
		(width 0.13462)
		(layer "F.Cu")
		(net "P5E_PEX1_STN2_RX_DP<36>")
	)
	(segment
		(start 178.764946 -28.99029)
		(end 178.285902 -28.99029)
		(width 0.13462)
		(layer "F.Cu")
		(net "P5E_PEX1_STN2_RX_DP<36>")
	)
	(segment
		(start 178.124612 -28.829)
		(end 177.458116 -28.829)
		(width 0.13462)
		(layer "F.Cu")
		(net "P5E_PEX1_STN2_RX_DP<36>")
	)
	(segment
		(start 178.764946 -28.990036)
		(end 178.764946 -28.99029)
		(width 0.13462)
		(layer "F.Cu")
		(net "P5E_PEX1_STN2_RX_DP<36>")
	)
	(segment
		(start 178.285902 -28.99029)
		(end 178.124612 -28.829)
		(width 0.13462)
		(layer "F.Cu")
		(net "P5E_PEX1_STN2_RX_DP<36>")
	)
	(segment
		(start 183.12511 -39.138098)
		(end 181.101492 -48.804068)
		(width 0.1651)
		(layer "In7.Cu")
		(net "P5E_PEX1_STN2_RX_DP<36>")
	)
	(segment
		(start 177.520092 -28.83154)
		(end 177.787046 -28.83154)
		(width 0.1651)
		(layer "In7.Cu")
		(net "P5E_PEX1_STN2_RX_DP<36>")
	)
	(segment
		(start 178.977544 -30.022038)
		(end 179.327556 -30.37205)
		(width 0.1651)
		(layer "In7.Cu")
		(net "P5E_PEX1_STN2_RX_DP<36>")
	)
	(segment
		(start 180.901848 -68.365624)
		(end 170.518328 -264.952226)
		(width 0.1651)
		(layer "In7.Cu")
		(net "P5E_PEX1_STN2_RX_DP<36>")
	)
	(segment
		(start 178.83378 -30.022038)
		(end 178.977544 -30.022038)
		(width 0.1651)
		(layer "In7.Cu")
		(net "P5E_PEX1_STN2_RX_DP<36>")
	)
	(segment
		(start 177.787046 -28.83154)
		(end 178.48326 -29.527754)
		(width 0.1651)
		(layer "In7.Cu")
		(net "P5E_PEX1_STN2_RX_DP<36>")
	)
	(segment
		(start 178.48326 -29.527754)
		(end 178.48326 -29.671518)
		(width 0.1651)
		(layer "In7.Cu")
		(net "P5E_PEX1_STN2_RX_DP<36>")
	)
	(segment
		(start 170.429428 -275.354796)
		(end 170.64482 -275.570188)
		(width 0.1143)
		(layer "In7.Cu")
		(net "P5E_PEX1_STN2_RX_DP<36>")
	)
	(segment
		(start 179.82184 -30.866334)
		(end 180.564282 -31.608776)
		(width 0.1651)
		(layer "In7.Cu")
		(net "P5E_PEX1_STN2_RX_DP<36>")
	)
	(segment
		(start 170.64482 -275.570188)
		(end 170.885612 -275.570188)
		(width 0.1143)
		(layer "In7.Cu")
		(net "P5E_PEX1_STN2_RX_DP<36>")
	)
	(segment
		(start 170.999912 -275.684488)
		(end 170.999912 -275.949918)
		(width 0.1143)
		(layer "In7.Cu")
		(net "P5E_PEX1_STN2_RX_DP<36>")
	)
	(segment
		(start 177.164746 -29.12237)
		(end 177.409856 -28.87726)
		(width 0.1651)
		(layer "In7.Cu")
		(net "P5E_PEX1_STN2_RX_DP<36>")
	)
	(segment
		(start 183.148478 -37.742622)
		(end 183.12511 -39.138098)
		(width 0.1651)
		(layer "In7.Cu")
		(net "P5E_PEX1_STN2_RX_DP<36>")
	)
	(segment
		(start 170.383708 -266.487402)
		(end 170.383708 -271.392904)
		(width 0.1651)
		(layer "In7.Cu")
		(net "P5E_PEX1_STN2_RX_DP<36>")
	)
	(segment
		(start 170.429428 -271.467072)
		(end 170.429428 -275.354796)
		(width 0.1143)
		(layer "In7.Cu")
		(net "P5E_PEX1_STN2_RX_DP<36>")
	)
	(segment
		(start 170.885612 -275.570188)
		(end 170.999912 -275.684488)
		(width 0.1143)
		(layer "In7.Cu")
		(net "P5E_PEX1_STN2_RX_DP<36>")
	)
	(segment
		(start 178.48326 -29.671518)
		(end 178.83378 -30.022038)
		(width 0.1651)
		(layer "In7.Cu")
		(net "P5E_PEX1_STN2_RX_DP<36>")
	)
	(segment
		(start 170.383708 -271.392904)
		(end 170.383708 -271.421352)
		(width 0.1143)
		(layer "In7.Cu")
		(net "P5E_PEX1_STN2_RX_DP<36>")
	)
	(segment
		(start 179.678076 -30.866334)
		(end 179.82184 -30.866334)
		(width 0.1651)
		(layer "In7.Cu")
		(net "P5E_PEX1_STN2_RX_DP<36>")
	)
	(segment
		(start 181.101492 -48.804068)
		(end 180.901848 -68.365624)
		(width 0.1651)
		(layer "In7.Cu")
		(net "P5E_PEX1_STN2_RX_DP<36>")
	)
	(segment
		(start 179.327556 -30.515814)
		(end 179.678076 -30.866334)
		(width 0.1651)
		(layer "In7.Cu")
		(net "P5E_PEX1_STN2_RX_DP<36>")
	)
	(segment
		(start 177.409856 -28.87726)
		(end 177.520092 -28.83154)
		(width 0.1651)
		(layer "In7.Cu")
		(net "P5E_PEX1_STN2_RX_DP<36>")
	)
	(segment
		(start 179.327556 -30.37205)
		(end 179.327556 -30.515814)
		(width 0.1651)
		(layer "In7.Cu")
		(net "P5E_PEX1_STN2_RX_DP<36>")
	)
	(segment
		(start 180.564282 -31.608776)
		(end 183.148478 -37.742622)
		(width 0.1651)
		(layer "In7.Cu")
		(net "P5E_PEX1_STN2_RX_DP<36>")
	)
	(segment
		(start 170.383708 -271.421352)
		(end 170.429428 -271.467072)
		(width 0.1143)
		(layer "In7.Cu")
		(net "P5E_PEX1_STN2_RX_DP<36>")
	)
	(segment
		(start 170.518328 -264.952226)
		(end 170.383708 -266.487402)
		(width 0.1651)
		(layer "In7.Cu")
		(net "P5E_PEX1_STN2_RX_DP<36>")
	)
	(segment
		(start 305.95697 -130.6449)
		(end 305.457606 -130.6449)
		(width 0.13462)
		(layer "F.Cu")
		(net "P5E_PEX2_STN0_TX_C_DP<4>")
	)
	(segment
		(start 311.637934 -130.4798)
		(end 306.12207 -130.4798)
		(width 0.13462)
		(layer "F.Cu")
		(net "P5E_PEX2_STN0_TX_C_DP<4>")
	)
	(segment
		(start 311.95264 -130.794506)
		(end 311.637934 -130.4798)
		(width 0.13462)
		(layer "F.Cu")
		(net "P5E_PEX2_STN0_TX_C_DP<4>")
	)
	(segment
		(start 306.12207 -130.4798)
		(end 305.95697 -130.6449)
		(width 0.13462)
		(layer "F.Cu")
		(net "P5E_PEX2_STN0_TX_C_DP<4>")
	)
	(segment
		(start 337.943444 -356.831646)
		(end 337.943444 -357.46309)
		(width 0.13462)
		(layer "F.Cu")
		(net "P5E_PEX2_STN6_TX_C_DN<99>")
	)
	(segment
		(start 338.263484 -356.511606)
		(end 337.943444 -356.831646)
		(width 0.13462)
		(layer "F.Cu")
		(net "P5E_PEX2_STN6_TX_C_DN<99>")
	)
	(segment
		(start 337.943444 -357.46309)
		(end 338.238084 -357.75773)
		(width 0.13462)
		(layer "F.Cu")
		(net "P5E_PEX2_STN6_TX_C_DN<99>")
	)
	(segment
		(start 340.41715 -382.9812)
		(end 340.29015 -383.1082)
		(width 0.1651)
		(layer "In13.Cu")
		(net "P5E_PEX2_STN6_TX_C_DN<99>")
	)
	(segment
		(start 340.29015 -383.1082)
		(end 340.29015 -383.490216)
		(width 0.1651)
		(layer "In13.Cu")
		(net "P5E_PEX2_STN6_TX_C_DN<99>")
	)
	(segment
		(start 338.238084 -357.75773)
		(end 337.947254 -358.04856)
		(width 0.1651)
		(layer "In13.Cu")
		(net "P5E_PEX2_STN6_TX_C_DN<99>")
	)
	(segment
		(start 337.947254 -358.04856)
		(end 337.947254 -358.90708)
		(width 0.1651)
		(layer "In13.Cu")
		(net "P5E_PEX2_STN6_TX_C_DN<99>")
	)
	(segment
		(start 341.416132 -382.529334)
		(end 340.964266 -382.9812)
		(width 0.1651)
		(layer "In13.Cu")
		(net "P5E_PEX2_STN6_TX_C_DN<99>")
	)
	(segment
		(start 341.416132 -368.8842)
		(end 341.416132 -382.529334)
		(width 0.1651)
		(layer "In13.Cu")
		(net "P5E_PEX2_STN6_TX_C_DN<99>")
	)
	(segment
		(start 337.947254 -358.90708)
		(end 341.416132 -368.8842)
		(width 0.1651)
		(layer "In13.Cu")
		(net "P5E_PEX2_STN6_TX_C_DN<99>")
	)
	(segment
		(start 340.964266 -382.9812)
		(end 340.41715 -382.9812)
		(width 0.1651)
		(layer "In13.Cu")
		(net "P5E_PEX2_STN6_TX_C_DN<99>")
	)
	(segment
		(start 385.814824 -101.095302)
		(end 386.121402 -101.40188)
		(width 0.13462)
		(layer "F.Cu")
		(net "P5E_PEX3_STN1_TX_C_DN<17>")
	)
	(segment
		(start 393.843002 -101.244908)
		(end 394.342366 -101.244908)
		(width 0.13462)
		(layer "F.Cu")
		(net "P5E_PEX3_STN1_TX_C_DN<17>")
	)
	(segment
		(start 393.68603 -101.40188)
		(end 393.843002 -101.244908)
		(width 0.13462)
		(layer "F.Cu")
		(net "P5E_PEX3_STN1_TX_C_DN<17>")
	)
	(segment
		(start 386.121402 -101.40188)
		(end 393.68603 -101.40188)
		(width 0.13462)
		(layer "F.Cu")
		(net "P5E_PEX3_STN1_TX_C_DN<17>")
	)
	(segment
		(start 386.70738 -350.365314)
		(end 387.027928 -350.685862)
		(width 0.13462)
		(layer "F.Cu")
		(net "P5E_PEX3_STN6_TX_C_DP<104>")
	)
	(segment
		(start 387.027928 -351.31629)
		(end 386.73278 -351.611438)
		(width 0.13462)
		(layer "F.Cu")
		(net "P5E_PEX3_STN6_TX_C_DP<104>")
	)
	(segment
		(start 387.027928 -350.685862)
		(end 387.027928 -351.31629)
		(width 0.13462)
		(layer "F.Cu")
		(net "P5E_PEX3_STN6_TX_C_DP<104>")
	)
	(segment
		(start 384.797046 -359.540556)
		(end 385.46913 -358.068626)
		(width 0.1651)
		(layer "In13.Cu")
		(net "P5E_PEX3_STN6_TX_C_DP<104>")
	)
	(segment
		(start 374.06326 -369.334034)
		(end 375.3231 -367.756948)
		(width 0.1651)
		(layer "In13.Cu")
		(net "P5E_PEX3_STN6_TX_C_DP<104>")
	)
	(segment
		(start 385.46913 -358.068626)
		(end 385.46913 -353.910646)
		(width 0.1651)
		(layer "In13.Cu")
		(net "P5E_PEX3_STN6_TX_C_DP<104>")
	)
	(segment
		(start 391.73404 -396.088108)
		(end 391.510266 -395.491716)
		(width 0.1651)
		(layer "In13.Cu")
		(net "P5E_PEX3_STN6_TX_C_DP<104>")
	)
	(segment
		(start 387.02361 -351.902268)
		(end 386.73278 -351.611438)
		(width 0.1651)
		(layer "In13.Cu")
		(net "P5E_PEX3_STN6_TX_C_DP<104>")
	)
	(segment
		(start 390.889998 -409.290012)
		(end 390.889998 -409.672028)
		(width 0.1651)
		(layer "In13.Cu")
		(net "P5E_PEX3_STN6_TX_C_DP<104>")
	)
	(segment
		(start 373.71401 -373.039132)
		(end 374.06326 -369.334034)
		(width 0.1651)
		(layer "In13.Cu")
		(net "P5E_PEX3_STN6_TX_C_DP<104>")
	)
	(segment
		(start 387.02361 -352.356166)
		(end 387.02361 -351.902268)
		(width 0.1651)
		(layer "In13.Cu")
		(net "P5E_PEX3_STN6_TX_C_DP<104>")
	)
	(segment
		(start 391.73404 -409.512262)
		(end 391.73404 -396.088108)
		(width 0.1651)
		(layer "In13.Cu")
		(net "P5E_PEX3_STN6_TX_C_DP<104>")
	)
	(segment
		(start 387.004814 -391.410444)
		(end 376.200924 -386.707634)
		(width 0.1651)
		(layer "In13.Cu")
		(net "P5E_PEX3_STN6_TX_C_DP<104>")
	)
	(segment
		(start 375.3231 -367.756948)
		(end 384.797046 -359.540556)
		(width 0.1651)
		(layer "In13.Cu")
		(net "P5E_PEX3_STN6_TX_C_DP<104>")
	)
	(segment
		(start 389.218932 -392.778742)
		(end 387.004814 -391.410444)
		(width 0.1651)
		(layer "In13.Cu")
		(net "P5E_PEX3_STN6_TX_C_DP<104>")
	)
	(segment
		(start 376.200924 -386.707634)
		(end 374.635014 -385.58597)
		(width 0.1651)
		(layer "In13.Cu")
		(net "P5E_PEX3_STN6_TX_C_DP<104>")
	)
	(segment
		(start 391.286746 -394.896086)
		(end 389.218932 -392.778742)
		(width 0.1651)
		(layer "In13.Cu")
		(net "P5E_PEX3_STN6_TX_C_DP<104>")
	)
	(segment
		(start 391.510266 -395.491716)
		(end 391.510012 -395.491716)
		(width 0.1651)
		(layer "In13.Cu")
		(net "P5E_PEX3_STN6_TX_C_DP<104>")
	)
	(segment
		(start 390.889998 -409.672028)
		(end 391.016998 -409.799028)
		(width 0.1651)
		(layer "In13.Cu")
		(net "P5E_PEX3_STN6_TX_C_DP<104>")
	)
	(segment
		(start 374.156986 -384.597148)
		(end 373.71401 -373.039132)
		(width 0.1651)
		(layer "In13.Cu")
		(net "P5E_PEX3_STN6_TX_C_DP<104>")
	)
	(segment
		(start 391.510012 -395.491716)
		(end 391.286746 -394.896086)
		(width 0.1651)
		(layer "In13.Cu")
		(net "P5E_PEX3_STN6_TX_C_DP<104>")
	)
	(segment
		(start 391.016998 -409.799028)
		(end 391.447274 -409.799028)
		(width 0.1651)
		(layer "In13.Cu")
		(net "P5E_PEX3_STN6_TX_C_DP<104>")
	)
	(segment
		(start 385.46913 -353.910646)
		(end 387.02361 -352.356166)
		(width 0.1651)
		(layer "In13.Cu")
		(net "P5E_PEX3_STN6_TX_C_DP<104>")
	)
	(segment
		(start 374.635014 -385.58597)
		(end 374.156986 -384.597148)
		(width 0.1651)
		(layer "In13.Cu")
		(net "P5E_PEX3_STN6_TX_C_DP<104>")
	)
	(segment
		(start 391.447274 -409.799028)
		(end 391.73404 -409.512262)
		(width 0.1651)
		(layer "In13.Cu")
		(net "P5E_PEX3_STN6_TX_C_DP<104>")
	)
	(segment
		(start 179.90947 -98.522536)
		(end 181.560216 -98.522536)
		(width 0.13208)
		(layer "F.Cu")
		(net "NIC3_RBT_ARB_IN")
	)
	(segment
		(start 175.49495 -98.734372)
		(end 177.58537 -98.734372)
		(width 0.13208)
		(layer "F.Cu")
		(net "NIC3_RBT_ARB_IN")
	)
	(segment
		(start 177.58537 -98.734372)
		(end 177.797206 -98.522536)
		(width 0.13208)
		(layer "F.Cu")
		(net "NIC3_RBT_ARB_IN")
	)
	(segment
		(start 181.560216 -98.522536)
		(end 181.877716 -98.840036)
		(width 0.13208)
		(layer "F.Cu")
		(net "NIC3_RBT_ARB_IN")
	)
	(segment
		(start 177.797206 -98.522536)
		(end 179.90947 -98.522536)
		(width 0.13208)
		(layer "F.Cu")
		(net "NIC3_RBT_ARB_IN")
	)
	(segment
		(start 181.877716 -98.840036)
		(end 184.757314 -98.840036)
		(width 0.13208)
		(layer "F.Cu")
		(net "NIC3_RBT_ARB_IN")
	)
	(via
		(at 179.90947 -98.522536)
		(size 0.762)
		(drill 0.381)
		(layers "F.Cu" "B.Cu")
		(net "NIC3_RBT_ARB_IN")
	)
	(segment
		(start 33.504632 -30.353)
		(end 33.2105 -30.058868)
		(width 0.13462)
		(layer "F.Cu")
		(net "P5E_PEX0_STN2_RX_DN<41>")
	)
	(segment
		(start 36.024566 -30.353)
		(end 33.504632 -30.353)
		(width 0.13462)
		(layer "F.Cu")
		(net "P5E_PEX0_STN2_RX_DN<41>")
	)
	(segment
		(start 36.18738 -30.190186)
		(end 36.024566 -30.353)
		(width 0.13462)
		(layer "F.Cu")
		(net "P5E_PEX0_STN2_RX_DN<41>")
	)
	(segment
		(start 36.6649 -30.190186)
		(end 36.18738 -30.190186)
		(width 0.13462)
		(layer "F.Cu")
		(net "P5E_PEX0_STN2_RX_DN<41>")
	)
	(segment
		(start 38.205918 -49.3776)
		(end 36.88969 -39.636954)
		(width 0.1651)
		(layer "In7.Cu")
		(net "P5E_PEX0_STN2_RX_DN<41>")
	)
	(segment
		(start 50.14976 -273.365214)
		(end 50.03546 -273.479514)
		(width 0.1143)
		(layer "In7.Cu")
		(net "P5E_PEX0_STN2_RX_DN<41>")
	)
	(segment
		(start 49.81575 -271.3736)
		(end 49.81575 -271.345152)
		(width 0.1143)
		(layer "In7.Cu")
		(net "P5E_PEX0_STN2_RX_DN<41>")
	)
	(segment
		(start 41.813226 -147.970494)
		(end 42.119296 -119.573802)
		(width 0.1651)
		(layer "In7.Cu")
		(net "P5E_PEX0_STN2_RX_DN<41>")
	)
	(segment
		(start 50.03546 -273.479514)
		(end 49.920906 -273.479514)
		(width 0.1143)
		(layer "In7.Cu")
		(net "P5E_PEX0_STN2_RX_DN<41>")
	)
	(segment
		(start 49.769522 -249.971052)
		(end 41.813226 -147.970494)
		(width 0.1651)
		(layer "In7.Cu")
		(net "P5E_PEX0_STN2_RX_DN<41>")
	)
	(segment
		(start 50.14976 -273.099784)
		(end 50.14976 -273.365214)
		(width 0.1143)
		(layer "In7.Cu")
		(net "P5E_PEX0_STN2_RX_DN<41>")
	)
	(segment
		(start 49.920906 -273.479514)
		(end 49.77003 -273.328638)
		(width 0.1143)
		(layer "In7.Cu")
		(net "P5E_PEX0_STN2_RX_DN<41>")
	)
	(segment
		(start 49.81575 -267.669264)
		(end 49.416716 -263.616948)
		(width 0.1651)
		(layer "In7.Cu")
		(net "P5E_PEX0_STN2_RX_DN<41>")
	)
	(segment
		(start 49.81575 -271.345152)
		(end 49.81575 -267.669264)
		(width 0.1651)
		(layer "In7.Cu")
		(net "P5E_PEX0_STN2_RX_DN<41>")
	)
	(segment
		(start 49.56429 -260.611112)
		(end 49.769522 -249.971052)
		(width 0.1651)
		(layer "In7.Cu")
		(net "P5E_PEX0_STN2_RX_DN<41>")
	)
	(segment
		(start 38.10635 -55.754524)
		(end 38.205918 -49.3776)
		(width 0.1651)
		(layer "In7.Cu")
		(net "P5E_PEX0_STN2_RX_DN<41>")
	)
	(segment
		(start 35.789108 -30.349698)
		(end 33.50133 -30.349698)
		(width 0.1651)
		(layer "In7.Cu")
		(net "P5E_PEX0_STN2_RX_DN<41>")
	)
	(segment
		(start 38.466014 -64.739774)
		(end 38.10635 -55.754524)
		(width 0.1651)
		(layer "In7.Cu")
		(net "P5E_PEX0_STN2_RX_DN<41>")
	)
	(segment
		(start 49.77003 -271.41932)
		(end 49.81575 -271.3736)
		(width 0.1143)
		(layer "In7.Cu")
		(net "P5E_PEX0_STN2_RX_DN<41>")
	)
	(segment
		(start 37.412422 -31.973012)
		(end 35.789108 -30.349698)
		(width 0.1651)
		(layer "In7.Cu")
		(net "P5E_PEX0_STN2_RX_DN<41>")
	)
	(segment
		(start 49.77003 -273.328638)
		(end 49.77003 -271.41932)
		(width 0.1143)
		(layer "In7.Cu")
		(net "P5E_PEX0_STN2_RX_DN<41>")
	)
	(segment
		(start 49.416716 -263.616948)
		(end 49.56429 -260.611112)
		(width 0.1651)
		(layer "In7.Cu")
		(net "P5E_PEX0_STN2_RX_DN<41>")
	)
	(segment
		(start 33.50133 -30.349698)
		(end 33.2105 -30.058868)
		(width 0.1651)
		(layer "In7.Cu")
		(net "P5E_PEX0_STN2_RX_DN<41>")
	)
	(segment
		(start 42.119296 -119.573802)
		(end 41.665652 -104.603296)
		(width 0.1651)
		(layer "In7.Cu")
		(net "P5E_PEX0_STN2_RX_DN<41>")
	)
	(segment
		(start 37.388038 -35.00755)
		(end 37.412422 -31.973012)
		(width 0.1651)
		(layer "In7.Cu")
		(net "P5E_PEX0_STN2_RX_DN<41>")
	)
	(segment
		(start 41.665652 -104.603296)
		(end 38.466014 -64.739774)
		(width 0.1651)
		(layer "In7.Cu")
		(net "P5E_PEX0_STN2_RX_DN<41>")
	)
	(segment
		(start 36.88969 -39.636954)
		(end 36.863274 -37.96284)
		(width 0.1651)
		(layer "In7.Cu")
		(net "P5E_PEX0_STN2_RX_DN<41>")
	)
	(segment
		(start 36.863274 -37.96284)
		(end 37.388038 -35.00755)
		(width 0.1651)
		(layer "In7.Cu")
		(net "P5E_PEX0_STN2_RX_DN<41>")
	)
	(segment
		(start 178.285648 -32.589978)
		(end 178.11877 -32.4231)
		(width 0.13462)
		(layer "F.Cu")
		(net "P5E_PEX1_STN2_RX_DP<38>")
	)
	(segment
		(start 178.764946 -32.589978)
		(end 178.285648 -32.589978)
		(width 0.13462)
		(layer "F.Cu")
		(net "P5E_PEX1_STN2_RX_DP<38>")
	)
	(segment
		(start 178.11877 -32.4231)
		(end 177.463958 -32.4231)
		(width 0.13462)
		(layer "F.Cu")
		(net "P5E_PEX1_STN2_RX_DP<38>")
	)
	(segment
		(start 177.463958 -32.4231)
		(end 177.164746 -32.722312)
		(width 0.13462)
		(layer "F.Cu")
		(net "P5E_PEX1_STN2_RX_DP<38>")
	)
	(segment
		(start 178.967638 -67.907408)
		(end 178.940714 -61.00953)
		(width 0.1651)
		(layer "In7.Cu")
		(net "P5E_PEX1_STN2_RX_DP<38>")
	)
	(segment
		(start 177.73142 -39.731442)
		(end 177.701448 -37.832538)
		(width 0.1651)
		(layer "In7.Cu")
		(net "P5E_PEX1_STN2_RX_DP<38>")
	)
	(segment
		(start 178.137058 -34.179256)
		(end 178.144678 -33.683702)
		(width 0.1651)
		(layer "In7.Cu")
		(net "P5E_PEX1_STN2_RX_DP<38>")
	)
	(segment
		(start 169.099992 -275.684488)
		(end 168.985692 -275.570188)
		(width 0.1143)
		(layer "In7.Cu")
		(net "P5E_PEX1_STN2_RX_DP<38>")
	)
	(segment
		(start 177.913284 -32.431482)
		(end 177.455576 -32.431482)
		(width 0.1651)
		(layer "In7.Cu")
		(net "P5E_PEX1_STN2_RX_DP<38>")
	)
	(segment
		(start 178.108864 -35.647122)
		(end 178.225704 -35.019996)
		(width 0.1651)
		(layer "In7.Cu")
		(net "P5E_PEX1_STN2_RX_DP<38>")
	)
	(segment
		(start 178.940714 -61.00953)
		(end 179.113434 -49.959514)
		(width 0.1651)
		(layer "In7.Cu")
		(net "P5E_PEX1_STN2_RX_DP<38>")
	)
	(segment
		(start 178.237134 -34.28238)
		(end 178.137058 -34.179256)
		(width 0.1651)
		(layer "In7.Cu")
		(net "P5E_PEX1_STN2_RX_DP<38>")
	)
	(segment
		(start 168.985692 -275.570188)
		(end 168.7449 -275.570188)
		(width 0.1143)
		(layer "In7.Cu")
		(net "P5E_PEX1_STN2_RX_DP<38>")
	)
	(segment
		(start 169.099992 -275.949918)
		(end 169.099992 -275.684488)
		(width 0.1143)
		(layer "In7.Cu")
		(net "P5E_PEX1_STN2_RX_DP<38>")
	)
	(segment
		(start 168.567354 -264.812272)
		(end 178.967638 -67.907408)
		(width 0.1651)
		(layer "In7.Cu")
		(net "P5E_PEX1_STN2_RX_DP<38>")
	)
	(segment
		(start 168.529508 -275.354796)
		(end 168.529508 -271.467072)
		(width 0.1143)
		(layer "In7.Cu")
		(net "P5E_PEX1_STN2_RX_DP<38>")
	)
	(segment
		(start 179.113434 -49.959514)
		(end 177.73142 -39.731442)
		(width 0.1651)
		(layer "In7.Cu")
		(net "P5E_PEX1_STN2_RX_DP<38>")
	)
	(segment
		(start 178.225704 -35.019996)
		(end 178.237134 -34.28238)
		(width 0.1651)
		(layer "In7.Cu")
		(net "P5E_PEX1_STN2_RX_DP<38>")
	)
	(segment
		(start 168.7449 -275.570188)
		(end 168.529508 -275.354796)
		(width 0.1143)
		(layer "In7.Cu")
		(net "P5E_PEX1_STN2_RX_DP<38>")
	)
	(segment
		(start 168.483788 -271.392904)
		(end 168.483788 -265.765788)
		(width 0.1651)
		(layer "In7.Cu")
		(net "P5E_PEX1_STN2_RX_DP<38>")
	)
	(segment
		(start 178.144678 -33.683702)
		(end 178.248056 -33.583626)
		(width 0.1651)
		(layer "In7.Cu")
		(net "P5E_PEX1_STN2_RX_DP<38>")
	)
	(segment
		(start 178.260502 -32.7787)
		(end 177.913284 -32.431482)
		(width 0.1651)
		(layer "In7.Cu")
		(net "P5E_PEX1_STN2_RX_DP<38>")
	)
	(segment
		(start 178.248056 -33.583626)
		(end 178.260502 -32.7787)
		(width 0.1651)
		(layer "In7.Cu")
		(net "P5E_PEX1_STN2_RX_DP<38>")
	)
	(segment
		(start 177.980594 -36.334192)
		(end 177.899314 -36.215574)
		(width 0.1651)
		(layer "In7.Cu")
		(net "P5E_PEX1_STN2_RX_DP<38>")
	)
	(segment
		(start 177.701448 -37.832538)
		(end 177.980594 -36.334192)
		(width 0.1651)
		(layer "In7.Cu")
		(net "P5E_PEX1_STN2_RX_DP<38>")
	)
	(segment
		(start 177.455576 -32.431482)
		(end 177.164746 -32.722312)
		(width 0.1651)
		(layer "In7.Cu")
		(net "P5E_PEX1_STN2_RX_DP<38>")
	)
	(segment
		(start 168.483788 -271.421352)
		(end 168.483788 -271.392904)
		(width 0.1143)
		(layer "In7.Cu")
		(net "P5E_PEX1_STN2_RX_DP<38>")
	)
	(segment
		(start 168.529508 -271.467072)
		(end 168.483788 -271.421352)
		(width 0.1143)
		(layer "In7.Cu")
		(net "P5E_PEX1_STN2_RX_DP<38>")
	)
	(segment
		(start 177.899314 -36.215574)
		(end 177.990246 -35.728402)
		(width 0.1651)
		(layer "In7.Cu")
		(net "P5E_PEX1_STN2_RX_DP<38>")
	)
	(segment
		(start 168.483788 -265.765788)
		(end 168.567354 -264.812272)
		(width 0.1651)
		(layer "In7.Cu")
		(net "P5E_PEX1_STN2_RX_DP<38>")
	)
	(segment
		(start 177.990246 -35.728402)
		(end 178.108864 -35.647122)
		(width 0.1651)
		(layer "In7.Cu")
		(net "P5E_PEX1_STN2_RX_DP<38>")
	)
	(segment
		(start 300.21657 -152.1968)
		(end 300.374812 -152.355042)
		(width 0.13462)
		(layer "F.Cu")
		(net "P5E_PEX2_STN0_RX_DP<13>")
	)
	(segment
		(start 297.403012 -152.487376)
		(end 297.693588 -152.1968)
		(width 0.13462)
		(layer "F.Cu")
		(net "P5E_PEX2_STN0_RX_DP<13>")
	)
	(segment
		(start 300.374812 -152.355042)
		(end 300.857412 -152.355042)
		(width 0.13462)
		(layer "F.Cu")
		(net "P5E_PEX2_STN0_RX_DP<13>")
	)
	(segment
		(start 297.693588 -152.1968)
		(end 300.21657 -152.1968)
		(width 0.13462)
		(layer "F.Cu")
		(net "P5E_PEX2_STN0_RX_DP<13>")
	)
	(segment
		(start 302.701706 -156.854398)
		(end 302.979074 -157.265116)
		(width 0.1651)
		(layer "In5.Cu")
		(net "P5E_PEX2_STN0_RX_DP<13>")
	)
	(segment
		(start 308.835298 -273.670014)
		(end 308.949598 -273.784314)
		(width 0.1143)
		(layer "In5.Cu")
		(net "P5E_PEX2_STN0_RX_DP<13>")
	)
	(segment
		(start 308.333902 -271.526)
		(end 308.333902 -271.554448)
		(width 0.1143)
		(layer "In5.Cu")
		(net "P5E_PEX2_STN0_RX_DP<13>")
	)
	(segment
		(start 308.850284 -267.84427)
		(end 308.333902 -270.513048)
		(width 0.1651)
		(layer "In5.Cu")
		(net "P5E_PEX2_STN0_RX_DP<13>")
	)
	(segment
		(start 302.979074 -157.265116)
		(end 303.102518 -157.288992)
		(width 0.1651)
		(layer "In5.Cu")
		(net "P5E_PEX2_STN0_RX_DP<13>")
	)
	(segment
		(start 303.379632 -157.699202)
		(end 303.355756 -157.822646)
		(width 0.1651)
		(layer "In5.Cu")
		(net "P5E_PEX2_STN0_RX_DP<13>")
	)
	(segment
		(start 308.333902 -270.513048)
		(end 308.333902 -271.526)
		(width 0.1651)
		(layer "In5.Cu")
		(net "P5E_PEX2_STN0_RX_DP<13>")
	)
	(segment
		(start 308.379622 -273.45513)
		(end 308.594506 -273.670014)
		(width 0.1143)
		(layer "In5.Cu")
		(net "P5E_PEX2_STN0_RX_DP<13>")
	)
	(segment
		(start 303.102518 -157.288992)
		(end 303.379632 -157.699202)
		(width 0.1651)
		(layer "In5.Cu")
		(net "P5E_PEX2_STN0_RX_DP<13>")
	)
	(segment
		(start 297.693842 -152.196546)
		(end 299.898054 -152.196546)
		(width 0.1651)
		(layer "In5.Cu")
		(net "P5E_PEX2_STN0_RX_DP<13>")
	)
	(segment
		(start 303.355756 -157.822646)
		(end 303.633378 -158.233364)
		(width 0.1651)
		(layer "In5.Cu")
		(net "P5E_PEX2_STN0_RX_DP<13>")
	)
	(segment
		(start 303.756568 -158.25724)
		(end 304.215292 -158.936436)
		(width 0.1651)
		(layer "In5.Cu")
		(net "P5E_PEX2_STN0_RX_DP<13>")
	)
	(segment
		(start 308.333902 -271.554448)
		(end 308.379622 -271.600168)
		(width 0.1143)
		(layer "In5.Cu")
		(net "P5E_PEX2_STN0_RX_DP<13>")
	)
	(segment
		(start 303.633378 -158.233364)
		(end 303.756568 -158.25724)
		(width 0.1651)
		(layer "In5.Cu")
		(net "P5E_PEX2_STN0_RX_DP<13>")
	)
	(segment
		(start 299.898054 -152.196546)
		(end 300.820582 -153.119074)
		(width 0.1651)
		(layer "In5.Cu")
		(net "P5E_PEX2_STN0_RX_DP<13>")
	)
	(segment
		(start 297.403012 -152.487376)
		(end 297.693842 -152.196546)
		(width 0.1651)
		(layer "In5.Cu")
		(net "P5E_PEX2_STN0_RX_DP<13>")
	)
	(segment
		(start 308.379622 -271.600168)
		(end 308.379622 -273.45513)
		(width 0.1143)
		(layer "In5.Cu")
		(net "P5E_PEX2_STN0_RX_DP<13>")
	)
	(segment
		(start 308.949598 -273.784314)
		(end 308.949598 -274.049744)
		(width 0.1143)
		(layer "In5.Cu")
		(net "P5E_PEX2_STN0_RX_DP<13>")
	)
	(segment
		(start 304.215292 -158.936436)
		(end 305.221386 -161.356548)
		(width 0.1651)
		(layer "In5.Cu")
		(net "P5E_PEX2_STN0_RX_DP<13>")
	)
	(segment
		(start 301.681642 -155.185618)
		(end 302.725582 -156.730954)
		(width 0.1651)
		(layer "In5.Cu")
		(net "P5E_PEX2_STN0_RX_DP<13>")
	)
	(segment
		(start 308.775608 -260.651244)
		(end 308.850284 -267.84427)
		(width 0.1651)
		(layer "In5.Cu")
		(net "P5E_PEX2_STN0_RX_DP<13>")
	)
	(segment
		(start 302.725582 -156.730954)
		(end 302.701706 -156.854398)
		(width 0.1651)
		(layer "In5.Cu")
		(net "P5E_PEX2_STN0_RX_DP<13>")
	)
	(segment
		(start 305.221386 -161.356548)
		(end 308.775608 -260.651244)
		(width 0.1651)
		(layer "In5.Cu")
		(net "P5E_PEX2_STN0_RX_DP<13>")
	)
	(segment
		(start 300.820582 -153.119074)
		(end 301.681642 -155.185618)
		(width 0.1651)
		(layer "In5.Cu")
		(net "P5E_PEX2_STN0_RX_DP<13>")
	)
	(segment
		(start 308.594506 -273.670014)
		(end 308.835298 -273.670014)
		(width 0.1143)
		(layer "In5.Cu")
		(net "P5E_PEX2_STN0_RX_DP<13>")
	)
	(segment
		(start 335.3943 -367.862104)
		(end 335.35874 -367.704624)
		(width 0.1651)
		(layer "In9.Cu")
		(net "P5E_PEX2_STN6_RX_DP<101>")
	)
	(segment
		(start 329.010518 -364.812072)
		(end 315.420502 -359.466134)
		(width 0.1651)
		(layer "In9.Cu")
		(net "P5E_PEX2_STN6_RX_DP<101>")
	)
	(segment
		(start 285.121604 -326.089264)
		(end 284.583886 -324.79107)
		(width 0.1651)
		(layer "In9.Cu")
		(net "P5E_PEX2_STN6_RX_DP<101>")
	)
	(segment
		(start 334.940402 -367.439956)
		(end 334.782668 -367.475262)
		(width 0.1651)
		(layer "In9.Cu")
		(net "P5E_PEX2_STN6_RX_DP<101>")
	)
	(segment
		(start 329.060556 -364.927134)
		(end 329.010518 -364.812072)
		(width 0.1651)
		(layer "In9.Cu")
		(net "P5E_PEX2_STN6_RX_DP<101>")
	)
	(segment
		(start 336.541364 -368.452908)
		(end 335.97088 -368.091974)
		(width 0.1651)
		(layer "In9.Cu")
		(net "P5E_PEX2_STN6_RX_DP<101>")
	)
	(segment
		(start 336.73415 -369.319048)
		(end 336.541364 -368.452908)
		(width 0.1651)
		(layer "In9.Cu")
		(net "P5E_PEX2_STN6_RX_DP<101>")
	)
	(segment
		(start 331.811884 -365.914178)
		(end 331.696568 -365.96447)
		(width 0.1651)
		(layer "In9.Cu")
		(net "P5E_PEX2_STN6_RX_DP<101>")
	)
	(segment
		(start 335.97088 -368.091974)
		(end 335.813146 -368.12728)
		(width 0.1651)
		(layer "In9.Cu")
		(net "P5E_PEX2_STN6_RX_DP<101>")
	)
	(segment
		(start 284.583886 -319.8876)
		(end 284.629606 -319.84188)
		(width 0.1143)
		(layer "In9.Cu")
		(net "P5E_PEX2_STN6_RX_DP<101>")
	)
	(segment
		(start 336.017108 -374.899174)
		(end 336.447384 -374.899174)
		(width 0.1651)
		(layer "In9.Cu")
		(net "P5E_PEX2_STN6_RX_DP<101>")
	)
	(segment
		(start 334.328516 -367.052352)
		(end 333.70901 -366.66043)
		(width 0.1651)
		(layer "In9.Cu")
		(net "P5E_PEX2_STN6_RX_DP<101>")
	)
	(segment
		(start 284.583886 -319.916048)
		(end 284.583886 -319.8876)
		(width 0.1143)
		(layer "In9.Cu")
		(net "P5E_PEX2_STN6_RX_DP<101>")
	)
	(segment
		(start 330.609194 -365.53648)
		(end 330.14793 -365.35487)
		(width 0.1651)
		(layer "In9.Cu")
		(net "P5E_PEX2_STN6_RX_DP<101>")
	)
	(segment
		(start 336.73415 -374.612408)
		(end 336.73415 -369.319048)
		(width 0.1651)
		(layer "In9.Cu")
		(net "P5E_PEX2_STN6_RX_DP<101>")
	)
	(segment
		(start 335.35874 -367.704624)
		(end 334.940402 -367.439956)
		(width 0.1651)
		(layer "In9.Cu")
		(net "P5E_PEX2_STN6_RX_DP<101>")
	)
	(segment
		(start 331.185266 -365.667544)
		(end 330.72451 -365.486442)
		(width 0.1651)
		(layer "In9.Cu")
		(net "P5E_PEX2_STN6_RX_DP<101>")
	)
	(segment
		(start 329.52182 -365.108744)
		(end 329.060556 -364.927134)
		(width 0.1651)
		(layer "In9.Cu")
		(net "P5E_PEX2_STN6_RX_DP<101>")
	)
	(segment
		(start 284.583886 -324.79107)
		(end 284.583886 -319.916048)
		(width 0.1651)
		(layer "In9.Cu")
		(net "P5E_PEX2_STN6_RX_DP<101>")
	)
	(segment
		(start 330.097892 -365.239808)
		(end 329.637136 -365.058706)
		(width 0.1651)
		(layer "In9.Cu")
		(net "P5E_PEX2_STN6_RX_DP<101>")
	)
	(segment
		(start 314.62853 -358.68991)
		(end 301.983648 -340.220046)
		(width 0.1651)
		(layer "In9.Cu")
		(net "P5E_PEX2_STN6_RX_DP<101>")
	)
	(segment
		(start 284.629606 -319.84188)
		(end 284.629606 -316.455044)
		(width 0.1143)
		(layer "In9.Cu")
		(net "P5E_PEX2_STN6_RX_DP<101>")
	)
	(segment
		(start 330.72451 -365.486442)
		(end 330.609194 -365.53648)
		(width 0.1651)
		(layer "In9.Cu")
		(net "P5E_PEX2_STN6_RX_DP<101>")
	)
	(segment
		(start 315.420502 -359.466134)
		(end 314.62853 -358.68991)
		(width 0.1651)
		(layer "In9.Cu")
		(net "P5E_PEX2_STN6_RX_DP<101>")
	)
	(segment
		(start 284.855158 -316.229492)
		(end 285.110936 -316.229492)
		(width 0.1143)
		(layer "In9.Cu")
		(net "P5E_PEX2_STN6_RX_DP<101>")
	)
	(segment
		(start 330.14793 -365.35487)
		(end 330.097892 -365.239808)
		(width 0.1651)
		(layer "In9.Cu")
		(net "P5E_PEX2_STN6_RX_DP<101>")
	)
	(segment
		(start 285.110936 -316.229492)
		(end 285.199836 -316.140592)
		(width 0.1143)
		(layer "In9.Cu")
		(net "P5E_PEX2_STN6_RX_DP<101>")
	)
	(segment
		(start 285.199836 -316.140592)
		(end 285.199836 -315.849762)
		(width 0.1143)
		(layer "In9.Cu")
		(net "P5E_PEX2_STN6_RX_DP<101>")
	)
	(segment
		(start 331.696568 -365.96447)
		(end 331.235558 -365.78286)
		(width 0.1651)
		(layer "In9.Cu")
		(net "P5E_PEX2_STN6_RX_DP<101>")
	)
	(segment
		(start 336.447384 -374.899174)
		(end 336.73415 -374.612408)
		(width 0.1651)
		(layer "In9.Cu")
		(net "P5E_PEX2_STN6_RX_DP<101>")
	)
	(segment
		(start 335.813146 -368.12728)
		(end 335.3943 -367.862104)
		(width 0.1651)
		(layer "In9.Cu")
		(net "P5E_PEX2_STN6_RX_DP<101>")
	)
	(segment
		(start 329.637136 -365.058706)
		(end 329.52182 -365.108744)
		(width 0.1651)
		(layer "In9.Cu")
		(net "P5E_PEX2_STN6_RX_DP<101>")
	)
	(segment
		(start 334.363822 -367.210086)
		(end 334.328516 -367.052352)
		(width 0.1651)
		(layer "In9.Cu")
		(net "P5E_PEX2_STN6_RX_DP<101>")
	)
	(segment
		(start 334.782668 -367.475262)
		(end 334.363822 -367.210086)
		(width 0.1651)
		(layer "In9.Cu")
		(net "P5E_PEX2_STN6_RX_DP<101>")
	)
	(segment
		(start 331.235558 -365.78286)
		(end 331.185266 -365.667544)
		(width 0.1651)
		(layer "In9.Cu")
		(net "P5E_PEX2_STN6_RX_DP<101>")
	)
	(segment
		(start 333.70901 -366.66043)
		(end 331.811884 -365.914178)
		(width 0.1651)
		(layer "In9.Cu")
		(net "P5E_PEX2_STN6_RX_DP<101>")
	)
	(segment
		(start 335.890108 -374.390158)
		(end 335.890108 -374.772174)
		(width 0.1651)
		(layer "In9.Cu")
		(net "P5E_PEX2_STN6_RX_DP<101>")
	)
	(segment
		(start 301.983648 -340.220046)
		(end 289.334956 -330.302616)
		(width 0.1651)
		(layer "In9.Cu")
		(net "P5E_PEX2_STN6_RX_DP<101>")
	)
	(segment
		(start 289.334956 -330.302616)
		(end 285.121604 -326.089264)
		(width 0.1651)
		(layer "In9.Cu")
		(net "P5E_PEX2_STN6_RX_DP<101>")
	)
	(segment
		(start 335.890108 -374.772174)
		(end 336.017108 -374.899174)
		(width 0.1651)
		(layer "In9.Cu")
		(net "P5E_PEX2_STN6_RX_DP<101>")
	)
	(segment
		(start 284.629606 -316.455044)
		(end 284.855158 -316.229492)
		(width 0.1143)
		(layer "In9.Cu")
		(net "P5E_PEX2_STN6_RX_DP<101>")
	)
	(segment
		(start 385.205224 -120.113298)
		(end 385.532122 -119.7864)
		(width 0.13462)
		(layer "F.Cu")
		(net "P5E_PEX3_STN1_TX_C_DN<24>")
	)
	(segment
		(start 385.532122 -119.7864)
		(end 393.66698 -119.7864)
		(width 0.13462)
		(layer "F.Cu")
		(net "P5E_PEX3_STN1_TX_C_DN<24>")
	)
	(segment
		(start 393.66698 -119.7864)
		(end 393.835636 -119.955056)
		(width 0.13462)
		(layer "F.Cu")
		(net "P5E_PEX3_STN1_TX_C_DN<24>")
	)
	(segment
		(start 393.835636 -119.955056)
		(end 394.342366 -119.955056)
		(width 0.13462)
		(layer "F.Cu")
		(net "P5E_PEX3_STN1_TX_C_DN<24>")
	)
	(segment
		(start 405.434038 -319.934082)
		(end 405.479758 -319.888362)
		(width 0.1143)
		(layer "In5.Cu")
		(net "P5E_PEX3_STN6_RX_DP<96>")
	)
	(segment
		(start 390.074658 -366.18291)
		(end 389.917178 -366.146334)
		(width 0.1651)
		(layer "In5.Cu")
		(net "P5E_PEX3_STN6_RX_DP<96>")
	)
	(segment
		(start 405.479758 -319.888362)
		(end 405.479758 -318.355472)
		(width 0.1143)
		(layer "In5.Cu")
		(net "P5E_PEX3_STN6_RX_DP<96>")
	)
	(segment
		(start 405.434038 -321.519804)
		(end 405.434038 -319.96253)
		(width 0.1651)
		(layer "In5.Cu")
		(net "P5E_PEX3_STN6_RX_DP<96>")
	)
	(segment
		(start 391.433558 -376.003058)
		(end 391.766044 -375.670572)
		(width 0.1651)
		(layer "In5.Cu")
		(net "P5E_PEX3_STN6_RX_DP<96>")
	)
	(segment
		(start 402.61286 -326.088248)
		(end 404.644606 -323.283834)
		(width 0.1651)
		(layer "In5.Cu")
		(net "P5E_PEX3_STN6_RX_DP<96>")
	)
	(segment
		(start 405.935688 -318.129666)
		(end 406.049988 -318.015366)
		(width 0.1143)
		(layer "In5.Cu")
		(net "P5E_PEX3_STN6_RX_DP<96>")
	)
	(segment
		(start 391.766044 -368.893852)
		(end 390.074404 -366.18291)
		(width 0.1651)
		(layer "In5.Cu")
		(net "P5E_PEX3_STN6_RX_DP<96>")
	)
	(segment
		(start 391.766044 -375.670572)
		(end 391.766044 -368.893852)
		(width 0.1651)
		(layer "In5.Cu")
		(net "P5E_PEX3_STN6_RX_DP<96>")
	)
	(segment
		(start 406.049988 -318.015366)
		(end 406.049988 -317.749936)
		(width 0.1143)
		(layer "In5.Cu")
		(net "P5E_PEX3_STN6_RX_DP<96>")
	)
	(segment
		(start 405.434038 -319.96253)
		(end 405.434038 -319.934082)
		(width 0.1143)
		(layer "In5.Cu")
		(net "P5E_PEX3_STN6_RX_DP<96>")
	)
	(segment
		(start 404.644606 -323.283834)
		(end 405.434038 -321.519804)
		(width 0.1651)
		(layer "In5.Cu")
		(net "P5E_PEX3_STN6_RX_DP<96>")
	)
	(segment
		(start 390.889998 -375.490232)
		(end 390.889998 -375.82983)
		(width 0.1651)
		(layer "In5.Cu")
		(net "P5E_PEX3_STN6_RX_DP<96>")
	)
	(segment
		(start 390.889998 -375.82983)
		(end 391.063226 -376.003058)
		(width 0.1651)
		(layer "In5.Cu")
		(net "P5E_PEX3_STN6_RX_DP<96>")
	)
	(segment
		(start 385.46913 -341.834724)
		(end 386.001768 -341.181436)
		(width 0.1651)
		(layer "In5.Cu")
		(net "P5E_PEX3_STN6_RX_DP<96>")
	)
	(segment
		(start 390.074404 -366.18291)
		(end 390.074658 -366.18291)
		(width 0.1651)
		(layer "In5.Cu")
		(net "P5E_PEX3_STN6_RX_DP<96>")
	)
	(segment
		(start 405.705564 -318.129666)
		(end 405.935688 -318.129666)
		(width 0.1143)
		(layer "In5.Cu")
		(net "P5E_PEX3_STN6_RX_DP<96>")
	)
	(segment
		(start 386.001768 -341.181436)
		(end 402.61286 -326.088248)
		(width 0.1651)
		(layer "In5.Cu")
		(net "P5E_PEX3_STN6_RX_DP<96>")
	)
	(segment
		(start 389.691118 -365.568484)
		(end 385.46913 -358.801924)
		(width 0.1651)
		(layer "In5.Cu")
		(net "P5E_PEX3_STN6_RX_DP<96>")
	)
	(segment
		(start 389.654542 -365.725964)
		(end 389.691118 -365.568484)
		(width 0.1651)
		(layer "In5.Cu")
		(net "P5E_PEX3_STN6_RX_DP<96>")
	)
	(segment
		(start 405.479758 -318.355472)
		(end 405.705564 -318.129666)
		(width 0.1143)
		(layer "In5.Cu")
		(net "P5E_PEX3_STN6_RX_DP<96>")
	)
	(segment
		(start 389.917178 -366.146334)
		(end 389.654542 -365.725964)
		(width 0.1651)
		(layer "In5.Cu")
		(net "P5E_PEX3_STN6_RX_DP<96>")
	)
	(segment
		(start 385.46913 -358.801924)
		(end 385.46913 -341.834724)
		(width 0.1651)
		(layer "In5.Cu")
		(net "P5E_PEX3_STN6_RX_DP<96>")
	)
	(segment
		(start 391.063226 -376.003058)
		(end 391.433558 -376.003058)
		(width 0.1651)
		(layer "In5.Cu")
		(net "P5E_PEX3_STN6_RX_DP<96>")
	)
	(segment
		(start 62.019434 -28.55468)
		(end 61.360558 -28.55468)
		(width 0.13462)
		(layer "F.Cu")
		(net "P5E_PEX0_STN2_RX_DN<36>")
	)
	(segment
		(start 62.664848 -28.390088)
		(end 62.184026 -28.390088)
		(width 0.13462)
		(layer "F.Cu")
		(net "P5E_PEX0_STN2_RX_DN<36>")
	)
	(segment
		(start 61.360558 -28.55468)
		(end 61.064648 -28.25877)
		(width 0.13462)
		(layer "F.Cu")
		(net "P5E_PEX0_STN2_RX_DN<36>")
	)
	(segment
		(start 62.184026 -28.390088)
		(end 62.019434 -28.55468)
		(width 0.13462)
		(layer "F.Cu")
		(net "P5E_PEX0_STN2_RX_DN<36>")
	)
	(segment
		(start 67.306698 -39.169594)
		(end 65.28308 -48.834802)
		(width 0.1651)
		(layer "In7.Cu")
		(net "P5E_PEX0_STN2_RX_DN<36>")
	)
	(segment
		(start 54.56555 -271.421352)
		(end 54.51983 -271.467072)
		(width 0.1143)
		(layer "In7.Cu")
		(net "P5E_PEX0_STN2_RX_DN<36>")
	)
	(segment
		(start 61.357764 -28.551886)
		(end 61.363606 -28.5496)
		(width 0.1651)
		(layer "In7.Cu")
		(net "P5E_PEX0_STN2_RX_DN<36>")
	)
	(segment
		(start 65.28308 -48.834802)
		(end 65.08369 -68.374514)
		(width 0.1651)
		(layer "In7.Cu")
		(net "P5E_PEX0_STN2_RX_DN<36>")
	)
	(segment
		(start 54.56555 -266.499848)
		(end 54.56555 -271.392904)
		(width 0.1651)
		(layer "In7.Cu")
		(net "P5E_PEX0_STN2_RX_DN<36>")
	)
	(segment
		(start 65.08369 -68.374514)
		(end 54.699662 -264.972038)
		(width 0.1651)
		(layer "In7.Cu")
		(net "P5E_PEX0_STN2_RX_DN<36>")
	)
	(segment
		(start 54.51983 -275.275802)
		(end 54.623716 -275.379688)
		(width 0.1143)
		(layer "In7.Cu")
		(net "P5E_PEX0_STN2_RX_DN<36>")
	)
	(segment
		(start 61.363606 -28.5496)
		(end 61.803788 -28.5496)
		(width 0.1651)
		(layer "In7.Cu")
		(net "P5E_PEX0_STN2_RX_DN<36>")
	)
	(segment
		(start 54.623716 -275.379688)
		(end 54.785514 -275.379688)
		(width 0.1143)
		(layer "In7.Cu")
		(net "P5E_PEX0_STN2_RX_DN<36>")
	)
	(segment
		(start 54.785514 -275.379688)
		(end 54.899814 -275.265388)
		(width 0.1143)
		(layer "In7.Cu")
		(net "P5E_PEX0_STN2_RX_DN<36>")
	)
	(segment
		(start 64.70269 -31.448502)
		(end 67.331336 -37.688012)
		(width 0.1651)
		(layer "In7.Cu")
		(net "P5E_PEX0_STN2_RX_DN<36>")
	)
	(segment
		(start 54.899814 -275.265388)
		(end 54.899814 -274.999958)
		(width 0.1143)
		(layer "In7.Cu")
		(net "P5E_PEX0_STN2_RX_DN<36>")
	)
	(segment
		(start 54.699662 -264.972038)
		(end 54.56555 -266.499848)
		(width 0.1651)
		(layer "In7.Cu")
		(net "P5E_PEX0_STN2_RX_DN<36>")
	)
	(segment
		(start 54.56555 -271.392904)
		(end 54.56555 -271.421352)
		(width 0.1143)
		(layer "In7.Cu")
		(net "P5E_PEX0_STN2_RX_DN<36>")
	)
	(segment
		(start 54.51983 -271.467072)
		(end 54.51983 -275.275802)
		(width 0.1143)
		(layer "In7.Cu")
		(net "P5E_PEX0_STN2_RX_DN<36>")
	)
	(segment
		(start 67.331336 -37.688012)
		(end 67.306698 -39.169594)
		(width 0.1651)
		(layer "In7.Cu")
		(net "P5E_PEX0_STN2_RX_DN<36>")
	)
	(segment
		(start 61.803788 -28.5496)
		(end 64.70269 -31.448502)
		(width 0.1651)
		(layer "In7.Cu")
		(net "P5E_PEX0_STN2_RX_DN<36>")
	)
	(segment
		(start 61.064648 -28.25877)
		(end 61.357764 -28.551886)
		(width 0.1651)
		(layer "In7.Cu")
		(net "P5E_PEX0_STN2_RX_DN<36>")
	)
	(segment
		(start 151.46401 -32.4231)
		(end 151.164798 -32.722312)
		(width 0.13462)
		(layer "F.Cu")
		(net "P5E_PEX1_STN2_RX_DP<42>")
	)
	(segment
		(start 152.118822 -32.4231)
		(end 151.46401 -32.4231)
		(width 0.13462)
		(layer "F.Cu")
		(net "P5E_PEX1_STN2_RX_DP<42>")
	)
	(segment
		(start 152.2857 -32.589978)
		(end 152.118822 -32.4231)
		(width 0.13462)
		(layer "F.Cu")
		(net "P5E_PEX1_STN2_RX_DP<42>")
	)
	(segment
		(start 152.764998 -32.589978)
		(end 152.2857 -32.589978)
		(width 0.13462)
		(layer "F.Cu")
		(net "P5E_PEX1_STN2_RX_DP<42>")
	)
	(segment
		(start 165.185598 -275.570188)
		(end 164.944806 -275.570188)
		(width 0.1143)
		(layer "In7.Cu")
		(net "P5E_PEX1_STN2_RX_DP<42>")
	)
	(segment
		(start 152.24887 -33.533842)
		(end 152.260554 -32.7787)
		(width 0.1651)
		(layer "In7.Cu")
		(net "P5E_PEX1_STN2_RX_DP<42>")
	)
	(segment
		(start 151.7015 -37.832538)
		(end 152.006808 -36.19373)
		(width 0.1651)
		(layer "In7.Cu")
		(net "P5E_PEX1_STN2_RX_DP<42>")
	)
	(segment
		(start 164.462714 -258.724654)
		(end 164.63137 -250.005342)
		(width 0.1651)
		(layer "In7.Cu")
		(net "P5E_PEX1_STN2_RX_DP<42>")
	)
	(segment
		(start 156.981652 -119.585994)
		(end 156.53893 -104.96804)
		(width 0.1651)
		(layer "In7.Cu")
		(net "P5E_PEX1_STN2_RX_DP<42>")
	)
	(segment
		(start 151.455628 -32.431482)
		(end 151.164798 -32.722312)
		(width 0.1651)
		(layer "In7.Cu")
		(net "P5E_PEX1_STN2_RX_DP<42>")
	)
	(segment
		(start 164.683694 -267.781786)
		(end 164.239448 -263.273032)
		(width 0.1651)
		(layer "In7.Cu")
		(net "P5E_PEX1_STN2_RX_DP<42>")
	)
	(segment
		(start 151.731472 -39.731442)
		(end 151.7015 -37.832538)
		(width 0.1651)
		(layer "In7.Cu")
		(net "P5E_PEX1_STN2_RX_DP<42>")
	)
	(segment
		(start 152.237948 -34.232596)
		(end 152.137872 -34.129472)
		(width 0.1651)
		(layer "In7.Cu")
		(net "P5E_PEX1_STN2_RX_DP<42>")
	)
	(segment
		(start 152.225756 -35.019996)
		(end 152.237948 -34.232596)
		(width 0.1651)
		(layer "In7.Cu")
		(net "P5E_PEX1_STN2_RX_DP<42>")
	)
	(segment
		(start 153.044906 -49.45253)
		(end 151.731472 -39.731442)
		(width 0.1651)
		(layer "In7.Cu")
		(net "P5E_PEX1_STN2_RX_DP<42>")
	)
	(segment
		(start 151.913336 -32.431482)
		(end 151.455628 -32.431482)
		(width 0.1651)
		(layer "In7.Cu")
		(net "P5E_PEX1_STN2_RX_DP<42>")
	)
	(segment
		(start 164.729414 -271.467072)
		(end 164.683694 -271.421352)
		(width 0.1143)
		(layer "In7.Cu")
		(net "P5E_PEX1_STN2_RX_DP<42>")
	)
	(segment
		(start 152.952704 -55.371238)
		(end 153.044906 -49.45253)
		(width 0.1651)
		(layer "In7.Cu")
		(net "P5E_PEX1_STN2_RX_DP<42>")
	)
	(segment
		(start 152.01646 -35.58794)
		(end 152.135078 -35.50666)
		(width 0.1651)
		(layer "In7.Cu")
		(net "P5E_PEX1_STN2_RX_DP<42>")
	)
	(segment
		(start 164.63137 -250.005342)
		(end 156.675328 -148.011896)
		(width 0.1651)
		(layer "In7.Cu")
		(net "P5E_PEX1_STN2_RX_DP<42>")
	)
	(segment
		(start 165.299898 -275.684488)
		(end 165.185598 -275.570188)
		(width 0.1143)
		(layer "In7.Cu")
		(net "P5E_PEX1_STN2_RX_DP<42>")
	)
	(segment
		(start 164.683694 -271.421352)
		(end 164.683694 -271.392904)
		(width 0.1143)
		(layer "In7.Cu")
		(net "P5E_PEX1_STN2_RX_DP<42>")
	)
	(segment
		(start 165.299898 -275.949918)
		(end 165.299898 -275.684488)
		(width 0.1143)
		(layer "In7.Cu")
		(net "P5E_PEX1_STN2_RX_DP<42>")
	)
	(segment
		(start 164.944806 -275.570188)
		(end 164.729414 -275.354796)
		(width 0.1143)
		(layer "In7.Cu")
		(net "P5E_PEX1_STN2_RX_DP<42>")
	)
	(segment
		(start 164.683694 -271.392904)
		(end 164.683694 -267.781786)
		(width 0.1651)
		(layer "In7.Cu")
		(net "P5E_PEX1_STN2_RX_DP<42>")
	)
	(segment
		(start 153.34488 -65.176654)
		(end 152.952704 -55.371238)
		(width 0.1651)
		(layer "In7.Cu")
		(net "P5E_PEX1_STN2_RX_DP<42>")
	)
	(segment
		(start 152.137872 -34.129472)
		(end 152.145492 -33.633918)
		(width 0.1651)
		(layer "In7.Cu")
		(net "P5E_PEX1_STN2_RX_DP<42>")
	)
	(segment
		(start 156.675328 -148.011896)
		(end 156.981652 -119.585994)
		(width 0.1651)
		(layer "In7.Cu")
		(net "P5E_PEX1_STN2_RX_DP<42>")
	)
	(segment
		(start 164.239448 -263.273032)
		(end 164.462714 -258.724654)
		(width 0.1651)
		(layer "In7.Cu")
		(net "P5E_PEX1_STN2_RX_DP<42>")
	)
	(segment
		(start 152.145492 -33.633918)
		(end 152.24887 -33.533842)
		(width 0.1651)
		(layer "In7.Cu")
		(net "P5E_PEX1_STN2_RX_DP<42>")
	)
	(segment
		(start 152.006808 -36.19373)
		(end 151.925528 -36.075112)
		(width 0.1651)
		(layer "In7.Cu")
		(net "P5E_PEX1_STN2_RX_DP<42>")
	)
	(segment
		(start 152.260554 -32.7787)
		(end 151.913336 -32.431482)
		(width 0.1651)
		(layer "In7.Cu")
		(net "P5E_PEX1_STN2_RX_DP<42>")
	)
	(segment
		(start 152.135078 -35.50666)
		(end 152.225756 -35.019996)
		(width 0.1651)
		(layer "In7.Cu")
		(net "P5E_PEX1_STN2_RX_DP<42>")
	)
	(segment
		(start 156.53893 -104.96804)
		(end 153.34488 -65.176654)
		(width 0.1651)
		(layer "In7.Cu")
		(net "P5E_PEX1_STN2_RX_DP<42>")
	)
	(segment
		(start 164.729414 -275.354796)
		(end 164.729414 -271.467072)
		(width 0.1143)
		(layer "In7.Cu")
		(net "P5E_PEX1_STN2_RX_DP<42>")
	)
	(segment
		(start 151.925528 -36.075112)
		(end 152.01646 -35.58794)
		(width 0.1651)
		(layer "In7.Cu")
		(net "P5E_PEX1_STN2_RX_DP<42>")
	)
	(segment
		(start 300.857412 -155.954984)
		(end 300.374812 -155.954984)
		(width 0.13462)
		(layer "F.Cu")
		(net "P5E_PEX2_STN0_RX_DP<15>")
	)
	(segment
		(start 300.374812 -155.954984)
		(end 300.223428 -155.8036)
		(width 0.13462)
		(layer "F.Cu")
		(net "P5E_PEX2_STN0_RX_DP<15>")
	)
	(segment
		(start 297.68673 -155.8036)
		(end 297.403012 -156.087318)
		(width 0.13462)
		(layer "F.Cu")
		(net "P5E_PEX2_STN0_RX_DP<15>")
	)
	(segment
		(start 300.223428 -155.8036)
		(end 297.68673 -155.8036)
		(width 0.13462)
		(layer "F.Cu")
		(net "P5E_PEX2_STN0_RX_DP<15>")
	)
	(segment
		(start 297.403012 -156.087318)
		(end 297.611546 -155.878784)
		(width 0.1651)
		(layer "In5.Cu")
		(net "P5E_PEX2_STN0_RX_DP<15>")
	)
	(segment
		(start 299.162724 -158.971488)
		(end 299.29201 -159.06877)
		(width 0.1651)
		(layer "In5.Cu")
		(net "P5E_PEX2_STN0_RX_DP<15>")
	)
	(segment
		(start 299.190918 -158.351474)
		(end 299.093636 -158.48076)
		(width 0.1651)
		(layer "In5.Cu")
		(net "P5E_PEX2_STN0_RX_DP<15>")
	)
	(segment
		(start 299.020484 -157.144212)
		(end 298.923202 -157.273498)
		(width 0.1651)
		(layer "In5.Cu")
		(net "P5E_PEX2_STN0_RX_DP<15>")
	)
	(segment
		(start 306.433982 -271.554448)
		(end 306.479702 -271.600168)
		(width 0.1143)
		(layer "In5.Cu")
		(net "P5E_PEX2_STN0_RX_DP<15>")
	)
	(segment
		(start 306.906422 -267.744956)
		(end 306.433982 -270.204692)
		(width 0.1651)
		(layer "In5.Cu")
		(net "P5E_PEX2_STN0_RX_DP<15>")
	)
	(segment
		(start 299.83049 -162.8902)
		(end 306.737258 -261.285482)
		(width 0.1651)
		(layer "In5.Cu")
		(net "P5E_PEX2_STN0_RX_DP<15>")
	)
	(segment
		(start 299.093636 -158.48076)
		(end 299.162724 -158.971488)
		(width 0.1651)
		(layer "In5.Cu")
		(net "P5E_PEX2_STN0_RX_DP<15>")
	)
	(segment
		(start 298.426124 -155.796488)
		(end 298.89704 -156.267404)
		(width 0.1651)
		(layer "In5.Cu")
		(net "P5E_PEX2_STN0_RX_DP<15>")
	)
	(segment
		(start 298.923202 -157.273498)
		(end 298.992544 -157.764226)
		(width 0.1651)
		(layer "In5.Cu")
		(net "P5E_PEX2_STN0_RX_DP<15>")
	)
	(segment
		(start 306.737258 -261.285482)
		(end 306.906422 -267.744956)
		(width 0.1651)
		(layer "In5.Cu")
		(net "P5E_PEX2_STN0_RX_DP<15>")
	)
	(segment
		(start 306.694586 -273.670014)
		(end 306.935378 -273.670014)
		(width 0.1143)
		(layer "In5.Cu")
		(net "P5E_PEX2_STN0_RX_DP<15>")
	)
	(segment
		(start 306.479702 -271.600168)
		(end 306.479702 -273.45513)
		(width 0.1143)
		(layer "In5.Cu")
		(net "P5E_PEX2_STN0_RX_DP<15>")
	)
	(segment
		(start 306.433982 -271.526)
		(end 306.433982 -271.554448)
		(width 0.1143)
		(layer "In5.Cu")
		(net "P5E_PEX2_STN0_RX_DP<15>")
	)
	(segment
		(start 299.12183 -157.861254)
		(end 299.190918 -158.351474)
		(width 0.1651)
		(layer "In5.Cu")
		(net "P5E_PEX2_STN0_RX_DP<15>")
	)
	(segment
		(start 299.29201 -159.06877)
		(end 299.83049 -162.8902)
		(width 0.1651)
		(layer "In5.Cu")
		(net "P5E_PEX2_STN0_RX_DP<15>")
	)
	(segment
		(start 297.611546 -155.878784)
		(end 297.810428 -155.796488)
		(width 0.1651)
		(layer "In5.Cu")
		(net "P5E_PEX2_STN0_RX_DP<15>")
	)
	(segment
		(start 297.810428 -155.796488)
		(end 298.426124 -155.796488)
		(width 0.1651)
		(layer "In5.Cu")
		(net "P5E_PEX2_STN0_RX_DP<15>")
	)
	(segment
		(start 298.89704 -156.267404)
		(end 299.020484 -157.144212)
		(width 0.1651)
		(layer "In5.Cu")
		(net "P5E_PEX2_STN0_RX_DP<15>")
	)
	(segment
		(start 307.049678 -273.784314)
		(end 307.049678 -274.049744)
		(width 0.1143)
		(layer "In5.Cu")
		(net "P5E_PEX2_STN0_RX_DP<15>")
	)
	(segment
		(start 298.992544 -157.764226)
		(end 299.12183 -157.861254)
		(width 0.1651)
		(layer "In5.Cu")
		(net "P5E_PEX2_STN0_RX_DP<15>")
	)
	(segment
		(start 306.433982 -270.204692)
		(end 306.433982 -271.526)
		(width 0.1651)
		(layer "In5.Cu")
		(net "P5E_PEX2_STN0_RX_DP<15>")
	)
	(segment
		(start 306.479702 -273.45513)
		(end 306.694586 -273.670014)
		(width 0.1143)
		(layer "In5.Cu")
		(net "P5E_PEX2_STN0_RX_DP<15>")
	)
	(segment
		(start 306.935378 -273.670014)
		(end 307.049678 -273.784314)
		(width 0.1143)
		(layer "In5.Cu")
		(net "P5E_PEX2_STN0_RX_DP<15>")
	)
	(segment
		(start 304.67808 -337.37296)
		(end 305.702462 -338.460842)
		(width 0.1651)
		(layer "In5.Cu")
		(net "P5E_PEX2_STN6_RX_DN<108>")
	)
	(segment
		(start 337.41614 -393.51712)
		(end 339.01126 -395.097)
		(width 0.1651)
		(layer "In5.Cu")
		(net "P5E_PEX2_STN6_RX_DN<108>")
	)
	(segment
		(start 334.72247 -391.689082)
		(end 337.41614 -393.51712)
		(width 0.1651)
		(layer "In5.Cu")
		(net "P5E_PEX2_STN6_RX_DN<108>")
	)
	(segment
		(start 338.090002 -402.408136)
		(end 338.090002 -402.790152)
		(width 0.1651)
		(layer "In5.Cu")
		(net "P5E_PEX2_STN6_RX_DN<108>")
	)
	(segment
		(start 328.784966 -389.224774)
		(end 334.72247 -391.689082)
		(width 0.1651)
		(layer "In5.Cu")
		(net "P5E_PEX2_STN6_RX_DN<108>")
	)
	(segment
		(start 278.653748 -323.172328)
		(end 279.481788 -323.75729)
		(width 0.1651)
		(layer "In5.Cu")
		(net "P5E_PEX2_STN6_RX_DN<108>")
	)
	(segment
		(start 338.217002 -402.281136)
		(end 338.090002 -402.408136)
		(width 0.1651)
		(layer "In5.Cu")
		(net "P5E_PEX2_STN6_RX_DN<108>")
	)
	(segment
		(start 278.215852 -322.11391)
		(end 278.653748 -323.172328)
		(width 0.1651)
		(layer "In5.Cu")
		(net "P5E_PEX2_STN6_RX_DN<108>")
	)
	(segment
		(start 327.56856 -388.015226)
		(end 328.784966 -389.224774)
		(width 0.1651)
		(layer "In5.Cu")
		(net "P5E_PEX2_STN6_RX_DN<108>")
	)
	(segment
		(start 278.549862 -318.434466)
		(end 278.435562 -318.320166)
		(width 0.1143)
		(layer "In5.Cu")
		(net "P5E_PEX2_STN6_RX_DN<108>")
	)
	(segment
		(start 278.215852 -319.995296)
		(end 278.215852 -322.11391)
		(width 0.1651)
		(layer "In5.Cu")
		(net "P5E_PEX2_STN6_RX_DN<108>")
	)
	(segment
		(start 316.010544 -361.57789)
		(end 327.56856 -388.015226)
		(width 0.1651)
		(layer "In5.Cu")
		(net "P5E_PEX2_STN6_RX_DN<108>")
	)
	(segment
		(start 338.764118 -402.281136)
		(end 338.217002 -402.281136)
		(width 0.1651)
		(layer "In5.Cu")
		(net "P5E_PEX2_STN6_RX_DN<108>")
	)
	(segment
		(start 278.170132 -319.921128)
		(end 278.215852 -319.966848)
		(width 0.1143)
		(layer "In5.Cu")
		(net "P5E_PEX2_STN6_RX_DN<108>")
	)
	(segment
		(start 339.01126 -395.097)
		(end 339.215984 -395.615668)
		(width 0.1651)
		(layer "In5.Cu")
		(net "P5E_PEX2_STN6_RX_DN<108>")
	)
	(segment
		(start 278.284432 -318.320166)
		(end 278.170132 -318.434466)
		(width 0.1143)
		(layer "In5.Cu")
		(net "P5E_PEX2_STN6_RX_DN<108>")
	)
	(segment
		(start 315.45022 -360.756962)
		(end 316.010544 -361.57789)
		(width 0.1651)
		(layer "In5.Cu")
		(net "P5E_PEX2_STN6_RX_DN<108>")
	)
	(segment
		(start 305.702462 -338.460842)
		(end 315.45022 -360.756962)
		(width 0.1651)
		(layer "In5.Cu")
		(net "P5E_PEX2_STN6_RX_DN<108>")
	)
	(segment
		(start 279.481788 -323.75729)
		(end 304.67808 -337.37296)
		(width 0.1651)
		(layer "In5.Cu")
		(net "P5E_PEX2_STN6_RX_DN<108>")
	)
	(segment
		(start 278.170132 -318.434466)
		(end 278.170132 -319.921128)
		(width 0.1143)
		(layer "In5.Cu")
		(net "P5E_PEX2_STN6_RX_DN<108>")
	)
	(segment
		(start 339.215984 -395.615668)
		(end 339.215984 -401.82927)
		(width 0.1651)
		(layer "In5.Cu")
		(net "P5E_PEX2_STN6_RX_DN<108>")
	)
	(segment
		(start 278.549862 -318.699896)
		(end 278.549862 -318.434466)
		(width 0.1143)
		(layer "In5.Cu")
		(net "P5E_PEX2_STN6_RX_DN<108>")
	)
	(segment
		(start 339.215984 -401.82927)
		(end 338.764118 -402.281136)
		(width 0.1651)
		(layer "In5.Cu")
		(net "P5E_PEX2_STN6_RX_DN<108>")
	)
	(segment
		(start 278.215852 -319.966848)
		(end 278.215852 -319.995296)
		(width 0.1143)
		(layer "In5.Cu")
		(net "P5E_PEX2_STN6_RX_DN<108>")
	)
	(segment
		(start 278.435562 -318.320166)
		(end 278.284432 -318.320166)
		(width 0.1143)
		(layer "In5.Cu")
		(net "P5E_PEX2_STN6_RX_DN<108>")
	)
	(segment
		(start 402.107654 -119.51208)
		(end 399.582132 -119.51208)
		(width 0.13462)
		(layer "F.Cu")
		(net "P5E_PEX3_STN1_RX_DP<24>")
	)
	(segment
		(start 399.582132 -119.51208)
		(end 399.42516 -119.355108)
		(width 0.13462)
		(layer "F.Cu")
		(net "P5E_PEX3_STN1_RX_DP<24>")
	)
	(segment
		(start 399.42516 -119.355108)
		(end 398.94256 -119.355108)
		(width 0.13462)
		(layer "F.Cu")
		(net "P5E_PEX3_STN1_RX_DP<24>")
	)
	(segment
		(start 402.39696 -119.222774)
		(end 402.107654 -119.51208)
		(width 0.13462)
		(layer "F.Cu")
		(net "P5E_PEX3_STN1_RX_DP<24>")
	)
	(segment
		(start 415.549588 -273.784314)
		(end 415.549588 -274.049744)
		(width 0.1143)
		(layer "In5.Cu")
		(net "P5E_PEX3_STN1_RX_DP<24>")
	)
	(segment
		(start 384.367024 -151.562054)
		(end 384.802888 -158.20644)
		(width 0.1651)
		(layer "In5.Cu")
		(net "P5E_PEX3_STN1_RX_DP<24>")
	)
	(segment
		(start 387.598666 -140.622274)
		(end 385.547108 -145.16735)
		(width 0.1651)
		(layer "In5.Cu")
		(net "P5E_PEX3_STN1_RX_DP<24>")
	)
	(segment
		(start 392.696446 -125.476508)
		(end 391.074148 -127.992124)
		(width 0.1651)
		(layer "In5.Cu")
		(net "P5E_PEX3_STN1_RX_DP<24>")
	)
	(segment
		(start 384.802888 -158.20644)
		(end 385.806696 -163.938458)
		(width 0.1651)
		(layer "In5.Cu")
		(net "P5E_PEX3_STN1_RX_DP<24>")
	)
	(segment
		(start 414.933892 -268.419834)
		(end 414.933892 -271.526)
		(width 0.1651)
		(layer "In5.Cu")
		(net "P5E_PEX3_STN1_RX_DP<24>")
	)
	(segment
		(start 402.10613 -119.513604)
		(end 400.357086 -119.513604)
		(width 0.1651)
		(layer "In5.Cu")
		(net "P5E_PEX3_STN1_RX_DP<24>")
	)
	(segment
		(start 389.303006 -137.613898)
		(end 387.598666 -140.622274)
		(width 0.1651)
		(layer "In5.Cu")
		(net "P5E_PEX3_STN1_RX_DP<24>")
	)
	(segment
		(start 414.933892 -271.526)
		(end 414.933892 -271.554448)
		(width 0.1143)
		(layer "In5.Cu")
		(net "P5E_PEX3_STN1_RX_DP<24>")
	)
	(segment
		(start 400.357086 -119.513604)
		(end 398.312132 -120.150382)
		(width 0.1651)
		(layer "In5.Cu")
		(net "P5E_PEX3_STN1_RX_DP<24>")
	)
	(segment
		(start 415.194496 -273.670014)
		(end 415.435288 -273.670014)
		(width 0.1143)
		(layer "In5.Cu")
		(net "P5E_PEX3_STN1_RX_DP<24>")
	)
	(segment
		(start 385.547108 -145.16735)
		(end 384.367024 -151.562054)
		(width 0.1651)
		(layer "In5.Cu")
		(net "P5E_PEX3_STN1_RX_DP<24>")
	)
	(segment
		(start 414.979612 -271.600168)
		(end 414.979612 -273.45513)
		(width 0.1143)
		(layer "In5.Cu")
		(net "P5E_PEX3_STN1_RX_DP<24>")
	)
	(segment
		(start 402.39696 -119.222774)
		(end 402.10613 -119.513604)
		(width 0.1651)
		(layer "In5.Cu")
		(net "P5E_PEX3_STN1_RX_DP<24>")
	)
	(segment
		(start 415.435288 -273.670014)
		(end 415.549588 -273.784314)
		(width 0.1143)
		(layer "In5.Cu")
		(net "P5E_PEX3_STN1_RX_DP<24>")
	)
	(segment
		(start 414.979612 -273.45513)
		(end 415.194496 -273.670014)
		(width 0.1143)
		(layer "In5.Cu")
		(net "P5E_PEX3_STN1_RX_DP<24>")
	)
	(segment
		(start 385.806696 -163.938458)
		(end 414.933892 -268.419834)
		(width 0.1651)
		(layer "In5.Cu")
		(net "P5E_PEX3_STN1_RX_DP<24>")
	)
	(segment
		(start 414.933892 -271.554448)
		(end 414.979612 -271.600168)
		(width 0.1143)
		(layer "In5.Cu")
		(net "P5E_PEX3_STN1_RX_DP<24>")
	)
	(segment
		(start 398.312132 -120.150382)
		(end 392.696446 -125.476508)
		(width 0.1651)
		(layer "In5.Cu")
		(net "P5E_PEX3_STN1_RX_DP<24>")
	)
	(segment
		(start 391.074148 -127.992124)
		(end 390.721596 -128.909064)
		(width 0.1651)
		(layer "In5.Cu")
		(net "P5E_PEX3_STN1_RX_DP<24>")
	)
	(segment
		(start 390.721596 -128.909064)
		(end 389.303006 -137.613898)
		(width 0.1651)
		(layer "In5.Cu")
		(net "P5E_PEX3_STN1_RX_DP<24>")
	)
	(segment
		(start 403.908514 -322.497958)
		(end 404.484078 -321.211956)
		(width 0.1651)
		(layer "In5.Cu")
		(net "P5E_PEX3_STN6_RX_DP<97>")
	)
	(segment
		(start 388.68985 -374.729756)
		(end 388.863078 -374.902984)
		(width 0.1651)
		(layer "In5.Cu")
		(net "P5E_PEX3_STN6_RX_DP<97>")
	)
	(segment
		(start 385.293108 -362.850684)
		(end 382.36017 -358.812846)
		(width 0.1651)
		(layer "In5.Cu")
		(net "P5E_PEX3_STN6_RX_DP<97>")
	)
	(segment
		(start 386.275834 -364.397798)
		(end 385.984496 -363.996732)
		(width 0.1651)
		(layer "In5.Cu")
		(net "P5E_PEX3_STN6_RX_DP<97>")
	)
	(segment
		(start 382.36017 -358.812846)
		(end 382.36017 -341.980774)
		(width 0.1651)
		(layer "In5.Cu")
		(net "P5E_PEX3_STN6_RX_DP<97>")
	)
	(segment
		(start 382.36017 -341.980774)
		(end 383.2606 -340.63686)
		(width 0.1651)
		(layer "In5.Cu")
		(net "P5E_PEX3_STN6_RX_DP<97>")
	)
	(segment
		(start 385.984496 -363.996732)
		(end 386.009896 -363.83722)
		(width 0.1651)
		(layer "In5.Cu")
		(net "P5E_PEX3_STN6_RX_DP<97>")
	)
	(segment
		(start 385.5593 -363.411262)
		(end 385.267962 -363.01045)
		(width 0.1651)
		(layer "In5.Cu")
		(net "P5E_PEX3_STN6_RX_DP<97>")
	)
	(segment
		(start 383.2606 -340.63686)
		(end 401.868386 -325.185786)
		(width 0.1651)
		(layer "In5.Cu")
		(net "P5E_PEX3_STN6_RX_DP<97>")
	)
	(segment
		(start 386.992368 -365.384334)
		(end 386.70103 -364.983268)
		(width 0.1651)
		(layer "In5.Cu")
		(net "P5E_PEX3_STN6_RX_DP<97>")
	)
	(segment
		(start 387.152134 -365.409734)
		(end 386.992368 -365.384334)
		(width 0.1651)
		(layer "In5.Cu")
		(net "P5E_PEX3_STN6_RX_DP<97>")
	)
	(segment
		(start 404.755604 -316.229492)
		(end 404.985728 -316.229492)
		(width 0.1143)
		(layer "In5.Cu")
		(net "P5E_PEX3_STN6_RX_DP<97>")
	)
	(segment
		(start 386.435346 -364.423198)
		(end 386.275834 -364.397798)
		(width 0.1651)
		(layer "In5.Cu")
		(net "P5E_PEX3_STN6_RX_DP<97>")
	)
	(segment
		(start 404.529798 -319.888362)
		(end 404.529798 -316.455298)
		(width 0.1143)
		(layer "In5.Cu")
		(net "P5E_PEX3_STN6_RX_DP<97>")
	)
	(segment
		(start 404.985728 -316.229492)
		(end 405.100028 -316.115192)
		(width 0.1143)
		(layer "In5.Cu")
		(net "P5E_PEX3_STN6_RX_DP<97>")
	)
	(segment
		(start 404.484078 -321.211956)
		(end 404.484078 -319.96253)
		(width 0.1651)
		(layer "In5.Cu")
		(net "P5E_PEX3_STN6_RX_DP<97>")
	)
	(segment
		(start 404.484078 -319.96253)
		(end 404.484078 -319.934082)
		(width 0.1143)
		(layer "In5.Cu")
		(net "P5E_PEX3_STN6_RX_DP<97>")
	)
	(segment
		(start 385.718812 -363.436662)
		(end 385.5593 -363.411262)
		(width 0.1651)
		(layer "In5.Cu")
		(net "P5E_PEX3_STN6_RX_DP<97>")
	)
	(segment
		(start 389.23341 -374.902984)
		(end 389.565896 -374.570498)
		(width 0.1651)
		(layer "In5.Cu")
		(net "P5E_PEX3_STN6_RX_DP<97>")
	)
	(segment
		(start 385.267962 -363.01045)
		(end 385.293108 -362.850684)
		(width 0.1651)
		(layer "In5.Cu")
		(net "P5E_PEX3_STN6_RX_DP<97>")
	)
	(segment
		(start 386.009896 -363.83722)
		(end 385.718812 -363.436662)
		(width 0.1651)
		(layer "In5.Cu")
		(net "P5E_PEX3_STN6_RX_DP<97>")
	)
	(segment
		(start 389.565896 -374.570498)
		(end 389.565896 -368.732562)
		(width 0.1651)
		(layer "In5.Cu")
		(net "P5E_PEX3_STN6_RX_DP<97>")
	)
	(segment
		(start 405.100028 -316.115192)
		(end 405.100028 -315.849762)
		(width 0.1143)
		(layer "In5.Cu")
		(net "P5E_PEX3_STN6_RX_DP<97>")
	)
	(segment
		(start 389.565896 -368.732562)
		(end 387.152134 -365.409734)
		(width 0.1651)
		(layer "In5.Cu")
		(net "P5E_PEX3_STN6_RX_DP<97>")
	)
	(segment
		(start 404.529798 -316.455298)
		(end 404.755604 -316.229492)
		(width 0.1143)
		(layer "In5.Cu")
		(net "P5E_PEX3_STN6_RX_DP<97>")
	)
	(segment
		(start 388.68985 -374.390158)
		(end 388.68985 -374.729756)
		(width 0.1651)
		(layer "In5.Cu")
		(net "P5E_PEX3_STN6_RX_DP<97>")
	)
	(segment
		(start 386.72643 -364.823756)
		(end 386.435346 -364.423198)
		(width 0.1651)
		(layer "In5.Cu")
		(net "P5E_PEX3_STN6_RX_DP<97>")
	)
	(segment
		(start 386.70103 -364.983268)
		(end 386.72643 -364.823756)
		(width 0.1651)
		(layer "In5.Cu")
		(net "P5E_PEX3_STN6_RX_DP<97>")
	)
	(segment
		(start 401.868386 -325.185786)
		(end 403.908514 -322.497958)
		(width 0.1651)
		(layer "In5.Cu")
		(net "P5E_PEX3_STN6_RX_DP<97>")
	)
	(segment
		(start 404.484078 -319.934082)
		(end 404.529798 -319.888362)
		(width 0.1143)
		(layer "In5.Cu")
		(net "P5E_PEX3_STN6_RX_DP<97>")
	)
	(segment
		(start 388.863078 -374.902984)
		(end 389.23341 -374.902984)
		(width 0.1651)
		(layer "In5.Cu")
		(net "P5E_PEX3_STN6_RX_DP<97>")
	)
	(segment
		(start 189.357508 -104.840024)
		(end 190.83782 -104.840024)
		(width 0.13208)
		(layer "F.Cu")
		(net "NCSI_NIC3_CRS_DV")
	)
	(segment
		(start 190.83782 -104.840024)
		(end 191.791844 -103.886)
		(width 0.13208)
		(layer "F.Cu")
		(net "NCSI_NIC3_CRS_DV")
	)
	(via
		(at 191.791844 -103.886)
		(size 0.508)
		(drill 0.254)
		(layers "F.Cu" "B.Cu")
		(net "NCSI_NIC3_CRS_DV")
	)
	(segment
		(start 192.53454 -104.120696)
		(end 192.299844 -103.886)
		(width 0.13208)
		(layer "B.Cu")
		(net "NCSI_NIC3_CRS_DV")
	)
	(segment
		(start 193.241676 -104.120696)
		(end 192.53454 -104.120696)
		(width 0.13208)
		(layer "B.Cu")
		(net "NCSI_NIC3_CRS_DV")
	)
	(segment
		(start 192.299844 -103.886)
		(end 191.791844 -103.886)
		(width 0.13208)
		(layer "B.Cu")
		(net "NCSI_NIC3_CRS_DV")
	)
	(segment
		(start 267.651992 -25.390094)
		(end 268.864842 -25.390094)
		(width 0.13208)
		(layer "F.Cu")
		(net "PRSNT_SSD9_N")
	)
	(segment
		(start 267.102082 -26.266394)
		(end 266.320524 -26.266394)
		(width 0.13208)
		(layer "F.Cu")
		(net "PRSNT_SSD9_N")
	)
	(segment
		(start 267.102082 -26.266394)
		(end 267.102082 -25.940004)
		(width 0.13208)
		(layer "F.Cu")
		(net "PRSNT_SSD9_N")
	)
	(segment
		(start 267.102082 -25.940004)
		(end 267.651992 -25.390094)
		(width 0.13208)
		(layer "F.Cu")
		(net "PRSNT_SSD9_N")
	)
	(via
		(at 267.102082 -26.266394)
		(size 0.508)
		(drill 0.254)
		(layers "F.Cu" "B.Cu")
		(net "PRSNT_SSD9_N")
	)
	(segment
		(start 36.6649 -30.790134)
		(end 36.1823 -30.790134)
		(width 0.13462)
		(layer "F.Cu")
		(net "P5E_PEX0_STN2_RX_DP<41>")
	)
	(segment
		(start 33.505648 -30.62732)
		(end 33.2105 -30.922468)
		(width 0.13462)
		(layer "F.Cu")
		(net "P5E_PEX0_STN2_RX_DP<41>")
	)
	(segment
		(start 36.019486 -30.62732)
		(end 33.505648 -30.62732)
		(width 0.13462)
		(layer "F.Cu")
		(net "P5E_PEX0_STN2_RX_DP<41>")
	)
	(segment
		(start 36.1823 -30.790134)
		(end 36.019486 -30.62732)
		(width 0.13462)
		(layer "F.Cu")
		(net "P5E_PEX0_STN2_RX_DP<41>")
	)
	(segment
		(start 36.779454 -31.738824)
		(end 37.129466 -32.088836)
		(width 0.1651)
		(layer "In7.Cu")
		(net "P5E_PEX0_STN2_RX_DP<41>")
	)
	(segment
		(start 49.53381 -267.683234)
		(end 49.53381 -271.345152)
		(width 0.1651)
		(layer "In7.Cu")
		(net "P5E_PEX0_STN2_RX_DP<41>")
	)
	(segment
		(start 49.57953 -271.41932)
		(end 49.57953 -273.407632)
		(width 0.1143)
		(layer "In7.Cu")
		(net "P5E_PEX0_STN2_RX_DP<41>")
	)
	(segment
		(start 36.608004 -39.658036)
		(end 37.92347 -49.394364)
		(width 0.1651)
		(layer "In7.Cu")
		(net "P5E_PEX0_STN2_RX_DP<41>")
	)
	(segment
		(start 34.57575 -30.733238)
		(end 35.07105 -30.733238)
		(width 0.1651)
		(layer "In7.Cu")
		(net "P5E_PEX0_STN2_RX_DP<41>")
	)
	(segment
		(start 38.184328 -64.756792)
		(end 41.383966 -104.61879)
		(width 0.1651)
		(layer "In7.Cu")
		(net "P5E_PEX0_STN2_RX_DP<41>")
	)
	(segment
		(start 41.837102 -119.576596)
		(end 41.531032 -147.979892)
		(width 0.1651)
		(layer "In7.Cu")
		(net "P5E_PEX0_STN2_RX_DP<41>")
	)
	(segment
		(start 49.487328 -249.979434)
		(end 49.28235 -260.60146)
		(width 0.1651)
		(layer "In7.Cu")
		(net "P5E_PEX0_STN2_RX_DP<41>")
	)
	(segment
		(start 49.134014 -263.623806)
		(end 49.53381 -267.683234)
		(width 0.1651)
		(layer "In7.Cu")
		(net "P5E_PEX0_STN2_RX_DP<41>")
	)
	(segment
		(start 49.841912 -273.670014)
		(end 50.03546 -273.670014)
		(width 0.1143)
		(layer "In7.Cu")
		(net "P5E_PEX0_STN2_RX_DP<41>")
	)
	(segment
		(start 50.03546 -273.670014)
		(end 50.14976 -273.784314)
		(width 0.1143)
		(layer "In7.Cu")
		(net "P5E_PEX0_STN2_RX_DP<41>")
	)
	(segment
		(start 33.2105 -30.922468)
		(end 33.50133 -30.631638)
		(width 0.1651)
		(layer "In7.Cu")
		(net "P5E_PEX0_STN2_RX_DP<41>")
	)
	(segment
		(start 41.531032 -147.979892)
		(end 49.487328 -249.979434)
		(width 0.1651)
		(layer "In7.Cu")
		(net "P5E_PEX0_STN2_RX_DP<41>")
	)
	(segment
		(start 37.824156 -55.75808)
		(end 38.184328 -64.756792)
		(width 0.1651)
		(layer "In7.Cu")
		(net "P5E_PEX0_STN2_RX_DP<41>")
	)
	(segment
		(start 35.07105 -30.733238)
		(end 35.17265 -30.631638)
		(width 0.1651)
		(layer "In7.Cu")
		(net "P5E_PEX0_STN2_RX_DP<41>")
	)
	(segment
		(start 37.106098 -34.981642)
		(end 36.580826 -37.940234)
		(width 0.1651)
		(layer "In7.Cu")
		(net "P5E_PEX0_STN2_RX_DP<41>")
	)
	(segment
		(start 36.607496 -39.641272)
		(end 36.608004 -39.658036)
		(width 0.1651)
		(layer "In7.Cu")
		(net "P5E_PEX0_STN2_RX_DP<41>")
	)
	(segment
		(start 35.17265 -30.631638)
		(end 35.672268 -30.631638)
		(width 0.1651)
		(layer "In7.Cu")
		(net "P5E_PEX0_STN2_RX_DP<41>")
	)
	(segment
		(start 37.129466 -32.088836)
		(end 37.106098 -34.981642)
		(width 0.1651)
		(layer "In7.Cu")
		(net "P5E_PEX0_STN2_RX_DP<41>")
	)
	(segment
		(start 36.63569 -31.738824)
		(end 36.779454 -31.738824)
		(width 0.1651)
		(layer "In7.Cu")
		(net "P5E_PEX0_STN2_RX_DP<41>")
	)
	(segment
		(start 49.57953 -273.407632)
		(end 49.841912 -273.670014)
		(width 0.1143)
		(layer "In7.Cu")
		(net "P5E_PEX0_STN2_RX_DP<41>")
	)
	(segment
		(start 36.60775 -39.641272)
		(end 36.607496 -39.641272)
		(width 0.1651)
		(layer "In7.Cu")
		(net "P5E_PEX0_STN2_RX_DP<41>")
	)
	(segment
		(start 49.28235 -260.60146)
		(end 49.134014 -263.623806)
		(width 0.1651)
		(layer "In7.Cu")
		(net "P5E_PEX0_STN2_RX_DP<41>")
	)
	(segment
		(start 34.47415 -30.631638)
		(end 34.57575 -30.733238)
		(width 0.1651)
		(layer "In7.Cu")
		(net "P5E_PEX0_STN2_RX_DP<41>")
	)
	(segment
		(start 37.92347 -49.394364)
		(end 37.824156 -55.75808)
		(width 0.1651)
		(layer "In7.Cu")
		(net "P5E_PEX0_STN2_RX_DP<41>")
	)
	(segment
		(start 49.53381 -271.345152)
		(end 49.53381 -271.3736)
		(width 0.1143)
		(layer "In7.Cu")
		(net "P5E_PEX0_STN2_RX_DP<41>")
	)
	(segment
		(start 36.580826 -37.940234)
		(end 36.60775 -39.641272)
		(width 0.1651)
		(layer "In7.Cu")
		(net "P5E_PEX0_STN2_RX_DP<41>")
	)
	(segment
		(start 33.50133 -30.631638)
		(end 34.47415 -30.631638)
		(width 0.1651)
		(layer "In7.Cu")
		(net "P5E_PEX0_STN2_RX_DP<41>")
	)
	(segment
		(start 36.28517 -31.388304)
		(end 36.63569 -31.738824)
		(width 0.1651)
		(layer "In7.Cu")
		(net "P5E_PEX0_STN2_RX_DP<41>")
	)
	(segment
		(start 36.28517 -31.24454)
		(end 36.28517 -31.388304)
		(width 0.1651)
		(layer "In7.Cu")
		(net "P5E_PEX0_STN2_RX_DP<41>")
	)
	(segment
		(start 41.383966 -104.61879)
		(end 41.837102 -119.576596)
		(width 0.1651)
		(layer "In7.Cu")
		(net "P5E_PEX0_STN2_RX_DP<41>")
	)
	(segment
		(start 50.14976 -273.784314)
		(end 50.14976 -274.049744)
		(width 0.1143)
		(layer "In7.Cu")
		(net "P5E_PEX0_STN2_RX_DP<41>")
	)
	(segment
		(start 49.53381 -271.3736)
		(end 49.57953 -271.41932)
		(width 0.1143)
		(layer "In7.Cu")
		(net "P5E_PEX0_STN2_RX_DP<41>")
	)
	(segment
		(start 35.672268 -30.631638)
		(end 36.28517 -31.24454)
		(width 0.1651)
		(layer "In7.Cu")
		(net "P5E_PEX0_STN2_RX_DP<41>")
	)
	(segment
		(start 152.124664 -33.952942)
		(end 149.60473 -33.952942)
		(width 0.13462)
		(layer "F.Cu")
		(net "P5E_PEX1_STN2_RX_DN<43>")
	)
	(segment
		(start 152.287478 -33.790128)
		(end 152.124664 -33.952942)
		(width 0.13462)
		(layer "F.Cu")
		(net "P5E_PEX1_STN2_RX_DN<43>")
	)
	(segment
		(start 149.60473 -33.952942)
		(end 149.310598 -33.65881)
		(width 0.13462)
		(layer "F.Cu")
		(net "P5E_PEX1_STN2_RX_DN<43>")
	)
	(segment
		(start 152.764998 -33.790128)
		(end 152.287478 -33.790128)
		(width 0.13462)
		(layer "F.Cu")
		(net "P5E_PEX1_STN2_RX_DN<43>")
	)
	(segment
		(start 155.46959 -138.51128)
		(end 156.174694 -131.985766)
		(width 0.1651)
		(layer "In7.Cu")
		(net "P5E_PEX1_STN2_RX_DN<43>")
	)
	(segment
		(start 163.970208 -273.328638)
		(end 163.970208 -271.41932)
		(width 0.1143)
		(layer "In7.Cu")
		(net "P5E_PEX1_STN2_RX_DN<43>")
	)
	(segment
		(start 164.015928 -271.3736)
		(end 164.015928 -271.345152)
		(width 0.1143)
		(layer "In7.Cu")
		(net "P5E_PEX1_STN2_RX_DN<43>")
	)
	(segment
		(start 152.668478 -65.250314)
		(end 152.277318 -55.479696)
		(width 0.1651)
		(layer "In7.Cu")
		(net "P5E_PEX1_STN2_RX_DN<43>")
	)
	(segment
		(start 151.056594 -39.76497)
		(end 150.988268 -35.355276)
		(width 0.1651)
		(layer "In7.Cu")
		(net "P5E_PEX1_STN2_RX_DN<43>")
	)
	(segment
		(start 163.557458 -262.822944)
		(end 163.83508 -248.471436)
		(width 0.1651)
		(layer "In7.Cu")
		(net "P5E_PEX1_STN2_RX_DN<43>")
	)
	(segment
		(start 164.015928 -271.345152)
		(end 164.015928 -267.871956)
		(width 0.1651)
		(layer "In7.Cu")
		(net "P5E_PEX1_STN2_RX_DN<43>")
	)
	(segment
		(start 152.371044 -49.492662)
		(end 151.056594 -39.76497)
		(width 0.1651)
		(layer "In7.Cu")
		(net "P5E_PEX1_STN2_RX_DN<43>")
	)
	(segment
		(start 155.435808 -141.670024)
		(end 155.46959 -138.51128)
		(width 0.1651)
		(layer "In7.Cu")
		(net "P5E_PEX1_STN2_RX_DN<43>")
	)
	(segment
		(start 164.235638 -273.479514)
		(end 164.121084 -273.479514)
		(width 0.1143)
		(layer "In7.Cu")
		(net "P5E_PEX1_STN2_RX_DN<43>")
	)
	(segment
		(start 164.121084 -273.479514)
		(end 163.970208 -273.328638)
		(width 0.1143)
		(layer "In7.Cu")
		(net "P5E_PEX1_STN2_RX_DN<43>")
	)
	(segment
		(start 156.174694 -131.985766)
		(end 156.308298 -119.592598)
		(width 0.1651)
		(layer "In7.Cu")
		(net "P5E_PEX1_STN2_RX_DN<43>")
	)
	(segment
		(start 152.277318 -55.479696)
		(end 152.371044 -49.492662)
		(width 0.1651)
		(layer "In7.Cu")
		(net "P5E_PEX1_STN2_RX_DN<43>")
	)
	(segment
		(start 164.349938 -273.099784)
		(end 164.349938 -273.365214)
		(width 0.1143)
		(layer "In7.Cu")
		(net "P5E_PEX1_STN2_RX_DN<43>")
	)
	(segment
		(start 164.349938 -273.365214)
		(end 164.235638 -273.479514)
		(width 0.1143)
		(layer "In7.Cu")
		(net "P5E_PEX1_STN2_RX_DN<43>")
	)
	(segment
		(start 150.988268 -35.355276)
		(end 150.988268 -34.98596)
		(width 0.1651)
		(layer "In7.Cu")
		(net "P5E_PEX1_STN2_RX_DN<43>")
	)
	(segment
		(start 149.951948 -33.94964)
		(end 149.601428 -33.94964)
		(width 0.1651)
		(layer "In7.Cu")
		(net "P5E_PEX1_STN2_RX_DN<43>")
	)
	(segment
		(start 163.970208 -271.41932)
		(end 164.015928 -271.3736)
		(width 0.1143)
		(layer "In7.Cu")
		(net "P5E_PEX1_STN2_RX_DN<43>")
	)
	(segment
		(start 164.015928 -267.871956)
		(end 163.557458 -263.216136)
		(width 0.1651)
		(layer "In7.Cu")
		(net "P5E_PEX1_STN2_RX_DN<43>")
	)
	(segment
		(start 163.83508 -248.471436)
		(end 155.435808 -141.670024)
		(width 0.1651)
		(layer "In7.Cu")
		(net "P5E_PEX1_STN2_RX_DN<43>")
	)
	(segment
		(start 156.308298 -119.592598)
		(end 155.870656 -105.13822)
		(width 0.1651)
		(layer "In7.Cu")
		(net "P5E_PEX1_STN2_RX_DN<43>")
	)
	(segment
		(start 163.557458 -263.216136)
		(end 163.557458 -262.822944)
		(width 0.1651)
		(layer "In7.Cu")
		(net "P5E_PEX1_STN2_RX_DN<43>")
	)
	(segment
		(start 149.601428 -33.94964)
		(end 149.310598 -33.65881)
		(width 0.1651)
		(layer "In7.Cu")
		(net "P5E_PEX1_STN2_RX_DN<43>")
	)
	(segment
		(start 150.988268 -34.98596)
		(end 149.951948 -33.94964)
		(width 0.1651)
		(layer "In7.Cu")
		(net "P5E_PEX1_STN2_RX_DN<43>")
	)
	(segment
		(start 155.870656 -105.13822)
		(end 152.668478 -65.250314)
		(width 0.1651)
		(layer "In7.Cu")
		(net "P5E_PEX1_STN2_RX_DN<43>")
	)
	(segment
		(start 305.95697 -134.245096)
		(end 305.457606 -134.245096)
		(width 0.13462)
		(layer "F.Cu")
		(net "P5E_PEX2_STN0_TX_C_DP<6>")
	)
	(segment
		(start 306.120546 -134.08152)
		(end 305.95697 -134.245096)
		(width 0.13462)
		(layer "F.Cu")
		(net "P5E_PEX2_STN0_TX_C_DP<6>")
	)
	(segment
		(start 311.639458 -134.08152)
		(end 306.120546 -134.08152)
		(width 0.13462)
		(layer "F.Cu")
		(net "P5E_PEX2_STN0_TX_C_DP<6>")
	)
	(segment
		(start 311.95264 -134.394702)
		(end 311.639458 -134.08152)
		(width 0.13462)
		(layer "F.Cu")
		(net "P5E_PEX2_STN0_TX_C_DP<6>")
	)
	(segment
		(start 315.906404 -350.685354)
		(end 315.906404 -351.316798)
		(width 0.13462)
		(layer "F.Cu")
		(net "P5E_PEX2_STN6_TX_C_DP<110>")
	)
	(segment
		(start 315.906404 -351.316798)
		(end 315.611764 -351.611438)
		(width 0.13462)
		(layer "F.Cu")
		(net "P5E_PEX2_STN6_TX_C_DP<110>")
	)
	(segment
		(start 315.586364 -350.365314)
		(end 315.906404 -350.685354)
		(width 0.13462)
		(layer "F.Cu")
		(net "P5E_PEX2_STN6_TX_C_DP<110>")
	)
	(segment
		(start 316.584838 -364.463584)
		(end 316.471554 -364.408466)
		(width 0.1651)
		(layer "In13.Cu")
		(net "P5E_PEX2_STN6_TX_C_DP<110>")
	)
	(segment
		(start 329.07478 -392.10107)
		(end 324.93966 -388.734554)
		(width 0.1651)
		(layer "In13.Cu")
		(net "P5E_PEX2_STN6_TX_C_DP<110>")
	)
	(segment
		(start 314.348114 -357.966264)
		(end 314.348114 -353.910646)
		(width 0.1651)
		(layer "In13.Cu")
		(net "P5E_PEX2_STN6_TX_C_DP<110>")
	)
	(segment
		(start 333.81696 -409.799028)
		(end 334.247236 -409.799028)
		(width 0.1651)
		(layer "In13.Cu")
		(net "P5E_PEX2_STN6_TX_C_DP<110>")
	)
	(segment
		(start 334.247236 -409.799028)
		(end 334.534002 -409.512262)
		(width 0.1651)
		(layer "In13.Cu")
		(net "P5E_PEX2_STN6_TX_C_DP<110>")
	)
	(segment
		(start 315.902594 -351.902268)
		(end 315.611764 -351.611438)
		(width 0.1651)
		(layer "In13.Cu")
		(net "P5E_PEX2_STN6_TX_C_DP<110>")
	)
	(segment
		(start 333.68996 -409.290012)
		(end 333.68996 -409.672028)
		(width 0.1651)
		(layer "In13.Cu")
		(net "P5E_PEX2_STN6_TX_C_DP<110>")
	)
	(segment
		(start 314.348114 -353.910646)
		(end 315.902594 -352.356166)
		(width 0.1651)
		(layer "In13.Cu")
		(net "P5E_PEX2_STN6_TX_C_DP<110>")
	)
	(segment
		(start 334.320642 -395.404086)
		(end 332.255622 -393.437872)
		(width 0.1651)
		(layer "In13.Cu")
		(net "P5E_PEX2_STN6_TX_C_DP<110>")
	)
	(segment
		(start 332.255622 -393.437872)
		(end 329.07478 -392.10107)
		(width 0.1651)
		(layer "In13.Cu")
		(net "P5E_PEX2_STN6_TX_C_DP<110>")
	)
	(segment
		(start 316.310264 -363.94009)
		(end 316.365382 -363.82706)
		(width 0.1651)
		(layer "In13.Cu")
		(net "P5E_PEX2_STN6_TX_C_DP<110>")
	)
	(segment
		(start 334.534002 -395.84884)
		(end 334.320642 -395.404086)
		(width 0.1651)
		(layer "In13.Cu")
		(net "P5E_PEX2_STN6_TX_C_DP<110>")
	)
	(segment
		(start 316.584584 -364.463584)
		(end 316.584838 -364.463584)
		(width 0.1651)
		(layer "In13.Cu")
		(net "P5E_PEX2_STN6_TX_C_DP<110>")
	)
	(segment
		(start 333.68996 -409.672028)
		(end 333.81696 -409.799028)
		(width 0.1651)
		(layer "In13.Cu")
		(net "P5E_PEX2_STN6_TX_C_DP<110>")
	)
	(segment
		(start 316.365382 -363.82706)
		(end 314.348114 -357.966264)
		(width 0.1651)
		(layer "In13.Cu")
		(net "P5E_PEX2_STN6_TX_C_DP<110>")
	)
	(segment
		(start 315.902594 -352.356166)
		(end 315.902594 -351.902268)
		(width 0.1651)
		(layer "In13.Cu")
		(net "P5E_PEX2_STN6_TX_C_DP<110>")
	)
	(segment
		(start 334.534002 -409.512262)
		(end 334.534002 -395.84884)
		(width 0.1651)
		(layer "In13.Cu")
		(net "P5E_PEX2_STN6_TX_C_DP<110>")
	)
	(segment
		(start 324.93966 -388.734554)
		(end 316.584584 -364.463584)
		(width 0.1651)
		(layer "In13.Cu")
		(net "P5E_PEX2_STN6_TX_C_DP<110>")
	)
	(segment
		(start 316.471554 -364.408466)
		(end 316.310264 -363.94009)
		(width 0.1651)
		(layer "In13.Cu")
		(net "P5E_PEX2_STN6_TX_C_DP<110>")
	)
	(segment
		(start 402.107908 -134.6073)
		(end 399.577814 -134.6073)
		(width 0.13462)
		(layer "F.Cu")
		(net "P5E_PEX3_STN1_RX_DN<30>")
	)
	(segment
		(start 399.577814 -134.6073)
		(end 399.42008 -134.765034)
		(width 0.13462)
		(layer "F.Cu")
		(net "P5E_PEX3_STN1_RX_DN<30>")
	)
	(segment
		(start 399.42008 -134.765034)
		(end 398.94256 -134.765034)
		(width 0.13462)
		(layer "F.Cu")
		(net "P5E_PEX3_STN1_RX_DN<30>")
	)
	(segment
		(start 402.39696 -134.896352)
		(end 402.107908 -134.6073)
		(width 0.13462)
		(layer "F.Cu")
		(net "P5E_PEX3_STN1_RX_DN<30>")
	)
	(segment
		(start 400.733006 -134.605522)
		(end 400.237706 -134.605522)
		(width 0.1651)
		(layer "In5.Cu")
		(net "P5E_PEX3_STN1_RX_DN<30>")
	)
	(segment
		(start 399.435828 -134.937754)
		(end 399.323306 -135.044688)
		(width 0.1651)
		(layer "In5.Cu")
		(net "P5E_PEX3_STN1_RX_DN<30>")
	)
	(segment
		(start 397.725392 -142.648432)
		(end 397.44269 -143.33093)
		(width 0.1651)
		(layer "In5.Cu")
		(net "P5E_PEX3_STN1_RX_DN<30>")
	)
	(segment
		(start 421.249602 -273.365214)
		(end 421.249602 -273.099784)
		(width 0.1143)
		(layer "In5.Cu")
		(net "P5E_PEX3_STN1_RX_DN<30>")
	)
	(segment
		(start 391.57148 -150.682452)
		(end 391.604246 -151.17699)
		(width 0.1651)
		(layer "In5.Cu")
		(net "P5E_PEX3_STN1_RX_DN<30>")
	)
	(segment
		(start 394.750798 -145.920968)
		(end 393.99718 -146.674586)
		(width 0.1651)
		(layer "In5.Cu")
		(net "P5E_PEX3_STN1_RX_DN<30>")
	)
	(segment
		(start 396.487142 -144.286478)
		(end 395.063218 -145.454624)
		(width 0.1651)
		(layer "In5.Cu")
		(net "P5E_PEX3_STN1_RX_DN<30>")
	)
	(segment
		(start 398.435576 -140.104876)
		(end 398.435576 -140.600176)
		(width 0.1651)
		(layer "In5.Cu")
		(net "P5E_PEX3_STN1_RX_DN<30>")
	)
	(segment
		(start 391.640822 -151.889206)
		(end 391.675112 -152.40508)
		(width 0.1651)
		(layer "In5.Cu")
		(net "P5E_PEX3_STN1_RX_DN<30>")
	)
	(segment
		(start 398.00276 -141.979142)
		(end 398.064482 -142.128494)
		(width 0.1651)
		(layer "In5.Cu")
		(net "P5E_PEX3_STN1_RX_DN<30>")
	)
	(segment
		(start 420.870126 -273.376136)
		(end 420.973504 -273.479514)
		(width 0.1143)
		(layer "In5.Cu")
		(net "P5E_PEX3_STN1_RX_DN<30>")
	)
	(segment
		(start 420.915846 -271.526)
		(end 420.915846 -271.554448)
		(width 0.1143)
		(layer "In5.Cu")
		(net "P5E_PEX3_STN1_RX_DN<30>")
	)
	(segment
		(start 391.86485 -147.328636)
		(end 391.538206 -147.574)
		(width 0.1651)
		(layer "In5.Cu")
		(net "P5E_PEX3_STN1_RX_DN<30>")
	)
	(segment
		(start 420.915846 -271.554448)
		(end 420.870126 -271.600168)
		(width 0.1143)
		(layer "In5.Cu")
		(net "P5E_PEX3_STN1_RX_DN<30>")
	)
	(segment
		(start 397.725392 -142.648178)
		(end 397.725392 -142.648432)
		(width 0.1651)
		(layer "In5.Cu")
		(net "P5E_PEX3_STN1_RX_DN<30>")
	)
	(segment
		(start 391.44956 -150.576026)
		(end 391.57148 -150.682452)
		(width 0.1651)
		(layer "In5.Cu")
		(net "P5E_PEX3_STN1_RX_DN<30>")
	)
	(segment
		(start 420.973504 -273.479514)
		(end 421.135302 -273.479514)
		(width 0.1143)
		(layer "In5.Cu")
		(net "P5E_PEX3_STN1_RX_DN<30>")
	)
	(segment
		(start 392.007344 -147.257262)
		(end 391.86485 -147.328636)
		(width 0.1651)
		(layer "In5.Cu")
		(net "P5E_PEX3_STN1_RX_DN<30>")
	)
	(segment
		(start 391.449814 -150.576026)
		(end 391.44956 -150.576026)
		(width 0.1651)
		(layer "In5.Cu")
		(net "P5E_PEX3_STN1_RX_DN<30>")
	)
	(segment
		(start 397.874998 -142.586202)
		(end 397.725392 -142.648178)
		(width 0.1651)
		(layer "In5.Cu")
		(net "P5E_PEX3_STN1_RX_DN<30>")
	)
	(segment
		(start 398.321276 -141.209776)
		(end 398.00276 -141.979142)
		(width 0.1651)
		(layer "In5.Cu")
		(net "P5E_PEX3_STN1_RX_DN<30>")
	)
	(segment
		(start 400.847306 -134.719822)
		(end 400.733006 -134.605522)
		(width 0.1651)
		(layer "In5.Cu")
		(net "P5E_PEX3_STN1_RX_DN<30>")
	)
	(segment
		(start 391.604246 -151.17699)
		(end 391.49782 -151.298656)
		(width 0.1651)
		(layer "In5.Cu")
		(net "P5E_PEX3_STN1_RX_DN<30>")
	)
	(segment
		(start 398.435576 -139.380976)
		(end 398.321276 -139.495276)
		(width 0.1651)
		(layer "In5.Cu")
		(net "P5E_PEX3_STN1_RX_DN<30>")
	)
	(segment
		(start 391.803636 -154.767026)
		(end 391.733532 -154.847036)
		(width 0.1651)
		(layer "In5.Cu")
		(net "P5E_PEX3_STN1_RX_DN<30>")
	)
	(segment
		(start 398.321276 -137.163302)
		(end 398.321276 -138.771376)
		(width 0.1651)
		(layer "In5.Cu")
		(net "P5E_PEX3_STN1_RX_DN<30>")
	)
	(segment
		(start 398.435576 -138.885676)
		(end 398.435576 -139.380976)
		(width 0.1651)
		(layer "In5.Cu")
		(net "P5E_PEX3_STN1_RX_DN<30>")
	)
	(segment
		(start 401.342606 -134.719822)
		(end 400.847306 -134.719822)
		(width 0.1651)
		(layer "In5.Cu")
		(net "P5E_PEX3_STN1_RX_DN<30>")
	)
	(segment
		(start 391.656062 -153.681176)
		(end 391.688574 -154.175206)
		(width 0.1651)
		(layer "In5.Cu")
		(net "P5E_PEX3_STN1_RX_DN<30>")
	)
	(segment
		(start 391.733532 -154.847036)
		(end 391.856976 -156.713936)
		(width 0.1651)
		(layer "In5.Cu")
		(net "P5E_PEX3_STN1_RX_DN<30>")
	)
	(segment
		(start 391.738866 -153.586688)
		(end 391.656062 -153.681176)
		(width 0.1651)
		(layer "In5.Cu")
		(net "P5E_PEX3_STN1_RX_DN<30>")
	)
	(segment
		(start 391.769092 -154.245564)
		(end 391.803636 -154.767026)
		(width 0.1651)
		(layer "In5.Cu")
		(net "P5E_PEX3_STN1_RX_DN<30>")
	)
	(segment
		(start 402.39696 -134.896352)
		(end 402.103844 -134.603236)
		(width 0.1651)
		(layer "In5.Cu")
		(net "P5E_PEX3_STN1_RX_DN<30>")
	)
	(segment
		(start 391.538206 -147.574)
		(end 391.285476 -148.099526)
		(width 0.1651)
		(layer "In5.Cu")
		(net "P5E_PEX3_STN1_RX_DN<30>")
	)
	(segment
		(start 391.688574 -154.175206)
		(end 391.769092 -154.245564)
		(width 0.1651)
		(layer "In5.Cu")
		(net "P5E_PEX3_STN1_RX_DN<30>")
	)
	(segment
		(start 391.7061 -153.09215)
		(end 391.738866 -153.586688)
		(width 0.1651)
		(layer "In5.Cu")
		(net "P5E_PEX3_STN1_RX_DN<30>")
	)
	(segment
		(start 395.063218 -145.454624)
		(end 394.750798 -145.920968)
		(width 0.1651)
		(layer "In5.Cu")
		(net "P5E_PEX3_STN1_RX_DN<30>")
	)
	(segment
		(start 399.16608 -135.644382)
		(end 398.95399 -136.092438)
		(width 0.1651)
		(layer "In5.Cu")
		(net "P5E_PEX3_STN1_RX_DN<30>")
	)
	(segment
		(start 398.064482 -142.128494)
		(end 397.874998 -142.586202)
		(width 0.1651)
		(layer "In5.Cu")
		(net "P5E_PEX3_STN1_RX_DN<30>")
	)
	(segment
		(start 398.321276 -139.990576)
		(end 398.435576 -140.104876)
		(width 0.1651)
		(layer "In5.Cu")
		(net "P5E_PEX3_STN1_RX_DN<30>")
	)
	(segment
		(start 391.49782 -151.298656)
		(end 391.530586 -151.792686)
		(width 0.1651)
		(layer "In5.Cu")
		(net "P5E_PEX3_STN1_RX_DN<30>")
	)
	(segment
		(start 398.321276 -139.495276)
		(end 398.321276 -139.990576)
		(width 0.1651)
		(layer "In5.Cu")
		(net "P5E_PEX3_STN1_RX_DN<30>")
	)
	(segment
		(start 402.103844 -134.603236)
		(end 402.097748 -134.605522)
		(width 0.1651)
		(layer "In5.Cu")
		(net "P5E_PEX3_STN1_RX_DN<30>")
	)
	(segment
		(start 398.801844 -136.147302)
		(end 398.321276 -137.163302)
		(width 0.1651)
		(layer "In5.Cu")
		(net "P5E_PEX3_STN1_RX_DN<30>")
	)
	(segment
		(start 398.435576 -140.600176)
		(end 398.321276 -140.714476)
		(width 0.1651)
		(layer "In5.Cu")
		(net "P5E_PEX3_STN1_RX_DN<30>")
	)
	(segment
		(start 401.456906 -134.605522)
		(end 401.342606 -134.719822)
		(width 0.1651)
		(layer "In5.Cu")
		(net "P5E_PEX3_STN1_RX_DN<30>")
	)
	(segment
		(start 391.285476 -148.099526)
		(end 391.449814 -150.576026)
		(width 0.1651)
		(layer "In5.Cu")
		(net "P5E_PEX3_STN1_RX_DN<30>")
	)
	(segment
		(start 398.95399 -136.092438)
		(end 398.801844 -136.147048)
		(width 0.1651)
		(layer "In5.Cu")
		(net "P5E_PEX3_STN1_RX_DN<30>")
	)
	(segment
		(start 391.578592 -152.515316)
		(end 391.611358 -153.009346)
		(width 0.1651)
		(layer "In5.Cu")
		(net "P5E_PEX3_STN1_RX_DN<30>")
	)
	(segment
		(start 391.530586 -151.792686)
		(end 391.640822 -151.889206)
		(width 0.1651)
		(layer "In5.Cu")
		(net "P5E_PEX3_STN1_RX_DN<30>")
	)
	(segment
		(start 398.321276 -138.771376)
		(end 398.435576 -138.885676)
		(width 0.1651)
		(layer "In5.Cu")
		(net "P5E_PEX3_STN1_RX_DN<30>")
	)
	(segment
		(start 402.097748 -134.605522)
		(end 401.456906 -134.605522)
		(width 0.1651)
		(layer "In5.Cu")
		(net "P5E_PEX3_STN1_RX_DN<30>")
	)
	(segment
		(start 399.323306 -135.044688)
		(end 399.111724 -135.492236)
		(width 0.1651)
		(layer "In5.Cu")
		(net "P5E_PEX3_STN1_RX_DN<30>")
	)
	(segment
		(start 397.44269 -143.33093)
		(end 396.487142 -144.286478)
		(width 0.1651)
		(layer "In5.Cu")
		(net "P5E_PEX3_STN1_RX_DN<30>")
	)
	(segment
		(start 398.321276 -140.714476)
		(end 398.321276 -141.209776)
		(width 0.1651)
		(layer "In5.Cu")
		(net "P5E_PEX3_STN1_RX_DN<30>")
	)
	(segment
		(start 421.135302 -273.479514)
		(end 421.249602 -273.365214)
		(width 0.1143)
		(layer "In5.Cu")
		(net "P5E_PEX3_STN1_RX_DN<30>")
	)
	(segment
		(start 420.870126 -271.600168)
		(end 420.870126 -273.376136)
		(width 0.1143)
		(layer "In5.Cu")
		(net "P5E_PEX3_STN1_RX_DN<30>")
	)
	(segment
		(start 391.611358 -153.009346)
		(end 391.7061 -153.09215)
		(width 0.1651)
		(layer "In5.Cu")
		(net "P5E_PEX3_STN1_RX_DN<30>")
	)
	(segment
		(start 399.111724 -135.492236)
		(end 399.16608 -135.644382)
		(width 0.1651)
		(layer "In5.Cu")
		(net "P5E_PEX3_STN1_RX_DN<30>")
	)
	(segment
		(start 392.306302 -147.17014)
		(end 392.007344 -147.257262)
		(width 0.1651)
		(layer "In5.Cu")
		(net "P5E_PEX3_STN1_RX_DN<30>")
	)
	(segment
		(start 393.99718 -146.674586)
		(end 392.800586 -147.17014)
		(width 0.1651)
		(layer "In5.Cu")
		(net "P5E_PEX3_STN1_RX_DN<30>")
	)
	(segment
		(start 420.915846 -267.233654)
		(end 420.915846 -271.526)
		(width 0.1651)
		(layer "In5.Cu")
		(net "P5E_PEX3_STN1_RX_DN<30>")
	)
	(segment
		(start 391.856976 -156.713936)
		(end 392.568176 -160.706816)
		(width 0.1651)
		(layer "In5.Cu")
		(net "P5E_PEX3_STN1_RX_DN<30>")
	)
	(segment
		(start 400.237706 -134.605522)
		(end 399.435828 -134.937754)
		(width 0.1651)
		(layer "In5.Cu")
		(net "P5E_PEX3_STN1_RX_DN<30>")
	)
	(segment
		(start 392.568176 -160.706816)
		(end 420.915846 -267.233654)
		(width 0.1651)
		(layer "In5.Cu")
		(net "P5E_PEX3_STN1_RX_DN<30>")
	)
	(segment
		(start 398.801844 -136.147048)
		(end 398.801844 -136.147302)
		(width 0.1651)
		(layer "In5.Cu")
		(net "P5E_PEX3_STN1_RX_DN<30>")
	)
	(segment
		(start 392.800586 -147.17014)
		(end 392.306302 -147.17014)
		(width 0.1651)
		(layer "In5.Cu")
		(net "P5E_PEX3_STN1_RX_DN<30>")
	)
	(segment
		(start 391.675112 -152.40508)
		(end 391.578592 -152.515316)
		(width 0.1651)
		(layer "In5.Cu")
		(net "P5E_PEX3_STN1_RX_DN<30>")
	)
	(segment
		(start 391.444734 -316.229492)
		(end 391.22858 -316.445646)
		(width 0.1143)
		(layer "In15.Cu")
		(net "P5E_PEX3_STN6_RX_DP<111>")
	)
	(segment
		(start 370.910612 -391.592054)
		(end 371.305074 -391.892028)
		(width 0.1651)
		(layer "In15.Cu")
		(net "P5E_PEX3_STN6_RX_DP<111>")
	)
	(segment
		(start 368.482372 -338.921598)
		(end 367.045494 -341.361522)
		(width 0.1651)
		(layer "In15.Cu")
		(net "P5E_PEX3_STN6_RX_DP<111>")
	)
	(segment
		(start 375.489978 -400.772122)
		(end 375.489978 -400.390106)
		(width 0.1651)
		(layer "In15.Cu")
		(net "P5E_PEX3_STN6_RX_DP<111>")
	)
	(segment
		(start 367.045494 -341.361522)
		(end 366.960658 -341.834978)
		(width 0.1651)
		(layer "In15.Cu")
		(net "P5E_PEX3_STN6_RX_DP<111>")
	)
	(segment
		(start 391.799826 -316.115192)
		(end 391.685526 -316.229492)
		(width 0.1143)
		(layer "In15.Cu")
		(net "P5E_PEX3_STN6_RX_DP<111>")
	)
	(segment
		(start 366.625632 -371.2083)
		(end 367.187988 -386.045202)
		(width 0.1651)
		(layer "In15.Cu")
		(net "P5E_PEX3_STN6_RX_DP<111>")
	)
	(segment
		(start 371.465348 -391.870184)
		(end 372.767352 -392.85926)
		(width 0.1651)
		(layer "In15.Cu")
		(net "P5E_PEX3_STN6_RX_DP<111>")
	)
	(segment
		(start 391.18286 -319.966848)
		(end 391.18286 -319.995296)
		(width 0.1143)
		(layer "In15.Cu")
		(net "P5E_PEX3_STN6_RX_DP<111>")
	)
	(segment
		(start 391.799826 -315.849762)
		(end 391.799826 -316.115192)
		(width 0.1143)
		(layer "In15.Cu")
		(net "P5E_PEX3_STN6_RX_DP<111>")
	)
	(segment
		(start 372.767352 -392.85926)
		(end 375.397776 -394.046202)
		(width 0.1651)
		(layer "In15.Cu")
		(net "P5E_PEX3_STN6_RX_DP<111>")
	)
	(segment
		(start 376.33402 -395.37767)
		(end 376.33402 -400.612356)
		(width 0.1651)
		(layer "In15.Cu")
		(net "P5E_PEX3_STN6_RX_DP<111>")
	)
	(segment
		(start 375.616978 -400.899122)
		(end 375.489978 -400.772122)
		(width 0.1651)
		(layer "In15.Cu")
		(net "P5E_PEX3_STN6_RX_DP<111>")
	)
	(segment
		(start 367.187988 -386.045202)
		(end 368.86388 -389.893556)
		(width 0.1651)
		(layer "In15.Cu")
		(net "P5E_PEX3_STN6_RX_DP<111>")
	)
	(segment
		(start 391.18286 -320.202306)
		(end 389.959088 -321.426078)
		(width 0.1651)
		(layer "In15.Cu")
		(net "P5E_PEX3_STN6_RX_DP<111>")
	)
	(segment
		(start 376.33402 -400.612356)
		(end 376.047254 -400.899122)
		(width 0.1651)
		(layer "In15.Cu")
		(net "P5E_PEX3_STN6_RX_DP<111>")
	)
	(segment
		(start 375.397776 -394.046202)
		(end 376.074432 -394.697712)
		(width 0.1651)
		(layer "In15.Cu")
		(net "P5E_PEX3_STN6_RX_DP<111>")
	)
	(segment
		(start 369.93957 -390.854184)
		(end 370.334286 -391.154158)
		(width 0.1651)
		(layer "In15.Cu")
		(net "P5E_PEX3_STN6_RX_DP<111>")
	)
	(segment
		(start 391.22858 -319.921128)
		(end 391.18286 -319.966848)
		(width 0.1143)
		(layer "In15.Cu")
		(net "P5E_PEX3_STN6_RX_DP<111>")
	)
	(segment
		(start 389.959088 -321.426078)
		(end 368.482372 -338.921598)
		(width 0.1651)
		(layer "In15.Cu")
		(net "P5E_PEX3_STN6_RX_DP<111>")
	)
	(segment
		(start 376.074432 -394.697712)
		(end 376.33402 -395.37767)
		(width 0.1651)
		(layer "In15.Cu")
		(net "P5E_PEX3_STN6_RX_DP<111>")
	)
	(segment
		(start 370.334286 -391.154158)
		(end 370.49456 -391.132314)
		(width 0.1651)
		(layer "In15.Cu")
		(net "P5E_PEX3_STN6_RX_DP<111>")
	)
	(segment
		(start 391.18286 -319.995296)
		(end 391.18286 -320.202306)
		(width 0.1651)
		(layer "In15.Cu")
		(net "P5E_PEX3_STN6_RX_DP<111>")
	)
	(segment
		(start 391.22858 -316.445646)
		(end 391.22858 -319.921128)
		(width 0.1143)
		(layer "In15.Cu")
		(net "P5E_PEX3_STN6_RX_DP<111>")
	)
	(segment
		(start 391.685526 -316.229492)
		(end 391.444734 -316.229492)
		(width 0.1143)
		(layer "In15.Cu")
		(net "P5E_PEX3_STN6_RX_DP<111>")
	)
	(segment
		(start 369.917726 -390.694164)
		(end 369.93957 -390.854184)
		(width 0.1651)
		(layer "In15.Cu")
		(net "P5E_PEX3_STN6_RX_DP<111>")
	)
	(segment
		(start 366.960658 -341.834978)
		(end 366.625632 -371.2083)
		(width 0.1651)
		(layer "In15.Cu")
		(net "P5E_PEX3_STN6_RX_DP<111>")
	)
	(segment
		(start 368.86388 -389.893556)
		(end 369.917726 -390.694164)
		(width 0.1651)
		(layer "In15.Cu")
		(net "P5E_PEX3_STN6_RX_DP<111>")
	)
	(segment
		(start 370.49456 -391.132314)
		(end 370.888768 -391.43178)
		(width 0.1651)
		(layer "In15.Cu")
		(net "P5E_PEX3_STN6_RX_DP<111>")
	)
	(segment
		(start 371.305074 -391.892028)
		(end 371.465348 -391.870184)
		(width 0.1651)
		(layer "In15.Cu")
		(net "P5E_PEX3_STN6_RX_DP<111>")
	)
	(segment
		(start 376.047254 -400.899122)
		(end 375.616978 -400.899122)
		(width 0.1651)
		(layer "In15.Cu")
		(net "P5E_PEX3_STN6_RX_DP<111>")
	)
	(segment
		(start 370.888768 -391.43178)
		(end 370.910612 -391.592054)
		(width 0.1651)
		(layer "In15.Cu")
		(net "P5E_PEX3_STN6_RX_DP<111>")
	)
	(segment
		(start 181.048914 -101.782372)
		(end 182.191152 -100.640134)
		(width 0.13208)
		(layer "F.Cu")
		(net "NCSI_NIC3_TX_EN")
	)
	(segment
		(start 180.31587 -101.782372)
		(end 181.048914 -101.782372)
		(width 0.13208)
		(layer "F.Cu")
		(net "NCSI_NIC3_TX_EN")
	)
	(segment
		(start 182.191152 -100.640134)
		(end 184.757314 -100.640134)
		(width 0.13208)
		(layer "F.Cu")
		(net "NCSI_NIC3_TX_EN")
	)
	(segment
		(start 175.49495 -101.782372)
		(end 180.31587 -101.782372)
		(width 0.13208)
		(layer "F.Cu")
		(net "NCSI_NIC3_TX_EN")
	)
	(via
		(at 180.31587 -101.782372)
		(size 0.762)
		(drill 0.381)
		(layers "F.Cu" "B.Cu")
		(net "NCSI_NIC3_TX_EN")
	)
	(segment
		(start 88.019382 -30.62732)
		(end 85.505544 -30.62732)
		(width 0.13462)
		(layer "F.Cu")
		(net "P5E_PEX0_STN2_RX_DP<33>")
	)
	(segment
		(start 88.182196 -30.790134)
		(end 88.019382 -30.62732)
		(width 0.13462)
		(layer "F.Cu")
		(net "P5E_PEX0_STN2_RX_DP<33>")
	)
	(segment
		(start 85.505544 -30.62732)
		(end 85.210396 -30.922468)
		(width 0.13462)
		(layer "F.Cu")
		(net "P5E_PEX0_STN2_RX_DP<33>")
	)
	(segment
		(start 88.664796 -30.790134)
		(end 88.182196 -30.790134)
		(width 0.13462)
		(layer "F.Cu")
		(net "P5E_PEX0_STN2_RX_DP<33>")
	)
	(segment
		(start 88.359488 -31.499556)
		(end 88.393778 -31.341822)
		(width 0.1651)
		(layer "In7.Cu")
		(net "P5E_PEX0_STN2_RX_DP<33>")
	)
	(segment
		(start 78.415388 -143.970756)
		(end 78.73111 -116.662708)
		(width 0.1651)
		(layer "In7.Cu")
		(net "P5E_PEX0_STN2_RX_DP<33>")
	)
	(segment
		(start 89.739216 -61.179456)
		(end 89.923366 -49.394364)
		(width 0.1651)
		(layer "In7.Cu")
		(net "P5E_PEX0_STN2_RX_DP<33>")
	)
	(segment
		(start 57.473342 -267.004546)
		(end 77.03947 -154.656282)
		(width 0.1651)
		(layer "In7.Cu")
		(net "P5E_PEX0_STN2_RX_DP<33>")
	)
	(segment
		(start 57.749948 -274.049744)
		(end 57.749948 -273.784314)
		(width 0.1143)
		(layer "In7.Cu")
		(net "P5E_PEX0_STN2_RX_DP<33>")
	)
	(segment
		(start 57.179718 -273.407632)
		(end 57.179718 -271.41932)
		(width 0.1143)
		(layer "In7.Cu")
		(net "P5E_PEX0_STN2_RX_DP<33>")
	)
	(segment
		(start 88.627966 -31.91637)
		(end 88.359488 -31.499556)
		(width 0.1651)
		(layer "In7.Cu")
		(net "P5E_PEX0_STN2_RX_DP<33>")
	)
	(segment
		(start 85.44941 -30.683454)
		(end 85.210396 -30.922468)
		(width 0.1651)
		(layer "In7.Cu")
		(net "P5E_PEX0_STN2_RX_DP<33>")
	)
	(segment
		(start 57.133998 -271.3736)
		(end 57.133998 -271.345152)
		(width 0.1143)
		(layer "In7.Cu")
		(net "P5E_PEX0_STN2_RX_DP<33>")
	)
	(segment
		(start 57.133998 -270.917416)
		(end 57.473342 -267.004546)
		(width 0.1651)
		(layer "In7.Cu")
		(net "P5E_PEX0_STN2_RX_DP<33>")
	)
	(segment
		(start 77.03947 -154.656282)
		(end 78.415388 -143.970756)
		(width 0.1651)
		(layer "In7.Cu")
		(net "P5E_PEX0_STN2_RX_DP<33>")
	)
	(segment
		(start 89.303098 -34.076386)
		(end 89.311226 -33.05302)
		(width 0.1651)
		(layer "In7.Cu")
		(net "P5E_PEX0_STN2_RX_DP<33>")
	)
	(segment
		(start 57.749948 -273.784314)
		(end 57.635648 -273.670014)
		(width 0.1143)
		(layer "In7.Cu")
		(net "P5E_PEX0_STN2_RX_DP<33>")
	)
	(segment
		(start 87.28075 -30.631638)
		(end 87.16645 -30.745938)
		(width 0.1651)
		(layer "In7.Cu")
		(net "P5E_PEX0_STN2_RX_DP<33>")
	)
	(segment
		(start 85.574378 -30.631638)
		(end 85.44941 -30.683454)
		(width 0.1651)
		(layer "In7.Cu")
		(net "P5E_PEX0_STN2_RX_DP<33>")
	)
	(segment
		(start 86.55685 -30.631638)
		(end 85.574378 -30.631638)
		(width 0.1651)
		(layer "In7.Cu")
		(net "P5E_PEX0_STN2_RX_DP<33>")
	)
	(segment
		(start 78.73111 -116.662708)
		(end 89.739216 -61.179456)
		(width 0.1651)
		(layer "In7.Cu")
		(net "P5E_PEX0_STN2_RX_DP<33>")
	)
	(segment
		(start 57.133998 -271.345152)
		(end 57.133998 -270.917416)
		(width 0.1651)
		(layer "In7.Cu")
		(net "P5E_PEX0_STN2_RX_DP<33>")
	)
	(segment
		(start 57.179718 -271.41932)
		(end 57.133998 -271.3736)
		(width 0.1143)
		(layer "In7.Cu")
		(net "P5E_PEX0_STN2_RX_DP<33>")
	)
	(segment
		(start 88.6079 -39.65829)
		(end 88.583516 -38.129464)
		(width 0.1651)
		(layer "In7.Cu")
		(net "P5E_PEX0_STN2_RX_DP<33>")
	)
	(segment
		(start 89.923366 -49.394364)
		(end 88.6079 -39.65829)
		(width 0.1651)
		(layer "In7.Cu")
		(net "P5E_PEX0_STN2_RX_DP<33>")
	)
	(segment
		(start 87.16645 -30.745938)
		(end 86.67115 -30.745938)
		(width 0.1651)
		(layer "In7.Cu")
		(net "P5E_PEX0_STN2_RX_DP<33>")
	)
	(segment
		(start 86.67115 -30.745938)
		(end 86.55685 -30.631638)
		(width 0.1651)
		(layer "In7.Cu")
		(net "P5E_PEX0_STN2_RX_DP<33>")
	)
	(segment
		(start 57.635648 -273.670014)
		(end 57.4421 -273.670014)
		(width 0.1143)
		(layer "In7.Cu")
		(net "P5E_PEX0_STN2_RX_DP<33>")
	)
	(segment
		(start 89.053924 -32.366966)
		(end 88.785954 -31.95066)
		(width 0.1651)
		(layer "In7.Cu")
		(net "P5E_PEX0_STN2_RX_DP<33>")
	)
	(segment
		(start 87.936832 -30.631638)
		(end 87.28075 -30.631638)
		(width 0.1651)
		(layer "In7.Cu")
		(net "P5E_PEX0_STN2_RX_DP<33>")
	)
	(segment
		(start 88.785954 -31.95066)
		(end 88.627966 -31.91637)
		(width 0.1651)
		(layer "In7.Cu")
		(net "P5E_PEX0_STN2_RX_DP<33>")
	)
	(segment
		(start 88.583516 -38.129464)
		(end 89.303098 -34.076386)
		(width 0.1651)
		(layer "In7.Cu")
		(net "P5E_PEX0_STN2_RX_DP<33>")
	)
	(segment
		(start 57.4421 -273.670014)
		(end 57.179718 -273.407632)
		(width 0.1143)
		(layer "In7.Cu")
		(net "P5E_PEX0_STN2_RX_DP<33>")
	)
	(segment
		(start 88.393778 -31.341822)
		(end 87.936832 -30.631638)
		(width 0.1651)
		(layer "In7.Cu")
		(net "P5E_PEX0_STN2_RX_DP<33>")
	)
	(segment
		(start 89.311226 -33.05302)
		(end 89.053924 -32.366966)
		(width 0.1651)
		(layer "In7.Cu")
		(net "P5E_PEX0_STN2_RX_DP<33>")
	)
	(segment
		(start 149.605746 -30.62732)
		(end 149.310598 -30.922468)
		(width 0.13462)
		(layer "F.Cu")
		(net "P5E_PEX1_STN2_RX_DP<41>")
	)
	(segment
		(start 152.764998 -30.790134)
		(end 152.282398 -30.790134)
		(width 0.13462)
		(layer "F.Cu")
		(net "P5E_PEX1_STN2_RX_DP<41>")
	)
	(segment
		(start 152.282398 -30.790134)
		(end 152.119584 -30.62732)
		(width 0.13462)
		(layer "F.Cu")
		(net "P5E_PEX1_STN2_RX_DP<41>")
	)
	(segment
		(start 152.119584 -30.62732)
		(end 149.605746 -30.62732)
		(width 0.13462)
		(layer "F.Cu")
		(net "P5E_PEX1_STN2_RX_DP<41>")
	)
	(segment
		(start 166.249858 -273.784314)
		(end 166.249858 -274.049744)
		(width 0.1143)
		(layer "In7.Cu")
		(net "P5E_PEX1_STN2_RX_DP<41>")
	)
	(segment
		(start 165.587426 -249.979434)
		(end 165.382448 -260.60146)
		(width 0.1651)
		(layer "In7.Cu")
		(net "P5E_PEX1_STN2_RX_DP<41>")
	)
	(segment
		(start 153.924254 -55.75808)
		(end 154.284426 -64.756792)
		(width 0.1651)
		(layer "In7.Cu")
		(net "P5E_PEX1_STN2_RX_DP<41>")
	)
	(segment
		(start 165.94201 -273.670014)
		(end 166.135558 -273.670014)
		(width 0.1143)
		(layer "In7.Cu")
		(net "P5E_PEX1_STN2_RX_DP<41>")
	)
	(segment
		(start 152.385268 -31.24454)
		(end 152.385268 -31.388304)
		(width 0.1651)
		(layer "In7.Cu")
		(net "P5E_PEX1_STN2_RX_DP<41>")
	)
	(segment
		(start 153.206196 -34.981642)
		(end 152.680924 -37.940234)
		(width 0.1651)
		(layer "In7.Cu")
		(net "P5E_PEX1_STN2_RX_DP<41>")
	)
	(segment
		(start 152.707848 -39.641272)
		(end 152.707594 -39.641272)
		(width 0.1651)
		(layer "In7.Cu")
		(net "P5E_PEX1_STN2_RX_DP<41>")
	)
	(segment
		(start 153.229564 -32.088836)
		(end 153.206196 -34.981642)
		(width 0.1651)
		(layer "In7.Cu")
		(net "P5E_PEX1_STN2_RX_DP<41>")
	)
	(segment
		(start 151.772366 -30.631638)
		(end 152.385268 -31.24454)
		(width 0.1651)
		(layer "In7.Cu")
		(net "P5E_PEX1_STN2_RX_DP<41>")
	)
	(segment
		(start 150.675848 -30.733238)
		(end 151.171148 -30.733238)
		(width 0.1651)
		(layer "In7.Cu")
		(net "P5E_PEX1_STN2_RX_DP<41>")
	)
	(segment
		(start 149.601428 -30.631638)
		(end 150.574248 -30.631638)
		(width 0.1651)
		(layer "In7.Cu")
		(net "P5E_PEX1_STN2_RX_DP<41>")
	)
	(segment
		(start 151.272748 -30.631638)
		(end 151.772366 -30.631638)
		(width 0.1651)
		(layer "In7.Cu")
		(net "P5E_PEX1_STN2_RX_DP<41>")
	)
	(segment
		(start 157.9372 -119.576596)
		(end 157.63113 -147.979892)
		(width 0.1651)
		(layer "In7.Cu")
		(net "P5E_PEX1_STN2_RX_DP<41>")
	)
	(segment
		(start 157.63113 -147.979892)
		(end 165.587426 -249.979434)
		(width 0.1651)
		(layer "In7.Cu")
		(net "P5E_PEX1_STN2_RX_DP<41>")
	)
	(segment
		(start 165.633908 -267.683234)
		(end 165.633908 -271.345152)
		(width 0.1651)
		(layer "In7.Cu")
		(net "P5E_PEX1_STN2_RX_DP<41>")
	)
	(segment
		(start 165.679628 -273.407632)
		(end 165.94201 -273.670014)
		(width 0.1143)
		(layer "In7.Cu")
		(net "P5E_PEX1_STN2_RX_DP<41>")
	)
	(segment
		(start 165.633908 -271.345152)
		(end 165.633908 -271.3736)
		(width 0.1143)
		(layer "In7.Cu")
		(net "P5E_PEX1_STN2_RX_DP<41>")
	)
	(segment
		(start 165.633908 -271.3736)
		(end 165.679628 -271.41932)
		(width 0.1143)
		(layer "In7.Cu")
		(net "P5E_PEX1_STN2_RX_DP<41>")
	)
	(segment
		(start 149.310598 -30.922468)
		(end 149.601428 -30.631638)
		(width 0.1651)
		(layer "In7.Cu")
		(net "P5E_PEX1_STN2_RX_DP<41>")
	)
	(segment
		(start 152.879552 -31.738824)
		(end 153.229564 -32.088836)
		(width 0.1651)
		(layer "In7.Cu")
		(net "P5E_PEX1_STN2_RX_DP<41>")
	)
	(segment
		(start 154.023568 -49.394364)
		(end 153.924254 -55.75808)
		(width 0.1651)
		(layer "In7.Cu")
		(net "P5E_PEX1_STN2_RX_DP<41>")
	)
	(segment
		(start 152.680924 -37.940234)
		(end 152.707848 -39.641272)
		(width 0.1651)
		(layer "In7.Cu")
		(net "P5E_PEX1_STN2_RX_DP<41>")
	)
	(segment
		(start 157.484064 -104.61879)
		(end 157.9372 -119.576596)
		(width 0.1651)
		(layer "In7.Cu")
		(net "P5E_PEX1_STN2_RX_DP<41>")
	)
	(segment
		(start 165.234112 -263.623806)
		(end 165.633908 -267.683234)
		(width 0.1651)
		(layer "In7.Cu")
		(net "P5E_PEX1_STN2_RX_DP<41>")
	)
	(segment
		(start 152.708102 -39.658036)
		(end 154.023568 -49.394364)
		(width 0.1651)
		(layer "In7.Cu")
		(net "P5E_PEX1_STN2_RX_DP<41>")
	)
	(segment
		(start 152.707594 -39.641272)
		(end 152.708102 -39.658036)
		(width 0.1651)
		(layer "In7.Cu")
		(net "P5E_PEX1_STN2_RX_DP<41>")
	)
	(segment
		(start 165.382448 -260.60146)
		(end 165.234112 -263.623806)
		(width 0.1651)
		(layer "In7.Cu")
		(net "P5E_PEX1_STN2_RX_DP<41>")
	)
	(segment
		(start 152.735788 -31.738824)
		(end 152.879552 -31.738824)
		(width 0.1651)
		(layer "In7.Cu")
		(net "P5E_PEX1_STN2_RX_DP<41>")
	)
	(segment
		(start 151.171148 -30.733238)
		(end 151.272748 -30.631638)
		(width 0.1651)
		(layer "In7.Cu")
		(net "P5E_PEX1_STN2_RX_DP<41>")
	)
	(segment
		(start 154.284426 -64.756792)
		(end 157.484064 -104.61879)
		(width 0.1651)
		(layer "In7.Cu")
		(net "P5E_PEX1_STN2_RX_DP<41>")
	)
	(segment
		(start 165.679628 -271.41932)
		(end 165.679628 -273.407632)
		(width 0.1143)
		(layer "In7.Cu")
		(net "P5E_PEX1_STN2_RX_DP<41>")
	)
	(segment
		(start 166.135558 -273.670014)
		(end 166.249858 -273.784314)
		(width 0.1143)
		(layer "In7.Cu")
		(net "P5E_PEX1_STN2_RX_DP<41>")
	)
	(segment
		(start 152.385268 -31.388304)
		(end 152.735788 -31.738824)
		(width 0.1651)
		(layer "In7.Cu")
		(net "P5E_PEX1_STN2_RX_DP<41>")
	)
	(segment
		(start 150.574248 -30.631638)
		(end 150.675848 -30.733238)
		(width 0.1651)
		(layer "In7.Cu")
		(net "P5E_PEX1_STN2_RX_DP<41>")
	)
	(segment
		(start 314.278518 -135.60298)
		(end 306.122324 -135.60298)
		(width 0.13462)
		(layer "F.Cu")
		(net "P5E_PEX2_STN0_TX_C_DN<7>")
	)
	(segment
		(start 306.122324 -135.60298)
		(end 305.964336 -135.444992)
		(width 0.13462)
		(layer "F.Cu")
		(net "P5E_PEX2_STN0_TX_C_DN<7>")
	)
	(segment
		(start 314.594748 -135.28675)
		(end 314.278518 -135.60298)
		(width 0.13462)
		(layer "F.Cu")
		(net "P5E_PEX2_STN0_TX_C_DN<7>")
	)
	(segment
		(start 305.964336 -135.444992)
		(end 305.457606 -135.444992)
		(width 0.13462)
		(layer "F.Cu")
		(net "P5E_PEX2_STN0_TX_C_DN<7>")
	)
	(segment
		(start 339.215984 -368.88166)
		(end 338.69376 -368.10442)
		(width 0.1651)
		(layer "In9.Cu")
		(net "P5E_PEX2_STN6_RX_DN<100>")
	)
	(segment
		(start 285.815532 -324.433692)
		(end 285.815532 -319.916048)
		(width 0.1651)
		(layer "In9.Cu")
		(net "P5E_PEX2_STN6_RX_DN<100>")
	)
	(segment
		(start 286.060642 -318.320166)
		(end 286.149796 -318.40932)
		(width 0.1143)
		(layer "In9.Cu")
		(net "P5E_PEX2_STN6_RX_DN<100>")
	)
	(segment
		(start 285.883858 -318.320166)
		(end 286.060642 -318.320166)
		(width 0.1143)
		(layer "In9.Cu")
		(net "P5E_PEX2_STN6_RX_DN<100>")
	)
	(segment
		(start 317.27013 -341.256874)
		(end 295.347644 -332.6511)
		(width 0.1651)
		(layer "In9.Cu")
		(net "P5E_PEX2_STN6_RX_DN<100>")
	)
	(segment
		(start 317.739014 -342.2396)
		(end 317.27013 -341.256874)
		(width 0.1651)
		(layer "In9.Cu")
		(net "P5E_PEX2_STN6_RX_DN<100>")
	)
	(segment
		(start 318.41948 -359.05186)
		(end 317.739014 -358.371394)
		(width 0.1651)
		(layer "In9.Cu")
		(net "P5E_PEX2_STN6_RX_DN<100>")
	)
	(segment
		(start 286.149796 -318.40932)
		(end 286.149796 -318.699896)
		(width 0.1143)
		(layer "In9.Cu")
		(net "P5E_PEX2_STN6_RX_DN<100>")
	)
	(segment
		(start 338.090002 -376.790204)
		(end 338.090002 -376.408188)
		(width 0.1651)
		(layer "In9.Cu")
		(net "P5E_PEX2_STN6_RX_DN<100>")
	)
	(segment
		(start 295.347644 -332.6511)
		(end 289.94227 -329.11161)
		(width 0.1651)
		(layer "In9.Cu")
		(net "P5E_PEX2_STN6_RX_DN<100>")
	)
	(segment
		(start 339.215984 -375.829322)
		(end 339.215984 -368.88166)
		(width 0.1651)
		(layer "In9.Cu")
		(net "P5E_PEX2_STN6_RX_DN<100>")
	)
	(segment
		(start 285.815532 -319.916048)
		(end 285.815532 -319.8876)
		(width 0.1143)
		(layer "In9.Cu")
		(net "P5E_PEX2_STN6_RX_DN<100>")
	)
	(segment
		(start 338.69376 -368.10442)
		(end 335.19872 -365.83874)
		(width 0.1651)
		(layer "In9.Cu")
		(net "P5E_PEX2_STN6_RX_DN<100>")
	)
	(segment
		(start 338.090002 -376.408188)
		(end 338.217002 -376.281188)
		(width 0.1651)
		(layer "In9.Cu")
		(net "P5E_PEX2_STN6_RX_DN<100>")
	)
	(segment
		(start 285.769812 -318.434212)
		(end 285.883858 -318.320166)
		(width 0.1143)
		(layer "In9.Cu")
		(net "P5E_PEX2_STN6_RX_DN<100>")
	)
	(segment
		(start 338.217002 -376.281188)
		(end 338.764118 -376.281188)
		(width 0.1651)
		(layer "In9.Cu")
		(net "P5E_PEX2_STN6_RX_DN<100>")
	)
	(segment
		(start 285.769812 -319.84188)
		(end 285.769812 -318.434212)
		(width 0.1143)
		(layer "In9.Cu")
		(net "P5E_PEX2_STN6_RX_DN<100>")
	)
	(segment
		(start 285.815532 -319.8876)
		(end 285.769812 -319.84188)
		(width 0.1143)
		(layer "In9.Cu")
		(net "P5E_PEX2_STN6_RX_DN<100>")
	)
	(segment
		(start 289.94227 -329.11161)
		(end 286.205168 -325.374508)
		(width 0.1651)
		(layer "In9.Cu")
		(net "P5E_PEX2_STN6_RX_DN<100>")
	)
	(segment
		(start 335.19872 -365.83874)
		(end 318.41948 -359.05186)
		(width 0.1651)
		(layer "In9.Cu")
		(net "P5E_PEX2_STN6_RX_DN<100>")
	)
	(segment
		(start 338.764118 -376.281188)
		(end 339.215984 -375.829322)
		(width 0.1651)
		(layer "In9.Cu")
		(net "P5E_PEX2_STN6_RX_DN<100>")
	)
	(segment
		(start 286.205168 -325.374508)
		(end 285.815532 -324.433692)
		(width 0.1651)
		(layer "In9.Cu")
		(net "P5E_PEX2_STN6_RX_DN<100>")
	)
	(segment
		(start 317.739014 -358.371394)
		(end 317.739014 -342.2396)
		(width 0.1651)
		(layer "In9.Cu")
		(net "P5E_PEX2_STN6_RX_DN<100>")
	)
	(segment
		(start 400.245072 -132.79882)
		(end 399.589752 -132.79882)
		(width 0.13462)
		(layer "F.Cu")
		(net "P5E_PEX3_STN1_RX_DN<29>")
	)
	(segment
		(start 399.589752 -132.79882)
		(end 399.423636 -132.964936)
		(width 0.13462)
		(layer "F.Cu")
		(net "P5E_PEX3_STN1_RX_DN<29>")
	)
	(segment
		(start 399.423636 -132.964936)
		(end 398.94256 -132.964936)
		(width 0.13462)
		(layer "F.Cu")
		(net "P5E_PEX3_STN1_RX_DN<29>")
	)
	(segment
		(start 400.54276 -133.096508)
		(end 400.245072 -132.79882)
		(width 0.13462)
		(layer "F.Cu")
		(net "P5E_PEX3_STN1_RX_DN<29>")
	)
	(segment
		(start 396.578074 -142.396464)
		(end 396.36192 -142.918434)
		(width 0.1651)
		(layer "In5.Cu")
		(net "P5E_PEX3_STN1_RX_DN<29>")
	)
	(segment
		(start 395.619732 -143.745204)
		(end 395.458442 -143.73733)
		(width 0.1651)
		(layer "In5.Cu")
		(net "P5E_PEX3_STN1_RX_DN<29>")
	)
	(segment
		(start 397.71828 -135.866632)
		(end 397.780256 -136.015984)
		(width 0.1651)
		(layer "In5.Cu")
		(net "P5E_PEX3_STN1_RX_DN<29>")
	)
	(segment
		(start 397.780256 -136.015984)
		(end 397.590772 -136.473692)
		(width 0.1651)
		(layer "In5.Cu")
		(net "P5E_PEX3_STN1_RX_DN<29>")
	)
	(segment
		(start 395.458442 -143.73733)
		(end 394.43787 -144.662144)
		(width 0.1651)
		(layer "In5.Cu")
		(net "P5E_PEX3_STN1_RX_DN<29>")
	)
	(segment
		(start 397.365982 -138.44524)
		(end 397.365982 -138.94054)
		(width 0.1651)
		(layer "In5.Cu")
		(net "P5E_PEX3_STN1_RX_DN<29>")
	)
	(segment
		(start 396.854934 -141.727428)
		(end 396.91691 -141.87678)
		(width 0.1651)
		(layer "In5.Cu")
		(net "P5E_PEX3_STN1_RX_DN<29>")
	)
	(segment
		(start 397.365982 -140.15974)
		(end 397.251682 -140.27404)
		(width 0.1651)
		(layer "In5.Cu")
		(net "P5E_PEX3_STN1_RX_DN<29>")
	)
	(segment
		(start 399.360644 -133.337046)
		(end 399.356326 -133.498844)
		(width 0.1651)
		(layer "In5.Cu")
		(net "P5E_PEX3_STN1_RX_DN<29>")
	)
	(segment
		(start 396.91691 -141.87678)
		(end 396.727426 -142.334742)
		(width 0.1651)
		(layer "In5.Cu")
		(net "P5E_PEX3_STN1_RX_DN<29>")
	)
	(segment
		(start 400.25193 -132.805678)
		(end 400.035014 -132.805678)
		(width 0.1651)
		(layer "In5.Cu")
		(net "P5E_PEX3_STN1_RX_DN<29>")
	)
	(segment
		(start 390.751822 -147.013168)
		(end 390.31037 -147.823936)
		(width 0.1651)
		(layer "In5.Cu")
		(net "P5E_PEX3_STN1_RX_DN<29>")
	)
	(segment
		(start 391.304272 -146.477736)
		(end 390.939274 -146.783806)
		(width 0.1651)
		(layer "In5.Cu")
		(net "P5E_PEX3_STN1_RX_DN<29>")
	)
	(segment
		(start 397.590772 -136.473692)
		(end 397.441166 -136.535668)
		(width 0.1651)
		(layer "In5.Cu")
		(net "P5E_PEX3_STN1_RX_DN<29>")
	)
	(segment
		(start 397.251682 -138.33094)
		(end 397.365982 -138.44524)
		(width 0.1651)
		(layer "In5.Cu")
		(net "P5E_PEX3_STN1_RX_DN<29>")
	)
	(segment
		(start 419.920166 -275.276056)
		(end 420.023544 -275.379434)
		(width 0.1143)
		(layer "In5.Cu")
		(net "P5E_PEX3_STN1_RX_DN<29>")
	)
	(segment
		(start 395.987016 -143.412464)
		(end 395.619732 -143.745204)
		(width 0.1651)
		(layer "In5.Cu")
		(net "P5E_PEX3_STN1_RX_DN<29>")
	)
	(segment
		(start 397.441166 -136.535668)
		(end 397.251682 -136.993122)
		(width 0.1651)
		(layer "In5.Cu")
		(net "P5E_PEX3_STN1_RX_DN<29>")
	)
	(segment
		(start 399.826734 -132.892038)
		(end 399.757392 -132.96138)
		(width 0.1651)
		(layer "In5.Cu")
		(net "P5E_PEX3_STN1_RX_DN<29>")
	)
	(segment
		(start 390.939274 -146.783806)
		(end 390.751822 -147.013168)
		(width 0.1651)
		(layer "In5.Cu")
		(net "P5E_PEX3_STN1_RX_DN<29>")
	)
	(segment
		(start 396.727426 -142.334742)
		(end 396.578074 -142.396464)
		(width 0.1651)
		(layer "In5.Cu")
		(net "P5E_PEX3_STN1_RX_DN<29>")
	)
	(segment
		(start 397.251682 -136.993122)
		(end 397.251682 -138.33094)
		(width 0.1651)
		(layer "In5.Cu")
		(net "P5E_PEX3_STN1_RX_DN<29>")
	)
	(segment
		(start 394.43787 -144.662144)
		(end 394.035026 -145.264632)
		(width 0.1651)
		(layer "In5.Cu")
		(net "P5E_PEX3_STN1_RX_DN<29>")
	)
	(segment
		(start 398.996408 -133.839712)
		(end 398.834864 -133.83514)
		(width 0.1651)
		(layer "In5.Cu")
		(net "P5E_PEX3_STN1_RX_DN<29>")
	)
	(segment
		(start 419.965886 -267.461238)
		(end 419.965886 -271.570704)
		(width 0.1651)
		(layer "In5.Cu")
		(net "P5E_PEX3_STN1_RX_DN<29>")
	)
	(segment
		(start 395.995144 -143.25092)
		(end 395.987016 -143.412464)
		(width 0.1651)
		(layer "In5.Cu")
		(net "P5E_PEX3_STN1_RX_DN<29>")
	)
	(segment
		(start 398.834864 -133.83514)
		(end 398.381728 -134.2644)
		(width 0.1651)
		(layer "In5.Cu")
		(net "P5E_PEX3_STN1_RX_DN<29>")
	)
	(segment
		(start 397.365982 -139.66444)
		(end 397.365982 -140.15974)
		(width 0.1651)
		(layer "In5.Cu")
		(net "P5E_PEX3_STN1_RX_DN<29>")
	)
	(segment
		(start 397.251682 -139.05484)
		(end 397.251682 -139.55014)
		(width 0.1651)
		(layer "In5.Cu")
		(net "P5E_PEX3_STN1_RX_DN<29>")
	)
	(segment
		(start 420.023544 -275.379434)
		(end 420.185342 -275.379434)
		(width 0.1143)
		(layer "In5.Cu")
		(net "P5E_PEX3_STN1_RX_DN<29>")
	)
	(segment
		(start 400.54276 -133.096508)
		(end 400.25193 -132.805678)
		(width 0.1651)
		(layer "In5.Cu")
		(net "P5E_PEX3_STN1_RX_DN<29>")
	)
	(segment
		(start 419.920166 -271.644872)
		(end 419.920166 -275.276056)
		(width 0.1143)
		(layer "In5.Cu")
		(net "P5E_PEX3_STN1_RX_DN<29>")
	)
	(segment
		(start 397.251682 -140.76934)
		(end 396.854934 -141.727428)
		(width 0.1651)
		(layer "In5.Cu")
		(net "P5E_PEX3_STN1_RX_DN<29>")
	)
	(segment
		(start 420.299642 -275.265134)
		(end 420.299642 -274.999704)
		(width 0.1143)
		(layer "In5.Cu")
		(net "P5E_PEX3_STN1_RX_DN<29>")
	)
	(segment
		(start 399.757392 -132.96138)
		(end 399.360644 -133.337046)
		(width 0.1651)
		(layer "In5.Cu")
		(net "P5E_PEX3_STN1_RX_DN<29>")
	)
	(segment
		(start 390.89076 -156.74721)
		(end 391.616184 -160.843468)
		(width 0.1651)
		(layer "In5.Cu")
		(net "P5E_PEX3_STN1_RX_DN<29>")
	)
	(segment
		(start 398.057116 -135.347202)
		(end 397.907764 -135.409178)
		(width 0.1651)
		(layer "In5.Cu")
		(net "P5E_PEX3_STN1_RX_DN<29>")
	)
	(segment
		(start 397.251682 -140.27404)
		(end 397.251682 -140.76934)
		(width 0.1651)
		(layer "In5.Cu")
		(net "P5E_PEX3_STN1_RX_DN<29>")
	)
	(segment
		(start 400.035014 -132.805678)
		(end 399.826734 -132.892038)
		(width 0.1651)
		(layer "In5.Cu")
		(net "P5E_PEX3_STN1_RX_DN<29>")
	)
	(segment
		(start 419.965886 -271.570704)
		(end 419.965886 -271.599152)
		(width 0.1143)
		(layer "In5.Cu")
		(net "P5E_PEX3_STN1_RX_DN<29>")
	)
	(segment
		(start 392.992864 -146.056604)
		(end 392.520932 -146.207734)
		(width 0.1651)
		(layer "In5.Cu")
		(net "P5E_PEX3_STN1_RX_DN<29>")
	)
	(segment
		(start 392.377168 -146.13382)
		(end 391.304272 -146.477736)
		(width 0.1651)
		(layer "In5.Cu")
		(net "P5E_PEX3_STN1_RX_DN<29>")
	)
	(segment
		(start 394.035026 -145.264632)
		(end 393.538202 -145.761456)
		(width 0.1651)
		(layer "In5.Cu")
		(net "P5E_PEX3_STN1_RX_DN<29>")
	)
	(segment
		(start 420.185342 -275.379434)
		(end 420.299642 -275.265134)
		(width 0.1143)
		(layer "In5.Cu")
		(net "P5E_PEX3_STN1_RX_DN<29>")
	)
	(segment
		(start 419.965886 -271.599152)
		(end 419.920166 -271.644872)
		(width 0.1143)
		(layer "In5.Cu")
		(net "P5E_PEX3_STN1_RX_DN<29>")
	)
	(segment
		(start 392.520932 -146.207734)
		(end 392.377168 -146.13382)
		(width 0.1651)
		(layer "In5.Cu")
		(net "P5E_PEX3_STN1_RX_DN<29>")
	)
	(segment
		(start 397.251682 -139.55014)
		(end 397.365982 -139.66444)
		(width 0.1651)
		(layer "In5.Cu")
		(net "P5E_PEX3_STN1_RX_DN<29>")
	)
	(segment
		(start 397.907764 -135.409178)
		(end 397.71828 -135.866632)
		(width 0.1651)
		(layer "In5.Cu")
		(net "P5E_PEX3_STN1_RX_DN<29>")
	)
	(segment
		(start 399.356326 -133.498844)
		(end 398.996408 -133.839712)
		(width 0.1651)
		(layer "In5.Cu")
		(net "P5E_PEX3_STN1_RX_DN<29>")
	)
	(segment
		(start 396.36192 -142.918434)
		(end 395.995144 -143.25092)
		(width 0.1651)
		(layer "In5.Cu")
		(net "P5E_PEX3_STN1_RX_DN<29>")
	)
	(segment
		(start 393.066778 -145.912586)
		(end 392.992864 -146.056604)
		(width 0.1651)
		(layer "In5.Cu")
		(net "P5E_PEX3_STN1_RX_DN<29>")
	)
	(segment
		(start 390.31037 -147.823936)
		(end 390.89076 -156.74721)
		(width 0.1651)
		(layer "In5.Cu")
		(net "P5E_PEX3_STN1_RX_DN<29>")
	)
	(segment
		(start 398.184878 -134.740142)
		(end 398.2466 -134.889494)
		(width 0.1651)
		(layer "In5.Cu")
		(net "P5E_PEX3_STN1_RX_DN<29>")
	)
	(segment
		(start 393.538202 -145.761456)
		(end 393.066778 -145.912586)
		(width 0.1651)
		(layer "In5.Cu")
		(net "P5E_PEX3_STN1_RX_DN<29>")
	)
	(segment
		(start 397.365982 -138.94054)
		(end 397.251682 -139.05484)
		(width 0.1651)
		(layer "In5.Cu")
		(net "P5E_PEX3_STN1_RX_DN<29>")
	)
	(segment
		(start 398.381728 -134.2644)
		(end 398.184878 -134.740142)
		(width 0.1651)
		(layer "In5.Cu")
		(net "P5E_PEX3_STN1_RX_DN<29>")
	)
	(segment
		(start 398.2466 -134.889494)
		(end 398.057116 -135.347202)
		(width 0.1651)
		(layer "In5.Cu")
		(net "P5E_PEX3_STN1_RX_DN<29>")
	)
	(segment
		(start 391.616184 -160.843468)
		(end 419.965886 -267.461238)
		(width 0.1651)
		(layer "In5.Cu")
		(net "P5E_PEX3_STN1_RX_DN<29>")
	)
	(segment
		(start 371.233192 -388.03326)
		(end 370.268246 -385.531868)
		(width 0.1651)
		(layer "In15.Cu")
		(net "P5E_PEX3_STN6_RX_DP<108>")
	)
	(segment
		(start 369.733576 -372.469918)
		(end 369.733576 -372.469664)
		(width 0.1651)
		(layer "In15.Cu")
		(net "P5E_PEX3_STN6_RX_DP<108>")
	)
	(segment
		(start 369.733576 -372.469664)
		(end 369.734084 -372.469156)
		(width 0.1651)
		(layer "In15.Cu")
		(net "P5E_PEX3_STN6_RX_DP<108>")
	)
	(segment
		(start 393.81176 -321.793362)
		(end 394.033756 -321.257422)
		(width 0.1651)
		(layer "In15.Cu")
		(net "P5E_PEX3_STN6_RX_DP<108>")
	)
	(segment
		(start 380.50978 -393.61364)
		(end 380.467616 -393.45743)
		(width 0.1651)
		(layer "In15.Cu")
		(net "P5E_PEX3_STN6_RX_DP<108>")
	)
	(segment
		(start 394.53566 -318.129666)
		(end 394.64996 -318.015366)
		(width 0.1143)
		(layer "In15.Cu")
		(net "P5E_PEX3_STN6_RX_DP<108>")
	)
	(segment
		(start 394.033756 -319.995296)
		(end 394.033756 -319.966848)
		(width 0.1143)
		(layer "In15.Cu")
		(net "P5E_PEX3_STN6_RX_DP<108>")
	)
	(segment
		(start 376.467878 -391.158222)
		(end 374.067578 -390.10971)
		(width 0.1651)
		(layer "In15.Cu")
		(net "P5E_PEX3_STN6_RX_DP<108>")
	)
	(segment
		(start 394.033756 -319.966848)
		(end 394.079476 -319.921128)
		(width 0.1143)
		(layer "In15.Cu")
		(net "P5E_PEX3_STN6_RX_DP<108>")
	)
	(segment
		(start 381.095504 -393.818618)
		(end 380.939294 -393.860782)
		(width 0.1651)
		(layer "In15.Cu")
		(net "P5E_PEX3_STN6_RX_DP<108>")
	)
	(segment
		(start 394.079476 -319.921128)
		(end 394.079476 -318.345058)
		(width 0.1143)
		(layer "In15.Cu")
		(net "P5E_PEX3_STN6_RX_DP<108>")
	)
	(segment
		(start 369.762786 -371.946424)
		(end 369.891564 -342.397588)
		(width 0.1651)
		(layer "In15.Cu")
		(net "P5E_PEX3_STN6_RX_DP<108>")
	)
	(segment
		(start 370.74475 -340.83371)
		(end 385.47294 -329.075542)
		(width 0.1651)
		(layer "In15.Cu")
		(net "P5E_PEX3_STN6_RX_DP<108>")
	)
	(segment
		(start 382.933956 -396.29461)
		(end 382.371854 -394.893546)
		(width 0.1651)
		(layer "In15.Cu")
		(net "P5E_PEX3_STN6_RX_DP<108>")
	)
	(segment
		(start 394.079476 -318.345058)
		(end 394.294868 -318.129666)
		(width 0.1143)
		(layer "In15.Cu")
		(net "P5E_PEX3_STN6_RX_DP<108>")
	)
	(segment
		(start 369.891564 -342.397588)
		(end 369.94338 -342.142826)
		(width 0.1651)
		(layer "In15.Cu")
		(net "P5E_PEX3_STN6_RX_DP<108>")
	)
	(segment
		(start 382.216914 -401.999196)
		(end 382.64719 -401.999196)
		(width 0.1651)
		(layer "In15.Cu")
		(net "P5E_PEX3_STN6_RX_DP<108>")
	)
	(segment
		(start 394.033756 -321.257422)
		(end 394.033756 -319.995296)
		(width 0.1651)
		(layer "In15.Cu")
		(net "P5E_PEX3_STN6_RX_DP<108>")
	)
	(segment
		(start 382.089914 -401.872196)
		(end 382.216914 -401.999196)
		(width 0.1651)
		(layer "In15.Cu")
		(net "P5E_PEX3_STN6_RX_DP<108>")
	)
	(segment
		(start 369.734084 -372.469156)
		(end 369.734084 -372.468394)
		(width 0.1651)
		(layer "In15.Cu")
		(net "P5E_PEX3_STN6_RX_DP<108>")
	)
	(segment
		(start 394.294868 -318.129666)
		(end 394.53566 -318.129666)
		(width 0.1143)
		(layer "In15.Cu")
		(net "P5E_PEX3_STN6_RX_DP<108>")
	)
	(segment
		(start 380.038356 -393.210796)
		(end 379.8824 -393.25296)
		(width 0.1651)
		(layer "In15.Cu")
		(net "P5E_PEX3_STN6_RX_DP<108>")
	)
	(segment
		(start 382.371854 -394.893546)
		(end 381.722122 -394.17879)
		(width 0.1651)
		(layer "In15.Cu")
		(net "P5E_PEX3_STN6_RX_DP<108>")
	)
	(segment
		(start 382.089914 -401.49018)
		(end 382.089914 -401.872196)
		(width 0.1651)
		(layer "In15.Cu")
		(net "P5E_PEX3_STN6_RX_DP<108>")
	)
	(segment
		(start 382.64719 -401.999196)
		(end 382.933956 -401.71243)
		(width 0.1651)
		(layer "In15.Cu")
		(net "P5E_PEX3_STN6_RX_DP<108>")
	)
	(segment
		(start 379.410468 -392.849862)
		(end 376.467878 -391.158222)
		(width 0.1651)
		(layer "In15.Cu")
		(net "P5E_PEX3_STN6_RX_DP<108>")
	)
	(segment
		(start 379.452632 -393.005818)
		(end 379.410468 -392.849862)
		(width 0.1651)
		(layer "In15.Cu")
		(net "P5E_PEX3_STN6_RX_DP<108>")
	)
	(segment
		(start 369.94338 -342.142826)
		(end 370.74475 -340.83371)
		(width 0.1651)
		(layer "In15.Cu")
		(net "P5E_PEX3_STN6_RX_DP<108>")
	)
	(segment
		(start 374.067578 -390.10971)
		(end 371.233192 -388.03326)
		(width 0.1651)
		(layer "In15.Cu")
		(net "P5E_PEX3_STN6_RX_DP<108>")
	)
	(segment
		(start 370.268246 -385.531868)
		(end 369.733576 -372.469918)
		(width 0.1651)
		(layer "In15.Cu")
		(net "P5E_PEX3_STN6_RX_DP<108>")
	)
	(segment
		(start 381.722122 -394.17879)
		(end 381.095504 -393.818618)
		(width 0.1651)
		(layer "In15.Cu")
		(net "P5E_PEX3_STN6_RX_DP<108>")
	)
	(segment
		(start 385.47294 -329.075542)
		(end 391.831068 -324.426834)
		(width 0.1651)
		(layer "In15.Cu")
		(net "P5E_PEX3_STN6_RX_DP<108>")
	)
	(segment
		(start 369.734084 -372.468394)
		(end 369.762786 -371.946424)
		(width 0.1651)
		(layer "In15.Cu")
		(net "P5E_PEX3_STN6_RX_DP<108>")
	)
	(segment
		(start 391.831068 -324.426834)
		(end 393.81176 -321.793362)
		(width 0.1651)
		(layer "In15.Cu")
		(net "P5E_PEX3_STN6_RX_DP<108>")
	)
	(segment
		(start 380.939294 -393.860782)
		(end 380.50978 -393.61364)
		(width 0.1651)
		(layer "In15.Cu")
		(net "P5E_PEX3_STN6_RX_DP<108>")
	)
	(segment
		(start 394.64996 -318.015366)
		(end 394.64996 -317.749936)
		(width 0.1143)
		(layer "In15.Cu")
		(net "P5E_PEX3_STN6_RX_DP<108>")
	)
	(segment
		(start 379.8824 -393.25296)
		(end 379.452632 -393.005818)
		(width 0.1651)
		(layer "In15.Cu")
		(net "P5E_PEX3_STN6_RX_DP<108>")
	)
	(segment
		(start 380.467616 -393.45743)
		(end 380.038356 -393.210796)
		(width 0.1651)
		(layer "In15.Cu")
		(net "P5E_PEX3_STN6_RX_DP<108>")
	)
	(segment
		(start 382.933956 -401.71243)
		(end 382.933956 -396.29461)
		(width 0.1651)
		(layer "In15.Cu")
		(net "P5E_PEX3_STN6_RX_DP<108>")
	)
	(via
		(at 55.488332 -154.629104)
		(size 0.6604)
		(drill 0.3302)
		(layers "F.Cu" "B.Cu")
		(net "RST_HP_NIC0_N")
	)
	(segment
		(start 55.488332 -154.629104)
		(end 55.488332 -155.321254)
		(width 0.13208)
		(layer "B.Cu")
		(net "RST_HP_NIC0_N")
	)
	(segment
		(start 57.918096 -153.72461)
		(end 55.83047 -153.72461)
		(width 0.13208)
		(layer "B.Cu")
		(net "RST_HP_NIC0_N")
	)
	(segment
		(start 56.64708 -156.480002)
		(end 57.861962 -156.480002)
		(width 0.13208)
		(layer "B.Cu")
		(net "RST_HP_NIC0_N")
	)
	(segment
		(start 55.488332 -155.321254)
		(end 56.64708 -156.480002)
		(width 0.13208)
		(layer "B.Cu")
		(net "RST_HP_NIC0_N")
	)
	(segment
		(start 55.83047 -153.72461)
		(end 55.488332 -154.066748)
		(width 0.13208)
		(layer "B.Cu")
		(net "RST_HP_NIC0_N")
	)
	(segment
		(start 55.488332 -154.066748)
		(end 55.488332 -154.629104)
		(width 0.13208)
		(layer "B.Cu")
		(net "RST_HP_NIC0_N")
	)
	(segment
		(start 196.306186 -88.375998)
		(end 196.306186 -87.811102)
		(width 0.13208)
		(layer "F.Cu")
		(net "RST_NIC3_PERST1_R_N")
	)
	(segment
		(start 183.463438 -115.234974)
		(end 183.412638 -115.285774)
		(width 0.13208)
		(layer "F.Cu")
		(net "RST_NIC3_PERST1_R_N")
	)
	(segment
		(start 196.306186 -87.811102)
		(end 196.368162 -87.749126)
		(width 0.13208)
		(layer "F.Cu")
		(net "RST_NIC3_PERST1_R_N")
	)
	(segment
		(start 184.757314 -115.234974)
		(end 183.463438 -115.234974)
		(width 0.13208)
		(layer "F.Cu")
		(net "RST_NIC3_PERST1_R_N")
	)
	(segment
		(start 196.368162 -87.749126)
		(end 196.723508 -87.749126)
		(width 0.13208)
		(layer "F.Cu")
		(net "RST_NIC3_PERST1_R_N")
	)
	(via
		(at 183.412638 -115.285774)
		(size 0.508)
		(drill 0.254)
		(layers "F.Cu" "B.Cu")
		(net "RST_NIC3_PERST1_R_N")
	)
	(via
		(at 196.306186 -88.375998)
		(size 0.508)
		(drill 0.254)
		(layers "F.Cu" "B.Cu")
		(net "RST_NIC3_PERST1_R_N")
	)
	(segment
		(start 188.437012 -97.6503)
		(end 188.437012 -104.874822)
		(width 0.15494)
		(layer "In11.Cu")
		(net "RST_NIC3_PERST1_R_N")
	)
	(segment
		(start 188.437012 -104.874822)
		(end 189.227714 -105.665524)
		(width 0.15494)
		(layer "In11.Cu")
		(net "RST_NIC3_PERST1_R_N")
	)
	(segment
		(start 189.227714 -105.665524)
		(end 189.227714 -107.914186)
		(width 0.15494)
		(layer "In11.Cu")
		(net "RST_NIC3_PERST1_R_N")
	)
	(segment
		(start 190.107062 -95.98025)
		(end 188.437012 -97.6503)
		(width 0.15494)
		(layer "In11.Cu")
		(net "RST_NIC3_PERST1_R_N")
	)
	(segment
		(start 188.839348 -108.302552)
		(end 187.734448 -108.302552)
		(width 0.15494)
		(layer "In11.Cu")
		(net "RST_NIC3_PERST1_R_N")
	)
	(segment
		(start 183.98109 -115.285774)
		(end 183.412638 -115.285774)
		(width 0.15494)
		(layer "In11.Cu")
		(net "RST_NIC3_PERST1_R_N")
	)
	(segment
		(start 184.851294 -111.185706)
		(end 184.851294 -114.41557)
		(width 0.15494)
		(layer "In11.Cu")
		(net "RST_NIC3_PERST1_R_N")
	)
	(segment
		(start 189.227714 -107.914186)
		(end 188.839348 -108.302552)
		(width 0.15494)
		(layer "In11.Cu")
		(net "RST_NIC3_PERST1_R_N")
	)
	(segment
		(start 184.851294 -114.41557)
		(end 183.98109 -115.285774)
		(width 0.15494)
		(layer "In11.Cu")
		(net "RST_NIC3_PERST1_R_N")
	)
	(segment
		(start 187.734448 -108.302552)
		(end 184.851294 -111.185706)
		(width 0.15494)
		(layer "In11.Cu")
		(net "RST_NIC3_PERST1_R_N")
	)
	(segment
		(start 190.107062 -93.711268)
		(end 190.107062 -95.98025)
		(width 0.15494)
		(layer "In11.Cu")
		(net "RST_NIC3_PERST1_R_N")
	)
	(segment
		(start 196.306186 -88.375998)
		(end 195.442332 -88.375998)
		(width 0.15494)
		(layer "In11.Cu")
		(net "RST_NIC3_PERST1_R_N")
	)
	(segment
		(start 195.442332 -88.375998)
		(end 190.107062 -93.711268)
		(width 0.15494)
		(layer "In11.Cu")
		(net "RST_NIC3_PERST1_R_N")
	)
	(segment
		(start 204.11948 -30.62732)
		(end 201.605642 -30.62732)
		(width 0.13462)
		(layer "F.Cu")
		(net "P5E_PEX1_STN2_RX_DP<33>")
	)
	(segment
		(start 204.282294 -30.790134)
		(end 204.11948 -30.62732)
		(width 0.13462)
		(layer "F.Cu")
		(net "P5E_PEX1_STN2_RX_DP<33>")
	)
	(segment
		(start 204.764894 -30.790134)
		(end 204.282294 -30.790134)
		(width 0.13462)
		(layer "F.Cu")
		(net "P5E_PEX1_STN2_RX_DP<33>")
	)
	(segment
		(start 201.605642 -30.62732)
		(end 201.310494 -30.922468)
		(width 0.13462)
		(layer "F.Cu")
		(net "P5E_PEX1_STN2_RX_DP<33>")
	)
	(segment
		(start 201.674476 -30.631638)
		(end 201.549508 -30.683454)
		(width 0.1651)
		(layer "In7.Cu")
		(net "P5E_PEX1_STN2_RX_DP<33>")
	)
	(segment
		(start 173.542198 -273.670014)
		(end 173.279816 -273.407632)
		(width 0.1143)
		(layer "In7.Cu")
		(net "P5E_PEX1_STN2_RX_DP<33>")
	)
	(segment
		(start 204.459586 -31.499556)
		(end 204.493876 -31.341822)
		(width 0.1651)
		(layer "In7.Cu")
		(net "P5E_PEX1_STN2_RX_DP<33>")
	)
	(segment
		(start 173.735746 -273.670014)
		(end 173.542198 -273.670014)
		(width 0.1143)
		(layer "In7.Cu")
		(net "P5E_PEX1_STN2_RX_DP<33>")
	)
	(segment
		(start 204.707998 -39.65829)
		(end 204.683614 -38.129464)
		(width 0.1651)
		(layer "In7.Cu")
		(net "P5E_PEX1_STN2_RX_DP<33>")
	)
	(segment
		(start 204.886052 -31.95066)
		(end 204.728064 -31.91637)
		(width 0.1651)
		(layer "In7.Cu")
		(net "P5E_PEX1_STN2_RX_DP<33>")
	)
	(segment
		(start 173.279816 -271.41932)
		(end 173.234096 -271.3736)
		(width 0.1143)
		(layer "In7.Cu")
		(net "P5E_PEX1_STN2_RX_DP<33>")
	)
	(segment
		(start 173.234096 -271.345152)
		(end 173.234096 -270.917416)
		(width 0.1651)
		(layer "In7.Cu")
		(net "P5E_PEX1_STN2_RX_DP<33>")
	)
	(segment
		(start 204.03693 -30.631638)
		(end 203.380848 -30.631638)
		(width 0.1651)
		(layer "In7.Cu")
		(net "P5E_PEX1_STN2_RX_DP<33>")
	)
	(segment
		(start 173.57344 -267.004546)
		(end 193.139568 -154.656282)
		(width 0.1651)
		(layer "In7.Cu")
		(net "P5E_PEX1_STN2_RX_DP<33>")
	)
	(segment
		(start 173.234096 -270.917416)
		(end 173.57344 -267.004546)
		(width 0.1651)
		(layer "In7.Cu")
		(net "P5E_PEX1_STN2_RX_DP<33>")
	)
	(segment
		(start 202.656948 -30.631638)
		(end 201.674476 -30.631638)
		(width 0.1651)
		(layer "In7.Cu")
		(net "P5E_PEX1_STN2_RX_DP<33>")
	)
	(segment
		(start 206.023464 -49.394364)
		(end 204.707998 -39.65829)
		(width 0.1651)
		(layer "In7.Cu")
		(net "P5E_PEX1_STN2_RX_DP<33>")
	)
	(segment
		(start 194.831208 -116.662708)
		(end 205.839314 -61.179456)
		(width 0.1651)
		(layer "In7.Cu")
		(net "P5E_PEX1_STN2_RX_DP<33>")
	)
	(segment
		(start 194.515486 -143.970756)
		(end 194.831208 -116.662708)
		(width 0.1651)
		(layer "In7.Cu")
		(net "P5E_PEX1_STN2_RX_DP<33>")
	)
	(segment
		(start 205.411324 -33.05302)
		(end 205.154022 -32.366966)
		(width 0.1651)
		(layer "In7.Cu")
		(net "P5E_PEX1_STN2_RX_DP<33>")
	)
	(segment
		(start 173.850046 -274.049744)
		(end 173.850046 -273.784314)
		(width 0.1143)
		(layer "In7.Cu")
		(net "P5E_PEX1_STN2_RX_DP<33>")
	)
	(segment
		(start 205.403196 -34.076386)
		(end 205.411324 -33.05302)
		(width 0.1651)
		(layer "In7.Cu")
		(net "P5E_PEX1_STN2_RX_DP<33>")
	)
	(segment
		(start 204.728064 -31.91637)
		(end 204.459586 -31.499556)
		(width 0.1651)
		(layer "In7.Cu")
		(net "P5E_PEX1_STN2_RX_DP<33>")
	)
	(segment
		(start 204.493876 -31.341822)
		(end 204.03693 -30.631638)
		(width 0.1651)
		(layer "In7.Cu")
		(net "P5E_PEX1_STN2_RX_DP<33>")
	)
	(segment
		(start 205.154022 -32.366966)
		(end 204.886052 -31.95066)
		(width 0.1651)
		(layer "In7.Cu")
		(net "P5E_PEX1_STN2_RX_DP<33>")
	)
	(segment
		(start 173.850046 -273.784314)
		(end 173.735746 -273.670014)
		(width 0.1143)
		(layer "In7.Cu")
		(net "P5E_PEX1_STN2_RX_DP<33>")
	)
	(segment
		(start 201.549508 -30.683454)
		(end 201.310494 -30.922468)
		(width 0.1651)
		(layer "In7.Cu")
		(net "P5E_PEX1_STN2_RX_DP<33>")
	)
	(segment
		(start 203.380848 -30.631638)
		(end 203.266548 -30.745938)
		(width 0.1651)
		(layer "In7.Cu")
		(net "P5E_PEX1_STN2_RX_DP<33>")
	)
	(segment
		(start 205.839314 -61.179456)
		(end 206.023464 -49.394364)
		(width 0.1651)
		(layer "In7.Cu")
		(net "P5E_PEX1_STN2_RX_DP<33>")
	)
	(segment
		(start 173.279816 -273.407632)
		(end 173.279816 -271.41932)
		(width 0.1143)
		(layer "In7.Cu")
		(net "P5E_PEX1_STN2_RX_DP<33>")
	)
	(segment
		(start 202.771248 -30.745938)
		(end 202.656948 -30.631638)
		(width 0.1651)
		(layer "In7.Cu")
		(net "P5E_PEX1_STN2_RX_DP<33>")
	)
	(segment
		(start 204.683614 -38.129464)
		(end 205.403196 -34.076386)
		(width 0.1651)
		(layer "In7.Cu")
		(net "P5E_PEX1_STN2_RX_DP<33>")
	)
	(segment
		(start 203.266548 -30.745938)
		(end 202.771248 -30.745938)
		(width 0.1651)
		(layer "In7.Cu")
		(net "P5E_PEX1_STN2_RX_DP<33>")
	)
	(segment
		(start 193.139568 -154.656282)
		(end 194.515486 -143.970756)
		(width 0.1651)
		(layer "In7.Cu")
		(net "P5E_PEX1_STN2_RX_DP<33>")
	)
	(segment
		(start 173.234096 -271.3736)
		(end 173.234096 -271.345152)
		(width 0.1143)
		(layer "In7.Cu")
		(net "P5E_PEX1_STN2_RX_DP<33>")
	)
	(segment
		(start 300.379892 -148.155152)
		(end 300.857412 -148.155152)
		(width 0.13462)
		(layer "F.Cu")
		(net "P5E_PEX2_STN0_RX_DN<11>")
	)
	(segment
		(start 300.219364 -148.31568)
		(end 300.379892 -148.155152)
		(width 0.13462)
		(layer "F.Cu")
		(net "P5E_PEX2_STN0_RX_DN<11>")
	)
	(segment
		(start 297.403012 -148.023834)
		(end 297.694858 -148.31568)
		(width 0.13462)
		(layer "F.Cu")
		(net "P5E_PEX2_STN0_RX_DN<11>")
	)
	(segment
		(start 297.694858 -148.31568)
		(end 300.219364 -148.31568)
		(width 0.13462)
		(layer "F.Cu")
		(net "P5E_PEX2_STN0_RX_DN<11>")
	)
	(segment
		(start 304.07356 -154.710638)
		(end 306.20081 -157.91053)
		(width 0.1651)
		(layer "In5.Cu")
		(net "P5E_PEX2_STN0_RX_DN<11>")
	)
	(segment
		(start 310.57342 -273.479514)
		(end 310.735218 -273.479514)
		(width 0.1143)
		(layer "In5.Cu")
		(net "P5E_PEX2_STN0_RX_DN<11>")
	)
	(segment
		(start 310.735218 -273.479514)
		(end 310.849518 -273.365214)
		(width 0.1143)
		(layer "In5.Cu")
		(net "P5E_PEX2_STN0_RX_DN<11>")
	)
	(segment
		(start 310.515762 -271.554448)
		(end 310.470042 -271.600168)
		(width 0.1143)
		(layer "In5.Cu")
		(net "P5E_PEX2_STN0_RX_DN<11>")
	)
	(segment
		(start 311.058052 -268.156182)
		(end 310.515762 -270.91513)
		(width 0.1651)
		(layer "In5.Cu")
		(net "P5E_PEX2_STN0_RX_DN<11>")
	)
	(segment
		(start 307.46827 -161.047684)
		(end 307.468778 -161.050224)
		(width 0.1651)
		(layer "In5.Cu")
		(net "P5E_PEX2_STN0_RX_DN<11>")
	)
	(segment
		(start 299.902118 -148.314664)
		(end 302.483774 -150.89632)
		(width 0.1651)
		(layer "In5.Cu")
		(net "P5E_PEX2_STN0_RX_DN<11>")
	)
	(segment
		(start 310.470042 -271.600168)
		(end 310.470042 -273.376136)
		(width 0.1143)
		(layer "In5.Cu")
		(net "P5E_PEX2_STN0_RX_DN<11>")
	)
	(segment
		(start 310.849518 -273.365214)
		(end 310.849518 -273.099784)
		(width 0.1143)
		(layer "In5.Cu")
		(net "P5E_PEX2_STN0_RX_DN<11>")
	)
	(segment
		(start 310.470042 -273.376136)
		(end 310.57342 -273.479514)
		(width 0.1143)
		(layer "In5.Cu")
		(net "P5E_PEX2_STN0_RX_DN<11>")
	)
	(segment
		(start 310.515762 -270.91513)
		(end 310.515762 -271.526)
		(width 0.1651)
		(layer "In5.Cu")
		(net "P5E_PEX2_STN0_RX_DN<11>")
	)
	(segment
		(start 297.693842 -148.314664)
		(end 299.902118 -148.314664)
		(width 0.1651)
		(layer "In5.Cu")
		(net "P5E_PEX2_STN0_RX_DN<11>")
	)
	(segment
		(start 306.20081 -157.91053)
		(end 307.419502 -160.825434)
		(width 0.1651)
		(layer "In5.Cu")
		(net "P5E_PEX2_STN0_RX_DN<11>")
	)
	(segment
		(start 307.468778 -161.050224)
		(end 307.48986 -161.146236)
		(width 0.1651)
		(layer "In5.Cu")
		(net "P5E_PEX2_STN0_RX_DN<11>")
	)
	(segment
		(start 307.419502 -160.825434)
		(end 307.46827 -161.047684)
		(width 0.1651)
		(layer "In5.Cu")
		(net "P5E_PEX2_STN0_RX_DN<11>")
	)
	(segment
		(start 302.483774 -150.89632)
		(end 304.07356 -154.710638)
		(width 0.1651)
		(layer "In5.Cu")
		(net "P5E_PEX2_STN0_RX_DN<11>")
	)
	(segment
		(start 310.515762 -271.526)
		(end 310.515762 -271.554448)
		(width 0.1143)
		(layer "In5.Cu")
		(net "P5E_PEX2_STN0_RX_DN<11>")
	)
	(segment
		(start 297.403012 -148.023834)
		(end 297.693842 -148.314664)
		(width 0.1651)
		(layer "In5.Cu")
		(net "P5E_PEX2_STN0_RX_DN<11>")
	)
	(segment
		(start 307.490114 -161.147506)
		(end 307.516784 -161.269172)
		(width 0.1651)
		(layer "In5.Cu")
		(net "P5E_PEX2_STN0_RX_DN<11>")
	)
	(segment
		(start 311.023 -260.513576)
		(end 311.058052 -268.156182)
		(width 0.1651)
		(layer "In5.Cu")
		(net "P5E_PEX2_STN0_RX_DN<11>")
	)
	(segment
		(start 307.48986 -161.146236)
		(end 307.490114 -161.147506)
		(width 0.1651)
		(layer "In5.Cu")
		(net "P5E_PEX2_STN0_RX_DN<11>")
	)
	(segment
		(start 307.516784 -161.269172)
		(end 311.023 -260.513576)
		(width 0.1651)
		(layer "In5.Cu")
		(net "P5E_PEX2_STN0_RX_DN<11>")
	)
	(segment
		(start 399.581878 -123.3932)
		(end 399.42008 -123.554998)
		(width 0.13462)
		(layer "F.Cu")
		(net "P5E_PEX3_STN1_RX_DN<26>")
	)
	(segment
		(start 402.103844 -123.3932)
		(end 399.581878 -123.3932)
		(width 0.13462)
		(layer "F.Cu")
		(net "P5E_PEX3_STN1_RX_DN<26>")
	)
	(segment
		(start 402.39696 -123.686316)
		(end 402.103844 -123.3932)
		(width 0.13462)
		(layer "F.Cu")
		(net "P5E_PEX3_STN1_RX_DN<26>")
	)
	(segment
		(start 399.42008 -123.554998)
		(end 398.94256 -123.554998)
		(width 0.13462)
		(layer "F.Cu")
		(net "P5E_PEX3_STN1_RX_DN<26>")
	)
	(segment
		(start 401.304252 -123.509786)
		(end 400.808952 -123.509786)
		(width 0.1651)
		(layer "In5.Cu")
		(net "P5E_PEX3_STN1_RX_DN<26>")
	)
	(segment
		(start 397.879824 -124.960634)
		(end 397.722598 -124.923296)
		(width 0.1651)
		(layer "In5.Cu")
		(net "P5E_PEX3_STN1_RX_DN<26>")
	)
	(segment
		(start 392.678412 -131.756912)
		(end 392.594084 -132.245354)
		(width 0.1651)
		(layer "In5.Cu")
		(net "P5E_PEX3_STN1_RX_DN<26>")
	)
	(segment
		(start 391.254234 -139.332462)
		(end 390.215374 -142.91818)
		(width 0.1651)
		(layer "In5.Cu")
		(net "P5E_PEX3_STN1_RX_DN<26>")
	)
	(segment
		(start 390.215374 -142.91818)
		(end 387.714236 -146.275806)
		(width 0.1651)
		(layer "In5.Cu")
		(net "P5E_PEX3_STN1_RX_DN<26>")
	)
	(segment
		(start 392.885676 -130.555238)
		(end 392.801348 -131.04368)
		(width 0.1651)
		(layer "In5.Cu")
		(net "P5E_PEX3_STN1_RX_DN<26>")
	)
	(segment
		(start 387.714236 -146.275806)
		(end 387.410706 -147.433538)
		(width 0.1651)
		(layer "In5.Cu")
		(net "P5E_PEX3_STN1_RX_DN<26>")
	)
	(segment
		(start 395.199616 -126.66218)
		(end 394.574268 -127.453644)
		(width 0.1651)
		(layer "In5.Cu")
		(net "P5E_PEX3_STN1_RX_DN<26>")
	)
	(segment
		(start 402.10613 -123.395486)
		(end 401.418552 -123.395486)
		(width 0.1651)
		(layer "In5.Cu")
		(net "P5E_PEX3_STN1_RX_DN<26>")
	)
	(segment
		(start 402.39696 -123.686316)
		(end 402.10613 -123.395486)
		(width 0.1651)
		(layer "In5.Cu")
		(net "P5E_PEX3_STN1_RX_DN<26>")
	)
	(segment
		(start 417.116006 -267.893546)
		(end 417.116006 -271.526)
		(width 0.1651)
		(layer "In5.Cu")
		(net "P5E_PEX3_STN1_RX_DN<26>")
	)
	(segment
		(start 393.836906 -128.57099)
		(end 393.529566 -128.959864)
		(width 0.1651)
		(layer "In5.Cu")
		(net "P5E_PEX3_STN1_RX_DN<26>")
	)
	(segment
		(start 417.070286 -273.376136)
		(end 417.173664 -273.479514)
		(width 0.1143)
		(layer "In5.Cu")
		(net "P5E_PEX3_STN1_RX_DN<26>")
	)
	(segment
		(start 396.684754 -125.56363)
		(end 395.868906 -126.066804)
		(width 0.1651)
		(layer "In5.Cu")
		(net "P5E_PEX3_STN1_RX_DN<26>")
	)
	(segment
		(start 398.301718 -124.700284)
		(end 397.879824 -124.960634)
		(width 0.1651)
		(layer "In5.Cu")
		(net "P5E_PEX3_STN1_RX_DN<26>")
	)
	(segment
		(start 399.339562 -124.060204)
		(end 398.917668 -124.320554)
		(width 0.1651)
		(layer "In5.Cu")
		(net "P5E_PEX3_STN1_RX_DN<26>")
	)
	(segment
		(start 400.694652 -123.395486)
		(end 400.199352 -123.395486)
		(width 0.1651)
		(layer "In5.Cu")
		(net "P5E_PEX3_STN1_RX_DN<26>")
	)
	(segment
		(start 417.335462 -273.479514)
		(end 417.449762 -273.365214)
		(width 0.1143)
		(layer "In5.Cu")
		(net "P5E_PEX3_STN1_RX_DN<26>")
	)
	(segment
		(start 400.808952 -123.509786)
		(end 400.694652 -123.395486)
		(width 0.1651)
		(layer "In5.Cu")
		(net "P5E_PEX3_STN1_RX_DN<26>")
	)
	(segment
		(start 393.529566 -128.959864)
		(end 393.369038 -128.97866)
		(width 0.1651)
		(layer "In5.Cu")
		(net "P5E_PEX3_STN1_RX_DN<26>")
	)
	(segment
		(start 392.585194 -131.624832)
		(end 392.678412 -131.756912)
		(width 0.1651)
		(layer "In5.Cu")
		(net "P5E_PEX3_STN1_RX_DN<26>")
	)
	(segment
		(start 392.669268 -131.136898)
		(end 392.585194 -131.624832)
		(width 0.1651)
		(layer "In5.Cu")
		(net "P5E_PEX3_STN1_RX_DN<26>")
	)
	(segment
		(start 397.301212 -125.183138)
		(end 397.263874 -125.340618)
		(width 0.1651)
		(layer "In5.Cu")
		(net "P5E_PEX3_STN1_RX_DN<26>")
	)
	(segment
		(start 396.84198 -125.600714)
		(end 396.684754 -125.56363)
		(width 0.1651)
		(layer "In5.Cu")
		(net "P5E_PEX3_STN1_RX_DN<26>")
	)
	(segment
		(start 392.792458 -130.423158)
		(end 392.885676 -130.555238)
		(width 0.1651)
		(layer "In5.Cu")
		(net "P5E_PEX3_STN1_RX_DN<26>")
	)
	(segment
		(start 392.594084 -132.245354)
		(end 392.46175 -132.338572)
		(width 0.1651)
		(layer "In5.Cu")
		(net "P5E_PEX3_STN1_RX_DN<26>")
	)
	(segment
		(start 400.199352 -123.395486)
		(end 399.376646 -123.902978)
		(width 0.1651)
		(layer "In5.Cu")
		(net "P5E_PEX3_STN1_RX_DN<26>")
	)
	(segment
		(start 401.418552 -123.395486)
		(end 401.304252 -123.509786)
		(width 0.1651)
		(layer "In5.Cu")
		(net "P5E_PEX3_STN1_RX_DN<26>")
	)
	(segment
		(start 392.801348 -131.04368)
		(end 392.669014 -131.136898)
		(width 0.1651)
		(layer "In5.Cu")
		(net "P5E_PEX3_STN1_RX_DN<26>")
	)
	(segment
		(start 398.760442 -124.283216)
		(end 398.339056 -124.543058)
		(width 0.1651)
		(layer "In5.Cu")
		(net "P5E_PEX3_STN1_RX_DN<26>")
	)
	(segment
		(start 417.449762 -273.365214)
		(end 417.449762 -273.099784)
		(width 0.1143)
		(layer "In5.Cu")
		(net "P5E_PEX3_STN1_RX_DN<26>")
	)
	(segment
		(start 417.070286 -271.600168)
		(end 417.070286 -273.376136)
		(width 0.1143)
		(layer "In5.Cu")
		(net "P5E_PEX3_STN1_RX_DN<26>")
	)
	(segment
		(start 394.593064 -127.614426)
		(end 394.285724 -128.0033)
		(width 0.1651)
		(layer "In5.Cu")
		(net "P5E_PEX3_STN1_RX_DN<26>")
	)
	(segment
		(start 398.339056 -124.543058)
		(end 398.301718 -124.700284)
		(width 0.1651)
		(layer "In5.Cu")
		(net "P5E_PEX3_STN1_RX_DN<26>")
	)
	(segment
		(start 393.061952 -129.367026)
		(end 392.920982 -129.678176)
		(width 0.1651)
		(layer "In5.Cu")
		(net "P5E_PEX3_STN1_RX_DN<26>")
	)
	(segment
		(start 388.05612 -157.384496)
		(end 388.867142 -161.883598)
		(width 0.1651)
		(layer "In5.Cu")
		(net "P5E_PEX3_STN1_RX_DN<26>")
	)
	(segment
		(start 394.574268 -127.453898)
		(end 394.593064 -127.614426)
		(width 0.1651)
		(layer "In5.Cu")
		(net "P5E_PEX3_STN1_RX_DN<26>")
	)
	(segment
		(start 387.410706 -147.433538)
		(end 388.05612 -157.384496)
		(width 0.1651)
		(layer "In5.Cu")
		(net "P5E_PEX3_STN1_RX_DN<26>")
	)
	(segment
		(start 417.116006 -271.554448)
		(end 417.070286 -271.600168)
		(width 0.1143)
		(layer "In5.Cu")
		(net "P5E_PEX3_STN1_RX_DN<26>")
	)
	(segment
		(start 392.669014 -131.136898)
		(end 392.669268 -131.136898)
		(width 0.1651)
		(layer "In5.Cu")
		(net "P5E_PEX3_STN1_RX_DN<26>")
	)
	(segment
		(start 394.285724 -128.0033)
		(end 394.125196 -128.022096)
		(width 0.1651)
		(layer "In5.Cu")
		(net "P5E_PEX3_STN1_RX_DN<26>")
	)
	(segment
		(start 392.46175 -132.338572)
		(end 391.254234 -139.332462)
		(width 0.1651)
		(layer "In5.Cu")
		(net "P5E_PEX3_STN1_RX_DN<26>")
	)
	(segment
		(start 394.574268 -127.453644)
		(end 394.574268 -127.453898)
		(width 0.1651)
		(layer "In5.Cu")
		(net "P5E_PEX3_STN1_RX_DN<26>")
	)
	(segment
		(start 388.867142 -161.883598)
		(end 417.116006 -267.893546)
		(width 0.1651)
		(layer "In5.Cu")
		(net "P5E_PEX3_STN1_RX_DN<26>")
	)
	(segment
		(start 392.920982 -129.678176)
		(end 392.792458 -130.423158)
		(width 0.1651)
		(layer "In5.Cu")
		(net "P5E_PEX3_STN1_RX_DN<26>")
	)
	(segment
		(start 393.369038 -128.97866)
		(end 393.061952 -129.367026)
		(width 0.1651)
		(layer "In5.Cu")
		(net "P5E_PEX3_STN1_RX_DN<26>")
	)
	(segment
		(start 399.376646 -123.902978)
		(end 399.339562 -124.060204)
		(width 0.1651)
		(layer "In5.Cu")
		(net "P5E_PEX3_STN1_RX_DN<26>")
	)
	(segment
		(start 394.125196 -128.022096)
		(end 393.81811 -128.410462)
		(width 0.1651)
		(layer "In5.Cu")
		(net "P5E_PEX3_STN1_RX_DN<26>")
	)
	(segment
		(start 397.722598 -124.923296)
		(end 397.301212 -125.183138)
		(width 0.1651)
		(layer "In5.Cu")
		(net "P5E_PEX3_STN1_RX_DN<26>")
	)
	(segment
		(start 417.173664 -273.479514)
		(end 417.335462 -273.479514)
		(width 0.1143)
		(layer "In5.Cu")
		(net "P5E_PEX3_STN1_RX_DN<26>")
	)
	(segment
		(start 397.263874 -125.340618)
		(end 396.84198 -125.600714)
		(width 0.1651)
		(layer "In5.Cu")
		(net "P5E_PEX3_STN1_RX_DN<26>")
	)
	(segment
		(start 417.116006 -271.526)
		(end 417.116006 -271.554448)
		(width 0.1143)
		(layer "In5.Cu")
		(net "P5E_PEX3_STN1_RX_DN<26>")
	)
	(segment
		(start 393.81811 -128.410462)
		(end 393.836906 -128.57099)
		(width 0.1651)
		(layer "In5.Cu")
		(net "P5E_PEX3_STN1_RX_DN<26>")
	)
	(segment
		(start 395.868906 -126.066804)
		(end 395.199616 -126.66218)
		(width 0.1651)
		(layer "In5.Cu")
		(net "P5E_PEX3_STN1_RX_DN<26>")
	)
	(segment
		(start 398.917668 -124.320554)
		(end 398.760442 -124.283216)
		(width 0.1651)
		(layer "In5.Cu")
		(net "P5E_PEX3_STN1_RX_DN<26>")
	)
	(segment
		(start 384.290062 -400.772122)
		(end 384.417062 -400.899122)
		(width 0.1651)
		(layer "In15.Cu")
		(net "P5E_PEX3_STN6_RX_DP<107>")
	)
	(segment
		(start 373.672608 -340.570566)
		(end 385.92887 -330.280518)
		(width 0.1651)
		(layer "In15.Cu")
		(net "P5E_PEX3_STN6_RX_DP<107>")
	)
	(segment
		(start 394.66901 -322.272914)
		(end 394.98397 -321.512692)
		(width 0.1651)
		(layer "In15.Cu")
		(net "P5E_PEX3_STN6_RX_DP<107>")
	)
	(segment
		(start 382.104138 -392.910568)
		(end 381.94742 -392.94943)
		(width 0.1651)
		(layer "In15.Cu")
		(net "P5E_PEX3_STN6_RX_DP<107>")
	)
	(segment
		(start 384.290062 -400.390106)
		(end 384.290062 -400.772122)
		(width 0.1651)
		(layer "In15.Cu")
		(net "P5E_PEX3_STN6_RX_DP<107>")
	)
	(segment
		(start 371.235224 -385.312158)
		(end 370.760498 -373.398542)
		(width 0.1651)
		(layer "In15.Cu")
		(net "P5E_PEX3_STN6_RX_DP<107>")
	)
	(segment
		(start 381.484124 -392.536426)
		(end 380.37516 -391.86739)
		(width 0.1651)
		(layer "In15.Cu")
		(net "P5E_PEX3_STN6_RX_DP<107>")
	)
	(segment
		(start 384.847338 -400.899122)
		(end 385.134104 -400.612356)
		(width 0.1651)
		(layer "In15.Cu")
		(net "P5E_PEX3_STN6_RX_DP<107>")
	)
	(segment
		(start 394.98397 -321.512692)
		(end 394.98397 -319.995296)
		(width 0.1651)
		(layer "In15.Cu")
		(net "P5E_PEX3_STN6_RX_DP<107>")
	)
	(segment
		(start 381.522986 -392.693398)
		(end 381.484124 -392.536426)
		(width 0.1651)
		(layer "In15.Cu")
		(net "P5E_PEX3_STN6_RX_DP<107>")
	)
	(segment
		(start 372.08079 -387.454394)
		(end 371.235224 -385.312158)
		(width 0.1651)
		(layer "In15.Cu")
		(net "P5E_PEX3_STN6_RX_DP<107>")
	)
	(segment
		(start 395.02969 -319.921128)
		(end 395.02969 -316.44463)
		(width 0.1143)
		(layer "In15.Cu")
		(net "P5E_PEX3_STN6_RX_DP<107>")
	)
	(segment
		(start 394.98397 -319.995296)
		(end 394.98397 -319.966848)
		(width 0.1143)
		(layer "In15.Cu")
		(net "P5E_PEX3_STN6_RX_DP<107>")
	)
	(segment
		(start 382.99136 -393.57935)
		(end 382.566926 -393.323318)
		(width 0.1651)
		(layer "In15.Cu")
		(net "P5E_PEX3_STN6_RX_DP<107>")
	)
	(segment
		(start 370.760498 -373.398542)
		(end 370.873528 -371.346984)
		(width 0.1651)
		(layer "In15.Cu")
		(net "P5E_PEX3_STN6_RX_DP<107>")
	)
	(segment
		(start 385.134104 -395.328902)
		(end 384.826002 -394.552678)
		(width 0.1651)
		(layer "In15.Cu")
		(net "P5E_PEX3_STN6_RX_DP<107>")
	)
	(segment
		(start 385.92887 -330.280518)
		(end 392.308588 -325.493634)
		(width 0.1651)
		(layer "In15.Cu")
		(net "P5E_PEX3_STN6_RX_DP<107>")
	)
	(segment
		(start 373.03329 -342.107012)
		(end 373.672608 -340.570566)
		(width 0.1651)
		(layer "In15.Cu")
		(net "P5E_PEX3_STN6_RX_DP<107>")
	)
	(segment
		(start 382.528064 -393.166346)
		(end 382.104138 -392.910568)
		(width 0.1651)
		(layer "In15.Cu")
		(net "P5E_PEX3_STN6_RX_DP<107>")
	)
	(segment
		(start 370.873528 -371.346984)
		(end 373.03329 -357.995728)
		(width 0.1651)
		(layer "In15.Cu")
		(net "P5E_PEX3_STN6_RX_DP<107>")
	)
	(segment
		(start 384.826002 -394.552678)
		(end 383.148078 -393.540488)
		(width 0.1651)
		(layer "In15.Cu")
		(net "P5E_PEX3_STN6_RX_DP<107>")
	)
	(segment
		(start 394.98397 -319.966848)
		(end 395.02969 -319.921128)
		(width 0.1143)
		(layer "In15.Cu")
		(net "P5E_PEX3_STN6_RX_DP<107>")
	)
	(segment
		(start 395.244828 -316.229492)
		(end 395.48562 -316.229492)
		(width 0.1143)
		(layer "In15.Cu")
		(net "P5E_PEX3_STN6_RX_DP<107>")
	)
	(segment
		(start 373.03329 -357.995728)
		(end 373.03329 -342.107012)
		(width 0.1651)
		(layer "In15.Cu")
		(net "P5E_PEX3_STN6_RX_DP<107>")
	)
	(segment
		(start 384.417062 -400.899122)
		(end 384.847338 -400.899122)
		(width 0.1651)
		(layer "In15.Cu")
		(net "P5E_PEX3_STN6_RX_DP<107>")
	)
	(segment
		(start 385.134104 -400.612356)
		(end 385.134104 -395.328902)
		(width 0.1651)
		(layer "In15.Cu")
		(net "P5E_PEX3_STN6_RX_DP<107>")
	)
	(segment
		(start 383.148078 -393.540488)
		(end 382.99136 -393.57935)
		(width 0.1651)
		(layer "In15.Cu")
		(net "P5E_PEX3_STN6_RX_DP<107>")
	)
	(segment
		(start 395.59992 -316.115192)
		(end 395.59992 -315.849762)
		(width 0.1143)
		(layer "In15.Cu")
		(net "P5E_PEX3_STN6_RX_DP<107>")
	)
	(segment
		(start 392.308588 -325.493634)
		(end 394.66901 -322.272914)
		(width 0.1651)
		(layer "In15.Cu")
		(net "P5E_PEX3_STN6_RX_DP<107>")
	)
	(segment
		(start 374.665748 -389.289798)
		(end 372.08079 -387.454394)
		(width 0.1651)
		(layer "In15.Cu")
		(net "P5E_PEX3_STN6_RX_DP<107>")
	)
	(segment
		(start 395.48562 -316.229492)
		(end 395.59992 -316.115192)
		(width 0.1143)
		(layer "In15.Cu")
		(net "P5E_PEX3_STN6_RX_DP<107>")
	)
	(segment
		(start 381.94742 -392.94943)
		(end 381.522986 -392.693398)
		(width 0.1651)
		(layer "In15.Cu")
		(net "P5E_PEX3_STN6_RX_DP<107>")
	)
	(segment
		(start 382.566926 -393.323318)
		(end 382.528064 -393.166346)
		(width 0.1651)
		(layer "In15.Cu")
		(net "P5E_PEX3_STN6_RX_DP<107>")
	)
	(segment
		(start 380.37516 -391.86739)
		(end 374.665748 -389.289798)
		(width 0.1651)
		(layer "In15.Cu")
		(net "P5E_PEX3_STN6_RX_DP<107>")
	)
	(segment
		(start 395.02969 -316.44463)
		(end 395.244828 -316.229492)
		(width 0.1143)
		(layer "In15.Cu")
		(net "P5E_PEX3_STN6_RX_DP<107>")
	)
	(segment
		(start 62.187328 -30.190186)
		(end 62.024514 -30.353)
		(width 0.13462)
		(layer "F.Cu")
		(net "P5E_PEX0_STN2_RX_DN<37>")
	)
	(segment
		(start 62.664848 -30.190186)
		(end 62.187328 -30.190186)
		(width 0.13462)
		(layer "F.Cu")
		(net "P5E_PEX0_STN2_RX_DN<37>")
	)
	(segment
		(start 59.50458 -30.353)
		(end 59.210448 -30.058868)
		(width 0.13462)
		(layer "F.Cu")
		(net "P5E_PEX0_STN2_RX_DN<37>")
	)
	(segment
		(start 62.024514 -30.353)
		(end 59.50458 -30.353)
		(width 0.13462)
		(layer "F.Cu")
		(net "P5E_PEX0_STN2_RX_DN<37>")
	)
	(segment
		(start 63.387986 -35.00755)
		(end 63.41237 -31.973012)
		(width 0.1651)
		(layer "In7.Cu")
		(net "P5E_PEX0_STN2_RX_DN<37>")
	)
	(segment
		(start 59.501278 -30.349698)
		(end 59.210448 -30.058868)
		(width 0.1651)
		(layer "In7.Cu")
		(net "P5E_PEX0_STN2_RX_DN<37>")
	)
	(segment
		(start 53.615844 -271.345152)
		(end 53.615844 -266.392152)
		(width 0.1651)
		(layer "In7.Cu")
		(net "P5E_PEX0_STN2_RX_DN<37>")
	)
	(segment
		(start 64.120522 -68.498974)
		(end 64.304926 -50.110644)
		(width 0.1651)
		(layer "In7.Cu")
		(net "P5E_PEX0_STN2_RX_DN<37>")
	)
	(segment
		(start 53.570124 -271.41932)
		(end 53.615844 -271.3736)
		(width 0.1143)
		(layer "In7.Cu")
		(net "P5E_PEX0_STN2_RX_DN<37>")
	)
	(segment
		(start 53.721 -273.479514)
		(end 53.570124 -273.328638)
		(width 0.1143)
		(layer "In7.Cu")
		(net "P5E_PEX0_STN2_RX_DN<37>")
	)
	(segment
		(start 62.884558 -39.308786)
		(end 62.863222 -37.96284)
		(width 0.1651)
		(layer "In7.Cu")
		(net "P5E_PEX0_STN2_RX_DN<37>")
	)
	(segment
		(start 53.949854 -273.365214)
		(end 53.835554 -273.479514)
		(width 0.1143)
		(layer "In7.Cu")
		(net "P5E_PEX0_STN2_RX_DN<37>")
	)
	(segment
		(start 62.93358 -39.962328)
		(end 62.884558 -39.308786)
		(width 0.1651)
		(layer "In7.Cu")
		(net "P5E_PEX0_STN2_RX_DN<37>")
	)
	(segment
		(start 53.615844 -271.3736)
		(end 53.615844 -271.345152)
		(width 0.1143)
		(layer "In7.Cu")
		(net "P5E_PEX0_STN2_RX_DN<37>")
	)
	(segment
		(start 53.949854 -273.099784)
		(end 53.949854 -273.365214)
		(width 0.1143)
		(layer "In7.Cu")
		(net "P5E_PEX0_STN2_RX_DN<37>")
	)
	(segment
		(start 63.41237 -31.973012)
		(end 61.789056 -30.349698)
		(width 0.1651)
		(layer "In7.Cu")
		(net "P5E_PEX0_STN2_RX_DN<37>")
	)
	(segment
		(start 53.615844 -266.392152)
		(end 53.7464 -264.905998)
		(width 0.1651)
		(layer "In7.Cu")
		(net "P5E_PEX0_STN2_RX_DN<37>")
	)
	(segment
		(start 64.304926 -50.110644)
		(end 62.93358 -39.962328)
		(width 0.1651)
		(layer "In7.Cu")
		(net "P5E_PEX0_STN2_RX_DN<37>")
	)
	(segment
		(start 62.863222 -37.96284)
		(end 63.387986 -35.00755)
		(width 0.1651)
		(layer "In7.Cu")
		(net "P5E_PEX0_STN2_RX_DN<37>")
	)
	(segment
		(start 61.789056 -30.349698)
		(end 59.501278 -30.349698)
		(width 0.1651)
		(layer "In7.Cu")
		(net "P5E_PEX0_STN2_RX_DN<37>")
	)
	(segment
		(start 53.835554 -273.479514)
		(end 53.721 -273.479514)
		(width 0.1143)
		(layer "In7.Cu")
		(net "P5E_PEX0_STN2_RX_DN<37>")
	)
	(segment
		(start 53.570124 -273.328638)
		(end 53.570124 -271.41932)
		(width 0.1143)
		(layer "In7.Cu")
		(net "P5E_PEX0_STN2_RX_DN<37>")
	)
	(segment
		(start 53.7464 -264.905998)
		(end 64.120522 -68.498974)
		(width 0.1651)
		(layer "In7.Cu")
		(net "P5E_PEX0_STN2_RX_DN<37>")
	)
	(segment
		(start 159.31515 -28.829)
		(end 158.025592 -28.829)
		(width 0.13462)
		(layer "F.Cu")
		(net "P5E_PEX1_STN2_TX_C_DP<40>")
	)
	(segment
		(start 159.625792 -29.139642)
		(end 159.31515 -28.829)
		(width 0.13462)
		(layer "F.Cu")
		(net "P5E_PEX1_STN2_TX_C_DP<40>")
	)
	(segment
		(start 157.864556 -28.990036)
		(end 157.364938 -28.990036)
		(width 0.13462)
		(layer "F.Cu")
		(net "P5E_PEX1_STN2_TX_C_DP<40>")
	)
	(segment
		(start 158.025592 -28.829)
		(end 157.864556 -28.990036)
		(width 0.13462)
		(layer "F.Cu")
		(net "P5E_PEX1_STN2_TX_C_DP<40>")
	)
	(segment
		(start 314.27674 -132.2832)
		(end 306.12207 -132.2832)
		(width 0.13462)
		(layer "F.Cu")
		(net "P5E_PEX2_STN0_TX_C_DP<5>")
	)
	(segment
		(start 305.960272 -132.444998)
		(end 305.457606 -132.444998)
		(width 0.13462)
		(layer "F.Cu")
		(net "P5E_PEX2_STN0_TX_C_DP<5>")
	)
	(segment
		(start 306.12207 -132.2832)
		(end 305.960272 -132.444998)
		(width 0.13462)
		(layer "F.Cu")
		(net "P5E_PEX2_STN0_TX_C_DP<5>")
	)
	(segment
		(start 314.594748 -132.601208)
		(end 314.27674 -132.2832)
		(width 0.13462)
		(layer "F.Cu")
		(net "P5E_PEX2_STN0_TX_C_DP<5>")
	)
	(segment
		(start 399.578576 -108.8898)
		(end 399.423382 -109.044994)
		(width 0.13462)
		(layer "F.Cu")
		(net "P5E_PEX3_STN1_RX_DN<21>")
	)
	(segment
		(start 400.256248 -108.8898)
		(end 399.578576 -108.8898)
		(width 0.13462)
		(layer "F.Cu")
		(net "P5E_PEX3_STN1_RX_DN<21>")
	)
	(segment
		(start 400.54276 -109.176312)
		(end 400.256248 -108.8898)
		(width 0.13462)
		(layer "F.Cu")
		(net "P5E_PEX3_STN1_RX_DN<21>")
	)
	(segment
		(start 399.423382 -109.044994)
		(end 398.94256 -109.044994)
		(width 0.13462)
		(layer "F.Cu")
		(net "P5E_PEX3_STN1_RX_DN<21>")
	)
	(segment
		(start 397.015208 -110.66653)
		(end 396.58417 -110.911132)
		(width 0.1651)
		(layer "In5.Cu")
		(net "P5E_PEX3_STN1_RX_DN<21>")
	)
	(segment
		(start 398.762982 -109.543596)
		(end 398.332198 -109.787944)
		(width 0.1651)
		(layer "In5.Cu")
		(net "P5E_PEX3_STN1_RX_DN<21>")
	)
	(segment
		(start 387.261862 -126.85014)
		(end 387.066536 -127.305562)
		(width 0.1651)
		(layer "In5.Cu")
		(net "P5E_PEX3_STN1_RX_DN<21>")
	)
	(segment
		(start 398.289272 -109.943646)
		(end 397.858234 -110.188248)
		(width 0.1651)
		(layer "In5.Cu")
		(net "P5E_PEX3_STN1_RX_DN<21>")
	)
	(segment
		(start 395.997684 -111.112554)
		(end 395.954758 -111.268256)
		(width 0.1651)
		(layer "In5.Cu")
		(net "P5E_PEX3_STN1_RX_DN<21>")
	)
	(segment
		(start 397.858234 -110.188248)
		(end 397.702532 -110.145322)
		(width 0.1651)
		(layer "In5.Cu")
		(net "P5E_PEX3_STN1_RX_DN<21>")
	)
	(segment
		(start 400.54276 -109.176312)
		(end 400.25193 -108.885482)
		(width 0.1651)
		(layer "In5.Cu")
		(net "P5E_PEX3_STN1_RX_DN<21>")
	)
	(segment
		(start 395.367764 -111.469932)
		(end 391.023602 -113.93424)
		(width 0.1651)
		(layer "In5.Cu")
		(net "P5E_PEX3_STN1_RX_DN<21>")
	)
	(segment
		(start 385.472686 -130.726688)
		(end 384.852926 -132.169662)
		(width 0.1651)
		(layer "In5.Cu")
		(net "P5E_PEX3_STN1_RX_DN<21>")
	)
	(segment
		(start 387.066536 -127.305562)
		(end 386.916168 -127.365506)
		(width 0.1651)
		(layer "In5.Cu")
		(net "P5E_PEX3_STN1_RX_DN<21>")
	)
	(segment
		(start 384.852926 -136.432798)
		(end 383.659888 -139.737338)
		(width 0.1651)
		(layer "In5.Cu")
		(net "P5E_PEX3_STN1_RX_DN<21>")
	)
	(segment
		(start 383.211578 -164.60978)
		(end 412.365952 -269.144496)
		(width 0.1651)
		(layer "In5.Cu")
		(net "P5E_PEX3_STN1_RX_DN<21>")
	)
	(segment
		(start 382.159764 -158.511494)
		(end 383.211578 -164.60978)
		(width 0.1651)
		(layer "In5.Cu")
		(net "P5E_PEX3_STN1_RX_DN<21>")
	)
	(segment
		(start 412.585408 -275.379434)
		(end 412.699708 -275.265134)
		(width 0.1143)
		(layer "In5.Cu")
		(net "P5E_PEX3_STN1_RX_DN<21>")
	)
	(segment
		(start 387.201918 -126.700026)
		(end 387.261862 -126.85014)
		(width 0.1651)
		(layer "In5.Cu")
		(net "P5E_PEX3_STN1_RX_DN<21>")
	)
	(segment
		(start 399.91919 -108.885482)
		(end 399.920206 -108.886498)
		(width 0.1651)
		(layer "In5.Cu")
		(net "P5E_PEX3_STN1_RX_DN<21>")
	)
	(segment
		(start 385.623054 -130.666744)
		(end 385.472686 -130.726688)
		(width 0.1651)
		(layer "In5.Cu")
		(net "P5E_PEX3_STN1_RX_DN<21>")
	)
	(segment
		(start 395.954758 -111.268256)
		(end 395.52372 -111.512858)
		(width 0.1651)
		(layer "In5.Cu")
		(net "P5E_PEX3_STN1_RX_DN<21>")
	)
	(segment
		(start 412.42361 -275.379434)
		(end 412.585408 -275.379434)
		(width 0.1143)
		(layer "In5.Cu")
		(net "P5E_PEX3_STN1_RX_DN<21>")
	)
	(segment
		(start 383.659888 -139.737338)
		(end 381.675132 -150.684484)
		(width 0.1651)
		(layer "In5.Cu")
		(net "P5E_PEX3_STN1_RX_DN<21>")
	)
	(segment
		(start 396.428468 -110.868206)
		(end 395.997684 -111.112554)
		(width 0.1651)
		(layer "In5.Cu")
		(net "P5E_PEX3_STN1_RX_DN<21>")
	)
	(segment
		(start 396.58417 -110.911132)
		(end 396.428468 -110.868206)
		(width 0.1651)
		(layer "In5.Cu")
		(net "P5E_PEX3_STN1_RX_DN<21>")
	)
	(segment
		(start 385.758436 -130.061208)
		(end 385.81838 -130.211322)
		(width 0.1651)
		(layer "In5.Cu")
		(net "P5E_PEX3_STN1_RX_DN<21>")
	)
	(segment
		(start 399.349976 -109.34192)
		(end 398.918684 -109.586522)
		(width 0.1651)
		(layer "In5.Cu")
		(net "P5E_PEX3_STN1_RX_DN<21>")
	)
	(segment
		(start 388.20217 -124.370846)
		(end 387.201918 -126.700026)
		(width 0.1651)
		(layer "In5.Cu")
		(net "P5E_PEX3_STN1_RX_DN<21>")
	)
	(segment
		(start 391.023602 -113.93424)
		(end 390.971786 -113.984532)
		(width 0.1651)
		(layer "In5.Cu")
		(net "P5E_PEX3_STN1_RX_DN<21>")
	)
	(segment
		(start 386.435092 -128.4859)
		(end 386.239766 -128.940814)
		(width 0.1651)
		(layer "In5.Cu")
		(net "P5E_PEX3_STN1_RX_DN<21>")
	)
	(segment
		(start 386.29971 -129.090928)
		(end 386.10413 -129.54635)
		(width 0.1651)
		(layer "In5.Cu")
		(net "P5E_PEX3_STN1_RX_DN<21>")
	)
	(segment
		(start 412.320232 -275.276056)
		(end 412.42361 -275.379434)
		(width 0.1143)
		(layer "In5.Cu")
		(net "P5E_PEX3_STN1_RX_DN<21>")
	)
	(segment
		(start 399.920206 -108.886498)
		(end 399.920206 -108.887006)
		(width 0.1651)
		(layer "In5.Cu")
		(net "P5E_PEX3_STN1_RX_DN<21>")
	)
	(segment
		(start 381.675132 -150.684484)
		(end 382.159764 -158.511494)
		(width 0.1651)
		(layer "In5.Cu")
		(net "P5E_PEX3_STN1_RX_DN<21>")
	)
	(segment
		(start 386.916168 -127.365506)
		(end 386.720842 -127.82042)
		(width 0.1651)
		(layer "In5.Cu")
		(net "P5E_PEX3_STN1_RX_DN<21>")
	)
	(segment
		(start 390.971786 -113.984532)
		(end 390.311132 -115.159028)
		(width 0.1651)
		(layer "In5.Cu")
		(net "P5E_PEX3_STN1_RX_DN<21>")
	)
	(segment
		(start 412.320232 -271.644872)
		(end 412.320232 -275.276056)
		(width 0.1143)
		(layer "In5.Cu")
		(net "P5E_PEX3_STN1_RX_DN<21>")
	)
	(segment
		(start 412.365952 -271.599152)
		(end 412.320232 -271.644872)
		(width 0.1143)
		(layer "In5.Cu")
		(net "P5E_PEX3_STN1_RX_DN<21>")
	)
	(segment
		(start 386.780786 -127.970534)
		(end 386.58546 -128.425956)
		(width 0.1651)
		(layer "In5.Cu")
		(net "P5E_PEX3_STN1_RX_DN<21>")
	)
	(segment
		(start 395.52372 -111.512858)
		(end 395.367764 -111.469932)
		(width 0.1651)
		(layer "In5.Cu")
		(net "P5E_PEX3_STN1_RX_DN<21>")
	)
	(segment
		(start 390.311132 -115.159028)
		(end 388.20217 -124.370846)
		(width 0.1651)
		(layer "In5.Cu")
		(net "P5E_PEX3_STN1_RX_DN<21>")
	)
	(segment
		(start 397.702532 -110.145322)
		(end 397.058134 -110.510828)
		(width 0.1651)
		(layer "In5.Cu")
		(net "P5E_PEX3_STN1_RX_DN<21>")
	)
	(segment
		(start 386.10413 -129.54635)
		(end 385.953762 -129.606294)
		(width 0.1651)
		(layer "In5.Cu")
		(net "P5E_PEX3_STN1_RX_DN<21>")
	)
	(segment
		(start 412.699708 -275.265134)
		(end 412.699708 -274.999704)
		(width 0.1143)
		(layer "In5.Cu")
		(net "P5E_PEX3_STN1_RX_DN<21>")
	)
	(segment
		(start 397.058134 -110.510828)
		(end 397.015208 -110.66653)
		(width 0.1651)
		(layer "In5.Cu")
		(net "P5E_PEX3_STN1_RX_DN<21>")
	)
	(segment
		(start 399.920206 -108.887006)
		(end 399.392902 -109.186218)
		(width 0.1651)
		(layer "In5.Cu")
		(net "P5E_PEX3_STN1_RX_DN<21>")
	)
	(segment
		(start 400.25193 -108.885482)
		(end 399.91919 -108.885482)
		(width 0.1651)
		(layer "In5.Cu")
		(net "P5E_PEX3_STN1_RX_DN<21>")
	)
	(segment
		(start 412.365952 -271.570704)
		(end 412.365952 -271.599152)
		(width 0.1143)
		(layer "In5.Cu")
		(net "P5E_PEX3_STN1_RX_DN<21>")
	)
	(segment
		(start 386.239766 -128.940814)
		(end 386.29971 -129.090928)
		(width 0.1651)
		(layer "In5.Cu")
		(net "P5E_PEX3_STN1_RX_DN<21>")
	)
	(segment
		(start 398.918684 -109.586522)
		(end 398.762982 -109.543596)
		(width 0.1651)
		(layer "In5.Cu")
		(net "P5E_PEX3_STN1_RX_DN<21>")
	)
	(segment
		(start 386.720842 -127.82042)
		(end 386.780786 -127.970534)
		(width 0.1651)
		(layer "In5.Cu")
		(net "P5E_PEX3_STN1_RX_DN<21>")
	)
	(segment
		(start 386.58546 -128.425956)
		(end 386.435092 -128.4859)
		(width 0.1651)
		(layer "In5.Cu")
		(net "P5E_PEX3_STN1_RX_DN<21>")
	)
	(segment
		(start 385.81838 -130.211322)
		(end 385.623054 -130.666744)
		(width 0.1651)
		(layer "In5.Cu")
		(net "P5E_PEX3_STN1_RX_DN<21>")
	)
	(segment
		(start 412.365952 -269.144496)
		(end 412.365952 -271.570704)
		(width 0.1651)
		(layer "In5.Cu")
		(net "P5E_PEX3_STN1_RX_DN<21>")
	)
	(segment
		(start 384.852926 -132.169662)
		(end 384.852926 -136.432798)
		(width 0.1651)
		(layer "In5.Cu")
		(net "P5E_PEX3_STN1_RX_DN<21>")
	)
	(segment
		(start 399.392902 -109.186218)
		(end 399.349976 -109.34192)
		(width 0.1651)
		(layer "In5.Cu")
		(net "P5E_PEX3_STN1_RX_DN<21>")
	)
	(segment
		(start 385.953762 -129.606294)
		(end 385.758436 -130.061208)
		(width 0.1651)
		(layer "In5.Cu")
		(net "P5E_PEX3_STN1_RX_DN<21>")
	)
	(segment
		(start 398.332198 -109.787944)
		(end 398.289272 -109.943646)
		(width 0.1651)
		(layer "In5.Cu")
		(net "P5E_PEX3_STN1_RX_DN<21>")
	)
	(segment
		(start 371.483128 -350.685862)
		(end 371.483128 -351.31629)
		(width 0.13462)
		(layer "F.Cu")
		(net "P5E_PEX3_STN6_TX_C_DP<103>")
	)
	(segment
		(start 371.16258 -350.365314)
		(end 371.483128 -350.685862)
		(width 0.13462)
		(layer "F.Cu")
		(net "P5E_PEX3_STN6_TX_C_DP<103>")
	)
	(segment
		(start 371.483128 -351.31629)
		(end 371.18798 -351.611438)
		(width 0.13462)
		(layer "F.Cu")
		(net "P5E_PEX3_STN6_TX_C_DP<103>")
	)
	(segment
		(start 373.561864 -363.290612)
		(end 373.617236 -363.13872)
		(width 0.1651)
		(layer "In7.Cu")
		(net "P5E_PEX3_STN6_TX_C_DP<103>")
	)
	(segment
		(start 374.43791 -364.900718)
		(end 374.286018 -364.845346)
		(width 0.1651)
		(layer "In7.Cu")
		(net "P5E_PEX3_STN6_TX_C_DP<103>")
	)
	(segment
		(start 371.47881 -358.546146)
		(end 371.47881 -351.902268)
		(width 0.1651)
		(layer "In7.Cu")
		(net "P5E_PEX3_STN6_TX_C_DP<103>")
	)
	(segment
		(start 375.489978 -382.18999)
		(end 375.489978 -382.57226)
		(width 0.1651)
		(layer "In7.Cu")
		(net "P5E_PEX3_STN6_TX_C_DP<103>")
	)
	(segment
		(start 373.923052 -363.79531)
		(end 373.77116 -363.739938)
		(width 0.1651)
		(layer "In7.Cu")
		(net "P5E_PEX3_STN6_TX_C_DP<103>")
	)
	(segment
		(start 375.616978 -382.69926)
		(end 376.047254 -382.69926)
		(width 0.1651)
		(layer "In7.Cu")
		(net "P5E_PEX3_STN6_TX_C_DP<103>")
	)
	(segment
		(start 373.77116 -363.739938)
		(end 373.561864 -363.290612)
		(width 0.1651)
		(layer "In7.Cu")
		(net "P5E_PEX3_STN6_TX_C_DP<103>")
	)
	(segment
		(start 376.047254 -382.69926)
		(end 376.33402 -382.412494)
		(width 0.1651)
		(layer "In7.Cu")
		(net "P5E_PEX3_STN6_TX_C_DP<103>")
	)
	(segment
		(start 375.489978 -382.57226)
		(end 375.616978 -382.69926)
		(width 0.1651)
		(layer "In7.Cu")
		(net "P5E_PEX3_STN6_TX_C_DP<103>")
	)
	(segment
		(start 373.617236 -363.13872)
		(end 371.47881 -358.546146)
		(width 0.1651)
		(layer "In7.Cu")
		(net "P5E_PEX3_STN6_TX_C_DP<103>")
	)
	(segment
		(start 376.33402 -382.412494)
		(end 376.33402 -368.972846)
		(width 0.1651)
		(layer "In7.Cu")
		(net "P5E_PEX3_STN6_TX_C_DP<103>")
	)
	(segment
		(start 374.286018 -364.845346)
		(end 374.076722 -364.39602)
		(width 0.1651)
		(layer "In7.Cu")
		(net "P5E_PEX3_STN6_TX_C_DP<103>")
	)
	(segment
		(start 371.47881 -351.902268)
		(end 371.18798 -351.611438)
		(width 0.1651)
		(layer "In7.Cu")
		(net "P5E_PEX3_STN6_TX_C_DP<103>")
	)
	(segment
		(start 374.076722 -364.39602)
		(end 374.132094 -364.244128)
		(width 0.1651)
		(layer "In7.Cu")
		(net "P5E_PEX3_STN6_TX_C_DP<103>")
	)
	(segment
		(start 374.132094 -364.244128)
		(end 373.923052 -363.79531)
		(width 0.1651)
		(layer "In7.Cu")
		(net "P5E_PEX3_STN6_TX_C_DP<103>")
	)
	(segment
		(start 376.33402 -368.972846)
		(end 374.43791 -364.900718)
		(width 0.1651)
		(layer "In7.Cu")
		(net "P5E_PEX3_STN6_TX_C_DP<103>")
	)
	(via
		(at 62.66053 -159.095186)
		(size 0.6604)
		(drill 0.3302)
		(layers "F.Cu" "B.Cu")
		(net "HP_NIC0_PWRGD_R")
	)
	(segment
		(start 60.312046 -158.379922)
		(end 62.479428 -158.379922)
		(width 0.13208)
		(layer "B.Cu")
		(net "HP_NIC0_PWRGD_R")
	)
	(segment
		(start 62.66053 -158.561024)
		(end 62.66053 -159.095186)
		(width 0.13208)
		(layer "B.Cu")
		(net "HP_NIC0_PWRGD_R")
	)
	(segment
		(start 60.511436 -160.81375)
		(end 62.657736 -160.81375)
		(width 0.13208)
		(layer "B.Cu")
		(net "HP_NIC0_PWRGD_R")
	)
	(segment
		(start 62.479428 -158.379922)
		(end 62.66053 -158.561024)
		(width 0.13208)
		(layer "B.Cu")
		(net "HP_NIC0_PWRGD_R")
	)
	(segment
		(start 62.657736 -160.81375)
		(end 62.66053 -160.810956)
		(width 0.13208)
		(layer "B.Cu")
		(net "HP_NIC0_PWRGD_R")
	)
	(segment
		(start 62.66053 -159.095186)
		(end 62.66053 -160.810956)
		(width 0.13208)
		(layer "B.Cu")
		(net "HP_NIC0_PWRGD_R")
	)
	(segment
		(start 35.36061 -28.55468)
		(end 35.0647 -28.25877)
		(width 0.13462)
		(layer "F.Cu")
		(net "P5E_PEX0_STN2_RX_DN<40>")
	)
	(segment
		(start 36.019486 -28.55468)
		(end 35.36061 -28.55468)
		(width 0.13462)
		(layer "F.Cu")
		(net "P5E_PEX0_STN2_RX_DN<40>")
	)
	(segment
		(start 36.6649 -28.390088)
		(end 36.184078 -28.390088)
		(width 0.13462)
		(layer "F.Cu")
		(net "P5E_PEX0_STN2_RX_DN<40>")
	)
	(segment
		(start 36.184078 -28.390088)
		(end 36.019486 -28.55468)
		(width 0.13462)
		(layer "F.Cu")
		(net "P5E_PEX0_STN2_RX_DN<40>")
	)
	(segment
		(start 35.0647 -28.25877)
		(end 35.35553 -28.5496)
		(width 0.1651)
		(layer "In7.Cu")
		(net "P5E_PEX0_STN2_RX_DN<40>")
	)
	(segment
		(start 39.169848 -48.829722)
		(end 39.070534 -55.191914)
		(width 0.1651)
		(layer "In7.Cu")
		(net "P5E_PEX0_STN2_RX_DN<40>")
	)
	(segment
		(start 50.76571 -268.123162)
		(end 50.76571 -271.392904)
		(width 0.1651)
		(layer "In7.Cu")
		(net "P5E_PEX0_STN2_RX_DN<40>")
	)
	(segment
		(start 42.612056 -104.30002)
		(end 43.074844 -119.564404)
		(width 0.1651)
		(layer "In7.Cu")
		(net "P5E_PEX0_STN2_RX_DN<40>")
	)
	(segment
		(start 41.331388 -37.688012)
		(end 41.316656 -38.576758)
		(width 0.1651)
		(layer "In7.Cu")
		(net "P5E_PEX0_STN2_RX_DN<40>")
	)
	(segment
		(start 41.316656 -38.576758)
		(end 39.169848 -48.829722)
		(width 0.1651)
		(layer "In7.Cu")
		(net "P5E_PEX0_STN2_RX_DN<40>")
	)
	(segment
		(start 39.070534 -55.191914)
		(end 39.468298 -65.131442)
		(width 0.1651)
		(layer "In7.Cu")
		(net "P5E_PEX0_STN2_RX_DN<40>")
	)
	(segment
		(start 39.468298 -65.131442)
		(end 42.612056 -104.30002)
		(width 0.1651)
		(layer "In7.Cu")
		(net "P5E_PEX0_STN2_RX_DN<40>")
	)
	(segment
		(start 35.80384 -28.5496)
		(end 38.702742 -31.448502)
		(width 0.1651)
		(layer "In7.Cu")
		(net "P5E_PEX0_STN2_RX_DN<40>")
	)
	(segment
		(start 50.71999 -275.275802)
		(end 50.823876 -275.379688)
		(width 0.1143)
		(layer "In7.Cu")
		(net "P5E_PEX0_STN2_RX_DN<40>")
	)
	(segment
		(start 50.76571 -271.421352)
		(end 50.71999 -271.467072)
		(width 0.1143)
		(layer "In7.Cu")
		(net "P5E_PEX0_STN2_RX_DN<40>")
	)
	(segment
		(start 50.823876 -275.379688)
		(end 50.985674 -275.379688)
		(width 0.1143)
		(layer "In7.Cu")
		(net "P5E_PEX0_STN2_RX_DN<40>")
	)
	(segment
		(start 51.099974 -275.265388)
		(end 51.099974 -274.999958)
		(width 0.1143)
		(layer "In7.Cu")
		(net "P5E_PEX0_STN2_RX_DN<40>")
	)
	(segment
		(start 38.702742 -31.448502)
		(end 41.331388 -37.688012)
		(width 0.1651)
		(layer "In7.Cu")
		(net "P5E_PEX0_STN2_RX_DN<40>")
	)
	(segment
		(start 50.985674 -275.379688)
		(end 51.099974 -275.265388)
		(width 0.1143)
		(layer "In7.Cu")
		(net "P5E_PEX0_STN2_RX_DN<40>")
	)
	(segment
		(start 35.35553 -28.5496)
		(end 35.80384 -28.5496)
		(width 0.1651)
		(layer "In7.Cu")
		(net "P5E_PEX0_STN2_RX_DN<40>")
	)
	(segment
		(start 50.76571 -271.392904)
		(end 50.76571 -271.421352)
		(width 0.1143)
		(layer "In7.Cu")
		(net "P5E_PEX0_STN2_RX_DN<40>")
	)
	(segment
		(start 50.4444 -264.860786)
		(end 50.76571 -268.123162)
		(width 0.1651)
		(layer "In7.Cu")
		(net "P5E_PEX0_STN2_RX_DN<40>")
	)
	(segment
		(start 50.71999 -271.467072)
		(end 50.71999 -275.275802)
		(width 0.1143)
		(layer "In7.Cu")
		(net "P5E_PEX0_STN2_RX_DN<40>")
	)
	(segment
		(start 43.074844 -119.564404)
		(end 42.769028 -147.93849)
		(width 0.1651)
		(layer "In7.Cu")
		(net "P5E_PEX0_STN2_RX_DN<40>")
	)
	(segment
		(start 42.769028 -147.93849)
		(end 50.730658 -250.008136)
		(width 0.1651)
		(layer "In7.Cu")
		(net "P5E_PEX0_STN2_RX_DN<40>")
	)
	(segment
		(start 50.730658 -250.008136)
		(end 50.4444 -264.860786)
		(width 0.1651)
		(layer "In7.Cu")
		(net "P5E_PEX0_STN2_RX_DN<40>")
	)
	(segment
		(start 204.285596 -32.589978)
		(end 204.118718 -32.4231)
		(width 0.13462)
		(layer "F.Cu")
		(net "P5E_PEX1_STN2_RX_DP<34>")
	)
	(segment
		(start 204.764894 -32.589978)
		(end 204.285596 -32.589978)
		(width 0.13462)
		(layer "F.Cu")
		(net "P5E_PEX1_STN2_RX_DP<34>")
	)
	(segment
		(start 203.463906 -32.4231)
		(end 203.164694 -32.722312)
		(width 0.13462)
		(layer "F.Cu")
		(net "P5E_PEX1_STN2_RX_DP<34>")
	)
	(segment
		(start 204.118718 -32.4231)
		(end 203.463906 -32.4231)
		(width 0.13462)
		(layer "F.Cu")
		(net "P5E_PEX1_STN2_RX_DP<34>")
	)
	(segment
		(start 204.258418 -32.905954)
		(end 204.245972 -33.724088)
		(width 0.1651)
		(layer "In7.Cu")
		(net "P5E_PEX1_STN2_RX_DP<34>")
	)
	(segment
		(start 172.612812 -266.82319)
		(end 172.283882 -270.641064)
		(width 0.1651)
		(layer "In7.Cu")
		(net "P5E_PEX1_STN2_RX_DP<34>")
	)
	(segment
		(start 204.245972 -33.724088)
		(end 204.155294 -33.811464)
		(width 0.1651)
		(layer "In7.Cu")
		(net "P5E_PEX1_STN2_RX_DP<34>")
	)
	(segment
		(start 172.283882 -271.392904)
		(end 172.283882 -271.421352)
		(width 0.1143)
		(layer "In7.Cu")
		(net "P5E_PEX1_STN2_RX_DP<34>")
	)
	(segment
		(start 172.785786 -275.570188)
		(end 172.900086 -275.684488)
		(width 0.1143)
		(layer "In7.Cu")
		(net "P5E_PEX1_STN2_RX_DP<34>")
	)
	(segment
		(start 172.544994 -275.570188)
		(end 172.785786 -275.570188)
		(width 0.1143)
		(layer "In7.Cu")
		(net "P5E_PEX1_STN2_RX_DP<34>")
	)
	(segment
		(start 203.7842 -32.431482)
		(end 204.258418 -32.905954)
		(width 0.1651)
		(layer "In7.Cu")
		(net "P5E_PEX1_STN2_RX_DP<34>")
	)
	(segment
		(start 203.700634 -37.779198)
		(end 203.731114 -39.714678)
		(width 0.1651)
		(layer "In7.Cu")
		(net "P5E_PEX1_STN2_RX_DP<34>")
	)
	(segment
		(start 192.172844 -154.509978)
		(end 172.612812 -266.82319)
		(width 0.1651)
		(layer "In7.Cu")
		(net "P5E_PEX1_STN2_RX_DP<34>")
	)
	(segment
		(start 172.329602 -271.467072)
		(end 172.329602 -275.354796)
		(width 0.1143)
		(layer "In7.Cu")
		(net "P5E_PEX1_STN2_RX_DP<34>")
	)
	(segment
		(start 193.560192 -143.730472)
		(end 192.172844 -154.509978)
		(width 0.1651)
		(layer "In7.Cu")
		(net "P5E_PEX1_STN2_RX_DP<34>")
	)
	(segment
		(start 172.329602 -275.354796)
		(end 172.544994 -275.570188)
		(width 0.1143)
		(layer "In7.Cu")
		(net "P5E_PEX1_STN2_RX_DP<34>")
	)
	(segment
		(start 172.283882 -271.421352)
		(end 172.329602 -271.467072)
		(width 0.1143)
		(layer "In7.Cu")
		(net "P5E_PEX1_STN2_RX_DP<34>")
	)
	(segment
		(start 203.547726 -32.431482)
		(end 203.7842 -32.431482)
		(width 0.1651)
		(layer "In7.Cu")
		(net "P5E_PEX1_STN2_RX_DP<34>")
	)
	(segment
		(start 172.900086 -275.684488)
		(end 172.900086 -275.949918)
		(width 0.1143)
		(layer "In7.Cu")
		(net "P5E_PEX1_STN2_RX_DP<34>")
	)
	(segment
		(start 193.875152 -116.573554)
		(end 193.560192 -143.730472)
		(width 0.1651)
		(layer "In7.Cu")
		(net "P5E_PEX1_STN2_RX_DP<34>")
	)
	(segment
		(start 203.731368 -39.731442)
		(end 205.044802 -49.45253)
		(width 0.1651)
		(layer "In7.Cu")
		(net "P5E_PEX1_STN2_RX_DP<34>")
	)
	(segment
		(start 203.863448 -36.280852)
		(end 203.77277 -36.768024)
		(width 0.1651)
		(layer "In7.Cu")
		(net "P5E_PEX1_STN2_RX_DP<34>")
	)
	(segment
		(start 172.283882 -270.641064)
		(end 172.283882 -271.392904)
		(width 0.1651)
		(layer "In7.Cu")
		(net "P5E_PEX1_STN2_RX_DP<34>")
	)
	(segment
		(start 204.861414 -61.197744)
		(end 193.875152 -116.573554)
		(width 0.1651)
		(layer "In7.Cu")
		(net "P5E_PEX1_STN2_RX_DP<34>")
	)
	(segment
		(start 204.147674 -34.307018)
		(end 204.235304 -34.397188)
		(width 0.1651)
		(layer "In7.Cu")
		(net "P5E_PEX1_STN2_RX_DP<34>")
	)
	(segment
		(start 203.390246 -32.49676)
		(end 203.547726 -32.431482)
		(width 0.1651)
		(layer "In7.Cu")
		(net "P5E_PEX1_STN2_RX_DP<34>")
	)
	(segment
		(start 204.226668 -34.95675)
		(end 203.997052 -36.189412)
		(width 0.1651)
		(layer "In7.Cu")
		(net "P5E_PEX1_STN2_RX_DP<34>")
	)
	(segment
		(start 203.86421 -36.901374)
		(end 203.700634 -37.779198)
		(width 0.1651)
		(layer "In7.Cu")
		(net "P5E_PEX1_STN2_RX_DP<34>")
	)
	(segment
		(start 203.997052 -36.189412)
		(end 203.863448 -36.280852)
		(width 0.1651)
		(layer "In7.Cu")
		(net "P5E_PEX1_STN2_RX_DP<34>")
	)
	(segment
		(start 203.77277 -36.768024)
		(end 203.86421 -36.901374)
		(width 0.1651)
		(layer "In7.Cu")
		(net "P5E_PEX1_STN2_RX_DP<34>")
	)
	(segment
		(start 205.044802 -49.45253)
		(end 204.861414 -61.197744)
		(width 0.1651)
		(layer "In7.Cu")
		(net "P5E_PEX1_STN2_RX_DP<34>")
	)
	(segment
		(start 204.235304 -34.397188)
		(end 204.226668 -34.95675)
		(width 0.1651)
		(layer "In7.Cu")
		(net "P5E_PEX1_STN2_RX_DP<34>")
	)
	(segment
		(start 203.73086 -39.714678)
		(end 203.731368 -39.731442)
		(width 0.1651)
		(layer "In7.Cu")
		(net "P5E_PEX1_STN2_RX_DP<34>")
	)
	(segment
		(start 204.155294 -33.811464)
		(end 204.147674 -34.307018)
		(width 0.1651)
		(layer "In7.Cu")
		(net "P5E_PEX1_STN2_RX_DP<34>")
	)
	(segment
		(start 203.731114 -39.714678)
		(end 203.73086 -39.714678)
		(width 0.1651)
		(layer "In7.Cu")
		(net "P5E_PEX1_STN2_RX_DP<34>")
	)
	(segment
		(start 203.164694 -32.722312)
		(end 203.390246 -32.49676)
		(width 0.1651)
		(layer "In7.Cu")
		(net "P5E_PEX1_STN2_RX_DP<34>")
	)
	(segment
		(start 305.95697 -150.554944)
		(end 305.457606 -150.554944)
		(width 0.13462)
		(layer "F.Cu")
		(net "P5E_PEX2_STN0_TX_C_DN<12>")
	)
	(segment
		(start 311.64149 -150.3934)
		(end 306.118514 -150.3934)
		(width 0.13462)
		(layer "F.Cu")
		(net "P5E_PEX2_STN0_TX_C_DN<12>")
	)
	(segment
		(start 311.95264 -150.70455)
		(end 311.64149 -150.3934)
		(width 0.13462)
		(layer "F.Cu")
		(net "P5E_PEX2_STN0_TX_C_DN<12>")
	)
	(segment
		(start 306.118514 -150.3934)
		(end 305.95697 -150.554944)
		(width 0.13462)
		(layer "F.Cu")
		(net "P5E_PEX2_STN0_TX_C_DN<12>")
	)
	(segment
		(start 402.39696 -131.29641)
		(end 402.10105 -131.0005)
		(width 0.13462)
		(layer "F.Cu")
		(net "P5E_PEX3_STN1_RX_DN<28>")
	)
	(segment
		(start 399.584672 -131.0005)
		(end 399.42008 -131.165092)
		(width 0.13462)
		(layer "F.Cu")
		(net "P5E_PEX3_STN1_RX_DN<28>")
	)
	(segment
		(start 402.10105 -131.0005)
		(end 399.584672 -131.0005)
		(width 0.13462)
		(layer "F.Cu")
		(net "P5E_PEX3_STN1_RX_DN<28>")
	)
	(segment
		(start 399.42008 -131.165092)
		(end 398.94256 -131.165092)
		(width 0.13462)
		(layer "F.Cu")
		(net "P5E_PEX3_STN1_RX_DN<28>")
	)
	(segment
		(start 392.272012 -143.733266)
		(end 391.1854 -144.82064)
		(width 0.1651)
		(layer "In5.Cu")
		(net "P5E_PEX3_STN1_RX_DN<28>")
	)
	(segment
		(start 392.842242 -143.48968)
		(end 392.683746 -143.458184)
		(width 0.1651)
		(layer "In5.Cu")
		(net "P5E_PEX3_STN1_RX_DN<28>")
	)
	(segment
		(start 419.073584 -273.479514)
		(end 419.235382 -273.479514)
		(width 0.1143)
		(layer "In5.Cu")
		(net "P5E_PEX3_STN1_RX_DN<28>")
	)
	(segment
		(start 396.957296 -134.907528)
		(end 397.019272 -135.05688)
		(width 0.1651)
		(layer "In5.Cu")
		(net "P5E_PEX3_STN1_RX_DN<28>")
	)
	(segment
		(start 397.423894 -133.781038)
		(end 397.48587 -133.93039)
		(width 0.1651)
		(layer "In5.Cu")
		(net "P5E_PEX3_STN1_RX_DN<28>")
	)
	(segment
		(start 397.14678 -134.450074)
		(end 396.957296 -134.907528)
		(width 0.1651)
		(layer "In5.Cu")
		(net "P5E_PEX3_STN1_RX_DN<28>")
	)
	(segment
		(start 419.235382 -273.479514)
		(end 419.349682 -273.365214)
		(width 0.1143)
		(layer "In5.Cu")
		(net "P5E_PEX3_STN1_RX_DN<28>")
	)
	(segment
		(start 391.1854 -144.82064)
		(end 390.89076 -145.218658)
		(width 0.1651)
		(layer "In5.Cu")
		(net "P5E_PEX3_STN1_RX_DN<28>")
	)
	(segment
		(start 390.459722 -145.800572)
		(end 389.512302 -147.079716)
		(width 0.1651)
		(layer "In5.Cu")
		(net "P5E_PEX3_STN1_RX_DN<28>")
	)
	(segment
		(start 398.903444 -131.932172)
		(end 398.742662 -131.94792)
		(width 0.1651)
		(layer "In5.Cu")
		(net "P5E_PEX3_STN1_RX_DN<28>")
	)
	(segment
		(start 389.344154 -147.684744)
		(end 389.938514 -156.892244)
		(width 0.1651)
		(layer "In5.Cu")
		(net "P5E_PEX3_STN1_RX_DN<28>")
	)
	(segment
		(start 393.25423 -143.214344)
		(end 392.842242 -143.48968)
		(width 0.1651)
		(layer "In5.Cu")
		(net "P5E_PEX3_STN1_RX_DN<28>")
	)
	(segment
		(start 399.202148 -131.388358)
		(end 399.217896 -131.54914)
		(width 0.1651)
		(layer "In5.Cu")
		(net "P5E_PEX3_STN1_RX_DN<28>")
	)
	(segment
		(start 398.428464 -132.330698)
		(end 398.444466 -132.49148)
		(width 0.1651)
		(layer "In5.Cu")
		(net "P5E_PEX3_STN1_RX_DN<28>")
	)
	(segment
		(start 396.829788 -135.514842)
		(end 396.680182 -135.576564)
		(width 0.1651)
		(layer "In5.Cu")
		(net "P5E_PEX3_STN1_RX_DN<28>")
	)
	(segment
		(start 402.10613 -131.00558)
		(end 401.577048 -131.00558)
		(width 0.1651)
		(layer "In5.Cu")
		(net "P5E_PEX3_STN1_RX_DN<28>")
	)
	(segment
		(start 397.968978 -132.890514)
		(end 397.613378 -133.323584)
		(width 0.1651)
		(layer "In5.Cu")
		(net "P5E_PEX3_STN1_RX_DN<28>")
	)
	(segment
		(start 418.970206 -271.600168)
		(end 418.970206 -273.376136)
		(width 0.1143)
		(layer "In5.Cu")
		(net "P5E_PEX3_STN1_RX_DN<28>")
	)
	(segment
		(start 397.48587 -133.93039)
		(end 397.296386 -134.388352)
		(width 0.1651)
		(layer "In5.Cu")
		(net "P5E_PEX3_STN1_RX_DN<28>")
	)
	(segment
		(start 392.683746 -143.458184)
		(end 392.272012 -143.733266)
		(width 0.1651)
		(layer "In5.Cu")
		(net "P5E_PEX3_STN1_RX_DN<28>")
	)
	(segment
		(start 398.742662 -131.94792)
		(end 398.428464 -132.330698)
		(width 0.1651)
		(layer "In5.Cu")
		(net "P5E_PEX3_STN1_RX_DN<28>")
	)
	(segment
		(start 399.217896 -131.54914)
		(end 398.903444 -131.932172)
		(width 0.1651)
		(layer "In5.Cu")
		(net "P5E_PEX3_STN1_RX_DN<28>")
	)
	(segment
		(start 419.015926 -267.605256)
		(end 419.015926 -271.526)
		(width 0.1651)
		(layer "In5.Cu")
		(net "P5E_PEX3_STN1_RX_DN<28>")
	)
	(segment
		(start 396.075662 -140.883132)
		(end 395.145514 -141.813026)
		(width 0.1651)
		(layer "In5.Cu")
		(net "P5E_PEX3_STN1_RX_DN<28>")
	)
	(segment
		(start 398.444466 -132.49148)
		(end 398.12976 -132.874512)
		(width 0.1651)
		(layer "In5.Cu")
		(net "P5E_PEX3_STN1_RX_DN<28>")
	)
	(segment
		(start 418.970206 -273.376136)
		(end 419.073584 -273.479514)
		(width 0.1143)
		(layer "In5.Cu")
		(net "P5E_PEX3_STN1_RX_DN<28>")
	)
	(segment
		(start 419.015926 -271.526)
		(end 419.015926 -271.554448)
		(width 0.1143)
		(layer "In5.Cu")
		(net "P5E_PEX3_STN1_RX_DN<28>")
	)
	(segment
		(start 394.29944 -142.37843)
		(end 394.267944 -142.536926)
		(width 0.1651)
		(layer "In5.Cu")
		(net "P5E_PEX3_STN1_RX_DN<28>")
	)
	(segment
		(start 389.512302 -147.079716)
		(end 389.344154 -147.684744)
		(width 0.1651)
		(layer "In5.Cu")
		(net "P5E_PEX3_STN1_RX_DN<28>")
	)
	(segment
		(start 419.349682 -273.365214)
		(end 419.349682 -273.099784)
		(width 0.1143)
		(layer "In5.Cu")
		(net "P5E_PEX3_STN1_RX_DN<28>")
	)
	(segment
		(start 393.855956 -142.812262)
		(end 393.69746 -142.780766)
		(width 0.1651)
		(layer "In5.Cu")
		(net "P5E_PEX3_STN1_RX_DN<28>")
	)
	(segment
		(start 389.938514 -156.892244)
		(end 390.691878 -161.14268)
		(width 0.1651)
		(layer "In5.Cu")
		(net "P5E_PEX3_STN1_RX_DN<28>")
	)
	(segment
		(start 399.516346 -131.00558)
		(end 399.202148 -131.388358)
		(width 0.1651)
		(layer "In5.Cu")
		(net "P5E_PEX3_STN1_RX_DN<28>")
	)
	(segment
		(start 393.285726 -143.055848)
		(end 393.25423 -143.214344)
		(width 0.1651)
		(layer "In5.Cu")
		(net "P5E_PEX3_STN1_RX_DN<28>")
	)
	(segment
		(start 394.267944 -142.536926)
		(end 393.855956 -142.812262)
		(width 0.1651)
		(layer "In5.Cu")
		(net "P5E_PEX3_STN1_RX_DN<28>")
	)
	(segment
		(start 419.015926 -271.554448)
		(end 418.970206 -271.600168)
		(width 0.1143)
		(layer "In5.Cu")
		(net "P5E_PEX3_STN1_RX_DN<28>")
	)
	(segment
		(start 396.680182 -135.576564)
		(end 396.296642 -136.502648)
		(width 0.1651)
		(layer "In5.Cu")
		(net "P5E_PEX3_STN1_RX_DN<28>")
	)
	(segment
		(start 390.619488 -145.776696)
		(end 390.459722 -145.800572)
		(width 0.1651)
		(layer "In5.Cu")
		(net "P5E_PEX3_STN1_RX_DN<28>")
	)
	(segment
		(start 396.296642 -140.348462)
		(end 396.075662 -140.883132)
		(width 0.1651)
		(layer "In5.Cu")
		(net "P5E_PEX3_STN1_RX_DN<28>")
	)
	(segment
		(start 397.019272 -135.05688)
		(end 396.829788 -135.514842)
		(width 0.1651)
		(layer "In5.Cu")
		(net "P5E_PEX3_STN1_RX_DN<28>")
	)
	(segment
		(start 390.89076 -145.218658)
		(end 390.914636 -145.378424)
		(width 0.1651)
		(layer "In5.Cu")
		(net "P5E_PEX3_STN1_RX_DN<28>")
	)
	(segment
		(start 398.12976 -132.874512)
		(end 397.968978 -132.890514)
		(width 0.1651)
		(layer "In5.Cu")
		(net "P5E_PEX3_STN1_RX_DN<28>")
	)
	(segment
		(start 390.914636 -145.378424)
		(end 390.619488 -145.776696)
		(width 0.1651)
		(layer "In5.Cu")
		(net "P5E_PEX3_STN1_RX_DN<28>")
	)
	(segment
		(start 396.296642 -136.502648)
		(end 396.296642 -140.348462)
		(width 0.1651)
		(layer "In5.Cu")
		(net "P5E_PEX3_STN1_RX_DN<28>")
	)
	(segment
		(start 402.39696 -131.29641)
		(end 402.10613 -131.00558)
		(width 0.1651)
		(layer "In5.Cu")
		(net "P5E_PEX3_STN1_RX_DN<28>")
	)
	(segment
		(start 395.145514 -141.813026)
		(end 394.29944 -142.37843)
		(width 0.1651)
		(layer "In5.Cu")
		(net "P5E_PEX3_STN1_RX_DN<28>")
	)
	(segment
		(start 397.296386 -134.388352)
		(end 397.14678 -134.450074)
		(width 0.1651)
		(layer "In5.Cu")
		(net "P5E_PEX3_STN1_RX_DN<28>")
	)
	(segment
		(start 401.577048 -131.00558)
		(end 401.462748 -131.11988)
		(width 0.1651)
		(layer "In5.Cu")
		(net "P5E_PEX3_STN1_RX_DN<28>")
	)
	(segment
		(start 390.691878 -161.14268)
		(end 419.015926 -267.605256)
		(width 0.1651)
		(layer "In5.Cu")
		(net "P5E_PEX3_STN1_RX_DN<28>")
	)
	(segment
		(start 397.613378 -133.323584)
		(end 397.423894 -133.781038)
		(width 0.1651)
		(layer "In5.Cu")
		(net "P5E_PEX3_STN1_RX_DN<28>")
	)
	(segment
		(start 401.462748 -131.11988)
		(end 400.967448 -131.11988)
		(width 0.1651)
		(layer "In5.Cu")
		(net "P5E_PEX3_STN1_RX_DN<28>")
	)
	(segment
		(start 400.853148 -131.00558)
		(end 399.516346 -131.00558)
		(width 0.1651)
		(layer "In5.Cu")
		(net "P5E_PEX3_STN1_RX_DN<28>")
	)
	(segment
		(start 400.967448 -131.11988)
		(end 400.853148 -131.00558)
		(width 0.1651)
		(layer "In5.Cu")
		(net "P5E_PEX3_STN1_RX_DN<28>")
	)
	(segment
		(start 393.69746 -142.780766)
		(end 393.285726 -143.055848)
		(width 0.1651)
		(layer "In5.Cu")
		(net "P5E_PEX3_STN1_RX_DN<28>")
	)
	(segment
		(start 384.193288 -356.831138)
		(end 384.193288 -357.463598)
		(width 0.13462)
		(layer "F.Cu")
		(net "P5E_PEX3_STN6_TX_C_DN<105>")
	)
	(segment
		(start 384.193288 -357.463598)
		(end 384.48742 -357.75773)
		(width 0.13462)
		(layer "F.Cu")
		(net "P5E_PEX3_STN6_TX_C_DN<105>")
	)
	(segment
		(start 384.51282 -356.511606)
		(end 384.193288 -356.831138)
		(width 0.13462)
		(layer "F.Cu")
		(net "P5E_PEX3_STN6_TX_C_DN<105>")
	)
	(segment
		(start 388.68985 -409.108148)
		(end 388.81685 -408.981148)
		(width 0.1651)
		(layer "In13.Cu")
		(net "P5E_PEX3_STN6_TX_C_DN<105>")
	)
	(segment
		(start 387.796278 -392.7856)
		(end 386.221478 -391.8204)
		(width 0.1651)
		(layer "In13.Cu")
		(net "P5E_PEX3_STN6_TX_C_DN<105>")
	)
	(segment
		(start 389.815832 -395.478)
		(end 389.498078 -394.5128)
		(width 0.1651)
		(layer "In13.Cu")
		(net "P5E_PEX3_STN6_TX_C_DN<105>")
	)
	(segment
		(start 373.470932 -384.722116)
		(end 373.028464 -372.949978)
		(width 0.1651)
		(layer "In13.Cu")
		(net "P5E_PEX3_STN6_TX_C_DN<105>")
	)
	(segment
		(start 384.19659 -358.04856)
		(end 384.48742 -357.75773)
		(width 0.1651)
		(layer "In13.Cu")
		(net "P5E_PEX3_STN6_TX_C_DN<105>")
	)
	(segment
		(start 388.68985 -409.490164)
		(end 388.68985 -409.108148)
		(width 0.1651)
		(layer "In13.Cu")
		(net "P5E_PEX3_STN6_TX_C_DN<105>")
	)
	(segment
		(start 383.74955 -359.421938)
		(end 384.19659 -358.448864)
		(width 0.1651)
		(layer "In13.Cu")
		(net "P5E_PEX3_STN6_TX_C_DN<105>")
	)
	(segment
		(start 388.81685 -408.981148)
		(end 389.363966 -408.981148)
		(width 0.1651)
		(layer "In13.Cu")
		(net "P5E_PEX3_STN6_TX_C_DN<105>")
	)
	(segment
		(start 389.815832 -408.529282)
		(end 389.815832 -395.478)
		(width 0.1651)
		(layer "In13.Cu")
		(net "P5E_PEX3_STN6_TX_C_DN<105>")
	)
	(segment
		(start 386.221478 -391.8204)
		(end 375.959878 -387.4516)
		(width 0.1651)
		(layer "In13.Cu")
		(net "P5E_PEX3_STN6_TX_C_DN<105>")
	)
	(segment
		(start 389.498078 -394.5128)
		(end 387.796278 -392.7856)
		(width 0.1651)
		(layer "In13.Cu")
		(net "P5E_PEX3_STN6_TX_C_DN<105>")
	)
	(segment
		(start 373.360188 -369.063524)
		(end 375.0183 -366.919002)
		(width 0.1651)
		(layer "In13.Cu")
		(net "P5E_PEX3_STN6_TX_C_DN<105>")
	)
	(segment
		(start 373.028464 -372.949978)
		(end 373.028464 -372.949216)
		(width 0.1651)
		(layer "In13.Cu")
		(net "P5E_PEX3_STN6_TX_C_DN<105>")
	)
	(segment
		(start 384.19659 -358.448864)
		(end 384.19659 -358.04856)
		(width 0.1651)
		(layer "In13.Cu")
		(net "P5E_PEX3_STN6_TX_C_DN<105>")
	)
	(segment
		(start 389.363966 -408.981148)
		(end 389.815832 -408.529282)
		(width 0.1651)
		(layer "In13.Cu")
		(net "P5E_PEX3_STN6_TX_C_DN<105>")
	)
	(segment
		(start 373.92737 -386.014214)
		(end 373.470932 -384.722116)
		(width 0.1651)
		(layer "In13.Cu")
		(net "P5E_PEX3_STN6_TX_C_DN<105>")
	)
	(segment
		(start 373.028464 -372.949216)
		(end 373.360188 -369.063524)
		(width 0.1651)
		(layer "In13.Cu")
		(net "P5E_PEX3_STN6_TX_C_DN<105>")
	)
	(segment
		(start 375.959878 -387.4516)
		(end 373.92737 -386.014214)
		(width 0.1651)
		(layer "In13.Cu")
		(net "P5E_PEX3_STN6_TX_C_DN<105>")
	)
	(segment
		(start 375.0183 -366.919002)
		(end 383.74955 -359.421938)
		(width 0.1651)
		(layer "In13.Cu")
		(net "P5E_PEX3_STN6_TX_C_DN<105>")
	)
	(segment
		(start 88.664796 -31.99003)
		(end 88.183974 -31.99003)
		(width 0.13462)
		(layer "F.Cu")
		(net "P5E_PEX0_STN2_RX_DN<34>")
	)
	(segment
		(start 88.025224 -32.14878)
		(end 87.354664 -32.14878)
		(width 0.13462)
		(layer "F.Cu")
		(net "P5E_PEX0_STN2_RX_DN<34>")
	)
	(segment
		(start 88.183974 -31.99003)
		(end 88.025224 -32.14878)
		(width 0.13462)
		(layer "F.Cu")
		(net "P5E_PEX0_STN2_RX_DN<34>")
	)
	(segment
		(start 87.354664 -32.14878)
		(end 87.064596 -31.858712)
		(width 0.13462)
		(layer "F.Cu")
		(net "P5E_PEX0_STN2_RX_DN<34>")
	)
	(segment
		(start 56.52389 -275.379688)
		(end 56.420004 -275.275802)
		(width 0.1143)
		(layer "In7.Cu")
		(net "P5E_PEX0_STN2_RX_DN<34>")
	)
	(segment
		(start 56.420004 -271.467072)
		(end 56.465724 -271.421352)
		(width 0.1143)
		(layer "In7.Cu")
		(net "P5E_PEX0_STN2_RX_DN<34>")
	)
	(segment
		(start 56.799988 -274.999958)
		(end 56.799988 -275.265388)
		(width 0.1143)
		(layer "In7.Cu")
		(net "P5E_PEX0_STN2_RX_DN<34>")
	)
	(segment
		(start 89.043002 -61.227716)
		(end 89.227152 -49.435766)
		(width 0.1651)
		(layer "In7.Cu")
		(net "P5E_PEX0_STN2_RX_DN<34>")
	)
	(segment
		(start 88.442292 -32.790892)
		(end 87.800942 -32.149542)
		(width 0.1651)
		(layer "In7.Cu")
		(net "P5E_PEX0_STN2_RX_DN<34>")
	)
	(segment
		(start 56.465724 -270.653256)
		(end 56.792622 -266.859512)
		(width 0.1651)
		(layer "In7.Cu")
		(net "P5E_PEX0_STN2_RX_DN<34>")
	)
	(segment
		(start 88.408256 -34.984944)
		(end 88.442292 -32.790892)
		(width 0.1651)
		(layer "In7.Cu")
		(net "P5E_PEX0_STN2_RX_DN<34>")
	)
	(segment
		(start 76.351638 -154.552142)
		(end 77.742034 -143.750284)
		(width 0.1651)
		(layer "In7.Cu")
		(net "P5E_PEX0_STN2_RX_DN<34>")
	)
	(segment
		(start 87.355426 -32.149542)
		(end 87.064596 -31.858712)
		(width 0.1651)
		(layer "In7.Cu")
		(net "P5E_PEX0_STN2_RX_DN<34>")
	)
	(segment
		(start 77.742034 -143.750284)
		(end 78.05674 -116.602764)
		(width 0.1651)
		(layer "In7.Cu")
		(net "P5E_PEX0_STN2_RX_DN<34>")
	)
	(segment
		(start 56.465724 -271.392904)
		(end 56.465724 -270.653256)
		(width 0.1651)
		(layer "In7.Cu")
		(net "P5E_PEX0_STN2_RX_DN<34>")
	)
	(segment
		(start 56.799988 -275.265388)
		(end 56.685688 -275.379688)
		(width 0.1143)
		(layer "In7.Cu")
		(net "P5E_PEX0_STN2_RX_DN<34>")
	)
	(segment
		(start 56.420004 -275.275802)
		(end 56.420004 -271.467072)
		(width 0.1143)
		(layer "In7.Cu")
		(net "P5E_PEX0_STN2_RX_DN<34>")
	)
	(segment
		(start 56.792622 -266.859512)
		(end 76.351638 -154.552142)
		(width 0.1651)
		(layer "In7.Cu")
		(net "P5E_PEX0_STN2_RX_DN<34>")
	)
	(segment
		(start 87.800942 -32.149542)
		(end 87.355426 -32.149542)
		(width 0.1651)
		(layer "In7.Cu")
		(net "P5E_PEX0_STN2_RX_DN<34>")
	)
	(segment
		(start 87.882984 -37.803074)
		(end 88.408256 -34.984944)
		(width 0.1651)
		(layer "In7.Cu")
		(net "P5E_PEX0_STN2_RX_DN<34>")
	)
	(segment
		(start 87.912956 -39.71036)
		(end 87.882984 -37.803074)
		(width 0.1651)
		(layer "In7.Cu")
		(net "P5E_PEX0_STN2_RX_DN<34>")
	)
	(segment
		(start 78.05674 -116.602764)
		(end 89.043002 -61.227716)
		(width 0.1651)
		(layer "In7.Cu")
		(net "P5E_PEX0_STN2_RX_DN<34>")
	)
	(segment
		(start 56.465724 -271.421352)
		(end 56.465724 -271.392904)
		(width 0.1143)
		(layer "In7.Cu")
		(net "P5E_PEX0_STN2_RX_DN<34>")
	)
	(segment
		(start 56.685688 -275.379688)
		(end 56.52389 -275.379688)
		(width 0.1143)
		(layer "In7.Cu")
		(net "P5E_PEX0_STN2_RX_DN<34>")
	)
	(segment
		(start 89.227152 -49.435766)
		(end 87.912956 -39.71036)
		(width 0.1651)
		(layer "In7.Cu")
		(net "P5E_PEX0_STN2_RX_DN<34>")
	)
	(segment
		(start 187.941458 -30.35808)
		(end 184.035954 -30.35808)
		(width 0.13462)
		(layer "F.Cu")
		(net "P5E_PEX1_STN2_TX_C_DN<37>")
	)
	(segment
		(start 188.267848 -30.03169)
		(end 187.941458 -30.35808)
		(width 0.13462)
		(layer "F.Cu")
		(net "P5E_PEX1_STN2_TX_C_DN<37>")
	)
	(segment
		(start 183.86806 -30.190186)
		(end 183.364886 -30.190186)
		(width 0.13462)
		(layer "F.Cu")
		(net "P5E_PEX1_STN2_TX_C_DN<37>")
	)
	(segment
		(start 184.035954 -30.35808)
		(end 183.86806 -30.190186)
		(width 0.13462)
		(layer "F.Cu")
		(net "P5E_PEX1_STN2_TX_C_DN<37>")
	)
	(segment
		(start 300.378114 -130.6449)
		(end 300.220634 -130.48742)
		(width 0.13462)
		(layer "F.Cu")
		(net "P5E_PEX2_STN0_RX_DP<4>")
	)
	(segment
		(start 300.220634 -130.48742)
		(end 299.547026 -130.48742)
		(width 0.13462)
		(layer "F.Cu")
		(net "P5E_PEX2_STN0_RX_DP<4>")
	)
	(segment
		(start 299.547026 -130.48742)
		(end 299.257212 -130.777234)
		(width 0.13462)
		(layer "F.Cu")
		(net "P5E_PEX2_STN0_RX_DP<4>")
	)
	(segment
		(start 300.857412 -130.6449)
		(end 300.378114 -130.6449)
		(width 0.13462)
		(layer "F.Cu")
		(net "P5E_PEX2_STN0_RX_DP<4>")
	)
	(segment
		(start 327.692004 -269.76578)
		(end 319.272666 -240.959894)
		(width 0.1651)
		(layer "In5.Cu")
		(net "P5E_PEX2_STN0_RX_DP<4>")
	)
	(segment
		(start 303.378616 -132.3213)
		(end 303.22393 -132.368798)
		(width 0.1651)
		(layer "In5.Cu")
		(net "P5E_PEX2_STN0_RX_DP<4>")
	)
	(segment
		(start 301.222156 -131.181856)
		(end 301.067724 -131.229608)
		(width 0.1651)
		(layer "In5.Cu")
		(net "P5E_PEX2_STN0_RX_DP<4>")
	)
	(segment
		(start 304.456846 -132.891022)
		(end 304.302414 -132.93852)
		(width 0.1651)
		(layer "In5.Cu")
		(net "P5E_PEX2_STN0_RX_DP<4>")
	)
	(segment
		(start 311.799732 -284.499812)
		(end 312.065162 -284.499812)
		(width 0.1143)
		(layer "In5.Cu")
		(net "P5E_PEX2_STN0_RX_DP<4>")
	)
	(segment
		(start 301.067724 -131.229608)
		(end 300.629574 -130.99796)
		(width 0.1651)
		(layer "In5.Cu")
		(net "P5E_PEX2_STN0_RX_DP<4>")
	)
	(segment
		(start 315.22162 -149.80666)
		(end 314.11672 -148.56206)
		(width 0.1651)
		(layer "In5.Cu")
		(net "P5E_PEX2_STN0_RX_DP<4>")
	)
	(segment
		(start 312.87466 -148.26488)
		(end 312.41238 -147.778978)
		(width 0.1651)
		(layer "In5.Cu")
		(net "P5E_PEX2_STN0_RX_DP<4>")
	)
	(segment
		(start 312.065162 -284.499812)
		(end 312.179462 -284.385512)
		(width 0.1143)
		(layer "In5.Cu")
		(net "P5E_PEX2_STN0_RX_DP<4>")
	)
	(segment
		(start 312.423556 -283.929582)
		(end 316.050422 -283.929582)
		(width 0.1143)
		(layer "In5.Cu")
		(net "P5E_PEX2_STN0_RX_DP<4>")
	)
	(segment
		(start 312.179462 -284.173676)
		(end 312.423556 -283.929582)
		(width 0.1143)
		(layer "In5.Cu")
		(net "P5E_PEX2_STN0_RX_DP<4>")
	)
	(segment
		(start 301.70755 -131.567682)
		(end 301.660052 -131.412996)
		(width 0.1651)
		(layer "In5.Cu")
		(net "P5E_PEX2_STN0_RX_DP<4>")
	)
	(segment
		(start 303.816512 -132.55244)
		(end 303.378616 -132.3213)
		(width 0.1651)
		(layer "In5.Cu")
		(net "P5E_PEX2_STN0_RX_DP<4>")
	)
	(segment
		(start 300.629574 -130.99796)
		(end 300.582076 -130.843528)
		(width 0.1651)
		(layer "In5.Cu")
		(net "P5E_PEX2_STN0_RX_DP<4>")
	)
	(segment
		(start 316.050422 -283.929582)
		(end 316.096142 -283.883862)
		(width 0.1143)
		(layer "In5.Cu")
		(net "P5E_PEX2_STN0_RX_DP<4>")
	)
	(segment
		(start 318.151764 -283.180536)
		(end 325.6915 -275.89226)
		(width 0.1651)
		(layer "In5.Cu")
		(net "P5E_PEX2_STN0_RX_DP<4>")
	)
	(segment
		(start 309.743856 -137.053066)
		(end 308.458362 -135.90397)
		(width 0.1651)
		(layer "In5.Cu")
		(net "P5E_PEX2_STN0_RX_DP<4>")
	)
	(segment
		(start 304.302414 -132.93852)
		(end 303.86401 -132.706872)
		(width 0.1651)
		(layer "In5.Cu")
		(net "P5E_PEX2_STN0_RX_DP<4>")
	)
	(segment
		(start 299.548042 -130.486404)
		(end 299.257212 -130.777234)
		(width 0.1651)
		(layer "In5.Cu")
		(net "P5E_PEX2_STN0_RX_DP<4>")
	)
	(segment
		(start 307.084984 -134.676388)
		(end 305.99888 -133.7056)
		(width 0.1651)
		(layer "In5.Cu")
		(net "P5E_PEX2_STN0_RX_DP<4>")
	)
	(segment
		(start 307.587142 -135.125206)
		(end 307.461666 -135.132318)
		(width 0.1651)
		(layer "In5.Cu")
		(net "P5E_PEX2_STN0_RX_DP<4>")
	)
	(segment
		(start 327.595992 -272.49501)
		(end 327.692004 -269.76578)
		(width 0.1651)
		(layer "In5.Cu")
		(net "P5E_PEX2_STN0_RX_DP<4>")
	)
	(segment
		(start 308.332886 -135.911082)
		(end 307.963316 -135.580628)
		(width 0.1651)
		(layer "In5.Cu")
		(net "P5E_PEX2_STN0_RX_DP<4>")
	)
	(segment
		(start 305.535076 -133.460744)
		(end 305.380644 -133.508242)
		(width 0.1651)
		(layer "In5.Cu")
		(net "P5E_PEX2_STN0_RX_DP<4>")
	)
	(segment
		(start 311.257188 -140.067284)
		(end 310.518556 -138.195812)
		(width 0.1651)
		(layer "In5.Cu")
		(net "P5E_PEX2_STN0_RX_DP<4>")
	)
	(segment
		(start 302.300386 -131.751578)
		(end 302.1457 -131.799076)
		(width 0.1651)
		(layer "In5.Cu")
		(net "P5E_PEX2_STN0_RX_DP<4>")
	)
	(segment
		(start 312.41238 -147.778978)
		(end 311.257188 -140.067284)
		(width 0.1651)
		(layer "In5.Cu")
		(net "P5E_PEX2_STN0_RX_DP<4>")
	)
	(segment
		(start 316.12459 -283.883862)
		(end 317.14948 -283.883862)
		(width 0.1651)
		(layer "In5.Cu")
		(net "P5E_PEX2_STN0_RX_DP<4>")
	)
	(segment
		(start 310.518556 -138.195812)
		(end 309.743856 -137.053066)
		(width 0.1651)
		(layer "In5.Cu")
		(net "P5E_PEX2_STN0_RX_DP<4>")
	)
	(segment
		(start 312.179462 -284.385512)
		(end 312.179462 -284.173676)
		(width 0.1143)
		(layer "In5.Cu")
		(net "P5E_PEX2_STN0_RX_DP<4>")
	)
	(segment
		(start 304.894742 -133.122162)
		(end 304.456846 -132.891022)
		(width 0.1651)
		(layer "In5.Cu")
		(net "P5E_PEX2_STN0_RX_DP<4>")
	)
	(segment
		(start 300.582076 -130.843528)
		(end 299.906182 -130.486404)
		(width 0.1651)
		(layer "In5.Cu")
		(net "P5E_PEX2_STN0_RX_DP<4>")
	)
	(segment
		(start 308.458362 -135.90397)
		(end 308.332886 -135.911082)
		(width 0.1651)
		(layer "In5.Cu")
		(net "P5E_PEX2_STN0_RX_DP<4>")
	)
	(segment
		(start 325.6915 -275.89226)
		(end 327.595992 -272.49501)
		(width 0.1651)
		(layer "In5.Cu")
		(net "P5E_PEX2_STN0_RX_DP<4>")
	)
	(segment
		(start 302.1457 -131.799076)
		(end 301.70755 -131.567682)
		(width 0.1651)
		(layer "In5.Cu")
		(net "P5E_PEX2_STN0_RX_DP<4>")
	)
	(segment
		(start 302.78578 -132.137404)
		(end 302.738282 -131.982718)
		(width 0.1651)
		(layer "In5.Cu")
		(net "P5E_PEX2_STN0_RX_DP<4>")
	)
	(segment
		(start 307.092096 -134.801864)
		(end 307.084984 -134.676388)
		(width 0.1651)
		(layer "In5.Cu")
		(net "P5E_PEX2_STN0_RX_DP<4>")
	)
	(segment
		(start 307.963316 -135.580628)
		(end 307.956204 -135.455152)
		(width 0.1651)
		(layer "In5.Cu")
		(net "P5E_PEX2_STN0_RX_DP<4>")
	)
	(segment
		(start 303.86401 -132.706872)
		(end 303.816512 -132.55244)
		(width 0.1651)
		(layer "In5.Cu")
		(net "P5E_PEX2_STN0_RX_DP<4>")
	)
	(segment
		(start 319.272666 -240.959894)
		(end 317.38824 -232.261156)
		(width 0.1651)
		(layer "In5.Cu")
		(net "P5E_PEX2_STN0_RX_DP<4>")
	)
	(segment
		(start 317.38824 -232.261156)
		(end 317.99022 -168.33342)
		(width 0.1651)
		(layer "In5.Cu")
		(net "P5E_PEX2_STN0_RX_DP<4>")
	)
	(segment
		(start 303.22393 -132.368798)
		(end 302.78578 -132.137404)
		(width 0.1651)
		(layer "In5.Cu")
		(net "P5E_PEX2_STN0_RX_DP<4>")
	)
	(segment
		(start 305.99888 -133.7056)
		(end 305.535076 -133.460744)
		(width 0.1651)
		(layer "In5.Cu")
		(net "P5E_PEX2_STN0_RX_DP<4>")
	)
	(segment
		(start 304.94224 -133.276594)
		(end 304.894742 -133.122162)
		(width 0.1651)
		(layer "In5.Cu")
		(net "P5E_PEX2_STN0_RX_DP<4>")
	)
	(segment
		(start 317.3222 -150.85568)
		(end 315.22162 -149.80666)
		(width 0.1651)
		(layer "In5.Cu")
		(net "P5E_PEX2_STN0_RX_DP<4>")
	)
	(segment
		(start 307.956204 -135.455152)
		(end 307.587142 -135.125206)
		(width 0.1651)
		(layer "In5.Cu")
		(net "P5E_PEX2_STN0_RX_DP<4>")
	)
	(segment
		(start 307.461666 -135.132318)
		(end 307.092096 -134.801864)
		(width 0.1651)
		(layer "In5.Cu")
		(net "P5E_PEX2_STN0_RX_DP<4>")
	)
	(segment
		(start 305.380644 -133.508242)
		(end 304.94224 -133.276594)
		(width 0.1651)
		(layer "In5.Cu")
		(net "P5E_PEX2_STN0_RX_DP<4>")
	)
	(segment
		(start 317.99022 -168.33342)
		(end 317.62446 -151.55164)
		(width 0.1651)
		(layer "In5.Cu")
		(net "P5E_PEX2_STN0_RX_DP<4>")
	)
	(segment
		(start 316.096142 -283.883862)
		(end 316.12459 -283.883862)
		(width 0.1143)
		(layer "In5.Cu")
		(net "P5E_PEX2_STN0_RX_DP<4>")
	)
	(segment
		(start 299.906182 -130.486404)
		(end 299.548042 -130.486404)
		(width 0.1651)
		(layer "In5.Cu")
		(net "P5E_PEX2_STN0_RX_DP<4>")
	)
	(segment
		(start 301.660052 -131.412996)
		(end 301.222156 -131.181856)
		(width 0.1651)
		(layer "In5.Cu")
		(net "P5E_PEX2_STN0_RX_DP<4>")
	)
	(segment
		(start 314.11672 -148.56206)
		(end 312.87466 -148.26488)
		(width 0.1651)
		(layer "In5.Cu")
		(net "P5E_PEX2_STN0_RX_DP<4>")
	)
	(segment
		(start 317.14948 -283.883862)
		(end 318.151764 -283.180536)
		(width 0.1651)
		(layer "In5.Cu")
		(net "P5E_PEX2_STN0_RX_DP<4>")
	)
	(segment
		(start 302.738282 -131.982718)
		(end 302.300386 -131.751578)
		(width 0.1651)
		(layer "In5.Cu")
		(net "P5E_PEX2_STN0_RX_DP<4>")
	)
	(segment
		(start 317.62446 -151.55164)
		(end 317.3222 -150.85568)
		(width 0.1651)
		(layer "In5.Cu")
		(net "P5E_PEX2_STN0_RX_DP<4>")
	)
	(segment
		(start 393.839446 -112.644936)
		(end 394.342366 -112.644936)
		(width 0.13462)
		(layer "F.Cu")
		(net "P5E_PEX3_STN1_TX_C_DP<23>")
	)
	(segment
		(start 385.205224 -112.809782)
		(end 385.543806 -112.4712)
		(width 0.13462)
		(layer "F.Cu")
		(net "P5E_PEX3_STN1_TX_C_DP<23>")
	)
	(segment
		(start 385.543806 -112.4712)
		(end 393.66571 -112.4712)
		(width 0.13462)
		(layer "F.Cu")
		(net "P5E_PEX3_STN1_TX_C_DP<23>")
	)
	(segment
		(start 393.66571 -112.4712)
		(end 393.839446 -112.644936)
		(width 0.13462)
		(layer "F.Cu")
		(net "P5E_PEX3_STN1_TX_C_DP<23>")
	)
	(segment
		(start 386.207 -341.376)
		(end 402.824188 -326.277478)
		(width 0.1651)
		(layer "In5.Cu")
		(net "P5E_PEX3_STN6_RX_DN<96>")
	)
	(segment
		(start 404.890224 -323.42582)
		(end 405.715978 -321.580256)
		(width 0.1651)
		(layer "In5.Cu")
		(net "P5E_PEX3_STN6_RX_DN<96>")
	)
	(segment
		(start 406.049988 -318.434466)
		(end 406.049988 -318.699896)
		(width 0.1143)
		(layer "In5.Cu")
		(net "P5E_PEX3_STN6_RX_DN<96>")
	)
	(segment
		(start 390.889998 -376.458226)
		(end 391.063226 -376.284998)
		(width 0.1651)
		(layer "In5.Cu")
		(net "P5E_PEX3_STN6_RX_DN<96>")
	)
	(segment
		(start 385.75107 -358.721152)
		(end 385.75107 -341.935308)
		(width 0.1651)
		(layer "In5.Cu")
		(net "P5E_PEX3_STN6_RX_DN<96>")
	)
	(segment
		(start 405.935688 -318.320166)
		(end 406.049988 -318.434466)
		(width 0.1143)
		(layer "In5.Cu")
		(net "P5E_PEX3_STN6_RX_DN<96>")
	)
	(segment
		(start 391.063226 -376.284998)
		(end 391.550398 -376.284998)
		(width 0.1651)
		(layer "In5.Cu")
		(net "P5E_PEX3_STN6_RX_DN<96>")
	)
	(segment
		(start 405.715978 -319.96253)
		(end 405.715978 -319.934082)
		(width 0.1143)
		(layer "In5.Cu")
		(net "P5E_PEX3_STN6_RX_DN<96>")
	)
	(segment
		(start 392.047984 -368.81308)
		(end 385.75107 -358.721152)
		(width 0.1651)
		(layer "In5.Cu")
		(net "P5E_PEX3_STN6_RX_DN<96>")
	)
	(segment
		(start 405.670258 -319.888362)
		(end 405.670258 -318.434466)
		(width 0.1143)
		(layer "In5.Cu")
		(net "P5E_PEX3_STN6_RX_DN<96>")
	)
	(segment
		(start 402.824188 -326.277478)
		(end 404.890224 -323.42582)
		(width 0.1651)
		(layer "In5.Cu")
		(net "P5E_PEX3_STN6_RX_DN<96>")
	)
	(segment
		(start 391.550398 -376.284998)
		(end 392.047984 -375.787412)
		(width 0.1651)
		(layer "In5.Cu")
		(net "P5E_PEX3_STN6_RX_DN<96>")
	)
	(segment
		(start 385.75107 -341.935308)
		(end 386.207 -341.376)
		(width 0.1651)
		(layer "In5.Cu")
		(net "P5E_PEX3_STN6_RX_DN<96>")
	)
	(segment
		(start 392.047984 -375.787412)
		(end 392.047984 -368.81308)
		(width 0.1651)
		(layer "In5.Cu")
		(net "P5E_PEX3_STN6_RX_DN<96>")
	)
	(segment
		(start 390.889998 -376.790204)
		(end 390.889998 -376.458226)
		(width 0.1651)
		(layer "In5.Cu")
		(net "P5E_PEX3_STN6_RX_DN<96>")
	)
	(segment
		(start 405.784558 -318.320166)
		(end 405.935688 -318.320166)
		(width 0.1143)
		(layer "In5.Cu")
		(net "P5E_PEX3_STN6_RX_DN<96>")
	)
	(segment
		(start 405.670258 -318.434466)
		(end 405.784558 -318.320166)
		(width 0.1143)
		(layer "In5.Cu")
		(net "P5E_PEX3_STN6_RX_DN<96>")
	)
	(segment
		(start 405.715978 -321.580256)
		(end 405.715978 -319.96253)
		(width 0.1651)
		(layer "In5.Cu")
		(net "P5E_PEX3_STN6_RX_DN<96>")
	)
	(segment
		(start 405.715978 -319.934082)
		(end 405.670258 -319.888362)
		(width 0.1143)
		(layer "In5.Cu")
		(net "P5E_PEX3_STN6_RX_DN<96>")
	)
	(segment
		(start 88.664796 -28.99029)
		(end 88.185752 -28.99029)
		(width 0.13462)
		(layer "F.Cu")
		(net "P5E_PEX0_STN2_RX_DP<32>")
	)
	(segment
		(start 88.185752 -28.99029)
		(end 88.024462 -28.829)
		(width 0.13462)
		(layer "F.Cu")
		(net "P5E_PEX0_STN2_RX_DP<32>")
	)
	(segment
		(start 87.357966 -28.829)
		(end 87.064596 -29.12237)
		(width 0.13462)
		(layer "F.Cu")
		(net "P5E_PEX0_STN2_RX_DP<32>")
	)
	(segment
		(start 88.024462 -28.829)
		(end 87.357966 -28.829)
		(width 0.13462)
		(layer "F.Cu")
		(net "P5E_PEX0_STN2_RX_DP<32>")
	)
	(segment
		(start 88.664796 -28.990036)
		(end 88.664796 -28.99029)
		(width 0.13462)
		(layer "F.Cu")
		(net "P5E_PEX0_STN2_RX_DP<32>")
	)
	(segment
		(start 89.457022 -30.5562)
		(end 89.106502 -30.20568)
		(width 0.1651)
		(layer "In7.Cu")
		(net "P5E_PEX0_STN2_RX_DP<32>")
	)
	(segment
		(start 58.699908 -275.949918)
		(end 58.699908 -275.684488)
		(width 0.1143)
		(layer "In7.Cu")
		(net "P5E_PEX0_STN2_RX_DP<32>")
	)
	(segment
		(start 58.699908 -275.684488)
		(end 58.585608 -275.570188)
		(width 0.1143)
		(layer "In7.Cu")
		(net "P5E_PEX0_STN2_RX_DP<32>")
	)
	(segment
		(start 58.129424 -275.354796)
		(end 58.129424 -271.467072)
		(width 0.1143)
		(layer "In7.Cu")
		(net "P5E_PEX0_STN2_RX_DP<32>")
	)
	(segment
		(start 58.344816 -275.570188)
		(end 58.129424 -275.354796)
		(width 0.1143)
		(layer "In7.Cu")
		(net "P5E_PEX0_STN2_RX_DP<32>")
	)
	(segment
		(start 88.594692 -29.69387)
		(end 88.244172 -29.34335)
		(width 0.1651)
		(layer "In7.Cu")
		(net "P5E_PEX0_STN2_RX_DP<32>")
	)
	(segment
		(start 92.97289 -37.563552)
		(end 90.313256 -31.250636)
		(width 0.1651)
		(layer "In7.Cu")
		(net "P5E_PEX0_STN2_RX_DP<32>")
	)
	(segment
		(start 58.129424 -271.467072)
		(end 58.083704 -271.421352)
		(width 0.1143)
		(layer "In7.Cu")
		(net "P5E_PEX0_STN2_RX_DP<32>")
	)
	(segment
		(start 90.313256 -31.250636)
		(end 89.61882 -30.5562)
		(width 0.1651)
		(layer "In7.Cu")
		(net "P5E_PEX0_STN2_RX_DP<32>")
	)
	(segment
		(start 58.083704 -270.159734)
		(end 58.263282 -269.382494)
		(width 0.1651)
		(layer "In7.Cu")
		(net "P5E_PEX0_STN2_RX_DP<32>")
	)
	(segment
		(start 77.984096 -154.799284)
		(end 79.370174 -144.038066)
		(width 0.1651)
		(layer "In7.Cu")
		(net "P5E_PEX0_STN2_RX_DP<32>")
	)
	(segment
		(start 87.222584 -28.964382)
		(end 87.064596 -29.12237)
		(width 0.1651)
		(layer "In7.Cu")
		(net "P5E_PEX0_STN2_RX_DP<32>")
	)
	(segment
		(start 92.860876 -39.920926)
		(end 93.069156 -38.063424)
		(width 0.1651)
		(layer "In7.Cu")
		(net "P5E_PEX0_STN2_RX_DP<32>")
	)
	(segment
		(start 88.244172 -29.181552)
		(end 87.89416 -28.83154)
		(width 0.1651)
		(layer "In7.Cu")
		(net "P5E_PEX0_STN2_RX_DP<32>")
	)
	(segment
		(start 89.106502 -30.20568)
		(end 89.106502 -30.043882)
		(width 0.1651)
		(layer "In7.Cu")
		(net "P5E_PEX0_STN2_RX_DP<32>")
	)
	(segment
		(start 58.083704 -271.392904)
		(end 58.083704 -270.159734)
		(width 0.1651)
		(layer "In7.Cu")
		(net "P5E_PEX0_STN2_RX_DP<32>")
	)
	(segment
		(start 58.585608 -275.570188)
		(end 58.344816 -275.570188)
		(width 0.1143)
		(layer "In7.Cu")
		(net "P5E_PEX0_STN2_RX_DP<32>")
	)
	(segment
		(start 87.89416 -28.83154)
		(end 87.543386 -28.83154)
		(width 0.1651)
		(layer "In7.Cu")
		(net "P5E_PEX0_STN2_RX_DP<32>")
	)
	(segment
		(start 79.370174 -144.038066)
		(end 79.685388 -116.762022)
		(width 0.1651)
		(layer "In7.Cu")
		(net "P5E_PEX0_STN2_RX_DP<32>")
	)
	(segment
		(start 58.4962 -266.698222)
		(end 77.984096 -154.799284)
		(width 0.1651)
		(layer "In7.Cu")
		(net "P5E_PEX0_STN2_RX_DP<32>")
	)
	(segment
		(start 79.685388 -116.762022)
		(end 90.69324 -61.28004)
		(width 0.1651)
		(layer "In7.Cu")
		(net "P5E_PEX0_STN2_RX_DP<32>")
	)
	(segment
		(start 58.263282 -269.382494)
		(end 58.4962 -266.698222)
		(width 0.1651)
		(layer "In7.Cu")
		(net "P5E_PEX0_STN2_RX_DP<32>")
	)
	(segment
		(start 88.75649 -29.69387)
		(end 88.594692 -29.69387)
		(width 0.1651)
		(layer "In7.Cu")
		(net "P5E_PEX0_STN2_RX_DP<32>")
	)
	(segment
		(start 87.543386 -28.83154)
		(end 87.222584 -28.964382)
		(width 0.1651)
		(layer "In7.Cu")
		(net "P5E_PEX0_STN2_RX_DP<32>")
	)
	(segment
		(start 93.069156 -38.063424)
		(end 92.97289 -37.563552)
		(width 0.1651)
		(layer "In7.Cu")
		(net "P5E_PEX0_STN2_RX_DP<32>")
	)
	(segment
		(start 88.244172 -29.34335)
		(end 88.244172 -29.181552)
		(width 0.1651)
		(layer "In7.Cu")
		(net "P5E_PEX0_STN2_RX_DP<32>")
	)
	(segment
		(start 90.69324 -61.28004)
		(end 90.878914 -49.388014)
		(width 0.1651)
		(layer "In7.Cu")
		(net "P5E_PEX0_STN2_RX_DP<32>")
	)
	(segment
		(start 58.083704 -271.421352)
		(end 58.083704 -271.392904)
		(width 0.1143)
		(layer "In7.Cu")
		(net "P5E_PEX0_STN2_RX_DP<32>")
	)
	(segment
		(start 89.106502 -30.043882)
		(end 88.75649 -29.69387)
		(width 0.1651)
		(layer "In7.Cu")
		(net "P5E_PEX0_STN2_RX_DP<32>")
	)
	(segment
		(start 89.61882 -30.5562)
		(end 89.457022 -30.5562)
		(width 0.1651)
		(layer "In7.Cu")
		(net "P5E_PEX0_STN2_RX_DP<32>")
	)
	(segment
		(start 90.878914 -49.388014)
		(end 92.860876 -39.920926)
		(width 0.1651)
		(layer "In7.Cu")
		(net "P5E_PEX0_STN2_RX_DP<32>")
	)
	(segment
		(start 126.118874 -32.4231)
		(end 125.464062 -32.4231)
		(width 0.13462)
		(layer "F.Cu")
		(net "P5E_PEX1_STN2_RX_DP<46>")
	)
	(segment
		(start 126.285752 -32.589978)
		(end 126.118874 -32.4231)
		(width 0.13462)
		(layer "F.Cu")
		(net "P5E_PEX1_STN2_RX_DP<46>")
	)
	(segment
		(start 125.464062 -32.4231)
		(end 125.16485 -32.722312)
		(width 0.13462)
		(layer "F.Cu")
		(net "P5E_PEX1_STN2_RX_DP<46>")
	)
	(segment
		(start 126.76505 -32.589978)
		(end 126.285752 -32.589978)
		(width 0.13462)
		(layer "F.Cu")
		(net "P5E_PEX1_STN2_RX_DP<46>")
	)
	(segment
		(start 127.204216 -61.999622)
		(end 127.011684 -85.491066)
		(width 0.1651)
		(layer "In7.Cu")
		(net "P5E_PEX1_STN2_RX_DP<46>")
	)
	(segment
		(start 160.883854 -271.421352)
		(end 160.929574 -271.467072)
		(width 0.1143)
		(layer "In7.Cu")
		(net "P5E_PEX1_STN2_RX_DP<46>")
	)
	(segment
		(start 126.236222 -34.334958)
		(end 126.225808 -35.019996)
		(width 0.1651)
		(layer "In7.Cu")
		(net "P5E_PEX1_STN2_RX_DP<46>")
	)
	(segment
		(start 127.011684 -85.491066)
		(end 132.211572 -102.64521)
		(width 0.1651)
		(layer "In7.Cu")
		(net "P5E_PEX1_STN2_RX_DP<46>")
	)
	(segment
		(start 125.913388 -36.140898)
		(end 125.994668 -36.259516)
		(width 0.1651)
		(layer "In7.Cu")
		(net "P5E_PEX1_STN2_RX_DP<46>")
	)
	(segment
		(start 126.122938 -35.572446)
		(end 126.004066 -35.653726)
		(width 0.1651)
		(layer "In7.Cu")
		(net "P5E_PEX1_STN2_RX_DP<46>")
	)
	(segment
		(start 160.883854 -270.404336)
		(end 160.883854 -271.392904)
		(width 0.1651)
		(layer "In7.Cu")
		(net "P5E_PEX1_STN2_RX_DP<46>")
	)
	(segment
		(start 126.9238 -57.21223)
		(end 127.204216 -60.306966)
		(width 0.1651)
		(layer "In7.Cu")
		(net "P5E_PEX1_STN2_RX_DP<46>")
	)
	(segment
		(start 160.883854 -271.392904)
		(end 160.883854 -271.421352)
		(width 0.1143)
		(layer "In7.Cu")
		(net "P5E_PEX1_STN2_RX_DP<46>")
	)
	(segment
		(start 126.247398 -33.636458)
		(end 126.14402 -33.73628)
		(width 0.1651)
		(layer "In7.Cu")
		(net "P5E_PEX1_STN2_RX_DP<46>")
	)
	(segment
		(start 125.994668 -36.259516)
		(end 125.701552 -37.832538)
		(width 0.1651)
		(layer "In7.Cu")
		(net "P5E_PEX1_STN2_RX_DP<46>")
	)
	(segment
		(start 158.793688 -242.68049)
		(end 159.985456 -255.697482)
		(width 0.1651)
		(layer "In7.Cu")
		(net "P5E_PEX1_STN2_RX_DP<46>")
	)
	(segment
		(start 159.985456 -255.697482)
		(end 159.908494 -263.536684)
		(width 0.1651)
		(layer "In7.Cu")
		(net "P5E_PEX1_STN2_RX_DP<46>")
	)
	(segment
		(start 161.500058 -275.684488)
		(end 161.500058 -275.949918)
		(width 0.1143)
		(layer "In7.Cu")
		(net "P5E_PEX1_STN2_RX_DP<46>")
	)
	(segment
		(start 126.14402 -33.73628)
		(end 126.1364 -34.231834)
		(width 0.1651)
		(layer "In7.Cu")
		(net "P5E_PEX1_STN2_RX_DP<46>")
	)
	(segment
		(start 158.793434 -242.68049)
		(end 158.793688 -242.68049)
		(width 0.1651)
		(layer "In7.Cu")
		(net "P5E_PEX1_STN2_RX_DP<46>")
	)
	(segment
		(start 158.396686 -238.34217)
		(end 158.793434 -242.68049)
		(width 0.1651)
		(layer "In7.Cu")
		(net "P5E_PEX1_STN2_RX_DP<46>")
	)
	(segment
		(start 125.45568 -32.431482)
		(end 125.913388 -32.431482)
		(width 0.1651)
		(layer "In7.Cu")
		(net "P5E_PEX1_STN2_RX_DP<46>")
	)
	(segment
		(start 125.913388 -32.431482)
		(end 126.260606 -32.7787)
		(width 0.1651)
		(layer "In7.Cu")
		(net "P5E_PEX1_STN2_RX_DP<46>")
	)
	(segment
		(start 125.701552 -37.832538)
		(end 125.738636 -40.16883)
		(width 0.1651)
		(layer "In7.Cu")
		(net "P5E_PEX1_STN2_RX_DP<46>")
	)
	(segment
		(start 126.225808 -35.019996)
		(end 126.122938 -35.572446)
		(width 0.1651)
		(layer "In7.Cu")
		(net "P5E_PEX1_STN2_RX_DP<46>")
	)
	(segment
		(start 127.039624 -49.798986)
		(end 126.9238 -57.21223)
		(width 0.1651)
		(layer "In7.Cu")
		(net "P5E_PEX1_STN2_RX_DP<46>")
	)
	(segment
		(start 159.908494 -263.536684)
		(end 160.883854 -270.404336)
		(width 0.1651)
		(layer "In7.Cu")
		(net "P5E_PEX1_STN2_RX_DP<46>")
	)
	(segment
		(start 132.211572 -102.645718)
		(end 132.22351 -102.685088)
		(width 0.1651)
		(layer "In7.Cu")
		(net "P5E_PEX1_STN2_RX_DP<46>")
	)
	(segment
		(start 161.385758 -275.570188)
		(end 161.500058 -275.684488)
		(width 0.1143)
		(layer "In7.Cu")
		(net "P5E_PEX1_STN2_RX_DP<46>")
	)
	(segment
		(start 140.68933 -144.702276)
		(end 158.396686 -238.34217)
		(width 0.1651)
		(layer "In7.Cu")
		(net "P5E_PEX1_STN2_RX_DP<46>")
	)
	(segment
		(start 127.204216 -60.306966)
		(end 127.204216 -61.999622)
		(width 0.1651)
		(layer "In7.Cu")
		(net "P5E_PEX1_STN2_RX_DP<46>")
	)
	(segment
		(start 132.22351 -102.685088)
		(end 132.223764 -102.68585)
		(width 0.1651)
		(layer "In7.Cu")
		(net "P5E_PEX1_STN2_RX_DP<46>")
	)
	(segment
		(start 160.929574 -275.354796)
		(end 161.144966 -275.570188)
		(width 0.1143)
		(layer "In7.Cu")
		(net "P5E_PEX1_STN2_RX_DP<46>")
	)
	(segment
		(start 125.738636 -40.16883)
		(end 127.039624 -49.798986)
		(width 0.1651)
		(layer "In7.Cu")
		(net "P5E_PEX1_STN2_RX_DP<46>")
	)
	(segment
		(start 132.211572 -102.64521)
		(end 132.211572 -102.645718)
		(width 0.1651)
		(layer "In7.Cu")
		(net "P5E_PEX1_STN2_RX_DP<46>")
	)
	(segment
		(start 132.223764 -102.68585)
		(end 137.416032 -119.815864)
		(width 0.1651)
		(layer "In7.Cu")
		(net "P5E_PEX1_STN2_RX_DP<46>")
	)
	(segment
		(start 125.16485 -32.722312)
		(end 125.45568 -32.431482)
		(width 0.1651)
		(layer "In7.Cu")
		(net "P5E_PEX1_STN2_RX_DP<46>")
	)
	(segment
		(start 126.260606 -32.7787)
		(end 126.247398 -33.636458)
		(width 0.1651)
		(layer "In7.Cu")
		(net "P5E_PEX1_STN2_RX_DP<46>")
	)
	(segment
		(start 126.004066 -35.653726)
		(end 125.913388 -36.140898)
		(width 0.1651)
		(layer "In7.Cu")
		(net "P5E_PEX1_STN2_RX_DP<46>")
	)
	(segment
		(start 137.416032 -119.815864)
		(end 140.68933 -144.702276)
		(width 0.1651)
		(layer "In7.Cu")
		(net "P5E_PEX1_STN2_RX_DP<46>")
	)
	(segment
		(start 160.929574 -271.467072)
		(end 160.929574 -275.354796)
		(width 0.1143)
		(layer "In7.Cu")
		(net "P5E_PEX1_STN2_RX_DP<46>")
	)
	(segment
		(start 161.144966 -275.570188)
		(end 161.385758 -275.570188)
		(width 0.1143)
		(layer "In7.Cu")
		(net "P5E_PEX1_STN2_RX_DP<46>")
	)
	(segment
		(start 126.1364 -34.231834)
		(end 126.236222 -34.334958)
		(width 0.1651)
		(layer "In7.Cu")
		(net "P5E_PEX1_STN2_RX_DP<46>")
	)
	(segment
		(start 297.688254 -144.70888)
		(end 300.225968 -144.70888)
		(width 0.13462)
		(layer "F.Cu")
		(net "P5E_PEX2_STN0_RX_DN<9>")
	)
	(segment
		(start 300.379892 -144.554956)
		(end 300.857412 -144.554956)
		(width 0.13462)
		(layer "F.Cu")
		(net "P5E_PEX2_STN0_RX_DN<9>")
	)
	(segment
		(start 300.225968 -144.70888)
		(end 300.379892 -144.554956)
		(width 0.13462)
		(layer "F.Cu")
		(net "P5E_PEX2_STN0_RX_DN<9>")
	)
	(segment
		(start 297.403012 -144.423638)
		(end 297.688254 -144.70888)
		(width 0.13462)
		(layer "F.Cu")
		(net "P5E_PEX2_STN0_RX_DN<9>")
	)
	(segment
		(start 312.369962 -273.376136)
		(end 312.47334 -273.479514)
		(width 0.1143)
		(layer "In5.Cu")
		(net "P5E_PEX2_STN0_RX_DN<9>")
	)
	(segment
		(start 300.278546 -145.071846)
		(end 300.278546 -145.0721)
		(width 0.1651)
		(layer "In5.Cu")
		(net "P5E_PEX2_STN0_RX_DN<9>")
	)
	(segment
		(start 305.281584 -152.48255)
		(end 308.0385 -155.292806)
		(width 0.1651)
		(layer "In5.Cu")
		(net "P5E_PEX2_STN0_RX_DN<9>")
	)
	(segment
		(start 312.415682 -271.526)
		(end 312.415682 -271.554448)
		(width 0.1143)
		(layer "In5.Cu")
		(net "P5E_PEX2_STN0_RX_DN<9>")
	)
	(segment
		(start 312.999882 -261.973314)
		(end 312.999882 -268.288008)
		(width 0.1651)
		(layer "In5.Cu")
		(net "P5E_PEX2_STN0_RX_DN<9>")
	)
	(segment
		(start 312.415682 -271.554448)
		(end 312.369962 -271.600168)
		(width 0.1143)
		(layer "In5.Cu")
		(net "P5E_PEX2_STN0_RX_DN<9>")
	)
	(segment
		(start 297.693842 -144.714468)
		(end 299.42409 -144.714468)
		(width 0.1651)
		(layer "In5.Cu")
		(net "P5E_PEX2_STN0_RX_DN<9>")
	)
	(segment
		(start 299.42409 -144.714468)
		(end 300.278546 -145.071846)
		(width 0.1651)
		(layer "In5.Cu")
		(net "P5E_PEX2_STN0_RX_DN<9>")
	)
	(segment
		(start 308.0385 -155.292806)
		(end 309.324756 -160.116012)
		(width 0.1651)
		(layer "In5.Cu")
		(net "P5E_PEX2_STN0_RX_DN<9>")
	)
	(segment
		(start 312.635138 -273.479514)
		(end 312.749438 -273.365214)
		(width 0.1143)
		(layer "In5.Cu")
		(net "P5E_PEX2_STN0_RX_DN<9>")
	)
	(segment
		(start 312.999882 -268.288008)
		(end 312.415682 -271.225518)
		(width 0.1651)
		(layer "In5.Cu")
		(net "P5E_PEX2_STN0_RX_DN<9>")
	)
	(segment
		(start 312.749438 -273.365214)
		(end 312.749438 -273.099784)
		(width 0.1143)
		(layer "In5.Cu")
		(net "P5E_PEX2_STN0_RX_DN<9>")
	)
	(segment
		(start 309.324756 -160.115758)
		(end 309.417212 -160.462976)
		(width 0.1651)
		(layer "In5.Cu")
		(net "P5E_PEX2_STN0_RX_DN<9>")
	)
	(segment
		(start 297.403012 -144.423638)
		(end 297.693842 -144.714468)
		(width 0.1651)
		(layer "In5.Cu")
		(net "P5E_PEX2_STN0_RX_DN<9>")
	)
	(segment
		(start 309.324756 -160.116012)
		(end 309.324756 -160.115758)
		(width 0.1651)
		(layer "In5.Cu")
		(net "P5E_PEX2_STN0_RX_DN<9>")
	)
	(segment
		(start 312.415682 -271.225518)
		(end 312.415682 -271.526)
		(width 0.1651)
		(layer "In5.Cu")
		(net "P5E_PEX2_STN0_RX_DN<9>")
	)
	(segment
		(start 304.53584 -150.41118)
		(end 305.281584 -152.48255)
		(width 0.1651)
		(layer "In5.Cu")
		(net "P5E_PEX2_STN0_RX_DN<9>")
	)
	(segment
		(start 300.278546 -145.0721)
		(end 302.593502 -147.418806)
		(width 0.1651)
		(layer "In5.Cu")
		(net "P5E_PEX2_STN0_RX_DN<9>")
	)
	(segment
		(start 312.47334 -273.479514)
		(end 312.635138 -273.479514)
		(width 0.1143)
		(layer "In5.Cu")
		(net "P5E_PEX2_STN0_RX_DN<9>")
	)
	(segment
		(start 312.369962 -271.600168)
		(end 312.369962 -273.376136)
		(width 0.1143)
		(layer "In5.Cu")
		(net "P5E_PEX2_STN0_RX_DN<9>")
	)
	(segment
		(start 309.417212 -160.462976)
		(end 312.999882 -261.973314)
		(width 0.1651)
		(layer "In5.Cu")
		(net "P5E_PEX2_STN0_RX_DN<9>")
	)
	(segment
		(start 302.593502 -147.418806)
		(end 304.53584 -150.41118)
		(width 0.1651)
		(layer "In5.Cu")
		(net "P5E_PEX2_STN0_RX_DN<9>")
	)
	(segment
		(start 402.096986 -119.7864)
		(end 399.588736 -119.7864)
		(width 0.13462)
		(layer "F.Cu")
		(net "P5E_PEX3_STN1_RX_DN<24>")
	)
	(segment
		(start 402.39696 -120.086374)
		(end 402.096986 -119.7864)
		(width 0.13462)
		(layer "F.Cu")
		(net "P5E_PEX3_STN1_RX_DN<24>")
	)
	(segment
		(start 399.42008 -119.955056)
		(end 398.94256 -119.955056)
		(width 0.13462)
		(layer "F.Cu")
		(net "P5E_PEX3_STN1_RX_DN<24>")
	)
	(segment
		(start 399.588736 -119.7864)
		(end 399.42008 -119.955056)
		(width 0.13462)
		(layer "F.Cu")
		(net "P5E_PEX3_STN1_RX_DN<24>")
	)
	(segment
		(start 392.91514 -125.657864)
		(end 392.646916 -126.073916)
		(width 0.1651)
		(layer "In5.Cu")
		(net "P5E_PEX3_STN1_RX_DN<24>")
	)
	(segment
		(start 388.657592 -139.325096)
		(end 388.700772 -139.480798)
		(width 0.1651)
		(layer "In5.Cu")
		(net "P5E_PEX3_STN1_RX_DN<24>")
	)
	(segment
		(start 389.057388 -138.851132)
		(end 388.901686 -138.894312)
		(width 0.1651)
		(layer "In5.Cu")
		(net "P5E_PEX3_STN1_RX_DN<24>")
	)
	(segment
		(start 396.578328 -122.183652)
		(end 396.219172 -122.524266)
		(width 0.1651)
		(layer "In5.Cu")
		(net "P5E_PEX3_STN1_RX_DN<24>")
	)
	(segment
		(start 396.219172 -122.524266)
		(end 396.214854 -122.686064)
		(width 0.1651)
		(layer "In5.Cu")
		(net "P5E_PEX3_STN1_RX_DN<24>")
	)
	(segment
		(start 389.573262 -137.708894)
		(end 389.25881 -138.264138)
		(width 0.1651)
		(layer "In5.Cu")
		(net "P5E_PEX3_STN1_RX_DN<24>")
	)
	(segment
		(start 389.301736 -138.41984)
		(end 389.057388 -138.851132)
		(width 0.1651)
		(layer "In5.Cu")
		(net "P5E_PEX3_STN1_RX_DN<24>")
	)
	(segment
		(start 394.449808 -124.202444)
		(end 394.44549 -124.364242)
		(width 0.1651)
		(layer "In5.Cu")
		(net "P5E_PEX3_STN1_RX_DN<24>")
	)
	(segment
		(start 393.924282 -124.701046)
		(end 392.91514 -125.657864)
		(width 0.1651)
		(layer "In5.Cu")
		(net "P5E_PEX3_STN1_RX_DN<24>")
	)
	(segment
		(start 398.45869 -120.400064)
		(end 397.103854 -121.68505)
		(width 0.1651)
		(layer "In5.Cu")
		(net "P5E_PEX3_STN1_RX_DN<24>")
	)
	(segment
		(start 415.549588 -273.365214)
		(end 415.549588 -273.099784)
		(width 0.1143)
		(layer "In5.Cu")
		(net "P5E_PEX3_STN1_RX_DN<24>")
	)
	(segment
		(start 388.456424 -139.91209)
		(end 388.300722 -139.95527)
		(width 0.1651)
		(layer "In5.Cu")
		(net "P5E_PEX3_STN1_RX_DN<24>")
	)
	(segment
		(start 415.170112 -271.600168)
		(end 415.170112 -273.376136)
		(width 0.1143)
		(layer "In5.Cu")
		(net "P5E_PEX3_STN1_RX_DN<24>")
	)
	(segment
		(start 396.214854 -122.686064)
		(end 395.85519 -123.026932)
		(width 0.1651)
		(layer "In5.Cu")
		(net "P5E_PEX3_STN1_RX_DN<24>")
	)
	(segment
		(start 395.33449 -123.363482)
		(end 395.330172 -123.52528)
		(width 0.1651)
		(layer "In5.Cu")
		(net "P5E_PEX3_STN1_RX_DN<24>")
	)
	(segment
		(start 397.099536 -121.846594)
		(end 396.739872 -122.187716)
		(width 0.1651)
		(layer "In5.Cu")
		(net "P5E_PEX3_STN1_RX_DN<24>")
	)
	(segment
		(start 392.680952 -126.231904)
		(end 392.41222 -126.648464)
		(width 0.1651)
		(layer "In5.Cu")
		(net "P5E_PEX3_STN1_RX_DN<24>")
	)
	(segment
		(start 415.215832 -268.381226)
		(end 415.215832 -271.526)
		(width 0.1651)
		(layer "In5.Cu")
		(net "P5E_PEX3_STN1_RX_DN<24>")
	)
	(segment
		(start 387.420866 -141.979904)
		(end 387.269482 -142.037054)
		(width 0.1651)
		(layer "In5.Cu")
		(net "P5E_PEX3_STN1_RX_DN<24>")
	)
	(segment
		(start 387.624574 -141.528292)
		(end 387.420866 -141.979904)
		(width 0.1651)
		(layer "In5.Cu")
		(net "P5E_PEX3_STN1_RX_DN<24>")
	)
	(segment
		(start 395.693646 -123.022868)
		(end 395.33449 -123.363482)
		(width 0.1651)
		(layer "In5.Cu")
		(net "P5E_PEX3_STN1_RX_DN<24>")
	)
	(segment
		(start 392.41222 -126.648464)
		(end 392.254232 -126.682754)
		(width 0.1651)
		(layer "In5.Cu")
		(net "P5E_PEX3_STN1_RX_DN<24>")
	)
	(segment
		(start 394.970508 -123.866148)
		(end 394.808964 -123.86183)
		(width 0.1651)
		(layer "In5.Cu")
		(net "P5E_PEX3_STN1_RX_DN<24>")
	)
	(segment
		(start 385.083304 -158.172912)
		(end 386.082286 -163.875974)
		(width 0.1651)
		(layer "In5.Cu")
		(net "P5E_PEX3_STN1_RX_DN<24>")
	)
	(segment
		(start 385.81838 -145.252186)
		(end 384.650742 -151.578564)
		(width 0.1651)
		(layer "In5.Cu")
		(net "P5E_PEX3_STN1_RX_DN<24>")
	)
	(segment
		(start 386.082286 -163.875974)
		(end 415.215832 -268.381226)
		(width 0.1651)
		(layer "In5.Cu")
		(net "P5E_PEX3_STN1_RX_DN<24>")
	)
	(segment
		(start 415.170112 -273.376136)
		(end 415.27349 -273.479514)
		(width 0.1143)
		(layer "In5.Cu")
		(net "P5E_PEX3_STN1_RX_DN<24>")
	)
	(segment
		(start 396.739872 -122.187716)
		(end 396.578328 -122.183652)
		(width 0.1651)
		(layer "In5.Cu")
		(net "P5E_PEX3_STN1_RX_DN<24>")
	)
	(segment
		(start 392.254232 -126.682754)
		(end 391.327132 -128.120648)
		(width 0.1651)
		(layer "In5.Cu")
		(net "P5E_PEX3_STN1_RX_DN<24>")
	)
	(segment
		(start 388.300722 -139.95527)
		(end 387.85038 -140.750036)
		(width 0.1651)
		(layer "In5.Cu")
		(net "P5E_PEX3_STN1_RX_DN<24>")
	)
	(segment
		(start 415.27349 -273.479514)
		(end 415.435288 -273.479514)
		(width 0.1143)
		(layer "In5.Cu")
		(net "P5E_PEX3_STN1_RX_DN<24>")
	)
	(segment
		(start 397.103854 -121.68505)
		(end 397.099536 -121.846594)
		(width 0.1651)
		(layer "In5.Cu")
		(net "P5E_PEX3_STN1_RX_DN<24>")
	)
	(segment
		(start 394.085826 -124.70511)
		(end 393.924282 -124.701046)
		(width 0.1651)
		(layer "In5.Cu")
		(net "P5E_PEX3_STN1_RX_DN<24>")
	)
	(segment
		(start 389.25881 -138.264138)
		(end 389.301736 -138.41984)
		(width 0.1651)
		(layer "In5.Cu")
		(net "P5E_PEX3_STN1_RX_DN<24>")
	)
	(segment
		(start 415.435288 -273.479514)
		(end 415.549588 -273.365214)
		(width 0.1143)
		(layer "In5.Cu")
		(net "P5E_PEX3_STN1_RX_DN<24>")
	)
	(segment
		(start 387.85038 -140.750036)
		(end 387.567424 -141.376908)
		(width 0.1651)
		(layer "In5.Cu")
		(net "P5E_PEX3_STN1_RX_DN<24>")
	)
	(segment
		(start 415.215832 -271.526)
		(end 415.215832 -271.554448)
		(width 0.1143)
		(layer "In5.Cu")
		(net "P5E_PEX3_STN1_RX_DN<24>")
	)
	(segment
		(start 395.330172 -123.52528)
		(end 394.970508 -123.866148)
		(width 0.1651)
		(layer "In5.Cu")
		(net "P5E_PEX3_STN1_RX_DN<24>")
	)
	(segment
		(start 400.400012 -119.795544)
		(end 398.45869 -120.400064)
		(width 0.1651)
		(layer "In5.Cu")
		(net "P5E_PEX3_STN1_RX_DN<24>")
	)
	(segment
		(start 387.269482 -142.037054)
		(end 385.81838 -145.252186)
		(width 0.1651)
		(layer "In5.Cu")
		(net "P5E_PEX3_STN1_RX_DN<24>")
	)
	(segment
		(start 394.44549 -124.364242)
		(end 394.085826 -124.70511)
		(width 0.1651)
		(layer "In5.Cu")
		(net "P5E_PEX3_STN1_RX_DN<24>")
	)
	(segment
		(start 387.567424 -141.376908)
		(end 387.624574 -141.528292)
		(width 0.1651)
		(layer "In5.Cu")
		(net "P5E_PEX3_STN1_RX_DN<24>")
	)
	(segment
		(start 402.39696 -120.086374)
		(end 402.10613 -119.795544)
		(width 0.1651)
		(layer "In5.Cu")
		(net "P5E_PEX3_STN1_RX_DN<24>")
	)
	(segment
		(start 395.85519 -123.026932)
		(end 395.693646 -123.022868)
		(width 0.1651)
		(layer "In5.Cu")
		(net "P5E_PEX3_STN1_RX_DN<24>")
	)
	(segment
		(start 392.646916 -126.073916)
		(end 392.680952 -126.231904)
		(width 0.1651)
		(layer "In5.Cu")
		(net "P5E_PEX3_STN1_RX_DN<24>")
	)
	(segment
		(start 390.995408 -128.983232)
		(end 389.573262 -137.708894)
		(width 0.1651)
		(layer "In5.Cu")
		(net "P5E_PEX3_STN1_RX_DN<24>")
	)
	(segment
		(start 391.327132 -128.120648)
		(end 390.995408 -128.983232)
		(width 0.1651)
		(layer "In5.Cu")
		(net "P5E_PEX3_STN1_RX_DN<24>")
	)
	(segment
		(start 384.650742 -151.578564)
		(end 385.083304 -158.172912)
		(width 0.1651)
		(layer "In5.Cu")
		(net "P5E_PEX3_STN1_RX_DN<24>")
	)
	(segment
		(start 388.700772 -139.480798)
		(end 388.456424 -139.91209)
		(width 0.1651)
		(layer "In5.Cu")
		(net "P5E_PEX3_STN1_RX_DN<24>")
	)
	(segment
		(start 402.10613 -119.795544)
		(end 400.400012 -119.795544)
		(width 0.1651)
		(layer "In5.Cu")
		(net "P5E_PEX3_STN1_RX_DN<24>")
	)
	(segment
		(start 415.215832 -271.554448)
		(end 415.170112 -271.600168)
		(width 0.1143)
		(layer "In5.Cu")
		(net "P5E_PEX3_STN1_RX_DN<24>")
	)
	(segment
		(start 388.901686 -138.894312)
		(end 388.657592 -139.325096)
		(width 0.1651)
		(layer "In5.Cu")
		(net "P5E_PEX3_STN1_RX_DN<24>")
	)
	(segment
		(start 394.808964 -123.86183)
		(end 394.449808 -124.202444)
		(width 0.1651)
		(layer "In5.Cu")
		(net "P5E_PEX3_STN1_RX_DN<24>")
	)
	(segment
		(start 375.18594 -356.511606)
		(end 374.866408 -356.831138)
		(width 0.13462)
		(layer "F.Cu")
		(net "P5E_PEX3_STN6_TX_C_DN<101>")
	)
	(segment
		(start 374.866408 -357.463598)
		(end 375.16054 -357.75773)
		(width 0.13462)
		(layer "F.Cu")
		(net "P5E_PEX3_STN6_TX_C_DN<101>")
	)
	(segment
		(start 374.866408 -356.831138)
		(end 374.866408 -357.463598)
		(width 0.13462)
		(layer "F.Cu")
		(net "P5E_PEX3_STN6_TX_C_DN<101>")
	)
	(segment
		(start 379.89002 -383.490216)
		(end 379.89002 -383.1082)
		(width 0.1651)
		(layer "In7.Cu")
		(net "P5E_PEX3_STN6_TX_C_DN<101>")
	)
	(segment
		(start 374.86971 -358.04856)
		(end 375.16054 -357.75773)
		(width 0.1651)
		(layer "In7.Cu")
		(net "P5E_PEX3_STN6_TX_C_DN<101>")
	)
	(segment
		(start 380.564136 -382.9812)
		(end 381.016002 -382.529334)
		(width 0.1651)
		(layer "In7.Cu")
		(net "P5E_PEX3_STN6_TX_C_DN<101>")
	)
	(segment
		(start 379.89002 -383.1082)
		(end 380.01702 -382.9812)
		(width 0.1651)
		(layer "In7.Cu")
		(net "P5E_PEX3_STN6_TX_C_DN<101>")
	)
	(segment
		(start 381.016002 -382.529334)
		(end 381.016002 -368.71402)
		(width 0.1651)
		(layer "In7.Cu")
		(net "P5E_PEX3_STN6_TX_C_DN<101>")
	)
	(segment
		(start 380.01702 -382.9812)
		(end 380.564136 -382.9812)
		(width 0.1651)
		(layer "In7.Cu")
		(net "P5E_PEX3_STN6_TX_C_DN<101>")
	)
	(segment
		(start 381.016002 -368.71402)
		(end 374.86971 -358.53243)
		(width 0.1651)
		(layer "In7.Cu")
		(net "P5E_PEX3_STN6_TX_C_DN<101>")
	)
	(segment
		(start 374.86971 -358.53243)
		(end 374.86971 -358.04856)
		(width 0.1651)
		(layer "In7.Cu")
		(net "P5E_PEX3_STN6_TX_C_DN<101>")
	)
	(segment
		(start 175.49495 -99.750372)
		(end 178.030124 -99.750372)
		(width 0.13208)
		(layer "F.Cu")
		(net "NIC3_SLOT_ID1")
	)
	(segment
		(start 175.49495 -100.766372)
		(end 175.49495 -99.750372)
		(width 0.13208)
		(layer "F.Cu")
		(net "NIC3_SLOT_ID1")
	)
	(segment
		(start 178.030124 -99.750372)
		(end 178.319684 -100.039932)
		(width 0.13208)
		(layer "F.Cu")
		(net "NIC3_SLOT_ID1")
	)
	(segment
		(start 178.319684 -100.039932)
		(end 184.757314 -100.039932)
		(width 0.13208)
		(layer "F.Cu")
		(net "NIC3_SLOT_ID1")
	)
	(via
		(at 178.319684 -100.039932)
		(size 0.762)
		(drill 0.381)
		(layers "F.Cu" "B.Cu")
		(net "NIC3_SLOT_ID1")
	)
	(segment
		(start 152.284176 -28.390088)
		(end 152.119584 -28.55468)
		(width 0.13462)
		(layer "F.Cu")
		(net "P5E_PEX1_STN2_RX_DN<40>")
	)
	(segment
		(start 152.119584 -28.55468)
		(end 151.460708 -28.55468)
		(width 0.13462)
		(layer "F.Cu")
		(net "P5E_PEX1_STN2_RX_DN<40>")
	)
	(segment
		(start 151.460708 -28.55468)
		(end 151.164798 -28.25877)
		(width 0.13462)
		(layer "F.Cu")
		(net "P5E_PEX1_STN2_RX_DN<40>")
	)
	(segment
		(start 152.764998 -28.390088)
		(end 152.284176 -28.390088)
		(width 0.13462)
		(layer "F.Cu")
		(net "P5E_PEX1_STN2_RX_DN<40>")
	)
	(segment
		(start 166.865808 -268.123162)
		(end 166.865808 -271.392904)
		(width 0.1651)
		(layer "In7.Cu")
		(net "P5E_PEX1_STN2_RX_DN<40>")
	)
	(segment
		(start 166.820088 -275.275802)
		(end 166.923974 -275.379688)
		(width 0.1143)
		(layer "In7.Cu")
		(net "P5E_PEX1_STN2_RX_DN<40>")
	)
	(segment
		(start 166.865808 -271.421352)
		(end 166.820088 -271.467072)
		(width 0.1143)
		(layer "In7.Cu")
		(net "P5E_PEX1_STN2_RX_DN<40>")
	)
	(segment
		(start 151.903938 -28.5496)
		(end 154.80284 -31.448502)
		(width 0.1651)
		(layer "In7.Cu")
		(net "P5E_PEX1_STN2_RX_DN<40>")
	)
	(segment
		(start 158.869126 -147.93849)
		(end 166.830756 -250.008136)
		(width 0.1651)
		(layer "In7.Cu")
		(net "P5E_PEX1_STN2_RX_DN<40>")
	)
	(segment
		(start 158.712154 -104.30002)
		(end 159.174942 -119.564404)
		(width 0.1651)
		(layer "In7.Cu")
		(net "P5E_PEX1_STN2_RX_DN<40>")
	)
	(segment
		(start 167.085772 -275.379688)
		(end 167.200072 -275.265388)
		(width 0.1143)
		(layer "In7.Cu")
		(net "P5E_PEX1_STN2_RX_DN<40>")
	)
	(segment
		(start 166.830756 -250.008136)
		(end 166.544498 -264.860786)
		(width 0.1651)
		(layer "In7.Cu")
		(net "P5E_PEX1_STN2_RX_DN<40>")
	)
	(segment
		(start 166.923974 -275.379688)
		(end 167.085772 -275.379688)
		(width 0.1143)
		(layer "In7.Cu")
		(net "P5E_PEX1_STN2_RX_DN<40>")
	)
	(segment
		(start 154.80284 -31.448502)
		(end 157.431486 -37.688012)
		(width 0.1651)
		(layer "In7.Cu")
		(net "P5E_PEX1_STN2_RX_DN<40>")
	)
	(segment
		(start 159.174942 -119.564404)
		(end 158.869126 -147.93849)
		(width 0.1651)
		(layer "In7.Cu")
		(net "P5E_PEX1_STN2_RX_DN<40>")
	)
	(segment
		(start 157.416754 -38.576758)
		(end 155.269946 -48.829722)
		(width 0.1651)
		(layer "In7.Cu")
		(net "P5E_PEX1_STN2_RX_DN<40>")
	)
	(segment
		(start 151.455628 -28.5496)
		(end 151.903938 -28.5496)
		(width 0.1651)
		(layer "In7.Cu")
		(net "P5E_PEX1_STN2_RX_DN<40>")
	)
	(segment
		(start 155.269946 -48.829722)
		(end 155.170632 -55.191914)
		(width 0.1651)
		(layer "In7.Cu")
		(net "P5E_PEX1_STN2_RX_DN<40>")
	)
	(segment
		(start 166.544498 -264.860786)
		(end 166.865808 -268.123162)
		(width 0.1651)
		(layer "In7.Cu")
		(net "P5E_PEX1_STN2_RX_DN<40>")
	)
	(segment
		(start 155.568396 -65.131442)
		(end 158.712154 -104.30002)
		(width 0.1651)
		(layer "In7.Cu")
		(net "P5E_PEX1_STN2_RX_DN<40>")
	)
	(segment
		(start 166.865808 -271.392904)
		(end 166.865808 -271.421352)
		(width 0.1143)
		(layer "In7.Cu")
		(net "P5E_PEX1_STN2_RX_DN<40>")
	)
	(segment
		(start 155.170632 -55.191914)
		(end 155.568396 -65.131442)
		(width 0.1651)
		(layer "In7.Cu")
		(net "P5E_PEX1_STN2_RX_DN<40>")
	)
	(segment
		(start 167.200072 -275.265388)
		(end 167.200072 -274.999958)
		(width 0.1143)
		(layer "In7.Cu")
		(net "P5E_PEX1_STN2_RX_DN<40>")
	)
	(segment
		(start 151.164798 -28.25877)
		(end 151.455628 -28.5496)
		(width 0.1651)
		(layer "In7.Cu")
		(net "P5E_PEX1_STN2_RX_DN<40>")
	)
	(segment
		(start 166.820088 -271.467072)
		(end 166.820088 -275.275802)
		(width 0.1143)
		(layer "In7.Cu")
		(net "P5E_PEX1_STN2_RX_DN<40>")
	)
	(segment
		(start 157.431486 -37.688012)
		(end 157.416754 -38.576758)
		(width 0.1651)
		(layer "In7.Cu")
		(net "P5E_PEX1_STN2_RX_DN<40>")
	)
	(segment
		(start 297.701208 -121.0691)
		(end 297.403012 -121.367296)
		(width 0.13462)
		(layer "F.Cu")
		(net "P5E_PEX2_STN0_RX_DP<1>")
	)
	(segment
		(start 300.857412 -121.234962)
		(end 300.374812 -121.234962)
		(width 0.13462)
		(layer "F.Cu")
		(net "P5E_PEX2_STN0_RX_DP<1>")
	)
	(segment
		(start 300.374812 -121.234962)
		(end 300.20895 -121.0691)
		(width 0.13462)
		(layer "F.Cu")
		(net "P5E_PEX2_STN0_RX_DP<1>")
	)
	(segment
		(start 300.20895 -121.0691)
		(end 297.701208 -121.0691)
		(width 0.13462)
		(layer "F.Cu")
		(net "P5E_PEX2_STN0_RX_DP<1>")
	)
	(segment
		(start 309.083202 -127.694182)
		(end 308.75986 -127.319278)
		(width 0.1651)
		(layer "In5.Cu")
		(net "P5E_PEX2_STN0_RX_DP<1>")
	)
	(segment
		(start 309.397654 -128.19507)
		(end 309.074058 -127.819658)
		(width 0.1651)
		(layer "In5.Cu")
		(net "P5E_PEX2_STN0_RX_DP<1>")
	)
	(segment
		(start 315.17209 -133.37159)
		(end 314.743084 -132.942584)
		(width 0.1651)
		(layer "In5.Cu")
		(net "P5E_PEX2_STN0_RX_DP<1>")
	)
	(segment
		(start 320.54038 -149.910546)
		(end 320.28384 -146.3929)
		(width 0.1651)
		(layer "In5.Cu")
		(net "P5E_PEX2_STN0_RX_DP<1>")
	)
	(segment
		(start 307.547518 -126.049786)
		(end 307.556662 -125.924564)
		(width 0.1651)
		(layer "In5.Cu")
		(net "P5E_PEX2_STN0_RX_DP<1>")
	)
	(segment
		(start 314.294774 -286.779716)
		(end 316.075822 -286.779716)
		(width 0.1143)
		(layer "In5.Cu")
		(net "P5E_PEX2_STN0_RX_DP<1>")
	)
	(segment
		(start 314.743084 -132.942584)
		(end 312.582306 -131.751578)
		(width 0.1651)
		(layer "In5.Cu")
		(net "P5E_PEX2_STN0_RX_DP<1>")
	)
	(segment
		(start 330.615036 -269.313406)
		(end 321.839844 -239.260888)
		(width 0.1651)
		(layer "In5.Cu")
		(net "P5E_PEX2_STN0_RX_DP<1>")
	)
	(segment
		(start 316.075822 -286.779716)
		(end 316.121542 -286.733996)
		(width 0.1143)
		(layer "In5.Cu")
		(net "P5E_PEX2_STN0_RX_DP<1>")
	)
	(segment
		(start 321.839844 -239.260888)
		(end 320.385186 -232.123996)
		(width 0.1651)
		(layer "In5.Cu")
		(net "P5E_PEX2_STN0_RX_DP<1>")
	)
	(segment
		(start 328.052176 -277.634192)
		(end 330.467208 -273.294602)
		(width 0.1651)
		(layer "In5.Cu")
		(net "P5E_PEX2_STN0_RX_DP<1>")
	)
	(segment
		(start 299.75937 -121.076466)
		(end 297.693842 -121.076466)
		(width 0.1651)
		(layer "In5.Cu")
		(net "P5E_PEX2_STN0_RX_DP<1>")
	)
	(segment
		(start 300.735492 -121.606818)
		(end 300.278038 -121.416572)
		(width 0.1651)
		(layer "In5.Cu")
		(net "P5E_PEX2_STN0_RX_DP<1>")
	)
	(segment
		(start 316.121542 -286.733996)
		(end 316.14999 -286.733996)
		(width 0.1143)
		(layer "In5.Cu")
		(net "P5E_PEX2_STN0_RX_DP<1>")
	)
	(segment
		(start 312.582306 -131.751578)
		(end 309.52313 -128.204214)
		(width 0.1651)
		(layer "In5.Cu")
		(net "P5E_PEX2_STN0_RX_DP<1>")
	)
	(segment
		(start 307.99659 -126.434342)
		(end 307.871368 -126.425198)
		(width 0.1651)
		(layer "In5.Cu")
		(net "P5E_PEX2_STN0_RX_DP<1>")
	)
	(segment
		(start 313.965336 -287.349946)
		(end 314.079636 -287.235646)
		(width 0.1143)
		(layer "In5.Cu")
		(net "P5E_PEX2_STN0_RX_DP<1>")
	)
	(segment
		(start 300.885098 -121.54535)
		(end 300.735492 -121.606818)
		(width 0.1651)
		(layer "In5.Cu")
		(net "P5E_PEX2_STN0_RX_DP<1>")
	)
	(segment
		(start 302.010826 -122.014234)
		(end 301.86122 -122.075702)
		(width 0.1651)
		(layer "In5.Cu")
		(net "P5E_PEX2_STN0_RX_DP<1>")
	)
	(segment
		(start 302.529494 -122.354086)
		(end 302.468026 -122.20448)
		(width 0.1651)
		(layer "In5.Cu")
		(net "P5E_PEX2_STN0_RX_DP<1>")
	)
	(segment
		(start 301.403766 -121.885202)
		(end 301.342298 -121.735596)
		(width 0.1651)
		(layer "In5.Cu")
		(net "P5E_PEX2_STN0_RX_DP<1>")
	)
	(segment
		(start 309.52313 -128.204214)
		(end 309.397654 -128.19507)
		(width 0.1651)
		(layer "In5.Cu")
		(net "P5E_PEX2_STN0_RX_DP<1>")
	)
	(segment
		(start 314.079636 -286.994854)
		(end 314.294774 -286.779716)
		(width 0.1143)
		(layer "In5.Cu")
		(net "P5E_PEX2_STN0_RX_DP<1>")
	)
	(segment
		(start 319.500758 -285.886398)
		(end 328.052176 -277.634192)
		(width 0.1651)
		(layer "In5.Cu")
		(net "P5E_PEX2_STN0_RX_DP<1>")
	)
	(segment
		(start 320.385186 -232.123996)
		(end 321.04838 -168.536366)
		(width 0.1651)
		(layer "In5.Cu")
		(net "P5E_PEX2_STN0_RX_DP<1>")
	)
	(segment
		(start 317.412624 -134.61873)
		(end 315.17209 -133.37159)
		(width 0.1651)
		(layer "In5.Cu")
		(net "P5E_PEX2_STN0_RX_DP<1>")
	)
	(segment
		(start 308.319932 -126.809246)
		(end 307.99659 -126.434342)
		(width 0.1651)
		(layer "In5.Cu")
		(net "P5E_PEX2_STN0_RX_DP<1>")
	)
	(segment
		(start 302.468026 -122.20448)
		(end 302.010826 -122.014234)
		(width 0.1651)
		(layer "In5.Cu")
		(net "P5E_PEX2_STN0_RX_DP<1>")
	)
	(segment
		(start 321.04838 -168.536366)
		(end 320.54038 -149.910546)
		(width 0.1651)
		(layer "In5.Cu")
		(net "P5E_PEX2_STN0_RX_DP<1>")
	)
	(segment
		(start 313.699906 -287.349946)
		(end 313.965336 -287.349946)
		(width 0.1143)
		(layer "In5.Cu")
		(net "P5E_PEX2_STN0_RX_DP<1>")
	)
	(segment
		(start 304.262282 -122.951494)
		(end 304.112676 -123.013216)
		(width 0.1651)
		(layer "In5.Cu")
		(net "P5E_PEX2_STN0_RX_DP<1>")
	)
	(segment
		(start 320.28384 -146.3929)
		(end 317.871602 -135.332724)
		(width 0.1651)
		(layer "In5.Cu")
		(net "P5E_PEX2_STN0_RX_DP<1>")
	)
	(segment
		(start 307.093112 -125.386846)
		(end 304.897282 -123.215908)
		(width 0.1651)
		(layer "In5.Cu")
		(net "P5E_PEX2_STN0_RX_DP<1>")
	)
	(segment
		(start 308.634384 -127.310134)
		(end 308.310788 -126.934722)
		(width 0.1651)
		(layer "In5.Cu")
		(net "P5E_PEX2_STN0_RX_DP<1>")
	)
	(segment
		(start 297.693842 -121.076466)
		(end 297.403012 -121.367296)
		(width 0.1651)
		(layer "In5.Cu")
		(net "P5E_PEX2_STN0_RX_DP<1>")
	)
	(segment
		(start 303.136554 -122.482864)
		(end 302.986948 -122.544586)
		(width 0.1651)
		(layer "In5.Cu")
		(net "P5E_PEX2_STN0_RX_DP<1>")
	)
	(segment
		(start 307.556662 -125.924564)
		(end 307.093112 -125.386846)
		(width 0.1651)
		(layer "In5.Cu")
		(net "P5E_PEX2_STN0_RX_DP<1>")
	)
	(segment
		(start 330.467208 -273.294602)
		(end 330.615036 -269.313406)
		(width 0.1651)
		(layer "In5.Cu")
		(net "P5E_PEX2_STN0_RX_DP<1>")
	)
	(segment
		(start 307.871368 -126.425198)
		(end 307.547518 -126.049786)
		(width 0.1651)
		(layer "In5.Cu")
		(net "P5E_PEX2_STN0_RX_DP<1>")
	)
	(segment
		(start 308.75986 -127.319278)
		(end 308.634384 -127.310134)
		(width 0.1651)
		(layer "In5.Cu")
		(net "P5E_PEX2_STN0_RX_DP<1>")
	)
	(segment
		(start 317.871602 -135.332724)
		(end 317.412624 -134.61873)
		(width 0.1651)
		(layer "In5.Cu")
		(net "P5E_PEX2_STN0_RX_DP<1>")
	)
	(segment
		(start 303.655222 -122.822716)
		(end 303.593754 -122.67311)
		(width 0.1651)
		(layer "In5.Cu")
		(net "P5E_PEX2_STN0_RX_DP<1>")
	)
	(segment
		(start 304.112676 -123.013216)
		(end 303.655222 -122.822716)
		(width 0.1651)
		(layer "In5.Cu")
		(net "P5E_PEX2_STN0_RX_DP<1>")
	)
	(segment
		(start 318.120268 -286.733996)
		(end 319.500758 -285.886398)
		(width 0.1651)
		(layer "In5.Cu")
		(net "P5E_PEX2_STN0_RX_DP<1>")
	)
	(segment
		(start 300.21657 -121.266966)
		(end 299.75937 -121.076466)
		(width 0.1651)
		(layer "In5.Cu")
		(net "P5E_PEX2_STN0_RX_DP<1>")
	)
	(segment
		(start 301.342298 -121.735596)
		(end 300.885098 -121.54535)
		(width 0.1651)
		(layer "In5.Cu")
		(net "P5E_PEX2_STN0_RX_DP<1>")
	)
	(segment
		(start 301.86122 -122.075702)
		(end 301.403766 -121.885202)
		(width 0.1651)
		(layer "In5.Cu")
		(net "P5E_PEX2_STN0_RX_DP<1>")
	)
	(segment
		(start 300.278038 -121.416572)
		(end 300.21657 -121.266712)
		(width 0.1651)
		(layer "In5.Cu")
		(net "P5E_PEX2_STN0_RX_DP<1>")
	)
	(segment
		(start 303.593754 -122.67311)
		(end 303.136554 -122.482864)
		(width 0.1651)
		(layer "In5.Cu")
		(net "P5E_PEX2_STN0_RX_DP<1>")
	)
	(segment
		(start 304.897282 -123.215908)
		(end 304.262282 -122.951494)
		(width 0.1651)
		(layer "In5.Cu")
		(net "P5E_PEX2_STN0_RX_DP<1>")
	)
	(segment
		(start 316.14999 -286.733996)
		(end 318.120268 -286.733996)
		(width 0.1651)
		(layer "In5.Cu")
		(net "P5E_PEX2_STN0_RX_DP<1>")
	)
	(segment
		(start 302.986948 -122.544586)
		(end 302.529494 -122.354086)
		(width 0.1651)
		(layer "In5.Cu")
		(net "P5E_PEX2_STN0_RX_DP<1>")
	)
	(segment
		(start 314.079636 -287.235646)
		(end 314.079636 -286.994854)
		(width 0.1143)
		(layer "In5.Cu")
		(net "P5E_PEX2_STN0_RX_DP<1>")
	)
	(segment
		(start 300.21657 -121.266712)
		(end 300.21657 -121.266966)
		(width 0.1651)
		(layer "In5.Cu")
		(net "P5E_PEX2_STN0_RX_DP<1>")
	)
	(segment
		(start 308.310788 -126.934722)
		(end 308.319932 -126.809246)
		(width 0.1651)
		(layer "In5.Cu")
		(net "P5E_PEX2_STN0_RX_DP<1>")
	)
	(segment
		(start 309.074058 -127.819658)
		(end 309.083202 -127.694182)
		(width 0.1651)
		(layer "In5.Cu")
		(net "P5E_PEX2_STN0_RX_DP<1>")
	)
	(segment
		(start 400.258788 -112.19688)
		(end 399.573496 -112.19688)
		(width 0.13462)
		(layer "F.Cu")
		(net "P5E_PEX3_STN1_RX_DP<23>")
	)
	(segment
		(start 400.54276 -111.912908)
		(end 400.258788 -112.19688)
		(width 0.13462)
		(layer "F.Cu")
		(net "P5E_PEX3_STN1_RX_DP<23>")
	)
	(segment
		(start 399.573496 -112.19688)
		(end 399.421604 -112.044988)
		(width 0.13462)
		(layer "F.Cu")
		(net "P5E_PEX3_STN1_RX_DP<23>")
	)
	(segment
		(start 399.421604 -112.044988)
		(end 398.94256 -112.044988)
		(width 0.13462)
		(layer "F.Cu")
		(net "P5E_PEX3_STN1_RX_DP<23>")
	)
	(segment
		(start 389.745728 -128.369314)
		(end 388.282688 -137.393934)
		(width 0.1651)
		(layer "In5.Cu")
		(net "P5E_PEX3_STN1_RX_DP<23>")
	)
	(segment
		(start 383.378964 -151.208994)
		(end 383.611882 -154.781758)
		(width 0.1651)
		(layer "In5.Cu")
		(net "P5E_PEX3_STN1_RX_DP<23>")
	)
	(segment
		(start 400.54276 -111.912908)
		(end 400.25193 -112.203738)
		(width 0.1651)
		(layer "In5.Cu")
		(net "P5E_PEX3_STN1_RX_DP<23>")
	)
	(segment
		(start 399.566384 -112.203738)
		(end 395.31798 -113.941098)
		(width 0.1651)
		(layer "In5.Cu")
		(net "P5E_PEX3_STN1_RX_DP<23>")
	)
	(segment
		(start 384.505708 -145.064734)
		(end 383.94259 -148.135594)
		(width 0.1651)
		(layer "In5.Cu")
		(net "P5E_PEX3_STN1_RX_DP<23>")
	)
	(segment
		(start 414.244536 -275.570188)
		(end 414.485328 -275.570188)
		(width 0.1143)
		(layer "In5.Cu")
		(net "P5E_PEX3_STN1_RX_DP<23>")
	)
	(segment
		(start 413.983932 -271.570958)
		(end 413.983932 -271.599406)
		(width 0.1143)
		(layer "In5.Cu")
		(net "P5E_PEX3_STN1_RX_DP<23>")
	)
	(segment
		(start 414.485328 -275.570188)
		(end 414.599628 -275.684488)
		(width 0.1143)
		(layer "In5.Cu")
		(net "P5E_PEX3_STN1_RX_DP<23>")
	)
	(segment
		(start 413.983932 -271.599406)
		(end 414.029652 -271.645126)
		(width 0.1143)
		(layer "In5.Cu")
		(net "P5E_PEX3_STN1_RX_DP<23>")
	)
	(segment
		(start 388.282688 -137.393934)
		(end 386.292852 -140.990066)
		(width 0.1651)
		(layer "In5.Cu")
		(net "P5E_PEX3_STN1_RX_DP<23>")
	)
	(segment
		(start 414.029652 -271.645126)
		(end 414.029652 -275.355304)
		(width 0.1143)
		(layer "In5.Cu")
		(net "P5E_PEX3_STN1_RX_DP<23>")
	)
	(segment
		(start 413.983932 -268.60881)
		(end 413.983932 -271.570958)
		(width 0.1651)
		(layer "In5.Cu")
		(net "P5E_PEX3_STN1_RX_DP<23>")
	)
	(segment
		(start 383.611882 -154.781758)
		(end 383.84353 -158.33471)
		(width 0.1651)
		(layer "In5.Cu")
		(net "P5E_PEX3_STN1_RX_DP<23>")
	)
	(segment
		(start 393.24915 -116.962174)
		(end 391.39368 -120.951244)
		(width 0.1651)
		(layer "In5.Cu")
		(net "P5E_PEX3_STN1_RX_DP<23>")
	)
	(segment
		(start 395.31798 -113.941098)
		(end 394.517626 -114.704622)
		(width 0.1651)
		(layer "In5.Cu")
		(net "P5E_PEX3_STN1_RX_DP<23>")
	)
	(segment
		(start 391.39368 -120.951244)
		(end 389.745728 -128.369314)
		(width 0.1651)
		(layer "In5.Cu")
		(net "P5E_PEX3_STN1_RX_DP<23>")
	)
	(segment
		(start 394.517626 -114.704622)
		(end 393.906756 -116.017548)
		(width 0.1651)
		(layer "In5.Cu")
		(net "P5E_PEX3_STN1_RX_DP<23>")
	)
	(segment
		(start 384.83032 -164.093144)
		(end 413.983932 -268.60881)
		(width 0.1651)
		(layer "In5.Cu")
		(net "P5E_PEX3_STN1_RX_DP<23>")
	)
	(segment
		(start 383.84353 -158.33471)
		(end 384.83032 -164.093144)
		(width 0.1651)
		(layer "In5.Cu")
		(net "P5E_PEX3_STN1_RX_DP<23>")
	)
	(segment
		(start 414.029652 -275.355304)
		(end 414.244536 -275.570188)
		(width 0.1143)
		(layer "In5.Cu")
		(net "P5E_PEX3_STN1_RX_DP<23>")
	)
	(segment
		(start 400.25193 -112.203738)
		(end 399.566384 -112.203738)
		(width 0.1651)
		(layer "In5.Cu")
		(net "P5E_PEX3_STN1_RX_DP<23>")
	)
	(segment
		(start 383.94259 -148.135848)
		(end 383.378964 -151.208994)
		(width 0.1651)
		(layer "In5.Cu")
		(net "P5E_PEX3_STN1_RX_DP<23>")
	)
	(segment
		(start 386.292852 -140.990066)
		(end 384.505708 -145.064734)
		(width 0.1651)
		(layer "In5.Cu")
		(net "P5E_PEX3_STN1_RX_DP<23>")
	)
	(segment
		(start 383.94259 -148.135594)
		(end 383.94259 -148.135848)
		(width 0.1651)
		(layer "In5.Cu")
		(net "P5E_PEX3_STN1_RX_DP<23>")
	)
	(segment
		(start 414.599628 -275.684488)
		(end 414.599628 -275.949918)
		(width 0.1143)
		(layer "In5.Cu")
		(net "P5E_PEX3_STN1_RX_DP<23>")
	)
	(segment
		(start 393.906756 -116.017548)
		(end 393.24915 -116.962174)
		(width 0.1651)
		(layer "In5.Cu")
		(net "P5E_PEX3_STN1_RX_DP<23>")
	)
	(segment
		(start 402.629624 -319.888362)
		(end 402.629624 -316.455298)
		(width 0.1143)
		(layer "In5.Cu")
		(net "P5E_PEX3_STN6_RX_DP<99>")
	)
	(segment
		(start 402.583904 -319.96253)
		(end 402.583904 -319.934082)
		(width 0.1143)
		(layer "In5.Cu")
		(net "P5E_PEX3_STN6_RX_DP<99>")
	)
	(segment
		(start 402.328126 -321.293744)
		(end 402.583904 -320.722244)
		(width 0.1651)
		(layer "In5.Cu")
		(net "P5E_PEX3_STN6_RX_DP<99>")
	)
	(segment
		(start 383.194052 -366.432338)
		(end 383.032508 -366.426242)
		(width 0.1651)
		(layer "In5.Cu")
		(net "P5E_PEX3_STN6_RX_DP<99>")
	)
	(segment
		(start 381.535432 -364.644686)
		(end 381.373888 -364.63859)
		(width 0.1651)
		(layer "In5.Cu")
		(net "P5E_PEX3_STN6_RX_DP<99>")
	)
	(segment
		(start 381.86614 -365.169196)
		(end 381.872236 -365.007652)
		(width 0.1651)
		(layer "In5.Cu")
		(net "P5E_PEX3_STN6_RX_DP<99>")
	)
	(segment
		(start 385.166108 -374.570498)
		(end 385.166108 -368.55781)
		(width 0.1651)
		(layer "In5.Cu")
		(net "P5E_PEX3_STN6_RX_DP<99>")
	)
	(segment
		(start 400.505422 -323.558662)
		(end 402.328126 -321.293744)
		(width 0.1651)
		(layer "In5.Cu")
		(net "P5E_PEX3_STN6_RX_DP<99>")
	)
	(segment
		(start 382.701546 -365.901478)
		(end 382.364742 -365.538512)
		(width 0.1651)
		(layer "In5.Cu")
		(net "P5E_PEX3_STN6_RX_DP<99>")
	)
	(segment
		(start 385.166108 -368.55781)
		(end 383.194052 -366.432338)
		(width 0.1651)
		(layer "In5.Cu")
		(net "P5E_PEX3_STN6_RX_DP<99>")
	)
	(segment
		(start 403.085554 -316.229492)
		(end 403.199854 -316.115192)
		(width 0.1143)
		(layer "In5.Cu")
		(net "P5E_PEX3_STN6_RX_DP<99>")
	)
	(segment
		(start 384.46329 -374.902984)
		(end 384.833622 -374.902984)
		(width 0.1651)
		(layer "In5.Cu")
		(net "P5E_PEX3_STN6_RX_DP<99>")
	)
	(segment
		(start 402.85543 -316.229492)
		(end 403.085554 -316.229492)
		(width 0.1143)
		(layer "In5.Cu")
		(net "P5E_PEX3_STN6_RX_DP<99>")
	)
	(segment
		(start 381.373888 -364.63859)
		(end 381.03683 -364.27537)
		(width 0.1651)
		(layer "In5.Cu")
		(net "P5E_PEX3_STN6_RX_DP<99>")
	)
	(segment
		(start 381.872236 -365.007652)
		(end 381.535432 -364.644686)
		(width 0.1651)
		(layer "In5.Cu")
		(net "P5E_PEX3_STN6_RX_DP<99>")
	)
	(segment
		(start 382.364742 -365.538512)
		(end 382.203198 -365.532416)
		(width 0.1651)
		(layer "In5.Cu")
		(net "P5E_PEX3_STN6_RX_DP<99>")
	)
	(segment
		(start 402.629624 -316.455298)
		(end 402.85543 -316.229492)
		(width 0.1143)
		(layer "In5.Cu")
		(net "P5E_PEX3_STN6_RX_DP<99>")
	)
	(segment
		(start 382.203198 -365.532416)
		(end 381.86614 -365.169196)
		(width 0.1651)
		(layer "In5.Cu")
		(net "P5E_PEX3_STN6_RX_DP<99>")
	)
	(segment
		(start 402.583904 -319.934082)
		(end 402.629624 -319.888362)
		(width 0.1143)
		(layer "In5.Cu")
		(net "P5E_PEX3_STN6_RX_DP<99>")
	)
	(segment
		(start 376.14225 -358.831896)
		(end 376.14225 -341.833708)
		(width 0.1651)
		(layer "In5.Cu")
		(net "P5E_PEX3_STN6_RX_DP<99>")
	)
	(segment
		(start 376.14225 -341.833708)
		(end 376.694954 -341.162894)
		(width 0.1651)
		(layer "In5.Cu")
		(net "P5E_PEX3_STN6_RX_DP<99>")
	)
	(segment
		(start 384.833622 -374.902984)
		(end 385.166108 -374.570498)
		(width 0.1651)
		(layer "In5.Cu")
		(net "P5E_PEX3_STN6_RX_DP<99>")
	)
	(segment
		(start 381.042926 -364.113826)
		(end 376.14225 -358.831896)
		(width 0.1651)
		(layer "In5.Cu")
		(net "P5E_PEX3_STN6_RX_DP<99>")
	)
	(segment
		(start 384.290062 -374.729756)
		(end 384.46329 -374.902984)
		(width 0.1651)
		(layer "In5.Cu")
		(net "P5E_PEX3_STN6_RX_DP<99>")
	)
	(segment
		(start 382.69545 -366.063022)
		(end 382.701546 -365.901478)
		(width 0.1651)
		(layer "In5.Cu")
		(net "P5E_PEX3_STN6_RX_DP<99>")
	)
	(segment
		(start 403.199854 -316.115192)
		(end 403.199854 -315.849762)
		(width 0.1143)
		(layer "In5.Cu")
		(net "P5E_PEX3_STN6_RX_DP<99>")
	)
	(segment
		(start 402.583904 -320.722244)
		(end 402.583904 -319.96253)
		(width 0.1651)
		(layer "In5.Cu")
		(net "P5E_PEX3_STN6_RX_DP<99>")
	)
	(segment
		(start 376.694954 -341.162894)
		(end 400.505422 -323.558662)
		(width 0.1651)
		(layer "In5.Cu")
		(net "P5E_PEX3_STN6_RX_DP<99>")
	)
	(segment
		(start 383.032508 -366.426242)
		(end 382.69545 -366.063022)
		(width 0.1651)
		(layer "In5.Cu")
		(net "P5E_PEX3_STN6_RX_DP<99>")
	)
	(segment
		(start 381.03683 -364.27537)
		(end 381.042926 -364.113826)
		(width 0.1651)
		(layer "In5.Cu")
		(net "P5E_PEX3_STN6_RX_DP<99>")
	)
	(segment
		(start 384.290062 -374.390158)
		(end 384.290062 -374.729756)
		(width 0.1651)
		(layer "In5.Cu")
		(net "P5E_PEX3_STN6_RX_DP<99>")
	)
	(segment
		(start 183.3626 -97.663)
		(end 183.38546 -97.64014)
		(width 0.13208)
		(layer "F.Cu")
		(net "RST_NIC3_PERST3_R_N")
	)
	(segment
		(start 175.49495 -97.718372)
		(end 182.027068 -97.718372)
		(width 0.13208)
		(layer "F.Cu")
		(net "RST_NIC3_PERST3_R_N")
	)
	(segment
		(start 183.33974 -97.64014)
		(end 183.3626 -97.663)
		(width 0.13208)
		(layer "F.Cu")
		(net "RST_NIC3_PERST3_R_N")
	)
	(segment
		(start 183.38546 -97.64014)
		(end 184.757314 -97.64014)
		(width 0.13208)
		(layer "F.Cu")
		(net "RST_NIC3_PERST3_R_N")
	)
	(segment
		(start 182.1053 -97.64014)
		(end 183.33974 -97.64014)
		(width 0.13208)
		(layer "F.Cu")
		(net "RST_NIC3_PERST3_R_N")
	)
	(segment
		(start 182.027068 -97.718372)
		(end 182.1053 -97.64014)
		(width 0.13208)
		(layer "F.Cu")
		(net "RST_NIC3_PERST3_R_N")
	)
	(via
		(at 183.3626 -97.663)
		(size 0.508)
		(drill 0.254)
		(layers "F.Cu" "B.Cu")
		(net "RST_NIC3_PERST3_R_N")
	)
	(segment
		(start 88.019382 -28.55468)
		(end 87.360506 -28.55468)
		(width 0.13462)
		(layer "F.Cu")
		(net "P5E_PEX0_STN2_RX_DN<32>")
	)
	(segment
		(start 87.360506 -28.55468)
		(end 87.064596 -28.25877)
		(width 0.13462)
		(layer "F.Cu")
		(net "P5E_PEX0_STN2_RX_DN<32>")
	)
	(segment
		(start 88.664796 -28.390088)
		(end 88.183974 -28.390088)
		(width 0.13462)
		(layer "F.Cu")
		(net "P5E_PEX0_STN2_RX_DN<32>")
	)
	(segment
		(start 88.183974 -28.390088)
		(end 88.019382 -28.55468)
		(width 0.13462)
		(layer "F.Cu")
		(net "P5E_PEX0_STN2_RX_DN<32>")
	)
	(segment
		(start 58.776362 -266.734544)
		(end 78.262988 -154.841448)
		(width 0.1651)
		(layer "In7.Cu")
		(net "P5E_PEX0_STN2_RX_DN<32>")
	)
	(segment
		(start 58.699908 -275.265388)
		(end 58.585608 -275.379688)
		(width 0.1143)
		(layer "In7.Cu")
		(net "P5E_PEX0_STN2_RX_DN<32>")
	)
	(segment
		(start 91.1606 -49.41951)
		(end 93.139768 -39.96563)
		(width 0.1651)
		(layer "In7.Cu")
		(net "P5E_PEX0_STN2_RX_DN<32>")
	)
	(segment
		(start 87.355426 -28.5496)
		(end 87.064596 -28.25877)
		(width 0.1651)
		(layer "In7.Cu")
		(net "P5E_PEX0_STN2_RX_DN<32>")
	)
	(segment
		(start 90.974926 -61.310012)
		(end 91.1606 -49.41951)
		(width 0.1651)
		(layer "In7.Cu")
		(net "P5E_PEX0_STN2_RX_DN<32>")
	)
	(segment
		(start 93.354398 -38.052248)
		(end 93.244162 -37.481256)
		(width 0.1651)
		(layer "In7.Cu")
		(net "P5E_PEX0_STN2_RX_DN<32>")
	)
	(segment
		(start 78.262988 -154.841448)
		(end 79.652114 -144.057878)
		(width 0.1651)
		(layer "In7.Cu")
		(net "P5E_PEX0_STN2_RX_DN<32>")
	)
	(segment
		(start 58.42381 -275.379688)
		(end 58.319924 -275.275802)
		(width 0.1143)
		(layer "In7.Cu")
		(net "P5E_PEX0_STN2_RX_DN<32>")
	)
	(segment
		(start 58.365644 -270.191992)
		(end 58.542682 -269.42669)
		(width 0.1651)
		(layer "In7.Cu")
		(net "P5E_PEX0_STN2_RX_DN<32>")
	)
	(segment
		(start 58.365644 -271.421352)
		(end 58.365644 -271.392904)
		(width 0.1143)
		(layer "In7.Cu")
		(net "P5E_PEX0_STN2_RX_DN<32>")
	)
	(segment
		(start 58.776108 -266.734544)
		(end 58.776362 -266.734544)
		(width 0.1651)
		(layer "In7.Cu")
		(net "P5E_PEX0_STN2_RX_DN<32>")
	)
	(segment
		(start 90.551762 -31.090362)
		(end 88.011 -28.5496)
		(width 0.1651)
		(layer "In7.Cu")
		(net "P5E_PEX0_STN2_RX_DN<32>")
	)
	(segment
		(start 93.244162 -37.481256)
		(end 90.551762 -31.090362)
		(width 0.1651)
		(layer "In7.Cu")
		(net "P5E_PEX0_STN2_RX_DN<32>")
	)
	(segment
		(start 88.011 -28.5496)
		(end 87.355426 -28.5496)
		(width 0.1651)
		(layer "In7.Cu")
		(net "P5E_PEX0_STN2_RX_DN<32>")
	)
	(segment
		(start 58.365644 -271.392904)
		(end 58.365644 -270.191992)
		(width 0.1651)
		(layer "In7.Cu")
		(net "P5E_PEX0_STN2_RX_DN<32>")
	)
	(segment
		(start 58.699908 -274.999958)
		(end 58.699908 -275.265388)
		(width 0.1143)
		(layer "In7.Cu")
		(net "P5E_PEX0_STN2_RX_DN<32>")
	)
	(segment
		(start 93.139768 -39.96563)
		(end 93.354398 -38.052248)
		(width 0.1651)
		(layer "In7.Cu")
		(net "P5E_PEX0_STN2_RX_DN<32>")
	)
	(segment
		(start 79.652114 -144.057878)
		(end 79.967074 -116.791232)
		(width 0.1651)
		(layer "In7.Cu")
		(net "P5E_PEX0_STN2_RX_DN<32>")
	)
	(segment
		(start 58.542682 -269.42669)
		(end 58.776108 -266.734544)
		(width 0.1651)
		(layer "In7.Cu")
		(net "P5E_PEX0_STN2_RX_DN<32>")
	)
	(segment
		(start 58.319924 -275.275802)
		(end 58.319924 -271.467072)
		(width 0.1143)
		(layer "In7.Cu")
		(net "P5E_PEX0_STN2_RX_DN<32>")
	)
	(segment
		(start 58.585608 -275.379688)
		(end 58.42381 -275.379688)
		(width 0.1143)
		(layer "In7.Cu")
		(net "P5E_PEX0_STN2_RX_DN<32>")
	)
	(segment
		(start 58.319924 -271.467072)
		(end 58.365644 -271.421352)
		(width 0.1143)
		(layer "In7.Cu")
		(net "P5E_PEX0_STN2_RX_DN<32>")
	)
	(segment
		(start 79.967074 -116.791232)
		(end 90.974926 -61.310012)
		(width 0.1651)
		(layer "In7.Cu")
		(net "P5E_PEX0_STN2_RX_DN<32>")
	)
	(segment
		(start 132.025644 -28.829)
		(end 131.864608 -28.990036)
		(width 0.13462)
		(layer "F.Cu")
		(net "P5E_PEX1_STN2_TX_C_DP<44>")
	)
	(segment
		(start 133.625844 -29.139642)
		(end 133.315202 -28.829)
		(width 0.13462)
		(layer "F.Cu")
		(net "P5E_PEX1_STN2_TX_C_DP<44>")
	)
	(segment
		(start 133.315202 -28.829)
		(end 132.025644 -28.829)
		(width 0.13462)
		(layer "F.Cu")
		(net "P5E_PEX1_STN2_TX_C_DP<44>")
	)
	(segment
		(start 131.864608 -28.990036)
		(end 131.36499 -28.990036)
		(width 0.13462)
		(layer "F.Cu")
		(net "P5E_PEX1_STN2_TX_C_DP<44>")
	)
	(segment
		(start 306.11826 -124.38888)
		(end 305.964336 -124.234956)
		(width 0.13462)
		(layer "F.Cu")
		(net "P5E_PEX2_STN0_TX_C_DN<3>")
	)
	(segment
		(start 314.282582 -124.38888)
		(end 306.11826 -124.38888)
		(width 0.13462)
		(layer "F.Cu")
		(net "P5E_PEX2_STN0_TX_C_DN<3>")
	)
	(segment
		(start 305.964336 -124.234956)
		(end 305.457606 -124.234956)
		(width 0.13462)
		(layer "F.Cu")
		(net "P5E_PEX2_STN0_TX_C_DN<3>")
	)
	(segment
		(start 314.594748 -124.076714)
		(end 314.282582 -124.38888)
		(width 0.13462)
		(layer "F.Cu")
		(net "P5E_PEX2_STN0_TX_C_DN<3>")
	)
	(segment
		(start 400.250152 -121.31548)
		(end 399.582132 -121.31548)
		(width 0.13462)
		(layer "F.Cu")
		(net "P5E_PEX3_STN1_RX_DP<25>")
	)
	(segment
		(start 400.54276 -121.022872)
		(end 400.250152 -121.31548)
		(width 0.13462)
		(layer "F.Cu")
		(net "P5E_PEX3_STN1_RX_DP<25>")
	)
	(segment
		(start 399.421604 -121.154952)
		(end 398.94256 -121.154952)
		(width 0.13462)
		(layer "F.Cu")
		(net "P5E_PEX3_STN1_RX_DP<25>")
	)
	(segment
		(start 399.582132 -121.31548)
		(end 399.421604 -121.154952)
		(width 0.13462)
		(layer "F.Cu")
		(net "P5E_PEX3_STN1_RX_DP<25>")
	)
	(segment
		(start 386.587492 -145.587212)
		(end 386.150866 -147.266914)
		(width 0.1651)
		(layer "In5.Cu")
		(net "P5E_PEX3_STN1_RX_DP<25>")
	)
	(segment
		(start 400.25193 -121.313702)
		(end 400.032474 -121.313702)
		(width 0.1651)
		(layer "In5.Cu")
		(net "P5E_PEX3_STN1_RX_DP<25>")
	)
	(segment
		(start 386.150866 -147.266914)
		(end 386.153406 -147.311364)
		(width 0.1651)
		(layer "In5.Cu")
		(net "P5E_PEX3_STN1_RX_DP<25>")
	)
	(segment
		(start 387.705346 -162.425888)
		(end 415.883852 -268.07414)
		(width 0.1651)
		(layer "In5.Cu")
		(net "P5E_PEX3_STN1_RX_DP<25>")
	)
	(segment
		(start 386.153406 -147.311364)
		(end 386.15366 -147.311364)
		(width 0.1651)
		(layer "In5.Cu")
		(net "P5E_PEX3_STN1_RX_DP<25>")
	)
	(segment
		(start 416.144456 -275.569934)
		(end 416.385248 -275.569934)
		(width 0.1143)
		(layer "In5.Cu")
		(net "P5E_PEX3_STN1_RX_DP<25>")
	)
	(segment
		(start 400.54276 -121.022872)
		(end 400.25193 -121.313702)
		(width 0.1651)
		(layer "In5.Cu")
		(net "P5E_PEX3_STN1_RX_DP<25>")
	)
	(segment
		(start 416.385248 -275.569934)
		(end 416.499548 -275.684234)
		(width 0.1143)
		(layer "In5.Cu")
		(net "P5E_PEX3_STN1_RX_DP<25>")
	)
	(segment
		(start 391.792714 -128.887982)
		(end 390.221724 -137.931144)
		(width 0.1651)
		(layer "In5.Cu")
		(net "P5E_PEX3_STN1_RX_DP<25>")
	)
	(segment
		(start 394.076428 -125.831854)
		(end 391.981182 -128.458722)
		(width 0.1651)
		(layer "In5.Cu")
		(net "P5E_PEX3_STN1_RX_DP<25>")
	)
	(segment
		(start 415.929572 -271.644872)
		(end 415.929572 -275.35505)
		(width 0.1143)
		(layer "In5.Cu")
		(net "P5E_PEX3_STN1_RX_DP<25>")
	)
	(segment
		(start 386.763768 -157.255972)
		(end 387.705346 -162.425888)
		(width 0.1651)
		(layer "In5.Cu")
		(net "P5E_PEX3_STN1_RX_DP<25>")
	)
	(segment
		(start 415.883852 -271.599152)
		(end 415.929572 -271.644872)
		(width 0.1143)
		(layer "In5.Cu")
		(net "P5E_PEX3_STN1_RX_DP<25>")
	)
	(segment
		(start 386.15366 -147.311364)
		(end 386.763768 -157.255972)
		(width 0.1651)
		(layer "In5.Cu")
		(net "P5E_PEX3_STN1_RX_DP<25>")
	)
	(segment
		(start 415.929572 -275.35505)
		(end 416.144456 -275.569934)
		(width 0.1143)
		(layer "In5.Cu")
		(net "P5E_PEX3_STN1_RX_DP<25>")
	)
	(segment
		(start 400.032474 -121.313702)
		(end 398.287494 -122.009662)
		(width 0.1651)
		(layer "In5.Cu")
		(net "P5E_PEX3_STN1_RX_DP<25>")
	)
	(segment
		(start 390.221724 -137.931144)
		(end 388.87527 -142.635986)
		(width 0.1651)
		(layer "In5.Cu")
		(net "P5E_PEX3_STN1_RX_DP<25>")
	)
	(segment
		(start 388.87527 -142.635986)
		(end 386.587492 -145.587212)
		(width 0.1651)
		(layer "In5.Cu")
		(net "P5E_PEX3_STN1_RX_DP<25>")
	)
	(segment
		(start 415.883852 -271.570704)
		(end 415.883852 -271.599152)
		(width 0.1143)
		(layer "In5.Cu")
		(net "P5E_PEX3_STN1_RX_DP<25>")
	)
	(segment
		(start 416.499548 -275.684234)
		(end 416.499548 -275.949664)
		(width 0.1143)
		(layer "In5.Cu")
		(net "P5E_PEX3_STN1_RX_DP<25>")
	)
	(segment
		(start 391.981182 -128.458722)
		(end 391.792714 -128.887982)
		(width 0.1651)
		(layer "In5.Cu")
		(net "P5E_PEX3_STN1_RX_DP<25>")
	)
	(segment
		(start 415.883852 -268.07414)
		(end 415.883852 -271.570704)
		(width 0.1651)
		(layer "In5.Cu")
		(net "P5E_PEX3_STN1_RX_DP<25>")
	)
	(segment
		(start 398.287494 -122.009662)
		(end 394.076428 -125.831854)
		(width 0.1651)
		(layer "In5.Cu")
		(net "P5E_PEX3_STN1_RX_DP<25>")
	)
	(segment
		(start 377.975368 -345.171014)
		(end 378.2695 -345.465146)
		(width 0.13462)
		(layer "F.Cu")
		(net "P5E_PEX3_STN6_TX_C_DN<109>")
	)
	(segment
		(start 378.2949 -344.219022)
		(end 377.975368 -344.538554)
		(width 0.13462)
		(layer "F.Cu")
		(net "P5E_PEX3_STN6_TX_C_DN<109>")
	)
	(segment
		(start 377.975368 -344.538554)
		(end 377.975368 -345.171014)
		(width 0.13462)
		(layer "F.Cu")
		(net "P5E_PEX3_STN6_TX_C_DN<109>")
	)
	(segment
		(start 369.016534 -373.359172)
		(end 369.599972 -367.449862)
		(width 0.1651)
		(layer "In13.Cu")
		(net "P5E_PEX3_STN6_TX_C_DN<109>")
	)
	(segment
		(start 375.86285 -359.5116)
		(end 376.42419 -358.036114)
		(width 0.1651)
		(layer "In13.Cu")
		(net "P5E_PEX3_STN6_TX_C_DN<109>")
	)
	(segment
		(start 379.89002 -409.490164)
		(end 379.89002 -409.108148)
		(width 0.1651)
		(layer "In13.Cu")
		(net "P5E_PEX3_STN6_TX_C_DN<109>")
	)
	(segment
		(start 377.97867 -345.755976)
		(end 378.2695 -345.465146)
		(width 0.1651)
		(layer "In13.Cu")
		(net "P5E_PEX3_STN6_TX_C_DN<109>")
	)
	(segment
		(start 376.42419 -358.036114)
		(end 376.42419 -347.881194)
		(width 0.1651)
		(layer "In13.Cu")
		(net "P5E_PEX3_STN6_TX_C_DN<109>")
	)
	(segment
		(start 381.016002 -408.529282)
		(end 381.016002 -395.097)
		(width 0.1651)
		(layer "In13.Cu")
		(net "P5E_PEX3_STN6_TX_C_DN<109>")
	)
	(segment
		(start 379.89002 -409.108148)
		(end 380.01702 -408.981148)
		(width 0.1651)
		(layer "In13.Cu")
		(net "P5E_PEX3_STN6_TX_C_DN<109>")
	)
	(segment
		(start 380.564136 -408.981148)
		(end 381.016002 -408.529282)
		(width 0.1651)
		(layer "In13.Cu")
		(net "P5E_PEX3_STN6_TX_C_DN<109>")
	)
	(segment
		(start 371.968268 -363.89056)
		(end 375.86285 -359.5116)
		(width 0.1651)
		(layer "In13.Cu")
		(net "P5E_PEX3_STN6_TX_C_DN<109>")
	)
	(segment
		(start 375.832878 -391.6426)
		(end 373.763794 -390.760458)
		(width 0.1651)
		(layer "In13.Cu")
		(net "P5E_PEX3_STN6_TX_C_DN<109>")
	)
	(segment
		(start 369.525042 -385.680458)
		(end 369.016534 -373.359172)
		(width 0.1651)
		(layer "In13.Cu")
		(net "P5E_PEX3_STN6_TX_C_DN<109>")
	)
	(segment
		(start 380.01702 -408.981148)
		(end 380.564136 -408.981148)
		(width 0.1651)
		(layer "In13.Cu")
		(net "P5E_PEX3_STN6_TX_C_DN<109>")
	)
	(segment
		(start 376.42419 -347.881194)
		(end 377.97867 -346.326714)
		(width 0.1651)
		(layer "In13.Cu")
		(net "P5E_PEX3_STN6_TX_C_DN<109>")
	)
	(segment
		(start 381.016002 -395.097)
		(end 380.740158 -394.579348)
		(width 0.1651)
		(layer "In13.Cu")
		(net "P5E_PEX3_STN6_TX_C_DN<109>")
	)
	(segment
		(start 380.740158 -394.579348)
		(end 375.832878 -391.6426)
		(width 0.1651)
		(layer "In13.Cu")
		(net "P5E_PEX3_STN6_TX_C_DN<109>")
	)
	(segment
		(start 377.97867 -346.326714)
		(end 377.97867 -345.755976)
		(width 0.1651)
		(layer "In13.Cu")
		(net "P5E_PEX3_STN6_TX_C_DN<109>")
	)
	(segment
		(start 370.65966 -388.461504)
		(end 369.525042 -385.680458)
		(width 0.1651)
		(layer "In13.Cu")
		(net "P5E_PEX3_STN6_TX_C_DN<109>")
	)
	(segment
		(start 373.763794 -390.760458)
		(end 370.65966 -388.461504)
		(width 0.1651)
		(layer "In13.Cu")
		(net "P5E_PEX3_STN6_TX_C_DN<109>")
	)
	(segment
		(start 369.599972 -367.449862)
		(end 371.968268 -363.89056)
		(width 0.1651)
		(layer "In13.Cu")
		(net "P5E_PEX3_STN6_TX_C_DN<109>")
	)
	(segment
		(start 183.75376 -101.240082)
		(end 184.757314 -101.240082)
		(width 0.13208)
		(layer "F.Cu")
		(net "NCSI_NIC3_TXD1")
	)
	(segment
		(start 175.49495 -102.798372)
		(end 181.141624 -102.798372)
		(width 0.13208)
		(layer "F.Cu")
		(net "NCSI_NIC3_TXD1")
	)
	(segment
		(start 181.141624 -102.798372)
		(end 182.699914 -101.240082)
		(width 0.13208)
		(layer "F.Cu")
		(net "NCSI_NIC3_TXD1")
	)
	(segment
		(start 182.699914 -101.240082)
		(end 183.75376 -101.240082)
		(width 0.13208)
		(layer "F.Cu")
		(net "NCSI_NIC3_TXD1")
	)
	(via
		(at 183.75376 -101.240082)
		(size 0.508)
		(drill 0.254)
		(layers "F.Cu" "B.Cu")
		(net "NCSI_NIC3_TXD1")
	)
	(segment
		(start 123.604782 -33.952942)
		(end 123.31065 -33.65881)
		(width 0.13462)
		(layer "F.Cu")
		(net "P5E_PEX1_STN2_RX_DN<47>")
	)
	(segment
		(start 126.28753 -33.790128)
		(end 126.124716 -33.952942)
		(width 0.13462)
		(layer "F.Cu")
		(net "P5E_PEX1_STN2_RX_DN<47>")
	)
	(segment
		(start 126.76505 -33.790128)
		(end 126.28753 -33.790128)
		(width 0.13462)
		(layer "F.Cu")
		(net "P5E_PEX1_STN2_RX_DN<47>")
	)
	(segment
		(start 126.124716 -33.952942)
		(end 123.604782 -33.952942)
		(width 0.13462)
		(layer "F.Cu")
		(net "P5E_PEX1_STN2_RX_DN<47>")
	)
	(segment
		(start 159.235394 -263.578594)
		(end 159.235394 -262.327898)
		(width 0.1651)
		(layer "In7.Cu")
		(net "P5E_PEX1_STN2_RX_DN<47>")
	)
	(segment
		(start 159.235394 -262.327898)
		(end 159.30118 -255.61163)
		(width 0.1651)
		(layer "In7.Cu")
		(net "P5E_PEX1_STN2_RX_DN<47>")
	)
	(segment
		(start 131.53644 -102.744524)
		(end 126.33198 -85.574378)
		(width 0.1651)
		(layer "In7.Cu")
		(net "P5E_PEX1_STN2_RX_DN<47>")
	)
	(segment
		(start 126.249938 -57.243218)
		(end 126.365508 -49.854612)
		(width 0.1651)
		(layer "In7.Cu")
		(net "P5E_PEX1_STN2_RX_DN<47>")
	)
	(segment
		(start 123.60148 -33.94964)
		(end 123.31065 -33.65881)
		(width 0.1651)
		(layer "In7.Cu")
		(net "P5E_PEX1_STN2_RX_DN<47>")
	)
	(segment
		(start 123.952 -33.94964)
		(end 123.60148 -33.94964)
		(width 0.1651)
		(layer "In7.Cu")
		(net "P5E_PEX1_STN2_RX_DN<47>")
	)
	(segment
		(start 126.365508 -49.854612)
		(end 125.063758 -40.2209)
		(width 0.1651)
		(layer "In7.Cu")
		(net "P5E_PEX1_STN2_RX_DN<47>")
	)
	(segment
		(start 160.549844 -273.099784)
		(end 160.549844 -273.365214)
		(width 0.1143)
		(layer "In7.Cu")
		(net "P5E_PEX1_STN2_RX_DN<47>")
	)
	(segment
		(start 160.170114 -271.41932)
		(end 160.215834 -271.3736)
		(width 0.1143)
		(layer "In7.Cu")
		(net "P5E_PEX1_STN2_RX_DN<47>")
	)
	(segment
		(start 131.536694 -102.745032)
		(end 131.53644 -102.744524)
		(width 0.1651)
		(layer "In7.Cu")
		(net "P5E_PEX1_STN2_RX_DN<47>")
	)
	(segment
		(start 159.648652 -267.026644)
		(end 159.235394 -263.578594)
		(width 0.1651)
		(layer "In7.Cu")
		(net "P5E_PEX1_STN2_RX_DN<47>")
	)
	(segment
		(start 160.435544 -273.479514)
		(end 160.32099 -273.479514)
		(width 0.1143)
		(layer "In7.Cu")
		(net "P5E_PEX1_STN2_RX_DN<47>")
	)
	(segment
		(start 125.063758 -40.2209)
		(end 124.98832 -35.355276)
		(width 0.1651)
		(layer "In7.Cu")
		(net "P5E_PEX1_STN2_RX_DN<47>")
	)
	(segment
		(start 160.017968 -268.824202)
		(end 159.648652 -267.026644)
		(width 0.1651)
		(layer "In7.Cu")
		(net "P5E_PEX1_STN2_RX_DN<47>")
	)
	(segment
		(start 160.170114 -273.328638)
		(end 160.170114 -271.41932)
		(width 0.1143)
		(layer "In7.Cu")
		(net "P5E_PEX1_STN2_RX_DN<47>")
	)
	(segment
		(start 126.521464 -60.243212)
		(end 126.249938 -57.243218)
		(width 0.1651)
		(layer "In7.Cu")
		(net "P5E_PEX1_STN2_RX_DN<47>")
	)
	(segment
		(start 160.32099 -273.479514)
		(end 160.170114 -273.328638)
		(width 0.1143)
		(layer "In7.Cu")
		(net "P5E_PEX1_STN2_RX_DN<47>")
	)
	(segment
		(start 126.521464 -62.60846)
		(end 126.521464 -60.243212)
		(width 0.1651)
		(layer "In7.Cu")
		(net "P5E_PEX1_STN2_RX_DN<47>")
	)
	(segment
		(start 136.7409 -119.914416)
		(end 131.536694 -102.745032)
		(width 0.1651)
		(layer "In7.Cu")
		(net "P5E_PEX1_STN2_RX_DN<47>")
	)
	(segment
		(start 124.98832 -34.98596)
		(end 123.952 -33.94964)
		(width 0.1651)
		(layer "In7.Cu")
		(net "P5E_PEX1_STN2_RX_DN<47>")
	)
	(segment
		(start 157.728412 -238.434118)
		(end 139.994894 -144.65427)
		(width 0.1651)
		(layer "In7.Cu")
		(net "P5E_PEX1_STN2_RX_DN<47>")
	)
	(segment
		(start 159.30118 -255.61163)
		(end 157.728412 -238.434118)
		(width 0.1651)
		(layer "In7.Cu")
		(net "P5E_PEX1_STN2_RX_DN<47>")
	)
	(segment
		(start 124.98832 -35.355276)
		(end 124.98832 -34.98596)
		(width 0.1651)
		(layer "In7.Cu")
		(net "P5E_PEX1_STN2_RX_DN<47>")
	)
	(segment
		(start 160.549844 -273.365214)
		(end 160.435544 -273.479514)
		(width 0.1143)
		(layer "In7.Cu")
		(net "P5E_PEX1_STN2_RX_DN<47>")
	)
	(segment
		(start 160.215834 -271.345152)
		(end 160.215834 -270.472916)
		(width 0.1651)
		(layer "In7.Cu")
		(net "P5E_PEX1_STN2_RX_DN<47>")
	)
	(segment
		(start 160.215834 -271.3736)
		(end 160.215834 -271.345152)
		(width 0.1143)
		(layer "In7.Cu")
		(net "P5E_PEX1_STN2_RX_DN<47>")
	)
	(segment
		(start 126.33198 -85.574378)
		(end 126.521464 -62.60846)
		(width 0.1651)
		(layer "In7.Cu")
		(net "P5E_PEX1_STN2_RX_DN<47>")
	)
	(segment
		(start 139.994894 -144.65427)
		(end 136.7409 -119.914416)
		(width 0.1651)
		(layer "In7.Cu")
		(net "P5E_PEX1_STN2_RX_DN<47>")
	)
	(segment
		(start 160.215834 -270.472916)
		(end 160.017968 -268.824202)
		(width 0.1651)
		(layer "In7.Cu")
		(net "P5E_PEX1_STN2_RX_DN<47>")
	)
	(segment
		(start 299.257212 -142.62354)
		(end 299.539152 -142.90548)
		(width 0.13462)
		(layer "F.Cu")
		(net "P5E_PEX2_STN0_RX_DN<8>")
	)
	(segment
		(start 299.539152 -142.90548)
		(end 300.225968 -142.90548)
		(width 0.13462)
		(layer "F.Cu")
		(net "P5E_PEX2_STN0_RX_DN<8>")
	)
	(segment
		(start 300.225968 -142.90548)
		(end 300.376336 -142.755112)
		(width 0.13462)
		(layer "F.Cu")
		(net "P5E_PEX2_STN0_RX_DN<8>")
	)
	(segment
		(start 300.376336 -142.755112)
		(end 300.857412 -142.755112)
		(width 0.13462)
		(layer "F.Cu")
		(net "P5E_PEX2_STN0_RX_DN<8>")
	)
	(segment
		(start 314.744354 -270.75384)
		(end 314.08497 -265.20775)
		(width 0.1651)
		(layer "In5.Cu")
		(net "P5E_PEX2_STN0_RX_DN<8>")
	)
	(segment
		(start 314.270136 -273.90852)
		(end 314.315856 -273.8628)
		(width 0.1143)
		(layer "In5.Cu")
		(net "P5E_PEX2_STN0_RX_DN<8>")
	)
	(segment
		(start 310.472836 -160.610042)
		(end 310.37403 -159.983424)
		(width 0.1651)
		(layer "In5.Cu")
		(net "P5E_PEX2_STN0_RX_DN<8>")
	)
	(segment
		(start 301.87646 -144.304258)
		(end 299.7962 -142.91437)
		(width 0.1651)
		(layer "In5.Cu")
		(net "P5E_PEX2_STN0_RX_DN<8>")
	)
	(segment
		(start 314.315856 -273.8628)
		(end 314.315856 -273.834352)
		(width 0.1143)
		(layer "In5.Cu")
		(net "P5E_PEX2_STN0_RX_DN<8>")
	)
	(segment
		(start 314.791344 -271.535144)
		(end 314.744354 -270.75384)
		(width 0.1651)
		(layer "In5.Cu")
		(net "P5E_PEX2_STN0_RX_DN<8>")
	)
	(segment
		(start 314.08497 -265.20775)
		(end 310.472836 -160.610042)
		(width 0.1651)
		(layer "In5.Cu")
		(net "P5E_PEX2_STN0_RX_DN<8>")
	)
	(segment
		(start 310.37403 -159.983424)
		(end 308.863746 -154.698954)
		(width 0.1651)
		(layer "In5.Cu")
		(net "P5E_PEX2_STN0_RX_DN<8>")
	)
	(segment
		(start 314.315856 -273.834352)
		(end 314.315856 -273.600672)
		(width 0.1651)
		(layer "In5.Cu")
		(net "P5E_PEX2_STN0_RX_DN<8>")
	)
	(segment
		(start 308.863746 -154.698954)
		(end 307.47589 -152.831292)
		(width 0.1651)
		(layer "In5.Cu")
		(net "P5E_PEX2_STN0_RX_DN<8>")
	)
	(segment
		(start 299.7962 -142.91437)
		(end 299.548042 -142.91437)
		(width 0.1651)
		(layer "In5.Cu")
		(net "P5E_PEX2_STN0_RX_DN<8>")
	)
	(segment
		(start 306.013866 -151.432514)
		(end 305.46675 -149.895306)
		(width 0.1651)
		(layer "In5.Cu")
		(net "P5E_PEX2_STN0_RX_DN<8>")
	)
	(segment
		(start 314.270136 -274.885404)
		(end 314.270136 -273.90852)
		(width 0.1143)
		(layer "In5.Cu")
		(net "P5E_PEX2_STN0_RX_DN<8>")
	)
	(segment
		(start 314.791852 -272.451322)
		(end 314.791852 -271.535652)
		(width 0.1651)
		(layer "In5.Cu")
		(net "P5E_PEX2_STN0_RX_DN<8>")
	)
	(segment
		(start 299.548042 -142.91437)
		(end 299.257212 -142.62354)
		(width 0.1651)
		(layer "In5.Cu")
		(net "P5E_PEX2_STN0_RX_DN<8>")
	)
	(segment
		(start 314.315856 -273.600672)
		(end 314.791852 -272.451322)
		(width 0.1651)
		(layer "In5.Cu")
		(net "P5E_PEX2_STN0_RX_DN<8>")
	)
	(segment
		(start 307.47589 -152.831292)
		(end 306.013866 -151.432514)
		(width 0.1651)
		(layer "In5.Cu")
		(net "P5E_PEX2_STN0_RX_DN<8>")
	)
	(segment
		(start 314.791852 -271.535652)
		(end 314.791344 -271.535144)
		(width 0.1651)
		(layer "In5.Cu")
		(net "P5E_PEX2_STN0_RX_DN<8>")
	)
	(segment
		(start 305.46675 -149.895306)
		(end 301.87646 -144.304258)
		(width 0.1651)
		(layer "In5.Cu")
		(net "P5E_PEX2_STN0_RX_DN<8>")
	)
	(segment
		(start 314.384436 -274.999704)
		(end 314.270136 -274.885404)
		(width 0.1143)
		(layer "In5.Cu")
		(net "P5E_PEX2_STN0_RX_DN<8>")
	)
	(segment
		(start 314.649866 -274.999704)
		(end 314.384436 -274.999704)
		(width 0.1143)
		(layer "In5.Cu")
		(net "P5E_PEX2_STN0_RX_DN<8>")
	)
	(segment
		(start 393.839446 -109.044994)
		(end 394.342366 -109.044994)
		(width 0.13462)
		(layer "F.Cu")
		(net "P5E_PEX3_STN1_TX_C_DP<21>")
	)
	(segment
		(start 385.525264 -108.8898)
		(end 393.684252 -108.8898)
		(width 0.13462)
		(layer "F.Cu")
		(net "P5E_PEX3_STN1_TX_C_DP<21>")
	)
	(segment
		(start 393.684252 -108.8898)
		(end 393.839446 -109.044994)
		(width 0.13462)
		(layer "F.Cu")
		(net "P5E_PEX3_STN1_TX_C_DP<21>")
	)
	(segment
		(start 385.205224 -109.20984)
		(end 385.525264 -108.8898)
		(width 0.13462)
		(layer "F.Cu")
		(net "P5E_PEX3_STN1_TX_C_DP<21>")
	)
	(segment
		(start 403.199854 -316.534292)
		(end 403.199854 -316.799722)
		(width 0.1143)
		(layer "In5.Cu")
		(net "P5E_PEX3_STN6_RX_DN<99>")
	)
	(segment
		(start 402.865844 -319.934082)
		(end 402.820124 -319.888362)
		(width 0.1143)
		(layer "In5.Cu")
		(net "P5E_PEX3_STN6_RX_DN<99>")
	)
	(segment
		(start 385.448048 -368.446812)
		(end 376.42419 -358.721152)
		(width 0.1651)
		(layer "In5.Cu")
		(net "P5E_PEX3_STN6_RX_DN<99>")
	)
	(segment
		(start 400.702526 -323.763894)
		(end 402.570696 -321.44208)
		(width 0.1651)
		(layer "In5.Cu")
		(net "P5E_PEX3_STN6_RX_DN<99>")
	)
	(segment
		(start 376.42419 -341.935054)
		(end 376.890534 -341.369142)
		(width 0.1651)
		(layer "In5.Cu")
		(net "P5E_PEX3_STN6_RX_DN<99>")
	)
	(segment
		(start 385.448048 -374.687338)
		(end 385.448048 -368.446812)
		(width 0.1651)
		(layer "In5.Cu")
		(net "P5E_PEX3_STN6_RX_DN<99>")
	)
	(segment
		(start 384.950462 -375.184924)
		(end 385.448048 -374.687338)
		(width 0.1651)
		(layer "In5.Cu")
		(net "P5E_PEX3_STN6_RX_DN<99>")
	)
	(segment
		(start 402.865844 -320.782696)
		(end 402.865844 -319.96253)
		(width 0.1651)
		(layer "In5.Cu")
		(net "P5E_PEX3_STN6_RX_DN<99>")
	)
	(segment
		(start 384.290062 -375.358152)
		(end 384.46329 -375.184924)
		(width 0.1651)
		(layer "In5.Cu")
		(net "P5E_PEX3_STN6_RX_DN<99>")
	)
	(segment
		(start 384.46329 -375.184924)
		(end 384.950462 -375.184924)
		(width 0.1651)
		(layer "In5.Cu")
		(net "P5E_PEX3_STN6_RX_DN<99>")
	)
	(segment
		(start 402.820124 -316.534292)
		(end 402.934424 -316.419992)
		(width 0.1143)
		(layer "In5.Cu")
		(net "P5E_PEX3_STN6_RX_DN<99>")
	)
	(segment
		(start 402.934424 -316.419992)
		(end 403.085554 -316.419992)
		(width 0.1143)
		(layer "In5.Cu")
		(net "P5E_PEX3_STN6_RX_DN<99>")
	)
	(segment
		(start 402.865844 -319.96253)
		(end 402.865844 -319.934082)
		(width 0.1143)
		(layer "In5.Cu")
		(net "P5E_PEX3_STN6_RX_DN<99>")
	)
	(segment
		(start 376.890534 -341.369142)
		(end 400.702526 -323.763894)
		(width 0.1651)
		(layer "In5.Cu")
		(net "P5E_PEX3_STN6_RX_DN<99>")
	)
	(segment
		(start 402.820124 -319.888362)
		(end 402.820124 -316.534292)
		(width 0.1143)
		(layer "In5.Cu")
		(net "P5E_PEX3_STN6_RX_DN<99>")
	)
	(segment
		(start 402.570696 -321.44208)
		(end 402.865844 -320.782696)
		(width 0.1651)
		(layer "In5.Cu")
		(net "P5E_PEX3_STN6_RX_DN<99>")
	)
	(segment
		(start 403.085554 -316.419992)
		(end 403.199854 -316.534292)
		(width 0.1143)
		(layer "In5.Cu")
		(net "P5E_PEX3_STN6_RX_DN<99>")
	)
	(segment
		(start 384.290062 -375.69013)
		(end 384.290062 -375.358152)
		(width 0.1651)
		(layer "In5.Cu")
		(net "P5E_PEX3_STN6_RX_DN<99>")
	)
	(segment
		(start 376.42419 -358.721152)
		(end 376.42419 -341.935054)
		(width 0.1651)
		(layer "In5.Cu")
		(net "P5E_PEX3_STN6_RX_DN<99>")
	)
	(segment
		(start 189.357508 -97.039938)
		(end 191.20739 -97.039938)
		(width 0.13208)
		(layer "F.Cu")
		(net "PWRGD_NIC3_PWR_GOOD")
	)
	(via
		(at 191.20739 -97.039938)
		(size 0.508)
		(drill 0.254)
		(layers "F.Cu" "B.Cu")
		(net "PWRGD_NIC3_PWR_GOOD")
	)
	(segment
		(start 186.603894 -97.663)
		(end 187.454794 -97.663)
		(width 0.13208)
		(layer "B.Cu")
		(net "PWRGD_NIC3_PWR_GOOD")
	)
	(segment
		(start 190.560452 -96.393)
		(end 191.20739 -97.039938)
		(width 0.13208)
		(layer "B.Cu")
		(net "PWRGD_NIC3_PWR_GOOD")
	)
	(segment
		(start 187.454794 -96.79305)
		(end 187.854844 -96.393)
		(width 0.13208)
		(layer "B.Cu")
		(net "PWRGD_NIC3_PWR_GOOD")
	)
	(segment
		(start 187.454794 -97.663)
		(end 187.454794 -96.79305)
		(width 0.13208)
		(layer "B.Cu")
		(net "PWRGD_NIC3_PWR_GOOD")
	)
	(segment
		(start 187.854844 -96.393)
		(end 190.560452 -96.393)
		(width 0.13208)
		(layer "B.Cu")
		(net "PWRGD_NIC3_PWR_GOOD")
	)
	(segment
		(start 152.764998 -30.190186)
		(end 152.287478 -30.190186)
		(width 0.13462)
		(layer "F.Cu")
		(net "P5E_PEX1_STN2_RX_DN<41>")
	)
	(segment
		(start 152.287478 -30.190186)
		(end 152.124664 -30.353)
		(width 0.13462)
		(layer "F.Cu")
		(net "P5E_PEX1_STN2_RX_DN<41>")
	)
	(segment
		(start 149.60473 -30.353)
		(end 149.310598 -30.058868)
		(width 0.13462)
		(layer "F.Cu")
		(net "P5E_PEX1_STN2_RX_DN<41>")
	)
	(segment
		(start 152.124664 -30.353)
		(end 149.60473 -30.353)
		(width 0.13462)
		(layer "F.Cu")
		(net "P5E_PEX1_STN2_RX_DN<41>")
	)
	(segment
		(start 154.566112 -64.739774)
		(end 154.206448 -55.754524)
		(width 0.1651)
		(layer "In7.Cu")
		(net "P5E_PEX1_STN2_RX_DN<41>")
	)
	(segment
		(start 165.516814 -263.616948)
		(end 165.664388 -260.611112)
		(width 0.1651)
		(layer "In7.Cu")
		(net "P5E_PEX1_STN2_RX_DN<41>")
	)
	(segment
		(start 166.135558 -273.479514)
		(end 166.021004 -273.479514)
		(width 0.1143)
		(layer "In7.Cu")
		(net "P5E_PEX1_STN2_RX_DN<41>")
	)
	(segment
		(start 165.664388 -260.611112)
		(end 165.86962 -249.971052)
		(width 0.1651)
		(layer "In7.Cu")
		(net "P5E_PEX1_STN2_RX_DN<41>")
	)
	(segment
		(start 157.913324 -147.970494)
		(end 158.219394 -119.573802)
		(width 0.1651)
		(layer "In7.Cu")
		(net "P5E_PEX1_STN2_RX_DN<41>")
	)
	(segment
		(start 153.488136 -35.00755)
		(end 153.51252 -31.973012)
		(width 0.1651)
		(layer "In7.Cu")
		(net "P5E_PEX1_STN2_RX_DN<41>")
	)
	(segment
		(start 152.989788 -39.636954)
		(end 152.963372 -37.96284)
		(width 0.1651)
		(layer "In7.Cu")
		(net "P5E_PEX1_STN2_RX_DN<41>")
	)
	(segment
		(start 157.76575 -104.603296)
		(end 154.566112 -64.739774)
		(width 0.1651)
		(layer "In7.Cu")
		(net "P5E_PEX1_STN2_RX_DN<41>")
	)
	(segment
		(start 166.021004 -273.479514)
		(end 165.870128 -273.328638)
		(width 0.1143)
		(layer "In7.Cu")
		(net "P5E_PEX1_STN2_RX_DN<41>")
	)
	(segment
		(start 154.306016 -49.3776)
		(end 152.989788 -39.636954)
		(width 0.1651)
		(layer "In7.Cu")
		(net "P5E_PEX1_STN2_RX_DN<41>")
	)
	(segment
		(start 154.206448 -55.754524)
		(end 154.306016 -49.3776)
		(width 0.1651)
		(layer "In7.Cu")
		(net "P5E_PEX1_STN2_RX_DN<41>")
	)
	(segment
		(start 165.915848 -271.3736)
		(end 165.915848 -271.345152)
		(width 0.1143)
		(layer "In7.Cu")
		(net "P5E_PEX1_STN2_RX_DN<41>")
	)
	(segment
		(start 149.601428 -30.349698)
		(end 149.310598 -30.058868)
		(width 0.1651)
		(layer "In7.Cu")
		(net "P5E_PEX1_STN2_RX_DN<41>")
	)
	(segment
		(start 153.51252 -31.973012)
		(end 151.889206 -30.349698)
		(width 0.1651)
		(layer "In7.Cu")
		(net "P5E_PEX1_STN2_RX_DN<41>")
	)
	(segment
		(start 151.889206 -30.349698)
		(end 149.601428 -30.349698)
		(width 0.1651)
		(layer "In7.Cu")
		(net "P5E_PEX1_STN2_RX_DN<41>")
	)
	(segment
		(start 166.249858 -273.099784)
		(end 166.249858 -273.365214)
		(width 0.1143)
		(layer "In7.Cu")
		(net "P5E_PEX1_STN2_RX_DN<41>")
	)
	(segment
		(start 165.870128 -273.328638)
		(end 165.870128 -271.41932)
		(width 0.1143)
		(layer "In7.Cu")
		(net "P5E_PEX1_STN2_RX_DN<41>")
	)
	(segment
		(start 165.86962 -249.971052)
		(end 157.913324 -147.970494)
		(width 0.1651)
		(layer "In7.Cu")
		(net "P5E_PEX1_STN2_RX_DN<41>")
	)
	(segment
		(start 165.915848 -271.345152)
		(end 165.915848 -267.669264)
		(width 0.1651)
		(layer "In7.Cu")
		(net "P5E_PEX1_STN2_RX_DN<41>")
	)
	(segment
		(start 165.870128 -271.41932)
		(end 165.915848 -271.3736)
		(width 0.1143)
		(layer "In7.Cu")
		(net "P5E_PEX1_STN2_RX_DN<41>")
	)
	(segment
		(start 165.915848 -267.669264)
		(end 165.516814 -263.616948)
		(width 0.1651)
		(layer "In7.Cu")
		(net "P5E_PEX1_STN2_RX_DN<41>")
	)
	(segment
		(start 166.249858 -273.365214)
		(end 166.135558 -273.479514)
		(width 0.1143)
		(layer "In7.Cu")
		(net "P5E_PEX1_STN2_RX_DN<41>")
	)
	(segment
		(start 152.963372 -37.96284)
		(end 153.488136 -35.00755)
		(width 0.1651)
		(layer "In7.Cu")
		(net "P5E_PEX1_STN2_RX_DN<41>")
	)
	(segment
		(start 158.219394 -119.573802)
		(end 157.76575 -104.603296)
		(width 0.1651)
		(layer "In7.Cu")
		(net "P5E_PEX1_STN2_RX_DN<41>")
	)
	(segment
		(start 300.374812 -132.444998)
		(end 300.213014 -132.2832)
		(width 0.13462)
		(layer "F.Cu")
		(net "P5E_PEX2_STN0_RX_DP<5>")
	)
	(segment
		(start 300.857412 -132.444998)
		(end 300.374812 -132.444998)
		(width 0.13462)
		(layer "F.Cu")
		(net "P5E_PEX2_STN0_RX_DP<5>")
	)
	(segment
		(start 297.697144 -132.2832)
		(end 297.403012 -132.577332)
		(width 0.13462)
		(layer "F.Cu")
		(net "P5E_PEX2_STN0_RX_DP<5>")
	)
	(segment
		(start 300.213014 -132.2832)
		(end 297.697144 -132.2832)
		(width 0.13462)
		(layer "F.Cu")
		(net "P5E_PEX2_STN0_RX_DP<5>")
	)
	(segment
		(start 300.337982 -132.726938)
		(end 300.337728 -132.727192)
		(width 0.1651)
		(layer "In5.Cu")
		(net "P5E_PEX2_STN0_RX_DP<5>")
	)
	(segment
		(start 307.517546 -136.747504)
		(end 307.115718 -136.457182)
		(width 0.1651)
		(layer "In5.Cu")
		(net "P5E_PEX2_STN0_RX_DP<5>")
	)
	(segment
		(start 316.449964 -233.359452)
		(end 315.41339 -222.619316)
		(width 0.1651)
		(layer "In5.Cu")
		(net "P5E_PEX2_STN0_RX_DP<5>")
	)
	(segment
		(start 303.164748 -134.146036)
		(end 303.011332 -134.19709)
		(width 0.1651)
		(layer "In5.Cu")
		(net "P5E_PEX2_STN0_RX_DP<5>")
	)
	(segment
		(start 304.254662 -134.693152)
		(end 304.100992 -134.743952)
		(width 0.1651)
		(layer "In5.Cu")
		(net "P5E_PEX2_STN0_RX_DP<5>")
	)
	(segment
		(start 313.699906 -283.549852)
		(end 313.965336 -283.549852)
		(width 0.1143)
		(layer "In5.Cu")
		(net "P5E_PEX2_STN0_RX_DP<5>")
	)
	(segment
		(start 301.921418 -133.649974)
		(end 301.478696 -133.42747)
		(width 0.1651)
		(layer "In5.Cu")
		(net "P5E_PEX2_STN0_RX_DP<5>")
	)
	(segment
		(start 306.266088 -135.702548)
		(end 305.344576 -135.240014)
		(width 0.1651)
		(layer "In5.Cu")
		(net "P5E_PEX2_STN0_RX_DP<5>")
	)
	(segment
		(start 305.19116 -135.291068)
		(end 304.748184 -135.068564)
		(width 0.1651)
		(layer "In5.Cu")
		(net "P5E_PEX2_STN0_RX_DP<5>")
	)
	(segment
		(start 326.648826 -272.229834)
		(end 326.700642 -270.270224)
		(width 0.1651)
		(layer "In5.Cu")
		(net "P5E_PEX2_STN0_RX_DP<5>")
	)
	(segment
		(start 304.69713 -134.915148)
		(end 304.254662 -134.693152)
		(width 0.1651)
		(layer "In5.Cu")
		(net "P5E_PEX2_STN0_RX_DP<5>")
	)
	(segment
		(start 326.700642 -270.270224)
		(end 319.075308 -244.204744)
		(width 0.1651)
		(layer "In5.Cu")
		(net "P5E_PEX2_STN0_RX_DP<5>")
	)
	(segment
		(start 317.59652 -282.388056)
		(end 324.94601 -275.243798)
		(width 0.1651)
		(layer "In5.Cu")
		(net "P5E_PEX2_STN0_RX_DP<5>")
	)
	(segment
		(start 302.517302 -133.82117)
		(end 302.074834 -133.599174)
		(width 0.1651)
		(layer "In5.Cu")
		(net "P5E_PEX2_STN0_RX_DP<5>")
	)
	(segment
		(start 307.677058 -136.72185)
		(end 307.517546 -136.747504)
		(width 0.1651)
		(layer "In5.Cu")
		(net "P5E_PEX2_STN0_RX_DP<5>")
	)
	(segment
		(start 308.898798 -137.604246)
		(end 307.677058 -136.72185)
		(width 0.1651)
		(layer "In5.Cu")
		(net "P5E_PEX2_STN0_RX_DP<5>")
	)
	(segment
		(start 309.565802 -138.618976)
		(end 308.898798 -137.604246)
		(width 0.1651)
		(layer "In5.Cu")
		(net "P5E_PEX2_STN0_RX_DP<5>")
	)
	(segment
		(start 301.478696 -133.42747)
		(end 301.427642 -133.274054)
		(width 0.1651)
		(layer "In5.Cu")
		(net "P5E_PEX2_STN0_RX_DP<5>")
	)
	(segment
		(start 311.820306 -151.39924)
		(end 310.439562 -142.071598)
		(width 0.1651)
		(layer "In5.Cu")
		(net "P5E_PEX2_STN0_RX_DP<5>")
	)
	(segment
		(start 319.075308 -244.204744)
		(end 316.449964 -233.359452)
		(width 0.1651)
		(layer "In5.Cu")
		(net "P5E_PEX2_STN0_RX_DP<5>")
	)
	(segment
		(start 314.079636 -283.19476)
		(end 314.294774 -282.979622)
		(width 0.1143)
		(layer "In5.Cu")
		(net "P5E_PEX2_STN0_RX_DP<5>")
	)
	(segment
		(start 303.65827 -134.521448)
		(end 303.607216 -134.368032)
		(width 0.1651)
		(layer "In5.Cu")
		(net "P5E_PEX2_STN0_RX_DP<5>")
	)
	(segment
		(start 303.011332 -134.19709)
		(end 302.568356 -133.974586)
		(width 0.1651)
		(layer "In5.Cu")
		(net "P5E_PEX2_STN0_RX_DP<5>")
	)
	(segment
		(start 300.337728 -132.727192)
		(end 299.459904 -132.286502)
		(width 0.1651)
		(layer "In5.Cu")
		(net "P5E_PEX2_STN0_RX_DP<5>")
	)
	(segment
		(start 313.965336 -283.549852)
		(end 314.079636 -283.435552)
		(width 0.1143)
		(layer "In5.Cu")
		(net "P5E_PEX2_STN0_RX_DP<5>")
	)
	(segment
		(start 300.985174 -133.052058)
		(end 300.831758 -133.102858)
		(width 0.1651)
		(layer "In5.Cu")
		(net "P5E_PEX2_STN0_RX_DP<5>")
	)
	(segment
		(start 315.41339 -222.619316)
		(end 313.201304 -160.728406)
		(width 0.1651)
		(layer "In5.Cu")
		(net "P5E_PEX2_STN0_RX_DP<5>")
	)
	(segment
		(start 304.100992 -134.743952)
		(end 303.65827 -134.521448)
		(width 0.1651)
		(layer "In5.Cu")
		(net "P5E_PEX2_STN0_RX_DP<5>")
	)
	(segment
		(start 314.294774 -282.979622)
		(end 316.04331 -282.979622)
		(width 0.1143)
		(layer "In5.Cu")
		(net "P5E_PEX2_STN0_RX_DP<5>")
	)
	(segment
		(start 300.831758 -133.102858)
		(end 300.388782 -132.880354)
		(width 0.1651)
		(layer "In5.Cu")
		(net "P5E_PEX2_STN0_RX_DP<5>")
	)
	(segment
		(start 311.820306 -151.399748)
		(end 311.820306 -151.39924)
		(width 0.1651)
		(layer "In5.Cu")
		(net "P5E_PEX2_STN0_RX_DP<5>")
	)
	(segment
		(start 316.766702 -282.933902)
		(end 317.59652 -282.388056)
		(width 0.1651)
		(layer "In5.Cu")
		(net "P5E_PEX2_STN0_RX_DP<5>")
	)
	(segment
		(start 304.748184 -135.068564)
		(end 304.69713 -134.915148)
		(width 0.1651)
		(layer "In5.Cu")
		(net "P5E_PEX2_STN0_RX_DP<5>")
	)
	(segment
		(start 311.82056 -151.400002)
		(end 311.820306 -151.399748)
		(width 0.1651)
		(layer "In5.Cu")
		(net "P5E_PEX2_STN0_RX_DP<5>")
	)
	(segment
		(start 297.693842 -132.286502)
		(end 297.403012 -132.577332)
		(width 0.1651)
		(layer "In5.Cu")
		(net "P5E_PEX2_STN0_RX_DP<5>")
	)
	(segment
		(start 302.568356 -133.974586)
		(end 302.517302 -133.82117)
		(width 0.1651)
		(layer "In5.Cu")
		(net "P5E_PEX2_STN0_RX_DP<5>")
	)
	(segment
		(start 314.079636 -283.435552)
		(end 314.079636 -283.19476)
		(width 0.1143)
		(layer "In5.Cu")
		(net "P5E_PEX2_STN0_RX_DP<5>")
	)
	(segment
		(start 302.074834 -133.599174)
		(end 301.921418 -133.649974)
		(width 0.1651)
		(layer "In5.Cu")
		(net "P5E_PEX2_STN0_RX_DP<5>")
	)
	(segment
		(start 303.607216 -134.368032)
		(end 303.164748 -134.146036)
		(width 0.1651)
		(layer "In5.Cu")
		(net "P5E_PEX2_STN0_RX_DP<5>")
	)
	(segment
		(start 313.201304 -160.728406)
		(end 311.82056 -151.400002)
		(width 0.1651)
		(layer "In5.Cu")
		(net "P5E_PEX2_STN0_RX_DP<5>")
	)
	(segment
		(start 316.117478 -282.933902)
		(end 316.766702 -282.933902)
		(width 0.1651)
		(layer "In5.Cu")
		(net "P5E_PEX2_STN0_RX_DP<5>")
	)
	(segment
		(start 316.08903 -282.933902)
		(end 316.117478 -282.933902)
		(width 0.1143)
		(layer "In5.Cu")
		(net "P5E_PEX2_STN0_RX_DP<5>")
	)
	(segment
		(start 305.344576 -135.240014)
		(end 305.19116 -135.291068)
		(width 0.1651)
		(layer "In5.Cu")
		(net "P5E_PEX2_STN0_RX_DP<5>")
	)
	(segment
		(start 309.831232 -139.23772)
		(end 309.565802 -138.618976)
		(width 0.1651)
		(layer "In5.Cu")
		(net "P5E_PEX2_STN0_RX_DP<5>")
	)
	(segment
		(start 307.090064 -136.29767)
		(end 306.266088 -135.702548)
		(width 0.1651)
		(layer "In5.Cu")
		(net "P5E_PEX2_STN0_RX_DP<5>")
	)
	(segment
		(start 307.115718 -136.457182)
		(end 307.090064 -136.29767)
		(width 0.1651)
		(layer "In5.Cu")
		(net "P5E_PEX2_STN0_RX_DP<5>")
	)
	(segment
		(start 301.427642 -133.274054)
		(end 300.985174 -133.052058)
		(width 0.1651)
		(layer "In5.Cu")
		(net "P5E_PEX2_STN0_RX_DP<5>")
	)
	(segment
		(start 316.04331 -282.979622)
		(end 316.08903 -282.933902)
		(width 0.1143)
		(layer "In5.Cu")
		(net "P5E_PEX2_STN0_RX_DP<5>")
	)
	(segment
		(start 300.388782 -132.880354)
		(end 300.337982 -132.726938)
		(width 0.1651)
		(layer "In5.Cu")
		(net "P5E_PEX2_STN0_RX_DP<5>")
	)
	(segment
		(start 324.94601 -275.243798)
		(end 326.648826 -272.229834)
		(width 0.1651)
		(layer "In5.Cu")
		(net "P5E_PEX2_STN0_RX_DP<5>")
	)
	(segment
		(start 299.459904 -132.286502)
		(end 297.693842 -132.286502)
		(width 0.1651)
		(layer "In5.Cu")
		(net "P5E_PEX2_STN0_RX_DP<5>")
	)
	(segment
		(start 310.439562 -142.071598)
		(end 309.831232 -139.23772)
		(width 0.1651)
		(layer "In5.Cu")
		(net "P5E_PEX2_STN0_RX_DP<5>")
	)
	(segment
		(start 385.205224 -104.695498)
		(end 385.518406 -105.00868)
		(width 0.13462)
		(layer "F.Cu")
		(net "P5E_PEX3_STN1_TX_C_DN<19>")
	)
	(segment
		(start 393.679426 -105.00868)
		(end 393.843002 -104.845104)
		(width 0.13462)
		(layer "F.Cu")
		(net "P5E_PEX3_STN1_TX_C_DN<19>")
	)
	(segment
		(start 393.843002 -104.845104)
		(end 394.342366 -104.845104)
		(width 0.13462)
		(layer "F.Cu")
		(net "P5E_PEX3_STN1_TX_C_DN<19>")
	)
	(segment
		(start 385.518406 -105.00868)
		(end 393.679426 -105.00868)
		(width 0.13462)
		(layer "F.Cu")
		(net "P5E_PEX3_STN1_TX_C_DN<19>")
	)
	(segment
		(start 380.564136 -401.181062)
		(end 380.01702 -401.181062)
		(width 0.1651)
		(layer "In15.Cu")
		(net "P5E_PEX3_STN6_RX_DN<109>")
	)
	(segment
		(start 393.36599 -320.72199)
		(end 393.045442 -321.496436)
		(width 0.1651)
		(layer "In15.Cu")
		(net "P5E_PEX3_STN6_RX_DN<109>")
	)
	(segment
		(start 370.237258 -340.356698)
		(end 369.247166 -341.990172)
		(width 0.1651)
		(layer "In15.Cu")
		(net "P5E_PEX3_STN6_RX_DN<109>")
	)
	(segment
		(start 393.7 -316.534292)
		(end 393.5857 -316.419992)
		(width 0.1143)
		(layer "In15.Cu")
		(net "P5E_PEX3_STN6_RX_DN<109>")
	)
	(segment
		(start 390.518396 -324.104762)
		(end 370.237258 -340.356698)
		(width 0.1651)
		(layer "In15.Cu")
		(net "P5E_PEX3_STN6_RX_DN<109>")
	)
	(segment
		(start 393.32027 -319.921128)
		(end 393.36599 -319.966848)
		(width 0.1143)
		(layer "In15.Cu")
		(net "P5E_PEX3_STN6_RX_DN<109>")
	)
	(segment
		(start 393.36599 -319.966848)
		(end 393.36599 -319.995296)
		(width 0.1143)
		(layer "In15.Cu")
		(net "P5E_PEX3_STN6_RX_DN<109>")
	)
	(segment
		(start 393.5857 -316.419992)
		(end 393.423902 -316.419992)
		(width 0.1143)
		(layer "In15.Cu")
		(net "P5E_PEX3_STN6_RX_DN<109>")
	)
	(segment
		(start 393.423902 -316.419992)
		(end 393.32027 -316.523624)
		(width 0.1143)
		(layer "In15.Cu")
		(net "P5E_PEX3_STN6_RX_DN<109>")
	)
	(segment
		(start 369.206018 -342.197436)
		(end 368.934746 -371.377972)
		(width 0.1651)
		(layer "In15.Cu")
		(net "P5E_PEX3_STN6_RX_DN<109>")
	)
	(segment
		(start 370.65966 -388.461504)
		(end 373.763794 -390.760458)
		(width 0.1651)
		(layer "In15.Cu")
		(net "P5E_PEX3_STN6_RX_DN<109>")
	)
	(segment
		(start 375.832878 -391.6426)
		(end 380.740158 -394.579348)
		(width 0.1651)
		(layer "In15.Cu")
		(net "P5E_PEX3_STN6_RX_DN<109>")
	)
	(segment
		(start 393.7 -316.799722)
		(end 393.7 -316.534292)
		(width 0.1143)
		(layer "In15.Cu")
		(net "P5E_PEX3_STN6_RX_DN<109>")
	)
	(segment
		(start 393.32027 -316.523624)
		(end 393.32027 -319.921128)
		(width 0.1143)
		(layer "In15.Cu")
		(net "P5E_PEX3_STN6_RX_DN<109>")
	)
	(segment
		(start 369.247166 -341.990172)
		(end 369.206018 -342.197436)
		(width 0.1651)
		(layer "In15.Cu")
		(net "P5E_PEX3_STN6_RX_DN<109>")
	)
	(segment
		(start 393.045442 -321.496436)
		(end 390.518396 -324.104762)
		(width 0.1651)
		(layer "In15.Cu")
		(net "P5E_PEX3_STN6_RX_DN<109>")
	)
	(segment
		(start 393.36599 -319.995296)
		(end 393.36599 -320.72199)
		(width 0.1651)
		(layer "In15.Cu")
		(net "P5E_PEX3_STN6_RX_DN<109>")
	)
	(segment
		(start 380.740158 -394.579348)
		(end 381.016002 -395.097)
		(width 0.1651)
		(layer "In15.Cu")
		(net "P5E_PEX3_STN6_RX_DN<109>")
	)
	(segment
		(start 368.934746 -371.377972)
		(end 369.525042 -385.680458)
		(width 0.1651)
		(layer "In15.Cu")
		(net "P5E_PEX3_STN6_RX_DN<109>")
	)
	(segment
		(start 369.525042 -385.680458)
		(end 370.65966 -388.461504)
		(width 0.1651)
		(layer "In15.Cu")
		(net "P5E_PEX3_STN6_RX_DN<109>")
	)
	(segment
		(start 379.89002 -401.308062)
		(end 379.89002 -401.690078)
		(width 0.1651)
		(layer "In15.Cu")
		(net "P5E_PEX3_STN6_RX_DN<109>")
	)
	(segment
		(start 380.01702 -401.181062)
		(end 379.89002 -401.308062)
		(width 0.1651)
		(layer "In15.Cu")
		(net "P5E_PEX3_STN6_RX_DN<109>")
	)
	(segment
		(start 381.016002 -395.097)
		(end 381.016002 -400.729196)
		(width 0.1651)
		(layer "In15.Cu")
		(net "P5E_PEX3_STN6_RX_DN<109>")
	)
	(segment
		(start 381.016002 -400.729196)
		(end 380.564136 -401.181062)
		(width 0.1651)
		(layer "In15.Cu")
		(net "P5E_PEX3_STN6_RX_DN<109>")
	)
	(segment
		(start 373.763794 -390.760458)
		(end 375.832878 -391.6426)
		(width 0.1651)
		(layer "In15.Cu")
		(net "P5E_PEX3_STN6_RX_DN<109>")
	)
	(segment
		(start 195.18884 -114.035078)
		(end 197.299834 -114.035078)
		(width 0.13208)
		(layer "F.Cu")
		(net "NIC3_BIF2_N")
	)
	(segment
		(start 193.93154 -114.06124)
		(end 193.957702 -114.035078)
		(width 0.13208)
		(layer "F.Cu")
		(net "NIC3_BIF2_N")
	)
	(segment
		(start 191.361314 -114.035078)
		(end 191.387476 -114.06124)
		(width 0.13208)
		(layer "F.Cu")
		(net "NIC3_BIF2_N")
	)
	(segment
		(start 193.957702 -114.035078)
		(end 195.18884 -114.035078)
		(width 0.13208)
		(layer "F.Cu")
		(net "NIC3_BIF2_N")
	)
	(segment
		(start 199.186546 -113.912904)
		(end 199.313546 -114.039904)
		(width 0.13208)
		(layer "F.Cu")
		(net "NIC3_BIF2_N")
	)
	(segment
		(start 191.387476 -114.06124)
		(end 193.93154 -114.06124)
		(width 0.13208)
		(layer "F.Cu")
		(net "NIC3_BIF2_N")
	)
	(segment
		(start 197.422008 -113.912904)
		(end 199.186546 -113.912904)
		(width 0.13208)
		(layer "F.Cu")
		(net "NIC3_BIF2_N")
	)
	(segment
		(start 189.357508 -114.035078)
		(end 191.361314 -114.035078)
		(width 0.13208)
		(layer "F.Cu")
		(net "NIC3_BIF2_N")
	)
	(segment
		(start 197.299834 -114.035078)
		(end 197.422008 -113.912904)
		(width 0.13208)
		(layer "F.Cu")
		(net "NIC3_BIF2_N")
	)
	(segment
		(start 200.291446 -114.42954)
		(end 199.313546 -114.42954)
		(width 0.13208)
		(layer "F.Cu")
		(net "NIC3_BIF2_N")
	)
	(segment
		(start 199.313546 -114.039904)
		(end 199.313546 -114.42954)
		(width 0.13208)
		(layer "F.Cu")
		(net "NIC3_BIF2_N")
	)
	(via
		(at 195.18884 -114.035078)
		(size 0.762)
		(drill 0.381)
		(layers "F.Cu" "B.Cu")
		(net "NIC3_BIF2_N")
	)
	(segment
		(start 161.948114 -34.2265)
		(end 158.031434 -34.2265)
		(width 0.13462)
		(layer "F.Cu")
		(net "P5E_PEX1_STN2_TX_C_DP<43>")
	)
	(segment
		(start 158.031434 -34.2265)
		(end 157.867858 -34.390076)
		(width 0.13462)
		(layer "F.Cu")
		(net "P5E_PEX1_STN2_TX_C_DP<43>")
	)
	(segment
		(start 157.867858 -34.390076)
		(end 157.364938 -34.390076)
		(width 0.13462)
		(layer "F.Cu")
		(net "P5E_PEX1_STN2_TX_C_DP<43>")
	)
	(segment
		(start 162.2679 -34.546286)
		(end 161.948114 -34.2265)
		(width 0.13462)
		(layer "F.Cu")
		(net "P5E_PEX1_STN2_TX_C_DP<43>")
	)
	(segment
		(start 306.131722 -151.92248)
		(end 305.964336 -151.755094)
		(width 0.13462)
		(layer "F.Cu")
		(net "P5E_PEX2_STN0_TX_C_DN<13>")
	)
	(segment
		(start 305.964336 -151.755094)
		(end 305.457606 -151.755094)
		(width 0.13462)
		(layer "F.Cu")
		(net "P5E_PEX2_STN0_TX_C_DN<13>")
	)
	(segment
		(start 314.26912 -151.92248)
		(end 306.131722 -151.92248)
		(width 0.13462)
		(layer "F.Cu")
		(net "P5E_PEX2_STN0_TX_C_DN<13>")
	)
	(segment
		(start 314.594748 -151.596852)
		(end 314.26912 -151.92248)
		(width 0.13462)
		(layer "F.Cu")
		(net "P5E_PEX2_STN0_TX_C_DN<13>")
	)
	(segment
		(start 385.525264 -108.61548)
		(end 393.672568 -108.61548)
		(width 0.13462)
		(layer "F.Cu")
		(net "P5E_PEX3_STN1_TX_C_DN<21>")
	)
	(segment
		(start 393.843002 -108.445046)
		(end 394.342366 -108.445046)
		(width 0.13462)
		(layer "F.Cu")
		(net "P5E_PEX3_STN1_TX_C_DN<21>")
	)
	(segment
		(start 385.205224 -108.29544)
		(end 385.525264 -108.61548)
		(width 0.13462)
		(layer "F.Cu")
		(net "P5E_PEX3_STN1_TX_C_DN<21>")
	)
	(segment
		(start 393.672568 -108.61548)
		(end 393.843002 -108.445046)
		(width 0.13462)
		(layer "F.Cu")
		(net "P5E_PEX3_STN1_TX_C_DN<21>")
	)
	(segment
		(start 384.964178 -401.181062)
		(end 385.416044 -400.729196)
		(width 0.1651)
		(layer "In15.Cu")
		(net "P5E_PEX3_STN6_RX_DN<107>")
	)
	(segment
		(start 395.26591 -319.966848)
		(end 395.22019 -319.921128)
		(width 0.1143)
		(layer "In15.Cu")
		(net "P5E_PEX3_STN6_RX_DN<107>")
	)
	(segment
		(start 395.26591 -319.995296)
		(end 395.26591 -319.966848)
		(width 0.1143)
		(layer "In15.Cu")
		(net "P5E_PEX3_STN6_RX_DN<107>")
	)
	(segment
		(start 384.290062 -401.690078)
		(end 384.290062 -401.308062)
		(width 0.1651)
		(layer "In15.Cu")
		(net "P5E_PEX3_STN6_RX_DN<107>")
	)
	(segment
		(start 384.417062 -401.181062)
		(end 384.964178 -401.181062)
		(width 0.1651)
		(layer "In15.Cu")
		(net "P5E_PEX3_STN6_RX_DN<107>")
	)
	(segment
		(start 385.416044 -400.729196)
		(end 385.416044 -395.2748)
		(width 0.1651)
		(layer "In15.Cu")
		(net "P5E_PEX3_STN6_RX_DN<107>")
	)
	(segment
		(start 385.053078 -394.3604)
		(end 380.506478 -391.6172)
		(width 0.1651)
		(layer "In15.Cu")
		(net "P5E_PEX3_STN6_RX_DN<107>")
	)
	(segment
		(start 384.290062 -401.308062)
		(end 384.417062 -401.181062)
		(width 0.1651)
		(layer "In15.Cu")
		(net "P5E_PEX3_STN6_RX_DN<107>")
	)
	(segment
		(start 373.906796 -340.742524)
		(end 386.104384 -330.501498)
		(width 0.1651)
		(layer "In15.Cu")
		(net "P5E_PEX3_STN6_RX_DN<107>")
	)
	(segment
		(start 394.91666 -322.41236)
		(end 395.26591 -321.568826)
		(width 0.1651)
		(layer "In15.Cu")
		(net "P5E_PEX3_STN6_RX_DN<107>")
	)
	(segment
		(start 392.51128 -325.69404)
		(end 394.91666 -322.41236)
		(width 0.1651)
		(layer "In15.Cu")
		(net "P5E_PEX3_STN6_RX_DN<107>")
	)
	(segment
		(start 380.506478 -391.6172)
		(end 374.806718 -389.043926)
		(width 0.1651)
		(layer "In15.Cu")
		(net "P5E_PEX3_STN6_RX_DN<107>")
	)
	(segment
		(start 371.042946 -373.400574)
		(end 371.154452 -371.377464)
		(width 0.1651)
		(layer "In15.Cu")
		(net "P5E_PEX3_STN6_RX_DN<107>")
	)
	(segment
		(start 373.31523 -342.1634)
		(end 373.906796 -340.742524)
		(width 0.1651)
		(layer "In15.Cu")
		(net "P5E_PEX3_STN6_RX_DN<107>")
	)
	(segment
		(start 395.48562 -316.419992)
		(end 395.59992 -316.534292)
		(width 0.1143)
		(layer "In15.Cu")
		(net "P5E_PEX3_STN6_RX_DN<107>")
	)
	(segment
		(start 386.104384 -330.501498)
		(end 392.51128 -325.69404)
		(width 0.1651)
		(layer "In15.Cu")
		(net "P5E_PEX3_STN6_RX_DN<107>")
	)
	(segment
		(start 371.515132 -385.25323)
		(end 371.042946 -373.400574)
		(width 0.1651)
		(layer "In15.Cu")
		(net "P5E_PEX3_STN6_RX_DN<107>")
	)
	(segment
		(start 371.154452 -371.377464)
		(end 373.31523 -358.018588)
		(width 0.1651)
		(layer "In15.Cu")
		(net "P5E_PEX3_STN6_RX_DN<107>")
	)
	(segment
		(start 374.806718 -389.043926)
		(end 372.312438 -387.272784)
		(width 0.1651)
		(layer "In15.Cu")
		(net "P5E_PEX3_STN6_RX_DN<107>")
	)
	(segment
		(start 373.31523 -358.018588)
		(end 373.31523 -342.1634)
		(width 0.1651)
		(layer "In15.Cu")
		(net "P5E_PEX3_STN6_RX_DN<107>")
	)
	(segment
		(start 395.26591 -321.568826)
		(end 395.26591 -319.995296)
		(width 0.1651)
		(layer "In15.Cu")
		(net "P5E_PEX3_STN6_RX_DN<107>")
	)
	(segment
		(start 372.312438 -387.272784)
		(end 371.515132 -385.25323)
		(width 0.1651)
		(layer "In15.Cu")
		(net "P5E_PEX3_STN6_RX_DN<107>")
	)
	(segment
		(start 395.323822 -316.419992)
		(end 395.48562 -316.419992)
		(width 0.1143)
		(layer "In15.Cu")
		(net "P5E_PEX3_STN6_RX_DN<107>")
	)
	(segment
		(start 395.22019 -316.523624)
		(end 395.323822 -316.419992)
		(width 0.1143)
		(layer "In15.Cu")
		(net "P5E_PEX3_STN6_RX_DN<107>")
	)
	(segment
		(start 385.416044 -395.2748)
		(end 385.053078 -394.3604)
		(width 0.1651)
		(layer "In15.Cu")
		(net "P5E_PEX3_STN6_RX_DN<107>")
	)
	(segment
		(start 395.22019 -319.921128)
		(end 395.22019 -316.523624)
		(width 0.1143)
		(layer "In15.Cu")
		(net "P5E_PEX3_STN6_RX_DN<107>")
	)
	(segment
		(start 395.59992 -316.534292)
		(end 395.59992 -316.799722)
		(width 0.1143)
		(layer "In15.Cu")
		(net "P5E_PEX3_STN6_RX_DN<107>")
	)
	(segment
		(start 189.357508 -97.64014)
		(end 190.399924 -97.64014)
		(width 0.13208)
		(layer "F.Cu")
		(net "NIC3_MAIN_PWR_EN_R")
	)
	(via
		(at 189.378844 -98.552)
		(size 0.6604)
		(drill 0.3302)
		(layers "F.Cu" "B.Cu")
		(net "NIC3_MAIN_PWR_EN_R")
	)
	(via
		(at 190.399924 -97.64014)
		(size 0.508)
		(drill 0.254)
		(layers "F.Cu" "B.Cu")
		(net "NIC3_MAIN_PWR_EN_R")
	)
	(segment
		(start 188.254894 -98.552)
		(end 189.378844 -98.552)
		(width 0.13208)
		(layer "B.Cu")
		(net "NIC3_MAIN_PWR_EN_R")
	)
	(segment
		(start 189.869064 -98.171)
		(end 190.399924 -97.64014)
		(width 0.13208)
		(layer "B.Cu")
		(net "NIC3_MAIN_PWR_EN_R")
	)
	(segment
		(start 189.378844 -98.552)
		(end 189.759844 -98.171)
		(width 0.13208)
		(layer "B.Cu")
		(net "NIC3_MAIN_PWR_EN_R")
	)
	(segment
		(start 189.759844 -98.171)
		(end 189.869064 -98.171)
		(width 0.13208)
		(layer "B.Cu")
		(net "NIC3_MAIN_PWR_EN_R")
	)
	(segment
		(start 151.454866 -32.14878)
		(end 151.164798 -31.858712)
		(width 0.13462)
		(layer "F.Cu")
		(net "P5E_PEX1_STN2_RX_DN<42>")
	)
	(segment
		(start 152.764998 -31.99003)
		(end 152.284176 -31.99003)
		(width 0.13462)
		(layer "F.Cu")
		(net "P5E_PEX1_STN2_RX_DN<42>")
	)
	(segment
		(start 152.284176 -31.99003)
		(end 152.125426 -32.14878)
		(width 0.13462)
		(layer "F.Cu")
		(net "P5E_PEX1_STN2_RX_DN<42>")
	)
	(segment
		(start 152.125426 -32.14878)
		(end 151.454866 -32.14878)
		(width 0.13462)
		(layer "F.Cu")
		(net "P5E_PEX1_STN2_RX_DN<42>")
	)
	(segment
		(start 152.544526 -32.663638)
		(end 152.030176 -32.149542)
		(width 0.1651)
		(layer "In7.Cu")
		(net "P5E_PEX1_STN2_RX_DN<42>")
	)
	(segment
		(start 165.185598 -275.379688)
		(end 165.0238 -275.379688)
		(width 0.1143)
		(layer "In7.Cu")
		(net "P5E_PEX1_STN2_RX_DN<42>")
	)
	(segment
		(start 153.234898 -55.367682)
		(end 153.327354 -49.435766)
		(width 0.1651)
		(layer "In7.Cu")
		(net "P5E_PEX1_STN2_RX_DN<42>")
	)
	(segment
		(start 153.626566 -65.159636)
		(end 153.234898 -55.367682)
		(width 0.1651)
		(layer "In7.Cu")
		(net "P5E_PEX1_STN2_RX_DN<42>")
	)
	(segment
		(start 152.507442 -35.04819)
		(end 152.544526 -32.663638)
		(width 0.1651)
		(layer "In7.Cu")
		(net "P5E_PEX1_STN2_RX_DN<42>")
	)
	(segment
		(start 164.919914 -275.275802)
		(end 164.919914 -271.467072)
		(width 0.1143)
		(layer "In7.Cu")
		(net "P5E_PEX1_STN2_RX_DN<42>")
	)
	(segment
		(start 165.0238 -275.379688)
		(end 164.919914 -275.275802)
		(width 0.1143)
		(layer "In7.Cu")
		(net "P5E_PEX1_STN2_RX_DN<42>")
	)
	(segment
		(start 152.030176 -32.149542)
		(end 151.455628 -32.149542)
		(width 0.1651)
		(layer "In7.Cu")
		(net "P5E_PEX1_STN2_RX_DN<42>")
	)
	(segment
		(start 156.820616 -104.952546)
		(end 153.626566 -65.159636)
		(width 0.1651)
		(layer "In7.Cu")
		(net "P5E_PEX1_STN2_RX_DN<42>")
	)
	(segment
		(start 164.965634 -271.392904)
		(end 164.965634 -267.767816)
		(width 0.1651)
		(layer "In7.Cu")
		(net "P5E_PEX1_STN2_RX_DN<42>")
	)
	(segment
		(start 164.919914 -271.467072)
		(end 164.965634 -271.421352)
		(width 0.1143)
		(layer "In7.Cu")
		(net "P5E_PEX1_STN2_RX_DN<42>")
	)
	(segment
		(start 164.744654 -258.734306)
		(end 164.913564 -249.99696)
		(width 0.1651)
		(layer "In7.Cu")
		(net "P5E_PEX1_STN2_RX_DN<42>")
	)
	(segment
		(start 157.263846 -119.5832)
		(end 156.820616 -104.952546)
		(width 0.1651)
		(layer "In7.Cu")
		(net "P5E_PEX1_STN2_RX_DN<42>")
	)
	(segment
		(start 165.299898 -274.999958)
		(end 165.299898 -275.265388)
		(width 0.1143)
		(layer "In7.Cu")
		(net "P5E_PEX1_STN2_RX_DN<42>")
	)
	(segment
		(start 152.013158 -39.71036)
		(end 151.983948 -37.856414)
		(width 0.1651)
		(layer "In7.Cu")
		(net "P5E_PEX1_STN2_RX_DN<42>")
	)
	(segment
		(start 151.983948 -37.856414)
		(end 152.507442 -35.04819)
		(width 0.1651)
		(layer "In7.Cu")
		(net "P5E_PEX1_STN2_RX_DN<42>")
	)
	(segment
		(start 153.327354 -49.435766)
		(end 152.013158 -39.71036)
		(width 0.1651)
		(layer "In7.Cu")
		(net "P5E_PEX1_STN2_RX_DN<42>")
	)
	(segment
		(start 164.965634 -267.767816)
		(end 164.52215 -263.266174)
		(width 0.1651)
		(layer "In7.Cu")
		(net "P5E_PEX1_STN2_RX_DN<42>")
	)
	(segment
		(start 165.299898 -275.265388)
		(end 165.185598 -275.379688)
		(width 0.1143)
		(layer "In7.Cu")
		(net "P5E_PEX1_STN2_RX_DN<42>")
	)
	(segment
		(start 164.913564 -249.99696)
		(end 156.957522 -148.002498)
		(width 0.1651)
		(layer "In7.Cu")
		(net "P5E_PEX1_STN2_RX_DN<42>")
	)
	(segment
		(start 151.455628 -32.149542)
		(end 151.164798 -31.858712)
		(width 0.1651)
		(layer "In7.Cu")
		(net "P5E_PEX1_STN2_RX_DN<42>")
	)
	(segment
		(start 164.52215 -263.266174)
		(end 164.744654 -258.734306)
		(width 0.1651)
		(layer "In7.Cu")
		(net "P5E_PEX1_STN2_RX_DN<42>")
	)
	(segment
		(start 164.965634 -271.421352)
		(end 164.965634 -271.392904)
		(width 0.1143)
		(layer "In7.Cu")
		(net "P5E_PEX1_STN2_RX_DN<42>")
	)
	(segment
		(start 156.957522 -148.002498)
		(end 157.263846 -119.5832)
		(width 0.1651)
		(layer "In7.Cu")
		(net "P5E_PEX1_STN2_RX_DN<42>")
	)
	(segment
		(start 306.13223 -122.8598)
		(end 305.95697 -123.03506)
		(width 0.13462)
		(layer "F.Cu")
		(net "P5E_PEX2_STN0_TX_C_DP<2>")
	)
	(segment
		(start 305.95697 -123.03506)
		(end 305.457606 -123.03506)
		(width 0.13462)
		(layer "F.Cu")
		(net "P5E_PEX2_STN0_TX_C_DP<2>")
	)
	(segment
		(start 311.627774 -122.8598)
		(end 306.13223 -122.8598)
		(width 0.13462)
		(layer "F.Cu")
		(net "P5E_PEX2_STN0_TX_C_DP<2>")
	)
	(segment
		(start 311.95264 -123.184666)
		(end 311.627774 -122.8598)
		(width 0.13462)
		(layer "F.Cu")
		(net "P5E_PEX2_STN0_TX_C_DP<2>")
	)
	(segment
		(start 399.42516 -110.245144)
		(end 398.94256 -110.245144)
		(width 0.13462)
		(layer "F.Cu")
		(net "P5E_PEX3_STN1_RX_DP<22>")
	)
	(segment
		(start 402.39696 -110.11281)
		(end 402.09089 -110.41888)
		(width 0.13462)
		(layer "F.Cu")
		(net "P5E_PEX3_STN1_RX_DP<22>")
	)
	(segment
		(start 402.09089 -110.41888)
		(end 399.598896 -110.41888)
		(width 0.13462)
		(layer "F.Cu")
		(net "P5E_PEX3_STN1_RX_DP<22>")
	)
	(segment
		(start 399.598896 -110.41888)
		(end 399.42516 -110.245144)
		(width 0.13462)
		(layer "F.Cu")
		(net "P5E_PEX3_STN1_RX_DP<22>")
	)
	(segment
		(start 413.033972 -271.554448)
		(end 413.079692 -271.600168)
		(width 0.1143)
		(layer "In5.Cu")
		(net "P5E_PEX3_STN1_RX_DP<22>")
	)
	(segment
		(start 385.37134 -140.590016)
		(end 383.48412 -144.791938)
		(width 0.1651)
		(layer "In5.Cu")
		(net "P5E_PEX3_STN1_RX_DP<22>")
	)
	(segment
		(start 392.788648 -114.177826)
		(end 392.623294 -114.24666)
		(width 0.1651)
		(layer "In5.Cu")
		(net "P5E_PEX3_STN1_RX_DP<22>")
	)
	(segment
		(start 382.382268 -150.991316)
		(end 382.382014 -150.991316)
		(width 0.1651)
		(layer "In5.Cu")
		(net "P5E_PEX3_STN1_RX_DP<22>")
	)
	(segment
		(start 392.171682 -114.24666)
		(end 391.54735 -114.534442)
		(width 0.1651)
		(layer "In5.Cu")
		(net "P5E_PEX3_STN1_RX_DP<22>")
	)
	(segment
		(start 400.087338 -110.40364)
		(end 395.884654 -112.114584)
		(width 0.1651)
		(layer "In5.Cu")
		(net "P5E_PEX3_STN1_RX_DP<22>")
	)
	(segment
		(start 413.079692 -271.600168)
		(end 413.079692 -273.45513)
		(width 0.1143)
		(layer "In5.Cu")
		(net "P5E_PEX3_STN1_RX_DP<22>")
	)
	(segment
		(start 383.92481 -164.482018)
		(end 413.033972 -268.825472)
		(width 0.1651)
		(layer "In5.Cu")
		(net "P5E_PEX3_STN1_RX_DP<22>")
	)
	(segment
		(start 387.308852 -136.92378)
		(end 385.37134 -140.590016)
		(width 0.1651)
		(layer "In5.Cu")
		(net "P5E_PEX3_STN1_RX_DP<22>")
	)
	(segment
		(start 413.033972 -268.825472)
		(end 413.033972 -271.526)
		(width 0.1651)
		(layer "In5.Cu")
		(net "P5E_PEX3_STN1_RX_DP<22>")
	)
	(segment
		(start 395.884654 -112.114584)
		(end 392.788648 -114.177826)
		(width 0.1651)
		(layer "In5.Cu")
		(net "P5E_PEX3_STN1_RX_DP<22>")
	)
	(segment
		(start 391.54735 -114.534442)
		(end 391.216642 -114.922554)
		(width 0.1651)
		(layer "In5.Cu")
		(net "P5E_PEX3_STN1_RX_DP<22>")
	)
	(segment
		(start 382.834896 -158.40456)
		(end 383.92481 -164.482018)
		(width 0.1651)
		(layer "In5.Cu")
		(net "P5E_PEX3_STN1_RX_DP<22>")
	)
	(segment
		(start 392.623294 -114.24666)
		(end 392.171682 -114.24666)
		(width 0.1651)
		(layer "In5.Cu")
		(net "P5E_PEX3_STN1_RX_DP<22>")
	)
	(segment
		(start 383.48412 -144.791938)
		(end 382.382268 -150.991316)
		(width 0.1651)
		(layer "In5.Cu")
		(net "P5E_PEX3_STN1_RX_DP<22>")
	)
	(segment
		(start 413.649668 -273.784314)
		(end 413.649668 -274.049744)
		(width 0.1143)
		(layer "In5.Cu")
		(net "P5E_PEX3_STN1_RX_DP<22>")
	)
	(segment
		(start 390.901174 -115.598956)
		(end 387.308852 -136.92378)
		(width 0.1651)
		(layer "In5.Cu")
		(net "P5E_PEX3_STN1_RX_DP<22>")
	)
	(segment
		(start 413.033972 -271.526)
		(end 413.033972 -271.554448)
		(width 0.1143)
		(layer "In5.Cu")
		(net "P5E_PEX3_STN1_RX_DP<22>")
	)
	(segment
		(start 413.079692 -273.45513)
		(end 413.294576 -273.670014)
		(width 0.1143)
		(layer "In5.Cu")
		(net "P5E_PEX3_STN1_RX_DP<22>")
	)
	(segment
		(start 391.216642 -114.922554)
		(end 390.901174 -115.598956)
		(width 0.1651)
		(layer "In5.Cu")
		(net "P5E_PEX3_STN1_RX_DP<22>")
	)
	(segment
		(start 413.535368 -273.670014)
		(end 413.649668 -273.784314)
		(width 0.1143)
		(layer "In5.Cu")
		(net "P5E_PEX3_STN1_RX_DP<22>")
	)
	(segment
		(start 382.376172 -151.024336)
		(end 382.834896 -158.40456)
		(width 0.1651)
		(layer "In5.Cu")
		(net "P5E_PEX3_STN1_RX_DP<22>")
	)
	(segment
		(start 382.382014 -150.991316)
		(end 382.376172 -151.024336)
		(width 0.1651)
		(layer "In5.Cu")
		(net "P5E_PEX3_STN1_RX_DP<22>")
	)
	(segment
		(start 402.10613 -110.40364)
		(end 400.087338 -110.40364)
		(width 0.1651)
		(layer "In5.Cu")
		(net "P5E_PEX3_STN1_RX_DP<22>")
	)
	(segment
		(start 402.39696 -110.11281)
		(end 402.10613 -110.40364)
		(width 0.1651)
		(layer "In5.Cu")
		(net "P5E_PEX3_STN1_RX_DP<22>")
	)
	(segment
		(start 413.294576 -273.670014)
		(end 413.535368 -273.670014)
		(width 0.1143)
		(layer "In5.Cu")
		(net "P5E_PEX3_STN1_RX_DP<22>")
	)
	(segment
		(start 397.49984 -316.534292)
		(end 397.49984 -316.799722)
		(width 0.1143)
		(layer "In15.Cu")
		(net "P5E_PEX3_STN6_RX_DN<105>")
	)
	(segment
		(start 397.38554 -316.419992)
		(end 397.49984 -316.534292)
		(width 0.1143)
		(layer "In15.Cu")
		(net "P5E_PEX3_STN6_RX_DN<105>")
	)
	(segment
		(start 394.532866 -326.613012)
		(end 396.588996 -323.502782)
		(width 0.1651)
		(layer "In15.Cu")
		(net "P5E_PEX3_STN6_RX_DN<105>")
	)
	(segment
		(start 373.470932 -384.722116)
		(end 373.028464 -372.949978)
		(width 0.1651)
		(layer "In15.Cu")
		(net "P5E_PEX3_STN6_RX_DN<105>")
	)
	(segment
		(start 388.68985 -401.308062)
		(end 388.81685 -401.181062)
		(width 0.1651)
		(layer "In15.Cu")
		(net "P5E_PEX3_STN6_RX_DN<105>")
	)
	(segment
		(start 379.28423 -358.964738)
		(end 379.53315 -358.033066)
		(width 0.1651)
		(layer "In15.Cu")
		(net "P5E_PEX3_STN6_RX_DN<105>")
	)
	(segment
		(start 389.815832 -400.729196)
		(end 389.815832 -395.477238)
		(width 0.1651)
		(layer "In15.Cu")
		(net "P5E_PEX3_STN6_RX_DN<105>")
	)
	(segment
		(start 389.498332 -394.5128)
		(end 387.796278 -392.7856)
		(width 0.1651)
		(layer "In15.Cu")
		(net "P5E_PEX3_STN6_RX_DN<105>")
	)
	(segment
		(start 388.81685 -401.181062)
		(end 389.363966 -401.181062)
		(width 0.1651)
		(layer "In15.Cu")
		(net "P5E_PEX3_STN6_RX_DN<105>")
	)
	(segment
		(start 379.53315 -358.033066)
		(end 379.53315 -342.172544)
		(width 0.1651)
		(layer "In15.Cu")
		(net "P5E_PEX3_STN6_RX_DN<105>")
	)
	(segment
		(start 397.223742 -316.419992)
		(end 397.38554 -316.419992)
		(width 0.1143)
		(layer "In15.Cu")
		(net "P5E_PEX3_STN6_RX_DN<105>")
	)
	(segment
		(start 374.244362 -367.727738)
		(end 379.28423 -358.964738)
		(width 0.1651)
		(layer "In15.Cu")
		(net "P5E_PEX3_STN6_RX_DN<105>")
	)
	(segment
		(start 373.194834 -371.08384)
		(end 373.540528 -369.344956)
		(width 0.1651)
		(layer "In15.Cu")
		(net "P5E_PEX3_STN6_RX_DN<105>")
	)
	(segment
		(start 373.540528 -369.344956)
		(end 374.244362 -367.727738)
		(width 0.1651)
		(layer "In15.Cu")
		(net "P5E_PEX3_STN6_RX_DN<105>")
	)
	(segment
		(start 397.16583 -322.109592)
		(end 397.16583 -319.995296)
		(width 0.1651)
		(layer "In15.Cu")
		(net "P5E_PEX3_STN6_RX_DN<105>")
	)
	(segment
		(start 389.363966 -401.181062)
		(end 389.815832 -400.729196)
		(width 0.1651)
		(layer "In15.Cu")
		(net "P5E_PEX3_STN6_RX_DN<105>")
	)
	(segment
		(start 389.815832 -395.477238)
		(end 389.498332 -394.5128)
		(width 0.1651)
		(layer "In15.Cu")
		(net "P5E_PEX3_STN6_RX_DN<105>")
	)
	(segment
		(start 380.04877 -340.962488)
		(end 390.27862 -330.527152)
		(width 0.1651)
		(layer "In15.Cu")
		(net "P5E_PEX3_STN6_RX_DN<105>")
	)
	(segment
		(start 375.959878 -387.4516)
		(end 373.92737 -386.014214)
		(width 0.1651)
		(layer "In15.Cu")
		(net "P5E_PEX3_STN6_RX_DN<105>")
	)
	(segment
		(start 379.53315 -342.172544)
		(end 380.04877 -340.962488)
		(width 0.1651)
		(layer "In15.Cu")
		(net "P5E_PEX3_STN6_RX_DN<105>")
	)
	(segment
		(start 397.12011 -319.921128)
		(end 397.12011 -316.523624)
		(width 0.1143)
		(layer "In15.Cu")
		(net "P5E_PEX3_STN6_RX_DN<105>")
	)
	(segment
		(start 397.16583 -319.995296)
		(end 397.16583 -319.966848)
		(width 0.1143)
		(layer "In15.Cu")
		(net "P5E_PEX3_STN6_RX_DN<105>")
	)
	(segment
		(start 387.796278 -392.7856)
		(end 386.221478 -391.8204)
		(width 0.1651)
		(layer "In15.Cu")
		(net "P5E_PEX3_STN6_RX_DN<105>")
	)
	(segment
		(start 373.92737 -386.014214)
		(end 373.470932 -384.722116)
		(width 0.1651)
		(layer "In15.Cu")
		(net "P5E_PEX3_STN6_RX_DN<105>")
	)
	(segment
		(start 397.16583 -319.966848)
		(end 397.12011 -319.921128)
		(width 0.1143)
		(layer "In15.Cu")
		(net "P5E_PEX3_STN6_RX_DN<105>")
	)
	(segment
		(start 397.12011 -316.523624)
		(end 397.223742 -316.419992)
		(width 0.1143)
		(layer "In15.Cu")
		(net "P5E_PEX3_STN6_RX_DN<105>")
	)
	(segment
		(start 396.588996 -323.502782)
		(end 397.16583 -322.109592)
		(width 0.1651)
		(layer "In15.Cu")
		(net "P5E_PEX3_STN6_RX_DN<105>")
	)
	(segment
		(start 373.028464 -372.949978)
		(end 373.194834 -371.08384)
		(width 0.1651)
		(layer "In15.Cu")
		(net "P5E_PEX3_STN6_RX_DN<105>")
	)
	(segment
		(start 388.68985 -401.690078)
		(end 388.68985 -401.308062)
		(width 0.1651)
		(layer "In15.Cu")
		(net "P5E_PEX3_STN6_RX_DN<105>")
	)
	(segment
		(start 390.27862 -330.527152)
		(end 394.532866 -326.613012)
		(width 0.1651)
		(layer "In15.Cu")
		(net "P5E_PEX3_STN6_RX_DN<105>")
	)
	(segment
		(start 386.221478 -391.8204)
		(end 375.959878 -387.4516)
		(width 0.1651)
		(layer "In15.Cu")
		(net "P5E_PEX3_STN6_RX_DN<105>")
	)
	(segment
		(start 188.873638 -114.635026)
		(end 188.528706 -114.290094)
		(width 0.13208)
		(layer "F.Cu")
		(net "RST_NIC3_PERST0_R_N")
	)
	(segment
		(start 188.528706 -114.290094)
		(end 186.842146 -114.290094)
		(width 0.13208)
		(layer "F.Cu")
		(net "RST_NIC3_PERST0_R_N")
	)
	(segment
		(start 189.357508 -114.635026)
		(end 188.873638 -114.635026)
		(width 0.13208)
		(layer "F.Cu")
		(net "RST_NIC3_PERST0_R_N")
	)
	(segment
		(start 197.739508 -87.749126)
		(end 197.739508 -88.39581)
		(width 0.13208)
		(layer "F.Cu")
		(net "RST_NIC3_PERST0_R_N")
	)
	(via
		(at 186.842146 -114.290094)
		(size 0.508)
		(drill 0.254)
		(layers "F.Cu" "B.Cu")
		(net "RST_NIC3_PERST0_R_N")
	)
	(via
		(at 197.739508 -88.39581)
		(size 0.508)
		(drill 0.254)
		(layers "F.Cu" "B.Cu")
		(net "RST_NIC3_PERST0_R_N")
	)
	(segment
		(start 185.842402 -114.290094)
		(end 185.34761 -113.795302)
		(width 0.15494)
		(layer "In11.Cu")
		(net "RST_NIC3_PERST0_R_N")
	)
	(segment
		(start 189.803786 -108.12145)
		(end 189.803786 -105.429812)
		(width 0.15494)
		(layer "In11.Cu")
		(net "RST_NIC3_PERST0_R_N")
	)
	(segment
		(start 188.99378 -104.619806)
		(end 188.99378 -98.06559)
		(width 0.15494)
		(layer "In11.Cu")
		(net "RST_NIC3_PERST0_R_N")
	)
	(segment
		(start 189.803786 -105.429812)
		(end 188.99378 -104.619806)
		(width 0.15494)
		(layer "In11.Cu")
		(net "RST_NIC3_PERST0_R_N")
	)
	(segment
		(start 197.252336 -88.882982)
		(end 197.739508 -88.39581)
		(width 0.15494)
		(layer "In11.Cu")
		(net "RST_NIC3_PERST0_R_N")
	)
	(segment
		(start 187.972446 -108.766356)
		(end 189.15888 -108.766356)
		(width 0.15494)
		(layer "In11.Cu")
		(net "RST_NIC3_PERST0_R_N")
	)
	(segment
		(start 185.34761 -113.795302)
		(end 185.34761 -111.391192)
		(width 0.15494)
		(layer "In11.Cu")
		(net "RST_NIC3_PERST0_R_N")
	)
	(segment
		(start 186.842146 -114.290094)
		(end 185.842402 -114.290094)
		(width 0.15494)
		(layer "In11.Cu")
		(net "RST_NIC3_PERST0_R_N")
	)
	(segment
		(start 189.15888 -108.766356)
		(end 189.803786 -108.12145)
		(width 0.15494)
		(layer "In11.Cu")
		(net "RST_NIC3_PERST0_R_N")
	)
	(segment
		(start 195.90766 -88.882982)
		(end 197.252336 -88.882982)
		(width 0.15494)
		(layer "In11.Cu")
		(net "RST_NIC3_PERST0_R_N")
	)
	(segment
		(start 188.99378 -98.06559)
		(end 190.794386 -96.264984)
		(width 0.15494)
		(layer "In11.Cu")
		(net "RST_NIC3_PERST0_R_N")
	)
	(segment
		(start 190.794386 -93.996256)
		(end 195.90766 -88.882982)
		(width 0.15494)
		(layer "In11.Cu")
		(net "RST_NIC3_PERST0_R_N")
	)
	(segment
		(start 190.794386 -96.264984)
		(end 190.794386 -93.996256)
		(width 0.15494)
		(layer "In11.Cu")
		(net "RST_NIC3_PERST0_R_N")
	)
	(segment
		(start 185.34761 -111.391192)
		(end 187.972446 -108.766356)
		(width 0.15494)
		(layer "In11.Cu")
		(net "RST_NIC3_PERST0_R_N")
	)
	(segment
		(start 126.28245 -30.790134)
		(end 126.119636 -30.62732)
		(width 0.13462)
		(layer "F.Cu")
		(net "P5E_PEX1_STN2_RX_DP<45>")
	)
	(segment
		(start 126.76505 -30.790134)
		(end 126.28245 -30.790134)
		(width 0.13462)
		(layer "F.Cu")
		(net "P5E_PEX1_STN2_RX_DP<45>")
	)
	(segment
		(start 123.605798 -30.62732)
		(end 123.31065 -30.922468)
		(width 0.13462)
		(layer "F.Cu")
		(net "P5E_PEX1_STN2_RX_DP<45>")
	)
	(segment
		(start 126.119636 -30.62732)
		(end 123.605798 -30.62732)
		(width 0.13462)
		(layer "F.Cu")
		(net "P5E_PEX1_STN2_RX_DP<45>")
	)
	(segment
		(start 128.016 -49.884838)
		(end 126.717806 -40.277288)
		(width 0.1651)
		(layer "In7.Cu")
		(net "P5E_PEX1_STN2_RX_DP<45>")
	)
	(segment
		(start 124.680218 -30.733238)
		(end 124.578618 -30.631638)
		(width 0.1651)
		(layer "In7.Cu")
		(net "P5E_PEX1_STN2_RX_DP<45>")
	)
	(segment
		(start 161.834068 -271.345152)
		(end 161.834068 -270.305276)
		(width 0.1651)
		(layer "In7.Cu")
		(net "P5E_PEX1_STN2_RX_DP<45>")
	)
	(segment
		(start 128.166622 -61.48832)
		(end 128.166622 -60.146692)
		(width 0.1651)
		(layer "In7.Cu")
		(net "P5E_PEX1_STN2_RX_DP<45>")
	)
	(segment
		(start 162.14217 -273.670014)
		(end 161.879788 -273.407632)
		(width 0.1143)
		(layer "In7.Cu")
		(net "P5E_PEX1_STN2_RX_DP<45>")
	)
	(segment
		(start 126.717806 -40.277288)
		(end 126.680976 -37.940234)
		(width 0.1651)
		(layer "In7.Cu")
		(net "P5E_PEX1_STN2_RX_DP<45>")
	)
	(segment
		(start 125.772418 -30.631638)
		(end 125.277118 -30.631638)
		(width 0.1651)
		(layer "In7.Cu")
		(net "P5E_PEX1_STN2_RX_DP<45>")
	)
	(segment
		(start 125.277118 -30.631638)
		(end 125.175518 -30.733238)
		(width 0.1651)
		(layer "In7.Cu")
		(net "P5E_PEX1_STN2_RX_DP<45>")
	)
	(segment
		(start 127.229616 -32.088836)
		(end 126.784354 -31.643574)
		(width 0.1651)
		(layer "In7.Cu")
		(net "P5E_PEX1_STN2_RX_DP<45>")
	)
	(segment
		(start 125.175518 -30.733238)
		(end 124.680218 -30.733238)
		(width 0.1651)
		(layer "In7.Cu")
		(net "P5E_PEX1_STN2_RX_DP<45>")
	)
	(segment
		(start 127.206248 -34.981642)
		(end 127.229616 -32.088836)
		(width 0.1651)
		(layer "In7.Cu")
		(net "P5E_PEX1_STN2_RX_DP<45>")
	)
	(segment
		(start 127.975614 -85.352382)
		(end 128.166622 -61.48832)
		(width 0.1651)
		(layer "In7.Cu")
		(net "P5E_PEX1_STN2_RX_DP<45>")
	)
	(segment
		(start 127.898906 -57.373774)
		(end 128.016 -49.884838)
		(width 0.1651)
		(layer "In7.Cu")
		(net "P5E_PEX1_STN2_RX_DP<45>")
	)
	(segment
		(start 128.166622 -60.146692)
		(end 127.898906 -57.373774)
		(width 0.1651)
		(layer "In7.Cu")
		(net "P5E_PEX1_STN2_RX_DP<45>")
	)
	(segment
		(start 126.680976 -37.940234)
		(end 127.206248 -34.981642)
		(width 0.1651)
		(layer "In7.Cu")
		(net "P5E_PEX1_STN2_RX_DP<45>")
	)
	(segment
		(start 126.290324 -31.293054)
		(end 126.290324 -31.149544)
		(width 0.1651)
		(layer "In7.Cu")
		(net "P5E_PEX1_STN2_RX_DP<45>")
	)
	(segment
		(start 162.335718 -273.670014)
		(end 162.14217 -273.670014)
		(width 0.1143)
		(layer "In7.Cu")
		(net "P5E_PEX1_STN2_RX_DP<45>")
	)
	(segment
		(start 160.871662 -263.52119)
		(end 160.948624 -255.658366)
		(width 0.1651)
		(layer "In7.Cu")
		(net "P5E_PEX1_STN2_RX_DP<45>")
	)
	(segment
		(start 124.578618 -30.631638)
		(end 123.60148 -30.631638)
		(width 0.1651)
		(layer "In7.Cu")
		(net "P5E_PEX1_STN2_RX_DP<45>")
	)
	(segment
		(start 141.640306 -144.549876)
		(end 138.36015 -119.612156)
		(width 0.1651)
		(layer "In7.Cu")
		(net "P5E_PEX1_STN2_RX_DP<45>")
	)
	(segment
		(start 161.879788 -271.41932)
		(end 161.834068 -271.3736)
		(width 0.1143)
		(layer "In7.Cu")
		(net "P5E_PEX1_STN2_RX_DP<45>")
	)
	(segment
		(start 133.165596 -102.474522)
		(end 133.165596 -102.474014)
		(width 0.1651)
		(layer "In7.Cu")
		(net "P5E_PEX1_STN2_RX_DP<45>")
	)
	(segment
		(start 161.834068 -270.305276)
		(end 160.871662 -263.52119)
		(width 0.1651)
		(layer "In7.Cu")
		(net "P5E_PEX1_STN2_RX_DP<45>")
	)
	(segment
		(start 161.834068 -271.3736)
		(end 161.834068 -271.345152)
		(width 0.1143)
		(layer "In7.Cu")
		(net "P5E_PEX1_STN2_RX_DP<45>")
	)
	(segment
		(start 162.450018 -273.784314)
		(end 162.335718 -273.670014)
		(width 0.1143)
		(layer "In7.Cu")
		(net "P5E_PEX1_STN2_RX_DP<45>")
	)
	(segment
		(start 133.165596 -102.474014)
		(end 127.975614 -85.352382)
		(width 0.1651)
		(layer "In7.Cu")
		(net "P5E_PEX1_STN2_RX_DP<45>")
	)
	(segment
		(start 159.351218 -238.208566)
		(end 141.640306 -144.549876)
		(width 0.1651)
		(layer "In7.Cu")
		(net "P5E_PEX1_STN2_RX_DP<45>")
	)
	(segment
		(start 162.450018 -274.049744)
		(end 162.450018 -273.784314)
		(width 0.1143)
		(layer "In7.Cu")
		(net "P5E_PEX1_STN2_RX_DP<45>")
	)
	(segment
		(start 126.290324 -31.149544)
		(end 125.772418 -30.631638)
		(width 0.1651)
		(layer "In7.Cu")
		(net "P5E_PEX1_STN2_RX_DP<45>")
	)
	(segment
		(start 126.640844 -31.643574)
		(end 126.290324 -31.293054)
		(width 0.1651)
		(layer "In7.Cu")
		(net "P5E_PEX1_STN2_RX_DP<45>")
	)
	(segment
		(start 123.60148 -30.631638)
		(end 123.31065 -30.922468)
		(width 0.1651)
		(layer "In7.Cu")
		(net "P5E_PEX1_STN2_RX_DP<45>")
	)
	(segment
		(start 126.784354 -31.643574)
		(end 126.640844 -31.643574)
		(width 0.1651)
		(layer "In7.Cu")
		(net "P5E_PEX1_STN2_RX_DP<45>")
	)
	(segment
		(start 133.177788 -102.514654)
		(end 133.177534 -102.513892)
		(width 0.1651)
		(layer "In7.Cu")
		(net "P5E_PEX1_STN2_RX_DP<45>")
	)
	(segment
		(start 133.177534 -102.513892)
		(end 133.165596 -102.474522)
		(width 0.1651)
		(layer "In7.Cu")
		(net "P5E_PEX1_STN2_RX_DP<45>")
	)
	(segment
		(start 161.879788 -273.407632)
		(end 161.879788 -271.41932)
		(width 0.1143)
		(layer "In7.Cu")
		(net "P5E_PEX1_STN2_RX_DP<45>")
	)
	(segment
		(start 160.948624 -255.658366)
		(end 159.351218 -238.208566)
		(width 0.1651)
		(layer "In7.Cu")
		(net "P5E_PEX1_STN2_RX_DP<45>")
	)
	(segment
		(start 138.36015 -119.612156)
		(end 133.177788 -102.514654)
		(width 0.1651)
		(layer "In7.Cu")
		(net "P5E_PEX1_STN2_RX_DP<45>")
	)
	(segment
		(start 297.700446 -148.59)
		(end 300.209712 -148.59)
		(width 0.13462)
		(layer "F.Cu")
		(net "P5E_PEX2_STN0_RX_DP<11>")
	)
	(segment
		(start 300.374812 -148.7551)
		(end 300.857412 -148.7551)
		(width 0.13462)
		(layer "F.Cu")
		(net "P5E_PEX2_STN0_RX_DP<11>")
	)
	(segment
		(start 297.403012 -148.887434)
		(end 297.700446 -148.59)
		(width 0.13462)
		(layer "F.Cu")
		(net "P5E_PEX2_STN0_RX_DP<11>")
	)
	(segment
		(start 300.209712 -148.59)
		(end 300.374812 -148.7551)
		(width 0.13462)
		(layer "F.Cu")
		(net "P5E_PEX2_STN0_RX_DP<11>")
	)
	(segment
		(start 310.233822 -270.887444)
		(end 310.233822 -271.526)
		(width 0.1651)
		(layer "In5.Cu")
		(net "P5E_PEX2_STN0_RX_DP<11>")
	)
	(segment
		(start 310.494426 -273.670014)
		(end 310.735218 -273.670014)
		(width 0.1143)
		(layer "In5.Cu")
		(net "P5E_PEX2_STN0_RX_DP<11>")
	)
	(segment
		(start 301.302674 -150.114)
		(end 301.302674 -150.23973)
		(width 0.1651)
		(layer "In5.Cu")
		(net "P5E_PEX2_STN0_RX_DP<11>")
	)
	(segment
		(start 310.735218 -273.670014)
		(end 310.849518 -273.784314)
		(width 0.1143)
		(layer "In5.Cu")
		(net "P5E_PEX2_STN0_RX_DP<11>")
	)
	(segment
		(start 307.21427 -161.206942)
		(end 307.214524 -161.207196)
		(width 0.1651)
		(layer "In5.Cu")
		(net "P5E_PEX2_STN0_RX_DP<11>")
	)
	(segment
		(start 300.476412 -149.413468)
		(end 300.826932 -149.763988)
		(width 0.1651)
		(layer "In5.Cu")
		(net "P5E_PEX2_STN0_RX_DP<11>")
	)
	(segment
		(start 310.279542 -273.45513)
		(end 310.494426 -273.670014)
		(width 0.1143)
		(layer "In5.Cu")
		(net "P5E_PEX2_STN0_RX_DP<11>")
	)
	(segment
		(start 303.823624 -154.844242)
		(end 305.950874 -158.044388)
		(width 0.1651)
		(layer "In5.Cu")
		(net "P5E_PEX2_STN0_RX_DP<11>")
	)
	(segment
		(start 307.192426 -161.108136)
		(end 307.192934 -161.110676)
		(width 0.1651)
		(layer "In5.Cu")
		(net "P5E_PEX2_STN0_RX_DP<11>")
	)
	(segment
		(start 307.19268 -161.107882)
		(end 307.19268 -161.108136)
		(width 0.1651)
		(layer "In5.Cu")
		(net "P5E_PEX2_STN0_RX_DP<11>")
	)
	(segment
		(start 301.302674 -150.23973)
		(end 301.653194 -150.59025)
		(width 0.1651)
		(layer "In5.Cu")
		(net "P5E_PEX2_STN0_RX_DP<11>")
	)
	(segment
		(start 310.849518 -273.784314)
		(end 310.849518 -274.049744)
		(width 0.1143)
		(layer "In5.Cu")
		(net "P5E_PEX2_STN0_RX_DP<11>")
	)
	(segment
		(start 307.19268 -161.108136)
		(end 307.192426 -161.108136)
		(width 0.1651)
		(layer "In5.Cu")
		(net "P5E_PEX2_STN0_RX_DP<11>")
	)
	(segment
		(start 297.403012 -148.887434)
		(end 297.693842 -148.596604)
		(width 0.1651)
		(layer "In5.Cu")
		(net "P5E_PEX2_STN0_RX_DP<11>")
	)
	(segment
		(start 307.1495 -160.910778)
		(end 307.19268 -161.107882)
		(width 0.1651)
		(layer "In5.Cu")
		(net "P5E_PEX2_STN0_RX_DP<11>")
	)
	(segment
		(start 307.192934 -161.110676)
		(end 307.21427 -161.206942)
		(width 0.1651)
		(layer "In5.Cu")
		(net "P5E_PEX2_STN0_RX_DP<11>")
	)
	(segment
		(start 302.245014 -151.05634)
		(end 303.823624 -154.844242)
		(width 0.1651)
		(layer "In5.Cu")
		(net "P5E_PEX2_STN0_RX_DP<11>")
	)
	(segment
		(start 299.785278 -148.596604)
		(end 300.476412 -149.287738)
		(width 0.1651)
		(layer "In5.Cu")
		(net "P5E_PEX2_STN0_RX_DP<11>")
	)
	(segment
		(start 305.950874 -158.044388)
		(end 307.1495 -160.910778)
		(width 0.1651)
		(layer "In5.Cu")
		(net "P5E_PEX2_STN0_RX_DP<11>")
	)
	(segment
		(start 300.826932 -149.763988)
		(end 300.952662 -149.763988)
		(width 0.1651)
		(layer "In5.Cu")
		(net "P5E_PEX2_STN0_RX_DP<11>")
	)
	(segment
		(start 310.775858 -268.129258)
		(end 310.233822 -270.887444)
		(width 0.1651)
		(layer "In5.Cu")
		(net "P5E_PEX2_STN0_RX_DP<11>")
	)
	(segment
		(start 301.778924 -150.59025)
		(end 302.245014 -151.05634)
		(width 0.1651)
		(layer "In5.Cu")
		(net "P5E_PEX2_STN0_RX_DP<11>")
	)
	(segment
		(start 307.23586 -161.304478)
		(end 310.74106 -260.519164)
		(width 0.1651)
		(layer "In5.Cu")
		(net "P5E_PEX2_STN0_RX_DP<11>")
	)
	(segment
		(start 297.693842 -148.596604)
		(end 299.785278 -148.596604)
		(width 0.1651)
		(layer "In5.Cu")
		(net "P5E_PEX2_STN0_RX_DP<11>")
	)
	(segment
		(start 310.233822 -271.526)
		(end 310.233822 -271.554448)
		(width 0.1143)
		(layer "In5.Cu")
		(net "P5E_PEX2_STN0_RX_DP<11>")
	)
	(segment
		(start 300.476412 -149.287738)
		(end 300.476412 -149.413468)
		(width 0.1651)
		(layer "In5.Cu")
		(net "P5E_PEX2_STN0_RX_DP<11>")
	)
	(segment
		(start 310.233822 -271.554448)
		(end 310.279542 -271.600168)
		(width 0.1143)
		(layer "In5.Cu")
		(net "P5E_PEX2_STN0_RX_DP<11>")
	)
	(segment
		(start 310.74106 -260.519164)
		(end 310.775858 -268.129258)
		(width 0.1651)
		(layer "In5.Cu")
		(net "P5E_PEX2_STN0_RX_DP<11>")
	)
	(segment
		(start 300.952662 -149.763988)
		(end 301.302674 -150.114)
		(width 0.1651)
		(layer "In5.Cu")
		(net "P5E_PEX2_STN0_RX_DP<11>")
	)
	(segment
		(start 301.653194 -150.59025)
		(end 301.778924 -150.59025)
		(width 0.1651)
		(layer "In5.Cu")
		(net "P5E_PEX2_STN0_RX_DP<11>")
	)
	(segment
		(start 310.279542 -271.600168)
		(end 310.279542 -273.45513)
		(width 0.1143)
		(layer "In5.Cu")
		(net "P5E_PEX2_STN0_RX_DP<11>")
	)
	(segment
		(start 307.214524 -161.207196)
		(end 307.23586 -161.304478)
		(width 0.1651)
		(layer "In5.Cu")
		(net "P5E_PEX2_STN0_RX_DP<11>")
	)
	(segment
		(start 387.847332 -121.005346)
		(end 388.157466 -121.31548)
		(width 0.13462)
		(layer "F.Cu")
		(net "P5E_PEX3_STN1_TX_C_DN<25>")
	)
	(segment
		(start 388.157466 -121.31548)
		(end 393.682474 -121.31548)
		(width 0.13462)
		(layer "F.Cu")
		(net "P5E_PEX3_STN1_TX_C_DN<25>")
	)
	(segment
		(start 393.682474 -121.31548)
		(end 393.843002 -121.154952)
		(width 0.13462)
		(layer "F.Cu")
		(net "P5E_PEX3_STN1_TX_C_DN<25>")
	)
	(segment
		(start 393.843002 -121.154952)
		(end 394.342366 -121.154952)
		(width 0.13462)
		(layer "F.Cu")
		(net "P5E_PEX3_STN1_TX_C_DN<25>")
	)
	(segment
		(start 383.918968 -357.462582)
		(end 383.62382 -357.75773)
		(width 0.13462)
		(layer "F.Cu")
		(net "P5E_PEX3_STN6_TX_C_DP<105>")
	)
	(segment
		(start 383.918968 -356.832154)
		(end 383.918968 -357.462582)
		(width 0.13462)
		(layer "F.Cu")
		(net "P5E_PEX3_STN6_TX_C_DP<105>")
	)
	(segment
		(start 383.59842 -356.511606)
		(end 383.918968 -356.832154)
		(width 0.13462)
		(layer "F.Cu")
		(net "P5E_PEX3_STN6_TX_C_DP<105>")
	)
	(segment
		(start 388.68985 -408.190192)
		(end 388.68985 -408.572208)
		(width 0.1651)
		(layer "In13.Cu")
		(net "P5E_PEX3_STN6_TX_C_DP<105>")
	)
	(segment
		(start 389.247126 -408.699208)
		(end 389.533892 -408.412442)
		(width 0.1651)
		(layer "In13.Cu")
		(net "P5E_PEX3_STN6_TX_C_DP<105>")
	)
	(segment
		(start 387.619494 -393.008104)
		(end 387.18109 -392.739372)
		(width 0.1651)
		(layer "In13.Cu")
		(net "P5E_PEX3_STN6_TX_C_DP<105>")
	)
	(segment
		(start 389.533892 -408.412442)
		(end 389.533892 -395.523466)
		(width 0.1651)
		(layer "In13.Cu")
		(net "P5E_PEX3_STN6_TX_C_DP<105>")
	)
	(segment
		(start 383.91465 -358.04856)
		(end 383.62382 -357.75773)
		(width 0.1651)
		(layer "In13.Cu")
		(net "P5E_PEX3_STN6_TX_C_DP<105>")
	)
	(segment
		(start 389.533892 -395.523466)
		(end 389.250682 -394.663676)
		(width 0.1651)
		(layer "In13.Cu")
		(net "P5E_PEX3_STN6_TX_C_DP<105>")
	)
	(segment
		(start 373.691404 -386.192776)
		(end 373.19077 -384.77571)
		(width 0.1651)
		(layer "In13.Cu")
		(net "P5E_PEX3_STN6_TX_C_DP<105>")
	)
	(segment
		(start 387.18109 -392.739372)
		(end 387.04139 -392.7729)
		(width 0.1651)
		(layer "In13.Cu")
		(net "P5E_PEX3_STN6_TX_C_DP<105>")
	)
	(segment
		(start 388.81685 -408.699208)
		(end 389.247126 -408.699208)
		(width 0.1651)
		(layer "In13.Cu")
		(net "P5E_PEX3_STN6_TX_C_DP<105>")
	)
	(segment
		(start 372.746778 -372.933722)
		(end 372.747286 -372.925848)
		(width 0.1651)
		(layer "In13.Cu")
		(net "P5E_PEX3_STN6_TX_C_DP<105>")
	)
	(segment
		(start 374.81256 -366.723676)
		(end 383.518918 -359.247948)
		(width 0.1651)
		(layer "In13.Cu")
		(net "P5E_PEX3_STN6_TX_C_DP<105>")
	)
	(segment
		(start 388.200646 -393.742672)
		(end 388.201662 -393.598908)
		(width 0.1651)
		(layer "In13.Cu")
		(net "P5E_PEX3_STN6_TX_C_DP<105>")
	)
	(segment
		(start 386.618734 -392.51382)
		(end 386.585206 -392.37412)
		(width 0.1651)
		(layer "In13.Cu")
		(net "P5E_PEX3_STN6_TX_C_DP<105>")
	)
	(segment
		(start 388.201662 -393.598908)
		(end 387.619494 -393.008104)
		(width 0.1651)
		(layer "In13.Cu")
		(net "P5E_PEX3_STN6_TX_C_DP<105>")
	)
	(segment
		(start 388.68985 -408.572208)
		(end 388.81685 -408.699208)
		(width 0.1651)
		(layer "In13.Cu")
		(net "P5E_PEX3_STN6_TX_C_DP<105>")
	)
	(segment
		(start 383.518918 -359.247948)
		(end 383.91465 -358.387142)
		(width 0.1651)
		(layer "In13.Cu")
		(net "P5E_PEX3_STN6_TX_C_DP<105>")
	)
	(segment
		(start 383.91465 -358.387142)
		(end 383.91465 -358.04856)
		(width 0.1651)
		(layer "In13.Cu")
		(net "P5E_PEX3_STN6_TX_C_DP<105>")
	)
	(segment
		(start 386.585206 -392.37412)
		(end 386.091684 -392.07186)
		(width 0.1651)
		(layer "In13.Cu")
		(net "P5E_PEX3_STN6_TX_C_DP<105>")
	)
	(segment
		(start 373.086122 -368.95659)
		(end 374.81256 -366.723676)
		(width 0.1651)
		(layer "In13.Cu")
		(net "P5E_PEX3_STN6_TX_C_DP<105>")
	)
	(segment
		(start 375.821702 -387.69925)
		(end 373.691404 -386.192776)
		(width 0.1651)
		(layer "In13.Cu")
		(net "P5E_PEX3_STN6_TX_C_DP<105>")
	)
	(segment
		(start 386.091684 -392.07186)
		(end 375.821702 -387.69925)
		(width 0.1651)
		(layer "In13.Cu")
		(net "P5E_PEX3_STN6_TX_C_DP<105>")
	)
	(segment
		(start 389.250682 -394.663676)
		(end 388.692136 -394.096748)
		(width 0.1651)
		(layer "In13.Cu")
		(net "P5E_PEX3_STN6_TX_C_DP<105>")
	)
	(segment
		(start 388.548372 -394.095732)
		(end 388.200646 -393.742672)
		(width 0.1651)
		(layer "In13.Cu")
		(net "P5E_PEX3_STN6_TX_C_DP<105>")
	)
	(segment
		(start 372.747286 -372.925848)
		(end 373.086122 -368.95659)
		(width 0.1651)
		(layer "In13.Cu")
		(net "P5E_PEX3_STN6_TX_C_DP<105>")
	)
	(segment
		(start 388.692136 -394.096748)
		(end 388.548372 -394.095732)
		(width 0.1651)
		(layer "In13.Cu")
		(net "P5E_PEX3_STN6_TX_C_DP<105>")
	)
	(segment
		(start 387.04139 -392.7729)
		(end 386.618734 -392.51382)
		(width 0.1651)
		(layer "In13.Cu")
		(net "P5E_PEX3_STN6_TX_C_DP<105>")
	)
	(segment
		(start 372.746016 -372.942612)
		(end 372.746778 -372.933722)
		(width 0.1651)
		(layer "In13.Cu")
		(net "P5E_PEX3_STN6_TX_C_DP<105>")
	)
	(segment
		(start 373.19077 -384.77571)
		(end 372.746016 -372.942612)
		(width 0.1651)
		(layer "In13.Cu")
		(net "P5E_PEX3_STN6_TX_C_DP<105>")
	)
	(segment
		(start 189.357508 -99.439984)
		(end 191.791844 -99.439984)
		(width 0.13208)
		(layer "F.Cu")
		(net "NIC3_DATA_OUT")
	)
	(via
		(at 191.791844 -99.439984)
		(size 0.508)
		(drill 0.254)
		(layers "F.Cu" "B.Cu")
		(net "NIC3_DATA_OUT")
	)
	(segment
		(start 193.241676 -98.021648)
		(end 191.82334 -99.439984)
		(width 0.13208)
		(layer "B.Cu")
		(net "NIC3_DATA_OUT")
	)
	(segment
		(start 191.82334 -99.439984)
		(end 191.791844 -99.439984)
		(width 0.13208)
		(layer "B.Cu")
		(net "NIC3_DATA_OUT")
	)
	(segment
		(start 62.024514 -28.829)
		(end 61.358018 -28.829)
		(width 0.13462)
		(layer "F.Cu")
		(net "P5E_PEX0_STN2_RX_DP<36>")
	)
	(segment
		(start 62.664848 -28.99029)
		(end 62.185804 -28.99029)
		(width 0.13462)
		(layer "F.Cu")
		(net "P5E_PEX0_STN2_RX_DP<36>")
	)
	(segment
		(start 62.664848 -28.990036)
		(end 62.664848 -28.99029)
		(width 0.13462)
		(layer "F.Cu")
		(net "P5E_PEX0_STN2_RX_DP<36>")
	)
	(segment
		(start 62.185804 -28.99029)
		(end 62.024514 -28.829)
		(width 0.13462)
		(layer "F.Cu")
		(net "P5E_PEX0_STN2_RX_DP<36>")
	)
	(segment
		(start 61.358018 -28.829)
		(end 61.064648 -29.12237)
		(width 0.13462)
		(layer "F.Cu")
		(net "P5E_PEX0_STN2_RX_DP<36>")
	)
	(segment
		(start 61.686948 -28.83154)
		(end 62.383162 -29.527754)
		(width 0.1651)
		(layer "In7.Cu")
		(net "P5E_PEX0_STN2_RX_DP<36>")
	)
	(segment
		(start 63.721742 -30.866334)
		(end 64.464184 -31.608776)
		(width 0.1651)
		(layer "In7.Cu")
		(net "P5E_PEX0_STN2_RX_DP<36>")
	)
	(segment
		(start 61.064648 -29.12237)
		(end 61.309758 -28.87726)
		(width 0.1651)
		(layer "In7.Cu")
		(net "P5E_PEX0_STN2_RX_DP<36>")
	)
	(segment
		(start 61.419994 -28.83154)
		(end 61.686948 -28.83154)
		(width 0.1651)
		(layer "In7.Cu")
		(net "P5E_PEX0_STN2_RX_DP<36>")
	)
	(segment
		(start 54.785514 -275.570188)
		(end 54.899814 -275.684488)
		(width 0.1143)
		(layer "In7.Cu")
		(net "P5E_PEX0_STN2_RX_DP<36>")
	)
	(segment
		(start 63.577978 -30.866334)
		(end 63.721742 -30.866334)
		(width 0.1651)
		(layer "In7.Cu")
		(net "P5E_PEX0_STN2_RX_DP<36>")
	)
	(segment
		(start 67.025012 -39.138098)
		(end 65.001394 -48.804068)
		(width 0.1651)
		(layer "In7.Cu")
		(net "P5E_PEX0_STN2_RX_DP<36>")
	)
	(segment
		(start 62.383162 -29.671518)
		(end 62.733682 -30.022038)
		(width 0.1651)
		(layer "In7.Cu")
		(net "P5E_PEX0_STN2_RX_DP<36>")
	)
	(segment
		(start 62.733682 -30.022038)
		(end 62.877446 -30.022038)
		(width 0.1651)
		(layer "In7.Cu")
		(net "P5E_PEX0_STN2_RX_DP<36>")
	)
	(segment
		(start 64.80175 -68.365624)
		(end 54.41823 -264.952226)
		(width 0.1651)
		(layer "In7.Cu")
		(net "P5E_PEX0_STN2_RX_DP<36>")
	)
	(segment
		(start 54.28361 -271.421352)
		(end 54.32933 -271.467072)
		(width 0.1143)
		(layer "In7.Cu")
		(net "P5E_PEX0_STN2_RX_DP<36>")
	)
	(segment
		(start 62.383162 -29.527754)
		(end 62.383162 -29.671518)
		(width 0.1651)
		(layer "In7.Cu")
		(net "P5E_PEX0_STN2_RX_DP<36>")
	)
	(segment
		(start 54.32933 -271.467072)
		(end 54.32933 -275.354796)
		(width 0.1143)
		(layer "In7.Cu")
		(net "P5E_PEX0_STN2_RX_DP<36>")
	)
	(segment
		(start 54.41823 -264.952226)
		(end 54.28361 -266.487402)
		(width 0.1651)
		(layer "In7.Cu")
		(net "P5E_PEX0_STN2_RX_DP<36>")
	)
	(segment
		(start 67.04838 -37.742622)
		(end 67.025012 -39.138098)
		(width 0.1651)
		(layer "In7.Cu")
		(net "P5E_PEX0_STN2_RX_DP<36>")
	)
	(segment
		(start 54.899814 -275.684488)
		(end 54.899814 -275.949918)
		(width 0.1143)
		(layer "In7.Cu")
		(net "P5E_PEX0_STN2_RX_DP<36>")
	)
	(segment
		(start 54.28361 -271.392904)
		(end 54.28361 -271.421352)
		(width 0.1143)
		(layer "In7.Cu")
		(net "P5E_PEX0_STN2_RX_DP<36>")
	)
	(segment
		(start 54.28361 -266.487402)
		(end 54.28361 -271.392904)
		(width 0.1651)
		(layer "In7.Cu")
		(net "P5E_PEX0_STN2_RX_DP<36>")
	)
	(segment
		(start 65.001394 -48.804068)
		(end 64.80175 -68.365624)
		(width 0.1651)
		(layer "In7.Cu")
		(net "P5E_PEX0_STN2_RX_DP<36>")
	)
	(segment
		(start 63.227458 -30.37205)
		(end 63.227458 -30.515814)
		(width 0.1651)
		(layer "In7.Cu")
		(net "P5E_PEX0_STN2_RX_DP<36>")
	)
	(segment
		(start 64.464184 -31.608776)
		(end 67.04838 -37.742622)
		(width 0.1651)
		(layer "In7.Cu")
		(net "P5E_PEX0_STN2_RX_DP<36>")
	)
	(segment
		(start 62.877446 -30.022038)
		(end 63.227458 -30.37205)
		(width 0.1651)
		(layer "In7.Cu")
		(net "P5E_PEX0_STN2_RX_DP<36>")
	)
	(segment
		(start 63.227458 -30.515814)
		(end 63.577978 -30.866334)
		(width 0.1651)
		(layer "In7.Cu")
		(net "P5E_PEX0_STN2_RX_DP<36>")
	)
	(segment
		(start 61.309758 -28.87726)
		(end 61.419994 -28.83154)
		(width 0.1651)
		(layer "In7.Cu")
		(net "P5E_PEX0_STN2_RX_DP<36>")
	)
	(segment
		(start 54.544722 -275.570188)
		(end 54.785514 -275.570188)
		(width 0.1143)
		(layer "In7.Cu")
		(net "P5E_PEX0_STN2_RX_DP<36>")
	)
	(segment
		(start 54.32933 -275.354796)
		(end 54.544722 -275.570188)
		(width 0.1143)
		(layer "In7.Cu")
		(net "P5E_PEX0_STN2_RX_DP<36>")
	)
	(segment
		(start 152.282398 -34.390076)
		(end 152.119584 -34.227262)
		(width 0.13462)
		(layer "F.Cu")
		(net "P5E_PEX1_STN2_RX_DP<43>")
	)
	(segment
		(start 149.605746 -34.227262)
		(end 149.310598 -34.52241)
		(width 0.13462)
		(layer "F.Cu")
		(net "P5E_PEX1_STN2_RX_DP<43>")
	)
	(segment
		(start 152.764998 -34.390076)
		(end 152.282398 -34.390076)
		(width 0.13462)
		(layer "F.Cu")
		(net "P5E_PEX1_STN2_RX_DP<43>")
	)
	(segment
		(start 152.119584 -34.227262)
		(end 149.605746 -34.227262)
		(width 0.13462)
		(layer "F.Cu")
		(net "P5E_PEX1_STN2_RX_DP<43>")
	)
	(segment
		(start 163.733988 -271.345152)
		(end 163.733988 -267.885926)
		(width 0.1651)
		(layer "In7.Cu")
		(net "P5E_PEX1_STN2_RX_DP<43>")
	)
	(segment
		(start 164.349938 -274.049744)
		(end 164.349938 -273.784314)
		(width 0.1143)
		(layer "In7.Cu")
		(net "P5E_PEX1_STN2_RX_DP<43>")
	)
	(segment
		(start 155.153614 -141.679676)
		(end 155.18765 -138.494516)
		(width 0.1651)
		(layer "In7.Cu")
		(net "P5E_PEX1_STN2_RX_DP<43>")
	)
	(segment
		(start 152.386792 -65.267332)
		(end 151.995124 -55.483252)
		(width 0.1651)
		(layer "In7.Cu")
		(net "P5E_PEX1_STN2_RX_DP<43>")
	)
	(segment
		(start 163.733988 -271.3736)
		(end 163.733988 -271.345152)
		(width 0.1143)
		(layer "In7.Cu")
		(net "P5E_PEX1_STN2_RX_DP<43>")
	)
	(segment
		(start 163.275518 -262.82015)
		(end 163.552886 -248.479818)
		(width 0.1651)
		(layer "In7.Cu")
		(net "P5E_PEX1_STN2_RX_DP<43>")
	)
	(segment
		(start 150.636986 -37.459158)
		(end 150.629366 -36.963604)
		(width 0.1651)
		(layer "In7.Cu")
		(net "P5E_PEX1_STN2_RX_DP<43>")
	)
	(segment
		(start 163.779708 -273.407632)
		(end 163.779708 -271.41932)
		(width 0.1143)
		(layer "In7.Cu")
		(net "P5E_PEX1_STN2_RX_DP<43>")
	)
	(segment
		(start 150.655528 -38.652704)
		(end 150.647908 -38.157404)
		(width 0.1651)
		(layer "In7.Cu")
		(net "P5E_PEX1_STN2_RX_DP<43>")
	)
	(segment
		(start 150.774908 -39.786052)
		(end 150.758906 -38.75278)
		(width 0.1651)
		(layer "In7.Cu")
		(net "P5E_PEX1_STN2_RX_DP<43>")
	)
	(segment
		(start 155.892754 -131.969002)
		(end 156.026104 -119.595392)
		(width 0.1651)
		(layer "In7.Cu")
		(net "P5E_PEX1_STN2_RX_DP<43>")
	)
	(segment
		(start 150.706328 -35.1028)
		(end 149.835108 -34.23158)
		(width 0.1651)
		(layer "In7.Cu")
		(net "P5E_PEX1_STN2_RX_DP<43>")
	)
	(segment
		(start 150.647908 -38.157404)
		(end 150.747984 -38.05428)
		(width 0.1651)
		(layer "In7.Cu")
		(net "P5E_PEX1_STN2_RX_DP<43>")
	)
	(segment
		(start 151.995124 -55.483252)
		(end 152.088596 -49.509426)
		(width 0.1651)
		(layer "In7.Cu")
		(net "P5E_PEX1_STN2_RX_DP<43>")
	)
	(segment
		(start 150.706328 -35.357562)
		(end 150.706328 -35.1028)
		(width 0.1651)
		(layer "In7.Cu")
		(net "P5E_PEX1_STN2_RX_DP<43>")
	)
	(segment
		(start 150.747984 -38.05428)
		(end 150.740364 -37.559234)
		(width 0.1651)
		(layer "In7.Cu")
		(net "P5E_PEX1_STN2_RX_DP<43>")
	)
	(segment
		(start 149.835108 -34.23158)
		(end 149.601428 -34.23158)
		(width 0.1651)
		(layer "In7.Cu")
		(net "P5E_PEX1_STN2_RX_DP<43>")
	)
	(segment
		(start 155.18765 -138.494516)
		(end 155.892754 -131.969002)
		(width 0.1651)
		(layer "In7.Cu")
		(net "P5E_PEX1_STN2_RX_DP<43>")
	)
	(segment
		(start 163.779708 -271.41932)
		(end 163.733988 -271.3736)
		(width 0.1143)
		(layer "In7.Cu")
		(net "P5E_PEX1_STN2_RX_DP<43>")
	)
	(segment
		(start 163.733988 -267.885926)
		(end 163.275518 -263.230106)
		(width 0.1651)
		(layer "In7.Cu")
		(net "P5E_PEX1_STN2_RX_DP<43>")
	)
	(segment
		(start 150.729442 -36.86048)
		(end 150.706328 -35.357562)
		(width 0.1651)
		(layer "In7.Cu")
		(net "P5E_PEX1_STN2_RX_DP<43>")
	)
	(segment
		(start 164.349938 -273.784314)
		(end 164.235638 -273.670014)
		(width 0.1143)
		(layer "In7.Cu")
		(net "P5E_PEX1_STN2_RX_DP<43>")
	)
	(segment
		(start 150.740364 -37.559234)
		(end 150.636986 -37.459158)
		(width 0.1651)
		(layer "In7.Cu")
		(net "P5E_PEX1_STN2_RX_DP<43>")
	)
	(segment
		(start 156.026104 -119.595392)
		(end 155.58897 -105.153714)
		(width 0.1651)
		(layer "In7.Cu")
		(net "P5E_PEX1_STN2_RX_DP<43>")
	)
	(segment
		(start 155.58897 -105.153714)
		(end 152.386792 -65.267332)
		(width 0.1651)
		(layer "In7.Cu")
		(net "P5E_PEX1_STN2_RX_DP<43>")
	)
	(segment
		(start 163.275518 -263.230106)
		(end 163.275518 -262.82015)
		(width 0.1651)
		(layer "In7.Cu")
		(net "P5E_PEX1_STN2_RX_DP<43>")
	)
	(segment
		(start 150.629366 -36.963604)
		(end 150.729442 -36.86048)
		(width 0.1651)
		(layer "In7.Cu")
		(net "P5E_PEX1_STN2_RX_DP<43>")
	)
	(segment
		(start 164.04209 -273.670014)
		(end 163.779708 -273.407632)
		(width 0.1143)
		(layer "In7.Cu")
		(net "P5E_PEX1_STN2_RX_DP<43>")
	)
	(segment
		(start 163.552886 -248.479818)
		(end 155.153614 -141.679676)
		(width 0.1651)
		(layer "In7.Cu")
		(net "P5E_PEX1_STN2_RX_DP<43>")
	)
	(segment
		(start 164.235638 -273.670014)
		(end 164.04209 -273.670014)
		(width 0.1143)
		(layer "In7.Cu")
		(net "P5E_PEX1_STN2_RX_DP<43>")
	)
	(segment
		(start 152.088596 -49.509426)
		(end 150.774908 -39.786052)
		(width 0.1651)
		(layer "In7.Cu")
		(net "P5E_PEX1_STN2_RX_DP<43>")
	)
	(segment
		(start 150.758906 -38.75278)
		(end 150.655528 -38.652704)
		(width 0.1651)
		(layer "In7.Cu")
		(net "P5E_PEX1_STN2_RX_DP<43>")
	)
	(segment
		(start 149.601428 -34.23158)
		(end 149.310598 -34.52241)
		(width 0.1651)
		(layer "In7.Cu")
		(net "P5E_PEX1_STN2_RX_DP<43>")
	)
	(segment
		(start 300.207172 -135.8773)
		(end 297.702986 -135.8773)
		(width 0.13462)
		(layer "F.Cu")
		(net "P5E_PEX2_STN0_RX_DP<7>")
	)
	(segment
		(start 300.374812 -136.04494)
		(end 300.207172 -135.8773)
		(width 0.13462)
		(layer "F.Cu")
		(net "P5E_PEX2_STN0_RX_DP<7>")
	)
	(segment
		(start 300.857412 -136.04494)
		(end 300.374812 -136.04494)
		(width 0.13462)
		(layer "F.Cu")
		(net "P5E_PEX2_STN0_RX_DP<7>")
	)
	(segment
		(start 297.702986 -135.8773)
		(end 297.403012 -136.177274)
		(width 0.13462)
		(layer "F.Cu")
		(net "P5E_PEX2_STN0_RX_DP<7>")
	)
	(segment
		(start 314.079636 -281.29484)
		(end 314.079636 -281.535632)
		(width 0.1143)
		(layer "In5.Cu")
		(net "P5E_PEX2_STN0_RX_DP<7>")
	)
	(segment
		(start 316.591188 -280.407364)
		(end 316.360556 -280.94559)
		(width 0.1651)
		(layer "In5.Cu")
		(net "P5E_PEX2_STN0_RX_DP<7>")
	)
	(segment
		(start 307.47462 -144.159732)
		(end 307.584348 -144.642586)
		(width 0.1651)
		(layer "In5.Cu")
		(net "P5E_PEX2_STN0_RX_DP<7>")
	)
	(segment
		(start 307.879242 -146.451574)
		(end 308.016148 -146.53768)
		(width 0.1651)
		(layer "In5.Cu")
		(net "P5E_PEX2_STN0_RX_DP<7>")
	)
	(segment
		(start 314.752736 -264.857484)
		(end 315.406278 -269.468854)
		(width 0.1651)
		(layer "In5.Cu")
		(net "P5E_PEX2_STN0_RX_DP<7>")
	)
	(segment
		(start 314.079636 -281.535632)
		(end 313.965336 -281.649932)
		(width 0.1143)
		(layer "In5.Cu")
		(net "P5E_PEX2_STN0_RX_DP<7>")
	)
	(segment
		(start 304.006504 -137.671302)
		(end 305.243992 -138.926062)
		(width 0.1651)
		(layer "In5.Cu")
		(net "P5E_PEX2_STN0_RX_DP<7>")
	)
	(segment
		(start 315.406278 -269.468854)
		(end 316.677802 -276.331172)
		(width 0.1651)
		(layer "In5.Cu")
		(net "P5E_PEX2_STN0_RX_DP<7>")
	)
	(segment
		(start 316.14999 -281.033982)
		(end 316.121542 -281.033982)
		(width 0.1143)
		(layer "In5.Cu")
		(net "P5E_PEX2_STN0_RX_DP<7>")
	)
	(segment
		(start 305.924712 -140.697204)
		(end 306.796186 -141.568678)
		(width 0.1651)
		(layer "In5.Cu")
		(net "P5E_PEX2_STN0_RX_DP<7>")
	)
	(segment
		(start 300.409102 -136.331706)
		(end 300.86808 -136.518396)
		(width 0.1651)
		(layer "In5.Cu")
		(net "P5E_PEX2_STN0_RX_DP<7>")
	)
	(segment
		(start 303.276 -137.374376)
		(end 304.006504 -137.671302)
		(width 0.1651)
		(layer "In5.Cu")
		(net "P5E_PEX2_STN0_RX_DP<7>")
	)
	(segment
		(start 316.121542 -281.033982)
		(end 316.075822 -281.079702)
		(width 0.1143)
		(layer "In5.Cu")
		(net "P5E_PEX2_STN0_RX_DP<7>")
	)
	(segment
		(start 307.76926 -145.968466)
		(end 307.879242 -146.451574)
		(width 0.1651)
		(layer "In5.Cu")
		(net "P5E_PEX2_STN0_RX_DP<7>")
	)
	(segment
		(start 300.86808 -136.518396)
		(end 301.016924 -136.455404)
		(width 0.1651)
		(layer "In5.Cu")
		(net "P5E_PEX2_STN0_RX_DP<7>")
	)
	(segment
		(start 311.198768 -160.51276)
		(end 314.752736 -264.857484)
		(width 0.1651)
		(layer "In5.Cu")
		(net "P5E_PEX2_STN0_RX_DP<7>")
	)
	(segment
		(start 307.855112 -145.83156)
		(end 307.76926 -145.968466)
		(width 0.1651)
		(layer "In5.Cu")
		(net "P5E_PEX2_STN0_RX_DP<7>")
	)
	(segment
		(start 314.294774 -281.079702)
		(end 314.079636 -281.29484)
		(width 0.1143)
		(layer "In5.Cu")
		(net "P5E_PEX2_STN0_RX_DP<7>")
	)
	(segment
		(start 297.693842 -135.886444)
		(end 299.618146 -135.886444)
		(width 0.1651)
		(layer "In5.Cu")
		(net "P5E_PEX2_STN0_RX_DP<7>")
	)
	(segment
		(start 316.677802 -276.331172)
		(end 316.591188 -280.407364)
		(width 0.1651)
		(layer "In5.Cu")
		(net "P5E_PEX2_STN0_RX_DP<7>")
	)
	(segment
		(start 302.146462 -136.91489)
		(end 302.605186 -137.101326)
		(width 0.1651)
		(layer "In5.Cu")
		(net "P5E_PEX2_STN0_RX_DP<7>")
	)
	(segment
		(start 307.227478 -143.590518)
		(end 307.33746 -144.073626)
		(width 0.1651)
		(layer "In5.Cu")
		(net "P5E_PEX2_STN0_RX_DP<7>")
	)
	(segment
		(start 301.475648 -136.64184)
		(end 301.538386 -136.791192)
		(width 0.1651)
		(layer "In5.Cu")
		(net "P5E_PEX2_STN0_RX_DP<7>")
	)
	(segment
		(start 306.940204 -141.814042)
		(end 307.313584 -143.453612)
		(width 0.1651)
		(layer "In5.Cu")
		(net "P5E_PEX2_STN0_RX_DP<7>")
	)
	(segment
		(start 307.745384 -145.348706)
		(end 307.855112 -145.83156)
		(width 0.1651)
		(layer "In5.Cu")
		(net "P5E_PEX2_STN0_RX_DP<7>")
	)
	(segment
		(start 316.360556 -280.94559)
		(end 316.27191 -281.033982)
		(width 0.1651)
		(layer "In5.Cu")
		(net "P5E_PEX2_STN0_RX_DP<7>")
	)
	(segment
		(start 305.243992 -138.926062)
		(end 305.605434 -139.540996)
		(width 0.1651)
		(layer "In5.Cu")
		(net "P5E_PEX2_STN0_RX_DP<7>")
	)
	(segment
		(start 305.605434 -139.926568)
		(end 305.924712 -140.697204)
		(width 0.1651)
		(layer "In5.Cu")
		(net "P5E_PEX2_STN0_RX_DP<7>")
	)
	(segment
		(start 300.34611 -136.182608)
		(end 300.409102 -136.331706)
		(width 0.1651)
		(layer "In5.Cu")
		(net "P5E_PEX2_STN0_RX_DP<7>")
	)
	(segment
		(start 307.584348 -144.642586)
		(end 307.498496 -144.779492)
		(width 0.1651)
		(layer "In5.Cu")
		(net "P5E_PEX2_STN0_RX_DP<7>")
	)
	(segment
		(start 305.605434 -139.540996)
		(end 305.605434 -139.926568)
		(width 0.1651)
		(layer "In5.Cu")
		(net "P5E_PEX2_STN0_RX_DP<7>")
	)
	(segment
		(start 303.127156 -137.437114)
		(end 303.276 -137.374376)
		(width 0.1651)
		(layer "In5.Cu")
		(net "P5E_PEX2_STN0_RX_DP<7>")
	)
	(segment
		(start 302.605186 -137.101326)
		(end 302.667924 -137.250424)
		(width 0.1651)
		(layer "In5.Cu")
		(net "P5E_PEX2_STN0_RX_DP<7>")
	)
	(segment
		(start 301.997364 -136.977628)
		(end 302.146462 -136.91489)
		(width 0.1651)
		(layer "In5.Cu")
		(net "P5E_PEX2_STN0_RX_DP<7>")
	)
	(segment
		(start 306.796186 -141.568678)
		(end 306.940204 -141.814042)
		(width 0.1651)
		(layer "In5.Cu")
		(net "P5E_PEX2_STN0_RX_DP<7>")
	)
	(segment
		(start 307.313584 -143.453612)
		(end 307.227478 -143.590518)
		(width 0.1651)
		(layer "In5.Cu")
		(net "P5E_PEX2_STN0_RX_DP<7>")
	)
	(segment
		(start 307.33746 -144.073626)
		(end 307.47462 -144.159732)
		(width 0.1651)
		(layer "In5.Cu")
		(net "P5E_PEX2_STN0_RX_DP<7>")
	)
	(segment
		(start 316.075822 -281.079702)
		(end 314.294774 -281.079702)
		(width 0.1143)
		(layer "In5.Cu")
		(net "P5E_PEX2_STN0_RX_DP<7>")
	)
	(segment
		(start 308.016148 -146.53768)
		(end 311.198514 -160.511744)
		(width 0.1651)
		(layer "In5.Cu")
		(net "P5E_PEX2_STN0_RX_DP<7>")
	)
	(segment
		(start 307.498496 -144.779492)
		(end 307.608478 -145.2626)
		(width 0.1651)
		(layer "In5.Cu")
		(net "P5E_PEX2_STN0_RX_DP<7>")
	)
	(segment
		(start 311.198514 -160.511744)
		(end 311.198768 -160.51276)
		(width 0.1651)
		(layer "In5.Cu")
		(net "P5E_PEX2_STN0_RX_DP<7>")
	)
	(segment
		(start 297.403012 -136.177274)
		(end 297.693842 -135.886444)
		(width 0.1651)
		(layer "In5.Cu")
		(net "P5E_PEX2_STN0_RX_DP<7>")
	)
	(segment
		(start 316.27191 -281.033982)
		(end 316.14999 -281.033982)
		(width 0.1651)
		(layer "In5.Cu")
		(net "P5E_PEX2_STN0_RX_DP<7>")
	)
	(segment
		(start 301.538386 -136.791192)
		(end 301.997364 -136.977628)
		(width 0.1651)
		(layer "In5.Cu")
		(net "P5E_PEX2_STN0_RX_DP<7>")
	)
	(segment
		(start 307.608478 -145.2626)
		(end 307.745384 -145.348706)
		(width 0.1651)
		(layer "In5.Cu")
		(net "P5E_PEX2_STN0_RX_DP<7>")
	)
	(segment
		(start 302.667924 -137.250424)
		(end 303.127156 -137.437114)
		(width 0.1651)
		(layer "In5.Cu")
		(net "P5E_PEX2_STN0_RX_DP<7>")
	)
	(segment
		(start 299.618146 -135.886444)
		(end 300.34611 -136.182608)
		(width 0.1651)
		(layer "In5.Cu")
		(net "P5E_PEX2_STN0_RX_DP<7>")
	)
	(segment
		(start 301.016924 -136.455404)
		(end 301.475648 -136.64184)
		(width 0.1651)
		(layer "In5.Cu")
		(net "P5E_PEX2_STN0_RX_DP<7>")
	)
	(segment
		(start 313.965336 -281.649932)
		(end 313.699906 -281.649932)
		(width 0.1143)
		(layer "In5.Cu")
		(net "P5E_PEX2_STN0_RX_DP<7>")
	)
	(segment
		(start 399.581116 -132.5245)
		(end 399.421604 -132.364988)
		(width 0.13462)
		(layer "F.Cu")
		(net "P5E_PEX3_STN1_RX_DP<29>")
	)
	(segment
		(start 400.251168 -132.5245)
		(end 399.581116 -132.5245)
		(width 0.13462)
		(layer "F.Cu")
		(net "P5E_PEX3_STN1_RX_DP<29>")
	)
	(segment
		(start 399.421604 -132.364988)
		(end 398.94256 -132.364988)
		(width 0.13462)
		(layer "F.Cu")
		(net "P5E_PEX3_STN1_RX_DP<29>")
	)
	(segment
		(start 400.54276 -132.232908)
		(end 400.251168 -132.5245)
		(width 0.13462)
		(layer "F.Cu")
		(net "P5E_PEX3_STN1_RX_DP<29>")
	)
	(segment
		(start 396.125446 -142.75181)
		(end 394.222732 -144.47647)
		(width 0.1651)
		(layer "In5.Cu")
		(net "P5E_PEX3_STN1_RX_DP<29>")
	)
	(segment
		(start 420.299642 -275.684234)
		(end 420.299642 -275.949664)
		(width 0.1143)
		(layer "In5.Cu")
		(net "P5E_PEX3_STN1_RX_DP<29>")
	)
	(segment
		(start 391.340594 -160.904428)
		(end 419.683946 -267.498322)
		(width 0.1651)
		(layer "In5.Cu")
		(net "P5E_PEX3_STN1_RX_DP<29>")
	)
	(segment
		(start 419.683946 -271.599152)
		(end 419.729666 -271.644872)
		(width 0.1143)
		(layer "In5.Cu")
		(net "P5E_PEX3_STN1_RX_DP<29>")
	)
	(segment
		(start 420.185342 -275.569934)
		(end 420.299642 -275.684234)
		(width 0.1143)
		(layer "In5.Cu")
		(net "P5E_PEX3_STN1_RX_DP<29>")
	)
	(segment
		(start 419.683946 -271.570704)
		(end 419.683946 -271.599152)
		(width 0.1143)
		(layer "In5.Cu")
		(net "P5E_PEX3_STN1_RX_DP<29>")
	)
	(segment
		(start 399.97888 -132.523738)
		(end 399.666968 -132.653024)
		(width 0.1651)
		(layer "In5.Cu")
		(net "P5E_PEX3_STN1_RX_DP<29>")
	)
	(segment
		(start 419.729666 -271.644872)
		(end 419.729666 -275.35505)
		(width 0.1143)
		(layer "In5.Cu")
		(net "P5E_PEX3_STN1_RX_DP<29>")
	)
	(segment
		(start 419.729666 -275.35505)
		(end 419.94455 -275.569934)
		(width 0.1143)
		(layer "In5.Cu")
		(net "P5E_PEX3_STN1_RX_DP<29>")
	)
	(segment
		(start 390.610344 -156.780992)
		(end 391.340594 -160.904428)
		(width 0.1651)
		(layer "In5.Cu")
		(net "P5E_PEX3_STN1_RX_DP<29>")
	)
	(segment
		(start 419.94455 -275.569934)
		(end 420.185342 -275.569934)
		(width 0.1143)
		(layer "In5.Cu")
		(net "P5E_PEX3_STN1_RX_DP<29>")
	)
	(segment
		(start 396.969742 -140.713206)
		(end 396.125446 -142.75181)
		(width 0.1651)
		(layer "In5.Cu")
		(net "P5E_PEX3_STN1_RX_DP<29>")
	)
	(segment
		(start 390.023604 -147.76069)
		(end 390.610344 -156.780992)
		(width 0.1651)
		(layer "In5.Cu")
		(net "P5E_PEX3_STN1_RX_DP<29>")
	)
	(segment
		(start 393.387072 -145.513806)
		(end 391.165334 -146.226022)
		(width 0.1651)
		(layer "In5.Cu")
		(net "P5E_PEX3_STN1_RX_DP<29>")
	)
	(segment
		(start 393.816078 -145.0848)
		(end 393.387072 -145.513806)
		(width 0.1651)
		(layer "In5.Cu")
		(net "P5E_PEX3_STN1_RX_DP<29>")
	)
	(segment
		(start 394.222732 -144.47647)
		(end 393.816078 -145.0848)
		(width 0.1651)
		(layer "In5.Cu")
		(net "P5E_PEX3_STN1_RX_DP<29>")
	)
	(segment
		(start 396.969742 -136.936988)
		(end 396.969742 -140.713206)
		(width 0.1651)
		(layer "In5.Cu")
		(net "P5E_PEX3_STN1_RX_DP<29>")
	)
	(segment
		(start 419.683946 -267.498322)
		(end 419.683946 -271.570704)
		(width 0.1651)
		(layer "In5.Cu")
		(net "P5E_PEX3_STN1_RX_DP<29>")
	)
	(segment
		(start 400.54276 -132.232908)
		(end 400.25193 -132.523738)
		(width 0.1651)
		(layer "In5.Cu")
		(net "P5E_PEX3_STN1_RX_DP<29>")
	)
	(segment
		(start 399.560796 -132.759196)
		(end 398.143984 -134.100824)
		(width 0.1651)
		(layer "In5.Cu")
		(net "P5E_PEX3_STN1_RX_DP<29>")
	)
	(segment
		(start 399.666968 -132.653024)
		(end 399.560796 -132.759196)
		(width 0.1651)
		(layer "In5.Cu")
		(net "P5E_PEX3_STN1_RX_DP<29>")
	)
	(segment
		(start 398.143984 -134.100824)
		(end 396.969742 -136.936988)
		(width 0.1651)
		(layer "In5.Cu")
		(net "P5E_PEX3_STN1_RX_DP<29>")
	)
	(segment
		(start 400.25193 -132.523738)
		(end 399.97888 -132.523738)
		(width 0.1651)
		(layer "In5.Cu")
		(net "P5E_PEX3_STN1_RX_DP<29>")
	)
	(segment
		(start 390.737852 -146.58467)
		(end 390.516618 -146.854926)
		(width 0.1651)
		(layer "In5.Cu")
		(net "P5E_PEX3_STN1_RX_DP<29>")
	)
	(segment
		(start 391.165334 -146.226022)
		(end 390.737852 -146.58467)
		(width 0.1651)
		(layer "In5.Cu")
		(net "P5E_PEX3_STN1_RX_DP<29>")
	)
	(segment
		(start 390.516618 -146.854926)
		(end 390.023604 -147.76069)
		(width 0.1651)
		(layer "In5.Cu")
		(net "P5E_PEX3_STN1_RX_DP<29>")
	)
	(segment
		(start 383.918968 -350.685862)
		(end 383.918968 -351.31629)
		(width 0.13462)
		(layer "F.Cu")
		(net "P5E_PEX3_STN6_TX_C_DP<97>")
	)
	(segment
		(start 383.918968 -351.31629)
		(end 383.62382 -351.611438)
		(width 0.13462)
		(layer "F.Cu")
		(net "P5E_PEX3_STN6_TX_C_DP<97>")
	)
	(segment
		(start 383.59842 -350.365314)
		(end 383.918968 -350.685862)
		(width 0.13462)
		(layer "F.Cu")
		(net "P5E_PEX3_STN6_TX_C_DP<97>")
	)
	(segment
		(start 383.91465 -352.356166)
		(end 382.36017 -353.910646)
		(width 0.1651)
		(layer "In7.Cu")
		(net "P5E_PEX3_STN6_TX_C_DP<97>")
	)
	(segment
		(start 387.27507 -365.753904)
		(end 387.246622 -365.913162)
		(width 0.1651)
		(layer "In7.Cu")
		(net "P5E_PEX3_STN6_TX_C_DP<97>")
	)
	(segment
		(start 383.62382 -351.611438)
		(end 383.91465 -351.902268)
		(width 0.1651)
		(layer "In7.Cu")
		(net "P5E_PEX3_STN6_TX_C_DP<97>")
	)
	(segment
		(start 389.533892 -382.412494)
		(end 389.247126 -382.69926)
		(width 0.1651)
		(layer "In7.Cu")
		(net "P5E_PEX3_STN6_TX_C_DP<97>")
	)
	(segment
		(start 388.386828 -367.348262)
		(end 389.533892 -368.993166)
		(width 0.1651)
		(layer "In7.Cu")
		(net "P5E_PEX3_STN6_TX_C_DP<97>")
	)
	(segment
		(start 388.227824 -367.319814)
		(end 388.386828 -367.348262)
		(width 0.1651)
		(layer "In7.Cu")
		(net "P5E_PEX3_STN6_TX_C_DP<97>")
	)
	(segment
		(start 388.81685 -382.69926)
		(end 388.68985 -382.57226)
		(width 0.1651)
		(layer "In7.Cu")
		(net "P5E_PEX3_STN6_TX_C_DP<97>")
	)
	(segment
		(start 387.944106 -366.913414)
		(end 388.227824 -367.319814)
		(width 0.1651)
		(layer "In7.Cu")
		(net "P5E_PEX3_STN6_TX_C_DP<97>")
	)
	(segment
		(start 388.68985 -382.57226)
		(end 388.68985 -382.18999)
		(width 0.1651)
		(layer "In7.Cu")
		(net "P5E_PEX3_STN6_TX_C_DP<97>")
	)
	(segment
		(start 389.533892 -368.993166)
		(end 389.533892 -382.412494)
		(width 0.1651)
		(layer "In7.Cu")
		(net "P5E_PEX3_STN6_TX_C_DP<97>")
	)
	(segment
		(start 387.972554 -366.754156)
		(end 387.944106 -366.913414)
		(width 0.1651)
		(layer "In7.Cu")
		(net "P5E_PEX3_STN6_TX_C_DP<97>")
	)
	(segment
		(start 382.36017 -358.706166)
		(end 387.27507 -365.753904)
		(width 0.1651)
		(layer "In7.Cu")
		(net "P5E_PEX3_STN6_TX_C_DP<97>")
	)
	(segment
		(start 389.247126 -382.69926)
		(end 388.81685 -382.69926)
		(width 0.1651)
		(layer "In7.Cu")
		(net "P5E_PEX3_STN6_TX_C_DP<97>")
	)
	(segment
		(start 387.689344 -366.34801)
		(end 387.972554 -366.754156)
		(width 0.1651)
		(layer "In7.Cu")
		(net "P5E_PEX3_STN6_TX_C_DP<97>")
	)
	(segment
		(start 382.36017 -353.910646)
		(end 382.36017 -358.706166)
		(width 0.1651)
		(layer "In7.Cu")
		(net "P5E_PEX3_STN6_TX_C_DP<97>")
	)
	(segment
		(start 387.246622 -365.913162)
		(end 387.53034 -366.319562)
		(width 0.1651)
		(layer "In7.Cu")
		(net "P5E_PEX3_STN6_TX_C_DP<97>")
	)
	(segment
		(start 383.91465 -351.902268)
		(end 383.91465 -352.356166)
		(width 0.1651)
		(layer "In7.Cu")
		(net "P5E_PEX3_STN6_TX_C_DP<97>")
	)
	(segment
		(start 387.53034 -366.319562)
		(end 387.689344 -366.34801)
		(width 0.1651)
		(layer "In7.Cu")
		(net "P5E_PEX3_STN6_TX_C_DP<97>")
	)
	(segment
		(start 43.418252 -154.159966)
		(end 41.977564 -152.719278)
		(width 0.13208)
		(layer "F.Cu")
		(net "NCSI_NIC0_RXD1")
	)
	(segment
		(start 41.977564 -152.719278)
		(end 40.396668 -152.719278)
		(width 0.13208)
		(layer "F.Cu")
		(net "NCSI_NIC0_RXD1")
	)
	(segment
		(start 40.396668 -152.719278)
		(end 39.972742 -152.295352)
		(width 0.13208)
		(layer "F.Cu")
		(net "NCSI_NIC0_RXD1")
	)
	(segment
		(start 46.042326 -154.159966)
		(end 43.418252 -154.159966)
		(width 0.13208)
		(layer "F.Cu")
		(net "NCSI_NIC0_RXD1")
	)
	(segment
		(start 39.972742 -152.295352)
		(end 38.999922 -152.295352)
		(width 0.13208)
		(layer "F.Cu")
		(net "NCSI_NIC0_RXD1")
	)
	(via
		(at 40.396668 -152.719278)
		(size 0.762)
		(drill 0.381)
		(layers "F.Cu" "B.Cu")
		(net "NCSI_NIC0_RXD1")
	)
	(segment
		(start 196.239384 -138.661648)
		(end 196.239384 -137.645648)
		(width 0.13208)
		(layer "F.Cu")
		(net "PRSNTB0_NIC3_N")
	)
	(segment
		(start 189.357508 -137.24509)
		(end 195.008754 -137.24509)
		(width 0.13208)
		(layer "F.Cu")
		(net "PRSNTB0_NIC3_N")
	)
	(segment
		(start 195.838826 -137.24509)
		(end 196.239384 -137.645648)
		(width 0.13208)
		(layer "F.Cu")
		(net "PRSNTB0_NIC3_N")
	)
	(segment
		(start 195.008754 -137.24509)
		(end 195.838826 -137.24509)
		(width 0.13208)
		(layer "F.Cu")
		(net "PRSNTB0_NIC3_N")
	)
	(via
		(at 195.008754 -137.24509)
		(size 0.762)
		(drill 0.381)
		(layers "F.Cu" "B.Cu")
		(net "PRSNTB0_NIC3_N")
	)
	(segment
		(start 184.031382 -34.2265)
		(end 183.867806 -34.390076)
		(width 0.13462)
		(layer "F.Cu")
		(net "P5E_PEX1_STN2_TX_C_DP<39>")
	)
	(segment
		(start 183.867806 -34.390076)
		(end 183.364886 -34.390076)
		(width 0.13462)
		(layer "F.Cu")
		(net "P5E_PEX1_STN2_TX_C_DP<39>")
	)
	(segment
		(start 187.948062 -34.2265)
		(end 184.031382 -34.2265)
		(width 0.13462)
		(layer "F.Cu")
		(net "P5E_PEX1_STN2_TX_C_DP<39>")
	)
	(segment
		(start 188.267848 -34.546286)
		(end 187.948062 -34.2265)
		(width 0.13462)
		(layer "F.Cu")
		(net "P5E_PEX1_STN2_TX_C_DP<39>")
	)
	(segment
		(start 300.376336 -133.645148)
		(end 300.214284 -133.8072)
		(width 0.13462)
		(layer "F.Cu")
		(net "P5E_PEX2_STN0_RX_DN<6>")
	)
	(segment
		(start 300.214284 -133.8072)
		(end 299.550836 -133.8072)
		(width 0.13462)
		(layer "F.Cu")
		(net "P5E_PEX2_STN0_RX_DN<6>")
	)
	(segment
		(start 299.550836 -133.8072)
		(end 299.257212 -133.513576)
		(width 0.13462)
		(layer "F.Cu")
		(net "P5E_PEX2_STN0_RX_DN<6>")
	)
	(segment
		(start 300.857412 -133.645148)
		(end 300.376336 -133.645148)
		(width 0.13462)
		(layer "F.Cu")
		(net "P5E_PEX2_STN0_RX_DN<6>")
	)
	(segment
		(start 299.946568 -133.804406)
		(end 299.548042 -133.804406)
		(width 0.1651)
		(layer "In5.Cu")
		(net "P5E_PEX2_STN0_RX_DN<6>")
	)
	(segment
		(start 312.369962 -282.485592)
		(end 312.369962 -282.35275)
		(width 0.1143)
		(layer "In5.Cu")
		(net "P5E_PEX2_STN0_RX_DN<6>")
	)
	(segment
		(start 312.369962 -282.35275)
		(end 312.50255 -282.220162)
		(width 0.1143)
		(layer "In5.Cu")
		(net "P5E_PEX2_STN0_RX_DN<6>")
	)
	(segment
		(start 316.050422 -282.220162)
		(end 316.096142 -282.265882)
		(width 0.1143)
		(layer "In5.Cu")
		(net "P5E_PEX2_STN0_RX_DN<6>")
	)
	(segment
		(start 316.53607 -282.265882)
		(end 317.206122 -281.817826)
		(width 0.1651)
		(layer "In5.Cu")
		(net "P5E_PEX2_STN0_RX_DN<6>")
	)
	(segment
		(start 317.69939 -281.22245)
		(end 317.945008 -280.642822)
		(width 0.1651)
		(layer "In5.Cu")
		(net "P5E_PEX2_STN0_RX_DN<6>")
	)
	(segment
		(start 315.993526 -264.69721)
		(end 312.437272 -160.243774)
		(width 0.1651)
		(layer "In5.Cu")
		(net "P5E_PEX2_STN0_RX_DN<6>")
	)
	(segment
		(start 312.484262 -282.599892)
		(end 312.369962 -282.485592)
		(width 0.1143)
		(layer "In5.Cu")
		(net "P5E_PEX2_STN0_RX_DN<6>")
	)
	(segment
		(start 312.50255 -282.220162)
		(end 316.050422 -282.220162)
		(width 0.1143)
		(layer "In5.Cu")
		(net "P5E_PEX2_STN0_RX_DN<6>")
	)
	(segment
		(start 316.12459 -282.265882)
		(end 316.53607 -282.265882)
		(width 0.1651)
		(layer "In5.Cu")
		(net "P5E_PEX2_STN0_RX_DN<6>")
	)
	(segment
		(start 308.932072 -138.902186)
		(end 308.511702 -138.402314)
		(width 0.1651)
		(layer "In5.Cu")
		(net "P5E_PEX2_STN0_RX_DN<6>")
	)
	(segment
		(start 316.096142 -282.265882)
		(end 316.12459 -282.265882)
		(width 0.1143)
		(layer "In5.Cu")
		(net "P5E_PEX2_STN0_RX_DN<6>")
	)
	(segment
		(start 308.511702 -138.402314)
		(end 299.946568 -133.804406)
		(width 0.1651)
		(layer "In5.Cu")
		(net "P5E_PEX2_STN0_RX_DN<6>")
	)
	(segment
		(start 318.033146 -277.089108)
		(end 318.033146 -276.694646)
		(width 0.1651)
		(layer "In5.Cu")
		(net "P5E_PEX2_STN0_RX_DN<6>")
	)
	(segment
		(start 317.945008 -280.642822)
		(end 318.033146 -277.089108)
		(width 0.1651)
		(layer "In5.Cu")
		(net "P5E_PEX2_STN0_RX_DN<6>")
	)
	(segment
		(start 309.085742 -140.908278)
		(end 309.085742 -139.7889)
		(width 0.1651)
		(layer "In5.Cu")
		(net "P5E_PEX2_STN0_RX_DN<6>")
	)
	(segment
		(start 312.437272 -160.243774)
		(end 309.085742 -140.908278)
		(width 0.1651)
		(layer "In5.Cu")
		(net "P5E_PEX2_STN0_RX_DN<6>")
	)
	(segment
		(start 316.906656 -270.77416)
		(end 315.993526 -264.69721)
		(width 0.1651)
		(layer "In5.Cu")
		(net "P5E_PEX2_STN0_RX_DN<6>")
	)
	(segment
		(start 318.033146 -276.694646)
		(end 316.906656 -270.77416)
		(width 0.1651)
		(layer "In5.Cu")
		(net "P5E_PEX2_STN0_RX_DN<6>")
	)
	(segment
		(start 309.085742 -139.7889)
		(end 308.932072 -138.902186)
		(width 0.1651)
		(layer "In5.Cu")
		(net "P5E_PEX2_STN0_RX_DN<6>")
	)
	(segment
		(start 299.548042 -133.804406)
		(end 299.257212 -133.513576)
		(width 0.1651)
		(layer "In5.Cu")
		(net "P5E_PEX2_STN0_RX_DN<6>")
	)
	(segment
		(start 317.206122 -281.817826)
		(end 317.69939 -281.22245)
		(width 0.1651)
		(layer "In5.Cu")
		(net "P5E_PEX2_STN0_RX_DN<6>")
	)
	(segment
		(start 312.749692 -282.599892)
		(end 312.484262 -282.599892)
		(width 0.1143)
		(layer "In5.Cu")
		(net "P5E_PEX2_STN0_RX_DN<6>")
	)
	(segment
		(start 399.578576 -99.59848)
		(end 399.42516 -99.445064)
		(width 0.13462)
		(layer "F.Cu")
		(net "P5E_PEX3_STN1_RX_DP<16>")
	)
	(segment
		(start 399.42516 -99.445064)
		(end 398.94256 -99.445064)
		(width 0.13462)
		(layer "F.Cu")
		(net "P5E_PEX3_STN1_RX_DP<16>")
	)
	(segment
		(start 402.39696 -99.31273)
		(end 402.11121 -99.59848)
		(width 0.13462)
		(layer "F.Cu")
		(net "P5E_PEX3_STN1_RX_DP<16>")
	)
	(segment
		(start 402.11121 -99.59848)
		(end 399.578576 -99.59848)
		(width 0.13462)
		(layer "F.Cu")
		(net "P5E_PEX3_STN1_RX_DP<16>")
	)
	(segment
		(start 407.835354 -273.66976)
		(end 407.949654 -273.78406)
		(width 0.1143)
		(layer "In5.Cu")
		(net "P5E_PEX3_STN1_RX_DP<16>")
	)
	(segment
		(start 377.698 -126.35865)
		(end 376.314208 -149.937724)
		(width 0.1651)
		(layer "In5.Cu")
		(net "P5E_PEX3_STN1_RX_DP<16>")
	)
	(segment
		(start 384.233674 -109.97438)
		(end 382.59512 -110.640876)
		(width 0.1651)
		(layer "In5.Cu")
		(net "P5E_PEX3_STN1_RX_DP<16>")
	)
	(segment
		(start 407.333958 -271.525746)
		(end 407.333958 -271.554194)
		(width 0.1143)
		(layer "In5.Cu")
		(net "P5E_PEX3_STN1_RX_DP<16>")
	)
	(segment
		(start 407.379678 -271.599914)
		(end 407.379678 -273.454876)
		(width 0.1143)
		(layer "In5.Cu")
		(net "P5E_PEX3_STN1_RX_DP<16>")
	)
	(segment
		(start 376.315478 -149.955758)
		(end 376.988832 -159.572198)
		(width 0.1651)
		(layer "In5.Cu")
		(net "P5E_PEX3_STN1_RX_DP<16>")
	)
	(segment
		(start 376.315224 -149.955758)
		(end 376.315478 -149.955758)
		(width 0.1651)
		(layer "In5.Cu")
		(net "P5E_PEX3_STN1_RX_DP<16>")
	)
	(segment
		(start 382.121664 -111.125508)
		(end 379.32106 -119.642636)
		(width 0.1651)
		(layer "In5.Cu")
		(net "P5E_PEX3_STN1_RX_DP<16>")
	)
	(segment
		(start 384.889248 -109.382306)
		(end 384.233674 -109.97438)
		(width 0.1651)
		(layer "In5.Cu")
		(net "P5E_PEX3_STN1_RX_DP<16>")
	)
	(segment
		(start 379.32106 -119.642636)
		(end 377.698 -126.35865)
		(width 0.1651)
		(layer "In5.Cu")
		(net "P5E_PEX3_STN1_RX_DP<16>")
	)
	(segment
		(start 407.379678 -273.454876)
		(end 407.594562 -273.66976)
		(width 0.1143)
		(layer "In5.Cu")
		(net "P5E_PEX3_STN1_RX_DP<16>")
	)
	(segment
		(start 407.333958 -271.554194)
		(end 407.379678 -271.599914)
		(width 0.1143)
		(layer "In5.Cu")
		(net "P5E_PEX3_STN1_RX_DP<16>")
	)
	(segment
		(start 387.332474 -107.761532)
		(end 384.889248 -109.382306)
		(width 0.1651)
		(layer "In5.Cu")
		(net "P5E_PEX3_STN1_RX_DP<16>")
	)
	(segment
		(start 402.10613 -99.60356)
		(end 400.191986 -99.60356)
		(width 0.1651)
		(layer "In5.Cu")
		(net "P5E_PEX3_STN1_RX_DP<16>")
	)
	(segment
		(start 393.206986 -103.095806)
		(end 387.332474 -107.761532)
		(width 0.1651)
		(layer "In5.Cu")
		(net "P5E_PEX3_STN1_RX_DP<16>")
	)
	(segment
		(start 376.314208 -149.937724)
		(end 376.315224 -149.955758)
		(width 0.1651)
		(layer "In5.Cu")
		(net "P5E_PEX3_STN1_RX_DP<16>")
	)
	(segment
		(start 407.594562 -273.66976)
		(end 407.835354 -273.66976)
		(width 0.1143)
		(layer "In5.Cu")
		(net "P5E_PEX3_STN1_RX_DP<16>")
	)
	(segment
		(start 407.333958 -270.105124)
		(end 407.333958 -271.525746)
		(width 0.1651)
		(layer "In5.Cu")
		(net "P5E_PEX3_STN1_RX_DP<16>")
	)
	(segment
		(start 382.59512 -110.640876)
		(end 382.121664 -111.125508)
		(width 0.1651)
		(layer "In5.Cu")
		(net "P5E_PEX3_STN1_RX_DP<16>")
	)
	(segment
		(start 407.949654 -273.78406)
		(end 407.949654 -274.04949)
		(width 0.1143)
		(layer "In5.Cu")
		(net "P5E_PEX3_STN1_RX_DP<16>")
	)
	(segment
		(start 402.39696 -99.31273)
		(end 402.10613 -99.60356)
		(width 0.1651)
		(layer "In5.Cu")
		(net "P5E_PEX3_STN1_RX_DP<16>")
	)
	(segment
		(start 378.244354 -166.070534)
		(end 407.333958 -270.105124)
		(width 0.1651)
		(layer "In5.Cu")
		(net "P5E_PEX3_STN1_RX_DP<16>")
	)
	(segment
		(start 400.191986 -99.60356)
		(end 393.206986 -103.095806)
		(width 0.1651)
		(layer "In5.Cu")
		(net "P5E_PEX3_STN1_RX_DP<16>")
	)
	(segment
		(start 376.988832 -159.572198)
		(end 378.244354 -166.070534)
		(width 0.1651)
		(layer "In5.Cu")
		(net "P5E_PEX3_STN1_RX_DP<16>")
	)
	(segment
		(start 396.88389 -322.053458)
		(end 396.88389 -319.995296)
		(width 0.1651)
		(layer "In15.Cu")
		(net "P5E_PEX3_STN6_RX_DP<105>")
	)
	(segment
		(start 373.99214 -367.600738)
		(end 379.02134 -358.85628)
		(width 0.1651)
		(layer "In15.Cu")
		(net "P5E_PEX3_STN6_RX_DP<105>")
	)
	(segment
		(start 373.691404 -386.192776)
		(end 373.19077 -384.77571)
		(width 0.1651)
		(layer "In15.Cu")
		(net "P5E_PEX3_STN6_RX_DP<105>")
	)
	(segment
		(start 396.88389 -319.995296)
		(end 396.88389 -319.966848)
		(width 0.1143)
		(layer "In15.Cu")
		(net "P5E_PEX3_STN6_RX_DP<105>")
	)
	(segment
		(start 388.216902 -393.777216)
		(end 388.218172 -393.615672)
		(width 0.1651)
		(layer "In15.Cu")
		(net "P5E_PEX3_STN6_RX_DP<105>")
	)
	(segment
		(start 372.746016 -372.942612)
		(end 372.91518 -371.043708)
		(width 0.1651)
		(layer "In15.Cu")
		(net "P5E_PEX3_STN6_RX_DP<105>")
	)
	(segment
		(start 373.269764 -369.26012)
		(end 373.99214 -367.600738)
		(width 0.1651)
		(layer "In15.Cu")
		(net "P5E_PEX3_STN6_RX_DP<105>")
	)
	(segment
		(start 397.38554 -316.229492)
		(end 397.49984 -316.115192)
		(width 0.1143)
		(layer "In15.Cu")
		(net "P5E_PEX3_STN6_RX_DP<105>")
	)
	(segment
		(start 388.68985 -400.390106)
		(end 388.68985 -400.772122)
		(width 0.1651)
		(layer "In15.Cu")
		(net "P5E_PEX3_STN6_RX_DP<105>")
	)
	(segment
		(start 375.821702 -387.69925)
		(end 373.691404 -386.192776)
		(width 0.1651)
		(layer "In15.Cu")
		(net "P5E_PEX3_STN6_RX_DP<105>")
	)
	(segment
		(start 388.218172 -393.615672)
		(end 387.619494 -393.008104)
		(width 0.1651)
		(layer "In15.Cu")
		(net "P5E_PEX3_STN6_RX_DP<105>")
	)
	(segment
		(start 384.782822 -391.514584)
		(end 375.821702 -387.69925)
		(width 0.1651)
		(layer "In15.Cu")
		(net "P5E_PEX3_STN6_RX_DP<105>")
	)
	(segment
		(start 387.619494 -393.008104)
		(end 386.091684 -392.07186)
		(width 0.1651)
		(layer "In15.Cu")
		(net "P5E_PEX3_STN6_RX_DP<105>")
	)
	(segment
		(start 388.726426 -394.131546)
		(end 388.564882 -394.130276)
		(width 0.1651)
		(layer "In15.Cu")
		(net "P5E_PEX3_STN6_RX_DP<105>")
	)
	(segment
		(start 385.299204 -391.858754)
		(end 384.843274 -391.664698)
		(width 0.1651)
		(layer "In15.Cu")
		(net "P5E_PEX3_STN6_RX_DP<105>")
	)
	(segment
		(start 379.25121 -342.114886)
		(end 379.810264 -340.802976)
		(width 0.1651)
		(layer "In15.Cu")
		(net "P5E_PEX3_STN6_RX_DP<105>")
	)
	(segment
		(start 389.247126 -400.899122)
		(end 389.533892 -400.612356)
		(width 0.1651)
		(layer "In15.Cu")
		(net "P5E_PEX3_STN6_RX_DP<105>")
	)
	(segment
		(start 396.92961 -316.44463)
		(end 397.144748 -316.229492)
		(width 0.1143)
		(layer "In15.Cu")
		(net "P5E_PEX3_STN6_RX_DP<105>")
	)
	(segment
		(start 379.25121 -357.995982)
		(end 379.25121 -342.114886)
		(width 0.1651)
		(layer "In15.Cu")
		(net "P5E_PEX3_STN6_RX_DP<105>")
	)
	(segment
		(start 390.082278 -330.32446)
		(end 394.316458 -326.428608)
		(width 0.1651)
		(layer "In15.Cu")
		(net "P5E_PEX3_STN6_RX_DP<105>")
	)
	(segment
		(start 388.68985 -400.772122)
		(end 388.81685 -400.899122)
		(width 0.1651)
		(layer "In15.Cu")
		(net "P5E_PEX3_STN6_RX_DP<105>")
	)
	(segment
		(start 397.49984 -316.115192)
		(end 397.49984 -315.849762)
		(width 0.1143)
		(layer "In15.Cu")
		(net "P5E_PEX3_STN6_RX_DP<105>")
	)
	(segment
		(start 394.316458 -326.428608)
		(end 396.338806 -323.36994)
		(width 0.1651)
		(layer "In15.Cu")
		(net "P5E_PEX3_STN6_RX_DP<105>")
	)
	(segment
		(start 388.81685 -400.899122)
		(end 389.247126 -400.899122)
		(width 0.1651)
		(layer "In15.Cu")
		(net "P5E_PEX3_STN6_RX_DP<105>")
	)
	(segment
		(start 389.250936 -394.663676)
		(end 388.72668 -394.131546)
		(width 0.1651)
		(layer "In15.Cu")
		(net "P5E_PEX3_STN6_RX_DP<105>")
	)
	(segment
		(start 372.91518 -371.043708)
		(end 373.269764 -369.26012)
		(width 0.1651)
		(layer "In15.Cu")
		(net "P5E_PEX3_STN6_RX_DP<105>")
	)
	(segment
		(start 379.02134 -358.85628)
		(end 379.25121 -357.995982)
		(width 0.1651)
		(layer "In15.Cu")
		(net "P5E_PEX3_STN6_RX_DP<105>")
	)
	(segment
		(start 385.449064 -391.798302)
		(end 385.299204 -391.858754)
		(width 0.1651)
		(layer "In15.Cu")
		(net "P5E_PEX3_STN6_RX_DP<105>")
	)
	(segment
		(start 388.72668 -394.131546)
		(end 388.726426 -394.131546)
		(width 0.1651)
		(layer "In15.Cu")
		(net "P5E_PEX3_STN6_RX_DP<105>")
	)
	(segment
		(start 388.564882 -394.130276)
		(end 388.216902 -393.777216)
		(width 0.1651)
		(layer "In15.Cu")
		(net "P5E_PEX3_STN6_RX_DP<105>")
	)
	(segment
		(start 389.533892 -395.522704)
		(end 389.250936 -394.663676)
		(width 0.1651)
		(layer "In15.Cu")
		(net "P5E_PEX3_STN6_RX_DP<105>")
	)
	(segment
		(start 384.843274 -391.664698)
		(end 384.782822 -391.514584)
		(width 0.1651)
		(layer "In15.Cu")
		(net "P5E_PEX3_STN6_RX_DP<105>")
	)
	(segment
		(start 396.338806 -323.36994)
		(end 396.88389 -322.053458)
		(width 0.1651)
		(layer "In15.Cu")
		(net "P5E_PEX3_STN6_RX_DP<105>")
	)
	(segment
		(start 396.88389 -319.966848)
		(end 396.92961 -319.921128)
		(width 0.1143)
		(layer "In15.Cu")
		(net "P5E_PEX3_STN6_RX_DP<105>")
	)
	(segment
		(start 386.091684 -392.07186)
		(end 385.449064 -391.798302)
		(width 0.1651)
		(layer "In15.Cu")
		(net "P5E_PEX3_STN6_RX_DP<105>")
	)
	(segment
		(start 379.810264 -340.802976)
		(end 390.082278 -330.32446)
		(width 0.1651)
		(layer "In15.Cu")
		(net "P5E_PEX3_STN6_RX_DP<105>")
	)
	(segment
		(start 396.92961 -319.921128)
		(end 396.92961 -316.44463)
		(width 0.1143)
		(layer "In15.Cu")
		(net "P5E_PEX3_STN6_RX_DP<105>")
	)
	(segment
		(start 389.533892 -400.612356)
		(end 389.533892 -395.522704)
		(width 0.1651)
		(layer "In15.Cu")
		(net "P5E_PEX3_STN6_RX_DP<105>")
	)
	(segment
		(start 397.144748 -316.229492)
		(end 397.38554 -316.229492)
		(width 0.1143)
		(layer "In15.Cu")
		(net "P5E_PEX3_STN6_RX_DP<105>")
	)
	(segment
		(start 373.19077 -384.77571)
		(end 372.746016 -372.942612)
		(width 0.1651)
		(layer "In15.Cu")
		(net "P5E_PEX3_STN6_RX_DP<105>")
	)
	(segment
		(start 38.999922 -153.322528)
		(end 39.00805 -153.3144)
		(width 0.13208)
		(layer "F.Cu")
		(net "NIC0_SLOT_ID0")
	)
	(segment
		(start 42.931334 -154.759914)
		(end 42.14368 -153.97226)
		(width 0.13208)
		(layer "F.Cu")
		(net "NIC0_SLOT_ID0")
	)
	(segment
		(start 40.18788 -153.97226)
		(end 39.53002 -153.3144)
		(width 0.13208)
		(layer "F.Cu")
		(net "NIC0_SLOT_ID0")
	)
	(segment
		(start 39.53002 -153.3144)
		(end 39.00805 -153.3144)
		(width 0.13208)
		(layer "F.Cu")
		(net "NIC0_SLOT_ID0")
	)
	(segment
		(start 46.042326 -154.759914)
		(end 42.931334 -154.759914)
		(width 0.13208)
		(layer "F.Cu")
		(net "NIC0_SLOT_ID0")
	)
	(segment
		(start 38.999922 -154.327352)
		(end 38.999922 -153.322528)
		(width 0.13208)
		(layer "F.Cu")
		(net "NIC0_SLOT_ID0")
	)
	(segment
		(start 42.14368 -153.97226)
		(end 40.18788 -153.97226)
		(width 0.13208)
		(layer "F.Cu")
		(net "NIC0_SLOT_ID0")
	)
	(via
		(at 40.18788 -153.97226)
		(size 0.762)
		(drill 0.381)
		(layers "F.Cu" "B.Cu")
		(net "NIC0_SLOT_ID0")
	)
	(segment
		(start 196.621146 -113.43513)
		(end 193.97345 -113.43513)
		(width 0.13208)
		(layer "F.Cu")
		(net "NIC3_BIF1_N")
	)
	(segment
		(start 199.313546 -113.054892)
		(end 199.313546 -113.41354)
		(width 0.13208)
		(layer "F.Cu")
		(net "NIC3_BIF1_N")
	)
	(segment
		(start 199.186292 -112.927638)
		(end 199.313546 -113.054892)
		(width 0.13208)
		(layer "F.Cu")
		(net "NIC3_BIF1_N")
	)
	(segment
		(start 197.108318 -113.43513)
		(end 197.61581 -112.927638)
		(width 0.13208)
		(layer "F.Cu")
		(net "NIC3_BIF1_N")
	)
	(segment
		(start 191.661034 -113.7666)
		(end 191.329564 -113.43513)
		(width 0.13208)
		(layer "F.Cu")
		(net "NIC3_BIF1_N")
	)
	(segment
		(start 196.621146 -113.43513)
		(end 197.108318 -113.43513)
		(width 0.13208)
		(layer "F.Cu")
		(net "NIC3_BIF1_N")
	)
	(segment
		(start 197.61581 -112.927638)
		(end 199.186292 -112.927638)
		(width 0.13208)
		(layer "F.Cu")
		(net "NIC3_BIF1_N")
	)
	(segment
		(start 193.97345 -113.43513)
		(end 193.64198 -113.7666)
		(width 0.13208)
		(layer "F.Cu")
		(net "NIC3_BIF1_N")
	)
	(segment
		(start 193.64198 -113.7666)
		(end 191.661034 -113.7666)
		(width 0.13208)
		(layer "F.Cu")
		(net "NIC3_BIF1_N")
	)
	(segment
		(start 200.291446 -113.41354)
		(end 199.313546 -113.41354)
		(width 0.13208)
		(layer "F.Cu")
		(net "NIC3_BIF1_N")
	)
	(segment
		(start 191.329564 -113.43513)
		(end 189.357508 -113.43513)
		(width 0.13208)
		(layer "F.Cu")
		(net "NIC3_BIF1_N")
	)
	(via
		(at 196.621146 -113.43513)
		(size 0.762)
		(drill 0.381)
		(layers "F.Cu" "B.Cu")
		(net "NIC3_BIF1_N")
	)
	(segment
		(start 10.187432 -30.190186)
		(end 10.024618 -30.353)
		(width 0.13462)
		(layer "F.Cu")
		(net "P5E_PEX0_STN2_RX_DN<45>")
	)
	(segment
		(start 10.664952 -30.190186)
		(end 10.187432 -30.190186)
		(width 0.13462)
		(layer "F.Cu")
		(net "P5E_PEX0_STN2_RX_DN<45>")
	)
	(segment
		(start 10.024618 -30.353)
		(end 7.504684 -30.353)
		(width 0.13462)
		(layer "F.Cu")
		(net "P5E_PEX0_STN2_RX_DN<45>")
	)
	(segment
		(start 7.504684 -30.353)
		(end 7.210552 -30.058868)
		(width 0.13462)
		(layer "F.Cu")
		(net "P5E_PEX0_STN2_RX_DN<45>")
	)
	(segment
		(start 45.053758 -263.502648)
		(end 45.13072 -255.646936)
		(width 0.1651)
		(layer "In7.Cu")
		(net "P5E_PEX0_STN2_RX_DN<45>")
	)
	(segment
		(start 12.157964 -85.311742)
		(end 12.348464 -61.48959)
		(width 0.1651)
		(layer "In7.Cu")
		(net "P5E_PEX0_STN2_RX_DN<45>")
	)
	(segment
		(start 11.412474 -31.973012)
		(end 9.78916 -30.349698)
		(width 0.1651)
		(layer "In7.Cu")
		(net "P5E_PEX0_STN2_RX_DN<45>")
	)
	(segment
		(start 25.818846 -144.505172)
		(end 22.536658 -119.552466)
		(width 0.1651)
		(layer "In7.Cu")
		(net "P5E_PEX0_STN2_RX_DN<45>")
	)
	(segment
		(start 9.78916 -30.349698)
		(end 7.501382 -30.349698)
		(width 0.1651)
		(layer "In7.Cu")
		(net "P5E_PEX0_STN2_RX_DN<45>")
	)
	(segment
		(start 12.19835 -49.868074)
		(end 10.899394 -40.256206)
		(width 0.1651)
		(layer "In7.Cu")
		(net "P5E_PEX0_STN2_RX_DN<45>")
	)
	(segment
		(start 46.01591 -271.3736)
		(end 46.01591 -271.345152)
		(width 0.1143)
		(layer "In7.Cu")
		(net "P5E_PEX0_STN2_RX_DN<45>")
	)
	(segment
		(start 22.536658 -119.552466)
		(end 17.347438 -102.432612)
		(width 0.1651)
		(layer "In7.Cu")
		(net "P5E_PEX0_STN2_RX_DN<45>")
	)
	(segment
		(start 12.081002 -57.362344)
		(end 12.19835 -49.868074)
		(width 0.1651)
		(layer "In7.Cu")
		(net "P5E_PEX0_STN2_RX_DN<45>")
	)
	(segment
		(start 46.01591 -270.28521)
		(end 45.053758 -263.502648)
		(width 0.1651)
		(layer "In7.Cu")
		(net "P5E_PEX0_STN2_RX_DN<45>")
	)
	(segment
		(start 46.34992 -273.099784)
		(end 46.34992 -273.365214)
		(width 0.1143)
		(layer "In7.Cu")
		(net "P5E_PEX0_STN2_RX_DN<45>")
	)
	(segment
		(start 46.34992 -273.365214)
		(end 46.23562 -273.479514)
		(width 0.1143)
		(layer "In7.Cu")
		(net "P5E_PEX0_STN2_RX_DN<45>")
	)
	(segment
		(start 45.97019 -271.41932)
		(end 46.01591 -271.3736)
		(width 0.1143)
		(layer "In7.Cu")
		(net "P5E_PEX0_STN2_RX_DN<45>")
	)
	(segment
		(start 7.501382 -30.349698)
		(end 7.210552 -30.058868)
		(width 0.1651)
		(layer "In7.Cu")
		(net "P5E_PEX0_STN2_RX_DN<45>")
	)
	(segment
		(start 17.3355 -102.392734)
		(end 17.335246 -102.391972)
		(width 0.1651)
		(layer "In7.Cu")
		(net "P5E_PEX0_STN2_RX_DN<45>")
	)
	(segment
		(start 46.01591 -271.345152)
		(end 46.01591 -270.28521)
		(width 0.1651)
		(layer "In7.Cu")
		(net "P5E_PEX0_STN2_RX_DN<45>")
	)
	(segment
		(start 46.23562 -273.479514)
		(end 46.121066 -273.479514)
		(width 0.1143)
		(layer "In7.Cu")
		(net "P5E_PEX0_STN2_RX_DN<45>")
	)
	(segment
		(start 45.13072 -255.646936)
		(end 43.530774 -238.16945)
		(width 0.1651)
		(layer "In7.Cu")
		(net "P5E_PEX0_STN2_RX_DN<45>")
	)
	(segment
		(start 43.530774 -238.16945)
		(end 25.818846 -144.505172)
		(width 0.1651)
		(layer "In7.Cu")
		(net "P5E_PEX0_STN2_RX_DN<45>")
	)
	(segment
		(start 17.335246 -102.391972)
		(end 12.157964 -85.311742)
		(width 0.1651)
		(layer "In7.Cu")
		(net "P5E_PEX0_STN2_RX_DN<45>")
	)
	(segment
		(start 45.97019 -273.328638)
		(end 45.97019 -271.41932)
		(width 0.1143)
		(layer "In7.Cu")
		(net "P5E_PEX0_STN2_RX_DN<45>")
	)
	(segment
		(start 46.121066 -273.479514)
		(end 45.97019 -273.328638)
		(width 0.1143)
		(layer "In7.Cu")
		(net "P5E_PEX0_STN2_RX_DN<45>")
	)
	(segment
		(start 17.347438 -102.432104)
		(end 17.3355 -102.392734)
		(width 0.1651)
		(layer "In7.Cu")
		(net "P5E_PEX0_STN2_RX_DN<45>")
	)
	(segment
		(start 11.38809 -35.00755)
		(end 11.412474 -31.973012)
		(width 0.1651)
		(layer "In7.Cu")
		(net "P5E_PEX0_STN2_RX_DN<45>")
	)
	(segment
		(start 10.899394 -40.256206)
		(end 10.863326 -37.96284)
		(width 0.1651)
		(layer "In7.Cu")
		(net "P5E_PEX0_STN2_RX_DN<45>")
	)
	(segment
		(start 12.348464 -61.48959)
		(end 12.348464 -60.132976)
		(width 0.1651)
		(layer "In7.Cu")
		(net "P5E_PEX0_STN2_RX_DN<45>")
	)
	(segment
		(start 17.347438 -102.432612)
		(end 17.347438 -102.432104)
		(width 0.1651)
		(layer "In7.Cu")
		(net "P5E_PEX0_STN2_RX_DN<45>")
	)
	(segment
		(start 10.863326 -37.96284)
		(end 11.38809 -35.00755)
		(width 0.1651)
		(layer "In7.Cu")
		(net "P5E_PEX0_STN2_RX_DN<45>")
	)
	(segment
		(start 12.348464 -60.132976)
		(end 12.081002 -57.362344)
		(width 0.1651)
		(layer "In7.Cu")
		(net "P5E_PEX0_STN2_RX_DN<45>")
	)
	(segment
		(start 211.296504 -32.4104)
		(end 210.04403 -32.4104)
		(width 0.13462)
		(layer "F.Cu")
		(net "P5E_PEX1_STN2_TX_C_DP<34>")
	)
	(segment
		(start 211.625688 -32.739584)
		(end 211.296504 -32.4104)
		(width 0.13462)
		(layer "F.Cu")
		(net "P5E_PEX1_STN2_TX_C_DP<34>")
	)
	(segment
		(start 210.04403 -32.4104)
		(end 209.864452 -32.589978)
		(width 0.13462)
		(layer "F.Cu")
		(net "P5E_PEX1_STN2_TX_C_DP<34>")
	)
	(segment
		(start 209.864452 -32.589978)
		(end 209.364834 -32.589978)
		(width 0.13462)
		(layer "F.Cu")
		(net "P5E_PEX1_STN2_TX_C_DP<34>")
	)
	(segment
		(start 297.694096 -120.79478)
		(end 297.403012 -120.503696)
		(width 0.13462)
		(layer "F.Cu")
		(net "P5E_PEX2_STN0_RX_DN<1>")
	)
	(segment
		(start 300.379892 -120.635014)
		(end 300.220126 -120.79478)
		(width 0.13462)
		(layer "F.Cu")
		(net "P5E_PEX2_STN0_RX_DN<1>")
	)
	(segment
		(start 300.857412 -120.635014)
		(end 300.379892 -120.635014)
		(width 0.13462)
		(layer "F.Cu")
		(net "P5E_PEX2_STN0_RX_DN<1>")
	)
	(segment
		(start 300.220126 -120.79478)
		(end 297.694096 -120.79478)
		(width 0.13462)
		(layer "F.Cu")
		(net "P5E_PEX2_STN0_RX_DN<1>")
	)
	(segment
		(start 312.7629 -131.52882)
		(end 307.29936 -125.19406)
		(width 0.1651)
		(layer "In5.Cu")
		(net "P5E_PEX2_STN0_RX_DN<1>")
	)
	(segment
		(start 316.075822 -286.970216)
		(end 316.121542 -287.015936)
		(width 0.1143)
		(layer "In5.Cu")
		(net "P5E_PEX2_STN0_RX_DN<1>")
	)
	(segment
		(start 314.270136 -287.235646)
		(end 314.270136 -287.073848)
		(width 0.1143)
		(layer "In5.Cu")
		(net "P5E_PEX2_STN0_RX_DN<1>")
	)
	(segment
		(start 307.29936 -125.19406)
		(end 305.05654 -122.97664)
		(width 0.1651)
		(layer "In5.Cu")
		(net "P5E_PEX2_STN0_RX_DN<1>")
	)
	(segment
		(start 305.05654 -122.97664)
		(end 299.815758 -120.794526)
		(width 0.1651)
		(layer "In5.Cu")
		(net "P5E_PEX2_STN0_RX_DN<1>")
	)
	(segment
		(start 330.746608 -273.37258)
		(end 330.8985 -269.2781)
		(width 0.1651)
		(layer "In5.Cu")
		(net "P5E_PEX2_STN0_RX_DN<1>")
	)
	(segment
		(start 297.693842 -120.794526)
		(end 297.403012 -120.503696)
		(width 0.1651)
		(layer "In5.Cu")
		(net "P5E_PEX2_STN0_RX_DN<1>")
	)
	(segment
		(start 314.384436 -287.349946)
		(end 314.270136 -287.235646)
		(width 0.1143)
		(layer "In5.Cu")
		(net "P5E_PEX2_STN0_RX_DN<1>")
	)
	(segment
		(start 318.13627 -135.222996)
		(end 317.61176 -134.40664)
		(width 0.1651)
		(layer "In5.Cu")
		(net "P5E_PEX2_STN0_RX_DN<1>")
	)
	(segment
		(start 299.815758 -120.794526)
		(end 297.693842 -120.794526)
		(width 0.1651)
		(layer "In5.Cu")
		(net "P5E_PEX2_STN0_RX_DN<1>")
	)
	(segment
		(start 320.563748 -146.35226)
		(end 318.13627 -135.222996)
		(width 0.1651)
		(layer "In5.Cu")
		(net "P5E_PEX2_STN0_RX_DN<1>")
	)
	(segment
		(start 322.11391 -239.19307)
		(end 320.667634 -232.097072)
		(width 0.1651)
		(layer "In5.Cu")
		(net "P5E_PEX2_STN0_RX_DN<1>")
	)
	(segment
		(start 318.200024 -287.015936)
		(end 318.267842 -286.974534)
		(width 0.1651)
		(layer "In5.Cu")
		(net "P5E_PEX2_STN0_RX_DN<1>")
	)
	(segment
		(start 328.278236 -277.807928)
		(end 330.746608 -273.37258)
		(width 0.1651)
		(layer "In5.Cu")
		(net "P5E_PEX2_STN0_RX_DN<1>")
	)
	(segment
		(start 314.91428 -132.715)
		(end 312.7629 -131.52882)
		(width 0.1651)
		(layer "In5.Cu")
		(net "P5E_PEX2_STN0_RX_DN<1>")
	)
	(segment
		(start 320.667634 -232.097072)
		(end 321.330574 -168.53408)
		(width 0.1651)
		(layer "In5.Cu")
		(net "P5E_PEX2_STN0_RX_DN<1>")
	)
	(segment
		(start 320.822066 -149.896322)
		(end 320.563748 -146.35226)
		(width 0.1651)
		(layer "In5.Cu")
		(net "P5E_PEX2_STN0_RX_DN<1>")
	)
	(segment
		(start 330.8985 -269.2781)
		(end 322.11391 -239.19307)
		(width 0.1651)
		(layer "In5.Cu")
		(net "P5E_PEX2_STN0_RX_DN<1>")
	)
	(segment
		(start 315.34354 -133.14426)
		(end 314.91428 -132.715)
		(width 0.1651)
		(layer "In5.Cu")
		(net "P5E_PEX2_STN0_RX_DN<1>")
	)
	(segment
		(start 316.121542 -287.015936)
		(end 316.14999 -287.015936)
		(width 0.1143)
		(layer "In5.Cu")
		(net "P5E_PEX2_STN0_RX_DN<1>")
	)
	(segment
		(start 319.674494 -286.11068)
		(end 328.278236 -277.807928)
		(width 0.1651)
		(layer "In5.Cu")
		(net "P5E_PEX2_STN0_RX_DN<1>")
	)
	(segment
		(start 316.14999 -287.015936)
		(end 318.200024 -287.015936)
		(width 0.1651)
		(layer "In5.Cu")
		(net "P5E_PEX2_STN0_RX_DN<1>")
	)
	(segment
		(start 321.330574 -168.53408)
		(end 320.822066 -149.896322)
		(width 0.1651)
		(layer "In5.Cu")
		(net "P5E_PEX2_STN0_RX_DN<1>")
	)
	(segment
		(start 314.373768 -286.970216)
		(end 316.075822 -286.970216)
		(width 0.1143)
		(layer "In5.Cu")
		(net "P5E_PEX2_STN0_RX_DN<1>")
	)
	(segment
		(start 318.267842 -286.97428)
		(end 319.674494 -286.11068)
		(width 0.1651)
		(layer "In5.Cu")
		(net "P5E_PEX2_STN0_RX_DN<1>")
	)
	(segment
		(start 314.649866 -287.349946)
		(end 314.384436 -287.349946)
		(width 0.1143)
		(layer "In5.Cu")
		(net "P5E_PEX2_STN0_RX_DN<1>")
	)
	(segment
		(start 318.267842 -286.974534)
		(end 318.267842 -286.97428)
		(width 0.1651)
		(layer "In5.Cu")
		(net "P5E_PEX2_STN0_RX_DN<1>")
	)
	(segment
		(start 317.61176 -134.40664)
		(end 315.34354 -133.14426)
		(width 0.1651)
		(layer "In5.Cu")
		(net "P5E_PEX2_STN0_RX_DN<1>")
	)
	(segment
		(start 314.270136 -287.073848)
		(end 314.373768 -286.970216)
		(width 0.1143)
		(layer "In5.Cu")
		(net "P5E_PEX2_STN0_RX_DN<1>")
	)
	(segment
		(start 399.58899 -123.11888)
		(end 399.42516 -122.95505)
		(width 0.13462)
		(layer "F.Cu")
		(net "P5E_PEX3_STN1_RX_DP<26>")
	)
	(segment
		(start 402.39696 -122.822716)
		(end 402.100796 -123.11888)
		(width 0.13462)
		(layer "F.Cu")
		(net "P5E_PEX3_STN1_RX_DP<26>")
	)
	(segment
		(start 402.100796 -123.11888)
		(end 399.58899 -123.11888)
		(width 0.13462)
		(layer "F.Cu")
		(net "P5E_PEX3_STN1_RX_DP<26>")
	)
	(segment
		(start 399.42516 -122.95505)
		(end 398.94256 -122.95505)
		(width 0.13462)
		(layer "F.Cu")
		(net "P5E_PEX3_STN1_RX_DP<26>")
	)
	(segment
		(start 416.879786 -273.45513)
		(end 417.09467 -273.670014)
		(width 0.1143)
		(layer "In5.Cu")
		(net "P5E_PEX3_STN1_RX_DP<26>")
	)
	(segment
		(start 387.126226 -147.406106)
		(end 387.775704 -157.418786)
		(width 0.1651)
		(layer "In5.Cu")
		(net "P5E_PEX3_STN1_RX_DP<26>")
	)
	(segment
		(start 402.10613 -123.113546)
		(end 400.119342 -123.113546)
		(width 0.1651)
		(layer "In5.Cu")
		(net "P5E_PEX3_STN1_RX_DP<26>")
	)
	(segment
		(start 417.335462 -273.670014)
		(end 417.449762 -273.784314)
		(width 0.1143)
		(layer "In5.Cu")
		(net "P5E_PEX3_STN1_RX_DP<26>")
	)
	(segment
		(start 388.591552 -161.945066)
		(end 416.834066 -267.93063)
		(width 0.1651)
		(layer "In5.Cu")
		(net "P5E_PEX3_STN1_RX_DP<26>")
	)
	(segment
		(start 392.819382 -129.219198)
		(end 392.649202 -129.59461)
		(width 0.1651)
		(layer "In5.Cu")
		(net "P5E_PEX3_STN1_RX_DP<26>")
	)
	(segment
		(start 387.775704 -157.418786)
		(end 388.591552 -161.945066)
		(width 0.1651)
		(layer "In5.Cu")
		(net "P5E_PEX3_STN1_RX_DP<26>")
	)
	(segment
		(start 416.834066 -271.554448)
		(end 416.879786 -271.600168)
		(width 0.1143)
		(layer "In5.Cu")
		(net "P5E_PEX3_STN1_RX_DP<26>")
	)
	(segment
		(start 392.649202 -129.59461)
		(end 390.978898 -139.268962)
		(width 0.1651)
		(layer "In5.Cu")
		(net "P5E_PEX3_STN1_RX_DP<26>")
	)
	(segment
		(start 389.95858 -142.790672)
		(end 387.455156 -146.151092)
		(width 0.1651)
		(layer "In5.Cu")
		(net "P5E_PEX3_STN1_RX_DP<26>")
	)
	(segment
		(start 394.993622 -126.46787)
		(end 392.819382 -129.219198)
		(width 0.1651)
		(layer "In5.Cu")
		(net "P5E_PEX3_STN1_RX_DP<26>")
	)
	(segment
		(start 417.09467 -273.670014)
		(end 417.335462 -273.670014)
		(width 0.1143)
		(layer "In5.Cu")
		(net "P5E_PEX3_STN1_RX_DP<26>")
	)
	(segment
		(start 390.978898 -139.268962)
		(end 389.95858 -142.790672)
		(width 0.1651)
		(layer "In5.Cu")
		(net "P5E_PEX3_STN1_RX_DP<26>")
	)
	(segment
		(start 402.39696 -122.822716)
		(end 402.10613 -123.113546)
		(width 0.1651)
		(layer "In5.Cu")
		(net "P5E_PEX3_STN1_RX_DP<26>")
	)
	(segment
		(start 395.699742 -125.839474)
		(end 394.993622 -126.46787)
		(width 0.1651)
		(layer "In5.Cu")
		(net "P5E_PEX3_STN1_RX_DP<26>")
	)
	(segment
		(start 387.455156 -146.151092)
		(end 387.126226 -147.406106)
		(width 0.1651)
		(layer "In5.Cu")
		(net "P5E_PEX3_STN1_RX_DP<26>")
	)
	(segment
		(start 416.879786 -271.600168)
		(end 416.879786 -273.45513)
		(width 0.1143)
		(layer "In5.Cu")
		(net "P5E_PEX3_STN1_RX_DP<26>")
	)
	(segment
		(start 400.119342 -123.113546)
		(end 395.699742 -125.839474)
		(width 0.1651)
		(layer "In5.Cu")
		(net "P5E_PEX3_STN1_RX_DP<26>")
	)
	(segment
		(start 416.834066 -271.526)
		(end 416.834066 -271.554448)
		(width 0.1143)
		(layer "In5.Cu")
		(net "P5E_PEX3_STN1_RX_DP<26>")
	)
	(segment
		(start 416.834066 -267.93063)
		(end 416.834066 -271.526)
		(width 0.1651)
		(layer "In5.Cu")
		(net "P5E_PEX3_STN1_RX_DP<26>")
	)
	(segment
		(start 417.449762 -273.784314)
		(end 417.449762 -274.049744)
		(width 0.1143)
		(layer "In5.Cu")
		(net "P5E_PEX3_STN1_RX_DP<26>")
	)
	(segment
		(start 384.193288 -350.684846)
		(end 384.193288 -351.317306)
		(width 0.13462)
		(layer "F.Cu")
		(net "P5E_PEX3_STN6_TX_C_DN<97>")
	)
	(segment
		(start 384.51282 -350.365314)
		(end 384.193288 -350.684846)
		(width 0.13462)
		(layer "F.Cu")
		(net "P5E_PEX3_STN6_TX_C_DN<97>")
	)
	(segment
		(start 384.193288 -351.317306)
		(end 384.48742 -351.611438)
		(width 0.13462)
		(layer "F.Cu")
		(net "P5E_PEX3_STN6_TX_C_DN<97>")
	)
	(segment
		(start 389.815832 -368.90452)
		(end 389.815832 -382.529334)
		(width 0.1651)
		(layer "In7.Cu")
		(net "P5E_PEX3_STN6_TX_C_DN<97>")
	)
	(segment
		(start 384.19659 -351.902268)
		(end 384.19659 -352.473006)
		(width 0.1651)
		(layer "In7.Cu")
		(net "P5E_PEX3_STN6_TX_C_DN<97>")
	)
	(segment
		(start 389.815832 -382.529334)
		(end 389.363966 -382.9812)
		(width 0.1651)
		(layer "In7.Cu")
		(net "P5E_PEX3_STN6_TX_C_DN<97>")
	)
	(segment
		(start 389.363966 -382.9812)
		(end 388.81685 -382.9812)
		(width 0.1651)
		(layer "In7.Cu")
		(net "P5E_PEX3_STN6_TX_C_DN<97>")
	)
	(segment
		(start 384.19659 -352.473006)
		(end 382.64211 -354.027486)
		(width 0.1651)
		(layer "In7.Cu")
		(net "P5E_PEX3_STN6_TX_C_DN<97>")
	)
	(segment
		(start 382.64211 -354.027486)
		(end 382.64211 -358.61752)
		(width 0.1651)
		(layer "In7.Cu")
		(net "P5E_PEX3_STN6_TX_C_DN<97>")
	)
	(segment
		(start 384.48742 -351.611438)
		(end 384.19659 -351.902268)
		(width 0.1651)
		(layer "In7.Cu")
		(net "P5E_PEX3_STN6_TX_C_DN<97>")
	)
	(segment
		(start 388.68985 -383.1082)
		(end 388.68985 -383.490216)
		(width 0.1651)
		(layer "In7.Cu")
		(net "P5E_PEX3_STN6_TX_C_DN<97>")
	)
	(segment
		(start 388.81685 -382.9812)
		(end 388.68985 -383.1082)
		(width 0.1651)
		(layer "In7.Cu")
		(net "P5E_PEX3_STN6_TX_C_DN<97>")
	)
	(segment
		(start 382.64211 -358.61752)
		(end 389.815832 -368.90452)
		(width 0.1651)
		(layer "In7.Cu")
		(net "P5E_PEX3_STN6_TX_C_DN<97>")
	)
	(segment
		(start 55.356506 -151.19223)
		(end 56.461406 -150.08733)
		(width 0.13208)
		(layer "F.Cu")
		(net "RST_NIC0_PERST1_R_N")
	)
	(segment
		(start 51.949604 -140.165074)
		(end 51.987196 -140.127482)
		(width 0.13208)
		(layer "F.Cu")
		(net "RST_NIC0_PERST1_R_N")
	)
	(segment
		(start 50.64252 -140.165074)
		(end 51.949604 -140.165074)
		(width 0.13208)
		(layer "F.Cu")
		(net "RST_NIC0_PERST1_R_N")
	)
	(segment
		(start 55.356506 -155.419806)
		(end 55.356506 -151.19223)
		(width 0.13208)
		(layer "F.Cu")
		(net "RST_NIC0_PERST1_R_N")
	)
	(via
		(at 56.461406 -150.08733)
		(size 0.508)
		(drill 0.254)
		(layers "F.Cu" "B.Cu")
		(net "RST_NIC0_PERST1_R_N")
	)
	(via
		(at 51.987196 -140.127482)
		(size 0.508)
		(drill 0.254)
		(layers "F.Cu" "B.Cu")
		(net "RST_NIC0_PERST1_R_N")
	)
	(segment
		(start 56.461406 -150.08733)
		(end 53.273706 -146.89963)
		(width 0.15494)
		(layer "In7.Cu")
		(net "RST_NIC0_PERST1_R_N")
	)
	(segment
		(start 53.273706 -146.89963)
		(end 53.273706 -141.413992)
		(width 0.15494)
		(layer "In7.Cu")
		(net "RST_NIC0_PERST1_R_N")
	)
	(segment
		(start 53.273706 -141.413992)
		(end 51.987196 -140.127482)
		(width 0.15494)
		(layer "In7.Cu")
		(net "RST_NIC0_PERST1_R_N")
	)
	(segment
		(start 189.357508 -98.240088)
		(end 190.833756 -98.240088)
		(width 0.13208)
		(layer "F.Cu")
		(net "NIC3_LD_N")
	)
	(segment
		(start 192.045844 -97.028)
		(end 192.045844 -95.989648)
		(width 0.13208)
		(layer "F.Cu")
		(net "NIC3_LD_N")
	)
	(segment
		(start 190.833756 -98.240088)
		(end 192.045844 -97.028)
		(width 0.13208)
		(layer "F.Cu")
		(net "NIC3_LD_N")
	)
	(via
		(at 192.045844 -95.989648)
		(size 0.508)
		(drill 0.254)
		(layers "F.Cu" "B.Cu")
		(net "NIC3_LD_N")
	)
	(segment
		(start 192.045844 -95.989648)
		(end 193.241676 -95.989648)
		(width 0.13208)
		(layer "B.Cu")
		(net "NIC3_LD_N")
	)
	(segment
		(start 204.287374 -30.190186)
		(end 204.12456 -30.353)
		(width 0.13462)
		(layer "F.Cu")
		(net "P5E_PEX1_STN2_RX_DN<33>")
	)
	(segment
		(start 204.12456 -30.353)
		(end 201.604626 -30.353)
		(width 0.13462)
		(layer "F.Cu")
		(net "P5E_PEX1_STN2_RX_DN<33>")
	)
	(segment
		(start 201.604626 -30.353)
		(end 201.310494 -30.058868)
		(width 0.13462)
		(layer "F.Cu")
		(net "P5E_PEX1_STN2_RX_DN<33>")
	)
	(segment
		(start 204.764894 -30.190186)
		(end 204.287374 -30.190186)
		(width 0.13462)
		(layer "F.Cu")
		(net "P5E_PEX1_STN2_RX_DN<33>")
	)
	(segment
		(start 204.190854 -30.349698)
		(end 201.601324 -30.349698)
		(width 0.1651)
		(layer "In7.Cu")
		(net "P5E_PEX1_STN2_RX_DN<33>")
	)
	(segment
		(start 173.850046 -273.099784)
		(end 173.850046 -273.365214)
		(width 0.1143)
		(layer "In7.Cu")
		(net "P5E_PEX1_STN2_RX_DN<33>")
	)
	(segment
		(start 204.966062 -38.15207)
		(end 205.685136 -34.102294)
		(width 0.1651)
		(layer "In7.Cu")
		(net "P5E_PEX1_STN2_RX_DN<33>")
	)
	(segment
		(start 206.121 -61.209428)
		(end 206.305912 -49.3776)
		(width 0.1651)
		(layer "In7.Cu")
		(net "P5E_PEX1_STN2_RX_DN<33>")
	)
	(segment
		(start 173.853348 -267.040868)
		(end 193.41846 -154.698446)
		(width 0.1651)
		(layer "In7.Cu")
		(net "P5E_PEX1_STN2_RX_DN<33>")
	)
	(segment
		(start 201.601324 -30.349698)
		(end 201.310494 -30.058868)
		(width 0.1651)
		(layer "In7.Cu")
		(net "P5E_PEX1_STN2_RX_DN<33>")
	)
	(segment
		(start 195.112894 -116.691918)
		(end 206.121 -61.209428)
		(width 0.1651)
		(layer "In7.Cu")
		(net "P5E_PEX1_STN2_RX_DN<33>")
	)
	(segment
		(start 173.470316 -273.328638)
		(end 173.470316 -271.41932)
		(width 0.1143)
		(layer "In7.Cu")
		(net "P5E_PEX1_STN2_RX_DN<33>")
	)
	(segment
		(start 173.516036 -271.3736)
		(end 173.516036 -271.345152)
		(width 0.1143)
		(layer "In7.Cu")
		(net "P5E_PEX1_STN2_RX_DN<33>")
	)
	(segment
		(start 194.797426 -143.990568)
		(end 195.112894 -116.691918)
		(width 0.1651)
		(layer "In7.Cu")
		(net "P5E_PEX1_STN2_RX_DN<33>")
	)
	(segment
		(start 193.41846 -154.698446)
		(end 194.797426 -143.990568)
		(width 0.1651)
		(layer "In7.Cu")
		(net "P5E_PEX1_STN2_RX_DN<33>")
	)
	(segment
		(start 173.735746 -273.479514)
		(end 173.621192 -273.479514)
		(width 0.1143)
		(layer "In7.Cu")
		(net "P5E_PEX1_STN2_RX_DN<33>")
	)
	(segment
		(start 173.850046 -273.365214)
		(end 173.735746 -273.479514)
		(width 0.1143)
		(layer "In7.Cu")
		(net "P5E_PEX1_STN2_RX_DN<33>")
	)
	(segment
		(start 173.621192 -273.479514)
		(end 173.470316 -273.328638)
		(width 0.1143)
		(layer "In7.Cu")
		(net "P5E_PEX1_STN2_RX_DN<33>")
	)
	(segment
		(start 205.685136 -34.102294)
		(end 205.693772 -33.002982)
		(width 0.1651)
		(layer "In7.Cu")
		(net "P5E_PEX1_STN2_RX_DN<33>")
	)
	(segment
		(start 173.470316 -271.41932)
		(end 173.516036 -271.3736)
		(width 0.1143)
		(layer "In7.Cu")
		(net "P5E_PEX1_STN2_RX_DN<33>")
	)
	(segment
		(start 173.516036 -270.929862)
		(end 173.853348 -267.040868)
		(width 0.1651)
		(layer "In7.Cu")
		(net "P5E_PEX1_STN2_RX_DN<33>")
	)
	(segment
		(start 204.989684 -39.636954)
		(end 204.966062 -38.15207)
		(width 0.1651)
		(layer "In7.Cu")
		(net "P5E_PEX1_STN2_RX_DN<33>")
	)
	(segment
		(start 205.407514 -32.239712)
		(end 204.190854 -30.349698)
		(width 0.1651)
		(layer "In7.Cu")
		(net "P5E_PEX1_STN2_RX_DN<33>")
	)
	(segment
		(start 173.516036 -271.345152)
		(end 173.516036 -270.929862)
		(width 0.1651)
		(layer "In7.Cu")
		(net "P5E_PEX1_STN2_RX_DN<33>")
	)
	(segment
		(start 206.305912 -49.3776)
		(end 204.989684 -39.636954)
		(width 0.1651)
		(layer "In7.Cu")
		(net "P5E_PEX1_STN2_RX_DN<33>")
	)
	(segment
		(start 205.693772 -33.002982)
		(end 205.407514 -32.239712)
		(width 0.1651)
		(layer "In7.Cu")
		(net "P5E_PEX1_STN2_RX_DN<33>")
	)
	(segment
		(start 305.960526 -133.645148)
		(end 305.457606 -133.645148)
		(width 0.13462)
		(layer "F.Cu")
		(net "P5E_PEX2_STN0_TX_C_DN<6>")
	)
	(segment
		(start 311.625742 -133.8072)
		(end 306.122578 -133.8072)
		(width 0.13462)
		(layer "F.Cu")
		(net "P5E_PEX2_STN0_TX_C_DN<6>")
	)
	(segment
		(start 306.122578 -133.8072)
		(end 305.960526 -133.645148)
		(width 0.13462)
		(layer "F.Cu")
		(net "P5E_PEX2_STN0_TX_C_DN<6>")
	)
	(segment
		(start 311.95264 -133.480302)
		(end 311.625742 -133.8072)
		(width 0.13462)
		(layer "F.Cu")
		(net "P5E_PEX2_STN0_TX_C_DN<6>")
	)
	(segment
		(start 402.39696 -102.912672)
		(end 402.109432 -103.2002)
		(width 0.13462)
		(layer "F.Cu")
		(net "P5E_PEX3_STN1_RX_DP<18>")
	)
	(segment
		(start 399.42516 -103.045006)
		(end 398.94256 -103.045006)
		(width 0.13462)
		(layer "F.Cu")
		(net "P5E_PEX3_STN1_RX_DP<18>")
	)
	(segment
		(start 402.109432 -103.2002)
		(end 399.580354 -103.2002)
		(width 0.13462)
		(layer "F.Cu")
		(net "P5E_PEX3_STN1_RX_DP<18>")
	)
	(segment
		(start 399.580354 -103.2002)
		(end 399.42516 -103.045006)
		(width 0.13462)
		(layer "F.Cu")
		(net "P5E_PEX3_STN1_RX_DP<18>")
	)
	(segment
		(start 409.233878 -271.526)
		(end 409.233878 -271.554448)
		(width 0.1143)
		(layer "In5.Cu")
		(net "P5E_PEX3_STN1_RX_DP<18>")
	)
	(segment
		(start 381.14351 -120.379236)
		(end 380.005844 -126.602744)
		(width 0.1651)
		(layer "In5.Cu")
		(net "P5E_PEX3_STN1_RX_DP<18>")
	)
	(segment
		(start 378.401834 -150.34133)
		(end 378.681742 -154.568144)
		(width 0.1651)
		(layer "In5.Cu")
		(net "P5E_PEX3_STN1_RX_DP<18>")
	)
	(segment
		(start 409.279598 -271.600168)
		(end 409.279598 -273.45513)
		(width 0.1143)
		(layer "In5.Cu")
		(net "P5E_PEX3_STN1_RX_DP<18>")
	)
	(segment
		(start 378.681742 -154.568144)
		(end 378.96165 -158.791148)
		(width 0.1651)
		(layer "In5.Cu")
		(net "P5E_PEX3_STN1_RX_DP<18>")
	)
	(segment
		(start 380.005844 -126.602744)
		(end 378.401834 -150.34133)
		(width 0.1651)
		(layer "In5.Cu")
		(net "P5E_PEX3_STN1_RX_DP<18>")
	)
	(segment
		(start 409.735274 -273.670014)
		(end 409.849574 -273.784314)
		(width 0.1143)
		(layer "In5.Cu")
		(net "P5E_PEX3_STN1_RX_DP<18>")
	)
	(segment
		(start 409.233878 -269.772892)
		(end 409.233878 -271.526)
		(width 0.1651)
		(layer "In5.Cu")
		(net "P5E_PEX3_STN1_RX_DP<18>")
	)
	(segment
		(start 409.494482 -273.670014)
		(end 409.735274 -273.670014)
		(width 0.1143)
		(layer "In5.Cu")
		(net "P5E_PEX3_STN1_RX_DP<18>")
	)
	(segment
		(start 400.230848 -103.203502)
		(end 393.031218 -106.897932)
		(width 0.1651)
		(layer "In5.Cu")
		(net "P5E_PEX3_STN1_RX_DP<18>")
	)
	(segment
		(start 409.849574 -273.784314)
		(end 409.849574 -274.049744)
		(width 0.1143)
		(layer "In5.Cu")
		(net "P5E_PEX3_STN1_RX_DP<18>")
	)
	(segment
		(start 382.13792 -118.307358)
		(end 381.14351 -120.379236)
		(width 0.1651)
		(layer "In5.Cu")
		(net "P5E_PEX3_STN1_RX_DP<18>")
	)
	(segment
		(start 409.279598 -273.45513)
		(end 409.494482 -273.670014)
		(width 0.1143)
		(layer "In5.Cu")
		(net "P5E_PEX3_STN1_RX_DP<18>")
	)
	(segment
		(start 409.233878 -271.554448)
		(end 409.279598 -271.600168)
		(width 0.1143)
		(layer "In5.Cu")
		(net "P5E_PEX3_STN1_RX_DP<18>")
	)
	(segment
		(start 378.96165 -158.791148)
		(end 380.08814 -165.304216)
		(width 0.1651)
		(layer "In5.Cu")
		(net "P5E_PEX3_STN1_RX_DP<18>")
	)
	(segment
		(start 380.08814 -165.304216)
		(end 409.233878 -269.772892)
		(width 0.1651)
		(layer "In5.Cu")
		(net "P5E_PEX3_STN1_RX_DP<18>")
	)
	(segment
		(start 402.10613 -103.203502)
		(end 400.230848 -103.203502)
		(width 0.1651)
		(layer "In5.Cu")
		(net "P5E_PEX3_STN1_RX_DP<18>")
	)
	(segment
		(start 402.39696 -102.912672)
		(end 402.10613 -103.203502)
		(width 0.1651)
		(layer "In5.Cu")
		(net "P5E_PEX3_STN1_RX_DP<18>")
	)
	(segment
		(start 393.031218 -106.897932)
		(end 382.13792 -118.307358)
		(width 0.1651)
		(layer "In5.Cu")
		(net "P5E_PEX3_STN1_RX_DP<18>")
	)
	(segment
		(start 377.701048 -344.53957)
		(end 377.701048 -345.169998)
		(width 0.13462)
		(layer "F.Cu")
		(net "P5E_PEX3_STN6_TX_C_DP<109>")
	)
	(segment
		(start 377.701048 -345.169998)
		(end 377.4059 -345.465146)
		(width 0.13462)
		(layer "F.Cu")
		(net "P5E_PEX3_STN6_TX_C_DP<109>")
	)
	(segment
		(start 377.3805 -344.219022)
		(end 377.701048 -344.53957)
		(width 0.13462)
		(layer "F.Cu")
		(net "P5E_PEX3_STN6_TX_C_DP<109>")
	)
	(segment
		(start 380.528068 -394.781024)
		(end 379.408182 -394.110972)
		(width 0.1651)
		(layer "In13.Cu")
		(net "P5E_PEX3_STN6_TX_C_DP<109>")
	)
	(segment
		(start 377.784106 -393.138914)
		(end 375.704608 -391.894568)
		(width 0.1651)
		(layer "In13.Cu")
		(net "P5E_PEX3_STN6_TX_C_DP<109>")
	)
	(segment
		(start 378.244608 -393.532868)
		(end 377.819158 -393.27836)
		(width 0.1651)
		(layer "In13.Cu")
		(net "P5E_PEX3_STN6_TX_C_DP<109>")
	)
	(segment
		(start 376.14225 -357.984044)
		(end 376.14225 -347.764354)
		(width 0.1651)
		(layer "In13.Cu")
		(net "P5E_PEX3_STN6_TX_C_DP<109>")
	)
	(segment
		(start 370.428266 -388.641336)
		(end 369.245134 -385.741418)
		(width 0.1651)
		(layer "In13.Cu")
		(net "P5E_PEX3_STN6_TX_C_DP<109>")
	)
	(segment
		(start 379.89002 -408.190192)
		(end 379.89002 -408.572208)
		(width 0.1651)
		(layer "In13.Cu")
		(net "P5E_PEX3_STN6_TX_C_DP<109>")
	)
	(segment
		(start 379.408182 -394.110972)
		(end 379.26899 -394.146024)
		(width 0.1651)
		(layer "In13.Cu")
		(net "P5E_PEX3_STN6_TX_C_DP<109>")
	)
	(segment
		(start 378.84354 -393.891516)
		(end 378.808742 -393.75207)
		(width 0.1651)
		(layer "In13.Cu")
		(net "P5E_PEX3_STN6_TX_C_DP<109>")
	)
	(segment
		(start 369.245134 -385.741418)
		(end 368.733832 -373.351044)
		(width 0.1651)
		(layer "In13.Cu")
		(net "P5E_PEX3_STN6_TX_C_DP<109>")
	)
	(segment
		(start 376.14225 -347.764354)
		(end 377.69673 -346.209874)
		(width 0.1651)
		(layer "In13.Cu")
		(net "P5E_PEX3_STN6_TX_C_DP<109>")
	)
	(segment
		(start 378.3838 -393.497816)
		(end 378.244608 -393.532868)
		(width 0.1651)
		(layer "In13.Cu")
		(net "P5E_PEX3_STN6_TX_C_DP<109>")
	)
	(segment
		(start 377.69673 -345.755976)
		(end 377.4059 -345.465146)
		(width 0.1651)
		(layer "In13.Cu")
		(net "P5E_PEX3_STN6_TX_C_DP<109>")
	)
	(segment
		(start 379.26899 -394.146024)
		(end 378.84354 -393.891516)
		(width 0.1651)
		(layer "In13.Cu")
		(net "P5E_PEX3_STN6_TX_C_DP<109>")
	)
	(segment
		(start 369.32616 -367.352072)
		(end 371.744494 -363.71784)
		(width 0.1651)
		(layer "In13.Cu")
		(net "P5E_PEX3_STN6_TX_C_DP<109>")
	)
	(segment
		(start 378.808742 -393.75207)
		(end 378.3838 -393.497816)
		(width 0.1651)
		(layer "In13.Cu")
		(net "P5E_PEX3_STN6_TX_C_DP<109>")
	)
	(segment
		(start 380.447296 -408.699208)
		(end 380.734062 -408.412442)
		(width 0.1651)
		(layer "In13.Cu")
		(net "P5E_PEX3_STN6_TX_C_DP<109>")
	)
	(segment
		(start 380.734062 -395.167612)
		(end 380.528068 -394.781024)
		(width 0.1651)
		(layer "In13.Cu")
		(net "P5E_PEX3_STN6_TX_C_DP<109>")
	)
	(segment
		(start 375.704608 -391.894568)
		(end 373.62257 -391.006838)
		(width 0.1651)
		(layer "In13.Cu")
		(net "P5E_PEX3_STN6_TX_C_DP<109>")
	)
	(segment
		(start 368.733832 -373.351044)
		(end 369.32616 -367.352072)
		(width 0.1651)
		(layer "In13.Cu")
		(net "P5E_PEX3_STN6_TX_C_DP<109>")
	)
	(segment
		(start 371.744494 -363.71784)
		(end 375.617486 -359.362756)
		(width 0.1651)
		(layer "In13.Cu")
		(net "P5E_PEX3_STN6_TX_C_DP<109>")
	)
	(segment
		(start 373.62257 -391.006838)
		(end 370.428266 -388.641336)
		(width 0.1651)
		(layer "In13.Cu")
		(net "P5E_PEX3_STN6_TX_C_DP<109>")
	)
	(segment
		(start 377.69673 -346.209874)
		(end 377.69673 -345.755976)
		(width 0.1651)
		(layer "In13.Cu")
		(net "P5E_PEX3_STN6_TX_C_DP<109>")
	)
	(segment
		(start 377.819158 -393.27836)
		(end 377.784106 -393.138914)
		(width 0.1651)
		(layer "In13.Cu")
		(net "P5E_PEX3_STN6_TX_C_DP<109>")
	)
	(segment
		(start 375.617486 -359.362756)
		(end 376.14225 -357.984044)
		(width 0.1651)
		(layer "In13.Cu")
		(net "P5E_PEX3_STN6_TX_C_DP<109>")
	)
	(segment
		(start 380.734062 -408.412442)
		(end 380.734062 -395.167612)
		(width 0.1651)
		(layer "In13.Cu")
		(net "P5E_PEX3_STN6_TX_C_DP<109>")
	)
	(segment
		(start 380.01702 -408.699208)
		(end 380.447296 -408.699208)
		(width 0.1651)
		(layer "In13.Cu")
		(net "P5E_PEX3_STN6_TX_C_DP<109>")
	)
	(segment
		(start 379.89002 -408.572208)
		(end 380.01702 -408.699208)
		(width 0.1651)
		(layer "In13.Cu")
		(net "P5E_PEX3_STN6_TX_C_DP<109>")
	)
	(segment
		(start 50.64252 -153.560018)
		(end 52.832 -153.560018)
		(width 0.13208)
		(layer "F.Cu")
		(net "NCSI_NIC0_TXD0")
	)
	(via
		(at 52.832 -153.560018)
		(size 0.508)
		(drill 0.254)
		(layers "F.Cu" "B.Cu")
		(net "NCSI_NIC0_TXD0")
	)
	(segment
		(start 49.95545 -151.9936)
		(end 51.917854 -151.9936)
		(width 0.13208)
		(layer "B.Cu")
		(net "NCSI_NIC0_TXD0")
	)
	(segment
		(start 51.917854 -151.9936)
		(end 52.832 -152.907746)
		(width 0.13208)
		(layer "B.Cu")
		(net "NCSI_NIC0_TXD0")
	)
	(segment
		(start 52.832 -152.907746)
		(end 52.832 -153.560018)
		(width 0.13208)
		(layer "B.Cu")
		(net "NCSI_NIC0_TXD0")
	)
	(segment
		(start 189.357508 -100.039932)
		(end 190.358776 -100.039932)
		(width 0.13208)
		(layer "F.Cu")
		(net "NIC3_CLK")
	)
	(via
		(at 190.358776 -100.039932)
		(size 0.508)
		(drill 0.254)
		(layers "F.Cu" "B.Cu")
		(net "NIC3_CLK")
	)
	(segment
		(start 192.239392 -100.039932)
		(end 190.358776 -100.039932)
		(width 0.13208)
		(layer "B.Cu")
		(net "NIC3_CLK")
	)
	(segment
		(start 193.241676 -99.037648)
		(end 192.239392 -100.039932)
		(width 0.13208)
		(layer "B.Cu")
		(net "NIC3_CLK")
	)
	(segment
		(start 132.023358 -30.6324)
		(end 131.865624 -30.790134)
		(width 0.13462)
		(layer "F.Cu")
		(net "P5E_PEX1_STN2_TX_C_DP<45>")
	)
	(segment
		(start 131.865624 -30.790134)
		(end 131.36499 -30.790134)
		(width 0.13462)
		(layer "F.Cu")
		(net "P5E_PEX1_STN2_TX_C_DP<45>")
	)
	(segment
		(start 135.954262 -30.6324)
		(end 132.023358 -30.6324)
		(width 0.13462)
		(layer "F.Cu")
		(net "P5E_PEX1_STN2_TX_C_DP<45>")
	)
	(segment
		(start 136.267952 -30.94609)
		(end 135.954262 -30.6324)
		(width 0.13462)
		(layer "F.Cu")
		(net "P5E_PEX1_STN2_TX_C_DP<45>")
	)
	(segment
		(start 314.594748 -121.391172)
		(end 314.272676 -121.0691)
		(width 0.13462)
		(layer "F.Cu")
		(net "P5E_PEX2_STN0_TX_C_DP<1>")
	)
	(segment
		(start 306.126134 -121.0691)
		(end 305.960272 -121.234962)
		(width 0.13462)
		(layer "F.Cu")
		(net "P5E_PEX2_STN0_TX_C_DP<1>")
	)
	(segment
		(start 314.272676 -121.0691)
		(end 306.126134 -121.0691)
		(width 0.13462)
		(layer "F.Cu")
		(net "P5E_PEX2_STN0_TX_C_DP<1>")
	)
	(segment
		(start 305.960272 -121.234962)
		(end 305.457606 -121.234962)
		(width 0.13462)
		(layer "F.Cu")
		(net "P5E_PEX2_STN0_TX_C_DP<1>")
	)
	(segment
		(start 400.253708 -101.40188)
		(end 399.578576 -101.40188)
		(width 0.13462)
		(layer "F.Cu")
		(net "P5E_PEX3_STN1_RX_DP<17>")
	)
	(segment
		(start 400.54276 -101.112828)
		(end 400.253708 -101.40188)
		(width 0.13462)
		(layer "F.Cu")
		(net "P5E_PEX3_STN1_RX_DP<17>")
	)
	(segment
		(start 399.578576 -101.40188)
		(end 399.421604 -101.244908)
		(width 0.13462)
		(layer "F.Cu")
		(net "P5E_PEX3_STN1_RX_DP<17>")
	)
	(segment
		(start 399.421604 -101.244908)
		(end 398.94256 -101.244908)
		(width 0.13462)
		(layer "F.Cu")
		(net "P5E_PEX3_STN1_RX_DP<17>")
	)
	(segment
		(start 408.329638 -275.35505)
		(end 408.544522 -275.569934)
		(width 0.1143)
		(layer "In5.Cu")
		(net "P5E_PEX3_STN1_RX_DP<17>")
	)
	(segment
		(start 408.785314 -275.569934)
		(end 408.899614 -275.684234)
		(width 0.1143)
		(layer "In5.Cu")
		(net "P5E_PEX3_STN1_RX_DP<17>")
	)
	(segment
		(start 408.283918 -269.939516)
		(end 408.283918 -271.570704)
		(width 0.1651)
		(layer "In5.Cu")
		(net "P5E_PEX3_STN1_RX_DP<17>")
	)
	(segment
		(start 408.899614 -275.684234)
		(end 408.899614 -275.949664)
		(width 0.1143)
		(layer "In5.Cu")
		(net "P5E_PEX3_STN1_RX_DP<17>")
	)
	(segment
		(start 378.76099 -126.572518)
		(end 377.335288 -150.181056)
		(width 0.1651)
		(layer "In5.Cu")
		(net "P5E_PEX3_STN1_RX_DP<17>")
	)
	(segment
		(start 408.283918 -271.599152)
		(end 408.329638 -271.644872)
		(width 0.1143)
		(layer "In5.Cu")
		(net "P5E_PEX3_STN1_RX_DP<17>")
	)
	(segment
		(start 380.263908 -119.854218)
		(end 378.76099 -126.572518)
		(width 0.1651)
		(layer "In5.Cu")
		(net "P5E_PEX3_STN1_RX_DP<17>")
	)
	(segment
		(start 379.10008 -165.415214)
		(end 408.283918 -269.939516)
		(width 0.1651)
		(layer "In5.Cu")
		(net "P5E_PEX3_STN1_RX_DP<17>")
	)
	(segment
		(start 408.544522 -275.569934)
		(end 408.785314 -275.569934)
		(width 0.1143)
		(layer "In5.Cu")
		(net "P5E_PEX3_STN1_RX_DP<17>")
	)
	(segment
		(start 408.329638 -271.644872)
		(end 408.329638 -275.35505)
		(width 0.1143)
		(layer "In5.Cu")
		(net "P5E_PEX3_STN1_RX_DP<17>")
	)
	(segment
		(start 381.634238 -117.142768)
		(end 380.263908 -119.854218)
		(width 0.1651)
		(layer "In5.Cu")
		(net "P5E_PEX3_STN1_RX_DP<17>")
	)
	(segment
		(start 399.760186 -101.403658)
		(end 399.723102 -101.440742)
		(width 0.1651)
		(layer "In5.Cu")
		(net "P5E_PEX3_STN1_RX_DP<17>")
	)
	(segment
		(start 393.022074 -105.264204)
		(end 381.634238 -117.142768)
		(width 0.1651)
		(layer "In5.Cu")
		(net "P5E_PEX3_STN1_RX_DP<17>")
	)
	(segment
		(start 399.723102 -101.440742)
		(end 393.022074 -105.264204)
		(width 0.1651)
		(layer "In5.Cu")
		(net "P5E_PEX3_STN1_RX_DP<17>")
	)
	(segment
		(start 377.905264 -158.872936)
		(end 379.10008 -165.415214)
		(width 0.1651)
		(layer "In5.Cu")
		(net "P5E_PEX3_STN1_RX_DP<17>")
	)
	(segment
		(start 400.25193 -101.403658)
		(end 399.760186 -101.403658)
		(width 0.1651)
		(layer "In5.Cu")
		(net "P5E_PEX3_STN1_RX_DP<17>")
	)
	(segment
		(start 408.283918 -271.570704)
		(end 408.283918 -271.599152)
		(width 0.1143)
		(layer "In5.Cu")
		(net "P5E_PEX3_STN1_RX_DP<17>")
	)
	(segment
		(start 377.335288 -150.181056)
		(end 377.905264 -158.872936)
		(width 0.1651)
		(layer "In5.Cu")
		(net "P5E_PEX3_STN1_RX_DP<17>")
	)
	(segment
		(start 400.54276 -101.112828)
		(end 400.25193 -101.403658)
		(width 0.1651)
		(layer "In5.Cu")
		(net "P5E_PEX3_STN1_RX_DP<17>")
	)
	(segment
		(start 380.810008 -344.53957)
		(end 380.810008 -345.169998)
		(width 0.13462)
		(layer "F.Cu")
		(net "P5E_PEX3_STN6_TX_C_DP<99>")
	)
	(segment
		(start 380.810008 -345.169998)
		(end 380.51486 -345.465146)
		(width 0.13462)
		(layer "F.Cu")
		(net "P5E_PEX3_STN6_TX_C_DP<99>")
	)
	(segment
		(start 380.48946 -344.219022)
		(end 380.810008 -344.53957)
		(width 0.13462)
		(layer "F.Cu")
		(net "P5E_PEX3_STN6_TX_C_DP<99>")
	)
	(segment
		(start 383.365756 -365.936784)
		(end 383.408174 -365.780828)
		(width 0.1651)
		(layer "In7.Cu")
		(net "P5E_PEX3_STN6_TX_C_DP<99>")
	)
	(segment
		(start 385.134104 -382.412494)
		(end 385.134104 -368.79276)
		(width 0.1651)
		(layer "In7.Cu")
		(net "P5E_PEX3_STN6_TX_C_DP<99>")
	)
	(segment
		(start 384.847338 -382.69926)
		(end 385.134104 -382.412494)
		(width 0.1651)
		(layer "In7.Cu")
		(net "P5E_PEX3_STN6_TX_C_DP<99>")
	)
	(segment
		(start 383.408174 -365.780828)
		(end 379.25121 -358.52608)
		(width 0.1651)
		(layer "In7.Cu")
		(net "P5E_PEX3_STN6_TX_C_DP<99>")
	)
	(segment
		(start 380.80569 -345.755976)
		(end 380.51486 -345.465146)
		(width 0.1651)
		(layer "In7.Cu")
		(net "P5E_PEX3_STN6_TX_C_DP<99>")
	)
	(segment
		(start 384.290062 -382.18999)
		(end 384.290062 -382.57226)
		(width 0.1651)
		(layer "In7.Cu")
		(net "P5E_PEX3_STN6_TX_C_DP<99>")
	)
	(segment
		(start 384.218688 -367.424716)
		(end 383.972054 -366.994694)
		(width 0.1651)
		(layer "In7.Cu")
		(net "P5E_PEX3_STN6_TX_C_DP<99>")
	)
	(segment
		(start 383.768346 -366.409224)
		(end 383.61239 -366.366806)
		(width 0.1651)
		(layer "In7.Cu")
		(net "P5E_PEX3_STN6_TX_C_DP<99>")
	)
	(segment
		(start 384.290062 -382.57226)
		(end 384.417062 -382.69926)
		(width 0.1651)
		(layer "In7.Cu")
		(net "P5E_PEX3_STN6_TX_C_DP<99>")
	)
	(segment
		(start 384.014472 -366.838738)
		(end 383.768346 -366.409224)
		(width 0.1651)
		(layer "In7.Cu")
		(net "P5E_PEX3_STN6_TX_C_DP<99>")
	)
	(segment
		(start 384.417062 -382.69926)
		(end 384.847338 -382.69926)
		(width 0.1651)
		(layer "In7.Cu")
		(net "P5E_PEX3_STN6_TX_C_DP<99>")
	)
	(segment
		(start 383.61239 -366.366806)
		(end 383.365756 -365.936784)
		(width 0.1651)
		(layer "In7.Cu")
		(net "P5E_PEX3_STN6_TX_C_DP<99>")
	)
	(segment
		(start 384.374644 -367.467134)
		(end 384.218688 -367.424716)
		(width 0.1651)
		(layer "In7.Cu")
		(net "P5E_PEX3_STN6_TX_C_DP<99>")
	)
	(segment
		(start 380.80569 -346.209874)
		(end 380.80569 -345.755976)
		(width 0.1651)
		(layer "In7.Cu")
		(net "P5E_PEX3_STN6_TX_C_DP<99>")
	)
	(segment
		(start 379.25121 -347.764354)
		(end 380.80569 -346.209874)
		(width 0.1651)
		(layer "In7.Cu")
		(net "P5E_PEX3_STN6_TX_C_DP<99>")
	)
	(segment
		(start 383.972054 -366.994694)
		(end 384.014472 -366.838738)
		(width 0.1651)
		(layer "In7.Cu")
		(net "P5E_PEX3_STN6_TX_C_DP<99>")
	)
	(segment
		(start 379.25121 -358.52608)
		(end 379.25121 -347.764354)
		(width 0.1651)
		(layer "In7.Cu")
		(net "P5E_PEX3_STN6_TX_C_DP<99>")
	)
	(segment
		(start 385.134104 -368.79276)
		(end 384.374644 -367.467134)
		(width 0.1651)
		(layer "In7.Cu")
		(net "P5E_PEX3_STN6_TX_C_DP<99>")
	)
	(segment
		(start 47.073312 -139.029186)
		(end 46.537372 -139.565126)
		(width 0.13208)
		(layer "F.Cu")
		(net "NIC0_AUX_PWR_EN_R")
	)
	(segment
		(start 47.073312 -138.564112)
		(end 47.073312 -139.029186)
		(width 0.13208)
		(layer "F.Cu")
		(net "NIC0_AUX_PWR_EN_R")
	)
	(segment
		(start 46.537372 -139.565126)
		(end 46.042326 -139.565126)
		(width 0.13208)
		(layer "F.Cu")
		(net "NIC0_AUX_PWR_EN_R")
	)
	(via
		(at 47.073312 -138.564112)
		(size 0.508)
		(drill 0.254)
		(layers "F.Cu" "B.Cu")
		(net "NIC0_AUX_PWR_EN_R")
	)
	(segment
		(start 47.490888 -138.564112)
		(end 47.633382 -138.421618)
		(width 0.13208)
		(layer "B.Cu")
		(net "NIC0_AUX_PWR_EN_R")
	)
	(segment
		(start 47.073312 -138.564112)
		(end 47.490888 -138.564112)
		(width 0.13208)
		(layer "B.Cu")
		(net "NIC0_AUX_PWR_EN_R")
	)
	(segment
		(start 47.633382 -138.421618)
		(end 48.465994 -138.421618)
		(width 0.13208)
		(layer "B.Cu")
		(net "NIC0_AUX_PWR_EN_R")
	)
	(segment
		(start 48.592994 -137.668)
		(end 53.086 -137.668)
		(width 0.13208)
		(layer "B.Cu")
		(net "NIC0_AUX_PWR_EN_R")
	)
	(segment
		(start 48.465994 -137.795)
		(end 48.592994 -137.668)
		(width 0.13208)
		(layer "B.Cu")
		(net "NIC0_AUX_PWR_EN_R")
	)
	(segment
		(start 48.465994 -138.421618)
		(end 48.465994 -137.795)
		(width 0.13208)
		(layer "B.Cu")
		(net "NIC0_AUX_PWR_EN_R")
	)
	(segment
		(start 53.086 -137.668)
		(end 53.96484 -138.54684)
		(width 0.13208)
		(layer "B.Cu")
		(net "NIC0_AUX_PWR_EN_R")
	)
	(segment
		(start 53.96484 -138.54684)
		(end 53.96484 -140.181076)
		(width 0.13208)
		(layer "B.Cu")
		(net "NIC0_AUX_PWR_EN_R")
	)
	(segment
		(start 199.305418 -112.078516)
		(end 199.305418 -112.394492)
		(width 0.13208)
		(layer "F.Cu")
		(net "NIC3_BIF0_N")
	)
	(segment
		(start 197.541388 -111.884714)
		(end 199.111616 -111.884714)
		(width 0.13208)
		(layer "F.Cu")
		(net "NIC3_BIF0_N")
	)
	(segment
		(start 196.348858 -112.834928)
		(end 197.127876 -112.05591)
		(width 0.13208)
		(layer "F.Cu")
		(net "NIC3_BIF0_N")
	)
	(segment
		(start 199.308466 -112.39754)
		(end 199.305418 -112.394492)
		(width 0.13208)
		(layer "F.Cu")
		(net "NIC3_BIF0_N")
	)
	(segment
		(start 189.357508 -112.834928)
		(end 191.584834 -112.834928)
		(width 0.13208)
		(layer "F.Cu")
		(net "NIC3_BIF0_N")
	)
	(segment
		(start 197.127876 -112.05591)
		(end 197.541388 -111.884714)
		(width 0.13208)
		(layer "F.Cu")
		(net "NIC3_BIF0_N")
	)
	(segment
		(start 191.666622 -112.75314)
		(end 193.462148 -112.75314)
		(width 0.13208)
		(layer "F.Cu")
		(net "NIC3_BIF0_N")
	)
	(segment
		(start 199.111616 -111.884714)
		(end 199.305418 -112.078516)
		(width 0.13208)
		(layer "F.Cu")
		(net "NIC3_BIF0_N")
	)
	(segment
		(start 191.584834 -112.834928)
		(end 191.666622 -112.75314)
		(width 0.13208)
		(layer "F.Cu")
		(net "NIC3_BIF0_N")
	)
	(segment
		(start 193.462148 -112.75314)
		(end 193.543936 -112.834928)
		(width 0.13208)
		(layer "F.Cu")
		(net "NIC3_BIF0_N")
	)
	(segment
		(start 193.543936 -112.834928)
		(end 196.348858 -112.834928)
		(width 0.13208)
		(layer "F.Cu")
		(net "NIC3_BIF0_N")
	)
	(segment
		(start 200.291446 -112.39754)
		(end 199.308466 -112.39754)
		(width 0.13208)
		(layer "F.Cu")
		(net "NIC3_BIF0_N")
	)
	(via
		(at 197.127876 -112.05591)
		(size 0.762)
		(drill 0.381)
		(layers "F.Cu" "B.Cu")
		(net "NIC3_BIF0_N")
	)
	(segment
		(start 35.354768 -32.14878)
		(end 35.0647 -31.858712)
		(width 0.13462)
		(layer "F.Cu")
		(net "P5E_PEX0_STN2_RX_DN<42>")
	)
	(segment
		(start 36.025328 -32.14878)
		(end 35.354768 -32.14878)
		(width 0.13462)
		(layer "F.Cu")
		(net "P5E_PEX0_STN2_RX_DN<42>")
	)
	(segment
		(start 36.6649 -31.99003)
		(end 36.184078 -31.99003)
		(width 0.13462)
		(layer "F.Cu")
		(net "P5E_PEX0_STN2_RX_DN<42>")
	)
	(segment
		(start 36.184078 -31.99003)
		(end 36.025328 -32.14878)
		(width 0.13462)
		(layer "F.Cu")
		(net "P5E_PEX0_STN2_RX_DN<42>")
	)
	(segment
		(start 37.526468 -65.159636)
		(end 37.1348 -55.367682)
		(width 0.1651)
		(layer "In7.Cu")
		(net "P5E_PEX0_STN2_RX_DN<42>")
	)
	(segment
		(start 48.923702 -275.379688)
		(end 48.819816 -275.275802)
		(width 0.1143)
		(layer "In7.Cu")
		(net "P5E_PEX0_STN2_RX_DN<42>")
	)
	(segment
		(start 48.865536 -271.392904)
		(end 48.865536 -267.767816)
		(width 0.1651)
		(layer "In7.Cu")
		(net "P5E_PEX0_STN2_RX_DN<42>")
	)
	(segment
		(start 49.1998 -275.265388)
		(end 49.0855 -275.379688)
		(width 0.1143)
		(layer "In7.Cu")
		(net "P5E_PEX0_STN2_RX_DN<42>")
	)
	(segment
		(start 40.857424 -148.002498)
		(end 41.163748 -119.5832)
		(width 0.1651)
		(layer "In7.Cu")
		(net "P5E_PEX0_STN2_RX_DN<42>")
	)
	(segment
		(start 48.644556 -258.734306)
		(end 48.813466 -249.99696)
		(width 0.1651)
		(layer "In7.Cu")
		(net "P5E_PEX0_STN2_RX_DN<42>")
	)
	(segment
		(start 36.407344 -35.04819)
		(end 36.444428 -32.663638)
		(width 0.1651)
		(layer "In7.Cu")
		(net "P5E_PEX0_STN2_RX_DN<42>")
	)
	(segment
		(start 35.930078 -32.149542)
		(end 35.35553 -32.149542)
		(width 0.1651)
		(layer "In7.Cu")
		(net "P5E_PEX0_STN2_RX_DN<42>")
	)
	(segment
		(start 35.35553 -32.149542)
		(end 35.0647 -31.858712)
		(width 0.1651)
		(layer "In7.Cu")
		(net "P5E_PEX0_STN2_RX_DN<42>")
	)
	(segment
		(start 48.422052 -263.266174)
		(end 48.644556 -258.734306)
		(width 0.1651)
		(layer "In7.Cu")
		(net "P5E_PEX0_STN2_RX_DN<42>")
	)
	(segment
		(start 48.819816 -271.467072)
		(end 48.865536 -271.421352)
		(width 0.1143)
		(layer "In7.Cu")
		(net "P5E_PEX0_STN2_RX_DN<42>")
	)
	(segment
		(start 37.1348 -55.367682)
		(end 37.227256 -49.435766)
		(width 0.1651)
		(layer "In7.Cu")
		(net "P5E_PEX0_STN2_RX_DN<42>")
	)
	(segment
		(start 35.91306 -39.71036)
		(end 35.88385 -37.856414)
		(width 0.1651)
		(layer "In7.Cu")
		(net "P5E_PEX0_STN2_RX_DN<42>")
	)
	(segment
		(start 37.227256 -49.435766)
		(end 35.91306 -39.71036)
		(width 0.1651)
		(layer "In7.Cu")
		(net "P5E_PEX0_STN2_RX_DN<42>")
	)
	(segment
		(start 48.813466 -249.99696)
		(end 40.857424 -148.002498)
		(width 0.1651)
		(layer "In7.Cu")
		(net "P5E_PEX0_STN2_RX_DN<42>")
	)
	(segment
		(start 48.865536 -267.767816)
		(end 48.422052 -263.266174)
		(width 0.1651)
		(layer "In7.Cu")
		(net "P5E_PEX0_STN2_RX_DN<42>")
	)
	(segment
		(start 36.444428 -32.663638)
		(end 35.930078 -32.149542)
		(width 0.1651)
		(layer "In7.Cu")
		(net "P5E_PEX0_STN2_RX_DN<42>")
	)
	(segment
		(start 40.720518 -104.952546)
		(end 37.526468 -65.159636)
		(width 0.1651)
		(layer "In7.Cu")
		(net "P5E_PEX0_STN2_RX_DN<42>")
	)
	(segment
		(start 48.819816 -275.275802)
		(end 48.819816 -271.467072)
		(width 0.1143)
		(layer "In7.Cu")
		(net "P5E_PEX0_STN2_RX_DN<42>")
	)
	(segment
		(start 35.88385 -37.856414)
		(end 36.407344 -35.04819)
		(width 0.1651)
		(layer "In7.Cu")
		(net "P5E_PEX0_STN2_RX_DN<42>")
	)
	(segment
		(start 49.1998 -274.999958)
		(end 49.1998 -275.265388)
		(width 0.1143)
		(layer "In7.Cu")
		(net "P5E_PEX0_STN2_RX_DN<42>")
	)
	(segment
		(start 48.865536 -271.421352)
		(end 48.865536 -271.392904)
		(width 0.1143)
		(layer "In7.Cu")
		(net "P5E_PEX0_STN2_RX_DN<42>")
	)
	(segment
		(start 49.0855 -275.379688)
		(end 48.923702 -275.379688)
		(width 0.1143)
		(layer "In7.Cu")
		(net "P5E_PEX0_STN2_RX_DN<42>")
	)
	(segment
		(start 41.163748 -119.5832)
		(end 40.720518 -104.952546)
		(width 0.1651)
		(layer "In7.Cu")
		(net "P5E_PEX0_STN2_RX_DN<42>")
	)
	(segment
		(start 183.87187 -33.790128)
		(end 183.364886 -33.790128)
		(width 0.13462)
		(layer "F.Cu")
		(net "P5E_PEX1_STN2_TX_C_DN<39>")
	)
	(segment
		(start 184.033922 -33.95218)
		(end 183.87187 -33.790128)
		(width 0.13462)
		(layer "F.Cu")
		(net "P5E_PEX1_STN2_TX_C_DN<39>")
	)
	(segment
		(start 187.947554 -33.95218)
		(end 184.033922 -33.95218)
		(width 0.13462)
		(layer "F.Cu")
		(net "P5E_PEX1_STN2_TX_C_DN<39>")
	)
	(segment
		(start 188.267848 -33.631886)
		(end 187.947554 -33.95218)
		(width 0.13462)
		(layer "F.Cu")
		(net "P5E_PEX1_STN2_TX_C_DN<39>")
	)
	(segment
		(start 305.964336 -155.355036)
		(end 305.457606 -155.355036)
		(width 0.13462)
		(layer "F.Cu")
		(net "P5E_PEX2_STN0_TX_C_DN<15>")
	)
	(segment
		(start 314.594748 -155.196794)
		(end 314.267342 -155.5242)
		(width 0.13462)
		(layer "F.Cu")
		(net "P5E_PEX2_STN0_TX_C_DN<15>")
	)
	(segment
		(start 314.267342 -155.5242)
		(end 306.1335 -155.5242)
		(width 0.13462)
		(layer "F.Cu")
		(net "P5E_PEX2_STN0_TX_C_DN<15>")
	)
	(segment
		(start 306.1335 -155.5242)
		(end 305.964336 -155.355036)
		(width 0.13462)
		(layer "F.Cu")
		(net "P5E_PEX2_STN0_TX_C_DN<15>")
	)
	(segment
		(start 385.205224 -123.71324)
		(end 385.525264 -123.3932)
		(width 0.13462)
		(layer "F.Cu")
		(net "P5E_PEX3_STN1_TX_C_DN<26>")
	)
	(segment
		(start 393.673838 -123.3932)
		(end 393.835636 -123.554998)
		(width 0.13462)
		(layer "F.Cu")
		(net "P5E_PEX3_STN1_TX_C_DN<26>")
	)
	(segment
		(start 385.525264 -123.3932)
		(end 393.673838 -123.3932)
		(width 0.13462)
		(layer "F.Cu")
		(net "P5E_PEX3_STN1_TX_C_DN<26>")
	)
	(segment
		(start 393.835636 -123.554998)
		(end 394.342366 -123.554998)
		(width 0.13462)
		(layer "F.Cu")
		(net "P5E_PEX3_STN1_TX_C_DN<26>")
	)
	(segment
		(start 392.179556 -319.921128)
		(end 392.133836 -319.966848)
		(width 0.1143)
		(layer "In15.Cu")
		(net "P5E_PEX3_STN6_RX_DP<110>")
	)
	(segment
		(start 367.959894 -341.92083)
		(end 367.630456 -372.171468)
		(width 0.1651)
		(layer "In15.Cu")
		(net "P5E_PEX3_STN6_RX_DP<110>")
	)
	(segment
		(start 367.630456 -372.171468)
		(end 368.231928 -385.875276)
		(width 0.1651)
		(layer "In15.Cu")
		(net "P5E_PEX3_STN6_RX_DP<110>")
	)
	(segment
		(start 377.689872 -401.872196)
		(end 377.689872 -401.49018)
		(width 0.1651)
		(layer "In15.Cu")
		(net "P5E_PEX3_STN6_RX_DP<110>")
	)
	(segment
		(start 374.141492 -392.301984)
		(end 374.198896 -392.453368)
		(width 0.1651)
		(layer "In15.Cu")
		(net "P5E_PEX3_STN6_RX_DP<110>")
	)
	(segment
		(start 377.799092 -395.216634)
		(end 377.95962 -395.236446)
		(width 0.1651)
		(layer "In15.Cu")
		(net "P5E_PEX3_STN6_RX_DP<110>")
	)
	(segment
		(start 378.269754 -395.634464)
		(end 378.533914 -396.53464)
		(width 0.1651)
		(layer "In15.Cu")
		(net "P5E_PEX3_STN6_RX_DP<110>")
	)
	(segment
		(start 392.394694 -318.129666)
		(end 392.179556 -318.344804)
		(width 0.1143)
		(layer "In15.Cu")
		(net "P5E_PEX3_STN6_RX_DP<110>")
	)
	(segment
		(start 377.816872 -401.999196)
		(end 377.689872 -401.872196)
		(width 0.1651)
		(layer "In15.Cu")
		(net "P5E_PEX3_STN6_RX_DP<110>")
	)
	(segment
		(start 392.749786 -318.015366)
		(end 392.635486 -318.129666)
		(width 0.1143)
		(layer "In15.Cu")
		(net "P5E_PEX3_STN6_RX_DP<110>")
	)
	(segment
		(start 392.635486 -318.129666)
		(end 392.394694 -318.129666)
		(width 0.1143)
		(layer "In15.Cu")
		(net "P5E_PEX3_STN6_RX_DP<110>")
	)
	(segment
		(start 368.231928 -385.875276)
		(end 369.625372 -389.243824)
		(width 0.1651)
		(layer "In15.Cu")
		(net "P5E_PEX3_STN6_RX_DP<110>")
	)
	(segment
		(start 368.01298 -341.612728)
		(end 367.959894 -341.92083)
		(width 0.1651)
		(layer "In15.Cu")
		(net "P5E_PEX3_STN6_RX_DP<110>")
	)
	(segment
		(start 392.133836 -319.995296)
		(end 392.133836 -320.623184)
		(width 0.1651)
		(layer "In15.Cu")
		(net "P5E_PEX3_STN6_RX_DP<110>")
	)
	(segment
		(start 375.533412 -392.927078)
		(end 377.155456 -394.205206)
		(width 0.1651)
		(layer "In15.Cu")
		(net "P5E_PEX3_STN6_RX_DP<110>")
	)
	(segment
		(start 392.133836 -319.966848)
		(end 392.133836 -319.995296)
		(width 0.1143)
		(layer "In15.Cu")
		(net "P5E_PEX3_STN6_RX_DP<110>")
	)
	(segment
		(start 377.494292 -394.825728)
		(end 377.799092 -395.216634)
		(width 0.1651)
		(layer "In15.Cu")
		(net "P5E_PEX3_STN6_RX_DP<110>")
	)
	(segment
		(start 392.179556 -318.344804)
		(end 392.179556 -319.921128)
		(width 0.1143)
		(layer "In15.Cu")
		(net "P5E_PEX3_STN6_RX_DP<110>")
	)
	(segment
		(start 377.514104 -394.665454)
		(end 377.494292 -394.825728)
		(width 0.1651)
		(layer "In15.Cu")
		(net "P5E_PEX3_STN6_RX_DP<110>")
	)
	(segment
		(start 374.651016 -392.656314)
		(end 374.802146 -392.59891)
		(width 0.1651)
		(layer "In15.Cu")
		(net "P5E_PEX3_STN6_RX_DP<110>")
	)
	(segment
		(start 373.024146 -391.800334)
		(end 374.141492 -392.301984)
		(width 0.1651)
		(layer "In15.Cu")
		(net "P5E_PEX3_STN6_RX_DP<110>")
	)
	(segment
		(start 374.198896 -392.453368)
		(end 374.651016 -392.656314)
		(width 0.1651)
		(layer "In15.Cu")
		(net "P5E_PEX3_STN6_RX_DP<110>")
	)
	(segment
		(start 369.625372 -389.243824)
		(end 373.024146 -391.800334)
		(width 0.1651)
		(layer "In15.Cu")
		(net "P5E_PEX3_STN6_RX_DP<110>")
	)
	(segment
		(start 374.802146 -392.59891)
		(end 375.533412 -392.927078)
		(width 0.1651)
		(layer "In15.Cu")
		(net "P5E_PEX3_STN6_RX_DP<110>")
	)
	(segment
		(start 377.95962 -395.236446)
		(end 378.269754 -395.634464)
		(width 0.1651)
		(layer "In15.Cu")
		(net "P5E_PEX3_STN6_RX_DP<110>")
	)
	(segment
		(start 378.533914 -401.71243)
		(end 378.247148 -401.999196)
		(width 0.1651)
		(layer "In15.Cu")
		(net "P5E_PEX3_STN6_RX_DP<110>")
	)
	(segment
		(start 390.185148 -322.571872)
		(end 369.18773 -339.606636)
		(width 0.1651)
		(layer "In15.Cu")
		(net "P5E_PEX3_STN6_RX_DP<110>")
	)
	(segment
		(start 377.155456 -394.205206)
		(end 377.514104 -394.665454)
		(width 0.1651)
		(layer "In15.Cu")
		(net "P5E_PEX3_STN6_RX_DP<110>")
	)
	(segment
		(start 392.749786 -317.749936)
		(end 392.749786 -318.015366)
		(width 0.1143)
		(layer "In15.Cu")
		(net "P5E_PEX3_STN6_RX_DP<110>")
	)
	(segment
		(start 392.133836 -320.623184)
		(end 390.185148 -322.571872)
		(width 0.1651)
		(layer "In15.Cu")
		(net "P5E_PEX3_STN6_RX_DP<110>")
	)
	(segment
		(start 369.18773 -339.606636)
		(end 368.01298 -341.612728)
		(width 0.1651)
		(layer "In15.Cu")
		(net "P5E_PEX3_STN6_RX_DP<110>")
	)
	(segment
		(start 378.247148 -401.999196)
		(end 377.816872 -401.999196)
		(width 0.1651)
		(layer "In15.Cu")
		(net "P5E_PEX3_STN6_RX_DP<110>")
	)
	(segment
		(start 378.533914 -396.53464)
		(end 378.533914 -401.71243)
		(width 0.1651)
		(layer "In15.Cu")
		(net "P5E_PEX3_STN6_RX_DP<110>")
	)
	(segment
		(start 38.39083 -142.892018)
		(end 38.39083 -143.14805)
		(width 0.13208)
		(layer "F.Cu")
		(net "NIC0_BIF0_N")
	)
	(segment
		(start 40.381428 -143.350234)
		(end 41.72204 -143.350234)
		(width 0.13208)
		(layer "F.Cu")
		(net "NIC0_BIF0_N")
	)
	(segment
		(start 38.387782 -142.88897)
		(end 38.39083 -142.892018)
		(width 0.13208)
		(layer "F.Cu")
		(net "NIC0_BIF0_N")
	)
	(segment
		(start 37.404802 -142.88897)
		(end 38.387782 -142.88897)
		(width 0.13208)
		(layer "F.Cu")
		(net "NIC0_BIF0_N")
	)
	(segment
		(start 38.39083 -143.14805)
		(end 38.644576 -143.401796)
		(width 0.13208)
		(layer "F.Cu")
		(net "NIC0_BIF0_N")
	)
	(segment
		(start 41.72204 -143.350234)
		(end 42.507154 -142.56512)
		(width 0.13208)
		(layer "F.Cu")
		(net "NIC0_BIF0_N")
	)
	(segment
		(start 42.507154 -142.56512)
		(end 46.042326 -142.56512)
		(width 0.13208)
		(layer "F.Cu")
		(net "NIC0_BIF0_N")
	)
	(segment
		(start 38.644576 -143.401796)
		(end 40.329866 -143.401796)
		(width 0.13208)
		(layer "F.Cu")
		(net "NIC0_BIF0_N")
	)
	(segment
		(start 40.329866 -143.401796)
		(end 40.381428 -143.350234)
		(width 0.13208)
		(layer "F.Cu")
		(net "NIC0_BIF0_N")
	)
	(via
		(at 40.381428 -143.350234)
		(size 0.762)
		(drill 0.381)
		(layers "F.Cu" "B.Cu")
		(net "NIC0_BIF0_N")
	)
	(segment
		(start 179.970684 -138.864848)
		(end 179.970684 -137.848848)
		(width 0.13208)
		(layer "F.Cu")
		(net "PRSNTB1_NIC3_N")
	)
	(segment
		(start 182.33136 -137.24509)
		(end 180.711602 -138.864848)
		(width 0.13208)
		(layer "F.Cu")
		(net "PRSNTB1_NIC3_N")
	)
	(segment
		(start 180.711602 -138.864848)
		(end 179.970684 -138.864848)
		(width 0.13208)
		(layer "F.Cu")
		(net "PRSNTB1_NIC3_N")
	)
	(segment
		(start 184.757314 -137.24509)
		(end 182.33136 -137.24509)
		(width 0.13208)
		(layer "F.Cu")
		(net "PRSNTB1_NIC3_N")
	)
	(via
		(at 180.711602 -138.864848)
		(size 0.508)
		(drill 0.254)
		(layers "F.Cu" "B.Cu")
		(net "PRSNTB1_NIC3_N")
	)
	(segment
		(start 7.504684 -33.952942)
		(end 7.210552 -33.65881)
		(width 0.13462)
		(layer "F.Cu")
		(net "P5E_PEX0_STN2_RX_DN<47>")
	)
	(segment
		(start 10.187432 -33.790128)
		(end 10.024618 -33.952942)
		(width 0.13462)
		(layer "F.Cu")
		(net "P5E_PEX0_STN2_RX_DN<47>")
	)
	(segment
		(start 10.664952 -33.790128)
		(end 10.187432 -33.790128)
		(width 0.13462)
		(layer "F.Cu")
		(net "P5E_PEX0_STN2_RX_DN<47>")
	)
	(segment
		(start 10.024618 -33.952942)
		(end 7.504684 -33.952942)
		(width 0.13462)
		(layer "F.Cu")
		(net "P5E_PEX0_STN2_RX_DN<47>")
	)
	(segment
		(start 43.91787 -268.824202)
		(end 43.548554 -267.026644)
		(width 0.1651)
		(layer "In7.Cu")
		(net "P5E_PEX0_STN2_RX_DN<47>")
	)
	(segment
		(start 41.628314 -238.434118)
		(end 23.894796 -144.65427)
		(width 0.1651)
		(layer "In7.Cu")
		(net "P5E_PEX0_STN2_RX_DN<47>")
	)
	(segment
		(start 44.070016 -271.41932)
		(end 44.115736 -271.3736)
		(width 0.1143)
		(layer "In7.Cu")
		(net "P5E_PEX0_STN2_RX_DN<47>")
	)
	(segment
		(start 10.231882 -85.574378)
		(end 10.421366 -62.60846)
		(width 0.1651)
		(layer "In7.Cu")
		(net "P5E_PEX0_STN2_RX_DN<47>")
	)
	(segment
		(start 10.421366 -62.60846)
		(end 10.421366 -60.243212)
		(width 0.1651)
		(layer "In7.Cu")
		(net "P5E_PEX0_STN2_RX_DN<47>")
	)
	(segment
		(start 44.115736 -271.345152)
		(end 44.115736 -270.472916)
		(width 0.1651)
		(layer "In7.Cu")
		(net "P5E_PEX0_STN2_RX_DN<47>")
	)
	(segment
		(start 7.501382 -33.94964)
		(end 7.210552 -33.65881)
		(width 0.1651)
		(layer "In7.Cu")
		(net "P5E_PEX0_STN2_RX_DN<47>")
	)
	(segment
		(start 8.888222 -34.98596)
		(end 7.851902 -33.94964)
		(width 0.1651)
		(layer "In7.Cu")
		(net "P5E_PEX0_STN2_RX_DN<47>")
	)
	(segment
		(start 7.851902 -33.94964)
		(end 7.501382 -33.94964)
		(width 0.1651)
		(layer "In7.Cu")
		(net "P5E_PEX0_STN2_RX_DN<47>")
	)
	(segment
		(start 44.115736 -271.3736)
		(end 44.115736 -271.345152)
		(width 0.1143)
		(layer "In7.Cu")
		(net "P5E_PEX0_STN2_RX_DN<47>")
	)
	(segment
		(start 44.220892 -273.479514)
		(end 44.070016 -273.328638)
		(width 0.1143)
		(layer "In7.Cu")
		(net "P5E_PEX0_STN2_RX_DN<47>")
	)
	(segment
		(start 23.894796 -144.65427)
		(end 20.640802 -119.914416)
		(width 0.1651)
		(layer "In7.Cu")
		(net "P5E_PEX0_STN2_RX_DN<47>")
	)
	(segment
		(start 44.335446 -273.479514)
		(end 44.220892 -273.479514)
		(width 0.1143)
		(layer "In7.Cu")
		(net "P5E_PEX0_STN2_RX_DN<47>")
	)
	(segment
		(start 44.449746 -273.365214)
		(end 44.335446 -273.479514)
		(width 0.1143)
		(layer "In7.Cu")
		(net "P5E_PEX0_STN2_RX_DN<47>")
	)
	(segment
		(start 43.135296 -262.327898)
		(end 43.201082 -255.61163)
		(width 0.1651)
		(layer "In7.Cu")
		(net "P5E_PEX0_STN2_RX_DN<47>")
	)
	(segment
		(start 10.421366 -60.243212)
		(end 10.14984 -57.243218)
		(width 0.1651)
		(layer "In7.Cu")
		(net "P5E_PEX0_STN2_RX_DN<47>")
	)
	(segment
		(start 15.436596 -102.745032)
		(end 15.436342 -102.744524)
		(width 0.1651)
		(layer "In7.Cu")
		(net "P5E_PEX0_STN2_RX_DN<47>")
	)
	(segment
		(start 10.14984 -57.243218)
		(end 10.26541 -49.854612)
		(width 0.1651)
		(layer "In7.Cu")
		(net "P5E_PEX0_STN2_RX_DN<47>")
	)
	(segment
		(start 44.070016 -273.328638)
		(end 44.070016 -271.41932)
		(width 0.1143)
		(layer "In7.Cu")
		(net "P5E_PEX0_STN2_RX_DN<47>")
	)
	(segment
		(start 44.115736 -270.472916)
		(end 43.91787 -268.824202)
		(width 0.1651)
		(layer "In7.Cu")
		(net "P5E_PEX0_STN2_RX_DN<47>")
	)
	(segment
		(start 43.548554 -267.026644)
		(end 43.135296 -263.578594)
		(width 0.1651)
		(layer "In7.Cu")
		(net "P5E_PEX0_STN2_RX_DN<47>")
	)
	(segment
		(start 43.135296 -263.578594)
		(end 43.135296 -262.327898)
		(width 0.1651)
		(layer "In7.Cu")
		(net "P5E_PEX0_STN2_RX_DN<47>")
	)
	(segment
		(start 43.201082 -255.61163)
		(end 41.628314 -238.434118)
		(width 0.1651)
		(layer "In7.Cu")
		(net "P5E_PEX0_STN2_RX_DN<47>")
	)
	(segment
		(start 8.888222 -35.355276)
		(end 8.888222 -34.98596)
		(width 0.1651)
		(layer "In7.Cu")
		(net "P5E_PEX0_STN2_RX_DN<47>")
	)
	(segment
		(start 44.449746 -273.099784)
		(end 44.449746 -273.365214)
		(width 0.1143)
		(layer "In7.Cu")
		(net "P5E_PEX0_STN2_RX_DN<47>")
	)
	(segment
		(start 10.26541 -49.854612)
		(end 8.96366 -40.2209)
		(width 0.1651)
		(layer "In7.Cu")
		(net "P5E_PEX0_STN2_RX_DN<47>")
	)
	(segment
		(start 8.96366 -40.2209)
		(end 8.888222 -35.355276)
		(width 0.1651)
		(layer "In7.Cu")
		(net "P5E_PEX0_STN2_RX_DN<47>")
	)
	(segment
		(start 15.436342 -102.744524)
		(end 10.231882 -85.574378)
		(width 0.1651)
		(layer "In7.Cu")
		(net "P5E_PEX0_STN2_RX_DN<47>")
	)
	(segment
		(start 20.640802 -119.914416)
		(end 15.436596 -102.745032)
		(width 0.1651)
		(layer "In7.Cu")
		(net "P5E_PEX0_STN2_RX_DN<47>")
	)
	(segment
		(start 204.11948 -28.55468)
		(end 203.460604 -28.55468)
		(width 0.13462)
		(layer "F.Cu")
		(net "P5E_PEX1_STN2_RX_DN<32>")
	)
	(segment
		(start 204.284072 -28.390088)
		(end 204.11948 -28.55468)
		(width 0.13462)
		(layer "F.Cu")
		(net "P5E_PEX1_STN2_RX_DN<32>")
	)
	(segment
		(start 204.764894 -28.390088)
		(end 204.284072 -28.390088)
		(width 0.13462)
		(layer "F.Cu")
		(net "P5E_PEX1_STN2_RX_DN<32>")
	)
	(segment
		(start 203.460604 -28.55468)
		(end 203.164694 -28.25877)
		(width 0.13462)
		(layer "F.Cu")
		(net "P5E_PEX1_STN2_RX_DN<32>")
	)
	(segment
		(start 174.465742 -271.392904)
		(end 174.465742 -270.191992)
		(width 0.1651)
		(layer "In7.Cu")
		(net "P5E_PEX1_STN2_RX_DN<32>")
	)
	(segment
		(start 174.800006 -274.999958)
		(end 174.800006 -275.265388)
		(width 0.1143)
		(layer "In7.Cu")
		(net "P5E_PEX1_STN2_RX_DN<32>")
	)
	(segment
		(start 174.465742 -270.191992)
		(end 174.64278 -269.42669)
		(width 0.1651)
		(layer "In7.Cu")
		(net "P5E_PEX1_STN2_RX_DN<32>")
	)
	(segment
		(start 174.465742 -271.421352)
		(end 174.465742 -271.392904)
		(width 0.1143)
		(layer "In7.Cu")
		(net "P5E_PEX1_STN2_RX_DN<32>")
	)
	(segment
		(start 194.363086 -154.841448)
		(end 195.752212 -144.057878)
		(width 0.1651)
		(layer "In7.Cu")
		(net "P5E_PEX1_STN2_RX_DN<32>")
	)
	(segment
		(start 174.420022 -271.467072)
		(end 174.465742 -271.421352)
		(width 0.1143)
		(layer "In7.Cu")
		(net "P5E_PEX1_STN2_RX_DN<32>")
	)
	(segment
		(start 203.455524 -28.5496)
		(end 203.164694 -28.25877)
		(width 0.1651)
		(layer "In7.Cu")
		(net "P5E_PEX1_STN2_RX_DN<32>")
	)
	(segment
		(start 195.752212 -144.057878)
		(end 196.067172 -116.791232)
		(width 0.1651)
		(layer "In7.Cu")
		(net "P5E_PEX1_STN2_RX_DN<32>")
	)
	(segment
		(start 174.876206 -266.734544)
		(end 174.87646 -266.734544)
		(width 0.1651)
		(layer "In7.Cu")
		(net "P5E_PEX1_STN2_RX_DN<32>")
	)
	(segment
		(start 196.067172 -116.791232)
		(end 207.075024 -61.310012)
		(width 0.1651)
		(layer "In7.Cu")
		(net "P5E_PEX1_STN2_RX_DN<32>")
	)
	(segment
		(start 209.239866 -39.96563)
		(end 209.454496 -38.052248)
		(width 0.1651)
		(layer "In7.Cu")
		(net "P5E_PEX1_STN2_RX_DN<32>")
	)
	(segment
		(start 207.075024 -61.310012)
		(end 207.260698 -49.41951)
		(width 0.1651)
		(layer "In7.Cu")
		(net "P5E_PEX1_STN2_RX_DN<32>")
	)
	(segment
		(start 174.420022 -275.275802)
		(end 174.420022 -271.467072)
		(width 0.1143)
		(layer "In7.Cu")
		(net "P5E_PEX1_STN2_RX_DN<32>")
	)
	(segment
		(start 174.87646 -266.734544)
		(end 194.363086 -154.841448)
		(width 0.1651)
		(layer "In7.Cu")
		(net "P5E_PEX1_STN2_RX_DN<32>")
	)
	(segment
		(start 206.65186 -31.090362)
		(end 204.111098 -28.5496)
		(width 0.1651)
		(layer "In7.Cu")
		(net "P5E_PEX1_STN2_RX_DN<32>")
	)
	(segment
		(start 207.260698 -49.41951)
		(end 209.239866 -39.96563)
		(width 0.1651)
		(layer "In7.Cu")
		(net "P5E_PEX1_STN2_RX_DN<32>")
	)
	(segment
		(start 204.111098 -28.5496)
		(end 203.455524 -28.5496)
		(width 0.1651)
		(layer "In7.Cu")
		(net "P5E_PEX1_STN2_RX_DN<32>")
	)
	(segment
		(start 174.64278 -269.42669)
		(end 174.876206 -266.734544)
		(width 0.1651)
		(layer "In7.Cu")
		(net "P5E_PEX1_STN2_RX_DN<32>")
	)
	(segment
		(start 174.523908 -275.379688)
		(end 174.420022 -275.275802)
		(width 0.1143)
		(layer "In7.Cu")
		(net "P5E_PEX1_STN2_RX_DN<32>")
	)
	(segment
		(start 209.34426 -37.481256)
		(end 206.65186 -31.090362)
		(width 0.1651)
		(layer "In7.Cu")
		(net "P5E_PEX1_STN2_RX_DN<32>")
	)
	(segment
		(start 209.454496 -38.052248)
		(end 209.34426 -37.481256)
		(width 0.1651)
		(layer "In7.Cu")
		(net "P5E_PEX1_STN2_RX_DN<32>")
	)
	(segment
		(start 174.685706 -275.379688)
		(end 174.523908 -275.379688)
		(width 0.1143)
		(layer "In7.Cu")
		(net "P5E_PEX1_STN2_RX_DN<32>")
	)
	(segment
		(start 174.800006 -275.265388)
		(end 174.685706 -275.379688)
		(width 0.1143)
		(layer "In7.Cu")
		(net "P5E_PEX1_STN2_RX_DN<32>")
	)
	(segment
		(start 306.13731 -153.9748)
		(end 305.95697 -154.15514)
		(width 0.13462)
		(layer "F.Cu")
		(net "P5E_PEX2_STN0_TX_C_DN<14>")
	)
	(segment
		(start 305.95697 -154.15514)
		(end 305.457606 -154.15514)
		(width 0.13462)
		(layer "F.Cu")
		(net "P5E_PEX2_STN0_TX_C_DN<14>")
	)
	(segment
		(start 311.622694 -153.9748)
		(end 306.13731 -153.9748)
		(width 0.13462)
		(layer "F.Cu")
		(net "P5E_PEX2_STN0_TX_C_DN<14>")
	)
	(segment
		(start 311.95264 -154.304746)
		(end 311.622694 -153.9748)
		(width 0.13462)
		(layer "F.Cu")
		(net "P5E_PEX2_STN0_TX_C_DN<14>")
	)
	(segment
		(start 393.67587 -123.11888)
		(end 393.8397 -122.95505)
		(width 0.13462)
		(layer "F.Cu")
		(net "P5E_PEX3_STN1_TX_C_DP<26>")
	)
	(segment
		(start 393.8397 -122.95505)
		(end 394.342366 -122.95505)
		(width 0.13462)
		(layer "F.Cu")
		(net "P5E_PEX3_STN1_TX_C_DP<26>")
	)
	(segment
		(start 385.525264 -123.11888)
		(end 393.67587 -123.11888)
		(width 0.13462)
		(layer "F.Cu")
		(net "P5E_PEX3_STN1_TX_C_DP<26>")
	)
	(segment
		(start 385.205224 -122.79884)
		(end 385.525264 -123.11888)
		(width 0.13462)
		(layer "F.Cu")
		(net "P5E_PEX3_STN1_TX_C_DP<26>")
	)
	(segment
		(start 401.475194 -324.496684)
		(end 403.344634 -322.098416)
		(width 0.1651)
		(layer "In5.Cu")
		(net "P5E_PEX3_STN6_RX_DN<98>")
	)
	(segment
		(start 403.770084 -318.434466)
		(end 403.884384 -318.320166)
		(width 0.1143)
		(layer "In5.Cu")
		(net "P5E_PEX3_STN6_RX_DN<98>")
	)
	(segment
		(start 387.647942 -368.343942)
		(end 379.53315 -358.721152)
		(width 0.1651)
		(layer "In5.Cu")
		(net "P5E_PEX3_STN6_RX_DN<98>")
	)
	(segment
		(start 386.489956 -376.458226)
		(end 386.663184 -376.284998)
		(width 0.1651)
		(layer "In5.Cu")
		(net "P5E_PEX3_STN6_RX_DN<98>")
	)
	(segment
		(start 403.344634 -322.098416)
		(end 403.815804 -321.045332)
		(width 0.1651)
		(layer "In5.Cu")
		(net "P5E_PEX3_STN6_RX_DN<98>")
	)
	(segment
		(start 379.53315 -358.721152)
		(end 379.53315 -342.21039)
		(width 0.1651)
		(layer "In5.Cu")
		(net "P5E_PEX3_STN6_RX_DN<98>")
	)
	(segment
		(start 379.53315 -342.21039)
		(end 379.711204 -341.72525)
		(width 0.1651)
		(layer "In5.Cu")
		(net "P5E_PEX3_STN6_RX_DN<98>")
	)
	(segment
		(start 404.149814 -318.434466)
		(end 404.149814 -318.699896)
		(width 0.1143)
		(layer "In5.Cu")
		(net "P5E_PEX3_STN6_RX_DN<98>")
	)
	(segment
		(start 403.770084 -319.888362)
		(end 403.770084 -318.434466)
		(width 0.1143)
		(layer "In5.Cu")
		(net "P5E_PEX3_STN6_RX_DN<98>")
	)
	(segment
		(start 386.489956 -376.790204)
		(end 386.489956 -376.458226)
		(width 0.1651)
		(layer "In5.Cu")
		(net "P5E_PEX3_STN6_RX_DN<98>")
	)
	(segment
		(start 386.663184 -376.284998)
		(end 387.150356 -376.284998)
		(width 0.1651)
		(layer "In5.Cu")
		(net "P5E_PEX3_STN6_RX_DN<98>")
	)
	(segment
		(start 403.884384 -318.320166)
		(end 404.035514 -318.320166)
		(width 0.1143)
		(layer "In5.Cu")
		(net "P5E_PEX3_STN6_RX_DN<98>")
	)
	(segment
		(start 404.035514 -318.320166)
		(end 404.149814 -318.434466)
		(width 0.1143)
		(layer "In5.Cu")
		(net "P5E_PEX3_STN6_RX_DN<98>")
	)
	(segment
		(start 387.150356 -376.284998)
		(end 387.647942 -375.787412)
		(width 0.1651)
		(layer "In5.Cu")
		(net "P5E_PEX3_STN6_RX_DN<98>")
	)
	(segment
		(start 387.647942 -375.787412)
		(end 387.647942 -368.343942)
		(width 0.1651)
		(layer "In5.Cu")
		(net "P5E_PEX3_STN6_RX_DN<98>")
	)
	(segment
		(start 379.711204 -341.72525)
		(end 379.905514 -341.495888)
		(width 0.1651)
		(layer "In5.Cu")
		(net "P5E_PEX3_STN6_RX_DN<98>")
	)
	(segment
		(start 403.815804 -321.045332)
		(end 403.815804 -319.96253)
		(width 0.1651)
		(layer "In5.Cu")
		(net "P5E_PEX3_STN6_RX_DN<98>")
	)
	(segment
		(start 379.905514 -341.495888)
		(end 401.475194 -324.496684)
		(width 0.1651)
		(layer "In5.Cu")
		(net "P5E_PEX3_STN6_RX_DN<98>")
	)
	(segment
		(start 403.815804 -319.934082)
		(end 403.770084 -319.888362)
		(width 0.1143)
		(layer "In5.Cu")
		(net "P5E_PEX3_STN6_RX_DN<98>")
	)
	(segment
		(start 403.815804 -319.96253)
		(end 403.815804 -319.934082)
		(width 0.1143)
		(layer "In5.Cu")
		(net "P5E_PEX3_STN6_RX_DN<98>")
	)
	(segment
		(start 40.187626 -158.9913)
		(end 39.590726 -158.3944)
		(width 0.13208)
		(layer "F.Cu")
		(net "NIC0_LD_N")
	)
	(segment
		(start 42.521632 -158.9913)
		(end 40.187626 -158.9913)
		(width 0.13208)
		(layer "F.Cu")
		(net "NIC0_LD_N")
	)
	(segment
		(start 44.352972 -157.15996)
		(end 42.521632 -158.9913)
		(width 0.13208)
		(layer "F.Cu")
		(net "NIC0_LD_N")
	)
	(segment
		(start 39.590726 -158.3944)
		(end 39.00805 -158.3944)
		(width 0.13208)
		(layer "F.Cu")
		(net "NIC0_LD_N")
	)
	(segment
		(start 46.042326 -157.15996)
		(end 44.352972 -157.15996)
		(width 0.13208)
		(layer "F.Cu")
		(net "NIC0_LD_N")
	)
	(via
		(at 40.187626 -158.9913)
		(size 0.762)
		(drill 0.381)
		(layers "F.Cu" "B.Cu")
		(net "NIC0_LD_N")
	)
	(segment
		(start 189.357508 -100.640134)
		(end 191.638682 -100.640134)
		(width 0.13208)
		(layer "F.Cu")
		(net "NIC3_SLOT_ID0")
	)
	(segment
		(start 191.638682 -100.640134)
		(end 192.068196 -101.069648)
		(width 0.13208)
		(layer "F.Cu")
		(net "NIC3_SLOT_ID0")
	)
	(via
		(at 192.068196 -101.069648)
		(size 0.508)
		(drill 0.254)
		(layers "F.Cu" "B.Cu")
		(net "NIC3_SLOT_ID0")
	)
	(segment
		(start 193.241676 -100.056696)
		(end 193.241676 -101.069648)
		(width 0.13208)
		(layer "B.Cu")
		(net "NIC3_SLOT_ID0")
	)
	(segment
		(start 193.241676 -101.069648)
		(end 192.068196 -101.069648)
		(width 0.13208)
		(layer "B.Cu")
		(net "NIC3_SLOT_ID0")
	)
	(segment
		(start 10.18413 -31.99003)
		(end 10.02538 -32.14878)
		(width 0.13462)
		(layer "F.Cu")
		(net "P5E_PEX0_STN2_RX_DN<46>")
	)
	(segment
		(start 10.664952 -31.99003)
		(end 10.18413 -31.99003)
		(width 0.13462)
		(layer "F.Cu")
		(net "P5E_PEX0_STN2_RX_DN<46>")
	)
	(segment
		(start 9.35482 -32.14878)
		(end 9.064752 -31.858712)
		(width 0.13462)
		(layer "F.Cu")
		(net "P5E_PEX0_STN2_RX_DN<46>")
	)
	(segment
		(start 10.02538 -32.14878)
		(end 9.35482 -32.14878)
		(width 0.13462)
		(layer "F.Cu")
		(net "P5E_PEX0_STN2_RX_DN<46>")
	)
	(segment
		(start 44.09059 -263.518142)
		(end 45.065696 -270.38427)
		(width 0.1651)
		(layer "In7.Cu")
		(net "P5E_PEX0_STN2_RX_DN<46>")
	)
	(segment
		(start 45.019976 -271.467072)
		(end 45.019976 -275.275802)
		(width 0.1143)
		(layer "In7.Cu")
		(net "P5E_PEX0_STN2_RX_DN<46>")
	)
	(segment
		(start 45.28566 -275.379688)
		(end 45.39996 -275.265388)
		(width 0.1143)
		(layer "In7.Cu")
		(net "P5E_PEX0_STN2_RX_DN<46>")
	)
	(segment
		(start 10.44448 -32.663638)
		(end 10.407396 -35.04819)
		(width 0.1651)
		(layer "In7.Cu")
		(net "P5E_PEX0_STN2_RX_DN<46>")
	)
	(segment
		(start 9.883902 -37.856414)
		(end 9.920224 -40.147748)
		(width 0.1651)
		(layer "In7.Cu")
		(net "P5E_PEX0_STN2_RX_DN<46>")
	)
	(segment
		(start 45.065696 -271.392904)
		(end 45.065696 -271.421352)
		(width 0.1143)
		(layer "In7.Cu")
		(net "P5E_PEX0_STN2_RX_DN<46>")
	)
	(segment
		(start 45.123862 -275.379688)
		(end 45.28566 -275.379688)
		(width 0.1143)
		(layer "In7.Cu")
		(net "P5E_PEX0_STN2_RX_DN<46>")
	)
	(segment
		(start 9.355582 -32.149542)
		(end 9.93013 -32.149542)
		(width 0.1651)
		(layer "In7.Cu")
		(net "P5E_PEX0_STN2_RX_DN<46>")
	)
	(segment
		(start 9.064752 -31.858712)
		(end 9.355582 -32.149542)
		(width 0.1651)
		(layer "In7.Cu")
		(net "P5E_PEX0_STN2_RX_DN<46>")
	)
	(segment
		(start 16.393414 -102.6033)
		(end 16.393414 -102.603808)
		(width 0.1651)
		(layer "In7.Cu")
		(net "P5E_PEX0_STN2_RX_DN<46>")
	)
	(segment
		(start 16.393414 -102.603808)
		(end 21.59254 -119.756174)
		(width 0.1651)
		(layer "In7.Cu")
		(net "P5E_PEX0_STN2_RX_DN<46>")
	)
	(segment
		(start 16.381476 -102.56393)
		(end 16.393414 -102.6033)
		(width 0.1651)
		(layer "In7.Cu")
		(net "P5E_PEX0_STN2_RX_DN<46>")
	)
	(segment
		(start 24.86787 -144.657572)
		(end 42.576242 -238.303054)
		(width 0.1651)
		(layer "In7.Cu")
		(net "P5E_PEX0_STN2_RX_DN<46>")
	)
	(segment
		(start 9.93013 -32.149542)
		(end 10.44448 -32.663638)
		(width 0.1651)
		(layer "In7.Cu")
		(net "P5E_PEX0_STN2_RX_DN<46>")
	)
	(segment
		(start 11.386058 -60.294012)
		(end 11.386058 -61.797946)
		(width 0.1651)
		(layer "In7.Cu")
		(net "P5E_PEX0_STN2_RX_DN<46>")
	)
	(segment
		(start 45.065696 -271.421352)
		(end 45.019976 -271.467072)
		(width 0.1143)
		(layer "In7.Cu")
		(net "P5E_PEX0_STN2_RX_DN<46>")
	)
	(segment
		(start 9.920224 -40.147748)
		(end 11.221974 -49.782222)
		(width 0.1651)
		(layer "In7.Cu")
		(net "P5E_PEX0_STN2_RX_DN<46>")
	)
	(segment
		(start 45.019976 -275.275802)
		(end 45.123862 -275.379688)
		(width 0.1143)
		(layer "In7.Cu")
		(net "P5E_PEX0_STN2_RX_DN<46>")
	)
	(segment
		(start 44.167552 -255.686052)
		(end 44.09059 -263.518142)
		(width 0.1651)
		(layer "In7.Cu")
		(net "P5E_PEX0_STN2_RX_DN<46>")
	)
	(segment
		(start 21.59254 -119.756174)
		(end 24.86787 -144.657572)
		(width 0.1651)
		(layer "In7.Cu")
		(net "P5E_PEX0_STN2_RX_DN<46>")
	)
	(segment
		(start 11.221974 -49.782222)
		(end 11.105896 -57.201562)
		(width 0.1651)
		(layer "In7.Cu")
		(net "P5E_PEX0_STN2_RX_DN<46>")
	)
	(segment
		(start 10.407396 -35.04819)
		(end 9.883902 -37.856414)
		(width 0.1651)
		(layer "In7.Cu")
		(net "P5E_PEX0_STN2_RX_DN<46>")
	)
	(segment
		(start 11.105896 -57.201562)
		(end 11.386058 -60.294012)
		(width 0.1651)
		(layer "In7.Cu")
		(net "P5E_PEX0_STN2_RX_DN<46>")
	)
	(segment
		(start 42.576242 -238.303054)
		(end 44.167552 -255.686052)
		(width 0.1651)
		(layer "In7.Cu")
		(net "P5E_PEX0_STN2_RX_DN<46>")
	)
	(segment
		(start 11.386058 -61.797946)
		(end 11.194034 -85.450426)
		(width 0.1651)
		(layer "In7.Cu")
		(net "P5E_PEX0_STN2_RX_DN<46>")
	)
	(segment
		(start 11.194034 -85.450426)
		(end 16.381222 -102.563168)
		(width 0.1651)
		(layer "In7.Cu")
		(net "P5E_PEX0_STN2_RX_DN<46>")
	)
	(segment
		(start 45.065696 -270.38427)
		(end 45.065696 -271.392904)
		(width 0.1651)
		(layer "In7.Cu")
		(net "P5E_PEX0_STN2_RX_DN<46>")
	)
	(segment
		(start 45.39996 -275.265388)
		(end 45.39996 -274.999958)
		(width 0.1143)
		(layer "In7.Cu")
		(net "P5E_PEX0_STN2_RX_DN<46>")
	)
	(segment
		(start 16.381222 -102.563168)
		(end 16.381476 -102.56393)
		(width 0.1651)
		(layer "In7.Cu")
		(net "P5E_PEX0_STN2_RX_DN<46>")
	)
	(segment
		(start 213.947502 -33.95218)
		(end 210.03387 -33.95218)
		(width 0.13462)
		(layer "F.Cu")
		(net "P5E_PEX1_STN2_TX_C_DN<35>")
	)
	(segment
		(start 210.03387 -33.95218)
		(end 209.871818 -33.790128)
		(width 0.13462)
		(layer "F.Cu")
		(net "P5E_PEX1_STN2_TX_C_DN<35>")
	)
	(segment
		(start 214.267796 -33.631886)
		(end 213.947502 -33.95218)
		(width 0.13462)
		(layer "F.Cu")
		(net "P5E_PEX1_STN2_TX_C_DN<35>")
	)
	(segment
		(start 209.871818 -33.790128)
		(end 209.364834 -33.790128)
		(width 0.13462)
		(layer "F.Cu")
		(net "P5E_PEX1_STN2_TX_C_DN<35>")
	)
	(segment
		(start 306.124356 -144.99082)
		(end 305.960272 -145.154904)
		(width 0.13462)
		(layer "F.Cu")
		(net "P5E_PEX2_STN0_TX_C_DP<9>")
	)
	(segment
		(start 314.594748 -145.311114)
		(end 314.274454 -144.99082)
		(width 0.13462)
		(layer "F.Cu")
		(net "P5E_PEX2_STN0_TX_C_DP<9>")
	)
	(segment
		(start 314.274454 -144.99082)
		(end 306.124356 -144.99082)
		(width 0.13462)
		(layer "F.Cu")
		(net "P5E_PEX2_STN0_TX_C_DP<9>")
	)
	(segment
		(start 305.960272 -145.154904)
		(end 305.457606 -145.154904)
		(width 0.13462)
		(layer "F.Cu")
		(net "P5E_PEX2_STN0_TX_C_DP<9>")
	)
	(segment
		(start 402.095208 -103.47452)
		(end 399.590514 -103.47452)
		(width 0.13462)
		(layer "F.Cu")
		(net "P5E_PEX3_STN1_RX_DN<18>")
	)
	(segment
		(start 399.42008 -103.644954)
		(end 398.94256 -103.644954)
		(width 0.13462)
		(layer "F.Cu")
		(net "P5E_PEX3_STN1_RX_DN<18>")
	)
	(segment
		(start 399.590514 -103.47452)
		(end 399.42008 -103.644954)
		(width 0.13462)
		(layer "F.Cu")
		(net "P5E_PEX3_STN1_RX_DN<18>")
	)
	(segment
		(start 402.39696 -103.776272)
		(end 402.095208 -103.47452)
		(width 0.13462)
		(layer "F.Cu")
		(net "P5E_PEX3_STN1_RX_DN<18>")
	)
	(segment
		(start 392.738356 -107.779058)
		(end 392.395964 -108.137452)
		(width 0.1651)
		(layer "In5.Cu")
		(net "P5E_PEX3_STN1_RX_DN<18>")
	)
	(segment
		(start 397.500602 -104.921812)
		(end 397.060166 -105.147872)
		(width 0.1651)
		(layer "In5.Cu")
		(net "P5E_PEX3_STN1_RX_DN<18>")
	)
	(segment
		(start 409.470098 -273.376136)
		(end 409.573476 -273.479514)
		(width 0.1143)
		(layer "In5.Cu")
		(net "P5E_PEX3_STN1_RX_DN<18>")
	)
	(segment
		(start 396.415768 -105.47858)
		(end 395.975332 -105.70464)
		(width 0.1651)
		(layer "In5.Cu")
		(net "P5E_PEX3_STN1_RX_DN<18>")
	)
	(segment
		(start 378.684536 -150.341584)
		(end 379.242066 -158.75762)
		(width 0.1651)
		(layer "In5.Cu")
		(net "P5E_PEX3_STN1_RX_DN<18>")
	)
	(segment
		(start 399.180304 -104.188006)
		(end 398.73936 -104.414574)
		(width 0.1651)
		(layer "In5.Cu")
		(net "P5E_PEX3_STN1_RX_DN<18>")
	)
	(segment
		(start 392.23442 -108.141262)
		(end 391.892536 -108.499402)
		(width 0.1651)
		(layer "In5.Cu")
		(net "P5E_PEX3_STN1_RX_DN<18>")
	)
	(segment
		(start 395.925802 -105.85831)
		(end 395.484858 -106.084878)
		(width 0.1651)
		(layer "In5.Cu")
		(net "P5E_PEX3_STN1_RX_DN<18>")
	)
	(segment
		(start 380.28626 -126.637796)
		(end 378.684536 -150.341584)
		(width 0.1651)
		(layer "In5.Cu")
		(net "P5E_PEX3_STN1_RX_DN<18>")
	)
	(segment
		(start 395.975332 -105.70464)
		(end 395.925802 -105.85831)
		(width 0.1651)
		(layer "In5.Cu")
		(net "P5E_PEX3_STN1_RX_DN<18>")
	)
	(segment
		(start 391.39241 -109.02315)
		(end 391.050526 -109.38129)
		(width 0.1651)
		(layer "In5.Cu")
		(net "P5E_PEX3_STN1_RX_DN<18>")
	)
	(segment
		(start 400.299174 -103.485442)
		(end 399.22958 -104.034336)
		(width 0.1651)
		(layer "In5.Cu")
		(net "P5E_PEX3_STN1_RX_DN<18>")
	)
	(segment
		(start 409.573476 -273.479514)
		(end 409.735274 -273.479514)
		(width 0.1143)
		(layer "In5.Cu")
		(net "P5E_PEX3_STN1_RX_DN<18>")
	)
	(segment
		(start 396.569692 -105.52811)
		(end 396.415768 -105.47858)
		(width 0.1651)
		(layer "In5.Cu")
		(net "P5E_PEX3_STN1_RX_DN<18>")
	)
	(segment
		(start 391.896346 -108.660946)
		(end 391.553954 -109.01934)
		(width 0.1651)
		(layer "In5.Cu")
		(net "P5E_PEX3_STN1_RX_DN<18>")
	)
	(segment
		(start 397.010636 -105.301796)
		(end 396.569692 -105.52811)
		(width 0.1651)
		(layer "In5.Cu")
		(net "P5E_PEX3_STN1_RX_DN<18>")
	)
	(segment
		(start 399.22958 -104.034082)
		(end 399.180304 -104.188006)
		(width 0.1651)
		(layer "In5.Cu")
		(net "P5E_PEX3_STN1_RX_DN<18>")
	)
	(segment
		(start 391.054336 -109.542834)
		(end 390.711944 -109.901228)
		(width 0.1651)
		(layer "In5.Cu")
		(net "P5E_PEX3_STN1_RX_DN<18>")
	)
	(segment
		(start 379.242066 -158.75762)
		(end 380.36373 -165.241986)
		(width 0.1651)
		(layer "In5.Cu")
		(net "P5E_PEX3_STN1_RX_DN<18>")
	)
	(segment
		(start 382.37287 -118.469918)
		(end 381.414274 -120.46712)
		(width 0.1651)
		(layer "In5.Cu")
		(net "P5E_PEX3_STN1_RX_DN<18>")
	)
	(segment
		(start 392.395964 -108.137452)
		(end 392.23442 -108.141262)
		(width 0.1651)
		(layer "In5.Cu")
		(net "P5E_PEX3_STN1_RX_DN<18>")
	)
	(segment
		(start 393.202414 -107.127294)
		(end 392.734546 -107.61726)
		(width 0.1651)
		(layer "In5.Cu")
		(net "P5E_PEX3_STN1_RX_DN<18>")
	)
	(segment
		(start 398.09547 -104.745028)
		(end 397.654526 -104.971342)
		(width 0.1651)
		(layer "In5.Cu")
		(net "P5E_PEX3_STN1_RX_DN<18>")
	)
	(segment
		(start 399.22958 -104.034336)
		(end 399.22958 -104.034082)
		(width 0.1651)
		(layer "In5.Cu")
		(net "P5E_PEX3_STN1_RX_DN<18>")
	)
	(segment
		(start 390.5504 -109.905038)
		(end 382.37287 -118.469918)
		(width 0.1651)
		(layer "In5.Cu")
		(net "P5E_PEX3_STN1_RX_DN<18>")
	)
	(segment
		(start 380.36373 -165.241986)
		(end 409.515818 -269.734284)
		(width 0.1651)
		(layer "In5.Cu")
		(net "P5E_PEX3_STN1_RX_DN<18>")
	)
	(segment
		(start 398.145 -104.591104)
		(end 398.09547 -104.745028)
		(width 0.1651)
		(layer "In5.Cu")
		(net "P5E_PEX3_STN1_RX_DN<18>")
	)
	(segment
		(start 409.470098 -271.600168)
		(end 409.470098 -273.376136)
		(width 0.1143)
		(layer "In5.Cu")
		(net "P5E_PEX3_STN1_RX_DN<18>")
	)
	(segment
		(start 394.2461 -106.591862)
		(end 393.202414 -107.127294)
		(width 0.1651)
		(layer "In5.Cu")
		(net "P5E_PEX3_STN1_RX_DN<18>")
	)
	(segment
		(start 395.330934 -106.035348)
		(end 394.890244 -106.261408)
		(width 0.1651)
		(layer "In5.Cu")
		(net "P5E_PEX3_STN1_RX_DN<18>")
	)
	(segment
		(start 390.711944 -109.901228)
		(end 390.5504 -109.905038)
		(width 0.1651)
		(layer "In5.Cu")
		(net "P5E_PEX3_STN1_RX_DN<18>")
	)
	(segment
		(start 402.39696 -103.776272)
		(end 402.10613 -103.485442)
		(width 0.1651)
		(layer "In5.Cu")
		(net "P5E_PEX3_STN1_RX_DN<18>")
	)
	(segment
		(start 409.735274 -273.479514)
		(end 409.849574 -273.365214)
		(width 0.1143)
		(layer "In5.Cu")
		(net "P5E_PEX3_STN1_RX_DN<18>")
	)
	(segment
		(start 394.890244 -106.261408)
		(end 394.840968 -106.415078)
		(width 0.1651)
		(layer "In5.Cu")
		(net "P5E_PEX3_STN1_RX_DN<18>")
	)
	(segment
		(start 409.515818 -271.526)
		(end 409.515818 -271.554448)
		(width 0.1143)
		(layer "In5.Cu")
		(net "P5E_PEX3_STN1_RX_DN<18>")
	)
	(segment
		(start 391.050526 -109.38129)
		(end 391.054336 -109.542834)
		(width 0.1651)
		(layer "In5.Cu")
		(net "P5E_PEX3_STN1_RX_DN<18>")
	)
	(segment
		(start 394.840968 -106.415078)
		(end 394.39977 -106.641392)
		(width 0.1651)
		(layer "In5.Cu")
		(net "P5E_PEX3_STN1_RX_DN<18>")
	)
	(segment
		(start 409.515818 -269.734284)
		(end 409.515818 -271.526)
		(width 0.1651)
		(layer "In5.Cu")
		(net "P5E_PEX3_STN1_RX_DN<18>")
	)
	(segment
		(start 395.484858 -106.084878)
		(end 395.330934 -106.035348)
		(width 0.1651)
		(layer "In5.Cu")
		(net "P5E_PEX3_STN1_RX_DN<18>")
	)
	(segment
		(start 381.414274 -120.46712)
		(end 380.28626 -126.637796)
		(width 0.1651)
		(layer "In5.Cu")
		(net "P5E_PEX3_STN1_RX_DN<18>")
	)
	(segment
		(start 409.849574 -273.365214)
		(end 409.849574 -273.099784)
		(width 0.1143)
		(layer "In5.Cu")
		(net "P5E_PEX3_STN1_RX_DN<18>")
	)
	(segment
		(start 397.060166 -105.147872)
		(end 397.010636 -105.301796)
		(width 0.1651)
		(layer "In5.Cu")
		(net "P5E_PEX3_STN1_RX_DN<18>")
	)
	(segment
		(start 392.734546 -107.61726)
		(end 392.738356 -107.779058)
		(width 0.1651)
		(layer "In5.Cu")
		(net "P5E_PEX3_STN1_RX_DN<18>")
	)
	(segment
		(start 398.585436 -104.365044)
		(end 398.145 -104.591104)
		(width 0.1651)
		(layer "In5.Cu")
		(net "P5E_PEX3_STN1_RX_DN<18>")
	)
	(segment
		(start 409.515818 -271.554448)
		(end 409.470098 -271.600168)
		(width 0.1143)
		(layer "In5.Cu")
		(net "P5E_PEX3_STN1_RX_DN<18>")
	)
	(segment
		(start 402.10613 -103.485442)
		(end 400.299174 -103.485442)
		(width 0.1651)
		(layer "In5.Cu")
		(net "P5E_PEX3_STN1_RX_DN<18>")
	)
	(segment
		(start 397.654526 -104.971342)
		(end 397.500602 -104.921812)
		(width 0.1651)
		(layer "In5.Cu")
		(net "P5E_PEX3_STN1_RX_DN<18>")
	)
	(segment
		(start 394.39977 -106.641392)
		(end 394.2461 -106.591862)
		(width 0.1651)
		(layer "In5.Cu")
		(net "P5E_PEX3_STN1_RX_DN<18>")
	)
	(segment
		(start 391.892536 -108.499402)
		(end 391.896346 -108.660946)
		(width 0.1651)
		(layer "In5.Cu")
		(net "P5E_PEX3_STN1_RX_DN<18>")
	)
	(segment
		(start 391.553954 -109.01934)
		(end 391.39241 -109.02315)
		(width 0.1651)
		(layer "In5.Cu")
		(net "P5E_PEX3_STN1_RX_DN<18>")
	)
	(segment
		(start 398.73936 -104.414574)
		(end 398.585436 -104.365044)
		(width 0.1651)
		(layer "In5.Cu")
		(net "P5E_PEX3_STN1_RX_DN<18>")
	)
	(segment
		(start 400.076924 -318.327786)
		(end 399.970244 -318.434466)
		(width 0.1143)
		(layer "In5.Cu")
		(net "P5E_PEX3_STN6_RX_DN<102>")
	)
	(segment
		(start 399.970244 -318.434466)
		(end 399.970244 -319.921128)
		(width 0.1143)
		(layer "In5.Cu")
		(net "P5E_PEX3_STN6_RX_DN<102>")
	)
	(segment
		(start 369.183666 -352.072702)
		(end 372.029736 -360.394504)
		(width 0.1651)
		(layer "In5.Cu")
		(net "P5E_PEX3_STN6_RX_DN<102>")
	)
	(segment
		(start 399.970244 -319.921128)
		(end 400.015964 -319.966848)
		(width 0.1143)
		(layer "In5.Cu")
		(net "P5E_PEX3_STN6_RX_DN<102>")
	)
	(segment
		(start 399.272506 -321.1703)
		(end 370.266976 -340.350348)
		(width 0.1651)
		(layer "In5.Cu")
		(net "P5E_PEX3_STN6_RX_DN<102>")
	)
	(segment
		(start 370.266976 -340.350348)
		(end 369.489482 -341.330026)
		(width 0.1651)
		(layer "In5.Cu")
		(net "P5E_PEX3_STN6_RX_DN<102>")
	)
	(segment
		(start 400.015964 -319.995296)
		(end 400.015964 -320.426842)
		(width 0.1651)
		(layer "In5.Cu")
		(net "P5E_PEX3_STN6_RX_DN<102>")
	)
	(segment
		(start 378.847858 -368.69116)
		(end 378.847858 -375.787412)
		(width 0.1651)
		(layer "In5.Cu")
		(net "P5E_PEX3_STN6_RX_DN<102>")
	)
	(segment
		(start 400.349974 -318.699896)
		(end 400.349974 -318.44996)
		(width 0.1143)
		(layer "In5.Cu")
		(net "P5E_PEX3_STN6_RX_DN<102>")
	)
	(segment
		(start 400.349974 -318.44996)
		(end 400.2278 -318.327786)
		(width 0.1143)
		(layer "In5.Cu")
		(net "P5E_PEX3_STN6_RX_DN<102>")
	)
	(segment
		(start 400.2278 -318.327786)
		(end 400.076924 -318.327786)
		(width 0.1143)
		(layer "In5.Cu")
		(net "P5E_PEX3_STN6_RX_DN<102>")
	)
	(segment
		(start 378.350272 -376.284998)
		(end 377.8631 -376.284998)
		(width 0.1651)
		(layer "In5.Cu")
		(net "P5E_PEX3_STN6_RX_DN<102>")
	)
	(segment
		(start 400.015964 -319.966848)
		(end 400.015964 -319.995296)
		(width 0.1143)
		(layer "In5.Cu")
		(net "P5E_PEX3_STN6_RX_DN<102>")
	)
	(segment
		(start 378.847858 -375.787412)
		(end 378.350272 -376.284998)
		(width 0.1651)
		(layer "In5.Cu")
		(net "P5E_PEX3_STN6_RX_DN<102>")
	)
	(segment
		(start 369.08105 -342.46439)
		(end 369.183666 -352.072702)
		(width 0.1651)
		(layer "In5.Cu")
		(net "P5E_PEX3_STN6_RX_DN<102>")
	)
	(segment
		(start 369.489482 -341.330026)
		(end 369.08105 -342.46439)
		(width 0.1651)
		(layer "In5.Cu")
		(net "P5E_PEX3_STN6_RX_DN<102>")
	)
	(segment
		(start 372.029736 -360.394504)
		(end 378.847858 -368.69116)
		(width 0.1651)
		(layer "In5.Cu")
		(net "P5E_PEX3_STN6_RX_DN<102>")
	)
	(segment
		(start 400.015964 -320.426842)
		(end 399.272506 -321.1703)
		(width 0.1651)
		(layer "In5.Cu")
		(net "P5E_PEX3_STN6_RX_DN<102>")
	)
	(segment
		(start 377.689872 -376.458226)
		(end 377.689872 -376.790204)
		(width 0.1651)
		(layer "In5.Cu")
		(net "P5E_PEX3_STN6_RX_DN<102>")
	)
	(segment
		(start 377.8631 -376.284998)
		(end 377.689872 -376.458226)
		(width 0.1651)
		(layer "In5.Cu")
		(net "P5E_PEX3_STN6_RX_DN<102>")
	)
	(segment
		(start 40.39108 -150.212552)
		(end 42.58691 -150.212552)
		(width 0.13208)
		(layer "F.Cu")
		(net "NCSI_NIC0_CRS_DV")
	)
	(segment
		(start 42.934382 -150.560024)
		(end 46.042326 -150.560024)
		(width 0.13208)
		(layer "F.Cu")
		(net "NCSI_NIC0_CRS_DV")
	)
	(segment
		(start 42.58691 -150.212552)
		(end 42.934382 -150.560024)
		(width 0.13208)
		(layer "F.Cu")
		(net "NCSI_NIC0_CRS_DV")
	)
	(segment
		(start 40.34028 -150.263352)
		(end 40.39108 -150.212552)
		(width 0.13208)
		(layer "F.Cu")
		(net "NCSI_NIC0_CRS_DV")
	)
	(segment
		(start 38.999922 -150.263352)
		(end 40.34028 -150.263352)
		(width 0.13208)
		(layer "F.Cu")
		(net "NCSI_NIC0_CRS_DV")
	)
	(via
		(at 40.39108 -150.212552)
		(size 0.762)
		(drill 0.381)
		(layers "F.Cu" "B.Cu")
		(net "NCSI_NIC0_CRS_DV")
	)
	(segment
		(start 248.433336 -24.790146)
		(end 248.675144 -25.031954)
		(width 0.381)
		(layer "F.Cu")
		(net "P3V3_SSD8")
	)
	(segment
		(start 238.168688 -30.971236)
		(end 237.59414 -30.396688)
		(width 0.381)
		(layer "F.Cu")
		(net "P3V3_SSD8")
	)
	(segment
		(start 248.675144 -25.031954)
		(end 250.1265 -25.031954)
		(width 0.381)
		(layer "F.Cu")
		(net "P3V3_SSD8")
	)
	(segment
		(start 247.464834 -24.790146)
		(end 248.433336 -24.790146)
		(width 0.381)
		(layer "F.Cu")
		(net "P3V3_SSD8")
	)
	(segment
		(start 257.824986 -14.735302)
		(end 257.76047 -14.799818)
		(width 0.381)
		(layer "F.Cu")
		(net "P3V3_SSD8")
	)
	(segment
		(start 225.046794 -37.47516)
		(end 224.341182 -37.47516)
		(width 0.4572)
		(layer "F.Cu")
		(net "P3V3_SSD8")
	)
	(segment
		(start 237.894114 -32.787336)
		(end 238.168688 -32.512762)
		(width 0.381)
		(layer "F.Cu")
		(net "P3V3_SSD8")
	)
	(segment
		(start 256.869438 -20.467574)
		(end 256.256536 -20.467574)
		(width 0.508)
		(layer "F.Cu")
		(net "P3V3_SSD8")
	)
	(segment
		(start 257.824986 -14.100302)
		(end 257.824986 -14.735302)
		(width 0.381)
		(layer "F.Cu")
		(net "P3V3_SSD8")
	)
	(segment
		(start 240.54816 -56.21147)
		(end 240.54816 -56.86679)
		(width 0.381)
		(layer "F.Cu")
		(net "P3V3_SSD8")
	)
	(segment
		(start 253.954026 -27.492198)
		(end 253.433072 -26.971244)
		(width 0.381)
		(layer "F.Cu")
		(net "P3V3_SSD8")
	)
	(segment
		(start 250.1265 -25.031954)
		(end 250.769882 -25.031954)
		(width 0.4572)
		(layer "F.Cu")
		(net "P3V3_SSD8")
	)
	(segment
		(start 251.671582 -25.742392)
		(end 251.671582 -26.360882)
		(width 0.4572)
		(layer "F.Cu")
		(net "P3V3_SSD8")
	)
	(segment
		(start 257.76047 -14.799818)
		(end 257.76047 -16.439388)
		(width 0.381)
		(layer "F.Cu")
		(net "P3V3_SSD8")
	)
	(segment
		(start 237.894114 -34.248852)
		(end 237.894114 -32.787336)
		(width 0.381)
		(layer "F.Cu")
		(net "P3V3_SSD8")
	)
	(segment
		(start 254.085598 -27.492198)
		(end 253.954026 -27.492198)
		(width 0.381)
		(layer "F.Cu")
		(net "P3V3_SSD8")
	)
	(segment
		(start 256.256536 -17.419574)
		(end 256.866136 -17.419574)
		(width 0.508)
		(layer "F.Cu")
		(net "P3V3_SSD8")
	)
	(segment
		(start 239.571784 -24.807418)
		(end 238.953294 -24.807418)
		(width 0.4572)
		(layer "F.Cu")
		(net "P3V3_SSD8")
	)
	(segment
		(start 238.168688 -32.512762)
		(end 238.168688 -30.971236)
		(width 0.381)
		(layer "F.Cu")
		(net "P3V3_SSD8")
	)
	(via
		(at 239.33404 -48.762158)
		(size 0.508)
		(drill 0.254)
		(layers "F.Cu" "B.Cu")
		(net "P3V3_SSD8")
	)
	(via
		(at 224.341182 -37.47516)
		(size 0.508)
		(drill 0.254)
		(layers "F.Cu" "B.Cu")
		(net "P3V3_SSD8")
	)
	(via
		(at 240.645696 -46.842426)
		(size 0.508)
		(drill 0.254)
		(layers "F.Cu" "B.Cu")
		(net "P3V3_SSD8")
	)
	(via
		(at 238.863124 -45.808138)
		(size 0.508)
		(drill 0.254)
		(layers "F.Cu" "B.Cu")
		(net "P3V3_SSD8")
	)
	(via
		(at 240.133124 -45.808138)
		(size 0.508)
		(drill 0.254)
		(layers "F.Cu" "B.Cu")
		(net "P3V3_SSD8")
	)
	(via
		(at 239.883696 -46.842426)
		(size 0.508)
		(drill 0.254)
		(layers "F.Cu" "B.Cu")
		(net "P3V3_SSD8")
	)
	(via
		(at 236.510576 -30.376876)
		(size 0.508)
		(drill 0.254)
		(layers "F.Cu" "B.Cu")
		(net "P3V3_SSD8")
	)
	(via
		(at 257.824986 -14.100302)
		(size 0.508)
		(drill 0.254)
		(layers "F.Cu" "B.Cu")
		(net "P3V3_SSD8")
	)
	(via
		(at 239.883696 -47.477426)
		(size 0.508)
		(drill 0.254)
		(layers "F.Cu" "B.Cu")
		(net "P3V3_SSD8")
	)
	(via
		(at 250.769882 -25.031954)
		(size 0.508)
		(drill 0.254)
		(layers "F.Cu" "B.Cu")
		(net "P3V3_SSD8")
	)
	(via
		(at 240.768124 -45.808138)
		(size 0.508)
		(drill 0.254)
		(layers "F.Cu" "B.Cu")
		(net "P3V3_SSD8")
	)
	(via
		(at 256.869438 -20.467574)
		(size 0.508)
		(drill 0.254)
		(layers "F.Cu" "B.Cu")
		(net "P3V3_SSD8")
	)
	(via
		(at 256.866136 -17.419574)
		(size 0.508)
		(drill 0.254)
		(layers "F.Cu" "B.Cu")
		(net "P3V3_SSD8")
	)
	(via
		(at 239.498124 -45.808138)
		(size 0.508)
		(drill 0.254)
		(layers "F.Cu" "B.Cu")
		(net "P3V3_SSD8")
	)
	(via
		(at 239.96904 -48.762158)
		(size 0.508)
		(drill 0.254)
		(layers "F.Cu" "B.Cu")
		(net "P3V3_SSD8")
	)
	(via
		(at 239.518698 -49.70272)
		(size 0.508)
		(drill 0.254)
		(layers "F.Cu" "B.Cu")
		(net "P3V3_SSD8")
	)
	(via
		(at 238.863124 -46.711616)
		(size 0.6604)
		(drill 0.3302)
		(layers "F.Cu" "B.Cu")
		(net "P3V3_SSD8")
	)
	(via
		(at 251.671582 -26.360882)
		(size 0.508)
		(drill 0.254)
		(layers "F.Cu" "B.Cu")
		(net "P3V3_SSD8")
	)
	(via
		(at 240.645696 -47.553626)
		(size 0.508)
		(drill 0.254)
		(layers "F.Cu" "B.Cu")
		(net "P3V3_SSD8")
	)
	(via
		(at 238.953294 -24.807418)
		(size 0.508)
		(drill 0.254)
		(layers "F.Cu" "B.Cu")
		(net "P3V3_SSD8")
	)
	(via
		(at 253.433072 -26.971244)
		(size 0.508)
		(drill 0.254)
		(layers "F.Cu" "B.Cu")
		(net "P3V3_SSD8")
	)
	(via
		(at 240.54816 -56.86679)
		(size 0.508)
		(drill 0.254)
		(layers "F.Cu" "B.Cu")
		(net "P3V3_SSD8")
	)
	(via
		(at 238.883698 -49.70272)
		(size 0.508)
		(drill 0.254)
		(layers "F.Cu" "B.Cu")
		(net "P3V3_SSD8")
	)
	(via
		(at 236.510576 -29.614876)
		(size 0.508)
		(drill 0.254)
		(layers "F.Cu" "B.Cu")
		(net "P3V3_SSD8")
	)
	(segment
		(start 226.80422 -38.322758)
		(end 225.18878 -38.322758)
		(width 0.508)
		(layer "In9.Cu")
		(net "P3V3_SSD8")
	)
	(segment
		(start 227.254054 -37.872924)
		(end 226.80422 -38.322758)
		(width 0.508)
		(layer "In9.Cu")
		(net "P3V3_SSD8")
	)
	(segment
		(start 225.18878 -38.322758)
		(end 224.341182 -37.47516)
		(width 0.508)
		(layer "In9.Cu")
		(net "P3V3_SSD8")
	)
	(segment
		(start 233.963718 -37.872924)
		(end 227.254054 -37.872924)
		(width 0.508)
		(layer "In9.Cu")
		(net "P3V3_SSD8")
	)
	(segment
		(start 159.625792 -32.739584)
		(end 159.296608 -32.4104)
		(width 0.13462)
		(layer "F.Cu")
		(net "P5E_PEX1_STN2_TX_C_DP<42>")
	)
	(segment
		(start 158.044134 -32.4104)
		(end 157.864556 -32.589978)
		(width 0.13462)
		(layer "F.Cu")
		(net "P5E_PEX1_STN2_TX_C_DP<42>")
	)
	(segment
		(start 159.296608 -32.4104)
		(end 158.044134 -32.4104)
		(width 0.13462)
		(layer "F.Cu")
		(net "P5E_PEX1_STN2_TX_C_DP<42>")
	)
	(segment
		(start 157.864556 -32.589978)
		(end 157.364938 -32.589978)
		(width 0.13462)
		(layer "F.Cu")
		(net "P5E_PEX1_STN2_TX_C_DP<42>")
	)
	(segment
		(start 305.960272 -136.04494)
		(end 305.457606 -136.04494)
		(width 0.13462)
		(layer "F.Cu")
		(net "P5E_PEX2_STN0_TX_C_DP<7>")
	)
	(segment
		(start 314.270898 -135.8773)
		(end 306.127912 -135.8773)
		(width 0.13462)
		(layer "F.Cu")
		(net "P5E_PEX2_STN0_TX_C_DP<7>")
	)
	(segment
		(start 306.127912 -135.8773)
		(end 305.960272 -136.04494)
		(width 0.13462)
		(layer "F.Cu")
		(net "P5E_PEX2_STN0_TX_C_DP<7>")
	)
	(segment
		(start 314.594748 -136.20115)
		(end 314.270898 -135.8773)
		(width 0.13462)
		(layer "F.Cu")
		(net "P5E_PEX2_STN0_TX_C_DP<7>")
	)
	(segment
		(start 399.423636 -112.644936)
		(end 398.94256 -112.644936)
		(width 0.13462)
		(layer "F.Cu")
		(net "P5E_PEX3_STN1_RX_DN<23>")
	)
	(segment
		(start 399.597372 -112.4712)
		(end 399.423636 -112.644936)
		(width 0.13462)
		(layer "F.Cu")
		(net "P5E_PEX3_STN1_RX_DN<23>")
	)
	(segment
		(start 400.237452 -112.4712)
		(end 399.597372 -112.4712)
		(width 0.13462)
		(layer "F.Cu")
		(net "P5E_PEX3_STN1_RX_DN<23>")
	)
	(segment
		(start 400.54276 -112.776508)
		(end 400.237452 -112.4712)
		(width 0.13462)
		(layer "F.Cu")
		(net "P5E_PEX3_STN1_RX_DN<23>")
	)
	(segment
		(start 391.871708 -120.592088)
		(end 391.662412 -121.04243)
		(width 0.1651)
		(layer "In5.Cu")
		(net "P5E_PEX3_STN1_RX_DN<23>")
	)
	(segment
		(start 391.662412 -121.04243)
		(end 391.53084 -121.635012)
		(width 0.1651)
		(layer "In5.Cu")
		(net "P5E_PEX3_STN1_RX_DN<23>")
	)
	(segment
		(start 414.265872 -271.599406)
		(end 414.220152 -271.645126)
		(width 0.1143)
		(layer "In5.Cu")
		(net "P5E_PEX3_STN1_RX_DN<23>")
	)
	(segment
		(start 385.10591 -164.031168)
		(end 414.265872 -268.570202)
		(width 0.1651)
		(layer "In5.Cu")
		(net "P5E_PEX3_STN1_RX_DN<23>")
	)
	(segment
		(start 390.580372 -125.912626)
		(end 390.022842 -128.4224)
		(width 0.1651)
		(layer "In5.Cu")
		(net "P5E_PEX3_STN1_RX_DN<23>")
	)
	(segment
		(start 391.35304 -122.961654)
		(end 391.245598 -123.445524)
		(width 0.1651)
		(layer "In5.Cu")
		(net "P5E_PEX3_STN1_RX_DN<23>")
	)
	(segment
		(start 397.972534 -113.284)
		(end 397.51381 -113.471452)
		(width 0.1651)
		(layer "In5.Cu")
		(net "P5E_PEX3_STN1_RX_DN<23>")
	)
	(segment
		(start 391.53084 -121.635012)
		(end 391.617708 -121.77141)
		(width 0.1651)
		(layer "In5.Cu")
		(net "P5E_PEX3_STN1_RX_DN<23>")
	)
	(segment
		(start 392.746992 -118.981728)
		(end 392.53795 -119.431054)
		(width 0.1651)
		(layer "In5.Cu")
		(net "P5E_PEX3_STN1_RX_DN<23>")
	)
	(segment
		(start 390.824212 -125.342142)
		(end 390.71677 -125.826012)
		(width 0.1651)
		(layer "In5.Cu")
		(net "P5E_PEX3_STN1_RX_DN<23>")
	)
	(segment
		(start 384.777234 -145.148046)
		(end 383.662682 -151.225504)
		(width 0.1651)
		(layer "In5.Cu")
		(net "P5E_PEX3_STN1_RX_DN<23>")
	)
	(segment
		(start 399.62201 -112.485678)
		(end 399.163794 -112.67313)
		(width 0.1651)
		(layer "In5.Cu")
		(net "P5E_PEX3_STN1_RX_DN<23>")
	)
	(segment
		(start 386.545836 -141.115288)
		(end 384.777234 -145.148046)
		(width 0.1651)
		(layer "In5.Cu")
		(net "P5E_PEX3_STN1_RX_DN<23>")
	)
	(segment
		(start 392.0236 -120.536716)
		(end 391.871708 -120.592088)
		(width 0.1651)
		(layer "In5.Cu")
		(net "P5E_PEX3_STN1_RX_DN<23>")
	)
	(segment
		(start 393.494768 -117.103398)
		(end 392.69162 -118.829836)
		(width 0.1651)
		(layer "In5.Cu")
		(net "P5E_PEX3_STN1_RX_DN<23>")
	)
	(segment
		(start 414.220152 -275.27631)
		(end 414.32353 -275.379688)
		(width 0.1143)
		(layer "In5.Cu")
		(net "P5E_PEX3_STN1_RX_DN<23>")
	)
	(segment
		(start 395.47419 -114.182144)
		(end 394.751052 -114.872008)
		(width 0.1651)
		(layer "In5.Cu")
		(net "P5E_PEX3_STN1_RX_DN<23>")
	)
	(segment
		(start 383.662682 -151.225504)
		(end 384.123946 -158.30169)
		(width 0.1651)
		(layer "In5.Cu")
		(net "P5E_PEX3_STN1_RX_DN<23>")
	)
	(segment
		(start 400.54276 -112.776508)
		(end 400.25193 -112.485678)
		(width 0.1651)
		(layer "In5.Cu")
		(net "P5E_PEX3_STN1_RX_DN<23>")
	)
	(segment
		(start 388.553198 -137.487406)
		(end 386.545836 -141.115288)
		(width 0.1651)
		(layer "In5.Cu")
		(net "P5E_PEX3_STN1_RX_DN<23>")
	)
	(segment
		(start 398.642586 -113.009934)
		(end 398.493488 -112.94745)
		(width 0.1651)
		(layer "In5.Cu")
		(net "P5E_PEX3_STN1_RX_DN<23>")
	)
	(segment
		(start 398.493488 -112.94745)
		(end 398.035272 -113.134902)
		(width 0.1651)
		(layer "In5.Cu")
		(net "P5E_PEX3_STN1_RX_DN<23>")
	)
	(segment
		(start 398.035272 -113.134902)
		(end 397.972534 -113.284)
		(width 0.1651)
		(layer "In5.Cu")
		(net "P5E_PEX3_STN1_RX_DN<23>")
	)
	(segment
		(start 399.101056 -112.822482)
		(end 398.642586 -113.009934)
		(width 0.1651)
		(layer "In5.Cu")
		(net "P5E_PEX3_STN1_RX_DN<23>")
	)
	(segment
		(start 390.844786 -124.722382)
		(end 390.737598 -125.205744)
		(width 0.1651)
		(layer "In5.Cu")
		(net "P5E_PEX3_STN1_RX_DN<23>")
	)
	(segment
		(start 414.265872 -268.570202)
		(end 414.265872 -271.570958)
		(width 0.1651)
		(layer "In5.Cu")
		(net "P5E_PEX3_STN1_RX_DN<23>")
	)
	(segment
		(start 390.737598 -125.205744)
		(end 390.824212 -125.342142)
		(width 0.1651)
		(layer "In5.Cu")
		(net "P5E_PEX3_STN1_RX_DN<23>")
	)
	(segment
		(start 391.002012 -124.0155)
		(end 391.088626 -124.151898)
		(width 0.1651)
		(layer "In5.Cu")
		(net "P5E_PEX3_STN1_RX_DN<23>")
	)
	(segment
		(start 392.17727 -119.935498)
		(end 392.232642 -120.087136)
		(width 0.1651)
		(layer "In5.Cu")
		(net "P5E_PEX3_STN1_RX_DN<23>")
	)
	(segment
		(start 400.25193 -112.485678)
		(end 399.62201 -112.485678)
		(width 0.1651)
		(layer "In5.Cu")
		(net "P5E_PEX3_STN1_RX_DN<23>")
	)
	(segment
		(start 394.751052 -114.872008)
		(end 394.152374 -116.158772)
		(width 0.1651)
		(layer "In5.Cu")
		(net "P5E_PEX3_STN1_RX_DN<23>")
	)
	(segment
		(start 391.373614 -122.341894)
		(end 391.266426 -122.825256)
		(width 0.1651)
		(layer "In5.Cu")
		(net "P5E_PEX3_STN1_RX_DN<23>")
	)
	(segment
		(start 391.617708 -121.77141)
		(end 391.510266 -122.25528)
		(width 0.1651)
		(layer "In5.Cu")
		(net "P5E_PEX3_STN1_RX_DN<23>")
	)
	(segment
		(start 392.53795 -119.431054)
		(end 392.386058 -119.486426)
		(width 0.1651)
		(layer "In5.Cu")
		(net "P5E_PEX3_STN1_RX_DN<23>")
	)
	(segment
		(start 390.71677 -125.826012)
		(end 390.580372 -125.912626)
		(width 0.1651)
		(layer "In5.Cu")
		(net "P5E_PEX3_STN1_RX_DN<23>")
	)
	(segment
		(start 414.220152 -271.645126)
		(end 414.220152 -275.27631)
		(width 0.1143)
		(layer "In5.Cu")
		(net "P5E_PEX3_STN1_RX_DN<23>")
	)
	(segment
		(start 392.386058 -119.486426)
		(end 392.17727 -119.935498)
		(width 0.1651)
		(layer "In5.Cu")
		(net "P5E_PEX3_STN1_RX_DN<23>")
	)
	(segment
		(start 392.69162 -118.829836)
		(end 392.746992 -118.981728)
		(width 0.1651)
		(layer "In5.Cu")
		(net "P5E_PEX3_STN1_RX_DN<23>")
	)
	(segment
		(start 391.1092 -123.532138)
		(end 391.002012 -124.0155)
		(width 0.1651)
		(layer "In5.Cu")
		(net "P5E_PEX3_STN1_RX_DN<23>")
	)
	(segment
		(start 391.266426 -122.825256)
		(end 391.35304 -122.961654)
		(width 0.1651)
		(layer "In5.Cu")
		(net "P5E_PEX3_STN1_RX_DN<23>")
	)
	(segment
		(start 414.265872 -271.570958)
		(end 414.265872 -271.599406)
		(width 0.1143)
		(layer "In5.Cu")
		(net "P5E_PEX3_STN1_RX_DN<23>")
	)
	(segment
		(start 384.123946 -158.30169)
		(end 385.10591 -164.031168)
		(width 0.1651)
		(layer "In5.Cu")
		(net "P5E_PEX3_STN1_RX_DN<23>")
	)
	(segment
		(start 414.32353 -275.379688)
		(end 414.485328 -275.379688)
		(width 0.1143)
		(layer "In5.Cu")
		(net "P5E_PEX3_STN1_RX_DN<23>")
	)
	(segment
		(start 394.152374 -116.158772)
		(end 393.494768 -117.103398)
		(width 0.1651)
		(layer "In5.Cu")
		(net "P5E_PEX3_STN1_RX_DN<23>")
	)
	(segment
		(start 397.364966 -113.408968)
		(end 395.47419 -114.182144)
		(width 0.1651)
		(layer "In5.Cu")
		(net "P5E_PEX3_STN1_RX_DN<23>")
	)
	(segment
		(start 392.232642 -120.087136)
		(end 392.0236 -120.536716)
		(width 0.1651)
		(layer "In5.Cu")
		(net "P5E_PEX3_STN1_RX_DN<23>")
	)
	(segment
		(start 390.022842 -128.4224)
		(end 388.553198 -137.487406)
		(width 0.1651)
		(layer "In5.Cu")
		(net "P5E_PEX3_STN1_RX_DN<23>")
	)
	(segment
		(start 390.981184 -124.635768)
		(end 390.844786 -124.722382)
		(width 0.1651)
		(layer "In5.Cu")
		(net "P5E_PEX3_STN1_RX_DN<23>")
	)
	(segment
		(start 391.510266 -122.25528)
		(end 391.373614 -122.341894)
		(width 0.1651)
		(layer "In5.Cu")
		(net "P5E_PEX3_STN1_RX_DN<23>")
	)
	(segment
		(start 397.51381 -113.471452)
		(end 397.364966 -113.408968)
		(width 0.1651)
		(layer "In5.Cu")
		(net "P5E_PEX3_STN1_RX_DN<23>")
	)
	(segment
		(start 414.485328 -275.379688)
		(end 414.599628 -275.265388)
		(width 0.1143)
		(layer "In5.Cu")
		(net "P5E_PEX3_STN1_RX_DN<23>")
	)
	(segment
		(start 414.599628 -275.265388)
		(end 414.599628 -274.999958)
		(width 0.1143)
		(layer "In5.Cu")
		(net "P5E_PEX3_STN1_RX_DN<23>")
	)
	(segment
		(start 391.245598 -123.445524)
		(end 391.1092 -123.532138)
		(width 0.1651)
		(layer "In5.Cu")
		(net "P5E_PEX3_STN1_RX_DN<23>")
	)
	(segment
		(start 399.163794 -112.67313)
		(end 399.101056 -112.822482)
		(width 0.1651)
		(layer "In5.Cu")
		(net "P5E_PEX3_STN1_RX_DN<23>")
	)
	(segment
		(start 391.088626 -124.151898)
		(end 390.981184 -124.635768)
		(width 0.1651)
		(layer "In5.Cu")
		(net "P5E_PEX3_STN1_RX_DN<23>")
	)
	(segment
		(start 377.701048 -356.832154)
		(end 377.701048 -357.462582)
		(width 0.13462)
		(layer "F.Cu")
		(net "P5E_PEX3_STN6_TX_C_DP<108>")
	)
	(segment
		(start 377.3805 -356.511606)
		(end 377.701048 -356.832154)
		(width 0.13462)
		(layer "F.Cu")
		(net "P5E_PEX3_STN6_TX_C_DP<108>")
	)
	(segment
		(start 377.701048 -357.462582)
		(end 377.4059 -357.75773)
		(width 0.13462)
		(layer "F.Cu")
		(net "P5E_PEX3_STN6_TX_C_DP<108>")
	)
	(segment
		(start 377.4059 -357.75773)
		(end 377.69673 -358.04856)
		(width 0.1651)
		(layer "In13.Cu")
		(net "P5E_PEX3_STN6_TX_C_DP<108>")
	)
	(segment
		(start 374.067578 -390.10971)
		(end 376.467878 -391.158222)
		(width 0.1651)
		(layer "In13.Cu")
		(net "P5E_PEX3_STN6_TX_C_DP<108>")
	)
	(segment
		(start 372.527322 -364.397544)
		(end 370.277898 -367.673636)
		(width 0.1651)
		(layer "In13.Cu")
		(net "P5E_PEX3_STN6_TX_C_DP<108>")
	)
	(segment
		(start 371.233192 -388.03326)
		(end 374.067578 -390.10971)
		(width 0.1651)
		(layer "In13.Cu")
		(net "P5E_PEX3_STN6_TX_C_DP<108>")
	)
	(segment
		(start 382.933956 -396.29461)
		(end 382.933956 -409.512262)
		(width 0.1651)
		(layer "In13.Cu")
		(net "P5E_PEX3_STN6_TX_C_DP<108>")
	)
	(segment
		(start 377.69673 -358.04856)
		(end 377.69673 -358.370632)
		(width 0.1651)
		(layer "In13.Cu")
		(net "P5E_PEX3_STN6_TX_C_DP<108>")
	)
	(segment
		(start 382.933956 -409.512262)
		(end 382.64719 -409.799028)
		(width 0.1651)
		(layer "In13.Cu")
		(net "P5E_PEX3_STN6_TX_C_DP<108>")
	)
	(segment
		(start 377.33351 -359.28681)
		(end 372.527322 -364.397544)
		(width 0.1651)
		(layer "In13.Cu")
		(net "P5E_PEX3_STN6_TX_C_DP<108>")
	)
	(segment
		(start 376.467878 -391.158222)
		(end 381.722122 -394.17879)
		(width 0.1651)
		(layer "In13.Cu")
		(net "P5E_PEX3_STN6_TX_C_DP<108>")
	)
	(segment
		(start 369.764056 -373.216678)
		(end 370.268246 -385.531868)
		(width 0.1651)
		(layer "In13.Cu")
		(net "P5E_PEX3_STN6_TX_C_DP<108>")
	)
	(segment
		(start 382.089914 -409.672028)
		(end 382.089914 -409.290012)
		(width 0.1651)
		(layer "In13.Cu")
		(net "P5E_PEX3_STN6_TX_C_DP<108>")
	)
	(segment
		(start 377.69673 -358.370632)
		(end 377.33351 -359.28681)
		(width 0.1651)
		(layer "In13.Cu")
		(net "P5E_PEX3_STN6_TX_C_DP<108>")
	)
	(segment
		(start 382.64719 -409.799028)
		(end 382.216914 -409.799028)
		(width 0.1651)
		(layer "In13.Cu")
		(net "P5E_PEX3_STN6_TX_C_DP<108>")
	)
	(segment
		(start 370.268246 -385.531868)
		(end 371.233192 -388.03326)
		(width 0.1651)
		(layer "In13.Cu")
		(net "P5E_PEX3_STN6_TX_C_DP<108>")
	)
	(segment
		(start 382.371854 -394.893546)
		(end 382.933956 -396.29461)
		(width 0.1651)
		(layer "In13.Cu")
		(net "P5E_PEX3_STN6_TX_C_DP<108>")
	)
	(segment
		(start 370.018564 -370.472208)
		(end 369.764056 -373.216678)
		(width 0.1651)
		(layer "In13.Cu")
		(net "P5E_PEX3_STN6_TX_C_DP<108>")
	)
	(segment
		(start 382.216914 -409.799028)
		(end 382.089914 -409.672028)
		(width 0.1651)
		(layer "In13.Cu")
		(net "P5E_PEX3_STN6_TX_C_DP<108>")
	)
	(segment
		(start 370.277898 -367.673636)
		(end 370.018564 -370.472208)
		(width 0.1651)
		(layer "In13.Cu")
		(net "P5E_PEX3_STN6_TX_C_DP<108>")
	)
	(segment
		(start 381.722122 -394.17879)
		(end 382.371854 -394.893546)
		(width 0.1651)
		(layer "In13.Cu")
		(net "P5E_PEX3_STN6_TX_C_DP<108>")
	)
	(segment
		(start 50.64252 -155.960064)
		(end 51.40833 -155.960064)
		(width 0.13208)
		(layer "F.Cu")
		(net "NIC0_RBT_ARB_OUT")
	)
	(segment
		(start 51.40833 -155.960064)
		(end 51.730402 -156.282136)
		(width 0.13208)
		(layer "F.Cu")
		(net "NIC0_RBT_ARB_OUT")
	)
	(segment
		(start 52.847494 -156.282136)
		(end 53.109876 -156.544518)
		(width 0.13208)
		(layer "F.Cu")
		(net "NIC0_RBT_ARB_OUT")
	)
	(segment
		(start 51.730402 -156.282136)
		(end 52.847494 -156.282136)
		(width 0.13208)
		(layer "F.Cu")
		(net "NIC0_RBT_ARB_OUT")
	)
	(via
		(at 53.109876 -156.544518)
		(size 0.508)
		(drill 0.254)
		(layers "F.Cu" "B.Cu")
		(net "NIC0_RBT_ARB_OUT")
	)
	(segment
		(start 50.546 -156.591)
		(end 50.854864 -156.282136)
		(width 0.13208)
		(layer "B.Cu")
		(net "NIC0_RBT_ARB_OUT")
	)
	(segment
		(start 49.28235 -156.591)
		(end 50.546 -156.591)
		(width 0.13208)
		(layer "B.Cu")
		(net "NIC0_RBT_ARB_OUT")
	)
	(segment
		(start 50.854864 -156.282136)
		(end 52.847494 -156.282136)
		(width 0.13208)
		(layer "B.Cu")
		(net "NIC0_RBT_ARB_OUT")
	)
	(segment
		(start 49.15535 -157.0736)
		(end 49.15535 -156.718)
		(width 0.13208)
		(layer "B.Cu")
		(net "NIC0_RBT_ARB_OUT")
	)
	(segment
		(start 49.15535 -156.718)
		(end 49.28235 -156.591)
		(width 0.13208)
		(layer "B.Cu")
		(net "NIC0_RBT_ARB_OUT")
	)
	(segment
		(start 52.847494 -156.282136)
		(end 53.109876 -156.544518)
		(width 0.13208)
		(layer "B.Cu")
		(net "NIC0_RBT_ARB_OUT")
	)
	(segment
		(start 263.894062 -32.787336)
		(end 264.168636 -32.512762)
		(width 0.381)
		(layer "F.Cu")
		(net "P3V3_SSD9")
	)
	(segment
		(start 274.433284 -24.790146)
		(end 274.675092 -25.031954)
		(width 0.381)
		(layer "F.Cu")
		(net "P3V3_SSD9")
	)
	(segment
		(start 282.869386 -20.467574)
		(end 282.256484 -20.467574)
		(width 0.508)
		(layer "F.Cu")
		(net "P3V3_SSD9")
	)
	(segment
		(start 251.046742 -37.47516)
		(end 250.34113 -37.47516)
		(width 0.4572)
		(layer "F.Cu")
		(net "P3V3_SSD9")
	)
	(segment
		(start 264.168636 -32.512762)
		(end 264.168636 -30.971236)
		(width 0.381)
		(layer "F.Cu")
		(net "P3V3_SSD9")
	)
	(segment
		(start 283.760418 -14.799818)
		(end 283.760418 -16.439388)
		(width 0.381)
		(layer "F.Cu")
		(net "P3V3_SSD9")
	)
	(segment
		(start 280.085546 -27.492198)
		(end 279.953974 -27.492198)
		(width 0.381)
		(layer "F.Cu")
		(net "P3V3_SSD9")
	)
	(segment
		(start 273.464782 -24.790146)
		(end 274.433284 -24.790146)
		(width 0.381)
		(layer "F.Cu")
		(net "P3V3_SSD9")
	)
	(segment
		(start 283.154374 -14.735302)
		(end 283.824934 -14.735302)
		(width 0.381)
		(layer "F.Cu")
		(net "P3V3_SSD9")
	)
	(segment
		(start 264.168636 -30.971236)
		(end 263.594088 -30.396688)
		(width 0.381)
		(layer "F.Cu")
		(net "P3V3_SSD9")
	)
	(segment
		(start 265.571732 -24.807418)
		(end 264.953242 -24.807418)
		(width 0.4572)
		(layer "F.Cu")
		(net "P3V3_SSD9")
	)
	(segment
		(start 279.953974 -27.492198)
		(end 279.43302 -26.971244)
		(width 0.381)
		(layer "F.Cu")
		(net "P3V3_SSD9")
	)
	(segment
		(start 274.675092 -25.031954)
		(end 276.126448 -25.031954)
		(width 0.381)
		(layer "F.Cu")
		(net "P3V3_SSD9")
	)
	(segment
		(start 263.894062 -34.248852)
		(end 263.894062 -32.787336)
		(width 0.381)
		(layer "F.Cu")
		(net "P3V3_SSD9")
	)
	(segment
		(start 277.67153 -25.742392)
		(end 277.67153 -26.360882)
		(width 0.4572)
		(layer "F.Cu")
		(net "P3V3_SSD9")
	)
	(segment
		(start 283.824934 -14.735302)
		(end 283.760418 -14.799818)
		(width 0.381)
		(layer "F.Cu")
		(net "P3V3_SSD9")
	)
	(segment
		(start 266.378944 -59.978036)
		(end 266.378944 -60.633356)
		(width 0.381)
		(layer "F.Cu")
		(net "P3V3_SSD9")
	)
	(segment
		(start 282.256484 -17.419574)
		(end 282.866084 -17.419574)
		(width 0.508)
		(layer "F.Cu")
		(net "P3V3_SSD9")
	)
	(segment
		(start 276.126448 -25.031954)
		(end 276.76983 -25.031954)
		(width 0.4572)
		(layer "F.Cu")
		(net "P3V3_SSD9")
	)
	(via
		(at 266.378944 -60.633356)
		(size 0.508)
		(drill 0.254)
		(layers "F.Cu" "B.Cu")
		(net "P3V3_SSD9")
	)
	(via
		(at 277.67153 -26.360882)
		(size 0.508)
		(drill 0.254)
		(layers "F.Cu" "B.Cu")
		(net "P3V3_SSD9")
	)
	(via
		(at 264.693908 -50.478182)
		(size 0.6604)
		(drill 0.3302)
		(layers "F.Cu" "B.Cu")
		(net "P3V3_SSD9")
	)
	(via
		(at 265.328908 -49.574704)
		(size 0.508)
		(drill 0.254)
		(layers "F.Cu" "B.Cu")
		(net "P3V3_SSD9")
	)
	(via
		(at 265.799824 -52.528724)
		(size 0.508)
		(drill 0.254)
		(layers "F.Cu" "B.Cu")
		(net "P3V3_SSD9")
	)
	(via
		(at 266.47648 -51.320192)
		(size 0.508)
		(drill 0.254)
		(layers "F.Cu" "B.Cu")
		(net "P3V3_SSD9")
	)
	(via
		(at 265.349482 -53.469286)
		(size 0.508)
		(drill 0.254)
		(layers "F.Cu" "B.Cu")
		(net "P3V3_SSD9")
	)
	(via
		(at 262.510524 -29.614876)
		(size 0.508)
		(drill 0.254)
		(layers "F.Cu" "B.Cu")
		(net "P3V3_SSD9")
	)
	(via
		(at 279.43302 -26.971244)
		(size 0.508)
		(drill 0.254)
		(layers "F.Cu" "B.Cu")
		(net "P3V3_SSD9")
	)
	(via
		(at 264.693908 -49.574704)
		(size 0.508)
		(drill 0.254)
		(layers "F.Cu" "B.Cu")
		(net "P3V3_SSD9")
	)
	(via
		(at 250.34113 -37.47516)
		(size 0.508)
		(drill 0.254)
		(layers "F.Cu" "B.Cu")
		(net "P3V3_SSD9")
	)
	(via
		(at 283.154374 -14.735302)
		(size 0.508)
		(drill 0.254)
		(layers "F.Cu" "B.Cu")
		(net "P3V3_SSD9")
	)
	(via
		(at 265.71448 -50.608992)
		(size 0.508)
		(drill 0.254)
		(layers "F.Cu" "B.Cu")
		(net "P3V3_SSD9")
	)
	(via
		(at 266.47648 -50.608992)
		(size 0.508)
		(drill 0.254)
		(layers "F.Cu" "B.Cu")
		(net "P3V3_SSD9")
	)
	(via
		(at 265.164824 -52.528724)
		(size 0.508)
		(drill 0.254)
		(layers "F.Cu" "B.Cu")
		(net "P3V3_SSD9")
	)
	(via
		(at 276.76983 -25.031954)
		(size 0.508)
		(drill 0.254)
		(layers "F.Cu" "B.Cu")
		(net "P3V3_SSD9")
	)
	(via
		(at 264.714482 -53.469286)
		(size 0.508)
		(drill 0.254)
		(layers "F.Cu" "B.Cu")
		(net "P3V3_SSD9")
	)
	(via
		(at 264.953242 -24.807418)
		(size 0.508)
		(drill 0.254)
		(layers "F.Cu" "B.Cu")
		(net "P3V3_SSD9")
	)
	(via
		(at 282.866084 -17.419574)
		(size 0.508)
		(drill 0.254)
		(layers "F.Cu" "B.Cu")
		(net "P3V3_SSD9")
	)
	(via
		(at 265.71448 -51.243992)
		(size 0.508)
		(drill 0.254)
		(layers "F.Cu" "B.Cu")
		(net "P3V3_SSD9")
	)
	(via
		(at 266.598908 -49.574704)
		(size 0.508)
		(drill 0.254)
		(layers "F.Cu" "B.Cu")
		(net "P3V3_SSD9")
	)
	(via
		(at 282.869386 -20.467574)
		(size 0.508)
		(drill 0.254)
		(layers "F.Cu" "B.Cu")
		(net "P3V3_SSD9")
	)
	(via
		(at 262.510524 -30.376876)
		(size 0.508)
		(drill 0.254)
		(layers "F.Cu" "B.Cu")
		(net "P3V3_SSD9")
	)
	(via
		(at 265.963908 -49.574704)
		(size 0.508)
		(drill 0.254)
		(layers "F.Cu" "B.Cu")
		(net "P3V3_SSD9")
	)
	(segment
		(start 253.254002 -37.872924)
		(end 252.804168 -38.322758)
		(width 0.508)
		(layer "In9.Cu")
		(net "P3V3_SSD9")
	)
	(segment
		(start 252.804168 -38.322758)
		(end 251.188728 -38.322758)
		(width 0.508)
		(layer "In9.Cu")
		(net "P3V3_SSD9")
	)
	(segment
		(start 259.963666 -37.872924)
		(end 253.254002 -37.872924)
		(width 0.508)
		(layer "In9.Cu")
		(net "P3V3_SSD9")
	)
	(segment
		(start 251.188728 -38.322758)
		(end 250.34113 -37.47516)
		(width 0.508)
		(layer "In9.Cu")
		(net "P3V3_SSD9")
	)
	(segment
		(start 36.018724 -32.4231)
		(end 35.363912 -32.4231)
		(width 0.13462)
		(layer "F.Cu")
		(net "P5E_PEX0_STN2_RX_DP<42>")
	)
	(segment
		(start 35.363912 -32.4231)
		(end 35.0647 -32.722312)
		(width 0.13462)
		(layer "F.Cu")
		(net "P5E_PEX0_STN2_RX_DP<42>")
	)
	(segment
		(start 36.6649 -32.589978)
		(end 36.185602 -32.589978)
		(width 0.13462)
		(layer "F.Cu")
		(net "P5E_PEX0_STN2_RX_DP<42>")
	)
	(segment
		(start 36.185602 -32.589978)
		(end 36.018724 -32.4231)
		(width 0.13462)
		(layer "F.Cu")
		(net "P5E_PEX0_STN2_RX_DP<42>")
	)
	(segment
		(start 36.125658 -35.019996)
		(end 36.13785 -34.232596)
		(width 0.1651)
		(layer "In7.Cu")
		(net "P5E_PEX0_STN2_RX_DP<42>")
	)
	(segment
		(start 36.03498 -35.50666)
		(end 36.125658 -35.019996)
		(width 0.1651)
		(layer "In7.Cu")
		(net "P5E_PEX0_STN2_RX_DP<42>")
	)
	(segment
		(start 37.244782 -65.176654)
		(end 36.852606 -55.371238)
		(width 0.1651)
		(layer "In7.Cu")
		(net "P5E_PEX0_STN2_RX_DP<42>")
	)
	(segment
		(start 35.35553 -32.431482)
		(end 35.0647 -32.722312)
		(width 0.1651)
		(layer "In7.Cu")
		(net "P5E_PEX0_STN2_RX_DP<42>")
	)
	(segment
		(start 36.852606 -55.371238)
		(end 36.944808 -49.45253)
		(width 0.1651)
		(layer "In7.Cu")
		(net "P5E_PEX0_STN2_RX_DP<42>")
	)
	(segment
		(start 35.82543 -36.075112)
		(end 35.916362 -35.58794)
		(width 0.1651)
		(layer "In7.Cu")
		(net "P5E_PEX0_STN2_RX_DP<42>")
	)
	(segment
		(start 48.531272 -250.005342)
		(end 40.57523 -148.011896)
		(width 0.1651)
		(layer "In7.Cu")
		(net "P5E_PEX0_STN2_RX_DP<42>")
	)
	(segment
		(start 48.629316 -271.467072)
		(end 48.583596 -271.421352)
		(width 0.1143)
		(layer "In7.Cu")
		(net "P5E_PEX0_STN2_RX_DP<42>")
	)
	(segment
		(start 35.601402 -37.832538)
		(end 35.90671 -36.19373)
		(width 0.1651)
		(layer "In7.Cu")
		(net "P5E_PEX0_STN2_RX_DP<42>")
	)
	(segment
		(start 49.1998 -275.684488)
		(end 49.0855 -275.570188)
		(width 0.1143)
		(layer "In7.Cu")
		(net "P5E_PEX0_STN2_RX_DP<42>")
	)
	(segment
		(start 48.13935 -263.273032)
		(end 48.362616 -258.724654)
		(width 0.1651)
		(layer "In7.Cu")
		(net "P5E_PEX0_STN2_RX_DP<42>")
	)
	(segment
		(start 40.881554 -119.585994)
		(end 40.438832 -104.96804)
		(width 0.1651)
		(layer "In7.Cu")
		(net "P5E_PEX0_STN2_RX_DP<42>")
	)
	(segment
		(start 36.944808 -49.45253)
		(end 35.631374 -39.731442)
		(width 0.1651)
		(layer "In7.Cu")
		(net "P5E_PEX0_STN2_RX_DP<42>")
	)
	(segment
		(start 48.583596 -271.421352)
		(end 48.583596 -271.392904)
		(width 0.1143)
		(layer "In7.Cu")
		(net "P5E_PEX0_STN2_RX_DP<42>")
	)
	(segment
		(start 49.1998 -275.949918)
		(end 49.1998 -275.684488)
		(width 0.1143)
		(layer "In7.Cu")
		(net "P5E_PEX0_STN2_RX_DP<42>")
	)
	(segment
		(start 48.583596 -271.392904)
		(end 48.583596 -267.781786)
		(width 0.1651)
		(layer "In7.Cu")
		(net "P5E_PEX0_STN2_RX_DP<42>")
	)
	(segment
		(start 48.844708 -275.570188)
		(end 48.629316 -275.354796)
		(width 0.1143)
		(layer "In7.Cu")
		(net "P5E_PEX0_STN2_RX_DP<42>")
	)
	(segment
		(start 36.045394 -33.633918)
		(end 36.148772 -33.533842)
		(width 0.1651)
		(layer "In7.Cu")
		(net "P5E_PEX0_STN2_RX_DP<42>")
	)
	(segment
		(start 35.631374 -39.731442)
		(end 35.601402 -37.832538)
		(width 0.1651)
		(layer "In7.Cu")
		(net "P5E_PEX0_STN2_RX_DP<42>")
	)
	(segment
		(start 36.148772 -33.533842)
		(end 36.160456 -32.7787)
		(width 0.1651)
		(layer "In7.Cu")
		(net "P5E_PEX0_STN2_RX_DP<42>")
	)
	(segment
		(start 40.57523 -148.011896)
		(end 40.881554 -119.585994)
		(width 0.1651)
		(layer "In7.Cu")
		(net "P5E_PEX0_STN2_RX_DP<42>")
	)
	(segment
		(start 48.583596 -267.781786)
		(end 48.13935 -263.273032)
		(width 0.1651)
		(layer "In7.Cu")
		(net "P5E_PEX0_STN2_RX_DP<42>")
	)
	(segment
		(start 49.0855 -275.570188)
		(end 48.844708 -275.570188)
		(width 0.1143)
		(layer "In7.Cu")
		(net "P5E_PEX0_STN2_RX_DP<42>")
	)
	(segment
		(start 48.629316 -275.354796)
		(end 48.629316 -271.467072)
		(width 0.1143)
		(layer "In7.Cu")
		(net "P5E_PEX0_STN2_RX_DP<42>")
	)
	(segment
		(start 36.037774 -34.129472)
		(end 36.045394 -33.633918)
		(width 0.1651)
		(layer "In7.Cu")
		(net "P5E_PEX0_STN2_RX_DP<42>")
	)
	(segment
		(start 36.13785 -34.232596)
		(end 36.037774 -34.129472)
		(width 0.1651)
		(layer "In7.Cu")
		(net "P5E_PEX0_STN2_RX_DP<42>")
	)
	(segment
		(start 35.916362 -35.58794)
		(end 36.03498 -35.50666)
		(width 0.1651)
		(layer "In7.Cu")
		(net "P5E_PEX0_STN2_RX_DP<42>")
	)
	(segment
		(start 35.90671 -36.19373)
		(end 35.82543 -36.075112)
		(width 0.1651)
		(layer "In7.Cu")
		(net "P5E_PEX0_STN2_RX_DP<42>")
	)
	(segment
		(start 36.160456 -32.7787)
		(end 35.813238 -32.431482)
		(width 0.1651)
		(layer "In7.Cu")
		(net "P5E_PEX0_STN2_RX_DP<42>")
	)
	(segment
		(start 40.438832 -104.96804)
		(end 37.244782 -65.176654)
		(width 0.1651)
		(layer "In7.Cu")
		(net "P5E_PEX0_STN2_RX_DP<42>")
	)
	(segment
		(start 48.362616 -258.724654)
		(end 48.531272 -250.005342)
		(width 0.1651)
		(layer "In7.Cu")
		(net "P5E_PEX0_STN2_RX_DP<42>")
	)
	(segment
		(start 35.813238 -32.431482)
		(end 35.35553 -32.431482)
		(width 0.1651)
		(layer "In7.Cu")
		(net "P5E_PEX0_STN2_RX_DP<42>")
	)
	(segment
		(start 203.458064 -28.829)
		(end 203.164694 -29.12237)
		(width 0.13462)
		(layer "F.Cu")
		(net "P5E_PEX1_STN2_RX_DP<32>")
	)
	(segment
		(start 204.12456 -28.829)
		(end 203.458064 -28.829)
		(width 0.13462)
		(layer "F.Cu")
		(net "P5E_PEX1_STN2_RX_DP<32>")
	)
	(segment
		(start 204.28585 -28.99029)
		(end 204.12456 -28.829)
		(width 0.13462)
		(layer "F.Cu")
		(net "P5E_PEX1_STN2_RX_DP<32>")
	)
	(segment
		(start 204.764894 -28.99029)
		(end 204.28585 -28.99029)
		(width 0.13462)
		(layer "F.Cu")
		(net "P5E_PEX1_STN2_RX_DP<32>")
	)
	(segment
		(start 204.764894 -28.990036)
		(end 204.764894 -28.99029)
		(width 0.13462)
		(layer "F.Cu")
		(net "P5E_PEX1_STN2_RX_DP<32>")
	)
	(segment
		(start 174.444914 -275.570188)
		(end 174.229522 -275.354796)
		(width 0.1143)
		(layer "In7.Cu")
		(net "P5E_PEX1_STN2_RX_DP<32>")
	)
	(segment
		(start 205.718918 -30.5562)
		(end 205.55712 -30.5562)
		(width 0.1651)
		(layer "In7.Cu")
		(net "P5E_PEX1_STN2_RX_DP<32>")
	)
	(segment
		(start 174.183802 -270.159734)
		(end 174.36338 -269.382494)
		(width 0.1651)
		(layer "In7.Cu")
		(net "P5E_PEX1_STN2_RX_DP<32>")
	)
	(segment
		(start 203.643484 -28.83154)
		(end 203.322682 -28.964382)
		(width 0.1651)
		(layer "In7.Cu")
		(net "P5E_PEX1_STN2_RX_DP<32>")
	)
	(segment
		(start 174.685706 -275.570188)
		(end 174.444914 -275.570188)
		(width 0.1143)
		(layer "In7.Cu")
		(net "P5E_PEX1_STN2_RX_DP<32>")
	)
	(segment
		(start 205.2066 -30.20568)
		(end 205.2066 -30.043882)
		(width 0.1651)
		(layer "In7.Cu")
		(net "P5E_PEX1_STN2_RX_DP<32>")
	)
	(segment
		(start 206.979012 -49.388014)
		(end 208.960974 -39.920926)
		(width 0.1651)
		(layer "In7.Cu")
		(net "P5E_PEX1_STN2_RX_DP<32>")
	)
	(segment
		(start 205.55712 -30.5562)
		(end 205.2066 -30.20568)
		(width 0.1651)
		(layer "In7.Cu")
		(net "P5E_PEX1_STN2_RX_DP<32>")
	)
	(segment
		(start 204.69479 -29.69387)
		(end 204.34427 -29.34335)
		(width 0.1651)
		(layer "In7.Cu")
		(net "P5E_PEX1_STN2_RX_DP<32>")
	)
	(segment
		(start 174.36338 -269.382494)
		(end 174.596298 -266.698222)
		(width 0.1651)
		(layer "In7.Cu")
		(net "P5E_PEX1_STN2_RX_DP<32>")
	)
	(segment
		(start 203.322682 -28.964382)
		(end 203.164694 -29.12237)
		(width 0.1651)
		(layer "In7.Cu")
		(net "P5E_PEX1_STN2_RX_DP<32>")
	)
	(segment
		(start 174.800006 -275.684488)
		(end 174.685706 -275.570188)
		(width 0.1143)
		(layer "In7.Cu")
		(net "P5E_PEX1_STN2_RX_DP<32>")
	)
	(segment
		(start 205.2066 -30.043882)
		(end 204.856588 -29.69387)
		(width 0.1651)
		(layer "In7.Cu")
		(net "P5E_PEX1_STN2_RX_DP<32>")
	)
	(segment
		(start 206.793338 -61.28004)
		(end 206.979012 -49.388014)
		(width 0.1651)
		(layer "In7.Cu")
		(net "P5E_PEX1_STN2_RX_DP<32>")
	)
	(segment
		(start 204.34427 -29.181552)
		(end 203.994258 -28.83154)
		(width 0.1651)
		(layer "In7.Cu")
		(net "P5E_PEX1_STN2_RX_DP<32>")
	)
	(segment
		(start 195.470272 -144.038066)
		(end 195.785486 -116.762022)
		(width 0.1651)
		(layer "In7.Cu")
		(net "P5E_PEX1_STN2_RX_DP<32>")
	)
	(segment
		(start 174.229522 -271.467072)
		(end 174.183802 -271.421352)
		(width 0.1143)
		(layer "In7.Cu")
		(net "P5E_PEX1_STN2_RX_DP<32>")
	)
	(segment
		(start 174.229522 -275.354796)
		(end 174.229522 -271.467072)
		(width 0.1143)
		(layer "In7.Cu")
		(net "P5E_PEX1_STN2_RX_DP<32>")
	)
	(segment
		(start 194.084194 -154.799284)
		(end 195.470272 -144.038066)
		(width 0.1651)
		(layer "In7.Cu")
		(net "P5E_PEX1_STN2_RX_DP<32>")
	)
	(segment
		(start 174.596298 -266.698222)
		(end 194.084194 -154.799284)
		(width 0.1651)
		(layer "In7.Cu")
		(net "P5E_PEX1_STN2_RX_DP<32>")
	)
	(segment
		(start 195.785486 -116.762022)
		(end 206.793338 -61.28004)
		(width 0.1651)
		(layer "In7.Cu")
		(net "P5E_PEX1_STN2_RX_DP<32>")
	)
	(segment
		(start 206.413354 -31.250636)
		(end 205.718918 -30.5562)
		(width 0.1651)
		(layer "In7.Cu")
		(net "P5E_PEX1_STN2_RX_DP<32>")
	)
	(segment
		(start 204.856588 -29.69387)
		(end 204.69479 -29.69387)
		(width 0.1651)
		(layer "In7.Cu")
		(net "P5E_PEX1_STN2_RX_DP<32>")
	)
	(segment
		(start 204.34427 -29.34335)
		(end 204.34427 -29.181552)
		(width 0.1651)
		(layer "In7.Cu")
		(net "P5E_PEX1_STN2_RX_DP<32>")
	)
	(segment
		(start 174.183802 -271.392904)
		(end 174.183802 -270.159734)
		(width 0.1651)
		(layer "In7.Cu")
		(net "P5E_PEX1_STN2_RX_DP<32>")
	)
	(segment
		(start 174.800006 -275.949918)
		(end 174.800006 -275.684488)
		(width 0.1143)
		(layer "In7.Cu")
		(net "P5E_PEX1_STN2_RX_DP<32>")
	)
	(segment
		(start 174.183802 -271.421352)
		(end 174.183802 -271.392904)
		(width 0.1143)
		(layer "In7.Cu")
		(net "P5E_PEX1_STN2_RX_DP<32>")
	)
	(segment
		(start 203.994258 -28.83154)
		(end 203.643484 -28.83154)
		(width 0.1651)
		(layer "In7.Cu")
		(net "P5E_PEX1_STN2_RX_DP<32>")
	)
	(segment
		(start 209.169254 -38.063424)
		(end 209.072988 -37.563552)
		(width 0.1651)
		(layer "In7.Cu")
		(net "P5E_PEX1_STN2_RX_DP<32>")
	)
	(segment
		(start 208.960974 -39.920926)
		(end 209.169254 -38.063424)
		(width 0.1651)
		(layer "In7.Cu")
		(net "P5E_PEX1_STN2_RX_DP<32>")
	)
	(segment
		(start 209.072988 -37.563552)
		(end 206.413354 -31.250636)
		(width 0.1651)
		(layer "In7.Cu")
		(net "P5E_PEX1_STN2_RX_DP<32>")
	)
	(segment
		(start 306.125372 -148.59)
		(end 305.960272 -148.7551)
		(width 0.13462)
		(layer "F.Cu")
		(net "P5E_PEX2_STN0_TX_C_DP<11>")
	)
	(segment
		(start 305.960272 -148.7551)
		(end 305.457606 -148.7551)
		(width 0.13462)
		(layer "F.Cu")
		(net "P5E_PEX2_STN0_TX_C_DP<11>")
	)
	(segment
		(start 314.594748 -148.91131)
		(end 314.273438 -148.59)
		(width 0.13462)
		(layer "F.Cu")
		(net "P5E_PEX2_STN0_TX_C_DP<11>")
	)
	(segment
		(start 314.273438 -148.59)
		(end 306.125372 -148.59)
		(width 0.13462)
		(layer "F.Cu")
		(net "P5E_PEX2_STN0_TX_C_DP<11>")
	)
	(segment
		(start 400.54276 -135.83285)
		(end 400.24431 -136.1313)
		(width 0.13462)
		(layer "F.Cu")
		(net "P5E_PEX3_STN1_RX_DP<31>")
	)
	(segment
		(start 399.421604 -135.96493)
		(end 398.94256 -135.96493)
		(width 0.13462)
		(layer "F.Cu")
		(net "P5E_PEX3_STN1_RX_DP<31>")
	)
	(segment
		(start 399.587974 -136.1313)
		(end 399.421604 -135.96493)
		(width 0.13462)
		(layer "F.Cu")
		(net "P5E_PEX3_STN1_RX_DP<31>")
	)
	(segment
		(start 400.24431 -136.1313)
		(end 399.587974 -136.1313)
		(width 0.13462)
		(layer "F.Cu")
		(net "P5E_PEX3_STN1_RX_DP<31>")
	)
	(segment
		(start 393.737592 -153.01214)
		(end 393.21105 -159.473646)
		(width 0.1651)
		(layer "In5.Cu")
		(net "P5E_PEX3_STN1_RX_DP<31>")
	)
	(segment
		(start 421.583866 -271.599406)
		(end 421.629586 -271.645126)
		(width 0.1143)
		(layer "In5.Cu")
		(net "P5E_PEX3_STN1_RX_DP<31>")
	)
	(segment
		(start 394.130784 -148.199094)
		(end 394.13053 -148.200872)
		(width 0.1651)
		(layer "In5.Cu")
		(net "P5E_PEX3_STN1_RX_DP<31>")
	)
	(segment
		(start 421.583866 -271.570958)
		(end 421.583866 -271.599406)
		(width 0.1143)
		(layer "In5.Cu")
		(net "P5E_PEX3_STN1_RX_DP<31>")
	)
	(segment
		(start 399.312384 -136.68629)
		(end 399.18767 -136.987534)
		(width 0.1651)
		(layer "In5.Cu")
		(net "P5E_PEX3_STN1_RX_DP<31>")
	)
	(segment
		(start 400.54276 -135.83285)
		(end 400.25193 -136.12368)
		(width 0.1651)
		(layer "In5.Cu")
		(net "P5E_PEX3_STN1_RX_DP<31>")
	)
	(segment
		(start 400.25193 -136.12368)
		(end 399.874994 -136.12368)
		(width 0.1651)
		(layer "In5.Cu")
		(net "P5E_PEX3_STN1_RX_DP<31>")
	)
	(segment
		(start 394.13053 -148.200872)
		(end 393.7381 -153.01214)
		(width 0.1651)
		(layer "In5.Cu")
		(net "P5E_PEX3_STN1_RX_DP<31>")
	)
	(segment
		(start 397.96593 -144.215612)
		(end 395.563852 -146.579844)
		(width 0.1651)
		(layer "In5.Cu")
		(net "P5E_PEX3_STN1_RX_DP<31>")
	)
	(segment
		(start 399.874994 -136.12368)
		(end 399.312384 -136.68629)
		(width 0.1651)
		(layer "In5.Cu")
		(net "P5E_PEX3_STN1_RX_DP<31>")
	)
	(segment
		(start 394.907516 -146.848576)
		(end 394.594842 -147.156424)
		(width 0.1651)
		(layer "In5.Cu")
		(net "P5E_PEX3_STN1_RX_DP<31>")
	)
	(segment
		(start 393.21105 -159.473646)
		(end 393.211558 -159.491172)
		(width 0.1651)
		(layer "In5.Cu")
		(net "P5E_PEX3_STN1_RX_DP<31>")
	)
	(segment
		(start 393.7381 -153.01214)
		(end 393.737592 -153.01214)
		(width 0.1651)
		(layer "In5.Cu")
		(net "P5E_PEX3_STN1_RX_DP<31>")
	)
	(segment
		(start 399.18767 -136.987534)
		(end 399.18767 -141.23035)
		(width 0.1651)
		(layer "In5.Cu")
		(net "P5E_PEX3_STN1_RX_DP<31>")
	)
	(segment
		(start 421.52062 -266.597638)
		(end 421.583866 -267.07973)
		(width 0.1651)
		(layer "In5.Cu")
		(net "P5E_PEX3_STN1_RX_DP<31>")
	)
	(segment
		(start 393.252198 -160.413446)
		(end 421.52062 -266.597638)
		(width 0.1651)
		(layer "In5.Cu")
		(net "P5E_PEX3_STN1_RX_DP<31>")
	)
	(segment
		(start 394.594842 -147.156424)
		(end 394.130784 -148.199094)
		(width 0.1651)
		(layer "In5.Cu")
		(net "P5E_PEX3_STN1_RX_DP<31>")
	)
	(segment
		(start 399.18767 -141.23035)
		(end 397.96593 -144.215612)
		(width 0.1651)
		(layer "In5.Cu")
		(net "P5E_PEX3_STN1_RX_DP<31>")
	)
	(segment
		(start 421.583866 -267.07973)
		(end 421.583866 -271.570958)
		(width 0.1651)
		(layer "In5.Cu")
		(net "P5E_PEX3_STN1_RX_DP<31>")
	)
	(segment
		(start 393.211558 -159.491172)
		(end 393.211812 -159.491172)
		(width 0.1651)
		(layer "In5.Cu")
		(net "P5E_PEX3_STN1_RX_DP<31>")
	)
	(segment
		(start 422.085262 -275.570188)
		(end 422.199562 -275.684488)
		(width 0.1143)
		(layer "In5.Cu")
		(net "P5E_PEX3_STN1_RX_DP<31>")
	)
	(segment
		(start 421.629586 -275.355304)
		(end 421.84447 -275.570188)
		(width 0.1143)
		(layer "In5.Cu")
		(net "P5E_PEX3_STN1_RX_DP<31>")
	)
	(segment
		(start 421.629586 -271.645126)
		(end 421.629586 -275.355304)
		(width 0.1143)
		(layer "In5.Cu")
		(net "P5E_PEX3_STN1_RX_DP<31>")
	)
	(segment
		(start 421.84447 -275.570188)
		(end 422.085262 -275.570188)
		(width 0.1143)
		(layer "In5.Cu")
		(net "P5E_PEX3_STN1_RX_DP<31>")
	)
	(segment
		(start 422.199562 -275.684488)
		(end 422.199562 -275.949918)
		(width 0.1143)
		(layer "In5.Cu")
		(net "P5E_PEX3_STN1_RX_DP<31>")
	)
	(segment
		(start 395.563852 -146.579844)
		(end 394.907516 -146.848576)
		(width 0.1651)
		(layer "In5.Cu")
		(net "P5E_PEX3_STN1_RX_DP<31>")
	)
	(segment
		(start 393.211812 -159.491172)
		(end 393.252198 -160.413446)
		(width 0.1651)
		(layer "In5.Cu")
		(net "P5E_PEX3_STN1_RX_DP<31>")
	)
	(segment
		(start 380.810008 -351.31629)
		(end 380.51486 -351.611438)
		(width 0.13462)
		(layer "F.Cu")
		(net "P5E_PEX3_STN6_TX_C_DP<107>")
	)
	(segment
		(start 380.810008 -350.685862)
		(end 380.810008 -351.31629)
		(width 0.13462)
		(layer "F.Cu")
		(net "P5E_PEX3_STN6_TX_C_DP<107>")
	)
	(segment
		(start 380.48946 -350.365314)
		(end 380.810008 -350.685862)
		(width 0.13462)
		(layer "F.Cu")
		(net "P5E_PEX3_STN6_TX_C_DP<107>")
	)
	(segment
		(start 384.847338 -408.699208)
		(end 385.134104 -408.412442)
		(width 0.1651)
		(layer "In13.Cu")
		(net "P5E_PEX3_STN6_TX_C_DP<107>")
	)
	(segment
		(start 383.241804 -393.715494)
		(end 383.20726 -393.576048)
		(width 0.1651)
		(layer "In13.Cu")
		(net "P5E_PEX3_STN6_TX_C_DP<107>")
	)
	(segment
		(start 372.08079 -387.454394)
		(end 371.235224 -385.312158)
		(width 0.1651)
		(layer "In13.Cu")
		(net "P5E_PEX3_STN6_TX_C_DP<107>")
	)
	(segment
		(start 384.290062 -408.190192)
		(end 384.290062 -408.572208)
		(width 0.1651)
		(layer "In13.Cu")
		(net "P5E_PEX3_STN6_TX_C_DP<107>")
	)
	(segment
		(start 379.25121 -353.910646)
		(end 380.80569 -352.356166)
		(width 0.1651)
		(layer "In13.Cu")
		(net "P5E_PEX3_STN6_TX_C_DP<107>")
	)
	(segment
		(start 384.290062 -408.572208)
		(end 384.417062 -408.699208)
		(width 0.1651)
		(layer "In13.Cu")
		(net "P5E_PEX3_STN6_TX_C_DP<107>")
	)
	(segment
		(start 382.18491 -392.959336)
		(end 380.37516 -391.86739)
		(width 0.1651)
		(layer "In13.Cu")
		(net "P5E_PEX3_STN6_TX_C_DP<107>")
	)
	(segment
		(start 385.134104 -408.412442)
		(end 385.134104 -395.328902)
		(width 0.1651)
		(layer "In13.Cu")
		(net "P5E_PEX3_STN6_TX_C_DP<107>")
	)
	(segment
		(start 380.37516 -391.86739)
		(end 374.665748 -389.289798)
		(width 0.1651)
		(layer "In13.Cu")
		(net "P5E_PEX3_STN6_TX_C_DP<107>")
	)
	(segment
		(start 373.280432 -365.060484)
		(end 378.49937 -359.951782)
		(width 0.1651)
		(layer "In13.Cu")
		(net "P5E_PEX3_STN6_TX_C_DP<107>")
	)
	(segment
		(start 383.80543 -393.936982)
		(end 383.665984 -393.971526)
		(width 0.1651)
		(layer "In13.Cu")
		(net "P5E_PEX3_STN6_TX_C_DP<107>")
	)
	(segment
		(start 380.80569 -351.902268)
		(end 380.51486 -351.611438)
		(width 0.1651)
		(layer "In13.Cu")
		(net "P5E_PEX3_STN6_TX_C_DP<107>")
	)
	(segment
		(start 382.219454 -393.098782)
		(end 382.18491 -392.959336)
		(width 0.1651)
		(layer "In13.Cu")
		(net "P5E_PEX3_STN6_TX_C_DP<107>")
	)
	(segment
		(start 378.49937 -359.951782)
		(end 379.25121 -358.164384)
		(width 0.1651)
		(layer "In13.Cu")
		(net "P5E_PEX3_STN6_TX_C_DP<107>")
	)
	(segment
		(start 383.665984 -393.971526)
		(end 383.241804 -393.715494)
		(width 0.1651)
		(layer "In13.Cu")
		(net "P5E_PEX3_STN6_TX_C_DP<107>")
	)
	(segment
		(start 384.826002 -394.552678)
		(end 383.80543 -393.936982)
		(width 0.1651)
		(layer "In13.Cu")
		(net "P5E_PEX3_STN6_TX_C_DP<107>")
	)
	(segment
		(start 385.134104 -395.328902)
		(end 384.826002 -394.552678)
		(width 0.1651)
		(layer "In13.Cu")
		(net "P5E_PEX3_STN6_TX_C_DP<107>")
	)
	(segment
		(start 383.20726 -393.576048)
		(end 382.783334 -393.32027)
		(width 0.1651)
		(layer "In13.Cu")
		(net "P5E_PEX3_STN6_TX_C_DP<107>")
	)
	(segment
		(start 384.417062 -408.699208)
		(end 384.847338 -408.699208)
		(width 0.1651)
		(layer "In13.Cu")
		(net "P5E_PEX3_STN6_TX_C_DP<107>")
	)
	(segment
		(start 371.235224 -385.312158)
		(end 370.760498 -373.393716)
		(width 0.1651)
		(layer "In13.Cu")
		(net "P5E_PEX3_STN6_TX_C_DP<107>")
	)
	(segment
		(start 371.233446 -368.013996)
		(end 373.280432 -365.060484)
		(width 0.1651)
		(layer "In13.Cu")
		(net "P5E_PEX3_STN6_TX_C_DP<107>")
	)
	(segment
		(start 374.665748 -389.289798)
		(end 372.08079 -387.454394)
		(width 0.1651)
		(layer "In13.Cu")
		(net "P5E_PEX3_STN6_TX_C_DP<107>")
	)
	(segment
		(start 382.643888 -393.354814)
		(end 382.219454 -393.098782)
		(width 0.1651)
		(layer "In13.Cu")
		(net "P5E_PEX3_STN6_TX_C_DP<107>")
	)
	(segment
		(start 382.783334 -393.32027)
		(end 382.643888 -393.354814)
		(width 0.1651)
		(layer "In13.Cu")
		(net "P5E_PEX3_STN6_TX_C_DP<107>")
	)
	(segment
		(start 370.760498 -373.393716)
		(end 371.233446 -368.013996)
		(width 0.1651)
		(layer "In13.Cu")
		(net "P5E_PEX3_STN6_TX_C_DP<107>")
	)
	(segment
		(start 380.80569 -352.356166)
		(end 380.80569 -351.902268)
		(width 0.1651)
		(layer "In13.Cu")
		(net "P5E_PEX3_STN6_TX_C_DP<107>")
	)
	(segment
		(start 379.25121 -358.164384)
		(end 379.25121 -353.910646)
		(width 0.1651)
		(layer "In13.Cu")
		(net "P5E_PEX3_STN6_TX_C_DP<107>")
	)
	(segment
		(start 56.339486 -155.422854)
		(end 55.76951 -154.852878)
		(width 0.13208)
		(layer "F.Cu")
		(net "RST_NIC0_PERST0_R_N")
	)
	(segment
		(start 46.679866 -140.765022)
		(end 48.718978 -142.804134)
		(width 0.13208)
		(layer "F.Cu")
		(net "RST_NIC0_PERST0_R_N")
	)
	(segment
		(start 55.76951 -151.66594)
		(end 56.310022 -151.125428)
		(width 0.13208)
		(layer "F.Cu")
		(net "RST_NIC0_PERST0_R_N")
	)
	(segment
		(start 48.718978 -146.16684)
		(end 49.292002 -146.739864)
		(width 0.13208)
		(layer "F.Cu")
		(net "RST_NIC0_PERST0_R_N")
	)
	(segment
		(start 48.718978 -142.804134)
		(end 48.718978 -146.16684)
		(width 0.13208)
		(layer "F.Cu")
		(net "RST_NIC0_PERST0_R_N")
	)
	(segment
		(start 55.76951 -154.852878)
		(end 55.76951 -151.66594)
		(width 0.13208)
		(layer "F.Cu")
		(net "RST_NIC0_PERST0_R_N")
	)
	(segment
		(start 46.042326 -140.765022)
		(end 46.679866 -140.765022)
		(width 0.13208)
		(layer "F.Cu")
		(net "RST_NIC0_PERST0_R_N")
	)
	(via
		(at 56.310022 -151.125428)
		(size 0.508)
		(drill 0.254)
		(layers "F.Cu" "B.Cu")
		(net "RST_NIC0_PERST0_R_N")
	)
	(via
		(at 49.292002 -146.739864)
		(size 0.508)
		(drill 0.254)
		(layers "F.Cu" "B.Cu")
		(net "RST_NIC0_PERST0_R_N")
	)
	(segment
		(start 49.727866 -146.304)
		(end 51.129946 -146.304)
		(width 0.15494)
		(layer "In7.Cu")
		(net "RST_NIC0_PERST0_R_N")
	)
	(segment
		(start 49.292002 -146.739864)
		(end 49.727866 -146.304)
		(width 0.15494)
		(layer "In7.Cu")
		(net "RST_NIC0_PERST0_R_N")
	)
	(segment
		(start 56.310022 -150.620476)
		(end 56.310022 -151.125428)
		(width 0.15494)
		(layer "In7.Cu")
		(net "RST_NIC0_PERST0_R_N")
	)
	(segment
		(start 51.129946 -146.304)
		(end 51.5747 -146.748754)
		(width 0.15494)
		(layer "In7.Cu")
		(net "RST_NIC0_PERST0_R_N")
	)
	(segment
		(start 52.4383 -146.748754)
		(end 56.310022 -150.620476)
		(width 0.15494)
		(layer "In7.Cu")
		(net "RST_NIC0_PERST0_R_N")
	)
	(segment
		(start 51.5747 -146.748754)
		(end 52.4383 -146.748754)
		(width 0.15494)
		(layer "In7.Cu")
		(net "RST_NIC0_PERST0_R_N")
	)
	(segment
		(start 62.025276 -32.14878)
		(end 61.354716 -32.14878)
		(width 0.13462)
		(layer "F.Cu")
		(net "P5E_PEX0_STN2_RX_DN<38>")
	)
	(segment
		(start 62.184026 -31.99003)
		(end 62.025276 -32.14878)
		(width 0.13462)
		(layer "F.Cu")
		(net "P5E_PEX0_STN2_RX_DN<38>")
	)
	(segment
		(start 61.354716 -32.14878)
		(end 61.064648 -31.858712)
		(width 0.13462)
		(layer "F.Cu")
		(net "P5E_PEX0_STN2_RX_DN<38>")
	)
	(segment
		(start 62.664848 -31.99003)
		(end 62.184026 -31.99003)
		(width 0.13462)
		(layer "F.Cu")
		(net "P5E_PEX0_STN2_RX_DN<38>")
	)
	(segment
		(start 52.66563 -265.778234)
		(end 52.748688 -264.832084)
		(width 0.1651)
		(layer "In7.Cu")
		(net "P5E_PEX0_STN2_RX_DN<38>")
	)
	(segment
		(start 63.295784 -49.94275)
		(end 61.913008 -39.71036)
		(width 0.1651)
		(layer "In7.Cu")
		(net "P5E_PEX0_STN2_RX_DN<38>")
	)
	(segment
		(start 52.66563 -271.392904)
		(end 52.66563 -265.778234)
		(width 0.1651)
		(layer "In7.Cu")
		(net "P5E_PEX0_STN2_RX_DN<38>")
	)
	(segment
		(start 61.355478 -32.149542)
		(end 61.064648 -31.858712)
		(width 0.1651)
		(layer "In7.Cu")
		(net "P5E_PEX0_STN2_RX_DN<38>")
	)
	(segment
		(start 52.61991 -271.467072)
		(end 52.66563 -271.421352)
		(width 0.1143)
		(layer "In7.Cu")
		(net "P5E_PEX0_STN2_RX_DN<38>")
	)
	(segment
		(start 52.748688 -264.832084)
		(end 63.149734 -67.914266)
		(width 0.1651)
		(layer "In7.Cu")
		(net "P5E_PEX0_STN2_RX_DN<38>")
	)
	(segment
		(start 52.61991 -275.275802)
		(end 52.61991 -271.467072)
		(width 0.1143)
		(layer "In7.Cu")
		(net "P5E_PEX0_STN2_RX_DN<38>")
	)
	(segment
		(start 52.723796 -275.379688)
		(end 52.61991 -275.275802)
		(width 0.1143)
		(layer "In7.Cu")
		(net "P5E_PEX0_STN2_RX_DN<38>")
	)
	(segment
		(start 52.66563 -271.421352)
		(end 52.66563 -271.392904)
		(width 0.1143)
		(layer "In7.Cu")
		(net "P5E_PEX0_STN2_RX_DN<38>")
	)
	(segment
		(start 52.999894 -274.999958)
		(end 52.999894 -275.265388)
		(width 0.1143)
		(layer "In7.Cu")
		(net "P5E_PEX0_STN2_RX_DN<38>")
	)
	(segment
		(start 62.407292 -35.04819)
		(end 62.444376 -32.663638)
		(width 0.1651)
		(layer "In7.Cu")
		(net "P5E_PEX0_STN2_RX_DN<38>")
	)
	(segment
		(start 61.883798 -37.856414)
		(end 62.407292 -35.04819)
		(width 0.1651)
		(layer "In7.Cu")
		(net "P5E_PEX0_STN2_RX_DN<38>")
	)
	(segment
		(start 52.885594 -275.379688)
		(end 52.723796 -275.379688)
		(width 0.1143)
		(layer "In7.Cu")
		(net "P5E_PEX0_STN2_RX_DN<38>")
	)
	(segment
		(start 52.999894 -275.265388)
		(end 52.885594 -275.379688)
		(width 0.1143)
		(layer "In7.Cu")
		(net "P5E_PEX0_STN2_RX_DN<38>")
	)
	(segment
		(start 62.444376 -32.663638)
		(end 61.930026 -32.149542)
		(width 0.1651)
		(layer "In7.Cu")
		(net "P5E_PEX0_STN2_RX_DN<38>")
	)
	(segment
		(start 63.12281 -61.011308)
		(end 63.295784 -49.94275)
		(width 0.1651)
		(layer "In7.Cu")
		(net "P5E_PEX0_STN2_RX_DN<38>")
	)
	(segment
		(start 61.930026 -32.149542)
		(end 61.355478 -32.149542)
		(width 0.1651)
		(layer "In7.Cu")
		(net "P5E_PEX0_STN2_RX_DN<38>")
	)
	(segment
		(start 61.913008 -39.71036)
		(end 61.883798 -37.856414)
		(width 0.1651)
		(layer "In7.Cu")
		(net "P5E_PEX0_STN2_RX_DN<38>")
	)
	(segment
		(start 63.149734 -67.914266)
		(end 63.12281 -61.011308)
		(width 0.1651)
		(layer "In7.Cu")
		(net "P5E_PEX0_STN2_RX_DN<38>")
	)
	(segment
		(start 133.296406 -28.55468)
		(end 132.032756 -28.55468)
		(width 0.13462)
		(layer "F.Cu")
		(net "P5E_PEX1_STN2_TX_C_DN<44>")
	)
	(segment
		(start 133.625844 -28.225242)
		(end 133.296406 -28.55468)
		(width 0.13462)
		(layer "F.Cu")
		(net "P5E_PEX1_STN2_TX_C_DN<44>")
	)
	(segment
		(start 132.032756 -28.55468)
		(end 131.868164 -28.390088)
		(width 0.13462)
		(layer "F.Cu")
		(net "P5E_PEX1_STN2_TX_C_DN<44>")
	)
	(segment
		(start 131.868164 -28.390088)
		(end 131.36499 -28.390088)
		(width 0.13462)
		(layer "F.Cu")
		(net "P5E_PEX1_STN2_TX_C_DN<44>")
	)
	(segment
		(start 299.257212 -147.087336)
		(end 299.557948 -146.7866)
		(width 0.13462)
		(layer "F.Cu")
		(net "P5E_PEX2_STN0_RX_DP<10>")
	)
	(segment
		(start 299.557948 -146.7866)
		(end 300.2026 -146.7866)
		(width 0.13462)
		(layer "F.Cu")
		(net "P5E_PEX2_STN0_RX_DP<10>")
	)
	(segment
		(start 300.2026 -146.7866)
		(end 300.371002 -146.955002)
		(width 0.13462)
		(layer "F.Cu")
		(net "P5E_PEX2_STN0_RX_DP<10>")
	)
	(segment
		(start 300.371002 -146.955002)
		(end 300.857412 -146.955002)
		(width 0.13462)
		(layer "F.Cu")
		(net "P5E_PEX2_STN0_RX_DP<10>")
	)
	(segment
		(start 311.745376 -268.155928)
		(end 311.183782 -271.013428)
		(width 0.1651)
		(layer "In5.Cu")
		(net "P5E_PEX2_STN0_RX_DP<10>")
	)
	(segment
		(start 311.229502 -275.355304)
		(end 311.444386 -275.570188)
		(width 0.1143)
		(layer "In5.Cu")
		(net "P5E_PEX2_STN0_RX_DP<10>")
	)
	(segment
		(start 299.548042 -146.796506)
		(end 300.028864 -146.796506)
		(width 0.1651)
		(layer "In5.Cu")
		(net "P5E_PEX2_STN0_RX_DP<10>")
	)
	(segment
		(start 307.100986 -156.583888)
		(end 307.649118 -158.81731)
		(width 0.1651)
		(layer "In5.Cu")
		(net "P5E_PEX2_STN0_RX_DP<10>")
	)
	(segment
		(start 300.855126 -147.622768)
		(end 301.599854 -148.367496)
		(width 0.1651)
		(layer "In5.Cu")
		(net "P5E_PEX2_STN0_RX_DP<10>")
	)
	(segment
		(start 308.19725 -161.050732)
		(end 311.71007 -260.49986)
		(width 0.1651)
		(layer "In5.Cu")
		(net "P5E_PEX2_STN0_RX_DP<10>")
	)
	(segment
		(start 301.851822 -148.901658)
		(end 302.128428 -149.313138)
		(width 0.1651)
		(layer "In5.Cu")
		(net "P5E_PEX2_STN0_RX_DP<10>")
	)
	(segment
		(start 300.729396 -147.622768)
		(end 300.855126 -147.622768)
		(width 0.1651)
		(layer "In5.Cu")
		(net "P5E_PEX2_STN0_RX_DP<10>")
	)
	(segment
		(start 311.444386 -275.570188)
		(end 311.685178 -275.570188)
		(width 0.1143)
		(layer "In5.Cu")
		(net "P5E_PEX2_STN0_RX_DP<10>")
	)
	(segment
		(start 306.816506 -156.139388)
		(end 307.100986 -156.583888)
		(width 0.1651)
		(layer "In5.Cu")
		(net "P5E_PEX2_STN0_RX_DP<10>")
	)
	(segment
		(start 301.599854 -148.367496)
		(end 301.876206 -148.778468)
		(width 0.1651)
		(layer "In5.Cu")
		(net "P5E_PEX2_STN0_RX_DP<10>")
	)
	(segment
		(start 307.649118 -158.81731)
		(end 307.649118 -158.817564)
		(width 0.1651)
		(layer "In5.Cu")
		(net "P5E_PEX2_STN0_RX_DP<10>")
	)
	(segment
		(start 311.229502 -271.645126)
		(end 311.229502 -275.355304)
		(width 0.1143)
		(layer "In5.Cu")
		(net "P5E_PEX2_STN0_RX_DP<10>")
	)
	(segment
		(start 302.128428 -149.313138)
		(end 302.251872 -149.337268)
		(width 0.1651)
		(layer "In5.Cu")
		(net "P5E_PEX2_STN0_RX_DP<10>")
	)
	(segment
		(start 311.183782 -271.599406)
		(end 311.229502 -271.645126)
		(width 0.1143)
		(layer "In5.Cu")
		(net "P5E_PEX2_STN0_RX_DP<10>")
	)
	(segment
		(start 303.211992 -150.765256)
		(end 304.139346 -153.04135)
		(width 0.1651)
		(layer "In5.Cu")
		(net "P5E_PEX2_STN0_RX_DP<10>")
	)
	(segment
		(start 311.685178 -275.570188)
		(end 311.799478 -275.684488)
		(width 0.1143)
		(layer "In5.Cu")
		(net "P5E_PEX2_STN0_RX_DP<10>")
	)
	(segment
		(start 307.649118 -158.817564)
		(end 308.19725 -161.050732)
		(width 0.1651)
		(layer "In5.Cu")
		(net "P5E_PEX2_STN0_RX_DP<10>")
	)
	(segment
		(start 311.71007 -260.49986)
		(end 311.745376 -268.155928)
		(width 0.1651)
		(layer "In5.Cu")
		(net "P5E_PEX2_STN0_RX_DP<10>")
	)
	(segment
		(start 300.378876 -147.272248)
		(end 300.729396 -147.622768)
		(width 0.1651)
		(layer "In5.Cu")
		(net "P5E_PEX2_STN0_RX_DP<10>")
	)
	(segment
		(start 304.139346 -153.04135)
		(end 305.8668 -155.363164)
		(width 0.1651)
		(layer "In5.Cu")
		(net "P5E_PEX2_STN0_RX_DP<10>")
	)
	(segment
		(start 305.8668 -155.363164)
		(end 306.816506 -156.139388)
		(width 0.1651)
		(layer "In5.Cu")
		(net "P5E_PEX2_STN0_RX_DP<10>")
	)
	(segment
		(start 301.876206 -148.778468)
		(end 301.851822 -148.901658)
		(width 0.1651)
		(layer "In5.Cu")
		(net "P5E_PEX2_STN0_RX_DP<10>")
	)
	(segment
		(start 300.378876 -147.146518)
		(end 300.378876 -147.272248)
		(width 0.1651)
		(layer "In5.Cu")
		(net "P5E_PEX2_STN0_RX_DP<10>")
	)
	(segment
		(start 311.183782 -271.570958)
		(end 311.183782 -271.599406)
		(width 0.1143)
		(layer "In5.Cu")
		(net "P5E_PEX2_STN0_RX_DP<10>")
	)
	(segment
		(start 311.183782 -271.013428)
		(end 311.183782 -271.570958)
		(width 0.1651)
		(layer "In5.Cu")
		(net "P5E_PEX2_STN0_RX_DP<10>")
	)
	(segment
		(start 302.251872 -149.337268)
		(end 303.211992 -150.765256)
		(width 0.1651)
		(layer "In5.Cu")
		(net "P5E_PEX2_STN0_RX_DP<10>")
	)
	(segment
		(start 311.799478 -275.684488)
		(end 311.799478 -275.949918)
		(width 0.1143)
		(layer "In5.Cu")
		(net "P5E_PEX2_STN0_RX_DP<10>")
	)
	(segment
		(start 300.028864 -146.796506)
		(end 300.378876 -147.146518)
		(width 0.1651)
		(layer "In5.Cu")
		(net "P5E_PEX2_STN0_RX_DP<10>")
	)
	(segment
		(start 299.257212 -147.087336)
		(end 299.548042 -146.796506)
		(width 0.1651)
		(layer "In5.Cu")
		(net "P5E_PEX2_STN0_RX_DP<10>")
	)
	(segment
		(start 384.193288 -344.538554)
		(end 384.193288 -345.171014)
		(width 0.13462)
		(layer "F.Cu")
		(net "P5E_PEX3_STN6_TX_C_DN<106>")
	)
	(segment
		(start 384.51282 -344.219022)
		(end 384.193288 -344.538554)
		(width 0.13462)
		(layer "F.Cu")
		(net "P5E_PEX3_STN6_TX_C_DN<106>")
	)
	(segment
		(start 384.193288 -345.171014)
		(end 384.48742 -345.465146)
		(width 0.13462)
		(layer "F.Cu")
		(net "P5E_PEX3_STN6_TX_C_DN<106>")
	)
	(segment
		(start 374.34774 -366.022636)
		(end 372.440708 -368.55781)
		(width 0.1651)
		(layer "In13.Cu")
		(net "P5E_PEX3_STN6_TX_C_DN<106>")
	)
	(segment
		(start 372.440708 -368.55781)
		(end 372.031514 -373.377206)
		(width 0.1651)
		(layer "In13.Cu")
		(net "P5E_PEX3_STN6_TX_C_DN<106>")
	)
	(segment
		(start 381.9525 -359.45445)
		(end 374.34774 -366.022636)
		(width 0.1651)
		(layer "In13.Cu")
		(net "P5E_PEX3_STN6_TX_C_DN<106>")
	)
	(segment
		(start 385.37007 -393.111736)
		(end 385.992878 -393.4714)
		(width 0.1651)
		(layer "In13.Cu")
		(net "P5E_PEX3_STN6_TX_C_DN<106>")
	)
	(segment
		(start 387.615938 -409.629102)
		(end 387.164072 -410.080968)
		(width 0.1651)
		(layer "In13.Cu")
		(net "P5E_PEX3_STN6_TX_C_DN<106>")
	)
	(segment
		(start 385.992878 -393.4714)
		(end 386.932678 -394.3604)
		(width 0.1651)
		(layer "In13.Cu")
		(net "P5E_PEX3_STN6_TX_C_DN<106>")
	)
	(segment
		(start 384.808984 -392.787378)
		(end 384.913124 -392.759438)
		(width 0.1651)
		(layer "In13.Cu")
		(net "P5E_PEX3_STN6_TX_C_DN<106>")
	)
	(segment
		(start 381.420878 -390.8298)
		(end 384.808984 -392.787378)
		(width 0.1651)
		(layer "In13.Cu")
		(net "P5E_PEX3_STN6_TX_C_DN<106>")
	)
	(segment
		(start 385.34213 -393.007596)
		(end 385.37007 -393.111736)
		(width 0.1651)
		(layer "In13.Cu")
		(net "P5E_PEX3_STN6_TX_C_DN<106>")
	)
	(segment
		(start 387.164072 -410.080968)
		(end 386.616956 -410.080968)
		(width 0.1651)
		(layer "In13.Cu")
		(net "P5E_PEX3_STN6_TX_C_DN<106>")
	)
	(segment
		(start 372.031514 -373.377206)
		(end 372.48211 -385.024122)
		(width 0.1651)
		(layer "In13.Cu")
		(net "P5E_PEX3_STN6_TX_C_DN<106>")
	)
	(segment
		(start 382.64211 -347.881194)
		(end 382.64211 -357.947722)
		(width 0.1651)
		(layer "In13.Cu")
		(net "P5E_PEX3_STN6_TX_C_DN<106>")
	)
	(segment
		(start 384.48742 -345.465146)
		(end 384.19659 -345.755976)
		(width 0.1651)
		(layer "In13.Cu")
		(net "P5E_PEX3_STN6_TX_C_DN<106>")
	)
	(segment
		(start 384.19659 -345.755976)
		(end 384.19659 -346.326714)
		(width 0.1651)
		(layer "In13.Cu")
		(net "P5E_PEX3_STN6_TX_C_DN<106>")
	)
	(segment
		(start 386.932678 -394.3604)
		(end 387.615938 -396.1384)
		(width 0.1651)
		(layer "In13.Cu")
		(net "P5E_PEX3_STN6_TX_C_DN<106>")
	)
	(segment
		(start 386.489956 -410.207968)
		(end 386.489956 -410.589984)
		(width 0.1651)
		(layer "In13.Cu")
		(net "P5E_PEX3_STN6_TX_C_DN<106>")
	)
	(segment
		(start 386.616956 -410.080968)
		(end 386.489956 -410.207968)
		(width 0.1651)
		(layer "In13.Cu")
		(net "P5E_PEX3_STN6_TX_C_DN<106>")
	)
	(segment
		(start 387.615938 -396.1384)
		(end 387.615938 -409.629102)
		(width 0.1651)
		(layer "In13.Cu")
		(net "P5E_PEX3_STN6_TX_C_DN<106>")
	)
	(segment
		(start 372.48211 -385.024122)
		(end 373.147082 -386.68198)
		(width 0.1651)
		(layer "In13.Cu")
		(net "P5E_PEX3_STN6_TX_C_DN<106>")
	)
	(segment
		(start 384.19659 -346.326714)
		(end 382.64211 -347.881194)
		(width 0.1651)
		(layer "In13.Cu")
		(net "P5E_PEX3_STN6_TX_C_DN<106>")
	)
	(segment
		(start 382.64211 -357.947722)
		(end 381.9525 -359.45445)
		(width 0.1651)
		(layer "In13.Cu")
		(net "P5E_PEX3_STN6_TX_C_DN<106>")
	)
	(segment
		(start 384.913124 -392.759438)
		(end 385.34213 -393.007596)
		(width 0.1651)
		(layer "In13.Cu")
		(net "P5E_PEX3_STN6_TX_C_DN<106>")
	)
	(segment
		(start 375.466356 -388.281672)
		(end 381.420878 -390.8298)
		(width 0.1651)
		(layer "In13.Cu")
		(net "P5E_PEX3_STN6_TX_C_DN<106>")
	)
	(segment
		(start 373.147082 -386.68198)
		(end 375.466356 -388.281672)
		(width 0.1651)
		(layer "In13.Cu")
		(net "P5E_PEX3_STN6_TX_C_DN<106>")
	)
	(segment
		(start 51.456844 -154.759914)
		(end 51.655218 -154.958288)
		(width 0.13208)
		(layer "F.Cu")
		(net "NCSI_NIC0_TX_EN")
	)
	(segment
		(start 51.655218 -154.958288)
		(end 53.126132 -154.958288)
		(width 0.13208)
		(layer "F.Cu")
		(net "NCSI_NIC0_TX_EN")
	)
	(segment
		(start 50.64252 -154.759914)
		(end 51.456844 -154.759914)
		(width 0.13208)
		(layer "F.Cu")
		(net "NCSI_NIC0_TX_EN")
	)
	(via
		(at 53.126132 -154.958288)
		(size 0.508)
		(drill 0.254)
		(layers "F.Cu" "B.Cu")
		(net "NCSI_NIC0_TX_EN")
	)
	(segment
		(start 50.5206 -154.0256)
		(end 51.453288 -154.958288)
		(width 0.13208)
		(layer "B.Cu")
		(net "NCSI_NIC0_TX_EN")
	)
	(segment
		(start 49.95545 -154.0256)
		(end 50.5206 -154.0256)
		(width 0.13208)
		(layer "B.Cu")
		(net "NCSI_NIC0_TX_EN")
	)
	(segment
		(start 51.453288 -154.958288)
		(end 53.126132 -154.958288)
		(width 0.13208)
		(layer "B.Cu")
		(net "NCSI_NIC0_TX_EN")
	)
	(segment
		(start 293.65194 -25.390094)
		(end 294.86479 -25.390094)
		(width 0.13208)
		(layer "F.Cu")
		(net "PRSNT_SSD10_N")
	)
	(segment
		(start 293.10203 -25.940004)
		(end 293.65194 -25.390094)
		(width 0.13208)
		(layer "F.Cu")
		(net "PRSNT_SSD10_N")
	)
	(segment
		(start 293.10203 -26.266394)
		(end 292.320472 -26.266394)
		(width 0.13208)
		(layer "F.Cu")
		(net "PRSNT_SSD10_N")
	)
	(segment
		(start 293.10203 -26.266394)
		(end 293.10203 -25.940004)
		(width 0.13208)
		(layer "F.Cu")
		(net "PRSNT_SSD10_N")
	)
	(via
		(at 293.10203 -26.266394)
		(size 0.508)
		(drill 0.254)
		(layers "F.Cu" "B.Cu")
		(net "PRSNT_SSD10_N")
	)
	(segment
		(start 36.1823 -34.390076)
		(end 36.019486 -34.227262)
		(width 0.13462)
		(layer "F.Cu")
		(net "P5E_PEX0_STN2_RX_DP<43>")
	)
	(segment
		(start 36.6649 -34.390076)
		(end 36.1823 -34.390076)
		(width 0.13462)
		(layer "F.Cu")
		(net "P5E_PEX0_STN2_RX_DP<43>")
	)
	(segment
		(start 36.019486 -34.227262)
		(end 33.505648 -34.227262)
		(width 0.13462)
		(layer "F.Cu")
		(net "P5E_PEX0_STN2_RX_DP<43>")
	)
	(segment
		(start 33.505648 -34.227262)
		(end 33.2105 -34.52241)
		(width 0.13462)
		(layer "F.Cu")
		(net "P5E_PEX0_STN2_RX_DP<43>")
	)
	(segment
		(start 34.60623 -35.1028)
		(end 33.73501 -34.23158)
		(width 0.1651)
		(layer "In7.Cu")
		(net "P5E_PEX0_STN2_RX_DP<43>")
	)
	(segment
		(start 39.053516 -141.679676)
		(end 39.087552 -138.494516)
		(width 0.1651)
		(layer "In7.Cu")
		(net "P5E_PEX0_STN2_RX_DP<43>")
	)
	(segment
		(start 47.63389 -271.345152)
		(end 47.63389 -267.885926)
		(width 0.1651)
		(layer "In7.Cu")
		(net "P5E_PEX0_STN2_RX_DP<43>")
	)
	(segment
		(start 35.988498 -49.509426)
		(end 34.67481 -39.786052)
		(width 0.1651)
		(layer "In7.Cu")
		(net "P5E_PEX0_STN2_RX_DP<43>")
	)
	(segment
		(start 34.60623 -35.357562)
		(end 34.60623 -35.1028)
		(width 0.1651)
		(layer "In7.Cu")
		(net "P5E_PEX0_STN2_RX_DP<43>")
	)
	(segment
		(start 34.54781 -38.157404)
		(end 34.647886 -38.05428)
		(width 0.1651)
		(layer "In7.Cu")
		(net "P5E_PEX0_STN2_RX_DP<43>")
	)
	(segment
		(start 34.536888 -37.459158)
		(end 34.529268 -36.963604)
		(width 0.1651)
		(layer "In7.Cu")
		(net "P5E_PEX0_STN2_RX_DP<43>")
	)
	(segment
		(start 48.24984 -274.049744)
		(end 48.24984 -273.784314)
		(width 0.1143)
		(layer "In7.Cu")
		(net "P5E_PEX0_STN2_RX_DP<43>")
	)
	(segment
		(start 47.63389 -267.885926)
		(end 47.17542 -263.230106)
		(width 0.1651)
		(layer "In7.Cu")
		(net "P5E_PEX0_STN2_RX_DP<43>")
	)
	(segment
		(start 33.50133 -34.23158)
		(end 33.2105 -34.52241)
		(width 0.1651)
		(layer "In7.Cu")
		(net "P5E_PEX0_STN2_RX_DP<43>")
	)
	(segment
		(start 39.488872 -105.153714)
		(end 36.286694 -65.267332)
		(width 0.1651)
		(layer "In7.Cu")
		(net "P5E_PEX0_STN2_RX_DP<43>")
	)
	(segment
		(start 48.24984 -273.784314)
		(end 48.13554 -273.670014)
		(width 0.1143)
		(layer "In7.Cu")
		(net "P5E_PEX0_STN2_RX_DP<43>")
	)
	(segment
		(start 47.17542 -262.82015)
		(end 47.452788 -248.479818)
		(width 0.1651)
		(layer "In7.Cu")
		(net "P5E_PEX0_STN2_RX_DP<43>")
	)
	(segment
		(start 47.941992 -273.670014)
		(end 47.67961 -273.407632)
		(width 0.1143)
		(layer "In7.Cu")
		(net "P5E_PEX0_STN2_RX_DP<43>")
	)
	(segment
		(start 47.63389 -271.3736)
		(end 47.63389 -271.345152)
		(width 0.1143)
		(layer "In7.Cu")
		(net "P5E_PEX0_STN2_RX_DP<43>")
	)
	(segment
		(start 47.452788 -248.479818)
		(end 39.053516 -141.679676)
		(width 0.1651)
		(layer "In7.Cu")
		(net "P5E_PEX0_STN2_RX_DP<43>")
	)
	(segment
		(start 48.13554 -273.670014)
		(end 47.941992 -273.670014)
		(width 0.1143)
		(layer "In7.Cu")
		(net "P5E_PEX0_STN2_RX_DP<43>")
	)
	(segment
		(start 47.67961 -273.407632)
		(end 47.67961 -271.41932)
		(width 0.1143)
		(layer "In7.Cu")
		(net "P5E_PEX0_STN2_RX_DP<43>")
	)
	(segment
		(start 34.658808 -38.75278)
		(end 34.55543 -38.652704)
		(width 0.1651)
		(layer "In7.Cu")
		(net "P5E_PEX0_STN2_RX_DP<43>")
	)
	(segment
		(start 47.17542 -263.230106)
		(end 47.17542 -262.82015)
		(width 0.1651)
		(layer "In7.Cu")
		(net "P5E_PEX0_STN2_RX_DP<43>")
	)
	(segment
		(start 36.286694 -65.267332)
		(end 35.895026 -55.483252)
		(width 0.1651)
		(layer "In7.Cu")
		(net "P5E_PEX0_STN2_RX_DP<43>")
	)
	(segment
		(start 39.087552 -138.494516)
		(end 39.792656 -131.969002)
		(width 0.1651)
		(layer "In7.Cu")
		(net "P5E_PEX0_STN2_RX_DP<43>")
	)
	(segment
		(start 47.67961 -271.41932)
		(end 47.63389 -271.3736)
		(width 0.1143)
		(layer "In7.Cu")
		(net "P5E_PEX0_STN2_RX_DP<43>")
	)
	(segment
		(start 35.895026 -55.483252)
		(end 35.988498 -49.509426)
		(width 0.1651)
		(layer "In7.Cu")
		(net "P5E_PEX0_STN2_RX_DP<43>")
	)
	(segment
		(start 34.647886 -38.05428)
		(end 34.640266 -37.559234)
		(width 0.1651)
		(layer "In7.Cu")
		(net "P5E_PEX0_STN2_RX_DP<43>")
	)
	(segment
		(start 34.55543 -38.652704)
		(end 34.54781 -38.157404)
		(width 0.1651)
		(layer "In7.Cu")
		(net "P5E_PEX0_STN2_RX_DP<43>")
	)
	(segment
		(start 39.926006 -119.595392)
		(end 39.488872 -105.153714)
		(width 0.1651)
		(layer "In7.Cu")
		(net "P5E_PEX0_STN2_RX_DP<43>")
	)
	(segment
		(start 33.73501 -34.23158)
		(end 33.50133 -34.23158)
		(width 0.1651)
		(layer "In7.Cu")
		(net "P5E_PEX0_STN2_RX_DP<43>")
	)
	(segment
		(start 39.792656 -131.969002)
		(end 39.926006 -119.595392)
		(width 0.1651)
		(layer "In7.Cu")
		(net "P5E_PEX0_STN2_RX_DP<43>")
	)
	(segment
		(start 34.529268 -36.963604)
		(end 34.629344 -36.86048)
		(width 0.1651)
		(layer "In7.Cu")
		(net "P5E_PEX0_STN2_RX_DP<43>")
	)
	(segment
		(start 34.640266 -37.559234)
		(end 34.536888 -37.459158)
		(width 0.1651)
		(layer "In7.Cu")
		(net "P5E_PEX0_STN2_RX_DP<43>")
	)
	(segment
		(start 34.67481 -39.786052)
		(end 34.658808 -38.75278)
		(width 0.1651)
		(layer "In7.Cu")
		(net "P5E_PEX0_STN2_RX_DP<43>")
	)
	(segment
		(start 34.629344 -36.86048)
		(end 34.60623 -35.357562)
		(width 0.1651)
		(layer "In7.Cu")
		(net "P5E_PEX0_STN2_RX_DP<43>")
	)
	(segment
		(start 178.284124 -31.99003)
		(end 178.125374 -32.14878)
		(width 0.13462)
		(layer "F.Cu")
		(net "P5E_PEX1_STN2_RX_DN<38>")
	)
	(segment
		(start 178.764946 -31.99003)
		(end 178.284124 -31.99003)
		(width 0.13462)
		(layer "F.Cu")
		(net "P5E_PEX1_STN2_RX_DN<38>")
	)
	(segment
		(start 177.454814 -32.14878)
		(end 177.164746 -31.858712)
		(width 0.13462)
		(layer "F.Cu")
		(net "P5E_PEX1_STN2_RX_DN<38>")
	)
	(segment
		(start 178.125374 -32.14878)
		(end 177.454814 -32.14878)
		(width 0.13462)
		(layer "F.Cu")
		(net "P5E_PEX1_STN2_RX_DN<38>")
	)
	(segment
		(start 178.030124 -32.149542)
		(end 177.455576 -32.149542)
		(width 0.1651)
		(layer "In7.Cu")
		(net "P5E_PEX1_STN2_RX_DN<38>")
	)
	(segment
		(start 179.249832 -67.914266)
		(end 179.222908 -61.011308)
		(width 0.1651)
		(layer "In7.Cu")
		(net "P5E_PEX1_STN2_RX_DN<38>")
	)
	(segment
		(start 169.099992 -275.265388)
		(end 168.985692 -275.379688)
		(width 0.1143)
		(layer "In7.Cu")
		(net "P5E_PEX1_STN2_RX_DN<38>")
	)
	(segment
		(start 168.985692 -275.379688)
		(end 168.823894 -275.379688)
		(width 0.1143)
		(layer "In7.Cu")
		(net "P5E_PEX1_STN2_RX_DN<38>")
	)
	(segment
		(start 168.823894 -275.379688)
		(end 168.720008 -275.275802)
		(width 0.1143)
		(layer "In7.Cu")
		(net "P5E_PEX1_STN2_RX_DN<38>")
	)
	(segment
		(start 177.455576 -32.149542)
		(end 177.164746 -31.858712)
		(width 0.1651)
		(layer "In7.Cu")
		(net "P5E_PEX1_STN2_RX_DN<38>")
	)
	(segment
		(start 179.222908 -61.011308)
		(end 179.395882 -49.94275)
		(width 0.1651)
		(layer "In7.Cu")
		(net "P5E_PEX1_STN2_RX_DN<38>")
	)
	(segment
		(start 168.765728 -265.778234)
		(end 168.848786 -264.832084)
		(width 0.1651)
		(layer "In7.Cu")
		(net "P5E_PEX1_STN2_RX_DN<38>")
	)
	(segment
		(start 168.720008 -275.275802)
		(end 168.720008 -271.467072)
		(width 0.1143)
		(layer "In7.Cu")
		(net "P5E_PEX1_STN2_RX_DN<38>")
	)
	(segment
		(start 168.848786 -264.832084)
		(end 179.249832 -67.914266)
		(width 0.1651)
		(layer "In7.Cu")
		(net "P5E_PEX1_STN2_RX_DN<38>")
	)
	(segment
		(start 168.720008 -271.467072)
		(end 168.765728 -271.421352)
		(width 0.1143)
		(layer "In7.Cu")
		(net "P5E_PEX1_STN2_RX_DN<38>")
	)
	(segment
		(start 168.765728 -271.421352)
		(end 168.765728 -271.392904)
		(width 0.1143)
		(layer "In7.Cu")
		(net "P5E_PEX1_STN2_RX_DN<38>")
	)
	(segment
		(start 178.50739 -35.04819)
		(end 178.544474 -32.663638)
		(width 0.1651)
		(layer "In7.Cu")
		(net "P5E_PEX1_STN2_RX_DN<38>")
	)
	(segment
		(start 178.544474 -32.663638)
		(end 178.030124 -32.149542)
		(width 0.1651)
		(layer "In7.Cu")
		(net "P5E_PEX1_STN2_RX_DN<38>")
	)
	(segment
		(start 169.099992 -274.999958)
		(end 169.099992 -275.265388)
		(width 0.1143)
		(layer "In7.Cu")
		(net "P5E_PEX1_STN2_RX_DN<38>")
	)
	(segment
		(start 168.765728 -271.392904)
		(end 168.765728 -265.778234)
		(width 0.1651)
		(layer "In7.Cu")
		(net "P5E_PEX1_STN2_RX_DN<38>")
	)
	(segment
		(start 177.983896 -37.856414)
		(end 178.50739 -35.04819)
		(width 0.1651)
		(layer "In7.Cu")
		(net "P5E_PEX1_STN2_RX_DN<38>")
	)
	(segment
		(start 179.395882 -49.94275)
		(end 178.013106 -39.71036)
		(width 0.1651)
		(layer "In7.Cu")
		(net "P5E_PEX1_STN2_RX_DN<38>")
	)
	(segment
		(start 178.013106 -39.71036)
		(end 177.983896 -37.856414)
		(width 0.1651)
		(layer "In7.Cu")
		(net "P5E_PEX1_STN2_RX_DN<38>")
	)
	(segment
		(start 300.37786 -143.35506)
		(end 300.857412 -143.35506)
		(width 0.13462)
		(layer "F.Cu")
		(net "P5E_PEX2_STN0_RX_DP<8>")
	)
	(segment
		(start 299.257212 -143.48714)
		(end 299.564552 -143.1798)
		(width 0.13462)
		(layer "F.Cu")
		(net "P5E_PEX2_STN0_RX_DP<8>")
	)
	(segment
		(start 300.2026 -143.1798)
		(end 300.37786 -143.35506)
		(width 0.13462)
		(layer "F.Cu")
		(net "P5E_PEX2_STN0_RX_DP<8>")
	)
	(segment
		(start 299.564552 -143.1798)
		(end 300.2026 -143.1798)
		(width 0.13462)
		(layer "F.Cu")
		(net "P5E_PEX2_STN0_RX_DP<8>")
	)
	(segment
		(start 314.463176 -270.778986)
		(end 313.803538 -265.22934)
		(width 0.1651)
		(layer "In5.Cu")
		(net "P5E_PEX2_STN0_RX_DP<8>")
	)
	(segment
		(start 304.191416 -148.43125)
		(end 304.06848 -148.40458)
		(width 0.1651)
		(layer "In5.Cu")
		(net "P5E_PEX2_STN0_RX_DP<8>")
	)
	(segment
		(start 302.901096 -146.42211)
		(end 302.743108 -146.38782)
		(width 0.1651)
		(layer "In5.Cu")
		(net "P5E_PEX2_STN0_RX_DP<8>")
	)
	(segment
		(start 303.827434 -147.864576)
		(end 303.559972 -147.448016)
		(width 0.1651)
		(layer "In5.Cu")
		(net "P5E_PEX2_STN0_RX_DP<8>")
	)
	(segment
		(start 300.424088 -143.810482)
		(end 300.392592 -143.651986)
		(width 0.1651)
		(layer "In5.Cu")
		(net "P5E_PEX2_STN0_RX_DP<8>")
	)
	(segment
		(start 314.509912 -272.395188)
		(end 314.509912 -271.552162)
		(width 0.1651)
		(layer "In5.Cu")
		(net "P5E_PEX2_STN0_RX_DP<8>")
	)
	(segment
		(start 304.82286 -149.414484)
		(end 304.699924 -149.387814)
		(width 0.1651)
		(layer "In5.Cu")
		(net "P5E_PEX2_STN0_RX_DP<8>")
	)
	(segment
		(start 310.098186 -160.044384)
		(end 308.606698 -154.825954)
		(width 0.1651)
		(layer "In5.Cu")
		(net "P5E_PEX2_STN0_RX_DP<8>")
	)
	(segment
		(start 308.606698 -154.825954)
		(end 307.263546 -153.018744)
		(width 0.1651)
		(layer "In5.Cu")
		(net "P5E_PEX2_STN0_RX_DP<8>")
	)
	(segment
		(start 305.211734 -150.020528)
		(end 304.82286 -149.414484)
		(width 0.1651)
		(layer "In5.Cu")
		(net "P5E_PEX2_STN0_RX_DP<8>")
	)
	(segment
		(start 313.699906 -274.999704)
		(end 313.965336 -274.999704)
		(width 0.1143)
		(layer "In5.Cu")
		(net "P5E_PEX2_STN0_RX_DP<8>")
	)
	(segment
		(start 303.401984 -147.413726)
		(end 303.134268 -146.996658)
		(width 0.1651)
		(layer "In5.Cu")
		(net "P5E_PEX2_STN0_RX_DP<8>")
	)
	(segment
		(start 314.033916 -273.8628)
		(end 314.033916 -273.834352)
		(width 0.1143)
		(layer "In5.Cu")
		(net "P5E_PEX2_STN0_RX_DP<8>")
	)
	(segment
		(start 313.803538 -265.22934)
		(end 310.191404 -160.636966)
		(width 0.1651)
		(layer "In5.Cu")
		(net "P5E_PEX2_STN0_RX_DP<8>")
	)
	(segment
		(start 310.191404 -160.636966)
		(end 310.098186 -160.044384)
		(width 0.1651)
		(layer "In5.Cu")
		(net "P5E_PEX2_STN0_RX_DP<8>")
	)
	(segment
		(start 304.432208 -148.970746)
		(end 304.458878 -148.84781)
		(width 0.1651)
		(layer "In5.Cu")
		(net "P5E_PEX2_STN0_RX_DP<8>")
	)
	(segment
		(start 314.033916 -273.544538)
		(end 314.509912 -272.395188)
		(width 0.1651)
		(layer "In5.Cu")
		(net "P5E_PEX2_STN0_RX_DP<8>")
	)
	(segment
		(start 303.134268 -146.996658)
		(end 303.168558 -146.83867)
		(width 0.1651)
		(layer "In5.Cu")
		(net "P5E_PEX2_STN0_RX_DP<8>")
	)
	(segment
		(start 305.770534 -151.590248)
		(end 305.211734 -150.020528)
		(width 0.1651)
		(layer "In5.Cu")
		(net "P5E_PEX2_STN0_RX_DP<8>")
	)
	(segment
		(start 303.168558 -146.83867)
		(end 302.901096 -146.42211)
		(width 0.1651)
		(layer "In5.Cu")
		(net "P5E_PEX2_STN0_RX_DP<8>")
	)
	(segment
		(start 314.079636 -274.885404)
		(end 314.079636 -273.90852)
		(width 0.1143)
		(layer "In5.Cu")
		(net "P5E_PEX2_STN0_RX_DP<8>")
	)
	(segment
		(start 304.458878 -148.84781)
		(end 304.191416 -148.43125)
		(width 0.1651)
		(layer "In5.Cu")
		(net "P5E_PEX2_STN0_RX_DP<8>")
	)
	(segment
		(start 302.475392 -145.970752)
		(end 302.509682 -145.812764)
		(width 0.1651)
		(layer "In5.Cu")
		(net "P5E_PEX2_STN0_RX_DP<8>")
	)
	(segment
		(start 300.836076 -144.086072)
		(end 300.424088 -143.810482)
		(width 0.1651)
		(layer "In5.Cu")
		(net "P5E_PEX2_STN0_RX_DP<8>")
	)
	(segment
		(start 300.392592 -143.651986)
		(end 299.710602 -143.19631)
		(width 0.1651)
		(layer "In5.Cu")
		(net "P5E_PEX2_STN0_RX_DP<8>")
	)
	(segment
		(start 304.06848 -148.40458)
		(end 303.800764 -147.987512)
		(width 0.1651)
		(layer "In5.Cu")
		(net "P5E_PEX2_STN0_RX_DP<8>")
	)
	(segment
		(start 314.509912 -271.552162)
		(end 314.463176 -270.778986)
		(width 0.1651)
		(layer "In5.Cu")
		(net "P5E_PEX2_STN0_RX_DP<8>")
	)
	(segment
		(start 307.263546 -153.018744)
		(end 305.770534 -151.590248)
		(width 0.1651)
		(layer "In5.Cu")
		(net "P5E_PEX2_STN0_RX_DP<8>")
	)
	(segment
		(start 302.743108 -146.38782)
		(end 302.475392 -145.970752)
		(width 0.1651)
		(layer "In5.Cu")
		(net "P5E_PEX2_STN0_RX_DP<8>")
	)
	(segment
		(start 313.965336 -274.999704)
		(end 314.079636 -274.885404)
		(width 0.1143)
		(layer "In5.Cu")
		(net "P5E_PEX2_STN0_RX_DP<8>")
	)
	(segment
		(start 304.699924 -149.387814)
		(end 304.432208 -148.970746)
		(width 0.1651)
		(layer "In5.Cu")
		(net "P5E_PEX2_STN0_RX_DP<8>")
	)
	(segment
		(start 299.548042 -143.19631)
		(end 299.257212 -143.48714)
		(width 0.1651)
		(layer "In5.Cu")
		(net "P5E_PEX2_STN0_RX_DP<8>")
	)
	(segment
		(start 301.67072 -144.506188)
		(end 300.994572 -144.054322)
		(width 0.1651)
		(layer "In5.Cu")
		(net "P5E_PEX2_STN0_RX_DP<8>")
	)
	(segment
		(start 303.800764 -147.987512)
		(end 303.827434 -147.864576)
		(width 0.1651)
		(layer "In5.Cu")
		(net "P5E_PEX2_STN0_RX_DP<8>")
	)
	(segment
		(start 314.079636 -273.90852)
		(end 314.033916 -273.8628)
		(width 0.1143)
		(layer "In5.Cu")
		(net "P5E_PEX2_STN0_RX_DP<8>")
	)
	(segment
		(start 314.033916 -273.834352)
		(end 314.033916 -273.544538)
		(width 0.1651)
		(layer "In5.Cu")
		(net "P5E_PEX2_STN0_RX_DP<8>")
	)
	(segment
		(start 300.994572 -144.054322)
		(end 300.836076 -144.086072)
		(width 0.1651)
		(layer "In5.Cu")
		(net "P5E_PEX2_STN0_RX_DP<8>")
	)
	(segment
		(start 302.509682 -145.812764)
		(end 301.67072 -144.506188)
		(width 0.1651)
		(layer "In5.Cu")
		(net "P5E_PEX2_STN0_RX_DP<8>")
	)
	(segment
		(start 303.559972 -147.448016)
		(end 303.401984 -147.413726)
		(width 0.1651)
		(layer "In5.Cu")
		(net "P5E_PEX2_STN0_RX_DP<8>")
	)
	(segment
		(start 299.710602 -143.19631)
		(end 299.548042 -143.19631)
		(width 0.1651)
		(layer "In5.Cu")
		(net "P5E_PEX2_STN0_RX_DP<8>")
	)
	(segment
		(start 381.084328 -344.538554)
		(end 381.084328 -345.171014)
		(width 0.13462)
		(layer "F.Cu")
		(net "P5E_PEX3_STN6_TX_C_DN<99>")
	)
	(segment
		(start 381.084328 -345.171014)
		(end 381.37846 -345.465146)
		(width 0.13462)
		(layer "F.Cu")
		(net "P5E_PEX3_STN6_TX_C_DN<99>")
	)
	(segment
		(start 381.40386 -344.219022)
		(end 381.084328 -344.538554)
		(width 0.13462)
		(layer "F.Cu")
		(net "P5E_PEX3_STN6_TX_C_DN<99>")
	)
	(segment
		(start 379.53315 -358.450896)
		(end 379.53315 -347.881194)
		(width 0.1651)
		(layer "In7.Cu")
		(net "P5E_PEX3_STN6_TX_C_DN<99>")
	)
	(segment
		(start 384.290062 -383.490216)
		(end 384.290062 -383.1082)
		(width 0.1651)
		(layer "In7.Cu")
		(net "P5E_PEX3_STN6_TX_C_DN<99>")
	)
	(segment
		(start 385.416044 -368.717576)
		(end 379.53315 -358.450896)
		(width 0.1651)
		(layer "In7.Cu")
		(net "P5E_PEX3_STN6_TX_C_DN<99>")
	)
	(segment
		(start 381.08763 -346.326714)
		(end 381.08763 -345.755976)
		(width 0.1651)
		(layer "In7.Cu")
		(net "P5E_PEX3_STN6_TX_C_DN<99>")
	)
	(segment
		(start 381.08763 -345.755976)
		(end 381.37846 -345.465146)
		(width 0.1651)
		(layer "In7.Cu")
		(net "P5E_PEX3_STN6_TX_C_DN<99>")
	)
	(segment
		(start 384.964178 -382.9812)
		(end 385.416044 -382.529334)
		(width 0.1651)
		(layer "In7.Cu")
		(net "P5E_PEX3_STN6_TX_C_DN<99>")
	)
	(segment
		(start 379.53315 -347.881194)
		(end 381.08763 -346.326714)
		(width 0.1651)
		(layer "In7.Cu")
		(net "P5E_PEX3_STN6_TX_C_DN<99>")
	)
	(segment
		(start 385.416044 -382.529334)
		(end 385.416044 -368.717576)
		(width 0.1651)
		(layer "In7.Cu")
		(net "P5E_PEX3_STN6_TX_C_DN<99>")
	)
	(segment
		(start 384.290062 -383.1082)
		(end 384.417062 -382.9812)
		(width 0.1651)
		(layer "In7.Cu")
		(net "P5E_PEX3_STN6_TX_C_DN<99>")
	)
	(segment
		(start 384.417062 -382.9812)
		(end 384.964178 -382.9812)
		(width 0.1651)
		(layer "In7.Cu")
		(net "P5E_PEX3_STN6_TX_C_DN<99>")
	)
	(segment
		(start 39.16045 -116.7384)
		(end 39.16045 -117.7544)
		(width 0.13208)
		(layer "F.Cu")
		(net "PRSNTB0_NIC0_N")
	)
	(segment
		(start 40.39108 -118.154958)
		(end 39.561008 -118.154958)
		(width 0.13208)
		(layer "F.Cu")
		(net "PRSNTB0_NIC0_N")
	)
	(segment
		(start 39.561008 -118.154958)
		(end 39.16045 -117.7544)
		(width 0.13208)
		(layer "F.Cu")
		(net "PRSNTB0_NIC0_N")
	)
	(segment
		(start 46.042326 -118.154958)
		(end 40.39108 -118.154958)
		(width 0.13208)
		(layer "F.Cu")
		(net "PRSNTB0_NIC0_N")
	)
	(via
		(at 40.39108 -118.154958)
		(size 0.762)
		(drill 0.381)
		(layers "F.Cu" "B.Cu")
		(net "PRSNTB0_NIC0_N")
	)
	(segment
		(start 211.625688 -31.825184)
		(end 211.314792 -32.13608)
		(width 0.13462)
		(layer "F.Cu")
		(net "P5E_PEX1_STN2_TX_C_DN<34>")
	)
	(segment
		(start 211.314792 -32.13608)
		(end 210.014058 -32.13608)
		(width 0.13462)
		(layer "F.Cu")
		(net "P5E_PEX1_STN2_TX_C_DN<34>")
	)
	(segment
		(start 210.014058 -32.13608)
		(end 209.868008 -31.99003)
		(width 0.13462)
		(layer "F.Cu")
		(net "P5E_PEX1_STN2_TX_C_DN<34>")
	)
	(segment
		(start 209.868008 -31.99003)
		(end 209.364834 -31.99003)
		(width 0.13462)
		(layer "F.Cu")
		(net "P5E_PEX1_STN2_TX_C_DN<34>")
	)
	(segment
		(start 314.272676 -132.00888)
		(end 306.128166 -132.00888)
		(width 0.13462)
		(layer "F.Cu")
		(net "P5E_PEX2_STN0_TX_C_DN<5>")
	)
	(segment
		(start 314.594748 -131.686808)
		(end 314.272676 -132.00888)
		(width 0.13462)
		(layer "F.Cu")
		(net "P5E_PEX2_STN0_TX_C_DN<5>")
	)
	(segment
		(start 305.964336 -131.84505)
		(end 305.457606 -131.84505)
		(width 0.13462)
		(layer "F.Cu")
		(net "P5E_PEX2_STN0_TX_C_DN<5>")
	)
	(segment
		(start 306.128166 -132.00888)
		(end 305.964336 -131.84505)
		(width 0.13462)
		(layer "F.Cu")
		(net "P5E_PEX2_STN0_TX_C_DN<5>")
	)
	(segment
		(start 393.7 -316.115192)
		(end 393.5857 -316.229492)
		(width 0.1143)
		(layer "In15.Cu")
		(net "P5E_PEX3_STN6_RX_DP<109>")
	)
	(segment
		(start 370.428266 -388.641336)
		(end 373.62257 -391.006838)
		(width 0.1651)
		(layer "In15.Cu")
		(net "P5E_PEX3_STN6_RX_DP<109>")
	)
	(segment
		(start 368.924332 -342.16848)
		(end 368.652552 -371.382544)
		(width 0.1651)
		(layer "In15.Cu")
		(net "P5E_PEX3_STN6_RX_DP<109>")
	)
	(segment
		(start 392.805412 -321.338956)
		(end 390.32815 -323.89572)
		(width 0.1651)
		(layer "In15.Cu")
		(net "P5E_PEX3_STN6_RX_DP<109>")
	)
	(segment
		(start 380.01702 -400.899122)
		(end 379.89002 -400.772122)
		(width 0.1651)
		(layer "In15.Cu")
		(net "P5E_PEX3_STN6_RX_DP<109>")
	)
	(segment
		(start 380.734062 -400.612356)
		(end 380.447296 -400.899122)
		(width 0.1651)
		(layer "In15.Cu")
		(net "P5E_PEX3_STN6_RX_DP<109>")
	)
	(segment
		(start 378.842524 -393.77239)
		(end 378.881894 -393.929108)
		(width 0.1651)
		(layer "In15.Cu")
		(net "P5E_PEX3_STN6_RX_DP<109>")
	)
	(segment
		(start 375.704608 -391.894568)
		(end 377.796298 -393.14628)
		(width 0.1651)
		(layer "In15.Cu")
		(net "P5E_PEX3_STN6_RX_DP<109>")
	)
	(segment
		(start 379.30709 -394.183616)
		(end 379.464062 -394.144246)
		(width 0.1651)
		(layer "In15.Cu")
		(net "P5E_PEX3_STN6_RX_DP<109>")
	)
	(segment
		(start 380.528068 -394.781024)
		(end 380.734062 -395.167612)
		(width 0.1651)
		(layer "In15.Cu")
		(net "P5E_PEX3_STN6_RX_DP<109>")
	)
	(segment
		(start 393.344908 -316.229492)
		(end 393.12977 -316.44463)
		(width 0.1143)
		(layer "In15.Cu")
		(net "P5E_PEX3_STN6_RX_DP<109>")
	)
	(segment
		(start 370.021866 -340.167722)
		(end 368.980212 -341.88654)
		(width 0.1651)
		(layer "In15.Cu")
		(net "P5E_PEX3_STN6_RX_DP<109>")
	)
	(segment
		(start 393.5857 -316.229492)
		(end 393.344908 -316.229492)
		(width 0.1143)
		(layer "In15.Cu")
		(net "P5E_PEX3_STN6_RX_DP<109>")
	)
	(segment
		(start 393.12977 -319.921128)
		(end 393.08405 -319.966848)
		(width 0.1143)
		(layer "In15.Cu")
		(net "P5E_PEX3_STN6_RX_DP<109>")
	)
	(segment
		(start 393.08405 -319.995296)
		(end 393.08405 -320.665856)
		(width 0.1651)
		(layer "In15.Cu")
		(net "P5E_PEX3_STN6_RX_DP<109>")
	)
	(segment
		(start 380.447296 -400.899122)
		(end 380.01702 -400.899122)
		(width 0.1651)
		(layer "In15.Cu")
		(net "P5E_PEX3_STN6_RX_DP<109>")
	)
	(segment
		(start 377.835668 -393.302998)
		(end 378.260864 -393.557506)
		(width 0.1651)
		(layer "In15.Cu")
		(net "P5E_PEX3_STN6_RX_DP<109>")
	)
	(segment
		(start 373.62257 -391.006838)
		(end 375.704608 -391.894568)
		(width 0.1651)
		(layer "In15.Cu")
		(net "P5E_PEX3_STN6_RX_DP<109>")
	)
	(segment
		(start 369.245134 -385.741418)
		(end 370.428266 -388.641336)
		(width 0.1651)
		(layer "In15.Cu")
		(net "P5E_PEX3_STN6_RX_DP<109>")
	)
	(segment
		(start 393.12977 -316.44463)
		(end 393.12977 -319.921128)
		(width 0.1143)
		(layer "In15.Cu")
		(net "P5E_PEX3_STN6_RX_DP<109>")
	)
	(segment
		(start 378.881894 -393.929108)
		(end 379.30709 -394.183616)
		(width 0.1651)
		(layer "In15.Cu")
		(net "P5E_PEX3_STN6_RX_DP<109>")
	)
	(segment
		(start 378.260864 -393.557506)
		(end 378.417582 -393.518136)
		(width 0.1651)
		(layer "In15.Cu")
		(net "P5E_PEX3_STN6_RX_DP<109>")
	)
	(segment
		(start 390.32815 -323.89572)
		(end 370.021866 -340.167722)
		(width 0.1651)
		(layer "In15.Cu")
		(net "P5E_PEX3_STN6_RX_DP<109>")
	)
	(segment
		(start 379.89002 -400.772122)
		(end 379.89002 -400.390106)
		(width 0.1651)
		(layer "In15.Cu")
		(net "P5E_PEX3_STN6_RX_DP<109>")
	)
	(segment
		(start 377.796298 -393.14628)
		(end 377.835668 -393.302998)
		(width 0.1651)
		(layer "In15.Cu")
		(net "P5E_PEX3_STN6_RX_DP<109>")
	)
	(segment
		(start 379.464062 -394.144246)
		(end 380.528068 -394.781024)
		(width 0.1651)
		(layer "In15.Cu")
		(net "P5E_PEX3_STN6_RX_DP<109>")
	)
	(segment
		(start 393.7 -315.849762)
		(end 393.7 -316.115192)
		(width 0.1143)
		(layer "In15.Cu")
		(net "P5E_PEX3_STN6_RX_DP<109>")
	)
	(segment
		(start 378.417582 -393.518136)
		(end 378.842524 -393.77239)
		(width 0.1651)
		(layer "In15.Cu")
		(net "P5E_PEX3_STN6_RX_DP<109>")
	)
	(segment
		(start 393.08405 -319.966848)
		(end 393.08405 -319.995296)
		(width 0.1143)
		(layer "In15.Cu")
		(net "P5E_PEX3_STN6_RX_DP<109>")
	)
	(segment
		(start 380.734062 -395.167612)
		(end 380.734062 -400.612356)
		(width 0.1651)
		(layer "In15.Cu")
		(net "P5E_PEX3_STN6_RX_DP<109>")
	)
	(segment
		(start 368.980212 -341.88654)
		(end 368.924332 -342.16848)
		(width 0.1651)
		(layer "In15.Cu")
		(net "P5E_PEX3_STN6_RX_DP<109>")
	)
	(segment
		(start 393.08405 -320.665856)
		(end 392.805412 -321.338956)
		(width 0.1651)
		(layer "In15.Cu")
		(net "P5E_PEX3_STN6_RX_DP<109>")
	)
	(segment
		(start 368.652552 -371.382544)
		(end 369.245134 -385.741418)
		(width 0.1651)
		(layer "In15.Cu")
		(net "P5E_PEX3_STN6_RX_DP<109>")
	)
	(segment
		(start 52.044346 -159.3088)
		(end 51.095656 -158.36011)
		(width 0.13208)
		(layer "F.Cu")
		(net "RST_NIC0_PERST2_R_N")
	)
	(segment
		(start 51.095656 -158.36011)
		(end 50.64252 -158.36011)
		(width 0.13208)
		(layer "F.Cu")
		(net "RST_NIC0_PERST2_R_N")
	)
	(segment
		(start 54.356 -158.8516)
		(end 53.9496 -158.8516)
		(width 0.13208)
		(layer "F.Cu")
		(net "RST_NIC0_PERST2_R_N")
	)
	(segment
		(start 53.4924 -159.3088)
		(end 52.044346 -159.3088)
		(width 0.13208)
		(layer "F.Cu")
		(net "RST_NIC0_PERST2_R_N")
	)
	(segment
		(start 55.58155 -158.8516)
		(end 54.356 -158.8516)
		(width 0.13208)
		(layer "F.Cu")
		(net "RST_NIC0_PERST2_R_N")
	)
	(segment
		(start 53.9496 -158.8516)
		(end 53.4924 -159.3088)
		(width 0.13208)
		(layer "F.Cu")
		(net "RST_NIC0_PERST2_R_N")
	)
	(via
		(at 54.356 -158.8516)
		(size 0.762)
		(drill 0.381)
		(layers "F.Cu" "B.Cu")
		(net "RST_NIC0_PERST2_R_N")
	)
	(segment
		(start 126.284228 -28.390088)
		(end 126.119636 -28.55468)
		(width 0.13462)
		(layer "F.Cu")
		(net "P5E_PEX1_STN2_RX_DN<44>")
	)
	(segment
		(start 125.46076 -28.55468)
		(end 125.16485 -28.25877)
		(width 0.13462)
		(layer "F.Cu")
		(net "P5E_PEX1_STN2_RX_DN<44>")
	)
	(segment
		(start 126.119636 -28.55468)
		(end 125.46076 -28.55468)
		(width 0.13462)
		(layer "F.Cu")
		(net "P5E_PEX1_STN2_RX_DN<44>")
	)
	(segment
		(start 126.76505 -28.390088)
		(end 126.284228 -28.390088)
		(width 0.13462)
		(layer "F.Cu")
		(net "P5E_PEX1_STN2_RX_DN<44>")
	)
	(segment
		(start 125.463808 -28.5496)
		(end 125.90399 -28.5496)
		(width 0.1651)
		(layer "In7.Cu")
		(net "P5E_PEX1_STN2_RX_DN<44>")
	)
	(segment
		(start 163.399978 -275.265388)
		(end 163.399978 -274.999958)
		(width 0.1143)
		(layer "In7.Cu")
		(net "P5E_PEX1_STN2_RX_DN<44>")
	)
	(segment
		(start 129.406904 -61.851032)
		(end 129.217928 -85.173566)
		(width 0.1651)
		(layer "In7.Cu")
		(net "P5E_PEX1_STN2_RX_DN<44>")
	)
	(segment
		(start 129.217928 -85.173566)
		(end 139.57681 -119.34952)
		(width 0.1651)
		(layer "In7.Cu")
		(net "P5E_PEX1_STN2_RX_DN<44>")
	)
	(segment
		(start 125.16485 -28.25877)
		(end 125.457966 -28.551886)
		(width 0.1651)
		(layer "In7.Cu")
		(net "P5E_PEX1_STN2_RX_DN<44>")
	)
	(segment
		(start 163.285678 -275.379688)
		(end 163.399978 -275.265388)
		(width 0.1143)
		(layer "In7.Cu")
		(net "P5E_PEX1_STN2_RX_DN<44>")
	)
	(segment
		(start 127.479298 -30.4546)
		(end 129.042922 -32.018224)
		(width 0.1651)
		(layer "In7.Cu")
		(net "P5E_PEX1_STN2_RX_DN<44>")
	)
	(segment
		(start 163.065714 -269.50162)
		(end 163.065714 -271.392904)
		(width 0.1651)
		(layer "In7.Cu")
		(net "P5E_PEX1_STN2_RX_DN<44>")
	)
	(segment
		(start 129.13741 -57.32399)
		(end 129.406904 -60.059824)
		(width 0.1651)
		(layer "In7.Cu")
		(net "P5E_PEX1_STN2_RX_DN<44>")
	)
	(segment
		(start 131.4069 -39.16934)
		(end 129.260854 -49.41951)
		(width 0.1651)
		(layer "In7.Cu")
		(net "P5E_PEX1_STN2_RX_DN<44>")
	)
	(segment
		(start 160.58134 -238.036354)
		(end 162.189922 -255.60782)
		(width 0.1651)
		(layer "In7.Cu")
		(net "P5E_PEX1_STN2_RX_DN<44>")
	)
	(segment
		(start 163.019994 -275.275802)
		(end 163.12388 -275.379688)
		(width 0.1143)
		(layer "In7.Cu")
		(net "P5E_PEX1_STN2_RX_DN<44>")
	)
	(segment
		(start 125.457966 -28.551886)
		(end 125.463808 -28.5496)
		(width 0.1651)
		(layer "In7.Cu")
		(net "P5E_PEX1_STN2_RX_DN<44>")
	)
	(segment
		(start 163.12388 -275.379688)
		(end 163.285678 -275.379688)
		(width 0.1143)
		(layer "In7.Cu")
		(net "P5E_PEX1_STN2_RX_DN<44>")
	)
	(segment
		(start 126.815088 -29.460698)
		(end 127.479298 -30.4546)
		(width 0.1651)
		(layer "In7.Cu")
		(net "P5E_PEX1_STN2_RX_DN<44>")
	)
	(segment
		(start 131.431538 -37.688012)
		(end 131.4069 -39.16934)
		(width 0.1651)
		(layer "In7.Cu")
		(net "P5E_PEX1_STN2_RX_DN<44>")
	)
	(segment
		(start 129.406904 -60.059824)
		(end 129.406904 -61.851032)
		(width 0.1651)
		(layer "In7.Cu")
		(net "P5E_PEX1_STN2_RX_DN<44>")
	)
	(segment
		(start 163.065714 -271.392904)
		(end 163.065714 -271.421352)
		(width 0.1143)
		(layer "In7.Cu")
		(net "P5E_PEX1_STN2_RX_DN<44>")
	)
	(segment
		(start 129.042922 -32.018224)
		(end 131.431538 -37.688012)
		(width 0.1651)
		(layer "In7.Cu")
		(net "P5E_PEX1_STN2_RX_DN<44>")
	)
	(segment
		(start 162.189922 -255.60782)
		(end 162.11296 -263.459722)
		(width 0.1651)
		(layer "In7.Cu")
		(net "P5E_PEX1_STN2_RX_DN<44>")
	)
	(segment
		(start 142.865856 -144.353534)
		(end 160.58134 -238.036354)
		(width 0.1651)
		(layer "In7.Cu")
		(net "P5E_PEX1_STN2_RX_DN<44>")
	)
	(segment
		(start 163.019994 -271.467072)
		(end 163.019994 -275.275802)
		(width 0.1143)
		(layer "In7.Cu")
		(net "P5E_PEX1_STN2_RX_DN<44>")
	)
	(segment
		(start 139.57681 -119.34952)
		(end 142.865856 -144.353534)
		(width 0.1651)
		(layer "In7.Cu")
		(net "P5E_PEX1_STN2_RX_DN<44>")
	)
	(segment
		(start 163.065714 -271.421352)
		(end 163.019994 -271.467072)
		(width 0.1143)
		(layer "In7.Cu")
		(net "P5E_PEX1_STN2_RX_DN<44>")
	)
	(segment
		(start 125.90399 -28.5496)
		(end 126.815088 -29.460698)
		(width 0.1651)
		(layer "In7.Cu")
		(net "P5E_PEX1_STN2_RX_DN<44>")
	)
	(segment
		(start 129.260854 -49.41951)
		(end 129.13741 -57.32399)
		(width 0.1651)
		(layer "In7.Cu")
		(net "P5E_PEX1_STN2_RX_DN<44>")
	)
	(segment
		(start 162.11296 -263.459722)
		(end 163.065714 -269.50162)
		(width 0.1651)
		(layer "In7.Cu")
		(net "P5E_PEX1_STN2_RX_DN<44>")
	)
	(segment
		(start 300.208442 -130.2131)
		(end 299.556678 -130.2131)
		(width 0.13462)
		(layer "F.Cu")
		(net "P5E_PEX2_STN0_RX_DN<4>")
	)
	(segment
		(start 300.37659 -130.044952)
		(end 300.208442 -130.2131)
		(width 0.13462)
		(layer "F.Cu")
		(net "P5E_PEX2_STN0_RX_DN<4>")
	)
	(segment
		(start 300.857412 -130.044952)
		(end 300.37659 -130.044952)
		(width 0.13462)
		(layer "F.Cu")
		(net "P5E_PEX2_STN0_RX_DN<4>")
	)
	(segment
		(start 299.556678 -130.2131)
		(end 299.257212 -129.913634)
		(width 0.13462)
		(layer "F.Cu")
		(net "P5E_PEX2_STN0_RX_DN<4>")
	)
	(segment
		(start 327.975468 -269.73022)
		(end 319.546224 -240.890298)
		(width 0.1651)
		(layer "In5.Cu")
		(net "P5E_PEX2_STN0_RX_DN<4>")
	)
	(segment
		(start 299.548042 -130.204464)
		(end 299.257212 -129.913634)
		(width 0.1651)
		(layer "In5.Cu")
		(net "P5E_PEX2_STN0_RX_DN<4>")
	)
	(segment
		(start 311.531254 -139.993624)
		(end 310.769508 -138.063478)
		(width 0.1651)
		(layer "In5.Cu")
		(net "P5E_PEX2_STN0_RX_DN<4>")
	)
	(segment
		(start 319.546224 -240.890298)
		(end 317.670688 -232.2322)
		(width 0.1651)
		(layer "In5.Cu")
		(net "P5E_PEX2_STN0_RX_DN<4>")
	)
	(segment
		(start 306.161186 -133.472428)
		(end 299.976286 -130.204464)
		(width 0.1651)
		(layer "In5.Cu")
		(net "P5E_PEX2_STN0_RX_DN<4>")
	)
	(segment
		(start 318.272414 -168.331642)
		(end 317.905384 -151.490172)
		(width 0.1651)
		(layer "In5.Cu")
		(net "P5E_PEX2_STN0_RX_DN<4>")
	)
	(segment
		(start 312.678064 -147.649184)
		(end 311.531254 -139.993624)
		(width 0.1651)
		(layer "In5.Cu")
		(net "P5E_PEX2_STN0_RX_DN<4>")
	)
	(segment
		(start 312.484262 -284.499812)
		(end 312.369962 -284.385512)
		(width 0.1143)
		(layer "In5.Cu")
		(net "P5E_PEX2_STN0_RX_DN<4>")
	)
	(segment
		(start 312.50255 -284.120082)
		(end 316.050422 -284.120082)
		(width 0.1143)
		(layer "In5.Cu")
		(net "P5E_PEX2_STN0_RX_DN<4>")
	)
	(segment
		(start 317.238888 -284.165802)
		(end 318.33185 -283.398722)
		(width 0.1651)
		(layer "In5.Cu")
		(net "P5E_PEX2_STN0_RX_DN<4>")
	)
	(segment
		(start 310.769508 -138.063478)
		(end 309.957978 -136.865868)
		(width 0.1651)
		(layer "In5.Cu")
		(net "P5E_PEX2_STN0_RX_DN<4>")
	)
	(segment
		(start 314.182252 -148.287486)
		(end 314.182252 -148.28774)
		(width 0.1651)
		(layer "In5.Cu")
		(net "P5E_PEX2_STN0_RX_DN<4>")
	)
	(segment
		(start 317.905384 -151.490172)
		(end 317.540132 -150.649178)
		(width 0.1651)
		(layer "In5.Cu")
		(net "P5E_PEX2_STN0_RX_DN<4>")
	)
	(segment
		(start 317.670688 -232.2322)
		(end 318.272414 -168.331642)
		(width 0.1651)
		(layer "In5.Cu")
		(net "P5E_PEX2_STN0_RX_DN<4>")
	)
	(segment
		(start 299.976286 -130.204464)
		(end 299.548042 -130.204464)
		(width 0.1651)
		(layer "In5.Cu")
		(net "P5E_PEX2_STN0_RX_DN<4>")
	)
	(segment
		(start 316.050422 -284.120082)
		(end 316.096142 -284.165802)
		(width 0.1143)
		(layer "In5.Cu")
		(net "P5E_PEX2_STN0_RX_DN<4>")
	)
	(segment
		(start 316.096142 -284.165802)
		(end 316.12459 -284.165802)
		(width 0.1143)
		(layer "In5.Cu")
		(net "P5E_PEX2_STN0_RX_DN<4>")
	)
	(segment
		(start 318.33185 -283.398722)
		(end 325.917306 -276.06625)
		(width 0.1651)
		(layer "In5.Cu")
		(net "P5E_PEX2_STN0_RX_DN<4>")
	)
	(segment
		(start 325.917306 -276.06625)
		(end 327.875392 -272.573242)
		(width 0.1651)
		(layer "In5.Cu")
		(net "P5E_PEX2_STN0_RX_DN<4>")
	)
	(segment
		(start 313.021218 -148.009864)
		(end 312.678064 -147.649184)
		(width 0.1651)
		(layer "In5.Cu")
		(net "P5E_PEX2_STN0_RX_DN<4>")
	)
	(segment
		(start 327.875392 -272.573242)
		(end 327.975468 -269.73022)
		(width 0.1651)
		(layer "In5.Cu")
		(net "P5E_PEX2_STN0_RX_DN<4>")
	)
	(segment
		(start 315.396372 -149.578568)
		(end 314.268866 -148.308314)
		(width 0.1651)
		(layer "In5.Cu")
		(net "P5E_PEX2_STN0_RX_DN<4>")
	)
	(segment
		(start 314.182252 -148.28774)
		(end 313.021218 -148.009864)
		(width 0.1651)
		(layer "In5.Cu")
		(net "P5E_PEX2_STN0_RX_DN<4>")
	)
	(segment
		(start 312.749692 -284.499812)
		(end 312.484262 -284.499812)
		(width 0.1143)
		(layer "In5.Cu")
		(net "P5E_PEX2_STN0_RX_DN<4>")
	)
	(segment
		(start 314.268866 -148.308314)
		(end 314.182252 -148.287486)
		(width 0.1651)
		(layer "In5.Cu")
		(net "P5E_PEX2_STN0_RX_DN<4>")
	)
	(segment
		(start 312.369962 -284.25267)
		(end 312.50255 -284.120082)
		(width 0.1143)
		(layer "In5.Cu")
		(net "P5E_PEX2_STN0_RX_DN<4>")
	)
	(segment
		(start 317.540132 -150.649178)
		(end 315.396372 -149.578568)
		(width 0.1651)
		(layer "In5.Cu")
		(net "P5E_PEX2_STN0_RX_DN<4>")
	)
	(segment
		(start 309.957978 -136.865868)
		(end 306.161186 -133.472428)
		(width 0.1651)
		(layer "In5.Cu")
		(net "P5E_PEX2_STN0_RX_DN<4>")
	)
	(segment
		(start 312.369962 -284.385512)
		(end 312.369962 -284.25267)
		(width 0.1143)
		(layer "In5.Cu")
		(net "P5E_PEX2_STN0_RX_DN<4>")
	)
	(segment
		(start 316.12459 -284.165802)
		(end 317.238888 -284.165802)
		(width 0.1651)
		(layer "In5.Cu")
		(net "P5E_PEX2_STN0_RX_DN<4>")
	)
	(segment
		(start 377.975368 -356.831138)
		(end 377.975368 -357.463598)
		(width 0.13462)
		(layer "F.Cu")
		(net "P5E_PEX3_STN6_TX_C_DN<108>")
	)
	(segment
		(start 378.2949 -356.511606)
		(end 377.975368 -356.831138)
		(width 0.13462)
		(layer "F.Cu")
		(net "P5E_PEX3_STN6_TX_C_DN<108>")
	)
	(segment
		(start 377.975368 -357.463598)
		(end 378.2695 -357.75773)
		(width 0.13462)
		(layer "F.Cu")
		(net "P5E_PEX3_STN6_TX_C_DN<108>")
	)
	(segment
		(start 382.614678 -394.7414)
		(end 383.215896 -396.24)
		(width 0.1651)
		(layer "In13.Cu")
		(net "P5E_PEX3_STN6_TX_C_DN<108>")
	)
	(segment
		(start 372.838218 -388.859268)
		(end 372.838218 -388.859014)
		(width 0.1651)
		(layer "In13.Cu")
		(net "P5E_PEX3_STN6_TX_C_DN<108>")
	)
	(segment
		(start 374.209056 -389.863838)
		(end 376.594878 -390.906)
		(width 0.1651)
		(layer "In13.Cu")
		(net "P5E_PEX3_STN6_TX_C_DN<108>")
	)
	(segment
		(start 377.97867 -358.42448)
		(end 377.575826 -359.440734)
		(width 0.1651)
		(layer "In13.Cu")
		(net "P5E_PEX3_STN6_TX_C_DN<108>")
	)
	(segment
		(start 383.215896 -409.629102)
		(end 382.76403 -410.080968)
		(width 0.1651)
		(layer "In13.Cu")
		(net "P5E_PEX3_STN6_TX_C_DN<108>")
	)
	(segment
		(start 370.551964 -367.772696)
		(end 370.046758 -373.224044)
		(width 0.1651)
		(layer "In13.Cu")
		(net "P5E_PEX3_STN6_TX_C_DN<108>")
	)
	(segment
		(start 378.2695 -357.75773)
		(end 377.97867 -358.04856)
		(width 0.1651)
		(layer "In13.Cu")
		(net "P5E_PEX3_STN6_TX_C_DN<108>")
	)
	(segment
		(start 370.046758 -373.224044)
		(end 370.548154 -385.473702)
		(width 0.1651)
		(layer "In13.Cu")
		(net "P5E_PEX3_STN6_TX_C_DN<108>")
	)
	(segment
		(start 377.575826 -359.440734)
		(end 372.747794 -364.57509)
		(width 0.1651)
		(layer "In13.Cu")
		(net "P5E_PEX3_STN6_TX_C_DN<108>")
	)
	(segment
		(start 372.838218 -388.859014)
		(end 374.209056 -389.863584)
		(width 0.1651)
		(layer "In13.Cu")
		(net "P5E_PEX3_STN6_TX_C_DN<108>")
	)
	(segment
		(start 371.466618 -387.854444)
		(end 372.838218 -388.859268)
		(width 0.1651)
		(layer "In13.Cu")
		(net "P5E_PEX3_STN6_TX_C_DN<108>")
	)
	(segment
		(start 370.548154 -385.473702)
		(end 371.466618 -387.854444)
		(width 0.1651)
		(layer "In13.Cu")
		(net "P5E_PEX3_STN6_TX_C_DN<108>")
	)
	(segment
		(start 381.901192 -393.956286)
		(end 382.614678 -394.7414)
		(width 0.1651)
		(layer "In13.Cu")
		(net "P5E_PEX3_STN6_TX_C_DN<108>")
	)
	(segment
		(start 380.807976 -393.240006)
		(end 380.83617 -393.344146)
		(width 0.1651)
		(layer "In13.Cu")
		(net "P5E_PEX3_STN6_TX_C_DN<108>")
	)
	(segment
		(start 377.97867 -358.04856)
		(end 377.97867 -358.42448)
		(width 0.1651)
		(layer "In13.Cu")
		(net "P5E_PEX3_STN6_TX_C_DN<108>")
	)
	(segment
		(start 380.274322 -393.021058)
		(end 380.378462 -392.992864)
		(width 0.1651)
		(layer "In13.Cu")
		(net "P5E_PEX3_STN6_TX_C_DN<108>")
	)
	(segment
		(start 376.594878 -390.906)
		(end 380.274322 -393.021058)
		(width 0.1651)
		(layer "In13.Cu")
		(net "P5E_PEX3_STN6_TX_C_DN<108>")
	)
	(segment
		(start 382.089914 -410.207968)
		(end 382.089914 -410.589984)
		(width 0.1651)
		(layer "In13.Cu")
		(net "P5E_PEX3_STN6_TX_C_DN<108>")
	)
	(segment
		(start 374.209056 -389.863584)
		(end 374.209056 -389.863838)
		(width 0.1651)
		(layer "In13.Cu")
		(net "P5E_PEX3_STN6_TX_C_DN<108>")
	)
	(segment
		(start 382.216914 -410.080968)
		(end 382.089914 -410.207968)
		(width 0.1651)
		(layer "In13.Cu")
		(net "P5E_PEX3_STN6_TX_C_DN<108>")
	)
	(segment
		(start 383.215896 -396.24)
		(end 383.215896 -409.629102)
		(width 0.1651)
		(layer "In13.Cu")
		(net "P5E_PEX3_STN6_TX_C_DN<108>")
	)
	(segment
		(start 382.76403 -410.080968)
		(end 382.216914 -410.080968)
		(width 0.1651)
		(layer "In13.Cu")
		(net "P5E_PEX3_STN6_TX_C_DN<108>")
	)
	(segment
		(start 380.378462 -392.992864)
		(end 380.807976 -393.240006)
		(width 0.1651)
		(layer "In13.Cu")
		(net "P5E_PEX3_STN6_TX_C_DN<108>")
	)
	(segment
		(start 380.83617 -393.344146)
		(end 381.901192 -393.956286)
		(width 0.1651)
		(layer "In13.Cu")
		(net "P5E_PEX3_STN6_TX_C_DN<108>")
	)
	(segment
		(start 372.747794 -364.57509)
		(end 370.551964 -367.772696)
		(width 0.1651)
		(layer "In13.Cu")
		(net "P5E_PEX3_STN6_TX_C_DN<108>")
	)
	(segment
		(start 37.404802 -140.85697)
		(end 38.382702 -140.85697)
		(width 0.13208)
		(layer "F.Cu")
		(net "NIC0_BIF2_N")
	)
	(segment
		(start 38.509956 -140.379196)
		(end 40.397176 -140.379196)
		(width 0.13208)
		(layer "F.Cu")
		(net "NIC0_BIF2_N")
	)
	(segment
		(start 41.38295 -141.36497)
		(end 46.042326 -141.36497)
		(width 0.13208)
		(layer "F.Cu")
		(net "NIC0_BIF2_N")
	)
	(segment
		(start 38.382702 -140.85697)
		(end 38.382702 -140.50645)
		(width 0.13208)
		(layer "F.Cu")
		(net "NIC0_BIF2_N")
	)
	(segment
		(start 38.382702 -140.50645)
		(end 38.509956 -140.379196)
		(width 0.13208)
		(layer "F.Cu")
		(net "NIC0_BIF2_N")
	)
	(segment
		(start 40.397176 -140.379196)
		(end 41.38295 -141.36497)
		(width 0.13208)
		(layer "F.Cu")
		(net "NIC0_BIF2_N")
	)
	(via
		(at 40.397176 -140.379196)
		(size 0.762)
		(drill 0.381)
		(layers "F.Cu" "B.Cu")
		(net "NIC0_BIF2_N")
	)
	(segment
		(start 10.182352 -30.790134)
		(end 10.019538 -30.62732)
		(width 0.13462)
		(layer "F.Cu")
		(net "P5E_PEX0_STN2_RX_DP<45>")
	)
	(segment
		(start 10.664952 -30.790134)
		(end 10.182352 -30.790134)
		(width 0.13462)
		(layer "F.Cu")
		(net "P5E_PEX0_STN2_RX_DP<45>")
	)
	(segment
		(start 7.5057 -30.62732)
		(end 7.210552 -30.922468)
		(width 0.13462)
		(layer "F.Cu")
		(net "P5E_PEX0_STN2_RX_DP<45>")
	)
	(segment
		(start 10.019538 -30.62732)
		(end 7.5057 -30.62732)
		(width 0.13462)
		(layer "F.Cu")
		(net "P5E_PEX0_STN2_RX_DP<45>")
	)
	(segment
		(start 46.34992 -273.784314)
		(end 46.23562 -273.670014)
		(width 0.1143)
		(layer "In7.Cu")
		(net "P5E_PEX0_STN2_RX_DP<45>")
	)
	(segment
		(start 25.540208 -144.549876)
		(end 22.260052 -119.612156)
		(width 0.1651)
		(layer "In7.Cu")
		(net "P5E_PEX0_STN2_RX_DP<45>")
	)
	(segment
		(start 44.771564 -263.52119)
		(end 44.848526 -255.658366)
		(width 0.1651)
		(layer "In7.Cu")
		(net "P5E_PEX0_STN2_RX_DP<45>")
	)
	(segment
		(start 45.77969 -273.407632)
		(end 45.77969 -271.41932)
		(width 0.1143)
		(layer "In7.Cu")
		(net "P5E_PEX0_STN2_RX_DP<45>")
	)
	(segment
		(start 8.47852 -30.631638)
		(end 7.501382 -30.631638)
		(width 0.1651)
		(layer "In7.Cu")
		(net "P5E_PEX0_STN2_RX_DP<45>")
	)
	(segment
		(start 22.260052 -119.612156)
		(end 17.07769 -102.514654)
		(width 0.1651)
		(layer "In7.Cu")
		(net "P5E_PEX0_STN2_RX_DP<45>")
	)
	(segment
		(start 45.73397 -270.305276)
		(end 44.771564 -263.52119)
		(width 0.1651)
		(layer "In7.Cu")
		(net "P5E_PEX0_STN2_RX_DP<45>")
	)
	(segment
		(start 9.67232 -30.631638)
		(end 9.17702 -30.631638)
		(width 0.1651)
		(layer "In7.Cu")
		(net "P5E_PEX0_STN2_RX_DP<45>")
	)
	(segment
		(start 7.501382 -30.631638)
		(end 7.210552 -30.922468)
		(width 0.1651)
		(layer "In7.Cu")
		(net "P5E_PEX0_STN2_RX_DP<45>")
	)
	(segment
		(start 10.684256 -31.643574)
		(end 10.540746 -31.643574)
		(width 0.1651)
		(layer "In7.Cu")
		(net "P5E_PEX0_STN2_RX_DP<45>")
	)
	(segment
		(start 46.34992 -274.049744)
		(end 46.34992 -273.784314)
		(width 0.1143)
		(layer "In7.Cu")
		(net "P5E_PEX0_STN2_RX_DP<45>")
	)
	(segment
		(start 43.25112 -238.208566)
		(end 25.540208 -144.549876)
		(width 0.1651)
		(layer "In7.Cu")
		(net "P5E_PEX0_STN2_RX_DP<45>")
	)
	(segment
		(start 17.07769 -102.514654)
		(end 17.077436 -102.513892)
		(width 0.1651)
		(layer "In7.Cu")
		(net "P5E_PEX0_STN2_RX_DP<45>")
	)
	(segment
		(start 44.848526 -255.658366)
		(end 43.25112 -238.208566)
		(width 0.1651)
		(layer "In7.Cu")
		(net "P5E_PEX0_STN2_RX_DP<45>")
	)
	(segment
		(start 10.190226 -31.149544)
		(end 9.67232 -30.631638)
		(width 0.1651)
		(layer "In7.Cu")
		(net "P5E_PEX0_STN2_RX_DP<45>")
	)
	(segment
		(start 8.58012 -30.733238)
		(end 8.47852 -30.631638)
		(width 0.1651)
		(layer "In7.Cu")
		(net "P5E_PEX0_STN2_RX_DP<45>")
	)
	(segment
		(start 11.798808 -57.373774)
		(end 11.915902 -49.884838)
		(width 0.1651)
		(layer "In7.Cu")
		(net "P5E_PEX0_STN2_RX_DP<45>")
	)
	(segment
		(start 12.066524 -60.146692)
		(end 11.798808 -57.373774)
		(width 0.1651)
		(layer "In7.Cu")
		(net "P5E_PEX0_STN2_RX_DP<45>")
	)
	(segment
		(start 11.129518 -32.088836)
		(end 10.684256 -31.643574)
		(width 0.1651)
		(layer "In7.Cu")
		(net "P5E_PEX0_STN2_RX_DP<45>")
	)
	(segment
		(start 11.875516 -85.352382)
		(end 12.066524 -61.48832)
		(width 0.1651)
		(layer "In7.Cu")
		(net "P5E_PEX0_STN2_RX_DP<45>")
	)
	(segment
		(start 11.915902 -49.884838)
		(end 10.617708 -40.277288)
		(width 0.1651)
		(layer "In7.Cu")
		(net "P5E_PEX0_STN2_RX_DP<45>")
	)
	(segment
		(start 17.077436 -102.513892)
		(end 17.065498 -102.474522)
		(width 0.1651)
		(layer "In7.Cu")
		(net "P5E_PEX0_STN2_RX_DP<45>")
	)
	(segment
		(start 10.190226 -31.293054)
		(end 10.190226 -31.149544)
		(width 0.1651)
		(layer "In7.Cu")
		(net "P5E_PEX0_STN2_RX_DP<45>")
	)
	(segment
		(start 46.042072 -273.670014)
		(end 45.77969 -273.407632)
		(width 0.1143)
		(layer "In7.Cu")
		(net "P5E_PEX0_STN2_RX_DP<45>")
	)
	(segment
		(start 10.580878 -37.940234)
		(end 11.10615 -34.981642)
		(width 0.1651)
		(layer "In7.Cu")
		(net "P5E_PEX0_STN2_RX_DP<45>")
	)
	(segment
		(start 12.066524 -61.48832)
		(end 12.066524 -60.146692)
		(width 0.1651)
		(layer "In7.Cu")
		(net "P5E_PEX0_STN2_RX_DP<45>")
	)
	(segment
		(start 45.73397 -271.345152)
		(end 45.73397 -270.305276)
		(width 0.1651)
		(layer "In7.Cu")
		(net "P5E_PEX0_STN2_RX_DP<45>")
	)
	(segment
		(start 9.07542 -30.733238)
		(end 8.58012 -30.733238)
		(width 0.1651)
		(layer "In7.Cu")
		(net "P5E_PEX0_STN2_RX_DP<45>")
	)
	(segment
		(start 11.10615 -34.981642)
		(end 11.129518 -32.088836)
		(width 0.1651)
		(layer "In7.Cu")
		(net "P5E_PEX0_STN2_RX_DP<45>")
	)
	(segment
		(start 17.065498 -102.474522)
		(end 17.065498 -102.474014)
		(width 0.1651)
		(layer "In7.Cu")
		(net "P5E_PEX0_STN2_RX_DP<45>")
	)
	(segment
		(start 10.540746 -31.643574)
		(end 10.190226 -31.293054)
		(width 0.1651)
		(layer "In7.Cu")
		(net "P5E_PEX0_STN2_RX_DP<45>")
	)
	(segment
		(start 45.73397 -271.3736)
		(end 45.73397 -271.345152)
		(width 0.1143)
		(layer "In7.Cu")
		(net "P5E_PEX0_STN2_RX_DP<45>")
	)
	(segment
		(start 45.77969 -271.41932)
		(end 45.73397 -271.3736)
		(width 0.1143)
		(layer "In7.Cu")
		(net "P5E_PEX0_STN2_RX_DP<45>")
	)
	(segment
		(start 17.065498 -102.474014)
		(end 11.875516 -85.352382)
		(width 0.1651)
		(layer "In7.Cu")
		(net "P5E_PEX0_STN2_RX_DP<45>")
	)
	(segment
		(start 46.23562 -273.670014)
		(end 46.042072 -273.670014)
		(width 0.1143)
		(layer "In7.Cu")
		(net "P5E_PEX0_STN2_RX_DP<45>")
	)
	(segment
		(start 10.617708 -40.277288)
		(end 10.580878 -37.940234)
		(width 0.1651)
		(layer "In7.Cu")
		(net "P5E_PEX0_STN2_RX_DP<45>")
	)
	(segment
		(start 9.17702 -30.631638)
		(end 9.07542 -30.733238)
		(width 0.1651)
		(layer "In7.Cu")
		(net "P5E_PEX0_STN2_RX_DP<45>")
	)
	(segment
		(start 204.764894 -33.790128)
		(end 204.287374 -33.790128)
		(width 0.13462)
		(layer "F.Cu")
		(net "P5E_PEX1_STN2_RX_DN<35>")
	)
	(segment
		(start 204.287374 -33.790128)
		(end 204.12456 -33.952942)
		(width 0.13462)
		(layer "F.Cu")
		(net "P5E_PEX1_STN2_RX_DN<35>")
	)
	(segment
		(start 204.12456 -33.952942)
		(end 201.604626 -33.952942)
		(width 0.13462)
		(layer "F.Cu")
		(net "P5E_PEX1_STN2_RX_DN<35>")
	)
	(segment
		(start 201.604626 -33.952942)
		(end 201.310494 -33.65881)
		(width 0.13462)
		(layer "F.Cu")
		(net "P5E_PEX1_STN2_RX_DN<35>")
	)
	(segment
		(start 201.601324 -33.94964)
		(end 201.310494 -33.65881)
		(width 0.1651)
		(layer "In7.Cu")
		(net "P5E_PEX1_STN2_RX_DN<35>")
	)
	(segment
		(start 202.960986 -34.714688)
		(end 202.195938 -33.94964)
		(width 0.1651)
		(layer "In7.Cu")
		(net "P5E_PEX1_STN2_RX_DN<35>")
	)
	(segment
		(start 204.370686 -49.490884)
		(end 203.032106 -39.583614)
		(width 0.1651)
		(layer "In7.Cu")
		(net "P5E_PEX1_STN2_RX_DN<35>")
	)
	(segment
		(start 171.615862 -271.3736)
		(end 171.615862 -271.345152)
		(width 0.1143)
		(layer "In7.Cu")
		(net "P5E_PEX1_STN2_RX_DN<35>")
	)
	(segment
		(start 191.50711 -154.40914)
		(end 192.887346 -143.682974)
		(width 0.1651)
		(layer "In7.Cu")
		(net "P5E_PEX1_STN2_RX_DN<35>")
	)
	(segment
		(start 203.032106 -39.583614)
		(end 202.960986 -34.714688)
		(width 0.1651)
		(layer "In7.Cu")
		(net "P5E_PEX1_STN2_RX_DN<35>")
	)
	(segment
		(start 204.189076 -61.12764)
		(end 204.370686 -49.490884)
		(width 0.1651)
		(layer "In7.Cu")
		(net "P5E_PEX1_STN2_RX_DN<35>")
	)
	(segment
		(start 171.570142 -273.328638)
		(end 171.570142 -271.41932)
		(width 0.1143)
		(layer "In7.Cu")
		(net "P5E_PEX1_STN2_RX_DN<35>")
	)
	(segment
		(start 171.940728 -266.758166)
		(end 191.50711 -154.40914)
		(width 0.1651)
		(layer "In7.Cu")
		(net "P5E_PEX1_STN2_RX_DN<35>")
	)
	(segment
		(start 171.615862 -271.345152)
		(end 171.615862 -270.511524)
		(width 0.1651)
		(layer "In7.Cu")
		(net "P5E_PEX1_STN2_RX_DN<35>")
	)
	(segment
		(start 193.202814 -116.50345)
		(end 204.189076 -61.12764)
		(width 0.1651)
		(layer "In7.Cu")
		(net "P5E_PEX1_STN2_RX_DN<35>")
	)
	(segment
		(start 171.949872 -273.099784)
		(end 171.949872 -273.365214)
		(width 0.1143)
		(layer "In7.Cu")
		(net "P5E_PEX1_STN2_RX_DN<35>")
	)
	(segment
		(start 171.835572 -273.479514)
		(end 171.721018 -273.479514)
		(width 0.1143)
		(layer "In7.Cu")
		(net "P5E_PEX1_STN2_RX_DN<35>")
	)
	(segment
		(start 171.721018 -273.479514)
		(end 171.570142 -273.328638)
		(width 0.1143)
		(layer "In7.Cu")
		(net "P5E_PEX1_STN2_RX_DN<35>")
	)
	(segment
		(start 202.195938 -33.94964)
		(end 201.601324 -33.94964)
		(width 0.1651)
		(layer "In7.Cu")
		(net "P5E_PEX1_STN2_RX_DN<35>")
	)
	(segment
		(start 171.615862 -270.511524)
		(end 171.940728 -266.758166)
		(width 0.1651)
		(layer "In7.Cu")
		(net "P5E_PEX1_STN2_RX_DN<35>")
	)
	(segment
		(start 192.887346 -143.682974)
		(end 193.202814 -116.50345)
		(width 0.1651)
		(layer "In7.Cu")
		(net "P5E_PEX1_STN2_RX_DN<35>")
	)
	(segment
		(start 171.949872 -273.365214)
		(end 171.835572 -273.479514)
		(width 0.1143)
		(layer "In7.Cu")
		(net "P5E_PEX1_STN2_RX_DN<35>")
	)
	(segment
		(start 171.570142 -271.41932)
		(end 171.615862 -271.3736)
		(width 0.1143)
		(layer "In7.Cu")
		(net "P5E_PEX1_STN2_RX_DN<35>")
	)
	(segment
		(start 297.69816 -132.00888)
		(end 297.403012 -131.713732)
		(width 0.13462)
		(layer "F.Cu")
		(net "P5E_PEX2_STN0_RX_DN<5>")
	)
	(segment
		(start 300.857412 -131.84505)
		(end 300.379892 -131.84505)
		(width 0.13462)
		(layer "F.Cu")
		(net "P5E_PEX2_STN0_RX_DN<5>")
	)
	(segment
		(start 300.216062 -132.00888)
		(end 297.69816 -132.00888)
		(width 0.13462)
		(layer "F.Cu")
		(net "P5E_PEX2_STN0_RX_DN<5>")
	)
	(segment
		(start 300.379892 -131.84505)
		(end 300.216062 -132.00888)
		(width 0.13462)
		(layer "F.Cu")
		(net "P5E_PEX2_STN0_RX_DN<5>")
	)
	(segment
		(start 326.983852 -270.233394)
		(end 319.34785 -244.131846)
		(width 0.1651)
		(layer "In5.Cu")
		(net "P5E_PEX2_STN0_RX_DN<5>")
	)
	(segment
		(start 297.693842 -132.004562)
		(end 297.403012 -131.713732)
		(width 0.1651)
		(layer "In5.Cu")
		(net "P5E_PEX2_STN0_RX_DN<5>")
	)
	(segment
		(start 309.13451 -137.449306)
		(end 309.13451 -137.449052)
		(width 0.1651)
		(layer "In5.Cu")
		(net "P5E_PEX2_STN0_RX_DN<5>")
	)
	(segment
		(start 316.04331 -283.170122)
		(end 316.08903 -283.215842)
		(width 0.1143)
		(layer "In5.Cu")
		(net "P5E_PEX2_STN0_RX_DN<5>")
	)
	(segment
		(start 310.101234 -139.151868)
		(end 309.81523 -138.484864)
		(width 0.1651)
		(layer "In5.Cu")
		(net "P5E_PEX2_STN0_RX_DN<5>")
	)
	(segment
		(start 317.774066 -282.609036)
		(end 325.171562 -275.417788)
		(width 0.1651)
		(layer "In5.Cu")
		(net "P5E_PEX2_STN0_RX_DN<5>")
	)
	(segment
		(start 310.717184 -142.021306)
		(end 310.101234 -139.151868)
		(width 0.1651)
		(layer "In5.Cu")
		(net "P5E_PEX2_STN0_RX_DN<5>")
	)
	(segment
		(start 306.4129 -135.46074)
		(end 299.52696 -132.004562)
		(width 0.1651)
		(layer "In5.Cu")
		(net "P5E_PEX2_STN0_RX_DN<5>")
	)
	(segment
		(start 313.482736 -160.702752)
		(end 312.099452 -151.3586)
		(width 0.1651)
		(layer "In5.Cu")
		(net "P5E_PEX2_STN0_RX_DN<5>")
	)
	(segment
		(start 309.106062 -137.405872)
		(end 306.4129 -135.46074)
		(width 0.1651)
		(layer "In5.Cu")
		(net "P5E_PEX2_STN0_RX_DN<5>")
	)
	(segment
		(start 326.928988 -272.307558)
		(end 326.983852 -270.233394)
		(width 0.1651)
		(layer "In5.Cu")
		(net "P5E_PEX2_STN0_RX_DN<5>")
	)
	(segment
		(start 314.649866 -283.549852)
		(end 314.384436 -283.549852)
		(width 0.1143)
		(layer "In5.Cu")
		(net "P5E_PEX2_STN0_RX_DN<5>")
	)
	(segment
		(start 299.52696 -132.004562)
		(end 297.693842 -132.004562)
		(width 0.1651)
		(layer "In5.Cu")
		(net "P5E_PEX2_STN0_RX_DN<5>")
	)
	(segment
		(start 325.171562 -275.417788)
		(end 326.928988 -272.307558)
		(width 0.1651)
		(layer "In5.Cu")
		(net "P5E_PEX2_STN0_RX_DN<5>")
	)
	(segment
		(start 312.099706 -151.3586)
		(end 310.717184 -142.021306)
		(width 0.1651)
		(layer "In5.Cu")
		(net "P5E_PEX2_STN0_RX_DN<5>")
	)
	(segment
		(start 314.384436 -283.549852)
		(end 314.270136 -283.435552)
		(width 0.1143)
		(layer "In5.Cu")
		(net "P5E_PEX2_STN0_RX_DN<5>")
	)
	(segment
		(start 316.117478 -283.215842)
		(end 316.851284 -283.215842)
		(width 0.1651)
		(layer "In5.Cu")
		(net "P5E_PEX2_STN0_RX_DN<5>")
	)
	(segment
		(start 309.81523 -138.484864)
		(end 309.13451 -137.449306)
		(width 0.1651)
		(layer "In5.Cu")
		(net "P5E_PEX2_STN0_RX_DN<5>")
	)
	(segment
		(start 309.13451 -137.449052)
		(end 309.106062 -137.405872)
		(width 0.1651)
		(layer "In5.Cu")
		(net "P5E_PEX2_STN0_RX_DN<5>")
	)
	(segment
		(start 316.851284 -283.215842)
		(end 317.774066 -282.609036)
		(width 0.1651)
		(layer "In5.Cu")
		(net "P5E_PEX2_STN0_RX_DN<5>")
	)
	(segment
		(start 314.270136 -283.435552)
		(end 314.270136 -283.273754)
		(width 0.1143)
		(layer "In5.Cu")
		(net "P5E_PEX2_STN0_RX_DN<5>")
	)
	(segment
		(start 316.08903 -283.215842)
		(end 316.117478 -283.215842)
		(width 0.1143)
		(layer "In5.Cu")
		(net "P5E_PEX2_STN0_RX_DN<5>")
	)
	(segment
		(start 315.695076 -222.600774)
		(end 313.482736 -160.702752)
		(width 0.1651)
		(layer "In5.Cu")
		(net "P5E_PEX2_STN0_RX_DN<5>")
	)
	(segment
		(start 312.099452 -151.3586)
		(end 312.099706 -151.3586)
		(width 0.1651)
		(layer "In5.Cu")
		(net "P5E_PEX2_STN0_RX_DN<5>")
	)
	(segment
		(start 316.728856 -233.312462)
		(end 315.695076 -222.600774)
		(width 0.1651)
		(layer "In5.Cu")
		(net "P5E_PEX2_STN0_RX_DN<5>")
	)
	(segment
		(start 314.270136 -283.273754)
		(end 314.373768 -283.170122)
		(width 0.1143)
		(layer "In5.Cu")
		(net "P5E_PEX2_STN0_RX_DN<5>")
	)
	(segment
		(start 314.373768 -283.170122)
		(end 316.04331 -283.170122)
		(width 0.1143)
		(layer "In5.Cu")
		(net "P5E_PEX2_STN0_RX_DN<5>")
	)
	(segment
		(start 319.34785 -244.131846)
		(end 316.728856 -233.312462)
		(width 0.1651)
		(layer "In5.Cu")
		(net "P5E_PEX2_STN0_RX_DN<5>")
	)
	(segment
		(start 374.592088 -357.462582)
		(end 374.29694 -357.75773)
		(width 0.13462)
		(layer "F.Cu")
		(net "P5E_PEX3_STN6_TX_C_DP<101>")
	)
	(segment
		(start 374.27154 -356.511606)
		(end 374.592088 -356.832154)
		(width 0.13462)
		(layer "F.Cu")
		(net "P5E_PEX3_STN6_TX_C_DP<101>")
	)
	(segment
		(start 374.592088 -356.832154)
		(end 374.592088 -357.462582)
		(width 0.13462)
		(layer "F.Cu")
		(net "P5E_PEX3_STN6_TX_C_DP<101>")
	)
	(segment
		(start 379.151134 -366.391698)
		(end 378.894848 -365.967518)
		(width 0.1651)
		(layer "In7.Cu")
		(net "P5E_PEX3_STN6_TX_C_DP<101>")
	)
	(segment
		(start 378.93371 -365.810546)
		(end 374.58777 -358.61117)
		(width 0.1651)
		(layer "In7.Cu")
		(net "P5E_PEX3_STN6_TX_C_DP<101>")
	)
	(segment
		(start 379.563884 -366.854486)
		(end 379.308106 -366.43056)
		(width 0.1651)
		(layer "In7.Cu")
		(net "P5E_PEX3_STN6_TX_C_DP<101>")
	)
	(segment
		(start 379.89002 -382.18999)
		(end 379.89002 -382.57226)
		(width 0.1651)
		(layer "In7.Cu")
		(net "P5E_PEX3_STN6_TX_C_DP<101>")
	)
	(segment
		(start 378.894848 -365.967518)
		(end 378.93371 -365.810546)
		(width 0.1651)
		(layer "In7.Cu")
		(net "P5E_PEX3_STN6_TX_C_DP<101>")
	)
	(segment
		(start 379.781308 -367.435638)
		(end 379.525022 -367.011458)
		(width 0.1651)
		(layer "In7.Cu")
		(net "P5E_PEX3_STN6_TX_C_DP<101>")
	)
	(segment
		(start 380.01702 -382.69926)
		(end 380.447296 -382.69926)
		(width 0.1651)
		(layer "In7.Cu")
		(net "P5E_PEX3_STN6_TX_C_DP<101>")
	)
	(segment
		(start 379.93828 -367.4745)
		(end 379.781308 -367.435638)
		(width 0.1651)
		(layer "In7.Cu")
		(net "P5E_PEX3_STN6_TX_C_DP<101>")
	)
	(segment
		(start 379.89002 -382.57226)
		(end 380.01702 -382.69926)
		(width 0.1651)
		(layer "In7.Cu")
		(net "P5E_PEX3_STN6_TX_C_DP<101>")
	)
	(segment
		(start 379.308106 -366.43056)
		(end 379.151134 -366.391698)
		(width 0.1651)
		(layer "In7.Cu")
		(net "P5E_PEX3_STN6_TX_C_DP<101>")
	)
	(segment
		(start 380.734062 -382.412494)
		(end 380.734062 -368.79276)
		(width 0.1651)
		(layer "In7.Cu")
		(net "P5E_PEX3_STN6_TX_C_DP<101>")
	)
	(segment
		(start 379.525022 -367.011458)
		(end 379.563884 -366.854486)
		(width 0.1651)
		(layer "In7.Cu")
		(net "P5E_PEX3_STN6_TX_C_DP<101>")
	)
	(segment
		(start 374.58777 -358.61117)
		(end 374.58777 -358.04856)
		(width 0.1651)
		(layer "In7.Cu")
		(net "P5E_PEX3_STN6_TX_C_DP<101>")
	)
	(segment
		(start 374.58777 -358.04856)
		(end 374.29694 -357.75773)
		(width 0.1651)
		(layer "In7.Cu")
		(net "P5E_PEX3_STN6_TX_C_DP<101>")
	)
	(segment
		(start 380.734062 -368.79276)
		(end 379.93828 -367.4745)
		(width 0.1651)
		(layer "In7.Cu")
		(net "P5E_PEX3_STN6_TX_C_DP<101>")
	)
	(segment
		(start 380.447296 -382.69926)
		(end 380.734062 -382.412494)
		(width 0.1651)
		(layer "In7.Cu")
		(net "P5E_PEX3_STN6_TX_C_DP<101>")
	)
	(segment
		(start 44.62399 -157.759908)
		(end 46.042326 -157.759908)
		(width 0.13208)
		(layer "F.Cu")
		(net "NIC0_MAIN_PWR_EN_R")
	)
	(segment
		(start 39.557198 -159.4104)
		(end 40.391842 -160.245044)
		(width 0.13208)
		(layer "F.Cu")
		(net "NIC0_MAIN_PWR_EN_R")
	)
	(segment
		(start 42.138854 -160.245044)
		(end 44.62399 -157.759908)
		(width 0.13208)
		(layer "F.Cu")
		(net "NIC0_MAIN_PWR_EN_R")
	)
	(segment
		(start 39.00805 -159.4104)
		(end 39.557198 -159.4104)
		(width 0.13208)
		(layer "F.Cu")
		(net "NIC0_MAIN_PWR_EN_R")
	)
	(segment
		(start 40.391842 -160.245044)
		(end 42.138854 -160.245044)
		(width 0.13208)
		(layer "F.Cu")
		(net "NIC0_MAIN_PWR_EN_R")
	)
	(via
		(at 40.391842 -160.245044)
		(size 0.762)
		(drill 0.381)
		(layers "F.Cu" "B.Cu")
		(net "NIC0_MAIN_PWR_EN_R")
	)
	(segment
		(start 159.625792 -28.225242)
		(end 159.296354 -28.55468)
		(width 0.13462)
		(layer "F.Cu")
		(net "P5E_PEX1_STN2_TX_C_DN<40>")
	)
	(segment
		(start 159.296354 -28.55468)
		(end 158.032704 -28.55468)
		(width 0.13462)
		(layer "F.Cu")
		(net "P5E_PEX1_STN2_TX_C_DN<40>")
	)
	(segment
		(start 157.868112 -28.390088)
		(end 157.364938 -28.390088)
		(width 0.13462)
		(layer "F.Cu")
		(net "P5E_PEX1_STN2_TX_C_DN<40>")
	)
	(segment
		(start 158.032704 -28.55468)
		(end 157.868112 -28.390088)
		(width 0.13462)
		(layer "F.Cu")
		(net "P5E_PEX1_STN2_TX_C_DN<40>")
	)
	(segment
		(start 305.964336 -120.635014)
		(end 305.457606 -120.635014)
		(width 0.13462)
		(layer "F.Cu")
		(net "P5E_PEX2_STN0_TX_C_DN<1>")
	)
	(segment
		(start 314.27674 -120.79478)
		(end 306.124102 -120.79478)
		(width 0.13462)
		(layer "F.Cu")
		(net "P5E_PEX2_STN0_TX_C_DN<1>")
	)
	(segment
		(start 314.594748 -120.476772)
		(end 314.27674 -120.79478)
		(width 0.13462)
		(layer "F.Cu")
		(net "P5E_PEX2_STN0_TX_C_DN<1>")
	)
	(segment
		(start 306.124102 -120.79478)
		(end 305.964336 -120.635014)
		(width 0.13462)
		(layer "F.Cu")
		(net "P5E_PEX2_STN0_TX_C_DN<1>")
	)
	(segment
		(start 381.084328 -351.317306)
		(end 381.37846 -351.611438)
		(width 0.13462)
		(layer "F.Cu")
		(net "P5E_PEX3_STN6_TX_C_DN<107>")
	)
	(segment
		(start 381.40386 -350.365314)
		(end 381.084328 -350.684846)
		(width 0.13462)
		(layer "F.Cu")
		(net "P5E_PEX3_STN6_TX_C_DN<107>")
	)
	(segment
		(start 381.084328 -350.684846)
		(end 381.084328 -351.317306)
		(width 0.13462)
		(layer "F.Cu")
		(net "P5E_PEX3_STN6_TX_C_DN<107>")
	)
	(segment
		(start 379.53315 -354.027486)
		(end 381.08763 -352.473006)
		(width 0.1651)
		(layer "In13.Cu")
		(net "P5E_PEX3_STN6_TX_C_DN<107>")
	)
	(segment
		(start 385.053078 -394.3604)
		(end 380.506478 -391.6172)
		(width 0.1651)
		(layer "In13.Cu")
		(net "P5E_PEX3_STN6_TX_C_DN<107>")
	)
	(segment
		(start 373.497094 -365.243364)
		(end 378.737368 -360.11358)
		(width 0.1651)
		(layer "In13.Cu")
		(net "P5E_PEX3_STN6_TX_C_DN<107>")
	)
	(segment
		(start 371.042946 -373.400574)
		(end 371.50802 -368.11331)
		(width 0.1651)
		(layer "In13.Cu")
		(net "P5E_PEX3_STN6_TX_C_DN<107>")
	)
	(segment
		(start 384.964178 -408.981148)
		(end 385.416044 -408.529282)
		(width 0.1651)
		(layer "In13.Cu")
		(net "P5E_PEX3_STN6_TX_C_DN<107>")
	)
	(segment
		(start 371.50802 -368.11331)
		(end 373.497094 -365.243364)
		(width 0.1651)
		(layer "In13.Cu")
		(net "P5E_PEX3_STN6_TX_C_DN<107>")
	)
	(segment
		(start 374.806718 -389.043926)
		(end 372.312438 -387.272784)
		(width 0.1651)
		(layer "In13.Cu")
		(net "P5E_PEX3_STN6_TX_C_DN<107>")
	)
	(segment
		(start 378.737368 -360.11358)
		(end 379.53315 -358.22128)
		(width 0.1651)
		(layer "In13.Cu")
		(net "P5E_PEX3_STN6_TX_C_DN<107>")
	)
	(segment
		(start 380.506478 -391.6172)
		(end 374.806718 -389.043926)
		(width 0.1651)
		(layer "In13.Cu")
		(net "P5E_PEX3_STN6_TX_C_DN<107>")
	)
	(segment
		(start 371.515132 -385.25323)
		(end 371.042946 -373.400574)
		(width 0.1651)
		(layer "In13.Cu")
		(net "P5E_PEX3_STN6_TX_C_DN<107>")
	)
	(segment
		(start 384.290062 -409.490164)
		(end 384.290062 -409.108148)
		(width 0.1651)
		(layer "In13.Cu")
		(net "P5E_PEX3_STN6_TX_C_DN<107>")
	)
	(segment
		(start 384.417062 -408.981148)
		(end 384.964178 -408.981148)
		(width 0.1651)
		(layer "In13.Cu")
		(net "P5E_PEX3_STN6_TX_C_DN<107>")
	)
	(segment
		(start 381.08763 -351.902268)
		(end 381.37846 -351.611438)
		(width 0.1651)
		(layer "In13.Cu")
		(net "P5E_PEX3_STN6_TX_C_DN<107>")
	)
	(segment
		(start 385.416044 -395.2748)
		(end 385.053078 -394.3604)
		(width 0.1651)
		(layer "In13.Cu")
		(net "P5E_PEX3_STN6_TX_C_DN<107>")
	)
	(segment
		(start 372.312438 -387.272784)
		(end 371.515132 -385.25323)
		(width 0.1651)
		(layer "In13.Cu")
		(net "P5E_PEX3_STN6_TX_C_DN<107>")
	)
	(segment
		(start 381.08763 -352.473006)
		(end 381.08763 -351.902268)
		(width 0.1651)
		(layer "In13.Cu")
		(net "P5E_PEX3_STN6_TX_C_DN<107>")
	)
	(segment
		(start 385.416044 -408.529282)
		(end 385.416044 -395.2748)
		(width 0.1651)
		(layer "In13.Cu")
		(net "P5E_PEX3_STN6_TX_C_DN<107>")
	)
	(segment
		(start 379.53315 -358.22128)
		(end 379.53315 -354.027486)
		(width 0.1651)
		(layer "In13.Cu")
		(net "P5E_PEX3_STN6_TX_C_DN<107>")
	)
	(segment
		(start 384.290062 -409.108148)
		(end 384.417062 -408.981148)
		(width 0.1651)
		(layer "In13.Cu")
		(net "P5E_PEX3_STN6_TX_C_DN<107>")
	)
	(segment
		(start 62.019434 -30.62732)
		(end 59.505596 -30.62732)
		(width 0.13462)
		(layer "F.Cu")
		(net "P5E_PEX0_STN2_RX_DP<37>")
	)
	(segment
		(start 62.664848 -30.790134)
		(end 62.182248 -30.790134)
		(width 0.13462)
		(layer "F.Cu")
		(net "P5E_PEX0_STN2_RX_DP<37>")
	)
	(segment
		(start 59.505596 -30.62732)
		(end 59.210448 -30.922468)
		(width 0.13462)
		(layer "F.Cu")
		(net "P5E_PEX0_STN2_RX_DP<37>")
	)
	(segment
		(start 62.182248 -30.790134)
		(end 62.019434 -30.62732)
		(width 0.13462)
		(layer "F.Cu")
		(net "P5E_PEX0_STN2_RX_DP<37>")
	)
	(segment
		(start 62.65291 -39.991792)
		(end 62.602618 -39.321486)
		(width 0.1651)
		(layer "In7.Cu")
		(net "P5E_PEX0_STN2_RX_DP<37>")
	)
	(segment
		(start 62.285118 -31.388304)
		(end 62.285118 -31.24454)
		(width 0.1651)
		(layer "In7.Cu")
		(net "P5E_PEX0_STN2_RX_DP<37>")
	)
	(segment
		(start 62.635638 -31.738824)
		(end 62.285118 -31.388304)
		(width 0.1651)
		(layer "In7.Cu")
		(net "P5E_PEX0_STN2_RX_DP<37>")
	)
	(segment
		(start 62.779402 -31.738824)
		(end 62.635638 -31.738824)
		(width 0.1651)
		(layer "In7.Cu")
		(net "P5E_PEX0_STN2_RX_DP<37>")
	)
	(segment
		(start 63.129414 -32.088836)
		(end 62.779402 -31.738824)
		(width 0.1651)
		(layer "In7.Cu")
		(net "P5E_PEX0_STN2_RX_DP<37>")
	)
	(segment
		(start 53.333904 -266.379706)
		(end 53.464968 -264.886186)
		(width 0.1651)
		(layer "In7.Cu")
		(net "P5E_PEX0_STN2_RX_DP<37>")
	)
	(segment
		(start 60.478416 -30.631638)
		(end 59.501278 -30.631638)
		(width 0.1651)
		(layer "In7.Cu")
		(net "P5E_PEX0_STN2_RX_DP<37>")
	)
	(segment
		(start 53.949854 -274.049744)
		(end 53.949854 -273.784314)
		(width 0.1143)
		(layer "In7.Cu")
		(net "P5E_PEX0_STN2_RX_DP<37>")
	)
	(segment
		(start 53.835554 -273.670014)
		(end 53.642006 -273.670014)
		(width 0.1143)
		(layer "In7.Cu")
		(net "P5E_PEX0_STN2_RX_DP<37>")
	)
	(segment
		(start 53.333904 -271.3736)
		(end 53.333904 -271.345152)
		(width 0.1143)
		(layer "In7.Cu")
		(net "P5E_PEX0_STN2_RX_DP<37>")
	)
	(segment
		(start 62.580774 -37.940234)
		(end 63.106046 -34.981642)
		(width 0.1651)
		(layer "In7.Cu")
		(net "P5E_PEX0_STN2_RX_DP<37>")
	)
	(segment
		(start 59.501278 -30.631638)
		(end 59.210448 -30.922468)
		(width 0.1651)
		(layer "In7.Cu")
		(net "P5E_PEX0_STN2_RX_DP<37>")
	)
	(segment
		(start 53.949854 -273.784314)
		(end 53.835554 -273.670014)
		(width 0.1143)
		(layer "In7.Cu")
		(net "P5E_PEX0_STN2_RX_DP<37>")
	)
	(segment
		(start 53.642006 -273.670014)
		(end 53.379624 -273.407632)
		(width 0.1143)
		(layer "In7.Cu")
		(net "P5E_PEX0_STN2_RX_DP<37>")
	)
	(segment
		(start 63.106046 -34.981642)
		(end 63.129414 -32.088836)
		(width 0.1651)
		(layer "In7.Cu")
		(net "P5E_PEX0_STN2_RX_DP<37>")
	)
	(segment
		(start 60.580016 -30.733238)
		(end 60.478416 -30.631638)
		(width 0.1651)
		(layer "In7.Cu")
		(net "P5E_PEX0_STN2_RX_DP<37>")
	)
	(segment
		(start 53.379624 -273.407632)
		(end 53.379624 -271.41932)
		(width 0.1143)
		(layer "In7.Cu")
		(net "P5E_PEX0_STN2_RX_DP<37>")
	)
	(segment
		(start 62.285118 -31.24454)
		(end 61.672216 -30.631638)
		(width 0.1651)
		(layer "In7.Cu")
		(net "P5E_PEX0_STN2_RX_DP<37>")
	)
	(segment
		(start 61.672216 -30.631638)
		(end 61.176916 -30.631638)
		(width 0.1651)
		(layer "In7.Cu")
		(net "P5E_PEX0_STN2_RX_DP<37>")
	)
	(segment
		(start 53.464968 -264.886186)
		(end 63.838582 -68.490084)
		(width 0.1651)
		(layer "In7.Cu")
		(net "P5E_PEX0_STN2_RX_DP<37>")
	)
	(segment
		(start 53.333904 -271.345152)
		(end 53.333904 -266.379706)
		(width 0.1651)
		(layer "In7.Cu")
		(net "P5E_PEX0_STN2_RX_DP<37>")
	)
	(segment
		(start 63.838582 -68.490084)
		(end 64.022732 -50.12817)
		(width 0.1651)
		(layer "In7.Cu")
		(net "P5E_PEX0_STN2_RX_DP<37>")
	)
	(segment
		(start 64.022732 -50.12817)
		(end 62.65291 -39.991792)
		(width 0.1651)
		(layer "In7.Cu")
		(net "P5E_PEX0_STN2_RX_DP<37>")
	)
	(segment
		(start 62.602618 -39.321486)
		(end 62.580774 -37.940234)
		(width 0.1651)
		(layer "In7.Cu")
		(net "P5E_PEX0_STN2_RX_DP<37>")
	)
	(segment
		(start 53.379624 -271.41932)
		(end 53.333904 -271.3736)
		(width 0.1143)
		(layer "In7.Cu")
		(net "P5E_PEX0_STN2_RX_DP<37>")
	)
	(segment
		(start 61.176916 -30.631638)
		(end 61.075316 -30.733238)
		(width 0.1651)
		(layer "In7.Cu")
		(net "P5E_PEX0_STN2_RX_DP<37>")
	)
	(segment
		(start 61.075316 -30.733238)
		(end 60.580016 -30.733238)
		(width 0.1651)
		(layer "In7.Cu")
		(net "P5E_PEX0_STN2_RX_DP<37>")
	)
	(segment
		(start 136.267952 -33.631886)
		(end 135.947658 -33.95218)
		(width 0.13462)
		(layer "F.Cu")
		(net "P5E_PEX1_STN2_TX_C_DN<47>")
	)
	(segment
		(start 135.947658 -33.95218)
		(end 132.034026 -33.95218)
		(width 0.13462)
		(layer "F.Cu")
		(net "P5E_PEX1_STN2_TX_C_DN<47>")
	)
	(segment
		(start 132.034026 -33.95218)
		(end 131.871974 -33.790128)
		(width 0.13462)
		(layer "F.Cu")
		(net "P5E_PEX1_STN2_TX_C_DN<47>")
	)
	(segment
		(start 131.871974 -33.790128)
		(end 131.36499 -33.790128)
		(width 0.13462)
		(layer "F.Cu")
		(net "P5E_PEX1_STN2_TX_C_DN<47>")
	)
	(segment
		(start 300.378368 -123.03506)
		(end 300.857412 -123.03506)
		(width 0.13462)
		(layer "F.Cu")
		(net "P5E_PEX2_STN0_RX_DP<2>")
	)
	(segment
		(start 299.257212 -123.16714)
		(end 299.551852 -122.8725)
		(width 0.13462)
		(layer "F.Cu")
		(net "P5E_PEX2_STN0_RX_DP<2>")
	)
	(segment
		(start 299.551852 -122.8725)
		(end 300.215808 -122.8725)
		(width 0.13462)
		(layer "F.Cu")
		(net "P5E_PEX2_STN0_RX_DP<2>")
	)
	(segment
		(start 300.215808 -122.8725)
		(end 300.378368 -123.03506)
		(width 0.13462)
		(layer "F.Cu")
		(net "P5E_PEX2_STN0_RX_DP<2>")
	)
	(segment
		(start 302.888904 -124.152152)
		(end 303.346612 -124.342144)
		(width 0.1651)
		(layer "In5.Cu")
		(net "P5E_PEX2_STN0_RX_DP<2>")
	)
	(segment
		(start 299.257212 -123.16714)
		(end 299.548042 -122.87631)
		(width 0.1651)
		(layer "In5.Cu")
		(net "P5E_PEX2_STN0_RX_DP<2>")
	)
	(segment
		(start 319.353692 -232.167938)
		(end 321.01028 -239.951514)
		(width 0.1651)
		(layer "In5.Cu")
		(net "P5E_PEX2_STN0_RX_DP<2>")
	)
	(segment
		(start 317.589662 -285.783782)
		(end 316.12459 -285.783782)
		(width 0.1651)
		(layer "In5.Cu")
		(net "P5E_PEX2_STN0_RX_DP<2>")
	)
	(segment
		(start 302.22063 -123.874276)
		(end 302.369982 -123.812554)
		(width 0.1651)
		(layer "In5.Cu")
		(net "P5E_PEX2_STN0_RX_DP<2>")
	)
	(segment
		(start 329.65136 -269.508732)
		(end 329.488292 -273.073114)
		(width 0.1651)
		(layer "In5.Cu")
		(net "P5E_PEX2_STN0_RX_DP<2>")
	)
	(segment
		(start 302.369982 -123.812554)
		(end 302.827182 -124.002546)
		(width 0.1651)
		(layer "In5.Cu")
		(net "P5E_PEX2_STN0_RX_DP<2>")
	)
	(segment
		(start 318.66332 -143.64208)
		(end 319.56502 -149.98446)
		(width 0.1651)
		(layer "In5.Cu")
		(net "P5E_PEX2_STN0_RX_DP<2>")
	)
	(segment
		(start 301.7012 -123.534424)
		(end 301.762922 -123.68403)
		(width 0.1651)
		(layer "In5.Cu")
		(net "P5E_PEX2_STN0_RX_DP<2>")
	)
	(segment
		(start 300.63694 -123.215908)
		(end 301.094648 -123.406154)
		(width 0.1651)
		(layer "In5.Cu")
		(net "P5E_PEX2_STN0_RX_DP<2>")
	)
	(segment
		(start 308.414166 -129.40284)
		(end 308.688994 -129.814574)
		(width 0.1651)
		(layer "In5.Cu")
		(net "P5E_PEX2_STN0_RX_DP<2>")
	)
	(segment
		(start 316.050422 -285.829502)
		(end 312.423556 -285.829502)
		(width 0.1143)
		(layer "In5.Cu")
		(net "P5E_PEX2_STN0_RX_DP<2>")
	)
	(segment
		(start 309.091076 -130.417062)
		(end 309.365904 -130.828796)
		(width 0.1651)
		(layer "In5.Cu")
		(net "P5E_PEX2_STN0_RX_DP<2>")
	)
	(segment
		(start 329.488292 -273.073114)
		(end 327.21296 -277.083774)
		(width 0.1651)
		(layer "In5.Cu")
		(net "P5E_PEX2_STN0_RX_DP<2>")
	)
	(segment
		(start 306.584604 -126.661164)
		(end 308.012338 -128.800606)
		(width 0.1651)
		(layer "In5.Cu")
		(net "P5E_PEX2_STN0_RX_DP<2>")
	)
	(segment
		(start 309.767986 -131.431284)
		(end 311.629552 -134.220712)
		(width 0.1651)
		(layer "In5.Cu")
		(net "P5E_PEX2_STN0_RX_DP<2>")
	)
	(segment
		(start 309.60949 -131.399788)
		(end 309.767986 -131.431284)
		(width 0.1651)
		(layer "In5.Cu")
		(net "P5E_PEX2_STN0_RX_DP<2>")
	)
	(segment
		(start 309.365904 -130.828796)
		(end 309.334154 -130.987546)
		(width 0.1651)
		(layer "In5.Cu")
		(net "P5E_PEX2_STN0_RX_DP<2>")
	)
	(segment
		(start 319.56502 -149.98446)
		(end 320.06032 -168.457372)
		(width 0.1651)
		(layer "In5.Cu")
		(net "P5E_PEX2_STN0_RX_DP<2>")
	)
	(segment
		(start 308.688994 -129.814574)
		(end 308.657244 -129.973324)
		(width 0.1651)
		(layer "In5.Cu")
		(net "P5E_PEX2_STN0_RX_DP<2>")
	)
	(segment
		(start 301.762922 -123.68403)
		(end 302.22063 -123.874276)
		(width 0.1651)
		(layer "In5.Cu")
		(net "P5E_PEX2_STN0_RX_DP<2>")
	)
	(segment
		(start 311.629552 -134.220712)
		(end 315.914278 -138.49985)
		(width 0.1651)
		(layer "In5.Cu")
		(net "P5E_PEX2_STN0_RX_DP<2>")
	)
	(segment
		(start 300.575218 -123.066302)
		(end 300.63694 -123.215908)
		(width 0.1651)
		(layer "In5.Cu")
		(net "P5E_PEX2_STN0_RX_DP<2>")
	)
	(segment
		(start 299.548042 -122.87631)
		(end 300.118018 -122.87631)
		(width 0.1651)
		(layer "In5.Cu")
		(net "P5E_PEX2_STN0_RX_DP<2>")
	)
	(segment
		(start 308.012338 -128.800606)
		(end 307.980588 -128.959102)
		(width 0.1651)
		(layer "In5.Cu")
		(net "P5E_PEX2_STN0_RX_DP<2>")
	)
	(segment
		(start 316.12459 -285.783782)
		(end 316.096142 -285.783782)
		(width 0.1143)
		(layer "In5.Cu")
		(net "P5E_PEX2_STN0_RX_DP<2>")
	)
	(segment
		(start 307.980588 -128.959102)
		(end 308.255924 -129.371344)
		(width 0.1651)
		(layer "In5.Cu")
		(net "P5E_PEX2_STN0_RX_DP<2>")
	)
	(segment
		(start 309.334154 -130.987546)
		(end 309.60949 -131.399788)
		(width 0.1651)
		(layer "In5.Cu")
		(net "P5E_PEX2_STN0_RX_DP<2>")
	)
	(segment
		(start 316.096142 -285.783782)
		(end 316.050422 -285.829502)
		(width 0.1143)
		(layer "In5.Cu")
		(net "P5E_PEX2_STN0_RX_DP<2>")
	)
	(segment
		(start 312.179462 -286.285432)
		(end 312.065162 -286.399732)
		(width 0.1143)
		(layer "In5.Cu")
		(net "P5E_PEX2_STN0_RX_DP<2>")
	)
	(segment
		(start 308.255924 -129.371344)
		(end 308.41442 -129.40284)
		(width 0.1651)
		(layer "In5.Cu")
		(net "P5E_PEX2_STN0_RX_DP<2>")
	)
	(segment
		(start 303.495964 -124.280676)
		(end 304.728626 -124.79274)
		(width 0.1651)
		(layer "In5.Cu")
		(net "P5E_PEX2_STN0_RX_DP<2>")
	)
	(segment
		(start 321.01028 -239.951514)
		(end 329.65136 -269.508732)
		(width 0.1651)
		(layer "In5.Cu")
		(net "P5E_PEX2_STN0_RX_DP<2>")
	)
	(segment
		(start 318.973962 -285.067248)
		(end 317.589662 -285.783782)
		(width 0.1651)
		(layer "In5.Cu")
		(net "P5E_PEX2_STN0_RX_DP<2>")
	)
	(segment
		(start 308.657244 -129.973324)
		(end 308.93258 -130.385566)
		(width 0.1651)
		(layer "In5.Cu")
		(net "P5E_PEX2_STN0_RX_DP<2>")
	)
	(segment
		(start 320.06032 -168.457372)
		(end 319.353692 -232.167938)
		(width 0.1651)
		(layer "In5.Cu")
		(net "P5E_PEX2_STN0_RX_DP<2>")
	)
	(segment
		(start 315.914278 -138.49985)
		(end 318.66332 -143.64208)
		(width 0.1651)
		(layer "In5.Cu")
		(net "P5E_PEX2_STN0_RX_DP<2>")
	)
	(segment
		(start 312.423556 -285.829502)
		(end 312.179462 -286.073596)
		(width 0.1143)
		(layer "In5.Cu")
		(net "P5E_PEX2_STN0_RX_DP<2>")
	)
	(segment
		(start 303.346612 -124.342144)
		(end 303.495964 -124.280676)
		(width 0.1651)
		(layer "In5.Cu")
		(net "P5E_PEX2_STN0_RX_DP<2>")
	)
	(segment
		(start 301.094648 -123.406154)
		(end 301.244 -123.344432)
		(width 0.1651)
		(layer "In5.Cu")
		(net "P5E_PEX2_STN0_RX_DP<2>")
	)
	(segment
		(start 302.827182 -124.002546)
		(end 302.888904 -124.152152)
		(width 0.1651)
		(layer "In5.Cu")
		(net "P5E_PEX2_STN0_RX_DP<2>")
	)
	(segment
		(start 308.93258 -130.385566)
		(end 309.091076 -130.417062)
		(width 0.1651)
		(layer "In5.Cu")
		(net "P5E_PEX2_STN0_RX_DP<2>")
	)
	(segment
		(start 327.21296 -277.083774)
		(end 318.973962 -285.067248)
		(width 0.1651)
		(layer "In5.Cu")
		(net "P5E_PEX2_STN0_RX_DP<2>")
	)
	(segment
		(start 300.118018 -122.87631)
		(end 300.575218 -123.066302)
		(width 0.1651)
		(layer "In5.Cu")
		(net "P5E_PEX2_STN0_RX_DP<2>")
	)
	(segment
		(start 308.41442 -129.40284)
		(end 308.414166 -129.40284)
		(width 0.1651)
		(layer "In5.Cu")
		(net "P5E_PEX2_STN0_RX_DP<2>")
	)
	(segment
		(start 312.179462 -286.073596)
		(end 312.179462 -286.285432)
		(width 0.1143)
		(layer "In5.Cu")
		(net "P5E_PEX2_STN0_RX_DP<2>")
	)
	(segment
		(start 301.244 -123.344432)
		(end 301.7012 -123.534424)
		(width 0.1651)
		(layer "In5.Cu")
		(net "P5E_PEX2_STN0_RX_DP<2>")
	)
	(segment
		(start 304.728626 -124.79274)
		(end 306.584604 -126.661164)
		(width 0.1651)
		(layer "In5.Cu")
		(net "P5E_PEX2_STN0_RX_DP<2>")
	)
	(segment
		(start 312.065162 -286.399732)
		(end 311.799732 -286.399732)
		(width 0.1143)
		(layer "In5.Cu")
		(net "P5E_PEX2_STN0_RX_DP<2>")
	)
	(segment
		(start 372.07698 -350.365314)
		(end 371.757448 -350.684846)
		(width 0.13462)
		(layer "F.Cu")
		(net "P5E_PEX3_STN6_TX_C_DN<103>")
	)
	(segment
		(start 371.757448 -351.317306)
		(end 372.05158 -351.611438)
		(width 0.13462)
		(layer "F.Cu")
		(net "P5E_PEX3_STN6_TX_C_DN<103>")
	)
	(segment
		(start 371.757448 -350.684846)
		(end 371.757448 -351.317306)
		(width 0.13462)
		(layer "F.Cu")
		(net "P5E_PEX3_STN6_TX_C_DN<103>")
	)
	(segment
		(start 376.164094 -382.9812)
		(end 375.616978 -382.9812)
		(width 0.1651)
		(layer "In7.Cu")
		(net "P5E_PEX3_STN6_TX_C_DN<103>")
	)
	(segment
		(start 375.616978 -382.9812)
		(end 375.489978 -383.1082)
		(width 0.1651)
		(layer "In7.Cu")
		(net "P5E_PEX3_STN6_TX_C_DN<103>")
	)
	(segment
		(start 371.76075 -351.902268)
		(end 371.76075 -358.483662)
		(width 0.1651)
		(layer "In7.Cu")
		(net "P5E_PEX3_STN6_TX_C_DN<103>")
	)
	(segment
		(start 376.61596 -382.529334)
		(end 376.164094 -382.9812)
		(width 0.1651)
		(layer "In7.Cu")
		(net "P5E_PEX3_STN6_TX_C_DN<103>")
	)
	(segment
		(start 371.76075 -358.483662)
		(end 376.61596 -368.910362)
		(width 0.1651)
		(layer "In7.Cu")
		(net "P5E_PEX3_STN6_TX_C_DN<103>")
	)
	(segment
		(start 372.05158 -351.611438)
		(end 371.76075 -351.902268)
		(width 0.1651)
		(layer "In7.Cu")
		(net "P5E_PEX3_STN6_TX_C_DN<103>")
	)
	(segment
		(start 376.61596 -368.910362)
		(end 376.61596 -382.529334)
		(width 0.1651)
		(layer "In7.Cu")
		(net "P5E_PEX3_STN6_TX_C_DN<103>")
	)
	(segment
		(start 375.489978 -383.1082)
		(end 375.489978 -383.490216)
		(width 0.1651)
		(layer "In7.Cu")
		(net "P5E_PEX3_STN6_TX_C_DN<103>")
	)
	(segment
		(start 126.76505 -28.990036)
		(end 126.76505 -28.99029)
		(width 0.13462)
		(layer "F.Cu")
		(net "P5E_PEX1_STN2_RX_DP<44>")
	)
	(segment
		(start 126.286006 -28.99029)
		(end 126.124716 -28.829)
		(width 0.13462)
		(layer "F.Cu")
		(net "P5E_PEX1_STN2_RX_DP<44>")
	)
	(segment
		(start 126.76505 -28.99029)
		(end 126.286006 -28.99029)
		(width 0.13462)
		(layer "F.Cu")
		(net "P5E_PEX1_STN2_RX_DP<44>")
	)
	(segment
		(start 125.45822 -28.829)
		(end 125.16485 -29.12237)
		(width 0.13462)
		(layer "F.Cu")
		(net "P5E_PEX1_STN2_RX_DP<44>")
	)
	(segment
		(start 126.124716 -28.829)
		(end 125.45822 -28.829)
		(width 0.13462)
		(layer "F.Cu")
		(net "P5E_PEX1_STN2_RX_DP<44>")
	)
	(segment
		(start 131.125214 -39.137844)
		(end 128.979168 -49.388014)
		(width 0.1651)
		(layer "In7.Cu")
		(net "P5E_PEX1_STN2_RX_DP<44>")
	)
	(segment
		(start 163.044886 -275.570188)
		(end 163.285678 -275.570188)
		(width 0.1143)
		(layer "In7.Cu")
		(net "P5E_PEX1_STN2_RX_DP<44>")
	)
	(segment
		(start 125.410214 -28.877006)
		(end 125.519942 -28.83154)
		(width 0.1651)
		(layer "In7.Cu")
		(net "P5E_PEX1_STN2_RX_DP<44>")
	)
	(segment
		(start 163.285678 -275.570188)
		(end 163.399978 -275.684488)
		(width 0.1143)
		(layer "In7.Cu")
		(net "P5E_PEX1_STN2_RX_DP<44>")
	)
	(segment
		(start 162.783774 -271.421352)
		(end 162.829494 -271.467072)
		(width 0.1143)
		(layer "In7.Cu")
		(net "P5E_PEX1_STN2_RX_DP<44>")
	)
	(segment
		(start 131.148582 -37.742622)
		(end 131.125214 -39.137844)
		(width 0.1651)
		(layer "In7.Cu")
		(net "P5E_PEX1_STN2_RX_DP<44>")
	)
	(segment
		(start 128.93548 -85.214206)
		(end 139.300204 -119.40921)
		(width 0.1651)
		(layer "In7.Cu")
		(net "P5E_PEX1_STN2_RX_DP<44>")
	)
	(segment
		(start 128.997202 -32.89808)
		(end 129.189734 -33.354772)
		(width 0.1651)
		(layer "In7.Cu")
		(net "P5E_PEX1_STN2_RX_DP<44>")
	)
	(segment
		(start 129.460752 -33.998154)
		(end 129.653284 -34.454846)
		(width 0.1651)
		(layer "In7.Cu")
		(net "P5E_PEX1_STN2_RX_DP<44>")
	)
	(segment
		(start 127.26035 -30.634432)
		(end 128.804416 -32.178498)
		(width 0.1651)
		(layer "In7.Cu")
		(net "P5E_PEX1_STN2_RX_DP<44>")
	)
	(segment
		(start 128.804416 -32.178498)
		(end 129.051304 -32.764984)
		(width 0.1651)
		(layer "In7.Cu")
		(net "P5E_PEX1_STN2_RX_DP<44>")
	)
	(segment
		(start 160.301686 -238.07547)
		(end 161.907728 -255.61925)
		(width 0.1651)
		(layer "In7.Cu")
		(net "P5E_PEX1_STN2_RX_DP<44>")
	)
	(segment
		(start 125.16485 -29.12237)
		(end 125.410214 -28.877006)
		(width 0.1651)
		(layer "In7.Cu")
		(net "P5E_PEX1_STN2_RX_DP<44>")
	)
	(segment
		(start 142.587218 -144.398238)
		(end 160.301686 -238.07547)
		(width 0.1651)
		(layer "In7.Cu")
		(net "P5E_PEX1_STN2_RX_DP<44>")
	)
	(segment
		(start 162.783774 -269.523718)
		(end 162.783774 -271.392904)
		(width 0.1651)
		(layer "In7.Cu")
		(net "P5E_PEX1_STN2_RX_DP<44>")
	)
	(segment
		(start 129.051304 -32.764984)
		(end 128.997202 -32.89808)
		(width 0.1651)
		(layer "In7.Cu")
		(net "P5E_PEX1_STN2_RX_DP<44>")
	)
	(segment
		(start 163.399978 -275.684488)
		(end 163.399978 -275.949918)
		(width 0.1143)
		(layer "In7.Cu")
		(net "P5E_PEX1_STN2_RX_DP<44>")
	)
	(segment
		(start 126.59614 -29.64053)
		(end 127.26035 -30.634432)
		(width 0.1651)
		(layer "In7.Cu")
		(net "P5E_PEX1_STN2_RX_DP<44>")
	)
	(segment
		(start 128.979168 -49.388014)
		(end 128.855216 -57.335674)
		(width 0.1651)
		(layer "In7.Cu")
		(net "P5E_PEX1_STN2_RX_DP<44>")
	)
	(segment
		(start 129.515108 -33.865312)
		(end 129.460752 -33.998154)
		(width 0.1651)
		(layer "In7.Cu")
		(net "P5E_PEX1_STN2_RX_DP<44>")
	)
	(segment
		(start 128.855216 -57.335674)
		(end 129.124964 -60.073794)
		(width 0.1651)
		(layer "In7.Cu")
		(net "P5E_PEX1_STN2_RX_DP<44>")
	)
	(segment
		(start 129.32283 -33.408874)
		(end 129.515108 -33.865312)
		(width 0.1651)
		(layer "In7.Cu")
		(net "P5E_PEX1_STN2_RX_DP<44>")
	)
	(segment
		(start 129.78638 -34.509202)
		(end 131.148582 -37.742622)
		(width 0.1651)
		(layer "In7.Cu")
		(net "P5E_PEX1_STN2_RX_DP<44>")
	)
	(segment
		(start 162.829494 -275.354796)
		(end 163.044886 -275.570188)
		(width 0.1143)
		(layer "In7.Cu")
		(net "P5E_PEX1_STN2_RX_DP<44>")
	)
	(segment
		(start 129.653284 -34.454846)
		(end 129.78638 -34.509202)
		(width 0.1651)
		(layer "In7.Cu")
		(net "P5E_PEX1_STN2_RX_DP<44>")
	)
	(segment
		(start 129.124964 -61.849762)
		(end 128.93548 -85.214206)
		(width 0.1651)
		(layer "In7.Cu")
		(net "P5E_PEX1_STN2_RX_DP<44>")
	)
	(segment
		(start 161.830766 -263.48055)
		(end 162.783774 -269.523718)
		(width 0.1651)
		(layer "In7.Cu")
		(net "P5E_PEX1_STN2_RX_DP<44>")
	)
	(segment
		(start 125.78715 -28.83154)
		(end 126.59614 -29.64053)
		(width 0.1651)
		(layer "In7.Cu")
		(net "P5E_PEX1_STN2_RX_DP<44>")
	)
	(segment
		(start 139.300204 -119.40921)
		(end 142.587218 -144.398238)
		(width 0.1651)
		(layer "In7.Cu")
		(net "P5E_PEX1_STN2_RX_DP<44>")
	)
	(segment
		(start 129.189734 -33.354772)
		(end 129.32283 -33.408874)
		(width 0.1651)
		(layer "In7.Cu")
		(net "P5E_PEX1_STN2_RX_DP<44>")
	)
	(segment
		(start 125.519942 -28.83154)
		(end 125.78715 -28.83154)
		(width 0.1651)
		(layer "In7.Cu")
		(net "P5E_PEX1_STN2_RX_DP<44>")
	)
	(segment
		(start 162.829494 -271.467072)
		(end 162.829494 -275.354796)
		(width 0.1143)
		(layer "In7.Cu")
		(net "P5E_PEX1_STN2_RX_DP<44>")
	)
	(segment
		(start 161.907728 -255.61925)
		(end 161.830766 -263.48055)
		(width 0.1651)
		(layer "In7.Cu")
		(net "P5E_PEX1_STN2_RX_DP<44>")
	)
	(segment
		(start 129.124964 -60.073794)
		(end 129.124964 -61.849762)
		(width 0.1651)
		(layer "In7.Cu")
		(net "P5E_PEX1_STN2_RX_DP<44>")
	)
	(segment
		(start 162.783774 -271.392904)
		(end 162.783774 -271.421352)
		(width 0.1143)
		(layer "In7.Cu")
		(net "P5E_PEX1_STN2_RX_DP<44>")
	)
	(segment
		(start 300.379892 -151.755094)
		(end 300.857412 -151.755094)
		(width 0.13462)
		(layer "F.Cu")
		(net "P5E_PEX2_STN0_RX_DN<13>")
	)
	(segment
		(start 300.212506 -151.92248)
		(end 300.379892 -151.755094)
		(width 0.13462)
		(layer "F.Cu")
		(net "P5E_PEX2_STN0_RX_DN<13>")
	)
	(segment
		(start 297.403012 -151.623776)
		(end 297.701716 -151.92248)
		(width 0.13462)
		(layer "F.Cu")
		(net "P5E_PEX2_STN0_RX_DN<13>")
	)
	(segment
		(start 297.701716 -151.92248)
		(end 300.212506 -151.92248)
		(width 0.13462)
		(layer "F.Cu")
		(net "P5E_PEX2_STN0_RX_DN<13>")
	)
	(segment
		(start 308.835298 -273.479514)
		(end 308.949598 -273.365214)
		(width 0.1143)
		(layer "In5.Cu")
		(net "P5E_PEX2_STN0_RX_DN<13>")
	)
	(segment
		(start 308.615842 -270.540226)
		(end 308.615842 -271.526)
		(width 0.1651)
		(layer "In5.Cu")
		(net "P5E_PEX2_STN0_RX_DN<13>")
	)
	(segment
		(start 305.501548 -161.295334)
		(end 309.057548 -260.64464)
		(width 0.1651)
		(layer "In5.Cu")
		(net "P5E_PEX2_STN0_RX_DN<13>")
	)
	(segment
		(start 308.615842 -271.554448)
		(end 308.570122 -271.600168)
		(width 0.1143)
		(layer "In5.Cu")
		(net "P5E_PEX2_STN0_RX_DN<13>")
	)
	(segment
		(start 308.6735 -273.479514)
		(end 308.835298 -273.479514)
		(width 0.1143)
		(layer "In5.Cu")
		(net "P5E_PEX2_STN0_RX_DN<13>")
	)
	(segment
		(start 308.615842 -271.526)
		(end 308.615842 -271.554448)
		(width 0.1143)
		(layer "In5.Cu")
		(net "P5E_PEX2_STN0_RX_DN<13>")
	)
	(segment
		(start 309.132732 -267.869924)
		(end 308.615842 -270.540226)
		(width 0.1651)
		(layer "In5.Cu")
		(net "P5E_PEX2_STN0_RX_DN<13>")
	)
	(segment
		(start 304.464974 -158.80207)
		(end 304.475896 -158.828232)
		(width 0.1651)
		(layer "In5.Cu")
		(net "P5E_PEX2_STN0_RX_DN<13>")
	)
	(segment
		(start 297.403012 -151.623776)
		(end 297.693842 -151.914606)
		(width 0.1651)
		(layer "In5.Cu")
		(net "P5E_PEX2_STN0_RX_DN<13>")
	)
	(segment
		(start 304.475642 -158.828232)
		(end 305.501548 -161.295334)
		(width 0.1651)
		(layer "In5.Cu")
		(net "P5E_PEX2_STN0_RX_DN<13>")
	)
	(segment
		(start 300.014894 -151.914606)
		(end 301.059342 -152.959054)
		(width 0.1651)
		(layer "In5.Cu")
		(net "P5E_PEX2_STN0_RX_DN<13>")
	)
	(segment
		(start 297.693842 -151.914606)
		(end 300.014894 -151.914606)
		(width 0.1651)
		(layer "In5.Cu")
		(net "P5E_PEX2_STN0_RX_DN<13>")
	)
	(segment
		(start 308.949598 -273.365214)
		(end 308.949598 -273.099784)
		(width 0.1143)
		(layer "In5.Cu")
		(net "P5E_PEX2_STN0_RX_DN<13>")
	)
	(segment
		(start 301.059342 -152.959054)
		(end 301.931324 -155.050998)
		(width 0.1651)
		(layer "In5.Cu")
		(net "P5E_PEX2_STN0_RX_DN<13>")
	)
	(segment
		(start 308.570122 -273.376136)
		(end 308.6735 -273.479514)
		(width 0.1143)
		(layer "In5.Cu")
		(net "P5E_PEX2_STN0_RX_DN<13>")
	)
	(segment
		(start 308.570122 -271.600168)
		(end 308.570122 -273.376136)
		(width 0.1143)
		(layer "In5.Cu")
		(net "P5E_PEX2_STN0_RX_DN<13>")
	)
	(segment
		(start 301.931324 -155.050998)
		(end 304.464974 -158.80207)
		(width 0.1651)
		(layer "In5.Cu")
		(net "P5E_PEX2_STN0_RX_DN<13>")
	)
	(segment
		(start 304.475896 -158.828232)
		(end 304.475642 -158.828232)
		(width 0.1651)
		(layer "In5.Cu")
		(net "P5E_PEX2_STN0_RX_DN<13>")
	)
	(segment
		(start 309.057548 -260.64464)
		(end 309.132732 -267.869924)
		(width 0.1651)
		(layer "In5.Cu")
		(net "P5E_PEX2_STN0_RX_DN<13>")
	)
	(segment
		(start 374.27154 -350.365314)
		(end 374.592088 -350.685862)
		(width 0.13462)
		(layer "F.Cu")
		(net "P5E_PEX3_STN6_TX_C_DP<110>")
	)
	(segment
		(start 374.592088 -351.31629)
		(end 374.29694 -351.611438)
		(width 0.13462)
		(layer "F.Cu")
		(net "P5E_PEX3_STN6_TX_C_DP<110>")
	)
	(segment
		(start 374.592088 -350.685862)
		(end 374.592088 -351.31629)
		(width 0.13462)
		(layer "F.Cu")
		(net "P5E_PEX3_STN6_TX_C_DP<110>")
	)
	(segment
		(start 377.689872 -409.290012)
		(end 377.689872 -409.672028)
		(width 0.1651)
		(layer "In13.Cu")
		(net "P5E_PEX3_STN6_TX_C_DP<110>")
	)
	(segment
		(start 377.155456 -394.205206)
		(end 375.533412 -392.927078)
		(width 0.1651)
		(layer "In13.Cu")
		(net "P5E_PEX3_STN6_TX_C_DP<110>")
	)
	(segment
		(start 368.231928 -385.875276)
		(end 367.681002 -373.323104)
		(width 0.1651)
		(layer "In13.Cu")
		(net "P5E_PEX3_STN6_TX_C_DP<110>")
	)
	(segment
		(start 378.533914 -409.512262)
		(end 378.533914 -396.53464)
		(width 0.1651)
		(layer "In13.Cu")
		(net "P5E_PEX3_STN6_TX_C_DP<110>")
	)
	(segment
		(start 378.269754 -395.634464)
		(end 377.155456 -394.205206)
		(width 0.1651)
		(layer "In13.Cu")
		(net "P5E_PEX3_STN6_TX_C_DP<110>")
	)
	(segment
		(start 368.335814 -367.114582)
		(end 373.07012 -353.873562)
		(width 0.1651)
		(layer "In13.Cu")
		(net "P5E_PEX3_STN6_TX_C_DP<110>")
	)
	(segment
		(start 374.58777 -351.902268)
		(end 374.29694 -351.611438)
		(width 0.1651)
		(layer "In13.Cu")
		(net "P5E_PEX3_STN6_TX_C_DP<110>")
	)
	(segment
		(start 378.247148 -409.799028)
		(end 378.533914 -409.512262)
		(width 0.1651)
		(layer "In13.Cu")
		(net "P5E_PEX3_STN6_TX_C_DP<110>")
	)
	(segment
		(start 377.689872 -409.672028)
		(end 377.816872 -409.799028)
		(width 0.1651)
		(layer "In13.Cu")
		(net "P5E_PEX3_STN6_TX_C_DP<110>")
	)
	(segment
		(start 377.816872 -409.799028)
		(end 378.247148 -409.799028)
		(width 0.1651)
		(layer "In13.Cu")
		(net "P5E_PEX3_STN6_TX_C_DP<110>")
	)
	(segment
		(start 369.625372 -389.243824)
		(end 368.231928 -385.875276)
		(width 0.1651)
		(layer "In13.Cu")
		(net "P5E_PEX3_STN6_TX_C_DP<110>")
	)
	(segment
		(start 375.533412 -392.927078)
		(end 373.024146 -391.800334)
		(width 0.1651)
		(layer "In13.Cu")
		(net "P5E_PEX3_STN6_TX_C_DP<110>")
	)
	(segment
		(start 373.07012 -353.873562)
		(end 374.58777 -352.356166)
		(width 0.1651)
		(layer "In13.Cu")
		(net "P5E_PEX3_STN6_TX_C_DP<110>")
	)
	(segment
		(start 378.533914 -396.53464)
		(end 378.269754 -395.634464)
		(width 0.1651)
		(layer "In13.Cu")
		(net "P5E_PEX3_STN6_TX_C_DP<110>")
	)
	(segment
		(start 374.58777 -352.356166)
		(end 374.58777 -351.902268)
		(width 0.1651)
		(layer "In13.Cu")
		(net "P5E_PEX3_STN6_TX_C_DP<110>")
	)
	(segment
		(start 373.024146 -391.800334)
		(end 369.625372 -389.243824)
		(width 0.1651)
		(layer "In13.Cu")
		(net "P5E_PEX3_STN6_TX_C_DP<110>")
	)
	(segment
		(start 367.681002 -373.323104)
		(end 368.335814 -367.114582)
		(width 0.1651)
		(layer "In13.Cu")
		(net "P5E_PEX3_STN6_TX_C_DP<110>")
	)
	(segment
		(start 44.951396 -158.36011)
		(end 46.042326 -158.36011)
		(width 0.13208)
		(layer "F.Cu")
		(net "PWRGD_NIC0_PWR_GOOD")
	)
	(segment
		(start 40.818562 -161.501074)
		(end 41.810432 -161.501074)
		(width 0.13208)
		(layer "F.Cu")
		(net "PWRGD_NIC0_PWR_GOOD")
	)
	(segment
		(start 39.00805 -163.061396)
		(end 39.00805 -162.044126)
		(width 0.13208)
		(layer "F.Cu")
		(net "PWRGD_NIC0_PWR_GOOD")
	)
	(segment
		(start 39.00805 -162.044126)
		(end 40.27043 -162.044126)
		(width 0.13208)
		(layer "F.Cu")
		(net "PWRGD_NIC0_PWR_GOOD")
	)
	(segment
		(start 41.810432 -161.501074)
		(end 44.951396 -158.36011)
		(width 0.13208)
		(layer "F.Cu")
		(net "PWRGD_NIC0_PWR_GOOD")
	)
	(segment
		(start 40.27297 -162.046666)
		(end 40.818562 -161.501074)
		(width 0.13208)
		(layer "F.Cu")
		(net "PWRGD_NIC0_PWR_GOOD")
	)
	(segment
		(start 40.27043 -162.044126)
		(end 40.27297 -162.046666)
		(width 0.13208)
		(layer "F.Cu")
		(net "PWRGD_NIC0_PWR_GOOD")
	)
	(via
		(at 40.27297 -162.046666)
		(size 0.762)
		(drill 0.381)
		(layers "F.Cu" "B.Cu")
		(net "PWRGD_NIC0_PWR_GOOD")
	)
	(segment
		(start 88.187276 -33.790128)
		(end 88.024462 -33.952942)
		(width 0.13462)
		(layer "F.Cu")
		(net "P5E_PEX0_STN2_RX_DN<35>")
	)
	(segment
		(start 88.024462 -33.952942)
		(end 85.504528 -33.952942)
		(width 0.13462)
		(layer "F.Cu")
		(net "P5E_PEX0_STN2_RX_DN<35>")
	)
	(segment
		(start 88.664796 -33.790128)
		(end 88.187276 -33.790128)
		(width 0.13462)
		(layer "F.Cu")
		(net "P5E_PEX0_STN2_RX_DN<35>")
	)
	(segment
		(start 85.504528 -33.952942)
		(end 85.210396 -33.65881)
		(width 0.13462)
		(layer "F.Cu")
		(net "P5E_PEX0_STN2_RX_DN<35>")
	)
	(segment
		(start 55.84063 -266.758166)
		(end 75.407012 -154.40914)
		(width 0.1651)
		(layer "In7.Cu")
		(net "P5E_PEX0_STN2_RX_DN<35>")
	)
	(segment
		(start 55.849774 -273.099784)
		(end 55.849774 -273.365214)
		(width 0.1143)
		(layer "In7.Cu")
		(net "P5E_PEX0_STN2_RX_DN<35>")
	)
	(segment
		(start 85.501226 -33.94964)
		(end 85.210396 -33.65881)
		(width 0.1651)
		(layer "In7.Cu")
		(net "P5E_PEX0_STN2_RX_DN<35>")
	)
	(segment
		(start 76.787248 -143.682974)
		(end 77.102716 -116.50345)
		(width 0.1651)
		(layer "In7.Cu")
		(net "P5E_PEX0_STN2_RX_DN<35>")
	)
	(segment
		(start 88.088978 -61.12764)
		(end 88.270588 -49.490884)
		(width 0.1651)
		(layer "In7.Cu")
		(net "P5E_PEX0_STN2_RX_DN<35>")
	)
	(segment
		(start 55.62092 -273.479514)
		(end 55.470044 -273.328638)
		(width 0.1143)
		(layer "In7.Cu")
		(net "P5E_PEX0_STN2_RX_DN<35>")
	)
	(segment
		(start 77.102716 -116.50345)
		(end 88.088978 -61.12764)
		(width 0.1651)
		(layer "In7.Cu")
		(net "P5E_PEX0_STN2_RX_DN<35>")
	)
	(segment
		(start 55.515764 -271.3736)
		(end 55.515764 -271.345152)
		(width 0.1143)
		(layer "In7.Cu")
		(net "P5E_PEX0_STN2_RX_DN<35>")
	)
	(segment
		(start 55.470044 -273.328638)
		(end 55.470044 -271.41932)
		(width 0.1143)
		(layer "In7.Cu")
		(net "P5E_PEX0_STN2_RX_DN<35>")
	)
	(segment
		(start 55.849774 -273.365214)
		(end 55.735474 -273.479514)
		(width 0.1143)
		(layer "In7.Cu")
		(net "P5E_PEX0_STN2_RX_DN<35>")
	)
	(segment
		(start 55.735474 -273.479514)
		(end 55.62092 -273.479514)
		(width 0.1143)
		(layer "In7.Cu")
		(net "P5E_PEX0_STN2_RX_DN<35>")
	)
	(segment
		(start 75.407012 -154.40914)
		(end 76.787248 -143.682974)
		(width 0.1651)
		(layer "In7.Cu")
		(net "P5E_PEX0_STN2_RX_DN<35>")
	)
	(segment
		(start 88.270588 -49.490884)
		(end 86.932008 -39.583614)
		(width 0.1651)
		(layer "In7.Cu")
		(net "P5E_PEX0_STN2_RX_DN<35>")
	)
	(segment
		(start 86.860888 -34.714688)
		(end 86.09584 -33.94964)
		(width 0.1651)
		(layer "In7.Cu")
		(net "P5E_PEX0_STN2_RX_DN<35>")
	)
	(segment
		(start 55.470044 -271.41932)
		(end 55.515764 -271.3736)
		(width 0.1143)
		(layer "In7.Cu")
		(net "P5E_PEX0_STN2_RX_DN<35>")
	)
	(segment
		(start 55.515764 -271.345152)
		(end 55.515764 -270.511524)
		(width 0.1651)
		(layer "In7.Cu")
		(net "P5E_PEX0_STN2_RX_DN<35>")
	)
	(segment
		(start 86.09584 -33.94964)
		(end 85.501226 -33.94964)
		(width 0.1651)
		(layer "In7.Cu")
		(net "P5E_PEX0_STN2_RX_DN<35>")
	)
	(segment
		(start 55.515764 -270.511524)
		(end 55.84063 -266.758166)
		(width 0.1651)
		(layer "In7.Cu")
		(net "P5E_PEX0_STN2_RX_DN<35>")
	)
	(segment
		(start 86.932008 -39.583614)
		(end 86.860888 -34.714688)
		(width 0.1651)
		(layer "In7.Cu")
		(net "P5E_PEX0_STN2_RX_DN<35>")
	)
	(segment
		(start 157.868112 -30.190186)
		(end 157.364938 -30.190186)
		(width 0.13462)
		(layer "F.Cu")
		(net "P5E_PEX1_STN2_TX_C_DN<41>")
	)
	(segment
		(start 158.036006 -30.35808)
		(end 157.868112 -30.190186)
		(width 0.13462)
		(layer "F.Cu")
		(net "P5E_PEX1_STN2_TX_C_DN<41>")
	)
	(segment
		(start 161.94151 -30.35808)
		(end 158.036006 -30.35808)
		(width 0.13462)
		(layer "F.Cu")
		(net "P5E_PEX1_STN2_TX_C_DN<41>")
	)
	(segment
		(start 162.2679 -30.03169)
		(end 161.94151 -30.35808)
		(width 0.13462)
		(layer "F.Cu")
		(net "P5E_PEX1_STN2_TX_C_DN<41>")
	)
	(segment
		(start 300.857412 -124.834904)
		(end 300.374812 -124.834904)
		(width 0.13462)
		(layer "F.Cu")
		(net "P5E_PEX2_STN0_RX_DP<3>")
	)
	(segment
		(start 300.374812 -124.834904)
		(end 300.203108 -124.6632)
		(width 0.13462)
		(layer "F.Cu")
		(net "P5E_PEX2_STN0_RX_DP<3>")
	)
	(segment
		(start 300.203108 -124.6632)
		(end 297.70705 -124.6632)
		(width 0.13462)
		(layer "F.Cu")
		(net "P5E_PEX2_STN0_RX_DP<3>")
	)
	(segment
		(start 297.70705 -124.6632)
		(end 297.403012 -124.967238)
		(width 0.13462)
		(layer "F.Cu")
		(net "P5E_PEX2_STN0_RX_DP<3>")
	)
	(segment
		(start 302.971708 -125.642624)
		(end 302.822356 -125.704346)
		(width 0.1651)
		(layer "In5.Cu")
		(net "P5E_PEX2_STN0_RX_DP<3>")
	)
	(segment
		(start 308.15788 -131.381246)
		(end 308.001162 -131.341876)
		(width 0.1651)
		(layer "In5.Cu")
		(net "P5E_PEX2_STN0_RX_DP<3>")
	)
	(segment
		(start 308.783228 -132.42798)
		(end 308.62651 -132.38861)
		(width 0.1651)
		(layer "In5.Cu")
		(net "P5E_PEX2_STN0_RX_DP<3>")
	)
	(segment
		(start 306.460652 -128.540256)
		(end 306.303934 -128.500632)
		(width 0.1651)
		(layer "In5.Cu")
		(net "P5E_PEX2_STN0_RX_DP<3>")
	)
	(segment
		(start 304.858674 -126.426722)
		(end 302.971708 -125.642624)
		(width 0.1651)
		(layer "In5.Cu")
		(net "P5E_PEX2_STN0_RX_DP<3>")
	)
	(segment
		(start 301.68596 -125.107954)
		(end 300.923452 -124.960634)
		(width 0.1651)
		(layer "In5.Cu")
		(net "P5E_PEX2_STN0_RX_DP<3>")
	)
	(segment
		(start 307.532532 -130.334512)
		(end 307.532786 -130.334512)
		(width 0.1651)
		(layer "In5.Cu")
		(net "P5E_PEX2_STN0_RX_DP<3>")
	)
	(segment
		(start 316.121542 -284.833822)
		(end 316.14999 -284.833822)
		(width 0.1143)
		(layer "In5.Cu")
		(net "P5E_PEX2_STN0_RX_DP<3>")
	)
	(segment
		(start 314.079636 -285.335472)
		(end 314.079636 -285.09468)
		(width 0.1143)
		(layer "In5.Cu")
		(net "P5E_PEX2_STN0_RX_DP<3>")
	)
	(segment
		(start 320.119756 -240.358422)
		(end 318.389254 -232.225596)
		(width 0.1651)
		(layer "In5.Cu")
		(net "P5E_PEX2_STN0_RX_DP<3>")
	)
	(segment
		(start 308.001162 -131.341876)
		(end 307.746908 -130.916426)
		(width 0.1651)
		(layer "In5.Cu")
		(net "P5E_PEX2_STN0_RX_DP<3>")
	)
	(segment
		(start 306.303934 -128.500632)
		(end 306.049426 -128.075182)
		(width 0.1651)
		(layer "In5.Cu")
		(net "P5E_PEX2_STN0_RX_DP<3>")
	)
	(segment
		(start 297.693842 -124.676408)
		(end 297.403012 -124.967238)
		(width 0.1651)
		(layer "In5.Cu")
		(net "P5E_PEX2_STN0_RX_DP<3>")
	)
	(segment
		(start 302.364902 -125.514354)
		(end 302.30318 -125.364748)
		(width 0.1651)
		(layer "In5.Cu")
		(net "P5E_PEX2_STN0_RX_DP<3>")
	)
	(segment
		(start 326.452738 -276.487382)
		(end 328.544682 -272.77822)
		(width 0.1651)
		(layer "In5.Cu")
		(net "P5E_PEX2_STN0_RX_DP<3>")
	)
	(segment
		(start 300.303184 -124.957078)
		(end 300.212506 -124.822966)
		(width 0.1651)
		(layer "In5.Cu")
		(net "P5E_PEX2_STN0_RX_DP<3>")
	)
	(segment
		(start 314.079636 -285.09468)
		(end 314.294774 -284.879542)
		(width 0.1143)
		(layer "In5.Cu")
		(net "P5E_PEX2_STN0_RX_DP<3>")
	)
	(segment
		(start 305.671474 -127.219456)
		(end 304.858674 -126.426722)
		(width 0.1651)
		(layer "In5.Cu")
		(net "P5E_PEX2_STN0_RX_DP<3>")
	)
	(segment
		(start 308.41188 -131.806188)
		(end 308.15788 -131.381246)
		(width 0.1651)
		(layer "In5.Cu")
		(net "P5E_PEX2_STN0_RX_DP<3>")
	)
	(segment
		(start 302.822356 -125.704346)
		(end 302.364902 -125.514354)
		(width 0.1651)
		(layer "In5.Cu")
		(net "P5E_PEX2_STN0_RX_DP<3>")
	)
	(segment
		(start 314.250832 -139.342368)
		(end 312.037984 -137.875264)
		(width 0.1651)
		(layer "In5.Cu")
		(net "P5E_PEX2_STN0_RX_DP<3>")
	)
	(segment
		(start 307.532786 -130.334512)
		(end 307.376068 -130.295142)
		(width 0.1651)
		(layer "In5.Cu")
		(net "P5E_PEX2_STN0_RX_DP<3>")
	)
	(segment
		(start 316.14999 -284.833822)
		(end 317.400432 -284.833822)
		(width 0.1651)
		(layer "In5.Cu")
		(net "P5E_PEX2_STN0_RX_DP<3>")
	)
	(segment
		(start 300.212506 -124.822966)
		(end 299.45457 -124.676408)
		(width 0.1651)
		(layer "In5.Cu")
		(net "P5E_PEX2_STN0_RX_DP<3>")
	)
	(segment
		(start 307.376068 -130.295142)
		(end 307.12156 -129.869692)
		(width 0.1651)
		(layer "In5.Cu")
		(net "P5E_PEX2_STN0_RX_DP<3>")
	)
	(segment
		(start 314.572142 -140.240512)
		(end 314.250832 -139.342368)
		(width 0.1651)
		(layer "In5.Cu")
		(net "P5E_PEX2_STN0_RX_DP<3>")
	)
	(segment
		(start 314.294774 -284.879542)
		(end 316.075822 -284.879542)
		(width 0.1143)
		(layer "In5.Cu")
		(net "P5E_PEX2_STN0_RX_DP<3>")
	)
	(segment
		(start 300.923452 -124.960634)
		(end 300.789594 -125.051058)
		(width 0.1651)
		(layer "In5.Cu")
		(net "P5E_PEX2_STN0_RX_DP<3>")
	)
	(segment
		(start 307.161184 -129.712974)
		(end 306.460652 -128.540256)
		(width 0.1651)
		(layer "In5.Cu")
		(net "P5E_PEX2_STN0_RX_DP<3>")
	)
	(segment
		(start 313.699906 -285.449772)
		(end 313.965336 -285.449772)
		(width 0.1143)
		(layer "In5.Cu")
		(net "P5E_PEX2_STN0_RX_DP<3>")
	)
	(segment
		(start 302.30318 -125.364494)
		(end 301.68596 -125.107954)
		(width 0.1651)
		(layer "In5.Cu")
		(net "P5E_PEX2_STN0_RX_DP<3>")
	)
	(segment
		(start 306.049426 -128.075182)
		(end 306.08905 -127.918464)
		(width 0.1651)
		(layer "In5.Cu")
		(net "P5E_PEX2_STN0_RX_DP<3>")
	)
	(segment
		(start 317.400432 -284.833822)
		(end 318.500506 -284.196028)
		(width 0.1651)
		(layer "In5.Cu")
		(net "P5E_PEX2_STN0_RX_DP<3>")
	)
	(segment
		(start 328.544682 -272.77822)
		(end 328.65441 -269.578836)
		(width 0.1651)
		(layer "In5.Cu")
		(net "P5E_PEX2_STN0_RX_DP<3>")
	)
	(segment
		(start 319.04432 -168.404286)
		(end 318.58204 -150.0505)
		(width 0.1651)
		(layer "In5.Cu")
		(net "P5E_PEX2_STN0_RX_DP<3>")
	)
	(segment
		(start 318.389254 -232.225596)
		(end 319.04432 -168.404286)
		(width 0.1651)
		(layer "In5.Cu")
		(net "P5E_PEX2_STN0_RX_DP<3>")
	)
	(segment
		(start 307.746908 -130.916426)
		(end 307.786532 -130.759454)
		(width 0.1651)
		(layer "In5.Cu")
		(net "P5E_PEX2_STN0_RX_DP<3>")
	)
	(segment
		(start 307.12156 -129.869692)
		(end 307.161184 -129.712974)
		(width 0.1651)
		(layer "In5.Cu")
		(net "P5E_PEX2_STN0_RX_DP<3>")
	)
	(segment
		(start 307.786532 -130.759454)
		(end 307.532532 -130.334512)
		(width 0.1651)
		(layer "In5.Cu")
		(net "P5E_PEX2_STN0_RX_DP<3>")
	)
	(segment
		(start 308.372256 -131.96316)
		(end 308.41188 -131.806188)
		(width 0.1651)
		(layer "In5.Cu")
		(net "P5E_PEX2_STN0_RX_DP<3>")
	)
	(segment
		(start 299.45457 -124.676408)
		(end 297.693842 -124.676408)
		(width 0.1651)
		(layer "In5.Cu")
		(net "P5E_PEX2_STN0_RX_DP<3>")
	)
	(segment
		(start 318.500506 -284.196028)
		(end 326.452738 -276.487382)
		(width 0.1651)
		(layer "In5.Cu")
		(net "P5E_PEX2_STN0_RX_DP<3>")
	)
	(segment
		(start 317.78702 -144.429226)
		(end 314.572142 -140.240512)
		(width 0.1651)
		(layer "In5.Cu")
		(net "P5E_PEX2_STN0_RX_DP<3>")
	)
	(segment
		(start 318.58204 -150.0505)
		(end 317.78702 -144.429226)
		(width 0.1651)
		(layer "In5.Cu")
		(net "P5E_PEX2_STN0_RX_DP<3>")
	)
	(segment
		(start 328.65441 -269.578836)
		(end 320.119756 -240.358422)
		(width 0.1651)
		(layer "In5.Cu")
		(net "P5E_PEX2_STN0_RX_DP<3>")
	)
	(segment
		(start 313.965336 -285.449772)
		(end 314.079636 -285.335472)
		(width 0.1143)
		(layer "In5.Cu")
		(net "P5E_PEX2_STN0_RX_DP<3>")
	)
	(segment
		(start 308.62651 -132.38861)
		(end 308.372256 -131.96316)
		(width 0.1651)
		(layer "In5.Cu")
		(net "P5E_PEX2_STN0_RX_DP<3>")
	)
	(segment
		(start 316.075822 -284.879542)
		(end 316.121542 -284.833822)
		(width 0.1143)
		(layer "In5.Cu")
		(net "P5E_PEX2_STN0_RX_DP<3>")
	)
	(segment
		(start 302.30318 -125.364748)
		(end 302.30318 -125.364494)
		(width 0.1651)
		(layer "In5.Cu")
		(net "P5E_PEX2_STN0_RX_DP<3>")
	)
	(segment
		(start 306.08905 -127.918464)
		(end 305.671474 -127.219456)
		(width 0.1651)
		(layer "In5.Cu")
		(net "P5E_PEX2_STN0_RX_DP<3>")
	)
	(segment
		(start 312.037984 -137.875264)
		(end 308.783228 -132.42798)
		(width 0.1651)
		(layer "In5.Cu")
		(net "P5E_PEX2_STN0_RX_DP<3>")
	)
	(segment
		(start 300.789594 -125.051058)
		(end 300.303184 -124.957078)
		(width 0.1651)
		(layer "In5.Cu")
		(net "P5E_PEX2_STN0_RX_DP<3>")
	)
	(segment
		(start 284.330902 -344.219022)
		(end 284.010862 -344.539062)
		(width 0.13462)
		(layer "F.Cu")
		(net "P5E_PEX2_STN7_TX_C_DN<119>")
	)
	(segment
		(start 284.010862 -345.170506)
		(end 284.305502 -345.465146)
		(width 0.13462)
		(layer "F.Cu")
		(net "P5E_PEX2_STN7_TX_C_DN<119>")
	)
	(segment
		(start 284.010862 -344.539062)
		(end 284.010862 -345.170506)
		(width 0.13462)
		(layer "F.Cu")
		(net "P5E_PEX2_STN7_TX_C_DN<119>")
	)
	(segment
		(start 303.70526 -394.94206)
		(end 301.506382 -392.743182)
		(width 0.1651)
		(layer "In7.Cu")
		(net "P5E_PEX2_STN7_TX_C_DN<119>")
	)
	(segment
		(start 303.01692 -402.281136)
		(end 303.564036 -402.281136)
		(width 0.1651)
		(layer "In7.Cu")
		(net "P5E_PEX2_STN7_TX_C_DN<119>")
	)
	(segment
		(start 287.3248 -385.6482)
		(end 286.8168 -385.0894)
		(width 0.1651)
		(layer "In7.Cu")
		(net "P5E_PEX2_STN7_TX_C_DN<119>")
	)
	(segment
		(start 297.7642 -390.2202)
		(end 287.3248 -385.6482)
		(width 0.1651)
		(layer "In7.Cu")
		(net "P5E_PEX2_STN7_TX_C_DN<119>")
	)
	(segment
		(start 302.88992 -402.408136)
		(end 303.01692 -402.281136)
		(width 0.1651)
		(layer "In7.Cu")
		(net "P5E_PEX2_STN7_TX_C_DN<119>")
	)
	(segment
		(start 286.512 -384.5052)
		(end 282.460192 -358.267)
		(width 0.1651)
		(layer "In7.Cu")
		(net "P5E_PEX2_STN7_TX_C_DN<119>")
	)
	(segment
		(start 301.506382 -392.743182)
		(end 301.49927 -392.743182)
		(width 0.1651)
		(layer "In7.Cu")
		(net "P5E_PEX2_STN7_TX_C_DN<119>")
	)
	(segment
		(start 303.564036 -402.281136)
		(end 304.015902 -401.82927)
		(width 0.1651)
		(layer "In7.Cu")
		(net "P5E_PEX2_STN7_TX_C_DN<119>")
	)
	(segment
		(start 282.460192 -347.881194)
		(end 284.014672 -346.326714)
		(width 0.1651)
		(layer "In7.Cu")
		(net "P5E_PEX2_STN7_TX_C_DN<119>")
	)
	(segment
		(start 282.460192 -358.267)
		(end 282.460192 -347.881194)
		(width 0.1651)
		(layer "In7.Cu")
		(net "P5E_PEX2_STN7_TX_C_DN<119>")
	)
	(segment
		(start 304.015902 -395.7066)
		(end 303.70526 -394.94206)
		(width 0.1651)
		(layer "In7.Cu")
		(net "P5E_PEX2_STN7_TX_C_DN<119>")
	)
	(segment
		(start 304.015902 -401.82927)
		(end 304.015902 -395.7066)
		(width 0.1651)
		(layer "In7.Cu")
		(net "P5E_PEX2_STN7_TX_C_DN<119>")
	)
	(segment
		(start 284.014672 -345.755976)
		(end 284.305502 -345.465146)
		(width 0.1651)
		(layer "In7.Cu")
		(net "P5E_PEX2_STN7_TX_C_DN<119>")
	)
	(segment
		(start 302.88992 -402.790152)
		(end 302.88992 -402.408136)
		(width 0.1651)
		(layer "In7.Cu")
		(net "P5E_PEX2_STN7_TX_C_DN<119>")
	)
	(segment
		(start 284.014672 -346.326714)
		(end 284.014672 -345.755976)
		(width 0.1651)
		(layer "In7.Cu")
		(net "P5E_PEX2_STN7_TX_C_DN<119>")
	)
	(segment
		(start 286.8168 -385.0894)
		(end 286.512 -384.5052)
		(width 0.1651)
		(layer "In7.Cu")
		(net "P5E_PEX2_STN7_TX_C_DN<119>")
	)
	(segment
		(start 301.49927 -392.743182)
		(end 297.7642 -390.2202)
		(width 0.1651)
		(layer "In7.Cu")
		(net "P5E_PEX2_STN7_TX_C_DN<119>")
	)
	(segment
		(start 387.164072 -402.281136)
		(end 387.615938 -401.82927)
		(width 0.1651)
		(layer "In15.Cu")
		(net "P5E_PEX3_STN6_RX_DN<106>")
	)
	(segment
		(start 381.420878 -390.8298)
		(end 375.466356 -388.281672)
		(width 0.1651)
		(layer "In15.Cu")
		(net "P5E_PEX3_STN6_RX_DN<106>")
	)
	(segment
		(start 396.215616 -319.995296)
		(end 396.215616 -319.966848)
		(width 0.1143)
		(layer "In15.Cu")
		(net "P5E_PEX3_STN6_RX_DN<106>")
	)
	(segment
		(start 387.615938 -396.1384)
		(end 386.932678 -394.3604)
		(width 0.1651)
		(layer "In15.Cu")
		(net "P5E_PEX3_STN6_RX_DN<106>")
	)
	(segment
		(start 387.615938 -401.82927)
		(end 387.615938 -396.1384)
		(width 0.1651)
		(layer "In15.Cu")
		(net "P5E_PEX3_STN6_RX_DN<106>")
	)
	(segment
		(start 396.169896 -318.424052)
		(end 396.273782 -318.320166)
		(width 0.1143)
		(layer "In15.Cu")
		(net "P5E_PEX3_STN6_RX_DN<106>")
	)
	(segment
		(start 376.860562 -341.141558)
		(end 389.712962 -329.193906)
		(width 0.1651)
		(layer "In15.Cu")
		(net "P5E_PEX3_STN6_RX_DN<106>")
	)
	(segment
		(start 389.712962 -329.193906)
		(end 393.476988 -326.217026)
		(width 0.1651)
		(layer "In15.Cu")
		(net "P5E_PEX3_STN6_RX_DN<106>")
	)
	(segment
		(start 373.147082 -386.68198)
		(end 372.48211 -385.024122)
		(width 0.1651)
		(layer "In15.Cu")
		(net "P5E_PEX3_STN6_RX_DN<106>")
	)
	(segment
		(start 396.273782 -318.320166)
		(end 396.43558 -318.320166)
		(width 0.1143)
		(layer "In15.Cu")
		(net "P5E_PEX3_STN6_RX_DN<106>")
	)
	(segment
		(start 396.54988 -318.434466)
		(end 396.54988 -318.699896)
		(width 0.1143)
		(layer "In15.Cu")
		(net "P5E_PEX3_STN6_RX_DN<106>")
	)
	(segment
		(start 376.20575 -359.229406)
		(end 376.42419 -358.001824)
		(width 0.1651)
		(layer "In15.Cu")
		(net "P5E_PEX3_STN6_RX_DN<106>")
	)
	(segment
		(start 396.169896 -319.921128)
		(end 396.169896 -318.424052)
		(width 0.1143)
		(layer "In15.Cu")
		(net "P5E_PEX3_STN6_RX_DN<106>")
	)
	(segment
		(start 386.932678 -394.3604)
		(end 385.992878 -393.4714)
		(width 0.1651)
		(layer "In15.Cu")
		(net "P5E_PEX3_STN6_RX_DN<106>")
	)
	(segment
		(start 396.215616 -321.82816)
		(end 396.215616 -319.995296)
		(width 0.1651)
		(layer "In15.Cu")
		(net "P5E_PEX3_STN6_RX_DN<106>")
	)
	(segment
		(start 372.559834 -369.149122)
		(end 376.20575 -359.229406)
		(width 0.1651)
		(layer "In15.Cu")
		(net "P5E_PEX3_STN6_RX_DN<106>")
	)
	(segment
		(start 395.756892 -322.935346)
		(end 396.215616 -321.82816)
		(width 0.1651)
		(layer "In15.Cu")
		(net "P5E_PEX3_STN6_RX_DN<106>")
	)
	(segment
		(start 396.43558 -318.320166)
		(end 396.54988 -318.434466)
		(width 0.1143)
		(layer "In15.Cu")
		(net "P5E_PEX3_STN6_RX_DN<106>")
	)
	(segment
		(start 386.616956 -402.281136)
		(end 387.164072 -402.281136)
		(width 0.1651)
		(layer "In15.Cu")
		(net "P5E_PEX3_STN6_RX_DN<106>")
	)
	(segment
		(start 386.489956 -402.790152)
		(end 386.489956 -402.408136)
		(width 0.1651)
		(layer "In15.Cu")
		(net "P5E_PEX3_STN6_RX_DN<106>")
	)
	(segment
		(start 385.992878 -393.4714)
		(end 381.420878 -390.8298)
		(width 0.1651)
		(layer "In15.Cu")
		(net "P5E_PEX3_STN6_RX_DN<106>")
	)
	(segment
		(start 375.466356 -388.281672)
		(end 373.147082 -386.68198)
		(width 0.1651)
		(layer "In15.Cu")
		(net "P5E_PEX3_STN6_RX_DN<106>")
	)
	(segment
		(start 376.42419 -358.001824)
		(end 376.42419 -342.1634)
		(width 0.1651)
		(layer "In15.Cu")
		(net "P5E_PEX3_STN6_RX_DN<106>")
	)
	(segment
		(start 376.42419 -342.1634)
		(end 376.860562 -341.141558)
		(width 0.1651)
		(layer "In15.Cu")
		(net "P5E_PEX3_STN6_RX_DN<106>")
	)
	(segment
		(start 396.215616 -319.966848)
		(end 396.169896 -319.921128)
		(width 0.1143)
		(layer "In15.Cu")
		(net "P5E_PEX3_STN6_RX_DN<106>")
	)
	(segment
		(start 386.489956 -402.408136)
		(end 386.616956 -402.281136)
		(width 0.1651)
		(layer "In15.Cu")
		(net "P5E_PEX3_STN6_RX_DN<106>")
	)
	(segment
		(start 372.030752 -373.357394)
		(end 372.13667 -371.485922)
		(width 0.1651)
		(layer "In15.Cu")
		(net "P5E_PEX3_STN6_RX_DN<106>")
	)
	(segment
		(start 393.476988 -326.217026)
		(end 395.756892 -322.935346)
		(width 0.1651)
		(layer "In15.Cu")
		(net "P5E_PEX3_STN6_RX_DN<106>")
	)
	(segment
		(start 372.48211 -385.024122)
		(end 372.030752 -373.357394)
		(width 0.1651)
		(layer "In15.Cu")
		(net "P5E_PEX3_STN6_RX_DN<106>")
	)
	(segment
		(start 372.13667 -371.485922)
		(end 372.559834 -369.149122)
		(width 0.1651)
		(layer "In15.Cu")
		(net "P5E_PEX3_STN6_RX_DN<106>")
	)
	(segment
		(start 55.47995 -139.6492)
		(end 55.04815 -139.6492)
		(width 0.13208)
		(layer "F.Cu")
		(net "PRSNTB2_NIC0_N")
	)
	(segment
		(start 55.04815 -139.6492)
		(end 54.964076 -139.565126)
		(width 0.13208)
		(layer "F.Cu")
		(net "PRSNTB2_NIC0_N")
	)
	(segment
		(start 54.964076 -139.565126)
		(end 54.270148 -139.565126)
		(width 0.13208)
		(layer "F.Cu")
		(net "PRSNTB2_NIC0_N")
	)
	(segment
		(start 54.270148 -139.565126)
		(end 50.64252 -139.565126)
		(width 0.13208)
		(layer "F.Cu")
		(net "PRSNTB2_NIC0_N")
	)
	(segment
		(start 55.47995 -138.6332)
		(end 55.47995 -139.6492)
		(width 0.13208)
		(layer "F.Cu")
		(net "PRSNTB2_NIC0_N")
	)
	(via
		(at 54.270148 -139.565126)
		(size 0.762)
		(drill 0.381)
		(layers "F.Cu" "B.Cu")
		(net "PRSNTB2_NIC0_N")
	)
	(segment
		(start 307.820568 -85.871304)
		(end 308.265576 -85.426296)
		(width 0.13208)
		(layer "F.Cu")
		(net "RST_HP_NIC5_N")
	)
	(segment
		(start 307.820568 -87.479632)
		(end 307.820568 -86.247986)
		(width 0.13208)
		(layer "F.Cu")
		(net "RST_HP_NIC5_N")
	)
	(segment
		(start 308.265576 -85.426296)
		(end 311.099454 -85.426296)
		(width 0.13208)
		(layer "F.Cu")
		(net "RST_HP_NIC5_N")
	)
	(segment
		(start 309.234332 -87.599012)
		(end 307.939948 -87.599012)
		(width 0.13208)
		(layer "F.Cu")
		(net "RST_HP_NIC5_N")
	)
	(segment
		(start 307.820568 -86.247986)
		(end 307.820568 -85.871304)
		(width 0.13208)
		(layer "F.Cu")
		(net "RST_HP_NIC5_N")
	)
	(segment
		(start 307.939948 -87.599012)
		(end 307.820568 -87.479632)
		(width 0.13208)
		(layer "F.Cu")
		(net "RST_HP_NIC5_N")
	)
	(via
		(at 307.820568 -86.247986)
		(size 0.508)
		(drill 0.254)
		(layers "F.Cu" "B.Cu")
		(net "RST_HP_NIC5_N")
	)
	(segment
		(start 10.182352 -34.390076)
		(end 10.019538 -34.227262)
		(width 0.13462)
		(layer "F.Cu")
		(net "P5E_PEX0_STN2_RX_DP<47>")
	)
	(segment
		(start 10.019538 -34.227262)
		(end 7.5057 -34.227262)
		(width 0.13462)
		(layer "F.Cu")
		(net "P5E_PEX0_STN2_RX_DP<47>")
	)
	(segment
		(start 10.664952 -34.390076)
		(end 10.182352 -34.390076)
		(width 0.13462)
		(layer "F.Cu")
		(net "P5E_PEX0_STN2_RX_DP<47>")
	)
	(segment
		(start 7.5057 -34.227262)
		(end 7.210552 -34.52241)
		(width 0.13462)
		(layer "F.Cu")
		(net "P5E_PEX0_STN2_RX_DP<47>")
	)
	(segment
		(start 9.867646 -57.253632)
		(end 9.982962 -49.871376)
		(width 0.1651)
		(layer "In7.Cu")
		(net "P5E_PEX0_STN2_RX_DP<47>")
	)
	(segment
		(start 8.638794 -37.47135)
		(end 8.606282 -35.357562)
		(width 0.1651)
		(layer "In7.Cu")
		(net "P5E_PEX0_STN2_RX_DP<47>")
	)
	(segment
		(start 8.649716 -38.170104)
		(end 8.546338 -38.070028)
		(width 0.1651)
		(layer "In7.Cu")
		(net "P5E_PEX0_STN2_RX_DP<47>")
	)
	(segment
		(start 44.335446 -273.670014)
		(end 44.141898 -273.670014)
		(width 0.1143)
		(layer "In7.Cu")
		(net "P5E_PEX0_STN2_RX_DP<47>")
	)
	(segment
		(start 43.833796 -270.490188)
		(end 43.833542 -270.489934)
		(width 0.1651)
		(layer "In7.Cu")
		(net "P5E_PEX0_STN2_RX_DP<47>")
	)
	(segment
		(start 10.139426 -62.60719)
		(end 10.139426 -60.256166)
		(width 0.1651)
		(layer "In7.Cu")
		(net "P5E_PEX0_STN2_RX_DP<47>")
	)
	(segment
		(start 41.34866 -238.473234)
		(end 36.915344 -215.029288)
		(width 0.1651)
		(layer "In7.Cu")
		(net "P5E_PEX0_STN2_RX_DP<47>")
	)
	(segment
		(start 8.681974 -40.241982)
		(end 8.668512 -39.36365)
		(width 0.1651)
		(layer "In7.Cu")
		(net "P5E_PEX0_STN2_RX_DP<47>")
	)
	(segment
		(start 32.482282 -191.58585)
		(end 32.482028 -191.58585)
		(width 0.1651)
		(layer "In7.Cu")
		(net "P5E_PEX0_STN2_RX_DP<47>")
	)
	(segment
		(start 9.949434 -85.615018)
		(end 10.139426 -62.60719)
		(width 0.1651)
		(layer "In7.Cu")
		(net "P5E_PEX0_STN2_RX_DP<47>")
	)
	(segment
		(start 44.141898 -273.670014)
		(end 43.879516 -273.407632)
		(width 0.1143)
		(layer "In7.Cu")
		(net "P5E_PEX0_STN2_RX_DP<47>")
	)
	(segment
		(start 8.538718 -37.574474)
		(end 8.638794 -37.47135)
		(width 0.1651)
		(layer "In7.Cu")
		(net "P5E_PEX0_STN2_RX_DP<47>")
	)
	(segment
		(start 8.657336 -38.66515)
		(end 8.649716 -38.170104)
		(width 0.1651)
		(layer "In7.Cu")
		(net "P5E_PEX0_STN2_RX_DP<47>")
	)
	(segment
		(start 36.91509 -215.029288)
		(end 32.482282 -191.58585)
		(width 0.1651)
		(layer "In7.Cu")
		(net "P5E_PEX0_STN2_RX_DP<47>")
	)
	(segment
		(start 8.546338 -38.070028)
		(end 8.538718 -37.574474)
		(width 0.1651)
		(layer "In7.Cu")
		(net "P5E_PEX0_STN2_RX_DP<47>")
	)
	(segment
		(start 42.918888 -255.62306)
		(end 41.34866 -238.473234)
		(width 0.1651)
		(layer "In7.Cu")
		(net "P5E_PEX0_STN2_RX_DP<47>")
	)
	(segment
		(start 8.668512 -39.36365)
		(end 8.565134 -39.263574)
		(width 0.1651)
		(layer "In7.Cu")
		(net "P5E_PEX0_STN2_RX_DP<47>")
	)
	(segment
		(start 7.735062 -34.23158)
		(end 7.501382 -34.23158)
		(width 0.1651)
		(layer "In7.Cu")
		(net "P5E_PEX0_STN2_RX_DP<47>")
	)
	(segment
		(start 20.364196 -119.974106)
		(end 15.166594 -102.82682)
		(width 0.1651)
		(layer "In7.Cu")
		(net "P5E_PEX0_STN2_RX_DP<47>")
	)
	(segment
		(start 43.833542 -270.489934)
		(end 43.639232 -268.869414)
		(width 0.1651)
		(layer "In7.Cu")
		(net "P5E_PEX0_STN2_RX_DP<47>")
	)
	(segment
		(start 43.879516 -273.407632)
		(end 43.879516 -271.41932)
		(width 0.1143)
		(layer "In7.Cu")
		(net "P5E_PEX0_STN2_RX_DP<47>")
	)
	(segment
		(start 43.639232 -268.869414)
		(end 43.269916 -267.071856)
		(width 0.1651)
		(layer "In7.Cu")
		(net "P5E_PEX0_STN2_RX_DP<47>")
	)
	(segment
		(start 8.606282 -35.1028)
		(end 7.735062 -34.23158)
		(width 0.1651)
		(layer "In7.Cu")
		(net "P5E_PEX0_STN2_RX_DP<47>")
	)
	(segment
		(start 15.166594 -102.82682)
		(end 15.16634 -102.826058)
		(width 0.1651)
		(layer "In7.Cu")
		(net "P5E_PEX0_STN2_RX_DP<47>")
	)
	(segment
		(start 36.915344 -215.029288)
		(end 36.91509 -215.029288)
		(width 0.1651)
		(layer "In7.Cu")
		(net "P5E_PEX0_STN2_RX_DP<47>")
	)
	(segment
		(start 43.269916 -267.071856)
		(end 42.853356 -263.595612)
		(width 0.1651)
		(layer "In7.Cu")
		(net "P5E_PEX0_STN2_RX_DP<47>")
	)
	(segment
		(start 8.606282 -35.357562)
		(end 8.606282 -35.1028)
		(width 0.1651)
		(layer "In7.Cu")
		(net "P5E_PEX0_STN2_RX_DP<47>")
	)
	(segment
		(start 10.139426 -60.256166)
		(end 9.867646 -57.253632)
		(width 0.1651)
		(layer "In7.Cu")
		(net "P5E_PEX0_STN2_RX_DP<47>")
	)
	(segment
		(start 15.16634 -102.826058)
		(end 9.949434 -85.615018)
		(width 0.1651)
		(layer "In7.Cu")
		(net "P5E_PEX0_STN2_RX_DP<47>")
	)
	(segment
		(start 44.449746 -274.049744)
		(end 44.449746 -273.784314)
		(width 0.1143)
		(layer "In7.Cu")
		(net "P5E_PEX0_STN2_RX_DP<47>")
	)
	(segment
		(start 42.853356 -263.595612)
		(end 42.853356 -262.326374)
		(width 0.1651)
		(layer "In7.Cu")
		(net "P5E_PEX0_STN2_RX_DP<47>")
	)
	(segment
		(start 43.879516 -271.41932)
		(end 43.833796 -271.3736)
		(width 0.1143)
		(layer "In7.Cu")
		(net "P5E_PEX0_STN2_RX_DP<47>")
	)
	(segment
		(start 43.833796 -271.345152)
		(end 43.833796 -270.490188)
		(width 0.1651)
		(layer "In7.Cu")
		(net "P5E_PEX0_STN2_RX_DP<47>")
	)
	(segment
		(start 44.449746 -273.784314)
		(end 44.335446 -273.670014)
		(width 0.1143)
		(layer "In7.Cu")
		(net "P5E_PEX0_STN2_RX_DP<47>")
	)
	(segment
		(start 7.501382 -34.23158)
		(end 7.210552 -34.52241)
		(width 0.1651)
		(layer "In7.Cu")
		(net "P5E_PEX0_STN2_RX_DP<47>")
	)
	(segment
		(start 8.565134 -39.263574)
		(end 8.557514 -38.768274)
		(width 0.1651)
		(layer "In7.Cu")
		(net "P5E_PEX0_STN2_RX_DP<47>")
	)
	(segment
		(start 23.616158 -144.698974)
		(end 20.364196 -119.974106)
		(width 0.1651)
		(layer "In7.Cu")
		(net "P5E_PEX0_STN2_RX_DP<47>")
	)
	(segment
		(start 8.557514 -38.768274)
		(end 8.657336 -38.66515)
		(width 0.1651)
		(layer "In7.Cu")
		(net "P5E_PEX0_STN2_RX_DP<47>")
	)
	(segment
		(start 9.982962 -49.871376)
		(end 8.681974 -40.241982)
		(width 0.1651)
		(layer "In7.Cu")
		(net "P5E_PEX0_STN2_RX_DP<47>")
	)
	(segment
		(start 32.482028 -191.58585)
		(end 23.616158 -144.698974)
		(width 0.1651)
		(layer "In7.Cu")
		(net "P5E_PEX0_STN2_RX_DP<47>")
	)
	(segment
		(start 42.853356 -262.326374)
		(end 42.918888 -255.62306)
		(width 0.1651)
		(layer "In7.Cu")
		(net "P5E_PEX0_STN2_RX_DP<47>")
	)
	(segment
		(start 43.833796 -271.3736)
		(end 43.833796 -271.345152)
		(width 0.1143)
		(layer "In7.Cu")
		(net "P5E_PEX0_STN2_RX_DP<47>")
	)
	(segment
		(start 126.76505 -34.390076)
		(end 126.28245 -34.390076)
		(width 0.13462)
		(layer "F.Cu")
		(net "P5E_PEX1_STN2_RX_DP<47>")
	)
	(segment
		(start 126.28245 -34.390076)
		(end 126.119636 -34.227262)
		(width 0.13462)
		(layer "F.Cu")
		(net "P5E_PEX1_STN2_RX_DP<47>")
	)
	(segment
		(start 126.119636 -34.227262)
		(end 123.605798 -34.227262)
		(width 0.13462)
		(layer "F.Cu")
		(net "P5E_PEX1_STN2_RX_DP<47>")
	)
	(segment
		(start 123.605798 -34.227262)
		(end 123.31065 -34.52241)
		(width 0.13462)
		(layer "F.Cu")
		(net "P5E_PEX1_STN2_RX_DP<47>")
	)
	(segment
		(start 160.549844 -273.784314)
		(end 160.435544 -273.670014)
		(width 0.1143)
		(layer "In7.Cu")
		(net "P5E_PEX1_STN2_RX_DP<47>")
	)
	(segment
		(start 124.657612 -38.768274)
		(end 124.757434 -38.66515)
		(width 0.1651)
		(layer "In7.Cu")
		(net "P5E_PEX1_STN2_RX_DP<47>")
	)
	(segment
		(start 139.716256 -144.698974)
		(end 136.464294 -119.974106)
		(width 0.1651)
		(layer "In7.Cu")
		(net "P5E_PEX1_STN2_RX_DP<47>")
	)
	(segment
		(start 159.73933 -268.869414)
		(end 159.370014 -267.071856)
		(width 0.1651)
		(layer "In7.Cu")
		(net "P5E_PEX1_STN2_RX_DP<47>")
	)
	(segment
		(start 159.933894 -271.345152)
		(end 159.933894 -270.490188)
		(width 0.1651)
		(layer "In7.Cu")
		(net "P5E_PEX1_STN2_RX_DP<47>")
	)
	(segment
		(start 153.015188 -215.029288)
		(end 148.58238 -191.58585)
		(width 0.1651)
		(layer "In7.Cu")
		(net "P5E_PEX1_STN2_RX_DP<47>")
	)
	(segment
		(start 131.266692 -102.82682)
		(end 131.266438 -102.826058)
		(width 0.1651)
		(layer "In7.Cu")
		(net "P5E_PEX1_STN2_RX_DP<47>")
	)
	(segment
		(start 124.782072 -40.241982)
		(end 124.76861 -39.36365)
		(width 0.1651)
		(layer "In7.Cu")
		(net "P5E_PEX1_STN2_RX_DP<47>")
	)
	(segment
		(start 160.241996 -273.670014)
		(end 159.979614 -273.407632)
		(width 0.1143)
		(layer "In7.Cu")
		(net "P5E_PEX1_STN2_RX_DP<47>")
	)
	(segment
		(start 124.749814 -38.170104)
		(end 124.646436 -38.070028)
		(width 0.1651)
		(layer "In7.Cu")
		(net "P5E_PEX1_STN2_RX_DP<47>")
	)
	(segment
		(start 124.738892 -37.47135)
		(end 124.70638 -35.357562)
		(width 0.1651)
		(layer "In7.Cu")
		(net "P5E_PEX1_STN2_RX_DP<47>")
	)
	(segment
		(start 124.646436 -38.070028)
		(end 124.638816 -37.574474)
		(width 0.1651)
		(layer "In7.Cu")
		(net "P5E_PEX1_STN2_RX_DP<47>")
	)
	(segment
		(start 124.70638 -35.1028)
		(end 123.83516 -34.23158)
		(width 0.1651)
		(layer "In7.Cu")
		(net "P5E_PEX1_STN2_RX_DP<47>")
	)
	(segment
		(start 131.266438 -102.826058)
		(end 126.049532 -85.615018)
		(width 0.1651)
		(layer "In7.Cu")
		(net "P5E_PEX1_STN2_RX_DP<47>")
	)
	(segment
		(start 159.93364 -270.489934)
		(end 159.73933 -268.869414)
		(width 0.1651)
		(layer "In7.Cu")
		(net "P5E_PEX1_STN2_RX_DP<47>")
	)
	(segment
		(start 126.08306 -49.871376)
		(end 124.782072 -40.241982)
		(width 0.1651)
		(layer "In7.Cu")
		(net "P5E_PEX1_STN2_RX_DP<47>")
	)
	(segment
		(start 125.967744 -57.253632)
		(end 126.08306 -49.871376)
		(width 0.1651)
		(layer "In7.Cu")
		(net "P5E_PEX1_STN2_RX_DP<47>")
	)
	(segment
		(start 159.370014 -267.071856)
		(end 158.953454 -263.595612)
		(width 0.1651)
		(layer "In7.Cu")
		(net "P5E_PEX1_STN2_RX_DP<47>")
	)
	(segment
		(start 126.049532 -85.615018)
		(end 126.239524 -62.60719)
		(width 0.1651)
		(layer "In7.Cu")
		(net "P5E_PEX1_STN2_RX_DP<47>")
	)
	(segment
		(start 123.60148 -34.23158)
		(end 123.31065 -34.52241)
		(width 0.1651)
		(layer "In7.Cu")
		(net "P5E_PEX1_STN2_RX_DP<47>")
	)
	(segment
		(start 124.76861 -39.36365)
		(end 124.665232 -39.263574)
		(width 0.1651)
		(layer "In7.Cu")
		(net "P5E_PEX1_STN2_RX_DP<47>")
	)
	(segment
		(start 136.464294 -119.974106)
		(end 131.266692 -102.82682)
		(width 0.1651)
		(layer "In7.Cu")
		(net "P5E_PEX1_STN2_RX_DP<47>")
	)
	(segment
		(start 159.979614 -273.407632)
		(end 159.979614 -271.41932)
		(width 0.1143)
		(layer "In7.Cu")
		(net "P5E_PEX1_STN2_RX_DP<47>")
	)
	(segment
		(start 159.933894 -270.490188)
		(end 159.93364 -270.489934)
		(width 0.1651)
		(layer "In7.Cu")
		(net "P5E_PEX1_STN2_RX_DP<47>")
	)
	(segment
		(start 159.018986 -255.62306)
		(end 157.448758 -238.473234)
		(width 0.1651)
		(layer "In7.Cu")
		(net "P5E_PEX1_STN2_RX_DP<47>")
	)
	(segment
		(start 123.83516 -34.23158)
		(end 123.60148 -34.23158)
		(width 0.1651)
		(layer "In7.Cu")
		(net "P5E_PEX1_STN2_RX_DP<47>")
	)
	(segment
		(start 148.582126 -191.58585)
		(end 139.716256 -144.698974)
		(width 0.1651)
		(layer "In7.Cu")
		(net "P5E_PEX1_STN2_RX_DP<47>")
	)
	(segment
		(start 160.435544 -273.670014)
		(end 160.241996 -273.670014)
		(width 0.1143)
		(layer "In7.Cu")
		(net "P5E_PEX1_STN2_RX_DP<47>")
	)
	(segment
		(start 126.239524 -60.256166)
		(end 125.967744 -57.253632)
		(width 0.1651)
		(layer "In7.Cu")
		(net "P5E_PEX1_STN2_RX_DP<47>")
	)
	(segment
		(start 126.239524 -62.60719)
		(end 126.239524 -60.256166)
		(width 0.1651)
		(layer "In7.Cu")
		(net "P5E_PEX1_STN2_RX_DP<47>")
	)
	(segment
		(start 158.953454 -263.595612)
		(end 158.953454 -262.326374)
		(width 0.1651)
		(layer "In7.Cu")
		(net "P5E_PEX1_STN2_RX_DP<47>")
	)
	(segment
		(start 124.70638 -35.357562)
		(end 124.70638 -35.1028)
		(width 0.1651)
		(layer "In7.Cu")
		(net "P5E_PEX1_STN2_RX_DP<47>")
	)
	(segment
		(start 159.933894 -271.3736)
		(end 159.933894 -271.345152)
		(width 0.1143)
		(layer "In7.Cu")
		(net "P5E_PEX1_STN2_RX_DP<47>")
	)
	(segment
		(start 124.665232 -39.263574)
		(end 124.657612 -38.768274)
		(width 0.1651)
		(layer "In7.Cu")
		(net "P5E_PEX1_STN2_RX_DP<47>")
	)
	(segment
		(start 160.549844 -274.049744)
		(end 160.549844 -273.784314)
		(width 0.1143)
		(layer "In7.Cu")
		(net "P5E_PEX1_STN2_RX_DP<47>")
	)
	(segment
		(start 124.638816 -37.574474)
		(end 124.738892 -37.47135)
		(width 0.1651)
		(layer "In7.Cu")
		(net "P5E_PEX1_STN2_RX_DP<47>")
	)
	(segment
		(start 124.757434 -38.66515)
		(end 124.749814 -38.170104)
		(width 0.1651)
		(layer "In7.Cu")
		(net "P5E_PEX1_STN2_RX_DP<47>")
	)
	(segment
		(start 159.979614 -271.41932)
		(end 159.933894 -271.3736)
		(width 0.1143)
		(layer "In7.Cu")
		(net "P5E_PEX1_STN2_RX_DP<47>")
	)
	(segment
		(start 148.58238 -191.58585)
		(end 148.582126 -191.58585)
		(width 0.1651)
		(layer "In7.Cu")
		(net "P5E_PEX1_STN2_RX_DP<47>")
	)
	(segment
		(start 158.953454 -262.326374)
		(end 159.018986 -255.62306)
		(width 0.1651)
		(layer "In7.Cu")
		(net "P5E_PEX1_STN2_RX_DP<47>")
	)
	(segment
		(start 153.015442 -215.029288)
		(end 153.015188 -215.029288)
		(width 0.1651)
		(layer "In7.Cu")
		(net "P5E_PEX1_STN2_RX_DP<47>")
	)
	(segment
		(start 157.448758 -238.473234)
		(end 153.015442 -215.029288)
		(width 0.1651)
		(layer "In7.Cu")
		(net "P5E_PEX1_STN2_RX_DP<47>")
	)
	(segment
		(start 311.633616 -119.2657)
		(end 306.126388 -119.2657)
		(width 0.13462)
		(layer "F.Cu")
		(net "P5E_PEX2_STN0_TX_C_DP<0>")
	)
	(segment
		(start 306.126388 -119.2657)
		(end 305.95697 -119.435118)
		(width 0.13462)
		(layer "F.Cu")
		(net "P5E_PEX2_STN0_TX_C_DP<0>")
	)
	(segment
		(start 305.95697 -119.435118)
		(end 305.457606 -119.435118)
		(width 0.13462)
		(layer "F.Cu")
		(net "P5E_PEX2_STN0_TX_C_DP<0>")
	)
	(segment
		(start 311.95264 -119.584724)
		(end 311.633616 -119.2657)
		(width 0.13462)
		(layer "F.Cu")
		(net "P5E_PEX2_STN0_TX_C_DP<0>")
	)
	(segment
		(start 263.830054 -301.933864)
		(end 267.7922 -301.933864)
		(width 0.1651)
		(layer "In5.Cu")
		(net "P5E_PEX2_STN7_RX_DP<113>")
	)
	(segment
		(start 290.533836 -396.01521)
		(end 290.31057 -395.459966)
		(width 0.1651)
		(layer "In5.Cu")
		(net "P5E_PEX2_STN7_RX_DP<113>")
	)
	(segment
		(start 279.880568 -378.962158)
		(end 279.35301 -373.200676)
		(width 0.1651)
		(layer "In5.Cu")
		(net "P5E_PEX2_STN7_RX_DP<113>")
	)
	(segment
		(start 278.694134 -371.890544)
		(end 267.498322 -360.490262)
		(width 0.1651)
		(layer "In5.Cu")
		(net "P5E_PEX2_STN7_RX_DP<113>")
	)
	(segment
		(start 279.35301 -373.200676)
		(end 278.694134 -371.890544)
		(width 0.1651)
		(layer "In5.Cu")
		(net "P5E_PEX2_STN7_RX_DP<113>")
	)
	(segment
		(start 252.554232 -328.024998)
		(end 250.45416 -323.161914)
		(width 0.1651)
		(layer "In5.Cu")
		(net "P5E_PEX2_STN7_RX_DP<113>")
	)
	(segment
		(start 269.619984 -302.20539)
		(end 269.619984 -302.435514)
		(width 0.1143)
		(layer "In5.Cu")
		(net "P5E_PEX2_STN7_RX_DP<113>")
	)
	(segment
		(start 267.7922 -301.933864)
		(end 267.820648 -301.933864)
		(width 0.1143)
		(layer "In5.Cu")
		(net "P5E_PEX2_STN7_RX_DP<113>")
	)
	(segment
		(start 281.56027 -388.695946)
		(end 280.202386 -385.630928)
		(width 0.1651)
		(layer "In5.Cu")
		(net "P5E_PEX2_STN7_RX_DP<113>")
	)
	(segment
		(start 269.734284 -302.549814)
		(end 269.999714 -302.549814)
		(width 0.1143)
		(layer "In5.Cu")
		(net "P5E_PEX2_STN7_RX_DP<113>")
	)
	(segment
		(start 269.619984 -302.435514)
		(end 269.734284 -302.549814)
		(width 0.1143)
		(layer "In5.Cu")
		(net "P5E_PEX2_STN7_RX_DP<113>")
	)
	(segment
		(start 267.866368 -301.979584)
		(end 269.394178 -301.979584)
		(width 0.1143)
		(layer "In5.Cu")
		(net "P5E_PEX2_STN7_RX_DP<113>")
	)
	(segment
		(start 255.031748 -307.791612)
		(end 258.809236 -304.014124)
		(width 0.1651)
		(layer "In5.Cu")
		(net "P5E_PEX2_STN7_RX_DP<113>")
	)
	(segment
		(start 289.816794 -409.799028)
		(end 290.24707 -409.799028)
		(width 0.1651)
		(layer "In5.Cu")
		(net "P5E_PEX2_STN7_RX_DP<113>")
	)
	(segment
		(start 284.315662 -391.199624)
		(end 281.56027 -388.695946)
		(width 0.1651)
		(layer "In5.Cu")
		(net "P5E_PEX2_STN7_RX_DP<113>")
	)
	(segment
		(start 250.45416 -318.03467)
		(end 255.031748 -307.791612)
		(width 0.1651)
		(layer "In5.Cu")
		(net "P5E_PEX2_STN7_RX_DP<113>")
	)
	(segment
		(start 288.648902 -393.822682)
		(end 284.315662 -391.199624)
		(width 0.1651)
		(layer "In5.Cu")
		(net "P5E_PEX2_STN7_RX_DP<113>")
	)
	(segment
		(start 290.533836 -409.512262)
		(end 290.533836 -396.01521)
		(width 0.1651)
		(layer "In5.Cu")
		(net "P5E_PEX2_STN7_RX_DP<113>")
	)
	(segment
		(start 267.820648 -301.933864)
		(end 267.866368 -301.979584)
		(width 0.1143)
		(layer "In5.Cu")
		(net "P5E_PEX2_STN7_RX_DP<113>")
	)
	(segment
		(start 269.394178 -301.979584)
		(end 269.619984 -302.20539)
		(width 0.1143)
		(layer "In5.Cu")
		(net "P5E_PEX2_STN7_RX_DP<113>")
	)
	(segment
		(start 290.24707 -409.799028)
		(end 290.533836 -409.512262)
		(width 0.1651)
		(layer "In5.Cu")
		(net "P5E_PEX2_STN7_RX_DP<113>")
	)
	(segment
		(start 250.45416 -323.161914)
		(end 250.45416 -318.03467)
		(width 0.1651)
		(layer "In5.Cu")
		(net "P5E_PEX2_STN7_RX_DP<113>")
	)
	(segment
		(start 289.689794 -409.672028)
		(end 289.816794 -409.799028)
		(width 0.1651)
		(layer "In5.Cu")
		(net "P5E_PEX2_STN7_RX_DP<113>")
	)
	(segment
		(start 289.689794 -409.290012)
		(end 289.689794 -409.672028)
		(width 0.1651)
		(layer "In5.Cu")
		(net "P5E_PEX2_STN7_RX_DP<113>")
	)
	(segment
		(start 267.498322 -360.490262)
		(end 257.80873 -336.465672)
		(width 0.1651)
		(layer "In5.Cu")
		(net "P5E_PEX2_STN7_RX_DP<113>")
	)
	(segment
		(start 290.31057 -395.459966)
		(end 288.648902 -393.822682)
		(width 0.1651)
		(layer "In5.Cu")
		(net "P5E_PEX2_STN7_RX_DP<113>")
	)
	(segment
		(start 257.80873 -336.465672)
		(end 252.554232 -328.024998)
		(width 0.1651)
		(layer "In5.Cu")
		(net "P5E_PEX2_STN7_RX_DP<113>")
	)
	(segment
		(start 258.809236 -304.014124)
		(end 263.830054 -301.933864)
		(width 0.1651)
		(layer "In5.Cu")
		(net "P5E_PEX2_STN7_RX_DP<113>")
	)
	(segment
		(start 280.202386 -385.630928)
		(end 279.880568 -378.962158)
		(width 0.1651)
		(layer "In5.Cu")
		(net "P5E_PEX2_STN7_RX_DP<113>")
	)
	(segment
		(start 385.822952 -393.699238)
		(end 384.339084 -392.841734)
		(width 0.1651)
		(layer "In15.Cu")
		(net "P5E_PEX3_STN6_RX_DP<106>")
	)
	(segment
		(start 386.616956 -401.999196)
		(end 387.047232 -401.999196)
		(width 0.1651)
		(layer "In15.Cu")
		(net "P5E_PEX3_STN6_RX_DP<106>")
	)
	(segment
		(start 387.333998 -396.190724)
		(end 386.69214 -394.521436)
		(width 0.1651)
		(layer "In15.Cu")
		(net "P5E_PEX3_STN6_RX_DP<106>")
	)
	(segment
		(start 386.489956 -401.872196)
		(end 386.616956 -401.999196)
		(width 0.1651)
		(layer "In15.Cu")
		(net "P5E_PEX3_STN6_RX_DP<106>")
	)
	(segment
		(start 375.32945 -388.52983)
		(end 372.916958 -386.865876)
		(width 0.1651)
		(layer "In15.Cu")
		(net "P5E_PEX3_STN6_RX_DP<106>")
	)
	(segment
		(start 376.14225 -357.976932)
		(end 376.14225 -342.105488)
		(width 0.1651)
		(layer "In15.Cu")
		(net "P5E_PEX3_STN6_RX_DP<106>")
	)
	(segment
		(start 396.43558 -318.129666)
		(end 396.54988 -318.015366)
		(width 0.1143)
		(layer "In15.Cu")
		(net "P5E_PEX3_STN6_RX_DP<106>")
	)
	(segment
		(start 372.202202 -385.083812)
		(end 371.748304 -373.354854)
		(width 0.1651)
		(layer "In15.Cu")
		(net "P5E_PEX3_STN6_RX_DP<106>")
	)
	(segment
		(start 372.286784 -369.0747)
		(end 375.932446 -359.155492)
		(width 0.1651)
		(layer "In15.Cu")
		(net "P5E_PEX3_STN6_RX_DP<106>")
	)
	(segment
		(start 395.933676 -319.966848)
		(end 395.979396 -319.921128)
		(width 0.1143)
		(layer "In15.Cu")
		(net "P5E_PEX3_STN6_RX_DP<106>")
	)
	(segment
		(start 384.182874 -392.883644)
		(end 383.753614 -392.635486)
		(width 0.1651)
		(layer "In15.Cu")
		(net "P5E_PEX3_STN6_RX_DP<106>")
	)
	(segment
		(start 383.126996 -392.273536)
		(end 382.69799 -392.025378)
		(width 0.1651)
		(layer "In15.Cu")
		(net "P5E_PEX3_STN6_RX_DP<106>")
	)
	(segment
		(start 375.932446 -359.155492)
		(end 376.14225 -357.976932)
		(width 0.1651)
		(layer "In15.Cu")
		(net "P5E_PEX3_STN6_RX_DP<106>")
	)
	(segment
		(start 382.65608 -391.869422)
		(end 381.294386 -391.08253)
		(width 0.1651)
		(layer "In15.Cu")
		(net "P5E_PEX3_STN6_RX_DP<106>")
	)
	(segment
		(start 395.979396 -319.921128)
		(end 395.979396 -318.345058)
		(width 0.1143)
		(layer "In15.Cu")
		(net "P5E_PEX3_STN6_RX_DP<106>")
	)
	(segment
		(start 393.269216 -326.0217)
		(end 395.507972 -322.799456)
		(width 0.1651)
		(layer "In15.Cu")
		(net "P5E_PEX3_STN6_RX_DP<106>")
	)
	(segment
		(start 396.54988 -318.015366)
		(end 396.54988 -317.749936)
		(width 0.1143)
		(layer "In15.Cu")
		(net "P5E_PEX3_STN6_RX_DP<106>")
	)
	(segment
		(start 376.14225 -342.105488)
		(end 376.624596 -340.975696)
		(width 0.1651)
		(layer "In15.Cu")
		(net "P5E_PEX3_STN6_RX_DP<106>")
	)
	(segment
		(start 383.283206 -392.231626)
		(end 383.126996 -392.273536)
		(width 0.1651)
		(layer "In15.Cu")
		(net "P5E_PEX3_STN6_RX_DP<106>")
	)
	(segment
		(start 389.529066 -328.97953)
		(end 393.269216 -326.0217)
		(width 0.1651)
		(layer "In15.Cu")
		(net "P5E_PEX3_STN6_RX_DP<106>")
	)
	(segment
		(start 386.69214 -394.521436)
		(end 385.822952 -393.699238)
		(width 0.1651)
		(layer "In15.Cu")
		(net "P5E_PEX3_STN6_RX_DP<106>")
	)
	(segment
		(start 396.194788 -318.129666)
		(end 396.43558 -318.129666)
		(width 0.1143)
		(layer "In15.Cu")
		(net "P5E_PEX3_STN6_RX_DP<106>")
	)
	(segment
		(start 395.933676 -319.995296)
		(end 395.933676 -319.966848)
		(width 0.1143)
		(layer "In15.Cu")
		(net "P5E_PEX3_STN6_RX_DP<106>")
	)
	(segment
		(start 372.916958 -386.865876)
		(end 372.202202 -385.083812)
		(width 0.1651)
		(layer "In15.Cu")
		(net "P5E_PEX3_STN6_RX_DP<106>")
	)
	(segment
		(start 384.339084 -392.841734)
		(end 384.182874 -392.883644)
		(width 0.1651)
		(layer "In15.Cu")
		(net "P5E_PEX3_STN6_RX_DP<106>")
	)
	(segment
		(start 387.333998 -401.71243)
		(end 387.333998 -396.190724)
		(width 0.1651)
		(layer "In15.Cu")
		(net "P5E_PEX3_STN6_RX_DP<106>")
	)
	(segment
		(start 376.624596 -340.975696)
		(end 389.529066 -328.97953)
		(width 0.1651)
		(layer "In15.Cu")
		(net "P5E_PEX3_STN6_RX_DP<106>")
	)
	(segment
		(start 395.933676 -321.772026)
		(end 395.933676 -319.995296)
		(width 0.1651)
		(layer "In15.Cu")
		(net "P5E_PEX3_STN6_RX_DP<106>")
	)
	(segment
		(start 383.753614 -392.635486)
		(end 383.711958 -392.479276)
		(width 0.1651)
		(layer "In15.Cu")
		(net "P5E_PEX3_STN6_RX_DP<106>")
	)
	(segment
		(start 386.489956 -401.49018)
		(end 386.489956 -401.872196)
		(width 0.1651)
		(layer "In15.Cu")
		(net "P5E_PEX3_STN6_RX_DP<106>")
	)
	(segment
		(start 387.047232 -401.999196)
		(end 387.333998 -401.71243)
		(width 0.1651)
		(layer "In15.Cu")
		(net "P5E_PEX3_STN6_RX_DP<106>")
	)
	(segment
		(start 371.748304 -373.354854)
		(end 371.856 -371.452648)
		(width 0.1651)
		(layer "In15.Cu")
		(net "P5E_PEX3_STN6_RX_DP<106>")
	)
	(segment
		(start 395.979396 -318.345058)
		(end 396.194788 -318.129666)
		(width 0.1143)
		(layer "In15.Cu")
		(net "P5E_PEX3_STN6_RX_DP<106>")
	)
	(segment
		(start 395.507972 -322.799456)
		(end 395.933676 -321.772026)
		(width 0.1651)
		(layer "In15.Cu")
		(net "P5E_PEX3_STN6_RX_DP<106>")
	)
	(segment
		(start 382.69799 -392.025378)
		(end 382.65608 -391.869422)
		(width 0.1651)
		(layer "In15.Cu")
		(net "P5E_PEX3_STN6_RX_DP<106>")
	)
	(segment
		(start 381.294386 -391.08253)
		(end 375.32945 -388.52983)
		(width 0.1651)
		(layer "In15.Cu")
		(net "P5E_PEX3_STN6_RX_DP<106>")
	)
	(segment
		(start 371.856 -371.452648)
		(end 372.286784 -369.0747)
		(width 0.1651)
		(layer "In15.Cu")
		(net "P5E_PEX3_STN6_RX_DP<106>")
	)
	(segment
		(start 383.711958 -392.479276)
		(end 383.283206 -392.231626)
		(width 0.1651)
		(layer "In15.Cu")
		(net "P5E_PEX3_STN6_RX_DP<106>")
	)
	(segment
		(start 51.511962 -155.360116)
		(end 51.750214 -155.598368)
		(width 0.13208)
		(layer "F.Cu")
		(net "NIC0_SLOT_ID1")
	)
	(segment
		(start 50.64252 -155.360116)
		(end 51.511962 -155.360116)
		(width 0.13208)
		(layer "F.Cu")
		(net "NIC0_SLOT_ID1")
	)
	(via
		(at 51.750214 -155.598368)
		(size 0.508)
		(drill 0.254)
		(layers "F.Cu" "B.Cu")
		(net "NIC0_SLOT_ID1")
	)
	(segment
		(start 49.95545 -156.0576)
		(end 49.95545 -155.0416)
		(width 0.13208)
		(layer "B.Cu")
		(net "NIC0_SLOT_ID1")
	)
	(segment
		(start 50.920142 -155.598368)
		(end 51.750214 -155.598368)
		(width 0.13208)
		(layer "B.Cu")
		(net "NIC0_SLOT_ID1")
	)
	(segment
		(start 49.95545 -155.0416)
		(end 50.363374 -155.0416)
		(width 0.13208)
		(layer "B.Cu")
		(net "NIC0_SLOT_ID1")
	)
	(segment
		(start 50.363374 -155.0416)
		(end 50.920142 -155.598368)
		(width 0.13208)
		(layer "B.Cu")
		(net "NIC0_SLOT_ID1")
	)
	(segment
		(start 312.613548 -83.526376)
		(end 311.514744 -82.427572)
		(width 0.13208)
		(layer "F.Cu")
		(net "HP_NIC5_PWRGD_R")
	)
	(segment
		(start 311.50433 -81.749646)
		(end 311.514744 -81.76006)
		(width 0.13208)
		(layer "F.Cu")
		(net "HP_NIC5_PWRGD_R")
	)
	(segment
		(start 311.514744 -82.427572)
		(end 311.514744 -81.76006)
		(width 0.13208)
		(layer "F.Cu")
		(net "HP_NIC5_PWRGD_R")
	)
	(segment
		(start 310.257444 -81.749646)
		(end 311.50433 -81.749646)
		(width 0.13208)
		(layer "F.Cu")
		(net "HP_NIC5_PWRGD_R")
	)
	(segment
		(start 313.549538 -83.526376)
		(end 312.613548 -83.526376)
		(width 0.13208)
		(layer "F.Cu")
		(net "HP_NIC5_PWRGD_R")
	)
	(via
		(at 311.514744 -82.427572)
		(size 0.508)
		(drill 0.254)
		(layers "F.Cu" "B.Cu")
		(net "HP_NIC5_PWRGD_R")
	)
	(segment
		(start 319.651888 -25.390094)
		(end 319.101978 -25.940004)
		(width 0.13208)
		(layer "F.Cu")
		(net "PRSNT_SSD11_N")
	)
	(segment
		(start 320.864738 -25.390094)
		(end 319.651888 -25.390094)
		(width 0.13208)
		(layer "F.Cu")
		(net "PRSNT_SSD11_N")
	)
	(segment
		(start 319.101978 -25.940004)
		(end 319.101978 -26.266394)
		(width 0.13208)
		(layer "F.Cu")
		(net "PRSNT_SSD11_N")
	)
	(segment
		(start 318.32042 -26.266394)
		(end 319.101978 -26.266394)
		(width 0.13208)
		(layer "F.Cu")
		(net "PRSNT_SSD11_N")
	)
	(via
		(at 319.101978 -26.266394)
		(size 0.508)
		(drill 0.254)
		(layers "F.Cu" "B.Cu")
		(net "PRSNT_SSD11_N")
	)
	(segment
		(start 123.604782 -30.353)
		(end 123.31065 -30.058868)
		(width 0.13462)
		(layer "F.Cu")
		(net "P5E_PEX1_STN2_RX_DN<45>")
	)
	(segment
		(start 126.124716 -30.353)
		(end 123.604782 -30.353)
		(width 0.13462)
		(layer "F.Cu")
		(net "P5E_PEX1_STN2_RX_DN<45>")
	)
	(segment
		(start 126.76505 -30.190186)
		(end 126.28753 -30.190186)
		(width 0.13462)
		(layer "F.Cu")
		(net "P5E_PEX1_STN2_RX_DN<45>")
	)
	(segment
		(start 126.28753 -30.190186)
		(end 126.124716 -30.353)
		(width 0.13462)
		(layer "F.Cu")
		(net "P5E_PEX1_STN2_RX_DN<45>")
	)
	(segment
		(start 162.116008 -271.3736)
		(end 162.116008 -271.345152)
		(width 0.1143)
		(layer "In7.Cu")
		(net "P5E_PEX1_STN2_RX_DN<45>")
	)
	(segment
		(start 123.60148 -30.349698)
		(end 123.31065 -30.058868)
		(width 0.1651)
		(layer "In7.Cu")
		(net "P5E_PEX1_STN2_RX_DN<45>")
	)
	(segment
		(start 161.153856 -263.502648)
		(end 161.230818 -255.646936)
		(width 0.1651)
		(layer "In7.Cu")
		(net "P5E_PEX1_STN2_RX_DN<45>")
	)
	(segment
		(start 128.448562 -61.48959)
		(end 128.448562 -60.132976)
		(width 0.1651)
		(layer "In7.Cu")
		(net "P5E_PEX1_STN2_RX_DN<45>")
	)
	(segment
		(start 127.512572 -31.973012)
		(end 125.889258 -30.349698)
		(width 0.1651)
		(layer "In7.Cu")
		(net "P5E_PEX1_STN2_RX_DN<45>")
	)
	(segment
		(start 133.435344 -102.391972)
		(end 128.258062 -85.311742)
		(width 0.1651)
		(layer "In7.Cu")
		(net "P5E_PEX1_STN2_RX_DN<45>")
	)
	(segment
		(start 127.488188 -35.00755)
		(end 127.512572 -31.973012)
		(width 0.1651)
		(layer "In7.Cu")
		(net "P5E_PEX1_STN2_RX_DN<45>")
	)
	(segment
		(start 162.070288 -273.328638)
		(end 162.070288 -271.41932)
		(width 0.1143)
		(layer "In7.Cu")
		(net "P5E_PEX1_STN2_RX_DN<45>")
	)
	(segment
		(start 162.450018 -273.099784)
		(end 162.450018 -273.365214)
		(width 0.1143)
		(layer "In7.Cu")
		(net "P5E_PEX1_STN2_RX_DN<45>")
	)
	(segment
		(start 133.447536 -102.432612)
		(end 133.447536 -102.432104)
		(width 0.1651)
		(layer "In7.Cu")
		(net "P5E_PEX1_STN2_RX_DN<45>")
	)
	(segment
		(start 133.447536 -102.432104)
		(end 133.435598 -102.392734)
		(width 0.1651)
		(layer "In7.Cu")
		(net "P5E_PEX1_STN2_RX_DN<45>")
	)
	(segment
		(start 162.221164 -273.479514)
		(end 162.070288 -273.328638)
		(width 0.1143)
		(layer "In7.Cu")
		(net "P5E_PEX1_STN2_RX_DN<45>")
	)
	(segment
		(start 162.116008 -271.345152)
		(end 162.116008 -270.28521)
		(width 0.1651)
		(layer "In7.Cu")
		(net "P5E_PEX1_STN2_RX_DN<45>")
	)
	(segment
		(start 128.448562 -60.132976)
		(end 128.1811 -57.362344)
		(width 0.1651)
		(layer "In7.Cu")
		(net "P5E_PEX1_STN2_RX_DN<45>")
	)
	(segment
		(start 128.298448 -49.868074)
		(end 126.999492 -40.256206)
		(width 0.1651)
		(layer "In7.Cu")
		(net "P5E_PEX1_STN2_RX_DN<45>")
	)
	(segment
		(start 126.999492 -40.256206)
		(end 126.963424 -37.96284)
		(width 0.1651)
		(layer "In7.Cu")
		(net "P5E_PEX1_STN2_RX_DN<45>")
	)
	(segment
		(start 162.450018 -273.365214)
		(end 162.335718 -273.479514)
		(width 0.1143)
		(layer "In7.Cu")
		(net "P5E_PEX1_STN2_RX_DN<45>")
	)
	(segment
		(start 128.258062 -85.311742)
		(end 128.448562 -61.48959)
		(width 0.1651)
		(layer "In7.Cu")
		(net "P5E_PEX1_STN2_RX_DN<45>")
	)
	(segment
		(start 162.335718 -273.479514)
		(end 162.221164 -273.479514)
		(width 0.1143)
		(layer "In7.Cu")
		(net "P5E_PEX1_STN2_RX_DN<45>")
	)
	(segment
		(start 162.070288 -271.41932)
		(end 162.116008 -271.3736)
		(width 0.1143)
		(layer "In7.Cu")
		(net "P5E_PEX1_STN2_RX_DN<45>")
	)
	(segment
		(start 162.116008 -270.28521)
		(end 161.153856 -263.502648)
		(width 0.1651)
		(layer "In7.Cu")
		(net "P5E_PEX1_STN2_RX_DN<45>")
	)
	(segment
		(start 161.230818 -255.646936)
		(end 159.630872 -238.16945)
		(width 0.1651)
		(layer "In7.Cu")
		(net "P5E_PEX1_STN2_RX_DN<45>")
	)
	(segment
		(start 159.630872 -238.16945)
		(end 141.918944 -144.505172)
		(width 0.1651)
		(layer "In7.Cu")
		(net "P5E_PEX1_STN2_RX_DN<45>")
	)
	(segment
		(start 125.889258 -30.349698)
		(end 123.60148 -30.349698)
		(width 0.1651)
		(layer "In7.Cu")
		(net "P5E_PEX1_STN2_RX_DN<45>")
	)
	(segment
		(start 128.1811 -57.362344)
		(end 128.298448 -49.868074)
		(width 0.1651)
		(layer "In7.Cu")
		(net "P5E_PEX1_STN2_RX_DN<45>")
	)
	(segment
		(start 126.963424 -37.96284)
		(end 127.488188 -35.00755)
		(width 0.1651)
		(layer "In7.Cu")
		(net "P5E_PEX1_STN2_RX_DN<45>")
	)
	(segment
		(start 133.435598 -102.392734)
		(end 133.435344 -102.391972)
		(width 0.1651)
		(layer "In7.Cu")
		(net "P5E_PEX1_STN2_RX_DN<45>")
	)
	(segment
		(start 138.636756 -119.552466)
		(end 133.447536 -102.432612)
		(width 0.1651)
		(layer "In7.Cu")
		(net "P5E_PEX1_STN2_RX_DN<45>")
	)
	(segment
		(start 141.918944 -144.505172)
		(end 138.636756 -119.552466)
		(width 0.1651)
		(layer "In7.Cu")
		(net "P5E_PEX1_STN2_RX_DN<45>")
	)
	(segment
		(start 314.594748 -156.111194)
		(end 314.282074 -155.79852)
		(width 0.13462)
		(layer "F.Cu")
		(net "P5E_PEX2_STN0_TX_C_DP<15>")
	)
	(segment
		(start 306.116736 -155.79852)
		(end 305.960272 -155.954984)
		(width 0.13462)
		(layer "F.Cu")
		(net "P5E_PEX2_STN0_TX_C_DP<15>")
	)
	(segment
		(start 314.282074 -155.79852)
		(end 306.116736 -155.79852)
		(width 0.13462)
		(layer "F.Cu")
		(net "P5E_PEX2_STN0_TX_C_DP<15>")
	)
	(segment
		(start 305.960272 -155.954984)
		(end 305.457606 -155.954984)
		(width 0.13462)
		(layer "F.Cu")
		(net "P5E_PEX2_STN0_TX_C_DP<15>")
	)
	(segment
		(start 275.004022 -350.365314)
		(end 274.683982 -350.685354)
		(width 0.13462)
		(layer "F.Cu")
		(net "P5E_PEX2_STN7_TX_C_DN<115>")
	)
	(segment
		(start 274.683982 -350.685354)
		(end 274.683982 -351.316798)
		(width 0.13462)
		(layer "F.Cu")
		(net "P5E_PEX2_STN7_TX_C_DN<115>")
	)
	(segment
		(start 274.683982 -351.316798)
		(end 274.978622 -351.611438)
		(width 0.13462)
		(layer "F.Cu")
		(net "P5E_PEX2_STN7_TX_C_DN<115>")
	)
	(segment
		(start 294.763952 -402.281136)
		(end 295.215818 -401.82927)
		(width 0.1651)
		(layer "In7.Cu")
		(net "P5E_PEX2_STN7_TX_C_DN<115>")
	)
	(segment
		(start 274.687792 -352.473006)
		(end 274.687792 -351.902268)
		(width 0.1651)
		(layer "In7.Cu")
		(net "P5E_PEX2_STN7_TX_C_DN<115>")
	)
	(segment
		(start 295.215818 -395.6558)
		(end 294.8432 -394.6144)
		(width 0.1651)
		(layer "In7.Cu")
		(net "P5E_PEX2_STN7_TX_C_DN<115>")
	)
	(segment
		(start 294.089836 -402.408136)
		(end 294.216836 -402.281136)
		(width 0.1651)
		(layer "In7.Cu")
		(net "P5E_PEX2_STN7_TX_C_DN<115>")
	)
	(segment
		(start 273.133312 -354.027486)
		(end 274.687792 -352.473006)
		(width 0.1651)
		(layer "In7.Cu")
		(net "P5E_PEX2_STN7_TX_C_DN<115>")
	)
	(segment
		(start 285.09087 -388.972298)
		(end 283.33573 -387.2992)
		(width 0.1651)
		(layer "In7.Cu")
		(net "P5E_PEX2_STN7_TX_C_DN<115>")
	)
	(segment
		(start 294.8432 -394.6144)
		(end 292.735 -392.5062)
		(width 0.1651)
		(layer "In7.Cu")
		(net "P5E_PEX2_STN7_TX_C_DN<115>")
	)
	(segment
		(start 295.215818 -401.82927)
		(end 295.215818 -395.6558)
		(width 0.1651)
		(layer "In7.Cu")
		(net "P5E_PEX2_STN7_TX_C_DN<115>")
	)
	(segment
		(start 280.705814 -374.26265)
		(end 273.133312 -358.013)
		(width 0.1651)
		(layer "In7.Cu")
		(net "P5E_PEX2_STN7_TX_C_DN<115>")
	)
	(segment
		(start 294.216836 -402.281136)
		(end 294.763952 -402.281136)
		(width 0.1651)
		(layer "In7.Cu")
		(net "P5E_PEX2_STN7_TX_C_DN<115>")
	)
	(segment
		(start 273.133312 -358.013)
		(end 273.133312 -354.027486)
		(width 0.1651)
		(layer "In7.Cu")
		(net "P5E_PEX2_STN7_TX_C_DN<115>")
	)
	(segment
		(start 274.687792 -351.902268)
		(end 274.978622 -351.611438)
		(width 0.1651)
		(layer "In7.Cu")
		(net "P5E_PEX2_STN7_TX_C_DN<115>")
	)
	(segment
		(start 282.640278 -385.598924)
		(end 280.705814 -374.26265)
		(width 0.1651)
		(layer "In7.Cu")
		(net "P5E_PEX2_STN7_TX_C_DN<115>")
	)
	(segment
		(start 283.33573 -387.2992)
		(end 282.640278 -385.598924)
		(width 0.1651)
		(layer "In7.Cu")
		(net "P5E_PEX2_STN7_TX_C_DN<115>")
	)
	(segment
		(start 292.735 -392.5062)
		(end 285.09087 -388.972298)
		(width 0.1651)
		(layer "In7.Cu")
		(net "P5E_PEX2_STN7_TX_C_DN<115>")
	)
	(segment
		(start 294.089836 -402.790152)
		(end 294.089836 -402.408136)
		(width 0.1651)
		(layer "In7.Cu")
		(net "P5E_PEX2_STN7_TX_C_DN<115>")
	)
	(segment
		(start 377.3805 -350.365314)
		(end 377.701048 -350.685862)
		(width 0.13462)
		(layer "F.Cu")
		(net "P5E_PEX3_STN6_TX_C_DP<100>")
	)
	(segment
		(start 377.701048 -350.685862)
		(end 377.701048 -351.31629)
		(width 0.13462)
		(layer "F.Cu")
		(net "P5E_PEX3_STN6_TX_C_DP<100>")
	)
	(segment
		(start 377.701048 -351.31629)
		(end 377.4059 -351.611438)
		(width 0.13462)
		(layer "F.Cu")
		(net "P5E_PEX3_STN6_TX_C_DP<100>")
	)
	(segment
		(start 376.14225 -358.518714)
		(end 376.14225 -353.910646)
		(width 0.1651)
		(layer "In7.Cu")
		(net "P5E_PEX3_STN6_TX_C_DP<100>")
	)
	(segment
		(start 382.933956 -368.894614)
		(end 381.76073 -367.102136)
		(width 0.1651)
		(layer "In7.Cu")
		(net "P5E_PEX3_STN6_TX_C_DP<100>")
	)
	(segment
		(start 382.216914 -383.79908)
		(end 382.64719 -383.79908)
		(width 0.1651)
		(layer "In7.Cu")
		(net "P5E_PEX3_STN6_TX_C_DP<100>")
	)
	(segment
		(start 381.330962 -366.654334)
		(end 381.363982 -366.496092)
		(width 0.1651)
		(layer "In7.Cu")
		(net "P5E_PEX3_STN6_TX_C_DP<100>")
	)
	(segment
		(start 382.64719 -383.79908)
		(end 382.933956 -383.512314)
		(width 0.1651)
		(layer "In7.Cu")
		(net "P5E_PEX3_STN6_TX_C_DP<100>")
	)
	(segment
		(start 381.363982 -366.496092)
		(end 381.363728 -366.496092)
		(width 0.1651)
		(layer "In7.Cu")
		(net "P5E_PEX3_STN6_TX_C_DP<100>")
	)
	(segment
		(start 382.089914 -383.67208)
		(end 382.216914 -383.79908)
		(width 0.1651)
		(layer "In7.Cu")
		(net "P5E_PEX3_STN6_TX_C_DP<100>")
	)
	(segment
		(start 381.363728 -366.496092)
		(end 376.14225 -358.518714)
		(width 0.1651)
		(layer "In7.Cu")
		(net "P5E_PEX3_STN6_TX_C_DP<100>")
	)
	(segment
		(start 377.69673 -351.902268)
		(end 377.4059 -351.611438)
		(width 0.1651)
		(layer "In7.Cu")
		(net "P5E_PEX3_STN6_TX_C_DP<100>")
	)
	(segment
		(start 377.69673 -352.356166)
		(end 377.69673 -351.902268)
		(width 0.1651)
		(layer "In7.Cu")
		(net "P5E_PEX3_STN6_TX_C_DP<100>")
	)
	(segment
		(start 381.76073 -367.102136)
		(end 381.602488 -367.069116)
		(width 0.1651)
		(layer "In7.Cu")
		(net "P5E_PEX3_STN6_TX_C_DP<100>")
	)
	(segment
		(start 376.14225 -353.910646)
		(end 377.69673 -352.356166)
		(width 0.1651)
		(layer "In7.Cu")
		(net "P5E_PEX3_STN6_TX_C_DP<100>")
	)
	(segment
		(start 382.089914 -383.290064)
		(end 382.089914 -383.67208)
		(width 0.1651)
		(layer "In7.Cu")
		(net "P5E_PEX3_STN6_TX_C_DP<100>")
	)
	(segment
		(start 382.933956 -383.512314)
		(end 382.933956 -368.894614)
		(width 0.1651)
		(layer "In7.Cu")
		(net "P5E_PEX3_STN6_TX_C_DP<100>")
	)
	(segment
		(start 381.602488 -367.069116)
		(end 381.330962 -366.654334)
		(width 0.1651)
		(layer "In7.Cu")
		(net "P5E_PEX3_STN6_TX_C_DP<100>")
	)
	(segment
		(start 178.119532 -34.227262)
		(end 175.605694 -34.227262)
		(width 0.13462)
		(layer "F.Cu")
		(net "P5E_PEX1_STN2_RX_DP<39>")
	)
	(segment
		(start 178.764946 -34.390076)
		(end 178.282346 -34.390076)
		(width 0.13462)
		(layer "F.Cu")
		(net "P5E_PEX1_STN2_RX_DP<39>")
	)
	(segment
		(start 175.605694 -34.227262)
		(end 175.310546 -34.52241)
		(width 0.13462)
		(layer "F.Cu")
		(net "P5E_PEX1_STN2_RX_DP<39>")
	)
	(segment
		(start 178.282346 -34.390076)
		(end 178.119532 -34.227262)
		(width 0.13462)
		(layer "F.Cu")
		(net "P5E_PEX1_STN2_RX_DP<39>")
	)
	(segment
		(start 177.998882 -68.131182)
		(end 177.972974 -60.995052)
		(width 0.1651)
		(layer "In7.Cu")
		(net "P5E_PEX1_STN2_RX_DP<39>")
	)
	(segment
		(start 167.842184 -273.670014)
		(end 167.579802 -273.407632)
		(width 0.1143)
		(layer "In7.Cu")
		(net "P5E_PEX1_STN2_RX_DP<39>")
	)
	(segment
		(start 168.150032 -273.784314)
		(end 168.035732 -273.670014)
		(width 0.1143)
		(layer "In7.Cu")
		(net "P5E_PEX1_STN2_RX_DP<39>")
	)
	(segment
		(start 176.764442 -39.111174)
		(end 176.661064 -39.011352)
		(width 0.1651)
		(layer "In7.Cu")
		(net "P5E_PEX1_STN2_RX_DP<39>")
	)
	(segment
		(start 176.734978 -37.218874)
		(end 176.706276 -35.357562)
		(width 0.1651)
		(layer "In7.Cu")
		(net "P5E_PEX1_STN2_RX_DP<39>")
	)
	(segment
		(start 168.035732 -273.670014)
		(end 167.842184 -273.670014)
		(width 0.1143)
		(layer "In7.Cu")
		(net "P5E_PEX1_STN2_RX_DP<39>")
	)
	(segment
		(start 178.145694 -49.932336)
		(end 176.774856 -39.786052)
		(width 0.1651)
		(layer "In7.Cu")
		(net "P5E_PEX1_STN2_RX_DP<39>")
	)
	(segment
		(start 167.534082 -271.4752)
		(end 167.534082 -266.267438)
		(width 0.1651)
		(layer "In7.Cu")
		(net "P5E_PEX1_STN2_RX_DP<39>")
	)
	(segment
		(start 176.661064 -39.011352)
		(end 176.653444 -38.515798)
		(width 0.1651)
		(layer "In7.Cu")
		(net "P5E_PEX1_STN2_RX_DP<39>")
	)
	(segment
		(start 176.706276 -35.1028)
		(end 175.835056 -34.23158)
		(width 0.1651)
		(layer "In7.Cu")
		(net "P5E_PEX1_STN2_RX_DP<39>")
	)
	(segment
		(start 177.972974 -60.995052)
		(end 178.145694 -49.932336)
		(width 0.1651)
		(layer "In7.Cu")
		(net "P5E_PEX1_STN2_RX_DP<39>")
	)
	(segment
		(start 168.150032 -274.049744)
		(end 168.150032 -273.784314)
		(width 0.1143)
		(layer "In7.Cu")
		(net "P5E_PEX1_STN2_RX_DP<39>")
	)
	(segment
		(start 167.534082 -266.267438)
		(end 177.998882 -68.131182)
		(width 0.1651)
		(layer "In7.Cu")
		(net "P5E_PEX1_STN2_RX_DP<39>")
	)
	(segment
		(start 176.774856 -39.786052)
		(end 176.764442 -39.111174)
		(width 0.1651)
		(layer "In7.Cu")
		(net "P5E_PEX1_STN2_RX_DP<39>")
	)
	(segment
		(start 176.642522 -37.817552)
		(end 176.634902 -37.321998)
		(width 0.1651)
		(layer "In7.Cu")
		(net "P5E_PEX1_STN2_RX_DP<39>")
	)
	(segment
		(start 167.534082 -271.503648)
		(end 167.534082 -271.4752)
		(width 0.1143)
		(layer "In7.Cu")
		(net "P5E_PEX1_STN2_RX_DP<39>")
	)
	(segment
		(start 176.75352 -38.412674)
		(end 176.7459 -37.917628)
		(width 0.1651)
		(layer "In7.Cu")
		(net "P5E_PEX1_STN2_RX_DP<39>")
	)
	(segment
		(start 167.579802 -273.407632)
		(end 167.579802 -271.549368)
		(width 0.1143)
		(layer "In7.Cu")
		(net "P5E_PEX1_STN2_RX_DP<39>")
	)
	(segment
		(start 167.579802 -271.549368)
		(end 167.534082 -271.503648)
		(width 0.1143)
		(layer "In7.Cu")
		(net "P5E_PEX1_STN2_RX_DP<39>")
	)
	(segment
		(start 176.706276 -35.357562)
		(end 176.706276 -35.1028)
		(width 0.1651)
		(layer "In7.Cu")
		(net "P5E_PEX1_STN2_RX_DP<39>")
	)
	(segment
		(start 175.601376 -34.23158)
		(end 175.310546 -34.52241)
		(width 0.1651)
		(layer "In7.Cu")
		(net "P5E_PEX1_STN2_RX_DP<39>")
	)
	(segment
		(start 175.835056 -34.23158)
		(end 175.601376 -34.23158)
		(width 0.1651)
		(layer "In7.Cu")
		(net "P5E_PEX1_STN2_RX_DP<39>")
	)
	(segment
		(start 176.653444 -38.515798)
		(end 176.75352 -38.412674)
		(width 0.1651)
		(layer "In7.Cu")
		(net "P5E_PEX1_STN2_RX_DP<39>")
	)
	(segment
		(start 176.7459 -37.917628)
		(end 176.642522 -37.817552)
		(width 0.1651)
		(layer "In7.Cu")
		(net "P5E_PEX1_STN2_RX_DP<39>")
	)
	(segment
		(start 176.634902 -37.321998)
		(end 176.734978 -37.218874)
		(width 0.1651)
		(layer "In7.Cu")
		(net "P5E_PEX1_STN2_RX_DP<39>")
	)
	(segment
		(start 300.374812 -145.154904)
		(end 300.857412 -145.154904)
		(width 0.13462)
		(layer "F.Cu")
		(net "P5E_PEX2_STN0_RX_DP<9>")
	)
	(segment
		(start 300.203108 -144.9832)
		(end 300.374812 -145.154904)
		(width 0.13462)
		(layer "F.Cu")
		(net "P5E_PEX2_STN0_RX_DP<9>")
	)
	(segment
		(start 297.70705 -144.9832)
		(end 300.203108 -144.9832)
		(width 0.13462)
		(layer "F.Cu")
		(net "P5E_PEX2_STN0_RX_DP<9>")
	)
	(segment
		(start 297.403012 -145.287238)
		(end 297.70705 -144.9832)
		(width 0.13462)
		(layer "F.Cu")
		(net "P5E_PEX2_STN0_RX_DP<9>")
	)
	(segment
		(start 312.749438 -274.049744)
		(end 312.749438 -273.784314)
		(width 0.1143)
		(layer "In5.Cu")
		(net "P5E_PEX2_STN0_RX_DP<9>")
	)
	(segment
		(start 305.036982 -152.63622)
		(end 304.281586 -150.537418)
		(width 0.1651)
		(layer "In5.Cu")
		(net "P5E_PEX2_STN0_RX_DP<9>")
	)
	(segment
		(start 301.512478 -146.724624)
		(end 301.350934 -146.723354)
		(width 0.1651)
		(layer "In5.Cu")
		(net "P5E_PEX2_STN0_RX_DP<9>")
	)
	(segment
		(start 312.133742 -271.554448)
		(end 312.133742 -271.526)
		(width 0.1143)
		(layer "In5.Cu")
		(net "P5E_PEX2_STN0_RX_DP<9>")
	)
	(segment
		(start 299.367448 -144.996408)
		(end 297.693842 -144.996408)
		(width 0.1651)
		(layer "In5.Cu")
		(net "P5E_PEX2_STN0_RX_DP<9>")
	)
	(segment
		(start 301.0027 -146.370548)
		(end 301.00397 -146.209004)
		(width 0.1651)
		(layer "In5.Cu")
		(net "P5E_PEX2_STN0_RX_DP<9>")
	)
	(segment
		(start 312.133742 -271.197578)
		(end 312.717942 -268.260068)
		(width 0.1651)
		(layer "In5.Cu")
		(net "P5E_PEX2_STN0_RX_DP<9>")
	)
	(segment
		(start 312.635138 -273.670014)
		(end 312.394346 -273.670014)
		(width 0.1143)
		(layer "In5.Cu")
		(net "P5E_PEX2_STN0_RX_DP<9>")
	)
	(segment
		(start 300.11751 -145.310352)
		(end 299.367448 -144.996408)
		(width 0.1651)
		(layer "In5.Cu")
		(net "P5E_PEX2_STN0_RX_DP<9>")
	)
	(segment
		(start 309.136542 -160.504886)
		(end 307.785008 -155.437332)
		(width 0.1651)
		(layer "In5.Cu")
		(net "P5E_PEX2_STN0_RX_DP<9>")
	)
	(segment
		(start 312.179462 -271.600168)
		(end 312.133742 -271.554448)
		(width 0.1143)
		(layer "In5.Cu")
		(net "P5E_PEX2_STN0_RX_DP<9>")
	)
	(segment
		(start 312.749438 -273.784314)
		(end 312.635138 -273.670014)
		(width 0.1143)
		(layer "In5.Cu")
		(net "P5E_PEX2_STN0_RX_DP<9>")
	)
	(segment
		(start 302.372522 -147.596352)
		(end 301.512478 -146.724624)
		(width 0.1651)
		(layer "In5.Cu")
		(net "P5E_PEX2_STN0_RX_DP<9>")
	)
	(segment
		(start 307.785008 -155.437332)
		(end 305.036982 -152.63622)
		(width 0.1651)
		(layer "In5.Cu")
		(net "P5E_PEX2_STN0_RX_DP<9>")
	)
	(segment
		(start 301.00397 -146.209004)
		(end 300.11751 -145.310352)
		(width 0.1651)
		(layer "In5.Cu")
		(net "P5E_PEX2_STN0_RX_DP<9>")
	)
	(segment
		(start 301.350934 -146.723354)
		(end 301.0027 -146.370548)
		(width 0.1651)
		(layer "In5.Cu")
		(net "P5E_PEX2_STN0_RX_DP<9>")
	)
	(segment
		(start 312.394346 -273.670014)
		(end 312.179462 -273.45513)
		(width 0.1143)
		(layer "In5.Cu")
		(net "P5E_PEX2_STN0_RX_DP<9>")
	)
	(segment
		(start 312.179462 -273.45513)
		(end 312.179462 -271.600168)
		(width 0.1143)
		(layer "In5.Cu")
		(net "P5E_PEX2_STN0_RX_DP<9>")
	)
	(segment
		(start 312.717942 -261.978394)
		(end 309.136542 -160.504886)
		(width 0.1651)
		(layer "In5.Cu")
		(net "P5E_PEX2_STN0_RX_DP<9>")
	)
	(segment
		(start 304.281586 -150.537418)
		(end 302.372522 -147.596352)
		(width 0.1651)
		(layer "In5.Cu")
		(net "P5E_PEX2_STN0_RX_DP<9>")
	)
	(segment
		(start 297.693842 -144.996408)
		(end 297.403012 -145.287238)
		(width 0.1651)
		(layer "In5.Cu")
		(net "P5E_PEX2_STN0_RX_DP<9>")
	)
	(segment
		(start 312.133742 -271.526)
		(end 312.133742 -271.197578)
		(width 0.1651)
		(layer "In5.Cu")
		(net "P5E_PEX2_STN0_RX_DP<9>")
	)
	(segment
		(start 312.717942 -268.260068)
		(end 312.717942 -261.978394)
		(width 0.1651)
		(layer "In5.Cu")
		(net "P5E_PEX2_STN0_RX_DP<9>")
	)
	(segment
		(start 374.592088 -344.53957)
		(end 374.592088 -345.169998)
		(width 0.13462)
		(layer "F.Cu")
		(net "P5E_PEX3_STN6_TX_C_DP<102>")
	)
	(segment
		(start 374.27154 -344.219022)
		(end 374.592088 -344.53957)
		(width 0.13462)
		(layer "F.Cu")
		(net "P5E_PEX3_STN6_TX_C_DP<102>")
	)
	(segment
		(start 374.592088 -345.169998)
		(end 374.29694 -345.465146)
		(width 0.13462)
		(layer "F.Cu")
		(net "P5E_PEX3_STN6_TX_C_DP<102>")
	)
	(segment
		(start 374.58777 -345.755976)
		(end 374.29694 -345.465146)
		(width 0.1651)
		(layer "In7.Cu")
		(net "P5E_PEX3_STN6_TX_C_DP<102>")
	)
	(segment
		(start 377.689872 -383.290064)
		(end 377.689872 -383.67208)
		(width 0.1651)
		(layer "In7.Cu")
		(net "P5E_PEX3_STN6_TX_C_DP<102>")
	)
	(segment
		(start 377.38177 -366.886744)
		(end 377.148598 -366.449356)
		(width 0.1651)
		(layer "In7.Cu")
		(net "P5E_PEX3_STN6_TX_C_DP<102>")
	)
	(segment
		(start 373.03329 -358.477312)
		(end 373.03329 -347.764354)
		(width 0.1651)
		(layer "In7.Cu")
		(net "P5E_PEX3_STN6_TX_C_DP<102>")
	)
	(segment
		(start 378.247148 -383.79908)
		(end 378.533914 -383.512314)
		(width 0.1651)
		(layer "In7.Cu")
		(net "P5E_PEX3_STN6_TX_C_DP<102>")
	)
	(segment
		(start 377.816872 -383.79908)
		(end 378.247148 -383.79908)
		(width 0.1651)
		(layer "In7.Cu")
		(net "P5E_PEX3_STN6_TX_C_DP<102>")
	)
	(segment
		(start 377.148598 -366.449356)
		(end 377.195842 -366.29467)
		(width 0.1651)
		(layer "In7.Cu")
		(net "P5E_PEX3_STN6_TX_C_DP<102>")
	)
	(segment
		(start 378.533914 -368.807492)
		(end 377.536202 -366.933988)
		(width 0.1651)
		(layer "In7.Cu")
		(net "P5E_PEX3_STN6_TX_C_DP<102>")
	)
	(segment
		(start 373.03329 -347.764354)
		(end 374.58777 -346.209874)
		(width 0.1651)
		(layer "In7.Cu")
		(net "P5E_PEX3_STN6_TX_C_DP<102>")
	)
	(segment
		(start 377.689872 -383.67208)
		(end 377.816872 -383.79908)
		(width 0.1651)
		(layer "In7.Cu")
		(net "P5E_PEX3_STN6_TX_C_DP<102>")
	)
	(segment
		(start 378.533914 -383.512314)
		(end 378.533914 -368.807492)
		(width 0.1651)
		(layer "In7.Cu")
		(net "P5E_PEX3_STN6_TX_C_DP<102>")
	)
	(segment
		(start 377.536202 -366.933988)
		(end 377.38177 -366.886744)
		(width 0.1651)
		(layer "In7.Cu")
		(net "P5E_PEX3_STN6_TX_C_DP<102>")
	)
	(segment
		(start 377.195842 -366.29467)
		(end 373.03329 -358.477312)
		(width 0.1651)
		(layer "In7.Cu")
		(net "P5E_PEX3_STN6_TX_C_DP<102>")
	)
	(segment
		(start 374.58777 -346.209874)
		(end 374.58777 -345.755976)
		(width 0.1651)
		(layer "In7.Cu")
		(net "P5E_PEX3_STN6_TX_C_DP<102>")
	)
	(segment
		(start 62.024514 -33.952942)
		(end 59.50458 -33.952942)
		(width 0.13462)
		(layer "F.Cu")
		(net "P5E_PEX0_STN2_RX_DN<39>")
	)
	(segment
		(start 62.664848 -33.790128)
		(end 62.187328 -33.790128)
		(width 0.13462)
		(layer "F.Cu")
		(net "P5E_PEX0_STN2_RX_DN<39>")
	)
	(segment
		(start 59.50458 -33.952942)
		(end 59.210448 -33.65881)
		(width 0.13462)
		(layer "F.Cu")
		(net "P5E_PEX0_STN2_RX_DN<39>")
	)
	(segment
		(start 62.187328 -33.790128)
		(end 62.024514 -33.952942)
		(width 0.13462)
		(layer "F.Cu")
		(net "P5E_PEX0_STN2_RX_DN<39>")
	)
	(segment
		(start 59.851798 -33.94964)
		(end 59.501278 -33.94964)
		(width 0.1651)
		(layer "In7.Cu")
		(net "P5E_PEX0_STN2_RX_DN<39>")
	)
	(segment
		(start 51.715924 -266.275058)
		(end 62.180978 -68.13804)
		(width 0.1651)
		(layer "In7.Cu")
		(net "P5E_PEX0_STN2_RX_DN<39>")
	)
	(segment
		(start 51.670204 -273.328638)
		(end 51.670204 -271.549368)
		(width 0.1143)
		(layer "In7.Cu")
		(net "P5E_PEX0_STN2_RX_DN<39>")
	)
	(segment
		(start 60.888118 -35.355276)
		(end 60.888118 -34.98596)
		(width 0.1651)
		(layer "In7.Cu")
		(net "P5E_PEX0_STN2_RX_DN<39>")
	)
	(segment
		(start 51.715924 -271.4752)
		(end 51.715924 -266.275058)
		(width 0.1651)
		(layer "In7.Cu")
		(net "P5E_PEX0_STN2_RX_DN<39>")
	)
	(segment
		(start 51.82108 -273.479514)
		(end 51.670204 -273.328638)
		(width 0.1143)
		(layer "In7.Cu")
		(net "P5E_PEX0_STN2_RX_DN<39>")
	)
	(segment
		(start 51.715924 -271.503648)
		(end 51.715924 -271.4752)
		(width 0.1143)
		(layer "In7.Cu")
		(net "P5E_PEX0_STN2_RX_DN<39>")
	)
	(segment
		(start 51.670204 -271.549368)
		(end 51.715924 -271.503648)
		(width 0.1143)
		(layer "In7.Cu")
		(net "P5E_PEX0_STN2_RX_DN<39>")
	)
	(segment
		(start 62.328044 -49.915572)
		(end 60.956444 -39.76497)
		(width 0.1651)
		(layer "In7.Cu")
		(net "P5E_PEX0_STN2_RX_DN<39>")
	)
	(segment
		(start 62.180978 -68.13804)
		(end 62.15507 -60.99683)
		(width 0.1651)
		(layer "In7.Cu")
		(net "P5E_PEX0_STN2_RX_DN<39>")
	)
	(segment
		(start 52.049934 -273.099784)
		(end 52.049934 -273.365214)
		(width 0.1143)
		(layer "In7.Cu")
		(net "P5E_PEX0_STN2_RX_DN<39>")
	)
	(segment
		(start 62.15507 -60.99683)
		(end 62.328044 -49.915572)
		(width 0.1651)
		(layer "In7.Cu")
		(net "P5E_PEX0_STN2_RX_DN<39>")
	)
	(segment
		(start 60.956444 -39.76497)
		(end 60.888118 -35.355276)
		(width 0.1651)
		(layer "In7.Cu")
		(net "P5E_PEX0_STN2_RX_DN<39>")
	)
	(segment
		(start 52.049934 -273.365214)
		(end 51.935634 -273.479514)
		(width 0.1143)
		(layer "In7.Cu")
		(net "P5E_PEX0_STN2_RX_DN<39>")
	)
	(segment
		(start 51.935634 -273.479514)
		(end 51.82108 -273.479514)
		(width 0.1143)
		(layer "In7.Cu")
		(net "P5E_PEX0_STN2_RX_DN<39>")
	)
	(segment
		(start 60.888118 -34.98596)
		(end 59.851798 -33.94964)
		(width 0.1651)
		(layer "In7.Cu")
		(net "P5E_PEX0_STN2_RX_DN<39>")
	)
	(segment
		(start 59.501278 -33.94964)
		(end 59.210448 -33.65881)
		(width 0.1651)
		(layer "In7.Cu")
		(net "P5E_PEX0_STN2_RX_DN<39>")
	)
	(segment
		(start 204.764894 -34.390076)
		(end 204.282294 -34.390076)
		(width 0.13462)
		(layer "F.Cu")
		(net "P5E_PEX1_STN2_RX_DP<35>")
	)
	(segment
		(start 204.11948 -34.227262)
		(end 201.605642 -34.227262)
		(width 0.13462)
		(layer "F.Cu")
		(net "P5E_PEX1_STN2_RX_DP<35>")
	)
	(segment
		(start 204.282294 -34.390076)
		(end 204.11948 -34.227262)
		(width 0.13462)
		(layer "F.Cu")
		(net "P5E_PEX1_STN2_RX_DP<35>")
	)
	(segment
		(start 201.605642 -34.227262)
		(end 201.310494 -34.52241)
		(width 0.13462)
		(layer "F.Cu")
		(net "P5E_PEX1_STN2_RX_DP<35>")
	)
	(segment
		(start 203.90739 -61.097668)
		(end 204.088238 -49.507648)
		(width 0.1651)
		(layer "In7.Cu")
		(net "P5E_PEX1_STN2_RX_DP<35>")
	)
	(segment
		(start 202.079098 -34.23158)
		(end 201.727054 -34.23158)
		(width 0.1651)
		(layer "In7.Cu")
		(net "P5E_PEX1_STN2_RX_DP<35>")
	)
	(segment
		(start 192.921128 -116.47424)
		(end 203.90739 -61.097668)
		(width 0.1651)
		(layer "In7.Cu")
		(net "P5E_PEX1_STN2_RX_DP<35>")
	)
	(segment
		(start 171.333922 -271.345152)
		(end 171.333922 -270.499332)
		(width 0.1651)
		(layer "In7.Cu")
		(net "P5E_PEX1_STN2_RX_DP<35>")
	)
	(segment
		(start 202.68057 -34.833306)
		(end 202.079098 -34.23158)
		(width 0.1651)
		(layer "In7.Cu")
		(net "P5E_PEX1_STN2_RX_DP<35>")
	)
	(segment
		(start 192.605406 -143.663162)
		(end 192.921128 -116.47424)
		(width 0.1651)
		(layer "In7.Cu")
		(net "P5E_PEX1_STN2_RX_DP<35>")
	)
	(segment
		(start 202.608434 -37.72662)
		(end 202.720956 -37.610796)
		(width 0.1651)
		(layer "In7.Cu")
		(net "P5E_PEX1_STN2_RX_DP<35>")
	)
	(segment
		(start 202.75042 -39.604696)
		(end 202.731878 -38.33495)
		(width 0.1651)
		(layer "In7.Cu")
		(net "P5E_PEX1_STN2_RX_DP<35>")
	)
	(segment
		(start 171.949872 -274.049744)
		(end 171.949872 -273.784314)
		(width 0.1143)
		(layer "In7.Cu")
		(net "P5E_PEX1_STN2_RX_DP<35>")
	)
	(segment
		(start 202.6158 -38.222174)
		(end 202.608434 -37.72662)
		(width 0.1651)
		(layer "In7.Cu")
		(net "P5E_PEX1_STN2_RX_DP<35>")
	)
	(segment
		(start 191.228218 -154.366976)
		(end 192.605406 -143.663162)
		(width 0.1651)
		(layer "In7.Cu")
		(net "P5E_PEX1_STN2_RX_DP<35>")
	)
	(segment
		(start 201.727054 -34.23158)
		(end 201.512424 -34.32048)
		(width 0.1651)
		(layer "In7.Cu")
		(net "P5E_PEX1_STN2_RX_DP<35>")
	)
	(segment
		(start 171.66082 -266.721844)
		(end 191.228218 -154.366976)
		(width 0.1651)
		(layer "In7.Cu")
		(net "P5E_PEX1_STN2_RX_DP<35>")
	)
	(segment
		(start 171.333922 -271.3736)
		(end 171.333922 -271.345152)
		(width 0.1143)
		(layer "In7.Cu")
		(net "P5E_PEX1_STN2_RX_DP<35>")
	)
	(segment
		(start 171.379642 -271.41932)
		(end 171.333922 -271.3736)
		(width 0.1143)
		(layer "In7.Cu")
		(net "P5E_PEX1_STN2_RX_DP<35>")
	)
	(segment
		(start 171.642024 -273.670014)
		(end 171.379642 -273.407632)
		(width 0.1143)
		(layer "In7.Cu")
		(net "P5E_PEX1_STN2_RX_DP<35>")
	)
	(segment
		(start 202.703176 -36.391596)
		(end 202.68057 -34.833306)
		(width 0.1651)
		(layer "In7.Cu")
		(net "P5E_PEX1_STN2_RX_DP<35>")
	)
	(segment
		(start 202.5904 -36.507674)
		(end 202.703176 -36.391596)
		(width 0.1651)
		(layer "In7.Cu")
		(net "P5E_PEX1_STN2_RX_DP<35>")
	)
	(segment
		(start 171.835572 -273.670014)
		(end 171.642024 -273.670014)
		(width 0.1143)
		(layer "In7.Cu")
		(net "P5E_PEX1_STN2_RX_DP<35>")
	)
	(segment
		(start 204.088238 -49.507648)
		(end 202.75042 -39.604696)
		(width 0.1651)
		(layer "In7.Cu")
		(net "P5E_PEX1_STN2_RX_DP<35>")
	)
	(segment
		(start 202.597766 -37.002974)
		(end 202.5904 -36.507674)
		(width 0.1651)
		(layer "In7.Cu")
		(net "P5E_PEX1_STN2_RX_DP<35>")
	)
	(segment
		(start 202.731878 -38.33495)
		(end 202.6158 -38.222174)
		(width 0.1651)
		(layer "In7.Cu")
		(net "P5E_PEX1_STN2_RX_DP<35>")
	)
	(segment
		(start 201.512424 -34.32048)
		(end 201.310494 -34.52241)
		(width 0.1651)
		(layer "In7.Cu")
		(net "P5E_PEX1_STN2_RX_DP<35>")
	)
	(segment
		(start 171.333922 -270.499332)
		(end 171.66082 -266.721844)
		(width 0.1651)
		(layer "In7.Cu")
		(net "P5E_PEX1_STN2_RX_DP<35>")
	)
	(segment
		(start 171.379642 -273.407632)
		(end 171.379642 -271.41932)
		(width 0.1143)
		(layer "In7.Cu")
		(net "P5E_PEX1_STN2_RX_DP<35>")
	)
	(segment
		(start 171.949872 -273.784314)
		(end 171.835572 -273.670014)
		(width 0.1143)
		(layer "In7.Cu")
		(net "P5E_PEX1_STN2_RX_DP<35>")
	)
	(segment
		(start 202.720956 -37.610796)
		(end 202.713844 -37.11575)
		(width 0.1651)
		(layer "In7.Cu")
		(net "P5E_PEX1_STN2_RX_DP<35>")
	)
	(segment
		(start 202.713844 -37.11575)
		(end 202.597766 -37.002974)
		(width 0.1651)
		(layer "In7.Cu")
		(net "P5E_PEX1_STN2_RX_DP<35>")
	)
	(segment
		(start 305.960526 -146.355054)
		(end 305.457606 -146.355054)
		(width 0.13462)
		(layer "F.Cu")
		(net "P5E_PEX2_STN0_TX_C_DN<10>")
	)
	(segment
		(start 311.630568 -146.51228)
		(end 306.117752 -146.51228)
		(width 0.13462)
		(layer "F.Cu")
		(net "P5E_PEX2_STN0_TX_C_DN<10>")
	)
	(segment
		(start 311.95264 -146.190208)
		(end 311.630568 -146.51228)
		(width 0.13462)
		(layer "F.Cu")
		(net "P5E_PEX2_STN0_TX_C_DN<10>")
	)
	(segment
		(start 306.117752 -146.51228)
		(end 305.960526 -146.355054)
		(width 0.13462)
		(layer "F.Cu")
		(net "P5E_PEX2_STN0_TX_C_DN<10>")
	)
	(segment
		(start 282.571444 -387.866636)
		(end 281.560524 -385.417568)
		(width 0.1651)
		(layer "In5.Cu")
		(net "P5E_PEX2_STN7_RX_DN<114>")
	)
	(segment
		(start 256.407158 -308.219856)
		(end 257.193796 -307.433218)
		(width 0.1651)
		(layer "In5.Cu")
		(net "P5E_PEX2_STN7_RX_DN<114>")
	)
	(segment
		(start 251.8029 -318.562228)
		(end 254.717804 -312.014616)
		(width 0.1651)
		(layer "In5.Cu")
		(net "P5E_PEX2_STN7_RX_DN<114>")
	)
	(segment
		(start 254.71755 -312.014616)
		(end 254.851662 -311.963308)
		(width 0.1651)
		(layer "In5.Cu")
		(net "P5E_PEX2_STN7_RX_DN<114>")
	)
	(segment
		(start 292.016942 -408.981148)
		(end 292.564058 -408.981148)
		(width 0.1651)
		(layer "In5.Cu")
		(net "P5E_PEX2_STN7_RX_DN<114>")
	)
	(segment
		(start 292.564058 -408.981148)
		(end 293.015924 -408.529282)
		(width 0.1651)
		(layer "In5.Cu")
		(net "P5E_PEX2_STN7_RX_DN<114>")
	)
	(segment
		(start 251.8029 -322.95719)
		(end 251.8029 -318.562228)
		(width 0.1651)
		(layer "In5.Cu")
		(net "P5E_PEX2_STN7_RX_DN<114>")
	)
	(segment
		(start 264.170668 -303.165764)
		(end 267.7922 -303.165764)
		(width 0.1651)
		(layer "In5.Cu")
		(net "P5E_PEX2_STN7_RX_DN<114>")
	)
	(segment
		(start 271.215358 -303.499774)
		(end 270.949928 -303.499774)
		(width 0.1143)
		(layer "In5.Cu")
		(net "P5E_PEX2_STN7_RX_DN<114>")
	)
	(segment
		(start 291.889942 -409.108148)
		(end 292.016942 -408.981148)
		(width 0.1651)
		(layer "In5.Cu")
		(net "P5E_PEX2_STN7_RX_DN<114>")
	)
	(segment
		(start 255.00203 -311.376314)
		(end 255.203452 -310.92394)
		(width 0.1651)
		(layer "In5.Cu")
		(net "P5E_PEX2_STN7_RX_DN<114>")
	)
	(segment
		(start 255.822958 -309.781702)
		(end 256.024634 -309.329074)
		(width 0.1651)
		(layer "In5.Cu")
		(net "P5E_PEX2_STN7_RX_DN<114>")
	)
	(segment
		(start 258.038092 -306.588922)
		(end 258.181602 -306.588922)
		(width 0.1651)
		(layer "In5.Cu")
		(net "P5E_PEX2_STN7_RX_DN<114>")
	)
	(segment
		(start 292.2016 -393.9032)
		(end 284.985968 -390.106154)
		(width 0.1651)
		(layer "In5.Cu")
		(net "P5E_PEX2_STN7_RX_DN<114>")
	)
	(segment
		(start 293.015924 -408.529282)
		(end 293.015924 -394.716)
		(width 0.1651)
		(layer "In5.Cu")
		(net "P5E_PEX2_STN7_RX_DN<114>")
	)
	(segment
		(start 255.973072 -309.194962)
		(end 256.407158 -308.219856)
		(width 0.1651)
		(layer "In5.Cu")
		(net "P5E_PEX2_STN7_RX_DN<114>")
	)
	(segment
		(start 255.203198 -310.92394)
		(end 255.33731 -310.872378)
		(width 0.1651)
		(layer "In5.Cu")
		(net "P5E_PEX2_STN7_RX_DN<114>")
	)
	(segment
		(start 255.053338 -311.510426)
		(end 255.001776 -311.376314)
		(width 0.1651)
		(layer "In5.Cu")
		(net "P5E_PEX2_STN7_RX_DN<114>")
	)
	(segment
		(start 257.193796 -307.433218)
		(end 257.33756 -307.433218)
		(width 0.1651)
		(layer "In5.Cu")
		(net "P5E_PEX2_STN7_RX_DN<114>")
	)
	(segment
		(start 257.68808 -307.082698)
		(end 257.68808 -306.938934)
		(width 0.1651)
		(layer "In5.Cu")
		(net "P5E_PEX2_STN7_RX_DN<114>")
	)
	(segment
		(start 253.5174 -327.06564)
		(end 251.8029 -322.95719)
		(width 0.1651)
		(layer "In5.Cu")
		(net "P5E_PEX2_STN7_RX_DN<114>")
	)
	(segment
		(start 293.015924 -394.716)
		(end 292.2016 -393.9032)
		(width 0.1651)
		(layer "In5.Cu")
		(net "P5E_PEX2_STN7_RX_DN<114>")
	)
	(segment
		(start 255.33731 -310.872378)
		(end 255.538986 -310.41975)
		(width 0.1651)
		(layer "In5.Cu")
		(net "P5E_PEX2_STN7_RX_DN<114>")
	)
	(segment
		(start 258.532122 -306.094892)
		(end 259.54482 -305.082194)
		(width 0.1651)
		(layer "In5.Cu")
		(net "P5E_PEX2_STN7_RX_DN<114>")
	)
	(segment
		(start 267.866368 -303.120044)
		(end 271.215358 -303.120044)
		(width 0.1143)
		(layer "In5.Cu")
		(net "P5E_PEX2_STN7_RX_DN<114>")
	)
	(segment
		(start 281.560524 -385.417568)
		(end 281.19832 -378.90704)
		(width 0.1651)
		(layer "In5.Cu")
		(net "P5E_PEX2_STN7_RX_DN<114>")
	)
	(segment
		(start 267.7922 -303.165764)
		(end 267.820648 -303.165764)
		(width 0.1143)
		(layer "In5.Cu")
		(net "P5E_PEX2_STN7_RX_DN<114>")
	)
	(segment
		(start 255.688846 -309.833264)
		(end 255.822958 -309.781702)
		(width 0.1651)
		(layer "In5.Cu")
		(net "P5E_PEX2_STN7_RX_DN<114>")
	)
	(segment
		(start 257.33756 -307.433218)
		(end 257.68808 -307.082698)
		(width 0.1651)
		(layer "In5.Cu")
		(net "P5E_PEX2_STN7_RX_DN<114>")
	)
	(segment
		(start 271.329658 -303.234344)
		(end 271.329658 -303.385474)
		(width 0.1143)
		(layer "In5.Cu")
		(net "P5E_PEX2_STN7_RX_DN<114>")
	)
	(segment
		(start 259.54482 -305.082194)
		(end 264.170668 -303.165764)
		(width 0.1651)
		(layer "In5.Cu")
		(net "P5E_PEX2_STN7_RX_DN<114>")
	)
	(segment
		(start 255.487424 -310.285638)
		(end 255.688846 -309.833264)
		(width 0.1651)
		(layer "In5.Cu")
		(net "P5E_PEX2_STN7_RX_DN<114>")
	)
	(segment
		(start 271.329658 -303.385474)
		(end 271.215358 -303.499774)
		(width 0.1143)
		(layer "In5.Cu")
		(net "P5E_PEX2_STN7_RX_DN<114>")
	)
	(segment
		(start 284.985968 -390.106154)
		(end 282.571444 -387.866636)
		(width 0.1651)
		(layer "In5.Cu")
		(net "P5E_PEX2_STN7_RX_DN<114>")
	)
	(segment
		(start 258.532122 -306.238402)
		(end 258.532122 -306.094892)
		(width 0.1651)
		(layer "In5.Cu")
		(net "P5E_PEX2_STN7_RX_DN<114>")
	)
	(segment
		(start 291.889942 -409.490164)
		(end 291.889942 -409.108148)
		(width 0.1651)
		(layer "In5.Cu")
		(net "P5E_PEX2_STN7_RX_DN<114>")
	)
	(segment
		(start 280.612596 -372.775988)
		(end 279.92324 -371.32514)
		(width 0.1651)
		(layer "In5.Cu")
		(net "P5E_PEX2_STN7_RX_DN<114>")
	)
	(segment
		(start 255.001776 -311.376314)
		(end 255.00203 -311.376314)
		(width 0.1651)
		(layer "In5.Cu")
		(net "P5E_PEX2_STN7_RX_DN<114>")
	)
	(segment
		(start 257.68808 -306.938934)
		(end 258.038092 -306.588922)
		(width 0.1651)
		(layer "In5.Cu")
		(net "P5E_PEX2_STN7_RX_DN<114>")
	)
	(segment
		(start 254.717804 -312.014616)
		(end 254.71755 -312.014616)
		(width 0.1651)
		(layer "In5.Cu")
		(net "P5E_PEX2_STN7_RX_DN<114>")
	)
	(segment
		(start 268.6558 -359.847134)
		(end 258.99364 -335.99628)
		(width 0.1651)
		(layer "In5.Cu")
		(net "P5E_PEX2_STN7_RX_DN<114>")
	)
	(segment
		(start 256.024634 -309.329074)
		(end 255.973072 -309.194962)
		(width 0.1651)
		(layer "In5.Cu")
		(net "P5E_PEX2_STN7_RX_DN<114>")
	)
	(segment
		(start 281.19832 -378.90704)
		(end 280.612596 -372.775988)
		(width 0.1651)
		(layer "In5.Cu")
		(net "P5E_PEX2_STN7_RX_DN<114>")
	)
	(segment
		(start 267.820648 -303.165764)
		(end 267.866368 -303.120044)
		(width 0.1143)
		(layer "In5.Cu")
		(net "P5E_PEX2_STN7_RX_DN<114>")
	)
	(segment
		(start 258.99364 -335.99628)
		(end 253.5174 -327.06564)
		(width 0.1651)
		(layer "In5.Cu")
		(net "P5E_PEX2_STN7_RX_DN<114>")
	)
	(segment
		(start 258.181602 -306.588922)
		(end 258.532122 -306.238402)
		(width 0.1651)
		(layer "In5.Cu")
		(net "P5E_PEX2_STN7_RX_DN<114>")
	)
	(segment
		(start 271.215358 -303.120044)
		(end 271.329658 -303.234344)
		(width 0.1143)
		(layer "In5.Cu")
		(net "P5E_PEX2_STN7_RX_DN<114>")
	)
	(segment
		(start 254.851662 -311.963308)
		(end 255.053338 -311.510426)
		(width 0.1651)
		(layer "In5.Cu")
		(net "P5E_PEX2_STN7_RX_DN<114>")
	)
	(segment
		(start 255.538986 -310.41975)
		(end 255.487424 -310.285638)
		(width 0.1651)
		(layer "In5.Cu")
		(net "P5E_PEX2_STN7_RX_DN<114>")
	)
	(segment
		(start 279.92324 -371.32514)
		(end 268.6558 -359.847134)
		(width 0.1651)
		(layer "In5.Cu")
		(net "P5E_PEX2_STN7_RX_DN<114>")
	)
	(segment
		(start 255.203452 -310.92394)
		(end 255.203198 -310.92394)
		(width 0.1651)
		(layer "In5.Cu")
		(net "P5E_PEX2_STN7_RX_DN<114>")
	)
	(segment
		(start 401.299934 -316.534292)
		(end 401.185634 -316.419992)
		(width 0.1143)
		(layer "In5.Cu")
		(net "P5E_PEX3_STN6_RX_DN<101>")
	)
	(segment
		(start 370.18976 -342.22817)
		(end 370.04752 -342.62314)
		(width 0.1651)
		(layer "In5.Cu")
		(net "P5E_PEX3_STN6_RX_DN<101>")
	)
	(segment
		(start 381.048006 -374.687338)
		(end 380.55042 -375.184924)
		(width 0.1651)
		(layer "In5.Cu")
		(net "P5E_PEX3_STN6_RX_DN<101>")
	)
	(segment
		(start 401.185634 -316.419992)
		(end 401.034504 -316.419992)
		(width 0.1143)
		(layer "In5.Cu")
		(net "P5E_PEX3_STN6_RX_DN<101>")
	)
	(segment
		(start 370.14658 -351.90176)
		(end 372.855998 -359.82275)
		(width 0.1651)
		(layer "In5.Cu")
		(net "P5E_PEX3_STN6_RX_DN<101>")
	)
	(segment
		(start 370.957602 -341.044784)
		(end 370.332 -341.8332)
		(width 0.1651)
		(layer "In5.Cu")
		(net "P5E_PEX3_STN6_RX_DN<101>")
	)
	(segment
		(start 381.048006 -368.525044)
		(end 381.048006 -374.687338)
		(width 0.1651)
		(layer "In5.Cu")
		(net "P5E_PEX3_STN6_RX_DN<101>")
	)
	(segment
		(start 400.965924 -320.589656)
		(end 399.160746 -322.394834)
		(width 0.1651)
		(layer "In5.Cu")
		(net "P5E_PEX3_STN6_RX_DN<101>")
	)
	(segment
		(start 401.034504 -316.419992)
		(end 400.920204 -316.534292)
		(width 0.1143)
		(layer "In5.Cu")
		(net "P5E_PEX3_STN6_RX_DN<101>")
	)
	(segment
		(start 379.89002 -375.358152)
		(end 379.89002 -375.69013)
		(width 0.1651)
		(layer "In5.Cu")
		(net "P5E_PEX3_STN6_RX_DN<101>")
	)
	(segment
		(start 400.920204 -316.534292)
		(end 400.920204 -319.921128)
		(width 0.1143)
		(layer "In5.Cu")
		(net "P5E_PEX3_STN6_RX_DN<101>")
	)
	(segment
		(start 370.332 -341.8332)
		(end 370.190014 -342.227662)
		(width 0.1651)
		(layer "In5.Cu")
		(net "P5E_PEX3_STN6_RX_DN<101>")
	)
	(segment
		(start 400.965924 -319.995296)
		(end 400.965924 -320.589656)
		(width 0.1651)
		(layer "In5.Cu")
		(net "P5E_PEX3_STN6_RX_DN<101>")
	)
	(segment
		(start 370.190014 -342.227662)
		(end 370.18976 -342.22817)
		(width 0.1651)
		(layer "In5.Cu")
		(net "P5E_PEX3_STN6_RX_DN<101>")
	)
	(segment
		(start 372.855998 -359.82275)
		(end 381.048006 -368.525044)
		(width 0.1651)
		(layer "In5.Cu")
		(net "P5E_PEX3_STN6_RX_DN<101>")
	)
	(segment
		(start 399.160746 -322.394834)
		(end 370.957602 -341.044784)
		(width 0.1651)
		(layer "In5.Cu")
		(net "P5E_PEX3_STN6_RX_DN<101>")
	)
	(segment
		(start 380.063248 -375.184924)
		(end 379.89002 -375.358152)
		(width 0.1651)
		(layer "In5.Cu")
		(net "P5E_PEX3_STN6_RX_DN<101>")
	)
	(segment
		(start 380.55042 -375.184924)
		(end 380.063248 -375.184924)
		(width 0.1651)
		(layer "In5.Cu")
		(net "P5E_PEX3_STN6_RX_DN<101>")
	)
	(segment
		(start 401.299934 -316.799722)
		(end 401.299934 -316.534292)
		(width 0.1143)
		(layer "In5.Cu")
		(net "P5E_PEX3_STN6_RX_DN<101>")
	)
	(segment
		(start 370.04752 -342.62314)
		(end 370.14658 -351.90176)
		(width 0.1651)
		(layer "In5.Cu")
		(net "P5E_PEX3_STN6_RX_DN<101>")
	)
	(segment
		(start 400.920204 -319.921128)
		(end 400.965924 -319.966848)
		(width 0.1143)
		(layer "In5.Cu")
		(net "P5E_PEX3_STN6_RX_DN<101>")
	)
	(segment
		(start 400.965924 -319.966848)
		(end 400.965924 -319.995296)
		(width 0.1143)
		(layer "In5.Cu")
		(net "P5E_PEX3_STN6_RX_DN<101>")
	)
	(segment
		(start 50.64252 -154.159966)
		(end 51.689 -154.159966)
		(width 0.13208)
		(layer "F.Cu")
		(net "NCSI_NIC0_TXD1")
	)
	(via
		(at 51.689 -154.159966)
		(size 0.508)
		(drill 0.254)
		(layers "F.Cu" "B.Cu")
		(net "NCSI_NIC0_TXD1")
	)
	(segment
		(start 50.538634 -153.0096)
		(end 51.689 -154.159966)
		(width 0.13208)
		(layer "B.Cu")
		(net "NCSI_NIC0_TXD1")
	)
	(segment
		(start 49.95545 -153.0096)
		(end 50.538634 -153.0096)
		(width 0.13208)
		(layer "B.Cu")
		(net "NCSI_NIC0_TXD1")
	)
	(segment
		(start 211.625688 -28.225242)
		(end 211.29625 -28.55468)
		(width 0.13462)
		(layer "F.Cu")
		(net "P5E_PEX1_STN2_TX_C_DN<32>")
	)
	(segment
		(start 210.0326 -28.55468)
		(end 209.868008 -28.390088)
		(width 0.13462)
		(layer "F.Cu")
		(net "P5E_PEX1_STN2_TX_C_DN<32>")
	)
	(segment
		(start 211.29625 -28.55468)
		(end 210.0326 -28.55468)
		(width 0.13462)
		(layer "F.Cu")
		(net "P5E_PEX1_STN2_TX_C_DN<32>")
	)
	(segment
		(start 209.868008 -28.390088)
		(end 209.364834 -28.390088)
		(width 0.13462)
		(layer "F.Cu")
		(net "P5E_PEX1_STN2_TX_C_DN<32>")
	)
	(segment
		(start 299.257212 -150.687278)
		(end 299.55109 -150.3934)
		(width 0.13462)
		(layer "F.Cu")
		(net "P5E_PEX2_STN0_RX_DP<12>")
	)
	(segment
		(start 299.55109 -150.3934)
		(end 300.21657 -150.3934)
		(width 0.13462)
		(layer "F.Cu")
		(net "P5E_PEX2_STN0_RX_DP<12>")
	)
	(segment
		(start 300.21657 -150.3934)
		(end 300.378114 -150.554944)
		(width 0.13462)
		(layer "F.Cu")
		(net "P5E_PEX2_STN0_RX_DP<12>")
	)
	(segment
		(start 300.378114 -150.554944)
		(end 300.857412 -150.554944)
		(width 0.13462)
		(layer "F.Cu")
		(net "P5E_PEX2_STN0_RX_DP<12>")
	)
	(segment
		(start 302.212248 -153.895298)
		(end 302.328834 -153.942796)
		(width 0.1651)
		(layer "In5.Cu")
		(net "P5E_PEX2_STN0_RX_DP<12>")
	)
	(segment
		(start 309.329582 -275.355304)
		(end 309.544466 -275.570188)
		(width 0.1143)
		(layer "In5.Cu")
		(net "P5E_PEX2_STN0_RX_DP<12>")
	)
	(segment
		(start 309.785258 -275.570188)
		(end 309.899558 -275.684488)
		(width 0.1143)
		(layer "In5.Cu")
		(net "P5E_PEX2_STN0_RX_DP<12>")
	)
	(segment
		(start 309.283862 -271.570958)
		(end 309.283862 -271.599406)
		(width 0.1143)
		(layer "In5.Cu")
		(net "P5E_PEX2_STN0_RX_DP<12>")
	)
	(segment
		(start 306.222146 -161.211514)
		(end 309.750714 -260.77418)
		(width 0.1651)
		(layer "In5.Cu")
		(net "P5E_PEX2_STN0_RX_DP<12>")
	)
	(segment
		(start 301.410878 -151.760174)
		(end 301.614586 -152.244806)
		(width 0.1651)
		(layer "In5.Cu")
		(net "P5E_PEX2_STN0_RX_DP<12>")
	)
	(segment
		(start 309.899558 -275.684488)
		(end 309.899558 -275.949918)
		(width 0.1143)
		(layer "In5.Cu")
		(net "P5E_PEX2_STN0_RX_DP<12>")
	)
	(segment
		(start 305.082448 -158.4706)
		(end 306.222146 -161.211514)
		(width 0.1651)
		(layer "In5.Cu")
		(net "P5E_PEX2_STN0_RX_DP<12>")
	)
	(segment
		(start 302.818038 -155.10637)
		(end 305.082448 -158.4706)
		(width 0.1651)
		(layer "In5.Cu")
		(net "P5E_PEX2_STN0_RX_DP<12>")
	)
	(segment
		(start 301.567088 -152.361392)
		(end 301.759366 -152.818084)
		(width 0.1651)
		(layer "In5.Cu")
		(net "P5E_PEX2_STN0_RX_DP<12>")
	)
	(segment
		(start 301.875698 -152.865582)
		(end 302.067468 -153.32202)
		(width 0.1651)
		(layer "In5.Cu")
		(net "P5E_PEX2_STN0_RX_DP<12>")
	)
	(segment
		(start 309.544466 -275.570188)
		(end 309.785258 -275.570188)
		(width 0.1143)
		(layer "In5.Cu")
		(net "P5E_PEX2_STN0_RX_DP<12>")
	)
	(segment
		(start 309.329582 -271.645126)
		(end 309.329582 -275.355304)
		(width 0.1143)
		(layer "In5.Cu")
		(net "P5E_PEX2_STN0_RX_DP<12>")
	)
	(segment
		(start 302.067468 -153.32202)
		(end 302.01997 -153.438352)
		(width 0.1651)
		(layer "In5.Cu")
		(net "P5E_PEX2_STN0_RX_DP<12>")
	)
	(segment
		(start 299.548042 -150.396448)
		(end 300.022768 -150.396448)
		(width 0.1651)
		(layer "In5.Cu")
		(net "P5E_PEX2_STN0_RX_DP<12>")
	)
	(segment
		(start 309.750714 -260.77418)
		(end 309.813198 -268.035278)
		(width 0.1651)
		(layer "In5.Cu")
		(net "P5E_PEX2_STN0_RX_DP<12>")
	)
	(segment
		(start 299.257212 -150.687278)
		(end 299.548042 -150.396448)
		(width 0.1651)
		(layer "In5.Cu")
		(net "P5E_PEX2_STN0_RX_DP<12>")
	)
	(segment
		(start 309.283862 -271.599406)
		(end 309.329582 -271.645126)
		(width 0.1143)
		(layer "In5.Cu")
		(net "P5E_PEX2_STN0_RX_DP<12>")
	)
	(segment
		(start 302.01997 -153.438352)
		(end 302.212248 -153.895298)
		(width 0.1651)
		(layer "In5.Cu")
		(net "P5E_PEX2_STN0_RX_DP<12>")
	)
	(segment
		(start 309.813198 -268.035278)
		(end 309.283862 -270.75892)
		(width 0.1651)
		(layer "In5.Cu")
		(net "P5E_PEX2_STN0_RX_DP<12>")
	)
	(segment
		(start 301.759366 -152.818084)
		(end 301.875698 -152.865582)
		(width 0.1651)
		(layer "In5.Cu")
		(net "P5E_PEX2_STN0_RX_DP<12>")
	)
	(segment
		(start 302.328834 -153.942796)
		(end 302.818038 -155.10637)
		(width 0.1651)
		(layer "In5.Cu")
		(net "P5E_PEX2_STN0_RX_DP<12>")
	)
	(segment
		(start 301.614586 -152.244806)
		(end 301.567088 -152.361392)
		(width 0.1651)
		(layer "In5.Cu")
		(net "P5E_PEX2_STN0_RX_DP<12>")
	)
	(segment
		(start 309.283862 -270.75892)
		(end 309.283862 -271.570958)
		(width 0.1651)
		(layer "In5.Cu")
		(net "P5E_PEX2_STN0_RX_DP<12>")
	)
	(segment
		(start 300.022768 -150.396448)
		(end 301.410878 -151.760174)
		(width 0.1651)
		(layer "In5.Cu")
		(net "P5E_PEX2_STN0_RX_DP<12>")
	)
	(segment
		(start 380.48946 -356.511606)
		(end 380.810008 -356.832154)
		(width 0.13462)
		(layer "F.Cu")
		(net "P5E_PEX3_STN6_TX_C_DP<98>")
	)
	(segment
		(start 380.810008 -357.462582)
		(end 380.51486 -357.75773)
		(width 0.13462)
		(layer "F.Cu")
		(net "P5E_PEX3_STN6_TX_C_DP<98>")
	)
	(segment
		(start 380.810008 -356.832154)
		(end 380.810008 -357.462582)
		(width 0.13462)
		(layer "F.Cu")
		(net "P5E_PEX3_STN6_TX_C_DP<98>")
	)
	(segment
		(start 386.489956 -383.67208)
		(end 386.489956 -383.290064)
		(width 0.1651)
		(layer "In7.Cu")
		(net "P5E_PEX3_STN6_TX_C_DP<98>")
	)
	(segment
		(start 380.80569 -358.04856)
		(end 380.80569 -358.7623)
		(width 0.1651)
		(layer "In7.Cu")
		(net "P5E_PEX3_STN6_TX_C_DP<98>")
	)
	(segment
		(start 386.074158 -367.127282)
		(end 386.232146 -367.161064)
		(width 0.1651)
		(layer "In7.Cu")
		(net "P5E_PEX3_STN6_TX_C_DP<98>")
	)
	(segment
		(start 387.047232 -383.79908)
		(end 386.616956 -383.79908)
		(width 0.1651)
		(layer "In7.Cu")
		(net "P5E_PEX3_STN6_TX_C_DP<98>")
	)
	(segment
		(start 387.333998 -383.512314)
		(end 387.047232 -383.79908)
		(width 0.1651)
		(layer "In7.Cu")
		(net "P5E_PEX3_STN6_TX_C_DP<98>")
	)
	(segment
		(start 385.839208 -366.552734)
		(end 385.805172 -366.710976)
		(width 0.1651)
		(layer "In7.Cu")
		(net "P5E_PEX3_STN6_TX_C_DP<98>")
	)
	(segment
		(start 386.232146 -367.161064)
		(end 387.333998 -368.86642)
		(width 0.1651)
		(layer "In7.Cu")
		(net "P5E_PEX3_STN6_TX_C_DP<98>")
	)
	(segment
		(start 386.616956 -383.79908)
		(end 386.489956 -383.67208)
		(width 0.1651)
		(layer "In7.Cu")
		(net "P5E_PEX3_STN6_TX_C_DP<98>")
	)
	(segment
		(start 380.51486 -357.75773)
		(end 380.80569 -358.04856)
		(width 0.1651)
		(layer "In7.Cu")
		(net "P5E_PEX3_STN6_TX_C_DP<98>")
	)
	(segment
		(start 387.333998 -368.86642)
		(end 387.333998 -383.512314)
		(width 0.1651)
		(layer "In7.Cu")
		(net "P5E_PEX3_STN6_TX_C_DP<98>")
	)
	(segment
		(start 385.805172 -366.710976)
		(end 386.074158 -367.127282)
		(width 0.1651)
		(layer "In7.Cu")
		(net "P5E_PEX3_STN6_TX_C_DP<98>")
	)
	(segment
		(start 380.80569 -358.7623)
		(end 385.839208 -366.552734)
		(width 0.1651)
		(layer "In7.Cu")
		(net "P5E_PEX3_STN6_TX_C_DP<98>")
	)
	(segment
		(start 52.044092 -157.759908)
		(end 50.64252 -157.759908)
		(width 0.13208)
		(layer "F.Cu")
		(net "RST_NIC0_PERST3_R_N")
	)
	(segment
		(start 55.58155 -157.8356)
		(end 55.09895 -157.353)
		(width 0.13208)
		(layer "F.Cu")
		(net "RST_NIC0_PERST3_R_N")
	)
	(segment
		(start 55.09895 -157.353)
		(end 54.356 -157.353)
		(width 0.13208)
		(layer "F.Cu")
		(net "RST_NIC0_PERST3_R_N")
	)
	(segment
		(start 54.356 -157.353)
		(end 52.451 -157.353)
		(width 0.13208)
		(layer "F.Cu")
		(net "RST_NIC0_PERST3_R_N")
	)
	(segment
		(start 52.451 -157.353)
		(end 52.044092 -157.759908)
		(width 0.13208)
		(layer "F.Cu")
		(net "RST_NIC0_PERST3_R_N")
	)
	(via
		(at 54.356 -157.353)
		(size 0.762)
		(drill 0.381)
		(layers "F.Cu" "B.Cu")
		(net "RST_NIC0_PERST3_R_N")
	)
	(segment
		(start 185.62574 -31.825184)
		(end 185.314844 -32.13608)
		(width 0.13462)
		(layer "F.Cu")
		(net "P5E_PEX1_STN2_TX_C_DN<38>")
	)
	(segment
		(start 184.01411 -32.13608)
		(end 183.86806 -31.99003)
		(width 0.13462)
		(layer "F.Cu")
		(net "P5E_PEX1_STN2_TX_C_DN<38>")
	)
	(segment
		(start 185.314844 -32.13608)
		(end 184.01411 -32.13608)
		(width 0.13462)
		(layer "F.Cu")
		(net "P5E_PEX1_STN2_TX_C_DN<38>")
	)
	(segment
		(start 183.86806 -31.99003)
		(end 183.364886 -31.99003)
		(width 0.13462)
		(layer "F.Cu")
		(net "P5E_PEX1_STN2_TX_C_DN<38>")
	)
	(segment
		(start 305.960526 -130.044952)
		(end 305.457606 -130.044952)
		(width 0.13462)
		(layer "F.Cu")
		(net "P5E_PEX2_STN0_TX_C_DN<4>")
	)
	(segment
		(start 306.121054 -130.20548)
		(end 305.960526 -130.044952)
		(width 0.13462)
		(layer "F.Cu")
		(net "P5E_PEX2_STN0_TX_C_DN<4>")
	)
	(segment
		(start 311.95264 -129.880106)
		(end 311.627266 -130.20548)
		(width 0.13462)
		(layer "F.Cu")
		(net "P5E_PEX2_STN0_TX_C_DN<4>")
	)
	(segment
		(start 311.627266 -130.20548)
		(end 306.121054 -130.20548)
		(width 0.13462)
		(layer "F.Cu")
		(net "P5E_PEX2_STN0_TX_C_DN<4>")
	)
	(segment
		(start 283.416502 -344.219022)
		(end 283.736542 -344.539062)
		(width 0.13462)
		(layer "F.Cu")
		(net "P5E_PEX2_STN7_TX_C_DP<119>")
	)
	(segment
		(start 283.736542 -344.539062)
		(end 283.736542 -345.170506)
		(width 0.13462)
		(layer "F.Cu")
		(net "P5E_PEX2_STN7_TX_C_DP<119>")
	)
	(segment
		(start 283.736542 -345.170506)
		(end 283.441902 -345.465146)
		(width 0.13462)
		(layer "F.Cu")
		(net "P5E_PEX2_STN7_TX_C_DP<119>")
	)
	(segment
		(start 302.88992 -401.49018)
		(end 302.88992 -401.872196)
		(width 0.1651)
		(layer "In7.Cu")
		(net "P5E_PEX2_STN7_TX_C_DP<119>")
	)
	(segment
		(start 283.732732 -345.755976)
		(end 283.441902 -345.465146)
		(width 0.1651)
		(layer "In7.Cu")
		(net "P5E_PEX2_STN7_TX_C_DP<119>")
	)
	(segment
		(start 286.583628 -385.252214)
		(end 286.240474 -384.594354)
		(width 0.1651)
		(layer "In7.Cu")
		(net "P5E_PEX2_STN7_TX_C_DP<119>")
	)
	(segment
		(start 303.447196 -401.999196)
		(end 303.733962 -401.71243)
		(width 0.1651)
		(layer "In7.Cu")
		(net "P5E_PEX2_STN7_TX_C_DP<119>")
	)
	(segment
		(start 303.733962 -395.761718)
		(end 303.465484 -395.101064)
		(width 0.1651)
		(layer "In7.Cu")
		(net "P5E_PEX2_STN7_TX_C_DP<119>")
	)
	(segment
		(start 300.39691 -392.446256)
		(end 300.373034 -392.322812)
		(width 0.1651)
		(layer "In7.Cu")
		(net "P5E_PEX2_STN7_TX_C_DP<119>")
	)
	(segment
		(start 302.330612 -393.966192)
		(end 301.341282 -392.976862)
		(width 0.1651)
		(layer "In7.Cu")
		(net "P5E_PEX2_STN7_TX_C_DP<119>")
	)
	(segment
		(start 298.871132 -391.415524)
		(end 298.460414 -391.138156)
		(width 0.1651)
		(layer "In7.Cu")
		(net "P5E_PEX2_STN7_TX_C_DP<119>")
	)
	(segment
		(start 299.404786 -391.668762)
		(end 298.994576 -391.391648)
		(width 0.1651)
		(layer "In7.Cu")
		(net "P5E_PEX2_STN7_TX_C_DP<119>")
	)
	(segment
		(start 299.428662 -391.792206)
		(end 299.404786 -391.668762)
		(width 0.1651)
		(layer "In7.Cu")
		(net "P5E_PEX2_STN7_TX_C_DP<119>")
	)
	(segment
		(start 283.732732 -346.209874)
		(end 283.732732 -345.755976)
		(width 0.1651)
		(layer "In7.Cu")
		(net "P5E_PEX2_STN7_TX_C_DP<119>")
	)
	(segment
		(start 302.806608 -394.442188)
		(end 302.680878 -394.442188)
		(width 0.1651)
		(layer "In7.Cu")
		(net "P5E_PEX2_STN7_TX_C_DP<119>")
	)
	(segment
		(start 301.341282 -392.976862)
		(end 300.931072 -392.699748)
		(width 0.1651)
		(layer "In7.Cu")
		(net "P5E_PEX2_STN7_TX_C_DP<119>")
	)
	(segment
		(start 300.373034 -392.322812)
		(end 299.962824 -392.045698)
		(width 0.1651)
		(layer "In7.Cu")
		(net "P5E_PEX2_STN7_TX_C_DP<119>")
	)
	(segment
		(start 297.627548 -390.468358)
		(end 287.156652 -385.882388)
		(width 0.1651)
		(layer "In7.Cu")
		(net "P5E_PEX2_STN7_TX_C_DP<119>")
	)
	(segment
		(start 300.807628 -392.723624)
		(end 300.39691 -392.446256)
		(width 0.1651)
		(layer "In7.Cu")
		(net "P5E_PEX2_STN7_TX_C_DP<119>")
	)
	(segment
		(start 302.680878 -394.442188)
		(end 302.330612 -394.091922)
		(width 0.1651)
		(layer "In7.Cu")
		(net "P5E_PEX2_STN7_TX_C_DP<119>")
	)
	(segment
		(start 303.465484 -395.101064)
		(end 302.806608 -394.442188)
		(width 0.1651)
		(layer "In7.Cu")
		(net "P5E_PEX2_STN7_TX_C_DP<119>")
	)
	(segment
		(start 282.178252 -347.764354)
		(end 283.732732 -346.209874)
		(width 0.1651)
		(layer "In7.Cu")
		(net "P5E_PEX2_STN7_TX_C_DP<119>")
	)
	(segment
		(start 303.01692 -401.999196)
		(end 303.447196 -401.999196)
		(width 0.1651)
		(layer "In7.Cu")
		(net "P5E_PEX2_STN7_TX_C_DP<119>")
	)
	(segment
		(start 302.88992 -401.872196)
		(end 303.01692 -401.999196)
		(width 0.1651)
		(layer "In7.Cu")
		(net "P5E_PEX2_STN7_TX_C_DP<119>")
	)
	(segment
		(start 300.931072 -392.699748)
		(end 300.807628 -392.723624)
		(width 0.1651)
		(layer "In7.Cu")
		(net "P5E_PEX2_STN7_TX_C_DP<119>")
	)
	(segment
		(start 286.240474 -384.594354)
		(end 282.178252 -358.288844)
		(width 0.1651)
		(layer "In7.Cu")
		(net "P5E_PEX2_STN7_TX_C_DP<119>")
	)
	(segment
		(start 298.460414 -391.138156)
		(end 298.436538 -391.014712)
		(width 0.1651)
		(layer "In7.Cu")
		(net "P5E_PEX2_STN7_TX_C_DP<119>")
	)
	(segment
		(start 287.156652 -385.882388)
		(end 286.583628 -385.252214)
		(width 0.1651)
		(layer "In7.Cu")
		(net "P5E_PEX2_STN7_TX_C_DP<119>")
	)
	(segment
		(start 282.178252 -358.288844)
		(end 282.178252 -347.764354)
		(width 0.1651)
		(layer "In7.Cu")
		(net "P5E_PEX2_STN7_TX_C_DP<119>")
	)
	(segment
		(start 302.330612 -394.091922)
		(end 302.330612 -393.966192)
		(width 0.1651)
		(layer "In7.Cu")
		(net "P5E_PEX2_STN7_TX_C_DP<119>")
	)
	(segment
		(start 303.733962 -401.71243)
		(end 303.733962 -395.761718)
		(width 0.1651)
		(layer "In7.Cu")
		(net "P5E_PEX2_STN7_TX_C_DP<119>")
	)
	(segment
		(start 299.83938 -392.069574)
		(end 299.428662 -391.792206)
		(width 0.1651)
		(layer "In7.Cu")
		(net "P5E_PEX2_STN7_TX_C_DP<119>")
	)
	(segment
		(start 298.436538 -391.014712)
		(end 297.627548 -390.468358)
		(width 0.1651)
		(layer "In7.Cu")
		(net "P5E_PEX2_STN7_TX_C_DP<119>")
	)
	(segment
		(start 298.994576 -391.391648)
		(end 298.871132 -391.415524)
		(width 0.1651)
		(layer "In7.Cu")
		(net "P5E_PEX2_STN7_TX_C_DP<119>")
	)
	(segment
		(start 299.962824 -392.045698)
		(end 299.83938 -392.069574)
		(width 0.1651)
		(layer "In7.Cu")
		(net "P5E_PEX2_STN7_TX_C_DP<119>")
	)
	(segment
		(start 383.59842 -344.219022)
		(end 383.918968 -344.53957)
		(width 0.13462)
		(layer "F.Cu")
		(net "P5E_PEX3_STN6_TX_C_DP<106>")
	)
	(segment
		(start 383.918968 -344.53957)
		(end 383.918968 -345.169998)
		(width 0.13462)
		(layer "F.Cu")
		(net "P5E_PEX3_STN6_TX_C_DP<106>")
	)
	(segment
		(start 383.918968 -345.169998)
		(end 383.62382 -345.465146)
		(width 0.13462)
		(layer "F.Cu")
		(net "P5E_PEX3_STN6_TX_C_DP<106>")
	)
	(segment
		(start 382.36017 -347.764354)
		(end 383.91465 -346.209874)
		(width 0.1651)
		(layer "In13.Cu")
		(net "P5E_PEX3_STN6_TX_C_DP<106>")
	)
	(segment
		(start 381.721614 -359.281222)
		(end 382.36017 -357.886254)
		(width 0.1651)
		(layer "In13.Cu")
		(net "P5E_PEX3_STN6_TX_C_DP<106>")
	)
	(segment
		(start 387.047232 -409.799028)
		(end 387.333998 -409.512262)
		(width 0.1651)
		(layer "In13.Cu")
		(net "P5E_PEX3_STN6_TX_C_DP<106>")
	)
	(segment
		(start 372.916958 -386.865876)
		(end 372.202202 -385.083812)
		(width 0.1651)
		(layer "In13.Cu")
		(net "P5E_PEX3_STN6_TX_C_DP<106>")
	)
	(segment
		(start 387.333998 -396.190724)
		(end 386.69214 -394.521436)
		(width 0.1651)
		(layer "In13.Cu")
		(net "P5E_PEX3_STN6_TX_C_DP<106>")
	)
	(segment
		(start 386.489956 -409.290012)
		(end 386.489956 -409.672028)
		(width 0.1651)
		(layer "In13.Cu")
		(net "P5E_PEX3_STN6_TX_C_DP<106>")
	)
	(segment
		(start 386.69214 -394.521436)
		(end 385.822952 -393.699238)
		(width 0.1651)
		(layer "In13.Cu")
		(net "P5E_PEX3_STN6_TX_C_DP<106>")
	)
	(segment
		(start 383.91465 -345.755976)
		(end 383.62382 -345.465146)
		(width 0.1651)
		(layer "In13.Cu")
		(net "P5E_PEX3_STN6_TX_C_DP<106>")
	)
	(segment
		(start 386.616956 -409.799028)
		(end 387.047232 -409.799028)
		(width 0.1651)
		(layer "In13.Cu")
		(net "P5E_PEX3_STN6_TX_C_DP<106>")
	)
	(segment
		(start 383.91465 -346.209874)
		(end 383.91465 -345.755976)
		(width 0.1651)
		(layer "In13.Cu")
		(net "P5E_PEX3_STN6_TX_C_DP<106>")
	)
	(segment
		(start 387.333998 -409.512262)
		(end 387.333998 -396.190724)
		(width 0.1651)
		(layer "In13.Cu")
		(net "P5E_PEX3_STN6_TX_C_DP<106>")
	)
	(segment
		(start 371.749066 -373.370602)
		(end 372.166388 -368.453162)
		(width 0.1651)
		(layer "In13.Cu")
		(net "P5E_PEX3_STN6_TX_C_DP<106>")
	)
	(segment
		(start 375.32945 -388.52983)
		(end 372.916958 -386.865876)
		(width 0.1651)
		(layer "In13.Cu")
		(net "P5E_PEX3_STN6_TX_C_DP<106>")
	)
	(segment
		(start 385.822952 -393.699238)
		(end 381.294386 -391.08253)
		(width 0.1651)
		(layer "In13.Cu")
		(net "P5E_PEX3_STN6_TX_C_DP<106>")
	)
	(segment
		(start 372.202202 -385.083812)
		(end 371.749066 -373.370602)
		(width 0.1651)
		(layer "In13.Cu")
		(net "P5E_PEX3_STN6_TX_C_DP<106>")
	)
	(segment
		(start 374.140476 -365.829088)
		(end 381.721614 -359.281222)
		(width 0.1651)
		(layer "In13.Cu")
		(net "P5E_PEX3_STN6_TX_C_DP<106>")
	)
	(segment
		(start 382.36017 -357.886254)
		(end 382.36017 -347.764354)
		(width 0.1651)
		(layer "In13.Cu")
		(net "P5E_PEX3_STN6_TX_C_DP<106>")
	)
	(segment
		(start 381.294386 -391.08253)
		(end 375.32945 -388.52983)
		(width 0.1651)
		(layer "In13.Cu")
		(net "P5E_PEX3_STN6_TX_C_DP<106>")
	)
	(segment
		(start 386.489956 -409.672028)
		(end 386.616956 -409.799028)
		(width 0.1651)
		(layer "In13.Cu")
		(net "P5E_PEX3_STN6_TX_C_DP<106>")
	)
	(segment
		(start 372.166388 -368.453162)
		(end 374.140476 -365.829088)
		(width 0.1651)
		(layer "In13.Cu")
		(net "P5E_PEX3_STN6_TX_C_DP<106>")
	)
	(segment
		(start 42.373042 -155.360116)
		(end 46.042326 -155.360116)
		(width 0.13208)
		(layer "F.Cu")
		(net "NIC0_CLK")
	)
	(segment
		(start 42.23893 -155.226004)
		(end 42.373042 -155.360116)
		(width 0.13208)
		(layer "F.Cu")
		(net "NIC0_CLK")
	)
	(segment
		(start 39.00805 -155.3464)
		(end 39.462202 -155.3464)
		(width 0.13208)
		(layer "F.Cu")
		(net "NIC0_CLK")
	)
	(segment
		(start 39.582598 -155.226004)
		(end 40.398446 -155.226004)
		(width 0.13208)
		(layer "F.Cu")
		(net "NIC0_CLK")
	)
	(segment
		(start 39.462202 -155.3464)
		(end 39.582598 -155.226004)
		(width 0.13208)
		(layer "F.Cu")
		(net "NIC0_CLK")
	)
	(segment
		(start 40.398446 -155.226004)
		(end 42.23893 -155.226004)
		(width 0.13208)
		(layer "F.Cu")
		(net "NIC0_CLK")
	)
	(via
		(at 40.398446 -155.226004)
		(size 0.762)
		(drill 0.381)
		(layers "F.Cu" "B.Cu")
		(net "NIC0_CLK")
	)
	(segment
		(start 188.267848 -30.94609)
		(end 187.954158 -30.6324)
		(width 0.13462)
		(layer "F.Cu")
		(net "P5E_PEX1_STN2_TX_C_DP<37>")
	)
	(segment
		(start 183.86552 -30.790134)
		(end 183.364886 -30.790134)
		(width 0.13462)
		(layer "F.Cu")
		(net "P5E_PEX1_STN2_TX_C_DP<37>")
	)
	(segment
		(start 184.023254 -30.6324)
		(end 183.86552 -30.790134)
		(width 0.13462)
		(layer "F.Cu")
		(net "P5E_PEX1_STN2_TX_C_DP<37>")
	)
	(segment
		(start 187.954158 -30.6324)
		(end 184.023254 -30.6324)
		(width 0.13462)
		(layer "F.Cu")
		(net "P5E_PEX1_STN2_TX_C_DP<37>")
	)
	(segment
		(start 300.378368 -154.15514)
		(end 300.857412 -154.15514)
		(width 0.13462)
		(layer "F.Cu")
		(net "P5E_PEX2_STN0_RX_DP<14>")
	)
	(segment
		(start 299.544232 -154.0002)
		(end 300.223428 -154.0002)
		(width 0.13462)
		(layer "F.Cu")
		(net "P5E_PEX2_STN0_RX_DP<14>")
	)
	(segment
		(start 300.223428 -154.0002)
		(end 300.378368 -154.15514)
		(width 0.13462)
		(layer "F.Cu")
		(net "P5E_PEX2_STN0_RX_DP<14>")
	)
	(segment
		(start 299.257212 -154.28722)
		(end 299.544232 -154.0002)
		(width 0.13462)
		(layer "F.Cu")
		(net "P5E_PEX2_STN0_RX_DP<14>")
	)
	(segment
		(start 300.554644 -156.514038)
		(end 300.448472 -156.635958)
		(width 0.1651)
		(layer "In5.Cu")
		(net "P5E_PEX2_STN0_RX_DP<14>")
	)
	(segment
		(start 300.398942 -155.913836)
		(end 300.520862 -156.020008)
		(width 0.1651)
		(layer "In5.Cu")
		(net "P5E_PEX2_STN0_RX_DP<14>")
	)
	(segment
		(start 299.721016 -153.99512)
		(end 299.862748 -153.99512)
		(width 0.1651)
		(layer "In5.Cu")
		(net "P5E_PEX2_STN0_RX_DP<14>")
	)
	(segment
		(start 300.43755 -154.803856)
		(end 300.471332 -155.297632)
		(width 0.1651)
		(layer "In5.Cu")
		(net "P5E_PEX2_STN0_RX_DP<14>")
	)
	(segment
		(start 307.663596 -258.33578)
		(end 307.878226 -267.788136)
		(width 0.1651)
		(layer "In5.Cu")
		(net "P5E_PEX2_STN0_RX_DP<14>")
	)
	(segment
		(start 301.234094 -164.703506)
		(end 307.663596 -258.33578)
		(width 0.1651)
		(layer "In5.Cu")
		(net "P5E_PEX2_STN0_RX_DP<14>")
	)
	(segment
		(start 307.885338 -275.569934)
		(end 307.999638 -275.684234)
		(width 0.1143)
		(layer "In5.Cu")
		(net "P5E_PEX2_STN0_RX_DP<14>")
	)
	(segment
		(start 299.862748 -153.99512)
		(end 300.242478 -154.37485)
		(width 0.1651)
		(layer "In5.Cu")
		(net "P5E_PEX2_STN0_RX_DP<14>")
	)
	(segment
		(start 300.701202 -158.642304)
		(end 300.701202 -160.396682)
		(width 0.1651)
		(layer "In5.Cu")
		(net "P5E_PEX2_STN0_RX_DP<14>")
	)
	(segment
		(start 307.383942 -270.431006)
		(end 307.383942 -271.570704)
		(width 0.1651)
		(layer "In5.Cu")
		(net "P5E_PEX2_STN0_RX_DP<14>")
	)
	(segment
		(start 300.520862 -156.020008)
		(end 300.554644 -156.514038)
		(width 0.1651)
		(layer "In5.Cu")
		(net "P5E_PEX2_STN0_RX_DP<14>")
	)
	(segment
		(start 307.383942 -271.570704)
		(end 307.383942 -271.599152)
		(width 0.1143)
		(layer "In5.Cu")
		(net "P5E_PEX2_STN0_RX_DP<14>")
	)
	(segment
		(start 300.36516 -155.419552)
		(end 300.398942 -155.913836)
		(width 0.1651)
		(layer "In5.Cu")
		(net "P5E_PEX2_STN0_RX_DP<14>")
	)
	(segment
		(start 307.644546 -275.569934)
		(end 307.885338 -275.569934)
		(width 0.1143)
		(layer "In5.Cu")
		(net "P5E_PEX2_STN0_RX_DP<14>")
	)
	(segment
		(start 307.429662 -271.644872)
		(end 307.429662 -275.35505)
		(width 0.1143)
		(layer "In5.Cu")
		(net "P5E_PEX2_STN0_RX_DP<14>")
	)
	(segment
		(start 300.701202 -160.396682)
		(end 300.818042 -162.09645)
		(width 0.1651)
		(layer "In5.Cu")
		(net "P5E_PEX2_STN0_RX_DP<14>")
	)
	(segment
		(start 307.999638 -275.684234)
		(end 307.999638 -275.949664)
		(width 0.1143)
		(layer "In5.Cu")
		(net "P5E_PEX2_STN0_RX_DP<14>")
	)
	(segment
		(start 300.242478 -154.37485)
		(end 300.43755 -154.803856)
		(width 0.1651)
		(layer "In5.Cu")
		(net "P5E_PEX2_STN0_RX_DP<14>")
	)
	(segment
		(start 300.448472 -156.635958)
		(end 300.482254 -157.130242)
		(width 0.1651)
		(layer "In5.Cu")
		(net "P5E_PEX2_STN0_RX_DP<14>")
	)
	(segment
		(start 307.429662 -275.35505)
		(end 307.644546 -275.569934)
		(width 0.1143)
		(layer "In5.Cu")
		(net "P5E_PEX2_STN0_RX_DP<14>")
	)
	(segment
		(start 300.482254 -157.130242)
		(end 300.604428 -157.236414)
		(width 0.1651)
		(layer "In5.Cu")
		(net "P5E_PEX2_STN0_RX_DP<14>")
	)
	(segment
		(start 300.471332 -155.297632)
		(end 300.36516 -155.419552)
		(width 0.1651)
		(layer "In5.Cu")
		(net "P5E_PEX2_STN0_RX_DP<14>")
	)
	(segment
		(start 299.257212 -154.28722)
		(end 299.4279 -154.116532)
		(width 0.1651)
		(layer "In5.Cu")
		(net "P5E_PEX2_STN0_RX_DP<14>")
	)
	(segment
		(start 300.818042 -162.09645)
		(end 301.234094 -164.703506)
		(width 0.1651)
		(layer "In5.Cu")
		(net "P5E_PEX2_STN0_RX_DP<14>")
	)
	(segment
		(start 307.383942 -271.599152)
		(end 307.429662 -271.644872)
		(width 0.1143)
		(layer "In5.Cu")
		(net "P5E_PEX2_STN0_RX_DP<14>")
	)
	(segment
		(start 299.4279 -154.116532)
		(end 299.721016 -153.99512)
		(width 0.1651)
		(layer "In5.Cu")
		(net "P5E_PEX2_STN0_RX_DP<14>")
	)
	(segment
		(start 307.878226 -267.788136)
		(end 307.383942 -270.431006)
		(width 0.1651)
		(layer "In5.Cu")
		(net "P5E_PEX2_STN0_RX_DP<14>")
	)
	(segment
		(start 300.604428 -157.236414)
		(end 300.70044 -158.641796)
		(width 0.1651)
		(layer "In5.Cu")
		(net "P5E_PEX2_STN0_RX_DP<14>")
	)
	(segment
		(start 300.70044 -158.641796)
		(end 300.701202 -158.642304)
		(width 0.1651)
		(layer "In5.Cu")
		(net "P5E_PEX2_STN0_RX_DP<14>")
	)
	(segment
		(start 402.249894 -318.434466)
		(end 402.135594 -318.320166)
		(width 0.1143)
		(layer "In5.Cu")
		(net "P5E_PEX3_STN6_RX_DN<100>")
	)
	(segment
		(start 382.263142 -376.284998)
		(end 382.089914 -376.458226)
		(width 0.1651)
		(layer "In5.Cu")
		(net "P5E_PEX3_STN6_RX_DN<100>")
	)
	(segment
		(start 402.135594 -318.320166)
		(end 401.984464 -318.320166)
		(width 0.1143)
		(layer "In5.Cu")
		(net "P5E_PEX3_STN6_RX_DN<100>")
	)
	(segment
		(start 402.249894 -318.699896)
		(end 402.249894 -318.434466)
		(width 0.1143)
		(layer "In5.Cu")
		(net "P5E_PEX3_STN6_RX_DN<100>")
	)
	(segment
		(start 400.07286 -322.990972)
		(end 373.813324 -341.3252)
		(width 0.1651)
		(layer "In5.Cu")
		(net "P5E_PEX3_STN6_RX_DN<100>")
	)
	(segment
		(start 373.813324 -341.3252)
		(end 373.31523 -341.935308)
		(width 0.1651)
		(layer "In5.Cu")
		(net "P5E_PEX3_STN6_RX_DN<100>")
	)
	(segment
		(start 401.870164 -319.888362)
		(end 401.915884 -319.934082)
		(width 0.1143)
		(layer "In5.Cu")
		(net "P5E_PEX3_STN6_RX_DN<100>")
	)
	(segment
		(start 401.870164 -318.434466)
		(end 401.870164 -319.888362)
		(width 0.1143)
		(layer "In5.Cu")
		(net "P5E_PEX3_STN6_RX_DN<100>")
	)
	(segment
		(start 373.31523 -358.087676)
		(end 373.76354 -359.1687)
		(width 0.1651)
		(layer "In5.Cu")
		(net "P5E_PEX3_STN6_RX_DN<100>")
	)
	(segment
		(start 401.915884 -319.934082)
		(end 401.915884 -319.96253)
		(width 0.1143)
		(layer "In5.Cu")
		(net "P5E_PEX3_STN6_RX_DN<100>")
	)
	(segment
		(start 382.089914 -376.458226)
		(end 382.089914 -376.790204)
		(width 0.1651)
		(layer "In5.Cu")
		(net "P5E_PEX3_STN6_RX_DN<100>")
	)
	(segment
		(start 382.750314 -376.284998)
		(end 382.263142 -376.284998)
		(width 0.1651)
		(layer "In5.Cu")
		(net "P5E_PEX3_STN6_RX_DN<100>")
	)
	(segment
		(start 401.984464 -318.320166)
		(end 401.870164 -318.434466)
		(width 0.1143)
		(layer "In5.Cu")
		(net "P5E_PEX3_STN6_RX_DN<100>")
	)
	(segment
		(start 383.2479 -375.787412)
		(end 382.750314 -376.284998)
		(width 0.1651)
		(layer "In5.Cu")
		(net "P5E_PEX3_STN6_RX_DN<100>")
	)
	(segment
		(start 373.31523 -341.935308)
		(end 373.31523 -358.087676)
		(width 0.1651)
		(layer "In5.Cu")
		(net "P5E_PEX3_STN6_RX_DN<100>")
	)
	(segment
		(start 373.76354 -359.1687)
		(end 383.2479 -368.63909)
		(width 0.1651)
		(layer "In5.Cu")
		(net "P5E_PEX3_STN6_RX_DN<100>")
	)
	(segment
		(start 401.915884 -319.96253)
		(end 401.915884 -320.698622)
		(width 0.1651)
		(layer "In5.Cu")
		(net "P5E_PEX3_STN6_RX_DN<100>")
	)
	(segment
		(start 383.2479 -368.63909)
		(end 383.2479 -375.787412)
		(width 0.1651)
		(layer "In5.Cu")
		(net "P5E_PEX3_STN6_RX_DN<100>")
	)
	(segment
		(start 401.915884 -320.698622)
		(end 400.07286 -322.990972)
		(width 0.1651)
		(layer "In5.Cu")
		(net "P5E_PEX3_STN6_RX_DN<100>")
	)
	(segment
		(start 52.262024 -150.560024)
		(end 52.959 -151.257)
		(width 0.13208)
		(layer "F.Cu")
		(net "CLK_50M_NIC0_RBT_REF")
	)
	(segment
		(start 50.64252 -150.560024)
		(end 52.262024 -150.560024)
		(width 0.13208)
		(layer "F.Cu")
		(net "CLK_50M_NIC0_RBT_REF")
	)
	(via
		(at 52.959 -151.257)
		(size 0.508)
		(drill 0.254)
		(layers "F.Cu" "B.Cu")
		(net "CLK_50M_NIC0_RBT_REF")
	)
	(segment
		(start 49.95545 -150.9776)
		(end 50.4444 -150.9776)
		(width 0.13208)
		(layer "B.Cu")
		(net "CLK_50M_NIC0_RBT_REF")
	)
	(segment
		(start 50.861976 -150.560024)
		(end 52.262024 -150.560024)
		(width 0.13208)
		(layer "B.Cu")
		(net "CLK_50M_NIC0_RBT_REF")
	)
	(segment
		(start 52.262024 -150.560024)
		(end 52.959 -151.257)
		(width 0.13208)
		(layer "B.Cu")
		(net "CLK_50M_NIC0_RBT_REF")
	)
	(segment
		(start 50.4444 -150.9776)
		(end 50.861976 -150.560024)
		(width 0.13208)
		(layer "B.Cu")
		(net "CLK_50M_NIC0_RBT_REF")
	)
	(segment
		(start 158.023306 -30.6324)
		(end 157.865572 -30.790134)
		(width 0.13462)
		(layer "F.Cu")
		(net "P5E_PEX1_STN2_TX_C_DP<41>")
	)
	(segment
		(start 161.95421 -30.6324)
		(end 158.023306 -30.6324)
		(width 0.13462)
		(layer "F.Cu")
		(net "P5E_PEX1_STN2_TX_C_DP<41>")
	)
	(segment
		(start 157.865572 -30.790134)
		(end 157.364938 -30.790134)
		(width 0.13462)
		(layer "F.Cu")
		(net "P5E_PEX1_STN2_TX_C_DP<41>")
	)
	(segment
		(start 162.2679 -30.94609)
		(end 161.95421 -30.6324)
		(width 0.13462)
		(layer "F.Cu")
		(net "P5E_PEX1_STN2_TX_C_DP<41>")
	)
	(segment
		(start 300.379892 -135.444992)
		(end 300.221904 -135.60298)
		(width 0.13462)
		(layer "F.Cu")
		(net "P5E_PEX2_STN0_RX_DN<7>")
	)
	(segment
		(start 300.857412 -135.444992)
		(end 300.379892 -135.444992)
		(width 0.13462)
		(layer "F.Cu")
		(net "P5E_PEX2_STN0_RX_DN<7>")
	)
	(segment
		(start 300.221904 -135.60298)
		(end 297.692318 -135.60298)
		(width 0.13462)
		(layer "F.Cu")
		(net "P5E_PEX2_STN0_RX_DN<7>")
	)
	(segment
		(start 297.692318 -135.60298)
		(end 297.403012 -135.313674)
		(width 0.13462)
		(layer "F.Cu")
		(net "P5E_PEX2_STN0_RX_DN<7>")
	)
	(segment
		(start 305.887374 -139.464288)
		(end 305.469544 -138.752834)
		(width 0.1651)
		(layer "In5.Cu")
		(net "P5E_PEX2_STN0_RX_DN<7>")
	)
	(segment
		(start 316.960504 -276.308312)
		(end 315.684662 -269.423388)
		(width 0.1651)
		(layer "In5.Cu")
		(net "P5E_PEX2_STN0_RX_DN<7>")
	)
	(segment
		(start 314.384436 -281.649932)
		(end 314.270136 -281.535632)
		(width 0.1143)
		(layer "In5.Cu")
		(net "P5E_PEX2_STN0_RX_DN<7>")
	)
	(segment
		(start 307.20538 -141.708632)
		(end 307.020976 -141.394688)
		(width 0.1651)
		(layer "In5.Cu")
		(net "P5E_PEX2_STN0_RX_DN<7>")
	)
	(segment
		(start 311.479692 -160.476184)
		(end 311.479692 -160.455102)
		(width 0.1651)
		(layer "In5.Cu")
		(net "P5E_PEX2_STN0_RX_DN<7>")
	)
	(segment
		(start 315.684662 -269.423388)
		(end 315.034168 -264.832846)
		(width 0.1651)
		(layer "In5.Cu")
		(net "P5E_PEX2_STN0_RX_DN<7>")
	)
	(segment
		(start 297.693842 -135.604504)
		(end 297.403012 -135.313674)
		(width 0.1651)
		(layer "In5.Cu")
		(net "P5E_PEX2_STN0_RX_DN<7>")
	)
	(segment
		(start 305.887374 -139.870434)
		(end 305.887374 -139.464288)
		(width 0.1651)
		(layer "In5.Cu")
		(net "P5E_PEX2_STN0_RX_DN<7>")
	)
	(segment
		(start 316.5983 -281.107134)
		(end 316.872112 -280.46807)
		(width 0.1651)
		(layer "In5.Cu")
		(net "P5E_PEX2_STN0_RX_DN<7>")
	)
	(segment
		(start 316.872112 -280.46807)
		(end 316.960504 -276.308312)
		(width 0.1651)
		(layer "In5.Cu")
		(net "P5E_PEX2_STN0_RX_DN<7>")
	)
	(segment
		(start 307.20538 -141.708378)
		(end 307.20538 -141.708632)
		(width 0.1651)
		(layer "In5.Cu")
		(net "P5E_PEX2_STN0_RX_DN<7>")
	)
	(segment
		(start 314.270136 -281.535632)
		(end 314.270136 -281.373834)
		(width 0.1143)
		(layer "In5.Cu")
		(net "P5E_PEX2_STN0_RX_DN<7>")
	)
	(segment
		(start 314.373768 -281.270202)
		(end 316.075822 -281.270202)
		(width 0.1143)
		(layer "In5.Cu")
		(net "P5E_PEX2_STN0_RX_DN<7>")
	)
	(segment
		(start 307.020976 -141.394688)
		(end 306.163726 -140.537438)
		(width 0.1651)
		(layer "In5.Cu")
		(net "P5E_PEX2_STN0_RX_DN<7>")
	)
	(segment
		(start 311.473596 -160.449006)
		(end 307.205634 -141.708886)
		(width 0.1651)
		(layer "In5.Cu")
		(net "P5E_PEX2_STN0_RX_DN<7>")
	)
	(segment
		(start 314.649866 -281.649932)
		(end 314.384436 -281.649932)
		(width 0.1143)
		(layer "In5.Cu")
		(net "P5E_PEX2_STN0_RX_DN<7>")
	)
	(segment
		(start 314.270136 -281.373834)
		(end 314.373768 -281.270202)
		(width 0.1143)
		(layer "In5.Cu")
		(net "P5E_PEX2_STN0_RX_DN<7>")
	)
	(segment
		(start 311.479692 -160.455102)
		(end 311.473596 -160.449006)
		(width 0.1651)
		(layer "In5.Cu")
		(net "P5E_PEX2_STN0_RX_DN<7>")
	)
	(segment
		(start 299.673518 -135.604504)
		(end 297.693842 -135.604504)
		(width 0.1651)
		(layer "In5.Cu")
		(net "P5E_PEX2_STN0_RX_DN<7>")
	)
	(segment
		(start 316.075822 -281.270202)
		(end 316.121542 -281.315922)
		(width 0.1143)
		(layer "In5.Cu")
		(net "P5E_PEX2_STN0_RX_DN<7>")
	)
	(segment
		(start 316.388242 -281.315922)
		(end 316.5983 -281.107134)
		(width 0.1651)
		(layer "In5.Cu")
		(net "P5E_PEX2_STN0_RX_DN<7>")
	)
	(segment
		(start 306.163726 -140.537438)
		(end 305.887374 -139.870434)
		(width 0.1651)
		(layer "In5.Cu")
		(net "P5E_PEX2_STN0_RX_DN<7>")
	)
	(segment
		(start 316.121542 -281.315922)
		(end 316.14999 -281.315922)
		(width 0.1143)
		(layer "In5.Cu")
		(net "P5E_PEX2_STN0_RX_DN<7>")
	)
	(segment
		(start 305.469544 -138.752834)
		(end 304.166524 -137.43178)
		(width 0.1651)
		(layer "In5.Cu")
		(net "P5E_PEX2_STN0_RX_DN<7>")
	)
	(segment
		(start 315.034168 -264.832846)
		(end 311.479692 -160.476184)
		(width 0.1651)
		(layer "In5.Cu")
		(net "P5E_PEX2_STN0_RX_DN<7>")
	)
	(segment
		(start 307.205634 -141.708886)
		(end 307.20538 -141.708378)
		(width 0.1651)
		(layer "In5.Cu")
		(net "P5E_PEX2_STN0_RX_DN<7>")
	)
	(segment
		(start 304.166524 -137.43178)
		(end 299.673518 -135.604504)
		(width 0.1651)
		(layer "In5.Cu")
		(net "P5E_PEX2_STN0_RX_DN<7>")
	)
	(segment
		(start 316.14999 -281.315922)
		(end 316.388242 -281.315922)
		(width 0.1651)
		(layer "In5.Cu")
		(net "P5E_PEX2_STN0_RX_DN<7>")
	)
	(segment
		(start 267.820648 -304.115724)
		(end 267.7922 -304.115724)
		(width 0.1143)
		(layer "In5.Cu")
		(net "P5E_PEX2_STN7_RX_DN<115>")
	)
	(segment
		(start 259.26288 -307.351938)
		(end 259.119116 -307.351938)
		(width 0.1651)
		(layer "In5.Cu")
		(net "P5E_PEX2_STN7_RX_DN<115>")
	)
	(segment
		(start 260.859778 -305.611276)
		(end 260.457442 -306.013612)
		(width 0.1651)
		(layer "In5.Cu")
		(net "P5E_PEX2_STN7_RX_DN<115>")
	)
	(segment
		(start 255.222756 -314.029852)
		(end 254.530606 -315.33719)
		(width 0.1651)
		(layer "In5.Cu")
		(net "P5E_PEX2_STN7_RX_DN<115>")
	)
	(segment
		(start 269.315184 -304.070004)
		(end 267.866368 -304.070004)
		(width 0.1143)
		(layer "In5.Cu")
		(net "P5E_PEX2_STN7_RX_DN<115>")
	)
	(segment
		(start 260.457442 -306.157122)
		(end 260.106922 -306.507642)
		(width 0.1651)
		(layer "In5.Cu")
		(net "P5E_PEX2_STN7_RX_DN<115>")
	)
	(segment
		(start 269.315184 -304.449734)
		(end 269.429484 -304.335434)
		(width 0.1143)
		(layer "In5.Cu")
		(net "P5E_PEX2_STN7_RX_DN<115>")
	)
	(segment
		(start 282.2194 -378.8537)
		(end 282.601924 -385.262628)
		(width 0.1651)
		(layer "In5.Cu")
		(net "P5E_PEX2_STN7_RX_DN<115>")
	)
	(segment
		(start 280.851356 -370.851176)
		(end 281.644598 -372.458488)
		(width 0.1651)
		(layer "In5.Cu")
		(net "P5E_PEX2_STN7_RX_DN<115>")
	)
	(segment
		(start 258.769104 -307.845714)
		(end 258.418584 -308.196234)
		(width 0.1651)
		(layer "In5.Cu")
		(net "P5E_PEX2_STN7_RX_DN<115>")
	)
	(segment
		(start 294.763952 -410.080968)
		(end 294.216836 -410.080968)
		(width 0.1651)
		(layer "In5.Cu")
		(net "P5E_PEX2_STN7_RX_DN<115>")
	)
	(segment
		(start 285.403544 -389.172196)
		(end 293.0652 -393.2174)
		(width 0.1651)
		(layer "In5.Cu")
		(net "P5E_PEX2_STN7_RX_DN<115>")
	)
	(segment
		(start 269.429484 -304.335434)
		(end 269.429484 -304.184304)
		(width 0.1143)
		(layer "In5.Cu")
		(net "P5E_PEX2_STN7_RX_DN<115>")
	)
	(segment
		(start 258.418584 -308.196234)
		(end 258.27482 -308.196234)
		(width 0.1651)
		(layer "In5.Cu")
		(net "P5E_PEX2_STN7_RX_DN<115>")
	)
	(segment
		(start 257.25374 -309.468266)
		(end 257.305302 -309.602378)
		(width 0.1651)
		(layer "In5.Cu")
		(net "P5E_PEX2_STN7_RX_DN<115>")
	)
	(segment
		(start 267.866368 -304.070004)
		(end 267.820648 -304.115724)
		(width 0.1143)
		(layer "In5.Cu")
		(net "P5E_PEX2_STN7_RX_DN<115>")
	)
	(segment
		(start 259.963412 -306.507642)
		(end 259.6134 -306.857654)
		(width 0.1651)
		(layer "In5.Cu")
		(net "P5E_PEX2_STN7_RX_DN<115>")
	)
	(segment
		(start 269.511018 -359.30078)
		(end 280.851356 -370.851176)
		(width 0.1651)
		(layer "In5.Cu")
		(net "P5E_PEX2_STN7_RX_DN<115>")
	)
	(segment
		(start 283.4386 -387.342888)
		(end 285.403544 -389.172196)
		(width 0.1651)
		(layer "In5.Cu")
		(net "P5E_PEX2_STN7_RX_DN<115>")
	)
	(segment
		(start 254.530606 -315.33719)
		(end 252.80366 -319.33515)
		(width 0.1651)
		(layer "In5.Cu")
		(net "P5E_PEX2_STN7_RX_DN<115>")
	)
	(segment
		(start 259.9436 -335.63052)
		(end 269.511018 -359.30078)
		(width 0.1651)
		(layer "In5.Cu")
		(net "P5E_PEX2_STN7_RX_DN<115>")
	)
	(segment
		(start 255.998218 -312.28792)
		(end 255.222756 -314.029852)
		(width 0.1651)
		(layer "In5.Cu")
		(net "P5E_PEX2_STN7_RX_DN<115>")
	)
	(segment
		(start 256.969514 -310.106568)
		(end 256.768092 -310.558942)
		(width 0.1651)
		(layer "In5.Cu")
		(net "P5E_PEX2_STN7_RX_DN<115>")
	)
	(segment
		(start 281.644598 -372.458488)
		(end 282.2194 -378.8537)
		(width 0.1651)
		(layer "In5.Cu")
		(net "P5E_PEX2_STN7_RX_DN<115>")
	)
	(segment
		(start 256.617978 -311.145682)
		(end 256.483866 -311.197244)
		(width 0.1651)
		(layer "In5.Cu")
		(net "P5E_PEX2_STN7_RX_DN<115>")
	)
	(segment
		(start 259.119116 -307.351938)
		(end 258.769104 -307.70195)
		(width 0.1651)
		(layer "In5.Cu")
		(net "P5E_PEX2_STN7_RX_DN<115>")
	)
	(segment
		(start 256.334006 -311.78373)
		(end 256.13233 -312.236358)
		(width 0.1651)
		(layer "In5.Cu")
		(net "P5E_PEX2_STN7_RX_DN<115>")
	)
	(segment
		(start 257.305302 -309.602378)
		(end 257.103626 -310.055006)
		(width 0.1651)
		(layer "In5.Cu")
		(net "P5E_PEX2_STN7_RX_DN<115>")
	)
	(segment
		(start 258.27482 -308.196234)
		(end 257.455162 -309.015892)
		(width 0.1651)
		(layer "In5.Cu")
		(net "P5E_PEX2_STN7_RX_DN<115>")
	)
	(segment
		(start 257.455162 -309.015892)
		(end 257.25374 -309.468266)
		(width 0.1651)
		(layer "In5.Cu")
		(net "P5E_PEX2_STN7_RX_DN<115>")
	)
	(segment
		(start 259.6134 -306.857654)
		(end 259.6134 -307.001418)
		(width 0.1651)
		(layer "In5.Cu")
		(net "P5E_PEX2_STN7_RX_DN<115>")
	)
	(segment
		(start 257.103626 -310.055006)
		(end 256.969514 -310.106568)
		(width 0.1651)
		(layer "In5.Cu")
		(net "P5E_PEX2_STN7_RX_DN<115>")
	)
	(segment
		(start 295.215818 -409.629102)
		(end 294.763952 -410.080968)
		(width 0.1651)
		(layer "In5.Cu")
		(net "P5E_PEX2_STN7_RX_DN<115>")
	)
	(segment
		(start 256.282444 -311.649618)
		(end 256.334006 -311.78373)
		(width 0.1651)
		(layer "In5.Cu")
		(net "P5E_PEX2_STN7_RX_DN<115>")
	)
	(segment
		(start 269.429484 -304.184304)
		(end 269.315184 -304.070004)
		(width 0.1143)
		(layer "In5.Cu")
		(net "P5E_PEX2_STN7_RX_DN<115>")
	)
	(segment
		(start 267.7922 -304.115724)
		(end 264.824464 -304.115724)
		(width 0.1651)
		(layer "In5.Cu")
		(net "P5E_PEX2_STN7_RX_DN<115>")
	)
	(segment
		(start 282.601924 -385.262628)
		(end 283.4386 -387.342888)
		(width 0.1651)
		(layer "In5.Cu")
		(net "P5E_PEX2_STN7_RX_DN<115>")
	)
	(segment
		(start 260.457442 -306.013612)
		(end 260.457442 -306.157122)
		(width 0.1651)
		(layer "In5.Cu")
		(net "P5E_PEX2_STN7_RX_DN<115>")
	)
	(segment
		(start 256.819654 -310.693054)
		(end 256.617978 -311.145682)
		(width 0.1651)
		(layer "In5.Cu")
		(net "P5E_PEX2_STN7_RX_DN<115>")
	)
	(segment
		(start 295.215818 -395.3764)
		(end 295.215818 -409.629102)
		(width 0.1651)
		(layer "In5.Cu")
		(net "P5E_PEX2_STN7_RX_DN<115>")
	)
	(segment
		(start 294.216836 -410.080968)
		(end 294.089836 -410.207968)
		(width 0.1651)
		(layer "In5.Cu")
		(net "P5E_PEX2_STN7_RX_DN<115>")
	)
	(segment
		(start 264.824464 -304.115724)
		(end 260.859778 -305.611276)
		(width 0.1651)
		(layer "In5.Cu")
		(net "P5E_PEX2_STN7_RX_DN<115>")
	)
	(segment
		(start 256.13233 -312.236358)
		(end 255.998218 -312.28792)
		(width 0.1651)
		(layer "In5.Cu")
		(net "P5E_PEX2_STN7_RX_DN<115>")
	)
	(segment
		(start 258.769104 -307.70195)
		(end 258.769104 -307.845714)
		(width 0.1651)
		(layer "In5.Cu")
		(net "P5E_PEX2_STN7_RX_DN<115>")
	)
	(segment
		(start 259.6134 -307.001418)
		(end 259.26288 -307.351938)
		(width 0.1651)
		(layer "In5.Cu")
		(net "P5E_PEX2_STN7_RX_DN<115>")
	)
	(segment
		(start 269.049754 -304.449734)
		(end 269.315184 -304.449734)
		(width 0.1143)
		(layer "In5.Cu")
		(net "P5E_PEX2_STN7_RX_DN<115>")
	)
	(segment
		(start 252.80366 -322.705222)
		(end 254.413004 -326.572118)
		(width 0.1651)
		(layer "In5.Cu")
		(net "P5E_PEX2_STN7_RX_DN<115>")
	)
	(segment
		(start 294.089836 -410.207968)
		(end 294.089836 -410.589984)
		(width 0.1651)
		(layer "In5.Cu")
		(net "P5E_PEX2_STN7_RX_DN<115>")
	)
	(segment
		(start 256.768092 -310.558942)
		(end 256.819654 -310.693054)
		(width 0.1651)
		(layer "In5.Cu")
		(net "P5E_PEX2_STN7_RX_DN<115>")
	)
	(segment
		(start 254.413004 -326.572118)
		(end 259.9436 -335.63052)
		(width 0.1651)
		(layer "In5.Cu")
		(net "P5E_PEX2_STN7_RX_DN<115>")
	)
	(segment
		(start 256.483866 -311.197244)
		(end 256.282444 -311.649618)
		(width 0.1651)
		(layer "In5.Cu")
		(net "P5E_PEX2_STN7_RX_DN<115>")
	)
	(segment
		(start 293.0652 -393.2174)
		(end 295.215818 -395.3764)
		(width 0.1651)
		(layer "In5.Cu")
		(net "P5E_PEX2_STN7_RX_DN<115>")
	)
	(segment
		(start 252.80366 -319.33515)
		(end 252.80366 -322.705222)
		(width 0.1651)
		(layer "In5.Cu")
		(net "P5E_PEX2_STN7_RX_DN<115>")
	)
	(segment
		(start 260.106922 -306.507642)
		(end 259.963412 -306.507642)
		(width 0.1651)
		(layer "In5.Cu")
		(net "P5E_PEX2_STN7_RX_DN<115>")
	)
	(segment
		(start 375.489978 -375.358152)
		(end 375.489978 -375.69013)
		(width 0.1651)
		(layer "In5.Cu")
		(net "P5E_PEX3_STN6_RX_DN<103>")
	)
	(segment
		(start 397.798798 -320.888868)
		(end 369.466622 -339.714078)
		(width 0.1651)
		(layer "In5.Cu")
		(net "P5E_PEX3_STN6_RX_DN<103>")
	)
	(segment
		(start 368.711226 -340.665562)
		(end 368.123216 -342.29802)
		(width 0.1651)
		(layer "In5.Cu")
		(net "P5E_PEX3_STN6_RX_DN<103>")
	)
	(segment
		(start 399.066004 -320.208148)
		(end 398.92224 -320.42354)
		(width 0.1651)
		(layer "In5.Cu")
		(net "P5E_PEX3_STN6_RX_DN<103>")
	)
	(segment
		(start 399.066004 -319.984882)
		(end 399.066004 -320.01333)
		(width 0.1143)
		(layer "In5.Cu")
		(net "P5E_PEX3_STN6_RX_DN<103>")
	)
	(segment
		(start 369.466622 -339.714078)
		(end 368.711226 -340.665562)
		(width 0.1651)
		(layer "In5.Cu")
		(net "P5E_PEX3_STN6_RX_DN<103>")
	)
	(segment
		(start 399.134584 -316.419992)
		(end 399.020284 -316.534292)
		(width 0.1143)
		(layer "In5.Cu")
		(net "P5E_PEX3_STN6_RX_DN<103>")
	)
	(segment
		(start 368.123216 -342.29802)
		(end 368.230912 -352.318066)
		(width 0.1651)
		(layer "In5.Cu")
		(net "P5E_PEX3_STN6_RX_DN<103>")
	)
	(segment
		(start 399.400014 -316.799722)
		(end 399.400014 -316.534292)
		(width 0.1143)
		(layer "In5.Cu")
		(net "P5E_PEX3_STN6_RX_DN<103>")
	)
	(segment
		(start 368.230912 -352.318066)
		(end 371.213634 -361.04195)
		(width 0.1651)
		(layer "In5.Cu")
		(net "P5E_PEX3_STN6_RX_DN<103>")
	)
	(segment
		(start 371.213634 -361.04195)
		(end 376.647964 -368.731546)
		(width 0.1651)
		(layer "In5.Cu")
		(net "P5E_PEX3_STN6_RX_DN<103>")
	)
	(segment
		(start 398.92224 -320.42354)
		(end 397.798798 -320.888868)
		(width 0.1651)
		(layer "In5.Cu")
		(net "P5E_PEX3_STN6_RX_DN<103>")
	)
	(segment
		(start 399.066004 -320.01333)
		(end 399.066004 -320.208148)
		(width 0.1651)
		(layer "In5.Cu")
		(net "P5E_PEX3_STN6_RX_DN<103>")
	)
	(segment
		(start 399.020284 -316.534292)
		(end 399.020284 -319.939162)
		(width 0.1143)
		(layer "In5.Cu")
		(net "P5E_PEX3_STN6_RX_DN<103>")
	)
	(segment
		(start 399.400014 -316.534292)
		(end 399.285714 -316.419992)
		(width 0.1143)
		(layer "In5.Cu")
		(net "P5E_PEX3_STN6_RX_DN<103>")
	)
	(segment
		(start 399.020284 -319.939162)
		(end 399.066004 -319.984882)
		(width 0.1143)
		(layer "In5.Cu")
		(net "P5E_PEX3_STN6_RX_DN<103>")
	)
	(segment
		(start 376.647964 -374.687338)
		(end 376.150378 -375.184924)
		(width 0.1651)
		(layer "In5.Cu")
		(net "P5E_PEX3_STN6_RX_DN<103>")
	)
	(segment
		(start 376.150378 -375.184924)
		(end 375.663206 -375.184924)
		(width 0.1651)
		(layer "In5.Cu")
		(net "P5E_PEX3_STN6_RX_DN<103>")
	)
	(segment
		(start 399.285714 -316.419992)
		(end 399.134584 -316.419992)
		(width 0.1143)
		(layer "In5.Cu")
		(net "P5E_PEX3_STN6_RX_DN<103>")
	)
	(segment
		(start 376.647964 -368.731546)
		(end 376.647964 -374.687338)
		(width 0.1651)
		(layer "In5.Cu")
		(net "P5E_PEX3_STN6_RX_DN<103>")
	)
	(segment
		(start 375.663206 -375.184924)
		(end 375.489978 -375.358152)
		(width 0.1651)
		(layer "In5.Cu")
		(net "P5E_PEX3_STN6_RX_DN<103>")
	)
	(segment
		(start 157.871922 -33.790128)
		(end 157.364938 -33.790128)
		(width 0.13462)
		(layer "F.Cu")
		(net "P5E_PEX1_STN2_TX_C_DN<43>")
	)
	(segment
		(start 158.033974 -33.95218)
		(end 157.871922 -33.790128)
		(width 0.13462)
		(layer "F.Cu")
		(net "P5E_PEX1_STN2_TX_C_DN<43>")
	)
	(segment
		(start 162.2679 -33.631886)
		(end 161.947606 -33.95218)
		(width 0.13462)
		(layer "F.Cu")
		(net "P5E_PEX1_STN2_TX_C_DN<43>")
	)
	(segment
		(start 161.947606 -33.95218)
		(end 158.033974 -33.95218)
		(width 0.13462)
		(layer "F.Cu")
		(net "P5E_PEX1_STN2_TX_C_DN<43>")
	)
	(segment
		(start 311.95264 -122.270266)
		(end 311.637426 -122.58548)
		(width 0.13462)
		(layer "F.Cu")
		(net "P5E_PEX2_STN0_TX_C_DN<2>")
	)
	(segment
		(start 306.110894 -122.58548)
		(end 305.960526 -122.435112)
		(width 0.13462)
		(layer "F.Cu")
		(net "P5E_PEX2_STN0_TX_C_DN<2>")
	)
	(segment
		(start 305.960526 -122.435112)
		(end 305.457606 -122.435112)
		(width 0.13462)
		(layer "F.Cu")
		(net "P5E_PEX2_STN0_TX_C_DN<2>")
	)
	(segment
		(start 311.637426 -122.58548)
		(end 306.110894 -122.58548)
		(width 0.13462)
		(layer "F.Cu")
		(net "P5E_PEX2_STN0_TX_C_DN<2>")
	)
	(segment
		(start 277.198582 -344.219022)
		(end 277.518622 -344.539062)
		(width 0.13462)
		(layer "F.Cu")
		(net "P5E_PEX2_STN7_TX_C_DP<116>")
	)
	(segment
		(start 277.518622 -345.170506)
		(end 277.223982 -345.465146)
		(width 0.13462)
		(layer "F.Cu")
		(net "P5E_PEX2_STN7_TX_C_DP<116>")
	)
	(segment
		(start 277.518622 -344.539062)
		(end 277.518622 -345.170506)
		(width 0.13462)
		(layer "F.Cu")
		(net "P5E_PEX2_STN7_TX_C_DP<116>")
	)
	(segment
		(start 283.320236 -385.344416)
		(end 281.487626 -374.109742)
		(width 0.1651)
		(layer "In7.Cu")
		(net "P5E_PEX2_STN7_TX_C_DP<116>")
	)
	(segment
		(start 275.960332 -347.764354)
		(end 277.514812 -346.209874)
		(width 0.1651)
		(layer "In7.Cu")
		(net "P5E_PEX2_STN7_TX_C_DP<116>")
	)
	(segment
		(start 291.389562 -391.107168)
		(end 290.938204 -390.902444)
		(width 0.1651)
		(layer "In7.Cu")
		(net "P5E_PEX2_STN7_TX_C_DP<116>")
	)
	(segment
		(start 292.453822 -391.590022)
		(end 292.002464 -391.385044)
		(width 0.1651)
		(layer "In7.Cu")
		(net "P5E_PEX2_STN7_TX_C_DP<116>")
	)
	(segment
		(start 285.44774 -388.314184)
		(end 283.979112 -386.909564)
		(width 0.1651)
		(layer "In7.Cu")
		(net "P5E_PEX2_STN7_TX_C_DP<116>")
	)
	(segment
		(start 294.395906 -392.669014)
		(end 294.272462 -392.69289)
		(width 0.1651)
		(layer "In7.Cu")
		(net "P5E_PEX2_STN7_TX_C_DP<116>")
	)
	(segment
		(start 292.571424 -391.545826)
		(end 292.453822 -391.590022)
		(width 0.1651)
		(layer "In7.Cu")
		(net "P5E_PEX2_STN7_TX_C_DP<116>")
	)
	(segment
		(start 275.960332 -358.085898)
		(end 275.960332 -347.764354)
		(width 0.1651)
		(layer "In7.Cu")
		(net "P5E_PEX2_STN7_TX_C_DP<116>")
	)
	(segment
		(start 292.002464 -391.385044)
		(end 291.958268 -391.267442)
		(width 0.1651)
		(layer "In7.Cu")
		(net "P5E_PEX2_STN7_TX_C_DP<116>")
	)
	(segment
		(start 283.979112 -386.909564)
		(end 283.320236 -385.344416)
		(width 0.1651)
		(layer "In7.Cu")
		(net "P5E_PEX2_STN7_TX_C_DP<116>")
	)
	(segment
		(start 295.8084 -393.6238)
		(end 295.3639 -393.323572)
		(width 0.1651)
		(layer "In7.Cu")
		(net "P5E_PEX2_STN7_TX_C_DP<116>")
	)
	(segment
		(start 296.289984 -400.772122)
		(end 296.416984 -400.899122)
		(width 0.1651)
		(layer "In7.Cu")
		(net "P5E_PEX2_STN7_TX_C_DP<116>")
	)
	(segment
		(start 294.829992 -393.069572)
		(end 294.806116 -392.946382)
		(width 0.1651)
		(layer "In7.Cu")
		(net "P5E_PEX2_STN7_TX_C_DP<116>")
	)
	(segment
		(start 296.84726 -400.899122)
		(end 297.134026 -400.612356)
		(width 0.1651)
		(layer "In7.Cu")
		(net "P5E_PEX2_STN7_TX_C_DP<116>")
	)
	(segment
		(start 277.514812 -345.755976)
		(end 277.223982 -345.465146)
		(width 0.1651)
		(layer "In7.Cu")
		(net "P5E_PEX2_STN7_TX_C_DP<116>")
	)
	(segment
		(start 281.487626 -374.109742)
		(end 275.960332 -358.085898)
		(width 0.1651)
		(layer "In7.Cu")
		(net "P5E_PEX2_STN7_TX_C_DP<116>")
	)
	(segment
		(start 297.134026 -395.351)
		(end 296.9768 -394.6652)
		(width 0.1651)
		(layer "In7.Cu")
		(net "P5E_PEX2_STN7_TX_C_DP<116>")
	)
	(segment
		(start 296.416984 -400.899122)
		(end 296.84726 -400.899122)
		(width 0.1651)
		(layer "In7.Cu")
		(net "P5E_PEX2_STN7_TX_C_DP<116>")
	)
	(segment
		(start 295.3639 -393.323572)
		(end 295.240456 -393.347194)
		(width 0.1651)
		(layer "In7.Cu")
		(net "P5E_PEX2_STN7_TX_C_DP<116>")
	)
	(segment
		(start 293.861744 -392.415268)
		(end 293.837868 -392.291824)
		(width 0.1651)
		(layer "In7.Cu")
		(net "P5E_PEX2_STN7_TX_C_DP<116>")
	)
	(segment
		(start 277.514812 -346.209874)
		(end 277.514812 -345.755976)
		(width 0.1651)
		(layer "In7.Cu")
		(net "P5E_PEX2_STN7_TX_C_DP<116>")
	)
	(segment
		(start 296.289984 -400.390106)
		(end 296.289984 -400.772122)
		(width 0.1651)
		(layer "In7.Cu")
		(net "P5E_PEX2_STN7_TX_C_DP<116>")
	)
	(segment
		(start 294.272462 -392.69289)
		(end 293.861744 -392.415268)
		(width 0.1651)
		(layer "In7.Cu")
		(net "P5E_PEX2_STN7_TX_C_DP<116>")
	)
	(segment
		(start 291.507418 -391.062972)
		(end 291.389562 -391.107168)
		(width 0.1651)
		(layer "In7.Cu")
		(net "P5E_PEX2_STN7_TX_C_DP<116>")
	)
	(segment
		(start 297.134026 -400.612356)
		(end 297.134026 -395.351)
		(width 0.1651)
		(layer "In7.Cu")
		(net "P5E_PEX2_STN7_TX_C_DP<116>")
	)
	(segment
		(start 293.0652 -391.7696)
		(end 292.571424 -391.545826)
		(width 0.1651)
		(layer "In7.Cu")
		(net "P5E_PEX2_STN7_TX_C_DP<116>")
	)
	(segment
		(start 294.806116 -392.946382)
		(end 294.395906 -392.669014)
		(width 0.1651)
		(layer "In7.Cu")
		(net "P5E_PEX2_STN7_TX_C_DP<116>")
	)
	(segment
		(start 291.958268 -391.267442)
		(end 291.507418 -391.062972)
		(width 0.1651)
		(layer "In7.Cu")
		(net "P5E_PEX2_STN7_TX_C_DP<116>")
	)
	(segment
		(start 295.240456 -393.347194)
		(end 294.829992 -393.069572)
		(width 0.1651)
		(layer "In7.Cu")
		(net "P5E_PEX2_STN7_TX_C_DP<116>")
	)
	(segment
		(start 290.894008 -390.784588)
		(end 285.44774 -388.314184)
		(width 0.1651)
		(layer "In7.Cu")
		(net "P5E_PEX2_STN7_TX_C_DP<116>")
	)
	(segment
		(start 293.837868 -392.291824)
		(end 293.0652 -391.7696)
		(width 0.1651)
		(layer "In7.Cu")
		(net "P5E_PEX2_STN7_TX_C_DP<116>")
	)
	(segment
		(start 296.9768 -394.6652)
		(end 295.8084 -393.6238)
		(width 0.1651)
		(layer "In7.Cu")
		(net "P5E_PEX2_STN7_TX_C_DP<116>")
	)
	(segment
		(start 290.938204 -390.902444)
		(end 290.894008 -390.784588)
		(width 0.1651)
		(layer "In7.Cu")
		(net "P5E_PEX2_STN7_TX_C_DP<116>")
	)
	(segment
		(start 372.07698 -344.219022)
		(end 371.757448 -344.538554)
		(width 0.13462)
		(layer "F.Cu")
		(net "P5E_PEX3_STN6_TX_C_DN<111>")
	)
	(segment
		(start 371.757448 -345.171014)
		(end 372.05158 -345.465146)
		(width 0.13462)
		(layer "F.Cu")
		(net "P5E_PEX3_STN6_TX_C_DN<111>")
	)
	(segment
		(start 371.757448 -344.538554)
		(end 371.757448 -345.171014)
		(width 0.13462)
		(layer "F.Cu")
		(net "P5E_PEX3_STN6_TX_C_DN<111>")
	)
	(segment
		(start 375.548906 -393.800076)
		(end 372.896892 -392.603228)
		(width 0.1651)
		(layer "In13.Cu")
		(net "P5E_PEX3_STN6_TX_C_DN<111>")
	)
	(segment
		(start 376.315478 -394.5382)
		(end 375.548906 -393.800076)
		(width 0.1651)
		(layer "In13.Cu")
		(net "P5E_PEX3_STN6_TX_C_DN<111>")
	)
	(segment
		(start 371.76075 -345.755976)
		(end 372.05158 -345.465146)
		(width 0.1651)
		(layer "In13.Cu")
		(net "P5E_PEX3_STN6_TX_C_DN<111>")
	)
	(segment
		(start 367.467896 -385.981448)
		(end 366.98047 -373.118888)
		(width 0.1651)
		(layer "In13.Cu")
		(net "P5E_PEX3_STN6_TX_C_DN<111>")
	)
	(segment
		(start 375.616978 -408.981148)
		(end 376.164094 -408.981148)
		(width 0.1651)
		(layer "In13.Cu")
		(net "P5E_PEX3_STN6_TX_C_DN<111>")
	)
	(segment
		(start 371.76075 -346.326714)
		(end 371.76075 -345.755976)
		(width 0.1651)
		(layer "In13.Cu")
		(net "P5E_PEX3_STN6_TX_C_DN<111>")
	)
	(segment
		(start 367.637822 -366.95634)
		(end 370.204746 -347.882718)
		(width 0.1651)
		(layer "In13.Cu")
		(net "P5E_PEX3_STN6_TX_C_DN<111>")
	)
	(segment
		(start 375.489978 -409.108148)
		(end 375.616978 -408.981148)
		(width 0.1651)
		(layer "In13.Cu")
		(net "P5E_PEX3_STN6_TX_C_DN<111>")
	)
	(segment
		(start 369.092988 -389.71347)
		(end 367.467896 -385.981448)
		(width 0.1651)
		(layer "In13.Cu")
		(net "P5E_PEX3_STN6_TX_C_DN<111>")
	)
	(segment
		(start 376.164094 -408.981148)
		(end 376.61596 -408.529282)
		(width 0.1651)
		(layer "In13.Cu")
		(net "P5E_PEX3_STN6_TX_C_DN<111>")
	)
	(segment
		(start 376.61596 -408.529282)
		(end 376.61596 -395.3256)
		(width 0.1651)
		(layer "In13.Cu")
		(net "P5E_PEX3_STN6_TX_C_DN<111>")
	)
	(segment
		(start 372.896892 -392.603228)
		(end 369.092988 -389.71347)
		(width 0.1651)
		(layer "In13.Cu")
		(net "P5E_PEX3_STN6_TX_C_DN<111>")
	)
	(segment
		(start 375.489978 -409.490164)
		(end 375.489978 -409.108148)
		(width 0.1651)
		(layer "In13.Cu")
		(net "P5E_PEX3_STN6_TX_C_DN<111>")
	)
	(segment
		(start 366.98047 -373.118888)
		(end 367.637822 -366.95634)
		(width 0.1651)
		(layer "In13.Cu")
		(net "P5E_PEX3_STN6_TX_C_DN<111>")
	)
	(segment
		(start 376.61596 -395.3256)
		(end 376.315478 -394.5382)
		(width 0.1651)
		(layer "In13.Cu")
		(net "P5E_PEX3_STN6_TX_C_DN<111>")
	)
	(segment
		(start 370.204746 -347.882718)
		(end 371.76075 -346.326714)
		(width 0.1651)
		(layer "In13.Cu")
		(net "P5E_PEX3_STN6_TX_C_DN<111>")
	)
	(segment
		(start 88.187276 -30.190186)
		(end 88.024462 -30.353)
		(width 0.13462)
		(layer "F.Cu")
		(net "P5E_PEX0_STN2_RX_DN<33>")
	)
	(segment
		(start 88.024462 -30.353)
		(end 85.504528 -30.353)
		(width 0.13462)
		(layer "F.Cu")
		(net "P5E_PEX0_STN2_RX_DN<33>")
	)
	(segment
		(start 88.664796 -30.190186)
		(end 88.187276 -30.190186)
		(width 0.13462)
		(layer "F.Cu")
		(net "P5E_PEX0_STN2_RX_DN<33>")
	)
	(segment
		(start 85.504528 -30.353)
		(end 85.210396 -30.058868)
		(width 0.13462)
		(layer "F.Cu")
		(net "P5E_PEX0_STN2_RX_DN<33>")
	)
	(segment
		(start 90.205814 -49.3776)
		(end 88.889586 -39.636954)
		(width 0.1651)
		(layer "In7.Cu")
		(net "P5E_PEX0_STN2_RX_DN<33>")
	)
	(segment
		(start 89.585038 -34.102294)
		(end 89.593674 -33.002982)
		(width 0.1651)
		(layer "In7.Cu")
		(net "P5E_PEX0_STN2_RX_DN<33>")
	)
	(segment
		(start 77.318362 -154.698446)
		(end 78.697328 -143.990568)
		(width 0.1651)
		(layer "In7.Cu")
		(net "P5E_PEX0_STN2_RX_DN<33>")
	)
	(segment
		(start 79.012796 -116.691918)
		(end 90.020902 -61.209428)
		(width 0.1651)
		(layer "In7.Cu")
		(net "P5E_PEX0_STN2_RX_DN<33>")
	)
	(segment
		(start 57.415938 -271.3736)
		(end 57.415938 -271.345152)
		(width 0.1143)
		(layer "In7.Cu")
		(net "P5E_PEX0_STN2_RX_DN<33>")
	)
	(segment
		(start 57.75325 -267.040868)
		(end 77.318362 -154.698446)
		(width 0.1651)
		(layer "In7.Cu")
		(net "P5E_PEX0_STN2_RX_DN<33>")
	)
	(segment
		(start 57.749948 -273.099784)
		(end 57.749948 -273.365214)
		(width 0.1143)
		(layer "In7.Cu")
		(net "P5E_PEX0_STN2_RX_DN<33>")
	)
	(segment
		(start 57.635648 -273.479514)
		(end 57.521094 -273.479514)
		(width 0.1143)
		(layer "In7.Cu")
		(net "P5E_PEX0_STN2_RX_DN<33>")
	)
	(segment
		(start 88.090756 -30.349698)
		(end 85.501226 -30.349698)
		(width 0.1651)
		(layer "In7.Cu")
		(net "P5E_PEX0_STN2_RX_DN<33>")
	)
	(segment
		(start 89.593674 -33.002982)
		(end 89.307416 -32.239712)
		(width 0.1651)
		(layer "In7.Cu")
		(net "P5E_PEX0_STN2_RX_DN<33>")
	)
	(segment
		(start 57.370218 -273.328638)
		(end 57.370218 -271.41932)
		(width 0.1143)
		(layer "In7.Cu")
		(net "P5E_PEX0_STN2_RX_DN<33>")
	)
	(segment
		(start 88.865964 -38.15207)
		(end 89.585038 -34.102294)
		(width 0.1651)
		(layer "In7.Cu")
		(net "P5E_PEX0_STN2_RX_DN<33>")
	)
	(segment
		(start 57.370218 -271.41932)
		(end 57.415938 -271.3736)
		(width 0.1143)
		(layer "In7.Cu")
		(net "P5E_PEX0_STN2_RX_DN<33>")
	)
	(segment
		(start 89.307416 -32.239712)
		(end 88.090756 -30.349698)
		(width 0.1651)
		(layer "In7.Cu")
		(net "P5E_PEX0_STN2_RX_DN<33>")
	)
	(segment
		(start 90.020902 -61.209428)
		(end 90.205814 -49.3776)
		(width 0.1651)
		(layer "In7.Cu")
		(net "P5E_PEX0_STN2_RX_DN<33>")
	)
	(segment
		(start 85.501226 -30.349698)
		(end 85.210396 -30.058868)
		(width 0.1651)
		(layer "In7.Cu")
		(net "P5E_PEX0_STN2_RX_DN<33>")
	)
	(segment
		(start 57.415938 -271.345152)
		(end 57.415938 -270.929862)
		(width 0.1651)
		(layer "In7.Cu")
		(net "P5E_PEX0_STN2_RX_DN<33>")
	)
	(segment
		(start 88.889586 -39.636954)
		(end 88.865964 -38.15207)
		(width 0.1651)
		(layer "In7.Cu")
		(net "P5E_PEX0_STN2_RX_DN<33>")
	)
	(segment
		(start 57.521094 -273.479514)
		(end 57.370218 -273.328638)
		(width 0.1143)
		(layer "In7.Cu")
		(net "P5E_PEX0_STN2_RX_DN<33>")
	)
	(segment
		(start 78.697328 -143.990568)
		(end 79.012796 -116.691918)
		(width 0.1651)
		(layer "In7.Cu")
		(net "P5E_PEX0_STN2_RX_DN<33>")
	)
	(segment
		(start 57.749948 -273.365214)
		(end 57.635648 -273.479514)
		(width 0.1143)
		(layer "In7.Cu")
		(net "P5E_PEX0_STN2_RX_DN<33>")
	)
	(segment
		(start 57.415938 -270.929862)
		(end 57.75325 -267.040868)
		(width 0.1651)
		(layer "In7.Cu")
		(net "P5E_PEX0_STN2_RX_DN<33>")
	)
	(segment
		(start 178.287426 -33.790128)
		(end 178.124612 -33.952942)
		(width 0.13462)
		(layer "F.Cu")
		(net "P5E_PEX1_STN2_RX_DN<39>")
	)
	(segment
		(start 175.604678 -33.952942)
		(end 175.310546 -33.65881)
		(width 0.13462)
		(layer "F.Cu")
		(net "P5E_PEX1_STN2_RX_DN<39>")
	)
	(segment
		(start 178.764946 -33.790128)
		(end 178.287426 -33.790128)
		(width 0.13462)
		(layer "F.Cu")
		(net "P5E_PEX1_STN2_RX_DN<39>")
	)
	(segment
		(start 178.124612 -33.952942)
		(end 175.604678 -33.952942)
		(width 0.13462)
		(layer "F.Cu")
		(net "P5E_PEX1_STN2_RX_DN<39>")
	)
	(segment
		(start 176.988216 -35.355276)
		(end 176.988216 -34.98596)
		(width 0.1651)
		(layer "In7.Cu")
		(net "P5E_PEX1_STN2_RX_DN<39>")
	)
	(segment
		(start 167.816022 -271.4752)
		(end 167.816022 -266.275058)
		(width 0.1651)
		(layer "In7.Cu")
		(net "P5E_PEX1_STN2_RX_DN<39>")
	)
	(segment
		(start 167.770302 -271.549368)
		(end 167.816022 -271.503648)
		(width 0.1143)
		(layer "In7.Cu")
		(net "P5E_PEX1_STN2_RX_DN<39>")
	)
	(segment
		(start 175.951896 -33.94964)
		(end 175.601376 -33.94964)
		(width 0.1651)
		(layer "In7.Cu")
		(net "P5E_PEX1_STN2_RX_DN<39>")
	)
	(segment
		(start 168.150032 -273.099784)
		(end 168.150032 -273.365214)
		(width 0.1143)
		(layer "In7.Cu")
		(net "P5E_PEX1_STN2_RX_DN<39>")
	)
	(segment
		(start 178.255168 -60.99683)
		(end 178.428142 -49.915572)
		(width 0.1651)
		(layer "In7.Cu")
		(net "P5E_PEX1_STN2_RX_DN<39>")
	)
	(segment
		(start 177.056542 -39.76497)
		(end 176.988216 -35.355276)
		(width 0.1651)
		(layer "In7.Cu")
		(net "P5E_PEX1_STN2_RX_DN<39>")
	)
	(segment
		(start 168.035732 -273.479514)
		(end 167.921178 -273.479514)
		(width 0.1143)
		(layer "In7.Cu")
		(net "P5E_PEX1_STN2_RX_DN<39>")
	)
	(segment
		(start 178.281076 -68.13804)
		(end 178.255168 -60.99683)
		(width 0.1651)
		(layer "In7.Cu")
		(net "P5E_PEX1_STN2_RX_DN<39>")
	)
	(segment
		(start 168.150032 -273.365214)
		(end 168.035732 -273.479514)
		(width 0.1143)
		(layer "In7.Cu")
		(net "P5E_PEX1_STN2_RX_DN<39>")
	)
	(segment
		(start 176.988216 -34.98596)
		(end 175.951896 -33.94964)
		(width 0.1651)
		(layer "In7.Cu")
		(net "P5E_PEX1_STN2_RX_DN<39>")
	)
	(segment
		(start 175.601376 -33.94964)
		(end 175.310546 -33.65881)
		(width 0.1651)
		(layer "In7.Cu")
		(net "P5E_PEX1_STN2_RX_DN<39>")
	)
	(segment
		(start 167.816022 -266.275058)
		(end 178.281076 -68.13804)
		(width 0.1651)
		(layer "In7.Cu")
		(net "P5E_PEX1_STN2_RX_DN<39>")
	)
	(segment
		(start 167.921178 -273.479514)
		(end 167.770302 -273.328638)
		(width 0.1143)
		(layer "In7.Cu")
		(net "P5E_PEX1_STN2_RX_DN<39>")
	)
	(segment
		(start 178.428142 -49.915572)
		(end 177.056542 -39.76497)
		(width 0.1651)
		(layer "In7.Cu")
		(net "P5E_PEX1_STN2_RX_DN<39>")
	)
	(segment
		(start 167.770302 -273.328638)
		(end 167.770302 -271.549368)
		(width 0.1143)
		(layer "In7.Cu")
		(net "P5E_PEX1_STN2_RX_DN<39>")
	)
	(segment
		(start 167.816022 -271.503648)
		(end 167.816022 -271.4752)
		(width 0.1143)
		(layer "In7.Cu")
		(net "P5E_PEX1_STN2_RX_DN<39>")
	)
	(segment
		(start 300.378368 -134.245096)
		(end 300.214792 -134.08152)
		(width 0.13462)
		(layer "F.Cu")
		(net "P5E_PEX2_STN0_RX_DP<6>")
	)
	(segment
		(start 300.214792 -134.08152)
		(end 299.552868 -134.08152)
		(width 0.13462)
		(layer "F.Cu")
		(net "P5E_PEX2_STN0_RX_DP<6>")
	)
	(segment
		(start 299.552868 -134.08152)
		(end 299.257212 -134.377176)
		(width 0.13462)
		(layer "F.Cu")
		(net "P5E_PEX2_STN0_RX_DP<6>")
	)
	(segment
		(start 300.857412 -134.245096)
		(end 300.378368 -134.245096)
		(width 0.13462)
		(layer "F.Cu")
		(net "P5E_PEX2_STN0_RX_DP<6>")
	)
	(segment
		(start 317.751206 -277.085552)
		(end 317.751206 -276.721316)
		(width 0.1651)
		(layer "In5.Cu")
		(net "P5E_PEX2_STN0_RX_DP<6>")
	)
	(segment
		(start 312.179462 -282.485592)
		(end 312.179462 -282.273756)
		(width 0.1143)
		(layer "In5.Cu")
		(net "P5E_PEX2_STN0_RX_DP<6>")
	)
	(segment
		(start 312.065162 -282.599892)
		(end 312.179462 -282.485592)
		(width 0.1143)
		(layer "In5.Cu")
		(net "P5E_PEX2_STN0_RX_DP<6>")
	)
	(segment
		(start 312.179462 -282.273756)
		(end 312.423556 -282.029662)
		(width 0.1143)
		(layer "In5.Cu")
		(net "P5E_PEX2_STN0_RX_DP<6>")
	)
	(segment
		(start 300.833028 -134.729982)
		(end 300.786292 -134.575296)
		(width 0.1651)
		(layer "In5.Cu")
		(net "P5E_PEX2_STN0_RX_DP<6>")
	)
	(segment
		(start 316.628526 -270.821404)
		(end 315.712094 -264.723118)
		(width 0.1651)
		(layer "In5.Cu")
		(net "P5E_PEX2_STN0_RX_DP<6>")
	)
	(segment
		(start 317.455804 -281.074368)
		(end 317.664338 -280.582116)
		(width 0.1651)
		(layer "In5.Cu")
		(net "P5E_PEX2_STN0_RX_DP<6>")
	)
	(segment
		(start 308.803802 -140.932662)
		(end 308.803802 -139.813284)
		(width 0.1651)
		(layer "In5.Cu")
		(net "P5E_PEX2_STN0_RX_DP<6>")
	)
	(segment
		(start 303.41824 -136.118092)
		(end 302.981614 -135.88365)
		(width 0.1651)
		(layer "In5.Cu")
		(net "P5E_PEX2_STN0_RX_DP<6>")
	)
	(segment
		(start 307.09616 -137.96264)
		(end 307.095906 -137.96264)
		(width 0.1651)
		(layer "In5.Cu")
		(net "P5E_PEX2_STN0_RX_DP<6>")
	)
	(segment
		(start 301.860712 -135.15213)
		(end 301.42434 -134.917942)
		(width 0.1651)
		(layer "In5.Cu")
		(net "P5E_PEX2_STN0_RX_DP<6>")
	)
	(segment
		(start 304.947066 -136.808972)
		(end 304.792126 -136.855708)
		(width 0.1651)
		(layer "In5.Cu")
		(net "P5E_PEX2_STN0_RX_DP<6>")
	)
	(segment
		(start 316.050422 -282.029662)
		(end 316.096142 -281.983942)
		(width 0.1143)
		(layer "In5.Cu")
		(net "P5E_PEX2_STN0_RX_DP<6>")
	)
	(segment
		(start 301.42434 -134.917942)
		(end 301.269654 -134.964678)
		(width 0.1651)
		(layer "In5.Cu")
		(net "P5E_PEX2_STN0_RX_DP<6>")
	)
	(segment
		(start 312.156094 -160.27273)
		(end 308.803802 -140.932662)
		(width 0.1651)
		(layer "In5.Cu")
		(net "P5E_PEX2_STN0_RX_DP<6>")
	)
	(segment
		(start 305.42992 -137.197846)
		(end 305.383438 -137.04316)
		(width 0.1651)
		(layer "In5.Cu")
		(net "P5E_PEX2_STN0_RX_DP<6>")
	)
	(segment
		(start 303.57318 -136.07161)
		(end 303.41824 -136.118092)
		(width 0.1651)
		(layer "In5.Cu")
		(net "P5E_PEX2_STN0_RX_DP<6>")
	)
	(segment
		(start 308.3306 -138.625326)
		(end 307.09616 -137.96264)
		(width 0.1651)
		(layer "In5.Cu")
		(net "P5E_PEX2_STN0_RX_DP<6>")
	)
	(segment
		(start 306.457858 -137.619994)
		(end 306.021486 -137.385806)
		(width 0.1651)
		(layer "In5.Cu")
		(net "P5E_PEX2_STN0_RX_DP<6>")
	)
	(segment
		(start 299.548042 -134.086346)
		(end 299.257212 -134.377176)
		(width 0.1651)
		(layer "In5.Cu")
		(net "P5E_PEX2_STN0_RX_DP<6>")
	)
	(segment
		(start 304.792126 -136.855708)
		(end 304.3555 -136.621266)
		(width 0.1651)
		(layer "In5.Cu")
		(net "P5E_PEX2_STN0_RX_DP<6>")
	)
	(segment
		(start 317.015114 -281.606244)
		(end 317.455804 -281.074368)
		(width 0.1651)
		(layer "In5.Cu")
		(net "P5E_PEX2_STN0_RX_DP<6>")
	)
	(segment
		(start 302.935132 -135.728964)
		(end 302.49876 -135.494776)
		(width 0.1651)
		(layer "In5.Cu")
		(net "P5E_PEX2_STN0_RX_DP<6>")
	)
	(segment
		(start 308.66715 -139.025376)
		(end 308.3306 -138.625326)
		(width 0.1651)
		(layer "In5.Cu")
		(net "P5E_PEX2_STN0_RX_DP<6>")
	)
	(segment
		(start 307.095906 -137.96264)
		(end 306.940966 -138.009122)
		(width 0.1651)
		(layer "In5.Cu")
		(net "P5E_PEX2_STN0_RX_DP<6>")
	)
	(segment
		(start 308.803802 -139.813284)
		(end 308.66715 -139.025376)
		(width 0.1651)
		(layer "In5.Cu")
		(net "P5E_PEX2_STN0_RX_DP<6>")
	)
	(segment
		(start 300.786292 -134.575296)
		(end 299.875448 -134.086346)
		(width 0.1651)
		(layer "In5.Cu")
		(net "P5E_PEX2_STN0_RX_DP<6>")
	)
	(segment
		(start 312.423556 -282.029662)
		(end 316.050422 -282.029662)
		(width 0.1143)
		(layer "In5.Cu")
		(net "P5E_PEX2_STN0_RX_DP<6>")
	)
	(segment
		(start 306.50434 -137.77468)
		(end 306.457858 -137.619994)
		(width 0.1651)
		(layer "In5.Cu")
		(net "P5E_PEX2_STN0_RX_DP<6>")
	)
	(segment
		(start 316.12459 -281.983942)
		(end 316.450472 -281.983942)
		(width 0.1651)
		(layer "In5.Cu")
		(net "P5E_PEX2_STN0_RX_DP<6>")
	)
	(segment
		(start 301.907194 -135.306816)
		(end 301.860712 -135.15213)
		(width 0.1651)
		(layer "In5.Cu")
		(net "P5E_PEX2_STN0_RX_DP<6>")
	)
	(segment
		(start 301.269654 -134.964678)
		(end 300.833028 -134.729982)
		(width 0.1651)
		(layer "In5.Cu")
		(net "P5E_PEX2_STN0_RX_DP<6>")
	)
	(segment
		(start 305.383438 -137.04316)
		(end 304.947066 -136.808972)
		(width 0.1651)
		(layer "In5.Cu")
		(net "P5E_PEX2_STN0_RX_DP<6>")
	)
	(segment
		(start 316.450472 -281.983942)
		(end 317.015114 -281.606244)
		(width 0.1651)
		(layer "In5.Cu")
		(net "P5E_PEX2_STN0_RX_DP<6>")
	)
	(segment
		(start 302.34382 -135.541258)
		(end 301.907194 -135.306816)
		(width 0.1651)
		(layer "In5.Cu")
		(net "P5E_PEX2_STN0_RX_DP<6>")
	)
	(segment
		(start 317.751206 -276.721316)
		(end 316.628526 -270.821404)
		(width 0.1651)
		(layer "In5.Cu")
		(net "P5E_PEX2_STN0_RX_DP<6>")
	)
	(segment
		(start 304.309018 -136.46658)
		(end 303.57318 -136.07161)
		(width 0.1651)
		(layer "In5.Cu")
		(net "P5E_PEX2_STN0_RX_DP<6>")
	)
	(segment
		(start 316.096142 -281.983942)
		(end 316.12459 -281.983942)
		(width 0.1143)
		(layer "In5.Cu")
		(net "P5E_PEX2_STN0_RX_DP<6>")
	)
	(segment
		(start 304.3555 -136.621266)
		(end 304.309018 -136.46658)
		(width 0.1651)
		(layer "In5.Cu")
		(net "P5E_PEX2_STN0_RX_DP<6>")
	)
	(segment
		(start 302.49876 -135.494776)
		(end 302.34382 -135.541258)
		(width 0.1651)
		(layer "In5.Cu")
		(net "P5E_PEX2_STN0_RX_DP<6>")
	)
	(segment
		(start 315.712094 -264.723118)
		(end 312.156094 -160.27273)
		(width 0.1651)
		(layer "In5.Cu")
		(net "P5E_PEX2_STN0_RX_DP<6>")
	)
	(segment
		(start 299.875448 -134.086346)
		(end 299.548042 -134.086346)
		(width 0.1651)
		(layer "In5.Cu")
		(net "P5E_PEX2_STN0_RX_DP<6>")
	)
	(segment
		(start 305.866546 -137.432288)
		(end 305.42992 -137.197846)
		(width 0.1651)
		(layer "In5.Cu")
		(net "P5E_PEX2_STN0_RX_DP<6>")
	)
	(segment
		(start 302.981614 -135.88365)
		(end 302.935132 -135.728964)
		(width 0.1651)
		(layer "In5.Cu")
		(net "P5E_PEX2_STN0_RX_DP<6>")
	)
	(segment
		(start 317.664338 -280.582116)
		(end 317.751206 -277.085552)
		(width 0.1651)
		(layer "In5.Cu")
		(net "P5E_PEX2_STN0_RX_DP<6>")
	)
	(segment
		(start 306.940966 -138.009122)
		(end 306.50434 -137.77468)
		(width 0.1651)
		(layer "In5.Cu")
		(net "P5E_PEX2_STN0_RX_DP<6>")
	)
	(segment
		(start 311.799732 -282.599892)
		(end 312.065162 -282.599892)
		(width 0.1143)
		(layer "In5.Cu")
		(net "P5E_PEX2_STN0_RX_DP<6>")
	)
	(segment
		(start 306.021486 -137.385806)
		(end 305.866546 -137.432288)
		(width 0.1651)
		(layer "In5.Cu")
		(net "P5E_PEX2_STN0_RX_DP<6>")
	)
	(segment
		(start 269.619984 -304.335434)
		(end 269.619984 -304.10531)
		(width 0.1143)
		(layer "In5.Cu")
		(net "P5E_PEX2_STN7_RX_DP<115>")
	)
	(segment
		(start 294.089836 -409.672028)
		(end 294.089836 -409.290012)
		(width 0.1651)
		(layer "In5.Cu")
		(net "P5E_PEX2_STN7_RX_DP<115>")
	)
	(segment
		(start 252.52172 -319.27673)
		(end 252.52172 -322.76161)
		(width 0.1651)
		(layer "In5.Cu")
		(net "P5E_PEX2_STN7_RX_DP<115>")
	)
	(segment
		(start 267.820648 -303.833784)
		(end 267.7922 -303.833784)
		(width 0.1143)
		(layer "In5.Cu")
		(net "P5E_PEX2_STN7_RX_DP<115>")
	)
	(segment
		(start 264.772902 -303.833784)
		(end 260.703314 -305.36896)
		(width 0.1651)
		(layer "In5.Cu")
		(net "P5E_PEX2_STN7_RX_DP<115>")
	)
	(segment
		(start 292.895528 -393.447016)
		(end 294.933878 -395.492986)
		(width 0.1651)
		(layer "In5.Cu")
		(net "P5E_PEX2_STN7_RX_DP<115>")
	)
	(segment
		(start 294.216836 -409.799028)
		(end 294.089836 -409.672028)
		(width 0.1651)
		(layer "In5.Cu")
		(net "P5E_PEX2_STN7_RX_DP<115>")
	)
	(segment
		(start 285.238698 -389.404098)
		(end 292.895528 -393.447016)
		(width 0.1651)
		(layer "In5.Cu")
		(net "P5E_PEX2_STN7_RX_DP<115>")
	)
	(segment
		(start 267.7922 -303.833784)
		(end 264.772902 -303.833784)
		(width 0.1651)
		(layer "In5.Cu")
		(net "P5E_PEX2_STN7_RX_DP<115>")
	)
	(segment
		(start 252.52172 -322.76161)
		(end 254.160782 -326.700642)
		(width 0.1651)
		(layer "In5.Cu")
		(net "P5E_PEX2_STN7_RX_DP<115>")
	)
	(segment
		(start 269.999714 -304.449734)
		(end 269.734284 -304.449734)
		(width 0.1143)
		(layer "In5.Cu")
		(net "P5E_PEX2_STN7_RX_DP<115>")
	)
	(segment
		(start 254.276098 -315.215016)
		(end 252.52172 -319.27673)
		(width 0.1651)
		(layer "In5.Cu")
		(net "P5E_PEX2_STN7_RX_DP<115>")
	)
	(segment
		(start 294.933878 -395.492986)
		(end 294.933878 -409.512262)
		(width 0.1651)
		(layer "In5.Cu")
		(net "P5E_PEX2_STN7_RX_DP<115>")
	)
	(segment
		(start 269.734284 -304.449734)
		(end 269.619984 -304.335434)
		(width 0.1143)
		(layer "In5.Cu")
		(net "P5E_PEX2_STN7_RX_DP<115>")
	)
	(segment
		(start 257.218688 -308.853332)
		(end 254.96901 -313.906408)
		(width 0.1651)
		(layer "In5.Cu")
		(net "P5E_PEX2_STN7_RX_DP<115>")
	)
	(segment
		(start 267.866368 -303.879504)
		(end 267.820648 -303.833784)
		(width 0.1143)
		(layer "In5.Cu")
		(net "P5E_PEX2_STN7_RX_DP<115>")
	)
	(segment
		(start 283.200348 -387.506464)
		(end 285.238698 -389.404098)
		(width 0.1651)
		(layer "In5.Cu")
		(net "P5E_PEX2_STN7_RX_DP<115>")
	)
	(segment
		(start 254.96901 -313.906408)
		(end 254.276098 -315.215016)
		(width 0.1651)
		(layer "In5.Cu")
		(net "P5E_PEX2_STN7_RX_DP<115>")
	)
	(segment
		(start 254.160782 -326.700642)
		(end 259.69087 -335.757774)
		(width 0.1651)
		(layer "In5.Cu")
		(net "P5E_PEX2_STN7_RX_DP<115>")
	)
	(segment
		(start 269.619984 -304.10531)
		(end 269.394178 -303.879504)
		(width 0.1143)
		(layer "In5.Cu")
		(net "P5E_PEX2_STN7_RX_DP<115>")
	)
	(segment
		(start 294.647112 -409.799028)
		(end 294.216836 -409.799028)
		(width 0.1651)
		(layer "In5.Cu")
		(net "P5E_PEX2_STN7_RX_DP<115>")
	)
	(segment
		(start 282.323032 -385.325366)
		(end 283.200348 -387.506464)
		(width 0.1651)
		(layer "In5.Cu")
		(net "P5E_PEX2_STN7_RX_DP<115>")
	)
	(segment
		(start 280.618438 -371.01653)
		(end 281.3685 -372.536212)
		(width 0.1651)
		(layer "In5.Cu")
		(net "P5E_PEX2_STN7_RX_DP<115>")
	)
	(segment
		(start 260.703314 -305.36896)
		(end 257.218688 -308.853332)
		(width 0.1651)
		(layer "In5.Cu")
		(net "P5E_PEX2_STN7_RX_DP<115>")
	)
	(segment
		(start 269.394178 -303.879504)
		(end 267.866368 -303.879504)
		(width 0.1143)
		(layer "In5.Cu")
		(net "P5E_PEX2_STN7_RX_DP<115>")
	)
	(segment
		(start 269.27048 -359.45826)
		(end 280.618438 -371.01653)
		(width 0.1651)
		(layer "In5.Cu")
		(net "P5E_PEX2_STN7_RX_DP<115>")
	)
	(segment
		(start 281.3685 -372.536212)
		(end 281.937968 -378.874782)
		(width 0.1651)
		(layer "In5.Cu")
		(net "P5E_PEX2_STN7_RX_DP<115>")
	)
	(segment
		(start 281.937968 -378.874782)
		(end 282.323032 -385.325366)
		(width 0.1651)
		(layer "In5.Cu")
		(net "P5E_PEX2_STN7_RX_DP<115>")
	)
	(segment
		(start 259.69087 -335.757774)
		(end 269.27048 -359.45826)
		(width 0.1651)
		(layer "In5.Cu")
		(net "P5E_PEX2_STN7_RX_DP<115>")
	)
	(segment
		(start 294.933878 -409.512262)
		(end 294.647112 -409.799028)
		(width 0.1651)
		(layer "In5.Cu")
		(net "P5E_PEX2_STN7_RX_DP<115>")
	)
	(segment
		(start 387.62178 -350.365314)
		(end 387.302248 -350.684846)
		(width 0.13462)
		(layer "F.Cu")
		(net "P5E_PEX3_STN6_TX_C_DN<104>")
	)
	(segment
		(start 387.302248 -350.684846)
		(end 387.302248 -351.317306)
		(width 0.13462)
		(layer "F.Cu")
		(net "P5E_PEX3_STN6_TX_C_DN<104>")
	)
	(segment
		(start 387.302248 -351.317306)
		(end 387.59638 -351.611438)
		(width 0.13462)
		(layer "F.Cu")
		(net "P5E_PEX3_STN6_TX_C_DN<104>")
	)
	(segment
		(start 391.530078 -394.7414)
		(end 392.01598 -396.0368)
		(width 0.1651)
		(layer "In13.Cu")
		(net "P5E_PEX3_STN6_TX_C_DN<104>")
	)
	(segment
		(start 390.499854 -393.577572)
		(end 390.84631 -393.932156)
		(width 0.1651)
		(layer "In13.Cu")
		(net "P5E_PEX3_STN6_TX_C_DN<104>")
	)
	(segment
		(start 389.396478 -392.557)
		(end 390.392158 -393.576302)
		(width 0.1651)
		(layer "In13.Cu")
		(net "P5E_PEX3_STN6_TX_C_DN<104>")
	)
	(segment
		(start 391.016998 -410.080968)
		(end 390.889998 -410.207968)
		(width 0.1651)
		(layer "In13.Cu")
		(net "P5E_PEX3_STN6_TX_C_DN<104>")
	)
	(segment
		(start 385.75107 -354.027486)
		(end 385.75107 -358.130094)
		(width 0.1651)
		(layer "In13.Cu")
		(net "P5E_PEX3_STN6_TX_C_DN<104>")
	)
	(segment
		(start 392.01598 -409.629102)
		(end 391.564114 -410.080968)
		(width 0.1651)
		(layer "In13.Cu")
		(net "P5E_PEX3_STN6_TX_C_DN<104>")
	)
	(segment
		(start 390.84631 -393.932156)
		(end 390.84504 -394.040106)
		(width 0.1651)
		(layer "In13.Cu")
		(net "P5E_PEX3_STN6_TX_C_DN<104>")
	)
	(segment
		(start 390.84504 -394.040106)
		(end 391.530078 -394.7414)
		(width 0.1651)
		(layer "In13.Cu")
		(net "P5E_PEX3_STN6_TX_C_DN<104>")
	)
	(segment
		(start 387.30555 -351.902268)
		(end 387.30555 -352.473006)
		(width 0.1651)
		(layer "In13.Cu")
		(net "P5E_PEX3_STN6_TX_C_DN<104>")
	)
	(segment
		(start 387.59638 -351.611438)
		(end 387.30555 -351.902268)
		(width 0.1651)
		(layer "In13.Cu")
		(net "P5E_PEX3_STN6_TX_C_DN<104>")
	)
	(segment
		(start 376.340878 -386.461)
		(end 387.135878 -391.16)
		(width 0.1651)
		(layer "In13.Cu")
		(net "P5E_PEX3_STN6_TX_C_DN<104>")
	)
	(segment
		(start 390.889998 -410.207968)
		(end 390.889998 -410.589984)
		(width 0.1651)
		(layer "In13.Cu")
		(net "P5E_PEX3_STN6_TX_C_DN<104>")
	)
	(segment
		(start 374.33631 -369.44427)
		(end 373.996712 -373.047006)
		(width 0.1651)
		(layer "In13.Cu")
		(net "P5E_PEX3_STN6_TX_C_DN<104>")
	)
	(segment
		(start 387.30555 -352.473006)
		(end 385.75107 -354.027486)
		(width 0.1651)
		(layer "In13.Cu")
		(net "P5E_PEX3_STN6_TX_C_DN<104>")
	)
	(segment
		(start 385.75107 -358.130094)
		(end 385.028186 -359.71353)
		(width 0.1651)
		(layer "In13.Cu")
		(net "P5E_PEX3_STN6_TX_C_DN<104>")
	)
	(segment
		(start 392.01598 -396.0368)
		(end 392.01598 -409.629102)
		(width 0.1651)
		(layer "In13.Cu")
		(net "P5E_PEX3_STN6_TX_C_DN<104>")
	)
	(segment
		(start 374.857772 -385.398518)
		(end 376.340878 -386.461)
		(width 0.1651)
		(layer "In13.Cu")
		(net "P5E_PEX3_STN6_TX_C_DN<104>")
	)
	(segment
		(start 387.135878 -391.16)
		(end 389.396478 -392.557)
		(width 0.1651)
		(layer "In13.Cu")
		(net "P5E_PEX3_STN6_TX_C_DN<104>")
	)
	(segment
		(start 373.996712 -373.047006)
		(end 374.43664 -384.527298)
		(width 0.1651)
		(layer "In13.Cu")
		(net "P5E_PEX3_STN6_TX_C_DN<104>")
	)
	(segment
		(start 375.52757 -367.95329)
		(end 374.33631 -369.44427)
		(width 0.1651)
		(layer "In13.Cu")
		(net "P5E_PEX3_STN6_TX_C_DN<104>")
	)
	(segment
		(start 385.028186 -359.71353)
		(end 375.52757 -367.95329)
		(width 0.1651)
		(layer "In13.Cu")
		(net "P5E_PEX3_STN6_TX_C_DN<104>")
	)
	(segment
		(start 374.43664 -384.527298)
		(end 374.857772 -385.398518)
		(width 0.1651)
		(layer "In13.Cu")
		(net "P5E_PEX3_STN6_TX_C_DN<104>")
	)
	(segment
		(start 390.392158 -393.576302)
		(end 390.499854 -393.577572)
		(width 0.1651)
		(layer "In13.Cu")
		(net "P5E_PEX3_STN6_TX_C_DN<104>")
	)
	(segment
		(start 391.564114 -410.080968)
		(end 391.016998 -410.080968)
		(width 0.1651)
		(layer "In13.Cu")
		(net "P5E_PEX3_STN6_TX_C_DN<104>")
	)
	(segment
		(start 305.960526 -149.954996)
		(end 305.457606 -149.954996)
		(width 0.13462)
		(layer "F.Cu")
		(net "P5E_PEX2_STN0_TX_C_DP<12>")
	)
	(segment
		(start 311.62371 -150.11908)
		(end 306.12461 -150.11908)
		(width 0.13462)
		(layer "F.Cu")
		(net "P5E_PEX2_STN0_TX_C_DP<12>")
	)
	(segment
		(start 311.95264 -149.79015)
		(end 311.62371 -150.11908)
		(width 0.13462)
		(layer "F.Cu")
		(net "P5E_PEX2_STN0_TX_C_DP<12>")
	)
	(segment
		(start 306.12461 -150.11908)
		(end 305.960526 -149.954996)
		(width 0.13462)
		(layer "F.Cu")
		(net "P5E_PEX2_STN0_TX_C_DP<12>")
	)
	(segment
		(start 387.302248 -345.171014)
		(end 387.59638 -345.465146)
		(width 0.13462)
		(layer "F.Cu")
		(net "P5E_PEX3_STN6_TX_C_DN<96>")
	)
	(segment
		(start 387.62178 -344.219022)
		(end 387.302248 -344.538554)
		(width 0.13462)
		(layer "F.Cu")
		(net "P5E_PEX3_STN6_TX_C_DN<96>")
	)
	(segment
		(start 387.302248 -344.538554)
		(end 387.302248 -345.171014)
		(width 0.13462)
		(layer "F.Cu")
		(net "P5E_PEX3_STN6_TX_C_DN<96>")
	)
	(segment
		(start 391.564114 -384.08102)
		(end 391.016998 -384.08102)
		(width 0.1651)
		(layer "In7.Cu")
		(net "P5E_PEX3_STN6_TX_C_DN<96>")
	)
	(segment
		(start 391.016998 -384.08102)
		(end 390.889998 -384.20802)
		(width 0.1651)
		(layer "In7.Cu")
		(net "P5E_PEX3_STN6_TX_C_DN<96>")
	)
	(segment
		(start 387.30555 -346.326714)
		(end 385.75107 -347.881194)
		(width 0.1651)
		(layer "In7.Cu")
		(net "P5E_PEX3_STN6_TX_C_DN<96>")
	)
	(segment
		(start 390.889998 -384.20802)
		(end 390.889998 -384.590036)
		(width 0.1651)
		(layer "In7.Cu")
		(net "P5E_PEX3_STN6_TX_C_DN<96>")
	)
	(segment
		(start 385.75107 -347.881194)
		(end 385.75107 -358.66578)
		(width 0.1651)
		(layer "In7.Cu")
		(net "P5E_PEX3_STN6_TX_C_DN<96>")
	)
	(segment
		(start 387.59638 -345.465146)
		(end 387.30555 -345.755976)
		(width 0.1651)
		(layer "In7.Cu")
		(net "P5E_PEX3_STN6_TX_C_DN<96>")
	)
	(segment
		(start 385.75107 -358.66578)
		(end 392.01598 -368.86388)
		(width 0.1651)
		(layer "In7.Cu")
		(net "P5E_PEX3_STN6_TX_C_DN<96>")
	)
	(segment
		(start 392.01598 -383.629154)
		(end 391.564114 -384.08102)
		(width 0.1651)
		(layer "In7.Cu")
		(net "P5E_PEX3_STN6_TX_C_DN<96>")
	)
	(segment
		(start 392.01598 -368.86388)
		(end 392.01598 -383.629154)
		(width 0.1651)
		(layer "In7.Cu")
		(net "P5E_PEX3_STN6_TX_C_DN<96>")
	)
	(segment
		(start 387.30555 -345.755976)
		(end 387.30555 -346.326714)
		(width 0.1651)
		(layer "In7.Cu")
		(net "P5E_PEX3_STN6_TX_C_DN<96>")
	)
	(segment
		(start 39.16045 -96.1644)
		(end 39.16045 -97.1804)
		(width 0.13208)
		(layer "F.Cu")
		(net "PRSNTB3_NIC0_N")
	)
	(segment
		(start 42.455084 -97.1804)
		(end 40.367966 -97.1804)
		(width 0.13208)
		(layer "F.Cu")
		(net "PRSNTB3_NIC0_N")
	)
	(segment
		(start 40.367966 -97.1804)
		(end 39.16045 -97.1804)
		(width 0.13208)
		(layer "F.Cu")
		(net "PRSNTB3_NIC0_N")
	)
	(segment
		(start 42.590466 -97.045018)
		(end 42.455084 -97.1804)
		(width 0.13208)
		(layer "F.Cu")
		(net "PRSNTB3_NIC0_N")
	)
	(segment
		(start 46.042326 -97.045018)
		(end 42.590466 -97.045018)
		(width 0.13208)
		(layer "F.Cu")
		(net "PRSNTB3_NIC0_N")
	)
	(via
		(at 40.367966 -97.1804)
		(size 0.762)
		(drill 0.381)
		(layers "F.Cu" "B.Cu")
		(net "PRSNTB3_NIC0_N")
	)
	(segment
		(start 88.664796 -34.390076)
		(end 88.182196 -34.390076)
		(width 0.13462)
		(layer "F.Cu")
		(net "P5E_PEX0_STN2_RX_DP<35>")
	)
	(segment
		(start 88.182196 -34.390076)
		(end 88.019382 -34.227262)
		(width 0.13462)
		(layer "F.Cu")
		(net "P5E_PEX0_STN2_RX_DP<35>")
	)
	(segment
		(start 88.019382 -34.227262)
		(end 85.505544 -34.227262)
		(width 0.13462)
		(layer "F.Cu")
		(net "P5E_PEX0_STN2_RX_DP<35>")
	)
	(segment
		(start 85.505544 -34.227262)
		(end 85.210396 -34.52241)
		(width 0.13462)
		(layer "F.Cu")
		(net "P5E_PEX0_STN2_RX_DP<35>")
	)
	(segment
		(start 86.650322 -39.604696)
		(end 86.63178 -38.33495)
		(width 0.1651)
		(layer "In7.Cu")
		(net "P5E_PEX0_STN2_RX_DP<35>")
	)
	(segment
		(start 85.979 -34.23158)
		(end 85.626956 -34.23158)
		(width 0.1651)
		(layer "In7.Cu")
		(net "P5E_PEX0_STN2_RX_DP<35>")
	)
	(segment
		(start 85.412326 -34.32048)
		(end 85.210396 -34.52241)
		(width 0.1651)
		(layer "In7.Cu")
		(net "P5E_PEX0_STN2_RX_DP<35>")
	)
	(segment
		(start 86.63178 -38.33495)
		(end 86.515702 -38.222174)
		(width 0.1651)
		(layer "In7.Cu")
		(net "P5E_PEX0_STN2_RX_DP<35>")
	)
	(segment
		(start 55.735474 -273.670014)
		(end 55.541926 -273.670014)
		(width 0.1143)
		(layer "In7.Cu")
		(net "P5E_PEX0_STN2_RX_DP<35>")
	)
	(segment
		(start 86.508336 -37.72662)
		(end 86.620858 -37.610796)
		(width 0.1651)
		(layer "In7.Cu")
		(net "P5E_PEX0_STN2_RX_DP<35>")
	)
	(segment
		(start 86.603078 -36.391596)
		(end 86.580472 -34.833306)
		(width 0.1651)
		(layer "In7.Cu")
		(net "P5E_PEX0_STN2_RX_DP<35>")
	)
	(segment
		(start 55.849774 -273.784314)
		(end 55.735474 -273.670014)
		(width 0.1143)
		(layer "In7.Cu")
		(net "P5E_PEX0_STN2_RX_DP<35>")
	)
	(segment
		(start 55.279544 -271.41932)
		(end 55.233824 -271.3736)
		(width 0.1143)
		(layer "In7.Cu")
		(net "P5E_PEX0_STN2_RX_DP<35>")
	)
	(segment
		(start 55.233824 -271.345152)
		(end 55.233824 -270.499332)
		(width 0.1651)
		(layer "In7.Cu")
		(net "P5E_PEX0_STN2_RX_DP<35>")
	)
	(segment
		(start 86.515702 -38.222174)
		(end 86.508336 -37.72662)
		(width 0.1651)
		(layer "In7.Cu")
		(net "P5E_PEX0_STN2_RX_DP<35>")
	)
	(segment
		(start 86.620858 -37.610796)
		(end 86.613746 -37.11575)
		(width 0.1651)
		(layer "In7.Cu")
		(net "P5E_PEX0_STN2_RX_DP<35>")
	)
	(segment
		(start 55.560722 -266.721844)
		(end 75.12812 -154.366976)
		(width 0.1651)
		(layer "In7.Cu")
		(net "P5E_PEX0_STN2_RX_DP<35>")
	)
	(segment
		(start 87.807292 -61.097668)
		(end 87.98814 -49.507648)
		(width 0.1651)
		(layer "In7.Cu")
		(net "P5E_PEX0_STN2_RX_DP<35>")
	)
	(segment
		(start 55.233824 -270.499332)
		(end 55.560722 -266.721844)
		(width 0.1651)
		(layer "In7.Cu")
		(net "P5E_PEX0_STN2_RX_DP<35>")
	)
	(segment
		(start 55.279544 -273.407632)
		(end 55.279544 -271.41932)
		(width 0.1143)
		(layer "In7.Cu")
		(net "P5E_PEX0_STN2_RX_DP<35>")
	)
	(segment
		(start 76.82103 -116.47424)
		(end 87.807292 -61.097668)
		(width 0.1651)
		(layer "In7.Cu")
		(net "P5E_PEX0_STN2_RX_DP<35>")
	)
	(segment
		(start 76.505308 -143.663162)
		(end 76.82103 -116.47424)
		(width 0.1651)
		(layer "In7.Cu")
		(net "P5E_PEX0_STN2_RX_DP<35>")
	)
	(segment
		(start 85.626956 -34.23158)
		(end 85.412326 -34.32048)
		(width 0.1651)
		(layer "In7.Cu")
		(net "P5E_PEX0_STN2_RX_DP<35>")
	)
	(segment
		(start 55.541926 -273.670014)
		(end 55.279544 -273.407632)
		(width 0.1143)
		(layer "In7.Cu")
		(net "P5E_PEX0_STN2_RX_DP<35>")
	)
	(segment
		(start 86.497668 -37.002974)
		(end 86.490302 -36.507674)
		(width 0.1651)
		(layer "In7.Cu")
		(net "P5E_PEX0_STN2_RX_DP<35>")
	)
	(segment
		(start 86.613746 -37.11575)
		(end 86.497668 -37.002974)
		(width 0.1651)
		(layer "In7.Cu")
		(net "P5E_PEX0_STN2_RX_DP<35>")
	)
	(segment
		(start 55.233824 -271.3736)
		(end 55.233824 -271.345152)
		(width 0.1143)
		(layer "In7.Cu")
		(net "P5E_PEX0_STN2_RX_DP<35>")
	)
	(segment
		(start 87.98814 -49.507648)
		(end 86.650322 -39.604696)
		(width 0.1651)
		(layer "In7.Cu")
		(net "P5E_PEX0_STN2_RX_DP<35>")
	)
	(segment
		(start 55.849774 -274.049744)
		(end 55.849774 -273.784314)
		(width 0.1143)
		(layer "In7.Cu")
		(net "P5E_PEX0_STN2_RX_DP<35>")
	)
	(segment
		(start 86.580472 -34.833306)
		(end 85.979 -34.23158)
		(width 0.1651)
		(layer "In7.Cu")
		(net "P5E_PEX0_STN2_RX_DP<35>")
	)
	(segment
		(start 75.12812 -154.366976)
		(end 76.505308 -143.663162)
		(width 0.1651)
		(layer "In7.Cu")
		(net "P5E_PEX0_STN2_RX_DP<35>")
	)
	(segment
		(start 86.490302 -36.507674)
		(end 86.603078 -36.391596)
		(width 0.1651)
		(layer "In7.Cu")
		(net "P5E_PEX0_STN2_RX_DP<35>")
	)
	(segment
		(start 300.206664 -119.004842)
		(end 299.558456 -119.004842)
		(width 0.13462)
		(layer "F.Cu")
		(net "P5E_PEX2_STN0_RX_DN<0>")
	)
	(segment
		(start 300.37659 -118.834916)
		(end 300.206664 -119.004842)
		(width 0.13462)
		(layer "F.Cu")
		(net "P5E_PEX2_STN0_RX_DN<0>")
	)
	(segment
		(start 299.558456 -119.004842)
		(end 299.257212 -118.703598)
		(width 0.13462)
		(layer "F.Cu")
		(net "P5E_PEX2_STN0_RX_DN<0>")
	)
	(segment
		(start 300.857412 -118.834916)
		(end 300.37659 -118.834916)
		(width 0.13462)
		(layer "F.Cu")
		(net "P5E_PEX2_STN0_RX_DN<0>")
	)
	(segment
		(start 317.5889 -130.84302)
		(end 306.39258 -122.49404)
		(width 0.1651)
		(layer "In5.Cu")
		(net "P5E_PEX2_STN0_RX_DN<0>")
	)
	(segment
		(start 329.040744 -278.399748)
		(end 331.68844 -273.725132)
		(width 0.1651)
		(layer "In5.Cu")
		(net "P5E_PEX2_STN0_RX_DN<0>")
	)
	(segment
		(start 312.484262 -288.299906)
		(end 312.369962 -288.185606)
		(width 0.1143)
		(layer "In5.Cu")
		(net "P5E_PEX2_STN0_RX_DN<0>")
	)
	(segment
		(start 322.305934 -168.524174)
		(end 321.853306 -149.82825)
		(width 0.1651)
		(layer "In5.Cu")
		(net "P5E_PEX2_STN0_RX_DN<0>")
	)
	(segment
		(start 331.68844 -273.725132)
		(end 331.874368 -269.124938)
		(width 0.1651)
		(layer "In5.Cu")
		(net "P5E_PEX2_STN0_RX_DN<0>")
	)
	(segment
		(start 312.749692 -288.299906)
		(end 312.484262 -288.299906)
		(width 0.1143)
		(layer "In5.Cu")
		(net "P5E_PEX2_STN0_RX_DN<0>")
	)
	(segment
		(start 312.50255 -287.920176)
		(end 316.050422 -287.920176)
		(width 0.1143)
		(layer "In5.Cu")
		(net "P5E_PEX2_STN0_RX_DN<0>")
	)
	(segment
		(start 304.86858 -120.97512)
		(end 300.082966 -118.994428)
		(width 0.1651)
		(layer "In5.Cu")
		(net "P5E_PEX2_STN0_RX_DN<0>")
	)
	(segment
		(start 318.376046 -131.877562)
		(end 317.5889 -130.84302)
		(width 0.1651)
		(layer "In5.Cu")
		(net "P5E_PEX2_STN0_RX_DN<0>")
	)
	(segment
		(start 312.369962 -288.052764)
		(end 312.50255 -287.920176)
		(width 0.1143)
		(layer "In5.Cu")
		(net "P5E_PEX2_STN0_RX_DN<0>")
	)
	(segment
		(start 321.639692 -231.87533)
		(end 322.305934 -168.524174)
		(width 0.1651)
		(layer "In5.Cu")
		(net "P5E_PEX2_STN0_RX_DN<0>")
	)
	(segment
		(start 300.082966 -118.994428)
		(end 299.548042 -118.994428)
		(width 0.1651)
		(layer "In5.Cu")
		(net "P5E_PEX2_STN0_RX_DN<0>")
	)
	(segment
		(start 306.39258 -122.49404)
		(end 304.86858 -120.97512)
		(width 0.1651)
		(layer "In5.Cu")
		(net "P5E_PEX2_STN0_RX_DN<0>")
	)
	(segment
		(start 319.934336 -287.19272)
		(end 329.040744 -278.399748)
		(width 0.1651)
		(layer "In5.Cu")
		(net "P5E_PEX2_STN0_RX_DN<0>")
	)
	(segment
		(start 299.548042 -118.994428)
		(end 299.257212 -118.703598)
		(width 0.1651)
		(layer "In5.Cu")
		(net "P5E_PEX2_STN0_RX_DN<0>")
	)
	(segment
		(start 321.455796 -145.583656)
		(end 318.376046 -131.877562)
		(width 0.1651)
		(layer "In5.Cu")
		(net "P5E_PEX2_STN0_RX_DN<0>")
	)
	(segment
		(start 312.369962 -288.185606)
		(end 312.369962 -288.052764)
		(width 0.1143)
		(layer "In5.Cu")
		(net "P5E_PEX2_STN0_RX_DN<0>")
	)
	(segment
		(start 316.12459 -287.965896)
		(end 318.708786 -287.965896)
		(width 0.1651)
		(layer "In5.Cu")
		(net "P5E_PEX2_STN0_RX_DN<0>")
	)
	(segment
		(start 321.853306 -149.82825)
		(end 321.455796 -145.583656)
		(width 0.1651)
		(layer "In5.Cu")
		(net "P5E_PEX2_STN0_RX_DN<0>")
	)
	(segment
		(start 331.874368 -269.124938)
		(end 323.166994 -239.218724)
		(width 0.1651)
		(layer "In5.Cu")
		(net "P5E_PEX2_STN0_RX_DN<0>")
	)
	(segment
		(start 323.166994 -239.218724)
		(end 321.639692 -231.87533)
		(width 0.1651)
		(layer "In5.Cu")
		(net "P5E_PEX2_STN0_RX_DN<0>")
	)
	(segment
		(start 316.096142 -287.965896)
		(end 316.12459 -287.965896)
		(width 0.1143)
		(layer "In5.Cu")
		(net "P5E_PEX2_STN0_RX_DN<0>")
	)
	(segment
		(start 316.050422 -287.920176)
		(end 316.096142 -287.965896)
		(width 0.1143)
		(layer "In5.Cu")
		(net "P5E_PEX2_STN0_RX_DN<0>")
	)
	(segment
		(start 318.708786 -287.965896)
		(end 319.934336 -287.19272)
		(width 0.1651)
		(layer "In5.Cu")
		(net "P5E_PEX2_STN0_RX_DN<0>")
	)
	(segment
		(start 386.70738 -344.219022)
		(end 387.027928 -344.53957)
		(width 0.13462)
		(layer "F.Cu")
		(net "P5E_PEX3_STN6_TX_C_DP<96>")
	)
	(segment
		(start 387.027928 -345.169998)
		(end 386.73278 -345.465146)
		(width 0.13462)
		(layer "F.Cu")
		(net "P5E_PEX3_STN6_TX_C_DP<96>")
	)
	(segment
		(start 387.027928 -344.53957)
		(end 387.027928 -345.169998)
		(width 0.13462)
		(layer "F.Cu")
		(net "P5E_PEX3_STN6_TX_C_DP<96>")
	)
	(segment
		(start 390.55421 -367.023142)
		(end 391.73404 -368.943636)
		(width 0.1651)
		(layer "In7.Cu")
		(net "P5E_PEX3_STN6_TX_C_DP<96>")
	)
	(segment
		(start 391.447274 -383.79908)
		(end 391.016998 -383.79908)
		(width 0.1651)
		(layer "In7.Cu")
		(net "P5E_PEX3_STN6_TX_C_DP<96>")
	)
	(segment
		(start 391.73404 -383.512314)
		(end 391.447274 -383.79908)
		(width 0.1651)
		(layer "In7.Cu")
		(net "P5E_PEX3_STN6_TX_C_DP<96>")
	)
	(segment
		(start 390.889998 -383.67208)
		(end 390.889998 -383.290064)
		(width 0.1651)
		(layer "In7.Cu")
		(net "P5E_PEX3_STN6_TX_C_DP<96>")
	)
	(segment
		(start 390.137396 -366.563148)
		(end 390.396984 -366.98555)
		(width 0.1651)
		(layer "In7.Cu")
		(net "P5E_PEX3_STN6_TX_C_DP<96>")
	)
	(segment
		(start 387.02361 -345.755976)
		(end 387.02361 -346.209874)
		(width 0.1651)
		(layer "In7.Cu")
		(net "P5E_PEX3_STN6_TX_C_DP<96>")
	)
	(segment
		(start 387.02361 -346.209874)
		(end 385.46913 -347.764354)
		(width 0.1651)
		(layer "In7.Cu")
		(net "P5E_PEX3_STN6_TX_C_DP<96>")
	)
	(segment
		(start 391.016998 -383.79908)
		(end 390.889998 -383.67208)
		(width 0.1651)
		(layer "In7.Cu")
		(net "P5E_PEX3_STN6_TX_C_DP<96>")
	)
	(segment
		(start 385.46913 -358.745536)
		(end 390.174988 -366.405922)
		(width 0.1651)
		(layer "In7.Cu")
		(net "P5E_PEX3_STN6_TX_C_DP<96>")
	)
	(segment
		(start 391.73404 -368.943636)
		(end 391.73404 -383.512314)
		(width 0.1651)
		(layer "In7.Cu")
		(net "P5E_PEX3_STN6_TX_C_DP<96>")
	)
	(segment
		(start 390.174988 -366.405922)
		(end 390.137396 -366.563148)
		(width 0.1651)
		(layer "In7.Cu")
		(net "P5E_PEX3_STN6_TX_C_DP<96>")
	)
	(segment
		(start 385.46913 -347.764354)
		(end 385.46913 -358.745536)
		(width 0.1651)
		(layer "In7.Cu")
		(net "P5E_PEX3_STN6_TX_C_DP<96>")
	)
	(segment
		(start 386.73278 -345.465146)
		(end 387.02361 -345.755976)
		(width 0.1651)
		(layer "In7.Cu")
		(net "P5E_PEX3_STN6_TX_C_DP<96>")
	)
	(segment
		(start 390.396984 -366.98555)
		(end 390.55421 -367.023142)
		(width 0.1651)
		(layer "In7.Cu")
		(net "P5E_PEX3_STN6_TX_C_DP<96>")
	)
	(segment
		(start 43.979084 -156.560012)
		(end 42.806366 -157.73273)
		(width 0.13208)
		(layer "F.Cu")
		(net "NIC0_DATA_IN")
	)
	(segment
		(start 46.042326 -156.560012)
		(end 43.979084 -156.560012)
		(width 0.13208)
		(layer "F.Cu")
		(net "NIC0_DATA_IN")
	)
	(segment
		(start 40.040814 -157.3784)
		(end 39.00805 -157.3784)
		(width 0.13208)
		(layer "F.Cu")
		(net "NIC0_DATA_IN")
	)
	(segment
		(start 40.400224 -157.73273)
		(end 40.397684 -157.73527)
		(width 0.13208)
		(layer "F.Cu")
		(net "NIC0_DATA_IN")
	)
	(segment
		(start 40.397684 -157.73527)
		(end 40.040814 -157.3784)
		(width 0.13208)
		(layer "F.Cu")
		(net "NIC0_DATA_IN")
	)
	(segment
		(start 42.806366 -157.73273)
		(end 40.400224 -157.73273)
		(width 0.13208)
		(layer "F.Cu")
		(net "NIC0_DATA_IN")
	)
	(via
		(at 40.397684 -157.73527)
		(size 0.762)
		(drill 0.381)
		(layers "F.Cu" "B.Cu")
		(net "NIC0_DATA_IN")
	)
	(segment
		(start 9.358122 -28.829)
		(end 9.064752 -29.12237)
		(width 0.13462)
		(layer "F.Cu")
		(net "P5E_PEX0_STN2_RX_DP<44>")
	)
	(segment
		(start 10.024618 -28.829)
		(end 9.358122 -28.829)
		(width 0.13462)
		(layer "F.Cu")
		(net "P5E_PEX0_STN2_RX_DP<44>")
	)
	(segment
		(start 10.664952 -28.99029)
		(end 10.185908 -28.99029)
		(width 0.13462)
		(layer "F.Cu")
		(net "P5E_PEX0_STN2_RX_DP<44>")
	)
	(segment
		(start 10.185908 -28.99029)
		(end 10.024618 -28.829)
		(width 0.13462)
		(layer "F.Cu")
		(net "P5E_PEX0_STN2_RX_DP<44>")
	)
	(segment
		(start 10.664952 -28.990036)
		(end 10.664952 -28.99029)
		(width 0.13462)
		(layer "F.Cu")
		(net "P5E_PEX0_STN2_RX_DP<44>")
	)
	(segment
		(start 11.160252 -30.634432)
		(end 12.704318 -32.178498)
		(width 0.1651)
		(layer "In7.Cu")
		(net "P5E_PEX0_STN2_RX_DP<44>")
	)
	(segment
		(start 10.496042 -29.64053)
		(end 11.160252 -30.634432)
		(width 0.1651)
		(layer "In7.Cu")
		(net "P5E_PEX0_STN2_RX_DP<44>")
	)
	(segment
		(start 13.089636 -33.354772)
		(end 13.222732 -33.408874)
		(width 0.1651)
		(layer "In7.Cu")
		(net "P5E_PEX0_STN2_RX_DP<44>")
	)
	(segment
		(start 13.024866 -61.849762)
		(end 12.835382 -85.214206)
		(width 0.1651)
		(layer "In7.Cu")
		(net "P5E_PEX0_STN2_RX_DP<44>")
	)
	(segment
		(start 9.419844 -28.83154)
		(end 9.687052 -28.83154)
		(width 0.1651)
		(layer "In7.Cu")
		(net "P5E_PEX0_STN2_RX_DP<44>")
	)
	(segment
		(start 12.704318 -32.178498)
		(end 12.951206 -32.764984)
		(width 0.1651)
		(layer "In7.Cu")
		(net "P5E_PEX0_STN2_RX_DP<44>")
	)
	(segment
		(start 12.835382 -85.214206)
		(end 23.200106 -119.40921)
		(width 0.1651)
		(layer "In7.Cu")
		(net "P5E_PEX0_STN2_RX_DP<44>")
	)
	(segment
		(start 13.553186 -34.454846)
		(end 13.686282 -34.509202)
		(width 0.1651)
		(layer "In7.Cu")
		(net "P5E_PEX0_STN2_RX_DP<44>")
	)
	(segment
		(start 9.064752 -29.12237)
		(end 9.310116 -28.877006)
		(width 0.1651)
		(layer "In7.Cu")
		(net "P5E_PEX0_STN2_RX_DP<44>")
	)
	(segment
		(start 12.87907 -49.388014)
		(end 12.755118 -57.335674)
		(width 0.1651)
		(layer "In7.Cu")
		(net "P5E_PEX0_STN2_RX_DP<44>")
	)
	(segment
		(start 26.48712 -144.398238)
		(end 44.201588 -238.07547)
		(width 0.1651)
		(layer "In7.Cu")
		(net "P5E_PEX0_STN2_RX_DP<44>")
	)
	(segment
		(start 47.29988 -275.684488)
		(end 47.29988 -275.949918)
		(width 0.1143)
		(layer "In7.Cu")
		(net "P5E_PEX0_STN2_RX_DP<44>")
	)
	(segment
		(start 13.360654 -33.998154)
		(end 13.553186 -34.454846)
		(width 0.1651)
		(layer "In7.Cu")
		(net "P5E_PEX0_STN2_RX_DP<44>")
	)
	(segment
		(start 45.730668 -263.48055)
		(end 46.683676 -269.523718)
		(width 0.1651)
		(layer "In7.Cu")
		(net "P5E_PEX0_STN2_RX_DP<44>")
	)
	(segment
		(start 13.222732 -33.408874)
		(end 13.41501 -33.865312)
		(width 0.1651)
		(layer "In7.Cu")
		(net "P5E_PEX0_STN2_RX_DP<44>")
	)
	(segment
		(start 23.200106 -119.40921)
		(end 26.48712 -144.398238)
		(width 0.1651)
		(layer "In7.Cu")
		(net "P5E_PEX0_STN2_RX_DP<44>")
	)
	(segment
		(start 45.80763 -255.61925)
		(end 45.730668 -263.48055)
		(width 0.1651)
		(layer "In7.Cu")
		(net "P5E_PEX0_STN2_RX_DP<44>")
	)
	(segment
		(start 12.755118 -57.335674)
		(end 13.024866 -60.073794)
		(width 0.1651)
		(layer "In7.Cu")
		(net "P5E_PEX0_STN2_RX_DP<44>")
	)
	(segment
		(start 12.951206 -32.764984)
		(end 12.897104 -32.89808)
		(width 0.1651)
		(layer "In7.Cu")
		(net "P5E_PEX0_STN2_RX_DP<44>")
	)
	(segment
		(start 46.729396 -275.354796)
		(end 46.944788 -275.570188)
		(width 0.1143)
		(layer "In7.Cu")
		(net "P5E_PEX0_STN2_RX_DP<44>")
	)
	(segment
		(start 12.897104 -32.89808)
		(end 13.089636 -33.354772)
		(width 0.1651)
		(layer "In7.Cu")
		(net "P5E_PEX0_STN2_RX_DP<44>")
	)
	(segment
		(start 9.687052 -28.83154)
		(end 10.496042 -29.64053)
		(width 0.1651)
		(layer "In7.Cu")
		(net "P5E_PEX0_STN2_RX_DP<44>")
	)
	(segment
		(start 13.024866 -60.073794)
		(end 13.024866 -61.849762)
		(width 0.1651)
		(layer "In7.Cu")
		(net "P5E_PEX0_STN2_RX_DP<44>")
	)
	(segment
		(start 9.310116 -28.877006)
		(end 9.419844 -28.83154)
		(width 0.1651)
		(layer "In7.Cu")
		(net "P5E_PEX0_STN2_RX_DP<44>")
	)
	(segment
		(start 46.944788 -275.570188)
		(end 47.18558 -275.570188)
		(width 0.1143)
		(layer "In7.Cu")
		(net "P5E_PEX0_STN2_RX_DP<44>")
	)
	(segment
		(start 46.683676 -271.421352)
		(end 46.729396 -271.467072)
		(width 0.1143)
		(layer "In7.Cu")
		(net "P5E_PEX0_STN2_RX_DP<44>")
	)
	(segment
		(start 15.048484 -37.742622)
		(end 15.025116 -39.137844)
		(width 0.1651)
		(layer "In7.Cu")
		(net "P5E_PEX0_STN2_RX_DP<44>")
	)
	(segment
		(start 44.201588 -238.07547)
		(end 45.80763 -255.61925)
		(width 0.1651)
		(layer "In7.Cu")
		(net "P5E_PEX0_STN2_RX_DP<44>")
	)
	(segment
		(start 47.18558 -275.570188)
		(end 47.29988 -275.684488)
		(width 0.1143)
		(layer "In7.Cu")
		(net "P5E_PEX0_STN2_RX_DP<44>")
	)
	(segment
		(start 13.41501 -33.865312)
		(end 13.360654 -33.998154)
		(width 0.1651)
		(layer "In7.Cu")
		(net "P5E_PEX0_STN2_RX_DP<44>")
	)
	(segment
		(start 13.686282 -34.509202)
		(end 15.048484 -37.742622)
		(width 0.1651)
		(layer "In7.Cu")
		(net "P5E_PEX0_STN2_RX_DP<44>")
	)
	(segment
		(start 15.025116 -39.137844)
		(end 12.87907 -49.388014)
		(width 0.1651)
		(layer "In7.Cu")
		(net "P5E_PEX0_STN2_RX_DP<44>")
	)
	(segment
		(start 46.683676 -271.392904)
		(end 46.683676 -271.421352)
		(width 0.1143)
		(layer "In7.Cu")
		(net "P5E_PEX0_STN2_RX_DP<44>")
	)
	(segment
		(start 46.729396 -271.467072)
		(end 46.729396 -275.354796)
		(width 0.1143)
		(layer "In7.Cu")
		(net "P5E_PEX0_STN2_RX_DP<44>")
	)
	(segment
		(start 46.683676 -269.523718)
		(end 46.683676 -271.392904)
		(width 0.1651)
		(layer "In7.Cu")
		(net "P5E_PEX0_STN2_RX_DP<44>")
	)
	(segment
		(start 306.110894 -153.70048)
		(end 305.965352 -153.554938)
		(width 0.13462)
		(layer "F.Cu")
		(net "P5E_PEX2_STN0_TX_C_DP<14>")
	)
	(segment
		(start 305.965352 -153.554938)
		(end 305.457606 -153.554938)
		(width 0.13462)
		(layer "F.Cu")
		(net "P5E_PEX2_STN0_TX_C_DP<14>")
	)
	(segment
		(start 311.642506 -153.70048)
		(end 306.110894 -153.70048)
		(width 0.13462)
		(layer "F.Cu")
		(net "P5E_PEX2_STN0_TX_C_DP<14>")
	)
	(segment
		(start 311.95264 -153.390346)
		(end 311.642506 -153.70048)
		(width 0.13462)
		(layer "F.Cu")
		(net "P5E_PEX2_STN0_TX_C_DP<14>")
	)
	(segment
		(start 270.980662 -344.219022)
		(end 271.300702 -344.539062)
		(width 0.13462)
		(layer "F.Cu")
		(net "P5E_PEX2_STN7_TX_C_DP<113>")
	)
	(segment
		(start 271.300702 -344.539062)
		(end 271.300702 -345.170506)
		(width 0.13462)
		(layer "F.Cu")
		(net "P5E_PEX2_STN7_TX_C_DP<113>")
	)
	(segment
		(start 271.300702 -345.170506)
		(end 271.006062 -345.465146)
		(width 0.13462)
		(layer "F.Cu")
		(net "P5E_PEX2_STN7_TX_C_DP<113>")
	)
	(segment
		(start 271.006062 -345.465146)
		(end 271.296892 -345.755976)
		(width 0.1651)
		(layer "In7.Cu")
		(net "P5E_PEX2_STN7_TX_C_DP<113>")
	)
	(segment
		(start 289.775392 -394.643102)
		(end 289.901122 -394.643102)
		(width 0.1651)
		(layer "In7.Cu")
		(net "P5E_PEX2_STN7_TX_C_DP<113>")
	)
	(segment
		(start 289.901122 -394.643102)
		(end 290.251134 -394.993114)
		(width 0.1651)
		(layer "In7.Cu")
		(net "P5E_PEX2_STN7_TX_C_DP<113>")
	)
	(segment
		(start 271.296892 -346.209874)
		(end 269.742412 -347.764354)
		(width 0.1651)
		(layer "In7.Cu")
		(net "P5E_PEX2_STN7_TX_C_DP<113>")
	)
	(segment
		(start 290.533836 -401.71243)
		(end 290.24707 -401.999196)
		(width 0.1651)
		(layer "In7.Cu")
		(net "P5E_PEX2_STN7_TX_C_DP<113>")
	)
	(segment
		(start 278.444452 -374.946418)
		(end 280.596594 -386.7404)
		(width 0.1651)
		(layer "In7.Cu")
		(net "P5E_PEX2_STN7_TX_C_DP<113>")
	)
	(segment
		(start 289.816794 -401.999196)
		(end 289.689794 -401.872196)
		(width 0.1651)
		(layer "In7.Cu")
		(net "P5E_PEX2_STN7_TX_C_DP<113>")
	)
	(segment
		(start 283.882846 -390.947148)
		(end 286.60344 -392.350752)
		(width 0.1651)
		(layer "In7.Cu")
		(net "P5E_PEX2_STN7_TX_C_DP<113>")
	)
	(segment
		(start 290.533836 -395.901926)
		(end 290.533836 -401.71243)
		(width 0.1651)
		(layer "In7.Cu")
		(net "P5E_PEX2_STN7_TX_C_DP<113>")
	)
	(segment
		(start 289.424872 -394.166852)
		(end 289.424872 -394.292582)
		(width 0.1651)
		(layer "In7.Cu")
		(net "P5E_PEX2_STN7_TX_C_DP<113>")
	)
	(segment
		(start 287.642046 -392.886438)
		(end 287.680146 -393.006326)
		(width 0.1651)
		(layer "In7.Cu")
		(net "P5E_PEX2_STN7_TX_C_DP<113>")
	)
	(segment
		(start 290.24707 -401.999196)
		(end 289.816794 -401.999196)
		(width 0.1651)
		(layer "In7.Cu")
		(net "P5E_PEX2_STN7_TX_C_DP<113>")
	)
	(segment
		(start 269.742412 -347.764354)
		(end 269.742412 -358.43845)
		(width 0.1651)
		(layer "In7.Cu")
		(net "P5E_PEX2_STN7_TX_C_DP<113>")
	)
	(segment
		(start 280.596594 -386.7404)
		(end 281.3939 -388.66572)
		(width 0.1651)
		(layer "In7.Cu")
		(net "P5E_PEX2_STN7_TX_C_DP<113>")
	)
	(segment
		(start 287.08223 -392.697716)
		(end 287.202118 -392.659362)
		(width 0.1651)
		(layer "In7.Cu")
		(net "P5E_PEX2_STN7_TX_C_DP<113>")
	)
	(segment
		(start 289.424872 -394.292582)
		(end 289.775392 -394.643102)
		(width 0.1651)
		(layer "In7.Cu")
		(net "P5E_PEX2_STN7_TX_C_DP<113>")
	)
	(segment
		(start 287.680146 -393.006326)
		(end 288.120582 -393.233656)
		(width 0.1651)
		(layer "In7.Cu")
		(net "P5E_PEX2_STN7_TX_C_DP<113>")
	)
	(segment
		(start 288.24047 -393.195302)
		(end 288.680398 -393.422378)
		(width 0.1651)
		(layer "In7.Cu")
		(net "P5E_PEX2_STN7_TX_C_DP<113>")
	)
	(segment
		(start 281.3939 -388.66572)
		(end 283.882846 -390.947148)
		(width 0.1651)
		(layer "In7.Cu")
		(net "P5E_PEX2_STN7_TX_C_DP<113>")
	)
	(segment
		(start 287.202118 -392.659362)
		(end 287.642046 -392.886438)
		(width 0.1651)
		(layer "In7.Cu")
		(net "P5E_PEX2_STN7_TX_C_DP<113>")
	)
	(segment
		(start 289.689794 -401.872196)
		(end 289.689794 -401.49018)
		(width 0.1651)
		(layer "In7.Cu")
		(net "P5E_PEX2_STN7_TX_C_DP<113>")
	)
	(segment
		(start 288.120582 -393.233656)
		(end 288.24047 -393.195302)
		(width 0.1651)
		(layer "In7.Cu")
		(net "P5E_PEX2_STN7_TX_C_DP<113>")
	)
	(segment
		(start 286.60344 -392.350752)
		(end 286.641794 -392.470386)
		(width 0.1651)
		(layer "In7.Cu")
		(net "P5E_PEX2_STN7_TX_C_DP<113>")
	)
	(segment
		(start 286.641794 -392.470386)
		(end 287.08223 -392.697716)
		(width 0.1651)
		(layer "In7.Cu")
		(net "P5E_PEX2_STN7_TX_C_DP<113>")
	)
	(segment
		(start 269.742412 -358.43845)
		(end 278.444452 -374.946418)
		(width 0.1651)
		(layer "In7.Cu")
		(net "P5E_PEX2_STN7_TX_C_DP<113>")
	)
	(segment
		(start 271.296892 -345.755976)
		(end 271.296892 -346.209874)
		(width 0.1651)
		(layer "In7.Cu")
		(net "P5E_PEX2_STN7_TX_C_DP<113>")
	)
	(segment
		(start 290.251134 -394.993114)
		(end 290.533836 -395.901926)
		(width 0.1651)
		(layer "In7.Cu")
		(net "P5E_PEX2_STN7_TX_C_DP<113>")
	)
	(segment
		(start 288.680398 -393.422378)
		(end 289.424872 -394.166852)
		(width 0.1651)
		(layer "In7.Cu")
		(net "P5E_PEX2_STN7_TX_C_DP<113>")
	)
	(segment
		(start 395.415008 -327.282048)
		(end 397.61541 -323.736462)
		(width 0.1651)
		(layer "In15.Cu")
		(net "P5E_PEX3_STN6_RX_DN<104>")
	)
	(segment
		(start 390.889998 -402.790152)
		(end 390.889998 -402.408136)
		(width 0.1651)
		(layer "In15.Cu")
		(net "P5E_PEX3_STN6_RX_DN<104>")
	)
	(segment
		(start 374.647206 -384.962908)
		(end 374.43664 -384.527298)
		(width 0.1651)
		(layer "In15.Cu")
		(net "P5E_PEX3_STN6_RX_DN<104>")
	)
	(segment
		(start 387.591046 -391.35812)
		(end 376.340878 -386.461)
		(width 0.1651)
		(layer "In15.Cu")
		(net "P5E_PEX3_STN6_RX_DN<104>")
	)
	(segment
		(start 374.946672 -368.592862)
		(end 382.242822 -359.17886)
		(width 0.1651)
		(layer "In15.Cu")
		(net "P5E_PEX3_STN6_RX_DN<104>")
	)
	(segment
		(start 382.64211 -342.173814)
		(end 383.231644 -340.81974)
		(width 0.1651)
		(layer "In15.Cu")
		(net "P5E_PEX3_STN6_RX_DN<104>")
	)
	(segment
		(start 392.01598 -401.82927)
		(end 392.01598 -396.0368)
		(width 0.1651)
		(layer "In15.Cu")
		(net "P5E_PEX3_STN6_RX_DN<104>")
	)
	(segment
		(start 393.215876 -329.398376)
		(end 395.415008 -327.282048)
		(width 0.1651)
		(layer "In15.Cu")
		(net "P5E_PEX3_STN6_RX_DN<104>")
	)
	(segment
		(start 398.07007 -319.921128)
		(end 398.07007 -318.423798)
		(width 0.1143)
		(layer "In15.Cu")
		(net "P5E_PEX3_STN6_RX_DN<104>")
	)
	(segment
		(start 376.340878 -386.461)
		(end 374.857772 -385.398264)
		(width 0.1651)
		(layer "In15.Cu")
		(net "P5E_PEX3_STN6_RX_DN<104>")
	)
	(segment
		(start 388.656576 -392.016742)
		(end 387.591046 -391.35812)
		(width 0.1651)
		(layer "In15.Cu")
		(net "P5E_PEX3_STN6_RX_DN<104>")
	)
	(segment
		(start 374.646952 -384.963162)
		(end 374.647206 -384.962908)
		(width 0.1651)
		(layer "In15.Cu")
		(net "P5E_PEX3_STN6_RX_DN<104>")
	)
	(segment
		(start 391.564114 -402.281136)
		(end 392.01598 -401.82927)
		(width 0.1651)
		(layer "In15.Cu")
		(net "P5E_PEX3_STN6_RX_DN<104>")
	)
	(segment
		(start 374.520206 -369.506246)
		(end 374.946672 -368.592862)
		(width 0.1651)
		(layer "In15.Cu")
		(net "P5E_PEX3_STN6_RX_DN<104>")
	)
	(segment
		(start 398.3355 -318.320166)
		(end 398.4498 -318.434466)
		(width 0.1143)
		(layer "In15.Cu")
		(net "P5E_PEX3_STN6_RX_DN<104>")
	)
	(segment
		(start 398.11579 -319.995296)
		(end 398.11579 -319.966848)
		(width 0.1143)
		(layer "In15.Cu")
		(net "P5E_PEX3_STN6_RX_DN<104>")
	)
	(segment
		(start 373.996712 -373.047006)
		(end 374.1547 -371.374162)
		(width 0.1651)
		(layer "In15.Cu")
		(net "P5E_PEX3_STN6_RX_DN<104>")
	)
	(segment
		(start 382.242822 -359.17886)
		(end 382.64211 -358.011984)
		(width 0.1651)
		(layer "In15.Cu")
		(net "P5E_PEX3_STN6_RX_DN<104>")
	)
	(segment
		(start 398.173702 -318.320166)
		(end 398.3355 -318.320166)
		(width 0.1143)
		(layer "In15.Cu")
		(net "P5E_PEX3_STN6_RX_DN<104>")
	)
	(segment
		(start 397.61541 -323.736462)
		(end 398.11579 -322.5292)
		(width 0.1651)
		(layer "In15.Cu")
		(net "P5E_PEX3_STN6_RX_DN<104>")
	)
	(segment
		(start 374.1547 -371.374162)
		(end 374.520206 -369.506246)
		(width 0.1651)
		(layer "In15.Cu")
		(net "P5E_PEX3_STN6_RX_DN<104>")
	)
	(segment
		(start 398.11579 -319.966848)
		(end 398.07007 -319.921128)
		(width 0.1143)
		(layer "In15.Cu")
		(net "P5E_PEX3_STN6_RX_DN<104>")
	)
	(segment
		(start 391.016998 -402.281136)
		(end 391.564114 -402.281136)
		(width 0.1651)
		(layer "In15.Cu")
		(net "P5E_PEX3_STN6_RX_DN<104>")
	)
	(segment
		(start 383.231644 -340.81974)
		(end 393.215876 -329.398376)
		(width 0.1651)
		(layer "In15.Cu")
		(net "P5E_PEX3_STN6_RX_DN<104>")
	)
	(segment
		(start 392.01598 -396.0368)
		(end 391.662158 -395.093444)
		(width 0.1651)
		(layer "In15.Cu")
		(net "P5E_PEX3_STN6_RX_DN<104>")
	)
	(segment
		(start 390.889998 -402.408136)
		(end 391.016998 -402.281136)
		(width 0.1651)
		(layer "In15.Cu")
		(net "P5E_PEX3_STN6_RX_DN<104>")
	)
	(segment
		(start 374.857772 -385.398264)
		(end 374.646952 -384.963162)
		(width 0.1651)
		(layer "In15.Cu")
		(net "P5E_PEX3_STN6_RX_DN<104>")
	)
	(segment
		(start 374.43664 -384.527298)
		(end 373.996712 -373.047006)
		(width 0.1651)
		(layer "In15.Cu")
		(net "P5E_PEX3_STN6_RX_DN<104>")
	)
	(segment
		(start 382.64211 -358.011984)
		(end 382.64211 -342.173814)
		(width 0.1651)
		(layer "In15.Cu")
		(net "P5E_PEX3_STN6_RX_DN<104>")
	)
	(segment
		(start 398.4498 -318.434466)
		(end 398.4498 -318.699896)
		(width 0.1143)
		(layer "In15.Cu")
		(net "P5E_PEX3_STN6_RX_DN<104>")
	)
	(segment
		(start 398.07007 -318.423798)
		(end 398.173702 -318.320166)
		(width 0.1143)
		(layer "In15.Cu")
		(net "P5E_PEX3_STN6_RX_DN<104>")
	)
	(segment
		(start 398.11579 -322.5292)
		(end 398.11579 -319.995296)
		(width 0.1651)
		(layer "In15.Cu")
		(net "P5E_PEX3_STN6_RX_DN<104>")
	)
	(segment
		(start 391.662158 -395.093444)
		(end 388.656576 -392.016742)
		(width 0.1651)
		(layer "In15.Cu")
		(net "P5E_PEX3_STN6_RX_DN<104>")
	)
	(segment
		(start 306.12588 -144.7165)
		(end 305.964336 -144.554956)
		(width 0.13462)
		(layer "F.Cu")
		(net "P5E_PEX2_STN0_TX_C_DN<9>")
	)
	(segment
		(start 305.964336 -144.554956)
		(end 305.457606 -144.554956)
		(width 0.13462)
		(layer "F.Cu")
		(net "P5E_PEX2_STN0_TX_C_DN<9>")
	)
	(segment
		(start 314.274962 -144.7165)
		(end 306.12588 -144.7165)
		(width 0.13462)
		(layer "F.Cu")
		(net "P5E_PEX2_STN0_TX_C_DN<9>")
	)
	(segment
		(start 314.594748 -144.396714)
		(end 314.274962 -144.7165)
		(width 0.13462)
		(layer "F.Cu")
		(net "P5E_PEX2_STN0_TX_C_DN<9>")
	)
	(segment
		(start 280.901902 -351.316798)
		(end 281.196542 -351.611438)
		(width 0.13462)
		(layer "F.Cu")
		(net "P5E_PEX2_STN7_TX_C_DN<118>")
	)
	(segment
		(start 281.221942 -350.365314)
		(end 280.901902 -350.685354)
		(width 0.13462)
		(layer "F.Cu")
		(net "P5E_PEX2_STN7_TX_C_DN<118>")
	)
	(segment
		(start 280.901902 -350.685354)
		(end 280.901902 -351.316798)
		(width 0.13462)
		(layer "F.Cu")
		(net "P5E_PEX2_STN7_TX_C_DN<118>")
	)
	(segment
		(start 300.816772 -401.181062)
		(end 301.363888 -401.181062)
		(width 0.1651)
		(layer "In7.Cu")
		(net "P5E_PEX2_STN7_TX_C_DN<118>")
	)
	(segment
		(start 300.689772 -401.690078)
		(end 300.689772 -401.308062)
		(width 0.1651)
		(layer "In7.Cu")
		(net "P5E_PEX2_STN7_TX_C_DN<118>")
	)
	(segment
		(start 295.5544 -390.3218)
		(end 286.735266 -386.458714)
		(width 0.1651)
		(layer "In7.Cu")
		(net "P5E_PEX2_STN7_TX_C_DN<118>")
	)
	(segment
		(start 300.689772 -401.308062)
		(end 300.816772 -401.181062)
		(width 0.1651)
		(layer "In7.Cu")
		(net "P5E_PEX2_STN7_TX_C_DN<118>")
	)
	(segment
		(start 283.7434 -373.6086)
		(end 279.351232 -358.394)
		(width 0.1651)
		(layer "In7.Cu")
		(net "P5E_PEX2_STN7_TX_C_DN<118>")
	)
	(segment
		(start 279.351232 -358.394)
		(end 279.351232 -354.027486)
		(width 0.1651)
		(layer "In7.Cu")
		(net "P5E_PEX2_STN7_TX_C_DN<118>")
	)
	(segment
		(start 286.735266 -386.458714)
		(end 286.008064 -385.656328)
		(width 0.1651)
		(layer "In7.Cu")
		(net "P5E_PEX2_STN7_TX_C_DN<118>")
	)
	(segment
		(start 280.905712 -351.902268)
		(end 281.196542 -351.611438)
		(width 0.1651)
		(layer "In7.Cu")
		(net "P5E_PEX2_STN7_TX_C_DN<118>")
	)
	(segment
		(start 300.704504 -393.721336)
		(end 295.5544 -390.3218)
		(width 0.1651)
		(layer "In7.Cu")
		(net "P5E_PEX2_STN7_TX_C_DN<118>")
	)
	(segment
		(start 280.905712 -352.473006)
		(end 280.905712 -351.902268)
		(width 0.1651)
		(layer "In7.Cu")
		(net "P5E_PEX2_STN7_TX_C_DN<118>")
	)
	(segment
		(start 279.351232 -354.027486)
		(end 280.905712 -352.473006)
		(width 0.1651)
		(layer "In7.Cu")
		(net "P5E_PEX2_STN7_TX_C_DN<118>")
	)
	(segment
		(start 301.363888 -401.181062)
		(end 301.815754 -400.729196)
		(width 0.1651)
		(layer "In7.Cu")
		(net "P5E_PEX2_STN7_TX_C_DN<118>")
	)
	(segment
		(start 286.008064 -385.656328)
		(end 285.4452 -384.556)
		(width 0.1651)
		(layer "In7.Cu")
		(net "P5E_PEX2_STN7_TX_C_DN<118>")
	)
	(segment
		(start 301.598584 -394.611098)
		(end 300.704504 -393.721336)
		(width 0.1651)
		(layer "In7.Cu")
		(net "P5E_PEX2_STN7_TX_C_DN<118>")
	)
	(segment
		(start 285.4452 -384.556)
		(end 283.7434 -373.6086)
		(width 0.1651)
		(layer "In7.Cu")
		(net "P5E_PEX2_STN7_TX_C_DN<118>")
	)
	(segment
		(start 301.815754 -395.13383)
		(end 301.598584 -394.611098)
		(width 0.1651)
		(layer "In7.Cu")
		(net "P5E_PEX2_STN7_TX_C_DN<118>")
	)
	(segment
		(start 301.815754 -400.729196)
		(end 301.815754 -395.13383)
		(width 0.1651)
		(layer "In7.Cu")
		(net "P5E_PEX2_STN7_TX_C_DN<118>")
	)
	(segment
		(start 51.55184 -156.560012)
		(end 51.67884 -156.687012)
		(width 0.13208)
		(layer "F.Cu")
		(net "NIC0_RBT_ARB_IN")
	)
	(segment
		(start 51.67884 -156.687012)
		(end 51.67884 -157.0736)
		(width 0.13208)
		(layer "F.Cu")
		(net "NIC0_RBT_ARB_IN")
	)
	(segment
		(start 50.64252 -156.560012)
		(end 51.55184 -156.560012)
		(width 0.13208)
		(layer "F.Cu")
		(net "NIC0_RBT_ARB_IN")
	)
	(via
		(at 51.67884 -157.0736)
		(size 0.508)
		(drill 0.254)
		(layers "F.Cu" "B.Cu")
		(net "NIC0_RBT_ARB_IN")
	)
	(segment
		(start 49.95545 -157.0736)
		(end 51.67884 -157.0736)
		(width 0.13208)
		(layer "B.Cu")
		(net "NIC0_RBT_ARB_IN")
	)
	(segment
		(start 303.92878 -113.896394)
		(end 303.022 -112.989614)
		(width 0.13208)
		(layer "F.Cu")
		(net "NIC5_BIF2_N")
	)
	(segment
		(start 305.160172 -114.035078)
		(end 304.825146 -113.896394)
		(width 0.13208)
		(layer "F.Cu")
		(net "NIC5_BIF2_N")
	)
	(segment
		(start 304.825146 -113.896394)
		(end 303.92878 -113.896394)
		(width 0.13208)
		(layer "F.Cu")
		(net "NIC5_BIF2_N")
	)
	(segment
		(start 305.457606 -114.035078)
		(end 305.160172 -114.035078)
		(width 0.13208)
		(layer "F.Cu")
		(net "NIC5_BIF2_N")
	)
	(via
		(at 303.022 -112.989614)
		(size 0.508)
		(drill 0.254)
		(layers "F.Cu" "B.Cu")
		(net "NIC5_BIF2_N")
	)
	(via
		(at 297.731688 -109.982762)
		(size 0.6604)
		(drill 0.3302)
		(layers "F.Cu" "B.Cu")
		(net "NIC5_BIF2_N")
	)
	(segment
		(start 295.175178 -110.497366)
		(end 294.197278 -110.497366)
		(width 0.13208)
		(layer "B.Cu")
		(net "NIC5_BIF2_N")
	)
	(segment
		(start 302.659288 -112.626902)
		(end 302.445674 -112.111536)
		(width 0.13208)
		(layer "B.Cu")
		(net "NIC5_BIF2_N")
	)
	(segment
		(start 300.31436 -108.769912)
		(end 298.944538 -108.769912)
		(width 0.13208)
		(layer "B.Cu")
		(net "NIC5_BIF2_N")
	)
	(segment
		(start 295.175178 -110.19917)
		(end 295.175178 -110.497366)
		(width 0.13208)
		(layer "B.Cu")
		(net "NIC5_BIF2_N")
	)
	(segment
		(start 303.022 -112.989614)
		(end 302.659288 -112.626902)
		(width 0.13208)
		(layer "B.Cu")
		(net "NIC5_BIF2_N")
	)
	(segment
		(start 302.445674 -112.111536)
		(end 300.76394 -110.429802)
		(width 0.13208)
		(layer "B.Cu")
		(net "NIC5_BIF2_N")
	)
	(segment
		(start 295.391586 -109.982762)
		(end 295.175178 -110.19917)
		(width 0.13208)
		(layer "B.Cu")
		(net "NIC5_BIF2_N")
	)
	(segment
		(start 297.731688 -109.982762)
		(end 295.391586 -109.982762)
		(width 0.13208)
		(layer "B.Cu")
		(net "NIC5_BIF2_N")
	)
	(segment
		(start 300.76394 -110.429802)
		(end 300.76394 -109.219492)
		(width 0.13208)
		(layer "B.Cu")
		(net "NIC5_BIF2_N")
	)
	(segment
		(start 300.76394 -109.219492)
		(end 300.31436 -108.769912)
		(width 0.13208)
		(layer "B.Cu")
		(net "NIC5_BIF2_N")
	)
	(segment
		(start 298.944538 -108.769912)
		(end 297.731688 -109.982762)
		(width 0.13208)
		(layer "B.Cu")
		(net "NIC5_BIF2_N")
	)
	(segment
		(start 305.95697 -143.35506)
		(end 305.457606 -143.35506)
		(width 0.13462)
		(layer "F.Cu")
		(net "P5E_PEX2_STN0_TX_C_DP<8>")
	)
	(segment
		(start 311.63387 -143.185896)
		(end 306.126134 -143.185896)
		(width 0.13462)
		(layer "F.Cu")
		(net "P5E_PEX2_STN0_TX_C_DP<8>")
	)
	(segment
		(start 306.126134 -143.185896)
		(end 305.95697 -143.35506)
		(width 0.13462)
		(layer "F.Cu")
		(net "P5E_PEX2_STN0_TX_C_DP<8>")
	)
	(segment
		(start 311.95264 -143.504666)
		(end 311.63387 -143.185896)
		(width 0.13462)
		(layer "F.Cu")
		(net "P5E_PEX2_STN0_TX_C_DP<8>")
	)
	(segment
		(start 55.42915 -116.5352)
		(end 55.42915 -117.5512)
		(width 0.13208)
		(layer "F.Cu")
		(net "PRSNTB1_NIC0_N")
	)
	(segment
		(start 53.424836 -117.5512)
		(end 54.252876 -117.5512)
		(width 0.13208)
		(layer "F.Cu")
		(net "PRSNTB1_NIC0_N")
	)
	(segment
		(start 50.64252 -118.154958)
		(end 52.821078 -118.154958)
		(width 0.13208)
		(layer "F.Cu")
		(net "PRSNTB1_NIC0_N")
	)
	(segment
		(start 54.252876 -117.5512)
		(end 55.42915 -117.5512)
		(width 0.13208)
		(layer "F.Cu")
		(net "PRSNTB1_NIC0_N")
	)
	(segment
		(start 52.821078 -118.154958)
		(end 53.424836 -117.5512)
		(width 0.13208)
		(layer "F.Cu")
		(net "PRSNTB1_NIC0_N")
	)
	(via
		(at 54.252876 -117.5512)
		(size 0.762)
		(drill 0.381)
		(layers "F.Cu" "B.Cu")
		(net "PRSNTB1_NIC0_N")
	)
	(segment
		(start 10.019538 -28.55468)
		(end 9.360662 -28.55468)
		(width 0.13462)
		(layer "F.Cu")
		(net "P5E_PEX0_STN2_RX_DN<44>")
	)
	(segment
		(start 9.360662 -28.55468)
		(end 9.064752 -28.25877)
		(width 0.13462)
		(layer "F.Cu")
		(net "P5E_PEX0_STN2_RX_DN<44>")
	)
	(segment
		(start 10.664952 -28.390088)
		(end 10.18413 -28.390088)
		(width 0.13462)
		(layer "F.Cu")
		(net "P5E_PEX0_STN2_RX_DN<44>")
	)
	(segment
		(start 10.18413 -28.390088)
		(end 10.019538 -28.55468)
		(width 0.13462)
		(layer "F.Cu")
		(net "P5E_PEX0_STN2_RX_DN<44>")
	)
	(segment
		(start 9.357868 -28.551886)
		(end 9.36371 -28.5496)
		(width 0.1651)
		(layer "In7.Cu")
		(net "P5E_PEX0_STN2_RX_DN<44>")
	)
	(segment
		(start 11.3792 -30.4546)
		(end 12.942824 -32.018224)
		(width 0.1651)
		(layer "In7.Cu")
		(net "P5E_PEX0_STN2_RX_DN<44>")
	)
	(segment
		(start 44.481242 -238.036354)
		(end 46.089824 -255.60782)
		(width 0.1651)
		(layer "In7.Cu")
		(net "P5E_PEX0_STN2_RX_DN<44>")
	)
	(segment
		(start 47.29988 -275.265388)
		(end 47.29988 -274.999958)
		(width 0.1143)
		(layer "In7.Cu")
		(net "P5E_PEX0_STN2_RX_DN<44>")
	)
	(segment
		(start 9.064752 -28.25877)
		(end 9.357868 -28.551886)
		(width 0.1651)
		(layer "In7.Cu")
		(net "P5E_PEX0_STN2_RX_DN<44>")
	)
	(segment
		(start 46.919896 -271.467072)
		(end 46.919896 -275.275802)
		(width 0.1143)
		(layer "In7.Cu")
		(net "P5E_PEX0_STN2_RX_DN<44>")
	)
	(segment
		(start 12.942824 -32.018224)
		(end 15.33144 -37.688012)
		(width 0.1651)
		(layer "In7.Cu")
		(net "P5E_PEX0_STN2_RX_DN<44>")
	)
	(segment
		(start 23.476712 -119.34952)
		(end 26.765758 -144.353534)
		(width 0.1651)
		(layer "In7.Cu")
		(net "P5E_PEX0_STN2_RX_DN<44>")
	)
	(segment
		(start 10.71499 -29.460698)
		(end 11.3792 -30.4546)
		(width 0.1651)
		(layer "In7.Cu")
		(net "P5E_PEX0_STN2_RX_DN<44>")
	)
	(segment
		(start 46.965616 -269.50162)
		(end 46.965616 -271.392904)
		(width 0.1651)
		(layer "In7.Cu")
		(net "P5E_PEX0_STN2_RX_DN<44>")
	)
	(segment
		(start 13.037312 -57.32399)
		(end 13.306806 -60.059824)
		(width 0.1651)
		(layer "In7.Cu")
		(net "P5E_PEX0_STN2_RX_DN<44>")
	)
	(segment
		(start 46.089824 -255.60782)
		(end 46.012862 -263.459722)
		(width 0.1651)
		(layer "In7.Cu")
		(net "P5E_PEX0_STN2_RX_DN<44>")
	)
	(segment
		(start 26.765758 -144.353534)
		(end 44.481242 -238.036354)
		(width 0.1651)
		(layer "In7.Cu")
		(net "P5E_PEX0_STN2_RX_DN<44>")
	)
	(segment
		(start 15.33144 -37.688012)
		(end 15.306802 -39.16934)
		(width 0.1651)
		(layer "In7.Cu")
		(net "P5E_PEX0_STN2_RX_DN<44>")
	)
	(segment
		(start 13.160756 -49.41951)
		(end 13.037312 -57.32399)
		(width 0.1651)
		(layer "In7.Cu")
		(net "P5E_PEX0_STN2_RX_DN<44>")
	)
	(segment
		(start 9.36371 -28.5496)
		(end 9.803892 -28.5496)
		(width 0.1651)
		(layer "In7.Cu")
		(net "P5E_PEX0_STN2_RX_DN<44>")
	)
	(segment
		(start 47.023782 -275.379688)
		(end 47.18558 -275.379688)
		(width 0.1143)
		(layer "In7.Cu")
		(net "P5E_PEX0_STN2_RX_DN<44>")
	)
	(segment
		(start 9.803892 -28.5496)
		(end 10.71499 -29.460698)
		(width 0.1651)
		(layer "In7.Cu")
		(net "P5E_PEX0_STN2_RX_DN<44>")
	)
	(segment
		(start 46.965616 -271.392904)
		(end 46.965616 -271.421352)
		(width 0.1143)
		(layer "In7.Cu")
		(net "P5E_PEX0_STN2_RX_DN<44>")
	)
	(segment
		(start 47.18558 -275.379688)
		(end 47.29988 -275.265388)
		(width 0.1143)
		(layer "In7.Cu")
		(net "P5E_PEX0_STN2_RX_DN<44>")
	)
	(segment
		(start 13.306806 -61.851032)
		(end 13.11783 -85.173566)
		(width 0.1651)
		(layer "In7.Cu")
		(net "P5E_PEX0_STN2_RX_DN<44>")
	)
	(segment
		(start 13.306806 -60.059824)
		(end 13.306806 -61.851032)
		(width 0.1651)
		(layer "In7.Cu")
		(net "P5E_PEX0_STN2_RX_DN<44>")
	)
	(segment
		(start 15.306802 -39.16934)
		(end 13.160756 -49.41951)
		(width 0.1651)
		(layer "In7.Cu")
		(net "P5E_PEX0_STN2_RX_DN<44>")
	)
	(segment
		(start 46.012862 -263.459722)
		(end 46.965616 -269.50162)
		(width 0.1651)
		(layer "In7.Cu")
		(net "P5E_PEX0_STN2_RX_DN<44>")
	)
	(segment
		(start 46.965616 -271.421352)
		(end 46.919896 -271.467072)
		(width 0.1143)
		(layer "In7.Cu")
		(net "P5E_PEX0_STN2_RX_DN<44>")
	)
	(segment
		(start 46.919896 -275.275802)
		(end 47.023782 -275.379688)
		(width 0.1143)
		(layer "In7.Cu")
		(net "P5E_PEX0_STN2_RX_DN<44>")
	)
	(segment
		(start 13.11783 -85.173566)
		(end 23.476712 -119.34952)
		(width 0.1651)
		(layer "In7.Cu")
		(net "P5E_PEX0_STN2_RX_DN<44>")
	)
	(segment
		(start 300.37659 -153.554938)
		(end 300.857412 -153.554938)
		(width 0.13462)
		(layer "F.Cu")
		(net "P5E_PEX2_STN0_RX_DN<14>")
	)
	(segment
		(start 300.205648 -153.72588)
		(end 300.37659 -153.554938)
		(width 0.13462)
		(layer "F.Cu")
		(net "P5E_PEX2_STN0_RX_DN<14>")
	)
	(segment
		(start 299.257212 -153.42362)
		(end 299.559472 -153.72588)
		(width 0.13462)
		(layer "F.Cu")
		(net "P5E_PEX2_STN0_RX_DN<14>")
	)
	(segment
		(start 299.559472 -153.72588)
		(end 300.205648 -153.72588)
		(width 0.13462)
		(layer "F.Cu")
		(net "P5E_PEX2_STN0_RX_DN<14>")
	)
	(segment
		(start 301.51451 -164.671502)
		(end 307.945536 -258.322826)
		(width 0.1651)
		(layer "In5.Cu")
		(net "P5E_PEX2_STN0_RX_DN<14>")
	)
	(segment
		(start 299.257212 -153.42362)
		(end 299.546772 -153.71318)
		(width 0.1651)
		(layer "In5.Cu")
		(net "P5E_PEX2_STN0_RX_DN<14>")
	)
	(segment
		(start 307.885338 -275.379434)
		(end 307.999638 -275.265134)
		(width 0.1143)
		(layer "In5.Cu")
		(net "P5E_PEX2_STN0_RX_DN<14>")
	)
	(segment
		(start 307.620162 -271.644872)
		(end 307.620162 -275.276056)
		(width 0.1143)
		(layer "In5.Cu")
		(net "P5E_PEX2_STN0_RX_DN<14>")
	)
	(segment
		(start 300.477936 -154.211528)
		(end 300.715426 -154.733752)
		(width 0.1651)
		(layer "In5.Cu")
		(net "P5E_PEX2_STN0_RX_DN<14>")
	)
	(segment
		(start 300.983142 -158.632652)
		(end 300.983142 -160.386776)
		(width 0.1651)
		(layer "In5.Cu")
		(net "P5E_PEX2_STN0_RX_DN<14>")
	)
	(segment
		(start 299.546772 -153.71318)
		(end 299.979588 -153.71318)
		(width 0.1651)
		(layer "In5.Cu")
		(net "P5E_PEX2_STN0_RX_DN<14>")
	)
	(segment
		(start 307.665882 -271.570704)
		(end 307.665882 -271.599152)
		(width 0.1143)
		(layer "In5.Cu")
		(net "P5E_PEX2_STN0_RX_DN<14>")
	)
	(segment
		(start 308.160928 -267.81125)
		(end 307.665882 -270.457168)
		(width 0.1651)
		(layer "In5.Cu")
		(net "P5E_PEX2_STN0_RX_DN<14>")
	)
	(segment
		(start 300.715426 -154.733752)
		(end 300.982634 -158.632144)
		(width 0.1651)
		(layer "In5.Cu")
		(net "P5E_PEX2_STN0_RX_DN<14>")
	)
	(segment
		(start 299.979588 -153.71318)
		(end 300.477936 -154.211528)
		(width 0.1651)
		(layer "In5.Cu")
		(net "P5E_PEX2_STN0_RX_DN<14>")
	)
	(segment
		(start 300.982634 -158.632144)
		(end 300.983142 -158.632652)
		(width 0.1651)
		(layer "In5.Cu")
		(net "P5E_PEX2_STN0_RX_DN<14>")
	)
	(segment
		(start 307.665882 -270.457168)
		(end 307.665882 -271.570704)
		(width 0.1651)
		(layer "In5.Cu")
		(net "P5E_PEX2_STN0_RX_DN<14>")
	)
	(segment
		(start 300.983142 -160.386776)
		(end 301.098458 -162.064446)
		(width 0.1651)
		(layer "In5.Cu")
		(net "P5E_PEX2_STN0_RX_DN<14>")
	)
	(segment
		(start 307.620162 -275.276056)
		(end 307.72354 -275.379434)
		(width 0.1143)
		(layer "In5.Cu")
		(net "P5E_PEX2_STN0_RX_DN<14>")
	)
	(segment
		(start 307.945536 -258.322826)
		(end 308.160928 -267.81125)
		(width 0.1651)
		(layer "In5.Cu")
		(net "P5E_PEX2_STN0_RX_DN<14>")
	)
	(segment
		(start 301.098458 -162.064446)
		(end 301.51451 -164.671502)
		(width 0.1651)
		(layer "In5.Cu")
		(net "P5E_PEX2_STN0_RX_DN<14>")
	)
	(segment
		(start 307.665882 -271.599152)
		(end 307.620162 -271.644872)
		(width 0.1143)
		(layer "In5.Cu")
		(net "P5E_PEX2_STN0_RX_DN<14>")
	)
	(segment
		(start 307.72354 -275.379434)
		(end 307.885338 -275.379434)
		(width 0.1143)
		(layer "In5.Cu")
		(net "P5E_PEX2_STN0_RX_DN<14>")
	)
	(segment
		(start 307.999638 -275.265134)
		(end 307.999638 -274.999704)
		(width 0.1143)
		(layer "In5.Cu")
		(net "P5E_PEX2_STN0_RX_DN<14>")
	)
	(segment
		(start 41.640506 -151.465534)
		(end 43.73499 -153.560018)
		(width 0.13208)
		(layer "F.Cu")
		(net "NCSI_NIC0_RXD0")
	)
	(segment
		(start 39.437818 -151.279352)
		(end 39.624 -151.465534)
		(width 0.13208)
		(layer "F.Cu")
		(net "NCSI_NIC0_RXD0")
	)
	(segment
		(start 38.999922 -151.279352)
		(end 39.437818 -151.279352)
		(width 0.13208)
		(layer "F.Cu")
		(net "NCSI_NIC0_RXD0")
	)
	(segment
		(start 39.624 -151.465534)
		(end 40.182292 -151.465534)
		(width 0.13208)
		(layer "F.Cu")
		(net "NCSI_NIC0_RXD0")
	)
	(segment
		(start 40.182292 -151.465534)
		(end 41.640506 -151.465534)
		(width 0.13208)
		(layer "F.Cu")
		(net "NCSI_NIC0_RXD0")
	)
	(segment
		(start 43.73499 -153.560018)
		(end 46.042326 -153.560018)
		(width 0.13208)
		(layer "F.Cu")
		(net "NCSI_NIC0_RXD0")
	)
	(via
		(at 40.182292 -151.465534)
		(size 0.762)
		(drill 0.381)
		(layers "F.Cu" "B.Cu")
		(net "NCSI_NIC0_RXD0")
	)
	(segment
		(start 36.6649 -33.790128)
		(end 36.18738 -33.790128)
		(width 0.13462)
		(layer "F.Cu")
		(net "P5E_PEX0_STN2_RX_DN<43>")
	)
	(segment
		(start 33.504632 -33.952942)
		(end 33.2105 -33.65881)
		(width 0.13462)
		(layer "F.Cu")
		(net "P5E_PEX0_STN2_RX_DN<43>")
	)
	(segment
		(start 36.024566 -33.952942)
		(end 33.504632 -33.952942)
		(width 0.13462)
		(layer "F.Cu")
		(net "P5E_PEX0_STN2_RX_DN<43>")
	)
	(segment
		(start 36.18738 -33.790128)
		(end 36.024566 -33.952942)
		(width 0.13462)
		(layer "F.Cu")
		(net "P5E_PEX0_STN2_RX_DN<43>")
	)
	(segment
		(start 48.020986 -273.479514)
		(end 47.87011 -273.328638)
		(width 0.1143)
		(layer "In7.Cu")
		(net "P5E_PEX0_STN2_RX_DN<43>")
	)
	(segment
		(start 47.87011 -271.41932)
		(end 47.91583 -271.3736)
		(width 0.1143)
		(layer "In7.Cu")
		(net "P5E_PEX0_STN2_RX_DN<43>")
	)
	(segment
		(start 33.50133 -33.94964)
		(end 33.2105 -33.65881)
		(width 0.1651)
		(layer "In7.Cu")
		(net "P5E_PEX0_STN2_RX_DN<43>")
	)
	(segment
		(start 48.24984 -273.099784)
		(end 48.24984 -273.365214)
		(width 0.1143)
		(layer "In7.Cu")
		(net "P5E_PEX0_STN2_RX_DN<43>")
	)
	(segment
		(start 36.56838 -65.250314)
		(end 36.17722 -55.479696)
		(width 0.1651)
		(layer "In7.Cu")
		(net "P5E_PEX0_STN2_RX_DN<43>")
	)
	(segment
		(start 36.17722 -55.479696)
		(end 36.270946 -49.492662)
		(width 0.1651)
		(layer "In7.Cu")
		(net "P5E_PEX0_STN2_RX_DN<43>")
	)
	(segment
		(start 47.87011 -273.328638)
		(end 47.87011 -271.41932)
		(width 0.1143)
		(layer "In7.Cu")
		(net "P5E_PEX0_STN2_RX_DN<43>")
	)
	(segment
		(start 47.734982 -248.471436)
		(end 39.33571 -141.670024)
		(width 0.1651)
		(layer "In7.Cu")
		(net "P5E_PEX0_STN2_RX_DN<43>")
	)
	(segment
		(start 47.91583 -271.3736)
		(end 47.91583 -271.345152)
		(width 0.1143)
		(layer "In7.Cu")
		(net "P5E_PEX0_STN2_RX_DN<43>")
	)
	(segment
		(start 47.45736 -263.216136)
		(end 47.45736 -262.822944)
		(width 0.1651)
		(layer "In7.Cu")
		(net "P5E_PEX0_STN2_RX_DN<43>")
	)
	(segment
		(start 39.369492 -138.51128)
		(end 40.074596 -131.985766)
		(width 0.1651)
		(layer "In7.Cu")
		(net "P5E_PEX0_STN2_RX_DN<43>")
	)
	(segment
		(start 33.85185 -33.94964)
		(end 33.50133 -33.94964)
		(width 0.1651)
		(layer "In7.Cu")
		(net "P5E_PEX0_STN2_RX_DN<43>")
	)
	(segment
		(start 34.88817 -34.98596)
		(end 33.85185 -33.94964)
		(width 0.1651)
		(layer "In7.Cu")
		(net "P5E_PEX0_STN2_RX_DN<43>")
	)
	(segment
		(start 36.270946 -49.492662)
		(end 34.956496 -39.76497)
		(width 0.1651)
		(layer "In7.Cu")
		(net "P5E_PEX0_STN2_RX_DN<43>")
	)
	(segment
		(start 48.13554 -273.479514)
		(end 48.020986 -273.479514)
		(width 0.1143)
		(layer "In7.Cu")
		(net "P5E_PEX0_STN2_RX_DN<43>")
	)
	(segment
		(start 47.91583 -267.871956)
		(end 47.45736 -263.216136)
		(width 0.1651)
		(layer "In7.Cu")
		(net "P5E_PEX0_STN2_RX_DN<43>")
	)
	(segment
		(start 39.770558 -105.13822)
		(end 36.56838 -65.250314)
		(width 0.1651)
		(layer "In7.Cu")
		(net "P5E_PEX0_STN2_RX_DN<43>")
	)
	(segment
		(start 39.33571 -141.670024)
		(end 39.369492 -138.51128)
		(width 0.1651)
		(layer "In7.Cu")
		(net "P5E_PEX0_STN2_RX_DN<43>")
	)
	(segment
		(start 47.91583 -271.345152)
		(end 47.91583 -267.871956)
		(width 0.1651)
		(layer "In7.Cu")
		(net "P5E_PEX0_STN2_RX_DN<43>")
	)
	(segment
		(start 48.24984 -273.365214)
		(end 48.13554 -273.479514)
		(width 0.1143)
		(layer "In7.Cu")
		(net "P5E_PEX0_STN2_RX_DN<43>")
	)
	(segment
		(start 40.074596 -131.985766)
		(end 40.2082 -119.592598)
		(width 0.1651)
		(layer "In7.Cu")
		(net "P5E_PEX0_STN2_RX_DN<43>")
	)
	(segment
		(start 40.2082 -119.592598)
		(end 39.770558 -105.13822)
		(width 0.1651)
		(layer "In7.Cu")
		(net "P5E_PEX0_STN2_RX_DN<43>")
	)
	(segment
		(start 34.88817 -35.355276)
		(end 34.88817 -34.98596)
		(width 0.1651)
		(layer "In7.Cu")
		(net "P5E_PEX0_STN2_RX_DN<43>")
	)
	(segment
		(start 34.956496 -39.76497)
		(end 34.88817 -35.355276)
		(width 0.1651)
		(layer "In7.Cu")
		(net "P5E_PEX0_STN2_RX_DN<43>")
	)
	(segment
		(start 47.45736 -262.822944)
		(end 47.734982 -248.471436)
		(width 0.1651)
		(layer "In7.Cu")
		(net "P5E_PEX0_STN2_RX_DN<43>")
	)
	(segment
		(start 285.30296 -392.94689)
		(end 285.163768 -392.982196)
		(width 0.1651)
		(layer "In5.Cu")
		(net "P5E_PEX2_STN7_RX_DP<112>")
	)
	(segment
		(start 271.294352 -301.029624)
		(end 271.520158 -301.25543)
		(width 0.1143)
		(layer "In5.Cu")
		(net "P5E_PEX2_STN7_RX_DP<112>")
	)
	(segment
		(start 254.304292 -306.941728)
		(end 258.167886 -303.078134)
		(width 0.1651)
		(layer "In5.Cu")
		(net "P5E_PEX2_STN7_RX_DP<112>")
	)
	(segment
		(start 286.190182 -393.592558)
		(end 285.76397 -393.339066)
		(width 0.1651)
		(layer "In5.Cu")
		(net "P5E_PEX2_STN7_RX_DP<112>")
	)
	(segment
		(start 266.654534 -361.01782)
		(end 256.793238 -336.884264)
		(width 0.1651)
		(layer "In5.Cu")
		(net "P5E_PEX2_STN7_RX_DP<112>")
	)
	(segment
		(start 249.43562 -317.75781)
		(end 254.304292 -306.941728)
		(width 0.1651)
		(layer "In5.Cu")
		(net "P5E_PEX2_STN7_RX_DP<112>")
	)
	(segment
		(start 277.763986 -372.424198)
		(end 266.654534 -361.01782)
		(width 0.1651)
		(layer "In5.Cu")
		(net "P5E_PEX2_STN7_RX_DP<112>")
	)
	(segment
		(start 279.15362 -385.858258)
		(end 278.859488 -379.008132)
		(width 0.1651)
		(layer "In5.Cu")
		(net "P5E_PEX2_STN7_RX_DP<112>")
	)
	(segment
		(start 271.520158 -301.25543)
		(end 271.520158 -301.485554)
		(width 0.1143)
		(layer "In5.Cu")
		(net "P5E_PEX2_STN7_RX_DP<112>")
	)
	(segment
		(start 288.333942 -408.412442)
		(end 288.333942 -395.181836)
		(width 0.1651)
		(layer "In5.Cu")
		(net "P5E_PEX2_STN7_RX_DP<112>")
	)
	(segment
		(start 271.520158 -301.485554)
		(end 271.634458 -301.599854)
		(width 0.1143)
		(layer "In5.Cu")
		(net "P5E_PEX2_STN7_RX_DP<112>")
	)
	(segment
		(start 283.736288 -392.015218)
		(end 280.79954 -389.406638)
		(width 0.1651)
		(layer "In5.Cu")
		(net "P5E_PEX2_STN7_RX_DP<112>")
	)
	(segment
		(start 280.79954 -389.406638)
		(end 279.15362 -385.858258)
		(width 0.1651)
		(layer "In5.Cu")
		(net "P5E_PEX2_STN7_RX_DP<112>")
	)
	(segment
		(start 256.793238 -336.884264)
		(end 251.58827 -328.47788)
		(width 0.1651)
		(layer "In5.Cu")
		(net "P5E_PEX2_STN7_RX_DP<112>")
	)
	(segment
		(start 249.43562 -323.617082)
		(end 249.43562 -317.75781)
		(width 0.1651)
		(layer "In5.Cu")
		(net "P5E_PEX2_STN7_RX_DP<112>")
	)
	(segment
		(start 278.859488 -379.008132)
		(end 278.332438 -373.592344)
		(width 0.1651)
		(layer "In5.Cu")
		(net "P5E_PEX2_STN7_RX_DP<112>")
	)
	(segment
		(start 286.329374 -393.557252)
		(end 286.190182 -393.592558)
		(width 0.1651)
		(layer "In5.Cu")
		(net "P5E_PEX2_STN7_RX_DP<112>")
	)
	(segment
		(start 287.6169 -408.699208)
		(end 288.047176 -408.699208)
		(width 0.1651)
		(layer "In5.Cu")
		(net "P5E_PEX2_STN7_RX_DP<112>")
	)
	(segment
		(start 287.861756 -394.46835)
		(end 286.329374 -393.557252)
		(width 0.1651)
		(layer "In5.Cu")
		(net "P5E_PEX2_STN7_RX_DP<112>")
	)
	(segment
		(start 263.222994 -300.983904)
		(end 268.627352 -300.983904)
		(width 0.1651)
		(layer "In5.Cu")
		(net "P5E_PEX2_STN7_RX_DP<112>")
	)
	(segment
		(start 284.702504 -392.589512)
		(end 283.736288 -392.015218)
		(width 0.1651)
		(layer "In5.Cu")
		(net "P5E_PEX2_STN7_RX_DP<112>")
	)
	(segment
		(start 278.332438 -373.592344)
		(end 277.763986 -372.424198)
		(width 0.1651)
		(layer "In5.Cu")
		(net "P5E_PEX2_STN7_RX_DP<112>")
	)
	(segment
		(start 268.6558 -300.983904)
		(end 268.70152 -301.029624)
		(width 0.1143)
		(layer "In5.Cu")
		(net "P5E_PEX2_STN7_RX_DP<112>")
	)
	(segment
		(start 288.047176 -408.699208)
		(end 288.333942 -408.412442)
		(width 0.1651)
		(layer "In5.Cu")
		(net "P5E_PEX2_STN7_RX_DP<112>")
	)
	(segment
		(start 287.4899 -408.572208)
		(end 287.6169 -408.699208)
		(width 0.1651)
		(layer "In5.Cu")
		(net "P5E_PEX2_STN7_RX_DP<112>")
	)
	(segment
		(start 271.634458 -301.599854)
		(end 271.899888 -301.599854)
		(width 0.1143)
		(layer "In5.Cu")
		(net "P5E_PEX2_STN7_RX_DP<112>")
	)
	(segment
		(start 284.73781 -392.728958)
		(end 284.702504 -392.589512)
		(width 0.1651)
		(layer "In5.Cu")
		(net "P5E_PEX2_STN7_RX_DP<112>")
	)
	(segment
		(start 251.58827 -328.47788)
		(end 249.43562 -323.617082)
		(width 0.1651)
		(layer "In5.Cu")
		(net "P5E_PEX2_STN7_RX_DP<112>")
	)
	(segment
		(start 268.70152 -301.029624)
		(end 271.294352 -301.029624)
		(width 0.1143)
		(layer "In5.Cu")
		(net "P5E_PEX2_STN7_RX_DP<112>")
	)
	(segment
		(start 288.333942 -395.181836)
		(end 287.861756 -394.46835)
		(width 0.1651)
		(layer "In5.Cu")
		(net "P5E_PEX2_STN7_RX_DP<112>")
	)
	(segment
		(start 268.627352 -300.983904)
		(end 268.6558 -300.983904)
		(width 0.1143)
		(layer "In5.Cu")
		(net "P5E_PEX2_STN7_RX_DP<112>")
	)
	(segment
		(start 287.4899 -408.190192)
		(end 287.4899 -408.572208)
		(width 0.1651)
		(layer "In5.Cu")
		(net "P5E_PEX2_STN7_RX_DP<112>")
	)
	(segment
		(start 285.728664 -393.199874)
		(end 285.30296 -392.94689)
		(width 0.1651)
		(layer "In5.Cu")
		(net "P5E_PEX2_STN7_RX_DP<112>")
	)
	(segment
		(start 258.167886 -303.078134)
		(end 263.222994 -300.983904)
		(width 0.1651)
		(layer "In5.Cu")
		(net "P5E_PEX2_STN7_RX_DP<112>")
	)
	(segment
		(start 285.76397 -393.339066)
		(end 285.728664 -393.199874)
		(width 0.1651)
		(layer "In5.Cu")
		(net "P5E_PEX2_STN7_RX_DP<112>")
	)
	(segment
		(start 285.163768 -392.982196)
		(end 284.73781 -392.728958)
		(width 0.1651)
		(layer "In5.Cu")
		(net "P5E_PEX2_STN7_RX_DP<112>")
	)
	(segment
		(start 45.305218 -29.114242)
		(end 45.019976 -28.829)
		(width 0.13462)
		(layer "F.Cu")
		(net "P5E_PEX0_STN2_TX_DP<40>")
	)
	(segment
		(start 44.369736 -28.829)
		(end 44.059094 -29.139642)
		(width 0.13462)
		(layer "F.Cu")
		(net "P5E_PEX0_STN2_TX_DP<40>")
	)
	(segment
		(start 45.019976 -28.829)
		(end 44.369736 -28.829)
		(width 0.13462)
		(layer "F.Cu")
		(net "P5E_PEX0_STN2_TX_DP<40>")
	)
	(segment
		(start 50.49266 -271.105122)
		(end 50.484024 -271.113758)
		(width 0.1651)
		(layer "In11.Cu")
		(net "P5E_PEX0_STN2_TX_DP<40>")
	)
	(segment
		(start 50.744882 -280.319988)
		(end 50.985674 -280.319988)
		(width 0.1143)
		(layer "In11.Cu")
		(net "P5E_PEX0_STN2_TX_DP<40>")
	)
	(segment
		(start 50.529744 -280.10485)
		(end 50.744882 -280.319988)
		(width 0.1143)
		(layer "In11.Cu")
		(net "P5E_PEX0_STN2_TX_DP<40>")
	)
	(segment
		(start 49.845976 -252.613668)
		(end 50.119788 -266.03325)
		(width 0.1651)
		(layer "In11.Cu")
		(net "P5E_PEX0_STN2_TX_DP<40>")
	)
	(segment
		(start 64.30137 -49.912524)
		(end 64.963802 -60.607194)
		(width 0.1651)
		(layer "In11.Cu")
		(net "P5E_PEX0_STN2_TX_DP<40>")
	)
	(segment
		(start 51.847242 -32.033972)
		(end 53.582824 -34.872168)
		(width 0.1651)
		(layer "In11.Cu")
		(net "P5E_PEX0_STN2_TX_DP<40>")
	)
	(segment
		(start 50.484024 -271.427448)
		(end 50.529744 -271.473168)
		(width 0.1143)
		(layer "In11.Cu")
		(net "P5E_PEX0_STN2_TX_DP<40>")
	)
	(segment
		(start 57.49036 -119.281702)
		(end 56.148732 -135.243824)
		(width 0.1651)
		(layer "In11.Cu")
		(net "P5E_PEX0_STN2_TX_DP<40>")
	)
	(segment
		(start 50.084482 -30.40761)
		(end 50.210212 -30.407356)
		(width 0.1651)
		(layer "In11.Cu")
		(net "P5E_PEX0_STN2_TX_DP<40>")
	)
	(segment
		(start 50.119788 -266.03325)
		(end 50.49266 -269.820898)
		(width 0.1651)
		(layer "In11.Cu")
		(net "P5E_PEX0_STN2_TX_DP<40>")
	)
	(segment
		(start 45.596048 -28.823412)
		(end 47.88281 -28.823412)
		(width 0.1651)
		(layer "In11.Cu")
		(net "P5E_PEX0_STN2_TX_DP<40>")
	)
	(segment
		(start 45.305218 -29.114242)
		(end 45.596048 -28.823412)
		(width 0.1651)
		(layer "In11.Cu")
		(net "P5E_PEX0_STN2_TX_DP<40>")
	)
	(segment
		(start 50.210212 -30.407356)
		(end 50.561494 -30.756352)
		(width 0.1651)
		(layer "In11.Cu")
		(net "P5E_PEX0_STN2_TX_DP<40>")
	)
	(segment
		(start 50.913538 -31.231332)
		(end 51.039268 -31.231078)
		(width 0.1651)
		(layer "In11.Cu")
		(net "P5E_PEX0_STN2_TX_DP<40>")
	)
	(segment
		(start 50.49266 -269.820898)
		(end 50.49266 -271.105122)
		(width 0.1651)
		(layer "In11.Cu")
		(net "P5E_PEX0_STN2_TX_DP<40>")
	)
	(segment
		(start 49.145444 -29.349192)
		(end 49.732438 -29.93263)
		(width 0.1651)
		(layer "In11.Cu")
		(net "P5E_PEX0_STN2_TX_DP<40>")
	)
	(segment
		(start 50.484024 -271.399)
		(end 50.484024 -271.427448)
		(width 0.1143)
		(layer "In11.Cu")
		(net "P5E_PEX0_STN2_TX_DP<40>")
	)
	(segment
		(start 51.039268 -31.231078)
		(end 51.847242 -32.033972)
		(width 0.1651)
		(layer "In11.Cu")
		(net "P5E_PEX0_STN2_TX_DP<40>")
	)
	(segment
		(start 63.303404 -47.064676)
		(end 64.30137 -49.912524)
		(width 0.1651)
		(layer "In11.Cu")
		(net "P5E_PEX0_STN2_TX_DP<40>")
	)
	(segment
		(start 50.484024 -271.113758)
		(end 50.484024 -271.399)
		(width 0.1651)
		(layer "In11.Cu")
		(net "P5E_PEX0_STN2_TX_DP<40>")
	)
	(segment
		(start 53.582824 -34.872168)
		(end 63.303404 -47.064676)
		(width 0.1651)
		(layer "In11.Cu")
		(net "P5E_PEX0_STN2_TX_DP<40>")
	)
	(segment
		(start 49.732946 -30.05836)
		(end 50.084482 -30.40761)
		(width 0.1651)
		(layer "In11.Cu")
		(net "P5E_PEX0_STN2_TX_DP<40>")
	)
	(segment
		(start 56.148732 -135.243824)
		(end 49.845976 -252.613668)
		(width 0.1651)
		(layer "In11.Cu")
		(net "P5E_PEX0_STN2_TX_DP<40>")
	)
	(segment
		(start 50.985674 -280.319988)
		(end 51.099974 -280.434288)
		(width 0.1143)
		(layer "In11.Cu")
		(net "P5E_PEX0_STN2_TX_DP<40>")
	)
	(segment
		(start 50.529744 -271.473168)
		(end 50.529744 -280.10485)
		(width 0.1143)
		(layer "In11.Cu")
		(net "P5E_PEX0_STN2_TX_DP<40>")
	)
	(segment
		(start 64.538098 -69.570346)
		(end 57.49036 -119.281702)
		(width 0.1651)
		(layer "In11.Cu")
		(net "P5E_PEX0_STN2_TX_DP<40>")
	)
	(segment
		(start 50.561494 -30.756352)
		(end 50.561748 -30.882082)
		(width 0.1651)
		(layer "In11.Cu")
		(net "P5E_PEX0_STN2_TX_DP<40>")
	)
	(segment
		(start 47.88281 -28.823412)
		(end 49.145444 -29.349192)
		(width 0.1651)
		(layer "In11.Cu")
		(net "P5E_PEX0_STN2_TX_DP<40>")
	)
	(segment
		(start 50.561748 -30.882082)
		(end 50.913538 -31.231332)
		(width 0.1651)
		(layer "In11.Cu")
		(net "P5E_PEX0_STN2_TX_DP<40>")
	)
	(segment
		(start 49.732438 -29.93263)
		(end 49.732946 -30.05836)
		(width 0.1651)
		(layer "In11.Cu")
		(net "P5E_PEX0_STN2_TX_DP<40>")
	)
	(segment
		(start 64.963802 -60.607194)
		(end 64.538098 -69.570346)
		(width 0.1651)
		(layer "In11.Cu")
		(net "P5E_PEX0_STN2_TX_DP<40>")
	)
	(segment
		(start 51.099974 -280.434288)
		(end 51.099974 -280.699718)
		(width 0.1143)
		(layer "In11.Cu")
		(net "P5E_PEX0_STN2_TX_DP<40>")
	)
	(segment
		(start 137.028428 -343.365582)
		(end 137.028428 -342.734138)
		(width 0.13462)
		(layer "F.Cu")
		(net "P5E_PEX1_STN5_TX_DP<91>")
	)
	(segment
		(start 137.028428 -342.734138)
		(end 136.733788 -342.439498)
		(width 0.13462)
		(layer "F.Cu")
		(net "P5E_PEX1_STN5_TX_DP<91>")
	)
	(segment
		(start 136.708388 -343.685622)
		(end 137.028428 -343.365582)
		(width 0.13462)
		(layer "F.Cu")
		(net "P5E_PEX1_STN5_TX_DP<91>")
	)
	(segment
		(start 174.234856 -327.95718)
		(end 181.63921 -323.99859)
		(width 0.1651)
		(layer "In13.Cu")
		(net "P5E_PEX1_STN5_TX_DP<91>")
	)
	(segment
		(start 143.870172 -337.675474)
		(end 147.838414 -337.675474)
		(width 0.1651)
		(layer "In13.Cu")
		(net "P5E_PEX1_STN5_TX_DP<91>")
	)
	(segment
		(start 164.740082 -332.042516)
		(end 174.234856 -327.95718)
		(width 0.1651)
		(layer "In13.Cu")
		(net "P5E_PEX1_STN5_TX_DP<91>")
	)
	(segment
		(start 184.634124 -320.063114)
		(end 184.634124 -320.041016)
		(width 0.1143)
		(layer "In13.Cu")
		(net "P5E_PEX1_STN5_TX_DP<91>")
	)
	(segment
		(start 184.366916 -321.986656)
		(end 184.634124 -321.341496)
		(width 0.1651)
		(layer "In13.Cu")
		(net "P5E_PEX1_STN5_TX_DP<91>")
	)
	(segment
		(start 142.449042 -337.957922)
		(end 143.870172 -337.675474)
		(width 0.1651)
		(layer "In13.Cu")
		(net "P5E_PEX1_STN5_TX_DP<91>")
	)
	(segment
		(start 136.733788 -342.439498)
		(end 137.024618 -342.148668)
		(width 0.1651)
		(layer "In13.Cu")
		(net "P5E_PEX1_STN5_TX_DP<91>")
	)
	(segment
		(start 147.838414 -337.675474)
		(end 164.740082 -332.042516)
		(width 0.1651)
		(layer "In13.Cu")
		(net "P5E_PEX1_STN5_TX_DP<91>")
	)
	(segment
		(start 184.679844 -319.995296)
		(end 184.679844 -313.59475)
		(width 0.1143)
		(layer "In13.Cu")
		(net "P5E_PEX1_STN5_TX_DP<91>")
	)
	(segment
		(start 181.63921 -323.99859)
		(end 183.794654 -322.558918)
		(width 0.1651)
		(layer "In13.Cu")
		(net "P5E_PEX1_STN5_TX_DP<91>")
	)
	(segment
		(start 138.118342 -339.751924)
		(end 142.449042 -337.957922)
		(width 0.1651)
		(layer "In13.Cu")
		(net "P5E_PEX1_STN5_TX_DP<91>")
	)
	(segment
		(start 137.024618 -342.148668)
		(end 137.024618 -340.845648)
		(width 0.1651)
		(layer "In13.Cu")
		(net "P5E_PEX1_STN5_TX_DP<91>")
	)
	(segment
		(start 184.634124 -320.041016)
		(end 184.679844 -319.995296)
		(width 0.1143)
		(layer "In13.Cu")
		(net "P5E_PEX1_STN5_TX_DP<91>")
	)
	(segment
		(start 185.250074 -313.265312)
		(end 185.250074 -312.999882)
		(width 0.1143)
		(layer "In13.Cu")
		(net "P5E_PEX1_STN5_TX_DP<91>")
	)
	(segment
		(start 184.679844 -313.59475)
		(end 184.894982 -313.379612)
		(width 0.1143)
		(layer "In13.Cu")
		(net "P5E_PEX1_STN5_TX_DP<91>")
	)
	(segment
		(start 183.794654 -322.558918)
		(end 184.366916 -321.986656)
		(width 0.1651)
		(layer "In13.Cu")
		(net "P5E_PEX1_STN5_TX_DP<91>")
	)
	(segment
		(start 137.024618 -340.845648)
		(end 138.118342 -339.751924)
		(width 0.1651)
		(layer "In13.Cu")
		(net "P5E_PEX1_STN5_TX_DP<91>")
	)
	(segment
		(start 185.135774 -313.379612)
		(end 185.250074 -313.265312)
		(width 0.1143)
		(layer "In13.Cu")
		(net "P5E_PEX1_STN5_TX_DP<91>")
	)
	(segment
		(start 184.894982 -313.379612)
		(end 185.135774 -313.379612)
		(width 0.1143)
		(layer "In13.Cu")
		(net "P5E_PEX1_STN5_TX_DP<91>")
	)
	(segment
		(start 184.634124 -321.341496)
		(end 184.634124 -320.063114)
		(width 0.1651)
		(layer "In13.Cu")
		(net "P5E_PEX1_STN5_TX_DP<91>")
	)
	(segment
		(start 277.219664 -32.13608)
		(end 276.569932 -32.13608)
		(width 0.13462)
		(layer "F.Cu")
		(net "P5E_PEX2_STN2_TX_DN<42>")
	)
	(segment
		(start 277.50516 -31.850584)
		(end 277.219664 -32.13608)
		(width 0.13462)
		(layer "F.Cu")
		(net "P5E_PEX2_STN2_TX_DN<42>")
	)
	(segment
		(start 276.569932 -32.13608)
		(end 276.259036 -31.825184)
		(width 0.13462)
		(layer "F.Cu")
		(net "P5E_PEX2_STN2_TX_DN<42>")
	)
	(segment
		(start 294.010588 -68.660264)
		(end 283.732732 -95.804736)
		(width 0.1651)
		(layer "In11.Cu")
		(net "P5E_PEX2_STN2_TX_DN<42>")
	)
	(segment
		(start 294.225218 -48.492156)
		(end 294.868854 -50.37074)
		(width 0.1651)
		(layer "In11.Cu")
		(net "P5E_PEX2_STN2_TX_DN<42>")
	)
	(segment
		(start 281.065732 -271.399)
		(end 281.065732 -271.427448)
		(width 0.1143)
		(layer "In11.Cu")
		(net "P5E_PEX2_STN2_TX_DN<42>")
	)
	(segment
		(start 281.065732 -271.427448)
		(end 281.020012 -271.473168)
		(width 0.1143)
		(layer "In11.Cu")
		(net "P5E_PEX2_STN2_TX_DN<42>")
	)
	(segment
		(start 277.221696 -161.959544)
		(end 280.73477 -267.065252)
		(width 0.1651)
		(layer "In11.Cu")
		(net "P5E_PEX2_STN2_TX_DN<42>")
	)
	(segment
		(start 281.020012 -280.025856)
		(end 281.123644 -280.129488)
		(width 0.1143)
		(layer "In11.Cu")
		(net "P5E_PEX2_STN2_TX_DN<42>")
	)
	(segment
		(start 278.582628 -141.886686)
		(end 277.221696 -161.959544)
		(width 0.1651)
		(layer "In11.Cu")
		(net "P5E_PEX2_STN2_TX_DN<42>")
	)
	(segment
		(start 281.285442 -280.129488)
		(end 281.399742 -280.015188)
		(width 0.1143)
		(layer "In11.Cu")
		(net "P5E_PEX2_STN2_TX_DN<42>")
	)
	(segment
		(start 278.322024 -116.032026)
		(end 278.582628 -141.886686)
		(width 0.1651)
		(layer "In11.Cu")
		(net "P5E_PEX2_STN2_TX_DN<42>")
	)
	(segment
		(start 277.79599 -32.141414)
		(end 280.665428 -32.141414)
		(width 0.1651)
		(layer "In11.Cu")
		(net "P5E_PEX2_STN2_TX_DN<42>")
	)
	(segment
		(start 281.399742 -280.015188)
		(end 281.399742 -279.749504)
		(width 0.1143)
		(layer "In11.Cu")
		(net "P5E_PEX2_STN2_TX_DN<42>")
	)
	(segment
		(start 280.73477 -267.065252)
		(end 281.065732 -270.426688)
		(width 0.1651)
		(layer "In11.Cu")
		(net "P5E_PEX2_STN2_TX_DN<42>")
	)
	(segment
		(start 294.868854 -50.37074)
		(end 295.506648 -60.466732)
		(width 0.1651)
		(layer "In11.Cu")
		(net "P5E_PEX2_STN2_TX_DN<42>")
	)
	(segment
		(start 281.261312 -32.319468)
		(end 283.497274 -34.599372)
		(width 0.1651)
		(layer "In11.Cu")
		(net "P5E_PEX2_STN2_TX_DN<42>")
	)
	(segment
		(start 277.50516 -31.850584)
		(end 277.79599 -32.141414)
		(width 0.1651)
		(layer "In11.Cu")
		(net "P5E_PEX2_STN2_TX_DN<42>")
	)
	(segment
		(start 283.497274 -34.599372)
		(end 294.225218 -48.492156)
		(width 0.1651)
		(layer "In11.Cu")
		(net "P5E_PEX2_STN2_TX_DN<42>")
	)
	(segment
		(start 280.665428 -32.141414)
		(end 281.261312 -32.319468)
		(width 0.1651)
		(layer "In11.Cu")
		(net "P5E_PEX2_STN2_TX_DN<42>")
	)
	(segment
		(start 283.732732 -95.804736)
		(end 278.322024 -116.032026)
		(width 0.1651)
		(layer "In11.Cu")
		(net "P5E_PEX2_STN2_TX_DN<42>")
	)
	(segment
		(start 281.123644 -280.129488)
		(end 281.285442 -280.129488)
		(width 0.1143)
		(layer "In11.Cu")
		(net "P5E_PEX2_STN2_TX_DN<42>")
	)
	(segment
		(start 281.065732 -270.426688)
		(end 281.065732 -271.399)
		(width 0.1651)
		(layer "In11.Cu")
		(net "P5E_PEX2_STN2_TX_DN<42>")
	)
	(segment
		(start 295.506648 -60.466732)
		(end 294.010588 -68.660264)
		(width 0.1651)
		(layer "In11.Cu")
		(net "P5E_PEX2_STN2_TX_DN<42>")
	)
	(segment
		(start 281.020012 -271.473168)
		(end 281.020012 -280.025856)
		(width 0.1143)
		(layer "In11.Cu")
		(net "P5E_PEX2_STN2_TX_DN<42>")
	)
	(segment
		(start 337.349084 -355.978206)
		(end 337.669124 -355.658166)
		(width 0.13462)
		(layer "F.Cu")
		(net "P5E_PEX2_STN6_TX_DP<99>")
	)
	(segment
		(start 337.669124 -355.658166)
		(end 337.669124 -355.026722)
		(width 0.13462)
		(layer "F.Cu")
		(net "P5E_PEX2_STN6_TX_DP<99>")
	)
	(segment
		(start 337.669124 -355.026722)
		(end 337.374484 -354.732082)
		(width 0.13462)
		(layer "F.Cu")
		(net "P5E_PEX2_STN6_TX_DP<99>")
	)
	(segment
		(start 286.68345 -322.312538)
		(end 286.483806 -321.830446)
		(width 0.1651)
		(layer "In13.Cu")
		(net "P5E_PEX2_STN6_TX_DP<99>")
	)
	(segment
		(start 286.529526 -311.69483)
		(end 286.744664 -311.479692)
		(width 0.1143)
		(layer "In13.Cu")
		(net "P5E_PEX2_STN6_TX_DP<99>")
	)
	(segment
		(start 286.483806 -320.046096)
		(end 286.483806 -320.017648)
		(width 0.1143)
		(layer "In13.Cu")
		(net "P5E_PEX2_STN6_TX_DP<99>")
	)
	(segment
		(start 337.665314 -353.814126)
		(end 339.219794 -352.259646)
		(width 0.1651)
		(layer "In13.Cu")
		(net "P5E_PEX2_STN6_TX_DP<99>")
	)
	(segment
		(start 339.219794 -352.259646)
		(end 339.219794 -342.217502)
		(width 0.1651)
		(layer "In13.Cu")
		(net "P5E_PEX2_STN6_TX_DP<99>")
	)
	(segment
		(start 286.529526 -319.971928)
		(end 286.529526 -311.69483)
		(width 0.1143)
		(layer "In13.Cu")
		(net "P5E_PEX2_STN6_TX_DP<99>")
	)
	(segment
		(start 337.374484 -354.732082)
		(end 337.665314 -354.441252)
		(width 0.1651)
		(layer "In13.Cu")
		(net "P5E_PEX2_STN6_TX_DP<99>")
	)
	(segment
		(start 334.037178 -336.721704)
		(end 314.900818 -328.094086)
		(width 0.1651)
		(layer "In13.Cu")
		(net "P5E_PEX2_STN6_TX_DP<99>")
	)
	(segment
		(start 337.665314 -354.441252)
		(end 337.665314 -353.814126)
		(width 0.1651)
		(layer "In13.Cu")
		(net "P5E_PEX2_STN6_TX_DP<99>")
	)
	(segment
		(start 286.483806 -320.017648)
		(end 286.529526 -319.971928)
		(width 0.1143)
		(layer "In13.Cu")
		(net "P5E_PEX2_STN6_TX_DP<99>")
	)
	(segment
		(start 286.985456 -311.479692)
		(end 287.099756 -311.365392)
		(width 0.1143)
		(layer "In13.Cu")
		(net "P5E_PEX2_STN6_TX_DP<99>")
	)
	(segment
		(start 286.987996 -322.617084)
		(end 286.68345 -322.312538)
		(width 0.1651)
		(layer "In13.Cu")
		(net "P5E_PEX2_STN6_TX_DP<99>")
	)
	(segment
		(start 287.099756 -311.365392)
		(end 287.099756 -311.099962)
		(width 0.1143)
		(layer "In13.Cu")
		(net "P5E_PEX2_STN6_TX_DP<99>")
	)
	(segment
		(start 286.483806 -321.830446)
		(end 286.483806 -320.046096)
		(width 0.1651)
		(layer "In13.Cu")
		(net "P5E_PEX2_STN6_TX_DP<99>")
	)
	(segment
		(start 314.900818 -328.094086)
		(end 286.987996 -322.617084)
		(width 0.1651)
		(layer "In13.Cu")
		(net "P5E_PEX2_STN6_TX_DP<99>")
	)
	(segment
		(start 286.744664 -311.479692)
		(end 286.985456 -311.479692)
		(width 0.1143)
		(layer "In13.Cu")
		(net "P5E_PEX2_STN6_TX_DP<99>")
	)
	(segment
		(start 339.219794 -342.217502)
		(end 338.649056 -341.286338)
		(width 0.1651)
		(layer "In13.Cu")
		(net "P5E_PEX2_STN6_TX_DP<99>")
	)
	(segment
		(start 338.649056 -341.286338)
		(end 334.037178 -336.721704)
		(width 0.1651)
		(layer "In13.Cu")
		(net "P5E_PEX2_STN6_TX_DP<99>")
	)
	(segment
		(start 431.545238 -132.0038)
		(end 431.228246 -131.686808)
		(width 0.13462)
		(layer "F.Cu")
		(net "P5E_PEX3_STN0_TX_DN<5>")
	)
	(segment
		(start 432.182778 -132.0038)
		(end 431.545238 -132.0038)
		(width 0.13462)
		(layer "F.Cu")
		(net "P5E_PEX3_STN0_TX_DN<5>")
	)
	(segment
		(start 432.47437 -131.712208)
		(end 432.182778 -132.0038)
		(width 0.13462)
		(layer "F.Cu")
		(net "P5E_PEX3_STN0_TX_DN<5>")
	)
	(segment
		(start 443.632844 -159.328104)
		(end 434.977286 -174.326042)
		(width 0.1651)
		(layer "In9.Cu")
		(net "P5E_PEX3_STN0_TX_DN<5>")
	)
	(segment
		(start 432.119532 -283.169868)
		(end 423.823892 -283.169868)
		(width 0.1143)
		(layer "In9.Cu")
		(net "P5E_PEX3_STN0_TX_DN<5>")
	)
	(segment
		(start 423.720006 -283.273754)
		(end 423.720006 -283.435552)
		(width 0.1143)
		(layer "In9.Cu")
		(net "P5E_PEX3_STN0_TX_DN<5>")
	)
	(segment
		(start 432.653186 -251.048012)
		(end 443.123574 -266.71778)
		(width 0.1651)
		(layer "In9.Cu")
		(net "P5E_PEX3_STN0_TX_DN<5>")
	)
	(segment
		(start 435.19344 -133.728206)
		(end 439.708036 -144.627092)
		(width 0.1651)
		(layer "In9.Cu")
		(net "P5E_PEX3_STN0_TX_DN<5>")
	)
	(segment
		(start 439.708036 -144.627092)
		(end 440.097418 -145.016474)
		(width 0.1651)
		(layer "In9.Cu")
		(net "P5E_PEX3_STN0_TX_DN<5>")
	)
	(segment
		(start 432.47437 -131.712208)
		(end 432.7652 -132.003038)
		(width 0.1651)
		(layer "In9.Cu")
		(net "P5E_PEX3_STN0_TX_DN<5>")
	)
	(segment
		(start 434.977286 -174.326042)
		(end 433.862734 -178.482244)
		(width 0.1651)
		(layer "In9.Cu")
		(net "P5E_PEX3_STN0_TX_DN<5>")
	)
	(segment
		(start 433.862734 -178.482244)
		(end 430.086008 -221.652592)
		(width 0.1651)
		(layer "In9.Cu")
		(net "P5E_PEX3_STN0_TX_DN<5>")
	)
	(segment
		(start 432.1937 -283.215588)
		(end 432.165252 -283.215588)
		(width 0.1143)
		(layer "In9.Cu")
		(net "P5E_PEX3_STN0_TX_DN<5>")
	)
	(segment
		(start 432.7652 -132.003038)
		(end 433.468272 -132.003038)
		(width 0.1651)
		(layer "In9.Cu")
		(net "P5E_PEX3_STN0_TX_DN<5>")
	)
	(segment
		(start 432.165252 -283.215588)
		(end 432.119532 -283.169868)
		(width 0.1143)
		(layer "In9.Cu")
		(net "P5E_PEX3_STN0_TX_DN<5>")
	)
	(segment
		(start 433.468272 -132.003038)
		(end 435.19344 -133.728206)
		(width 0.1651)
		(layer "In9.Cu")
		(net "P5E_PEX3_STN0_TX_DN<5>")
	)
	(segment
		(start 423.834306 -283.549852)
		(end 424.09999 -283.549852)
		(width 0.1143)
		(layer "In9.Cu")
		(net "P5E_PEX3_STN0_TX_DN<5>")
	)
	(segment
		(start 444.139574 -272.00225)
		(end 443.225428 -274.208494)
		(width 0.1651)
		(layer "In9.Cu")
		(net "P5E_PEX3_STN0_TX_DN<5>")
	)
	(segment
		(start 430.086008 -221.652592)
		(end 432.653186 -251.048012)
		(width 0.1651)
		(layer "In9.Cu")
		(net "P5E_PEX3_STN0_TX_DN<5>")
	)
	(segment
		(start 433.127658 -283.215588)
		(end 432.1937 -283.215588)
		(width 0.1651)
		(layer "In9.Cu")
		(net "P5E_PEX3_STN0_TX_DN<5>")
	)
	(segment
		(start 443.123574 -266.71778)
		(end 443.825376 -268.412468)
		(width 0.1651)
		(layer "In9.Cu")
		(net "P5E_PEX3_STN0_TX_DN<5>")
	)
	(segment
		(start 434.989732 -282.44419)
		(end 433.127658 -283.215588)
		(width 0.1651)
		(layer "In9.Cu")
		(net "P5E_PEX3_STN0_TX_DN<5>")
	)
	(segment
		(start 443.225428 -274.208494)
		(end 434.989732 -282.44419)
		(width 0.1651)
		(layer "In9.Cu")
		(net "P5E_PEX3_STN0_TX_DN<5>")
	)
	(segment
		(start 423.720006 -283.435552)
		(end 423.834306 -283.549852)
		(width 0.1143)
		(layer "In9.Cu")
		(net "P5E_PEX3_STN0_TX_DN<5>")
	)
	(segment
		(start 443.632844 -153.55189)
		(end 443.632844 -159.328104)
		(width 0.1651)
		(layer "In9.Cu")
		(net "P5E_PEX3_STN0_TX_DN<5>")
	)
	(segment
		(start 443.825376 -268.412468)
		(end 444.139574 -272.00225)
		(width 0.1651)
		(layer "In9.Cu")
		(net "P5E_PEX3_STN0_TX_DN<5>")
	)
	(segment
		(start 423.823892 -283.169868)
		(end 423.720006 -283.273754)
		(width 0.1143)
		(layer "In9.Cu")
		(net "P5E_PEX3_STN0_TX_DN<5>")
	)
	(segment
		(start 440.097418 -145.016474)
		(end 443.632844 -153.55189)
		(width 0.1651)
		(layer "In9.Cu")
		(net "P5E_PEX3_STN0_TX_DN<5>")
	)
	(segment
		(start 387.026912 -349.512382)
		(end 387.026912 -348.879922)
		(width 0.13462)
		(layer "F.Cu")
		(net "P5E_PEX3_STN6_TX_DP<104>")
	)
	(segment
		(start 386.70738 -349.831914)
		(end 387.026912 -349.512382)
		(width 0.13462)
		(layer "F.Cu")
		(net "P5E_PEX3_STN6_TX_DP<104>")
	)
	(segment
		(start 387.026912 -348.879922)
		(end 386.73278 -348.58579)
		(width 0.13462)
		(layer "F.Cu")
		(net "P5E_PEX3_STN6_TX_DP<104>")
	)
	(segment
		(start 397.87957 -319.971928)
		(end 397.87957 -313.59475)
		(width 0.1143)
		(layer "In13.Cu")
		(net "P5E_PEX3_STN6_TX_DP<104>")
	)
	(segment
		(start 397.83385 -320.017648)
		(end 397.87957 -319.971928)
		(width 0.1143)
		(layer "In13.Cu")
		(net "P5E_PEX3_STN6_TX_DP<104>")
	)
	(segment
		(start 398.3355 -313.379612)
		(end 398.4498 -313.265312)
		(width 0.1143)
		(layer "In13.Cu")
		(net "P5E_PEX3_STN6_TX_DP<104>")
	)
	(segment
		(start 398.4498 -313.265312)
		(end 398.4498 -312.999882)
		(width 0.1143)
		(layer "In13.Cu")
		(net "P5E_PEX3_STN6_TX_DP<104>")
	)
	(segment
		(start 387.02361 -347.667834)
		(end 388.57809 -346.113354)
		(width 0.1651)
		(layer "In13.Cu")
		(net "P5E_PEX3_STN6_TX_DP<104>")
	)
	(segment
		(start 388.57809 -346.113354)
		(end 388.57809 -341.77732)
		(width 0.1651)
		(layer "In13.Cu")
		(net "P5E_PEX3_STN6_TX_DP<104>")
	)
	(segment
		(start 398.094708 -313.379612)
		(end 398.3355 -313.379612)
		(width 0.1143)
		(layer "In13.Cu")
		(net "P5E_PEX3_STN6_TX_DP<104>")
	)
	(segment
		(start 397.87957 -313.59475)
		(end 398.094708 -313.379612)
		(width 0.1143)
		(layer "In13.Cu")
		(net "P5E_PEX3_STN6_TX_DP<104>")
	)
	(segment
		(start 388.57809 -341.77732)
		(end 397.83385 -322.659502)
		(width 0.1651)
		(layer "In13.Cu")
		(net "P5E_PEX3_STN6_TX_DP<104>")
	)
	(segment
		(start 397.83385 -322.659502)
		(end 397.83385 -320.046096)
		(width 0.1651)
		(layer "In13.Cu")
		(net "P5E_PEX3_STN6_TX_DP<104>")
	)
	(segment
		(start 387.02361 -348.29496)
		(end 387.02361 -347.667834)
		(width 0.1651)
		(layer "In13.Cu")
		(net "P5E_PEX3_STN6_TX_DP<104>")
	)
	(segment
		(start 397.83385 -320.046096)
		(end 397.83385 -320.017648)
		(width 0.1143)
		(layer "In13.Cu")
		(net "P5E_PEX3_STN6_TX_DP<104>")
	)
	(segment
		(start 386.73278 -348.58579)
		(end 387.02361 -348.29496)
		(width 0.1651)
		(layer "In13.Cu")
		(net "P5E_PEX3_STN6_TX_DP<104>")
	)
	(segment
		(start 47.021496 -33.95218)
		(end 46.701202 -33.631886)
		(width 0.13462)
		(layer "F.Cu")
		(net "P5E_PEX0_STN2_TX_DN<43>")
	)
	(segment
		(start 47.652432 -33.95218)
		(end 47.021496 -33.95218)
		(width 0.13462)
		(layer "F.Cu")
		(net "P5E_PEX0_STN2_TX_DN<43>")
	)
	(segment
		(start 47.947326 -33.657286)
		(end 47.652432 -33.95218)
		(width 0.13462)
		(layer "F.Cu")
		(net "P5E_PEX0_STN2_TX_DN<43>")
	)
	(segment
		(start 61.230256 -49.134776)
		(end 61.6966 -50.493168)
		(width 0.1651)
		(layer "In11.Cu")
		(net "P5E_PEX0_STN2_TX_DN<43>")
	)
	(segment
		(start 43.06189 -115.22456)
		(end 42.801286 -116.459254)
		(width 0.1651)
		(layer "In11.Cu")
		(net "P5E_PEX0_STN2_TX_DN<43>")
	)
	(segment
		(start 47.91583 -269.62354)
		(end 47.91583 -271.399)
		(width 0.1651)
		(layer "In11.Cu")
		(net "P5E_PEX0_STN2_TX_DN<43>")
	)
	(segment
		(start 47.91583 -271.427448)
		(end 47.87011 -271.473168)
		(width 0.1143)
		(layer "In11.Cu")
		(net "P5E_PEX0_STN2_TX_DN<43>")
	)
	(segment
		(start 50.952908 -35.769296)
		(end 61.230256 -49.134776)
		(width 0.1651)
		(layer "In11.Cu")
		(net "P5E_PEX0_STN2_TX_DN<43>")
	)
	(segment
		(start 48.24984 -278.115268)
		(end 48.24984 -277.849838)
		(width 0.1143)
		(layer "In11.Cu")
		(net "P5E_PEX0_STN2_TX_DN<43>")
	)
	(segment
		(start 47.947326 -33.657286)
		(end 48.238156 -33.948116)
		(width 0.1651)
		(layer "In11.Cu")
		(net "P5E_PEX0_STN2_TX_DN<43>")
	)
	(segment
		(start 42.793666 -146.80565)
		(end 43.856402 -162.530282)
		(width 0.1651)
		(layer "In11.Cu")
		(net "P5E_PEX0_STN2_TX_DN<43>")
	)
	(segment
		(start 48.13554 -278.229568)
		(end 48.24984 -278.115268)
		(width 0.1143)
		(layer "In11.Cu")
		(net "P5E_PEX0_STN2_TX_DN<43>")
	)
	(segment
		(start 47.534576 -265.75258)
		(end 47.91583 -269.62354)
		(width 0.1651)
		(layer "In11.Cu")
		(net "P5E_PEX0_STN2_TX_DN<43>")
	)
	(segment
		(start 47.87011 -278.125936)
		(end 47.973742 -278.229568)
		(width 0.1143)
		(layer "In11.Cu")
		(net "P5E_PEX0_STN2_TX_DN<43>")
	)
	(segment
		(start 62.32779 -60.360052)
		(end 60.836556 -68.48983)
		(width 0.1651)
		(layer "In11.Cu")
		(net "P5E_PEX0_STN2_TX_DN<43>")
	)
	(segment
		(start 47.973742 -278.229568)
		(end 48.13554 -278.229568)
		(width 0.1143)
		(layer "In11.Cu")
		(net "P5E_PEX0_STN2_TX_DN<43>")
	)
	(segment
		(start 47.91583 -271.399)
		(end 47.91583 -271.427448)
		(width 0.1143)
		(layer "In11.Cu")
		(net "P5E_PEX0_STN2_TX_DN<43>")
	)
	(segment
		(start 48.238156 -33.948116)
		(end 49.15916 -33.948116)
		(width 0.1651)
		(layer "In11.Cu")
		(net "P5E_PEX0_STN2_TX_DN<43>")
	)
	(segment
		(start 60.836556 -68.48983)
		(end 50.621184 -95.476568)
		(width 0.1651)
		(layer "In11.Cu")
		(net "P5E_PEX0_STN2_TX_DN<43>")
	)
	(segment
		(start 45.779182 -111.782606)
		(end 44.560744 -112.983264)
		(width 0.1651)
		(layer "In11.Cu")
		(net "P5E_PEX0_STN2_TX_DN<43>")
	)
	(segment
		(start 47.87011 -271.473168)
		(end 47.87011 -278.125936)
		(width 0.1143)
		(layer "In11.Cu")
		(net "P5E_PEX0_STN2_TX_DN<43>")
	)
	(segment
		(start 44.560744 -112.983264)
		(end 43.06189 -115.22456)
		(width 0.1651)
		(layer "In11.Cu")
		(net "P5E_PEX0_STN2_TX_DN<43>")
	)
	(segment
		(start 50.621184 -95.476568)
		(end 48.936148 -101.666802)
		(width 0.1651)
		(layer "In11.Cu")
		(net "P5E_PEX0_STN2_TX_DN<43>")
	)
	(segment
		(start 42.801286 -116.459254)
		(end 42.793666 -146.80565)
		(width 0.1651)
		(layer "In11.Cu")
		(net "P5E_PEX0_STN2_TX_DN<43>")
	)
	(segment
		(start 49.15916 -33.948116)
		(end 50.952908 -35.769296)
		(width 0.1651)
		(layer "In11.Cu")
		(net "P5E_PEX0_STN2_TX_DN<43>")
	)
	(segment
		(start 43.856402 -162.530282)
		(end 47.534576 -265.75258)
		(width 0.1651)
		(layer "In11.Cu")
		(net "P5E_PEX0_STN2_TX_DN<43>")
	)
	(segment
		(start 48.936148 -101.666802)
		(end 45.779182 -111.782606)
		(width 0.1651)
		(layer "In11.Cu")
		(net "P5E_PEX0_STN2_TX_DN<43>")
	)
	(segment
		(start 61.6966 -50.493168)
		(end 62.32779 -60.360052)
		(width 0.1651)
		(layer "In11.Cu")
		(net "P5E_PEX0_STN2_TX_DN<43>")
	)
	(segment
		(start 140.137388 -343.365582)
		(end 140.137388 -342.734138)
		(width 0.13462)
		(layer "F.Cu")
		(net "P5E_PEX1_STN5_TX_DP<85>")
	)
	(segment
		(start 140.137388 -342.734138)
		(end 139.842748 -342.439498)
		(width 0.13462)
		(layer "F.Cu")
		(net "P5E_PEX1_STN5_TX_DP<85>")
	)
	(segment
		(start 139.817348 -343.685622)
		(end 140.137388 -343.365582)
		(width 0.13462)
		(layer "F.Cu")
		(net "P5E_PEX1_STN5_TX_DP<85>")
	)
	(segment
		(start 140.133578 -341.519764)
		(end 140.379704 -341.187786)
		(width 0.1651)
		(layer "In7.Cu")
		(net "P5E_PEX1_STN5_TX_DP<85>")
	)
	(segment
		(start 178.93411 -319.97396)
		(end 178.97983 -319.92824)
		(width 0.1143)
		(layer "In7.Cu")
		(net "P5E_PEX1_STN5_TX_DP<85>")
	)
	(segment
		(start 174.9425 -329.451716)
		(end 177.984912 -326.409304)
		(width 0.1651)
		(layer "In7.Cu")
		(net "P5E_PEX1_STN5_TX_DP<85>")
	)
	(segment
		(start 140.379704 -341.187786)
		(end 170.71467 -331.985874)
		(width 0.1651)
		(layer "In7.Cu")
		(net "P5E_PEX1_STN5_TX_DP<85>")
	)
	(segment
		(start 177.984912 -326.409304)
		(end 178.93411 -324.117462)
		(width 0.1651)
		(layer "In7.Cu")
		(net "P5E_PEX1_STN5_TX_DP<85>")
	)
	(segment
		(start 179.43576 -313.379612)
		(end 179.55006 -313.265312)
		(width 0.1143)
		(layer "In7.Cu")
		(net "P5E_PEX1_STN5_TX_DP<85>")
	)
	(segment
		(start 170.71467 -331.985874)
		(end 174.9425 -329.451716)
		(width 0.1651)
		(layer "In7.Cu")
		(net "P5E_PEX1_STN5_TX_DP<85>")
	)
	(segment
		(start 178.93411 -324.117462)
		(end 178.93411 -320.002408)
		(width 0.1651)
		(layer "In7.Cu")
		(net "P5E_PEX1_STN5_TX_DP<85>")
	)
	(segment
		(start 178.97983 -319.92824)
		(end 178.97983 -313.605418)
		(width 0.1143)
		(layer "In7.Cu")
		(net "P5E_PEX1_STN5_TX_DP<85>")
	)
	(segment
		(start 179.205636 -313.379612)
		(end 179.43576 -313.379612)
		(width 0.1143)
		(layer "In7.Cu")
		(net "P5E_PEX1_STN5_TX_DP<85>")
	)
	(segment
		(start 178.97983 -313.605418)
		(end 179.205636 -313.379612)
		(width 0.1143)
		(layer "In7.Cu")
		(net "P5E_PEX1_STN5_TX_DP<85>")
	)
	(segment
		(start 139.842748 -342.439498)
		(end 140.133578 -342.148668)
		(width 0.1651)
		(layer "In7.Cu")
		(net "P5E_PEX1_STN5_TX_DP<85>")
	)
	(segment
		(start 179.55006 -313.265312)
		(end 179.55006 -312.999882)
		(width 0.1143)
		(layer "In7.Cu")
		(net "P5E_PEX1_STN5_TX_DP<85>")
	)
	(segment
		(start 140.133578 -342.148668)
		(end 140.133578 -341.519764)
		(width 0.1651)
		(layer "In7.Cu")
		(net "P5E_PEX1_STN5_TX_DP<85>")
	)
	(segment
		(start 178.93411 -320.002408)
		(end 178.93411 -319.97396)
		(width 0.1143)
		(layer "In7.Cu")
		(net "P5E_PEX1_STN5_TX_DP<85>")
	)
	(segment
		(start 325.827644 -349.831914)
		(end 325.507604 -349.511874)
		(width 0.13462)
		(layer "F.Cu")
		(net "P5E_PEX2_STN5_TX_DN<86>")
	)
	(segment
		(start 325.507604 -349.511874)
		(end 325.507604 -348.88043)
		(width 0.13462)
		(layer "F.Cu")
		(net "P5E_PEX2_STN5_TX_DN<86>")
	)
	(segment
		(start 325.507604 -348.88043)
		(end 325.802244 -348.58579)
		(width 0.13462)
		(layer "F.Cu")
		(net "P5E_PEX2_STN5_TX_DN<86>")
	)
	(segment
		(start 303.791366 -329.855068)
		(end 303.750726 -329.755246)
		(width 0.1651)
		(layer "In7.Cu")
		(net "P5E_PEX2_STN5_TX_DN<86>")
	)
	(segment
		(start 296.265854 -319.8622)
		(end 296.220134 -319.81648)
		(width 0.1143)
		(layer "In7.Cu")
		(net "P5E_PEX2_STN5_TX_DN<86>")
	)
	(segment
		(start 296.485564 -311.670192)
		(end 296.599864 -311.784492)
		(width 0.1143)
		(layer "In7.Cu")
		(net "P5E_PEX2_STN5_TX_DN<86>")
	)
	(segment
		(start 296.265854 -321.719194)
		(end 296.265854 -319.890648)
		(width 0.1651)
		(layer "In7.Cu")
		(net "P5E_PEX2_STN5_TX_DN<86>")
	)
	(segment
		(start 327.065894 -346.230194)
		(end 327.065894 -341.9348)
		(width 0.1651)
		(layer "In7.Cu")
		(net "P5E_PEX2_STN5_TX_DN<86>")
	)
	(segment
		(start 296.220134 -319.81648)
		(end 296.220134 -311.784492)
		(width 0.1143)
		(layer "In7.Cu")
		(net "P5E_PEX2_STN5_TX_DN<86>")
	)
	(segment
		(start 325.802244 -348.58579)
		(end 325.511414 -348.29496)
		(width 0.1651)
		(layer "In7.Cu")
		(net "P5E_PEX2_STN5_TX_DN<86>")
	)
	(segment
		(start 321.807078 -337.446112)
		(end 303.791366 -329.855068)
		(width 0.1651)
		(layer "In7.Cu")
		(net "P5E_PEX2_STN5_TX_DN<86>")
	)
	(segment
		(start 325.511414 -348.29496)
		(end 325.511414 -347.784674)
		(width 0.1651)
		(layer "In7.Cu")
		(net "P5E_PEX2_STN5_TX_DN<86>")
	)
	(segment
		(start 296.220134 -311.784492)
		(end 296.334434 -311.670192)
		(width 0.1143)
		(layer "In7.Cu")
		(net "P5E_PEX2_STN5_TX_DN<86>")
	)
	(segment
		(start 296.599864 -311.784492)
		(end 296.599864 -312.049922)
		(width 0.1143)
		(layer "In7.Cu")
		(net "P5E_PEX2_STN5_TX_DN<86>")
	)
	(segment
		(start 303.750726 -329.755246)
		(end 303.294034 -329.562714)
		(width 0.1651)
		(layer "In7.Cu")
		(net "P5E_PEX2_STN5_TX_DN<86>")
	)
	(segment
		(start 326.00138 -340.231222)
		(end 321.807078 -337.446112)
		(width 0.1651)
		(layer "In7.Cu")
		(net "P5E_PEX2_STN5_TX_DN<86>")
	)
	(segment
		(start 303.194466 -329.603354)
		(end 300.329092 -328.396092)
		(width 0.1651)
		(layer "In7.Cu")
		(net "P5E_PEX2_STN5_TX_DN<86>")
	)
	(segment
		(start 298.113958 -326.180958)
		(end 296.265854 -321.719194)
		(width 0.1651)
		(layer "In7.Cu")
		(net "P5E_PEX2_STN5_TX_DN<86>")
	)
	(segment
		(start 325.511414 -347.784674)
		(end 327.065894 -346.230194)
		(width 0.1651)
		(layer "In7.Cu")
		(net "P5E_PEX2_STN5_TX_DN<86>")
	)
	(segment
		(start 327.065894 -341.9348)
		(end 326.00138 -340.231222)
		(width 0.1651)
		(layer "In7.Cu")
		(net "P5E_PEX2_STN5_TX_DN<86>")
	)
	(segment
		(start 296.265854 -319.890648)
		(end 296.265854 -319.8622)
		(width 0.1143)
		(layer "In7.Cu")
		(net "P5E_PEX2_STN5_TX_DN<86>")
	)
	(segment
		(start 300.329092 -328.396092)
		(end 298.113958 -326.180958)
		(width 0.1651)
		(layer "In7.Cu")
		(net "P5E_PEX2_STN5_TX_DN<86>")
	)
	(segment
		(start 303.294034 -329.562714)
		(end 303.194466 -329.603354)
		(width 0.1651)
		(layer "In7.Cu")
		(net "P5E_PEX2_STN5_TX_DN<86>")
	)
	(segment
		(start 296.334434 -311.670192)
		(end 296.485564 -311.670192)
		(width 0.1143)
		(layer "In7.Cu")
		(net "P5E_PEX2_STN5_TX_DN<86>")
	)
	(segment
		(start 313.391804 -343.685622)
		(end 313.071764 -343.365582)
		(width 0.13462)
		(layer "F.Cu")
		(net "P5E_PEX2_STN6_TX_DN<111>")
	)
	(segment
		(start 313.071764 -343.365582)
		(end 313.071764 -342.734138)
		(width 0.13462)
		(layer "F.Cu")
		(net "P5E_PEX2_STN6_TX_DN<111>")
	)
	(segment
		(start 313.071764 -342.734138)
		(end 313.366404 -342.439498)
		(width 0.13462)
		(layer "F.Cu")
		(net "P5E_PEX2_STN6_TX_DN<111>")
	)
	(segment
		(start 313.075574 -341.51316)
		(end 312.430668 -340.868254)
		(width 0.1651)
		(layer "In13.Cu")
		(net "P5E_PEX2_STN6_TX_DN<111>")
	)
	(segment
		(start 275.585428 -311.670192)
		(end 275.699728 -311.784492)
		(width 0.1143)
		(layer "In13.Cu")
		(net "P5E_PEX2_STN6_TX_DN<111>")
	)
	(segment
		(start 275.699728 -311.784492)
		(end 275.699728 -312.049922)
		(width 0.1143)
		(layer "In13.Cu")
		(net "P5E_PEX2_STN6_TX_DN<111>")
	)
	(segment
		(start 275.42363 -311.670192)
		(end 275.585428 -311.670192)
		(width 0.1143)
		(layer "In13.Cu")
		(net "P5E_PEX2_STN6_TX_DN<111>")
	)
	(segment
		(start 312.430668 -340.868254)
		(end 290.220146 -336.221832)
		(width 0.1651)
		(layer "In13.Cu")
		(net "P5E_PEX2_STN6_TX_DN<111>")
	)
	(segment
		(start 275.319998 -311.773824)
		(end 275.42363 -311.670192)
		(width 0.1143)
		(layer "In13.Cu")
		(net "P5E_PEX2_STN6_TX_DN<111>")
	)
	(segment
		(start 289.65652 -336.00009)
		(end 289.536124 -336.078576)
		(width 0.1651)
		(layer "In13.Cu")
		(net "P5E_PEX2_STN6_TX_DN<111>")
	)
	(segment
		(start 275.319998 -319.921128)
		(end 275.319998 -311.773824)
		(width 0.1143)
		(layer "In13.Cu")
		(net "P5E_PEX2_STN6_TX_DN<111>")
	)
	(segment
		(start 290.220146 -336.221832)
		(end 290.141406 -336.101436)
		(width 0.1651)
		(layer "In13.Cu")
		(net "P5E_PEX2_STN6_TX_DN<111>")
	)
	(segment
		(start 282.000452 -334.502252)
		(end 276.718522 -329.220322)
		(width 0.1651)
		(layer "In13.Cu")
		(net "P5E_PEX2_STN6_TX_DN<111>")
	)
	(segment
		(start 276.718522 -329.220322)
		(end 275.365718 -325.95439)
		(width 0.1651)
		(layer "In13.Cu")
		(net "P5E_PEX2_STN6_TX_DN<111>")
	)
	(segment
		(start 313.366404 -342.439498)
		(end 313.075574 -342.148668)
		(width 0.1651)
		(layer "In13.Cu")
		(net "P5E_PEX2_STN6_TX_DN<111>")
	)
	(segment
		(start 290.141406 -336.101436)
		(end 289.65652 -336.00009)
		(width 0.1651)
		(layer "In13.Cu")
		(net "P5E_PEX2_STN6_TX_DN<111>")
	)
	(segment
		(start 275.365718 -325.95439)
		(end 275.365718 -319.995296)
		(width 0.1651)
		(layer "In13.Cu")
		(net "P5E_PEX2_STN6_TX_DN<111>")
	)
	(segment
		(start 289.536124 -336.078576)
		(end 282.000452 -334.502252)
		(width 0.1651)
		(layer "In13.Cu")
		(net "P5E_PEX2_STN6_TX_DN<111>")
	)
	(segment
		(start 275.365718 -319.966848)
		(end 275.319998 -319.921128)
		(width 0.1143)
		(layer "In13.Cu")
		(net "P5E_PEX2_STN6_TX_DN<111>")
	)
	(segment
		(start 313.075574 -342.148668)
		(end 313.075574 -341.51316)
		(width 0.1651)
		(layer "In13.Cu")
		(net "P5E_PEX2_STN6_TX_DN<111>")
	)
	(segment
		(start 275.365718 -319.995296)
		(end 275.365718 -319.966848)
		(width 0.1143)
		(layer "In13.Cu")
		(net "P5E_PEX2_STN6_TX_DN<111>")
	)
	(segment
		(start 429.533558 -119.26062)
		(end 428.910242 -119.26062)
		(width 0.13462)
		(layer "F.Cu")
		(net "P5E_PEX3_STN0_TX_DP<0>")
	)
	(segment
		(start 429.832262 -119.559324)
		(end 429.533558 -119.26062)
		(width 0.13462)
		(layer "F.Cu")
		(net "P5E_PEX3_STN0_TX_DP<0>")
	)
	(segment
		(start 428.910242 -119.26062)
		(end 428.586138 -119.584724)
		(width 0.13462)
		(layer "F.Cu")
		(net "P5E_PEX3_STN0_TX_DP<0>")
	)
	(segment
		(start 436.891938 -125.399292)
		(end 437.02478 -125.45441)
		(width 0.1651)
		(layer "In9.Cu")
		(net "P5E_PEX3_STN0_TX_DP<0>")
	)
	(segment
		(start 434.180234 -120.433592)
		(end 434.208428 -120.574562)
		(width 0.1651)
		(layer "In9.Cu")
		(net "P5E_PEX3_STN0_TX_DP<0>")
	)
	(segment
		(start 439.292492 -130.928872)
		(end 439.60796 -131.24434)
		(width 0.1651)
		(layer "In9.Cu")
		(net "P5E_PEX3_STN0_TX_DP<0>")
	)
	(segment
		(start 432.143408 -287.729676)
		(end 425.644818 -287.729676)
		(width 0.1143)
		(layer "In9.Cu")
		(net "P5E_PEX3_STN0_TX_DP<0>")
	)
	(segment
		(start 439.60796 -131.24434)
		(end 448.189604 -151.961596)
		(width 0.1651)
		(layer "In9.Cu")
		(net "P5E_PEX3_STN0_TX_DP<0>")
	)
	(segment
		(start 425.42968 -288.185606)
		(end 425.31538 -288.299906)
		(width 0.1143)
		(layer "In9.Cu")
		(net "P5E_PEX3_STN0_TX_DP<0>")
	)
	(segment
		(start 431.318416 -119.268494)
		(end 431.420016 -119.370094)
		(width 0.1651)
		(layer "In9.Cu")
		(net "P5E_PEX3_STN0_TX_DP<0>")
	)
	(segment
		(start 435.741572 -122.356118)
		(end 435.916324 -122.77852)
		(width 0.1651)
		(layer "In9.Cu")
		(net "P5E_PEX3_STN0_TX_DP<0>")
	)
	(segment
		(start 431.420016 -119.370094)
		(end 431.877216 -119.370094)
		(width 0.1651)
		(layer "In9.Cu")
		(net "P5E_PEX3_STN0_TX_DP<0>")
	)
	(segment
		(start 447.858388 -161.16935)
		(end 439.286904 -176.023778)
		(width 0.1651)
		(layer "In9.Cu")
		(net "P5E_PEX3_STN0_TX_DP<0>")
	)
	(segment
		(start 436.597044 -124.421646)
		(end 436.771796 -124.843794)
		(width 0.1651)
		(layer "In9.Cu")
		(net "P5E_PEX3_STN0_TX_DP<0>")
	)
	(segment
		(start 436.036466 -123.333764)
		(end 436.169308 -123.388882)
		(width 0.1651)
		(layer "In9.Cu")
		(net "P5E_PEX3_STN0_TX_DP<0>")
	)
	(segment
		(start 434.082698 -287.683956)
		(end 432.217576 -287.683956)
		(width 0.1651)
		(layer "In9.Cu")
		(net "P5E_PEX3_STN0_TX_DP<0>")
	)
	(segment
		(start 432.436016 -119.268494)
		(end 434.180234 -120.433592)
		(width 0.1651)
		(layer "In9.Cu")
		(net "P5E_PEX3_STN0_TX_DP<0>")
	)
	(segment
		(start 437.103774 -249.385836)
		(end 446.899538 -264.044684)
		(width 0.1651)
		(layer "In9.Cu")
		(net "P5E_PEX3_STN0_TX_DP<0>")
	)
	(segment
		(start 435.86146 -122.911108)
		(end 436.036466 -123.333764)
		(width 0.1651)
		(layer "In9.Cu")
		(net "P5E_PEX3_STN0_TX_DP<0>")
	)
	(segment
		(start 448.244722 -267.29182)
		(end 448.715384 -272.702782)
		(width 0.1651)
		(layer "In9.Cu")
		(net "P5E_PEX3_STN0_TX_DP<0>")
	)
	(segment
		(start 436.169308 -123.388882)
		(end 436.34406 -123.811284)
		(width 0.1651)
		(layer "In9.Cu")
		(net "P5E_PEX3_STN0_TX_DP<0>")
	)
	(segment
		(start 432.189128 -287.683956)
		(end 432.143408 -287.729676)
		(width 0.1143)
		(layer "In9.Cu")
		(net "P5E_PEX3_STN0_TX_DP<0>")
	)
	(segment
		(start 436.464202 -124.366528)
		(end 436.597044 -124.421646)
		(width 0.1651)
		(layer "In9.Cu")
		(net "P5E_PEX3_STN0_TX_DP<0>")
	)
	(segment
		(start 437.546496 -126.713996)
		(end 439.292492 -130.928872)
		(width 0.1651)
		(layer "In9.Cu")
		(net "P5E_PEX3_STN0_TX_DP<0>")
	)
	(segment
		(start 437.293512 -126.10338)
		(end 437.238648 -126.236222)
		(width 0.1651)
		(layer "In9.Cu")
		(net "P5E_PEX3_STN0_TX_DP<0>")
	)
	(segment
		(start 435.488588 -121.745756)
		(end 435.433724 -121.878598)
		(width 0.1651)
		(layer "In9.Cu")
		(net "P5E_PEX3_STN0_TX_DP<0>")
	)
	(segment
		(start 436.289196 -123.943872)
		(end 436.464202 -124.366528)
		(width 0.1651)
		(layer "In9.Cu")
		(net "P5E_PEX3_STN0_TX_DP<0>")
	)
	(segment
		(start 432.217576 -287.683956)
		(end 432.189128 -287.683956)
		(width 0.1143)
		(layer "In9.Cu")
		(net "P5E_PEX3_STN0_TX_DP<0>")
	)
	(segment
		(start 429.832262 -119.559324)
		(end 430.123092 -119.268494)
		(width 0.1651)
		(layer "In9.Cu")
		(net "P5E_PEX3_STN0_TX_DP<0>")
	)
	(segment
		(start 425.42968 -287.944814)
		(end 425.42968 -288.185606)
		(width 0.1143)
		(layer "In9.Cu")
		(net "P5E_PEX3_STN0_TX_DP<0>")
	)
	(segment
		(start 447.03746 -276.752812)
		(end 437.537098 -286.253174)
		(width 0.1651)
		(layer "In9.Cu")
		(net "P5E_PEX3_STN0_TX_DP<0>")
	)
	(segment
		(start 446.899538 -264.044684)
		(end 448.244722 -267.29182)
		(width 0.1651)
		(layer "In9.Cu")
		(net "P5E_PEX3_STN0_TX_DP<0>")
	)
	(segment
		(start 448.189604 -159.92983)
		(end 447.858388 -161.16935)
		(width 0.1651)
		(layer "In9.Cu")
		(net "P5E_PEX3_STN0_TX_DP<0>")
	)
	(segment
		(start 436.771796 -124.843794)
		(end 436.716932 -124.976636)
		(width 0.1651)
		(layer "In9.Cu")
		(net "P5E_PEX3_STN0_TX_DP<0>")
	)
	(segment
		(start 437.413654 -126.658878)
		(end 437.546496 -126.713996)
		(width 0.1651)
		(layer "In9.Cu")
		(net "P5E_PEX3_STN0_TX_DP<0>")
	)
	(segment
		(start 435.916324 -122.77852)
		(end 435.86146 -122.911108)
		(width 0.1651)
		(layer "In9.Cu")
		(net "P5E_PEX3_STN0_TX_DP<0>")
	)
	(segment
		(start 437.238648 -126.236222)
		(end 437.413654 -126.658878)
		(width 0.1651)
		(layer "In9.Cu")
		(net "P5E_PEX3_STN0_TX_DP<0>")
	)
	(segment
		(start 436.34406 -123.811284)
		(end 436.289196 -123.943872)
		(width 0.1651)
		(layer "In9.Cu")
		(net "P5E_PEX3_STN0_TX_DP<0>")
	)
	(segment
		(start 448.189604 -151.961596)
		(end 448.189604 -159.92983)
		(width 0.1651)
		(layer "In9.Cu")
		(net "P5E_PEX3_STN0_TX_DP<0>")
	)
	(segment
		(start 431.978816 -119.268494)
		(end 432.436016 -119.268494)
		(width 0.1651)
		(layer "In9.Cu")
		(net "P5E_PEX3_STN0_TX_DP<0>")
	)
	(segment
		(start 431.877216 -119.370094)
		(end 431.978816 -119.268494)
		(width 0.1651)
		(layer "In9.Cu")
		(net "P5E_PEX3_STN0_TX_DP<0>")
	)
	(segment
		(start 439.286904 -176.023778)
		(end 438.422034 -179.192428)
		(width 0.1651)
		(layer "In9.Cu")
		(net "P5E_PEX3_STN0_TX_DP<0>")
	)
	(segment
		(start 436.716932 -124.976636)
		(end 436.891938 -125.399292)
		(width 0.1651)
		(layer "In9.Cu")
		(net "P5E_PEX3_STN0_TX_DP<0>")
	)
	(segment
		(start 435.433724 -121.878598)
		(end 435.60873 -122.301254)
		(width 0.1651)
		(layer "In9.Cu")
		(net "P5E_PEX3_STN0_TX_DP<0>")
	)
	(segment
		(start 448.715384 -272.702782)
		(end 447.03746 -276.752812)
		(width 0.1651)
		(layer "In9.Cu")
		(net "P5E_PEX3_STN0_TX_DP<0>")
	)
	(segment
		(start 437.02478 -125.45441)
		(end 437.293512 -126.10338)
		(width 0.1651)
		(layer "In9.Cu")
		(net "P5E_PEX3_STN0_TX_DP<0>")
	)
	(segment
		(start 435.60873 -122.301254)
		(end 435.741572 -122.356118)
		(width 0.1651)
		(layer "In9.Cu")
		(net "P5E_PEX3_STN0_TX_DP<0>")
	)
	(segment
		(start 430.123092 -119.268494)
		(end 431.318416 -119.268494)
		(width 0.1651)
		(layer "In9.Cu")
		(net "P5E_PEX3_STN0_TX_DP<0>")
	)
	(segment
		(start 425.31538 -288.299906)
		(end 425.04995 -288.299906)
		(width 0.1143)
		(layer "In9.Cu")
		(net "P5E_PEX3_STN0_TX_DP<0>")
	)
	(segment
		(start 437.537098 -286.253174)
		(end 434.082698 -287.683956)
		(width 0.1651)
		(layer "In9.Cu")
		(net "P5E_PEX3_STN0_TX_DP<0>")
	)
	(segment
		(start 435.23789 -121.14022)
		(end 435.488588 -121.745756)
		(width 0.1651)
		(layer "In9.Cu")
		(net "P5E_PEX3_STN0_TX_DP<0>")
	)
	(segment
		(start 438.422034 -179.192428)
		(end 434.695346 -221.785942)
		(width 0.1651)
		(layer "In9.Cu")
		(net "P5E_PEX3_STN0_TX_DP<0>")
	)
	(segment
		(start 434.588666 -120.828816)
		(end 434.729636 -120.800876)
		(width 0.1651)
		(layer "In9.Cu")
		(net "P5E_PEX3_STN0_TX_DP<0>")
	)
	(segment
		(start 434.729636 -120.800876)
		(end 435.23789 -121.14022)
		(width 0.1651)
		(layer "In9.Cu")
		(net "P5E_PEX3_STN0_TX_DP<0>")
	)
	(segment
		(start 434.695346 -221.785942)
		(end 437.103774 -249.385836)
		(width 0.1651)
		(layer "In9.Cu")
		(net "P5E_PEX3_STN0_TX_DP<0>")
	)
	(segment
		(start 425.644818 -287.729676)
		(end 425.42968 -287.944814)
		(width 0.1143)
		(layer "In9.Cu")
		(net "P5E_PEX3_STN0_TX_DP<0>")
	)
	(segment
		(start 434.208428 -120.574562)
		(end 434.588666 -120.828816)
		(width 0.1651)
		(layer "In9.Cu")
		(net "P5E_PEX3_STN0_TX_DP<0>")
	)
	(segment
		(start 434.460904 -355.026214)
		(end 434.166772 -354.732082)
		(width 0.13462)
		(layer "F.Cu")
		(net "P5E_PEX3_STN7_TX_DP<124>")
	)
	(segment
		(start 434.141372 -355.978206)
		(end 434.460904 -355.658674)
		(width 0.13462)
		(layer "F.Cu")
		(net "P5E_PEX3_STN7_TX_DP<124>")
	)
	(segment
		(start 434.460904 -355.658674)
		(end 434.460904 -355.026214)
		(width 0.13462)
		(layer "F.Cu")
		(net "P5E_PEX3_STN7_TX_DP<124>")
	)
	(segment
		(start 387.999986 -311.365392)
		(end 387.999986 -311.099962)
		(width 0.1143)
		(layer "In11.Cu")
		(net "P5E_PEX3_STN7_TX_DP<124>")
	)
	(segment
		(start 387.885686 -311.479692)
		(end 387.999986 -311.365392)
		(width 0.1143)
		(layer "In11.Cu")
		(net "P5E_PEX3_STN7_TX_DP<124>")
	)
	(segment
		(start 434.457602 -354.441252)
		(end 434.457602 -353.814126)
		(width 0.1651)
		(layer "In11.Cu")
		(net "P5E_PEX3_STN7_TX_DP<124>")
	)
	(segment
		(start 387.383782 -320.056256)
		(end 387.383782 -320.034158)
		(width 0.1143)
		(layer "In11.Cu")
		(net "P5E_PEX3_STN7_TX_DP<124>")
	)
	(segment
		(start 387.383782 -322.016628)
		(end 387.383782 -320.056256)
		(width 0.1651)
		(layer "In11.Cu")
		(net "P5E_PEX3_STN7_TX_DP<124>")
	)
	(segment
		(start 434.589682 -339.41639)
		(end 425.593002 -333.135986)
		(width 0.1651)
		(layer "In11.Cu")
		(net "P5E_PEX3_STN7_TX_DP<124>")
	)
	(segment
		(start 387.383782 -320.034158)
		(end 387.429502 -319.988438)
		(width 0.1143)
		(layer "In11.Cu")
		(net "P5E_PEX3_STN7_TX_DP<124>")
	)
	(segment
		(start 387.644894 -311.479692)
		(end 387.885686 -311.479692)
		(width 0.1143)
		(layer "In11.Cu")
		(net "P5E_PEX3_STN7_TX_DP<124>")
	)
	(segment
		(start 387.429502 -319.988438)
		(end 387.429502 -311.695084)
		(width 0.1143)
		(layer "In11.Cu")
		(net "P5E_PEX3_STN7_TX_DP<124>")
	)
	(segment
		(start 388.677404 -323.391784)
		(end 387.441694 -322.156074)
		(width 0.1651)
		(layer "In11.Cu")
		(net "P5E_PEX3_STN7_TX_DP<124>")
	)
	(segment
		(start 425.593002 -333.135986)
		(end 388.677404 -323.391784)
		(width 0.1651)
		(layer "In11.Cu")
		(net "P5E_PEX3_STN7_TX_DP<124>")
	)
	(segment
		(start 387.429502 -311.695084)
		(end 387.644894 -311.479692)
		(width 0.1143)
		(layer "In11.Cu")
		(net "P5E_PEX3_STN7_TX_DP<124>")
	)
	(segment
		(start 436.012082 -341.636604)
		(end 434.589682 -339.41639)
		(width 0.1651)
		(layer "In11.Cu")
		(net "P5E_PEX3_STN7_TX_DP<124>")
	)
	(segment
		(start 434.166772 -354.732082)
		(end 434.457602 -354.441252)
		(width 0.1651)
		(layer "In11.Cu")
		(net "P5E_PEX3_STN7_TX_DP<124>")
	)
	(segment
		(start 387.441694 -322.156074)
		(end 387.383782 -322.016628)
		(width 0.1651)
		(layer "In11.Cu")
		(net "P5E_PEX3_STN7_TX_DP<124>")
	)
	(segment
		(start 434.457602 -353.814126)
		(end 436.012082 -352.259646)
		(width 0.1651)
		(layer "In11.Cu")
		(net "P5E_PEX3_STN7_TX_DP<124>")
	)
	(segment
		(start 436.012082 -352.259646)
		(end 436.012082 -341.636604)
		(width 0.1651)
		(layer "In11.Cu")
		(net "P5E_PEX3_STN7_TX_DP<124>")
	)
	(segment
		(start 97.305114 -29.114242)
		(end 97.019872 -28.829)
		(width 0.13462)
		(layer "F.Cu")
		(net "P5E_PEX0_STN2_TX_DP<32>")
	)
	(segment
		(start 96.369632 -28.829)
		(end 96.05899 -29.139642)
		(width 0.13462)
		(layer "F.Cu")
		(net "P5E_PEX0_STN2_TX_DP<32>")
	)
	(segment
		(start 97.019872 -28.829)
		(end 96.369632 -28.829)
		(width 0.13462)
		(layer "F.Cu")
		(net "P5E_PEX0_STN2_TX_DP<32>")
	)
	(segment
		(start 79.415894 -140.76553)
		(end 79.154782 -141.889734)
		(width 0.1651)
		(layer "In11.Cu")
		(net "P5E_PEX0_STN2_TX_DP<32>")
	)
	(segment
		(start 105.03408 -34.178494)
		(end 104.998774 -34.299144)
		(width 0.1651)
		(layer "In11.Cu")
		(net "P5E_PEX0_STN2_TX_DP<32>")
	)
	(segment
		(start 58.083958 -271.399)
		(end 58.083958 -271.427448)
		(width 0.1143)
		(layer "In11.Cu")
		(net "P5E_PEX0_STN2_TX_DP<32>")
	)
	(segment
		(start 105.594658 -35.203892)
		(end 105.559098 -35.324542)
		(width 0.1651)
		(layer "In11.Cu")
		(net "P5E_PEX0_STN2_TX_DP<32>")
	)
	(segment
		(start 105.559098 -35.324542)
		(end 105.797096 -35.75939)
		(width 0.1651)
		(layer "In11.Cu")
		(net "P5E_PEX0_STN2_TX_DP<32>")
	)
	(segment
		(start 97.305114 -29.114242)
		(end 97.595944 -28.823412)
		(width 0.1651)
		(layer "In11.Cu")
		(net "P5E_PEX0_STN2_TX_DP<32>")
	)
	(segment
		(start 109.140244 -56.946546)
		(end 106.840528 -68.690744)
		(width 0.1651)
		(layer "In11.Cu")
		(net "P5E_PEX0_STN2_TX_DP<32>")
	)
	(segment
		(start 108.852208 -42.485818)
		(end 109.140244 -56.946546)
		(width 0.1651)
		(layer "In11.Cu")
		(net "P5E_PEX0_STN2_TX_DP<32>")
	)
	(segment
		(start 105.236518 -34.733992)
		(end 105.357168 -34.769298)
		(width 0.1651)
		(layer "In11.Cu")
		(net "P5E_PEX0_STN2_TX_DP<32>")
	)
	(segment
		(start 58.129678 -280.10485)
		(end 58.344816 -280.319988)
		(width 0.1143)
		(layer "In11.Cu")
		(net "P5E_PEX0_STN2_TX_DP<32>")
	)
	(segment
		(start 78.344268 -153.837386)
		(end 77.391514 -161.014918)
		(width 0.1651)
		(layer "In11.Cu")
		(net "P5E_PEX0_STN2_TX_DP<32>")
	)
	(segment
		(start 58.083958 -266.06373)
		(end 58.083958 -271.399)
		(width 0.1651)
		(layer "In11.Cu")
		(net "P5E_PEX0_STN2_TX_DP<32>")
	)
	(segment
		(start 105.917746 -35.794696)
		(end 108.167932 -39.912036)
		(width 0.1651)
		(layer "In11.Cu")
		(net "P5E_PEX0_STN2_TX_DP<32>")
	)
	(segment
		(start 96.91116 -80.133698)
		(end 95.231458 -81.8134)
		(width 0.1651)
		(layer "In11.Cu")
		(net "P5E_PEX0_STN2_TX_DP<32>")
	)
	(segment
		(start 79.415894 -135.763508)
		(end 79.415894 -140.76553)
		(width 0.1651)
		(layer "In11.Cu")
		(net "P5E_PEX0_STN2_TX_DP<32>")
	)
	(segment
		(start 103.544878 -76.534772)
		(end 96.91116 -80.133698)
		(width 0.1651)
		(layer "In11.Cu")
		(net "P5E_PEX0_STN2_TX_DP<32>")
	)
	(segment
		(start 104.443022 -75.376786)
		(end 103.544878 -76.534772)
		(width 0.1651)
		(layer "In11.Cu")
		(net "P5E_PEX0_STN2_TX_DP<32>")
	)
	(segment
		(start 108.167932 -39.912036)
		(end 108.852208 -42.485818)
		(width 0.1651)
		(layer "In11.Cu")
		(net "P5E_PEX0_STN2_TX_DP<32>")
	)
	(segment
		(start 105.797096 -35.75939)
		(end 105.917746 -35.794696)
		(width 0.1651)
		(layer "In11.Cu")
		(net "P5E_PEX0_STN2_TX_DP<32>")
	)
	(segment
		(start 105.357168 -34.769298)
		(end 105.594658 -35.203892)
		(width 0.1651)
		(layer "In11.Cu")
		(net "P5E_PEX0_STN2_TX_DP<32>")
	)
	(segment
		(start 97.595944 -28.823412)
		(end 99.35972 -28.823412)
		(width 0.1651)
		(layer "In11.Cu")
		(net "P5E_PEX0_STN2_TX_DP<32>")
	)
	(segment
		(start 80.174846 -117.958362)
		(end 79.415894 -135.763508)
		(width 0.1651)
		(layer "In11.Cu")
		(net "P5E_PEX0_STN2_TX_DP<32>")
	)
	(segment
		(start 95.231458 -81.8134)
		(end 81.667858 -105.9434)
		(width 0.1651)
		(layer "In11.Cu")
		(net "P5E_PEX0_STN2_TX_DP<32>")
	)
	(segment
		(start 99.35972 -28.823412)
		(end 101.65334 -29.735018)
		(width 0.1651)
		(layer "In11.Cu")
		(net "P5E_PEX0_STN2_TX_DP<32>")
	)
	(segment
		(start 81.667858 -105.9434)
		(end 80.174846 -117.958362)
		(width 0.1651)
		(layer "In11.Cu")
		(net "P5E_PEX0_STN2_TX_DP<32>")
	)
	(segment
		(start 58.699908 -280.434288)
		(end 58.699908 -280.699718)
		(width 0.1143)
		(layer "In11.Cu")
		(net "P5E_PEX0_STN2_TX_DP<32>")
	)
	(segment
		(start 101.65334 -29.735018)
		(end 103.759762 -31.84652)
		(width 0.1651)
		(layer "In11.Cu")
		(net "P5E_PEX0_STN2_TX_DP<32>")
	)
	(segment
		(start 58.083958 -271.427448)
		(end 58.129678 -271.473168)
		(width 0.1143)
		(layer "In11.Cu")
		(net "P5E_PEX0_STN2_TX_DP<32>")
	)
	(segment
		(start 58.585608 -280.319988)
		(end 58.699908 -280.434288)
		(width 0.1143)
		(layer "In11.Cu")
		(net "P5E_PEX0_STN2_TX_DP<32>")
	)
	(segment
		(start 103.759762 -31.84652)
		(end 105.03408 -34.178494)
		(width 0.1651)
		(layer "In11.Cu")
		(net "P5E_PEX0_STN2_TX_DP<32>")
	)
	(segment
		(start 58.129678 -271.473168)
		(end 58.129678 -280.10485)
		(width 0.1143)
		(layer "In11.Cu")
		(net "P5E_PEX0_STN2_TX_DP<32>")
	)
	(segment
		(start 78.968854 -146.24304)
		(end 78.344268 -153.837386)
		(width 0.1651)
		(layer "In11.Cu")
		(net "P5E_PEX0_STN2_TX_DP<32>")
	)
	(segment
		(start 104.998774 -34.299144)
		(end 105.236518 -34.733992)
		(width 0.1651)
		(layer "In11.Cu")
		(net "P5E_PEX0_STN2_TX_DP<32>")
	)
	(segment
		(start 58.344816 -280.319988)
		(end 58.585608 -280.319988)
		(width 0.1143)
		(layer "In11.Cu")
		(net "P5E_PEX0_STN2_TX_DP<32>")
	)
	(segment
		(start 106.840528 -68.690744)
		(end 104.443022 -75.376786)
		(width 0.1651)
		(layer "In11.Cu")
		(net "P5E_PEX0_STN2_TX_DP<32>")
	)
	(segment
		(start 77.391514 -161.014918)
		(end 58.083958 -266.06373)
		(width 0.1651)
		(layer "In11.Cu")
		(net "P5E_PEX0_STN2_TX_DP<32>")
	)
	(segment
		(start 79.154782 -141.889734)
		(end 78.968854 -146.24304)
		(width 0.1651)
		(layer "In11.Cu")
		(net "P5E_PEX0_STN2_TX_DP<32>")
	)
	(segment
		(start 137.302748 -342.734138)
		(end 137.597388 -342.439498)
		(width 0.13462)
		(layer "F.Cu")
		(net "P5E_PEX1_STN5_TX_DN<91>")
	)
	(segment
		(start 137.622788 -343.685622)
		(end 137.302748 -343.365582)
		(width 0.13462)
		(layer "F.Cu")
		(net "P5E_PEX1_STN5_TX_DN<91>")
	)
	(segment
		(start 137.302748 -343.365582)
		(end 137.302748 -342.734138)
		(width 0.13462)
		(layer "F.Cu")
		(net "P5E_PEX1_STN5_TX_DN<91>")
	)
	(segment
		(start 138.278108 -339.990938)
		(end 142.531338 -338.229194)
		(width 0.1651)
		(layer "In13.Cu")
		(net "P5E_PEX1_STN5_TX_DN<91>")
	)
	(segment
		(start 185.250074 -313.684412)
		(end 185.250074 -313.949842)
		(width 0.1143)
		(layer "In13.Cu")
		(net "P5E_PEX1_STN5_TX_DN<91>")
	)
	(segment
		(start 147.884388 -337.957414)
		(end 164.840666 -332.306422)
		(width 0.1651)
		(layer "In13.Cu")
		(net "P5E_PEX1_STN5_TX_DN<91>")
	)
	(segment
		(start 184.870344 -319.995296)
		(end 184.870344 -313.673744)
		(width 0.1143)
		(layer "In13.Cu")
		(net "P5E_PEX1_STN5_TX_DN<91>")
	)
	(segment
		(start 137.597388 -342.439498)
		(end 137.306558 -342.148668)
		(width 0.1651)
		(layer "In13.Cu")
		(net "P5E_PEX1_STN5_TX_DN<91>")
	)
	(segment
		(start 178.069748 -326.226932)
		(end 178.070002 -326.226678)
		(width 0.1651)
		(layer "In13.Cu")
		(net "P5E_PEX1_STN5_TX_DN<91>")
	)
	(segment
		(start 184.973976 -313.570112)
		(end 185.135774 -313.570112)
		(width 0.1143)
		(layer "In13.Cu")
		(net "P5E_PEX1_STN5_TX_DN<91>")
	)
	(segment
		(start 184.60593 -322.146422)
		(end 184.916064 -321.39763)
		(width 0.1651)
		(layer "In13.Cu")
		(net "P5E_PEX1_STN5_TX_DN<91>")
	)
	(segment
		(start 185.135774 -313.570112)
		(end 185.250074 -313.684412)
		(width 0.1143)
		(layer "In13.Cu")
		(net "P5E_PEX1_STN5_TX_DN<91>")
	)
	(segment
		(start 181.784498 -324.240906)
		(end 183.974486 -322.777866)
		(width 0.1651)
		(layer "In13.Cu")
		(net "P5E_PEX1_STN5_TX_DN<91>")
	)
	(segment
		(start 184.916064 -320.041016)
		(end 184.870344 -319.995296)
		(width 0.1143)
		(layer "In13.Cu")
		(net "P5E_PEX1_STN5_TX_DN<91>")
	)
	(segment
		(start 174.357284 -328.211434)
		(end 178.069748 -326.226932)
		(width 0.1651)
		(layer "In13.Cu")
		(net "P5E_PEX1_STN5_TX_DN<91>")
	)
	(segment
		(start 184.916064 -320.063114)
		(end 184.916064 -320.041016)
		(width 0.1143)
		(layer "In13.Cu")
		(net "P5E_PEX1_STN5_TX_DN<91>")
	)
	(segment
		(start 142.531338 -338.229194)
		(end 143.898112 -337.957414)
		(width 0.1651)
		(layer "In13.Cu")
		(net "P5E_PEX1_STN5_TX_DN<91>")
	)
	(segment
		(start 183.974486 -322.777866)
		(end 184.60593 -322.146422)
		(width 0.1651)
		(layer "In13.Cu")
		(net "P5E_PEX1_STN5_TX_DN<91>")
	)
	(segment
		(start 184.916064 -321.39763)
		(end 184.916064 -320.063114)
		(width 0.1651)
		(layer "In13.Cu")
		(net "P5E_PEX1_STN5_TX_DN<91>")
	)
	(segment
		(start 178.070002 -326.226678)
		(end 181.784498 -324.240906)
		(width 0.1651)
		(layer "In13.Cu")
		(net "P5E_PEX1_STN5_TX_DN<91>")
	)
	(segment
		(start 164.840666 -332.306422)
		(end 174.357284 -328.211434)
		(width 0.1651)
		(layer "In13.Cu")
		(net "P5E_PEX1_STN5_TX_DN<91>")
	)
	(segment
		(start 143.898112 -337.957414)
		(end 147.884388 -337.957414)
		(width 0.1651)
		(layer "In13.Cu")
		(net "P5E_PEX1_STN5_TX_DN<91>")
	)
	(segment
		(start 137.306558 -342.148668)
		(end 137.306558 -340.962488)
		(width 0.1651)
		(layer "In13.Cu")
		(net "P5E_PEX1_STN5_TX_DN<91>")
	)
	(segment
		(start 137.306558 -340.962488)
		(end 138.278108 -339.990938)
		(width 0.1651)
		(layer "In13.Cu")
		(net "P5E_PEX1_STN5_TX_DN<91>")
	)
	(segment
		(start 184.870344 -313.673744)
		(end 184.973976 -313.570112)
		(width 0.1143)
		(layer "In13.Cu")
		(net "P5E_PEX1_STN5_TX_DN<91>")
	)
	(segment
		(start 276.569678 -28.829)
		(end 276.259036 -29.139642)
		(width 0.13462)
		(layer "F.Cu")
		(net "P5E_PEX2_STN2_TX_DP<40>")
	)
	(segment
		(start 277.50516 -29.114242)
		(end 277.219918 -28.829)
		(width 0.13462)
		(layer "F.Cu")
		(net "P5E_PEX2_STN2_TX_DP<40>")
	)
	(segment
		(start 277.219918 -28.829)
		(end 276.569678 -28.829)
		(width 0.13462)
		(layer "F.Cu")
		(net "P5E_PEX2_STN2_TX_DP<40>")
	)
	(segment
		(start 280.082752 -28.823412)
		(end 281.345386 -29.349192)
		(width 0.1651)
		(layer "In11.Cu")
		(net "P5E_PEX2_STN2_TX_DP<40>")
	)
	(segment
		(start 277.50516 -29.114242)
		(end 277.79599 -28.823412)
		(width 0.1651)
		(layer "In11.Cu")
		(net "P5E_PEX2_STN2_TX_DP<40>")
	)
	(segment
		(start 282.045918 -252.613668)
		(end 282.31973 -266.03325)
		(width 0.1651)
		(layer "In11.Cu")
		(net "P5E_PEX2_STN2_TX_DP<40>")
	)
	(segment
		(start 282.692602 -269.820898)
		(end 282.692602 -271.105122)
		(width 0.1651)
		(layer "In11.Cu")
		(net "P5E_PEX2_STN2_TX_DP<40>")
	)
	(segment
		(start 282.944824 -280.319988)
		(end 283.185616 -280.319988)
		(width 0.1143)
		(layer "In11.Cu")
		(net "P5E_PEX2_STN2_TX_DP<40>")
	)
	(segment
		(start 283.11348 -31.231332)
		(end 283.23921 -31.231078)
		(width 0.1651)
		(layer "In11.Cu")
		(net "P5E_PEX2_STN2_TX_DP<40>")
	)
	(segment
		(start 282.761436 -30.756352)
		(end 282.76169 -30.882082)
		(width 0.1651)
		(layer "In11.Cu")
		(net "P5E_PEX2_STN2_TX_DP<40>")
	)
	(segment
		(start 282.410154 -30.407356)
		(end 282.761436 -30.756352)
		(width 0.1651)
		(layer "In11.Cu")
		(net "P5E_PEX2_STN2_TX_DP<40>")
	)
	(segment
		(start 297.163744 -60.607194)
		(end 296.73804 -69.570346)
		(width 0.1651)
		(layer "In11.Cu")
		(net "P5E_PEX2_STN2_TX_DP<40>")
	)
	(segment
		(start 281.932888 -30.05836)
		(end 282.284424 -30.40761)
		(width 0.1651)
		(layer "In11.Cu")
		(net "P5E_PEX2_STN2_TX_DP<40>")
	)
	(segment
		(start 277.79599 -28.823412)
		(end 280.082752 -28.823412)
		(width 0.1651)
		(layer "In11.Cu")
		(net "P5E_PEX2_STN2_TX_DP<40>")
	)
	(segment
		(start 282.692602 -271.105122)
		(end 282.683966 -271.113758)
		(width 0.1651)
		(layer "In11.Cu")
		(net "P5E_PEX2_STN2_TX_DP<40>")
	)
	(segment
		(start 282.683966 -271.427448)
		(end 282.729686 -271.473168)
		(width 0.1143)
		(layer "In11.Cu")
		(net "P5E_PEX2_STN2_TX_DP<40>")
	)
	(segment
		(start 282.76169 -30.882082)
		(end 283.11348 -31.231332)
		(width 0.1651)
		(layer "In11.Cu")
		(net "P5E_PEX2_STN2_TX_DP<40>")
	)
	(segment
		(start 281.93238 -29.93263)
		(end 281.932888 -30.05836)
		(width 0.1651)
		(layer "In11.Cu")
		(net "P5E_PEX2_STN2_TX_DP<40>")
	)
	(segment
		(start 288.348674 -135.243824)
		(end 282.045918 -252.613668)
		(width 0.1651)
		(layer "In11.Cu")
		(net "P5E_PEX2_STN2_TX_DP<40>")
	)
	(segment
		(start 284.047184 -32.033972)
		(end 285.782766 -34.872168)
		(width 0.1651)
		(layer "In11.Cu")
		(net "P5E_PEX2_STN2_TX_DP<40>")
	)
	(segment
		(start 283.299916 -280.434288)
		(end 283.299916 -280.699718)
		(width 0.1143)
		(layer "In11.Cu")
		(net "P5E_PEX2_STN2_TX_DP<40>")
	)
	(segment
		(start 295.503346 -47.064676)
		(end 296.501312 -49.912524)
		(width 0.1651)
		(layer "In11.Cu")
		(net "P5E_PEX2_STN2_TX_DP<40>")
	)
	(segment
		(start 282.284424 -30.40761)
		(end 282.410154 -30.407356)
		(width 0.1651)
		(layer "In11.Cu")
		(net "P5E_PEX2_STN2_TX_DP<40>")
	)
	(segment
		(start 282.683966 -271.113758)
		(end 282.683966 -271.399)
		(width 0.1651)
		(layer "In11.Cu")
		(net "P5E_PEX2_STN2_TX_DP<40>")
	)
	(segment
		(start 283.23921 -31.231078)
		(end 284.047184 -32.033972)
		(width 0.1651)
		(layer "In11.Cu")
		(net "P5E_PEX2_STN2_TX_DP<40>")
	)
	(segment
		(start 296.501312 -49.912524)
		(end 297.163744 -60.607194)
		(width 0.1651)
		(layer "In11.Cu")
		(net "P5E_PEX2_STN2_TX_DP<40>")
	)
	(segment
		(start 282.683966 -271.399)
		(end 282.683966 -271.427448)
		(width 0.1143)
		(layer "In11.Cu")
		(net "P5E_PEX2_STN2_TX_DP<40>")
	)
	(segment
		(start 296.73804 -69.570346)
		(end 289.690302 -119.281702)
		(width 0.1651)
		(layer "In11.Cu")
		(net "P5E_PEX2_STN2_TX_DP<40>")
	)
	(segment
		(start 289.690302 -119.281702)
		(end 288.348674 -135.243824)
		(width 0.1651)
		(layer "In11.Cu")
		(net "P5E_PEX2_STN2_TX_DP<40>")
	)
	(segment
		(start 285.782766 -34.872168)
		(end 295.503346 -47.064676)
		(width 0.1651)
		(layer "In11.Cu")
		(net "P5E_PEX2_STN2_TX_DP<40>")
	)
	(segment
		(start 282.729686 -271.473168)
		(end 282.729686 -280.10485)
		(width 0.1143)
		(layer "In11.Cu")
		(net "P5E_PEX2_STN2_TX_DP<40>")
	)
	(segment
		(start 282.729686 -280.10485)
		(end 282.944824 -280.319988)
		(width 0.1143)
		(layer "In11.Cu")
		(net "P5E_PEX2_STN2_TX_DP<40>")
	)
	(segment
		(start 283.185616 -280.319988)
		(end 283.299916 -280.434288)
		(width 0.1143)
		(layer "In11.Cu")
		(net "P5E_PEX2_STN2_TX_DP<40>")
	)
	(segment
		(start 281.345386 -29.349192)
		(end 281.93238 -29.93263)
		(width 0.1651)
		(layer "In11.Cu")
		(net "P5E_PEX2_STN2_TX_DP<40>")
	)
	(segment
		(start 282.31973 -266.03325)
		(end 282.692602 -269.820898)
		(width 0.1651)
		(layer "In11.Cu")
		(net "P5E_PEX2_STN2_TX_DP<40>")
	)
	(segment
		(start 343.592404 -354.732082)
		(end 343.887044 -355.026722)
		(width 0.13462)
		(layer "F.Cu")
		(net "P5E_PEX2_STN6_TX_DP<96>")
	)
	(segment
		(start 343.887044 -355.026722)
		(end 343.887044 -355.658166)
		(width 0.13462)
		(layer "F.Cu")
		(net "P5E_PEX2_STN6_TX_DP<96>")
	)
	(segment
		(start 343.887044 -355.658166)
		(end 343.567004 -355.978206)
		(width 0.13462)
		(layer "F.Cu")
		(net "P5E_PEX2_STN6_TX_DP<96>")
	)
	(segment
		(start 343.592404 -354.732082)
		(end 343.883234 -354.441252)
		(width 0.1651)
		(layer "In13.Cu")
		(net "P5E_PEX2_STN6_TX_DP<96>")
	)
	(segment
		(start 345.410282 -342.39454)
		(end 345.223338 -341.24265)
		(width 0.1651)
		(layer "In13.Cu")
		(net "P5E_PEX2_STN6_TX_DP<96>")
	)
	(segment
		(start 289.594798 -313.379612)
		(end 289.83559 -313.379612)
		(width 0.1143)
		(layer "In13.Cu")
		(net "P5E_PEX2_STN6_TX_DP<96>")
	)
	(segment
		(start 336.599276 -334.307434)
		(end 315.341254 -324.968108)
		(width 0.1651)
		(layer "In13.Cu")
		(net "P5E_PEX2_STN6_TX_DP<96>")
	)
	(segment
		(start 290.256722 -320.22288)
		(end 289.727132 -320.22288)
		(width 0.1143)
		(layer "In13.Cu")
		(net "P5E_PEX2_STN6_TX_DP<96>")
	)
	(segment
		(start 293.93134 -320.693542)
		(end 291.078412 -320.2686)
		(width 0.1651)
		(layer "In13.Cu")
		(net "P5E_PEX2_STN6_TX_DP<96>")
	)
	(segment
		(start 345.666822 -346.1004)
		(end 345.410282 -342.39454)
		(width 0.1651)
		(layer "In13.Cu")
		(net "P5E_PEX2_STN6_TX_DP<96>")
	)
	(segment
		(start 289.83559 -313.379612)
		(end 289.94989 -313.265312)
		(width 0.1143)
		(layer "In13.Cu")
		(net "P5E_PEX2_STN6_TX_DP<96>")
	)
	(segment
		(start 345.5416 -351.702624)
		(end 345.666822 -346.1004)
		(width 0.1651)
		(layer "In13.Cu")
		(net "P5E_PEX2_STN6_TX_DP<96>")
	)
	(segment
		(start 343.883234 -353.868482)
		(end 345.282266 -352.120962)
		(width 0.1651)
		(layer "In13.Cu")
		(net "P5E_PEX2_STN6_TX_DP<96>")
	)
	(segment
		(start 289.727132 -320.22288)
		(end 289.37966 -319.875408)
		(width 0.1143)
		(layer "In13.Cu")
		(net "P5E_PEX2_STN6_TX_DP<96>")
	)
	(segment
		(start 315.341254 -324.968108)
		(end 293.93134 -320.693542)
		(width 0.1651)
		(layer "In13.Cu")
		(net "P5E_PEX2_STN6_TX_DP<96>")
	)
	(segment
		(start 291.078412 -320.2686)
		(end 290.31692 -320.2686)
		(width 0.1651)
		(layer "In13.Cu")
		(net "P5E_PEX2_STN6_TX_DP<96>")
	)
	(segment
		(start 345.282266 -352.120962)
		(end 345.5416 -351.702624)
		(width 0.1651)
		(layer "In13.Cu")
		(net "P5E_PEX2_STN6_TX_DP<96>")
	)
	(segment
		(start 289.37966 -313.59475)
		(end 289.594798 -313.379612)
		(width 0.1143)
		(layer "In13.Cu")
		(net "P5E_PEX2_STN6_TX_DP<96>")
	)
	(segment
		(start 290.31692 -320.2686)
		(end 290.302442 -320.2686)
		(width 0.1143)
		(layer "In13.Cu")
		(net "P5E_PEX2_STN6_TX_DP<96>")
	)
	(segment
		(start 290.302442 -320.2686)
		(end 290.256722 -320.22288)
		(width 0.1143)
		(layer "In13.Cu")
		(net "P5E_PEX2_STN6_TX_DP<96>")
	)
	(segment
		(start 289.37966 -319.875408)
		(end 289.37966 -313.59475)
		(width 0.1143)
		(layer "In13.Cu")
		(net "P5E_PEX2_STN6_TX_DP<96>")
	)
	(segment
		(start 289.94989 -313.265312)
		(end 289.94989 -312.999882)
		(width 0.1143)
		(layer "In13.Cu")
		(net "P5E_PEX2_STN6_TX_DP<96>")
	)
	(segment
		(start 345.223338 -341.24265)
		(end 336.599276 -334.307434)
		(width 0.1651)
		(layer "In13.Cu")
		(net "P5E_PEX2_STN6_TX_DP<96>")
	)
	(segment
		(start 343.883234 -354.441252)
		(end 343.883234 -353.868482)
		(width 0.1651)
		(layer "In13.Cu")
		(net "P5E_PEX2_STN6_TX_DP<96>")
	)
	(segment
		(start 432.17592 -135.6106)
		(end 431.552096 -135.6106)
		(width 0.13462)
		(layer "F.Cu")
		(net "P5E_PEX3_STN0_TX_DN<7>")
	)
	(segment
		(start 431.552096 -135.6106)
		(end 431.228246 -135.28675)
		(width 0.13462)
		(layer "F.Cu")
		(net "P5E_PEX3_STN0_TX_DN<7>")
	)
	(segment
		(start 432.47437 -135.31215)
		(end 432.17592 -135.6106)
		(width 0.13462)
		(layer "F.Cu")
		(net "P5E_PEX3_STN0_TX_DN<7>")
	)
	(segment
		(start 430.370234 -279.635458)
		(end 430.484534 -279.749758)
		(width 0.1143)
		(layer "In9.Cu")
		(net "P5E_PEX3_STN0_TX_DN<7>")
	)
	(segment
		(start 433.141628 -173.584108)
		(end 431.951638 -178.021488)
		(width 0.1651)
		(layer "In9.Cu")
		(net "P5E_PEX3_STN0_TX_DN<7>")
	)
	(segment
		(start 431.295302 -279.153874)
		(end 431.080926 -279.36825)
		(width 0.1143)
		(layer "In9.Cu")
		(net "P5E_PEX3_STN0_TX_DN<7>")
	)
	(segment
		(start 437.660796 -145.317464)
		(end 438.33034 -145.987008)
		(width 0.1651)
		(layer "In9.Cu")
		(net "P5E_PEX3_STN0_TX_DN<7>")
	)
	(segment
		(start 432.47437 -135.31215)
		(end 432.7652 -135.60298)
		(width 0.1651)
		(layer "In9.Cu")
		(net "P5E_PEX3_STN0_TX_DN<7>")
	)
	(segment
		(start 438.33034 -145.987008)
		(end 441.697364 -154.11577)
		(width 0.1651)
		(layer "In9.Cu")
		(net "P5E_PEX3_STN0_TX_DN<7>")
	)
	(segment
		(start 432.7652 -135.60298)
		(end 433.46116 -135.60298)
		(width 0.1651)
		(layer "In9.Cu")
		(net "P5E_PEX3_STN0_TX_DN<7>")
	)
	(segment
		(start 430.329086 -246.62638)
		(end 430.32934 -246.62638)
		(width 0.1651)
		(layer "In9.Cu")
		(net "P5E_PEX3_STN0_TX_DN<7>")
	)
	(segment
		(start 432.39309 -277.344632)
		(end 431.637186 -278.87676)
		(width 0.1651)
		(layer "In9.Cu")
		(net "P5E_PEX3_STN0_TX_DN<7>")
	)
	(segment
		(start 431.637186 -278.87676)
		(end 431.370486 -279.143714)
		(width 0.1651)
		(layer "In9.Cu")
		(net "P5E_PEX3_STN0_TX_DN<7>")
	)
	(segment
		(start 430.484534 -279.749758)
		(end 430.749964 -279.749758)
		(width 0.1143)
		(layer "In9.Cu")
		(net "P5E_PEX3_STN0_TX_DN<7>")
	)
	(segment
		(start 431.370486 -279.143714)
		(end 431.360326 -279.153874)
		(width 0.1143)
		(layer "In9.Cu")
		(net "P5E_PEX3_STN0_TX_DN<7>")
	)
	(segment
		(start 428.14113 -221.581218)
		(end 430.329086 -246.62638)
		(width 0.1651)
		(layer "In9.Cu")
		(net "P5E_PEX3_STN0_TX_DN<7>")
	)
	(segment
		(start 432.517296 -271.674336)
		(end 432.39309 -277.344632)
		(width 0.1651)
		(layer "In9.Cu")
		(net "P5E_PEX3_STN0_TX_DN<7>")
	)
	(segment
		(start 431.951638 -178.021488)
		(end 428.14113 -221.581218)
		(width 0.1651)
		(layer "In9.Cu")
		(net "P5E_PEX3_STN0_TX_DN<7>")
	)
	(segment
		(start 441.697364 -158.760414)
		(end 433.141628 -173.584108)
		(width 0.1651)
		(layer "In9.Cu")
		(net "P5E_PEX3_STN0_TX_DN<7>")
	)
	(segment
		(start 441.697364 -154.11577)
		(end 441.697364 -158.760414)
		(width 0.1651)
		(layer "In9.Cu")
		(net "P5E_PEX3_STN0_TX_DN<7>")
	)
	(segment
		(start 433.46116 -135.60298)
		(end 433.761134 -135.902954)
		(width 0.1651)
		(layer "In9.Cu")
		(net "P5E_PEX3_STN0_TX_DN<7>")
	)
	(segment
		(start 431.360326 -279.153874)
		(end 431.295302 -279.153874)
		(width 0.1143)
		(layer "In9.Cu")
		(net "P5E_PEX3_STN0_TX_DN<7>")
	)
	(segment
		(start 430.32934 -246.62638)
		(end 432.517296 -271.674336)
		(width 0.1651)
		(layer "In9.Cu")
		(net "P5E_PEX3_STN0_TX_DN<7>")
	)
	(segment
		(start 430.370234 -279.479248)
		(end 430.370234 -279.635458)
		(width 0.1143)
		(layer "In9.Cu")
		(net "P5E_PEX3_STN0_TX_DN<7>")
	)
	(segment
		(start 430.480978 -279.36825)
		(end 430.370234 -279.479248)
		(width 0.1143)
		(layer "In9.Cu")
		(net "P5E_PEX3_STN0_TX_DN<7>")
	)
	(segment
		(start 431.080926 -279.36825)
		(end 430.480978 -279.36825)
		(width 0.1143)
		(layer "In9.Cu")
		(net "P5E_PEX3_STN0_TX_DN<7>")
	)
	(segment
		(start 433.761134 -135.902954)
		(end 437.660796 -145.317464)
		(width 0.1651)
		(layer "In9.Cu")
		(net "P5E_PEX3_STN0_TX_DN<7>")
	)
	(segment
		(start 381.40386 -355.978206)
		(end 381.083312 -355.657658)
		(width 0.13462)
		(layer "F.Cu")
		(net "P5E_PEX3_STN6_TX_DN<98>")
	)
	(segment
		(start 381.083312 -355.02723)
		(end 381.37846 -354.732082)
		(width 0.13462)
		(layer "F.Cu")
		(net "P5E_PEX3_STN6_TX_DN<98>")
	)
	(segment
		(start 381.083312 -355.657658)
		(end 381.083312 -355.02723)
		(width 0.13462)
		(layer "F.Cu")
		(net "P5E_PEX3_STN6_TX_DN<98>")
	)
	(segment
		(start 381.08763 -353.930966)
		(end 382.64211 -352.376486)
		(width 0.1651)
		(layer "In7.Cu")
		(net "P5E_PEX3_STN6_TX_DN<98>")
	)
	(segment
		(start 404.035514 -313.570112)
		(end 404.149814 -313.684412)
		(width 0.1143)
		(layer "In7.Cu")
		(net "P5E_PEX3_STN6_TX_DN<98>")
	)
	(segment
		(start 381.08763 -354.441252)
		(end 381.08763 -353.930966)
		(width 0.1651)
		(layer "In7.Cu")
		(net "P5E_PEX3_STN6_TX_DN<98>")
	)
	(segment
		(start 403.815804 -319.9892)
		(end 403.815804 -319.960752)
		(width 0.1143)
		(layer "In7.Cu")
		(net "P5E_PEX3_STN6_TX_DN<98>")
	)
	(segment
		(start 403.815804 -319.960752)
		(end 403.770084 -319.915032)
		(width 0.1143)
		(layer "In7.Cu")
		(net "P5E_PEX3_STN6_TX_DN<98>")
	)
	(segment
		(start 382.64211 -352.376486)
		(end 382.64211 -341.521034)
		(width 0.1651)
		(layer "In7.Cu")
		(net "P5E_PEX3_STN6_TX_DN<98>")
	)
	(segment
		(start 403.770084 -313.684412)
		(end 403.884384 -313.570112)
		(width 0.1143)
		(layer "In7.Cu")
		(net "P5E_PEX3_STN6_TX_DN<98>")
	)
	(segment
		(start 381.37846 -354.732082)
		(end 381.08763 -354.441252)
		(width 0.1651)
		(layer "In7.Cu")
		(net "P5E_PEX3_STN6_TX_DN<98>")
	)
	(segment
		(start 403.884384 -313.570112)
		(end 404.035514 -313.570112)
		(width 0.1143)
		(layer "In7.Cu")
		(net "P5E_PEX3_STN6_TX_DN<98>")
	)
	(segment
		(start 403.815804 -321.44716)
		(end 403.815804 -319.9892)
		(width 0.1651)
		(layer "In7.Cu")
		(net "P5E_PEX3_STN6_TX_DN<98>")
	)
	(segment
		(start 401.164298 -325.113142)
		(end 403.098254 -323.179186)
		(width 0.1651)
		(layer "In7.Cu")
		(net "P5E_PEX3_STN6_TX_DN<98>")
	)
	(segment
		(start 403.098254 -323.179186)
		(end 403.815804 -321.44716)
		(width 0.1651)
		(layer "In7.Cu")
		(net "P5E_PEX3_STN6_TX_DN<98>")
	)
	(segment
		(start 403.770084 -319.915032)
		(end 403.770084 -313.684412)
		(width 0.1143)
		(layer "In7.Cu")
		(net "P5E_PEX3_STN6_TX_DN<98>")
	)
	(segment
		(start 404.149814 -313.684412)
		(end 404.149814 -313.949842)
		(width 0.1143)
		(layer "In7.Cu")
		(net "P5E_PEX3_STN6_TX_DN<98>")
	)
	(segment
		(start 382.64211 -341.521034)
		(end 401.164298 -325.113142)
		(width 0.1651)
		(layer "In7.Cu")
		(net "P5E_PEX3_STN6_TX_DN<98>")
	)
	(segment
		(start 80.594962 -349.511874)
		(end 80.594962 -348.88043)
		(width 0.13462)
		(layer "F.Cu")
		(net "P5E_PEX0_STN5_TX_DN<89>")
	)
	(segment
		(start 80.594962 -348.88043)
		(end 80.889602 -348.58579)
		(width 0.13462)
		(layer "F.Cu")
		(net "P5E_PEX0_STN5_TX_DN<89>")
	)
	(segment
		(start 80.915002 -349.831914)
		(end 80.594962 -349.511874)
		(width 0.13462)
		(layer "F.Cu")
		(net "P5E_PEX0_STN5_TX_DN<89>")
	)
	(segment
		(start 66.870072 -319.84188)
		(end 66.870072 -313.684412)
		(width 0.1143)
		(layer "In7.Cu")
		(net "P5E_PEX0_STN5_TX_DN<89>")
	)
	(segment
		(start 67.249802 -313.684412)
		(end 67.249802 -313.949842)
		(width 0.1143)
		(layer "In7.Cu")
		(net "P5E_PEX0_STN5_TX_DN<89>")
	)
	(segment
		(start 66.915792 -319.916048)
		(end 66.915792 -319.8876)
		(width 0.1143)
		(layer "In7.Cu")
		(net "P5E_PEX0_STN5_TX_DN<89>")
	)
	(segment
		(start 68.763134 -324.947534)
		(end 67.374262 -322.869052)
		(width 0.1651)
		(layer "In7.Cu")
		(net "P5E_PEX0_STN5_TX_DN<89>")
	)
	(segment
		(start 69.69887 -325.88327)
		(end 68.763134 -324.947534)
		(width 0.1651)
		(layer "In7.Cu")
		(net "P5E_PEX0_STN5_TX_DN<89>")
	)
	(segment
		(start 82.153252 -341.691468)
		(end 81.751932 -340.56955)
		(width 0.1651)
		(layer "In7.Cu")
		(net "P5E_PEX0_STN5_TX_DN<89>")
	)
	(segment
		(start 66.984372 -313.570112)
		(end 67.135502 -313.570112)
		(width 0.1143)
		(layer "In7.Cu")
		(net "P5E_PEX0_STN5_TX_DN<89>")
	)
	(segment
		(start 66.870072 -313.684412)
		(end 66.984372 -313.570112)
		(width 0.1143)
		(layer "In7.Cu")
		(net "P5E_PEX0_STN5_TX_DN<89>")
	)
	(segment
		(start 67.374262 -322.869052)
		(end 66.915792 -321.762374)
		(width 0.1651)
		(layer "In7.Cu")
		(net "P5E_PEX0_STN5_TX_DN<89>")
	)
	(segment
		(start 80.598772 -348.29496)
		(end 80.598772 -347.658182)
		(width 0.1651)
		(layer "In7.Cu")
		(net "P5E_PEX0_STN5_TX_DN<89>")
	)
	(segment
		(start 81.751932 -340.56955)
		(end 69.69887 -325.88327)
		(width 0.1651)
		(layer "In7.Cu")
		(net "P5E_PEX0_STN5_TX_DN<89>")
	)
	(segment
		(start 66.915792 -321.762374)
		(end 66.915792 -319.916048)
		(width 0.1651)
		(layer "In7.Cu")
		(net "P5E_PEX0_STN5_TX_DN<89>")
	)
	(segment
		(start 66.915792 -319.8876)
		(end 66.870072 -319.84188)
		(width 0.1143)
		(layer "In7.Cu")
		(net "P5E_PEX0_STN5_TX_DN<89>")
	)
	(segment
		(start 80.889602 -348.58579)
		(end 80.598772 -348.29496)
		(width 0.1651)
		(layer "In7.Cu")
		(net "P5E_PEX0_STN5_TX_DN<89>")
	)
	(segment
		(start 67.135502 -313.570112)
		(end 67.249802 -313.684412)
		(width 0.1143)
		(layer "In7.Cu")
		(net "P5E_PEX0_STN5_TX_DN<89>")
	)
	(segment
		(start 82.153252 -346.103702)
		(end 82.153252 -341.691468)
		(width 0.1651)
		(layer "In7.Cu")
		(net "P5E_PEX0_STN5_TX_DN<89>")
	)
	(segment
		(start 80.598772 -347.658182)
		(end 82.153252 -346.103702)
		(width 0.1651)
		(layer "In7.Cu")
		(net "P5E_PEX0_STN5_TX_DN<89>")
	)
	(segment
		(start 161.405316 -31.850584)
		(end 161.11982 -32.13608)
		(width 0.13462)
		(layer "F.Cu")
		(net "P5E_PEX1_STN2_TX_DN<42>")
	)
	(segment
		(start 161.11982 -32.13608)
		(end 160.470088 -32.13608)
		(width 0.13462)
		(layer "F.Cu")
		(net "P5E_PEX1_STN2_TX_DN<42>")
	)
	(segment
		(start 160.470088 -32.13608)
		(end 160.159192 -31.825184)
		(width 0.13462)
		(layer "F.Cu")
		(net "P5E_PEX1_STN2_TX_DN<42>")
	)
	(segment
		(start 161.405316 -31.850584)
		(end 161.696146 -32.141414)
		(width 0.1651)
		(layer "In11.Cu")
		(net "P5E_PEX1_STN2_TX_DN<42>")
	)
	(segment
		(start 178.125374 -48.492156)
		(end 178.76901 -50.37074)
		(width 0.1651)
		(layer "In11.Cu")
		(net "P5E_PEX1_STN2_TX_DN<42>")
	)
	(segment
		(start 167.39743 -34.599372)
		(end 178.125374 -48.492156)
		(width 0.1651)
		(layer "In11.Cu")
		(net "P5E_PEX1_STN2_TX_DN<42>")
	)
	(segment
		(start 165.161468 -32.319468)
		(end 167.39743 -34.599372)
		(width 0.1651)
		(layer "In11.Cu")
		(net "P5E_PEX1_STN2_TX_DN<42>")
	)
	(segment
		(start 161.696146 -32.141414)
		(end 164.565584 -32.141414)
		(width 0.1651)
		(layer "In11.Cu")
		(net "P5E_PEX1_STN2_TX_DN<42>")
	)
	(segment
		(start 179.406804 -60.466732)
		(end 177.910744 -68.660264)
		(width 0.1651)
		(layer "In11.Cu")
		(net "P5E_PEX1_STN2_TX_DN<42>")
	)
	(segment
		(start 177.910744 -68.660264)
		(end 167.632888 -95.804736)
		(width 0.1651)
		(layer "In11.Cu")
		(net "P5E_PEX1_STN2_TX_DN<42>")
	)
	(segment
		(start 164.565584 -32.141414)
		(end 165.161468 -32.319468)
		(width 0.1651)
		(layer "In11.Cu")
		(net "P5E_PEX1_STN2_TX_DN<42>")
	)
	(segment
		(start 164.965888 -271.427448)
		(end 164.920168 -271.473168)
		(width 0.1143)
		(layer "In11.Cu")
		(net "P5E_PEX1_STN2_TX_DN<42>")
	)
	(segment
		(start 167.632888 -95.804736)
		(end 162.22218 -116.032026)
		(width 0.1651)
		(layer "In11.Cu")
		(net "P5E_PEX1_STN2_TX_DN<42>")
	)
	(segment
		(start 164.920168 -280.025856)
		(end 165.0238 -280.129488)
		(width 0.1143)
		(layer "In11.Cu")
		(net "P5E_PEX1_STN2_TX_DN<42>")
	)
	(segment
		(start 162.482784 -141.886686)
		(end 161.121852 -161.959544)
		(width 0.1651)
		(layer "In11.Cu")
		(net "P5E_PEX1_STN2_TX_DN<42>")
	)
	(segment
		(start 161.121852 -161.959544)
		(end 164.634926 -267.065252)
		(width 0.1651)
		(layer "In11.Cu")
		(net "P5E_PEX1_STN2_TX_DN<42>")
	)
	(segment
		(start 164.634926 -267.065252)
		(end 164.965888 -270.426688)
		(width 0.1651)
		(layer "In11.Cu")
		(net "P5E_PEX1_STN2_TX_DN<42>")
	)
	(segment
		(start 165.185598 -280.129488)
		(end 165.299898 -280.015188)
		(width 0.1143)
		(layer "In11.Cu")
		(net "P5E_PEX1_STN2_TX_DN<42>")
	)
	(segment
		(start 164.965888 -270.426688)
		(end 164.965888 -271.399)
		(width 0.1651)
		(layer "In11.Cu")
		(net "P5E_PEX1_STN2_TX_DN<42>")
	)
	(segment
		(start 164.920168 -271.473168)
		(end 164.920168 -280.025856)
		(width 0.1143)
		(layer "In11.Cu")
		(net "P5E_PEX1_STN2_TX_DN<42>")
	)
	(segment
		(start 165.299898 -280.015188)
		(end 165.299898 -279.749504)
		(width 0.1143)
		(layer "In11.Cu")
		(net "P5E_PEX1_STN2_TX_DN<42>")
	)
	(segment
		(start 162.22218 -116.032026)
		(end 162.482784 -141.886686)
		(width 0.1651)
		(layer "In11.Cu")
		(net "P5E_PEX1_STN2_TX_DN<42>")
	)
	(segment
		(start 165.0238 -280.129488)
		(end 165.185598 -280.129488)
		(width 0.1143)
		(layer "In11.Cu")
		(net "P5E_PEX1_STN2_TX_DN<42>")
	)
	(segment
		(start 178.76901 -50.37074)
		(end 179.406804 -60.466732)
		(width 0.1651)
		(layer "In11.Cu")
		(net "P5E_PEX1_STN2_TX_DN<42>")
	)
	(segment
		(start 164.965888 -271.399)
		(end 164.965888 -271.427448)
		(width 0.1143)
		(layer "In11.Cu")
		(net "P5E_PEX1_STN2_TX_DN<42>")
	)
	(segment
		(start 315.906404 -355.026722)
		(end 315.906404 -355.658166)
		(width 0.13462)
		(layer "F.Cu")
		(net "P5E_PEX2_STN5_TX_DP<82>")
	)
	(segment
		(start 315.611764 -354.732082)
		(end 315.906404 -355.026722)
		(width 0.13462)
		(layer "F.Cu")
		(net "P5E_PEX2_STN5_TX_DP<82>")
	)
	(segment
		(start 315.906404 -355.658166)
		(end 315.586364 -355.978206)
		(width 0.13462)
		(layer "F.Cu")
		(net "P5E_PEX2_STN5_TX_DP<82>")
	)
	(segment
		(start 292.18382 -319.865248)
		(end 292.18382 -319.8368)
		(width 0.1143)
		(layer "In7.Cu")
		(net "P5E_PEX2_STN5_TX_DP<82>")
	)
	(segment
		(start 292.68547 -311.479692)
		(end 292.79977 -311.365392)
		(width 0.1143)
		(layer "In7.Cu")
		(net "P5E_PEX2_STN5_TX_DP<82>")
	)
	(segment
		(start 315.902594 -354.441252)
		(end 315.902594 -353.814126)
		(width 0.1651)
		(layer "In7.Cu")
		(net "P5E_PEX2_STN5_TX_DP<82>")
	)
	(segment
		(start 317.184278 -341.20709)
		(end 315.77407 -340.146386)
		(width 0.1651)
		(layer "In7.Cu")
		(net "P5E_PEX2_STN5_TX_DP<82>")
	)
	(segment
		(start 317.457074 -341.985854)
		(end 317.45682 -341.9856)
		(width 0.1651)
		(layer "In7.Cu")
		(net "P5E_PEX2_STN5_TX_DP<82>")
	)
	(segment
		(start 317.45682 -341.9856)
		(end 317.320422 -341.596218)
		(width 0.1651)
		(layer "In7.Cu")
		(net "P5E_PEX2_STN5_TX_DP<82>")
	)
	(segment
		(start 292.79977 -311.365392)
		(end 292.79977 -311.099962)
		(width 0.1143)
		(layer "In7.Cu")
		(net "P5E_PEX2_STN5_TX_DP<82>")
	)
	(segment
		(start 292.18382 -319.8368)
		(end 292.22954 -319.79108)
		(width 0.1143)
		(layer "In7.Cu")
		(net "P5E_PEX2_STN5_TX_DP<82>")
	)
	(segment
		(start 292.455346 -311.479692)
		(end 292.68547 -311.479692)
		(width 0.1143)
		(layer "In7.Cu")
		(net "P5E_PEX2_STN5_TX_DP<82>")
	)
	(segment
		(start 294.462454 -328.744834)
		(end 292.18382 -323.243448)
		(width 0.1651)
		(layer "In7.Cu")
		(net "P5E_PEX2_STN5_TX_DP<82>")
	)
	(segment
		(start 292.22954 -311.705498)
		(end 292.455346 -311.479692)
		(width 0.1143)
		(layer "In7.Cu")
		(net "P5E_PEX2_STN5_TX_DP<82>")
	)
	(segment
		(start 292.18382 -323.243448)
		(end 292.18382 -319.865248)
		(width 0.1651)
		(layer "In7.Cu")
		(net "P5E_PEX2_STN5_TX_DP<82>")
	)
	(segment
		(start 315.902594 -353.814126)
		(end 317.457074 -352.259646)
		(width 0.1651)
		(layer "In7.Cu")
		(net "P5E_PEX2_STN5_TX_DP<82>")
	)
	(segment
		(start 315.77407 -340.146386)
		(end 297.89374 -332.176374)
		(width 0.1651)
		(layer "In7.Cu")
		(net "P5E_PEX2_STN5_TX_DP<82>")
	)
	(segment
		(start 317.320422 -341.596218)
		(end 317.320422 -341.595964)
		(width 0.1651)
		(layer "In7.Cu")
		(net "P5E_PEX2_STN5_TX_DP<82>")
	)
	(segment
		(start 297.89374 -332.176374)
		(end 294.462454 -328.744834)
		(width 0.1651)
		(layer "In7.Cu")
		(net "P5E_PEX2_STN5_TX_DP<82>")
	)
	(segment
		(start 292.22954 -319.79108)
		(end 292.22954 -311.705498)
		(width 0.1143)
		(layer "In7.Cu")
		(net "P5E_PEX2_STN5_TX_DP<82>")
	)
	(segment
		(start 317.320422 -341.595964)
		(end 317.184278 -341.20709)
		(width 0.1651)
		(layer "In7.Cu")
		(net "P5E_PEX2_STN5_TX_DP<82>")
	)
	(segment
		(start 315.611764 -354.732082)
		(end 315.902594 -354.441252)
		(width 0.1651)
		(layer "In7.Cu")
		(net "P5E_PEX2_STN5_TX_DP<82>")
	)
	(segment
		(start 317.457074 -352.259646)
		(end 317.457074 -341.985854)
		(width 0.1651)
		(layer "In7.Cu")
		(net "P5E_PEX2_STN5_TX_DP<82>")
	)
	(segment
		(start 287.439862 -349.831914)
		(end 287.119822 -349.511874)
		(width 0.13462)
		(layer "F.Cu")
		(net "P5E_PEX2_STN7_TX_DP<121>")
	)
	(segment
		(start 287.119822 -349.511874)
		(end 287.119822 -348.88043)
		(width 0.13462)
		(layer "F.Cu")
		(net "P5E_PEX2_STN7_TX_DP<121>")
	)
	(segment
		(start 287.119822 -348.88043)
		(end 287.414462 -348.58579)
		(width 0.13462)
		(layer "F.Cu")
		(net "P5E_PEX2_STN7_TX_DP<121>")
	)
	(segment
		(start 269.734284 -312.049922)
		(end 269.999714 -312.049922)
		(width 0.1143)
		(layer "In7.Cu")
		(net "P5E_PEX2_STN7_TX_DP<121>")
	)
	(segment
		(start 267.87856 -321.912996)
		(end 266.763754 -319.221358)
		(width 0.1651)
		(layer "In7.Cu")
		(net "P5E_PEX2_STN7_TX_DP<121>")
	)
	(segment
		(start 269.394178 -312.620152)
		(end 269.619984 -312.394346)
		(width 0.1143)
		(layer "In7.Cu")
		(net "P5E_PEX2_STN7_TX_DP<121>")
	)
	(segment
		(start 266.763754 -319.221358)
		(end 266.3698 -317.241174)
		(width 0.1651)
		(layer "In7.Cu")
		(net "P5E_PEX2_STN7_TX_DP<121>")
	)
	(segment
		(start 268.389608 -313.042046)
		(end 268.811502 -312.620152)
		(width 0.1143)
		(layer "In7.Cu")
		(net "P5E_PEX2_STN7_TX_DP<121>")
	)
	(segment
		(start 268.811502 -312.620152)
		(end 269.394178 -312.620152)
		(width 0.1143)
		(layer "In7.Cu")
		(net "P5E_PEX2_STN7_TX_DP<121>")
	)
	(segment
		(start 266.3698 -317.241174)
		(end 266.3698 -316.72403)
		(width 0.1651)
		(layer "In7.Cu")
		(net "P5E_PEX2_STN7_TX_DP<121>")
	)
	(segment
		(start 269.44447 -324.2564)
		(end 267.87856 -321.912996)
		(width 0.1651)
		(layer "In7.Cu")
		(net "P5E_PEX2_STN7_TX_DP<121>")
	)
	(segment
		(start 288.678112 -342.3412)
		(end 288.21634 -341.111332)
		(width 0.1651)
		(layer "In7.Cu")
		(net "P5E_PEX2_STN7_TX_DP<121>")
	)
	(segment
		(start 269.619984 -312.394346)
		(end 269.619984 -312.164222)
		(width 0.1143)
		(layer "In7.Cu")
		(net "P5E_PEX2_STN7_TX_DP<121>")
	)
	(segment
		(start 268.389608 -313.106816)
		(end 268.389608 -313.042046)
		(width 0.1143)
		(layer "In7.Cu")
		(net "P5E_PEX2_STN7_TX_DP<121>")
	)
	(segment
		(start 268.379448 -313.116976)
		(end 268.389608 -313.106816)
		(width 0.1143)
		(layer "In7.Cu")
		(net "P5E_PEX2_STN7_TX_DP<121>")
	)
	(segment
		(start 287.414462 -348.58579)
		(end 287.123632 -348.29496)
		(width 0.1651)
		(layer "In7.Cu")
		(net "P5E_PEX2_STN7_TX_DP<121>")
	)
	(segment
		(start 287.123632 -348.29496)
		(end 287.123632 -347.784674)
		(width 0.1651)
		(layer "In7.Cu")
		(net "P5E_PEX2_STN7_TX_DP<121>")
	)
	(segment
		(start 266.3698 -316.72403)
		(end 267.499846 -313.996578)
		(width 0.1651)
		(layer "In7.Cu")
		(net "P5E_PEX2_STN7_TX_DP<121>")
	)
	(segment
		(start 288.21634 -341.111332)
		(end 269.44447 -324.2564)
		(width 0.1651)
		(layer "In7.Cu")
		(net "P5E_PEX2_STN7_TX_DP<121>")
	)
	(segment
		(start 288.678112 -346.230194)
		(end 288.678112 -342.3412)
		(width 0.1651)
		(layer "In7.Cu")
		(net "P5E_PEX2_STN7_TX_DP<121>")
	)
	(segment
		(start 269.619984 -312.164222)
		(end 269.734284 -312.049922)
		(width 0.1143)
		(layer "In7.Cu")
		(net "P5E_PEX2_STN7_TX_DP<121>")
	)
	(segment
		(start 287.123632 -347.784674)
		(end 288.678112 -346.230194)
		(width 0.1651)
		(layer "In7.Cu")
		(net "P5E_PEX2_STN7_TX_DP<121>")
	)
	(segment
		(start 267.499846 -313.996578)
		(end 268.379448 -313.116976)
		(width 0.1651)
		(layer "In7.Cu")
		(net "P5E_PEX2_STN7_TX_DP<121>")
	)
	(segment
		(start 386.067808 -106.514138)
		(end 386.36575 -106.81208)
		(width 0.13462)
		(layer "F.Cu")
		(net "P5E_PEX3_STN1_TX_DP<20>")
	)
	(segment
		(start 386.99059 -106.81208)
		(end 387.313932 -106.488738)
		(width 0.13462)
		(layer "F.Cu")
		(net "P5E_PEX3_STN1_TX_DP<20>")
	)
	(segment
		(start 386.36575 -106.81208)
		(end 386.99059 -106.81208)
		(width 0.13462)
		(layer "F.Cu")
		(net "P5E_PEX3_STN1_TX_DP<20>")
	)
	(segment
		(start 376.374914 -117.988842)
		(end 372.376192 -131.172458)
		(width 0.1651)
		(layer "In9.Cu")
		(net "P5E_PEX3_STN1_TX_DP<20>")
	)
	(segment
		(start 411.394656 -278.420068)
		(end 411.635448 -278.420068)
		(width 0.1143)
		(layer "In9.Cu")
		(net "P5E_PEX3_STN1_TX_DP<20>")
	)
	(segment
		(start 379.874272 -109.540548)
		(end 376.374914 -117.988842)
		(width 0.1651)
		(layer "In9.Cu")
		(net "P5E_PEX3_STN1_TX_DP<20>")
	)
	(segment
		(start 411.134052 -271.471898)
		(end 411.134052 -271.500346)
		(width 0.1143)
		(layer "In9.Cu")
		(net "P5E_PEX3_STN1_TX_DP<20>")
	)
	(segment
		(start 386.067808 -106.514138)
		(end 385.776978 -106.804968)
		(width 0.1651)
		(layer "In9.Cu")
		(net "P5E_PEX3_STN1_TX_DP<20>")
	)
	(segment
		(start 383.864612 -106.804968)
		(end 381.72263 -107.69219)
		(width 0.1651)
		(layer "In9.Cu")
		(net "P5E_PEX3_STN1_TX_DP<20>")
	)
	(segment
		(start 372.376192 -131.172458)
		(end 372.376192 -138.253978)
		(width 0.1651)
		(layer "In9.Cu")
		(net "P5E_PEX3_STN1_TX_DP<20>")
	)
	(segment
		(start 411.635448 -278.420068)
		(end 411.749748 -278.534368)
		(width 0.1143)
		(layer "In9.Cu")
		(net "P5E_PEX3_STN1_TX_DP<20>")
	)
	(segment
		(start 385.776978 -106.804968)
		(end 383.864612 -106.804968)
		(width 0.1651)
		(layer "In9.Cu")
		(net "P5E_PEX3_STN1_TX_DP<20>")
	)
	(segment
		(start 411.749748 -278.534368)
		(end 411.749748 -278.799798)
		(width 0.1143)
		(layer "In9.Cu")
		(net "P5E_PEX3_STN1_TX_DP<20>")
	)
	(segment
		(start 372.376192 -138.253978)
		(end 374.95861 -144.488662)
		(width 0.1651)
		(layer "In9.Cu")
		(net "P5E_PEX3_STN1_TX_DP<20>")
	)
	(segment
		(start 411.179772 -278.205184)
		(end 411.394656 -278.420068)
		(width 0.1143)
		(layer "In9.Cu")
		(net "P5E_PEX3_STN1_TX_DP<20>")
	)
	(segment
		(start 376.250962 -162.077146)
		(end 411.134052 -265.13282)
		(width 0.1651)
		(layer "In9.Cu")
		(net "P5E_PEX3_STN1_TX_DP<20>")
	)
	(segment
		(start 374.95861 -144.488662)
		(end 375.683018 -159.221678)
		(width 0.1651)
		(layer "In9.Cu")
		(net "P5E_PEX3_STN1_TX_DP<20>")
	)
	(segment
		(start 375.683018 -159.221678)
		(end 376.250962 -162.077146)
		(width 0.1651)
		(layer "In9.Cu")
		(net "P5E_PEX3_STN1_TX_DP<20>")
	)
	(segment
		(start 381.72263 -107.69219)
		(end 379.874272 -109.540548)
		(width 0.1651)
		(layer "In9.Cu")
		(net "P5E_PEX3_STN1_TX_DP<20>")
	)
	(segment
		(start 411.179772 -271.546066)
		(end 411.179772 -278.205184)
		(width 0.1143)
		(layer "In9.Cu")
		(net "P5E_PEX3_STN1_TX_DP<20>")
	)
	(segment
		(start 411.134052 -265.13282)
		(end 411.134052 -271.471898)
		(width 0.1651)
		(layer "In9.Cu")
		(net "P5E_PEX3_STN1_TX_DP<20>")
	)
	(segment
		(start 411.134052 -271.500346)
		(end 411.179772 -271.546066)
		(width 0.1143)
		(layer "In9.Cu")
		(net "P5E_PEX3_STN1_TX_DP<20>")
	)
	(segment
		(start 374.591072 -343.36609)
		(end 374.591072 -342.73363)
		(width 0.13462)
		(layer "F.Cu")
		(net "P5E_PEX3_STN6_TX_DP<102>")
	)
	(segment
		(start 374.591072 -342.73363)
		(end 374.29694 -342.439498)
		(width 0.13462)
		(layer "F.Cu")
		(net "P5E_PEX3_STN6_TX_DP<102>")
	)
	(segment
		(start 374.27154 -343.685622)
		(end 374.591072 -343.36609)
		(width 0.13462)
		(layer "F.Cu")
		(net "P5E_PEX3_STN6_TX_DP<102>")
	)
	(segment
		(start 374.29694 -342.439498)
		(end 374.58777 -342.148668)
		(width 0.1651)
		(layer "In7.Cu")
		(net "P5E_PEX3_STN6_TX_DP<102>")
	)
	(segment
		(start 400.349974 -313.265312)
		(end 400.349974 -312.999882)
		(width 0.1143)
		(layer "In7.Cu")
		(net "P5E_PEX3_STN6_TX_DP<102>")
	)
	(segment
		(start 400.00555 -313.379612)
		(end 400.235674 -313.379612)
		(width 0.1143)
		(layer "In7.Cu")
		(net "P5E_PEX3_STN6_TX_DP<102>")
	)
	(segment
		(start 400.235674 -313.379612)
		(end 400.349974 -313.265312)
		(width 0.1143)
		(layer "In7.Cu")
		(net "P5E_PEX3_STN6_TX_DP<102>")
	)
	(segment
		(start 399.779744 -319.915032)
		(end 399.779744 -313.605418)
		(width 0.1143)
		(layer "In7.Cu")
		(net "P5E_PEX3_STN6_TX_DP<102>")
	)
	(segment
		(start 374.58777 -342.148668)
		(end 374.58777 -341.244428)
		(width 0.1651)
		(layer "In7.Cu")
		(net "P5E_PEX3_STN6_TX_DP<102>")
	)
	(segment
		(start 399.734024 -320.528696)
		(end 399.734024 -319.9892)
		(width 0.1651)
		(layer "In7.Cu")
		(net "P5E_PEX3_STN6_TX_DP<102>")
	)
	(segment
		(start 398.396968 -321.865752)
		(end 399.734024 -320.528696)
		(width 0.1651)
		(layer "In7.Cu")
		(net "P5E_PEX3_STN6_TX_DP<102>")
	)
	(segment
		(start 399.734024 -319.960752)
		(end 399.779744 -319.915032)
		(width 0.1143)
		(layer "In7.Cu")
		(net "P5E_PEX3_STN6_TX_DP<102>")
	)
	(segment
		(start 399.734024 -319.9892)
		(end 399.734024 -319.960752)
		(width 0.1143)
		(layer "In7.Cu")
		(net "P5E_PEX3_STN6_TX_DP<102>")
	)
	(segment
		(start 374.58777 -341.244428)
		(end 398.396968 -321.865752)
		(width 0.1651)
		(layer "In7.Cu")
		(net "P5E_PEX3_STN6_TX_DP<102>")
	)
	(segment
		(start 399.779744 -313.605418)
		(end 400.00555 -313.379612)
		(width 0.1143)
		(layer "In7.Cu")
		(net "P5E_PEX3_STN6_TX_DP<102>")
	)
	(segment
		(start 19.001486 -32.4104)
		(end 18.38833 -32.4104)
		(width 0.13462)
		(layer "F.Cu")
		(net "P5E_PEX0_STN2_TX_DP<46>")
	)
	(segment
		(start 18.38833 -32.4104)
		(end 18.059146 -32.739584)
		(width 0.13462)
		(layer "F.Cu")
		(net "P5E_PEX0_STN2_TX_DP<46>")
	)
	(segment
		(start 19.30527 -32.714184)
		(end 19.001486 -32.4104)
		(width 0.13462)
		(layer "F.Cu")
		(net "P5E_PEX0_STN2_TX_DP<46>")
	)
	(segment
		(start 19.30527 -32.714184)
		(end 19.5961 -32.423354)
		(width 0.1651)
		(layer "In11.Cu")
		(net "P5E_PEX0_STN2_TX_DP<46>")
	)
	(segment
		(start 32.69869 -104.937814)
		(end 32.095694 -116.818664)
		(width 0.1651)
		(layer "In11.Cu")
		(net "P5E_PEX0_STN2_TX_DP<46>")
	)
	(segment
		(start 20.853146 -32.512254)
		(end 20.942046 -32.423354)
		(width 0.1651)
		(layer "In11.Cu")
		(net "P5E_PEX0_STN2_TX_DP<46>")
	)
	(segment
		(start 44.82973 -280.10485)
		(end 45.044868 -280.319988)
		(width 0.1143)
		(layer "In11.Cu")
		(net "P5E_PEX0_STN2_TX_DP<46>")
	)
	(segment
		(start 45.28566 -280.319988)
		(end 45.39996 -280.434288)
		(width 0.1143)
		(layer "In11.Cu")
		(net "P5E_PEX0_STN2_TX_DP<46>")
	)
	(segment
		(start 37.161724 -62.965838)
		(end 36.277042 -78.744572)
		(width 0.1651)
		(layer "In11.Cu")
		(net "P5E_PEX0_STN2_TX_DP<46>")
	)
	(segment
		(start 20.268946 -32.423354)
		(end 20.357846 -32.512254)
		(width 0.1651)
		(layer "In11.Cu")
		(net "P5E_PEX0_STN2_TX_DP<46>")
	)
	(segment
		(start 32.095694 -116.818664)
		(end 32.558736 -138.17854)
		(width 0.1651)
		(layer "In11.Cu")
		(net "P5E_PEX0_STN2_TX_DP<46>")
	)
	(segment
		(start 44.78401 -271.427448)
		(end 44.82973 -271.473168)
		(width 0.1143)
		(layer "In11.Cu")
		(net "P5E_PEX0_STN2_TX_DP<46>")
	)
	(segment
		(start 20.357846 -32.512254)
		(end 20.853146 -32.512254)
		(width 0.1651)
		(layer "In11.Cu")
		(net "P5E_PEX0_STN2_TX_DP<46>")
	)
	(segment
		(start 36.41979 -50.504344)
		(end 37.161724 -62.965838)
		(width 0.1651)
		(layer "In11.Cu")
		(net "P5E_PEX0_STN2_TX_DP<46>")
	)
	(segment
		(start 45.39996 -280.434288)
		(end 45.39996 -280.699718)
		(width 0.1143)
		(layer "In11.Cu")
		(net "P5E_PEX0_STN2_TX_DP<46>")
	)
	(segment
		(start 24.221948 -33.620456)
		(end 34.557716 -46.559216)
		(width 0.1651)
		(layer "In11.Cu")
		(net "P5E_PEX0_STN2_TX_DP<46>")
	)
	(segment
		(start 34.557716 -46.559216)
		(end 35.867086 -48.925734)
		(width 0.1651)
		(layer "In11.Cu")
		(net "P5E_PEX0_STN2_TX_DP<46>")
	)
	(segment
		(start 36.277042 -78.744572)
		(end 32.69869 -104.937814)
		(width 0.1651)
		(layer "In11.Cu")
		(net "P5E_PEX0_STN2_TX_DP<46>")
	)
	(segment
		(start 45.044868 -280.319988)
		(end 45.28566 -280.319988)
		(width 0.1143)
		(layer "In11.Cu")
		(net "P5E_PEX0_STN2_TX_DP<46>")
	)
	(segment
		(start 19.5961 -32.423354)
		(end 20.268946 -32.423354)
		(width 0.1651)
		(layer "In11.Cu")
		(net "P5E_PEX0_STN2_TX_DP<46>")
	)
	(segment
		(start 43.778424 -264.559288)
		(end 44.78401 -270.220948)
		(width 0.1651)
		(layer "In11.Cu")
		(net "P5E_PEX0_STN2_TX_DP<46>")
	)
	(segment
		(start 44.78401 -271.399)
		(end 44.78401 -271.427448)
		(width 0.1143)
		(layer "In11.Cu")
		(net "P5E_PEX0_STN2_TX_DP<46>")
	)
	(segment
		(start 44.78401 -270.220948)
		(end 44.78401 -271.399)
		(width 0.1651)
		(layer "In11.Cu")
		(net "P5E_PEX0_STN2_TX_DP<46>")
	)
	(segment
		(start 32.558736 -138.17854)
		(end 43.778424 -264.559288)
		(width 0.1651)
		(layer "In11.Cu")
		(net "P5E_PEX0_STN2_TX_DP<46>")
	)
	(segment
		(start 35.867086 -48.925734)
		(end 36.41979 -50.504344)
		(width 0.1651)
		(layer "In11.Cu")
		(net "P5E_PEX0_STN2_TX_DP<46>")
	)
	(segment
		(start 44.82973 -271.473168)
		(end 44.82973 -280.10485)
		(width 0.1143)
		(layer "In11.Cu")
		(net "P5E_PEX0_STN2_TX_DP<46>")
	)
	(segment
		(start 20.942046 -32.423354)
		(end 21.329142 -32.423354)
		(width 0.1651)
		(layer "In11.Cu")
		(net "P5E_PEX0_STN2_TX_DP<46>")
	)
	(segment
		(start 21.329142 -32.423354)
		(end 24.221948 -33.620456)
		(width 0.1651)
		(layer "In11.Cu")
		(net "P5E_PEX0_STN2_TX_DP<46>")
	)
	(segment
		(start 135.405368 -28.250642)
		(end 135.10133 -28.55468)
		(width 0.13462)
		(layer "F.Cu")
		(net "P5E_PEX1_STN2_TX_DN<44>")
	)
	(segment
		(start 135.10133 -28.55468)
		(end 134.488682 -28.55468)
		(width 0.13462)
		(layer "F.Cu")
		(net "P5E_PEX1_STN2_TX_DN<44>")
	)
	(segment
		(start 134.488682 -28.55468)
		(end 134.159244 -28.225242)
		(width 0.13462)
		(layer "F.Cu")
		(net "P5E_PEX1_STN2_TX_DN<44>")
	)
	(segment
		(start 163.065968 -271.399)
		(end 163.065968 -271.427448)
		(width 0.1143)
		(layer "In11.Cu")
		(net "P5E_PEX1_STN2_TX_DN<44>")
	)
	(segment
		(start 140.001752 -29.272484)
		(end 152.02789 -44.445428)
		(width 0.1651)
		(layer "In11.Cu")
		(net "P5E_PEX1_STN2_TX_DN<44>")
	)
	(segment
		(start 154.038554 -48.143668)
		(end 154.786584 -50.356516)
		(width 0.1651)
		(layer "In11.Cu")
		(net "P5E_PEX1_STN2_TX_DN<44>")
	)
	(segment
		(start 163.12388 -280.129488)
		(end 163.285678 -280.129488)
		(width 0.1143)
		(layer "In11.Cu")
		(net "P5E_PEX1_STN2_TX_DN<44>")
	)
	(segment
		(start 163.285678 -280.129488)
		(end 163.399978 -280.015188)
		(width 0.1143)
		(layer "In11.Cu")
		(net "P5E_PEX1_STN2_TX_DN<44>")
	)
	(segment
		(start 162.175952 -264.583164)
		(end 163.065968 -270.72717)
		(width 0.1651)
		(layer "In11.Cu")
		(net "P5E_PEX1_STN2_TX_DN<44>")
	)
	(segment
		(start 163.020248 -271.473168)
		(end 163.020248 -280.025856)
		(width 0.1143)
		(layer "In11.Cu")
		(net "P5E_PEX1_STN2_TX_DN<44>")
	)
	(segment
		(start 138.22934 -28.541472)
		(end 140.001752 -29.272484)
		(width 0.1651)
		(layer "In11.Cu")
		(net "P5E_PEX1_STN2_TX_DN<44>")
	)
	(segment
		(start 154.917394 -145.385282)
		(end 162.175952 -264.583164)
		(width 0.1651)
		(layer "In11.Cu")
		(net "P5E_PEX1_STN2_TX_DN<44>")
	)
	(segment
		(start 163.065968 -270.72717)
		(end 163.065968 -271.399)
		(width 0.1651)
		(layer "In11.Cu")
		(net "P5E_PEX1_STN2_TX_DN<44>")
	)
	(segment
		(start 155.487878 -62.131194)
		(end 155.845256 -135.970264)
		(width 0.1651)
		(layer "In11.Cu")
		(net "P5E_PEX1_STN2_TX_DN<44>")
	)
	(segment
		(start 135.760714 -28.541472)
		(end 138.22934 -28.541472)
		(width 0.1651)
		(layer "In11.Cu")
		(net "P5E_PEX1_STN2_TX_DN<44>")
	)
	(segment
		(start 155.845256 -135.970264)
		(end 154.917394 -145.385282)
		(width 0.1651)
		(layer "In11.Cu")
		(net "P5E_PEX1_STN2_TX_DN<44>")
	)
	(segment
		(start 163.065968 -271.427448)
		(end 163.020248 -271.473168)
		(width 0.1143)
		(layer "In11.Cu")
		(net "P5E_PEX1_STN2_TX_DN<44>")
	)
	(segment
		(start 135.650732 -28.496006)
		(end 135.760714 -28.541472)
		(width 0.1651)
		(layer "In11.Cu")
		(net "P5E_PEX1_STN2_TX_DN<44>")
	)
	(segment
		(start 154.786584 -50.356516)
		(end 155.487878 -62.131194)
		(width 0.1651)
		(layer "In11.Cu")
		(net "P5E_PEX1_STN2_TX_DN<44>")
	)
	(segment
		(start 163.020248 -280.025856)
		(end 163.12388 -280.129488)
		(width 0.1143)
		(layer "In11.Cu")
		(net "P5E_PEX1_STN2_TX_DN<44>")
	)
	(segment
		(start 135.405368 -28.250642)
		(end 135.650732 -28.496006)
		(width 0.1651)
		(layer "In11.Cu")
		(net "P5E_PEX1_STN2_TX_DN<44>")
	)
	(segment
		(start 163.399978 -280.015188)
		(end 163.399978 -279.749504)
		(width 0.1143)
		(layer "In11.Cu")
		(net "P5E_PEX1_STN2_TX_DN<44>")
	)
	(segment
		(start 152.02789 -44.445428)
		(end 154.038554 -48.143668)
		(width 0.1651)
		(layer "In11.Cu")
		(net "P5E_PEX1_STN2_TX_DN<44>")
	)
	(segment
		(start 328.616564 -342.734138)
		(end 328.911204 -342.439498)
		(width 0.13462)
		(layer "F.Cu")
		(net "P5E_PEX2_STN5_TX_DN<87>")
	)
	(segment
		(start 328.616564 -343.365582)
		(end 328.616564 -342.734138)
		(width 0.13462)
		(layer "F.Cu")
		(net "P5E_PEX2_STN5_TX_DN<87>")
	)
	(segment
		(start 328.936604 -343.685622)
		(end 328.616564 -343.365582)
		(width 0.13462)
		(layer "F.Cu")
		(net "P5E_PEX2_STN5_TX_DN<87>")
	)
	(segment
		(start 328.620374 -341.6046)
		(end 328.0918 -340.4616)
		(width 0.1651)
		(layer "In7.Cu")
		(net "P5E_PEX2_STN5_TX_DN<87>")
	)
	(segment
		(start 297.284394 -313.570112)
		(end 297.435524 -313.570112)
		(width 0.1143)
		(layer "In7.Cu")
		(net "P5E_PEX2_STN5_TX_DN<87>")
	)
	(segment
		(start 300.055788 -326.480678)
		(end 299.705522 -326.130412)
		(width 0.1651)
		(layer "In7.Cu")
		(net "P5E_PEX2_STN5_TX_DN<87>")
	)
	(segment
		(start 321.810634 -336.118708)
		(end 300.980348 -327.530968)
		(width 0.1651)
		(layer "In7.Cu")
		(net "P5E_PEX2_STN5_TX_DN<87>")
	)
	(segment
		(start 299.579792 -326.130412)
		(end 298.831762 -325.382382)
		(width 0.1651)
		(layer "In7.Cu")
		(net "P5E_PEX2_STN5_TX_DN<87>")
	)
	(segment
		(start 328.0918 -340.4616)
		(end 321.810634 -336.118708)
		(width 0.1651)
		(layer "In7.Cu")
		(net "P5E_PEX2_STN5_TX_DN<87>")
	)
	(segment
		(start 328.911204 -342.439498)
		(end 328.620374 -342.148668)
		(width 0.1651)
		(layer "In7.Cu")
		(net "P5E_PEX2_STN5_TX_DN<87>")
	)
	(segment
		(start 297.435524 -313.570112)
		(end 297.549824 -313.684412)
		(width 0.1143)
		(layer "In7.Cu")
		(net "P5E_PEX2_STN5_TX_DN<87>")
	)
	(segment
		(start 300.055788 -326.606408)
		(end 300.055788 -326.480678)
		(width 0.1651)
		(layer "In7.Cu")
		(net "P5E_PEX2_STN5_TX_DN<87>")
	)
	(segment
		(start 300.980348 -327.530968)
		(end 300.055788 -326.606408)
		(width 0.1651)
		(layer "In7.Cu")
		(net "P5E_PEX2_STN5_TX_DN<87>")
	)
	(segment
		(start 297.170094 -319.81648)
		(end 297.170094 -313.684412)
		(width 0.1143)
		(layer "In7.Cu")
		(net "P5E_PEX2_STN5_TX_DN<87>")
	)
	(segment
		(start 297.170094 -313.684412)
		(end 297.284394 -313.570112)
		(width 0.1143)
		(layer "In7.Cu")
		(net "P5E_PEX2_STN5_TX_DN<87>")
	)
	(segment
		(start 297.215814 -319.8622)
		(end 297.170094 -319.81648)
		(width 0.1143)
		(layer "In7.Cu")
		(net "P5E_PEX2_STN5_TX_DN<87>")
	)
	(segment
		(start 297.215814 -321.481196)
		(end 297.215814 -319.890648)
		(width 0.1651)
		(layer "In7.Cu")
		(net "P5E_PEX2_STN5_TX_DN<87>")
	)
	(segment
		(start 299.705522 -326.130412)
		(end 299.579792 -326.130412)
		(width 0.1651)
		(layer "In7.Cu")
		(net "P5E_PEX2_STN5_TX_DN<87>")
	)
	(segment
		(start 298.831762 -325.382382)
		(end 297.215814 -321.481196)
		(width 0.1651)
		(layer "In7.Cu")
		(net "P5E_PEX2_STN5_TX_DN<87>")
	)
	(segment
		(start 297.215814 -319.890648)
		(end 297.215814 -319.8622)
		(width 0.1143)
		(layer "In7.Cu")
		(net "P5E_PEX2_STN5_TX_DN<87>")
	)
	(segment
		(start 328.620374 -342.148668)
		(end 328.620374 -341.6046)
		(width 0.1651)
		(layer "In7.Cu")
		(net "P5E_PEX2_STN5_TX_DN<87>")
	)
	(segment
		(start 297.549824 -313.684412)
		(end 297.549824 -313.949842)
		(width 0.1143)
		(layer "In7.Cu")
		(net "P5E_PEX2_STN5_TX_DN<87>")
	)
	(segment
		(start 312.477404 -343.685622)
		(end 312.797444 -343.365582)
		(width 0.13462)
		(layer "F.Cu")
		(net "P5E_PEX2_STN6_TX_DP<111>")
	)
	(segment
		(start 312.797444 -343.365582)
		(end 312.797444 -342.734138)
		(width 0.13462)
		(layer "F.Cu")
		(net "P5E_PEX2_STN6_TX_DP<111>")
	)
	(segment
		(start 312.797444 -342.734138)
		(end 312.502804 -342.439498)
		(width 0.13462)
		(layer "F.Cu")
		(net "P5E_PEX2_STN6_TX_DP<111>")
	)
	(segment
		(start 275.129498 -311.69483)
		(end 275.344636 -311.479692)
		(width 0.1143)
		(layer "In13.Cu")
		(net "P5E_PEX2_STN6_TX_DP<111>")
	)
	(segment
		(start 281.860498 -334.761078)
		(end 276.479508 -329.380088)
		(width 0.1651)
		(layer "In13.Cu")
		(net "P5E_PEX2_STN6_TX_DP<111>")
	)
	(segment
		(start 275.083778 -326.010524)
		(end 275.083778 -319.995296)
		(width 0.1651)
		(layer "In13.Cu")
		(net "P5E_PEX2_STN6_TX_DP<111>")
	)
	(segment
		(start 275.083778 -319.966848)
		(end 275.129498 -319.921128)
		(width 0.1143)
		(layer "In13.Cu")
		(net "P5E_PEX2_STN6_TX_DP<111>")
	)
	(segment
		(start 276.479508 -329.380088)
		(end 275.083778 -326.010524)
		(width 0.1651)
		(layer "In13.Cu")
		(net "P5E_PEX2_STN6_TX_DP<111>")
	)
	(segment
		(start 312.793634 -341.63)
		(end 312.290714 -341.12708)
		(width 0.1651)
		(layer "In13.Cu")
		(net "P5E_PEX2_STN6_TX_DP<111>")
	)
	(segment
		(start 312.502804 -342.439498)
		(end 312.793634 -342.148668)
		(width 0.1651)
		(layer "In13.Cu")
		(net "P5E_PEX2_STN6_TX_DP<111>")
	)
	(segment
		(start 312.290714 -341.12708)
		(end 281.860498 -334.761078)
		(width 0.1651)
		(layer "In13.Cu")
		(net "P5E_PEX2_STN6_TX_DP<111>")
	)
	(segment
		(start 275.344636 -311.479692)
		(end 275.585428 -311.479692)
		(width 0.1143)
		(layer "In13.Cu")
		(net "P5E_PEX2_STN6_TX_DP<111>")
	)
	(segment
		(start 312.793634 -342.148668)
		(end 312.793634 -341.63)
		(width 0.1651)
		(layer "In13.Cu")
		(net "P5E_PEX2_STN6_TX_DP<111>")
	)
	(segment
		(start 275.083778 -319.995296)
		(end 275.083778 -319.966848)
		(width 0.1143)
		(layer "In13.Cu")
		(net "P5E_PEX2_STN6_TX_DP<111>")
	)
	(segment
		(start 275.699728 -311.365392)
		(end 275.699728 -311.099962)
		(width 0.1143)
		(layer "In13.Cu")
		(net "P5E_PEX2_STN6_TX_DP<111>")
	)
	(segment
		(start 275.129498 -319.921128)
		(end 275.129498 -311.69483)
		(width 0.1143)
		(layer "In13.Cu")
		(net "P5E_PEX2_STN6_TX_DP<111>")
	)
	(segment
		(start 275.585428 -311.479692)
		(end 275.699728 -311.365392)
		(width 0.1143)
		(layer "In13.Cu")
		(net "P5E_PEX2_STN6_TX_DP<111>")
	)
	(segment
		(start 431.548032 -144.7165)
		(end 431.228246 -144.396714)
		(width 0.13462)
		(layer "F.Cu")
		(net "P5E_PEX3_STN0_TX_DN<9>")
	)
	(segment
		(start 432.47437 -144.422114)
		(end 432.179984 -144.7165)
		(width 0.13462)
		(layer "F.Cu")
		(net "P5E_PEX3_STN0_TX_DN<9>")
	)
	(segment
		(start 432.179984 -144.7165)
		(end 431.548032 -144.7165)
		(width 0.13462)
		(layer "F.Cu")
		(net "P5E_PEX3_STN0_TX_DN<9>")
	)
	(segment
		(start 428.516034 -271.357344)
		(end 428.516034 -271.471898)
		(width 0.1651)
		(layer "In9.Cu")
		(net "P5E_PEX3_STN0_TX_DN<9>")
	)
	(segment
		(start 428.470314 -278.12619)
		(end 428.573692 -278.229568)
		(width 0.1143)
		(layer "In9.Cu")
		(net "P5E_PEX3_STN0_TX_DN<9>")
	)
	(segment
		(start 428.516034 -271.471898)
		(end 428.516034 -271.500346)
		(width 0.1143)
		(layer "In9.Cu")
		(net "P5E_PEX3_STN0_TX_DN<9>")
	)
	(segment
		(start 428.573692 -278.229568)
		(end 428.73549 -278.229568)
		(width 0.1143)
		(layer "In9.Cu")
		(net "P5E_PEX3_STN0_TX_DN<9>")
	)
	(segment
		(start 432.7652 -144.712944)
		(end 433.472844 -144.712944)
		(width 0.1651)
		(layer "In9.Cu")
		(net "P5E_PEX3_STN0_TX_DN<9>")
	)
	(segment
		(start 429.496728 -260.314694)
		(end 429.496728 -268.989302)
		(width 0.1651)
		(layer "In9.Cu")
		(net "P5E_PEX3_STN0_TX_DN<9>")
	)
	(segment
		(start 431.278538 -172.971714)
		(end 429.998632 -177.74412)
		(width 0.1651)
		(layer "In9.Cu")
		(net "P5E_PEX3_STN0_TX_DN<9>")
	)
	(segment
		(start 428.470314 -271.546066)
		(end 428.470314 -278.12619)
		(width 0.1143)
		(layer "In9.Cu")
		(net "P5E_PEX3_STN0_TX_DN<9>")
	)
	(segment
		(start 438.085484 -150.546054)
		(end 439.761884 -154.593036)
		(width 0.1651)
		(layer "In9.Cu")
		(net "P5E_PEX3_STN0_TX_DN<9>")
	)
	(segment
		(start 439.761884 -158.27502)
		(end 431.278538 -172.971714)
		(width 0.1651)
		(layer "In9.Cu")
		(net "P5E_PEX3_STN0_TX_DN<9>")
	)
	(segment
		(start 429.496728 -268.989302)
		(end 428.516034 -271.357344)
		(width 0.1651)
		(layer "In9.Cu")
		(net "P5E_PEX3_STN0_TX_DN<9>")
	)
	(segment
		(start 428.73549 -278.229568)
		(end 428.84979 -278.115268)
		(width 0.1143)
		(layer "In9.Cu")
		(net "P5E_PEX3_STN0_TX_DN<9>")
	)
	(segment
		(start 439.761884 -154.593036)
		(end 439.761884 -158.27502)
		(width 0.1651)
		(layer "In9.Cu")
		(net "P5E_PEX3_STN0_TX_DN<9>")
	)
	(segment
		(start 429.998632 -177.74412)
		(end 426.135546 -221.85376)
		(width 0.1651)
		(layer "In9.Cu")
		(net "P5E_PEX3_STN0_TX_DN<9>")
	)
	(segment
		(start 428.84979 -278.115268)
		(end 428.84979 -277.849838)
		(width 0.1143)
		(layer "In9.Cu")
		(net "P5E_PEX3_STN0_TX_DN<9>")
	)
	(segment
		(start 428.516034 -271.500346)
		(end 428.470314 -271.546066)
		(width 0.1143)
		(layer "In9.Cu")
		(net "P5E_PEX3_STN0_TX_DN<9>")
	)
	(segment
		(start 433.472844 -144.712944)
		(end 435.627526 -146.867626)
		(width 0.1651)
		(layer "In9.Cu")
		(net "P5E_PEX3_STN0_TX_DN<9>")
	)
	(segment
		(start 432.47437 -144.422114)
		(end 432.7652 -144.712944)
		(width 0.1651)
		(layer "In9.Cu")
		(net "P5E_PEX3_STN0_TX_DN<9>")
	)
	(segment
		(start 435.627526 -146.867626)
		(end 438.085484 -150.546054)
		(width 0.1651)
		(layer "In9.Cu")
		(net "P5E_PEX3_STN0_TX_DN<9>")
	)
	(segment
		(start 426.135546 -221.85376)
		(end 429.496728 -260.314694)
		(width 0.1651)
		(layer "In9.Cu")
		(net "P5E_PEX3_STN0_TX_DN<9>")
	)
	(segment
		(start 415.807144 -343.36609)
		(end 415.807144 -342.73363)
		(width 0.13462)
		(layer "F.Cu")
		(net "P5E_PEX3_STN7_TX_DP<114>")
	)
	(segment
		(start 415.487612 -343.685622)
		(end 415.807144 -343.36609)
		(width 0.13462)
		(layer "F.Cu")
		(net "P5E_PEX3_STN7_TX_DP<114>")
	)
	(segment
		(start 415.807144 -342.73363)
		(end 415.513012 -342.439498)
		(width 0.13462)
		(layer "F.Cu")
		(net "P5E_PEX3_STN7_TX_DP<114>")
	)
	(segment
		(start 366.2807 -322.494656)
		(end 366.2807 -318.826896)
		(width 0.1651)
		(layer "In11.Cu")
		(net "P5E_PEX3_STN7_TX_DP<114>")
	)
	(segment
		(start 415.803588 -341.594694)
		(end 415.055812 -340.56447)
		(width 0.1651)
		(layer "In11.Cu")
		(net "P5E_PEX3_STN7_TX_DP<114>")
	)
	(segment
		(start 383.921 -302.883824)
		(end 383.949448 -302.883824)
		(width 0.1143)
		(layer "In11.Cu")
		(net "P5E_PEX3_STN7_TX_DP<114>")
	)
	(segment
		(start 390.584436 -303.499774)
		(end 390.849866 -303.499774)
		(width 0.1143)
		(layer "In11.Cu")
		(net "P5E_PEX3_STN7_TX_DP<114>")
	)
	(segment
		(start 378.781056 -302.883824)
		(end 383.921 -302.883824)
		(width 0.1651)
		(layer "In11.Cu")
		(net "P5E_PEX3_STN7_TX_DP<114>")
	)
	(segment
		(start 415.803842 -342.148668)
		(end 415.803842 -341.594948)
		(width 0.1651)
		(layer "In11.Cu")
		(net "P5E_PEX3_STN7_TX_DP<114>")
	)
	(segment
		(start 374.03278 -331.396848)
		(end 370.683282 -329.555602)
		(width 0.1651)
		(layer "In11.Cu")
		(net "P5E_PEX3_STN7_TX_DP<114>")
	)
	(segment
		(start 415.055812 -340.56447)
		(end 374.03278 -331.396848)
		(width 0.1651)
		(layer "In11.Cu")
		(net "P5E_PEX3_STN7_TX_DP<114>")
	)
	(segment
		(start 373.58828 -306.50434)
		(end 376.097038 -303.995582)
		(width 0.1651)
		(layer "In11.Cu")
		(net "P5E_PEX3_STN7_TX_DP<114>")
	)
	(segment
		(start 367.78311 -315.199776)
		(end 373.58828 -306.51196)
		(width 0.1651)
		(layer "In11.Cu")
		(net "P5E_PEX3_STN7_TX_DP<114>")
	)
	(segment
		(start 415.803842 -341.594948)
		(end 415.803588 -341.594694)
		(width 0.1651)
		(layer "In11.Cu")
		(net "P5E_PEX3_STN7_TX_DP<114>")
	)
	(segment
		(start 415.513012 -342.439498)
		(end 415.803842 -342.148668)
		(width 0.1651)
		(layer "In11.Cu")
		(net "P5E_PEX3_STN7_TX_DP<114>")
	)
	(segment
		(start 390.470136 -303.385474)
		(end 390.584436 -303.499774)
		(width 0.1143)
		(layer "In11.Cu")
		(net "P5E_PEX3_STN7_TX_DP<114>")
	)
	(segment
		(start 366.2807 -318.826896)
		(end 367.78311 -315.199776)
		(width 0.1651)
		(layer "In11.Cu")
		(net "P5E_PEX3_STN7_TX_DP<114>")
	)
	(segment
		(start 383.949448 -302.883824)
		(end 383.995168 -302.929544)
		(width 0.1143)
		(layer "In11.Cu")
		(net "P5E_PEX3_STN7_TX_DP<114>")
	)
	(segment
		(start 376.097038 -303.995582)
		(end 378.781056 -302.883824)
		(width 0.1651)
		(layer "In11.Cu")
		(net "P5E_PEX3_STN7_TX_DP<114>")
	)
	(segment
		(start 390.254998 -302.929544)
		(end 390.470136 -303.144682)
		(width 0.1143)
		(layer "In11.Cu")
		(net "P5E_PEX3_STN7_TX_DP<114>")
	)
	(segment
		(start 370.683282 -329.555602)
		(end 368.160554 -327.032874)
		(width 0.1651)
		(layer "In11.Cu")
		(net "P5E_PEX3_STN7_TX_DP<114>")
	)
	(segment
		(start 373.58828 -306.51196)
		(end 373.58828 -306.50434)
		(width 0.1651)
		(layer "In11.Cu")
		(net "P5E_PEX3_STN7_TX_DP<114>")
	)
	(segment
		(start 390.470136 -303.144682)
		(end 390.470136 -303.385474)
		(width 0.1143)
		(layer "In11.Cu")
		(net "P5E_PEX3_STN7_TX_DP<114>")
	)
	(segment
		(start 368.160554 -327.032874)
		(end 366.2807 -322.494656)
		(width 0.1651)
		(layer "In11.Cu")
		(net "P5E_PEX3_STN7_TX_DP<114>")
	)
	(segment
		(start 383.995168 -302.929544)
		(end 390.254998 -302.929544)
		(width 0.1143)
		(layer "In11.Cu")
		(net "P5E_PEX3_STN7_TX_DP<114>")
	)
	(segment
		(start 73.947274 -33.657286)
		(end 73.65238 -33.95218)
		(width 0.13462)
		(layer "F.Cu")
		(net "P5E_PEX0_STN2_TX_DN<39>")
	)
	(segment
		(start 73.65238 -33.95218)
		(end 73.021444 -33.95218)
		(width 0.13462)
		(layer "F.Cu")
		(net "P5E_PEX0_STN2_TX_DN<39>")
	)
	(segment
		(start 73.021444 -33.95218)
		(end 72.70115 -33.631886)
		(width 0.13462)
		(layer "F.Cu")
		(net "P5E_PEX0_STN2_TX_DN<39>")
	)
	(segment
		(start 87.776304 -62.053724)
		(end 86.882478 -63.834518)
		(width 0.1651)
		(layer "In11.Cu")
		(net "P5E_PEX0_STN2_TX_DN<39>")
	)
	(segment
		(start 51.715924 -271.399)
		(end 51.715924 -271.427448)
		(width 0.1143)
		(layer "In11.Cu")
		(net "P5E_PEX0_STN2_TX_DN<39>")
	)
	(segment
		(start 61.34608 -107.220512)
		(end 59.925458 -114.480086)
		(width 0.1651)
		(layer "In11.Cu")
		(net "P5E_PEX0_STN2_TX_DN<39>")
	)
	(segment
		(start 51.670204 -278.125936)
		(end 51.773836 -278.229568)
		(width 0.1143)
		(layer "In11.Cu")
		(net "P5E_PEX0_STN2_TX_DN<39>")
	)
	(segment
		(start 86.882478 -63.834518)
		(end 64.630808 -92.81541)
		(width 0.1651)
		(layer "In11.Cu")
		(net "P5E_PEX0_STN2_TX_DN<39>")
	)
	(segment
		(start 59.065922 -121.457974)
		(end 51.715924 -262.799068)
		(width 0.1651)
		(layer "In11.Cu")
		(net "P5E_PEX0_STN2_TX_DN<39>")
	)
	(segment
		(start 88.276938 -58.541412)
		(end 88.276938 -60.165234)
		(width 0.1651)
		(layer "In11.Cu")
		(net "P5E_PEX0_STN2_TX_DN<39>")
	)
	(segment
		(start 74.81189 -33.948116)
		(end 75.371198 -34.181034)
		(width 0.1651)
		(layer "In11.Cu")
		(net "P5E_PEX0_STN2_TX_DN<39>")
	)
	(segment
		(start 51.773836 -278.229568)
		(end 51.935634 -278.229568)
		(width 0.1143)
		(layer "In11.Cu")
		(net "P5E_PEX0_STN2_TX_DN<39>")
	)
	(segment
		(start 87.282274 -49.033938)
		(end 88.276938 -58.541412)
		(width 0.1651)
		(layer "In11.Cu")
		(net "P5E_PEX0_STN2_TX_DN<39>")
	)
	(segment
		(start 51.715924 -271.427448)
		(end 51.670204 -271.473168)
		(width 0.1143)
		(layer "In11.Cu")
		(net "P5E_PEX0_STN2_TX_DN<39>")
	)
	(segment
		(start 80.695038 -41.84396)
		(end 87.282274 -49.033938)
		(width 0.1651)
		(layer "In11.Cu")
		(net "P5E_PEX0_STN2_TX_DN<39>")
	)
	(segment
		(start 74.238104 -33.948116)
		(end 74.81189 -33.948116)
		(width 0.1651)
		(layer "In11.Cu")
		(net "P5E_PEX0_STN2_TX_DN<39>")
	)
	(segment
		(start 52.049934 -278.115268)
		(end 52.049934 -277.849838)
		(width 0.1143)
		(layer "In11.Cu")
		(net "P5E_PEX0_STN2_TX_DN<39>")
	)
	(segment
		(start 73.947274 -33.657286)
		(end 74.238104 -33.948116)
		(width 0.1651)
		(layer "In11.Cu")
		(net "P5E_PEX0_STN2_TX_DN<39>")
	)
	(segment
		(start 51.935634 -278.229568)
		(end 52.049934 -278.115268)
		(width 0.1143)
		(layer "In11.Cu")
		(net "P5E_PEX0_STN2_TX_DN<39>")
	)
	(segment
		(start 88.276938 -60.165234)
		(end 87.776304 -62.053724)
		(width 0.1651)
		(layer "In11.Cu")
		(net "P5E_PEX0_STN2_TX_DN<39>")
	)
	(segment
		(start 59.925458 -114.480086)
		(end 59.178698 -120.544336)
		(width 0.1651)
		(layer "In11.Cu")
		(net "P5E_PEX0_STN2_TX_DN<39>")
	)
	(segment
		(start 77.026008 -35.848798)
		(end 80.695038 -41.84396)
		(width 0.1651)
		(layer "In11.Cu")
		(net "P5E_PEX0_STN2_TX_DN<39>")
	)
	(segment
		(start 59.17819 -120.544336)
		(end 59.065922 -121.457974)
		(width 0.1651)
		(layer "In11.Cu")
		(net "P5E_PEX0_STN2_TX_DN<39>")
	)
	(segment
		(start 75.371198 -34.181034)
		(end 77.026008 -35.848798)
		(width 0.1651)
		(layer "In11.Cu")
		(net "P5E_PEX0_STN2_TX_DN<39>")
	)
	(segment
		(start 51.715924 -262.799068)
		(end 51.715924 -271.399)
		(width 0.1651)
		(layer "In11.Cu")
		(net "P5E_PEX0_STN2_TX_DN<39>")
	)
	(segment
		(start 59.178698 -120.544336)
		(end 59.17819 -120.544336)
		(width 0.1651)
		(layer "In11.Cu")
		(net "P5E_PEX0_STN2_TX_DN<39>")
	)
	(segment
		(start 64.630808 -92.81541)
		(end 61.34608 -107.220512)
		(width 0.1651)
		(layer "In11.Cu")
		(net "P5E_PEX0_STN2_TX_DN<39>")
	)
	(segment
		(start 51.670204 -271.473168)
		(end 51.670204 -278.125936)
		(width 0.1143)
		(layer "In11.Cu")
		(net "P5E_PEX0_STN2_TX_DN<39>")
	)
	(segment
		(start 135.405368 -31.850584)
		(end 135.119872 -32.13608)
		(width 0.13462)
		(layer "F.Cu")
		(net "P5E_PEX1_STN2_TX_DN<46>")
	)
	(segment
		(start 135.119872 -32.13608)
		(end 134.47014 -32.13608)
		(width 0.13462)
		(layer "F.Cu")
		(net "P5E_PEX1_STN2_TX_DN<46>")
	)
	(segment
		(start 134.47014 -32.13608)
		(end 134.159244 -31.825184)
		(width 0.13462)
		(layer "F.Cu")
		(net "P5E_PEX1_STN2_TX_DN<46>")
	)
	(segment
		(start 161.166048 -271.399)
		(end 161.166048 -271.427448)
		(width 0.1143)
		(layer "In11.Cu")
		(net "P5E_PEX1_STN2_TX_DN<46>")
	)
	(segment
		(start 152.658064 -78.771496)
		(end 149.079966 -104.96423)
		(width 0.1651)
		(layer "In11.Cu")
		(net "P5E_PEX1_STN2_TX_DN<46>")
	)
	(segment
		(start 161.166048 -270.196056)
		(end 161.166048 -271.399)
		(width 0.1651)
		(layer "In11.Cu")
		(net "P5E_PEX1_STN2_TX_DN<46>")
	)
	(segment
		(start 135.405368 -31.850584)
		(end 135.696198 -32.141414)
		(width 0.1651)
		(layer "In11.Cu")
		(net "P5E_PEX1_STN2_TX_DN<46>")
	)
	(segment
		(start 161.120328 -271.473168)
		(end 161.120328 -280.025856)
		(width 0.1143)
		(layer "In11.Cu")
		(net "P5E_PEX1_STN2_TX_DN<46>")
	)
	(segment
		(start 161.166048 -271.427448)
		(end 161.120328 -271.473168)
		(width 0.1143)
		(layer "In11.Cu")
		(net "P5E_PEX1_STN2_TX_DN<46>")
	)
	(segment
		(start 160.15843 -264.52195)
		(end 161.166048 -270.196056)
		(width 0.1651)
		(layer "In11.Cu")
		(net "P5E_PEX1_STN2_TX_DN<46>")
	)
	(segment
		(start 161.385758 -280.129488)
		(end 161.500058 -280.015188)
		(width 0.1143)
		(layer "In11.Cu")
		(net "P5E_PEX1_STN2_TX_DN<46>")
	)
	(segment
		(start 161.120328 -280.025856)
		(end 161.22396 -280.129488)
		(width 0.1143)
		(layer "In11.Cu")
		(net "P5E_PEX1_STN2_TX_DN<46>")
	)
	(segment
		(start 161.22396 -280.129488)
		(end 161.385758 -280.129488)
		(width 0.1143)
		(layer "In11.Cu")
		(net "P5E_PEX1_STN2_TX_DN<46>")
	)
	(segment
		(start 153.54427 -62.96533)
		(end 152.658064 -78.771496)
		(width 0.1651)
		(layer "In11.Cu")
		(net "P5E_PEX1_STN2_TX_DN<46>")
	)
	(segment
		(start 148.94052 -138.163046)
		(end 160.15843 -264.52195)
		(width 0.1651)
		(layer "In11.Cu")
		(net "P5E_PEX1_STN2_TX_DN<46>")
	)
	(segment
		(start 152.225502 -48.810164)
		(end 152.799034 -50.44821)
		(width 0.1651)
		(layer "In11.Cu")
		(net "P5E_PEX1_STN2_TX_DN<46>")
	)
	(segment
		(start 140.497052 -33.387538)
		(end 150.893272 -46.401736)
		(width 0.1651)
		(layer "In11.Cu")
		(net "P5E_PEX1_STN2_TX_DN<46>")
	)
	(segment
		(start 152.799034 -50.44821)
		(end 153.54427 -62.96533)
		(width 0.1651)
		(layer "In11.Cu")
		(net "P5E_PEX1_STN2_TX_DN<46>")
	)
	(segment
		(start 150.893272 -46.401736)
		(end 152.225502 -48.810164)
		(width 0.1651)
		(layer "In11.Cu")
		(net "P5E_PEX1_STN2_TX_DN<46>")
	)
	(segment
		(start 161.500058 -280.015188)
		(end 161.500058 -279.749504)
		(width 0.1143)
		(layer "In11.Cu")
		(net "P5E_PEX1_STN2_TX_DN<46>")
	)
	(segment
		(start 137.485374 -32.141414)
		(end 140.497052 -33.387538)
		(width 0.1651)
		(layer "In11.Cu")
		(net "P5E_PEX1_STN2_TX_DN<46>")
	)
	(segment
		(start 148.477986 -116.822728)
		(end 148.94052 -138.163046)
		(width 0.1651)
		(layer "In11.Cu")
		(net "P5E_PEX1_STN2_TX_DN<46>")
	)
	(segment
		(start 149.079966 -104.96423)
		(end 148.477986 -116.822728)
		(width 0.1651)
		(layer "In11.Cu")
		(net "P5E_PEX1_STN2_TX_DN<46>")
	)
	(segment
		(start 135.696198 -32.141414)
		(end 137.485374 -32.141414)
		(width 0.1651)
		(layer "In11.Cu")
		(net "P5E_PEX1_STN2_TX_DN<46>")
	)
	(segment
		(start 343.887044 -349.511874)
		(end 343.887044 -348.88043)
		(width 0.13462)
		(layer "F.Cu")
		(net "P5E_PEX2_STN5_TX_DP<95>")
	)
	(segment
		(start 343.887044 -348.88043)
		(end 343.592404 -348.58579)
		(width 0.13462)
		(layer "F.Cu")
		(net "P5E_PEX2_STN5_TX_DP<95>")
	)
	(segment
		(start 343.567004 -349.831914)
		(end 343.887044 -349.511874)
		(width 0.13462)
		(layer "F.Cu")
		(net "P5E_PEX2_STN5_TX_DP<95>")
	)
	(segment
		(start 343.883234 -347.667834)
		(end 345.437714 -346.113354)
		(width 0.1651)
		(layer "In7.Cu")
		(net "P5E_PEX2_STN5_TX_DP<95>")
	)
	(segment
		(start 304.533808 -319.890648)
		(end 304.533808 -319.8622)
		(width 0.1143)
		(layer "In7.Cu")
		(net "P5E_PEX2_STN5_TX_DP<95>")
	)
	(segment
		(start 304.579528 -319.81648)
		(end 304.579528 -313.605418)
		(width 0.1143)
		(layer "In7.Cu")
		(net "P5E_PEX2_STN5_TX_DP<95>")
	)
	(segment
		(start 327.481184 -329.624182)
		(end 309.52059 -322.39458)
		(width 0.1651)
		(layer "In7.Cu")
		(net "P5E_PEX2_STN5_TX_DP<95>")
	)
	(segment
		(start 309.520336 -322.39458)
		(end 307.20792 -321.46367)
		(width 0.1651)
		(layer "In7.Cu")
		(net "P5E_PEX2_STN5_TX_DP<95>")
	)
	(segment
		(start 304.805334 -313.379612)
		(end 305.035458 -313.379612)
		(width 0.1143)
		(layer "In7.Cu")
		(net "P5E_PEX2_STN5_TX_DP<95>")
	)
	(segment
		(start 305.149758 -313.265312)
		(end 305.149758 -312.999882)
		(width 0.1143)
		(layer "In7.Cu")
		(net "P5E_PEX2_STN5_TX_DP<95>")
	)
	(segment
		(start 304.533808 -320.126868)
		(end 304.533808 -319.890648)
		(width 0.1651)
		(layer "In7.Cu")
		(net "P5E_PEX2_STN5_TX_DP<95>")
	)
	(segment
		(start 345.074748 -341.445596)
		(end 327.481184 -329.624182)
		(width 0.1651)
		(layer "In7.Cu")
		(net "P5E_PEX2_STN5_TX_DP<95>")
	)
	(segment
		(start 305.035458 -313.379612)
		(end 305.149758 -313.265312)
		(width 0.1143)
		(layer "In7.Cu")
		(net "P5E_PEX2_STN5_TX_DP<95>")
	)
	(segment
		(start 307.20792 -321.463416)
		(end 305.54041 -320.792348)
		(width 0.1651)
		(layer "In7.Cu")
		(net "P5E_PEX2_STN5_TX_DP<95>")
	)
	(segment
		(start 307.20792 -321.46367)
		(end 307.20792 -321.463416)
		(width 0.1651)
		(layer "In7.Cu")
		(net "P5E_PEX2_STN5_TX_DP<95>")
	)
	(segment
		(start 345.075002 -341.446104)
		(end 345.074748 -341.445596)
		(width 0.1651)
		(layer "In7.Cu")
		(net "P5E_PEX2_STN5_TX_DP<95>")
	)
	(segment
		(start 304.579528 -313.605418)
		(end 304.805334 -313.379612)
		(width 0.1143)
		(layer "In7.Cu")
		(net "P5E_PEX2_STN5_TX_DP<95>")
	)
	(segment
		(start 305.54041 -320.792348)
		(end 304.533808 -320.126868)
		(width 0.1651)
		(layer "In7.Cu")
		(net "P5E_PEX2_STN5_TX_DP<95>")
	)
	(segment
		(start 345.437714 -346.113354)
		(end 345.437714 -342.085422)
		(width 0.1651)
		(layer "In7.Cu")
		(net "P5E_PEX2_STN5_TX_DP<95>")
	)
	(segment
		(start 345.437714 -342.085422)
		(end 345.075002 -341.446104)
		(width 0.1651)
		(layer "In7.Cu")
		(net "P5E_PEX2_STN5_TX_DP<95>")
	)
	(segment
		(start 309.52059 -322.39458)
		(end 309.520336 -322.39458)
		(width 0.1651)
		(layer "In7.Cu")
		(net "P5E_PEX2_STN5_TX_DP<95>")
	)
	(segment
		(start 304.533808 -319.8622)
		(end 304.579528 -319.81648)
		(width 0.1143)
		(layer "In7.Cu")
		(net "P5E_PEX2_STN5_TX_DP<95>")
	)
	(segment
		(start 343.592404 -348.58579)
		(end 343.883234 -348.29496)
		(width 0.1651)
		(layer "In7.Cu")
		(net "P5E_PEX2_STN5_TX_DP<95>")
	)
	(segment
		(start 343.883234 -348.29496)
		(end 343.883234 -347.667834)
		(width 0.1651)
		(layer "In7.Cu")
		(net "P5E_PEX2_STN5_TX_DP<95>")
	)
	(segment
		(start 284.010862 -342.734138)
		(end 284.305502 -342.439498)
		(width 0.13462)
		(layer "F.Cu")
		(net "P5E_PEX2_STN7_TX_DN<119>")
	)
	(segment
		(start 284.330902 -343.685622)
		(end 284.010862 -343.365582)
		(width 0.13462)
		(layer "F.Cu")
		(net "P5E_PEX2_STN7_TX_DN<119>")
	)
	(segment
		(start 284.010862 -343.365582)
		(end 284.010862 -342.734138)
		(width 0.13462)
		(layer "F.Cu")
		(net "P5E_PEX2_STN7_TX_DN<119>")
	)
	(segment
		(start 260.21157 -313.690762)
		(end 260.601968 -313.343798)
		(width 0.1651)
		(layer "In7.Cu")
		(net "P5E_PEX2_STN7_TX_DN<119>")
	)
	(segment
		(start 283.799026 -341.206328)
		(end 283.798772 -341.206328)
		(width 0.1651)
		(layer "In7.Cu")
		(net "P5E_PEX2_STN7_TX_DN<119>")
	)
	(segment
		(start 276.283674 -335.665064)
		(end 262.004556 -328.068178)
		(width 0.1651)
		(layer "In7.Cu")
		(net "P5E_PEX2_STN7_TX_DN<119>")
	)
	(segment
		(start 259.819902 -326.818498)
		(end 259.31622 -326.550528)
		(width 0.1651)
		(layer "In7.Cu")
		(net "P5E_PEX2_STN7_TX_DN<119>")
	)
	(segment
		(start 259.221986 -314.744608)
		(end 259.209286 -314.583572)
		(width 0.1651)
		(layer "In7.Cu")
		(net "P5E_PEX2_STN7_TX_DN<119>")
	)
	(segment
		(start 264.563352 -309.690008)
		(end 266.503912 -308.39283)
		(width 0.1651)
		(layer "In7.Cu")
		(net "P5E_PEX2_STN7_TX_DN<119>")
	)
	(segment
		(start 275.965158 -308.249828)
		(end 275.699728 -308.249828)
		(width 0.1143)
		(layer "In7.Cu")
		(net "P5E_PEX2_STN7_TX_DN<119>")
	)
	(segment
		(start 259.698744 -314.011056)
		(end 260.068822 -313.68238)
		(width 0.1651)
		(layer "In7.Cu")
		(net "P5E_PEX2_STN7_TX_DN<119>")
	)
	(segment
		(start 261.474712 -327.69429)
		(end 261.365238 -327.727818)
		(width 0.1651)
		(layer "In7.Cu")
		(net "P5E_PEX2_STN7_TX_DN<119>")
	)
	(segment
		(start 260.288786 -327.155048)
		(end 259.851652 -326.922638)
		(width 0.1651)
		(layer "In7.Cu")
		(net "P5E_PEX2_STN7_TX_DN<119>")
	)
	(segment
		(start 257.624834 -316.437264)
		(end 257.946652 -316.060836)
		(width 0.1651)
		(layer "In7.Cu")
		(net "P5E_PEX2_STN7_TX_DN<119>")
	)
	(segment
		(start 267.748766 -307.915818)
		(end 267.794486 -307.870098)
		(width 0.1143)
		(layer "In7.Cu")
		(net "P5E_PEX2_STN7_TX_DN<119>")
	)
	(segment
		(start 257.946652 -316.060836)
		(end 258.107688 -316.04839)
		(width 0.1651)
		(layer "In7.Cu")
		(net "P5E_PEX2_STN7_TX_DN<119>")
	)
	(segment
		(start 276.079458 -308.135528)
		(end 275.965158 -308.249828)
		(width 0.1143)
		(layer "In7.Cu")
		(net "P5E_PEX2_STN7_TX_DN<119>")
	)
	(segment
		(start 260.928104 -327.495408)
		(end 260.896354 -327.391268)
		(width 0.1651)
		(layer "In7.Cu")
		(net "P5E_PEX2_STN7_TX_DN<119>")
	)
	(segment
		(start 258.899914 -315.121544)
		(end 259.221986 -314.744608)
		(width 0.1651)
		(layer "In7.Cu")
		(net "P5E_PEX2_STN7_TX_DN<119>")
	)
	(segment
		(start 260.896354 -327.391268)
		(end 260.392926 -327.123298)
		(width 0.1651)
		(layer "In7.Cu")
		(net "P5E_PEX2_STN7_TX_DN<119>")
	)
	(segment
		(start 260.068822 -313.68238)
		(end 260.21157 -313.690762)
		(width 0.1651)
		(layer "In7.Cu")
		(net "P5E_PEX2_STN7_TX_DN<119>")
	)
	(segment
		(start 276.079458 -307.984398)
		(end 276.079458 -308.135528)
		(width 0.1143)
		(layer "In7.Cu")
		(net "P5E_PEX2_STN7_TX_DN<119>")
	)
	(segment
		(start 283.798772 -341.206328)
		(end 276.283674 -335.665064)
		(width 0.1651)
		(layer "In7.Cu")
		(net "P5E_PEX2_STN7_TX_DN<119>")
	)
	(segment
		(start 257.154426 -316.987682)
		(end 257.315462 -316.975236)
		(width 0.1651)
		(layer "In7.Cu")
		(net "P5E_PEX2_STN7_TX_DN<119>")
	)
	(segment
		(start 258.42976 -315.671454)
		(end 258.41706 -315.510418)
		(width 0.1651)
		(layer "In7.Cu")
		(net "P5E_PEX2_STN7_TX_DN<119>")
	)
	(segment
		(start 259.31622 -326.550528)
		(end 259.212334 -326.582278)
		(width 0.1651)
		(layer "In7.Cu")
		(net "P5E_PEX2_STN7_TX_DN<119>")
	)
	(segment
		(start 260.61035 -313.201304)
		(end 264.563352 -309.690008)
		(width 0.1651)
		(layer "In7.Cu")
		(net "P5E_PEX2_STN7_TX_DN<119>")
	)
	(segment
		(start 267.512038 -307.915818)
		(end 267.720318 -307.915818)
		(width 0.1651)
		(layer "In7.Cu")
		(net "P5E_PEX2_STN7_TX_DN<119>")
	)
	(segment
		(start 258.107688 -316.04839)
		(end 258.42976 -315.671454)
		(width 0.1651)
		(layer "In7.Cu")
		(net "P5E_PEX2_STN7_TX_DN<119>")
	)
	(segment
		(start 275.965158 -307.870098)
		(end 276.079458 -307.984398)
		(width 0.1143)
		(layer "In7.Cu")
		(net "P5E_PEX2_STN7_TX_DN<119>")
	)
	(segment
		(start 258.738878 -315.13399)
		(end 258.899914 -315.121544)
		(width 0.1651)
		(layer "In7.Cu")
		(net "P5E_PEX2_STN7_TX_DN<119>")
	)
	(segment
		(start 284.014672 -341.6046)
		(end 283.799026 -341.206328)
		(width 0.1651)
		(layer "In7.Cu")
		(net "P5E_PEX2_STN7_TX_DN<119>")
	)
	(segment
		(start 258.584192 -326.248268)
		(end 256.546604 -324.004432)
		(width 0.1651)
		(layer "In7.Cu")
		(net "P5E_PEX2_STN7_TX_DN<119>")
	)
	(segment
		(start 261.971028 -327.958704)
		(end 261.474712 -327.69429)
		(width 0.1651)
		(layer "In7.Cu")
		(net "P5E_PEX2_STN7_TX_DN<119>")
	)
	(segment
		(start 256.546604 -324.004432)
		(end 255.7526 -322.087494)
		(width 0.1651)
		(layer "In7.Cu")
		(net "P5E_PEX2_STN7_TX_DN<119>")
	)
	(segment
		(start 262.004556 -328.068178)
		(end 261.971028 -327.958704)
		(width 0.1651)
		(layer "In7.Cu")
		(net "P5E_PEX2_STN7_TX_DN<119>")
	)
	(segment
		(start 267.794486 -307.870098)
		(end 275.965158 -307.870098)
		(width 0.1143)
		(layer "In7.Cu")
		(net "P5E_PEX2_STN7_TX_DN<119>")
	)
	(segment
		(start 266.503912 -308.39283)
		(end 267.512038 -307.915818)
		(width 0.1651)
		(layer "In7.Cu")
		(net "P5E_PEX2_STN7_TX_DN<119>")
	)
	(segment
		(start 284.305502 -342.439498)
		(end 284.014672 -342.148668)
		(width 0.1651)
		(layer "In7.Cu")
		(net "P5E_PEX2_STN7_TX_DN<119>")
	)
	(segment
		(start 257.637534 -316.5983)
		(end 257.624834 -316.437264)
		(width 0.1651)
		(layer "In7.Cu")
		(net "P5E_PEX2_STN7_TX_DN<119>")
	)
	(segment
		(start 261.365238 -327.727818)
		(end 260.928104 -327.495408)
		(width 0.1651)
		(layer "In7.Cu")
		(net "P5E_PEX2_STN7_TX_DN<119>")
	)
	(segment
		(start 259.209286 -314.583572)
		(end 259.698744 -314.011056)
		(width 0.1651)
		(layer "In7.Cu")
		(net "P5E_PEX2_STN7_TX_DN<119>")
	)
	(segment
		(start 255.7526 -319.975992)
		(end 256.832608 -317.36411)
		(width 0.1651)
		(layer "In7.Cu")
		(net "P5E_PEX2_STN7_TX_DN<119>")
	)
	(segment
		(start 258.41706 -315.510418)
		(end 258.738878 -315.13399)
		(width 0.1651)
		(layer "In7.Cu")
		(net "P5E_PEX2_STN7_TX_DN<119>")
	)
	(segment
		(start 260.601968 -313.343798)
		(end 260.61035 -313.201304)
		(width 0.1651)
		(layer "In7.Cu")
		(net "P5E_PEX2_STN7_TX_DN<119>")
	)
	(segment
		(start 259.851652 -326.922638)
		(end 259.819902 -326.818498)
		(width 0.1651)
		(layer "In7.Cu")
		(net "P5E_PEX2_STN7_TX_DN<119>")
	)
	(segment
		(start 284.014672 -342.148668)
		(end 284.014672 -341.6046)
		(width 0.1651)
		(layer "In7.Cu")
		(net "P5E_PEX2_STN7_TX_DN<119>")
	)
	(segment
		(start 259.212334 -326.582278)
		(end 258.584192 -326.248268)
		(width 0.1651)
		(layer "In7.Cu")
		(net "P5E_PEX2_STN7_TX_DN<119>")
	)
	(segment
		(start 255.7526 -322.087494)
		(end 255.7526 -319.975992)
		(width 0.1651)
		(layer "In7.Cu")
		(net "P5E_PEX2_STN7_TX_DN<119>")
	)
	(segment
		(start 256.832608 -317.36411)
		(end 257.154426 -316.987682)
		(width 0.1651)
		(layer "In7.Cu")
		(net "P5E_PEX2_STN7_TX_DN<119>")
	)
	(segment
		(start 260.392926 -327.123298)
		(end 260.288786 -327.155048)
		(width 0.1651)
		(layer "In7.Cu")
		(net "P5E_PEX2_STN7_TX_DN<119>")
	)
	(segment
		(start 257.315462 -316.975236)
		(end 257.637534 -316.5983)
		(width 0.1651)
		(layer "In7.Cu")
		(net "P5E_PEX2_STN7_TX_DN<119>")
	)
	(segment
		(start 267.720318 -307.915818)
		(end 267.748766 -307.915818)
		(width 0.1143)
		(layer "In7.Cu")
		(net "P5E_PEX2_STN7_TX_DN<119>")
	)
	(segment
		(start 387.004306 -99.59848)
		(end 387.313932 -99.288854)
		(width 0.13462)
		(layer "F.Cu")
		(net "P5E_PEX3_STN1_TX_DP<16>")
	)
	(segment
		(start 386.067808 -99.314254)
		(end 386.352034 -99.59848)
		(width 0.13462)
		(layer "F.Cu")
		(net "P5E_PEX3_STN1_TX_DP<16>")
	)
	(segment
		(start 386.352034 -99.59848)
		(end 387.004306 -99.59848)
		(width 0.13462)
		(layer "F.Cu")
		(net "P5E_PEX3_STN1_TX_DP<16>")
	)
	(segment
		(start 376.467624 -106.241596)
		(end 376.467624 -106.272076)
		(width 0.1651)
		(layer "In9.Cu")
		(net "P5E_PEX3_STN1_TX_DP<16>")
	)
	(segment
		(start 376.467624 -106.272076)
		(end 374.422416 -111.209582)
		(width 0.1651)
		(layer "In9.Cu")
		(net "P5E_PEX3_STN1_TX_DP<16>")
	)
	(segment
		(start 384.556762 -99.605084)
		(end 382.076706 -100.632514)
		(width 0.1651)
		(layer "In9.Cu")
		(net "P5E_PEX3_STN1_TX_DP<16>")
	)
	(segment
		(start 407.949654 -278.534368)
		(end 407.949654 -278.799798)
		(width 0.1143)
		(layer "In9.Cu")
		(net "P5E_PEX3_STN1_TX_DP<16>")
	)
	(segment
		(start 371.10543 -145.421858)
		(end 371.815106 -159.875728)
		(width 0.1651)
		(layer "In9.Cu")
		(net "P5E_PEX3_STN1_TX_DP<16>")
	)
	(segment
		(start 407.379678 -278.205184)
		(end 407.594562 -278.420068)
		(width 0.1143)
		(layer "In9.Cu")
		(net "P5E_PEX3_STN1_TX_DP<16>")
	)
	(segment
		(start 407.333958 -271.471898)
		(end 407.333958 -271.500346)
		(width 0.1143)
		(layer "In9.Cu")
		(net "P5E_PEX3_STN1_TX_DP<16>")
	)
	(segment
		(start 385.776978 -99.605084)
		(end 384.556762 -99.605084)
		(width 0.1651)
		(layer "In9.Cu")
		(net "P5E_PEX3_STN1_TX_DP<16>")
	)
	(segment
		(start 407.379678 -271.546066)
		(end 407.379678 -278.205184)
		(width 0.1143)
		(layer "In9.Cu")
		(net "P5E_PEX3_STN1_TX_DP<16>")
	)
	(segment
		(start 368.505232 -130.71475)
		(end 368.505232 -139.143994)
		(width 0.1651)
		(layer "In9.Cu")
		(net "P5E_PEX3_STN1_TX_DP<16>")
	)
	(segment
		(start 374.422416 -111.209582)
		(end 368.505232 -130.71475)
		(width 0.1651)
		(layer "In9.Cu")
		(net "P5E_PEX3_STN1_TX_DP<16>")
	)
	(segment
		(start 386.067808 -99.314254)
		(end 385.776978 -99.605084)
		(width 0.1651)
		(layer "In9.Cu")
		(net "P5E_PEX3_STN1_TX_DP<16>")
	)
	(segment
		(start 407.594562 -278.420068)
		(end 407.835354 -278.420068)
		(width 0.1143)
		(layer "In9.Cu")
		(net "P5E_PEX3_STN1_TX_DP<16>")
	)
	(segment
		(start 407.333958 -265.983974)
		(end 407.333958 -271.471898)
		(width 0.1651)
		(layer "In9.Cu")
		(net "P5E_PEX3_STN1_TX_DP<16>")
	)
	(segment
		(start 372.379748 -162.714432)
		(end 407.333958 -265.983974)
		(width 0.1651)
		(layer "In9.Cu")
		(net "P5E_PEX3_STN1_TX_DP<16>")
	)
	(segment
		(start 407.333958 -271.500346)
		(end 407.379678 -271.546066)
		(width 0.1143)
		(layer "In9.Cu")
		(net "P5E_PEX3_STN1_TX_DP<16>")
	)
	(segment
		(start 407.835354 -278.420068)
		(end 407.949654 -278.534368)
		(width 0.1143)
		(layer "In9.Cu")
		(net "P5E_PEX3_STN1_TX_DP<16>")
	)
	(segment
		(start 382.076706 -100.632514)
		(end 376.467624 -106.241596)
		(width 0.1651)
		(layer "In9.Cu")
		(net "P5E_PEX3_STN1_TX_DP<16>")
	)
	(segment
		(start 368.505232 -139.143994)
		(end 371.10543 -145.421858)
		(width 0.1651)
		(layer "In9.Cu")
		(net "P5E_PEX3_STN1_TX_DP<16>")
	)
	(segment
		(start 371.815106 -159.875728)
		(end 372.379748 -162.714432)
		(width 0.1651)
		(layer "In9.Cu")
		(net "P5E_PEX3_STN1_TX_DP<16>")
	)
	(segment
		(start 440.359292 -355.978206)
		(end 440.678824 -355.658674)
		(width 0.13462)
		(layer "F.Cu")
		(net "P5E_PEX3_STN7_TX_DP<127>")
	)
	(segment
		(start 440.678824 -355.026214)
		(end 440.384692 -354.732082)
		(width 0.13462)
		(layer "F.Cu")
		(net "P5E_PEX3_STN7_TX_DP<127>")
	)
	(segment
		(start 440.678824 -355.658674)
		(end 440.678824 -355.026214)
		(width 0.13462)
		(layer "F.Cu")
		(net "P5E_PEX3_STN7_TX_DP<127>")
	)
	(segment
		(start 390.233662 -319.865248)
		(end 390.233662 -319.8368)
		(width 0.1143)
		(layer "In11.Cu")
		(net "P5E_PEX3_STN7_TX_DP<127>")
	)
	(segment
		(start 441.0202 -339.6488)
		(end 441.019438 -339.648292)
		(width 0.1651)
		(layer "In11.Cu")
		(net "P5E_PEX3_STN7_TX_DP<127>")
	)
	(segment
		(start 440.675522 -353.814126)
		(end 442.230002 -352.259646)
		(width 0.1651)
		(layer "In11.Cu")
		(net "P5E_PEX3_STN7_TX_DP<127>")
	)
	(segment
		(start 390.233662 -320.214498)
		(end 390.233662 -319.865248)
		(width 0.1651)
		(layer "In11.Cu")
		(net "P5E_PEX3_STN7_TX_DP<127>")
	)
	(segment
		(start 390.494774 -313.379612)
		(end 390.735566 -313.379612)
		(width 0.1143)
		(layer "In11.Cu")
		(net "P5E_PEX3_STN7_TX_DP<127>")
	)
	(segment
		(start 427.736 -330.3524)
		(end 390.485884 -320.541904)
		(width 0.1651)
		(layer "In11.Cu")
		(net "P5E_PEX3_STN7_TX_DP<127>")
	)
	(segment
		(start 441.001404 -339.635592)
		(end 440.99988 -339.634576)
		(width 0.1651)
		(layer "In11.Cu")
		(net "P5E_PEX3_STN7_TX_DP<127>")
	)
	(segment
		(start 440.99988 -339.634576)
		(end 427.736 -330.3524)
		(width 0.1651)
		(layer "In11.Cu")
		(net "P5E_PEX3_STN7_TX_DP<127>")
	)
	(segment
		(start 440.384692 -354.732082)
		(end 440.675522 -354.441252)
		(width 0.1651)
		(layer "In11.Cu")
		(net "P5E_PEX3_STN7_TX_DP<127>")
	)
	(segment
		(start 442.230002 -341.376)
		(end 441.0202 -339.6488)
		(width 0.1651)
		(layer "In11.Cu")
		(net "P5E_PEX3_STN7_TX_DP<127>")
	)
	(segment
		(start 390.279382 -319.79108)
		(end 390.279382 -313.595004)
		(width 0.1143)
		(layer "In11.Cu")
		(net "P5E_PEX3_STN7_TX_DP<127>")
	)
	(segment
		(start 390.279382 -313.595004)
		(end 390.494774 -313.379612)
		(width 0.1143)
		(layer "In11.Cu")
		(net "P5E_PEX3_STN7_TX_DP<127>")
	)
	(segment
		(start 390.735566 -313.379612)
		(end 390.849866 -313.265312)
		(width 0.1143)
		(layer "In11.Cu")
		(net "P5E_PEX3_STN7_TX_DP<127>")
	)
	(segment
		(start 390.233662 -319.8368)
		(end 390.279382 -319.79108)
		(width 0.1143)
		(layer "In11.Cu")
		(net "P5E_PEX3_STN7_TX_DP<127>")
	)
	(segment
		(start 440.675522 -354.441252)
		(end 440.675522 -353.814126)
		(width 0.1651)
		(layer "In11.Cu")
		(net "P5E_PEX3_STN7_TX_DP<127>")
	)
	(segment
		(start 441.019438 -339.648292)
		(end 441.001404 -339.635592)
		(width 0.1651)
		(layer "In11.Cu")
		(net "P5E_PEX3_STN7_TX_DP<127>")
	)
	(segment
		(start 442.230002 -352.259646)
		(end 442.230002 -341.376)
		(width 0.1651)
		(layer "In11.Cu")
		(net "P5E_PEX3_STN7_TX_DP<127>")
	)
	(segment
		(start 390.849866 -313.265312)
		(end 390.849866 -312.999882)
		(width 0.1143)
		(layer "In11.Cu")
		(net "P5E_PEX3_STN7_TX_DP<127>")
	)
	(segment
		(start 390.485884 -320.541904)
		(end 390.233662 -320.214498)
		(width 0.1651)
		(layer "In11.Cu")
		(net "P5E_PEX3_STN7_TX_DP<127>")
	)
	(segment
		(start 44.388532 -28.55468)
		(end 44.059094 -28.225242)
		(width 0.13462)
		(layer "F.Cu")
		(net "P5E_PEX0_STN2_TX_DN<40>")
	)
	(segment
		(start 45.00118 -28.55468)
		(end 44.388532 -28.55468)
		(width 0.13462)
		(layer "F.Cu")
		(net "P5E_PEX0_STN2_TX_DN<40>")
	)
	(segment
		(start 45.305218 -28.250642)
		(end 45.00118 -28.55468)
		(width 0.13462)
		(layer "F.Cu")
		(net "P5E_PEX0_STN2_TX_DN<40>")
	)
	(segment
		(start 50.765964 -271.427448)
		(end 50.720244 -271.473168)
		(width 0.1143)
		(layer "In11.Cu")
		(net "P5E_PEX0_STN2_TX_DN<40>")
	)
	(segment
		(start 53.814218 -34.710116)
		(end 63.553848 -46.926246)
		(width 0.1651)
		(layer "In11.Cu")
		(net "P5E_PEX0_STN2_TX_DN<40>")
	)
	(segment
		(start 50.12817 -252.61824)
		(end 50.401474 -266.016486)
		(width 0.1651)
		(layer "In11.Cu")
		(net "P5E_PEX0_STN2_TX_DN<40>")
	)
	(segment
		(start 45.305218 -28.250642)
		(end 45.596048 -28.541472)
		(width 0.1651)
		(layer "In11.Cu")
		(net "P5E_PEX0_STN2_TX_DN<40>")
	)
	(segment
		(start 64.817498 -69.60997)
		(end 64.817244 -69.60997)
		(width 0.1651)
		(layer "In11.Cu")
		(net "P5E_PEX0_STN2_TX_DN<40>")
	)
	(segment
		(start 50.985674 -280.129488)
		(end 51.099974 -280.015188)
		(width 0.1143)
		(layer "In11.Cu")
		(net "P5E_PEX0_STN2_TX_DN<40>")
	)
	(segment
		(start 50.765964 -271.399)
		(end 50.765964 -271.427448)
		(width 0.1143)
		(layer "In11.Cu")
		(net "P5E_PEX0_STN2_TX_DN<40>")
	)
	(segment
		(start 49.304956 -29.110178)
		(end 52.070254 -31.857696)
		(width 0.1651)
		(layer "In11.Cu")
		(net "P5E_PEX0_STN2_TX_DN<40>")
	)
	(segment
		(start 47.939198 -28.541472)
		(end 49.304956 -29.110178)
		(width 0.1651)
		(layer "In11.Cu")
		(net "P5E_PEX0_STN2_TX_DN<40>")
	)
	(segment
		(start 56.430164 -135.263128)
		(end 50.12817 -252.61824)
		(width 0.1651)
		(layer "In11.Cu")
		(net "P5E_PEX0_STN2_TX_DN<40>")
	)
	(segment
		(start 50.765964 -271.230598)
		(end 50.765964 -271.399)
		(width 0.1651)
		(layer "In11.Cu")
		(net "P5E_PEX0_STN2_TX_DN<40>")
	)
	(segment
		(start 51.099974 -280.015188)
		(end 51.099974 -279.749504)
		(width 0.1143)
		(layer "In11.Cu")
		(net "P5E_PEX0_STN2_TX_DN<40>")
	)
	(segment
		(start 64.819276 -69.597016)
		(end 64.817498 -69.60997)
		(width 0.1651)
		(layer "In11.Cu")
		(net "P5E_PEX0_STN2_TX_DN<40>")
	)
	(segment
		(start 50.823876 -280.129488)
		(end 50.985674 -280.129488)
		(width 0.1143)
		(layer "In11.Cu")
		(net "P5E_PEX0_STN2_TX_DN<40>")
	)
	(segment
		(start 50.720244 -280.025856)
		(end 50.823876 -280.129488)
		(width 0.1143)
		(layer "In11.Cu")
		(net "P5E_PEX0_STN2_TX_DN<40>")
	)
	(segment
		(start 64.580516 -49.856136)
		(end 65.24625 -60.605162)
		(width 0.1651)
		(layer "In11.Cu")
		(net "P5E_PEX0_STN2_TX_DN<40>")
	)
	(segment
		(start 50.401474 -266.016486)
		(end 50.7746 -269.806928)
		(width 0.1651)
		(layer "In11.Cu")
		(net "P5E_PEX0_STN2_TX_DN<40>")
	)
	(segment
		(start 64.817244 -69.60997)
		(end 57.770776 -119.313452)
		(width 0.1651)
		(layer "In11.Cu")
		(net "P5E_PEX0_STN2_TX_DN<40>")
	)
	(segment
		(start 45.596048 -28.541472)
		(end 47.939198 -28.541472)
		(width 0.1651)
		(layer "In11.Cu")
		(net "P5E_PEX0_STN2_TX_DN<40>")
	)
	(segment
		(start 50.720244 -271.473168)
		(end 50.720244 -280.025856)
		(width 0.1143)
		(layer "In11.Cu")
		(net "P5E_PEX0_STN2_TX_DN<40>")
	)
	(segment
		(start 52.070254 -31.857696)
		(end 53.814218 -34.710116)
		(width 0.1651)
		(layer "In11.Cu")
		(net "P5E_PEX0_STN2_TX_DN<40>")
	)
	(segment
		(start 50.7746 -271.221962)
		(end 50.765964 -271.230598)
		(width 0.1651)
		(layer "In11.Cu")
		(net "P5E_PEX0_STN2_TX_DN<40>")
	)
	(segment
		(start 50.7746 -269.806928)
		(end 50.7746 -271.221962)
		(width 0.1651)
		(layer "In11.Cu")
		(net "P5E_PEX0_STN2_TX_DN<40>")
	)
	(segment
		(start 63.553848 -46.926246)
		(end 64.580516 -49.856136)
		(width 0.1651)
		(layer "In11.Cu")
		(net "P5E_PEX0_STN2_TX_DN<40>")
	)
	(segment
		(start 65.24625 -60.605162)
		(end 64.819276 -69.597016)
		(width 0.1651)
		(layer "In11.Cu")
		(net "P5E_PEX0_STN2_TX_DN<40>")
	)
	(segment
		(start 57.770776 -119.313452)
		(end 56.430164 -135.263128)
		(width 0.1651)
		(layer "In11.Cu")
		(net "P5E_PEX0_STN2_TX_DN<40>")
	)
	(segment
		(start 213.405212 -31.850584)
		(end 213.119716 -32.13608)
		(width 0.13462)
		(layer "F.Cu")
		(net "P5E_PEX1_STN2_TX_DN<34>")
	)
	(segment
		(start 213.119716 -32.13608)
		(end 212.469984 -32.13608)
		(width 0.13462)
		(layer "F.Cu")
		(net "P5E_PEX1_STN2_TX_DN<34>")
	)
	(segment
		(start 212.469984 -32.13608)
		(end 212.159088 -31.825184)
		(width 0.13462)
		(layer "F.Cu")
		(net "P5E_PEX1_STN2_TX_DN<34>")
	)
	(segment
		(start 172.565822 -265.666982)
		(end 172.565822 -271.399)
		(width 0.1651)
		(layer "In11.Cu")
		(net "P5E_PEX1_STN2_TX_DN<34>")
	)
	(segment
		(start 193.150998 -149.418294)
		(end 191.732408 -161.43859)
		(width 0.1651)
		(layer "In11.Cu")
		(net "P5E_PEX1_STN2_TX_DN<34>")
	)
	(segment
		(start 219.117672 -74.425556)
		(end 218.527122 -75.263756)
		(width 0.1651)
		(layer "In11.Cu")
		(net "P5E_PEX1_STN2_TX_DN<34>")
	)
	(segment
		(start 217.06332 -32.141414)
		(end 218.772232 -33.86836)
		(width 0.1651)
		(layer "In11.Cu")
		(net "P5E_PEX1_STN2_TX_DN<34>")
	)
	(segment
		(start 193.887852 -132.513578)
		(end 193.887852 -140.132816)
		(width 0.1651)
		(layer "In11.Cu")
		(net "P5E_PEX1_STN2_TX_DN<34>")
	)
	(segment
		(start 172.899832 -280.015188)
		(end 172.899832 -279.749504)
		(width 0.1143)
		(layer "In11.Cu")
		(net "P5E_PEX1_STN2_TX_DN<34>")
	)
	(segment
		(start 193.479674 -141.883892)
		(end 193.15176 -149.41169)
		(width 0.1651)
		(layer "In11.Cu")
		(net "P5E_PEX1_STN2_TX_DN<34>")
	)
	(segment
		(start 221.34322 -68.266056)
		(end 219.117672 -74.425556)
		(width 0.1651)
		(layer "In11.Cu")
		(net "P5E_PEX1_STN2_TX_DN<34>")
	)
	(segment
		(start 172.565822 -271.427448)
		(end 172.520102 -271.473168)
		(width 0.1143)
		(layer "In11.Cu")
		(net "P5E_PEX1_STN2_TX_DN<34>")
	)
	(segment
		(start 223.080834 -41.785794)
		(end 223.309434 -42.652188)
		(width 0.1651)
		(layer "In11.Cu")
		(net "P5E_PEX1_STN2_TX_DN<34>")
	)
	(segment
		(start 193.887852 -140.132816)
		(end 193.479674 -141.883892)
		(width 0.1651)
		(layer "In11.Cu")
		(net "P5E_PEX1_STN2_TX_DN<34>")
	)
	(segment
		(start 172.785532 -280.129488)
		(end 172.899832 -280.015188)
		(width 0.1143)
		(layer "In11.Cu")
		(net "P5E_PEX1_STN2_TX_DN<34>")
	)
	(segment
		(start 213.696042 -32.141414)
		(end 217.06332 -32.141414)
		(width 0.1651)
		(layer "In11.Cu")
		(net "P5E_PEX1_STN2_TX_DN<34>")
	)
	(segment
		(start 193.15176 -149.41169)
		(end 193.15176 -149.413722)
		(width 0.1651)
		(layer "In11.Cu")
		(net "P5E_PEX1_STN2_TX_DN<34>")
	)
	(segment
		(start 172.520102 -271.473168)
		(end 172.520102 -280.025856)
		(width 0.1143)
		(layer "In11.Cu")
		(net "P5E_PEX1_STN2_TX_DN<34>")
	)
	(segment
		(start 195.309998 -111.841534)
		(end 195.309744 -111.841534)
		(width 0.1651)
		(layer "In11.Cu")
		(net "P5E_PEX1_STN2_TX_DN<34>")
	)
	(segment
		(start 172.520102 -280.025856)
		(end 172.623734 -280.129488)
		(width 0.1143)
		(layer "In11.Cu")
		(net "P5E_PEX1_STN2_TX_DN<34>")
	)
	(segment
		(start 223.56064 -56.75376)
		(end 221.34322 -68.266056)
		(width 0.1651)
		(layer "In11.Cu")
		(net "P5E_PEX1_STN2_TX_DN<34>")
	)
	(segment
		(start 218.527122 -75.263756)
		(end 212.0138 -78.775052)
		(width 0.1651)
		(layer "In11.Cu")
		(net "P5E_PEX1_STN2_TX_DN<34>")
	)
	(segment
		(start 191.732408 -161.43859)
		(end 172.565822 -265.666982)
		(width 0.1651)
		(layer "In11.Cu")
		(net "P5E_PEX1_STN2_TX_DN<34>")
	)
	(segment
		(start 218.772232 -33.86836)
		(end 223.080834 -41.785794)
		(width 0.1651)
		(layer "In11.Cu")
		(net "P5E_PEX1_STN2_TX_DN<34>")
	)
	(segment
		(start 196.116956 -105.301288)
		(end 195.309998 -111.841534)
		(width 0.1651)
		(layer "In11.Cu")
		(net "P5E_PEX1_STN2_TX_DN<34>")
	)
	(segment
		(start 210.064096 -80.722724)
		(end 196.116956 -105.301288)
		(width 0.1651)
		(layer "In11.Cu")
		(net "P5E_PEX1_STN2_TX_DN<34>")
	)
	(segment
		(start 194.503294 -118.379748)
		(end 193.887852 -132.513578)
		(width 0.1651)
		(layer "In11.Cu")
		(net "P5E_PEX1_STN2_TX_DN<34>")
	)
	(segment
		(start 212.0138 -78.775052)
		(end 210.064096 -80.722724)
		(width 0.1651)
		(layer "In11.Cu")
		(net "P5E_PEX1_STN2_TX_DN<34>")
	)
	(segment
		(start 172.623734 -280.129488)
		(end 172.785532 -280.129488)
		(width 0.1143)
		(layer "In11.Cu")
		(net "P5E_PEX1_STN2_TX_DN<34>")
	)
	(segment
		(start 223.309434 -42.652188)
		(end 223.56064 -56.75376)
		(width 0.1651)
		(layer "In11.Cu")
		(net "P5E_PEX1_STN2_TX_DN<34>")
	)
	(segment
		(start 195.309744 -111.841534)
		(end 194.503294 -118.379748)
		(width 0.1651)
		(layer "In11.Cu")
		(net "P5E_PEX1_STN2_TX_DN<34>")
	)
	(segment
		(start 213.405212 -31.850584)
		(end 213.696042 -32.141414)
		(width 0.1651)
		(layer "In11.Cu")
		(net "P5E_PEX1_STN2_TX_DN<34>")
	)
	(segment
		(start 193.151506 -149.413976)
		(end 193.150998 -149.418294)
		(width 0.1651)
		(layer "In11.Cu")
		(net "P5E_PEX1_STN2_TX_DN<34>")
	)
	(segment
		(start 172.565822 -271.399)
		(end 172.565822 -271.427448)
		(width 0.1143)
		(layer "In11.Cu")
		(net "P5E_PEX1_STN2_TX_DN<34>")
	)
	(segment
		(start 193.15176 -149.413722)
		(end 193.151506 -149.413976)
		(width 0.1651)
		(layer "In11.Cu")
		(net "P5E_PEX1_STN2_TX_DN<34>")
	)
	(segment
		(start 303.505108 -31.850584)
		(end 303.219612 -32.13608)
		(width 0.13462)
		(layer "F.Cu")
		(net "P5E_PEX2_STN2_TX_DN<38>")
	)
	(segment
		(start 303.219612 -32.13608)
		(end 302.56988 -32.13608)
		(width 0.13462)
		(layer "F.Cu")
		(net "P5E_PEX2_STN2_TX_DN<38>")
	)
	(segment
		(start 302.56988 -32.13608)
		(end 302.258984 -31.825184)
		(width 0.13462)
		(layer "F.Cu")
		(net "P5E_PEX2_STN2_TX_DN<38>")
	)
	(segment
		(start 285.085536 -280.129488)
		(end 285.199836 -280.015188)
		(width 0.1143)
		(layer "In11.Cu")
		(net "P5E_PEX2_STN2_TX_DN<38>")
	)
	(segment
		(start 284.865826 -271.399)
		(end 284.865826 -271.427448)
		(width 0.1143)
		(layer "In11.Cu")
		(net "P5E_PEX2_STN2_TX_DN<38>")
	)
	(segment
		(start 309.561738 -34.539936)
		(end 313.711844 -41.298876)
		(width 0.1651)
		(layer "In11.Cu")
		(net "P5E_PEX2_STN2_TX_DN<38>")
	)
	(segment
		(start 297.848528 -93.193108)
		(end 294.501316 -107.679744)
		(width 0.1651)
		(layer "In11.Cu")
		(net "P5E_PEX2_STN2_TX_DN<38>")
	)
	(segment
		(start 292.291008 -121.058686)
		(end 284.865826 -263.18337)
		(width 0.1651)
		(layer "In11.Cu")
		(net "P5E_PEX2_STN2_TX_DN<38>")
	)
	(segment
		(start 319.99047 -64.219836)
		(end 297.848528 -93.193108)
		(width 0.1651)
		(layer "In11.Cu")
		(net "P5E_PEX2_STN2_TX_DN<38>")
	)
	(segment
		(start 284.865826 -271.427448)
		(end 284.820106 -271.473168)
		(width 0.1143)
		(layer "In11.Cu")
		(net "P5E_PEX2_STN2_TX_DN<38>")
	)
	(segment
		(start 321.443604 -58.49747)
		(end 321.443604 -60.348876)
		(width 0.1651)
		(layer "In11.Cu")
		(net "P5E_PEX2_STN2_TX_DN<38>")
	)
	(segment
		(start 284.923738 -280.129488)
		(end 285.085536 -280.129488)
		(width 0.1143)
		(layer "In11.Cu")
		(net "P5E_PEX2_STN2_TX_DN<38>")
	)
	(segment
		(start 284.820106 -280.025856)
		(end 284.923738 -280.129488)
		(width 0.1143)
		(layer "In11.Cu")
		(net "P5E_PEX2_STN2_TX_DN<38>")
	)
	(segment
		(start 284.820106 -271.473168)
		(end 284.820106 -280.025856)
		(width 0.1143)
		(layer "In11.Cu")
		(net "P5E_PEX2_STN2_TX_DN<38>")
	)
	(segment
		(start 303.795938 -32.141414)
		(end 305.96459 -32.141414)
		(width 0.1651)
		(layer "In11.Cu")
		(net "P5E_PEX2_STN2_TX_DN<38>")
	)
	(segment
		(start 313.711844 -41.298876)
		(end 320.41338 -48.575468)
		(width 0.1651)
		(layer "In11.Cu")
		(net "P5E_PEX2_STN2_TX_DN<38>")
	)
	(segment
		(start 307.750464 -32.78378)
		(end 309.561738 -34.539936)
		(width 0.1651)
		(layer "In11.Cu")
		(net "P5E_PEX2_STN2_TX_DN<38>")
	)
	(segment
		(start 285.199836 -280.015188)
		(end 285.199836 -279.749504)
		(width 0.1143)
		(layer "In11.Cu")
		(net "P5E_PEX2_STN2_TX_DN<38>")
	)
	(segment
		(start 294.501316 -107.679744)
		(end 292.98138 -115.457732)
		(width 0.1651)
		(layer "In11.Cu")
		(net "P5E_PEX2_STN2_TX_DN<38>")
	)
	(segment
		(start 284.865826 -263.18337)
		(end 284.865826 -271.399)
		(width 0.1651)
		(layer "In11.Cu")
		(net "P5E_PEX2_STN2_TX_DN<38>")
	)
	(segment
		(start 321.443604 -60.348876)
		(end 320.90614 -62.36716)
		(width 0.1651)
		(layer "In11.Cu")
		(net "P5E_PEX2_STN2_TX_DN<38>")
	)
	(segment
		(start 305.96459 -32.141414)
		(end 307.750464 -32.78378)
		(width 0.1651)
		(layer "In11.Cu")
		(net "P5E_PEX2_STN2_TX_DN<38>")
	)
	(segment
		(start 292.98138 -115.457732)
		(end 292.291008 -121.058686)
		(width 0.1651)
		(layer "In11.Cu")
		(net "P5E_PEX2_STN2_TX_DN<38>")
	)
	(segment
		(start 320.41338 -48.575468)
		(end 321.443604 -58.49747)
		(width 0.1651)
		(layer "In11.Cu")
		(net "P5E_PEX2_STN2_TX_DN<38>")
	)
	(segment
		(start 303.505108 -31.850584)
		(end 303.795938 -32.141414)
		(width 0.1651)
		(layer "In11.Cu")
		(net "P5E_PEX2_STN2_TX_DN<38>")
	)
	(segment
		(start 320.90614 -62.36716)
		(end 319.99047 -64.219836)
		(width 0.1651)
		(layer "In11.Cu")
		(net "P5E_PEX2_STN2_TX_DN<38>")
	)
	(segment
		(start 271.575022 -343.365582)
		(end 271.575022 -342.734138)
		(width 0.13462)
		(layer "F.Cu")
		(net "P5E_PEX2_STN7_TX_DN<113>")
	)
	(segment
		(start 271.575022 -342.734138)
		(end 271.869662 -342.439498)
		(width 0.13462)
		(layer "F.Cu")
		(net "P5E_PEX2_STN7_TX_DN<113>")
	)
	(segment
		(start 271.895062 -343.685622)
		(end 271.575022 -343.365582)
		(width 0.13462)
		(layer "F.Cu")
		(net "P5E_PEX2_STN7_TX_DN<113>")
	)
	(segment
		(start 251.805186 -313.44235)
		(end 251.804678 -313.441842)
		(width 0.1651)
		(layer "In7.Cu")
		(net "P5E_PEX2_STN7_TX_DN<113>")
	)
	(segment
		(start 254.181864 -308.159658)
		(end 254.379476 -307.705252)
		(width 0.1651)
		(layer "In7.Cu")
		(net "P5E_PEX2_STN7_TX_DN<113>")
	)
	(segment
		(start 252.2601 -312.39333)
		(end 252.36043 -312.353706)
		(width 0.1651)
		(layer "In7.Cu")
		(net "P5E_PEX2_STN7_TX_DN<113>")
	)
	(segment
		(start 252.260354 -312.393584)
		(end 252.2601 -312.39333)
		(width 0.1651)
		(layer "In7.Cu")
		(net "P5E_PEX2_STN7_TX_DN<113>")
	)
	(segment
		(start 252.715522 -311.344818)
		(end 252.815852 -311.305194)
		(width 0.1651)
		(layer "In7.Cu")
		(net "P5E_PEX2_STN7_TX_DN<113>")
	)
	(segment
		(start 253.626366 -309.247794)
		(end 253.726696 -309.20817)
		(width 0.1651)
		(layer "In7.Cu")
		(net "P5E_PEX2_STN7_TX_DN<113>")
	)
	(segment
		(start 275.965158 -302.549814)
		(end 275.699728 -302.549814)
		(width 0.1143)
		(layer "In7.Cu")
		(net "P5E_PEX2_STN7_TX_DN<113>")
	)
	(segment
		(start 251.607574 -313.895994)
		(end 251.607828 -313.896248)
		(width 0.1651)
		(layer "In7.Cu")
		(net "P5E_PEX2_STN7_TX_DN<113>")
	)
	(segment
		(start 254.564642 -307.087778)
		(end 256.740914 -304.715164)
		(width 0.1651)
		(layer "In7.Cu")
		(net "P5E_PEX2_STN7_TX_DN<113>")
	)
	(segment
		(start 252.974094 -310.750458)
		(end 253.171198 -310.296306)
		(width 0.1651)
		(layer "In7.Cu")
		(net "P5E_PEX2_STN7_TX_DN<113>")
	)
	(segment
		(start 250.894342 -315.539628)
		(end 250.893834 -315.538866)
		(width 0.1651)
		(layer "In7.Cu")
		(net "P5E_PEX2_STN7_TX_DN<113>")
	)
	(segment
		(start 271.578832 -341.503)
		(end 269.951708 -339.801708)
		(width 0.1651)
		(layer "In7.Cu")
		(net "P5E_PEX2_STN7_TX_DN<113>")
	)
	(segment
		(start 267.93952 -302.170084)
		(end 275.965158 -302.170084)
		(width 0.1143)
		(layer "In7.Cu")
		(net "P5E_PEX2_STN7_TX_DN<113>")
	)
	(segment
		(start 252.06325 -312.847482)
		(end 252.260354 -312.393584)
		(width 0.1651)
		(layer "In7.Cu")
		(net "P5E_PEX2_STN7_TX_DN<113>")
	)
	(segment
		(start 251.483368 -327.417176)
		(end 249.936 -323.681344)
		(width 0.1651)
		(layer "In7.Cu")
		(net "P5E_PEX2_STN7_TX_DN<113>")
	)
	(segment
		(start 271.578832 -342.148668)
		(end 271.578832 -341.503)
		(width 0.1651)
		(layer "In7.Cu")
		(net "P5E_PEX2_STN7_TX_DN<113>")
	)
	(segment
		(start 254.379476 -307.705252)
		(end 254.340106 -307.604922)
		(width 0.1651)
		(layer "In7.Cu")
		(net "P5E_PEX2_STN7_TX_DN<113>")
	)
	(segment
		(start 251.905008 -313.402218)
		(end 252.10262 -312.947812)
		(width 0.1651)
		(layer "In7.Cu")
		(net "P5E_PEX2_STN7_TX_DN<113>")
	)
	(segment
		(start 254.081788 -308.199282)
		(end 254.181864 -308.159658)
		(width 0.1651)
		(layer "In7.Cu")
		(net "P5E_PEX2_STN7_TX_DN<113>")
	)
	(segment
		(start 253.468632 -309.802276)
		(end 253.429262 -309.701946)
		(width 0.1651)
		(layer "In7.Cu")
		(net "P5E_PEX2_STN7_TX_DN<113>")
	)
	(segment
		(start 253.924054 -308.753764)
		(end 253.884684 -308.653434)
		(width 0.1651)
		(layer "In7.Cu")
		(net "P5E_PEX2_STN7_TX_DN<113>")
	)
	(segment
		(start 254.564642 -307.087524)
		(end 254.564642 -307.087778)
		(width 0.1651)
		(layer "In7.Cu")
		(net "P5E_PEX2_STN7_TX_DN<113>")
	)
	(segment
		(start 252.97384 -310.750458)
		(end 252.974094 -310.750458)
		(width 0.1651)
		(layer "In7.Cu")
		(net "P5E_PEX2_STN7_TX_DN<113>")
	)
	(segment
		(start 252.36043 -312.353706)
		(end 252.557788 -311.8993)
		(width 0.1651)
		(layer "In7.Cu")
		(net "P5E_PEX2_STN7_TX_DN<113>")
	)
	(segment
		(start 252.518672 -311.79897)
		(end 252.715776 -311.344818)
		(width 0.1651)
		(layer "In7.Cu")
		(net "P5E_PEX2_STN7_TX_DN<113>")
	)
	(segment
		(start 253.429262 -309.701946)
		(end 253.626366 -309.247794)
		(width 0.1651)
		(layer "In7.Cu")
		(net "P5E_PEX2_STN7_TX_DN<113>")
	)
	(segment
		(start 252.518418 -311.79897)
		(end 252.518672 -311.79897)
		(width 0.1651)
		(layer "In7.Cu")
		(net "P5E_PEX2_STN7_TX_DN<113>")
	)
	(segment
		(start 266.535154 -302.215804)
		(end 267.865352 -302.215804)
		(width 0.1651)
		(layer "In7.Cu")
		(net "P5E_PEX2_STN7_TX_DN<113>")
	)
	(segment
		(start 257.842512 -303.614074)
		(end 259.695696 -302.889666)
		(width 0.1651)
		(layer "In7.Cu")
		(net "P5E_PEX2_STN7_TX_DN<113>")
	)
	(segment
		(start 252.815852 -311.305194)
		(end 253.01321 -310.850788)
		(width 0.1651)
		(layer "In7.Cu")
		(net "P5E_PEX2_STN7_TX_DN<113>")
	)
	(segment
		(start 251.804678 -313.441842)
		(end 251.905008 -313.402218)
		(width 0.1651)
		(layer "In7.Cu")
		(net "P5E_PEX2_STN7_TX_DN<113>")
	)
	(segment
		(start 256.740914 -304.715164)
		(end 257.842512 -303.614074)
		(width 0.1651)
		(layer "In7.Cu")
		(net "P5E_PEX2_STN7_TX_DN<113>")
	)
	(segment
		(start 249.936 -317.745618)
		(end 250.894342 -315.539628)
		(width 0.1651)
		(layer "In7.Cu")
		(net "P5E_PEX2_STN7_TX_DN<113>")
	)
	(segment
		(start 250.994164 -315.499496)
		(end 251.191776 -315.044836)
		(width 0.1651)
		(layer "In7.Cu")
		(net "P5E_PEX2_STN7_TX_DN<113>")
	)
	(segment
		(start 251.152152 -314.944506)
		(end 251.349256 -314.490354)
		(width 0.1651)
		(layer "In7.Cu")
		(net "P5E_PEX2_STN7_TX_DN<113>")
	)
	(segment
		(start 251.647198 -313.996324)
		(end 251.607574 -313.895994)
		(width 0.1651)
		(layer "In7.Cu")
		(net "P5E_PEX2_STN7_TX_DN<113>")
	)
	(segment
		(start 254.340106 -307.604922)
		(end 254.564642 -307.087524)
		(width 0.1651)
		(layer "In7.Cu")
		(net "P5E_PEX2_STN7_TX_DN<113>")
	)
	(segment
		(start 253.726696 -309.20817)
		(end 253.924054 -308.753764)
		(width 0.1651)
		(layer "In7.Cu")
		(net "P5E_PEX2_STN7_TX_DN<113>")
	)
	(segment
		(start 251.191776 -315.044836)
		(end 251.152152 -314.944506)
		(width 0.1651)
		(layer "In7.Cu")
		(net "P5E_PEX2_STN7_TX_DN<113>")
	)
	(segment
		(start 252.557788 -311.8993)
		(end 252.518418 -311.79897)
		(width 0.1651)
		(layer "In7.Cu")
		(net "P5E_PEX2_STN7_TX_DN<113>")
	)
	(segment
		(start 254.73914 -331.112368)
		(end 251.483368 -327.417176)
		(width 0.1651)
		(layer "In7.Cu")
		(net "P5E_PEX2_STN7_TX_DN<113>")
	)
	(segment
		(start 252.062996 -312.847482)
		(end 252.06325 -312.847482)
		(width 0.1651)
		(layer "In7.Cu")
		(net "P5E_PEX2_STN7_TX_DN<113>")
	)
	(segment
		(start 253.271274 -310.256682)
		(end 253.468632 -309.802276)
		(width 0.1651)
		(layer "In7.Cu")
		(net "P5E_PEX2_STN7_TX_DN<113>")
	)
	(segment
		(start 252.715776 -311.344818)
		(end 252.715522 -311.344818)
		(width 0.1651)
		(layer "In7.Cu")
		(net "P5E_PEX2_STN7_TX_DN<113>")
	)
	(segment
		(start 253.884684 -308.653434)
		(end 254.081788 -308.199282)
		(width 0.1651)
		(layer "In7.Cu")
		(net "P5E_PEX2_STN7_TX_DN<113>")
	)
	(segment
		(start 251.449586 -314.450984)
		(end 251.647198 -313.996324)
		(width 0.1651)
		(layer "In7.Cu")
		(net "P5E_PEX2_STN7_TX_DN<113>")
	)
	(segment
		(start 249.936 -323.681344)
		(end 249.936 -317.745618)
		(width 0.1651)
		(layer "In7.Cu")
		(net "P5E_PEX2_STN7_TX_DN<113>")
	)
	(segment
		(start 275.965158 -302.170084)
		(end 276.079458 -302.284384)
		(width 0.1143)
		(layer "In7.Cu")
		(net "P5E_PEX2_STN7_TX_DN<113>")
	)
	(segment
		(start 253.171198 -310.296306)
		(end 253.170944 -310.296306)
		(width 0.1651)
		(layer "In7.Cu")
		(net "P5E_PEX2_STN7_TX_DN<113>")
	)
	(segment
		(start 252.10262 -312.947812)
		(end 252.062996 -312.847482)
		(width 0.1651)
		(layer "In7.Cu")
		(net "P5E_PEX2_STN7_TX_DN<113>")
	)
	(segment
		(start 267.8938 -302.215804)
		(end 267.93952 -302.170084)
		(width 0.1143)
		(layer "In7.Cu")
		(net "P5E_PEX2_STN7_TX_DN<113>")
	)
	(segment
		(start 276.079458 -302.435514)
		(end 275.965158 -302.549814)
		(width 0.1143)
		(layer "In7.Cu")
		(net "P5E_PEX2_STN7_TX_DN<113>")
	)
	(segment
		(start 267.865352 -302.215804)
		(end 267.8938 -302.215804)
		(width 0.1143)
		(layer "In7.Cu")
		(net "P5E_PEX2_STN7_TX_DN<113>")
	)
	(segment
		(start 251.607828 -313.896248)
		(end 251.805186 -313.44235)
		(width 0.1651)
		(layer "In7.Cu")
		(net "P5E_PEX2_STN7_TX_DN<113>")
	)
	(segment
		(start 276.079458 -302.284384)
		(end 276.079458 -302.435514)
		(width 0.1143)
		(layer "In7.Cu")
		(net "P5E_PEX2_STN7_TX_DN<113>")
	)
	(segment
		(start 271.869662 -342.439498)
		(end 271.578832 -342.148668)
		(width 0.1651)
		(layer "In7.Cu")
		(net "P5E_PEX2_STN7_TX_DN<113>")
	)
	(segment
		(start 251.349256 -314.490354)
		(end 251.449586 -314.450984)
		(width 0.1651)
		(layer "In7.Cu")
		(net "P5E_PEX2_STN7_TX_DN<113>")
	)
	(segment
		(start 269.951708 -339.801708)
		(end 254.73914 -331.112368)
		(width 0.1651)
		(layer "In7.Cu")
		(net "P5E_PEX2_STN7_TX_DN<113>")
	)
	(segment
		(start 253.01321 -310.850788)
		(end 252.97384 -310.750458)
		(width 0.1651)
		(layer "In7.Cu")
		(net "P5E_PEX2_STN7_TX_DN<113>")
	)
	(segment
		(start 259.695696 -302.889666)
		(end 266.535154 -302.215804)
		(width 0.1651)
		(layer "In7.Cu")
		(net "P5E_PEX2_STN7_TX_DN<113>")
	)
	(segment
		(start 253.170944 -310.296306)
		(end 253.271274 -310.256682)
		(width 0.1651)
		(layer "In7.Cu")
		(net "P5E_PEX2_STN7_TX_DN<113>")
	)
	(segment
		(start 250.893834 -315.538866)
		(end 250.994164 -315.499496)
		(width 0.1651)
		(layer "In7.Cu")
		(net "P5E_PEX2_STN7_TX_DN<113>")
	)
	(segment
		(start 386.067808 -110.114334)
		(end 386.372354 -110.41888)
		(width 0.13462)
		(layer "F.Cu")
		(net "P5E_PEX3_STN1_TX_DP<22>")
	)
	(segment
		(start 386.372354 -110.41888)
		(end 386.983986 -110.41888)
		(width 0.13462)
		(layer "F.Cu")
		(net "P5E_PEX3_STN1_TX_DP<22>")
	)
	(segment
		(start 386.983986 -110.41888)
		(end 387.313932 -110.088934)
		(width 0.13462)
		(layer "F.Cu")
		(net "P5E_PEX3_STN1_TX_DP<22>")
	)
	(segment
		(start 413.535368 -278.420068)
		(end 413.294576 -278.420068)
		(width 0.1143)
		(layer "In9.Cu")
		(net "P5E_PEX3_STN1_TX_DP<22>")
	)
	(segment
		(start 413.079692 -278.205184)
		(end 413.079692 -271.546066)
		(width 0.1143)
		(layer "In9.Cu")
		(net "P5E_PEX3_STN1_TX_DP<22>")
	)
	(segment
		(start 413.033972 -271.500346)
		(end 413.033972 -271.471898)
		(width 0.1143)
		(layer "In9.Cu")
		(net "P5E_PEX3_STN1_TX_DP<22>")
	)
	(segment
		(start 413.079692 -271.546066)
		(end 413.033972 -271.500346)
		(width 0.1143)
		(layer "In9.Cu")
		(net "P5E_PEX3_STN1_TX_DP<22>")
	)
	(segment
		(start 413.294576 -278.420068)
		(end 413.079692 -278.205184)
		(width 0.1143)
		(layer "In9.Cu")
		(net "P5E_PEX3_STN1_TX_DP<22>")
	)
	(segment
		(start 382.561338 -110.838742)
		(end 383.608072 -110.405164)
		(width 0.1651)
		(layer "In9.Cu")
		(net "P5E_PEX3_STN1_TX_DP<22>")
	)
	(segment
		(start 381.396748 -111.497872)
		(end 381.698246 -111.196374)
		(width 0.1651)
		(layer "In9.Cu")
		(net "P5E_PEX3_STN1_TX_DP<22>")
	)
	(segment
		(start 374.311672 -131.45135)
		(end 377.539758 -120.810782)
		(width 0.1651)
		(layer "In9.Cu")
		(net "P5E_PEX3_STN1_TX_DP<22>")
	)
	(segment
		(start 385.776978 -110.405164)
		(end 386.067808 -110.114334)
		(width 0.1651)
		(layer "In9.Cu")
		(net "P5E_PEX3_STN1_TX_DP<22>")
	)
	(segment
		(start 381.698246 -111.196374)
		(end 382.561084 -110.838742)
		(width 0.1651)
		(layer "In9.Cu")
		(net "P5E_PEX3_STN1_TX_DP<22>")
	)
	(segment
		(start 376.883676 -144.015714)
		(end 374.311672 -137.806684)
		(width 0.1651)
		(layer "In9.Cu")
		(net "P5E_PEX3_STN1_TX_DP<22>")
	)
	(segment
		(start 413.649668 -278.799798)
		(end 413.649668 -278.534368)
		(width 0.1143)
		(layer "In9.Cu")
		(net "P5E_PEX3_STN1_TX_DP<22>")
	)
	(segment
		(start 413.033972 -271.471898)
		(end 413.033972 -264.707116)
		(width 0.1651)
		(layer "In9.Cu")
		(net "P5E_PEX3_STN1_TX_DP<22>")
	)
	(segment
		(start 413.033972 -264.707116)
		(end 378.185934 -161.757614)
		(width 0.1651)
		(layer "In9.Cu")
		(net "P5E_PEX3_STN1_TX_DP<22>")
	)
	(segment
		(start 377.430284 -155.152598)
		(end 376.883676 -144.015714)
		(width 0.1651)
		(layer "In9.Cu")
		(net "P5E_PEX3_STN1_TX_DP<22>")
	)
	(segment
		(start 377.539758 -120.810782)
		(end 381.396748 -111.497872)
		(width 0.1651)
		(layer "In9.Cu")
		(net "P5E_PEX3_STN1_TX_DP<22>")
	)
	(segment
		(start 374.311672 -137.806684)
		(end 374.311672 -131.45135)
		(width 0.1651)
		(layer "In9.Cu")
		(net "P5E_PEX3_STN1_TX_DP<22>")
	)
	(segment
		(start 377.613418 -158.879032)
		(end 377.430284 -155.152598)
		(width 0.1651)
		(layer "In9.Cu")
		(net "P5E_PEX3_STN1_TX_DP<22>")
	)
	(segment
		(start 383.608072 -110.405164)
		(end 385.776978 -110.405164)
		(width 0.1651)
		(layer "In9.Cu")
		(net "P5E_PEX3_STN1_TX_DP<22>")
	)
	(segment
		(start 382.561084 -110.838742)
		(end 382.561338 -110.838742)
		(width 0.1651)
		(layer "In9.Cu")
		(net "P5E_PEX3_STN1_TX_DP<22>")
	)
	(segment
		(start 378.185934 -161.757614)
		(end 377.613418 -158.879032)
		(width 0.1651)
		(layer "In9.Cu")
		(net "P5E_PEX3_STN1_TX_DP<22>")
	)
	(segment
		(start 413.649668 -278.534368)
		(end 413.535368 -278.420068)
		(width 0.1143)
		(layer "In9.Cu")
		(net "P5E_PEX3_STN1_TX_DP<22>")
	)
	(segment
		(start 419.190424 -348.880938)
		(end 419.485572 -348.58579)
		(width 0.13462)
		(layer "F.Cu")
		(net "P5E_PEX3_STN7_TX_DN<116>")
	)
	(segment
		(start 419.510972 -349.831914)
		(end 419.190424 -349.511366)
		(width 0.13462)
		(layer "F.Cu")
		(net "P5E_PEX3_STN7_TX_DN<116>")
	)
	(segment
		(start 419.190424 -349.511366)
		(end 419.190424 -348.880938)
		(width 0.13462)
		(layer "F.Cu")
		(net "P5E_PEX3_STN7_TX_DN<116>")
	)
	(segment
		(start 373.876316 -310.94807)
		(end 374.017286 -310.92013)
		(width 0.1651)
		(layer "In11.Cu")
		(net "P5E_PEX3_STN7_TX_DN<116>")
	)
	(segment
		(start 373.213122 -311.940956)
		(end 373.212868 -311.940702)
		(width 0.1651)
		(layer "In11.Cu")
		(net "P5E_PEX3_STN7_TX_DN<116>")
	)
	(segment
		(start 377.488958 -306.652422)
		(end 377.83897 -306.30241)
		(width 0.1651)
		(layer "In11.Cu")
		(net "P5E_PEX3_STN7_TX_DN<116>")
	)
	(segment
		(start 378.618242 -305.979576)
		(end 378.751084 -306.034694)
		(width 0.1651)
		(layer "In11.Cu")
		(net "P5E_PEX3_STN7_TX_DN<116>")
	)
	(segment
		(start 374.68048 -309.927498)
		(end 374.95607 -309.515256)
		(width 0.1651)
		(layer "In11.Cu")
		(net "P5E_PEX3_STN7_TX_DN<116>")
	)
	(segment
		(start 376.644662 -307.496718)
		(end 376.994674 -307.146706)
		(width 0.1651)
		(layer "In11.Cu")
		(net "P5E_PEX3_STN7_TX_DN<116>")
	)
	(segment
		(start 377.488958 -306.796186)
		(end 377.488958 -306.652422)
		(width 0.1651)
		(layer "In11.Cu")
		(net "P5E_PEX3_STN7_TX_DN<116>")
	)
	(segment
		(start 383.995168 -305.019964)
		(end 390.17575 -305.019964)
		(width 0.1143)
		(layer "In11.Cu")
		(net "P5E_PEX3_STN7_TX_DN<116>")
	)
	(segment
		(start 420.022528 -340.800944)
		(end 417.24453 -338.7852)
		(width 0.1651)
		(layer "In11.Cu")
		(net "P5E_PEX3_STN7_TX_DN<116>")
	)
	(segment
		(start 374.927876 -309.374286)
		(end 375.25198 -308.8894)
		(width 0.1651)
		(layer "In11.Cu")
		(net "P5E_PEX3_STN7_TX_DN<116>")
	)
	(segment
		(start 390.279636 -305.285648)
		(end 390.165336 -305.399948)
		(width 0.1143)
		(layer "In11.Cu")
		(net "P5E_PEX3_STN7_TX_DN<116>")
	)
	(segment
		(start 390.165336 -305.399948)
		(end 389.899906 -305.399948)
		(width 0.1143)
		(layer "In11.Cu")
		(net "P5E_PEX3_STN7_TX_DN<116>")
	)
	(segment
		(start 368.6683 -322.160392)
		(end 368.6683 -319.210436)
		(width 0.1651)
		(layer "In11.Cu")
		(net "P5E_PEX3_STN7_TX_DN<116>")
	)
	(segment
		(start 380.311914 -305.387756)
		(end 380.367032 -305.255168)
		(width 0.1651)
		(layer "In11.Cu")
		(net "P5E_PEX3_STN7_TX_DN<116>")
	)
	(segment
		(start 373.353838 -311.912762)
		(end 373.629428 -311.500774)
		(width 0.1651)
		(layer "In11.Cu")
		(net "P5E_PEX3_STN7_TX_DN<116>")
	)
	(segment
		(start 378.751084 -306.034694)
		(end 379.208792 -305.844702)
		(width 0.1651)
		(layer "In11.Cu")
		(net "P5E_PEX3_STN7_TX_DN<116>")
	)
	(segment
		(start 373.601234 -311.360058)
		(end 373.87657 -310.94807)
		(width 0.1651)
		(layer "In11.Cu")
		(net "P5E_PEX3_STN7_TX_DN<116>")
	)
	(segment
		(start 375.25198 -308.8894)
		(end 376.150378 -307.991002)
		(width 0.1651)
		(layer "In11.Cu")
		(net "P5E_PEX3_STN7_TX_DN<116>")
	)
	(segment
		(start 369.178332 -317.979298)
		(end 373.213122 -311.940956)
		(width 0.1651)
		(layer "In11.Cu")
		(net "P5E_PEX3_STN7_TX_DN<116>")
	)
	(segment
		(start 419.194742 -348.29496)
		(end 419.194742 -347.784674)
		(width 0.1651)
		(layer "In11.Cu")
		(net "P5E_PEX3_STN7_TX_DN<116>")
	)
	(segment
		(start 374.95607 -309.515256)
		(end 374.927876 -309.374286)
		(width 0.1651)
		(layer "In11.Cu")
		(net "P5E_PEX3_STN7_TX_DN<116>")
	)
	(segment
		(start 379.721364 -305.52263)
		(end 379.854206 -305.577748)
		(width 0.1651)
		(layer "In11.Cu")
		(net "P5E_PEX3_STN7_TX_DN<116>")
	)
	(segment
		(start 379.26391 -305.712114)
		(end 379.721364 -305.52263)
		(width 0.1651)
		(layer "In11.Cu")
		(net "P5E_PEX3_STN7_TX_DN<116>")
	)
	(segment
		(start 372.171468 -327.762108)
		(end 370.152168 -325.742808)
		(width 0.1651)
		(layer "In11.Cu")
		(net "P5E_PEX3_STN7_TX_DN<116>")
	)
	(segment
		(start 383.921 -305.065684)
		(end 383.949448 -305.065684)
		(width 0.1143)
		(layer "In11.Cu")
		(net "P5E_PEX3_STN7_TX_DN<116>")
	)
	(segment
		(start 373.629428 -311.500774)
		(end 373.601234 -311.360058)
		(width 0.1651)
		(layer "In11.Cu")
		(net "P5E_PEX3_STN7_TX_DN<116>")
	)
	(segment
		(start 377.138438 -307.146706)
		(end 377.488958 -306.796186)
		(width 0.1651)
		(layer "In11.Cu")
		(net "P5E_PEX3_STN7_TX_DN<116>")
	)
	(segment
		(start 373.212868 -311.940702)
		(end 373.353838 -311.912762)
		(width 0.1651)
		(layer "In11.Cu")
		(net "P5E_PEX3_STN7_TX_DN<116>")
	)
	(segment
		(start 390.279636 -305.12385)
		(end 390.279636 -305.285648)
		(width 0.1143)
		(layer "In11.Cu")
		(net "P5E_PEX3_STN7_TX_DN<116>")
	)
	(segment
		(start 374.017286 -310.92013)
		(end 374.292622 -310.508142)
		(width 0.1651)
		(layer "In11.Cu")
		(net "P5E_PEX3_STN7_TX_DN<116>")
	)
	(segment
		(start 374.292622 -310.508142)
		(end 374.264682 -310.367172)
		(width 0.1651)
		(layer "In11.Cu")
		(net "P5E_PEX3_STN7_TX_DN<116>")
	)
	(segment
		(start 417.24453 -338.7852)
		(end 375.067068 -329.35418)
		(width 0.1651)
		(layer "In11.Cu")
		(net "P5E_PEX3_STN7_TX_DN<116>")
	)
	(segment
		(start 377.83897 -306.30241)
		(end 378.618242 -305.979576)
		(width 0.1651)
		(layer "In11.Cu")
		(net "P5E_PEX3_STN7_TX_DN<116>")
	)
	(segment
		(start 376.644662 -307.640482)
		(end 376.644662 -307.496718)
		(width 0.1651)
		(layer "In11.Cu")
		(net "P5E_PEX3_STN7_TX_DN<116>")
	)
	(segment
		(start 379.208792 -305.844702)
		(end 379.26391 -305.712114)
		(width 0.1651)
		(layer "In11.Cu")
		(net "P5E_PEX3_STN7_TX_DN<116>")
	)
	(segment
		(start 419.485572 -348.58579)
		(end 419.194742 -348.29496)
		(width 0.1651)
		(layer "In11.Cu")
		(net "P5E_PEX3_STN7_TX_DN<116>")
	)
	(segment
		(start 370.152168 -325.742808)
		(end 368.6683 -322.160392)
		(width 0.1651)
		(layer "In11.Cu")
		(net "P5E_PEX3_STN7_TX_DN<116>")
	)
	(segment
		(start 376.994674 -307.146706)
		(end 377.138438 -307.146706)
		(width 0.1651)
		(layer "In11.Cu")
		(net "P5E_PEX3_STN7_TX_DN<116>")
	)
	(segment
		(start 379.854206 -305.577748)
		(end 380.311914 -305.387756)
		(width 0.1651)
		(layer "In11.Cu")
		(net "P5E_PEX3_STN7_TX_DN<116>")
	)
	(segment
		(start 374.264682 -310.367172)
		(end 374.539764 -309.955438)
		(width 0.1651)
		(layer "In11.Cu")
		(net "P5E_PEX3_STN7_TX_DN<116>")
	)
	(segment
		(start 420.749222 -346.230194)
		(end 420.749222 -342.224868)
		(width 0.1651)
		(layer "In11.Cu")
		(net "P5E_PEX3_STN7_TX_DN<116>")
	)
	(segment
		(start 420.749222 -342.224868)
		(end 420.022528 -340.800944)
		(width 0.1651)
		(layer "In11.Cu")
		(net "P5E_PEX3_STN7_TX_DN<116>")
	)
	(segment
		(start 390.17575 -305.019964)
		(end 390.279636 -305.12385)
		(width 0.1143)
		(layer "In11.Cu")
		(net "P5E_PEX3_STN7_TX_DN<116>")
	)
	(segment
		(start 419.194742 -347.784674)
		(end 420.749222 -346.230194)
		(width 0.1651)
		(layer "In11.Cu")
		(net "P5E_PEX3_STN7_TX_DN<116>")
	)
	(segment
		(start 376.294142 -307.991002)
		(end 376.644662 -307.640482)
		(width 0.1651)
		(layer "In11.Cu")
		(net "P5E_PEX3_STN7_TX_DN<116>")
	)
	(segment
		(start 383.949448 -305.065684)
		(end 383.995168 -305.019964)
		(width 0.1143)
		(layer "In11.Cu")
		(net "P5E_PEX3_STN7_TX_DN<116>")
	)
	(segment
		(start 380.824486 -305.065684)
		(end 383.921 -305.065684)
		(width 0.1651)
		(layer "In11.Cu")
		(net "P5E_PEX3_STN7_TX_DN<116>")
	)
	(segment
		(start 373.87657 -310.94807)
		(end 373.876316 -310.94807)
		(width 0.1651)
		(layer "In11.Cu")
		(net "P5E_PEX3_STN7_TX_DN<116>")
	)
	(segment
		(start 376.150378 -307.991002)
		(end 376.294142 -307.991002)
		(width 0.1651)
		(layer "In11.Cu")
		(net "P5E_PEX3_STN7_TX_DN<116>")
	)
	(segment
		(start 380.367032 -305.255168)
		(end 380.824486 -305.065684)
		(width 0.1651)
		(layer "In11.Cu")
		(net "P5E_PEX3_STN7_TX_DN<116>")
	)
	(segment
		(start 375.067068 -329.35418)
		(end 372.171468 -327.762108)
		(width 0.1651)
		(layer "In11.Cu")
		(net "P5E_PEX3_STN7_TX_DN<116>")
	)
	(segment
		(start 374.539764 -309.955438)
		(end 374.68048 -309.927498)
		(width 0.1651)
		(layer "In11.Cu")
		(net "P5E_PEX3_STN7_TX_DN<116>")
	)
	(segment
		(start 368.6683 -319.210436)
		(end 369.178332 -317.979298)
		(width 0.1651)
		(layer "In11.Cu")
		(net "P5E_PEX3_STN7_TX_DN<116>")
	)
	(segment
		(start 19.001232 -28.55468)
		(end 18.388584 -28.55468)
		(width 0.13462)
		(layer "F.Cu")
		(net "P5E_PEX0_STN2_TX_DN<44>")
	)
	(segment
		(start 19.30527 -28.250642)
		(end 19.001232 -28.55468)
		(width 0.13462)
		(layer "F.Cu")
		(net "P5E_PEX0_STN2_TX_DN<44>")
	)
	(segment
		(start 18.388584 -28.55468)
		(end 18.059146 -28.225242)
		(width 0.13462)
		(layer "F.Cu")
		(net "P5E_PEX0_STN2_TX_DN<44>")
	)
	(segment
		(start 46.96587 -271.427448)
		(end 46.92015 -271.473168)
		(width 0.1143)
		(layer "In11.Cu")
		(net "P5E_PEX0_STN2_TX_DN<44>")
	)
	(segment
		(start 47.18558 -280.129488)
		(end 47.29988 -280.015188)
		(width 0.1143)
		(layer "In11.Cu")
		(net "P5E_PEX0_STN2_TX_DN<44>")
	)
	(segment
		(start 47.29988 -280.015188)
		(end 47.29988 -279.749504)
		(width 0.1143)
		(layer "In11.Cu")
		(net "P5E_PEX0_STN2_TX_DN<44>")
	)
	(segment
		(start 19.550634 -28.496006)
		(end 19.660616 -28.541472)
		(width 0.1651)
		(layer "In11.Cu")
		(net "P5E_PEX0_STN2_TX_DN<44>")
	)
	(segment
		(start 35.927792 -44.445428)
		(end 37.938456 -48.143668)
		(width 0.1651)
		(layer "In11.Cu")
		(net "P5E_PEX0_STN2_TX_DN<44>")
	)
	(segment
		(start 19.660616 -28.541472)
		(end 22.129242 -28.541472)
		(width 0.1651)
		(layer "In11.Cu")
		(net "P5E_PEX0_STN2_TX_DN<44>")
	)
	(segment
		(start 23.901654 -29.272484)
		(end 35.927792 -44.445428)
		(width 0.1651)
		(layer "In11.Cu")
		(net "P5E_PEX0_STN2_TX_DN<44>")
	)
	(segment
		(start 46.96587 -271.399)
		(end 46.96587 -271.427448)
		(width 0.1143)
		(layer "In11.Cu")
		(net "P5E_PEX0_STN2_TX_DN<44>")
	)
	(segment
		(start 47.023782 -280.129488)
		(end 47.18558 -280.129488)
		(width 0.1143)
		(layer "In11.Cu")
		(net "P5E_PEX0_STN2_TX_DN<44>")
	)
	(segment
		(start 46.075854 -264.583164)
		(end 46.96587 -270.72717)
		(width 0.1651)
		(layer "In11.Cu")
		(net "P5E_PEX0_STN2_TX_DN<44>")
	)
	(segment
		(start 38.686486 -50.356516)
		(end 39.38778 -62.131194)
		(width 0.1651)
		(layer "In11.Cu")
		(net "P5E_PEX0_STN2_TX_DN<44>")
	)
	(segment
		(start 38.817296 -145.385282)
		(end 46.075854 -264.583164)
		(width 0.1651)
		(layer "In11.Cu")
		(net "P5E_PEX0_STN2_TX_DN<44>")
	)
	(segment
		(start 37.938456 -48.143668)
		(end 38.686486 -50.356516)
		(width 0.1651)
		(layer "In11.Cu")
		(net "P5E_PEX0_STN2_TX_DN<44>")
	)
	(segment
		(start 39.38778 -62.131194)
		(end 39.745158 -135.970264)
		(width 0.1651)
		(layer "In11.Cu")
		(net "P5E_PEX0_STN2_TX_DN<44>")
	)
	(segment
		(start 39.745158 -135.970264)
		(end 38.817296 -145.385282)
		(width 0.1651)
		(layer "In11.Cu")
		(net "P5E_PEX0_STN2_TX_DN<44>")
	)
	(segment
		(start 22.129242 -28.541472)
		(end 23.901654 -29.272484)
		(width 0.1651)
		(layer "In11.Cu")
		(net "P5E_PEX0_STN2_TX_DN<44>")
	)
	(segment
		(start 46.92015 -271.473168)
		(end 46.92015 -280.025856)
		(width 0.1143)
		(layer "In11.Cu")
		(net "P5E_PEX0_STN2_TX_DN<44>")
	)
	(segment
		(start 19.30527 -28.250642)
		(end 19.550634 -28.496006)
		(width 0.1651)
		(layer "In11.Cu")
		(net "P5E_PEX0_STN2_TX_DN<44>")
	)
	(segment
		(start 46.96587 -270.72717)
		(end 46.96587 -271.399)
		(width 0.1651)
		(layer "In11.Cu")
		(net "P5E_PEX0_STN2_TX_DN<44>")
	)
	(segment
		(start 46.92015 -280.025856)
		(end 47.023782 -280.129488)
		(width 0.1143)
		(layer "In11.Cu")
		(net "P5E_PEX0_STN2_TX_DN<44>")
	)
	(segment
		(start 139.817348 -355.978206)
		(end 140.137388 -355.658166)
		(width 0.13462)
		(layer "F.Cu")
		(net "P5E_PEX1_STN5_TX_DP<86>")
	)
	(segment
		(start 140.137388 -355.658166)
		(end 140.137388 -355.026722)
		(width 0.13462)
		(layer "F.Cu")
		(net "P5E_PEX1_STN5_TX_DP<86>")
	)
	(segment
		(start 140.137388 -355.026722)
		(end 139.842748 -354.732082)
		(width 0.13462)
		(layer "F.Cu")
		(net "P5E_PEX1_STN5_TX_DP<86>")
	)
	(segment
		(start 180.38572 -311.479692)
		(end 180.50002 -311.365392)
		(width 0.1143)
		(layer "In7.Cu")
		(net "P5E_PEX1_STN5_TX_DP<86>")
	)
	(segment
		(start 164.865812 -335.717896)
		(end 164.865812 -335.71815)
		(width 0.1651)
		(layer "In7.Cu")
		(net "P5E_PEX1_STN5_TX_DP<86>")
	)
	(segment
		(start 144.149318 -343.490042)
		(end 158.498286 -338.355686)
		(width 0.1651)
		(layer "In7.Cu")
		(net "P5E_PEX1_STN5_TX_DP<86>")
	)
	(segment
		(start 140.133578 -353.705922)
		(end 141.688058 -352.151442)
		(width 0.1651)
		(layer "In7.Cu")
		(net "P5E_PEX1_STN5_TX_DP<86>")
	)
	(segment
		(start 164.865558 -335.71815)
		(end 164.865812 -335.717896)
		(width 0.1651)
		(layer "In7.Cu")
		(net "P5E_PEX1_STN5_TX_DP<86>")
	)
	(segment
		(start 179.88407 -319.988438)
		(end 179.92979 -319.942718)
		(width 0.1143)
		(layer "In7.Cu")
		(net "P5E_PEX1_STN5_TX_DP<86>")
	)
	(segment
		(start 139.842748 -354.732082)
		(end 140.133578 -354.441252)
		(width 0.1651)
		(layer "In7.Cu")
		(net "P5E_PEX1_STN5_TX_DP<86>")
	)
	(segment
		(start 180.155596 -311.479692)
		(end 180.38572 -311.479692)
		(width 0.1143)
		(layer "In7.Cu")
		(net "P5E_PEX1_STN5_TX_DP<86>")
	)
	(segment
		(start 141.688058 -344.878152)
		(end 142.608808 -343.957402)
		(width 0.1651)
		(layer "In7.Cu")
		(net "P5E_PEX1_STN5_TX_DP<86>")
	)
	(segment
		(start 171.232576 -333.080868)
		(end 175.548036 -330.19746)
		(width 0.1651)
		(layer "In7.Cu")
		(net "P5E_PEX1_STN5_TX_DP<86>")
	)
	(segment
		(start 141.688058 -352.151442)
		(end 141.688058 -344.878152)
		(width 0.1651)
		(layer "In7.Cu")
		(net "P5E_PEX1_STN5_TX_DP<86>")
	)
	(segment
		(start 179.92979 -319.942718)
		(end 179.92979 -311.705498)
		(width 0.1143)
		(layer "In7.Cu")
		(net "P5E_PEX1_STN5_TX_DP<86>")
	)
	(segment
		(start 179.92979 -311.705498)
		(end 180.155596 -311.479692)
		(width 0.1143)
		(layer "In7.Cu")
		(net "P5E_PEX1_STN5_TX_DP<86>")
	)
	(segment
		(start 179.88407 -320.016886)
		(end 179.88407 -319.988438)
		(width 0.1143)
		(layer "In7.Cu")
		(net "P5E_PEX1_STN5_TX_DP<86>")
	)
	(segment
		(start 140.133578 -354.441252)
		(end 140.133578 -353.705922)
		(width 0.1651)
		(layer "In7.Cu")
		(net "P5E_PEX1_STN5_TX_DP<86>")
	)
	(segment
		(start 164.865812 -335.71815)
		(end 171.232576 -333.080868)
		(width 0.1651)
		(layer "In7.Cu")
		(net "P5E_PEX1_STN5_TX_DP<86>")
	)
	(segment
		(start 142.608808 -343.957402)
		(end 144.149318 -343.490042)
		(width 0.1651)
		(layer "In7.Cu")
		(net "P5E_PEX1_STN5_TX_DP<86>")
	)
	(segment
		(start 179.88407 -324.42912)
		(end 179.88407 -320.016886)
		(width 0.1651)
		(layer "In7.Cu")
		(net "P5E_PEX1_STN5_TX_DP<86>")
	)
	(segment
		(start 158.498286 -338.355686)
		(end 164.865558 -335.71815)
		(width 0.1651)
		(layer "In7.Cu")
		(net "P5E_PEX1_STN5_TX_DP<86>")
	)
	(segment
		(start 175.548036 -330.19746)
		(end 178.871372 -326.874124)
		(width 0.1651)
		(layer "In7.Cu")
		(net "P5E_PEX1_STN5_TX_DP<86>")
	)
	(segment
		(start 178.871372 -326.874124)
		(end 179.88407 -324.42912)
		(width 0.1651)
		(layer "In7.Cu")
		(net "P5E_PEX1_STN5_TX_DP<86>")
	)
	(segment
		(start 180.50002 -311.365392)
		(end 180.50002 -311.099962)
		(width 0.1143)
		(layer "In7.Cu")
		(net "P5E_PEX1_STN5_TX_DP<86>")
	)
	(segment
		(start 313.391804 -349.831914)
		(end 313.071764 -349.511874)
		(width 0.13462)
		(layer "F.Cu")
		(net "P5E_PEX2_STN5_TX_DN<80>")
	)
	(segment
		(start 313.071764 -348.88043)
		(end 313.366404 -348.58579)
		(width 0.13462)
		(layer "F.Cu")
		(net "P5E_PEX2_STN5_TX_DN<80>")
	)
	(segment
		(start 313.071764 -349.511874)
		(end 313.071764 -348.88043)
		(width 0.13462)
		(layer "F.Cu")
		(net "P5E_PEX2_STN5_TX_DN<80>")
	)
	(segment
		(start 293.069264 -329.866244)
		(end 290.56584 -325.21779)
		(width 0.1651)
		(layer "In7.Cu")
		(net "P5E_PEX2_STN5_TX_DN<80>")
	)
	(segment
		(start 312.661046 -347.136466)
		(end 296.554144 -333.373984)
		(width 0.1651)
		(layer "In7.Cu")
		(net "P5E_PEX2_STN5_TX_DN<80>")
	)
	(segment
		(start 290.78555 -311.670192)
		(end 290.89985 -311.784492)
		(width 0.1143)
		(layer "In7.Cu")
		(net "P5E_PEX2_STN5_TX_DN<80>")
	)
	(segment
		(start 290.56584 -319.8368)
		(end 290.52012 -319.79108)
		(width 0.1143)
		(layer "In7.Cu")
		(net "P5E_PEX2_STN5_TX_DN<80>")
	)
	(segment
		(start 290.56584 -319.865248)
		(end 290.56584 -319.8368)
		(width 0.1143)
		(layer "In7.Cu")
		(net "P5E_PEX2_STN5_TX_DN<80>")
	)
	(segment
		(start 290.56584 -325.21779)
		(end 290.56584 -319.865248)
		(width 0.1651)
		(layer "In7.Cu")
		(net "P5E_PEX2_STN5_TX_DN<80>")
	)
	(segment
		(start 290.52012 -319.79108)
		(end 290.52012 -311.784492)
		(width 0.1143)
		(layer "In7.Cu")
		(net "P5E_PEX2_STN5_TX_DN<80>")
	)
	(segment
		(start 313.075574 -347.550994)
		(end 312.661046 -347.136466)
		(width 0.1651)
		(layer "In7.Cu")
		(net "P5E_PEX2_STN5_TX_DN<80>")
	)
	(segment
		(start 290.63442 -311.670192)
		(end 290.78555 -311.670192)
		(width 0.1143)
		(layer "In7.Cu")
		(net "P5E_PEX2_STN5_TX_DN<80>")
	)
	(segment
		(start 296.554144 -333.373984)
		(end 293.069264 -329.866244)
		(width 0.1651)
		(layer "In7.Cu")
		(net "P5E_PEX2_STN5_TX_DN<80>")
	)
	(segment
		(start 290.52012 -311.784492)
		(end 290.63442 -311.670192)
		(width 0.1143)
		(layer "In7.Cu")
		(net "P5E_PEX2_STN5_TX_DN<80>")
	)
	(segment
		(start 290.89985 -311.784492)
		(end 290.89985 -312.049922)
		(width 0.1143)
		(layer "In7.Cu")
		(net "P5E_PEX2_STN5_TX_DN<80>")
	)
	(segment
		(start 313.075574 -348.29496)
		(end 313.075574 -347.550994)
		(width 0.1651)
		(layer "In7.Cu")
		(net "P5E_PEX2_STN5_TX_DN<80>")
	)
	(segment
		(start 313.366404 -348.58579)
		(end 313.075574 -348.29496)
		(width 0.1651)
		(layer "In7.Cu")
		(net "P5E_PEX2_STN5_TX_DN<80>")
	)
	(segment
		(start 277.792942 -355.658166)
		(end 277.792942 -355.026722)
		(width 0.13462)
		(layer "F.Cu")
		(net "P5E_PEX2_STN7_TX_DN<117>")
	)
	(segment
		(start 277.792942 -355.026722)
		(end 278.087582 -354.732082)
		(width 0.13462)
		(layer "F.Cu")
		(net "P5E_PEX2_STN7_TX_DN<117>")
	)
	(segment
		(start 278.112982 -355.978206)
		(end 277.792942 -355.658166)
		(width 0.13462)
		(layer "F.Cu")
		(net "P5E_PEX2_STN7_TX_DN<117>")
	)
	(segment
		(start 257.62204 -311.63641)
		(end 257.857498 -311.2008)
		(width 0.1651)
		(layer "In7.Cu")
		(net "P5E_PEX2_STN7_TX_DN<117>")
	)
	(segment
		(start 255.682242 -315.223144)
		(end 255.785366 -315.192156)
		(width 0.1651)
		(layer "In7.Cu")
		(net "P5E_PEX2_STN7_TX_DN<117>")
	)
	(segment
		(start 261.593838 -330.159868)
		(end 261.160514 -329.919076)
		(width 0.1651)
		(layer "In7.Cu")
		(net "P5E_PEX2_STN7_TX_DN<117>")
	)
	(segment
		(start 255.785366 -315.192156)
		(end 256.021332 -314.756292)
		(width 0.1651)
		(layer "In7.Cu")
		(net "P5E_PEX2_STN7_TX_DN<117>")
	)
	(segment
		(start 258.52755 -310.157622)
		(end 258.74726 -309.751476)
		(width 0.1651)
		(layer "In7.Cu")
		(net "P5E_PEX2_STN7_TX_DN<117>")
	)
	(segment
		(start 260.161278 -329.364086)
		(end 260.057646 -329.39355)
		(width 0.1651)
		(layer "In7.Cu")
		(net "P5E_PEX2_STN7_TX_DN<117>")
	)
	(segment
		(start 275.965158 -306.349908)
		(end 275.699728 -306.349908)
		(width 0.1143)
		(layer "In7.Cu")
		(net "P5E_PEX2_STN7_TX_DN<117>")
	)
	(segment
		(start 275.965158 -305.970178)
		(end 276.079458 -306.084478)
		(width 0.1143)
		(layer "In7.Cu")
		(net "P5E_PEX2_STN7_TX_DN<117>")
	)
	(segment
		(start 256.021332 -314.756292)
		(end 255.990598 -314.653168)
		(width 0.1651)
		(layer "In7.Cu")
		(net "P5E_PEX2_STN7_TX_DN<117>")
	)
	(segment
		(start 253.8222 -322.58635)
		(end 253.8222 -319.274952)
		(width 0.1651)
		(layer "In7.Cu")
		(net "P5E_PEX2_STN7_TX_DN<117>")
	)
	(segment
		(start 257.078226 -312.641996)
		(end 257.313684 -312.206386)
		(width 0.1651)
		(layer "In7.Cu")
		(net "P5E_PEX2_STN7_TX_DN<117>")
	)
	(segment
		(start 267.8684 -306.015898)
		(end 267.91412 -305.970178)
		(width 0.1143)
		(layer "In7.Cu")
		(net "P5E_PEX2_STN7_TX_DN<117>")
	)
	(segment
		(start 257.329178 -327.878186)
		(end 254.873506 -325.124572)
		(width 0.1651)
		(layer "In7.Cu")
		(net "P5E_PEX2_STN7_TX_DN<117>")
	)
	(segment
		(start 256.872994 -313.181238)
		(end 257.10896 -312.74512)
		(width 0.1651)
		(layer "In7.Cu")
		(net "P5E_PEX2_STN7_TX_DN<117>")
	)
	(segment
		(start 256.534412 -313.647582)
		(end 256.76987 -313.211972)
		(width 0.1651)
		(layer "In7.Cu")
		(net "P5E_PEX2_STN7_TX_DN<117>")
	)
	(segment
		(start 279.164542 -341.253318)
		(end 276.763988 -338.672678)
		(width 0.1651)
		(layer "In7.Cu")
		(net "P5E_PEX2_STN7_TX_DN<117>")
	)
	(segment
		(start 258.165854 -310.630824)
		(end 258.401312 -310.195214)
		(width 0.1651)
		(layer "In7.Cu")
		(net "P5E_PEX2_STN7_TX_DN<117>")
	)
	(segment
		(start 255.990598 -314.653168)
		(end 256.226056 -314.217558)
		(width 0.1651)
		(layer "In7.Cu")
		(net "P5E_PEX2_STN7_TX_DN<117>")
	)
	(segment
		(start 267.839952 -306.015898)
		(end 267.8684 -306.015898)
		(width 0.1143)
		(layer "In7.Cu")
		(net "P5E_PEX2_STN7_TX_DN<117>")
	)
	(segment
		(start 257.660648 -311.765696)
		(end 257.62204 -311.63641)
		(width 0.1651)
		(layer "In7.Cu")
		(net "P5E_PEX2_STN7_TX_DN<117>")
	)
	(segment
		(start 267.91412 -305.970178)
		(end 275.965158 -305.970178)
		(width 0.1143)
		(layer "In7.Cu")
		(net "P5E_PEX2_STN7_TX_DN<117>")
	)
	(segment
		(start 260.510274 -307.7972)
		(end 261.016496 -307.7972)
		(width 0.1651)
		(layer "In7.Cu")
		(net "P5E_PEX2_STN7_TX_DN<117>")
	)
	(segment
		(start 258.401312 -310.195214)
		(end 258.52755 -310.157622)
		(width 0.1651)
		(layer "In7.Cu")
		(net "P5E_PEX2_STN7_TX_DN<117>")
	)
	(segment
		(start 257.857498 -311.2008)
		(end 257.970274 -311.167272)
		(width 0.1651)
		(layer "In7.Cu")
		(net "P5E_PEX2_STN7_TX_DN<117>")
	)
	(segment
		(start 266.898374 -306.015898)
		(end 267.839952 -306.015898)
		(width 0.1651)
		(layer "In7.Cu")
		(net "P5E_PEX2_STN7_TX_DN<117>")
	)
	(segment
		(start 278.087582 -354.732082)
		(end 277.796752 -354.441252)
		(width 0.1651)
		(layer "In7.Cu")
		(net "P5E_PEX2_STN7_TX_DN<117>")
	)
	(segment
		(start 256.565146 -313.750706)
		(end 256.534412 -313.647582)
		(width 0.1651)
		(layer "In7.Cu")
		(net "P5E_PEX2_STN7_TX_DN<117>")
	)
	(segment
		(start 258.74726 -309.751476)
		(end 258.709668 -309.625238)
		(width 0.1651)
		(layer "In7.Cu")
		(net "P5E_PEX2_STN7_TX_DN<117>")
	)
	(segment
		(start 257.970274 -311.167272)
		(end 258.199382 -310.7436)
		(width 0.1651)
		(layer "In7.Cu")
		(net "P5E_PEX2_STN7_TX_DN<117>")
	)
	(segment
		(start 276.763988 -338.672678)
		(end 261.623302 -330.263246)
		(width 0.1651)
		(layer "In7.Cu")
		(net "P5E_PEX2_STN7_TX_DN<117>")
	)
	(segment
		(start 261.160514 -329.919076)
		(end 261.056882 -329.94854)
		(width 0.1651)
		(layer "In7.Cu")
		(net "P5E_PEX2_STN7_TX_DN<117>")
	)
	(segment
		(start 260.594602 -329.604624)
		(end 260.161278 -329.364086)
		(width 0.1651)
		(layer "In7.Cu")
		(net "P5E_PEX2_STN7_TX_DN<117>")
	)
	(segment
		(start 257.313684 -312.206386)
		(end 257.44297 -312.167778)
		(width 0.1651)
		(layer "In7.Cu")
		(net "P5E_PEX2_STN7_TX_DN<117>")
	)
	(segment
		(start 257.10896 -312.74512)
		(end 257.078226 -312.641996)
		(width 0.1651)
		(layer "In7.Cu")
		(net "P5E_PEX2_STN7_TX_DN<117>")
	)
	(segment
		(start 261.016496 -307.7972)
		(end 261.130796 -307.9115)
		(width 0.1651)
		(layer "In7.Cu")
		(net "P5E_PEX2_STN7_TX_DN<117>")
	)
	(segment
		(start 260.624066 -329.708256)
		(end 260.594602 -329.604624)
		(width 0.1651)
		(layer "In7.Cu")
		(net "P5E_PEX2_STN7_TX_DN<117>")
	)
	(segment
		(start 259.007356 -309.07482)
		(end 260.146292 -307.94706)
		(width 0.1651)
		(layer "In7.Cu")
		(net "P5E_PEX2_STN7_TX_DN<117>")
	)
	(segment
		(start 253.8222 -319.274952)
		(end 255.016508 -316.453774)
		(width 0.1651)
		(layer "In7.Cu")
		(net "P5E_PEX2_STN7_TX_DN<117>")
	)
	(segment
		(start 256.76987 -313.211972)
		(end 256.872994 -313.181238)
		(width 0.1651)
		(layer "In7.Cu")
		(net "P5E_PEX2_STN7_TX_DN<117>")
	)
	(segment
		(start 261.626096 -307.9115)
		(end 261.740396 -307.7972)
		(width 0.1651)
		(layer "In7.Cu")
		(net "P5E_PEX2_STN7_TX_DN<117>")
	)
	(segment
		(start 279.351232 -352.376486)
		(end 279.351232 -341.6554)
		(width 0.1651)
		(layer "In7.Cu")
		(net "P5E_PEX2_STN7_TX_DN<117>")
	)
	(segment
		(start 260.146292 -307.94706)
		(end 260.510274 -307.7972)
		(width 0.1651)
		(layer "In7.Cu")
		(net "P5E_PEX2_STN7_TX_DN<117>")
	)
	(segment
		(start 257.44297 -312.167778)
		(end 257.660648 -311.765696)
		(width 0.1651)
		(layer "In7.Cu")
		(net "P5E_PEX2_STN7_TX_DN<117>")
	)
	(segment
		(start 277.796752 -353.930966)
		(end 279.351232 -352.376486)
		(width 0.1651)
		(layer "In7.Cu")
		(net "P5E_PEX2_STN7_TX_DN<117>")
	)
	(segment
		(start 262.235696 -307.7972)
		(end 262.777224 -307.661818)
		(width 0.1651)
		(layer "In7.Cu")
		(net "P5E_PEX2_STN7_TX_DN<117>")
	)
	(segment
		(start 256.226056 -314.217558)
		(end 256.32918 -314.18657)
		(width 0.1651)
		(layer "In7.Cu")
		(net "P5E_PEX2_STN7_TX_DN<117>")
	)
	(segment
		(start 261.740396 -307.7972)
		(end 262.235696 -307.7972)
		(width 0.1651)
		(layer "In7.Cu")
		(net "P5E_PEX2_STN7_TX_DN<117>")
	)
	(segment
		(start 262.777224 -307.661818)
		(end 264.16635 -306.918614)
		(width 0.1651)
		(layer "In7.Cu")
		(net "P5E_PEX2_STN7_TX_DN<117>")
	)
	(segment
		(start 258.199382 -310.7436)
		(end 258.165854 -310.630824)
		(width 0.1651)
		(layer "In7.Cu")
		(net "P5E_PEX2_STN7_TX_DN<117>")
	)
	(segment
		(start 276.079458 -306.084478)
		(end 276.079458 -306.235608)
		(width 0.1143)
		(layer "In7.Cu")
		(net "P5E_PEX2_STN7_TX_DN<117>")
	)
	(segment
		(start 264.16635 -306.918614)
		(end 266.898374 -306.015898)
		(width 0.1651)
		(layer "In7.Cu")
		(net "P5E_PEX2_STN7_TX_DN<117>")
	)
	(segment
		(start 255.016508 -316.453774)
		(end 255.682242 -315.223144)
		(width 0.1651)
		(layer "In7.Cu")
		(net "P5E_PEX2_STN7_TX_DN<117>")
	)
	(segment
		(start 261.623302 -330.263246)
		(end 261.593838 -330.159868)
		(width 0.1651)
		(layer "In7.Cu")
		(net "P5E_PEX2_STN7_TX_DN<117>")
	)
	(segment
		(start 260.057646 -329.39355)
		(end 257.329178 -327.878186)
		(width 0.1651)
		(layer "In7.Cu")
		(net "P5E_PEX2_STN7_TX_DN<117>")
	)
	(segment
		(start 277.796752 -354.441252)
		(end 277.796752 -353.930966)
		(width 0.1651)
		(layer "In7.Cu")
		(net "P5E_PEX2_STN7_TX_DN<117>")
	)
	(segment
		(start 254.873506 -325.124572)
		(end 253.8222 -322.58635)
		(width 0.1651)
		(layer "In7.Cu")
		(net "P5E_PEX2_STN7_TX_DN<117>")
	)
	(segment
		(start 256.32918 -314.18657)
		(end 256.565146 -313.750706)
		(width 0.1651)
		(layer "In7.Cu")
		(net "P5E_PEX2_STN7_TX_DN<117>")
	)
	(segment
		(start 276.079458 -306.235608)
		(end 275.965158 -306.349908)
		(width 0.1143)
		(layer "In7.Cu")
		(net "P5E_PEX2_STN7_TX_DN<117>")
	)
	(segment
		(start 258.709668 -309.625238)
		(end 259.007356 -309.07482)
		(width 0.1651)
		(layer "In7.Cu")
		(net "P5E_PEX2_STN7_TX_DN<117>")
	)
	(segment
		(start 261.130796 -307.9115)
		(end 261.626096 -307.9115)
		(width 0.1651)
		(layer "In7.Cu")
		(net "P5E_PEX2_STN7_TX_DN<117>")
	)
	(segment
		(start 261.056882 -329.94854)
		(end 260.624066 -329.708256)
		(width 0.1651)
		(layer "In7.Cu")
		(net "P5E_PEX2_STN7_TX_DN<117>")
	)
	(segment
		(start 279.351232 -341.6554)
		(end 279.164542 -341.253318)
		(width 0.1651)
		(layer "In7.Cu")
		(net "P5E_PEX2_STN7_TX_DN<117>")
	)
	(segment
		(start 432.176682 -132.27812)
		(end 431.551334 -132.27812)
		(width 0.13462)
		(layer "F.Cu")
		(net "P5E_PEX3_STN0_TX_DP<5>")
	)
	(segment
		(start 431.551334 -132.27812)
		(end 431.228246 -132.601208)
		(width 0.13462)
		(layer "F.Cu")
		(net "P5E_PEX3_STN0_TX_DP<5>")
	)
	(segment
		(start 432.47437 -132.575808)
		(end 432.176682 -132.27812)
		(width 0.13462)
		(layer "F.Cu")
		(net "P5E_PEX3_STN0_TX_DP<5>")
	)
	(segment
		(start 434.16347 -133.240526)
		(end 434.30698 -133.240526)
		(width 0.1651)
		(layer "In9.Cu")
		(net "P5E_PEX3_STN0_TX_DP<5>")
	)
	(segment
		(start 436.259478 -137.304526)
		(end 436.39232 -137.359644)
		(width 0.1651)
		(layer "In9.Cu")
		(net "P5E_PEX3_STN0_TX_DP<5>")
	)
	(segment
		(start 432.7652 -132.284978)
		(end 433.351432 -132.284978)
		(width 0.1651)
		(layer "In9.Cu")
		(net "P5E_PEX3_STN0_TX_DP<5>")
	)
	(segment
		(start 436.687214 -138.33729)
		(end 436.820056 -138.392408)
		(width 0.1651)
		(layer "In9.Cu")
		(net "P5E_PEX3_STN0_TX_DP<5>")
	)
	(segment
		(start 435.283864 -134.683754)
		(end 435.229 -134.816596)
		(width 0.1651)
		(layer "In9.Cu")
		(net "P5E_PEX3_STN0_TX_DP<5>")
	)
	(segment
		(start 442.873638 -266.851384)
		(end 443.548262 -268.480286)
		(width 0.1651)
		(layer "In9.Cu")
		(net "P5E_PEX3_STN0_TX_DP<5>")
	)
	(segment
		(start 432.119532 -282.979368)
		(end 423.744898 -282.979368)
		(width 0.1143)
		(layer "In9.Cu")
		(net "P5E_PEX3_STN0_TX_DP<5>")
	)
	(segment
		(start 434.714396 -174.217076)
		(end 433.583842 -178.432968)
		(width 0.1651)
		(layer "In9.Cu")
		(net "P5E_PEX3_STN0_TX_DP<5>")
	)
	(segment
		(start 437.247792 -139.425172)
		(end 437.422544 -139.84732)
		(width 0.1651)
		(layer "In9.Cu")
		(net "P5E_PEX3_STN0_TX_DP<5>")
	)
	(segment
		(start 435.656736 -135.849106)
		(end 435.831742 -136.271762)
		(width 0.1651)
		(layer "In9.Cu")
		(net "P5E_PEX3_STN0_TX_DP<5>")
	)
	(segment
		(start 435.7116 -135.716264)
		(end 435.656736 -135.849106)
		(width 0.1651)
		(layer "In9.Cu")
		(net "P5E_PEX3_STN0_TX_DP<5>")
	)
	(segment
		(start 436.567072 -137.781792)
		(end 436.512208 -137.914634)
		(width 0.1651)
		(layer "In9.Cu")
		(net "P5E_PEX3_STN0_TX_DP<5>")
	)
	(segment
		(start 433.839874 -132.77342)
		(end 433.839874 -132.91693)
		(width 0.1651)
		(layer "In9.Cu")
		(net "P5E_PEX3_STN0_TX_DP<5>")
	)
	(segment
		(start 432.165252 -282.933648)
		(end 432.119532 -282.979368)
		(width 0.1143)
		(layer "In9.Cu")
		(net "P5E_PEX3_STN0_TX_DP<5>")
	)
	(segment
		(start 434.954426 -133.887972)
		(end 435.283864 -134.683754)
		(width 0.1651)
		(layer "In9.Cu")
		(net "P5E_PEX3_STN0_TX_DP<5>")
	)
	(segment
		(start 432.47437 -132.575808)
		(end 432.7652 -132.284978)
		(width 0.1651)
		(layer "In9.Cu")
		(net "P5E_PEX3_STN0_TX_DP<5>")
	)
	(segment
		(start 439.85815 -145.17624)
		(end 443.350904 -153.608024)
		(width 0.1651)
		(layer "In9.Cu")
		(net "P5E_PEX3_STN0_TX_DP<5>")
	)
	(segment
		(start 435.536848 -135.294116)
		(end 435.7116 -135.716264)
		(width 0.1651)
		(layer "In9.Cu")
		(net "P5E_PEX3_STN0_TX_DP<5>")
	)
	(segment
		(start 436.39232 -137.359644)
		(end 436.567072 -137.781792)
		(width 0.1651)
		(layer "In9.Cu")
		(net "P5E_PEX3_STN0_TX_DP<5>")
	)
	(segment
		(start 436.994808 -138.814556)
		(end 436.939944 -138.947398)
		(width 0.1651)
		(layer "In9.Cu")
		(net "P5E_PEX3_STN0_TX_DP<5>")
	)
	(segment
		(start 433.583842 -178.432968)
		(end 429.802798 -221.652592)
		(width 0.1651)
		(layer "In9.Cu")
		(net "P5E_PEX3_STN0_TX_DP<5>")
	)
	(segment
		(start 442.986414 -274.048728)
		(end 434.829966 -282.205176)
		(width 0.1651)
		(layer "In9.Cu")
		(net "P5E_PEX3_STN0_TX_DP<5>")
	)
	(segment
		(start 437.36768 -139.980162)
		(end 437.542686 -140.402818)
		(width 0.1651)
		(layer "In9.Cu")
		(net "P5E_PEX3_STN0_TX_DP<5>")
	)
	(segment
		(start 433.071524 -282.933648)
		(end 432.1937 -282.933648)
		(width 0.1651)
		(layer "In9.Cu")
		(net "P5E_PEX3_STN0_TX_DP<5>")
	)
	(segment
		(start 437.422544 -139.84732)
		(end 437.36768 -139.980162)
		(width 0.1651)
		(layer "In9.Cu")
		(net "P5E_PEX3_STN0_TX_DP<5>")
	)
	(segment
		(start 443.548262 -268.480286)
		(end 443.852554 -271.958054)
		(width 0.1651)
		(layer "In9.Cu")
		(net "P5E_PEX3_STN0_TX_DP<5>")
	)
	(segment
		(start 423.744898 -282.979368)
		(end 423.529506 -283.19476)
		(width 0.1143)
		(layer "In9.Cu")
		(net "P5E_PEX3_STN0_TX_DP<5>")
	)
	(segment
		(start 443.852554 -271.958054)
		(end 442.986414 -274.048728)
		(width 0.1651)
		(layer "In9.Cu")
		(net "P5E_PEX3_STN0_TX_DP<5>")
	)
	(segment
		(start 434.30698 -133.240526)
		(end 434.954426 -133.887972)
		(width 0.1651)
		(layer "In9.Cu")
		(net "P5E_PEX3_STN0_TX_DP<5>")
	)
	(segment
		(start 436.512208 -137.914634)
		(end 436.687214 -138.33729)
		(width 0.1651)
		(layer "In9.Cu")
		(net "P5E_PEX3_STN0_TX_DP<5>")
	)
	(segment
		(start 423.415206 -283.549852)
		(end 423.149776 -283.549852)
		(width 0.1143)
		(layer "In9.Cu")
		(net "P5E_PEX3_STN0_TX_DP<5>")
	)
	(segment
		(start 437.675782 -140.457682)
		(end 439.469022 -144.786858)
		(width 0.1651)
		(layer "In9.Cu")
		(net "P5E_PEX3_STN0_TX_DP<5>")
	)
	(segment
		(start 423.529506 -283.19476)
		(end 423.529506 -283.435552)
		(width 0.1143)
		(layer "In9.Cu")
		(net "P5E_PEX3_STN0_TX_DP<5>")
	)
	(segment
		(start 435.831742 -136.271762)
		(end 435.964584 -136.32688)
		(width 0.1651)
		(layer "In9.Cu")
		(net "P5E_PEX3_STN0_TX_DP<5>")
	)
	(segment
		(start 443.350904 -153.608024)
		(end 443.350904 -159.252412)
		(width 0.1651)
		(layer "In9.Cu")
		(net "P5E_PEX3_STN0_TX_DP<5>")
	)
	(segment
		(start 439.858404 -145.17624)
		(end 439.85815 -145.17624)
		(width 0.1651)
		(layer "In9.Cu")
		(net "P5E_PEX3_STN0_TX_DP<5>")
	)
	(segment
		(start 437.542686 -140.402818)
		(end 437.675782 -140.457682)
		(width 0.1651)
		(layer "In9.Cu")
		(net "P5E_PEX3_STN0_TX_DP<5>")
	)
	(segment
		(start 432.1937 -282.933648)
		(end 432.165252 -282.933648)
		(width 0.1143)
		(layer "In9.Cu")
		(net "P5E_PEX3_STN0_TX_DP<5>")
	)
	(segment
		(start 435.964584 -136.32688)
		(end 436.139336 -136.749028)
		(width 0.1651)
		(layer "In9.Cu")
		(net "P5E_PEX3_STN0_TX_DP<5>")
	)
	(segment
		(start 436.939944 -138.947398)
		(end 437.11495 -139.370054)
		(width 0.1651)
		(layer "In9.Cu")
		(net "P5E_PEX3_STN0_TX_DP<5>")
	)
	(segment
		(start 436.139336 -136.749028)
		(end 436.084472 -136.88187)
		(width 0.1651)
		(layer "In9.Cu")
		(net "P5E_PEX3_STN0_TX_DP<5>")
	)
	(segment
		(start 435.229 -134.816596)
		(end 435.404006 -135.239252)
		(width 0.1651)
		(layer "In9.Cu")
		(net "P5E_PEX3_STN0_TX_DP<5>")
	)
	(segment
		(start 432.378358 -251.144532)
		(end 442.873638 -266.851384)
		(width 0.1651)
		(layer "In9.Cu")
		(net "P5E_PEX3_STN0_TX_DP<5>")
	)
	(segment
		(start 436.084472 -136.88187)
		(end 436.259478 -137.304526)
		(width 0.1651)
		(layer "In9.Cu")
		(net "P5E_PEX3_STN0_TX_DP<5>")
	)
	(segment
		(start 433.351432 -132.284978)
		(end 433.839874 -132.77342)
		(width 0.1651)
		(layer "In9.Cu")
		(net "P5E_PEX3_STN0_TX_DP<5>")
	)
	(segment
		(start 433.839874 -132.91693)
		(end 434.16347 -133.240526)
		(width 0.1651)
		(layer "In9.Cu")
		(net "P5E_PEX3_STN0_TX_DP<5>")
	)
	(segment
		(start 443.350904 -159.252412)
		(end 434.714396 -174.217076)
		(width 0.1651)
		(layer "In9.Cu")
		(net "P5E_PEX3_STN0_TX_DP<5>")
	)
	(segment
		(start 435.404006 -135.239252)
		(end 435.536848 -135.294116)
		(width 0.1651)
		(layer "In9.Cu")
		(net "P5E_PEX3_STN0_TX_DP<5>")
	)
	(segment
		(start 436.820056 -138.392408)
		(end 436.994808 -138.814556)
		(width 0.1651)
		(layer "In9.Cu")
		(net "P5E_PEX3_STN0_TX_DP<5>")
	)
	(segment
		(start 439.469022 -144.786858)
		(end 439.858404 -145.17624)
		(width 0.1651)
		(layer "In9.Cu")
		(net "P5E_PEX3_STN0_TX_DP<5>")
	)
	(segment
		(start 434.829966 -282.205176)
		(end 433.071524 -282.933648)
		(width 0.1651)
		(layer "In9.Cu")
		(net "P5E_PEX3_STN0_TX_DP<5>")
	)
	(segment
		(start 429.802798 -221.652592)
		(end 432.378358 -251.144532)
		(width 0.1651)
		(layer "In9.Cu")
		(net "P5E_PEX3_STN0_TX_DP<5>")
	)
	(segment
		(start 423.529506 -283.435552)
		(end 423.415206 -283.549852)
		(width 0.1143)
		(layer "In9.Cu")
		(net "P5E_PEX3_STN0_TX_DP<5>")
	)
	(segment
		(start 437.11495 -139.370054)
		(end 437.247792 -139.425172)
		(width 0.1651)
		(layer "In9.Cu")
		(net "P5E_PEX3_STN0_TX_DP<5>")
	)
	(segment
		(start 434.735224 -343.365074)
		(end 434.735224 -342.734646)
		(width 0.13462)
		(layer "F.Cu")
		(net "P5E_PEX3_STN7_TX_DN<123>")
	)
	(segment
		(start 434.735224 -342.734646)
		(end 435.030372 -342.439498)
		(width 0.13462)
		(layer "F.Cu")
		(net "P5E_PEX3_STN7_TX_DN<123>")
	)
	(segment
		(start 435.055772 -343.685622)
		(end 434.735224 -343.365074)
		(width 0.13462)
		(layer "F.Cu")
		(net "P5E_PEX3_STN7_TX_DN<123>")
	)
	(segment
		(start 393.104878 -325.265542)
		(end 392.625834 -325.139304)
		(width 0.1651)
		(layer "In11.Cu")
		(net "P5E_PEX3_STN7_TX_DN<123>")
	)
	(segment
		(start 392.625834 -325.139304)
		(end 392.517122 -325.20255)
		(width 0.1651)
		(layer "In11.Cu")
		(net "P5E_PEX3_STN7_TX_DN<123>")
	)
	(segment
		(start 392.517122 -325.20255)
		(end 392.038332 -325.076312)
		(width 0.1651)
		(layer "In11.Cu")
		(net "P5E_PEX3_STN7_TX_DN<123>")
	)
	(segment
		(start 433.6288 -339.7758)
		(end 424.374818 -333.606648)
		(width 0.1651)
		(layer "In11.Cu")
		(net "P5E_PEX3_STN7_TX_DN<123>")
	)
	(segment
		(start 435.030372 -342.439498)
		(end 434.739542 -342.148668)
		(width 0.1651)
		(layer "In11.Cu")
		(net "P5E_PEX3_STN7_TX_DN<123>")
	)
	(segment
		(start 387.050026 -313.684412)
		(end 387.050026 -313.949842)
		(width 0.1143)
		(layer "In11.Cu")
		(net "P5E_PEX3_STN7_TX_DN<123>")
	)
	(segment
		(start 392.038332 -325.076312)
		(end 391.975086 -324.9676)
		(width 0.1651)
		(layer "In11.Cu")
		(net "P5E_PEX3_STN7_TX_DN<123>")
	)
	(segment
		(start 386.809742 -322.547742)
		(end 386.715762 -322.32092)
		(width 0.1651)
		(layer "In11.Cu")
		(net "P5E_PEX3_STN7_TX_DN<123>")
	)
	(segment
		(start 393.168124 -325.374254)
		(end 393.168124 -325.374508)
		(width 0.1651)
		(layer "In11.Cu")
		(net "P5E_PEX3_STN7_TX_DN<123>")
	)
	(segment
		(start 393.168124 -325.374508)
		(end 393.104878 -325.265542)
		(width 0.1651)
		(layer "In11.Cu")
		(net "P5E_PEX3_STN7_TX_DN<123>")
	)
	(segment
		(start 386.670042 -313.673998)
		(end 386.773928 -313.570112)
		(width 0.1143)
		(layer "In11.Cu")
		(net "P5E_PEX3_STN7_TX_DN<123>")
	)
	(segment
		(start 434.739542 -342.148668)
		(end 434.739542 -341.633048)
		(width 0.1651)
		(layer "In11.Cu")
		(net "P5E_PEX3_STN7_TX_DN<123>")
	)
	(segment
		(start 434.739542 -341.633048)
		(end 433.6288 -339.7758)
		(width 0.1651)
		(layer "In11.Cu")
		(net "P5E_PEX3_STN7_TX_DN<123>")
	)
	(segment
		(start 395.364462 -325.86168)
		(end 394.885418 -325.735442)
		(width 0.1651)
		(layer "In11.Cu")
		(net "P5E_PEX3_STN7_TX_DN<123>")
	)
	(segment
		(start 386.670042 -319.988438)
		(end 386.670042 -313.673998)
		(width 0.1143)
		(layer "In11.Cu")
		(net "P5E_PEX3_STN7_TX_DN<123>")
	)
	(segment
		(start 386.715762 -322.32092)
		(end 386.715762 -320.056256)
		(width 0.1651)
		(layer "In11.Cu")
		(net "P5E_PEX3_STN7_TX_DN<123>")
	)
	(segment
		(start 393.755626 -325.437246)
		(end 393.646914 -325.500492)
		(width 0.1651)
		(layer "In11.Cu")
		(net "P5E_PEX3_STN7_TX_DN<123>")
	)
	(segment
		(start 394.776706 -325.798688)
		(end 394.297916 -325.67245)
		(width 0.1651)
		(layer "In11.Cu")
		(net "P5E_PEX3_STN7_TX_DN<123>")
	)
	(segment
		(start 395.427708 -325.970392)
		(end 395.427708 -325.970646)
		(width 0.1651)
		(layer "In11.Cu")
		(net "P5E_PEX3_STN7_TX_DN<123>")
	)
	(segment
		(start 391.38733 -324.904354)
		(end 388.370826 -324.108826)
		(width 0.1651)
		(layer "In11.Cu")
		(net "P5E_PEX3_STN7_TX_DN<123>")
	)
	(segment
		(start 393.646914 -325.500492)
		(end 393.168124 -325.374254)
		(width 0.1651)
		(layer "In11.Cu")
		(net "P5E_PEX3_STN7_TX_DN<123>")
	)
	(segment
		(start 424.374818 -333.606648)
		(end 395.427708 -325.970392)
		(width 0.1651)
		(layer "In11.Cu")
		(net "P5E_PEX3_STN7_TX_DN<123>")
	)
	(segment
		(start 386.715762 -320.034158)
		(end 386.670042 -319.988438)
		(width 0.1143)
		(layer "In11.Cu")
		(net "P5E_PEX3_STN7_TX_DN<123>")
	)
	(segment
		(start 391.495788 -324.841108)
		(end 391.38733 -324.904354)
		(width 0.1651)
		(layer "In11.Cu")
		(net "P5E_PEX3_STN7_TX_DN<123>")
	)
	(segment
		(start 386.935726 -313.570112)
		(end 387.050026 -313.684412)
		(width 0.1143)
		(layer "In11.Cu")
		(net "P5E_PEX3_STN7_TX_DN<123>")
	)
	(segment
		(start 394.23467 -325.563484)
		(end 393.755626 -325.437246)
		(width 0.1651)
		(layer "In11.Cu")
		(net "P5E_PEX3_STN7_TX_DN<123>")
	)
	(segment
		(start 391.975086 -324.9676)
		(end 391.495788 -324.841108)
		(width 0.1651)
		(layer "In11.Cu")
		(net "P5E_PEX3_STN7_TX_DN<123>")
	)
	(segment
		(start 394.885418 -325.735442)
		(end 394.776706 -325.798688)
		(width 0.1651)
		(layer "In11.Cu")
		(net "P5E_PEX3_STN7_TX_DN<123>")
	)
	(segment
		(start 388.370826 -324.108826)
		(end 386.809742 -322.547742)
		(width 0.1651)
		(layer "In11.Cu")
		(net "P5E_PEX3_STN7_TX_DN<123>")
	)
	(segment
		(start 395.427708 -325.970646)
		(end 395.364462 -325.86168)
		(width 0.1651)
		(layer "In11.Cu")
		(net "P5E_PEX3_STN7_TX_DN<123>")
	)
	(segment
		(start 386.715762 -320.056256)
		(end 386.715762 -320.034158)
		(width 0.1143)
		(layer "In11.Cu")
		(net "P5E_PEX3_STN7_TX_DN<123>")
	)
	(segment
		(start 394.297916 -325.67245)
		(end 394.23467 -325.563484)
		(width 0.1651)
		(layer "In11.Cu")
		(net "P5E_PEX3_STN7_TX_DN<123>")
	)
	(segment
		(start 386.773928 -313.570112)
		(end 386.935726 -313.570112)
		(width 0.1143)
		(layer "In11.Cu")
		(net "P5E_PEX3_STN7_TX_DN<123>")
	)
	(segment
		(start 65.370202 -343.685622)
		(end 65.050162 -343.365582)
		(width 0.13462)
		(layer "F.Cu")
		(net "P5E_PEX0_STN5_TX_DN<81>")
	)
	(segment
		(start 65.050162 -342.734138)
		(end 65.344802 -342.439498)
		(width 0.13462)
		(layer "F.Cu")
		(net "P5E_PEX0_STN5_TX_DN<81>")
	)
	(segment
		(start 65.050162 -343.365582)
		(end 65.050162 -342.734138)
		(width 0.13462)
		(layer "F.Cu")
		(net "P5E_PEX0_STN5_TX_DN<81>")
	)
	(segment
		(start 59.535568 -313.570112)
		(end 59.649868 -313.684412)
		(width 0.1143)
		(layer "In7.Cu")
		(net "P5E_PEX0_STN5_TX_DN<81>")
	)
	(segment
		(start 59.270138 -319.81648)
		(end 59.270138 -313.684412)
		(width 0.1143)
		(layer "In7.Cu")
		(net "P5E_PEX0_STN5_TX_DN<81>")
	)
	(segment
		(start 65.344802 -342.439498)
		(end 65.053972 -342.148668)
		(width 0.1651)
		(layer "In7.Cu")
		(net "P5E_PEX0_STN5_TX_DN<81>")
	)
	(segment
		(start 59.384438 -313.570112)
		(end 59.535568 -313.570112)
		(width 0.1143)
		(layer "In7.Cu")
		(net "P5E_PEX0_STN5_TX_DN<81>")
	)
	(segment
		(start 59.649868 -313.684412)
		(end 59.649868 -313.949842)
		(width 0.1143)
		(layer "In7.Cu")
		(net "P5E_PEX0_STN5_TX_DN<81>")
	)
	(segment
		(start 65.053972 -339.377274)
		(end 59.315858 -325.525892)
		(width 0.1651)
		(layer "In7.Cu")
		(net "P5E_PEX0_STN5_TX_DN<81>")
	)
	(segment
		(start 59.315858 -319.890648)
		(end 59.315858 -319.8622)
		(width 0.1143)
		(layer "In7.Cu")
		(net "P5E_PEX0_STN5_TX_DN<81>")
	)
	(segment
		(start 59.270138 -313.684412)
		(end 59.384438 -313.570112)
		(width 0.1143)
		(layer "In7.Cu")
		(net "P5E_PEX0_STN5_TX_DN<81>")
	)
	(segment
		(start 59.315858 -325.525892)
		(end 59.315858 -319.890648)
		(width 0.1651)
		(layer "In7.Cu")
		(net "P5E_PEX0_STN5_TX_DN<81>")
	)
	(segment
		(start 59.315858 -319.8622)
		(end 59.270138 -319.81648)
		(width 0.1143)
		(layer "In7.Cu")
		(net "P5E_PEX0_STN5_TX_DN<81>")
	)
	(segment
		(start 65.053972 -342.148668)
		(end 65.053972 -339.377274)
		(width 0.1651)
		(layer "In7.Cu")
		(net "P5E_PEX0_STN5_TX_DN<81>")
	)
	(segment
		(start 186.488578 -28.55468)
		(end 186.15914 -28.225242)
		(width 0.13462)
		(layer "F.Cu")
		(net "P5E_PEX1_STN2_TX_DN<36>")
	)
	(segment
		(start 187.405264 -28.250642)
		(end 187.101226 -28.55468)
		(width 0.13462)
		(layer "F.Cu")
		(net "P5E_PEX1_STN2_TX_DN<36>")
	)
	(segment
		(start 187.101226 -28.55468)
		(end 186.488578 -28.55468)
		(width 0.13462)
		(layer "F.Cu")
		(net "P5E_PEX1_STN2_TX_DN<36>")
	)
	(segment
		(start 170.999912 -280.015188)
		(end 170.999912 -279.749504)
		(width 0.1143)
		(layer "In11.Cu")
		(net "P5E_PEX1_STN2_TX_DN<36>")
	)
	(segment
		(start 194.353942 -31.885636)
		(end 199.347328 -39.727886)
		(width 0.1651)
		(layer "In11.Cu")
		(net "P5E_PEX1_STN2_TX_DN<36>")
	)
	(segment
		(start 199.347328 -39.727886)
		(end 206.247238 -47.60849)
		(width 0.1651)
		(layer "In11.Cu")
		(net "P5E_PEX1_STN2_TX_DN<36>")
	)
	(segment
		(start 170.620182 -271.473168)
		(end 170.620182 -280.025856)
		(width 0.1143)
		(layer "In11.Cu")
		(net "P5E_PEX1_STN2_TX_DN<36>")
	)
	(segment
		(start 190.07201 -28.541472)
		(end 191.675512 -29.206952)
		(width 0.1651)
		(layer "In11.Cu")
		(net "P5E_PEX1_STN2_TX_DN<36>")
	)
	(segment
		(start 178.722274 -116.6876)
		(end 178.206654 -120.957594)
		(width 0.1651)
		(layer "In11.Cu")
		(net "P5E_PEX1_STN2_TX_DN<36>")
	)
	(segment
		(start 170.665902 -271.427448)
		(end 170.620182 -271.473168)
		(width 0.1143)
		(layer "In11.Cu")
		(net "P5E_PEX1_STN2_TX_DN<36>")
	)
	(segment
		(start 178.206654 -120.957594)
		(end 170.665902 -263.42467)
		(width 0.1651)
		(layer "In11.Cu")
		(net "P5E_PEX1_STN2_TX_DN<36>")
	)
	(segment
		(start 206.247238 -47.60849)
		(end 207.374236 -58.438034)
		(width 0.1651)
		(layer "In11.Cu")
		(net "P5E_PEX1_STN2_TX_DN<36>")
	)
	(segment
		(start 170.620182 -280.025856)
		(end 170.723814 -280.129488)
		(width 0.1143)
		(layer "In11.Cu")
		(net "P5E_PEX1_STN2_TX_DN<36>")
	)
	(segment
		(start 207.374236 -58.438034)
		(end 207.374236 -60.59424)
		(width 0.1651)
		(layer "In11.Cu")
		(net "P5E_PEX1_STN2_TX_DN<36>")
	)
	(segment
		(start 191.675512 -29.206952)
		(end 194.353942 -31.885636)
		(width 0.1651)
		(layer "In11.Cu")
		(net "P5E_PEX1_STN2_TX_DN<36>")
	)
	(segment
		(start 206.727806 -62.998604)
		(end 205.732634 -65.005458)
		(width 0.1651)
		(layer "In11.Cu")
		(net "P5E_PEX1_STN2_TX_DN<36>")
	)
	(segment
		(start 180.350668 -108.111798)
		(end 178.722274 -116.6876)
		(width 0.1651)
		(layer "In11.Cu")
		(net "P5E_PEX1_STN2_TX_DN<36>")
	)
	(segment
		(start 207.374236 -60.59424)
		(end 206.727806 -62.998604)
		(width 0.1651)
		(layer "In11.Cu")
		(net "P5E_PEX1_STN2_TX_DN<36>")
	)
	(segment
		(start 187.696094 -28.541472)
		(end 190.07201 -28.541472)
		(width 0.1651)
		(layer "In11.Cu")
		(net "P5E_PEX1_STN2_TX_DN<36>")
	)
	(segment
		(start 187.405264 -28.250642)
		(end 187.696094 -28.541472)
		(width 0.1651)
		(layer "In11.Cu")
		(net "P5E_PEX1_STN2_TX_DN<36>")
	)
	(segment
		(start 170.885612 -280.129488)
		(end 170.999912 -280.015188)
		(width 0.1143)
		(layer "In11.Cu")
		(net "P5E_PEX1_STN2_TX_DN<36>")
	)
	(segment
		(start 205.732634 -65.005458)
		(end 183.518048 -94.024958)
		(width 0.1651)
		(layer "In11.Cu")
		(net "P5E_PEX1_STN2_TX_DN<36>")
	)
	(segment
		(start 170.723814 -280.129488)
		(end 170.885612 -280.129488)
		(width 0.1143)
		(layer "In11.Cu")
		(net "P5E_PEX1_STN2_TX_DN<36>")
	)
	(segment
		(start 170.665902 -271.399)
		(end 170.665902 -271.427448)
		(width 0.1143)
		(layer "In11.Cu")
		(net "P5E_PEX1_STN2_TX_DN<36>")
	)
	(segment
		(start 183.518048 -94.024958)
		(end 180.350668 -108.111798)
		(width 0.1651)
		(layer "In11.Cu")
		(net "P5E_PEX1_STN2_TX_DN<36>")
	)
	(segment
		(start 170.665902 -263.42467)
		(end 170.665902 -271.399)
		(width 0.1651)
		(layer "In11.Cu")
		(net "P5E_PEX1_STN2_TX_DN<36>")
	)
	(segment
		(start 268.191742 -349.511874)
		(end 268.191742 -348.88043)
		(width 0.13462)
		(layer "F.Cu")
		(net "P5E_PEX2_STN7_TX_DP<112>")
	)
	(segment
		(start 268.191742 -348.88043)
		(end 267.897102 -348.58579)
		(width 0.13462)
		(layer "F.Cu")
		(net "P5E_PEX2_STN7_TX_DP<112>")
	)
	(segment
		(start 267.871702 -349.831914)
		(end 268.191742 -349.511874)
		(width 0.13462)
		(layer "F.Cu")
		(net "P5E_PEX2_STN7_TX_DP<112>")
	)
	(segment
		(start 274.484338 -301.599854)
		(end 274.749768 -301.599854)
		(width 0.1143)
		(layer "In7.Cu")
		(net "P5E_PEX2_STN7_TX_DP<112>")
	)
	(segment
		(start 259.290566 -301.657258)
		(end 266.12977 -300.983904)
		(width 0.1651)
		(layer "In7.Cu")
		(net "P5E_PEX2_STN7_TX_DP<112>")
	)
	(segment
		(start 274.370038 -301.25543)
		(end 274.370038 -301.485554)
		(width 0.1143)
		(layer "In7.Cu")
		(net "P5E_PEX2_STN7_TX_DP<112>")
	)
	(segment
		(start 268.187932 -347.667834)
		(end 260.75894 -339.68182)
		(width 0.1651)
		(layer "In7.Cu")
		(net "P5E_PEX2_STN7_TX_DP<112>")
	)
	(segment
		(start 253.294134 -306.343558)
		(end 256.97434 -302.492156)
		(width 0.1651)
		(layer "In7.Cu")
		(net "P5E_PEX2_STN7_TX_DP<112>")
	)
	(segment
		(start 268.187932 -348.29496)
		(end 268.187932 -347.667834)
		(width 0.1651)
		(layer "In7.Cu")
		(net "P5E_PEX2_STN7_TX_DP<112>")
	)
	(segment
		(start 266.12977 -300.983904)
		(end 267.865352 -300.983904)
		(width 0.1651)
		(layer "In7.Cu")
		(net "P5E_PEX2_STN7_TX_DP<112>")
	)
	(segment
		(start 250.552966 -328.53503)
		(end 248.539 -323.67347)
		(width 0.1651)
		(layer "In7.Cu")
		(net "P5E_PEX2_STN7_TX_DP<112>")
	)
	(segment
		(start 267.93952 -301.029624)
		(end 274.144232 -301.029624)
		(width 0.1143)
		(layer "In7.Cu")
		(net "P5E_PEX2_STN7_TX_DP<112>")
	)
	(segment
		(start 267.897102 -348.58579)
		(end 268.187932 -348.29496)
		(width 0.1651)
		(layer "In7.Cu")
		(net "P5E_PEX2_STN7_TX_DP<112>")
	)
	(segment
		(start 274.370038 -301.485554)
		(end 274.484338 -301.599854)
		(width 0.1143)
		(layer "In7.Cu")
		(net "P5E_PEX2_STN7_TX_DP<112>")
	)
	(segment
		(start 253.294134 -306.343812)
		(end 253.294134 -306.343558)
		(width 0.1651)
		(layer "In7.Cu")
		(net "P5E_PEX2_STN7_TX_DP<112>")
	)
	(segment
		(start 253.2888 -306.3494)
		(end 253.294134 -306.343812)
		(width 0.1651)
		(layer "In7.Cu")
		(net "P5E_PEX2_STN7_TX_DP<112>")
	)
	(segment
		(start 260.75894 -339.68182)
		(end 259.656326 -338.579206)
		(width 0.1651)
		(layer "In7.Cu")
		(net "P5E_PEX2_STN7_TX_DP<112>")
	)
	(segment
		(start 256.97434 -302.492156)
		(end 259.290566 -301.657258)
		(width 0.1651)
		(layer "In7.Cu")
		(net "P5E_PEX2_STN7_TX_DP<112>")
	)
	(segment
		(start 267.865352 -300.983904)
		(end 267.8938 -300.983904)
		(width 0.1143)
		(layer "In7.Cu")
		(net "P5E_PEX2_STN7_TX_DP<112>")
	)
	(segment
		(start 248.539 -317.173864)
		(end 253.2888 -306.3494)
		(width 0.1651)
		(layer "In7.Cu")
		(net "P5E_PEX2_STN7_TX_DP<112>")
	)
	(segment
		(start 248.539 -323.67347)
		(end 248.539 -317.173864)
		(width 0.1651)
		(layer "In7.Cu")
		(net "P5E_PEX2_STN7_TX_DP<112>")
	)
	(segment
		(start 267.8938 -300.983904)
		(end 267.93952 -301.029624)
		(width 0.1143)
		(layer "In7.Cu")
		(net "P5E_PEX2_STN7_TX_DP<112>")
	)
	(segment
		(start 274.144232 -301.029624)
		(end 274.370038 -301.25543)
		(width 0.1143)
		(layer "In7.Cu")
		(net "P5E_PEX2_STN7_TX_DP<112>")
	)
	(segment
		(start 259.656326 -338.579206)
		(end 250.552966 -328.53503)
		(width 0.1651)
		(layer "In7.Cu")
		(net "P5E_PEX2_STN7_TX_DP<112>")
	)
	(segment
		(start 383.4257 -130.434334)
		(end 383.704846 -130.71348)
		(width 0.13462)
		(layer "F.Cu")
		(net "P5E_PEX3_STN1_TX_DP<28>")
	)
	(segment
		(start 383.704846 -130.71348)
		(end 384.367278 -130.71348)
		(width 0.13462)
		(layer "F.Cu")
		(net "P5E_PEX3_STN1_TX_DP<28>")
	)
	(segment
		(start 384.367278 -130.71348)
		(end 384.671824 -130.408934)
		(width 0.13462)
		(layer "F.Cu")
		(net "P5E_PEX3_STN1_TX_DP<28>")
	)
	(segment
		(start 380.118112 -136.050782)
		(end 380.118112 -134.239508)
		(width 0.1651)
		(layer "In9.Cu")
		(net "P5E_PEX3_STN1_TX_DP<28>")
	)
	(segment
		(start 418.779706 -278.205184)
		(end 418.779706 -271.546066)
		(width 0.1143)
		(layer "In9.Cu")
		(net "P5E_PEX3_STN1_TX_DP<28>")
	)
	(segment
		(start 382.189736 -130.885692)
		(end 382.489964 -130.725164)
		(width 0.1651)
		(layer "In9.Cu")
		(net "P5E_PEX3_STN1_TX_DP<28>")
	)
	(segment
		(start 418.733986 -263.430258)
		(end 384.276346 -161.63925)
		(width 0.1651)
		(layer "In9.Cu")
		(net "P5E_PEX3_STN1_TX_DP<28>")
	)
	(segment
		(start 419.349682 -278.534368)
		(end 419.235382 -278.420068)
		(width 0.1143)
		(layer "In9.Cu")
		(net "P5E_PEX3_STN1_TX_DP<28>")
	)
	(segment
		(start 418.733986 -271.471898)
		(end 418.733986 -263.430258)
		(width 0.1651)
		(layer "In9.Cu")
		(net "P5E_PEX3_STN1_TX_DP<28>")
	)
	(segment
		(start 380.393956 -133.57352)
		(end 381.132334 -132.467858)
		(width 0.1651)
		(layer "In9.Cu")
		(net "P5E_PEX3_STN1_TX_DP<28>")
	)
	(segment
		(start 419.235382 -278.420068)
		(end 418.99459 -278.420068)
		(width 0.1143)
		(layer "In9.Cu")
		(net "P5E_PEX3_STN1_TX_DP<28>")
	)
	(segment
		(start 381.942594 -131.25577)
		(end 382.189736 -130.885692)
		(width 0.1651)
		(layer "In9.Cu")
		(net "P5E_PEX3_STN1_TX_DP<28>")
	)
	(segment
		(start 381.132334 -132.467858)
		(end 381.132588 -132.467858)
		(width 0.1651)
		(layer "In9.Cu")
		(net "P5E_PEX3_STN1_TX_DP<28>")
	)
	(segment
		(start 381.132588 -132.467858)
		(end 381.94234 -131.25577)
		(width 0.1651)
		(layer "In9.Cu")
		(net "P5E_PEX3_STN1_TX_DP<28>")
	)
	(segment
		(start 418.733986 -271.500346)
		(end 418.733986 -271.471898)
		(width 0.1143)
		(layer "In9.Cu")
		(net "P5E_PEX3_STN1_TX_DP<28>")
	)
	(segment
		(start 419.349682 -278.799798)
		(end 419.349682 -278.534368)
		(width 0.1143)
		(layer "In9.Cu")
		(net "P5E_PEX3_STN1_TX_DP<28>")
	)
	(segment
		(start 383.13487 -130.725164)
		(end 383.4257 -130.434334)
		(width 0.1651)
		(layer "In9.Cu")
		(net "P5E_PEX3_STN1_TX_DP<28>")
	)
	(segment
		(start 382.720342 -142.333472)
		(end 380.118112 -136.050782)
		(width 0.1651)
		(layer "In9.Cu")
		(net "P5E_PEX3_STN1_TX_DP<28>")
	)
	(segment
		(start 418.779706 -271.546066)
		(end 418.733986 -271.500346)
		(width 0.1143)
		(layer "In9.Cu")
		(net "P5E_PEX3_STN1_TX_DP<28>")
	)
	(segment
		(start 383.470658 -157.586934)
		(end 382.720342 -142.333472)
		(width 0.1651)
		(layer "In9.Cu")
		(net "P5E_PEX3_STN1_TX_DP<28>")
	)
	(segment
		(start 418.99459 -278.420068)
		(end 418.779706 -278.205184)
		(width 0.1143)
		(layer "In9.Cu")
		(net "P5E_PEX3_STN1_TX_DP<28>")
	)
	(segment
		(start 384.276346 -161.63925)
		(end 383.470658 -157.586934)
		(width 0.1651)
		(layer "In9.Cu")
		(net "P5E_PEX3_STN1_TX_DP<28>")
	)
	(segment
		(start 382.489964 -130.725164)
		(end 383.13487 -130.725164)
		(width 0.1651)
		(layer "In9.Cu")
		(net "P5E_PEX3_STN1_TX_DP<28>")
	)
	(segment
		(start 380.118112 -134.239508)
		(end 380.393956 -133.57352)
		(width 0.1651)
		(layer "In9.Cu")
		(net "P5E_PEX3_STN1_TX_DP<28>")
	)
	(segment
		(start 381.94234 -131.25577)
		(end 381.942594 -131.25577)
		(width 0.1651)
		(layer "In9.Cu")
		(net "P5E_PEX3_STN1_TX_DP<28>")
	)
	(segment
		(start 380.808992 -343.36609)
		(end 380.808992 -342.73363)
		(width 0.13462)
		(layer "F.Cu")
		(net "P5E_PEX3_STN6_TX_DP<99>")
	)
	(segment
		(start 380.48946 -343.685622)
		(end 380.808992 -343.36609)
		(width 0.13462)
		(layer "F.Cu")
		(net "P5E_PEX3_STN6_TX_DP<99>")
	)
	(segment
		(start 380.808992 -342.73363)
		(end 380.51486 -342.439498)
		(width 0.13462)
		(layer "F.Cu")
		(net "P5E_PEX3_STN6_TX_DP<99>")
	)
	(segment
		(start 380.80569 -341.49792)
		(end 400.313906 -324.084188)
		(width 0.1651)
		(layer "In7.Cu")
		(net "P5E_PEX3_STN6_TX_DP<99>")
	)
	(segment
		(start 402.583904 -319.9892)
		(end 402.583904 -319.960752)
		(width 0.1143)
		(layer "In7.Cu")
		(net "P5E_PEX3_STN6_TX_DP<99>")
	)
	(segment
		(start 380.51486 -342.439498)
		(end 380.80569 -342.148668)
		(width 0.1651)
		(layer "In7.Cu")
		(net "P5E_PEX3_STN6_TX_DP<99>")
	)
	(segment
		(start 402.583904 -319.960752)
		(end 402.629624 -319.915032)
		(width 0.1143)
		(layer "In7.Cu")
		(net "P5E_PEX3_STN6_TX_DP<99>")
	)
	(segment
		(start 400.313906 -324.084188)
		(end 402.063204 -322.33489)
		(width 0.1651)
		(layer "In7.Cu")
		(net "P5E_PEX3_STN6_TX_DP<99>")
	)
	(segment
		(start 402.063204 -322.33489)
		(end 402.583904 -321.077844)
		(width 0.1651)
		(layer "In7.Cu")
		(net "P5E_PEX3_STN6_TX_DP<99>")
	)
	(segment
		(start 403.085554 -311.479692)
		(end 403.199854 -311.365392)
		(width 0.1143)
		(layer "In7.Cu")
		(net "P5E_PEX3_STN6_TX_DP<99>")
	)
	(segment
		(start 380.80569 -342.148668)
		(end 380.80569 -341.49792)
		(width 0.1651)
		(layer "In7.Cu")
		(net "P5E_PEX3_STN6_TX_DP<99>")
	)
	(segment
		(start 402.85543 -311.479692)
		(end 403.085554 -311.479692)
		(width 0.1143)
		(layer "In7.Cu")
		(net "P5E_PEX3_STN6_TX_DP<99>")
	)
	(segment
		(start 402.583904 -321.077844)
		(end 402.583904 -319.9892)
		(width 0.1651)
		(layer "In7.Cu")
		(net "P5E_PEX3_STN6_TX_DP<99>")
	)
	(segment
		(start 403.199854 -311.365392)
		(end 403.199854 -311.099962)
		(width 0.1143)
		(layer "In7.Cu")
		(net "P5E_PEX3_STN6_TX_DP<99>")
	)
	(segment
		(start 402.629624 -311.705498)
		(end 402.85543 -311.479692)
		(width 0.1143)
		(layer "In7.Cu")
		(net "P5E_PEX3_STN6_TX_DP<99>")
	)
	(segment
		(start 402.629624 -319.915032)
		(end 402.629624 -311.705498)
		(width 0.1143)
		(layer "In7.Cu")
		(net "P5E_PEX3_STN6_TX_DP<99>")
	)
	(segment
		(start 71.588122 -355.978206)
		(end 71.268082 -355.658166)
		(width 0.13462)
		(layer "F.Cu")
		(net "P5E_PEX0_STN5_TX_DN<85>")
	)
	(segment
		(start 71.268082 -355.026722)
		(end 71.562722 -354.732082)
		(width 0.13462)
		(layer "F.Cu")
		(net "P5E_PEX0_STN5_TX_DN<85>")
	)
	(segment
		(start 71.268082 -355.658166)
		(end 71.268082 -355.026722)
		(width 0.13462)
		(layer "F.Cu")
		(net "P5E_PEX0_STN5_TX_DN<85>")
	)
	(segment
		(start 72.826372 -340.427564)
		(end 71.444866 -337.09229)
		(width 0.1651)
		(layer "In7.Cu")
		(net "P5E_PEX0_STN5_TX_DN<85>")
	)
	(segment
		(start 63.335662 -313.570112)
		(end 63.449962 -313.684412)
		(width 0.1143)
		(layer "In7.Cu")
		(net "P5E_PEX0_STN5_TX_DN<85>")
	)
	(segment
		(start 63.449962 -313.684412)
		(end 63.449962 -313.949842)
		(width 0.1143)
		(layer "In7.Cu")
		(net "P5E_PEX0_STN5_TX_DN<85>")
	)
	(segment
		(start 71.444866 -337.09229)
		(end 66.090292 -329.078844)
		(width 0.1651)
		(layer "In7.Cu")
		(net "P5E_PEX0_STN5_TX_DN<85>")
	)
	(segment
		(start 71.271892 -354.441252)
		(end 71.271892 -353.942142)
		(width 0.1651)
		(layer "In7.Cu")
		(net "P5E_PEX0_STN5_TX_DN<85>")
	)
	(segment
		(start 66.090292 -329.078844)
		(end 63.493396 -324.220332)
		(width 0.1651)
		(layer "In7.Cu")
		(net "P5E_PEX0_STN5_TX_DN<85>")
	)
	(segment
		(start 63.184532 -313.570112)
		(end 63.335662 -313.570112)
		(width 0.1143)
		(layer "In7.Cu")
		(net "P5E_PEX0_STN5_TX_DN<85>")
	)
	(segment
		(start 71.562722 -354.732082)
		(end 71.271892 -354.441252)
		(width 0.1651)
		(layer "In7.Cu")
		(net "P5E_PEX0_STN5_TX_DN<85>")
	)
	(segment
		(start 72.826372 -352.387662)
		(end 72.826372 -340.427564)
		(width 0.1651)
		(layer "In7.Cu")
		(net "P5E_PEX0_STN5_TX_DN<85>")
	)
	(segment
		(start 63.493396 -324.220332)
		(end 63.115952 -323.30898)
		(width 0.1651)
		(layer "In7.Cu")
		(net "P5E_PEX0_STN5_TX_DN<85>")
	)
	(segment
		(start 63.070232 -313.684412)
		(end 63.184532 -313.570112)
		(width 0.1143)
		(layer "In7.Cu")
		(net "P5E_PEX0_STN5_TX_DN<85>")
	)
	(segment
		(start 71.271892 -353.942142)
		(end 72.826372 -352.387662)
		(width 0.1651)
		(layer "In7.Cu")
		(net "P5E_PEX0_STN5_TX_DN<85>")
	)
	(segment
		(start 63.115952 -323.30898)
		(end 63.115952 -319.916048)
		(width 0.1651)
		(layer "In7.Cu")
		(net "P5E_PEX0_STN5_TX_DN<85>")
	)
	(segment
		(start 63.115952 -319.916048)
		(end 63.115952 -319.8876)
		(width 0.1143)
		(layer "In7.Cu")
		(net "P5E_PEX0_STN5_TX_DN<85>")
	)
	(segment
		(start 63.115952 -319.8876)
		(end 63.070232 -319.84188)
		(width 0.1143)
		(layer "In7.Cu")
		(net "P5E_PEX0_STN5_TX_DN<85>")
	)
	(segment
		(start 63.070232 -319.84188)
		(end 63.070232 -313.684412)
		(width 0.1143)
		(layer "In7.Cu")
		(net "P5E_PEX0_STN5_TX_DN<85>")
	)
	(segment
		(start 161.101278 -28.55468)
		(end 160.48863 -28.55468)
		(width 0.13462)
		(layer "F.Cu")
		(net "P5E_PEX1_STN2_TX_DN<40>")
	)
	(segment
		(start 161.405316 -28.250642)
		(end 161.101278 -28.55468)
		(width 0.13462)
		(layer "F.Cu")
		(net "P5E_PEX1_STN2_TX_DN<40>")
	)
	(segment
		(start 160.48863 -28.55468)
		(end 160.159192 -28.225242)
		(width 0.13462)
		(layer "F.Cu")
		(net "P5E_PEX1_STN2_TX_DN<40>")
	)
	(segment
		(start 161.405316 -28.250642)
		(end 161.696146 -28.541472)
		(width 0.1651)
		(layer "In11.Cu")
		(net "P5E_PEX1_STN2_TX_DN<40>")
	)
	(segment
		(start 166.874698 -271.221962)
		(end 166.866062 -271.230598)
		(width 0.1651)
		(layer "In11.Cu")
		(net "P5E_PEX1_STN2_TX_DN<40>")
	)
	(segment
		(start 161.696146 -28.541472)
		(end 164.039296 -28.541472)
		(width 0.1651)
		(layer "In11.Cu")
		(net "P5E_PEX1_STN2_TX_DN<40>")
	)
	(segment
		(start 166.866062 -271.399)
		(end 166.866062 -271.427448)
		(width 0.1143)
		(layer "In11.Cu")
		(net "P5E_PEX1_STN2_TX_DN<40>")
	)
	(segment
		(start 180.680614 -49.856136)
		(end 181.346348 -60.605162)
		(width 0.1651)
		(layer "In11.Cu")
		(net "P5E_PEX1_STN2_TX_DN<40>")
	)
	(segment
		(start 167.200072 -280.015188)
		(end 167.200072 -279.749504)
		(width 0.1143)
		(layer "In11.Cu")
		(net "P5E_PEX1_STN2_TX_DN<40>")
	)
	(segment
		(start 179.653946 -46.926246)
		(end 180.680614 -49.856136)
		(width 0.1651)
		(layer "In11.Cu")
		(net "P5E_PEX1_STN2_TX_DN<40>")
	)
	(segment
		(start 166.228268 -252.61824)
		(end 166.501572 -266.016486)
		(width 0.1651)
		(layer "In11.Cu")
		(net "P5E_PEX1_STN2_TX_DN<40>")
	)
	(segment
		(start 166.874698 -269.806928)
		(end 166.874698 -271.221962)
		(width 0.1651)
		(layer "In11.Cu")
		(net "P5E_PEX1_STN2_TX_DN<40>")
	)
	(segment
		(start 180.917596 -69.60997)
		(end 180.917342 -69.60997)
		(width 0.1651)
		(layer "In11.Cu")
		(net "P5E_PEX1_STN2_TX_DN<40>")
	)
	(segment
		(start 173.870874 -119.313452)
		(end 172.530262 -135.263128)
		(width 0.1651)
		(layer "In11.Cu")
		(net "P5E_PEX1_STN2_TX_DN<40>")
	)
	(segment
		(start 168.170352 -31.857696)
		(end 169.914316 -34.710116)
		(width 0.1651)
		(layer "In11.Cu")
		(net "P5E_PEX1_STN2_TX_DN<40>")
	)
	(segment
		(start 166.501572 -266.016486)
		(end 166.874698 -269.806928)
		(width 0.1651)
		(layer "In11.Cu")
		(net "P5E_PEX1_STN2_TX_DN<40>")
	)
	(segment
		(start 166.923974 -280.129488)
		(end 167.085772 -280.129488)
		(width 0.1143)
		(layer "In11.Cu")
		(net "P5E_PEX1_STN2_TX_DN<40>")
	)
	(segment
		(start 166.866062 -271.427448)
		(end 166.820342 -271.473168)
		(width 0.1143)
		(layer "In11.Cu")
		(net "P5E_PEX1_STN2_TX_DN<40>")
	)
	(segment
		(start 165.405054 -29.110178)
		(end 168.170352 -31.857696)
		(width 0.1651)
		(layer "In11.Cu")
		(net "P5E_PEX1_STN2_TX_DN<40>")
	)
	(segment
		(start 181.346348 -60.605162)
		(end 180.919374 -69.597016)
		(width 0.1651)
		(layer "In11.Cu")
		(net "P5E_PEX1_STN2_TX_DN<40>")
	)
	(segment
		(start 172.530262 -135.263128)
		(end 166.228268 -252.61824)
		(width 0.1651)
		(layer "In11.Cu")
		(net "P5E_PEX1_STN2_TX_DN<40>")
	)
	(segment
		(start 166.820342 -280.025856)
		(end 166.923974 -280.129488)
		(width 0.1143)
		(layer "In11.Cu")
		(net "P5E_PEX1_STN2_TX_DN<40>")
	)
	(segment
		(start 166.820342 -271.473168)
		(end 166.820342 -280.025856)
		(width 0.1143)
		(layer "In11.Cu")
		(net "P5E_PEX1_STN2_TX_DN<40>")
	)
	(segment
		(start 180.917342 -69.60997)
		(end 173.870874 -119.313452)
		(width 0.1651)
		(layer "In11.Cu")
		(net "P5E_PEX1_STN2_TX_DN<40>")
	)
	(segment
		(start 164.039296 -28.541472)
		(end 165.405054 -29.110178)
		(width 0.1651)
		(layer "In11.Cu")
		(net "P5E_PEX1_STN2_TX_DN<40>")
	)
	(segment
		(start 180.919374 -69.597016)
		(end 180.917596 -69.60997)
		(width 0.1651)
		(layer "In11.Cu")
		(net "P5E_PEX1_STN2_TX_DN<40>")
	)
	(segment
		(start 169.914316 -34.710116)
		(end 179.653946 -46.926246)
		(width 0.1651)
		(layer "In11.Cu")
		(net "P5E_PEX1_STN2_TX_DN<40>")
	)
	(segment
		(start 166.866062 -271.230598)
		(end 166.866062 -271.399)
		(width 0.1651)
		(layer "In11.Cu")
		(net "P5E_PEX1_STN2_TX_DN<40>")
	)
	(segment
		(start 167.085772 -280.129488)
		(end 167.200072 -280.015188)
		(width 0.1143)
		(layer "In11.Cu")
		(net "P5E_PEX1_STN2_TX_DN<40>")
	)
	(segment
		(start 334.834484 -349.511874)
		(end 334.834484 -348.88043)
		(width 0.13462)
		(layer "F.Cu")
		(net "P5E_PEX2_STN6_TX_DN<101>")
	)
	(segment
		(start 334.834484 -348.88043)
		(end 335.129124 -348.58579)
		(width 0.13462)
		(layer "F.Cu")
		(net "P5E_PEX2_STN6_TX_DN<101>")
	)
	(segment
		(start 335.154524 -349.831914)
		(end 334.834484 -349.511874)
		(width 0.13462)
		(layer "F.Cu")
		(net "P5E_PEX2_STN6_TX_DN<101>")
	)
	(segment
		(start 285.199836 -311.784492)
		(end 285.085536 -311.670192)
		(width 0.1143)
		(layer "In13.Cu")
		(net "P5E_PEX2_STN6_TX_DN<101>")
	)
	(segment
		(start 284.865826 -322.785994)
		(end 284.957012 -323.006212)
		(width 0.1651)
		(layer "In13.Cu")
		(net "P5E_PEX2_STN6_TX_DN<101>")
	)
	(segment
		(start 331.8764 -337.6168)
		(end 335.7626 -341.0966)
		(width 0.1651)
		(layer "In13.Cu")
		(net "P5E_PEX2_STN6_TX_DN<101>")
	)
	(segment
		(start 314.770008 -330.017374)
		(end 331.8764 -337.6168)
		(width 0.1651)
		(layer "In13.Cu")
		(net "P5E_PEX2_STN6_TX_DN<101>")
	)
	(segment
		(start 295.828974 -326.191626)
		(end 296.31513 -326.28713)
		(width 0.1651)
		(layer "In13.Cu")
		(net "P5E_PEX2_STN6_TX_DN<101>")
	)
	(segment
		(start 284.865826 -319.966848)
		(end 284.865826 -319.995296)
		(width 0.1143)
		(layer "In13.Cu")
		(net "P5E_PEX2_STN6_TX_DN<101>")
	)
	(segment
		(start 336.347054 -341.99195)
		(end 336.347054 -341.991696)
		(width 0.1651)
		(layer "In13.Cu")
		(net "P5E_PEX2_STN6_TX_DN<101>")
	)
	(segment
		(start 335.7626 -341.0966)
		(end 336.347054 -341.99195)
		(width 0.1651)
		(layer "In13.Cu")
		(net "P5E_PEX2_STN6_TX_DN<101>")
	)
	(segment
		(start 334.838294 -347.784674)
		(end 334.838294 -348.29496)
		(width 0.1651)
		(layer "In13.Cu")
		(net "P5E_PEX2_STN6_TX_DN<101>")
	)
	(segment
		(start 296.31513 -326.28713)
		(end 296.39514 -326.406764)
		(width 0.1651)
		(layer "In13.Cu")
		(net "P5E_PEX2_STN6_TX_DN<101>")
	)
	(segment
		(start 295.709594 -326.271636)
		(end 295.828974 -326.191626)
		(width 0.1651)
		(layer "In13.Cu")
		(net "P5E_PEX2_STN6_TX_DN<101>")
	)
	(segment
		(start 285.199836 -312.049922)
		(end 285.199836 -311.784492)
		(width 0.1143)
		(layer "In13.Cu")
		(net "P5E_PEX2_STN6_TX_DN<101>")
	)
	(segment
		(start 296.39514 -326.40651)
		(end 314.770008 -330.017374)
		(width 0.1651)
		(layer "In13.Cu")
		(net "P5E_PEX2_STN6_TX_DN<101>")
	)
	(segment
		(start 296.39514 -326.406764)
		(end 296.39514 -326.40651)
		(width 0.1651)
		(layer "In13.Cu")
		(net "P5E_PEX2_STN6_TX_DN<101>")
	)
	(segment
		(start 284.820106 -319.921128)
		(end 284.865826 -319.966848)
		(width 0.1143)
		(layer "In13.Cu")
		(net "P5E_PEX2_STN6_TX_DN<101>")
	)
	(segment
		(start 334.838294 -348.29496)
		(end 335.129124 -348.58579)
		(width 0.1651)
		(layer "In13.Cu")
		(net "P5E_PEX2_STN6_TX_DN<101>")
	)
	(segment
		(start 286.391604 -324.440804)
		(end 295.709594 -326.271636)
		(width 0.1651)
		(layer "In13.Cu")
		(net "P5E_PEX2_STN6_TX_DN<101>")
	)
	(segment
		(start 336.392774 -346.230194)
		(end 334.838294 -347.784674)
		(width 0.1651)
		(layer "In13.Cu")
		(net "P5E_PEX2_STN6_TX_DN<101>")
	)
	(segment
		(start 284.820106 -311.838594)
		(end 284.820106 -319.921128)
		(width 0.1143)
		(layer "In13.Cu")
		(net "P5E_PEX2_STN6_TX_DN<101>")
	)
	(segment
		(start 284.865826 -319.995296)
		(end 284.865826 -322.785994)
		(width 0.1651)
		(layer "In13.Cu")
		(net "P5E_PEX2_STN6_TX_DN<101>")
	)
	(segment
		(start 284.957012 -323.006212)
		(end 286.391604 -324.440804)
		(width 0.1651)
		(layer "In13.Cu")
		(net "P5E_PEX2_STN6_TX_DN<101>")
	)
	(segment
		(start 284.988508 -311.670192)
		(end 284.820106 -311.838594)
		(width 0.1143)
		(layer "In13.Cu")
		(net "P5E_PEX2_STN6_TX_DN<101>")
	)
	(segment
		(start 285.085536 -311.670192)
		(end 284.988508 -311.670192)
		(width 0.1143)
		(layer "In13.Cu")
		(net "P5E_PEX2_STN6_TX_DN<101>")
	)
	(segment
		(start 336.392774 -342.0618)
		(end 336.392774 -346.230194)
		(width 0.1651)
		(layer "In13.Cu")
		(net "P5E_PEX2_STN6_TX_DN<101>")
	)
	(segment
		(start 336.347054 -341.991696)
		(end 336.392774 -342.0618)
		(width 0.1651)
		(layer "In13.Cu")
		(net "P5E_PEX2_STN6_TX_DN<101>")
	)
	(segment
		(start 387.00075 -132.8166)
		(end 387.313932 -133.129782)
		(width 0.13462)
		(layer "F.Cu")
		(net "P5E_PEX3_STN1_TX_DP<29>")
	)
	(segment
		(start 386.35559 -132.8166)
		(end 387.00075 -132.8166)
		(width 0.13462)
		(layer "F.Cu")
		(net "P5E_PEX3_STN1_TX_DP<29>")
	)
	(segment
		(start 386.067808 -133.104382)
		(end 386.35559 -132.8166)
		(width 0.13462)
		(layer "F.Cu")
		(net "P5E_PEX3_STN1_TX_DP<29>")
	)
	(segment
		(start 419.920166 -271.600168)
		(end 419.965886 -271.554448)
		(width 0.1143)
		(layer "In9.Cu")
		(net "P5E_PEX3_STN1_TX_DP<29>")
	)
	(segment
		(start 420.299896 -279.749504)
		(end 420.299896 -280.015188)
		(width 0.1143)
		(layer "In9.Cu")
		(net "P5E_PEX3_STN1_TX_DP<29>")
	)
	(segment
		(start 382.912366 -138.932666)
		(end 382.722882 -138.474704)
		(width 0.1651)
		(layer "In9.Cu")
		(net "P5E_PEX3_STN1_TX_DP<29>")
	)
	(segment
		(start 419.920166 -280.025856)
		(end 419.920166 -271.600168)
		(width 0.1143)
		(layer "In9.Cu")
		(net "P5E_PEX3_STN1_TX_DP<29>")
	)
	(segment
		(start 420.185596 -280.129488)
		(end 420.023798 -280.129488)
		(width 0.1143)
		(layer "In9.Cu")
		(net "P5E_PEX3_STN1_TX_DP<29>")
	)
	(segment
		(start 419.965886 -263.170924)
		(end 385.788662 -162.20821)
		(width 0.1651)
		(layer "In9.Cu")
		(net "P5E_PEX3_STN1_TX_DP<29>")
	)
	(segment
		(start 384.227578 -145.02511)
		(end 384.203194 -144.530064)
		(width 0.1651)
		(layer "In9.Cu")
		(net "P5E_PEX3_STN1_TX_DP<29>")
	)
	(segment
		(start 384.118866 -145.144744)
		(end 384.227578 -145.02511)
		(width 0.1651)
		(layer "In9.Cu")
		(net "P5E_PEX3_STN1_TX_DP<29>")
	)
	(segment
		(start 384.14198 -143.285972)
		(end 384.021838 -143.177514)
		(width 0.1651)
		(layer "In9.Cu")
		(net "P5E_PEX3_STN1_TX_DP<29>")
	)
	(segment
		(start 384.20294 -146.857212)
		(end 384.17881 -146.362674)
		(width 0.1651)
		(layer "In9.Cu")
		(net "P5E_PEX3_STN1_TX_DP<29>")
	)
	(segment
		(start 384.1496 -132.813552)
		(end 384.2639 -132.927852)
		(width 0.1651)
		(layer "In9.Cu")
		(net "P5E_PEX3_STN1_TX_DP<29>")
	)
	(segment
		(start 384.685286 -156.661866)
		(end 384.298698 -148.798534)
		(width 0.1651)
		(layer "In9.Cu")
		(net "P5E_PEX3_STN1_TX_DP<29>")
	)
	(segment
		(start 384.40741 -148.678646)
		(end 384.383026 -148.183854)
		(width 0.1651)
		(layer "In9.Cu")
		(net "P5E_PEX3_STN1_TX_DP<29>")
	)
	(segment
		(start 383.379218 -140.059156)
		(end 383.189734 -139.601448)
		(width 0.1651)
		(layer "In9.Cu")
		(net "P5E_PEX3_STN1_TX_DP<29>")
	)
	(segment
		(start 384.347466 -147.460716)
		(end 384.323082 -146.965924)
		(width 0.1651)
		(layer "In9.Cu")
		(net "P5E_PEX3_STN1_TX_DP<29>")
	)
	(segment
		(start 385.776978 -132.813552)
		(end 386.067808 -133.104382)
		(width 0.1651)
		(layer "In9.Cu")
		(net "P5E_PEX3_STN1_TX_DP<29>")
	)
	(segment
		(start 384.238754 -147.580604)
		(end 384.347466 -147.460716)
		(width 0.1651)
		(layer "In9.Cu")
		(net "P5E_PEX3_STN1_TX_DP<29>")
	)
	(segment
		(start 381.57785 -134.26313)
		(end 382.629918 -133.211062)
		(width 0.1651)
		(layer "In9.Cu")
		(net "P5E_PEX3_STN1_TX_DP<29>")
	)
	(segment
		(start 384.287522 -146.242786)
		(end 384.263138 -145.74774)
		(width 0.1651)
		(layer "In9.Cu")
		(net "P5E_PEX3_STN1_TX_DP<29>")
	)
	(segment
		(start 383.317496 -140.208508)
		(end 383.379218 -140.059156)
		(width 0.1651)
		(layer "In9.Cu")
		(net "P5E_PEX3_STN1_TX_DP<29>")
	)
	(segment
		(start 384.2639 -132.927852)
		(end 384.7465 -132.927852)
		(width 0.1651)
		(layer "In9.Cu")
		(net "P5E_PEX3_STN1_TX_DP<29>")
	)
	(segment
		(start 384.17881 -146.362674)
		(end 384.287522 -146.242786)
		(width 0.1651)
		(layer "In9.Cu")
		(net "P5E_PEX3_STN1_TX_DP<29>")
	)
	(segment
		(start 385.788662 -162.20821)
		(end 384.685286 -156.661866)
		(width 0.1651)
		(layer "In9.Cu")
		(net "P5E_PEX3_STN1_TX_DP<29>")
	)
	(segment
		(start 382.573276 -138.412982)
		(end 381.3556 -135.473694)
		(width 0.1651)
		(layer "In9.Cu")
		(net "P5E_PEX3_STN1_TX_DP<29>")
	)
	(segment
		(start 383.951226 -141.738604)
		(end 383.317496 -140.208508)
		(width 0.1651)
		(layer "In9.Cu")
		(net "P5E_PEX3_STN1_TX_DP<29>")
	)
	(segment
		(start 384.142996 -145.639282)
		(end 384.118866 -145.144744)
		(width 0.1651)
		(layer "In9.Cu")
		(net "P5E_PEX3_STN1_TX_DP<29>")
	)
	(segment
		(start 384.323082 -146.965924)
		(end 384.20294 -146.857212)
		(width 0.1651)
		(layer "In9.Cu")
		(net "P5E_PEX3_STN1_TX_DP<29>")
	)
	(segment
		(start 420.023798 -280.129488)
		(end 419.920166 -280.025856)
		(width 0.1143)
		(layer "In9.Cu")
		(net "P5E_PEX3_STN1_TX_DP<29>")
	)
	(segment
		(start 384.383026 -148.183854)
		(end 384.262884 -148.075142)
		(width 0.1651)
		(layer "In9.Cu")
		(net "P5E_PEX3_STN1_TX_DP<29>")
	)
	(segment
		(start 384.021838 -143.177514)
		(end 383.951226 -141.738604)
		(width 0.1651)
		(layer "In9.Cu")
		(net "P5E_PEX3_STN1_TX_DP<29>")
	)
	(segment
		(start 383.189734 -139.601448)
		(end 383.040128 -139.539472)
		(width 0.1651)
		(layer "In9.Cu")
		(net "P5E_PEX3_STN1_TX_DP<29>")
	)
	(segment
		(start 419.965886 -271.554448)
		(end 419.965886 -271.526)
		(width 0.1143)
		(layer "In9.Cu")
		(net "P5E_PEX3_STN1_TX_DP<29>")
	)
	(segment
		(start 383.58953 -132.813552)
		(end 384.1496 -132.813552)
		(width 0.1651)
		(layer "In9.Cu")
		(net "P5E_PEX3_STN1_TX_DP<29>")
	)
	(segment
		(start 384.262884 -148.075142)
		(end 384.238754 -147.580604)
		(width 0.1651)
		(layer "In9.Cu")
		(net "P5E_PEX3_STN1_TX_DP<29>")
	)
	(segment
		(start 384.057652 -143.900652)
		(end 384.166364 -143.781018)
		(width 0.1651)
		(layer "In9.Cu")
		(net "P5E_PEX3_STN1_TX_DP<29>")
	)
	(segment
		(start 384.203194 -144.530064)
		(end 384.083052 -144.421606)
		(width 0.1651)
		(layer "In9.Cu")
		(net "P5E_PEX3_STN1_TX_DP<29>")
	)
	(segment
		(start 382.722882 -138.474704)
		(end 382.573276 -138.412982)
		(width 0.1651)
		(layer "In9.Cu")
		(net "P5E_PEX3_STN1_TX_DP<29>")
	)
	(segment
		(start 384.263138 -145.74774)
		(end 384.142996 -145.639282)
		(width 0.1651)
		(layer "In9.Cu")
		(net "P5E_PEX3_STN1_TX_DP<29>")
	)
	(segment
		(start 383.040128 -139.539472)
		(end 382.850644 -139.082018)
		(width 0.1651)
		(layer "In9.Cu")
		(net "P5E_PEX3_STN1_TX_DP<29>")
	)
	(segment
		(start 384.166364 -143.781018)
		(end 384.14198 -143.285972)
		(width 0.1651)
		(layer "In9.Cu")
		(net "P5E_PEX3_STN1_TX_DP<29>")
	)
	(segment
		(start 419.965886 -271.526)
		(end 419.965886 -263.170924)
		(width 0.1651)
		(layer "In9.Cu")
		(net "P5E_PEX3_STN1_TX_DP<29>")
	)
	(segment
		(start 382.629918 -133.211062)
		(end 383.58953 -132.813552)
		(width 0.1651)
		(layer "In9.Cu")
		(net "P5E_PEX3_STN1_TX_DP<29>")
	)
	(segment
		(start 384.298698 -148.798534)
		(end 384.40741 -148.678646)
		(width 0.1651)
		(layer "In9.Cu")
		(net "P5E_PEX3_STN1_TX_DP<29>")
	)
	(segment
		(start 381.3556 -134.799578)
		(end 381.57785 -134.26313)
		(width 0.1651)
		(layer "In9.Cu")
		(net "P5E_PEX3_STN1_TX_DP<29>")
	)
	(segment
		(start 381.3556 -135.473694)
		(end 381.3556 -134.799578)
		(width 0.1651)
		(layer "In9.Cu")
		(net "P5E_PEX3_STN1_TX_DP<29>")
	)
	(segment
		(start 420.299896 -280.015188)
		(end 420.185596 -280.129488)
		(width 0.1143)
		(layer "In9.Cu")
		(net "P5E_PEX3_STN1_TX_DP<29>")
	)
	(segment
		(start 382.850644 -139.082018)
		(end 382.912366 -138.932666)
		(width 0.1651)
		(layer "In9.Cu")
		(net "P5E_PEX3_STN1_TX_DP<29>")
	)
	(segment
		(start 384.8608 -132.813552)
		(end 385.776978 -132.813552)
		(width 0.1651)
		(layer "In9.Cu")
		(net "P5E_PEX3_STN1_TX_DP<29>")
	)
	(segment
		(start 384.7465 -132.927852)
		(end 384.8608 -132.813552)
		(width 0.1651)
		(layer "In9.Cu")
		(net "P5E_PEX3_STN1_TX_DP<29>")
	)
	(segment
		(start 384.083052 -144.421606)
		(end 384.057652 -143.900652)
		(width 0.1651)
		(layer "In9.Cu")
		(net "P5E_PEX3_STN1_TX_DP<29>")
	)
	(segment
		(start 428.242984 -343.36609)
		(end 428.242984 -342.73363)
		(width 0.13462)
		(layer "F.Cu")
		(net "P5E_PEX3_STN7_TX_DP<120>")
	)
	(segment
		(start 428.242984 -342.73363)
		(end 427.948852 -342.439498)
		(width 0.13462)
		(layer "F.Cu")
		(net "P5E_PEX3_STN7_TX_DP<120>")
	)
	(segment
		(start 427.923452 -343.685622)
		(end 428.242984 -343.36609)
		(width 0.13462)
		(layer "F.Cu")
		(net "P5E_PEX3_STN7_TX_DP<120>")
	)
	(segment
		(start 373.371364 -323.744844)
		(end 372.64086 -321.981322)
		(width 0.1651)
		(layer "In11.Cu")
		(net "P5E_PEX3_STN7_TX_DP<120>")
	)
	(segment
		(start 390.584436 -309.199788)
		(end 390.849866 -309.199788)
		(width 0.1143)
		(layer "In11.Cu")
		(net "P5E_PEX3_STN7_TX_DP<120>")
	)
	(segment
		(start 383.47269 -308.583838)
		(end 383.968752 -308.583838)
		(width 0.1651)
		(layer "In11.Cu")
		(net "P5E_PEX3_STN7_TX_DP<120>")
	)
	(segment
		(start 428.239682 -342.148668)
		(end 428.239682 -341.714328)
		(width 0.1651)
		(layer "In11.Cu")
		(net "P5E_PEX3_STN7_TX_DP<120>")
	)
	(segment
		(start 374.500902 -324.874382)
		(end 373.371364 -323.744844)
		(width 0.1651)
		(layer "In11.Cu")
		(net "P5E_PEX3_STN7_TX_DP<120>")
	)
	(segment
		(start 372.64086 -321.981322)
		(end 372.64086 -319.922144)
		(width 0.1651)
		(layer "In11.Cu")
		(net "P5E_PEX3_STN7_TX_DP<120>")
	)
	(segment
		(start 427.948852 -342.439498)
		(end 428.239682 -342.148668)
		(width 0.1651)
		(layer "In11.Cu")
		(net "P5E_PEX3_STN7_TX_DP<120>")
	)
	(segment
		(start 427.62932 -340.736936)
		(end 420.620444 -335.906618)
		(width 0.1651)
		(layer "In11.Cu")
		(net "P5E_PEX3_STN7_TX_DP<120>")
	)
	(segment
		(start 383.968752 -308.583838)
		(end 383.9972 -308.583838)
		(width 0.1143)
		(layer "In11.Cu")
		(net "P5E_PEX3_STN7_TX_DP<120>")
	)
	(segment
		(start 382.678432 -308.912768)
		(end 383.47269 -308.583838)
		(width 0.1651)
		(layer "In11.Cu")
		(net "P5E_PEX3_STN7_TX_DP<120>")
	)
	(segment
		(start 427.934628 -341.225886)
		(end 427.62932 -340.736936)
		(width 0.1651)
		(layer "In11.Cu")
		(net "P5E_PEX3_STN7_TX_DP<120>")
	)
	(segment
		(start 420.620444 -335.906618)
		(end 376.44578 -325.946262)
		(width 0.1651)
		(layer "In11.Cu")
		(net "P5E_PEX3_STN7_TX_DP<120>")
	)
	(segment
		(start 390.254998 -308.629558)
		(end 390.470136 -308.844696)
		(width 0.1143)
		(layer "In11.Cu")
		(net "P5E_PEX3_STN7_TX_DP<120>")
	)
	(segment
		(start 427.934374 -341.225886)
		(end 427.934628 -341.225886)
		(width 0.1651)
		(layer "In11.Cu")
		(net "P5E_PEX3_STN7_TX_DP<120>")
	)
	(segment
		(start 428.239682 -341.714328)
		(end 428.239428 -341.714074)
		(width 0.1651)
		(layer "In11.Cu")
		(net "P5E_PEX3_STN7_TX_DP<120>")
	)
	(segment
		(start 373.050054 -318.93383)
		(end 373.841264 -317.749936)
		(width 0.1651)
		(layer "In11.Cu")
		(net "P5E_PEX3_STN7_TX_DP<120>")
	)
	(segment
		(start 383.9972 -308.583838)
		(end 384.04292 -308.629558)
		(width 0.1143)
		(layer "In11.Cu")
		(net "P5E_PEX3_STN7_TX_DP<120>")
	)
	(segment
		(start 372.64086 -319.922144)
		(end 373.050054 -318.93383)
		(width 0.1651)
		(layer "In11.Cu")
		(net "P5E_PEX3_STN7_TX_DP<120>")
	)
	(segment
		(start 428.239428 -341.714074)
		(end 427.934374 -341.225886)
		(width 0.1651)
		(layer "In11.Cu")
		(net "P5E_PEX3_STN7_TX_DP<120>")
	)
	(segment
		(start 384.04292 -308.629558)
		(end 390.254998 -308.629558)
		(width 0.1143)
		(layer "In11.Cu")
		(net "P5E_PEX3_STN7_TX_DP<120>")
	)
	(segment
		(start 390.470136 -308.844696)
		(end 390.470136 -309.085488)
		(width 0.1143)
		(layer "In11.Cu")
		(net "P5E_PEX3_STN7_TX_DP<120>")
	)
	(segment
		(start 373.841264 -317.749936)
		(end 382.678432 -308.912768)
		(width 0.1651)
		(layer "In11.Cu")
		(net "P5E_PEX3_STN7_TX_DP<120>")
	)
	(segment
		(start 376.44578 -325.946262)
		(end 374.500902 -324.874382)
		(width 0.1651)
		(layer "In11.Cu")
		(net "P5E_PEX3_STN7_TX_DP<120>")
	)
	(segment
		(start 390.470136 -309.085488)
		(end 390.584436 -309.199788)
		(width 0.1143)
		(layer "In11.Cu")
		(net "P5E_PEX3_STN7_TX_DP<120>")
	)
	(segment
		(start 93.350842 -349.831914)
		(end 93.030802 -349.511874)
		(width 0.13462)
		(layer "F.Cu")
		(net "P5E_PEX0_STN5_TX_DN<95>")
	)
	(segment
		(start 93.030802 -349.511874)
		(end 93.030802 -348.88043)
		(width 0.13462)
		(layer "F.Cu")
		(net "P5E_PEX0_STN5_TX_DN<95>")
	)
	(segment
		(start 93.030802 -348.88043)
		(end 93.325442 -348.58579)
		(width 0.13462)
		(layer "F.Cu")
		(net "P5E_PEX0_STN5_TX_DN<95>")
	)
	(segment
		(start 72.570086 -313.684412)
		(end 72.684386 -313.570112)
		(width 0.1143)
		(layer "In7.Cu")
		(net "P5E_PEX0_STN5_TX_DN<95>")
	)
	(segment
		(start 72.684386 -313.570112)
		(end 72.835516 -313.570112)
		(width 0.1143)
		(layer "In7.Cu")
		(net "P5E_PEX0_STN5_TX_DN<95>")
	)
	(segment
		(start 93.099382 -338.779612)
		(end 72.737218 -320.323718)
		(width 0.1651)
		(layer "In7.Cu")
		(net "P5E_PEX0_STN5_TX_DN<95>")
	)
	(segment
		(start 72.949816 -313.684412)
		(end 72.949816 -313.949842)
		(width 0.1143)
		(layer "In7.Cu")
		(net "P5E_PEX0_STN5_TX_DN<95>")
	)
	(segment
		(start 72.835516 -313.570112)
		(end 72.949816 -313.684412)
		(width 0.1143)
		(layer "In7.Cu")
		(net "P5E_PEX0_STN5_TX_DN<95>")
	)
	(segment
		(start 72.615806 -320.05016)
		(end 72.615806 -319.916048)
		(width 0.1651)
		(layer "In7.Cu")
		(net "P5E_PEX0_STN5_TX_DN<95>")
	)
	(segment
		(start 94.589092 -346.103702)
		(end 94.589092 -342.139778)
		(width 0.1651)
		(layer "In7.Cu")
		(net "P5E_PEX0_STN5_TX_DN<95>")
	)
	(segment
		(start 72.615806 -319.916048)
		(end 72.615806 -319.8876)
		(width 0.1143)
		(layer "In7.Cu")
		(net "P5E_PEX0_STN5_TX_DN<95>")
	)
	(segment
		(start 93.034612 -348.29496)
		(end 93.034612 -347.658182)
		(width 0.1651)
		(layer "In7.Cu")
		(net "P5E_PEX0_STN5_TX_DN<95>")
	)
	(segment
		(start 72.615806 -319.8876)
		(end 72.570086 -319.84188)
		(width 0.1143)
		(layer "In7.Cu")
		(net "P5E_PEX0_STN5_TX_DN<95>")
	)
	(segment
		(start 93.325442 -348.58579)
		(end 93.034612 -348.29496)
		(width 0.1651)
		(layer "In7.Cu")
		(net "P5E_PEX0_STN5_TX_DN<95>")
	)
	(segment
		(start 94.589092 -342.139778)
		(end 93.099382 -338.779612)
		(width 0.1651)
		(layer "In7.Cu")
		(net "P5E_PEX0_STN5_TX_DN<95>")
	)
	(segment
		(start 93.034612 -347.658182)
		(end 94.589092 -346.103702)
		(width 0.1651)
		(layer "In7.Cu")
		(net "P5E_PEX0_STN5_TX_DN<95>")
	)
	(segment
		(start 72.737218 -320.323718)
		(end 72.615806 -320.05016)
		(width 0.1651)
		(layer "In7.Cu")
		(net "P5E_PEX0_STN5_TX_DN<95>")
	)
	(segment
		(start 72.570086 -319.84188)
		(end 72.570086 -313.684412)
		(width 0.1143)
		(layer "In7.Cu")
		(net "P5E_PEX0_STN5_TX_DN<95>")
	)
	(segment
		(start 138.047476 -30.05709)
		(end 137.751566 -30.353)
		(width 0.13462)
		(layer "F.Cu")
		(net "P5E_PEX1_STN2_TX_DN<45>")
	)
	(segment
		(start 137.122662 -30.353)
		(end 136.801352 -30.03169)
		(width 0.13462)
		(layer "F.Cu")
		(net "P5E_PEX1_STN2_TX_DN<45>")
	)
	(segment
		(start 137.751566 -30.353)
		(end 137.122662 -30.353)
		(width 0.13462)
		(layer "F.Cu")
		(net "P5E_PEX1_STN2_TX_DN<45>")
	)
	(segment
		(start 154.529536 -63.149734)
		(end 153.654506 -78.912974)
		(width 0.1651)
		(layer "In11.Cu")
		(net "P5E_PEX1_STN2_TX_DN<45>")
	)
	(segment
		(start 162.17392 -278.229568)
		(end 162.335718 -278.229568)
		(width 0.1143)
		(layer "In11.Cu")
		(net "P5E_PEX1_STN2_TX_DN<45>")
	)
	(segment
		(start 162.116008 -271.427448)
		(end 162.070288 -271.473168)
		(width 0.1143)
		(layer "In11.Cu")
		(net "P5E_PEX1_STN2_TX_DN<45>")
	)
	(segment
		(start 162.070288 -278.125936)
		(end 162.17392 -278.229568)
		(width 0.1143)
		(layer "In11.Cu")
		(net "P5E_PEX1_STN2_TX_DN<45>")
	)
	(segment
		(start 162.070288 -271.473168)
		(end 162.070288 -278.125936)
		(width 0.1143)
		(layer "In11.Cu")
		(net "P5E_PEX1_STN2_TX_DN<45>")
	)
	(segment
		(start 138.787886 -30.34792)
		(end 139.368276 -30.58795)
		(width 0.1651)
		(layer "In11.Cu")
		(net "P5E_PEX1_STN2_TX_DN<45>")
	)
	(segment
		(start 138.293094 -30.302708)
		(end 138.40206 -30.34792)
		(width 0.1651)
		(layer "In11.Cu")
		(net "P5E_PEX1_STN2_TX_DN<45>")
	)
	(segment
		(start 162.335718 -278.229568)
		(end 162.450018 -278.115268)
		(width 0.1143)
		(layer "In11.Cu")
		(net "P5E_PEX1_STN2_TX_DN<45>")
	)
	(segment
		(start 162.450018 -278.115268)
		(end 162.450018 -277.849838)
		(width 0.1143)
		(layer "In11.Cu")
		(net "P5E_PEX1_STN2_TX_DN<45>")
	)
	(segment
		(start 153.763218 -50.312828)
		(end 154.529536 -63.149734)
		(width 0.1651)
		(layer "In11.Cu")
		(net "P5E_PEX1_STN2_TX_DN<45>")
	)
	(segment
		(start 140.603478 -31.646114)
		(end 151.176228 -44.917868)
		(width 0.1651)
		(layer "In11.Cu")
		(net "P5E_PEX1_STN2_TX_DN<45>")
	)
	(segment
		(start 138.047476 -30.05709)
		(end 138.293094 -30.302708)
		(width 0.1651)
		(layer "In11.Cu")
		(net "P5E_PEX1_STN2_TX_DN<45>")
	)
	(segment
		(start 162.116008 -271.399)
		(end 162.116008 -271.427448)
		(width 0.1143)
		(layer "In11.Cu")
		(net "P5E_PEX1_STN2_TX_DN<45>")
	)
	(segment
		(start 153.124916 -48.4632)
		(end 153.763218 -50.312828)
		(width 0.1651)
		(layer "In11.Cu")
		(net "P5E_PEX1_STN2_TX_DN<45>")
	)
	(segment
		(start 149.922992 -137.972292)
		(end 161.087308 -264.159746)
		(width 0.1651)
		(layer "In11.Cu")
		(net "P5E_PEX1_STN2_TX_DN<45>")
	)
	(segment
		(start 151.176228 -44.917868)
		(end 153.124916 -48.4632)
		(width 0.1651)
		(layer "In11.Cu")
		(net "P5E_PEX1_STN2_TX_DN<45>")
	)
	(segment
		(start 161.087308 -264.159746)
		(end 162.116008 -270.360902)
		(width 0.1651)
		(layer "In11.Cu")
		(net "P5E_PEX1_STN2_TX_DN<45>")
	)
	(segment
		(start 138.40206 -30.34792)
		(end 138.787886 -30.34792)
		(width 0.1651)
		(layer "In11.Cu")
		(net "P5E_PEX1_STN2_TX_DN<45>")
	)
	(segment
		(start 150.02383 -105.234486)
		(end 149.52091 -116.209572)
		(width 0.1651)
		(layer "In11.Cu")
		(net "P5E_PEX1_STN2_TX_DN<45>")
	)
	(segment
		(start 153.654506 -78.912974)
		(end 150.02383 -105.234486)
		(width 0.1651)
		(layer "In11.Cu")
		(net "P5E_PEX1_STN2_TX_DN<45>")
	)
	(segment
		(start 139.368276 -30.58795)
		(end 140.603478 -31.646114)
		(width 0.1651)
		(layer "In11.Cu")
		(net "P5E_PEX1_STN2_TX_DN<45>")
	)
	(segment
		(start 149.52091 -116.209572)
		(end 149.922992 -137.972292)
		(width 0.1651)
		(layer "In11.Cu")
		(net "P5E_PEX1_STN2_TX_DN<45>")
	)
	(segment
		(start 162.116008 -270.360902)
		(end 162.116008 -271.399)
		(width 0.1651)
		(layer "In11.Cu")
		(net "P5E_PEX1_STN2_TX_DN<45>")
	)
	(segment
		(start 328.936604 -349.831914)
		(end 328.616564 -349.511874)
		(width 0.13462)
		(layer "F.Cu")
		(net "P5E_PEX2_STN6_TX_DN<104>")
	)
	(segment
		(start 328.616564 -348.88043)
		(end 328.911204 -348.58579)
		(width 0.13462)
		(layer "F.Cu")
		(net "P5E_PEX2_STN6_TX_DN<104>")
	)
	(segment
		(start 328.616564 -349.511874)
		(end 328.616564 -348.88043)
		(width 0.13462)
		(layer "F.Cu")
		(net "P5E_PEX2_STN6_TX_DN<104>")
	)
	(segment
		(start 292.089586 -328.794872)
		(end 291.60343 -328.699368)
		(width 0.1651)
		(layer "In13.Cu")
		(net "P5E_PEX2_STN6_TX_DN<104>")
	)
	(segment
		(start 328.911204 -348.58579)
		(end 328.620374 -348.29496)
		(width 0.1651)
		(layer "In13.Cu")
		(net "P5E_PEX2_STN6_TX_DN<104>")
	)
	(segment
		(start 292.16985 -328.914252)
		(end 292.089586 -328.794872)
		(width 0.1651)
		(layer "In13.Cu")
		(net "P5E_PEX2_STN6_TX_DN<104>")
	)
	(segment
		(start 329.6666 -341.2998)
		(end 327.3806 -338.963)
		(width 0.1651)
		(layer "In13.Cu")
		(net "P5E_PEX2_STN6_TX_DN<104>")
	)
	(segment
		(start 282.015692 -319.966848)
		(end 281.969972 -319.921128)
		(width 0.1143)
		(layer "In13.Cu")
		(net "P5E_PEX2_STN6_TX_DN<104>")
	)
	(segment
		(start 285.28772 -327.56094)
		(end 282.499054 -324.772274)
		(width 0.1651)
		(layer "In13.Cu")
		(net "P5E_PEX2_STN6_TX_DN<104>")
	)
	(segment
		(start 291.60343 -328.699368)
		(end 291.48405 -328.779378)
		(width 0.1651)
		(layer "In13.Cu")
		(net "P5E_PEX2_STN6_TX_DN<104>")
	)
	(segment
		(start 328.620374 -348.29496)
		(end 328.620374 -347.784674)
		(width 0.1651)
		(layer "In13.Cu")
		(net "P5E_PEX2_STN6_TX_DN<104>")
	)
	(segment
		(start 282.235402 -313.570112)
		(end 282.349702 -313.684412)
		(width 0.1143)
		(layer "In13.Cu")
		(net "P5E_PEX2_STN6_TX_DN<104>")
	)
	(segment
		(start 330.174854 -346.230194)
		(end 330.174854 -342.1126)
		(width 0.1651)
		(layer "In13.Cu")
		(net "P5E_PEX2_STN6_TX_DN<104>")
	)
	(segment
		(start 327.3806 -338.963)
		(end 315.000894 -333.40421)
		(width 0.1651)
		(layer "In13.Cu")
		(net "P5E_PEX2_STN6_TX_DN<104>")
	)
	(segment
		(start 282.073604 -313.570112)
		(end 282.235402 -313.570112)
		(width 0.1143)
		(layer "In13.Cu")
		(net "P5E_PEX2_STN6_TX_DN<104>")
	)
	(segment
		(start 282.015692 -323.605398)
		(end 282.015692 -319.995296)
		(width 0.1651)
		(layer "In13.Cu")
		(net "P5E_PEX2_STN6_TX_DN<104>")
	)
	(segment
		(start 315.000894 -333.40421)
		(end 292.16985 -328.914252)
		(width 0.1651)
		(layer "In13.Cu")
		(net "P5E_PEX2_STN6_TX_DN<104>")
	)
	(segment
		(start 282.499054 -324.772274)
		(end 282.015692 -323.605398)
		(width 0.1651)
		(layer "In13.Cu")
		(net "P5E_PEX2_STN6_TX_DN<104>")
	)
	(segment
		(start 281.969972 -313.673744)
		(end 282.073604 -313.570112)
		(width 0.1143)
		(layer "In13.Cu")
		(net "P5E_PEX2_STN6_TX_DN<104>")
	)
	(segment
		(start 291.48405 -328.779378)
		(end 285.28772 -327.56094)
		(width 0.1651)
		(layer "In13.Cu")
		(net "P5E_PEX2_STN6_TX_DN<104>")
	)
	(segment
		(start 282.349702 -313.684412)
		(end 282.349702 -313.949842)
		(width 0.1143)
		(layer "In13.Cu")
		(net "P5E_PEX2_STN6_TX_DN<104>")
	)
	(segment
		(start 330.174854 -342.1126)
		(end 329.6666 -341.2998)
		(width 0.1651)
		(layer "In13.Cu")
		(net "P5E_PEX2_STN6_TX_DN<104>")
	)
	(segment
		(start 328.620374 -347.784674)
		(end 330.174854 -346.230194)
		(width 0.1651)
		(layer "In13.Cu")
		(net "P5E_PEX2_STN6_TX_DN<104>")
	)
	(segment
		(start 282.015692 -319.995296)
		(end 282.015692 -319.966848)
		(width 0.1143)
		(layer "In13.Cu")
		(net "P5E_PEX2_STN6_TX_DN<104>")
	)
	(segment
		(start 281.969972 -319.921128)
		(end 281.969972 -313.673744)
		(width 0.1143)
		(layer "In13.Cu")
		(net "P5E_PEX2_STN6_TX_DN<104>")
	)
	(segment
		(start 383.4257 -108.32084)
		(end 383.72034 -108.61548)
		(width 0.13462)
		(layer "F.Cu")
		(net "P5E_PEX3_STN1_TX_DN<21>")
	)
	(segment
		(start 383.72034 -108.61548)
		(end 384.351784 -108.61548)
		(width 0.13462)
		(layer "F.Cu")
		(net "P5E_PEX3_STN1_TX_DN<21>")
	)
	(segment
		(start 384.351784 -108.61548)
		(end 384.671824 -108.29544)
		(width 0.13462)
		(layer "F.Cu")
		(net "P5E_PEX3_STN1_TX_DN<21>")
	)
	(segment
		(start 412.34487 -280.319988)
		(end 412.585662 -280.319988)
		(width 0.1143)
		(layer "In9.Cu")
		(net "P5E_PEX3_STN1_TX_DN<21>")
	)
	(segment
		(start 412.084012 -271.526)
		(end 412.084012 -271.554448)
		(width 0.1143)
		(layer "In9.Cu")
		(net "P5E_PEX3_STN1_TX_DN<21>")
	)
	(segment
		(start 375.912634 -144.22882)
		(end 376.456448 -155.297378)
		(width 0.1651)
		(layer "In9.Cu")
		(net "P5E_PEX3_STN1_TX_DN<21>")
	)
	(segment
		(start 373.343932 -131.276852)
		(end 373.343932 -138.027156)
		(width 0.1651)
		(layer "In9.Cu")
		(net "P5E_PEX3_STN1_TX_DN<21>")
	)
	(segment
		(start 377.218702 -161.917634)
		(end 412.084012 -264.919968)
		(width 0.1651)
		(layer "In9.Cu")
		(net "P5E_PEX3_STN1_TX_DN<21>")
	)
	(segment
		(start 376.638566 -159.000952)
		(end 377.218702 -161.917634)
		(width 0.1651)
		(layer "In9.Cu")
		(net "P5E_PEX3_STN1_TX_DN<21>")
	)
	(segment
		(start 380.747778 -110.246668)
		(end 376.919744 -119.487696)
		(width 0.1651)
		(layer "In9.Cu")
		(net "P5E_PEX3_STN1_TX_DN<21>")
	)
	(segment
		(start 412.699962 -280.434288)
		(end 412.699962 -280.699718)
		(width 0.1143)
		(layer "In9.Cu")
		(net "P5E_PEX3_STN1_TX_DN<21>")
	)
	(segment
		(start 412.129732 -271.600168)
		(end 412.129732 -280.10485)
		(width 0.1143)
		(layer "In9.Cu")
		(net "P5E_PEX3_STN1_TX_DN<21>")
	)
	(segment
		(start 412.084012 -264.919968)
		(end 412.084012 -271.526)
		(width 0.1651)
		(layer "In9.Cu")
		(net "P5E_PEX3_STN1_TX_DN<21>")
	)
	(segment
		(start 376.919744 -119.487696)
		(end 373.343932 -131.276852)
		(width 0.1651)
		(layer "In9.Cu")
		(net "P5E_PEX3_STN1_TX_DN<21>")
	)
	(segment
		(start 412.585662 -280.319988)
		(end 412.699962 -280.434288)
		(width 0.1143)
		(layer "In9.Cu")
		(net "P5E_PEX3_STN1_TX_DN<21>")
	)
	(segment
		(start 412.129732 -280.10485)
		(end 412.34487 -280.319988)
		(width 0.1143)
		(layer "In9.Cu")
		(net "P5E_PEX3_STN1_TX_DN<21>")
	)
	(segment
		(start 412.084012 -271.554448)
		(end 412.129732 -271.600168)
		(width 0.1143)
		(layer "In9.Cu")
		(net "P5E_PEX3_STN1_TX_DN<21>")
	)
	(segment
		(start 383.4257 -108.32084)
		(end 383.13487 -108.61167)
		(width 0.1651)
		(layer "In9.Cu")
		(net "P5E_PEX3_STN1_TX_DN<21>")
	)
	(segment
		(start 380.747778 -110.216188)
		(end 380.747778 -110.246668)
		(width 0.1651)
		(layer "In9.Cu")
		(net "P5E_PEX3_STN1_TX_DN<21>")
	)
	(segment
		(start 376.456448 -155.297378)
		(end 376.638566 -159.000952)
		(width 0.1651)
		(layer "In9.Cu")
		(net "P5E_PEX3_STN1_TX_DN<21>")
	)
	(segment
		(start 373.343932 -138.027156)
		(end 375.912634 -144.22882)
		(width 0.1651)
		(layer "In9.Cu")
		(net "P5E_PEX3_STN1_TX_DN<21>")
	)
	(segment
		(start 382.352296 -108.61167)
		(end 380.747778 -110.216188)
		(width 0.1651)
		(layer "In9.Cu")
		(net "P5E_PEX3_STN1_TX_DN<21>")
	)
	(segment
		(start 383.13487 -108.61167)
		(end 382.352296 -108.61167)
		(width 0.1651)
		(layer "In9.Cu")
		(net "P5E_PEX3_STN1_TX_DN<21>")
	)
	(segment
		(start 421.705532 -355.978206)
		(end 422.025064 -355.658674)
		(width 0.13462)
		(layer "F.Cu")
		(net "P5E_PEX3_STN7_TX_DP<118>")
	)
	(segment
		(start 422.025064 -355.026214)
		(end 421.730932 -354.732082)
		(width 0.13462)
		(layer "F.Cu")
		(net "P5E_PEX3_STN7_TX_DP<118>")
	)
	(segment
		(start 422.025064 -355.658674)
		(end 422.025064 -355.026214)
		(width 0.13462)
		(layer "F.Cu")
		(net "P5E_PEX3_STN7_TX_DP<118>")
	)
	(segment
		(start 373.166132 -326.349106)
		(end 371.705378 -324.888352)
		(width 0.1651)
		(layer "In11.Cu")
		(net "P5E_PEX3_STN7_TX_DP<118>")
	)
	(segment
		(start 383.949448 -306.683918)
		(end 383.995168 -306.729638)
		(width 0.1143)
		(layer "In11.Cu")
		(net "P5E_PEX3_STN7_TX_DP<118>")
	)
	(segment
		(start 422.021762 -354.441252)
		(end 422.021762 -353.814126)
		(width 0.1651)
		(layer "In11.Cu")
		(net "P5E_PEX3_STN7_TX_DP<118>")
	)
	(segment
		(start 423.576242 -341.748872)
		(end 422.639998 -339.916008)
		(width 0.1651)
		(layer "In11.Cu")
		(net "P5E_PEX3_STN7_TX_DP<118>")
	)
	(segment
		(start 370.926614 -318.537844)
		(end 372.935754 -315.531246)
		(width 0.1651)
		(layer "In11.Cu")
		(net "P5E_PEX3_STN7_TX_DP<118>")
	)
	(segment
		(start 371.705378 -324.888352)
		(end 370.58346 -322.179696)
		(width 0.1651)
		(layer "In11.Cu")
		(net "P5E_PEX3_STN7_TX_DP<118>")
	)
	(segment
		(start 380.98095 -307.48605)
		(end 382.917192 -306.683918)
		(width 0.1651)
		(layer "In11.Cu")
		(net "P5E_PEX3_STN7_TX_DP<118>")
	)
	(segment
		(start 390.254998 -306.729638)
		(end 390.470136 -306.944776)
		(width 0.1143)
		(layer "In11.Cu")
		(net "P5E_PEX3_STN7_TX_DP<118>")
	)
	(segment
		(start 422.639998 -339.916008)
		(end 419.2651 -337.55965)
		(width 0.1651)
		(layer "In11.Cu")
		(net "P5E_PEX3_STN7_TX_DP<118>")
	)
	(segment
		(start 390.470136 -307.185568)
		(end 390.584436 -307.299868)
		(width 0.1143)
		(layer "In11.Cu")
		(net "P5E_PEX3_STN7_TX_DP<118>")
	)
	(segment
		(start 383.921 -306.683918)
		(end 383.949448 -306.683918)
		(width 0.1143)
		(layer "In11.Cu")
		(net "P5E_PEX3_STN7_TX_DP<118>")
	)
	(segment
		(start 372.935754 -315.531246)
		(end 380.98095 -307.48605)
		(width 0.1651)
		(layer "In11.Cu")
		(net "P5E_PEX3_STN7_TX_DP<118>")
	)
	(segment
		(start 382.917192 -306.683918)
		(end 383.921 -306.683918)
		(width 0.1651)
		(layer "In11.Cu")
		(net "P5E_PEX3_STN7_TX_DP<118>")
	)
	(segment
		(start 370.58346 -322.179696)
		(end 370.58346 -319.366646)
		(width 0.1651)
		(layer "In11.Cu")
		(net "P5E_PEX3_STN7_TX_DP<118>")
	)
	(segment
		(start 370.58346 -319.366646)
		(end 370.926614 -318.537844)
		(width 0.1651)
		(layer "In11.Cu")
		(net "P5E_PEX3_STN7_TX_DP<118>")
	)
	(segment
		(start 421.730932 -354.732082)
		(end 422.021762 -354.441252)
		(width 0.1651)
		(layer "In11.Cu")
		(net "P5E_PEX3_STN7_TX_DP<118>")
	)
	(segment
		(start 390.584436 -307.299868)
		(end 390.849866 -307.299868)
		(width 0.1143)
		(layer "In11.Cu")
		(net "P5E_PEX3_STN7_TX_DP<118>")
	)
	(segment
		(start 375.674128 -327.73112)
		(end 373.166132 -326.349106)
		(width 0.1651)
		(layer "In11.Cu")
		(net "P5E_PEX3_STN7_TX_DP<118>")
	)
	(segment
		(start 423.576242 -352.259646)
		(end 423.576242 -341.748872)
		(width 0.1651)
		(layer "In11.Cu")
		(net "P5E_PEX3_STN7_TX_DP<118>")
	)
	(segment
		(start 390.470136 -306.944776)
		(end 390.470136 -307.185568)
		(width 0.1143)
		(layer "In11.Cu")
		(net "P5E_PEX3_STN7_TX_DP<118>")
	)
	(segment
		(start 422.021762 -353.814126)
		(end 423.576242 -352.259646)
		(width 0.1651)
		(layer "In11.Cu")
		(net "P5E_PEX3_STN7_TX_DP<118>")
	)
	(segment
		(start 383.995168 -306.729638)
		(end 390.254998 -306.729638)
		(width 0.1143)
		(layer "In11.Cu")
		(net "P5E_PEX3_STN7_TX_DP<118>")
	)
	(segment
		(start 419.2651 -337.55965)
		(end 375.674128 -327.73112)
		(width 0.1651)
		(layer "In11.Cu")
		(net "P5E_PEX3_STN7_TX_DP<118>")
	)
	(segment
		(start 89.921842 -355.658166)
		(end 89.921842 -355.026722)
		(width 0.13462)
		(layer "F.Cu")
		(net "P5E_PEX0_STN5_TX_DN<94>")
	)
	(segment
		(start 90.241882 -355.978206)
		(end 89.921842 -355.658166)
		(width 0.13462)
		(layer "F.Cu")
		(net "P5E_PEX0_STN5_TX_DN<94>")
	)
	(segment
		(start 89.921842 -355.026722)
		(end 90.216482 -354.732082)
		(width 0.13462)
		(layer "F.Cu")
		(net "P5E_PEX0_STN5_TX_DN<94>")
	)
	(segment
		(start 89.925652 -354.441252)
		(end 89.925652 -353.942142)
		(width 0.1651)
		(layer "In7.Cu")
		(net "P5E_PEX0_STN5_TX_DN<94>")
	)
	(segment
		(start 71.665846 -319.916048)
		(end 71.665846 -319.8876)
		(width 0.1143)
		(layer "In7.Cu")
		(net "P5E_PEX0_STN5_TX_DN<94>")
	)
	(segment
		(start 71.885556 -311.670192)
		(end 71.999856 -311.784492)
		(width 0.1143)
		(layer "In7.Cu")
		(net "P5E_PEX0_STN5_TX_DN<94>")
	)
	(segment
		(start 71.787258 -320.648076)
		(end 71.665846 -320.35496)
		(width 0.1651)
		(layer "In7.Cu")
		(net "P5E_PEX0_STN5_TX_DN<94>")
	)
	(segment
		(start 71.665846 -319.8876)
		(end 71.620126 -319.84188)
		(width 0.1143)
		(layer "In7.Cu")
		(net "P5E_PEX0_STN5_TX_DN<94>")
	)
	(segment
		(start 91.480132 -341.506302)
		(end 90.805762 -339.878162)
		(width 0.1651)
		(layer "In7.Cu")
		(net "P5E_PEX0_STN5_TX_DN<94>")
	)
	(segment
		(start 71.999856 -311.784492)
		(end 71.999856 -312.049922)
		(width 0.1143)
		(layer "In7.Cu")
		(net "P5E_PEX0_STN5_TX_DN<94>")
	)
	(segment
		(start 71.620126 -319.84188)
		(end 71.620126 -311.784492)
		(width 0.1143)
		(layer "In7.Cu")
		(net "P5E_PEX0_STN5_TX_DN<94>")
	)
	(segment
		(start 71.665846 -320.35496)
		(end 71.665846 -319.916048)
		(width 0.1651)
		(layer "In7.Cu")
		(net "P5E_PEX0_STN5_TX_DN<94>")
	)
	(segment
		(start 91.480132 -352.387662)
		(end 91.480132 -341.506302)
		(width 0.1651)
		(layer "In7.Cu")
		(net "P5E_PEX0_STN5_TX_DN<94>")
	)
	(segment
		(start 71.734426 -311.670192)
		(end 71.885556 -311.670192)
		(width 0.1143)
		(layer "In7.Cu")
		(net "P5E_PEX0_STN5_TX_DN<94>")
	)
	(segment
		(start 90.216482 -354.732082)
		(end 89.925652 -354.441252)
		(width 0.1651)
		(layer "In7.Cu")
		(net "P5E_PEX0_STN5_TX_DN<94>")
	)
	(segment
		(start 90.805762 -339.878162)
		(end 72.213978 -321.286378)
		(width 0.1651)
		(layer "In7.Cu")
		(net "P5E_PEX0_STN5_TX_DN<94>")
	)
	(segment
		(start 72.213978 -321.286378)
		(end 71.787258 -320.648076)
		(width 0.1651)
		(layer "In7.Cu")
		(net "P5E_PEX0_STN5_TX_DN<94>")
	)
	(segment
		(start 71.620126 -311.784492)
		(end 71.734426 -311.670192)
		(width 0.1143)
		(layer "In7.Cu")
		(net "P5E_PEX0_STN5_TX_DN<94>")
	)
	(segment
		(start 89.925652 -353.942142)
		(end 91.480132 -352.387662)
		(width 0.1651)
		(layer "In7.Cu")
		(net "P5E_PEX0_STN5_TX_DN<94>")
	)
	(segment
		(start 213.405212 -32.714184)
		(end 213.101428 -32.4104)
		(width 0.13462)
		(layer "F.Cu")
		(net "P5E_PEX1_STN2_TX_DP<34>")
	)
	(segment
		(start 212.488272 -32.4104)
		(end 212.159088 -32.739584)
		(width 0.13462)
		(layer "F.Cu")
		(net "P5E_PEX1_STN2_TX_DP<34>")
	)
	(segment
		(start 213.101428 -32.4104)
		(end 212.488272 -32.4104)
		(width 0.13462)
		(layer "F.Cu")
		(net "P5E_PEX1_STN2_TX_DP<34>")
	)
	(segment
		(start 172.54474 -280.319988)
		(end 172.329602 -280.10485)
		(width 0.1143)
		(layer "In11.Cu")
		(net "P5E_PEX1_STN2_TX_DP<34>")
	)
	(segment
		(start 215.81745 -32.537654)
		(end 215.32215 -32.537654)
		(width 0.1651)
		(layer "In11.Cu")
		(net "P5E_PEX1_STN2_TX_DP<34>")
	)
	(segment
		(start 221.070424 -68.191126)
		(end 223.278192 -56.729376)
		(width 0.1651)
		(layer "In11.Cu")
		(net "P5E_PEX1_STN2_TX_DP<34>")
	)
	(segment
		(start 172.283882 -271.399)
		(end 172.283882 -265.641074)
		(width 0.1651)
		(layer "In11.Cu")
		(net "P5E_PEX1_STN2_TX_DP<34>")
	)
	(segment
		(start 172.329602 -280.10485)
		(end 172.329602 -271.473168)
		(width 0.1143)
		(layer "In11.Cu")
		(net "P5E_PEX1_STN2_TX_DP<34>")
	)
	(segment
		(start 172.899832 -280.434288)
		(end 172.785532 -280.319988)
		(width 0.1143)
		(layer "In11.Cu")
		(net "P5E_PEX1_STN2_TX_DP<34>")
	)
	(segment
		(start 172.899832 -280.699718)
		(end 172.899832 -280.434288)
		(width 0.1143)
		(layer "In11.Cu")
		(net "P5E_PEX1_STN2_TX_DP<34>")
	)
	(segment
		(start 191.453262 -161.396426)
		(end 192.870328 -149.389084)
		(width 0.1651)
		(layer "In11.Cu")
		(net "P5E_PEX1_STN2_TX_DP<34>")
	)
	(segment
		(start 209.837782 -80.550258)
		(end 211.84362 -78.546452)
		(width 0.1651)
		(layer "In11.Cu")
		(net "P5E_PEX1_STN2_TX_DP<34>")
	)
	(segment
		(start 194.221862 -118.35638)
		(end 195.029836 -111.806228)
		(width 0.1651)
		(layer "In11.Cu")
		(net "P5E_PEX1_STN2_TX_DP<34>")
	)
	(segment
		(start 223.278192 -56.729376)
		(end 223.028002 -42.691304)
		(width 0.1651)
		(layer "In11.Cu")
		(net "P5E_PEX1_STN2_TX_DP<34>")
	)
	(segment
		(start 218.334844 -75.047094)
		(end 218.865196 -74.293984)
		(width 0.1651)
		(layer "In11.Cu")
		(net "P5E_PEX1_STN2_TX_DP<34>")
	)
	(segment
		(start 202.845162 -92.873068)
		(end 209.837782 -80.550258)
		(width 0.1651)
		(layer "In11.Cu")
		(net "P5E_PEX1_STN2_TX_DP<34>")
	)
	(segment
		(start 215.20785 -32.423354)
		(end 213.696042 -32.423354)
		(width 0.1651)
		(layer "In11.Cu")
		(net "P5E_PEX1_STN2_TX_DP<34>")
	)
	(segment
		(start 172.283882 -271.427448)
		(end 172.283882 -271.399)
		(width 0.1143)
		(layer "In11.Cu")
		(net "P5E_PEX1_STN2_TX_DP<34>")
	)
	(segment
		(start 172.283882 -265.641074)
		(end 191.453262 -161.396426)
		(width 0.1651)
		(layer "In11.Cu")
		(net "P5E_PEX1_STN2_TX_DP<34>")
	)
	(segment
		(start 195.843906 -105.211118)
		(end 202.844908 -92.873068)
		(width 0.1651)
		(layer "In11.Cu")
		(net "P5E_PEX1_STN2_TX_DP<34>")
	)
	(segment
		(start 213.696042 -32.423354)
		(end 213.405212 -32.714184)
		(width 0.1651)
		(layer "In11.Cu")
		(net "P5E_PEX1_STN2_TX_DP<34>")
	)
	(segment
		(start 195.029836 -111.806228)
		(end 195.03009 -111.806228)
		(width 0.1651)
		(layer "In11.Cu")
		(net "P5E_PEX1_STN2_TX_DP<34>")
	)
	(segment
		(start 193.199004 -141.845284)
		(end 193.605912 -140.100304)
		(width 0.1651)
		(layer "In11.Cu")
		(net "P5E_PEX1_STN2_TX_DP<34>")
	)
	(segment
		(start 193.605912 -132.507228)
		(end 194.221862 -118.35638)
		(width 0.1651)
		(layer "In11.Cu")
		(net "P5E_PEX1_STN2_TX_DP<34>")
	)
	(segment
		(start 215.32215 -32.537654)
		(end 215.20785 -32.423354)
		(width 0.1651)
		(layer "In11.Cu")
		(net "P5E_PEX1_STN2_TX_DP<34>")
	)
	(segment
		(start 172.329602 -271.473168)
		(end 172.283882 -271.427448)
		(width 0.1143)
		(layer "In11.Cu")
		(net "P5E_PEX1_STN2_TX_DP<34>")
	)
	(segment
		(start 223.028002 -42.691304)
		(end 222.816674 -41.890696)
		(width 0.1651)
		(layer "In11.Cu")
		(net "P5E_PEX1_STN2_TX_DP<34>")
	)
	(segment
		(start 218.543632 -34.038286)
		(end 216.945464 -32.423354)
		(width 0.1651)
		(layer "In11.Cu")
		(net "P5E_PEX1_STN2_TX_DP<34>")
	)
	(segment
		(start 195.03009 -111.806228)
		(end 195.843906 -105.211118)
		(width 0.1651)
		(layer "In11.Cu")
		(net "P5E_PEX1_STN2_TX_DP<34>")
	)
	(segment
		(start 222.816674 -41.890696)
		(end 218.543632 -34.038286)
		(width 0.1651)
		(layer "In11.Cu")
		(net "P5E_PEX1_STN2_TX_DP<34>")
	)
	(segment
		(start 211.84362 -78.546452)
		(end 218.334844 -75.047094)
		(width 0.1651)
		(layer "In11.Cu")
		(net "P5E_PEX1_STN2_TX_DP<34>")
	)
	(segment
		(start 172.785532 -280.319988)
		(end 172.54474 -280.319988)
		(width 0.1143)
		(layer "In11.Cu")
		(net "P5E_PEX1_STN2_TX_DP<34>")
	)
	(segment
		(start 192.870328 -149.389084)
		(end 193.199004 -141.845284)
		(width 0.1651)
		(layer "In11.Cu")
		(net "P5E_PEX1_STN2_TX_DP<34>")
	)
	(segment
		(start 202.844908 -92.873068)
		(end 202.845162 -92.873068)
		(width 0.1651)
		(layer "In11.Cu")
		(net "P5E_PEX1_STN2_TX_DP<34>")
	)
	(segment
		(start 216.945464 -32.423354)
		(end 215.93175 -32.423354)
		(width 0.1651)
		(layer "In11.Cu")
		(net "P5E_PEX1_STN2_TX_DP<34>")
	)
	(segment
		(start 215.93175 -32.423354)
		(end 215.81745 -32.537654)
		(width 0.1651)
		(layer "In11.Cu")
		(net "P5E_PEX1_STN2_TX_DP<34>")
	)
	(segment
		(start 193.605912 -140.100304)
		(end 193.605912 -132.507228)
		(width 0.1651)
		(layer "In11.Cu")
		(net "P5E_PEX1_STN2_TX_DP<34>")
	)
	(segment
		(start 218.865196 -74.293984)
		(end 221.070424 -68.191126)
		(width 0.1651)
		(layer "In11.Cu")
		(net "P5E_PEX1_STN2_TX_DP<34>")
	)
	(segment
		(start 293.063422 -349.511874)
		(end 293.063422 -348.88043)
		(width 0.13462)
		(layer "F.Cu")
		(net "P5E_PEX2_STN7_TX_DP<124>")
	)
	(segment
		(start 293.063422 -348.88043)
		(end 292.768782 -348.58579)
		(width 0.13462)
		(layer "F.Cu")
		(net "P5E_PEX2_STN7_TX_DP<124>")
	)
	(segment
		(start 292.743382 -349.831914)
		(end 293.063422 -349.511874)
		(width 0.13462)
		(layer "F.Cu")
		(net "P5E_PEX2_STN7_TX_DP<124>")
	)
	(segment
		(start 293.059612 -347.667834)
		(end 294.614092 -346.113354)
		(width 0.1651)
		(layer "In7.Cu")
		(net "P5E_PEX2_STN7_TX_DP<124>")
	)
	(segment
		(start 292.768782 -348.58579)
		(end 293.059612 -348.29496)
		(width 0.1651)
		(layer "In7.Cu")
		(net "P5E_PEX2_STN7_TX_DP<124>")
	)
	(segment
		(start 294.614092 -342.1888)
		(end 294.512492 -342.03005)
		(width 0.1651)
		(layer "In7.Cu")
		(net "P5E_PEX2_STN7_TX_DP<124>")
	)
	(segment
		(start 271.329658 -311.705498)
		(end 271.555464 -311.479692)
		(width 0.1143)
		(layer "In7.Cu")
		(net "P5E_PEX2_STN7_TX_DP<124>")
	)
	(segment
		(start 271.283938 -319.941448)
		(end 271.283938 -319.913)
		(width 0.1143)
		(layer "In7.Cu")
		(net "P5E_PEX2_STN7_TX_DP<124>")
	)
	(segment
		(start 293.059612 -348.29496)
		(end 293.059612 -347.667834)
		(width 0.1651)
		(layer "In7.Cu")
		(net "P5E_PEX2_STN7_TX_DP<124>")
	)
	(segment
		(start 272.001742 -322.971922)
		(end 271.283938 -321.23888)
		(width 0.1651)
		(layer "In7.Cu")
		(net "P5E_PEX2_STN7_TX_DP<124>")
	)
	(segment
		(start 271.329658 -319.86728)
		(end 271.329658 -311.705498)
		(width 0.1143)
		(layer "In7.Cu")
		(net "P5E_PEX2_STN7_TX_DP<124>")
	)
	(segment
		(start 294.614092 -346.113354)
		(end 294.614092 -342.1888)
		(width 0.1651)
		(layer "In7.Cu")
		(net "P5E_PEX2_STN7_TX_DP<124>")
	)
	(segment
		(start 271.283938 -321.23888)
		(end 271.283938 -319.941448)
		(width 0.1651)
		(layer "In7.Cu")
		(net "P5E_PEX2_STN7_TX_DP<124>")
	)
	(segment
		(start 271.283938 -319.913)
		(end 271.329658 -319.86728)
		(width 0.1143)
		(layer "In7.Cu")
		(net "P5E_PEX2_STN7_TX_DP<124>")
	)
	(segment
		(start 272.305018 -323.275198)
		(end 272.001742 -322.971922)
		(width 0.1651)
		(layer "In7.Cu")
		(net "P5E_PEX2_STN7_TX_DP<124>")
	)
	(segment
		(start 294.512492 -342.03005)
		(end 294.2082 -341.5538)
		(width 0.1651)
		(layer "In7.Cu")
		(net "P5E_PEX2_STN7_TX_DP<124>")
	)
	(segment
		(start 271.555464 -311.479692)
		(end 271.785588 -311.479692)
		(width 0.1143)
		(layer "In7.Cu")
		(net "P5E_PEX2_STN7_TX_DP<124>")
	)
	(segment
		(start 271.785588 -311.479692)
		(end 271.899888 -311.365392)
		(width 0.1143)
		(layer "In7.Cu")
		(net "P5E_PEX2_STN7_TX_DP<124>")
	)
	(segment
		(start 271.899888 -311.365392)
		(end 271.899888 -311.099962)
		(width 0.1143)
		(layer "In7.Cu")
		(net "P5E_PEX2_STN7_TX_DP<124>")
	)
	(segment
		(start 294.2082 -341.5538)
		(end 272.305018 -323.275198)
		(width 0.1651)
		(layer "In7.Cu")
		(net "P5E_PEX2_STN7_TX_DP<124>")
	)
	(segment
		(start 431.547016 -148.31568)
		(end 431.228246 -147.99691)
		(width 0.13462)
		(layer "F.Cu")
		(net "P5E_PEX3_STN0_TX_DN<11>")
	)
	(segment
		(start 432.181 -148.31568)
		(end 431.547016 -148.31568)
		(width 0.13462)
		(layer "F.Cu")
		(net "P5E_PEX3_STN0_TX_DN<11>")
	)
	(segment
		(start 432.47437 -148.02231)
		(end 432.181 -148.31568)
		(width 0.13462)
		(layer "F.Cu")
		(net "P5E_PEX3_STN0_TX_DN<11>")
	)
	(segment
		(start 426.949616 -278.115268)
		(end 426.949616 -277.849838)
		(width 0.1143)
		(layer "In9.Cu")
		(net "P5E_PEX3_STN0_TX_DN<11>")
	)
	(segment
		(start 426.57014 -271.546066)
		(end 426.57014 -278.12619)
		(width 0.1143)
		(layer "In9.Cu")
		(net "P5E_PEX3_STN0_TX_DN<11>")
	)
	(segment
		(start 426.61586 -271.471898)
		(end 426.61586 -271.500346)
		(width 0.1143)
		(layer "In9.Cu")
		(net "P5E_PEX3_STN0_TX_DN<11>")
	)
	(segment
		(start 433.569872 -148.31314)
		(end 435.108858 -149.852126)
		(width 0.1651)
		(layer "In9.Cu")
		(net "P5E_PEX3_STN0_TX_DN<11>")
	)
	(segment
		(start 429.46066 -172.248576)
		(end 428.104808 -177.303684)
		(width 0.1651)
		(layer "In9.Cu")
		(net "P5E_PEX3_STN0_TX_DN<11>")
	)
	(segment
		(start 432.7652 -148.31314)
		(end 433.569872 -148.31314)
		(width 0.1651)
		(layer "In9.Cu")
		(net "P5E_PEX3_STN0_TX_DN<11>")
	)
	(segment
		(start 427.561248 -260.775704)
		(end 427.561248 -268.64691)
		(width 0.1651)
		(layer "In9.Cu")
		(net "P5E_PEX3_STN0_TX_DN<11>")
	)
	(segment
		(start 426.835316 -278.229568)
		(end 426.949616 -278.115268)
		(width 0.1143)
		(layer "In9.Cu")
		(net "P5E_PEX3_STN0_TX_DN<11>")
	)
	(segment
		(start 436.690008 -152.22601)
		(end 437.82234 -154.959558)
		(width 0.1651)
		(layer "In9.Cu")
		(net "P5E_PEX3_STN0_TX_DN<11>")
	)
	(segment
		(start 426.673518 -278.229568)
		(end 426.835316 -278.229568)
		(width 0.1143)
		(layer "In9.Cu")
		(net "P5E_PEX3_STN0_TX_DN<11>")
	)
	(segment
		(start 437.82234 -157.763464)
		(end 429.46066 -172.248576)
		(width 0.1651)
		(layer "In9.Cu")
		(net "P5E_PEX3_STN0_TX_DN<11>")
	)
	(segment
		(start 428.104808 -177.303684)
		(end 424.182794 -222.13189)
		(width 0.1651)
		(layer "In9.Cu")
		(net "P5E_PEX3_STN0_TX_DN<11>")
	)
	(segment
		(start 426.57014 -278.12619)
		(end 426.673518 -278.229568)
		(width 0.1143)
		(layer "In9.Cu")
		(net "P5E_PEX3_STN0_TX_DN<11>")
	)
	(segment
		(start 427.561248 -268.64691)
		(end 426.61586 -270.929608)
		(width 0.1651)
		(layer "In9.Cu")
		(net "P5E_PEX3_STN0_TX_DN<11>")
	)
	(segment
		(start 435.108858 -149.852126)
		(end 435.108858 -149.859746)
		(width 0.1651)
		(layer "In9.Cu")
		(net "P5E_PEX3_STN0_TX_DN<11>")
	)
	(segment
		(start 426.61586 -271.500346)
		(end 426.57014 -271.546066)
		(width 0.1143)
		(layer "In9.Cu")
		(net "P5E_PEX3_STN0_TX_DN<11>")
	)
	(segment
		(start 437.82234 -154.959558)
		(end 437.82234 -157.763464)
		(width 0.1651)
		(layer "In9.Cu")
		(net "P5E_PEX3_STN0_TX_DN<11>")
	)
	(segment
		(start 424.182794 -222.13189)
		(end 427.561248 -260.775704)
		(width 0.1651)
		(layer "In9.Cu")
		(net "P5E_PEX3_STN0_TX_DN<11>")
	)
	(segment
		(start 435.108858 -149.859746)
		(end 436.690008 -152.22601)
		(width 0.1651)
		(layer "In9.Cu")
		(net "P5E_PEX3_STN0_TX_DN<11>")
	)
	(segment
		(start 432.47437 -148.02231)
		(end 432.7652 -148.31314)
		(width 0.1651)
		(layer "In9.Cu")
		(net "P5E_PEX3_STN0_TX_DN<11>")
	)
	(segment
		(start 426.61586 -270.929608)
		(end 426.61586 -271.471898)
		(width 0.1651)
		(layer "In9.Cu")
		(net "P5E_PEX3_STN0_TX_DN<11>")
	)
	(segment
		(start 409.269692 -343.685622)
		(end 409.589224 -343.36609)
		(width 0.13462)
		(layer "F.Cu")
		(net "P5E_PEX3_STN7_TX_DP<112>")
	)
	(segment
		(start 409.589224 -342.73363)
		(end 409.295092 -342.439498)
		(width 0.13462)
		(layer "F.Cu")
		(net "P5E_PEX3_STN7_TX_DP<112>")
	)
	(segment
		(start 409.589224 -343.36609)
		(end 409.589224 -342.73363)
		(width 0.13462)
		(layer "F.Cu")
		(net "P5E_PEX3_STN7_TX_DP<112>")
	)
	(segment
		(start 373.158766 -333.371698)
		(end 369.55984 -331.404214)
		(width 0.1651)
		(layer "In11.Cu")
		(net "P5E_PEX3_STN7_TX_DP<112>")
	)
	(segment
		(start 390.470136 -301.485554)
		(end 390.584436 -301.599854)
		(width 0.1143)
		(layer "In11.Cu")
		(net "P5E_PEX3_STN7_TX_DP<112>")
	)
	(segment
		(start 390.254998 -301.029624)
		(end 390.470136 -301.244762)
		(width 0.1143)
		(layer "In11.Cu")
		(net "P5E_PEX3_STN7_TX_DP<112>")
	)
	(segment
		(start 409.585922 -341.693246)
		(end 409.406344 -341.291418)
		(width 0.1651)
		(layer "In11.Cu")
		(net "P5E_PEX3_STN7_TX_DP<112>")
	)
	(segment
		(start 369.55984 -331.404214)
		(end 366.413034 -328.257408)
		(width 0.1651)
		(layer "In11.Cu")
		(net "P5E_PEX3_STN7_TX_DP<112>")
	)
	(segment
		(start 384.683 -300.983904)
		(end 384.72872 -301.029624)
		(width 0.1143)
		(layer "In11.Cu")
		(net "P5E_PEX3_STN7_TX_DP<112>")
	)
	(segment
		(start 371.71757 -305.32705)
		(end 374.799098 -302.245522)
		(width 0.1651)
		(layer "In11.Cu")
		(net "P5E_PEX3_STN7_TX_DP<112>")
	)
	(segment
		(start 374.829578 -302.245522)
		(end 377.875546 -300.983904)
		(width 0.1651)
		(layer "In11.Cu")
		(net "P5E_PEX3_STN7_TX_DP<112>")
	)
	(segment
		(start 364.22838 -318.296544)
		(end 366.14735 -313.663584)
		(width 0.1651)
		(layer "In11.Cu")
		(net "P5E_PEX3_STN7_TX_DP<112>")
	)
	(segment
		(start 409.406344 -341.291418)
		(end 373.158766 -333.371698)
		(width 0.1651)
		(layer "In11.Cu")
		(net "P5E_PEX3_STN7_TX_DP<112>")
	)
	(segment
		(start 384.654552 -300.983904)
		(end 384.683 -300.983904)
		(width 0.1143)
		(layer "In11.Cu")
		(net "P5E_PEX3_STN7_TX_DP<112>")
	)
	(segment
		(start 364.22838 -322.982844)
		(end 364.22838 -318.296544)
		(width 0.1651)
		(layer "In11.Cu")
		(net "P5E_PEX3_STN7_TX_DP<112>")
	)
	(segment
		(start 374.799098 -302.245522)
		(end 374.829578 -302.245522)
		(width 0.1651)
		(layer "In11.Cu")
		(net "P5E_PEX3_STN7_TX_DP<112>")
	)
	(segment
		(start 366.413034 -328.257408)
		(end 364.22838 -322.982844)
		(width 0.1651)
		(layer "In11.Cu")
		(net "P5E_PEX3_STN7_TX_DP<112>")
	)
	(segment
		(start 390.470136 -301.244762)
		(end 390.470136 -301.485554)
		(width 0.1143)
		(layer "In11.Cu")
		(net "P5E_PEX3_STN7_TX_DP<112>")
	)
	(segment
		(start 384.72872 -301.029624)
		(end 390.254998 -301.029624)
		(width 0.1143)
		(layer "In11.Cu")
		(net "P5E_PEX3_STN7_TX_DP<112>")
	)
	(segment
		(start 409.295092 -342.439498)
		(end 409.585922 -342.148668)
		(width 0.1651)
		(layer "In11.Cu")
		(net "P5E_PEX3_STN7_TX_DP<112>")
	)
	(segment
		(start 366.14735 -313.663584)
		(end 371.71757 -305.32705)
		(width 0.1651)
		(layer "In11.Cu")
		(net "P5E_PEX3_STN7_TX_DP<112>")
	)
	(segment
		(start 377.875546 -300.983904)
		(end 384.654552 -300.983904)
		(width 0.1651)
		(layer "In11.Cu")
		(net "P5E_PEX3_STN7_TX_DP<112>")
	)
	(segment
		(start 390.584436 -301.599854)
		(end 390.849866 -301.599854)
		(width 0.1143)
		(layer "In11.Cu")
		(net "P5E_PEX3_STN7_TX_DP<112>")
	)
	(segment
		(start 409.585922 -342.148668)
		(end 409.585922 -341.693246)
		(width 0.1651)
		(layer "In11.Cu")
		(net "P5E_PEX3_STN7_TX_DP<112>")
	)
	(segment
		(start 73.782682 -349.831914)
		(end 74.102722 -349.511874)
		(width 0.13462)
		(layer "F.Cu")
		(net "P5E_PEX0_STN5_TX_DP<86>")
	)
	(segment
		(start 74.102722 -349.511874)
		(end 74.102722 -348.88043)
		(width 0.13462)
		(layer "F.Cu")
		(net "P5E_PEX0_STN5_TX_DP<86>")
	)
	(segment
		(start 74.102722 -348.88043)
		(end 73.808082 -348.58579)
		(width 0.13462)
		(layer "F.Cu")
		(net "P5E_PEX0_STN5_TX_DP<86>")
	)
	(segment
		(start 74.098912 -347.541342)
		(end 75.653392 -345.986862)
		(width 0.1651)
		(layer "In7.Cu")
		(net "P5E_PEX0_STN5_TX_DP<86>")
	)
	(segment
		(start 75.653392 -345.986862)
		(end 75.653392 -341.108792)
		(width 0.1651)
		(layer "In7.Cu")
		(net "P5E_PEX0_STN5_TX_DP<86>")
	)
	(segment
		(start 75.653392 -341.108792)
		(end 69.431916 -331.798168)
		(width 0.1651)
		(layer "In7.Cu")
		(net "P5E_PEX0_STN5_TX_DP<86>")
	)
	(segment
		(start 64.172084 -323.798692)
		(end 63.783972 -322.860924)
		(width 0.1651)
		(layer "In7.Cu")
		(net "P5E_PEX0_STN5_TX_DP<86>")
	)
	(segment
		(start 64.055498 -311.479692)
		(end 64.285622 -311.479692)
		(width 0.1143)
		(layer "In7.Cu")
		(net "P5E_PEX0_STN5_TX_DP<86>")
	)
	(segment
		(start 64.399922 -311.365392)
		(end 64.399922 -311.099962)
		(width 0.1143)
		(layer "In7.Cu")
		(net "P5E_PEX0_STN5_TX_DP<86>")
	)
	(segment
		(start 73.808082 -348.58579)
		(end 74.098912 -348.29496)
		(width 0.1651)
		(layer "In7.Cu")
		(net "P5E_PEX0_STN5_TX_DP<86>")
	)
	(segment
		(start 74.098912 -348.29496)
		(end 74.098912 -347.541342)
		(width 0.1651)
		(layer "In7.Cu")
		(net "P5E_PEX0_STN5_TX_DP<86>")
	)
	(segment
		(start 64.285622 -311.479692)
		(end 64.399922 -311.365392)
		(width 0.1143)
		(layer "In7.Cu")
		(net "P5E_PEX0_STN5_TX_DP<86>")
	)
	(segment
		(start 63.829692 -311.705498)
		(end 64.055498 -311.479692)
		(width 0.1143)
		(layer "In7.Cu")
		(net "P5E_PEX0_STN5_TX_DP<86>")
	)
	(segment
		(start 66.349372 -327.641966)
		(end 64.172084 -323.798692)
		(width 0.1651)
		(layer "In7.Cu")
		(net "P5E_PEX0_STN5_TX_DP<86>")
	)
	(segment
		(start 63.783972 -319.8876)
		(end 63.829692 -319.84188)
		(width 0.1143)
		(layer "In7.Cu")
		(net "P5E_PEX0_STN5_TX_DP<86>")
	)
	(segment
		(start 69.431916 -331.798168)
		(end 66.349372 -327.641966)
		(width 0.1651)
		(layer "In7.Cu")
		(net "P5E_PEX0_STN5_TX_DP<86>")
	)
	(segment
		(start 63.783972 -322.860924)
		(end 63.783972 -319.916048)
		(width 0.1651)
		(layer "In7.Cu")
		(net "P5E_PEX0_STN5_TX_DP<86>")
	)
	(segment
		(start 63.783972 -319.916048)
		(end 63.783972 -319.8876)
		(width 0.1143)
		(layer "In7.Cu")
		(net "P5E_PEX0_STN5_TX_DP<86>")
	)
	(segment
		(start 63.829692 -319.84188)
		(end 63.829692 -311.705498)
		(width 0.1143)
		(layer "In7.Cu")
		(net "P5E_PEX0_STN5_TX_DP<86>")
	)
	(segment
		(start 130.810508 -342.734138)
		(end 130.515868 -342.439498)
		(width 0.13462)
		(layer "F.Cu")
		(net "P5E_PEX1_STN5_TX_DP<88>")
	)
	(segment
		(start 130.810508 -343.365582)
		(end 130.810508 -342.734138)
		(width 0.13462)
		(layer "F.Cu")
		(net "P5E_PEX1_STN5_TX_DP<88>")
	)
	(segment
		(start 130.490468 -343.685622)
		(end 130.810508 -343.365582)
		(width 0.13462)
		(layer "F.Cu")
		(net "P5E_PEX1_STN5_TX_DP<88>")
	)
	(segment
		(start 172.005752 -325.680578)
		(end 181.622446 -320.539618)
		(width 0.1651)
		(layer "In13.Cu")
		(net "P5E_PEX1_STN5_TX_DP<88>")
	)
	(segment
		(start 181.622446 -320.539618)
		(end 181.78399 -320.378074)
		(width 0.1651)
		(layer "In13.Cu")
		(net "P5E_PEX1_STN5_TX_DP<88>")
	)
	(segment
		(start 182.044848 -311.479692)
		(end 182.28564 -311.479692)
		(width 0.1143)
		(layer "In13.Cu")
		(net "P5E_PEX1_STN5_TX_DP<88>")
	)
	(segment
		(start 147.097496 -334.789272)
		(end 163.684966 -329.260708)
		(width 0.1651)
		(layer "In13.Cu")
		(net "P5E_PEX1_STN5_TX_DP<88>")
	)
	(segment
		(start 130.806698 -342.148668)
		(end 130.806698 -341.135462)
		(width 0.1651)
		(layer "In13.Cu")
		(net "P5E_PEX1_STN5_TX_DP<88>")
	)
	(segment
		(start 181.82971 -311.69483)
		(end 182.044848 -311.479692)
		(width 0.1143)
		(layer "In13.Cu")
		(net "P5E_PEX1_STN5_TX_DP<88>")
	)
	(segment
		(start 181.78399 -320.068448)
		(end 181.78399 -320.04)
		(width 0.1143)
		(layer "In13.Cu")
		(net "P5E_PEX1_STN5_TX_DP<88>")
	)
	(segment
		(start 167.84574 -327.470516)
		(end 172.005752 -325.680578)
		(width 0.1651)
		(layer "In13.Cu")
		(net "P5E_PEX1_STN5_TX_DP<88>")
	)
	(segment
		(start 181.78399 -320.378074)
		(end 181.78399 -320.068448)
		(width 0.1651)
		(layer "In13.Cu")
		(net "P5E_PEX1_STN5_TX_DP<88>")
	)
	(segment
		(start 133.683502 -338.258658)
		(end 142.05966 -334.789272)
		(width 0.1651)
		(layer "In13.Cu")
		(net "P5E_PEX1_STN5_TX_DP<88>")
	)
	(segment
		(start 182.39994 -311.365392)
		(end 182.39994 -311.099962)
		(width 0.1143)
		(layer "In13.Cu")
		(net "P5E_PEX1_STN5_TX_DP<88>")
	)
	(segment
		(start 181.82971 -319.99428)
		(end 181.82971 -311.69483)
		(width 0.1143)
		(layer "In13.Cu")
		(net "P5E_PEX1_STN5_TX_DP<88>")
	)
	(segment
		(start 181.78399 -320.04)
		(end 181.82971 -319.99428)
		(width 0.1143)
		(layer "In13.Cu")
		(net "P5E_PEX1_STN5_TX_DP<88>")
	)
	(segment
		(start 142.05966 -334.789272)
		(end 147.097496 -334.789272)
		(width 0.1651)
		(layer "In13.Cu")
		(net "P5E_PEX1_STN5_TX_DP<88>")
	)
	(segment
		(start 163.684966 -329.260708)
		(end 167.845486 -327.470516)
		(width 0.1651)
		(layer "In13.Cu")
		(net "P5E_PEX1_STN5_TX_DP<88>")
	)
	(segment
		(start 130.806698 -341.135462)
		(end 133.683502 -338.258658)
		(width 0.1651)
		(layer "In13.Cu")
		(net "P5E_PEX1_STN5_TX_DP<88>")
	)
	(segment
		(start 130.515868 -342.439498)
		(end 130.806698 -342.148668)
		(width 0.1651)
		(layer "In13.Cu")
		(net "P5E_PEX1_STN5_TX_DP<88>")
	)
	(segment
		(start 167.845486 -327.470516)
		(end 167.84574 -327.470516)
		(width 0.1651)
		(layer "In13.Cu")
		(net "P5E_PEX1_STN5_TX_DP<88>")
	)
	(segment
		(start 182.28564 -311.479692)
		(end 182.39994 -311.365392)
		(width 0.1143)
		(layer "In13.Cu")
		(net "P5E_PEX1_STN5_TX_DP<88>")
	)
	(segment
		(start 284.330902 -355.978206)
		(end 284.010862 -355.658166)
		(width 0.13462)
		(layer "F.Cu")
		(net "P5E_PEX2_STN7_TX_DN<120>")
	)
	(segment
		(start 284.010862 -355.026722)
		(end 284.305502 -354.732082)
		(width 0.13462)
		(layer "F.Cu")
		(net "P5E_PEX2_STN7_TX_DN<120>")
	)
	(segment
		(start 284.010862 -355.658166)
		(end 284.010862 -355.026722)
		(width 0.13462)
		(layer "F.Cu")
		(net "P5E_PEX2_STN7_TX_DN<120>")
	)
	(segment
		(start 260.034278 -315.28639)
		(end 260.034278 -315.286136)
		(width 0.1651)
		(layer "In7.Cu")
		(net "P5E_PEX2_STN7_TX_DN<120>")
	)
	(segment
		(start 266.735306 -309.399686)
		(end 267.734034 -308.865778)
		(width 0.1651)
		(layer "In7.Cu")
		(net "P5E_PEX2_STN7_TX_DN<120>")
	)
	(segment
		(start 262.518398 -327.03643)
		(end 262.363966 -327.083928)
		(width 0.1651)
		(layer "In7.Cu")
		(net "P5E_PEX2_STN7_TX_DN<120>")
	)
	(segment
		(start 257.557016 -318.159638)
		(end 258.068318 -317.566548)
		(width 0.1651)
		(layer "In7.Cu")
		(net "P5E_PEX2_STN7_TX_DN<120>")
	)
	(segment
		(start 257.394964 -323.469762)
		(end 256.72034 -321.841114)
		(width 0.1651)
		(layer "In7.Cu")
		(net "P5E_PEX2_STN7_TX_DN<120>")
	)
	(segment
		(start 264.045446 -327.877424)
		(end 263.557766 -327.618852)
		(width 0.1651)
		(layer "In7.Cu")
		(net "P5E_PEX2_STN7_TX_DN<120>")
	)
	(segment
		(start 274.065238 -309.199788)
		(end 273.799808 -309.199788)
		(width 0.1143)
		(layer "In7.Cu")
		(net "P5E_PEX2_STN7_TX_DN<120>")
	)
	(segment
		(start 262.363966 -327.083928)
		(end 261.926324 -326.85228)
		(width 0.1651)
		(layer "In7.Cu")
		(net "P5E_PEX2_STN7_TX_DN<120>")
	)
	(segment
		(start 259.118862 -325.364856)
		(end 257.394964 -323.469762)
		(width 0.1651)
		(layer "In7.Cu")
		(net "P5E_PEX2_STN7_TX_DN<120>")
	)
	(segment
		(start 258.068572 -317.566548)
		(end 258.193794 -317.55715)
		(width 0.1651)
		(layer "In7.Cu")
		(net "P5E_PEX2_STN7_TX_DN<120>")
	)
	(segment
		(start 258.068318 -317.566548)
		(end 258.068572 -317.566548)
		(width 0.1651)
		(layer "In7.Cu")
		(net "P5E_PEX2_STN7_TX_DN<120>")
	)
	(segment
		(start 274.179538 -308.934358)
		(end 274.179538 -309.085488)
		(width 0.1143)
		(layer "In7.Cu")
		(net "P5E_PEX2_STN7_TX_DN<120>")
	)
	(segment
		(start 274.179538 -309.085488)
		(end 274.065238 -309.199788)
		(width 0.1143)
		(layer "In7.Cu")
		(net "P5E_PEX2_STN7_TX_DN<120>")
	)
	(segment
		(start 264.79119 -311.110122)
		(end 265.27379 -310.71439)
		(width 0.1651)
		(layer "In7.Cu")
		(net "P5E_PEX2_STN7_TX_DN<120>")
	)
	(segment
		(start 260.627876 -314.597796)
		(end 263.889998 -311.712356)
		(width 0.1651)
		(layer "In7.Cu")
		(net "P5E_PEX2_STN7_TX_DN<120>")
	)
	(segment
		(start 261.389622 -326.48144)
		(end 261.286498 -326.51319)
		(width 0.1651)
		(layer "In7.Cu")
		(net "P5E_PEX2_STN7_TX_DN<120>")
	)
	(segment
		(start 285.265876 -340.908894)
		(end 276.228302 -334.428846)
		(width 0.1651)
		(layer "In7.Cu")
		(net "P5E_PEX2_STN7_TX_DN<120>")
	)
	(segment
		(start 260.043676 -315.411612)
		(end 260.034278 -315.28639)
		(width 0.1651)
		(layer "In7.Cu")
		(net "P5E_PEX2_STN7_TX_DN<120>")
	)
	(segment
		(start 258.95681 -316.672214)
		(end 259.28066 -316.296802)
		(width 0.1651)
		(layer "In7.Cu")
		(net "P5E_PEX2_STN7_TX_DN<120>")
	)
	(segment
		(start 267.839952 -308.865778)
		(end 267.8684 -308.865778)
		(width 0.1143)
		(layer "In7.Cu")
		(net "P5E_PEX2_STN7_TX_DN<120>")
	)
	(segment
		(start 258.831588 -316.681612)
		(end 258.95681 -316.672214)
		(width 0.1651)
		(layer "In7.Cu")
		(net "P5E_PEX2_STN7_TX_DN<120>")
	)
	(segment
		(start 263.003792 -327.423018)
		(end 262.956294 -327.268586)
		(width 0.1651)
		(layer "In7.Cu")
		(net "P5E_PEX2_STN7_TX_DN<120>")
	)
	(segment
		(start 259.594604 -315.796422)
		(end 259.719826 -315.787024)
		(width 0.1651)
		(layer "In7.Cu")
		(net "P5E_PEX2_STN7_TX_DN<120>")
	)
	(segment
		(start 256.72034 -320.167)
		(end 257.557016 -318.159638)
		(width 0.1651)
		(layer "In7.Cu")
		(net "P5E_PEX2_STN7_TX_DN<120>")
	)
	(segment
		(start 266.293092 -309.695088)
		(end 266.735306 -309.399686)
		(width 0.1651)
		(layer "In7.Cu")
		(net "P5E_PEX2_STN7_TX_DN<120>")
	)
	(segment
		(start 267.734034 -308.865778)
		(end 267.839952 -308.865778)
		(width 0.1651)
		(layer "In7.Cu")
		(net "P5E_PEX2_STN7_TX_DN<120>")
	)
	(segment
		(start 261.894574 -326.748902)
		(end 261.389622 -326.48144)
		(width 0.1651)
		(layer "In7.Cu")
		(net "P5E_PEX2_STN7_TX_DN<120>")
	)
	(segment
		(start 258.51739 -317.181738)
		(end 258.508246 -317.056516)
		(width 0.1651)
		(layer "In7.Cu")
		(net "P5E_PEX2_STN7_TX_DN<120>")
	)
	(segment
		(start 267.91412 -308.820058)
		(end 274.065238 -308.820058)
		(width 0.1143)
		(layer "In7.Cu")
		(net "P5E_PEX2_STN7_TX_DN<120>")
	)
	(segment
		(start 265.27379 -310.71439)
		(end 266.293092 -309.695088)
		(width 0.1651)
		(layer "In7.Cu")
		(net "P5E_PEX2_STN7_TX_DN<120>")
	)
	(segment
		(start 260.034278 -315.286136)
		(end 260.627876 -314.597796)
		(width 0.1651)
		(layer "In7.Cu")
		(net "P5E_PEX2_STN7_TX_DN<120>")
	)
	(segment
		(start 263.441434 -327.654666)
		(end 263.003792 -327.423018)
		(width 0.1651)
		(layer "In7.Cu")
		(net "P5E_PEX2_STN7_TX_DN<120>")
	)
	(segment
		(start 285.569152 -352.376486)
		(end 285.569152 -341.410036)
		(width 0.1651)
		(layer "In7.Cu")
		(net "P5E_PEX2_STN7_TX_DN<120>")
	)
	(segment
		(start 274.065238 -308.820058)
		(end 274.179538 -308.934358)
		(width 0.1143)
		(layer "In7.Cu")
		(net "P5E_PEX2_STN7_TX_DN<120>")
	)
	(segment
		(start 263.889998 -311.712356)
		(end 264.79119 -311.110122)
		(width 0.1651)
		(layer "In7.Cu")
		(net "P5E_PEX2_STN7_TX_DN<120>")
	)
	(segment
		(start 261.286498 -326.51319)
		(end 259.118862 -325.364856)
		(width 0.1651)
		(layer "In7.Cu")
		(net "P5E_PEX2_STN7_TX_DN<120>")
	)
	(segment
		(start 262.956294 -327.268586)
		(end 262.518398 -327.03643)
		(width 0.1651)
		(layer "In7.Cu")
		(net "P5E_PEX2_STN7_TX_DN<120>")
	)
	(segment
		(start 259.719826 -315.787024)
		(end 260.043676 -315.411612)
		(width 0.1651)
		(layer "In7.Cu")
		(net "P5E_PEX2_STN7_TX_DN<120>")
	)
	(segment
		(start 263.557766 -327.618852)
		(end 263.441434 -327.654666)
		(width 0.1651)
		(layer "In7.Cu")
		(net "P5E_PEX2_STN7_TX_DN<120>")
	)
	(segment
		(start 267.8684 -308.865778)
		(end 267.91412 -308.820058)
		(width 0.1143)
		(layer "In7.Cu")
		(net "P5E_PEX2_STN7_TX_DN<120>")
	)
	(segment
		(start 258.508246 -317.056516)
		(end 258.831588 -316.681612)
		(width 0.1651)
		(layer "In7.Cu")
		(net "P5E_PEX2_STN7_TX_DN<120>")
	)
	(segment
		(start 264.08126 -327.993756)
		(end 264.045446 -327.877424)
		(width 0.1651)
		(layer "In7.Cu")
		(net "P5E_PEX2_STN7_TX_DN<120>")
	)
	(segment
		(start 258.193794 -317.55715)
		(end 258.51739 -317.181738)
		(width 0.1651)
		(layer "In7.Cu")
		(net "P5E_PEX2_STN7_TX_DN<120>")
	)
	(segment
		(start 256.72034 -321.841114)
		(end 256.72034 -320.167)
		(width 0.1651)
		(layer "In7.Cu")
		(net "P5E_PEX2_STN7_TX_DN<120>")
	)
	(segment
		(start 261.926324 -326.85228)
		(end 261.894574 -326.748902)
		(width 0.1651)
		(layer "In7.Cu")
		(net "P5E_PEX2_STN7_TX_DN<120>")
	)
	(segment
		(start 285.569152 -341.410036)
		(end 285.265876 -340.908894)
		(width 0.1651)
		(layer "In7.Cu")
		(net "P5E_PEX2_STN7_TX_DN<120>")
	)
	(segment
		(start 259.28066 -316.296802)
		(end 259.271262 -316.171326)
		(width 0.1651)
		(layer "In7.Cu")
		(net "P5E_PEX2_STN7_TX_DN<120>")
	)
	(segment
		(start 284.014672 -354.441252)
		(end 284.014672 -353.930966)
		(width 0.1651)
		(layer "In7.Cu")
		(net "P5E_PEX2_STN7_TX_DN<120>")
	)
	(segment
		(start 259.271262 -316.171326)
		(end 259.594604 -315.796422)
		(width 0.1651)
		(layer "In7.Cu")
		(net "P5E_PEX2_STN7_TX_DN<120>")
	)
	(segment
		(start 284.014672 -353.930966)
		(end 285.569152 -352.376486)
		(width 0.1651)
		(layer "In7.Cu")
		(net "P5E_PEX2_STN7_TX_DN<120>")
	)
	(segment
		(start 284.305502 -354.732082)
		(end 284.014672 -354.441252)
		(width 0.1651)
		(layer "In7.Cu")
		(net "P5E_PEX2_STN7_TX_DN<120>")
	)
	(segment
		(start 276.228302 -334.428846)
		(end 264.08126 -327.993756)
		(width 0.1651)
		(layer "In7.Cu")
		(net "P5E_PEX2_STN7_TX_DN<120>")
	)
	(segment
		(start 387.007608 -136.4234)
		(end 387.313932 -136.729724)
		(width 0.13462)
		(layer "F.Cu")
		(net "P5E_PEX3_STN1_TX_DP<31>")
	)
	(segment
		(start 386.067808 -136.704324)
		(end 386.348732 -136.4234)
		(width 0.13462)
		(layer "F.Cu")
		(net "P5E_PEX3_STN1_TX_DP<31>")
	)
	(segment
		(start 386.348732 -136.4234)
		(end 387.007608 -136.4234)
		(width 0.13462)
		(layer "F.Cu")
		(net "P5E_PEX3_STN1_TX_DP<31>")
	)
	(segment
		(start 387.509512 -143.50873)
		(end 387.389624 -143.42872)
		(width 0.1651)
		(layer "In9.Cu")
		(net "P5E_PEX3_STN1_TX_DP<31>")
	)
	(segment
		(start 387.044184 -141.16685)
		(end 386.924296 -141.08684)
		(width 0.1651)
		(layer "In9.Cu")
		(net "P5E_PEX3_STN1_TX_DP<31>")
	)
	(segment
		(start 386.694172 -139.928346)
		(end 386.590794 -139.407392)
		(width 0.1651)
		(layer "In9.Cu")
		(net "P5E_PEX3_STN1_TX_DP<31>")
	)
	(segment
		(start 387.854952 -145.7706)
		(end 387.758686 -145.284952)
		(width 0.1651)
		(layer "In9.Cu")
		(net "P5E_PEX3_STN1_TX_DP<31>")
	)
	(segment
		(start 387.14045 -141.652752)
		(end 387.044184 -141.16685)
		(width 0.1651)
		(layer "In9.Cu")
		(net "P5E_PEX3_STN1_TX_DP<31>")
	)
	(segment
		(start 421.865806 -271.526)
		(end 421.865806 -262.564118)
		(width 0.1651)
		(layer "In9.Cu")
		(net "P5E_PEX3_STN1_TX_DP<31>")
	)
	(segment
		(start 421.820086 -271.600168)
		(end 421.865806 -271.554448)
		(width 0.1143)
		(layer "In9.Cu")
		(net "P5E_PEX3_STN1_TX_DP<31>")
	)
	(segment
		(start 421.865806 -262.564118)
		(end 395.697456 -185.260488)
		(width 0.1651)
		(layer "In9.Cu")
		(net "P5E_PEX3_STN1_TX_DP<31>")
	)
	(segment
		(start 388.224014 -147.626832)
		(end 388.30377 -147.507452)
		(width 0.1651)
		(layer "In9.Cu")
		(net "P5E_PEX3_STN1_TX_DP<31>")
	)
	(segment
		(start 422.199816 -279.749504)
		(end 422.199816 -280.015188)
		(width 0.1143)
		(layer "In9.Cu")
		(net "P5E_PEX3_STN1_TX_DP<31>")
	)
	(segment
		(start 387.758686 -145.284952)
		(end 387.838442 -145.165572)
		(width 0.1651)
		(layer "In9.Cu")
		(net "P5E_PEX3_STN1_TX_DP<31>")
	)
	(segment
		(start 385.452112 -137.480802)
		(end 385.308602 -137.480802)
		(width 0.1651)
		(layer "In9.Cu")
		(net "P5E_PEX3_STN1_TX_DP<31>")
	)
	(segment
		(start 385.793742 -137.822178)
		(end 385.452112 -137.480802)
		(width 0.1651)
		(layer "In9.Cu")
		(net "P5E_PEX3_STN1_TX_DP<31>")
	)
	(segment
		(start 387.99135 -146.455892)
		(end 388.071106 -146.336512)
		(width 0.1651)
		(layer "In9.Cu")
		(net "P5E_PEX3_STN1_TX_DP<31>")
	)
	(segment
		(start 388.461504 -148.822918)
		(end 388.55142 -148.688552)
		(width 0.1651)
		(layer "In9.Cu")
		(net "P5E_PEX3_STN1_TX_DP<31>")
	)
	(segment
		(start 386.813806 -140.008102)
		(end 386.694172 -139.928346)
		(width 0.1651)
		(layer "In9.Cu")
		(net "P5E_PEX3_STN1_TX_DP<31>")
	)
	(segment
		(start 387.97484 -145.85061)
		(end 387.854952 -145.7706)
		(width 0.1651)
		(layer "In9.Cu")
		(net "P5E_PEX3_STN1_TX_DP<31>")
	)
	(segment
		(start 385.793742 -137.965942)
		(end 385.793742 -137.822178)
		(width 0.1651)
		(layer "In9.Cu")
		(net "P5E_PEX3_STN1_TX_DP<31>")
	)
	(segment
		(start 387.276848 -142.33779)
		(end 387.15696 -142.25778)
		(width 0.1651)
		(layer "In9.Cu")
		(net "P5E_PEX3_STN1_TX_DP<31>")
	)
	(segment
		(start 386.907786 -140.481812)
		(end 386.813806 -140.008102)
		(width 0.1651)
		(layer "In9.Cu")
		(net "P5E_PEX3_STN1_TX_DP<31>")
	)
	(segment
		(start 387.526022 -144.114012)
		(end 387.605778 -143.994632)
		(width 0.1651)
		(layer "In9.Cu")
		(net "P5E_PEX3_STN1_TX_DP<31>")
	)
	(segment
		(start 388.32028 -148.11248)
		(end 388.224014 -147.626832)
		(width 0.1651)
		(layer "In9.Cu")
		(net "P5E_PEX3_STN1_TX_DP<31>")
	)
	(segment
		(start 387.15696 -142.25778)
		(end 387.060694 -141.772132)
		(width 0.1651)
		(layer "In9.Cu")
		(net "P5E_PEX3_STN1_TX_DP<31>")
	)
	(segment
		(start 388.30377 -147.507452)
		(end 388.207504 -147.02155)
		(width 0.1651)
		(layer "In9.Cu")
		(net "P5E_PEX3_STN1_TX_DP<31>")
	)
	(segment
		(start 385.308602 -137.480802)
		(end 384.93954 -137.11174)
		(width 0.1651)
		(layer "In9.Cu")
		(net "P5E_PEX3_STN1_TX_DP<31>")
	)
	(segment
		(start 388.071106 -146.336512)
		(end 387.97484 -145.85061)
		(width 0.1651)
		(layer "In9.Cu")
		(net "P5E_PEX3_STN1_TX_DP<31>")
	)
	(segment
		(start 386.924296 -141.08684)
		(end 386.82803 -140.601192)
		(width 0.1651)
		(layer "In9.Cu")
		(net "P5E_PEX3_STN1_TX_DP<31>")
	)
	(segment
		(start 421.923718 -280.129488)
		(end 421.820086 -280.025856)
		(width 0.1143)
		(layer "In9.Cu")
		(net "P5E_PEX3_STN1_TX_DP<31>")
	)
	(segment
		(start 388.087616 -146.94154)
		(end 387.99135 -146.455892)
		(width 0.1651)
		(layer "In9.Cu")
		(net "P5E_PEX3_STN1_TX_DP<31>")
	)
	(segment
		(start 388.4549 -148.202396)
		(end 388.32028 -148.11248)
		(width 0.1651)
		(layer "In9.Cu")
		(net "P5E_PEX3_STN1_TX_DP<31>")
	)
	(segment
		(start 386.82803 -140.601192)
		(end 386.907786 -140.481812)
		(width 0.1651)
		(layer "In9.Cu")
		(net "P5E_PEX3_STN1_TX_DP<31>")
	)
	(segment
		(start 421.865806 -271.554448)
		(end 421.865806 -271.526)
		(width 0.1143)
		(layer "In9.Cu")
		(net "P5E_PEX3_STN1_TX_DP<31>")
	)
	(segment
		(start 387.293358 -142.943072)
		(end 387.373114 -142.823692)
		(width 0.1651)
		(layer "In9.Cu")
		(net "P5E_PEX3_STN1_TX_DP<31>")
	)
	(segment
		(start 385.776978 -136.413494)
		(end 386.067808 -136.704324)
		(width 0.1651)
		(layer "In9.Cu")
		(net "P5E_PEX3_STN1_TX_DP<31>")
	)
	(segment
		(start 387.373114 -142.823692)
		(end 387.276848 -142.33779)
		(width 0.1651)
		(layer "In9.Cu")
		(net "P5E_PEX3_STN1_TX_DP<31>")
	)
	(segment
		(start 387.742176 -144.67967)
		(end 387.622288 -144.59966)
		(width 0.1651)
		(layer "In9.Cu")
		(net "P5E_PEX3_STN1_TX_DP<31>")
	)
	(segment
		(start 422.199816 -280.015188)
		(end 422.085516 -280.129488)
		(width 0.1143)
		(layer "In9.Cu")
		(net "P5E_PEX3_STN1_TX_DP<31>")
	)
	(segment
		(start 384.93954 -137.11174)
		(end 384.93954 -136.641586)
		(width 0.1651)
		(layer "In9.Cu")
		(net "P5E_PEX3_STN1_TX_DP<31>")
	)
	(segment
		(start 387.605778 -143.994632)
		(end 387.509512 -143.50873)
		(width 0.1651)
		(layer "In9.Cu")
		(net "P5E_PEX3_STN1_TX_DP<31>")
	)
	(segment
		(start 387.622288 -144.59966)
		(end 387.526022 -144.114012)
		(width 0.1651)
		(layer "In9.Cu")
		(net "P5E_PEX3_STN1_TX_DP<31>")
	)
	(segment
		(start 422.085516 -280.129488)
		(end 421.923718 -280.129488)
		(width 0.1143)
		(layer "In9.Cu")
		(net "P5E_PEX3_STN1_TX_DP<31>")
	)
	(segment
		(start 385.167632 -136.413494)
		(end 385.776978 -136.413494)
		(width 0.1651)
		(layer "In9.Cu")
		(net "P5E_PEX3_STN1_TX_DP<31>")
	)
	(segment
		(start 386.590794 -139.407392)
		(end 386.134864 -138.307064)
		(width 0.1651)
		(layer "In9.Cu")
		(net "P5E_PEX3_STN1_TX_DP<31>")
	)
	(segment
		(start 387.838442 -145.165572)
		(end 387.742176 -144.67967)
		(width 0.1651)
		(layer "In9.Cu")
		(net "P5E_PEX3_STN1_TX_DP<31>")
	)
	(segment
		(start 421.820086 -280.025856)
		(end 421.820086 -271.600168)
		(width 0.1143)
		(layer "In9.Cu")
		(net "P5E_PEX3_STN1_TX_DP<31>")
	)
	(segment
		(start 395.697456 -185.260488)
		(end 388.461504 -148.822918)
		(width 0.1651)
		(layer "In9.Cu")
		(net "P5E_PEX3_STN1_TX_DP<31>")
	)
	(segment
		(start 388.55142 -148.688552)
		(end 388.4549 -148.202396)
		(width 0.1651)
		(layer "In9.Cu")
		(net "P5E_PEX3_STN1_TX_DP<31>")
	)
	(segment
		(start 384.93954 -136.641586)
		(end 385.167632 -136.413494)
		(width 0.1651)
		(layer "In9.Cu")
		(net "P5E_PEX3_STN1_TX_DP<31>")
	)
	(segment
		(start 386.134864 -138.307064)
		(end 385.793742 -137.965942)
		(width 0.1651)
		(layer "In9.Cu")
		(net "P5E_PEX3_STN1_TX_DP<31>")
	)
	(segment
		(start 387.389624 -143.42872)
		(end 387.293358 -142.943072)
		(width 0.1651)
		(layer "In9.Cu")
		(net "P5E_PEX3_STN1_TX_DP<31>")
	)
	(segment
		(start 388.207504 -147.02155)
		(end 388.087616 -146.94154)
		(width 0.1651)
		(layer "In9.Cu")
		(net "P5E_PEX3_STN1_TX_DP<31>")
	)
	(segment
		(start 387.060694 -141.772132)
		(end 387.14045 -141.652752)
		(width 0.1651)
		(layer "In9.Cu")
		(net "P5E_PEX3_STN1_TX_DP<31>")
	)
	(segment
		(start 431.626264 -349.511366)
		(end 431.626264 -348.880938)
		(width 0.13462)
		(layer "F.Cu")
		(net "P5E_PEX3_STN7_TX_DP<122>")
	)
	(segment
		(start 431.946812 -349.831914)
		(end 431.626264 -349.511366)
		(width 0.13462)
		(layer "F.Cu")
		(net "P5E_PEX3_STN7_TX_DP<122>")
	)
	(segment
		(start 431.626264 -348.880938)
		(end 431.921412 -348.58579)
		(width 0.13462)
		(layer "F.Cu")
		(net "P5E_PEX3_STN7_TX_DP<122>")
	)
	(segment
		(start 431.630582 -348.29496)
		(end 431.630582 -347.784674)
		(width 0.1651)
		(layer "In11.Cu")
		(net "P5E_PEX3_STN7_TX_DP<122>")
	)
	(segment
		(start 385.720082 -315.014102)
		(end 385.834382 -314.899802)
		(width 0.1143)
		(layer "In11.Cu")
		(net "P5E_PEX3_STN7_TX_DP<122>")
	)
	(segment
		(start 385.720082 -318.961262)
		(end 385.720082 -315.014102)
		(width 0.1143)
		(layer "In11.Cu")
		(net "P5E_PEX3_STN7_TX_DP<122>")
	)
	(segment
		(start 385.765802 -319.03543)
		(end 385.765802 -319.006982)
		(width 0.1143)
		(layer "In11.Cu")
		(net "P5E_PEX3_STN7_TX_DP<122>")
	)
	(segment
		(start 385.992624 -323.127624)
		(end 385.765802 -322.58)
		(width 0.1651)
		(layer "In11.Cu")
		(net "P5E_PEX3_STN7_TX_DP<122>")
	)
	(segment
		(start 431.921412 -348.58579)
		(end 431.630582 -348.29496)
		(width 0.1651)
		(layer "In11.Cu")
		(net "P5E_PEX3_STN7_TX_DP<122>")
	)
	(segment
		(start 385.834382 -314.899802)
		(end 386.099812 -314.899802)
		(width 0.1143)
		(layer "In11.Cu")
		(net "P5E_PEX3_STN7_TX_DP<122>")
	)
	(segment
		(start 433.185062 -346.230194)
		(end 433.185062 -342.1888)
		(width 0.1651)
		(layer "In11.Cu")
		(net "P5E_PEX3_STN7_TX_DP<122>")
	)
	(segment
		(start 423.4434 -334.3656)
		(end 387.826758 -324.961758)
		(width 0.1651)
		(layer "In11.Cu")
		(net "P5E_PEX3_STN7_TX_DP<122>")
	)
	(segment
		(start 431.630582 -347.784674)
		(end 433.185062 -346.230194)
		(width 0.1651)
		(layer "In11.Cu")
		(net "P5E_PEX3_STN7_TX_DP<122>")
	)
	(segment
		(start 387.826758 -324.961758)
		(end 385.992624 -323.127624)
		(width 0.1651)
		(layer "In11.Cu")
		(net "P5E_PEX3_STN7_TX_DP<122>")
	)
	(segment
		(start 433.185062 -342.1888)
		(end 432.0286 -340.3346)
		(width 0.1651)
		(layer "In11.Cu")
		(net "P5E_PEX3_STN7_TX_DP<122>")
	)
	(segment
		(start 432.0286 -340.3346)
		(end 423.4434 -334.3656)
		(width 0.1651)
		(layer "In11.Cu")
		(net "P5E_PEX3_STN7_TX_DP<122>")
	)
	(segment
		(start 385.765802 -319.006982)
		(end 385.720082 -318.961262)
		(width 0.1143)
		(layer "In11.Cu")
		(net "P5E_PEX3_STN7_TX_DP<122>")
	)
	(segment
		(start 385.765802 -322.58)
		(end 385.765802 -319.03543)
		(width 0.1651)
		(layer "In11.Cu")
		(net "P5E_PEX3_STN7_TX_DP<122>")
	)
	(segment
		(start 18.370042 -32.13608)
		(end 18.059146 -31.825184)
		(width 0.13462)
		(layer "F.Cu")
		(net "P5E_PEX0_STN2_TX_DN<46>")
	)
	(segment
		(start 19.30527 -31.850584)
		(end 19.019774 -32.13608)
		(width 0.13462)
		(layer "F.Cu")
		(net "P5E_PEX0_STN2_TX_DN<46>")
	)
	(segment
		(start 19.019774 -32.13608)
		(end 18.370042 -32.13608)
		(width 0.13462)
		(layer "F.Cu")
		(net "P5E_PEX0_STN2_TX_DN<46>")
	)
	(segment
		(start 34.793174 -46.401736)
		(end 36.125404 -48.810164)
		(width 0.1651)
		(layer "In11.Cu")
		(net "P5E_PEX0_STN2_TX_DN<46>")
	)
	(segment
		(start 24.396954 -33.387538)
		(end 34.793174 -46.401736)
		(width 0.1651)
		(layer "In11.Cu")
		(net "P5E_PEX0_STN2_TX_DN<46>")
	)
	(segment
		(start 45.06595 -271.399)
		(end 45.06595 -271.427448)
		(width 0.1143)
		(layer "In11.Cu")
		(net "P5E_PEX0_STN2_TX_DN<46>")
	)
	(segment
		(start 36.557966 -78.771496)
		(end 32.979868 -104.96423)
		(width 0.1651)
		(layer "In11.Cu")
		(net "P5E_PEX0_STN2_TX_DN<46>")
	)
	(segment
		(start 45.06595 -271.427448)
		(end 45.02023 -271.473168)
		(width 0.1143)
		(layer "In11.Cu")
		(net "P5E_PEX0_STN2_TX_DN<46>")
	)
	(segment
		(start 45.02023 -280.025856)
		(end 45.123862 -280.129488)
		(width 0.1143)
		(layer "In11.Cu")
		(net "P5E_PEX0_STN2_TX_DN<46>")
	)
	(segment
		(start 45.39996 -280.015188)
		(end 45.39996 -279.749504)
		(width 0.1143)
		(layer "In11.Cu")
		(net "P5E_PEX0_STN2_TX_DN<46>")
	)
	(segment
		(start 36.698936 -50.44821)
		(end 37.444172 -62.96533)
		(width 0.1651)
		(layer "In11.Cu")
		(net "P5E_PEX0_STN2_TX_DN<46>")
	)
	(segment
		(start 36.125404 -48.810164)
		(end 36.698936 -50.44821)
		(width 0.1651)
		(layer "In11.Cu")
		(net "P5E_PEX0_STN2_TX_DN<46>")
	)
	(segment
		(start 45.02023 -271.473168)
		(end 45.02023 -280.025856)
		(width 0.1143)
		(layer "In11.Cu")
		(net "P5E_PEX0_STN2_TX_DN<46>")
	)
	(segment
		(start 19.5961 -32.141414)
		(end 21.385276 -32.141414)
		(width 0.1651)
		(layer "In11.Cu")
		(net "P5E_PEX0_STN2_TX_DN<46>")
	)
	(segment
		(start 45.28566 -280.129488)
		(end 45.39996 -280.015188)
		(width 0.1143)
		(layer "In11.Cu")
		(net "P5E_PEX0_STN2_TX_DN<46>")
	)
	(segment
		(start 32.377888 -116.822728)
		(end 32.840422 -138.163046)
		(width 0.1651)
		(layer "In11.Cu")
		(net "P5E_PEX0_STN2_TX_DN<46>")
	)
	(segment
		(start 21.385276 -32.141414)
		(end 24.396954 -33.387538)
		(width 0.1651)
		(layer "In11.Cu")
		(net "P5E_PEX0_STN2_TX_DN<46>")
	)
	(segment
		(start 32.840422 -138.163046)
		(end 44.058332 -264.52195)
		(width 0.1651)
		(layer "In11.Cu")
		(net "P5E_PEX0_STN2_TX_DN<46>")
	)
	(segment
		(start 37.444172 -62.96533)
		(end 36.557966 -78.771496)
		(width 0.1651)
		(layer "In11.Cu")
		(net "P5E_PEX0_STN2_TX_DN<46>")
	)
	(segment
		(start 45.06595 -270.196056)
		(end 45.06595 -271.399)
		(width 0.1651)
		(layer "In11.Cu")
		(net "P5E_PEX0_STN2_TX_DN<46>")
	)
	(segment
		(start 32.979868 -104.96423)
		(end 32.377888 -116.822728)
		(width 0.1651)
		(layer "In11.Cu")
		(net "P5E_PEX0_STN2_TX_DN<46>")
	)
	(segment
		(start 19.30527 -31.850584)
		(end 19.5961 -32.141414)
		(width 0.1651)
		(layer "In11.Cu")
		(net "P5E_PEX0_STN2_TX_DN<46>")
	)
	(segment
		(start 45.123862 -280.129488)
		(end 45.28566 -280.129488)
		(width 0.1143)
		(layer "In11.Cu")
		(net "P5E_PEX0_STN2_TX_DN<46>")
	)
	(segment
		(start 44.058332 -264.52195)
		(end 45.06595 -270.196056)
		(width 0.1651)
		(layer "In11.Cu")
		(net "P5E_PEX0_STN2_TX_DN<46>")
	)
	(segment
		(start 215.120982 -34.2265)
		(end 214.801196 -34.546286)
		(width 0.13462)
		(layer "F.Cu")
		(net "P5E_PEX1_STN2_TX_DP<35>")
	)
	(segment
		(start 216.04732 -34.520886)
		(end 215.752934 -34.2265)
		(width 0.13462)
		(layer "F.Cu")
		(net "P5E_PEX1_STN2_TX_DP<35>")
	)
	(segment
		(start 215.752934 -34.2265)
		(end 215.120982 -34.2265)
		(width 0.13462)
		(layer "F.Cu")
		(net "P5E_PEX1_STN2_TX_DP<35>")
	)
	(segment
		(start 218.007184 -35.344862)
		(end 218.24188 -35.781488)
		(width 0.1651)
		(layer "In11.Cu")
		(net "P5E_PEX1_STN2_TX_DP<35>")
	)
	(segment
		(start 171.333922 -265.45286)
		(end 171.333922 -271.399)
		(width 0.1651)
		(layer "In11.Cu")
		(net "P5E_PEX1_STN2_TX_DP<35>")
	)
	(segment
		(start 217.819224 -34.754058)
		(end 218.053666 -35.190176)
		(width 0.1651)
		(layer "In11.Cu")
		(net "P5E_PEX1_STN2_TX_DP<35>")
	)
	(segment
		(start 192.650872 -131.097782)
		(end 192.650872 -139.865608)
		(width 0.1651)
		(layer "In11.Cu")
		(net "P5E_PEX1_STN2_TX_DP<35>")
	)
	(segment
		(start 171.379642 -278.20493)
		(end 171.59478 -278.420068)
		(width 0.1143)
		(layer "In11.Cu")
		(net "P5E_PEX1_STN2_TX_DP<35>")
	)
	(segment
		(start 190.445644 -161.487866)
		(end 171.333922 -265.45286)
		(width 0.1651)
		(layer "In11.Cu")
		(net "P5E_PEX1_STN2_TX_DP<35>")
	)
	(segment
		(start 171.835572 -278.420068)
		(end 171.949872 -278.534368)
		(width 0.1143)
		(layer "In11.Cu")
		(net "P5E_PEX1_STN2_TX_DP<35>")
	)
	(segment
		(start 218.053666 -35.190176)
		(end 218.007184 -35.344862)
		(width 0.1651)
		(layer "In11.Cu")
		(net "P5E_PEX1_STN2_TX_DP<35>")
	)
	(segment
		(start 216.33815 -34.230056)
		(end 216.982802 -34.230056)
		(width 0.1651)
		(layer "In11.Cu")
		(net "P5E_PEX1_STN2_TX_DP<35>")
	)
	(segment
		(start 211.278724 -77.73924)
		(end 211.266786 -77.751178)
		(width 0.1651)
		(layer "In11.Cu")
		(net "P5E_PEX1_STN2_TX_DP<35>")
	)
	(segment
		(start 220.16974 -67.800728)
		(end 218.064842 -70.921626)
		(width 0.1651)
		(layer "In11.Cu")
		(net "P5E_PEX1_STN2_TX_DP<35>")
	)
	(segment
		(start 211.266786 -77.751178)
		(end 211.26704 -77.751178)
		(width 0.1651)
		(layer "In11.Cu")
		(net "P5E_PEX1_STN2_TX_DP<35>")
	)
	(segment
		(start 192.213484 -141.757654)
		(end 191.906398 -149.233636)
		(width 0.1651)
		(layer "In11.Cu")
		(net "P5E_PEX1_STN2_TX_DP<35>")
	)
	(segment
		(start 171.333922 -271.427448)
		(end 171.379642 -271.473168)
		(width 0.1143)
		(layer "In11.Cu")
		(net "P5E_PEX1_STN2_TX_DP<35>")
	)
	(segment
		(start 218.064588 -70.921626)
		(end 215.960706 -74.041508)
		(width 0.1651)
		(layer "In11.Cu")
		(net "P5E_PEX1_STN2_TX_DP<35>")
	)
	(segment
		(start 171.379642 -271.473168)
		(end 171.379642 -278.20493)
		(width 0.1143)
		(layer "In11.Cu")
		(net "P5E_PEX1_STN2_TX_DP<35>")
	)
	(segment
		(start 171.949872 -278.534368)
		(end 171.949872 -278.799798)
		(width 0.1143)
		(layer "In11.Cu")
		(net "P5E_PEX1_STN2_TX_DP<35>")
	)
	(segment
		(start 222.073724 -42.823892)
		(end 222.30207 -56.74106)
		(width 0.1651)
		(layer "In11.Cu")
		(net "P5E_PEX1_STN2_TX_DP<35>")
	)
	(segment
		(start 171.59478 -278.420068)
		(end 171.835572 -278.420068)
		(width 0.1143)
		(layer "In11.Cu")
		(net "P5E_PEX1_STN2_TX_DP<35>")
	)
	(segment
		(start 218.24188 -35.781488)
		(end 218.39682 -35.82797)
		(width 0.1651)
		(layer "In11.Cu")
		(net "P5E_PEX1_STN2_TX_DP<35>")
	)
	(segment
		(start 215.960706 -74.041508)
		(end 211.278724 -77.73924)
		(width 0.1651)
		(layer "In11.Cu")
		(net "P5E_PEX1_STN2_TX_DP<35>")
	)
	(segment
		(start 218.064842 -70.921626)
		(end 218.064588 -70.921626)
		(width 0.1651)
		(layer "In11.Cu")
		(net "P5E_PEX1_STN2_TX_DP<35>")
	)
	(segment
		(start 209.062574 -79.960724)
		(end 194.887342 -104.92359)
		(width 0.1651)
		(layer "In11.Cu")
		(net "P5E_PEX1_STN2_TX_DP<35>")
	)
	(segment
		(start 218.39682 -35.82797)
		(end 221.994222 -42.518584)
		(width 0.1651)
		(layer "In11.Cu")
		(net "P5E_PEX1_STN2_TX_DP<35>")
	)
	(segment
		(start 192.650872 -139.865608)
		(end 192.213484 -141.757654)
		(width 0.1651)
		(layer "In11.Cu")
		(net "P5E_PEX1_STN2_TX_DP<35>")
	)
	(segment
		(start 191.906398 -149.233636)
		(end 190.445644 -161.487866)
		(width 0.1651)
		(layer "In11.Cu")
		(net "P5E_PEX1_STN2_TX_DP<35>")
	)
	(segment
		(start 211.26704 -77.751178)
		(end 209.062574 -79.960724)
		(width 0.1651)
		(layer "In11.Cu")
		(net "P5E_PEX1_STN2_TX_DP<35>")
	)
	(segment
		(start 217.362786 -34.336228)
		(end 217.819224 -34.754058)
		(width 0.1651)
		(layer "In11.Cu")
		(net "P5E_PEX1_STN2_TX_DP<35>")
	)
	(segment
		(start 216.04732 -34.520886)
		(end 216.33815 -34.230056)
		(width 0.1651)
		(layer "In11.Cu")
		(net "P5E_PEX1_STN2_TX_DP<35>")
	)
	(segment
		(start 221.994222 -42.518584)
		(end 222.073724 -42.823892)
		(width 0.1651)
		(layer "In11.Cu")
		(net "P5E_PEX1_STN2_TX_DP<35>")
	)
	(segment
		(start 194.887342 -104.92359)
		(end 193.180462 -118.187978)
		(width 0.1651)
		(layer "In11.Cu")
		(net "P5E_PEX1_STN2_TX_DP<35>")
	)
	(segment
		(start 216.982802 -34.230056)
		(end 217.362786 -34.336228)
		(width 0.1651)
		(layer "In11.Cu")
		(net "P5E_PEX1_STN2_TX_DP<35>")
	)
	(segment
		(start 193.180462 -118.187978)
		(end 192.650872 -131.097782)
		(width 0.1651)
		(layer "In11.Cu")
		(net "P5E_PEX1_STN2_TX_DP<35>")
	)
	(segment
		(start 171.333922 -271.399)
		(end 171.333922 -271.427448)
		(width 0.1143)
		(layer "In11.Cu")
		(net "P5E_PEX1_STN2_TX_DP<35>")
	)
	(segment
		(start 222.30207 -56.74106)
		(end 220.16974 -67.800728)
		(width 0.1651)
		(layer "In11.Cu")
		(net "P5E_PEX1_STN2_TX_DP<35>")
	)
	(segment
		(start 315.455554 -144.983708)
		(end 315.128148 -145.311114)
		(width 0.13462)
		(layer "F.Cu")
		(net "P5E_PEX2_STN0_TX_DP<9>")
	)
	(segment
		(start 316.374272 -145.285714)
		(end 316.072266 -144.983708)
		(width 0.13462)
		(layer "F.Cu")
		(net "P5E_PEX2_STN0_TX_DP<9>")
	)
	(segment
		(start 316.072266 -144.983708)
		(end 315.455554 -144.983708)
		(width 0.13462)
		(layer "F.Cu")
		(net "P5E_PEX2_STN0_TX_DP<9>")
	)
	(segment
		(start 314.91555 -172.862748)
		(end 313.619642 -177.694844)
		(width 0.1651)
		(layer "In9.Cu")
		(net "P5E_PEX2_STN0_TX_DP<9>")
	)
	(segment
		(start 316.374272 -145.285714)
		(end 316.665102 -144.994884)
		(width 0.1651)
		(layer "In9.Cu")
		(net "P5E_PEX2_STN0_TX_DP<9>")
	)
	(segment
		(start 316.665102 -144.994884)
		(end 317.255906 -144.994884)
		(width 0.1651)
		(layer "In9.Cu")
		(net "P5E_PEX2_STN0_TX_DP<9>")
	)
	(segment
		(start 318.200786 -145.939764)
		(end 319.30848 -147.047458)
		(width 0.1651)
		(layer "In9.Cu")
		(net "P5E_PEX2_STN0_TX_DP<9>")
	)
	(segment
		(start 323.379846 -158.199328)
		(end 314.91555 -172.862748)
		(width 0.1651)
		(layer "In9.Cu")
		(net "P5E_PEX2_STN0_TX_DP<9>")
	)
	(segment
		(start 320.054224 -148.163788)
		(end 321.73545 -150.679658)
		(width 0.1651)
		(layer "In9.Cu")
		(net "P5E_PEX2_STN0_TX_DP<9>")
	)
	(segment
		(start 312.179716 -278.205184)
		(end 312.3946 -278.420068)
		(width 0.1143)
		(layer "In9.Cu")
		(net "P5E_PEX2_STN0_TX_DP<9>")
	)
	(segment
		(start 319.680336 -147.603972)
		(end 319.655698 -147.727162)
		(width 0.1651)
		(layer "In9.Cu")
		(net "P5E_PEX2_STN0_TX_DP<9>")
	)
	(segment
		(start 319.931034 -148.13915)
		(end 320.054478 -148.163788)
		(width 0.1651)
		(layer "In9.Cu")
		(net "P5E_PEX2_STN0_TX_DP<9>")
	)
	(segment
		(start 312.3946 -278.420068)
		(end 312.635392 -278.420068)
		(width 0.1143)
		(layer "In9.Cu")
		(net "P5E_PEX2_STN0_TX_DP<9>")
	)
	(segment
		(start 320.054478 -148.163788)
		(end 320.054224 -148.163788)
		(width 0.1651)
		(layer "In9.Cu")
		(net "P5E_PEX2_STN0_TX_DP<9>")
	)
	(segment
		(start 318.064134 -145.939764)
		(end 318.200786 -145.939764)
		(width 0.1651)
		(layer "In9.Cu")
		(net "P5E_PEX2_STN0_TX_DP<9>")
	)
	(segment
		(start 313.11469 -268.933168)
		(end 312.133996 -271.30121)
		(width 0.1651)
		(layer "In9.Cu")
		(net "P5E_PEX2_STN0_TX_DP<9>")
	)
	(segment
		(start 312.133996 -271.30121)
		(end 312.133996 -271.471898)
		(width 0.1651)
		(layer "In9.Cu")
		(net "P5E_PEX2_STN0_TX_DP<9>")
	)
	(segment
		(start 317.740538 -145.479516)
		(end 317.740538 -145.616168)
		(width 0.1651)
		(layer "In9.Cu")
		(net "P5E_PEX2_STN0_TX_DP<9>")
	)
	(segment
		(start 321.73545 -150.679658)
		(end 323.379846 -154.64917)
		(width 0.1651)
		(layer "In9.Cu")
		(net "P5E_PEX2_STN0_TX_DP<9>")
	)
	(segment
		(start 313.11469 -260.32714)
		(end 313.11469 -268.933168)
		(width 0.1651)
		(layer "In9.Cu")
		(net "P5E_PEX2_STN0_TX_DP<9>")
	)
	(segment
		(start 323.379846 -154.64917)
		(end 323.379846 -158.199328)
		(width 0.1651)
		(layer "In9.Cu")
		(net "P5E_PEX2_STN0_TX_DP<9>")
	)
	(segment
		(start 312.635392 -278.420068)
		(end 312.749692 -278.534368)
		(width 0.1143)
		(layer "In9.Cu")
		(net "P5E_PEX2_STN0_TX_DP<9>")
	)
	(segment
		(start 317.740538 -145.616168)
		(end 318.064134 -145.939764)
		(width 0.1651)
		(layer "In9.Cu")
		(net "P5E_PEX2_STN0_TX_DP<9>")
	)
	(segment
		(start 319.655698 -147.727162)
		(end 319.931034 -148.13915)
		(width 0.1651)
		(layer "In9.Cu")
		(net "P5E_PEX2_STN0_TX_DP<9>")
	)
	(segment
		(start 312.179716 -271.546066)
		(end 312.179716 -278.205184)
		(width 0.1143)
		(layer "In9.Cu")
		(net "P5E_PEX2_STN0_TX_DP<9>")
	)
	(segment
		(start 317.255906 -144.994884)
		(end 317.740538 -145.479516)
		(width 0.1651)
		(layer "In9.Cu")
		(net "P5E_PEX2_STN0_TX_DP<9>")
	)
	(segment
		(start 312.133996 -271.471898)
		(end 312.133996 -271.500346)
		(width 0.1143)
		(layer "In9.Cu")
		(net "P5E_PEX2_STN0_TX_DP<9>")
	)
	(segment
		(start 312.133996 -271.500346)
		(end 312.179716 -271.546066)
		(width 0.1143)
		(layer "In9.Cu")
		(net "P5E_PEX2_STN0_TX_DP<9>")
	)
	(segment
		(start 313.619642 -177.694844)
		(end 309.752238 -221.85376)
		(width 0.1651)
		(layer "In9.Cu")
		(net "P5E_PEX2_STN0_TX_DP<9>")
	)
	(segment
		(start 309.752238 -221.85376)
		(end 313.11469 -260.32714)
		(width 0.1651)
		(layer "In9.Cu")
		(net "P5E_PEX2_STN0_TX_DP<9>")
	)
	(segment
		(start 312.749692 -278.534368)
		(end 312.749692 -278.799798)
		(width 0.1143)
		(layer "In9.Cu")
		(net "P5E_PEX2_STN0_TX_DP<9>")
	)
	(segment
		(start 319.30848 -147.047458)
		(end 319.680336 -147.603972)
		(width 0.1651)
		(layer "In9.Cu")
		(net "P5E_PEX2_STN0_TX_DP<9>")
	)
	(segment
		(start 319.609724 -343.685622)
		(end 319.289684 -343.365582)
		(width 0.13462)
		(layer "F.Cu")
		(net "P5E_PEX2_STN6_TX_DN<109>")
	)
	(segment
		(start 319.289684 -342.734138)
		(end 319.584324 -342.439498)
		(width 0.13462)
		(layer "F.Cu")
		(net "P5E_PEX2_STN6_TX_DN<109>")
	)
	(segment
		(start 319.289684 -343.365582)
		(end 319.289684 -342.734138)
		(width 0.13462)
		(layer "F.Cu")
		(net "P5E_PEX2_STN6_TX_DN<109>")
	)
	(segment
		(start 277.599902 -311.784492)
		(end 277.599902 -312.049922)
		(width 0.1143)
		(layer "In13.Cu")
		(net "P5E_PEX2_STN6_TX_DN<109>")
	)
	(segment
		(start 277.220172 -319.921128)
		(end 277.220172 -311.787794)
		(width 0.1143)
		(layer "In13.Cu")
		(net "P5E_PEX2_STN6_TX_DN<109>")
	)
	(segment
		(start 313.1058 -338.4804)
		(end 294.404542 -334.847438)
		(width 0.1651)
		(layer "In13.Cu")
		(net "P5E_PEX2_STN6_TX_DN<109>")
	)
	(segment
		(start 318.962024 -341.131906)
		(end 313.1058 -338.4804)
		(width 0.1651)
		(layer "In13.Cu")
		(net "P5E_PEX2_STN6_TX_DN<109>")
	)
	(segment
		(start 294.404542 -334.847438)
		(end 294.404542 -334.847692)
		(width 0.1651)
		(layer "In13.Cu")
		(net "P5E_PEX2_STN6_TX_DN<109>")
	)
	(segment
		(start 292.59657 -334.495902)
		(end 283.126688 -332.656688)
		(width 0.1651)
		(layer "In13.Cu")
		(net "P5E_PEX2_STN6_TX_DN<109>")
	)
	(segment
		(start 293.18712 -334.520032)
		(end 292.70071 -334.425798)
		(width 0.1651)
		(layer "In13.Cu")
		(net "P5E_PEX2_STN6_TX_DN<109>")
	)
	(segment
		(start 293.847774 -334.64881)
		(end 293.743634 -334.718914)
		(width 0.1651)
		(layer "In13.Cu")
		(net "P5E_PEX2_STN6_TX_DN<109>")
	)
	(segment
		(start 277.265892 -319.995296)
		(end 277.265892 -319.966848)
		(width 0.1143)
		(layer "In13.Cu")
		(net "P5E_PEX2_STN6_TX_DN<109>")
	)
	(segment
		(start 277.485602 -311.670192)
		(end 277.599902 -311.784492)
		(width 0.1143)
		(layer "In13.Cu")
		(net "P5E_PEX2_STN6_TX_DN<109>")
	)
	(segment
		(start 294.404542 -334.847692)
		(end 294.334184 -334.743044)
		(width 0.1651)
		(layer "In13.Cu")
		(net "P5E_PEX2_STN6_TX_DN<109>")
	)
	(segment
		(start 292.70071 -334.425798)
		(end 292.59657 -334.495902)
		(width 0.1651)
		(layer "In13.Cu")
		(net "P5E_PEX2_STN6_TX_DN<109>")
	)
	(segment
		(start 283.126688 -332.656688)
		(end 278.27351 -327.80351)
		(width 0.1651)
		(layer "In13.Cu")
		(net "P5E_PEX2_STN6_TX_DN<109>")
	)
	(segment
		(start 277.265892 -325.370952)
		(end 277.265892 -319.995296)
		(width 0.1651)
		(layer "In13.Cu")
		(net "P5E_PEX2_STN6_TX_DN<109>")
	)
	(segment
		(start 277.265892 -319.966848)
		(end 277.220172 -319.921128)
		(width 0.1143)
		(layer "In13.Cu")
		(net "P5E_PEX2_STN6_TX_DN<109>")
	)
	(segment
		(start 294.334184 -334.743044)
		(end 293.847774 -334.64881)
		(width 0.1651)
		(layer "In13.Cu")
		(net "P5E_PEX2_STN6_TX_DN<109>")
	)
	(segment
		(start 293.257478 -334.62468)
		(end 293.18712 -334.520032)
		(width 0.1651)
		(layer "In13.Cu")
		(net "P5E_PEX2_STN6_TX_DN<109>")
	)
	(segment
		(start 277.220172 -311.787794)
		(end 277.337774 -311.670192)
		(width 0.1143)
		(layer "In13.Cu")
		(net "P5E_PEX2_STN6_TX_DN<109>")
	)
	(segment
		(start 277.337774 -311.670192)
		(end 277.485602 -311.670192)
		(width 0.1143)
		(layer "In13.Cu")
		(net "P5E_PEX2_STN6_TX_DN<109>")
	)
	(segment
		(start 319.293494 -342.148668)
		(end 319.293494 -341.633048)
		(width 0.1651)
		(layer "In13.Cu")
		(net "P5E_PEX2_STN6_TX_DN<109>")
	)
	(segment
		(start 319.584324 -342.439498)
		(end 319.293494 -342.148668)
		(width 0.1651)
		(layer "In13.Cu")
		(net "P5E_PEX2_STN6_TX_DN<109>")
	)
	(segment
		(start 278.27351 -327.80351)
		(end 277.265892 -325.370952)
		(width 0.1651)
		(layer "In13.Cu")
		(net "P5E_PEX2_STN6_TX_DN<109>")
	)
	(segment
		(start 293.743634 -334.718914)
		(end 293.257478 -334.62468)
		(width 0.1651)
		(layer "In13.Cu")
		(net "P5E_PEX2_STN6_TX_DN<109>")
	)
	(segment
		(start 319.293494 -341.633048)
		(end 318.962024 -341.131906)
		(width 0.1651)
		(layer "In13.Cu")
		(net "P5E_PEX2_STN6_TX_DN<109>")
	)
	(segment
		(start 429.53686 -122.591068)
		(end 428.90694 -122.591068)
		(width 0.13462)
		(layer "F.Cu")
		(net "P5E_PEX3_STN0_TX_DN<2>")
	)
	(segment
		(start 429.832262 -122.295666)
		(end 429.53686 -122.591068)
		(width 0.13462)
		(layer "F.Cu")
		(net "P5E_PEX3_STN0_TX_DN<2>")
	)
	(segment
		(start 428.90694 -122.591068)
		(end 428.586138 -122.270266)
		(width 0.13462)
		(layer "F.Cu")
		(net "P5E_PEX3_STN0_TX_DN<2>")
	)
	(segment
		(start 446.31356 -160.544256)
		(end 437.667146 -175.527208)
		(width 0.1651)
		(layer "In9.Cu")
		(net "P5E_PEX3_STN0_TX_DN<2>")
	)
	(segment
		(start 435.017164 -125.535182)
		(end 437.580024 -131.720844)
		(width 0.1651)
		(layer "In9.Cu")
		(net "P5E_PEX3_STN0_TX_DN<2>")
	)
	(segment
		(start 430.123092 -122.586496)
		(end 433.017676 -122.586496)
		(width 0.1651)
		(layer "In9.Cu")
		(net "P5E_PEX3_STN0_TX_DN<2>")
	)
	(segment
		(start 435.491636 -250.029726)
		(end 445.575182 -265.119866)
		(width 0.1651)
		(layer "In9.Cu")
		(net "P5E_PEX3_STN0_TX_DN<2>")
	)
	(segment
		(start 434.902102 -124.95784)
		(end 435.017164 -125.535182)
		(width 0.1651)
		(layer "In9.Cu")
		(net "P5E_PEX3_STN0_TX_DN<2>")
	)
	(segment
		(start 446.640966 -267.69314)
		(end 447.057526 -272.44802)
		(width 0.1651)
		(layer "In9.Cu")
		(net "P5E_PEX3_STN0_TX_DN<2>")
	)
	(segment
		(start 437.580024 -131.720844)
		(end 438.088278 -132.229098)
		(width 0.1651)
		(layer "In9.Cu")
		(net "P5E_PEX3_STN0_TX_DN<2>")
	)
	(segment
		(start 434.557932 -124.126752)
		(end 434.902102 -124.95784)
		(width 0.1651)
		(layer "In9.Cu")
		(net "P5E_PEX3_STN0_TX_DN<2>")
	)
	(segment
		(start 433.017676 -122.586496)
		(end 434.557932 -124.126752)
		(width 0.1651)
		(layer "In9.Cu")
		(net "P5E_PEX3_STN0_TX_DN<2>")
	)
	(segment
		(start 436.758334 -178.91506)
		(end 433.016914 -221.67723)
		(width 0.1651)
		(layer "In9.Cu")
		(net "P5E_PEX3_STN0_TX_DN<2>")
	)
	(segment
		(start 437.667146 -175.527208)
		(end 436.758334 -178.91506)
		(width 0.1651)
		(layer "In9.Cu")
		(net "P5E_PEX3_STN0_TX_DN<2>")
	)
	(segment
		(start 445.6557 -275.8313)
		(end 436.614062 -284.872938)
		(width 0.1651)
		(layer "In9.Cu")
		(net "P5E_PEX3_STN0_TX_DN<2>")
	)
	(segment
		(start 425.62018 -286.285686)
		(end 425.73448 -286.399986)
		(width 0.1143)
		(layer "In9.Cu")
		(net "P5E_PEX3_STN0_TX_DN<2>")
	)
	(segment
		(start 433.73421 -286.065976)
		(end 432.217576 -286.065976)
		(width 0.1651)
		(layer "In9.Cu")
		(net "P5E_PEX3_STN0_TX_DN<2>")
	)
	(segment
		(start 425.723812 -286.020256)
		(end 425.62018 -286.123888)
		(width 0.1143)
		(layer "In9.Cu")
		(net "P5E_PEX3_STN0_TX_DN<2>")
	)
	(segment
		(start 429.832262 -122.295666)
		(end 430.123092 -122.586496)
		(width 0.1651)
		(layer "In9.Cu")
		(net "P5E_PEX3_STN0_TX_DN<2>")
	)
	(segment
		(start 425.73448 -286.399986)
		(end 425.99991 -286.399986)
		(width 0.1143)
		(layer "In9.Cu")
		(net "P5E_PEX3_STN0_TX_DN<2>")
	)
	(segment
		(start 445.575182 -265.119866)
		(end 446.640966 -267.69314)
		(width 0.1651)
		(layer "In9.Cu")
		(net "P5E_PEX3_STN0_TX_DN<2>")
	)
	(segment
		(start 433.016914 -221.67723)
		(end 435.491636 -250.029726)
		(width 0.1651)
		(layer "In9.Cu")
		(net "P5E_PEX3_STN0_TX_DN<2>")
	)
	(segment
		(start 425.62018 -286.123888)
		(end 425.62018 -286.285686)
		(width 0.1143)
		(layer "In9.Cu")
		(net "P5E_PEX3_STN0_TX_DN<2>")
	)
	(segment
		(start 446.536064 -152.623266)
		(end 446.536064 -159.71139)
		(width 0.1651)
		(layer "In9.Cu")
		(net "P5E_PEX3_STN0_TX_DN<2>")
	)
	(segment
		(start 438.088278 -132.229098)
		(end 446.536064 -152.623266)
		(width 0.1651)
		(layer "In9.Cu")
		(net "P5E_PEX3_STN0_TX_DN<2>")
	)
	(segment
		(start 432.217576 -286.065976)
		(end 432.189128 -286.065976)
		(width 0.1143)
		(layer "In9.Cu")
		(net "P5E_PEX3_STN0_TX_DN<2>")
	)
	(segment
		(start 446.536064 -159.71139)
		(end 446.31356 -160.544256)
		(width 0.1651)
		(layer "In9.Cu")
		(net "P5E_PEX3_STN0_TX_DN<2>")
	)
	(segment
		(start 436.614062 -284.872938)
		(end 433.73421 -286.065976)
		(width 0.1651)
		(layer "In9.Cu")
		(net "P5E_PEX3_STN0_TX_DN<2>")
	)
	(segment
		(start 447.057526 -272.44802)
		(end 445.6557 -275.8313)
		(width 0.1651)
		(layer "In9.Cu")
		(net "P5E_PEX3_STN0_TX_DN<2>")
	)
	(segment
		(start 432.189128 -286.065976)
		(end 432.143408 -286.020256)
		(width 0.1143)
		(layer "In9.Cu")
		(net "P5E_PEX3_STN0_TX_DN<2>")
	)
	(segment
		(start 432.143408 -286.020256)
		(end 425.723812 -286.020256)
		(width 0.1143)
		(layer "In9.Cu")
		(net "P5E_PEX3_STN0_TX_DN<2>")
	)
	(segment
		(start 437.844184 -348.880938)
		(end 438.139332 -348.58579)
		(width 0.13462)
		(layer "F.Cu")
		(net "P5E_PEX3_STN7_TX_DN<125>")
	)
	(segment
		(start 437.844184 -349.511366)
		(end 437.844184 -348.880938)
		(width 0.13462)
		(layer "F.Cu")
		(net "P5E_PEX3_STN7_TX_DN<125>")
	)
	(segment
		(start 438.164732 -349.831914)
		(end 437.844184 -349.511366)
		(width 0.13462)
		(layer "F.Cu")
		(net "P5E_PEX3_STN7_TX_DN<125>")
	)
	(segment
		(start 439.402982 -346.230194)
		(end 439.402982 -341.536528)
		(width 0.1651)
		(layer "In11.Cu")
		(net "P5E_PEX3_STN7_TX_DN<125>")
	)
	(segment
		(start 388.569962 -313.673998)
		(end 388.673848 -313.570112)
		(width 0.1143)
		(layer "In11.Cu")
		(net "P5E_PEX3_STN7_TX_DN<125>")
	)
	(segment
		(start 389.249412 -322.142612)
		(end 388.615682 -321.508882)
		(width 0.1651)
		(layer "In11.Cu")
		(net "P5E_PEX3_STN7_TX_DN<125>")
	)
	(segment
		(start 388.569962 -319.988438)
		(end 388.569962 -313.673998)
		(width 0.1143)
		(layer "In11.Cu")
		(net "P5E_PEX3_STN7_TX_DN<125>")
	)
	(segment
		(start 438.404 -340.3346)
		(end 426.3644 -331.9018)
		(width 0.1651)
		(layer "In11.Cu")
		(net "P5E_PEX3_STN7_TX_DN<125>")
	)
	(segment
		(start 388.615682 -320.034158)
		(end 388.569962 -319.988438)
		(width 0.1143)
		(layer "In11.Cu")
		(net "P5E_PEX3_STN7_TX_DN<125>")
	)
	(segment
		(start 388.949946 -313.684412)
		(end 388.949946 -313.949842)
		(width 0.1143)
		(layer "In11.Cu")
		(net "P5E_PEX3_STN7_TX_DN<125>")
	)
	(segment
		(start 394.698982 -323.575426)
		(end 394.220192 -323.449696)
		(width 0.1651)
		(layer "In11.Cu")
		(net "P5E_PEX3_STN7_TX_DN<125>")
	)
	(segment
		(start 388.615682 -321.508882)
		(end 388.615682 -320.056256)
		(width 0.1651)
		(layer "In11.Cu")
		(net "P5E_PEX3_STN7_TX_DN<125>")
	)
	(segment
		(start 393.568936 -323.278246)
		(end 393.090146 -323.152516)
		(width 0.1651)
		(layer "In11.Cu")
		(net "P5E_PEX3_STN7_TX_DN<125>")
	)
	(segment
		(start 392.547348 -322.91782)
		(end 392.43889 -322.981066)
		(width 0.1651)
		(layer "In11.Cu")
		(net "P5E_PEX3_STN7_TX_DN<125>")
	)
	(segment
		(start 395.350238 -323.746876)
		(end 395.286992 -323.638164)
		(width 0.1651)
		(layer "In11.Cu")
		(net "P5E_PEX3_STN7_TX_DN<125>")
	)
	(segment
		(start 426.3644 -331.9018)
		(end 395.350238 -323.746876)
		(width 0.1651)
		(layer "In11.Cu")
		(net "P5E_PEX3_STN7_TX_DN<125>")
	)
	(segment
		(start 393.677648 -323.215)
		(end 393.568936 -323.278246)
		(width 0.1651)
		(layer "In11.Cu")
		(net "P5E_PEX3_STN7_TX_DN<125>")
	)
	(segment
		(start 388.673848 -313.570112)
		(end 388.835646 -313.570112)
		(width 0.1143)
		(layer "In11.Cu")
		(net "P5E_PEX3_STN7_TX_DN<125>")
	)
	(segment
		(start 439.402982 -341.536528)
		(end 438.404 -340.3346)
		(width 0.1651)
		(layer "In11.Cu")
		(net "P5E_PEX3_STN7_TX_DN<125>")
	)
	(segment
		(start 395.286992 -323.638164)
		(end 394.807694 -323.51218)
		(width 0.1651)
		(layer "In11.Cu")
		(net "P5E_PEX3_STN7_TX_DN<125>")
	)
	(segment
		(start 394.807694 -323.51218)
		(end 394.698982 -323.575426)
		(width 0.1651)
		(layer "In11.Cu")
		(net "P5E_PEX3_STN7_TX_DN<125>")
	)
	(segment
		(start 438.139332 -348.58579)
		(end 437.848502 -348.29496)
		(width 0.1651)
		(layer "In11.Cu")
		(net "P5E_PEX3_STN7_TX_DN<125>")
	)
	(segment
		(start 393.026646 -323.043804)
		(end 392.547348 -322.91782)
		(width 0.1651)
		(layer "In11.Cu")
		(net "P5E_PEX3_STN7_TX_DN<125>")
	)
	(segment
		(start 394.156946 -323.340984)
		(end 393.677648 -323.215)
		(width 0.1651)
		(layer "In11.Cu")
		(net "P5E_PEX3_STN7_TX_DN<125>")
	)
	(segment
		(start 388.615682 -320.056256)
		(end 388.615682 -320.034158)
		(width 0.1143)
		(layer "In11.Cu")
		(net "P5E_PEX3_STN7_TX_DN<125>")
	)
	(segment
		(start 394.220192 -323.449696)
		(end 394.156946 -323.340984)
		(width 0.1651)
		(layer "In11.Cu")
		(net "P5E_PEX3_STN7_TX_DN<125>")
	)
	(segment
		(start 393.090146 -323.152516)
		(end 393.026646 -323.043804)
		(width 0.1651)
		(layer "In11.Cu")
		(net "P5E_PEX3_STN7_TX_DN<125>")
	)
	(segment
		(start 388.835646 -313.570112)
		(end 388.949946 -313.684412)
		(width 0.1143)
		(layer "In11.Cu")
		(net "P5E_PEX3_STN7_TX_DN<125>")
	)
	(segment
		(start 437.848502 -347.784674)
		(end 439.402982 -346.230194)
		(width 0.1651)
		(layer "In11.Cu")
		(net "P5E_PEX3_STN7_TX_DN<125>")
	)
	(segment
		(start 392.43889 -322.981066)
		(end 389.249412 -322.142612)
		(width 0.1651)
		(layer "In11.Cu")
		(net "P5E_PEX3_STN7_TX_DN<125>")
	)
	(segment
		(start 437.848502 -348.29496)
		(end 437.848502 -347.784674)
		(width 0.1651)
		(layer "In11.Cu")
		(net "P5E_PEX3_STN7_TX_DN<125>")
	)
	(segment
		(start 21.947378 -34.520886)
		(end 21.652992 -34.2265)
		(width 0.13462)
		(layer "F.Cu")
		(net "P5E_PEX0_STN2_TX_DP<47>")
	)
	(segment
		(start 21.652992 -34.2265)
		(end 21.02104 -34.2265)
		(width 0.13462)
		(layer "F.Cu")
		(net "P5E_PEX0_STN2_TX_DP<47>")
	)
	(segment
		(start 21.02104 -34.2265)
		(end 20.701254 -34.546286)
		(width 0.13462)
		(layer "F.Cu")
		(net "P5E_PEX0_STN2_TX_DP<47>")
	)
	(segment
		(start 34.98723 -49.31283)
		(end 35.460686 -50.678842)
		(width 0.1651)
		(layer "In11.Cu")
		(net "P5E_PEX0_STN2_TX_DP<47>")
	)
	(segment
		(start 35.460686 -50.678842)
		(end 36.136072 -62.637416)
		(width 0.1651)
		(layer "In11.Cu")
		(net "P5E_PEX0_STN2_TX_DP<47>")
	)
	(segment
		(start 23.045928 -34.391854)
		(end 24.29383 -35.384486)
		(width 0.1651)
		(layer "In11.Cu")
		(net "P5E_PEX0_STN2_TX_DP<47>")
	)
	(segment
		(start 44.335446 -278.420068)
		(end 44.449746 -278.534368)
		(width 0.1143)
		(layer "In11.Cu")
		(net "P5E_PEX0_STN2_TX_DP<47>")
	)
	(segment
		(start 35.277806 -78.883256)
		(end 31.762192 -104.563164)
		(width 0.1651)
		(layer "In11.Cu")
		(net "P5E_PEX0_STN2_TX_DP<47>")
	)
	(segment
		(start 24.29383 -35.384486)
		(end 25.135078 -36.436046)
		(width 0.1651)
		(layer "In11.Cu")
		(net "P5E_PEX0_STN2_TX_DP<47>")
	)
	(segment
		(start 44.449746 -278.534368)
		(end 44.449746 -278.799798)
		(width 0.1143)
		(layer "In11.Cu")
		(net "P5E_PEX0_STN2_TX_DP<47>")
	)
	(segment
		(start 31.762192 -104.563164)
		(end 31.088076 -117.070886)
		(width 0.1651)
		(layer "In11.Cu")
		(net "P5E_PEX0_STN2_TX_DP<47>")
	)
	(segment
		(start 25.587452 -37.00145)
		(end 33.986216 -47.499778)
		(width 0.1651)
		(layer "In11.Cu")
		(net "P5E_PEX0_STN2_TX_DP<47>")
	)
	(segment
		(start 31.602172 -138.242294)
		(end 42.803064 -264.543286)
		(width 0.1651)
		(layer "In11.Cu")
		(net "P5E_PEX0_STN2_TX_DP<47>")
	)
	(segment
		(start 43.833796 -271.427448)
		(end 43.879516 -271.473168)
		(width 0.1143)
		(layer "In11.Cu")
		(net "P5E_PEX0_STN2_TX_DP<47>")
	)
	(segment
		(start 25.117298 -36.596574)
		(end 25.426924 -36.98367)
		(width 0.1651)
		(layer "In11.Cu")
		(net "P5E_PEX0_STN2_TX_DP<47>")
	)
	(segment
		(start 22.709124 -34.230056)
		(end 23.045928 -34.391854)
		(width 0.1651)
		(layer "In11.Cu")
		(net "P5E_PEX0_STN2_TX_DP<47>")
	)
	(segment
		(start 44.094654 -278.420068)
		(end 44.335446 -278.420068)
		(width 0.1143)
		(layer "In11.Cu")
		(net "P5E_PEX0_STN2_TX_DP<47>")
	)
	(segment
		(start 25.426924 -36.98367)
		(end 25.587452 -37.00145)
		(width 0.1651)
		(layer "In11.Cu")
		(net "P5E_PEX0_STN2_TX_DP<47>")
	)
	(segment
		(start 36.136072 -62.637416)
		(end 35.277806 -78.883256)
		(width 0.1651)
		(layer "In11.Cu")
		(net "P5E_PEX0_STN2_TX_DP<47>")
	)
	(segment
		(start 43.879516 -278.20493)
		(end 44.094654 -278.420068)
		(width 0.1143)
		(layer "In11.Cu")
		(net "P5E_PEX0_STN2_TX_DP<47>")
	)
	(segment
		(start 22.238208 -34.230056)
		(end 22.709124 -34.230056)
		(width 0.1651)
		(layer "In11.Cu")
		(net "P5E_PEX0_STN2_TX_DP<47>")
	)
	(segment
		(start 43.833796 -270.752062)
		(end 43.833796 -271.399)
		(width 0.1651)
		(layer "In11.Cu")
		(net "P5E_PEX0_STN2_TX_DP<47>")
	)
	(segment
		(start 25.135078 -36.436046)
		(end 25.117298 -36.596574)
		(width 0.1651)
		(layer "In11.Cu")
		(net "P5E_PEX0_STN2_TX_DP<47>")
	)
	(segment
		(start 31.088076 -117.070886)
		(end 31.602172 -138.242294)
		(width 0.1651)
		(layer "In11.Cu")
		(net "P5E_PEX0_STN2_TX_DP<47>")
	)
	(segment
		(start 33.986216 -47.499778)
		(end 34.98723 -49.31283)
		(width 0.1651)
		(layer "In11.Cu")
		(net "P5E_PEX0_STN2_TX_DP<47>")
	)
	(segment
		(start 43.833796 -271.399)
		(end 43.833796 -271.427448)
		(width 0.1143)
		(layer "In11.Cu")
		(net "P5E_PEX0_STN2_TX_DP<47>")
	)
	(segment
		(start 21.947378 -34.520886)
		(end 22.238208 -34.230056)
		(width 0.1651)
		(layer "In11.Cu")
		(net "P5E_PEX0_STN2_TX_DP<47>")
	)
	(segment
		(start 43.879516 -271.473168)
		(end 43.879516 -278.20493)
		(width 0.1143)
		(layer "In11.Cu")
		(net "P5E_PEX0_STN2_TX_DP<47>")
	)
	(segment
		(start 42.803064 -264.543286)
		(end 43.833796 -270.752062)
		(width 0.1651)
		(layer "In11.Cu")
		(net "P5E_PEX0_STN2_TX_DP<47>")
	)
	(segment
		(start 216.04732 -30.92069)
		(end 215.75395 -30.62732)
		(width 0.13462)
		(layer "F.Cu")
		(net "P5E_PEX1_STN2_TX_DP<33>")
	)
	(segment
		(start 215.75395 -30.62732)
		(end 215.119966 -30.62732)
		(width 0.13462)
		(layer "F.Cu")
		(net "P5E_PEX1_STN2_TX_DP<33>")
	)
	(segment
		(start 215.119966 -30.62732)
		(end 214.801196 -30.94609)
		(width 0.13462)
		(layer "F.Cu")
		(net "P5E_PEX1_STN2_TX_DP<33>")
	)
	(segment
		(start 195.213986 -118.530624)
		(end 194.560952 -133.834886)
		(width 0.1651)
		(layer "In11.Cu")
		(net "P5E_PEX1_STN2_TX_DP<33>")
	)
	(segment
		(start 219.003372 -75.784202)
		(end 212.435948 -79.352648)
		(width 0.1651)
		(layer "In11.Cu")
		(net "P5E_PEX1_STN2_TX_DP<33>")
	)
	(segment
		(start 173.735746 -278.420068)
		(end 173.850046 -278.534368)
		(width 0.1143)
		(layer "In11.Cu")
		(net "P5E_PEX1_STN2_TX_DP<33>")
	)
	(segment
		(start 216.78011 -30.62986)
		(end 217.28684 -30.852618)
		(width 0.1651)
		(layer "In11.Cu")
		(net "P5E_PEX1_STN2_TX_DP<33>")
	)
	(segment
		(start 223.496632 -40.728392)
		(end 223.989138 -42.583862)
		(width 0.1651)
		(layer "In11.Cu")
		(net "P5E_PEX1_STN2_TX_DP<33>")
	)
	(segment
		(start 173.850046 -278.534368)
		(end 173.850046 -278.799798)
		(width 0.1143)
		(layer "In11.Cu")
		(net "P5E_PEX1_STN2_TX_DP<33>")
	)
	(segment
		(start 203.713334 -93.315536)
		(end 203.713588 -93.315536)
		(width 0.1651)
		(layer "In11.Cu")
		(net "P5E_PEX1_STN2_TX_DP<33>")
	)
	(segment
		(start 220.94317 -36.050474)
		(end 223.496632 -40.728392)
		(width 0.1651)
		(layer "In11.Cu")
		(net "P5E_PEX1_STN2_TX_DP<33>")
	)
	(segment
		(start 192.50025 -161.016188)
		(end 173.234096 -265.833606)
		(width 0.1651)
		(layer "In11.Cu")
		(net "P5E_PEX1_STN2_TX_DP<33>")
	)
	(segment
		(start 220.632528 -35.481768)
		(end 220.602048 -35.585146)
		(width 0.1651)
		(layer "In11.Cu")
		(net "P5E_PEX1_STN2_TX_DP<33>")
	)
	(segment
		(start 194.560952 -133.834886)
		(end 194.560952 -140.36929)
		(width 0.1651)
		(layer "In11.Cu")
		(net "P5E_PEX1_STN2_TX_DP<33>")
	)
	(segment
		(start 210.581494 -81.181702)
		(end 203.713334 -93.315536)
		(width 0.1651)
		(layer "In11.Cu")
		(net "P5E_PEX1_STN2_TX_DP<33>")
	)
	(segment
		(start 220.08465 -34.478468)
		(end 220.054424 -34.581846)
		(width 0.1651)
		(layer "In11.Cu")
		(net "P5E_PEX1_STN2_TX_DP<33>")
	)
	(segment
		(start 173.234096 -265.833606)
		(end 173.234096 -271.399)
		(width 0.1651)
		(layer "In11.Cu")
		(net "P5E_PEX1_STN2_TX_DP<33>")
	)
	(segment
		(start 173.234096 -271.399)
		(end 173.234096 -271.427448)
		(width 0.1143)
		(layer "In11.Cu")
		(net "P5E_PEX1_STN2_TX_DP<33>")
	)
	(segment
		(start 196.837554 -105.463594)
		(end 195.213986 -118.530624)
		(width 0.1651)
		(layer "In11.Cu")
		(net "P5E_PEX1_STN2_TX_DP<33>")
	)
	(segment
		(start 173.279816 -278.20493)
		(end 173.494954 -278.420068)
		(width 0.1143)
		(layer "In11.Cu")
		(net "P5E_PEX1_STN2_TX_DP<33>")
	)
	(segment
		(start 216.33815 -30.62986)
		(end 216.78011 -30.62986)
		(width 0.1651)
		(layer "In11.Cu")
		(net "P5E_PEX1_STN2_TX_DP<33>")
	)
	(segment
		(start 223.989138 -42.583862)
		(end 224.260918 -56.83631)
		(width 0.1651)
		(layer "In11.Cu")
		(net "P5E_PEX1_STN2_TX_DP<33>")
	)
	(segment
		(start 224.260918 -56.83631)
		(end 222.00362 -68.424552)
		(width 0.1651)
		(layer "In11.Cu")
		(net "P5E_PEX1_STN2_TX_DP<33>")
	)
	(segment
		(start 216.04732 -30.92069)
		(end 216.33815 -30.62986)
		(width 0.1651)
		(layer "In11.Cu")
		(net "P5E_PEX1_STN2_TX_DP<33>")
	)
	(segment
		(start 203.713588 -93.315536)
		(end 196.837554 -105.463594)
		(width 0.1651)
		(layer "In11.Cu")
		(net "P5E_PEX1_STN2_TX_DP<33>")
	)
	(segment
		(start 219.718128 -74.822304)
		(end 219.003372 -75.784202)
		(width 0.1651)
		(layer "In11.Cu")
		(net "P5E_PEX1_STN2_TX_DP<33>")
	)
	(segment
		(start 220.291914 -35.016948)
		(end 220.395292 -35.047174)
		(width 0.1651)
		(layer "In11.Cu")
		(net "P5E_PEX1_STN2_TX_DP<33>")
	)
	(segment
		(start 220.839792 -36.020248)
		(end 220.94317 -36.050474)
		(width 0.1651)
		(layer "In11.Cu")
		(net "P5E_PEX1_STN2_TX_DP<33>")
	)
	(segment
		(start 173.494954 -278.420068)
		(end 173.735746 -278.420068)
		(width 0.1143)
		(layer "In11.Cu")
		(net "P5E_PEX1_STN2_TX_DP<33>")
	)
	(segment
		(start 222.00362 -68.424552)
		(end 219.718128 -74.822304)
		(width 0.1651)
		(layer "In11.Cu")
		(net "P5E_PEX1_STN2_TX_DP<33>")
	)
	(segment
		(start 217.28684 -30.852618)
		(end 219.066364 -32.612838)
		(width 0.1651)
		(layer "In11.Cu")
		(net "P5E_PEX1_STN2_TX_DP<33>")
	)
	(segment
		(start 220.395292 -35.047174)
		(end 220.632528 -35.481768)
		(width 0.1651)
		(layer "In11.Cu")
		(net "P5E_PEX1_STN2_TX_DP<33>")
	)
	(segment
		(start 193.946018 -148.226526)
		(end 193.719196 -150.913846)
		(width 0.1651)
		(layer "In11.Cu")
		(net "P5E_PEX1_STN2_TX_DP<33>")
	)
	(segment
		(start 173.234096 -271.427448)
		(end 173.279816 -271.473168)
		(width 0.1143)
		(layer "In11.Cu")
		(net "P5E_PEX1_STN2_TX_DP<33>")
	)
	(segment
		(start 212.435948 -79.352648)
		(end 210.581494 -81.181702)
		(width 0.1651)
		(layer "In11.Cu")
		(net "P5E_PEX1_STN2_TX_DP<33>")
	)
	(segment
		(start 219.066364 -32.612838)
		(end 220.08465 -34.478468)
		(width 0.1651)
		(layer "In11.Cu")
		(net "P5E_PEX1_STN2_TX_DP<33>")
	)
	(segment
		(start 194.560952 -140.36929)
		(end 194.219068 -141.840458)
		(width 0.1651)
		(layer "In11.Cu")
		(net "P5E_PEX1_STN2_TX_DP<33>")
	)
	(segment
		(start 193.719196 -150.913846)
		(end 193.718942 -150.913846)
		(width 0.1651)
		(layer "In11.Cu")
		(net "P5E_PEX1_STN2_TX_DP<33>")
	)
	(segment
		(start 193.718942 -150.913846)
		(end 193.492374 -153.60142)
		(width 0.1651)
		(layer "In11.Cu")
		(net "P5E_PEX1_STN2_TX_DP<33>")
	)
	(segment
		(start 194.219068 -141.840458)
		(end 193.946018 -148.226526)
		(width 0.1651)
		(layer "In11.Cu")
		(net "P5E_PEX1_STN2_TX_DP<33>")
	)
	(segment
		(start 220.054424 -34.581846)
		(end 220.291914 -35.016948)
		(width 0.1651)
		(layer "In11.Cu")
		(net "P5E_PEX1_STN2_TX_DP<33>")
	)
	(segment
		(start 193.492374 -153.60142)
		(end 192.50025 -161.016188)
		(width 0.1651)
		(layer "In11.Cu")
		(net "P5E_PEX1_STN2_TX_DP<33>")
	)
	(segment
		(start 173.279816 -271.473168)
		(end 173.279816 -278.20493)
		(width 0.1143)
		(layer "In11.Cu")
		(net "P5E_PEX1_STN2_TX_DP<33>")
	)
	(segment
		(start 220.602048 -35.585146)
		(end 220.839792 -36.020248)
		(width 0.1651)
		(layer "In11.Cu")
		(net "P5E_PEX1_STN2_TX_DP<33>")
	)
	(segment
		(start 267.325602 -109.18444)
		(end 267.620242 -108.8898)
		(width 0.13462)
		(layer "F.Cu")
		(net "P5E_PEX2_STN1_TX_DP<21>")
	)
	(segment
		(start 268.251686 -108.8898)
		(end 268.571726 -109.20984)
		(width 0.13462)
		(layer "F.Cu")
		(net "P5E_PEX2_STN1_TX_DP<21>")
	)
	(segment
		(start 267.620242 -108.8898)
		(end 268.251686 -108.8898)
		(width 0.13462)
		(layer "F.Cu")
		(net "P5E_PEX2_STN1_TX_DP<21>")
	)
	(segment
		(start 296.265854 -264.873486)
		(end 261.391654 -161.844736)
		(width 0.1651)
		(layer "In9.Cu")
		(net "P5E_PEX2_STN1_TX_DP<21>")
	)
	(segment
		(start 296.323766 -280.129488)
		(end 296.220134 -280.025856)
		(width 0.1143)
		(layer "In9.Cu")
		(net "P5E_PEX2_STN1_TX_DP<21>")
	)
	(segment
		(start 261.918958 -117.570758)
		(end 262.108442 -117.113304)
		(width 0.1651)
		(layer "In9.Cu")
		(net "P5E_PEX2_STN1_TX_DP<21>")
	)
	(segment
		(start 296.485564 -280.129488)
		(end 296.323766 -280.129488)
		(width 0.1143)
		(layer "In9.Cu")
		(net "P5E_PEX2_STN1_TX_DP<21>")
	)
	(segment
		(start 265.567922 -109.694726)
		(end 265.686286 -109.694726)
		(width 0.1651)
		(layer "In9.Cu")
		(net "P5E_PEX2_STN1_TX_DP<21>")
	)
	(segment
		(start 264.441686 -111.480854)
		(end 264.591292 -111.419132)
		(width 0.1651)
		(layer "In9.Cu")
		(net "P5E_PEX2_STN1_TX_DP<21>")
	)
	(segment
		(start 266.027916 -109.35335)
		(end 266.027916 -109.234732)
		(width 0.1651)
		(layer "In9.Cu")
		(net "P5E_PEX2_STN1_TX_DP<21>")
	)
	(segment
		(start 296.367454 -269.25905)
		(end 296.367454 -268.76375)
		(width 0.1651)
		(layer "In9.Cu")
		(net "P5E_PEX2_STN1_TX_DP<21>")
	)
	(segment
		(start 296.265854 -271.526)
		(end 296.265854 -269.36065)
		(width 0.1651)
		(layer "In9.Cu")
		(net "P5E_PEX2_STN1_TX_DP<21>")
	)
	(segment
		(start 261.96036 -117.670326)
		(end 261.918958 -117.570758)
		(width 0.1651)
		(layer "In9.Cu")
		(net "P5E_PEX2_STN1_TX_DP<21>")
	)
	(segment
		(start 262.914384 -115.46713)
		(end 262.852408 -115.317778)
		(width 0.1651)
		(layer "In9.Cu")
		(net "P5E_PEX2_STN1_TX_DP<21>")
	)
	(segment
		(start 266.027916 -109.234732)
		(end 266.369038 -108.89361)
		(width 0.1651)
		(layer "In9.Cu")
		(net "P5E_PEX2_STN1_TX_DP<21>")
	)
	(segment
		(start 262.38581 -116.444268)
		(end 262.575294 -115.986814)
		(width 0.1651)
		(layer "In9.Cu")
		(net "P5E_PEX2_STN1_TX_DP<21>")
	)
	(segment
		(start 257.525774 -137.971022)
		(end 257.525774 -131.318762)
		(width 0.1651)
		(layer "In9.Cu")
		(net "P5E_PEX2_STN1_TX_DP<21>")
	)
	(segment
		(start 264.7188 -110.811818)
		(end 264.908284 -110.354364)
		(width 0.1651)
		(layer "In9.Cu")
		(net "P5E_PEX2_STN1_TX_DP<21>")
	)
	(segment
		(start 263.84758 -113.21415)
		(end 263.785604 -113.064798)
		(width 0.1651)
		(layer "In9.Cu")
		(net "P5E_PEX2_STN1_TX_DP<21>")
	)
	(segment
		(start 264.908284 -110.354364)
		(end 265.567922 -109.694726)
		(width 0.1651)
		(layer "In9.Cu")
		(net "P5E_PEX2_STN1_TX_DP<21>")
	)
	(segment
		(start 263.191244 -114.798602)
		(end 263.380982 -114.34064)
		(width 0.1651)
		(layer "In9.Cu")
		(net "P5E_PEX2_STN1_TX_DP<21>")
	)
	(segment
		(start 263.380982 -114.34064)
		(end 263.319006 -114.191288)
		(width 0.1651)
		(layer "In9.Cu")
		(net "P5E_PEX2_STN1_TX_DP<21>")
	)
	(segment
		(start 265.686286 -109.694726)
		(end 266.027916 -109.35335)
		(width 0.1651)
		(layer "In9.Cu")
		(net "P5E_PEX2_STN1_TX_DP<21>")
	)
	(segment
		(start 296.367454 -268.76375)
		(end 296.265854 -268.66215)
		(width 0.1651)
		(layer "In9.Cu")
		(net "P5E_PEX2_STN1_TX_DP<21>")
	)
	(segment
		(start 296.265854 -268.66215)
		(end 296.265854 -264.873486)
		(width 0.1651)
		(layer "In9.Cu")
		(net "P5E_PEX2_STN1_TX_DP<21>")
	)
	(segment
		(start 263.785604 -113.064798)
		(end 263.975088 -112.607344)
		(width 0.1651)
		(layer "In9.Cu")
		(net "P5E_PEX2_STN1_TX_DP<21>")
	)
	(segment
		(start 261.770622 -118.128288)
		(end 261.96036 -117.670326)
		(width 0.1651)
		(layer "In9.Cu")
		(net "P5E_PEX2_STN1_TX_DP<21>")
	)
	(segment
		(start 261.671054 -118.169436)
		(end 261.770622 -118.128288)
		(width 0.1651)
		(layer "In9.Cu")
		(net "P5E_PEX2_STN1_TX_DP<21>")
	)
	(segment
		(start 262.852408 -115.317778)
		(end 263.041892 -114.860324)
		(width 0.1651)
		(layer "In9.Cu")
		(net "P5E_PEX2_STN1_TX_DP<21>")
	)
	(segment
		(start 262.108442 -117.113304)
		(end 262.258048 -117.051582)
		(width 0.1651)
		(layer "In9.Cu")
		(net "P5E_PEX2_STN1_TX_DP<21>")
	)
	(segment
		(start 296.220134 -271.600168)
		(end 296.265854 -271.554448)
		(width 0.1143)
		(layer "In9.Cu")
		(net "P5E_PEX2_STN1_TX_DP<21>")
	)
	(segment
		(start 262.447786 -116.59362)
		(end 262.38581 -116.444268)
		(width 0.1651)
		(layer "In9.Cu")
		(net "P5E_PEX2_STN1_TX_DP<21>")
	)
	(segment
		(start 264.780776 -110.96117)
		(end 264.7188 -110.811818)
		(width 0.1651)
		(layer "In9.Cu")
		(net "P5E_PEX2_STN1_TX_DP<21>")
	)
	(segment
		(start 263.319006 -114.191288)
		(end 263.50849 -113.733834)
		(width 0.1651)
		(layer "In9.Cu")
		(net "P5E_PEX2_STN1_TX_DP<21>")
	)
	(segment
		(start 296.220134 -280.025856)
		(end 296.220134 -271.600168)
		(width 0.1143)
		(layer "In9.Cu")
		(net "P5E_PEX2_STN1_TX_DP<21>")
	)
	(segment
		(start 296.599864 -279.749504)
		(end 296.599864 -280.015188)
		(width 0.1143)
		(layer "In9.Cu")
		(net "P5E_PEX2_STN1_TX_DP<21>")
	)
	(segment
		(start 257.525774 -131.318762)
		(end 261.085584 -119.582946)
		(width 0.1651)
		(layer "In9.Cu")
		(net "P5E_PEX2_STN1_TX_DP<21>")
	)
	(segment
		(start 266.369038 -108.89361)
		(end 267.034772 -108.89361)
		(width 0.1651)
		(layer "In9.Cu")
		(net "P5E_PEX2_STN1_TX_DP<21>")
	)
	(segment
		(start 260.819138 -158.966408)
		(end 260.091936 -144.166082)
		(width 0.1651)
		(layer "In9.Cu")
		(net "P5E_PEX2_STN1_TX_DP<21>")
	)
	(segment
		(start 264.124694 -112.545622)
		(end 264.314178 -112.08766)
		(width 0.1651)
		(layer "In9.Cu")
		(net "P5E_PEX2_STN1_TX_DP<21>")
	)
	(segment
		(start 296.265854 -269.36065)
		(end 296.367454 -269.25905)
		(width 0.1651)
		(layer "In9.Cu")
		(net "P5E_PEX2_STN1_TX_DP<21>")
	)
	(segment
		(start 262.575294 -115.986814)
		(end 262.724646 -115.925092)
		(width 0.1651)
		(layer "In9.Cu")
		(net "P5E_PEX2_STN1_TX_DP<21>")
	)
	(segment
		(start 263.975088 -112.607344)
		(end 264.124694 -112.545622)
		(width 0.1651)
		(layer "In9.Cu")
		(net "P5E_PEX2_STN1_TX_DP<21>")
	)
	(segment
		(start 261.391654 -161.844736)
		(end 260.819138 -158.966408)
		(width 0.1651)
		(layer "In9.Cu")
		(net "P5E_PEX2_STN1_TX_DP<21>")
	)
	(segment
		(start 264.252202 -111.938308)
		(end 264.441686 -111.480854)
		(width 0.1651)
		(layer "In9.Cu")
		(net "P5E_PEX2_STN1_TX_DP<21>")
	)
	(segment
		(start 260.091936 -144.166082)
		(end 257.525774 -137.971022)
		(width 0.1651)
		(layer "In9.Cu")
		(net "P5E_PEX2_STN1_TX_DP<21>")
	)
	(segment
		(start 262.258048 -117.051582)
		(end 262.447786 -116.59362)
		(width 0.1651)
		(layer "In9.Cu")
		(net "P5E_PEX2_STN1_TX_DP<21>")
	)
	(segment
		(start 263.658096 -113.672112)
		(end 263.84758 -113.21415)
		(width 0.1651)
		(layer "In9.Cu")
		(net "P5E_PEX2_STN1_TX_DP<21>")
	)
	(segment
		(start 296.265854 -271.554448)
		(end 296.265854 -271.526)
		(width 0.1143)
		(layer "In9.Cu")
		(net "P5E_PEX2_STN1_TX_DP<21>")
	)
	(segment
		(start 262.724646 -115.925092)
		(end 262.914384 -115.46713)
		(width 0.1651)
		(layer "In9.Cu")
		(net "P5E_PEX2_STN1_TX_DP<21>")
	)
	(segment
		(start 264.314178 -112.08766)
		(end 264.252202 -111.938308)
		(width 0.1651)
		(layer "In9.Cu")
		(net "P5E_PEX2_STN1_TX_DP<21>")
	)
	(segment
		(start 267.034772 -108.89361)
		(end 267.325602 -109.18444)
		(width 0.1651)
		(layer "In9.Cu")
		(net "P5E_PEX2_STN1_TX_DP<21>")
	)
	(segment
		(start 263.041892 -114.860324)
		(end 263.191244 -114.798602)
		(width 0.1651)
		(layer "In9.Cu")
		(net "P5E_PEX2_STN1_TX_DP<21>")
	)
	(segment
		(start 263.50849 -113.733834)
		(end 263.658096 -113.672112)
		(width 0.1651)
		(layer "In9.Cu")
		(net "P5E_PEX2_STN1_TX_DP<21>")
	)
	(segment
		(start 296.599864 -280.015188)
		(end 296.485564 -280.129488)
		(width 0.1143)
		(layer "In9.Cu")
		(net "P5E_PEX2_STN1_TX_DP<21>")
	)
	(segment
		(start 264.591292 -111.419132)
		(end 264.780776 -110.96117)
		(width 0.1651)
		(layer "In9.Cu")
		(net "P5E_PEX2_STN1_TX_DP<21>")
	)
	(segment
		(start 261.085584 -119.582946)
		(end 261.671054 -118.169436)
		(width 0.1651)
		(layer "In9.Cu")
		(net "P5E_PEX2_STN1_TX_DP<21>")
	)
	(segment
		(start 337.943444 -355.026722)
		(end 338.238084 -354.732082)
		(width 0.13462)
		(layer "F.Cu")
		(net "P5E_PEX2_STN6_TX_DN<99>")
	)
	(segment
		(start 337.943444 -355.658166)
		(end 337.943444 -355.026722)
		(width 0.13462)
		(layer "F.Cu")
		(net "P5E_PEX2_STN6_TX_DN<99>")
	)
	(segment
		(start 338.263484 -355.978206)
		(end 337.943444 -355.658166)
		(width 0.13462)
		(layer "F.Cu")
		(net "P5E_PEX2_STN6_TX_DN<99>")
	)
	(segment
		(start 287.12668 -322.356734)
		(end 286.922464 -322.152772)
		(width 0.1651)
		(layer "In13.Cu")
		(net "P5E_PEX2_STN6_TX_DN<99>")
	)
	(segment
		(start 286.985456 -311.670192)
		(end 287.099756 -311.784492)
		(width 0.1143)
		(layer "In13.Cu")
		(net "P5E_PEX2_STN6_TX_DN<99>")
	)
	(segment
		(start 337.947254 -354.441252)
		(end 337.947254 -353.930966)
		(width 0.1651)
		(layer "In13.Cu")
		(net "P5E_PEX2_STN6_TX_DN<99>")
	)
	(segment
		(start 298.76369 -324.640194)
		(end 298.683426 -324.520814)
		(width 0.1651)
		(layer "In13.Cu")
		(net "P5E_PEX2_STN6_TX_DN<99>")
	)
	(segment
		(start 339.501734 -352.376486)
		(end 339.501734 -342.137746)
		(width 0.1651)
		(layer "In13.Cu")
		(net "P5E_PEX2_STN6_TX_DN<99>")
	)
	(segment
		(start 287.099756 -311.784492)
		(end 287.099756 -312.049922)
		(width 0.1143)
		(layer "In13.Cu")
		(net "P5E_PEX2_STN6_TX_DN<99>")
	)
	(segment
		(start 334.199484 -336.485484)
		(end 314.986924 -327.823576)
		(width 0.1651)
		(layer "In13.Cu")
		(net "P5E_PEX2_STN6_TX_DN<99>")
	)
	(segment
		(start 286.720026 -319.971928)
		(end 286.720026 -311.773824)
		(width 0.1143)
		(layer "In13.Cu")
		(net "P5E_PEX2_STN6_TX_DN<99>")
	)
	(segment
		(start 298.683426 -324.520814)
		(end 298.19727 -324.42531)
		(width 0.1651)
		(layer "In13.Cu")
		(net "P5E_PEX2_STN6_TX_DN<99>")
	)
	(segment
		(start 298.07789 -324.505574)
		(end 297.591988 -324.410324)
		(width 0.1651)
		(layer "In13.Cu")
		(net "P5E_PEX2_STN6_TX_DN<99>")
	)
	(segment
		(start 286.922464 -322.152772)
		(end 286.765746 -321.774312)
		(width 0.1651)
		(layer "In13.Cu")
		(net "P5E_PEX2_STN6_TX_DN<99>")
	)
	(segment
		(start 338.871814 -341.109808)
		(end 334.199484 -336.485484)
		(width 0.1651)
		(layer "In13.Cu")
		(net "P5E_PEX2_STN6_TX_DN<99>")
	)
	(segment
		(start 286.720026 -311.773824)
		(end 286.823658 -311.670192)
		(width 0.1143)
		(layer "In13.Cu")
		(net "P5E_PEX2_STN6_TX_DN<99>")
	)
	(segment
		(start 286.765746 -321.774312)
		(end 286.765746 -320.046096)
		(width 0.1651)
		(layer "In13.Cu")
		(net "P5E_PEX2_STN6_TX_DN<99>")
	)
	(segment
		(start 339.501734 -342.137746)
		(end 338.871814 -341.109808)
		(width 0.1651)
		(layer "In13.Cu")
		(net "P5E_PEX2_STN6_TX_DN<99>")
	)
	(segment
		(start 298.19727 -324.42531)
		(end 298.07789 -324.505574)
		(width 0.1651)
		(layer "In13.Cu")
		(net "P5E_PEX2_STN6_TX_DN<99>")
	)
	(segment
		(start 337.947254 -353.930966)
		(end 339.501734 -352.376486)
		(width 0.1651)
		(layer "In13.Cu")
		(net "P5E_PEX2_STN6_TX_DN<99>")
	)
	(segment
		(start 286.765746 -320.046096)
		(end 286.765746 -320.017648)
		(width 0.1143)
		(layer "In13.Cu")
		(net "P5E_PEX2_STN6_TX_DN<99>")
	)
	(segment
		(start 297.511978 -324.290944)
		(end 297.025568 -324.19544)
		(width 0.1651)
		(layer "In13.Cu")
		(net "P5E_PEX2_STN6_TX_DN<99>")
	)
	(segment
		(start 297.025568 -324.19544)
		(end 296.906442 -324.275704)
		(width 0.1651)
		(layer "In13.Cu")
		(net "P5E_PEX2_STN6_TX_DN<99>")
	)
	(segment
		(start 314.986924 -327.823576)
		(end 298.76369 -324.640194)
		(width 0.1651)
		(layer "In13.Cu")
		(net "P5E_PEX2_STN6_TX_DN<99>")
	)
	(segment
		(start 286.765746 -320.017648)
		(end 286.720026 -319.971928)
		(width 0.1143)
		(layer "In13.Cu")
		(net "P5E_PEX2_STN6_TX_DN<99>")
	)
	(segment
		(start 338.238084 -354.732082)
		(end 337.947254 -354.441252)
		(width 0.1651)
		(layer "In13.Cu")
		(net "P5E_PEX2_STN6_TX_DN<99>")
	)
	(segment
		(start 297.591988 -324.410324)
		(end 297.511978 -324.290944)
		(width 0.1651)
		(layer "In13.Cu")
		(net "P5E_PEX2_STN6_TX_DN<99>")
	)
	(segment
		(start 296.906442 -324.275704)
		(end 287.12668 -322.356734)
		(width 0.1651)
		(layer "In13.Cu")
		(net "P5E_PEX2_STN6_TX_DN<99>")
	)
	(segment
		(start 286.823658 -311.670192)
		(end 286.985456 -311.670192)
		(width 0.1143)
		(layer "In13.Cu")
		(net "P5E_PEX2_STN6_TX_DN<99>")
	)
	(segment
		(start 383.4257 -123.68784)
		(end 383.72034 -123.3932)
		(width 0.13462)
		(layer "F.Cu")
		(net "P5E_PEX3_STN1_TX_DN<26>")
	)
	(segment
		(start 383.72034 -123.3932)
		(end 384.351784 -123.3932)
		(width 0.13462)
		(layer "F.Cu")
		(net "P5E_PEX3_STN1_TX_DN<26>")
	)
	(segment
		(start 384.351784 -123.3932)
		(end 384.671824 -123.71324)
		(width 0.13462)
		(layer "F.Cu")
		(net "P5E_PEX3_STN1_TX_DN<26>")
	)
	(segment
		(start 379.266958 -131.159504)
		(end 379.082046 -131.605528)
		(width 0.1651)
		(layer "In9.Cu")
		(net "P5E_PEX3_STN1_TX_DN<26>")
	)
	(segment
		(start 383.13487 -123.39701)
		(end 382.4986 -123.39701)
		(width 0.1651)
		(layer "In9.Cu")
		(net "P5E_PEX3_STN1_TX_DN<26>")
	)
	(segment
		(start 382.4986 -123.39701)
		(end 382.258824 -123.636786)
		(width 0.1651)
		(layer "In9.Cu")
		(net "P5E_PEX3_STN1_TX_DN<26>")
	)
	(segment
		(start 378.932694 -131.66725)
		(end 378.69876 -132.232146)
		(width 0.1651)
		(layer "In9.Cu")
		(net "P5E_PEX3_STN1_TX_DN<26>")
	)
	(segment
		(start 417.070286 -278.12619)
		(end 417.173664 -278.229568)
		(width 0.1143)
		(layer "In9.Cu")
		(net "P5E_PEX3_STN1_TX_DN<26>")
	)
	(segment
		(start 381.564388 -125.31344)
		(end 381.626364 -125.462792)
		(width 0.1651)
		(layer "In9.Cu")
		(net "P5E_PEX3_STN1_TX_DN<26>")
	)
	(segment
		(start 417.116006 -263.80948)
		(end 417.116006 -271.471898)
		(width 0.1651)
		(layer "In9.Cu")
		(net "P5E_PEX3_STN1_TX_DN<26>")
	)
	(segment
		(start 378.699014 -132.232146)
		(end 378.464572 -132.797296)
		(width 0.1651)
		(layer "In9.Cu")
		(net "P5E_PEX3_STN1_TX_DN<26>")
	)
	(segment
		(start 382.249426 -159.960564)
		(end 382.169416 -160.079944)
		(width 0.1651)
		(layer "In9.Cu")
		(net "P5E_PEX3_STN1_TX_DN<26>")
	)
	(segment
		(start 380.255526 -128.772412)
		(end 380.070868 -129.218436)
		(width 0.1651)
		(layer "In9.Cu")
		(net "P5E_PEX3_STN1_TX_DN<26>")
	)
	(segment
		(start 378.464572 -132.797296)
		(end 378.464572 -136.961118)
		(width 0.1651)
		(layer "In9.Cu")
		(net "P5E_PEX3_STN1_TX_DN<26>")
	)
	(segment
		(start 378.464572 -136.961118)
		(end 381.033274 -143.16202)
		(width 0.1651)
		(layer "In9.Cu")
		(net "P5E_PEX3_STN1_TX_DN<26>")
	)
	(segment
		(start 417.335462 -278.229568)
		(end 417.449762 -278.115268)
		(width 0.1143)
		(layer "In9.Cu")
		(net "P5E_PEX3_STN1_TX_DN<26>")
	)
	(segment
		(start 417.116006 -271.471898)
		(end 417.116006 -271.500346)
		(width 0.1143)
		(layer "In9.Cu")
		(net "P5E_PEX3_STN1_TX_DN<26>")
	)
	(segment
		(start 381.749046 -124.86767)
		(end 381.564388 -125.31344)
		(width 0.1651)
		(layer "In9.Cu")
		(net "P5E_PEX3_STN1_TX_DN<26>")
	)
	(segment
		(start 380.070868 -129.218436)
		(end 379.921262 -129.280412)
		(width 0.1651)
		(layer "In9.Cu")
		(net "P5E_PEX3_STN1_TX_DN<26>")
	)
	(segment
		(start 382.169416 -160.079944)
		(end 382.406652 -161.272474)
		(width 0.1651)
		(layer "In9.Cu")
		(net "P5E_PEX3_STN1_TX_DN<26>")
	)
	(segment
		(start 379.082046 -131.605528)
		(end 378.93244 -131.66725)
		(width 0.1651)
		(layer "In9.Cu")
		(net "P5E_PEX3_STN1_TX_DN<26>")
	)
	(segment
		(start 417.070286 -271.546066)
		(end 417.070286 -278.12619)
		(width 0.1143)
		(layer "In9.Cu")
		(net "P5E_PEX3_STN1_TX_DN<26>")
	)
	(segment
		(start 417.116006 -271.500346)
		(end 417.070286 -271.546066)
		(width 0.1143)
		(layer "In9.Cu")
		(net "P5E_PEX3_STN1_TX_DN<26>")
	)
	(segment
		(start 380.19355 -128.62306)
		(end 380.255526 -128.772412)
		(width 0.1651)
		(layer "In9.Cu")
		(net "P5E_PEX3_STN1_TX_DN<26>")
	)
	(segment
		(start 381.898652 -124.805694)
		(end 381.749046 -124.86767)
		(width 0.1651)
		(layer "In9.Cu")
		(net "P5E_PEX3_STN1_TX_DN<26>")
	)
	(segment
		(start 417.173664 -278.229568)
		(end 417.335462 -278.229568)
		(width 0.1143)
		(layer "In9.Cu")
		(net "P5E_PEX3_STN1_TX_DN<26>")
	)
	(segment
		(start 381.169418 -126.565914)
		(end 380.98476 -127.011938)
		(width 0.1651)
		(layer "In9.Cu")
		(net "P5E_PEX3_STN1_TX_DN<26>")
	)
	(segment
		(start 381.2921 -125.970792)
		(end 381.107442 -126.416562)
		(width 0.1651)
		(layer "In9.Cu")
		(net "P5E_PEX3_STN1_TX_DN<26>")
	)
	(segment
		(start 379.613922 -130.321558)
		(end 379.464316 -130.383534)
		(width 0.1651)
		(layer "In9.Cu")
		(net "P5E_PEX3_STN1_TX_DN<26>")
	)
	(segment
		(start 379.464316 -130.383534)
		(end 379.464316 -130.383788)
		(width 0.1651)
		(layer "In9.Cu")
		(net "P5E_PEX3_STN1_TX_DN<26>")
	)
	(segment
		(start 380.650496 -127.519938)
		(end 380.712472 -127.66929)
		(width 0.1651)
		(layer "In9.Cu")
		(net "P5E_PEX3_STN1_TX_DN<26>")
	)
	(segment
		(start 380.712472 -127.66929)
		(end 380.527814 -128.115314)
		(width 0.1651)
		(layer "In9.Cu")
		(net "P5E_PEX3_STN1_TX_DN<26>")
	)
	(segment
		(start 379.204982 -131.010152)
		(end 379.266958 -131.159504)
		(width 0.1651)
		(layer "In9.Cu")
		(net "P5E_PEX3_STN1_TX_DN<26>")
	)
	(segment
		(start 382.155192 -159.487108)
		(end 382.249426 -159.960564)
		(width 0.1651)
		(layer "In9.Cu")
		(net "P5E_PEX3_STN1_TX_DN<26>")
	)
	(segment
		(start 380.835154 -127.074168)
		(end 380.650496 -127.519938)
		(width 0.1651)
		(layer "In9.Cu")
		(net "P5E_PEX3_STN1_TX_DN<26>")
	)
	(segment
		(start 381.441706 -125.908816)
		(end 381.2921 -125.970792)
		(width 0.1651)
		(layer "In9.Cu")
		(net "P5E_PEX3_STN1_TX_DN<26>")
	)
	(segment
		(start 382.406652 -161.272474)
		(end 417.116006 -263.80948)
		(width 0.1651)
		(layer "In9.Cu")
		(net "P5E_PEX3_STN1_TX_DN<26>")
	)
	(segment
		(start 381.033274 -143.16202)
		(end 381.76581 -158.050738)
		(width 0.1651)
		(layer "In9.Cu")
		(net "P5E_PEX3_STN1_TX_DN<26>")
	)
	(segment
		(start 378.69876 -132.232146)
		(end 378.699014 -132.232146)
		(width 0.1651)
		(layer "In9.Cu")
		(net "P5E_PEX3_STN1_TX_DN<26>")
	)
	(segment
		(start 379.921262 -129.280412)
		(end 379.736604 -129.726182)
		(width 0.1651)
		(layer "In9.Cu")
		(net "P5E_PEX3_STN1_TX_DN<26>")
	)
	(segment
		(start 382.021334 -124.210318)
		(end 382.08331 -124.35967)
		(width 0.1651)
		(layer "In9.Cu")
		(net "P5E_PEX3_STN1_TX_DN<26>")
	)
	(segment
		(start 380.98476 -127.011938)
		(end 380.835154 -127.073914)
		(width 0.1651)
		(layer "In9.Cu")
		(net "P5E_PEX3_STN1_TX_DN<26>")
	)
	(segment
		(start 381.76581 -158.050738)
		(end 382.035558 -159.407098)
		(width 0.1651)
		(layer "In9.Cu")
		(net "P5E_PEX3_STN1_TX_DN<26>")
	)
	(segment
		(start 379.736604 -129.726182)
		(end 379.79858 -129.875534)
		(width 0.1651)
		(layer "In9.Cu")
		(net "P5E_PEX3_STN1_TX_DN<26>")
	)
	(segment
		(start 383.4257 -123.68784)
		(end 383.13487 -123.39701)
		(width 0.1651)
		(layer "In9.Cu")
		(net "P5E_PEX3_STN1_TX_DN<26>")
	)
	(segment
		(start 379.79858 -129.875534)
		(end 379.613922 -130.321558)
		(width 0.1651)
		(layer "In9.Cu")
		(net "P5E_PEX3_STN1_TX_DN<26>")
	)
	(segment
		(start 382.08331 -124.35967)
		(end 381.898652 -124.805694)
		(width 0.1651)
		(layer "In9.Cu")
		(net "P5E_PEX3_STN1_TX_DN<26>")
	)
	(segment
		(start 380.835154 -127.073914)
		(end 380.835154 -127.074168)
		(width 0.1651)
		(layer "In9.Cu")
		(net "P5E_PEX3_STN1_TX_DN<26>")
	)
	(segment
		(start 381.107442 -126.416562)
		(end 381.169418 -126.565914)
		(width 0.1651)
		(layer "In9.Cu")
		(net "P5E_PEX3_STN1_TX_DN<26>")
	)
	(segment
		(start 380.378208 -128.17729)
		(end 380.19355 -128.62306)
		(width 0.1651)
		(layer "In9.Cu")
		(net "P5E_PEX3_STN1_TX_DN<26>")
	)
	(segment
		(start 382.035558 -159.407098)
		(end 382.155192 -159.487108)
		(width 0.1651)
		(layer "In9.Cu")
		(net "P5E_PEX3_STN1_TX_DN<26>")
	)
	(segment
		(start 378.93244 -131.66725)
		(end 378.932694 -131.66725)
		(width 0.1651)
		(layer "In9.Cu")
		(net "P5E_PEX3_STN1_TX_DN<26>")
	)
	(segment
		(start 380.527814 -128.115314)
		(end 380.378208 -128.17729)
		(width 0.1651)
		(layer "In9.Cu")
		(net "P5E_PEX3_STN1_TX_DN<26>")
	)
	(segment
		(start 382.258824 -123.636786)
		(end 382.021334 -124.210318)
		(width 0.1651)
		(layer "In9.Cu")
		(net "P5E_PEX3_STN1_TX_DN<26>")
	)
	(segment
		(start 381.626364 -125.462792)
		(end 381.441706 -125.908816)
		(width 0.1651)
		(layer "In9.Cu")
		(net "P5E_PEX3_STN1_TX_DN<26>")
	)
	(segment
		(start 417.449762 -278.115268)
		(end 417.449762 -277.849838)
		(width 0.1143)
		(layer "In9.Cu")
		(net "P5E_PEX3_STN1_TX_DN<26>")
	)
	(segment
		(start 379.464316 -130.383788)
		(end 379.204982 -131.010152)
		(width 0.1651)
		(layer "In9.Cu")
		(net "P5E_PEX3_STN1_TX_DN<26>")
	)
	(segment
		(start 428.517304 -355.02723)
		(end 428.812452 -354.732082)
		(width 0.13462)
		(layer "F.Cu")
		(net "P5E_PEX3_STN7_TX_DP<121>")
	)
	(segment
		(start 428.837852 -355.978206)
		(end 428.517304 -355.657658)
		(width 0.13462)
		(layer "F.Cu")
		(net "P5E_PEX3_STN7_TX_DP<121>")
	)
	(segment
		(start 428.517304 -355.657658)
		(end 428.517304 -355.02723)
		(width 0.13462)
		(layer "F.Cu")
		(net "P5E_PEX3_STN7_TX_DP<121>")
	)
	(segment
		(start 428.812452 -354.732082)
		(end 428.521622 -354.441252)
		(width 0.1651)
		(layer "In11.Cu")
		(net "P5E_PEX3_STN7_TX_DP<121>")
	)
	(segment
		(start 384.81762 -318.036448)
		(end 384.81762 -318.008)
		(width 0.1143)
		(layer "In11.Cu")
		(net "P5E_PEX3_STN7_TX_DP<121>")
	)
	(segment
		(start 387.27126 -325.80326)
		(end 385.100322 -323.632322)
		(width 0.1651)
		(layer "In11.Cu")
		(net "P5E_PEX3_STN7_TX_DP<121>")
	)
	(segment
		(start 430.076102 -352.376486)
		(end 430.076102 -341.9348)
		(width 0.1651)
		(layer "In11.Cu")
		(net "P5E_PEX3_STN7_TX_DP<121>")
	)
	(segment
		(start 384.7719 -317.96228)
		(end 384.7719 -312.849514)
		(width 0.1143)
		(layer "In11.Cu")
		(net "P5E_PEX3_STN7_TX_DP<121>")
	)
	(segment
		(start 385.720082 -312.405014)
		(end 385.720082 -312.164222)
		(width 0.1143)
		(layer "In11.Cu")
		(net "P5E_PEX3_STN7_TX_DP<121>")
	)
	(segment
		(start 385.834382 -312.049922)
		(end 386.099812 -312.049922)
		(width 0.1143)
		(layer "In11.Cu")
		(net "P5E_PEX3_STN7_TX_DP<121>")
	)
	(segment
		(start 428.521622 -353.930966)
		(end 430.076102 -352.376486)
		(width 0.1651)
		(layer "In11.Cu")
		(net "P5E_PEX3_STN7_TX_DP<121>")
	)
	(segment
		(start 384.81762 -318.008)
		(end 384.7719 -317.96228)
		(width 0.1143)
		(layer "In11.Cu")
		(net "P5E_PEX3_STN7_TX_DP<121>")
	)
	(segment
		(start 385.494276 -312.63082)
		(end 385.720082 -312.405014)
		(width 0.1143)
		(layer "In11.Cu")
		(net "P5E_PEX3_STN7_TX_DP<121>")
	)
	(segment
		(start 384.7719 -312.849514)
		(end 384.990594 -312.63082)
		(width 0.1143)
		(layer "In11.Cu")
		(net "P5E_PEX3_STN7_TX_DP<121>")
	)
	(segment
		(start 421.368982 -334.806036)
		(end 387.27126 -325.80326)
		(width 0.1651)
		(layer "In11.Cu")
		(net "P5E_PEX3_STN7_TX_DP<121>")
	)
	(segment
		(start 384.990594 -312.63082)
		(end 385.494276 -312.63082)
		(width 0.1143)
		(layer "In11.Cu")
		(net "P5E_PEX3_STN7_TX_DP<121>")
	)
	(segment
		(start 429.1076 -340.2076)
		(end 421.368982 -334.806036)
		(width 0.1651)
		(layer "In11.Cu")
		(net "P5E_PEX3_STN7_TX_DP<121>")
	)
	(segment
		(start 385.720082 -312.164222)
		(end 385.834382 -312.049922)
		(width 0.1143)
		(layer "In11.Cu")
		(net "P5E_PEX3_STN7_TX_DP<121>")
	)
	(segment
		(start 384.81762 -322.950332)
		(end 384.81762 -318.036448)
		(width 0.1651)
		(layer "In11.Cu")
		(net "P5E_PEX3_STN7_TX_DP<121>")
	)
	(segment
		(start 385.100322 -323.632322)
		(end 384.81762 -322.950332)
		(width 0.1651)
		(layer "In11.Cu")
		(net "P5E_PEX3_STN7_TX_DP<121>")
	)
	(segment
		(start 428.521622 -354.441252)
		(end 428.521622 -353.930966)
		(width 0.1651)
		(layer "In11.Cu")
		(net "P5E_PEX3_STN7_TX_DP<121>")
	)
	(segment
		(start 430.076102 -341.9348)
		(end 429.1076 -340.2076)
		(width 0.1651)
		(layer "In11.Cu")
		(net "P5E_PEX3_STN7_TX_DP<121>")
	)
	(segment
		(start 99.947222 -30.92069)
		(end 99.653852 -30.62732)
		(width 0.13462)
		(layer "F.Cu")
		(net "P5E_PEX0_STN2_TX_DP<33>")
	)
	(segment
		(start 99.019868 -30.62732)
		(end 98.701098 -30.94609)
		(width 0.13462)
		(layer "F.Cu")
		(net "P5E_PEX0_STN2_TX_DP<33>")
	)
	(segment
		(start 99.653852 -30.62732)
		(end 99.019868 -30.62732)
		(width 0.13462)
		(layer "F.Cu")
		(net "P5E_PEX0_STN2_TX_DP<33>")
	)
	(segment
		(start 104.389428 -35.37839)
		(end 104.492806 -35.408616)
		(width 0.1651)
		(layer "In11.Cu")
		(net "P5E_PEX0_STN2_TX_DP<33>")
	)
	(segment
		(start 78.460854 -133.834886)
		(end 78.460854 -140.36929)
		(width 0.1651)
		(layer "In11.Cu")
		(net "P5E_PEX0_STN2_TX_DP<33>")
	)
	(segment
		(start 87.61349 -93.315536)
		(end 80.737456 -105.463594)
		(width 0.1651)
		(layer "In11.Cu")
		(net "P5E_PEX0_STN2_TX_DP<33>")
	)
	(segment
		(start 94.481396 -81.181702)
		(end 87.613236 -93.315536)
		(width 0.1651)
		(layer "In11.Cu")
		(net "P5E_PEX0_STN2_TX_DP<33>")
	)
	(segment
		(start 107.88904 -42.583862)
		(end 108.16082 -56.83631)
		(width 0.1651)
		(layer "In11.Cu")
		(net "P5E_PEX0_STN2_TX_DP<33>")
	)
	(segment
		(start 57.394856 -278.420068)
		(end 57.635648 -278.420068)
		(width 0.1143)
		(layer "In11.Cu")
		(net "P5E_PEX0_STN2_TX_DP<33>")
	)
	(segment
		(start 77.618844 -150.913846)
		(end 77.392276 -153.60142)
		(width 0.1651)
		(layer "In11.Cu")
		(net "P5E_PEX0_STN2_TX_DP<33>")
	)
	(segment
		(start 57.179718 -278.20493)
		(end 57.394856 -278.420068)
		(width 0.1143)
		(layer "In11.Cu")
		(net "P5E_PEX0_STN2_TX_DP<33>")
	)
	(segment
		(start 103.634286 -33.83661)
		(end 103.603806 -33.939988)
		(width 0.1651)
		(layer "In11.Cu")
		(net "P5E_PEX0_STN2_TX_DP<33>")
	)
	(segment
		(start 102.966266 -32.612838)
		(end 103.634286 -33.83661)
		(width 0.1651)
		(layer "In11.Cu")
		(net "P5E_PEX0_STN2_TX_DP<33>")
	)
	(segment
		(start 87.613236 -93.315536)
		(end 87.61349 -93.315536)
		(width 0.1651)
		(layer "In11.Cu")
		(net "P5E_PEX0_STN2_TX_DP<33>")
	)
	(segment
		(start 104.492552 -35.40887)
		(end 107.396534 -40.728392)
		(width 0.1651)
		(layer "In11.Cu")
		(net "P5E_PEX0_STN2_TX_DP<33>")
	)
	(segment
		(start 99.947222 -30.92069)
		(end 100.238052 -30.62986)
		(width 0.1651)
		(layer "In11.Cu")
		(net "P5E_PEX0_STN2_TX_DP<33>")
	)
	(segment
		(start 57.133998 -271.399)
		(end 57.133998 -271.427448)
		(width 0.1143)
		(layer "In11.Cu")
		(net "P5E_PEX0_STN2_TX_DP<33>")
	)
	(segment
		(start 57.179718 -271.473168)
		(end 57.179718 -278.20493)
		(width 0.1143)
		(layer "In11.Cu")
		(net "P5E_PEX0_STN2_TX_DP<33>")
	)
	(segment
		(start 104.151684 -34.943288)
		(end 104.389428 -35.37839)
		(width 0.1651)
		(layer "In11.Cu")
		(net "P5E_PEX0_STN2_TX_DP<33>")
	)
	(segment
		(start 100.680012 -30.62986)
		(end 101.186742 -30.852618)
		(width 0.1651)
		(layer "In11.Cu")
		(net "P5E_PEX0_STN2_TX_DP<33>")
	)
	(segment
		(start 103.84155 -34.374836)
		(end 103.944928 -34.405316)
		(width 0.1651)
		(layer "In11.Cu")
		(net "P5E_PEX0_STN2_TX_DP<33>")
	)
	(segment
		(start 78.460854 -140.36929)
		(end 78.11897 -141.840458)
		(width 0.1651)
		(layer "In11.Cu")
		(net "P5E_PEX0_STN2_TX_DP<33>")
	)
	(segment
		(start 96.33585 -79.352648)
		(end 94.481396 -81.181702)
		(width 0.1651)
		(layer "In11.Cu")
		(net "P5E_PEX0_STN2_TX_DP<33>")
	)
	(segment
		(start 107.396534 -40.728392)
		(end 107.88904 -42.583862)
		(width 0.1651)
		(layer "In11.Cu")
		(net "P5E_PEX0_STN2_TX_DP<33>")
	)
	(segment
		(start 104.492806 -35.408616)
		(end 104.492552 -35.40887)
		(width 0.1651)
		(layer "In11.Cu")
		(net "P5E_PEX0_STN2_TX_DP<33>")
	)
	(segment
		(start 77.392276 -153.60142)
		(end 76.400152 -161.016188)
		(width 0.1651)
		(layer "In11.Cu")
		(net "P5E_PEX0_STN2_TX_DP<33>")
	)
	(segment
		(start 79.113888 -118.530624)
		(end 78.460854 -133.834886)
		(width 0.1651)
		(layer "In11.Cu")
		(net "P5E_PEX0_STN2_TX_DP<33>")
	)
	(segment
		(start 103.61803 -74.822304)
		(end 102.903274 -75.784202)
		(width 0.1651)
		(layer "In11.Cu")
		(net "P5E_PEX0_STN2_TX_DP<33>")
	)
	(segment
		(start 103.944928 -34.405316)
		(end 104.182164 -34.83991)
		(width 0.1651)
		(layer "In11.Cu")
		(net "P5E_PEX0_STN2_TX_DP<33>")
	)
	(segment
		(start 108.16082 -56.83631)
		(end 105.903522 -68.424552)
		(width 0.1651)
		(layer "In11.Cu")
		(net "P5E_PEX0_STN2_TX_DP<33>")
	)
	(segment
		(start 103.603806 -33.939988)
		(end 103.84155 -34.374836)
		(width 0.1651)
		(layer "In11.Cu")
		(net "P5E_PEX0_STN2_TX_DP<33>")
	)
	(segment
		(start 77.619098 -150.913846)
		(end 77.618844 -150.913846)
		(width 0.1651)
		(layer "In11.Cu")
		(net "P5E_PEX0_STN2_TX_DP<33>")
	)
	(segment
		(start 57.749948 -278.534368)
		(end 57.749948 -278.799798)
		(width 0.1143)
		(layer "In11.Cu")
		(net "P5E_PEX0_STN2_TX_DP<33>")
	)
	(segment
		(start 104.182164 -34.83991)
		(end 104.151684 -34.943288)
		(width 0.1651)
		(layer "In11.Cu")
		(net "P5E_PEX0_STN2_TX_DP<33>")
	)
	(segment
		(start 102.903274 -75.784202)
		(end 96.33585 -79.352648)
		(width 0.1651)
		(layer "In11.Cu")
		(net "P5E_PEX0_STN2_TX_DP<33>")
	)
	(segment
		(start 57.635648 -278.420068)
		(end 57.749948 -278.534368)
		(width 0.1143)
		(layer "In11.Cu")
		(net "P5E_PEX0_STN2_TX_DP<33>")
	)
	(segment
		(start 78.11897 -141.840458)
		(end 77.84592 -148.226526)
		(width 0.1651)
		(layer "In11.Cu")
		(net "P5E_PEX0_STN2_TX_DP<33>")
	)
	(segment
		(start 77.84592 -148.226526)
		(end 77.619098 -150.913846)
		(width 0.1651)
		(layer "In11.Cu")
		(net "P5E_PEX0_STN2_TX_DP<33>")
	)
	(segment
		(start 57.133998 -265.833606)
		(end 57.133998 -271.399)
		(width 0.1651)
		(layer "In11.Cu")
		(net "P5E_PEX0_STN2_TX_DP<33>")
	)
	(segment
		(start 100.238052 -30.62986)
		(end 100.680012 -30.62986)
		(width 0.1651)
		(layer "In11.Cu")
		(net "P5E_PEX0_STN2_TX_DP<33>")
	)
	(segment
		(start 57.133998 -271.427448)
		(end 57.179718 -271.473168)
		(width 0.1143)
		(layer "In11.Cu")
		(net "P5E_PEX0_STN2_TX_DP<33>")
	)
	(segment
		(start 76.400152 -161.016188)
		(end 57.133998 -265.833606)
		(width 0.1651)
		(layer "In11.Cu")
		(net "P5E_PEX0_STN2_TX_DP<33>")
	)
	(segment
		(start 105.903522 -68.424552)
		(end 103.61803 -74.822304)
		(width 0.1651)
		(layer "In11.Cu")
		(net "P5E_PEX0_STN2_TX_DP<33>")
	)
	(segment
		(start 80.737456 -105.463594)
		(end 79.113888 -118.530624)
		(width 0.1651)
		(layer "In11.Cu")
		(net "P5E_PEX0_STN2_TX_DP<33>")
	)
	(segment
		(start 101.186742 -30.852618)
		(end 102.966266 -32.612838)
		(width 0.1651)
		(layer "In11.Cu")
		(net "P5E_PEX0_STN2_TX_DP<33>")
	)
	(segment
		(start 161.405316 -29.114242)
		(end 161.120074 -28.829)
		(width 0.13462)
		(layer "F.Cu")
		(net "P5E_PEX1_STN2_TX_DP<40>")
	)
	(segment
		(start 161.120074 -28.829)
		(end 160.469834 -28.829)
		(width 0.13462)
		(layer "F.Cu")
		(net "P5E_PEX1_STN2_TX_DP<40>")
	)
	(segment
		(start 160.469834 -28.829)
		(end 160.159192 -29.139642)
		(width 0.13462)
		(layer "F.Cu")
		(net "P5E_PEX1_STN2_TX_DP<40>")
	)
	(segment
		(start 173.590458 -119.281702)
		(end 172.24883 -135.243824)
		(width 0.1651)
		(layer "In11.Cu")
		(net "P5E_PEX1_STN2_TX_DP<40>")
	)
	(segment
		(start 169.682922 -34.872168)
		(end 179.403502 -47.064676)
		(width 0.1651)
		(layer "In11.Cu")
		(net "P5E_PEX1_STN2_TX_DP<40>")
	)
	(segment
		(start 166.584122 -271.427448)
		(end 166.629842 -271.473168)
		(width 0.1143)
		(layer "In11.Cu")
		(net "P5E_PEX1_STN2_TX_DP<40>")
	)
	(segment
		(start 161.696146 -28.823412)
		(end 163.982908 -28.823412)
		(width 0.1651)
		(layer "In11.Cu")
		(net "P5E_PEX1_STN2_TX_DP<40>")
	)
	(segment
		(start 166.629842 -280.10485)
		(end 166.84498 -280.319988)
		(width 0.1143)
		(layer "In11.Cu")
		(net "P5E_PEX1_STN2_TX_DP<40>")
	)
	(segment
		(start 166.592758 -271.105122)
		(end 166.584122 -271.113758)
		(width 0.1651)
		(layer "In11.Cu")
		(net "P5E_PEX1_STN2_TX_DP<40>")
	)
	(segment
		(start 166.219886 -266.03325)
		(end 166.592758 -269.820898)
		(width 0.1651)
		(layer "In11.Cu")
		(net "P5E_PEX1_STN2_TX_DP<40>")
	)
	(segment
		(start 161.405316 -29.114242)
		(end 161.696146 -28.823412)
		(width 0.1651)
		(layer "In11.Cu")
		(net "P5E_PEX1_STN2_TX_DP<40>")
	)
	(segment
		(start 166.592758 -269.820898)
		(end 166.592758 -271.105122)
		(width 0.1651)
		(layer "In11.Cu")
		(net "P5E_PEX1_STN2_TX_DP<40>")
	)
	(segment
		(start 167.085772 -280.319988)
		(end 167.200072 -280.434288)
		(width 0.1143)
		(layer "In11.Cu")
		(net "P5E_PEX1_STN2_TX_DP<40>")
	)
	(segment
		(start 165.245542 -29.349192)
		(end 165.832536 -29.93263)
		(width 0.1651)
		(layer "In11.Cu")
		(net "P5E_PEX1_STN2_TX_DP<40>")
	)
	(segment
		(start 167.200072 -280.434288)
		(end 167.200072 -280.699718)
		(width 0.1143)
		(layer "In11.Cu")
		(net "P5E_PEX1_STN2_TX_DP<40>")
	)
	(segment
		(start 166.584122 -271.113758)
		(end 166.584122 -271.399)
		(width 0.1651)
		(layer "In11.Cu")
		(net "P5E_PEX1_STN2_TX_DP<40>")
	)
	(segment
		(start 180.638196 -69.570346)
		(end 173.590458 -119.281702)
		(width 0.1651)
		(layer "In11.Cu")
		(net "P5E_PEX1_STN2_TX_DP<40>")
	)
	(segment
		(start 166.584122 -271.399)
		(end 166.584122 -271.427448)
		(width 0.1143)
		(layer "In11.Cu")
		(net "P5E_PEX1_STN2_TX_DP<40>")
	)
	(segment
		(start 166.31031 -30.407356)
		(end 166.661592 -30.756352)
		(width 0.1651)
		(layer "In11.Cu")
		(net "P5E_PEX1_STN2_TX_DP<40>")
	)
	(segment
		(start 172.24883 -135.243824)
		(end 165.946074 -252.613668)
		(width 0.1651)
		(layer "In11.Cu")
		(net "P5E_PEX1_STN2_TX_DP<40>")
	)
	(segment
		(start 166.84498 -280.319988)
		(end 167.085772 -280.319988)
		(width 0.1143)
		(layer "In11.Cu")
		(net "P5E_PEX1_STN2_TX_DP<40>")
	)
	(segment
		(start 166.629842 -271.473168)
		(end 166.629842 -280.10485)
		(width 0.1143)
		(layer "In11.Cu")
		(net "P5E_PEX1_STN2_TX_DP<40>")
	)
	(segment
		(start 165.946074 -252.613668)
		(end 166.219886 -266.03325)
		(width 0.1651)
		(layer "In11.Cu")
		(net "P5E_PEX1_STN2_TX_DP<40>")
	)
	(segment
		(start 181.0639 -60.607194)
		(end 180.638196 -69.570346)
		(width 0.1651)
		(layer "In11.Cu")
		(net "P5E_PEX1_STN2_TX_DP<40>")
	)
	(segment
		(start 163.982908 -28.823412)
		(end 165.245542 -29.349192)
		(width 0.1651)
		(layer "In11.Cu")
		(net "P5E_PEX1_STN2_TX_DP<40>")
	)
	(segment
		(start 167.139366 -31.231078)
		(end 167.94734 -32.033972)
		(width 0.1651)
		(layer "In11.Cu")
		(net "P5E_PEX1_STN2_TX_DP<40>")
	)
	(segment
		(start 166.18458 -30.40761)
		(end 166.31031 -30.407356)
		(width 0.1651)
		(layer "In11.Cu")
		(net "P5E_PEX1_STN2_TX_DP<40>")
	)
	(segment
		(start 166.661846 -30.882082)
		(end 167.013636 -31.231332)
		(width 0.1651)
		(layer "In11.Cu")
		(net "P5E_PEX1_STN2_TX_DP<40>")
	)
	(segment
		(start 167.013636 -31.231332)
		(end 167.139366 -31.231078)
		(width 0.1651)
		(layer "In11.Cu")
		(net "P5E_PEX1_STN2_TX_DP<40>")
	)
	(segment
		(start 166.661592 -30.756352)
		(end 166.661846 -30.882082)
		(width 0.1651)
		(layer "In11.Cu")
		(net "P5E_PEX1_STN2_TX_DP<40>")
	)
	(segment
		(start 167.94734 -32.033972)
		(end 169.682922 -34.872168)
		(width 0.1651)
		(layer "In11.Cu")
		(net "P5E_PEX1_STN2_TX_DP<40>")
	)
	(segment
		(start 165.832536 -29.93263)
		(end 165.833044 -30.05836)
		(width 0.1651)
		(layer "In11.Cu")
		(net "P5E_PEX1_STN2_TX_DP<40>")
	)
	(segment
		(start 179.403502 -47.064676)
		(end 180.401468 -49.912524)
		(width 0.1651)
		(layer "In11.Cu")
		(net "P5E_PEX1_STN2_TX_DP<40>")
	)
	(segment
		(start 165.833044 -30.05836)
		(end 166.18458 -30.40761)
		(width 0.1651)
		(layer "In11.Cu")
		(net "P5E_PEX1_STN2_TX_DP<40>")
	)
	(segment
		(start 180.401468 -49.912524)
		(end 181.0639 -60.607194)
		(width 0.1651)
		(layer "In11.Cu")
		(net "P5E_PEX1_STN2_TX_DP<40>")
	)
	(segment
		(start 313.732164 -129.905506)
		(end 313.43219 -130.20548)
		(width 0.13462)
		(layer "F.Cu")
		(net "P5E_PEX2_STN0_TX_DN<4>")
	)
	(segment
		(start 312.811414 -130.20548)
		(end 312.48604 -129.880106)
		(width 0.13462)
		(layer "F.Cu")
		(net "P5E_PEX2_STN0_TX_DN<4>")
	)
	(segment
		(start 313.43219 -130.20548)
		(end 312.811414 -130.20548)
		(width 0.13462)
		(layer "F.Cu")
		(net "P5E_PEX2_STN0_TX_DN<4>")
	)
	(segment
		(start 316.04331 -284.120082)
		(end 309.623714 -284.120082)
		(width 0.1143)
		(layer "In9.Cu")
		(net "P5E_PEX2_STN0_TX_DN<4>")
	)
	(segment
		(start 320.002154 -133.113272)
		(end 324.626224 -144.276572)
		(width 0.1651)
		(layer "In9.Cu")
		(net "P5E_PEX2_STN0_TX_DN<4>")
	)
	(segment
		(start 329.011534 -272.151602)
		(end 327.935082 -274.749768)
		(width 0.1651)
		(layer "In9.Cu")
		(net "P5E_PEX2_STN0_TX_DN<4>")
	)
	(segment
		(start 317.527432 -130.63855)
		(end 320.002154 -133.113272)
		(width 0.1651)
		(layer "In9.Cu")
		(net "P5E_PEX2_STN0_TX_DN<4>")
	)
	(segment
		(start 309.623714 -284.120082)
		(end 309.520082 -284.223714)
		(width 0.1143)
		(layer "In9.Cu")
		(net "P5E_PEX2_STN0_TX_DN<4>")
	)
	(segment
		(start 316.460124 -130.196336)
		(end 317.527432 -130.63855)
		(width 0.1651)
		(layer "In9.Cu")
		(net "P5E_PEX2_STN0_TX_DN<4>")
	)
	(segment
		(start 319.75298 -174.772828)
		(end 318.708024 -178.670712)
		(width 0.1651)
		(layer "In9.Cu")
		(net "P5E_PEX2_STN0_TX_DN<4>")
	)
	(segment
		(start 316.08903 -284.165802)
		(end 316.04331 -284.120082)
		(width 0.1143)
		(layer "In9.Cu")
		(net "P5E_PEX2_STN0_TX_DN<4>")
	)
	(segment
		(start 319.430908 -283.253942)
		(end 317.229744 -284.165802)
		(width 0.1651)
		(layer "In9.Cu")
		(net "P5E_PEX2_STN0_TX_DN<4>")
	)
	(segment
		(start 314.952634 -221.593156)
		(end 317.496698 -250.731782)
		(width 0.1651)
		(layer "In9.Cu")
		(net "P5E_PEX2_STN0_TX_DN<4>")
	)
	(segment
		(start 324.798436 -144.448784)
		(end 328.500486 -153.386282)
		(width 0.1651)
		(layer "In9.Cu")
		(net "P5E_PEX2_STN0_TX_DN<4>")
	)
	(segment
		(start 316.117478 -284.165802)
		(end 316.08903 -284.165802)
		(width 0.1143)
		(layer "In9.Cu")
		(net "P5E_PEX2_STN0_TX_DN<4>")
	)
	(segment
		(start 309.520082 -284.223714)
		(end 309.520082 -284.385512)
		(width 0.1143)
		(layer "In9.Cu")
		(net "P5E_PEX2_STN0_TX_DN<4>")
	)
	(segment
		(start 328.66457 -268.181582)
		(end 329.011534 -272.151602)
		(width 0.1651)
		(layer "In9.Cu")
		(net "P5E_PEX2_STN0_TX_DN<4>")
	)
	(segment
		(start 327.863708 -266.247626)
		(end 328.66457 -268.181582)
		(width 0.1651)
		(layer "In9.Cu")
		(net "P5E_PEX2_STN0_TX_DN<4>")
	)
	(segment
		(start 328.421238 -159.752792)
		(end 319.75298 -174.772828)
		(width 0.1651)
		(layer "In9.Cu")
		(net "P5E_PEX2_STN0_TX_DN<4>")
	)
	(segment
		(start 318.708024 -178.670712)
		(end 314.952634 -221.593156)
		(width 0.1651)
		(layer "In9.Cu")
		(net "P5E_PEX2_STN0_TX_DN<4>")
	)
	(segment
		(start 314.022994 -130.196336)
		(end 316.460124 -130.196336)
		(width 0.1651)
		(layer "In9.Cu")
		(net "P5E_PEX2_STN0_TX_DN<4>")
	)
	(segment
		(start 309.634382 -284.499812)
		(end 309.899812 -284.499812)
		(width 0.1143)
		(layer "In9.Cu")
		(net "P5E_PEX2_STN0_TX_DN<4>")
	)
	(segment
		(start 324.626224 -144.276572)
		(end 324.798436 -144.448784)
		(width 0.1651)
		(layer "In9.Cu")
		(net "P5E_PEX2_STN0_TX_DN<4>")
	)
	(segment
		(start 309.520082 -284.385512)
		(end 309.634382 -284.499812)
		(width 0.1143)
		(layer "In9.Cu")
		(net "P5E_PEX2_STN0_TX_DN<4>")
	)
	(segment
		(start 317.496698 -250.731782)
		(end 327.863708 -266.247626)
		(width 0.1651)
		(layer "In9.Cu")
		(net "P5E_PEX2_STN0_TX_DN<4>")
	)
	(segment
		(start 327.935082 -274.749768)
		(end 319.430908 -283.253942)
		(width 0.1651)
		(layer "In9.Cu")
		(net "P5E_PEX2_STN0_TX_DN<4>")
	)
	(segment
		(start 317.229744 -284.165802)
		(end 316.117478 -284.165802)
		(width 0.1651)
		(layer "In9.Cu")
		(net "P5E_PEX2_STN0_TX_DN<4>")
	)
	(segment
		(start 328.500486 -153.386282)
		(end 328.500486 -159.455866)
		(width 0.1651)
		(layer "In9.Cu")
		(net "P5E_PEX2_STN0_TX_DN<4>")
	)
	(segment
		(start 313.732164 -129.905506)
		(end 314.022994 -130.196336)
		(width 0.1651)
		(layer "In9.Cu")
		(net "P5E_PEX2_STN0_TX_DN<4>")
	)
	(segment
		(start 328.500486 -159.455866)
		(end 328.421238 -159.752792)
		(width 0.1651)
		(layer "In9.Cu")
		(net "P5E_PEX2_STN0_TX_DN<4>")
	)
	(segment
		(start 283.736542 -343.365582)
		(end 283.736542 -342.734138)
		(width 0.13462)
		(layer "F.Cu")
		(net "P5E_PEX2_STN7_TX_DP<119>")
	)
	(segment
		(start 283.736542 -342.734138)
		(end 283.441902 -342.439498)
		(width 0.13462)
		(layer "F.Cu")
		(net "P5E_PEX2_STN7_TX_DP<119>")
	)
	(segment
		(start 283.416502 -343.685622)
		(end 283.736542 -343.365582)
		(width 0.13462)
		(layer "F.Cu")
		(net "P5E_PEX2_STN7_TX_DP<119>")
	)
	(segment
		(start 267.720318 -307.633878)
		(end 267.748766 -307.633878)
		(width 0.1143)
		(layer "In7.Cu")
		(net "P5E_PEX2_STN7_TX_DP<119>")
	)
	(segment
		(start 255.47066 -319.919858)
		(end 256.589022 -317.214758)
		(width 0.1651)
		(layer "In7.Cu")
		(net "P5E_PEX2_STN7_TX_DP<119>")
	)
	(segment
		(start 260.335522 -313.067954)
		(end 264.390378 -309.466234)
		(width 0.1651)
		(layer "In7.Cu")
		(net "P5E_PEX2_STN7_TX_DP<119>")
	)
	(segment
		(start 283.441902 -342.439498)
		(end 283.732732 -342.148668)
		(width 0.1651)
		(layer "In7.Cu")
		(net "P5E_PEX2_STN7_TX_DP<119>")
	)
	(segment
		(start 267.748766 -307.633878)
		(end 267.794486 -307.679598)
		(width 0.1143)
		(layer "In7.Cu")
		(net "P5E_PEX2_STN7_TX_DP<119>")
	)
	(segment
		(start 283.58084 -341.396066)
		(end 276.133052 -335.904332)
		(width 0.1651)
		(layer "In7.Cu")
		(net "P5E_PEX2_STN7_TX_DP<119>")
	)
	(segment
		(start 276.384258 -308.249828)
		(end 276.649688 -308.249828)
		(width 0.1143)
		(layer "In7.Cu")
		(net "P5E_PEX2_STN7_TX_DP<119>")
	)
	(segment
		(start 260.335268 -313.067954)
		(end 260.335522 -313.067954)
		(width 0.1651)
		(layer "In7.Cu")
		(net "P5E_PEX2_STN7_TX_DP<119>")
	)
	(segment
		(start 258.40817 -326.474328)
		(end 256.304796 -324.157594)
		(width 0.1651)
		(layer "In7.Cu")
		(net "P5E_PEX2_STN7_TX_DP<119>")
	)
	(segment
		(start 267.794486 -307.679598)
		(end 276.044152 -307.679598)
		(width 0.1143)
		(layer "In7.Cu")
		(net "P5E_PEX2_STN7_TX_DP<119>")
	)
	(segment
		(start 276.133052 -335.904332)
		(end 258.40817 -326.474328)
		(width 0.1651)
		(layer "In7.Cu")
		(net "P5E_PEX2_STN7_TX_DP<119>")
	)
	(segment
		(start 267.448538 -307.633878)
		(end 267.720318 -307.633878)
		(width 0.1651)
		(layer "In7.Cu")
		(net "P5E_PEX2_STN7_TX_DP<119>")
	)
	(segment
		(start 259.496814 -313.812936)
		(end 260.335268 -313.067954)
		(width 0.1651)
		(layer "In7.Cu")
		(net "P5E_PEX2_STN7_TX_DP<119>")
	)
	(segment
		(start 276.269958 -307.905404)
		(end 276.269958 -308.135528)
		(width 0.1143)
		(layer "In7.Cu")
		(net "P5E_PEX2_STN7_TX_DP<119>")
	)
	(segment
		(start 256.304796 -324.157594)
		(end 255.47066 -322.143628)
		(width 0.1651)
		(layer "In7.Cu")
		(net "P5E_PEX2_STN7_TX_DP<119>")
	)
	(segment
		(start 276.044152 -307.679598)
		(end 276.269958 -307.905404)
		(width 0.1143)
		(layer "In7.Cu")
		(net "P5E_PEX2_STN7_TX_DP<119>")
	)
	(segment
		(start 256.589022 -317.214758)
		(end 259.496814 -313.812936)
		(width 0.1651)
		(layer "In7.Cu")
		(net "P5E_PEX2_STN7_TX_DP<119>")
	)
	(segment
		(start 255.47066 -322.143628)
		(end 255.47066 -319.919858)
		(width 0.1651)
		(layer "In7.Cu")
		(net "P5E_PEX2_STN7_TX_DP<119>")
	)
	(segment
		(start 283.732732 -342.148668)
		(end 283.732732 -341.676228)
		(width 0.1651)
		(layer "In7.Cu")
		(net "P5E_PEX2_STN7_TX_DP<119>")
	)
	(segment
		(start 266.364466 -308.146704)
		(end 267.448538 -307.633878)
		(width 0.1651)
		(layer "In7.Cu")
		(net "P5E_PEX2_STN7_TX_DP<119>")
	)
	(segment
		(start 264.390378 -309.466234)
		(end 266.364466 -308.146704)
		(width 0.1651)
		(layer "In7.Cu")
		(net "P5E_PEX2_STN7_TX_DP<119>")
	)
	(segment
		(start 283.732732 -341.676228)
		(end 283.58084 -341.396066)
		(width 0.1651)
		(layer "In7.Cu")
		(net "P5E_PEX2_STN7_TX_DP<119>")
	)
	(segment
		(start 276.269958 -308.135528)
		(end 276.384258 -308.249828)
		(width 0.1143)
		(layer "In7.Cu")
		(net "P5E_PEX2_STN7_TX_DP<119>")
	)
	(segment
		(start 384.974846 -101.40188)
		(end 385.281424 -101.095302)
		(width 0.13462)
		(layer "F.Cu")
		(net "P5E_PEX3_STN1_TX_DN<17>")
	)
	(segment
		(start 384.0353 -101.120702)
		(end 384.316478 -101.40188)
		(width 0.13462)
		(layer "F.Cu")
		(net "P5E_PEX3_STN1_TX_DN<17>")
	)
	(segment
		(start 384.316478 -101.40188)
		(end 384.974846 -101.40188)
		(width 0.13462)
		(layer "F.Cu")
		(net "P5E_PEX3_STN1_TX_DN<17>")
	)
	(segment
		(start 383.74447 -101.411532)
		(end 383.240788 -101.411532)
		(width 0.1651)
		(layer "In9.Cu")
		(net "P5E_PEX3_STN1_TX_DN<17>")
	)
	(segment
		(start 408.283918 -271.526)
		(end 408.283918 -271.554448)
		(width 0.1143)
		(layer "In9.Cu")
		(net "P5E_PEX3_STN1_TX_DN<17>")
	)
	(segment
		(start 373.347488 -162.555174)
		(end 408.283918 -265.771122)
		(width 0.1651)
		(layer "In9.Cu")
		(net "P5E_PEX3_STN1_TX_DN<17>")
	)
	(segment
		(start 408.283918 -265.771122)
		(end 408.283918 -271.526)
		(width 0.1651)
		(layer "In9.Cu")
		(net "P5E_PEX3_STN1_TX_DN<17>")
	)
	(segment
		(start 372.775226 -159.677608)
		(end 373.347488 -162.555174)
		(width 0.1651)
		(layer "In9.Cu")
		(net "P5E_PEX3_STN1_TX_DN<17>")
	)
	(segment
		(start 408.785568 -280.319988)
		(end 408.899868 -280.434288)
		(width 0.1143)
		(layer "In9.Cu")
		(net "P5E_PEX3_STN1_TX_DN<17>")
	)
	(segment
		(start 374.925844 -112.84458)
		(end 369.472972 -130.82016)
		(width 0.1651)
		(layer "In9.Cu")
		(net "P5E_PEX3_STN1_TX_DN<17>")
	)
	(segment
		(start 383.240788 -101.411532)
		(end 382.52527 -101.70795)
		(width 0.1651)
		(layer "In9.Cu")
		(net "P5E_PEX3_STN1_TX_DN<17>")
	)
	(segment
		(start 408.283918 -271.554448)
		(end 408.329638 -271.600168)
		(width 0.1143)
		(layer "In9.Cu")
		(net "P5E_PEX3_STN1_TX_DN<17>")
	)
	(segment
		(start 382.52527 -101.70795)
		(end 377.4059 -106.82732)
		(width 0.1651)
		(layer "In9.Cu")
		(net "P5E_PEX3_STN1_TX_DN<17>")
	)
	(segment
		(start 408.329638 -280.10485)
		(end 408.544776 -280.319988)
		(width 0.1143)
		(layer "In9.Cu")
		(net "P5E_PEX3_STN1_TX_DN<17>")
	)
	(segment
		(start 377.4059 -106.8578)
		(end 374.925844 -112.84458)
		(width 0.1651)
		(layer "In9.Cu")
		(net "P5E_PEX3_STN1_TX_DN<17>")
	)
	(segment
		(start 372.059962 -145.126456)
		(end 372.775226 -159.677608)
		(width 0.1651)
		(layer "In9.Cu")
		(net "P5E_PEX3_STN1_TX_DN<17>")
	)
	(segment
		(start 384.0353 -101.120702)
		(end 383.74447 -101.411532)
		(width 0.1651)
		(layer "In9.Cu")
		(net "P5E_PEX3_STN1_TX_DN<17>")
	)
	(segment
		(start 369.472972 -130.82016)
		(end 369.472972 -138.880088)
		(width 0.1651)
		(layer "In9.Cu")
		(net "P5E_PEX3_STN1_TX_DN<17>")
	)
	(segment
		(start 408.899868 -280.434288)
		(end 408.899868 -280.699718)
		(width 0.1143)
		(layer "In9.Cu")
		(net "P5E_PEX3_STN1_TX_DN<17>")
	)
	(segment
		(start 377.4059 -106.82732)
		(end 377.4059 -106.8578)
		(width 0.1651)
		(layer "In9.Cu")
		(net "P5E_PEX3_STN1_TX_DN<17>")
	)
	(segment
		(start 408.544776 -280.319988)
		(end 408.785568 -280.319988)
		(width 0.1143)
		(layer "In9.Cu")
		(net "P5E_PEX3_STN1_TX_DN<17>")
	)
	(segment
		(start 369.472972 -138.880088)
		(end 372.059962 -145.126456)
		(width 0.1651)
		(layer "In9.Cu")
		(net "P5E_PEX3_STN1_TX_DN<17>")
	)
	(segment
		(start 408.329638 -271.600168)
		(end 408.329638 -280.10485)
		(width 0.1143)
		(layer "In9.Cu")
		(net "P5E_PEX3_STN1_TX_DN<17>")
	)
	(segment
		(start 381.083312 -343.365074)
		(end 381.083312 -342.734646)
		(width 0.13462)
		(layer "F.Cu")
		(net "P5E_PEX3_STN6_TX_DN<99>")
	)
	(segment
		(start 381.40386 -343.685622)
		(end 381.083312 -343.365074)
		(width 0.13462)
		(layer "F.Cu")
		(net "P5E_PEX3_STN6_TX_DN<99>")
	)
	(segment
		(start 381.083312 -342.734646)
		(end 381.37846 -342.439498)
		(width 0.13462)
		(layer "F.Cu")
		(net "P5E_PEX3_STN6_TX_DN<99>")
	)
	(segment
		(start 400.507708 -324.289166)
		(end 402.302218 -322.494656)
		(width 0.1651)
		(layer "In7.Cu")
		(net "P5E_PEX3_STN6_TX_DN<99>")
	)
	(segment
		(start 381.08763 -342.148668)
		(end 381.08763 -341.624412)
		(width 0.1651)
		(layer "In7.Cu")
		(net "P5E_PEX3_STN6_TX_DN<99>")
	)
	(segment
		(start 403.199854 -311.784492)
		(end 403.199854 -312.049922)
		(width 0.1143)
		(layer "In7.Cu")
		(net "P5E_PEX3_STN6_TX_DN<99>")
	)
	(segment
		(start 402.865844 -319.9892)
		(end 402.865844 -319.960752)
		(width 0.1143)
		(layer "In7.Cu")
		(net "P5E_PEX3_STN6_TX_DN<99>")
	)
	(segment
		(start 402.865844 -319.960752)
		(end 402.820124 -319.915032)
		(width 0.1143)
		(layer "In7.Cu")
		(net "P5E_PEX3_STN6_TX_DN<99>")
	)
	(segment
		(start 402.865844 -321.133978)
		(end 402.865844 -319.9892)
		(width 0.1651)
		(layer "In7.Cu")
		(net "P5E_PEX3_STN6_TX_DN<99>")
	)
	(segment
		(start 381.08763 -341.624412)
		(end 400.507708 -324.289166)
		(width 0.1651)
		(layer "In7.Cu")
		(net "P5E_PEX3_STN6_TX_DN<99>")
	)
	(segment
		(start 402.820124 -319.915032)
		(end 402.820124 -311.784492)
		(width 0.1143)
		(layer "In7.Cu")
		(net "P5E_PEX3_STN6_TX_DN<99>")
	)
	(segment
		(start 403.085554 -311.670192)
		(end 403.199854 -311.784492)
		(width 0.1143)
		(layer "In7.Cu")
		(net "P5E_PEX3_STN6_TX_DN<99>")
	)
	(segment
		(start 402.934424 -311.670192)
		(end 403.085554 -311.670192)
		(width 0.1143)
		(layer "In7.Cu")
		(net "P5E_PEX3_STN6_TX_DN<99>")
	)
	(segment
		(start 402.302218 -322.494656)
		(end 402.865844 -321.133978)
		(width 0.1651)
		(layer "In7.Cu")
		(net "P5E_PEX3_STN6_TX_DN<99>")
	)
	(segment
		(start 381.37846 -342.439498)
		(end 381.08763 -342.148668)
		(width 0.1651)
		(layer "In7.Cu")
		(net "P5E_PEX3_STN6_TX_DN<99>")
	)
	(segment
		(start 402.820124 -311.784492)
		(end 402.934424 -311.670192)
		(width 0.1143)
		(layer "In7.Cu")
		(net "P5E_PEX3_STN6_TX_DN<99>")
	)
	(segment
		(start 99.652328 -33.95218)
		(end 99.021392 -33.95218)
		(width 0.13462)
		(layer "F.Cu")
		(net "P5E_PEX0_STN2_TX_DN<35>")
	)
	(segment
		(start 99.947222 -33.657286)
		(end 99.652328 -33.95218)
		(width 0.13462)
		(layer "F.Cu")
		(net "P5E_PEX0_STN2_TX_DN<35>")
	)
	(segment
		(start 99.021392 -33.95218)
		(end 98.701098 -33.631886)
		(width 0.13462)
		(layer "F.Cu")
		(net "P5E_PEX0_STN2_TX_DN<35>")
	)
	(segment
		(start 55.470044 -278.125936)
		(end 55.573676 -278.229568)
		(width 0.1143)
		(layer "In11.Cu")
		(net "P5E_PEX0_STN2_TX_DN<35>")
	)
	(segment
		(start 76.394056 -141.7955)
		(end 76.087732 -149.256242)
		(width 0.1651)
		(layer "In11.Cu")
		(net "P5E_PEX0_STN2_TX_DN<35>")
	)
	(segment
		(start 100.142294 -33.852358)
		(end 100.373688 -33.948116)
		(width 0.1651)
		(layer "In11.Cu")
		(net "P5E_PEX0_STN2_TX_DN<35>")
	)
	(segment
		(start 55.573676 -278.229568)
		(end 55.735474 -278.229568)
		(width 0.1143)
		(layer "In11.Cu")
		(net "P5E_PEX0_STN2_TX_DN<35>")
	)
	(segment
		(start 101.944932 -34.57829)
		(end 106.158538 -42.414952)
		(width 0.1651)
		(layer "In11.Cu")
		(net "P5E_PEX0_STN2_TX_DN<35>")
	)
	(segment
		(start 77.361796 -118.211854)
		(end 76.832714 -131.103624)
		(width 0.1651)
		(layer "In11.Cu")
		(net "P5E_PEX0_STN2_TX_DN<35>")
	)
	(segment
		(start 76.832714 -131.103624)
		(end 76.832714 -139.897866)
		(width 0.1651)
		(layer "In11.Cu")
		(net "P5E_PEX0_STN2_TX_DN<35>")
	)
	(segment
		(start 55.515764 -271.399)
		(end 55.515764 -271.427448)
		(width 0.1143)
		(layer "In11.Cu")
		(net "P5E_PEX0_STN2_TX_DN<35>")
	)
	(segment
		(start 55.470044 -271.473168)
		(end 55.470044 -278.125936)
		(width 0.1143)
		(layer "In11.Cu")
		(net "P5E_PEX0_STN2_TX_DN<35>")
	)
	(segment
		(start 76.832714 -139.897866)
		(end 76.394056 -141.7955)
		(width 0.1651)
		(layer "In11.Cu")
		(net "P5E_PEX0_STN2_TX_DN<35>")
	)
	(segment
		(start 55.515764 -271.427448)
		(end 55.470044 -271.473168)
		(width 0.1143)
		(layer "In11.Cu")
		(net "P5E_PEX0_STN2_TX_DN<35>")
	)
	(segment
		(start 106.48442 -56.765698)
		(end 104.33558 -67.91071)
		(width 0.1651)
		(layer "In11.Cu")
		(net "P5E_PEX0_STN2_TX_DN<35>")
	)
	(segment
		(start 100.921566 -33.948116)
		(end 101.403404 -34.082736)
		(width 0.1651)
		(layer "In11.Cu")
		(net "P5E_PEX0_STN2_TX_DN<35>")
	)
	(segment
		(start 99.947222 -33.657286)
		(end 100.142294 -33.852358)
		(width 0.1651)
		(layer "In11.Cu")
		(net "P5E_PEX0_STN2_TX_DN<35>")
	)
	(segment
		(start 76.087732 -149.256242)
		(end 74.624692 -161.53003)
		(width 0.1651)
		(layer "In11.Cu")
		(net "P5E_PEX0_STN2_TX_DN<35>")
	)
	(segment
		(start 55.735474 -278.229568)
		(end 55.849774 -278.115268)
		(width 0.1143)
		(layer "In11.Cu")
		(net "P5E_PEX0_STN2_TX_DN<35>")
	)
	(segment
		(start 93.189044 -80.13319)
		(end 79.06004 -105.014776)
		(width 0.1651)
		(layer "In11.Cu")
		(net "P5E_PEX0_STN2_TX_DN<35>")
	)
	(segment
		(start 79.06004 -105.014776)
		(end 77.361796 -118.211854)
		(width 0.1651)
		(layer "In11.Cu")
		(net "P5E_PEX0_STN2_TX_DN<35>")
	)
	(segment
		(start 100.069904 -74.235564)
		(end 95.366586 -77.950314)
		(width 0.1651)
		(layer "In11.Cu")
		(net "P5E_PEX0_STN2_TX_DN<35>")
	)
	(segment
		(start 106.158538 -42.414952)
		(end 106.255058 -42.785538)
		(width 0.1651)
		(layer "In11.Cu")
		(net "P5E_PEX0_STN2_TX_DN<35>")
	)
	(segment
		(start 95.366586 -77.950314)
		(end 93.189044 -80.13319)
		(width 0.1651)
		(layer "In11.Cu")
		(net "P5E_PEX0_STN2_TX_DN<35>")
	)
	(segment
		(start 106.255058 -42.785538)
		(end 106.48442 -56.765698)
		(width 0.1651)
		(layer "In11.Cu")
		(net "P5E_PEX0_STN2_TX_DN<35>")
	)
	(segment
		(start 55.515764 -265.478768)
		(end 55.515764 -271.399)
		(width 0.1651)
		(layer "In11.Cu")
		(net "P5E_PEX0_STN2_TX_DN<35>")
	)
	(segment
		(start 100.373688 -33.948116)
		(end 100.921566 -33.948116)
		(width 0.1651)
		(layer "In11.Cu")
		(net "P5E_PEX0_STN2_TX_DN<35>")
	)
	(segment
		(start 101.403404 -34.082736)
		(end 101.944932 -34.57829)
		(width 0.1651)
		(layer "In11.Cu")
		(net "P5E_PEX0_STN2_TX_DN<35>")
	)
	(segment
		(start 74.624692 -161.53003)
		(end 55.515764 -265.478768)
		(width 0.1651)
		(layer "In11.Cu")
		(net "P5E_PEX0_STN2_TX_DN<35>")
	)
	(segment
		(start 104.33558 -67.91071)
		(end 100.069904 -74.235564)
		(width 0.1651)
		(layer "In11.Cu")
		(net "P5E_PEX0_STN2_TX_DN<35>")
	)
	(segment
		(start 55.849774 -278.115268)
		(end 55.849774 -277.849838)
		(width 0.1143)
		(layer "In11.Cu")
		(net "P5E_PEX0_STN2_TX_DN<35>")
	)
	(segment
		(start 143.520668 -342.734138)
		(end 143.815308 -342.439498)
		(width 0.13462)
		(layer "F.Cu")
		(net "P5E_PEX1_STN5_TX_DN<94>")
	)
	(segment
		(start 143.520668 -343.365582)
		(end 143.520668 -342.734138)
		(width 0.13462)
		(layer "F.Cu")
		(net "P5E_PEX1_STN5_TX_DN<94>")
	)
	(segment
		(start 143.840708 -343.685622)
		(end 143.520668 -343.365582)
		(width 0.13462)
		(layer "F.Cu")
		(net "P5E_PEX1_STN5_TX_DN<94>")
	)
	(segment
		(start 187.349892 -323.472048)
		(end 187.765944 -322.467224)
		(width 0.1651)
		(layer "In13.Cu")
		(net "P5E_PEX1_STN5_TX_DN<94>")
	)
	(segment
		(start 188.099954 -311.784492)
		(end 188.099954 -312.049922)
		(width 0.1143)
		(layer "In13.Cu")
		(net "P5E_PEX1_STN5_TX_DN<94>")
	)
	(segment
		(start 187.720224 -319.995296)
		(end 187.720224 -311.773824)
		(width 0.1143)
		(layer "In13.Cu")
		(net "P5E_PEX1_STN5_TX_DN<94>")
	)
	(segment
		(start 165.67404 -335.116932)
		(end 177.22215 -330.147676)
		(width 0.1651)
		(layer "In13.Cu")
		(net "P5E_PEX1_STN5_TX_DN<94>")
	)
	(segment
		(start 185.754264 -325.067676)
		(end 187.349892 -323.472048)
		(width 0.1651)
		(layer "In13.Cu")
		(net "P5E_PEX1_STN5_TX_DN<94>")
	)
	(segment
		(start 181.863746 -327.666604)
		(end 183.803036 -326.371204)
		(width 0.1651)
		(layer "In13.Cu")
		(net "P5E_PEX1_STN5_TX_DN<94>")
	)
	(segment
		(start 187.720224 -311.773824)
		(end 187.823856 -311.670192)
		(width 0.1143)
		(layer "In13.Cu")
		(net "P5E_PEX1_STN5_TX_DN<94>")
	)
	(segment
		(start 187.765944 -320.041016)
		(end 187.720224 -319.995296)
		(width 0.1143)
		(layer "In13.Cu")
		(net "P5E_PEX1_STN5_TX_DN<94>")
	)
	(segment
		(start 183.803036 -326.371204)
		(end 183.803036 -326.37095)
		(width 0.1651)
		(layer "In13.Cu")
		(net "P5E_PEX1_STN5_TX_DN<94>")
	)
	(segment
		(start 183.803036 -326.37095)
		(end 185.754264 -325.067676)
		(width 0.1651)
		(layer "In13.Cu")
		(net "P5E_PEX1_STN5_TX_DN<94>")
	)
	(segment
		(start 187.765944 -320.063114)
		(end 187.765944 -320.041016)
		(width 0.1143)
		(layer "In13.Cu")
		(net "P5E_PEX1_STN5_TX_DN<94>")
	)
	(segment
		(start 187.823856 -311.670192)
		(end 187.985654 -311.670192)
		(width 0.1143)
		(layer "In13.Cu")
		(net "P5E_PEX1_STN5_TX_DN<94>")
	)
	(segment
		(start 143.524478 -342.148668)
		(end 143.524478 -341.647018)
		(width 0.1651)
		(layer "In13.Cu")
		(net "P5E_PEX1_STN5_TX_DN<94>")
	)
	(segment
		(start 146.938492 -341.361014)
		(end 165.67404 -335.116932)
		(width 0.1651)
		(layer "In13.Cu")
		(net "P5E_PEX1_STN5_TX_DN<94>")
	)
	(segment
		(start 177.22215 -330.147676)
		(end 181.863746 -327.666604)
		(width 0.1651)
		(layer "In13.Cu")
		(net "P5E_PEX1_STN5_TX_DN<94>")
	)
	(segment
		(start 143.810482 -341.361014)
		(end 146.938492 -341.361014)
		(width 0.1651)
		(layer "In13.Cu")
		(net "P5E_PEX1_STN5_TX_DN<94>")
	)
	(segment
		(start 187.765944 -322.467224)
		(end 187.765944 -320.063114)
		(width 0.1651)
		(layer "In13.Cu")
		(net "P5E_PEX1_STN5_TX_DN<94>")
	)
	(segment
		(start 143.524478 -341.647018)
		(end 143.810482 -341.361014)
		(width 0.1651)
		(layer "In13.Cu")
		(net "P5E_PEX1_STN5_TX_DN<94>")
	)
	(segment
		(start 187.985654 -311.670192)
		(end 188.099954 -311.784492)
		(width 0.1143)
		(layer "In13.Cu")
		(net "P5E_PEX1_STN5_TX_DN<94>")
	)
	(segment
		(start 143.815308 -342.439498)
		(end 143.524478 -342.148668)
		(width 0.1651)
		(layer "In13.Cu")
		(net "P5E_PEX1_STN5_TX_DN<94>")
	)
	(segment
		(start 316.078362 -148.59)
		(end 315.449458 -148.59)
		(width 0.13462)
		(layer "F.Cu")
		(net "P5E_PEX2_STN0_TX_DP<11>")
	)
	(segment
		(start 316.374272 -148.88591)
		(end 316.078362 -148.59)
		(width 0.13462)
		(layer "F.Cu")
		(net "P5E_PEX2_STN0_TX_DP<11>")
	)
	(segment
		(start 315.449458 -148.59)
		(end 315.128148 -148.91131)
		(width 0.13462)
		(layer "F.Cu")
		(net "P5E_PEX2_STN0_TX_DP<11>")
	)
	(segment
		(start 307.799486 -222.13189)
		(end 309.762652 -199.693276)
		(width 0.1651)
		(layer "In9.Cu")
		(net "P5E_PEX2_STN0_TX_DP<11>")
	)
	(segment
		(start 318.188848 -149.430994)
		(end 318.045084 -149.430994)
		(width 0.1651)
		(layer "In9.Cu")
		(net "P5E_PEX2_STN0_TX_DP<11>")
	)
	(segment
		(start 311.17921 -268.590776)
		(end 311.17921 -260.78815)
		(width 0.1651)
		(layer "In9.Cu")
		(net "P5E_PEX2_STN0_TX_DP<11>")
	)
	(segment
		(start 310.233822 -270.873474)
		(end 311.17921 -268.590776)
		(width 0.1651)
		(layer "In9.Cu")
		(net "P5E_PEX2_STN0_TX_DP<11>")
	)
	(segment
		(start 317.703708 -149.089618)
		(end 317.703708 -148.945854)
		(width 0.1651)
		(layer "In9.Cu")
		(net "P5E_PEX2_STN0_TX_DP<11>")
	)
	(segment
		(start 317.352934 -148.59508)
		(end 316.665102 -148.59508)
		(width 0.1651)
		(layer "In9.Cu")
		(net "P5E_PEX2_STN0_TX_DP<11>")
	)
	(segment
		(start 319.423542 -150.988014)
		(end 319.300352 -150.96363)
		(width 0.1651)
		(layer "In9.Cu")
		(net "P5E_PEX2_STN0_TX_DP<11>")
	)
	(segment
		(start 316.665102 -148.59508)
		(end 316.374272 -148.88591)
		(width 0.1651)
		(layer "In9.Cu")
		(net "P5E_PEX2_STN0_TX_DP<11>")
	)
	(segment
		(start 319.0494 -150.428198)
		(end 318.774318 -150.016464)
		(width 0.1651)
		(layer "In9.Cu")
		(net "P5E_PEX2_STN0_TX_DP<11>")
	)
	(segment
		(start 310.735218 -278.420068)
		(end 310.494426 -278.420068)
		(width 0.1143)
		(layer "In9.Cu")
		(net "P5E_PEX2_STN0_TX_DP<11>")
	)
	(segment
		(start 310.494426 -278.420068)
		(end 310.279542 -278.205184)
		(width 0.1143)
		(layer "In9.Cu")
		(net "P5E_PEX2_STN0_TX_DP<11>")
	)
	(segment
		(start 310.849518 -278.534368)
		(end 310.735218 -278.420068)
		(width 0.1143)
		(layer "In9.Cu")
		(net "P5E_PEX2_STN0_TX_DP<11>")
	)
	(segment
		(start 310.849518 -278.799798)
		(end 310.849518 -278.534368)
		(width 0.1143)
		(layer "In9.Cu")
		(net "P5E_PEX2_STN0_TX_DP<11>")
	)
	(segment
		(start 321.440302 -155.015692)
		(end 320.339974 -152.359614)
		(width 0.1651)
		(layer "In9.Cu")
		(net "P5E_PEX2_STN0_TX_DP<11>")
	)
	(segment
		(start 320.339974 -152.359614)
		(end 319.423542 -150.988014)
		(width 0.1651)
		(layer "In9.Cu")
		(net "P5E_PEX2_STN0_TX_DP<11>")
	)
	(segment
		(start 311.725818 -177.254408)
		(end 313.097672 -172.13961)
		(width 0.1651)
		(layer "In9.Cu")
		(net "P5E_PEX2_STN0_TX_DP<11>")
	)
	(segment
		(start 317.703708 -148.945854)
		(end 317.352934 -148.59508)
		(width 0.1651)
		(layer "In9.Cu")
		(net "P5E_PEX2_STN0_TX_DP<11>")
	)
	(segment
		(start 321.440302 -157.687772)
		(end 321.440302 -155.015692)
		(width 0.1651)
		(layer "In9.Cu")
		(net "P5E_PEX2_STN0_TX_DP<11>")
	)
	(segment
		(start 309.762398 -199.693276)
		(end 311.725818 -177.254408)
		(width 0.1651)
		(layer "In9.Cu")
		(net "P5E_PEX2_STN0_TX_DP<11>")
	)
	(segment
		(start 310.279542 -278.205184)
		(end 310.279542 -271.546066)
		(width 0.1143)
		(layer "In9.Cu")
		(net "P5E_PEX2_STN0_TX_DP<11>")
	)
	(segment
		(start 319.024762 -150.551388)
		(end 319.0494 -150.428198)
		(width 0.1651)
		(layer "In9.Cu")
		(net "P5E_PEX2_STN0_TX_DP<11>")
	)
	(segment
		(start 311.17921 -260.78815)
		(end 307.799486 -222.13189)
		(width 0.1651)
		(layer "In9.Cu")
		(net "P5E_PEX2_STN0_TX_DP<11>")
	)
	(segment
		(start 310.233822 -271.471898)
		(end 310.233822 -270.873474)
		(width 0.1651)
		(layer "In9.Cu")
		(net "P5E_PEX2_STN0_TX_DP<11>")
	)
	(segment
		(start 319.300352 -150.96363)
		(end 319.024762 -150.551388)
		(width 0.1651)
		(layer "In9.Cu")
		(net "P5E_PEX2_STN0_TX_DP<11>")
	)
	(segment
		(start 310.279542 -271.546066)
		(end 310.233822 -271.500346)
		(width 0.1143)
		(layer "In9.Cu")
		(net "P5E_PEX2_STN0_TX_DP<11>")
	)
	(segment
		(start 318.774318 -150.016464)
		(end 318.188848 -149.430994)
		(width 0.1651)
		(layer "In9.Cu")
		(net "P5E_PEX2_STN0_TX_DP<11>")
	)
	(segment
		(start 318.045084 -149.430994)
		(end 317.703708 -149.089618)
		(width 0.1651)
		(layer "In9.Cu")
		(net "P5E_PEX2_STN0_TX_DP<11>")
	)
	(segment
		(start 309.762652 -199.693276)
		(end 309.762398 -199.693276)
		(width 0.1651)
		(layer "In9.Cu")
		(net "P5E_PEX2_STN0_TX_DP<11>")
	)
	(segment
		(start 313.097672 -172.13961)
		(end 321.440302 -157.687772)
		(width 0.1651)
		(layer "In9.Cu")
		(net "P5E_PEX2_STN0_TX_DP<11>")
	)
	(segment
		(start 310.233822 -271.500346)
		(end 310.233822 -271.471898)
		(width 0.1143)
		(layer "In9.Cu")
		(net "P5E_PEX2_STN0_TX_DP<11>")
	)
	(segment
		(start 296.446702 -355.658166)
		(end 296.446702 -355.026722)
		(width 0.13462)
		(layer "F.Cu")
		(net "P5E_PEX2_STN7_TX_DN<126>")
	)
	(segment
		(start 296.766742 -355.978206)
		(end 296.446702 -355.658166)
		(width 0.13462)
		(layer "F.Cu")
		(net "P5E_PEX2_STN7_TX_DN<126>")
	)
	(segment
		(start 296.446702 -355.026722)
		(end 296.741342 -354.732082)
		(width 0.13462)
		(layer "F.Cu")
		(net "P5E_PEX2_STN7_TX_DN<126>")
	)
	(segment
		(start 273.420078 -311.784492)
		(end 273.534378 -311.670192)
		(width 0.1143)
		(layer "In7.Cu")
		(net "P5E_PEX2_STN7_TX_DN<126>")
	)
	(segment
		(start 273.799808 -311.784492)
		(end 273.799808 -312.049922)
		(width 0.1143)
		(layer "In7.Cu")
		(net "P5E_PEX2_STN7_TX_DN<126>")
	)
	(segment
		(start 273.70913 -321.53733)
		(end 273.465798 -320.949828)
		(width 0.1651)
		(layer "In7.Cu")
		(net "P5E_PEX2_STN7_TX_DN<126>")
	)
	(segment
		(start 296.741342 -354.732082)
		(end 296.450512 -354.441252)
		(width 0.1651)
		(layer "In7.Cu")
		(net "P5E_PEX2_STN7_TX_DN<126>")
	)
	(segment
		(start 273.420078 -319.794128)
		(end 273.420078 -311.784492)
		(width 0.1143)
		(layer "In7.Cu")
		(net "P5E_PEX2_STN7_TX_DN<126>")
	)
	(segment
		(start 273.913346 -321.741546)
		(end 273.70913 -321.53733)
		(width 0.1651)
		(layer "In7.Cu")
		(net "P5E_PEX2_STN7_TX_DN<126>")
	)
	(segment
		(start 273.534378 -311.670192)
		(end 273.685508 -311.670192)
		(width 0.1143)
		(layer "In7.Cu")
		(net "P5E_PEX2_STN7_TX_DN<126>")
	)
	(segment
		(start 297.247056 -340.275418)
		(end 273.913346 -321.741546)
		(width 0.1651)
		(layer "In7.Cu")
		(net "P5E_PEX2_STN7_TX_DN<126>")
	)
	(segment
		(start 273.465798 -319.839848)
		(end 273.420078 -319.794128)
		(width 0.1143)
		(layer "In7.Cu")
		(net "P5E_PEX2_STN7_TX_DN<126>")
	)
	(segment
		(start 298.004992 -341.639398)
		(end 297.247056 -340.275418)
		(width 0.1651)
		(layer "In7.Cu")
		(net "P5E_PEX2_STN7_TX_DN<126>")
	)
	(segment
		(start 273.465798 -319.868296)
		(end 273.465798 -319.839848)
		(width 0.1143)
		(layer "In7.Cu")
		(net "P5E_PEX2_STN7_TX_DN<126>")
	)
	(segment
		(start 296.450512 -353.930966)
		(end 298.004992 -352.376486)
		(width 0.1651)
		(layer "In7.Cu")
		(net "P5E_PEX2_STN7_TX_DN<126>")
	)
	(segment
		(start 298.004992 -352.376486)
		(end 298.004992 -341.639398)
		(width 0.1651)
		(layer "In7.Cu")
		(net "P5E_PEX2_STN7_TX_DN<126>")
	)
	(segment
		(start 296.450512 -354.441252)
		(end 296.450512 -353.930966)
		(width 0.1651)
		(layer "In7.Cu")
		(net "P5E_PEX2_STN7_TX_DN<126>")
	)
	(segment
		(start 273.685508 -311.670192)
		(end 273.799808 -311.784492)
		(width 0.1143)
		(layer "In7.Cu")
		(net "P5E_PEX2_STN7_TX_DN<126>")
	)
	(segment
		(start 273.465798 -320.949828)
		(end 273.465798 -319.868296)
		(width 0.1651)
		(layer "In7.Cu")
		(net "P5E_PEX2_STN7_TX_DN<126>")
	)
	(segment
		(start 383.72034 -123.11888)
		(end 384.351784 -123.11888)
		(width 0.13462)
		(layer "F.Cu")
		(net "P5E_PEX3_STN1_TX_DP<26>")
	)
	(segment
		(start 384.351784 -123.11888)
		(end 384.671824 -122.79884)
		(width 0.13462)
		(layer "F.Cu")
		(net "P5E_PEX3_STN1_TX_DP<26>")
	)
	(segment
		(start 383.4257 -122.82424)
		(end 383.72034 -123.11888)
		(width 0.13462)
		(layer "F.Cu")
		(net "P5E_PEX3_STN1_TX_DP<26>")
	)
	(segment
		(start 382.01981 -123.47702)
		(end 378.182632 -132.741162)
		(width 0.1651)
		(layer "In9.Cu")
		(net "P5E_PEX3_STN1_TX_DP<26>")
	)
	(segment
		(start 378.182632 -132.741162)
		(end 378.182632 -137.017252)
		(width 0.1651)
		(layer "In9.Cu")
		(net "P5E_PEX3_STN1_TX_DP<26>")
	)
	(segment
		(start 416.834066 -271.500346)
		(end 416.879786 -271.546066)
		(width 0.1143)
		(layer "In9.Cu")
		(net "P5E_PEX3_STN1_TX_DP<26>")
	)
	(segment
		(start 378.182632 -137.017252)
		(end 380.753874 -143.224758)
		(width 0.1651)
		(layer "In9.Cu")
		(net "P5E_PEX3_STN1_TX_DP<26>")
	)
	(segment
		(start 381.48514 -158.085282)
		(end 382.133602 -161.345626)
		(width 0.1651)
		(layer "In9.Cu")
		(net "P5E_PEX3_STN1_TX_DP<26>")
	)
	(segment
		(start 417.09467 -278.420068)
		(end 417.335462 -278.420068)
		(width 0.1143)
		(layer "In9.Cu")
		(net "P5E_PEX3_STN1_TX_DP<26>")
	)
	(segment
		(start 383.4257 -122.82424)
		(end 383.13487 -123.11507)
		(width 0.1651)
		(layer "In9.Cu")
		(net "P5E_PEX3_STN1_TX_DP<26>")
	)
	(segment
		(start 382.133602 -161.345626)
		(end 416.834066 -263.855962)
		(width 0.1651)
		(layer "In9.Cu")
		(net "P5E_PEX3_STN1_TX_DP<26>")
	)
	(segment
		(start 382.38176 -123.11507)
		(end 382.01981 -123.47702)
		(width 0.1651)
		(layer "In9.Cu")
		(net "P5E_PEX3_STN1_TX_DP<26>")
	)
	(segment
		(start 416.834066 -271.471898)
		(end 416.834066 -271.500346)
		(width 0.1143)
		(layer "In9.Cu")
		(net "P5E_PEX3_STN1_TX_DP<26>")
	)
	(segment
		(start 416.879786 -271.546066)
		(end 416.879786 -278.205184)
		(width 0.1143)
		(layer "In9.Cu")
		(net "P5E_PEX3_STN1_TX_DP<26>")
	)
	(segment
		(start 417.335462 -278.420068)
		(end 417.449762 -278.534368)
		(width 0.1143)
		(layer "In9.Cu")
		(net "P5E_PEX3_STN1_TX_DP<26>")
	)
	(segment
		(start 417.449762 -278.534368)
		(end 417.449762 -278.799798)
		(width 0.1143)
		(layer "In9.Cu")
		(net "P5E_PEX3_STN1_TX_DP<26>")
	)
	(segment
		(start 416.879786 -278.205184)
		(end 417.09467 -278.420068)
		(width 0.1143)
		(layer "In9.Cu")
		(net "P5E_PEX3_STN1_TX_DP<26>")
	)
	(segment
		(start 416.834066 -263.855962)
		(end 416.834066 -271.471898)
		(width 0.1651)
		(layer "In9.Cu")
		(net "P5E_PEX3_STN1_TX_DP<26>")
	)
	(segment
		(start 383.13487 -123.11507)
		(end 382.38176 -123.11507)
		(width 0.1651)
		(layer "In9.Cu")
		(net "P5E_PEX3_STN1_TX_DP<26>")
	)
	(segment
		(start 380.753874 -143.224758)
		(end 381.48514 -158.085282)
		(width 0.1651)
		(layer "In9.Cu")
		(net "P5E_PEX3_STN1_TX_DP<26>")
	)
	(segment
		(start 384.51282 -355.978206)
		(end 384.192272 -355.657658)
		(width 0.13462)
		(layer "F.Cu")
		(net "P5E_PEX3_STN6_TX_DN<105>")
	)
	(segment
		(start 384.192272 -355.657658)
		(end 384.192272 -355.02723)
		(width 0.13462)
		(layer "F.Cu")
		(net "P5E_PEX3_STN6_TX_DN<105>")
	)
	(segment
		(start 384.192272 -355.02723)
		(end 384.48742 -354.732082)
		(width 0.13462)
		(layer "F.Cu")
		(net "P5E_PEX3_STN6_TX_DN<105>")
	)
	(segment
		(start 390.16051 -335.102454)
		(end 395.413738 -326.027034)
		(width 0.1651)
		(layer "In13.Cu")
		(net "P5E_PEX3_STN6_TX_DN<105>")
	)
	(segment
		(start 396.802102 -323.238114)
		(end 397.16583 -322.360036)
		(width 0.1651)
		(layer "In13.Cu")
		(net "P5E_PEX3_STN6_TX_DN<105>")
	)
	(segment
		(start 397.12011 -311.773824)
		(end 397.223742 -311.670192)
		(width 0.1143)
		(layer "In13.Cu")
		(net "P5E_PEX3_STN6_TX_DN<105>")
	)
	(segment
		(start 385.98602 -341.371682)
		(end 390.16051 -335.102454)
		(width 0.1651)
		(layer "In13.Cu")
		(net "P5E_PEX3_STN6_TX_DN<105>")
	)
	(segment
		(start 397.38554 -311.670192)
		(end 397.49984 -311.784492)
		(width 0.1143)
		(layer "In13.Cu")
		(net "P5E_PEX3_STN6_TX_DN<105>")
	)
	(segment
		(start 385.75107 -342.254332)
		(end 385.98602 -341.371682)
		(width 0.1651)
		(layer "In13.Cu")
		(net "P5E_PEX3_STN6_TX_DN<105>")
	)
	(segment
		(start 385.75107 -352.376486)
		(end 385.75107 -342.254332)
		(width 0.1651)
		(layer "In13.Cu")
		(net "P5E_PEX3_STN6_TX_DN<105>")
	)
	(segment
		(start 395.413738 -326.027034)
		(end 396.802102 -323.238114)
		(width 0.1651)
		(layer "In13.Cu")
		(net "P5E_PEX3_STN6_TX_DN<105>")
	)
	(segment
		(start 397.16583 -320.046096)
		(end 397.16583 -320.017648)
		(width 0.1143)
		(layer "In13.Cu")
		(net "P5E_PEX3_STN6_TX_DN<105>")
	)
	(segment
		(start 397.223742 -311.670192)
		(end 397.38554 -311.670192)
		(width 0.1143)
		(layer "In13.Cu")
		(net "P5E_PEX3_STN6_TX_DN<105>")
	)
	(segment
		(start 397.16583 -322.360036)
		(end 397.16583 -320.046096)
		(width 0.1651)
		(layer "In13.Cu")
		(net "P5E_PEX3_STN6_TX_DN<105>")
	)
	(segment
		(start 397.49984 -311.784492)
		(end 397.49984 -312.049922)
		(width 0.1143)
		(layer "In13.Cu")
		(net "P5E_PEX3_STN6_TX_DN<105>")
	)
	(segment
		(start 397.12011 -319.971928)
		(end 397.12011 -311.773824)
		(width 0.1143)
		(layer "In13.Cu")
		(net "P5E_PEX3_STN6_TX_DN<105>")
	)
	(segment
		(start 384.19659 -353.930966)
		(end 385.75107 -352.376486)
		(width 0.1651)
		(layer "In13.Cu")
		(net "P5E_PEX3_STN6_TX_DN<105>")
	)
	(segment
		(start 384.48742 -354.732082)
		(end 384.19659 -354.441252)
		(width 0.1651)
		(layer "In13.Cu")
		(net "P5E_PEX3_STN6_TX_DN<105>")
	)
	(segment
		(start 397.16583 -320.017648)
		(end 397.12011 -319.971928)
		(width 0.1143)
		(layer "In13.Cu")
		(net "P5E_PEX3_STN6_TX_DN<105>")
	)
	(segment
		(start 384.19659 -354.441252)
		(end 384.19659 -353.930966)
		(width 0.1651)
		(layer "In13.Cu")
		(net "P5E_PEX3_STN6_TX_DN<105>")
	)
	(segment
		(start 44.36999 -32.13608)
		(end 44.059094 -31.825184)
		(width 0.13462)
		(layer "F.Cu")
		(net "P5E_PEX0_STN2_TX_DN<42>")
	)
	(segment
		(start 45.305218 -31.850584)
		(end 45.019722 -32.13608)
		(width 0.13462)
		(layer "F.Cu")
		(net "P5E_PEX0_STN2_TX_DN<42>")
	)
	(segment
		(start 45.019722 -32.13608)
		(end 44.36999 -32.13608)
		(width 0.13462)
		(layer "F.Cu")
		(net "P5E_PEX0_STN2_TX_DN<42>")
	)
	(segment
		(start 48.86579 -271.427448)
		(end 48.82007 -271.473168)
		(width 0.1143)
		(layer "In11.Cu")
		(net "P5E_PEX0_STN2_TX_DN<42>")
	)
	(segment
		(start 62.025276 -48.492156)
		(end 62.668912 -50.37074)
		(width 0.1651)
		(layer "In11.Cu")
		(net "P5E_PEX0_STN2_TX_DN<42>")
	)
	(segment
		(start 45.596048 -32.141414)
		(end 48.465486 -32.141414)
		(width 0.1651)
		(layer "In11.Cu")
		(net "P5E_PEX0_STN2_TX_DN<42>")
	)
	(segment
		(start 45.305218 -31.850584)
		(end 45.596048 -32.141414)
		(width 0.1651)
		(layer "In11.Cu")
		(net "P5E_PEX0_STN2_TX_DN<42>")
	)
	(segment
		(start 48.465486 -32.141414)
		(end 49.06137 -32.319468)
		(width 0.1651)
		(layer "In11.Cu")
		(net "P5E_PEX0_STN2_TX_DN<42>")
	)
	(segment
		(start 48.86579 -270.426688)
		(end 48.86579 -271.399)
		(width 0.1651)
		(layer "In11.Cu")
		(net "P5E_PEX0_STN2_TX_DN<42>")
	)
	(segment
		(start 48.534828 -267.065252)
		(end 48.86579 -270.426688)
		(width 0.1651)
		(layer "In11.Cu")
		(net "P5E_PEX0_STN2_TX_DN<42>")
	)
	(segment
		(start 48.82007 -271.473168)
		(end 48.82007 -280.025856)
		(width 0.1143)
		(layer "In11.Cu")
		(net "P5E_PEX0_STN2_TX_DN<42>")
	)
	(segment
		(start 49.06137 -32.319468)
		(end 51.297332 -34.599372)
		(width 0.1651)
		(layer "In11.Cu")
		(net "P5E_PEX0_STN2_TX_DN<42>")
	)
	(segment
		(start 48.86579 -271.399)
		(end 48.86579 -271.427448)
		(width 0.1143)
		(layer "In11.Cu")
		(net "P5E_PEX0_STN2_TX_DN<42>")
	)
	(segment
		(start 51.297332 -34.599372)
		(end 62.025276 -48.492156)
		(width 0.1651)
		(layer "In11.Cu")
		(net "P5E_PEX0_STN2_TX_DN<42>")
	)
	(segment
		(start 46.122082 -116.032026)
		(end 46.382686 -141.886686)
		(width 0.1651)
		(layer "In11.Cu")
		(net "P5E_PEX0_STN2_TX_DN<42>")
	)
	(segment
		(start 48.82007 -280.025856)
		(end 48.923702 -280.129488)
		(width 0.1143)
		(layer "In11.Cu")
		(net "P5E_PEX0_STN2_TX_DN<42>")
	)
	(segment
		(start 51.53279 -95.804736)
		(end 46.122082 -116.032026)
		(width 0.1651)
		(layer "In11.Cu")
		(net "P5E_PEX0_STN2_TX_DN<42>")
	)
	(segment
		(start 62.668912 -50.37074)
		(end 63.306706 -60.466732)
		(width 0.1651)
		(layer "In11.Cu")
		(net "P5E_PEX0_STN2_TX_DN<42>")
	)
	(segment
		(start 49.1998 -280.015188)
		(end 49.1998 -279.749504)
		(width 0.1143)
		(layer "In11.Cu")
		(net "P5E_PEX0_STN2_TX_DN<42>")
	)
	(segment
		(start 46.382686 -141.886686)
		(end 45.021754 -161.959544)
		(width 0.1651)
		(layer "In11.Cu")
		(net "P5E_PEX0_STN2_TX_DN<42>")
	)
	(segment
		(start 63.306706 -60.466732)
		(end 61.810646 -68.660264)
		(width 0.1651)
		(layer "In11.Cu")
		(net "P5E_PEX0_STN2_TX_DN<42>")
	)
	(segment
		(start 48.923702 -280.129488)
		(end 49.0855 -280.129488)
		(width 0.1143)
		(layer "In11.Cu")
		(net "P5E_PEX0_STN2_TX_DN<42>")
	)
	(segment
		(start 61.810646 -68.660264)
		(end 51.53279 -95.804736)
		(width 0.1651)
		(layer "In11.Cu")
		(net "P5E_PEX0_STN2_TX_DN<42>")
	)
	(segment
		(start 49.0855 -280.129488)
		(end 49.1998 -280.015188)
		(width 0.1143)
		(layer "In11.Cu")
		(net "P5E_PEX0_STN2_TX_DN<42>")
	)
	(segment
		(start 45.021754 -161.959544)
		(end 48.534828 -267.065252)
		(width 0.1651)
		(layer "In11.Cu")
		(net "P5E_PEX0_STN2_TX_DN<42>")
	)
	(segment
		(start 143.246348 -342.734138)
		(end 142.951708 -342.439498)
		(width 0.13462)
		(layer "F.Cu")
		(net "P5E_PEX1_STN5_TX_DP<94>")
	)
	(segment
		(start 142.926308 -343.685622)
		(end 143.246348 -343.365582)
		(width 0.13462)
		(layer "F.Cu")
		(net "P5E_PEX1_STN5_TX_DP<94>")
	)
	(segment
		(start 143.246348 -343.365582)
		(end 143.246348 -342.734138)
		(width 0.13462)
		(layer "F.Cu")
		(net "P5E_PEX1_STN5_TX_DP<94>")
	)
	(segment
		(start 188.099954 -311.365392)
		(end 188.099954 -311.099962)
		(width 0.1143)
		(layer "In13.Cu")
		(net "P5E_PEX1_STN5_TX_DP<94>")
	)
	(segment
		(start 143.242538 -342.148668)
		(end 143.242538 -341.530178)
		(width 0.1651)
		(layer "In13.Cu")
		(net "P5E_PEX1_STN5_TX_DP<94>")
	)
	(segment
		(start 187.484004 -320.063114)
		(end 187.484004 -320.041016)
		(width 0.1143)
		(layer "In13.Cu")
		(net "P5E_PEX1_STN5_TX_DP<94>")
	)
	(segment
		(start 143.693642 -341.079074)
		(end 146.892518 -341.079074)
		(width 0.1651)
		(layer "In13.Cu")
		(net "P5E_PEX1_STN5_TX_DP<94>")
	)
	(segment
		(start 187.744862 -311.479692)
		(end 187.985654 -311.479692)
		(width 0.1143)
		(layer "In13.Cu")
		(net "P5E_PEX1_STN5_TX_DP<94>")
	)
	(segment
		(start 187.110878 -323.312282)
		(end 187.484004 -322.41109)
		(width 0.1651)
		(layer "In13.Cu")
		(net "P5E_PEX1_STN5_TX_DP<94>")
	)
	(segment
		(start 187.529724 -311.69483)
		(end 187.744862 -311.479692)
		(width 0.1143)
		(layer "In13.Cu")
		(net "P5E_PEX1_STN5_TX_DP<94>")
	)
	(segment
		(start 165.573456 -334.853026)
		(end 177.099722 -329.893422)
		(width 0.1651)
		(layer "In13.Cu")
		(net "P5E_PEX1_STN5_TX_DP<94>")
	)
	(segment
		(start 187.484004 -322.41109)
		(end 187.484004 -320.063114)
		(width 0.1651)
		(layer "In13.Cu")
		(net "P5E_PEX1_STN5_TX_DP<94>")
	)
	(segment
		(start 177.099722 -329.893422)
		(end 181.718458 -327.424288)
		(width 0.1651)
		(layer "In13.Cu")
		(net "P5E_PEX1_STN5_TX_DP<94>")
	)
	(segment
		(start 142.951708 -342.439498)
		(end 143.242538 -342.148668)
		(width 0.1651)
		(layer "In13.Cu")
		(net "P5E_PEX1_STN5_TX_DP<94>")
	)
	(segment
		(start 143.242538 -341.530178)
		(end 143.693642 -341.079074)
		(width 0.1651)
		(layer "In13.Cu")
		(net "P5E_PEX1_STN5_TX_DP<94>")
	)
	(segment
		(start 187.484004 -320.041016)
		(end 187.529724 -319.995296)
		(width 0.1143)
		(layer "In13.Cu")
		(net "P5E_PEX1_STN5_TX_DP<94>")
	)
	(segment
		(start 146.892518 -341.079074)
		(end 165.573456 -334.853026)
		(width 0.1651)
		(layer "In13.Cu")
		(net "P5E_PEX1_STN5_TX_DP<94>")
	)
	(segment
		(start 181.718458 -327.424288)
		(end 185.574432 -324.848728)
		(width 0.1651)
		(layer "In13.Cu")
		(net "P5E_PEX1_STN5_TX_DP<94>")
	)
	(segment
		(start 185.574432 -324.848728)
		(end 187.110878 -323.312282)
		(width 0.1651)
		(layer "In13.Cu")
		(net "P5E_PEX1_STN5_TX_DP<94>")
	)
	(segment
		(start 187.529724 -319.995296)
		(end 187.529724 -311.69483)
		(width 0.1143)
		(layer "In13.Cu")
		(net "P5E_PEX1_STN5_TX_DP<94>")
	)
	(segment
		(start 187.985654 -311.479692)
		(end 188.099954 -311.365392)
		(width 0.1143)
		(layer "In13.Cu")
		(net "P5E_PEX1_STN5_TX_DP<94>")
	)
	(segment
		(start 313.44235 -122.58548)
		(end 312.801254 -122.58548)
		(width 0.13462)
		(layer "F.Cu")
		(net "P5E_PEX2_STN0_TX_DN<2>")
	)
	(segment
		(start 313.732164 -122.295666)
		(end 313.44235 -122.58548)
		(width 0.13462)
		(layer "F.Cu")
		(net "P5E_PEX2_STN0_TX_DN<2>")
	)
	(segment
		(start 312.801254 -122.58548)
		(end 312.48604 -122.270266)
		(width 0.13462)
		(layer "F.Cu")
		(net "P5E_PEX2_STN0_TX_DN<2>")
	)
	(segment
		(start 316.917578 -122.586496)
		(end 318.457834 -124.126752)
		(width 0.1651)
		(layer "In9.Cu")
		(net "P5E_PEX2_STN0_TX_DN<2>")
	)
	(segment
		(start 316.04331 -286.020256)
		(end 309.623714 -286.020256)
		(width 0.1143)
		(layer "In9.Cu")
		(net "P5E_PEX2_STN0_TX_DN<2>")
	)
	(segment
		(start 320.513964 -284.872938)
		(end 317.634112 -286.065976)
		(width 0.1651)
		(layer "In9.Cu")
		(net "P5E_PEX2_STN0_TX_DN<2>")
	)
	(segment
		(start 316.08903 -286.065976)
		(end 316.04331 -286.020256)
		(width 0.1143)
		(layer "In9.Cu")
		(net "P5E_PEX2_STN0_TX_DN<2>")
	)
	(segment
		(start 309.520082 -286.123888)
		(end 309.520082 -286.285686)
		(width 0.1143)
		(layer "In9.Cu")
		(net "P5E_PEX2_STN0_TX_DN<2>")
	)
	(segment
		(start 320.658236 -178.91506)
		(end 316.916816 -221.67723)
		(width 0.1651)
		(layer "In9.Cu")
		(net "P5E_PEX2_STN0_TX_DN<2>")
	)
	(segment
		(start 321.98818 -132.229098)
		(end 330.435966 -152.623266)
		(width 0.1651)
		(layer "In9.Cu")
		(net "P5E_PEX2_STN0_TX_DN<2>")
	)
	(segment
		(start 318.917066 -125.535182)
		(end 321.479926 -131.720844)
		(width 0.1651)
		(layer "In9.Cu")
		(net "P5E_PEX2_STN0_TX_DN<2>")
	)
	(segment
		(start 330.435966 -159.71139)
		(end 330.213462 -160.544256)
		(width 0.1651)
		(layer "In9.Cu")
		(net "P5E_PEX2_STN0_TX_DN<2>")
	)
	(segment
		(start 318.802004 -124.95784)
		(end 318.917066 -125.535182)
		(width 0.1651)
		(layer "In9.Cu")
		(net "P5E_PEX2_STN0_TX_DN<2>")
	)
	(segment
		(start 329.475084 -265.119866)
		(end 330.540868 -267.69314)
		(width 0.1651)
		(layer "In9.Cu")
		(net "P5E_PEX2_STN0_TX_DN<2>")
	)
	(segment
		(start 330.957428 -272.44802)
		(end 329.555602 -275.8313)
		(width 0.1651)
		(layer "In9.Cu")
		(net "P5E_PEX2_STN0_TX_DN<2>")
	)
	(segment
		(start 309.634382 -286.399986)
		(end 309.899812 -286.399986)
		(width 0.1143)
		(layer "In9.Cu")
		(net "P5E_PEX2_STN0_TX_DN<2>")
	)
	(segment
		(start 329.555602 -275.8313)
		(end 320.513964 -284.872938)
		(width 0.1651)
		(layer "In9.Cu")
		(net "P5E_PEX2_STN0_TX_DN<2>")
	)
	(segment
		(start 309.623714 -286.020256)
		(end 309.520082 -286.123888)
		(width 0.1143)
		(layer "In9.Cu")
		(net "P5E_PEX2_STN0_TX_DN<2>")
	)
	(segment
		(start 321.567048 -175.527208)
		(end 320.658236 -178.91506)
		(width 0.1651)
		(layer "In9.Cu")
		(net "P5E_PEX2_STN0_TX_DN<2>")
	)
	(segment
		(start 330.435966 -152.623266)
		(end 330.435966 -159.71139)
		(width 0.1651)
		(layer "In9.Cu")
		(net "P5E_PEX2_STN0_TX_DN<2>")
	)
	(segment
		(start 309.520082 -286.285686)
		(end 309.634382 -286.399986)
		(width 0.1143)
		(layer "In9.Cu")
		(net "P5E_PEX2_STN0_TX_DN<2>")
	)
	(segment
		(start 330.213462 -160.544256)
		(end 321.567048 -175.527208)
		(width 0.1651)
		(layer "In9.Cu")
		(net "P5E_PEX2_STN0_TX_DN<2>")
	)
	(segment
		(start 330.540868 -267.69314)
		(end 330.957428 -272.44802)
		(width 0.1651)
		(layer "In9.Cu")
		(net "P5E_PEX2_STN0_TX_DN<2>")
	)
	(segment
		(start 318.457834 -124.126752)
		(end 318.802004 -124.95784)
		(width 0.1651)
		(layer "In9.Cu")
		(net "P5E_PEX2_STN0_TX_DN<2>")
	)
	(segment
		(start 314.022994 -122.586496)
		(end 316.917578 -122.586496)
		(width 0.1651)
		(layer "In9.Cu")
		(net "P5E_PEX2_STN0_TX_DN<2>")
	)
	(segment
		(start 316.916816 -221.67723)
		(end 319.391538 -250.029726)
		(width 0.1651)
		(layer "In9.Cu")
		(net "P5E_PEX2_STN0_TX_DN<2>")
	)
	(segment
		(start 321.479926 -131.720844)
		(end 321.98818 -132.229098)
		(width 0.1651)
		(layer "In9.Cu")
		(net "P5E_PEX2_STN0_TX_DN<2>")
	)
	(segment
		(start 316.117478 -286.065976)
		(end 316.08903 -286.065976)
		(width 0.1143)
		(layer "In9.Cu")
		(net "P5E_PEX2_STN0_TX_DN<2>")
	)
	(segment
		(start 317.634112 -286.065976)
		(end 316.117478 -286.065976)
		(width 0.1651)
		(layer "In9.Cu")
		(net "P5E_PEX2_STN0_TX_DN<2>")
	)
	(segment
		(start 313.732164 -122.295666)
		(end 314.022994 -122.586496)
		(width 0.1651)
		(layer "In9.Cu")
		(net "P5E_PEX2_STN0_TX_DN<2>")
	)
	(segment
		(start 319.391538 -250.029726)
		(end 329.475084 -265.119866)
		(width 0.1651)
		(layer "In9.Cu")
		(net "P5E_PEX2_STN0_TX_DN<2>")
	)
	(segment
		(start 283.416502 -355.978206)
		(end 283.736542 -355.658166)
		(width 0.13462)
		(layer "F.Cu")
		(net "P5E_PEX2_STN7_TX_DP<120>")
	)
	(segment
		(start 283.736542 -355.026722)
		(end 283.441902 -354.732082)
		(width 0.13462)
		(layer "F.Cu")
		(net "P5E_PEX2_STN7_TX_DP<120>")
	)
	(segment
		(start 283.736542 -355.658166)
		(end 283.736542 -355.026722)
		(width 0.13462)
		(layer "F.Cu")
		(net "P5E_PEX2_STN7_TX_DP<120>")
	)
	(segment
		(start 274.370038 -308.855364)
		(end 274.370038 -309.085488)
		(width 0.1143)
		(layer "In7.Cu")
		(net "P5E_PEX2_STN7_TX_DP<120>")
	)
	(segment
		(start 264.853674 -310.69407)
		(end 264.85342 -310.69407)
		(width 0.1651)
		(layer "In7.Cu")
		(net "P5E_PEX2_STN7_TX_DP<120>")
	)
	(segment
		(start 274.370038 -309.085488)
		(end 274.484338 -309.199788)
		(width 0.1143)
		(layer "In7.Cu")
		(net "P5E_PEX2_STN7_TX_DP<120>")
	)
	(segment
		(start 267.839952 -308.583838)
		(end 267.8684 -308.583838)
		(width 0.1143)
		(layer "In7.Cu")
		(net "P5E_PEX2_STN7_TX_DP<120>")
	)
	(segment
		(start 263.717278 -311.488328)
		(end 264.183622 -311.17667)
		(width 0.1651)
		(layer "In7.Cu")
		(net "P5E_PEX2_STN7_TX_DP<120>")
	)
	(segment
		(start 264.183622 -311.17667)
		(end 264.183876 -311.17667)
		(width 0.1651)
		(layer "In7.Cu")
		(net "P5E_PEX2_STN7_TX_DP<120>")
	)
	(segment
		(start 264.85342 -310.69407)
		(end 264.853928 -310.693816)
		(width 0.1651)
		(layer "In7.Cu")
		(net "P5E_PEX2_STN7_TX_DP<120>")
	)
	(segment
		(start 260.426708 -314.399168)
		(end 260.440678 -314.386722)
		(width 0.1651)
		(layer "In7.Cu")
		(net "P5E_PEX2_STN7_TX_DP<120>")
	)
	(segment
		(start 257.313938 -318.009524)
		(end 259.820664 -315.10224)
		(width 0.1651)
		(layer "In7.Cu")
		(net "P5E_PEX2_STN7_TX_DP<120>")
	)
	(segment
		(start 276.079458 -334.66913)
		(end 258.943348 -325.59117)
		(width 0.1651)
		(layer "In7.Cu")
		(net "P5E_PEX2_STN7_TX_DP<120>")
	)
	(segment
		(start 283.732732 -354.441252)
		(end 283.732732 -353.814126)
		(width 0.1651)
		(layer "In7.Cu")
		(net "P5E_PEX2_STN7_TX_DP<120>")
	)
	(segment
		(start 285.287212 -341.488776)
		(end 285.054294 -341.104474)
		(width 0.1651)
		(layer "In7.Cu")
		(net "P5E_PEX2_STN7_TX_DP<120>")
	)
	(segment
		(start 256.4384 -320.110358)
		(end 257.313938 -318.009524)
		(width 0.1651)
		(layer "In7.Cu")
		(net "P5E_PEX2_STN7_TX_DP<120>")
	)
	(segment
		(start 264.403586 -311.029858)
		(end 264.623042 -310.8833)
		(width 0.1651)
		(layer "In7.Cu")
		(net "P5E_PEX2_STN7_TX_DP<120>")
	)
	(segment
		(start 266.11326 -309.47614)
		(end 266.590018 -309.15737)
		(width 0.1651)
		(layer "In7.Cu")
		(net "P5E_PEX2_STN7_TX_DP<120>")
	)
	(segment
		(start 274.484338 -309.199788)
		(end 274.749768 -309.199788)
		(width 0.1143)
		(layer "In7.Cu")
		(net "P5E_PEX2_STN7_TX_DP<120>")
	)
	(segment
		(start 256.4384 -321.897248)
		(end 256.4384 -320.110358)
		(width 0.1651)
		(layer "In7.Cu")
		(net "P5E_PEX2_STN7_TX_DP<120>")
	)
	(segment
		(start 274.144232 -308.629558)
		(end 274.370038 -308.855364)
		(width 0.1143)
		(layer "In7.Cu")
		(net "P5E_PEX2_STN7_TX_DP<120>")
	)
	(segment
		(start 283.441902 -354.732082)
		(end 283.732732 -354.441252)
		(width 0.1651)
		(layer "In7.Cu")
		(net "P5E_PEX2_STN7_TX_DP<120>")
	)
	(segment
		(start 267.8684 -308.583838)
		(end 267.91412 -308.629558)
		(width 0.1143)
		(layer "In7.Cu")
		(net "P5E_PEX2_STN7_TX_DP<120>")
	)
	(segment
		(start 257.153156 -323.623178)
		(end 256.4384 -321.897248)
		(width 0.1651)
		(layer "In7.Cu")
		(net "P5E_PEX2_STN7_TX_DP<120>")
	)
	(segment
		(start 260.440932 -314.386722)
		(end 263.717278 -311.488328)
		(width 0.1651)
		(layer "In7.Cu")
		(net "P5E_PEX2_STN7_TX_DP<120>")
	)
	(segment
		(start 264.183876 -311.17667)
		(end 264.403586 -311.029858)
		(width 0.1651)
		(layer "In7.Cu")
		(net "P5E_PEX2_STN7_TX_DP<120>")
	)
	(segment
		(start 267.91412 -308.629558)
		(end 274.144232 -308.629558)
		(width 0.1143)
		(layer "In7.Cu")
		(net "P5E_PEX2_STN7_TX_DP<120>")
	)
	(segment
		(start 285.287212 -352.259646)
		(end 285.287212 -341.488776)
		(width 0.1651)
		(layer "In7.Cu")
		(net "P5E_PEX2_STN7_TX_DP<120>")
	)
	(segment
		(start 285.054294 -341.104474)
		(end 276.079458 -334.66913)
		(width 0.1651)
		(layer "In7.Cu")
		(net "P5E_PEX2_STN7_TX_DP<120>")
	)
	(segment
		(start 265.084306 -310.505094)
		(end 266.11326 -309.47614)
		(width 0.1651)
		(layer "In7.Cu")
		(net "P5E_PEX2_STN7_TX_DP<120>")
	)
	(segment
		(start 259.820664 -315.101986)
		(end 260.426708 -314.399168)
		(width 0.1651)
		(layer "In7.Cu")
		(net "P5E_PEX2_STN7_TX_DP<120>")
	)
	(segment
		(start 264.853928 -310.693816)
		(end 265.084306 -310.505094)
		(width 0.1651)
		(layer "In7.Cu")
		(net "P5E_PEX2_STN7_TX_DP<120>")
	)
	(segment
		(start 258.943348 -325.59117)
		(end 257.153156 -323.623178)
		(width 0.1651)
		(layer "In7.Cu")
		(net "P5E_PEX2_STN7_TX_DP<120>")
	)
	(segment
		(start 260.440678 -314.386722)
		(end 260.440932 -314.386722)
		(width 0.1651)
		(layer "In7.Cu")
		(net "P5E_PEX2_STN7_TX_DP<120>")
	)
	(segment
		(start 267.663168 -308.583838)
		(end 267.839952 -308.583838)
		(width 0.1651)
		(layer "In7.Cu")
		(net "P5E_PEX2_STN7_TX_DP<120>")
	)
	(segment
		(start 259.820664 -315.10224)
		(end 259.820664 -315.101986)
		(width 0.1651)
		(layer "In7.Cu")
		(net "P5E_PEX2_STN7_TX_DP<120>")
	)
	(segment
		(start 283.732732 -353.814126)
		(end 285.287212 -352.259646)
		(width 0.1651)
		(layer "In7.Cu")
		(net "P5E_PEX2_STN7_TX_DP<120>")
	)
	(segment
		(start 266.590018 -309.15737)
		(end 267.663168 -308.583838)
		(width 0.1651)
		(layer "In7.Cu")
		(net "P5E_PEX2_STN7_TX_DP<120>")
	)
	(segment
		(start 264.623042 -310.8833)
		(end 264.853674 -310.69407)
		(width 0.1651)
		(layer "In7.Cu")
		(net "P5E_PEX2_STN7_TX_DP<120>")
	)
	(segment
		(start 429.534574 -146.78152)
		(end 428.909226 -146.78152)
		(width 0.13462)
		(layer "F.Cu")
		(net "P5E_PEX3_STN0_TX_DP<10>")
	)
	(segment
		(start 429.832262 -147.079208)
		(end 429.534574 -146.78152)
		(width 0.13462)
		(layer "F.Cu")
		(net "P5E_PEX3_STN0_TX_DP<10>")
	)
	(segment
		(start 428.909226 -146.78152)
		(end 428.586138 -147.104608)
		(width 0.13462)
		(layer "F.Cu")
		(net "P5E_PEX3_STN0_TX_DP<10>")
	)
	(segment
		(start 427.28388 -271.554448)
		(end 427.3296 -271.600168)
		(width 0.1143)
		(layer "In9.Cu")
		(net "P5E_PEX3_STN0_TX_DP<10>")
	)
	(segment
		(start 427.78553 -280.319988)
		(end 427.89983 -280.434288)
		(width 0.1143)
		(layer "In9.Cu")
		(net "P5E_PEX3_STN0_TX_DP<10>")
	)
	(segment
		(start 435.663848 -149.41677)
		(end 435.939438 -149.829012)
		(width 0.1651)
		(layer "In9.Cu")
		(net "P5E_PEX3_STN0_TX_DP<10>")
	)
	(segment
		(start 427.28388 -271.526)
		(end 427.28388 -271.554448)
		(width 0.1143)
		(layer "In9.Cu")
		(net "P5E_PEX3_STN0_TX_DP<10>")
	)
	(segment
		(start 435.413404 -148.881846)
		(end 435.688486 -149.29358)
		(width 0.1651)
		(layer "In9.Cu")
		(net "P5E_PEX3_STN0_TX_DP<10>")
	)
	(segment
		(start 429.832262 -147.079208)
		(end 430.123092 -146.788378)
		(width 0.1651)
		(layer "In9.Cu")
		(net "P5E_PEX3_STN0_TX_DP<10>")
	)
	(segment
		(start 435.939438 -149.829012)
		(end 436.062628 -149.853396)
		(width 0.1651)
		(layer "In9.Cu")
		(net "P5E_PEX3_STN0_TX_DP<10>")
	)
	(segment
		(start 430.123092 -146.788378)
		(end 432.242468 -146.788378)
		(width 0.1651)
		(layer "In9.Cu")
		(net "P5E_PEX3_STN0_TX_DP<10>")
	)
	(segment
		(start 424.866816 -222.099124)
		(end 428.247048 -260.76529)
		(width 0.1651)
		(layer "In9.Cu")
		(net "P5E_PEX3_STN0_TX_DP<10>")
	)
	(segment
		(start 436.33771 -150.26513)
		(end 436.313072 -150.38832)
		(width 0.1651)
		(layer "In9.Cu")
		(net "P5E_PEX3_STN0_TX_DP<10>")
	)
	(segment
		(start 427.28388 -271.09928)
		(end 427.28388 -271.526)
		(width 0.1651)
		(layer "In9.Cu")
		(net "P5E_PEX3_STN0_TX_DP<10>")
	)
	(segment
		(start 427.89983 -280.434288)
		(end 427.89983 -280.699718)
		(width 0.1143)
		(layer "In9.Cu")
		(net "P5E_PEX3_STN0_TX_DP<10>")
	)
	(segment
		(start 430.111916 -172.492162)
		(end 428.774606 -177.47996)
		(width 0.1651)
		(layer "In9.Cu")
		(net "P5E_PEX3_STN0_TX_DP<10>")
	)
	(segment
		(start 428.247048 -260.76529)
		(end 428.247048 -268.773402)
		(width 0.1651)
		(layer "In9.Cu")
		(net "P5E_PEX3_STN0_TX_DP<10>")
	)
	(segment
		(start 436.313072 -150.38832)
		(end 436.588408 -150.800562)
		(width 0.1651)
		(layer "In9.Cu")
		(net "P5E_PEX3_STN0_TX_DP<10>")
	)
	(segment
		(start 438.512204 -154.836622)
		(end 438.512204 -157.940248)
		(width 0.1651)
		(layer "In9.Cu")
		(net "P5E_PEX3_STN0_TX_DP<10>")
	)
	(segment
		(start 427.544738 -280.319988)
		(end 427.78553 -280.319988)
		(width 0.1143)
		(layer "In9.Cu")
		(net "P5E_PEX3_STN0_TX_DP<10>")
	)
	(segment
		(start 428.247048 -268.773402)
		(end 427.28388 -271.09928)
		(width 0.1651)
		(layer "In9.Cu")
		(net "P5E_PEX3_STN0_TX_DP<10>")
	)
	(segment
		(start 428.774606 -177.47996)
		(end 428.77232 -177.504852)
		(width 0.1651)
		(layer "In9.Cu")
		(net "P5E_PEX3_STN0_TX_DP<10>")
	)
	(segment
		(start 436.062628 -149.853396)
		(end 436.33771 -150.26513)
		(width 0.1651)
		(layer "In9.Cu")
		(net "P5E_PEX3_STN0_TX_DP<10>")
	)
	(segment
		(start 428.77232 -177.504852)
		(end 428.772574 -177.504852)
		(width 0.1651)
		(layer "In9.Cu")
		(net "P5E_PEX3_STN0_TX_DP<10>")
	)
	(segment
		(start 438.512204 -157.940248)
		(end 430.111916 -172.492162)
		(width 0.1651)
		(layer "In9.Cu")
		(net "P5E_PEX3_STN0_TX_DP<10>")
	)
	(segment
		(start 436.711852 -150.824946)
		(end 437.077104 -151.371808)
		(width 0.1651)
		(layer "In9.Cu")
		(net "P5E_PEX3_STN0_TX_DP<10>")
	)
	(segment
		(start 434.081682 -147.550124)
		(end 435.413404 -148.881846)
		(width 0.1651)
		(layer "In9.Cu")
		(net "P5E_PEX3_STN0_TX_DP<10>")
	)
	(segment
		(start 437.077104 -151.371808)
		(end 438.512204 -154.836622)
		(width 0.1651)
		(layer "In9.Cu")
		(net "P5E_PEX3_STN0_TX_DP<10>")
	)
	(segment
		(start 427.3296 -271.600168)
		(end 427.3296 -280.10485)
		(width 0.1143)
		(layer "In9.Cu")
		(net "P5E_PEX3_STN0_TX_DP<10>")
	)
	(segment
		(start 435.688486 -149.29358)
		(end 435.663848 -149.41677)
		(width 0.1651)
		(layer "In9.Cu")
		(net "P5E_PEX3_STN0_TX_DP<10>")
	)
	(segment
		(start 427.3296 -280.10485)
		(end 427.544738 -280.319988)
		(width 0.1143)
		(layer "In9.Cu")
		(net "P5E_PEX3_STN0_TX_DP<10>")
	)
	(segment
		(start 436.588408 -150.800562)
		(end 436.711852 -150.824946)
		(width 0.1651)
		(layer "In9.Cu")
		(net "P5E_PEX3_STN0_TX_DP<10>")
	)
	(segment
		(start 432.242468 -146.788378)
		(end 434.081682 -147.550124)
		(width 0.1651)
		(layer "In9.Cu")
		(net "P5E_PEX3_STN0_TX_DP<10>")
	)
	(segment
		(start 428.772574 -177.504852)
		(end 424.866816 -222.099124)
		(width 0.1651)
		(layer "In9.Cu")
		(net "P5E_PEX3_STN0_TX_DP<10>")
	)
	(segment
		(start 387.026912 -342.73363)
		(end 386.73278 -342.439498)
		(width 0.13462)
		(layer "F.Cu")
		(net "P5E_PEX3_STN6_TX_DP<96>")
	)
	(segment
		(start 386.70738 -343.685622)
		(end 387.026912 -343.36609)
		(width 0.13462)
		(layer "F.Cu")
		(net "P5E_PEX3_STN6_TX_DP<96>")
	)
	(segment
		(start 387.026912 -343.36609)
		(end 387.026912 -342.73363)
		(width 0.13462)
		(layer "F.Cu")
		(net "P5E_PEX3_STN6_TX_DP<96>")
	)
	(segment
		(start 405.434038 -319.960752)
		(end 405.479758 -319.915032)
		(width 0.1143)
		(layer "In7.Cu")
		(net "P5E_PEX3_STN6_TX_DP<96>")
	)
	(segment
		(start 387.02361 -342.148668)
		(end 387.02361 -341.38235)
		(width 0.1651)
		(layer "In7.Cu")
		(net "P5E_PEX3_STN6_TX_DP<96>")
	)
	(segment
		(start 405.479758 -319.915032)
		(end 405.479758 -313.605418)
		(width 0.1143)
		(layer "In7.Cu")
		(net "P5E_PEX3_STN6_TX_DP<96>")
	)
	(segment
		(start 406.049988 -313.265312)
		(end 406.049988 -312.999882)
		(width 0.1143)
		(layer "In7.Cu")
		(net "P5E_PEX3_STN6_TX_DP<96>")
	)
	(segment
		(start 404.504906 -324.170802)
		(end 405.434038 -321.928236)
		(width 0.1651)
		(layer "In7.Cu")
		(net "P5E_PEX3_STN6_TX_DP<96>")
	)
	(segment
		(start 405.479758 -313.605418)
		(end 405.705564 -313.379612)
		(width 0.1143)
		(layer "In7.Cu")
		(net "P5E_PEX3_STN6_TX_DP<96>")
	)
	(segment
		(start 386.73278 -342.439498)
		(end 387.02361 -342.148668)
		(width 0.1651)
		(layer "In7.Cu")
		(net "P5E_PEX3_STN6_TX_DP<96>")
	)
	(segment
		(start 387.02361 -341.38235)
		(end 404.504906 -324.170802)
		(width 0.1651)
		(layer "In7.Cu")
		(net "P5E_PEX3_STN6_TX_DP<96>")
	)
	(segment
		(start 405.935688 -313.379612)
		(end 406.049988 -313.265312)
		(width 0.1143)
		(layer "In7.Cu")
		(net "P5E_PEX3_STN6_TX_DP<96>")
	)
	(segment
		(start 405.705564 -313.379612)
		(end 405.935688 -313.379612)
		(width 0.1143)
		(layer "In7.Cu")
		(net "P5E_PEX3_STN6_TX_DP<96>")
	)
	(segment
		(start 405.434038 -319.9892)
		(end 405.434038 -319.960752)
		(width 0.1143)
		(layer "In7.Cu")
		(net "P5E_PEX3_STN6_TX_DP<96>")
	)
	(segment
		(start 405.434038 -321.928236)
		(end 405.434038 -319.9892)
		(width 0.1651)
		(layer "In7.Cu")
		(net "P5E_PEX3_STN6_TX_DP<96>")
	)
	(segment
		(start 30.786578 -357.810308)
		(end 29.05887 -369.453414)
		(width 0.1651)
		(layer "In5.Cu")
		(net "P5E_PEX0_STN7_RX_DN<120>")
	)
	(segment
		(start 35.50412 -308.820058)
		(end 35.4584 -308.865778)
		(width 0.1143)
		(layer "In5.Cu")
		(net "P5E_PEX0_STN7_RX_DN<120>")
	)
	(segment
		(start 28.5242 -382.9812)
		(end 28.037028 -382.9812)
		(width 0.1651)
		(layer "In5.Cu")
		(net "P5E_PEX0_STN7_RX_DN<120>")
	)
	(segment
		(start 28.037028 -382.9812)
		(end 27.910028 -383.1082)
		(width 0.1651)
		(layer "In5.Cu")
		(net "P5E_PEX0_STN7_RX_DN<120>")
	)
	(segment
		(start 34.798 -319.964816)
		(end 34.798 -321.644264)
		(width 0.1651)
		(layer "In5.Cu")
		(net "P5E_PEX0_STN7_RX_DN<120>")
	)
	(segment
		(start 33.909 -311.24525)
		(end 33.7947 -311.35955)
		(width 0.1651)
		(layer "In5.Cu")
		(net "P5E_PEX0_STN7_RX_DN<120>")
	)
	(segment
		(start 33.7947 -309.938674)
		(end 33.7947 -310.63565)
		(width 0.1651)
		(layer "In5.Cu")
		(net "P5E_PEX0_STN7_RX_DN<120>")
	)
	(segment
		(start 27.910028 -383.1082)
		(end 27.910028 -383.490216)
		(width 0.1651)
		(layer "In5.Cu")
		(net "P5E_PEX0_STN7_RX_DN<120>")
	)
	(segment
		(start 33.7947 -310.63565)
		(end 33.909 -310.74995)
		(width 0.1651)
		(layer "In5.Cu")
		(net "P5E_PEX0_STN7_RX_DN<120>")
	)
	(segment
		(start 29.05887 -382.44653)
		(end 28.5242 -382.9812)
		(width 0.1651)
		(layer "In5.Cu")
		(net "P5E_PEX0_STN7_RX_DN<120>")
	)
	(segment
		(start 39.015416 -309.199788)
		(end 39.129716 -309.085488)
		(width 0.1143)
		(layer "In5.Cu")
		(net "P5E_PEX0_STN7_RX_DN<120>")
	)
	(segment
		(start 30.786578 -341.81288)
		(end 30.786578 -357.810308)
		(width 0.1651)
		(layer "In5.Cu")
		(net "P5E_PEX0_STN7_RX_DN<120>")
	)
	(segment
		(start 34.798 -321.644264)
		(end 30.786578 -341.81288)
		(width 0.1651)
		(layer "In5.Cu")
		(net "P5E_PEX0_STN7_RX_DN<120>")
	)
	(segment
		(start 33.64484 -315.79185)
		(end 33.55594 -315.88075)
		(width 0.1651)
		(layer "In5.Cu")
		(net "P5E_PEX0_STN7_RX_DN<120>")
	)
	(segment
		(start 39.129716 -309.085488)
		(end 39.129716 -308.934358)
		(width 0.1143)
		(layer "In5.Cu")
		(net "P5E_PEX0_STN7_RX_DN<120>")
	)
	(segment
		(start 33.909 -310.74995)
		(end 33.909 -311.24525)
		(width 0.1651)
		(layer "In5.Cu")
		(net "P5E_PEX0_STN7_RX_DN<120>")
	)
	(segment
		(start 35.150806 -308.865778)
		(end 34.666936 -309.066438)
		(width 0.1651)
		(layer "In5.Cu")
		(net "P5E_PEX0_STN7_RX_DN<120>")
	)
	(segment
		(start 33.55594 -314.71235)
		(end 33.55594 -315.20765)
		(width 0.1651)
		(layer "In5.Cu")
		(net "P5E_PEX0_STN7_RX_DN<120>")
	)
	(segment
		(start 35.4584 -308.865778)
		(end 35.429952 -308.865778)
		(width 0.1143)
		(layer "In5.Cu")
		(net "P5E_PEX0_STN7_RX_DN<120>")
	)
	(segment
		(start 33.7947 -311.35955)
		(end 33.7947 -312.012584)
		(width 0.1651)
		(layer "In5.Cu")
		(net "P5E_PEX0_STN7_RX_DN<120>")
	)
	(segment
		(start 39.129716 -308.934358)
		(end 39.015416 -308.820058)
		(width 0.1143)
		(layer "In5.Cu")
		(net "P5E_PEX0_STN7_RX_DN<120>")
	)
	(segment
		(start 33.55594 -315.88075)
		(end 33.55594 -316.966092)
		(width 0.1651)
		(layer "In5.Cu")
		(net "P5E_PEX0_STN7_RX_DN<120>")
	)
	(segment
		(start 33.55594 -316.966092)
		(end 34.798 -319.964816)
		(width 0.1651)
		(layer "In5.Cu")
		(net "P5E_PEX0_STN7_RX_DN<120>")
	)
	(segment
		(start 35.429952 -308.865778)
		(end 35.150806 -308.865778)
		(width 0.1651)
		(layer "In5.Cu")
		(net "P5E_PEX0_STN7_RX_DN<120>")
	)
	(segment
		(start 33.64484 -315.29655)
		(end 33.64484 -315.79185)
		(width 0.1651)
		(layer "In5.Cu")
		(net "P5E_PEX0_STN7_RX_DN<120>")
	)
	(segment
		(start 33.55594 -314.03925)
		(end 33.64484 -314.12815)
		(width 0.1651)
		(layer "In5.Cu")
		(net "P5E_PEX0_STN7_RX_DN<120>")
	)
	(segment
		(start 33.7947 -312.012584)
		(end 33.55594 -312.589164)
		(width 0.1651)
		(layer "In5.Cu")
		(net "P5E_PEX0_STN7_RX_DN<120>")
	)
	(segment
		(start 39.015416 -308.820058)
		(end 35.50412 -308.820058)
		(width 0.1143)
		(layer "In5.Cu")
		(net "P5E_PEX0_STN7_RX_DN<120>")
	)
	(segment
		(start 29.05887 -369.453414)
		(end 29.05887 -382.44653)
		(width 0.1651)
		(layer "In5.Cu")
		(net "P5E_PEX0_STN7_RX_DN<120>")
	)
	(segment
		(start 33.55594 -315.20765)
		(end 33.64484 -315.29655)
		(width 0.1651)
		(layer "In5.Cu")
		(net "P5E_PEX0_STN7_RX_DN<120>")
	)
	(segment
		(start 34.666936 -309.066438)
		(end 33.7947 -309.938674)
		(width 0.1651)
		(layer "In5.Cu")
		(net "P5E_PEX0_STN7_RX_DN<120>")
	)
	(segment
		(start 33.64484 -314.62345)
		(end 33.55594 -314.71235)
		(width 0.1651)
		(layer "In5.Cu")
		(net "P5E_PEX0_STN7_RX_DN<120>")
	)
	(segment
		(start 33.64484 -314.12815)
		(end 33.64484 -314.62345)
		(width 0.1651)
		(layer "In5.Cu")
		(net "P5E_PEX0_STN7_RX_DN<120>")
	)
	(segment
		(start 33.55594 -312.589164)
		(end 33.55594 -314.03925)
		(width 0.1651)
		(layer "In5.Cu")
		(net "P5E_PEX0_STN7_RX_DN<120>")
	)
	(segment
		(start 38.749986 -309.199788)
		(end 39.015416 -309.199788)
		(width 0.1143)
		(layer "In5.Cu")
		(net "P5E_PEX0_STN7_RX_DN<120>")
	)
	(segment
		(start 137.028428 -344.539062)
		(end 136.708388 -344.219022)
		(width 0.13462)
		(layer "F.Cu")
		(net "P5E_PEX1_STN5_TX_C_DP<91>")
	)
	(segment
		(start 137.028428 -345.170506)
		(end 137.028428 -344.539062)
		(width 0.13462)
		(layer "F.Cu")
		(net "P5E_PEX1_STN5_TX_C_DP<91>")
	)
	(segment
		(start 136.733788 -345.465146)
		(end 137.028428 -345.170506)
		(width 0.13462)
		(layer "F.Cu")
		(net "P5E_PEX1_STN5_TX_C_DP<91>")
	)
	(segment
		(start 135.470138 -358.060752)
		(end 135.111998 -358.79532)
		(width 0.1651)
		(layer "In13.Cu")
		(net "P5E_PEX1_STN5_TX_C_DP<91>")
	)
	(segment
		(start 135.111998 -358.79532)
		(end 129.917952 -362.862368)
		(width 0.1651)
		(layer "In13.Cu")
		(net "P5E_PEX1_STN5_TX_C_DP<91>")
	)
	(segment
		(start 129.811018 -362.849414)
		(end 129.42062 -363.154976)
		(width 0.1651)
		(layer "In13.Cu")
		(net "P5E_PEX1_STN5_TX_C_DP<91>")
	)
	(segment
		(start 122.637042 -379.899164)
		(end 122.510042 -379.772164)
		(width 0.1651)
		(layer "In13.Cu")
		(net "P5E_PEX1_STN5_TX_C_DP<91>")
	)
	(segment
		(start 122.85853 -379.899164)
		(end 122.637042 -379.899164)
		(width 0.1651)
		(layer "In13.Cu")
		(net "P5E_PEX1_STN5_TX_C_DP<91>")
	)
	(segment
		(start 136.733788 -345.465146)
		(end 137.024618 -345.755976)
		(width 0.1651)
		(layer "In13.Cu")
		(net "P5E_PEX1_STN5_TX_C_DP<91>")
	)
	(segment
		(start 129.42062 -363.154976)
		(end 129.407666 -363.26191)
		(width 0.1651)
		(layer "In13.Cu")
		(net "P5E_PEX1_STN5_TX_C_DP<91>")
	)
	(segment
		(start 122.510042 -379.772164)
		(end 122.510042 -379.390148)
		(width 0.1651)
		(layer "In13.Cu")
		(net "P5E_PEX1_STN5_TX_C_DP<91>")
	)
	(segment
		(start 135.470138 -347.838522)
		(end 135.470138 -358.060752)
		(width 0.1651)
		(layer "In13.Cu")
		(net "P5E_PEX1_STN5_TX_C_DP<91>")
	)
	(segment
		(start 123.384818 -379.372876)
		(end 122.85853 -379.899164)
		(width 0.1651)
		(layer "In13.Cu")
		(net "P5E_PEX1_STN5_TX_C_DP<91>")
	)
	(segment
		(start 129.407666 -363.26191)
		(end 123.974098 -367.516664)
		(width 0.1651)
		(layer "In13.Cu")
		(net "P5E_PEX1_STN5_TX_C_DP<91>")
	)
	(segment
		(start 123.974098 -367.516664)
		(end 123.384818 -368.725704)
		(width 0.1651)
		(layer "In13.Cu")
		(net "P5E_PEX1_STN5_TX_C_DP<91>")
	)
	(segment
		(start 137.024618 -346.284042)
		(end 135.470138 -347.838522)
		(width 0.1651)
		(layer "In13.Cu")
		(net "P5E_PEX1_STN5_TX_C_DP<91>")
	)
	(segment
		(start 137.024618 -345.755976)
		(end 137.024618 -346.284042)
		(width 0.1651)
		(layer "In13.Cu")
		(net "P5E_PEX1_STN5_TX_C_DP<91>")
	)
	(segment
		(start 129.917952 -362.862368)
		(end 129.811018 -362.849414)
		(width 0.1651)
		(layer "In13.Cu")
		(net "P5E_PEX1_STN5_TX_C_DP<91>")
	)
	(segment
		(start 123.384818 -368.725704)
		(end 123.384818 -379.372876)
		(width 0.1651)
		(layer "In13.Cu")
		(net "P5E_PEX1_STN5_TX_C_DP<91>")
	)
	(segment
		(start 21.947378 -30.92069)
		(end 21.654008 -30.62732)
		(width 0.13462)
		(layer "F.Cu")
		(net "P5E_PEX0_STN2_TX_DP<45>")
	)
	(segment
		(start 21.020024 -30.62732)
		(end 20.701254 -30.94609)
		(width 0.13462)
		(layer "F.Cu")
		(net "P5E_PEX0_STN2_TX_DP<45>")
	)
	(segment
		(start 21.654008 -30.62732)
		(end 21.020024 -30.62732)
		(width 0.13462)
		(layer "F.Cu")
		(net "P5E_PEX0_STN2_TX_DP<45>")
	)
	(segment
		(start 34.840672 -45.07484)
		(end 36.765992 -48.578008)
		(width 0.1651)
		(layer "In11.Cu")
		(net "P5E_PEX0_STN2_TX_DP<45>")
	)
	(segment
		(start 22.245574 -30.62986)
		(end 22.631654 -30.62986)
		(width 0.1651)
		(layer "In11.Cu")
		(net "P5E_PEX0_STN2_TX_DP<45>")
	)
	(segment
		(start 33.540954 -137.987278)
		(end 44.707302 -264.195306)
		(width 0.1651)
		(layer "In11.Cu")
		(net "P5E_PEX0_STN2_TX_DP<45>")
	)
	(segment
		(start 33.641538 -105.23093)
		(end 33.138618 -116.205762)
		(width 0.1651)
		(layer "In11.Cu")
		(net "P5E_PEX0_STN2_TX_DP<45>")
	)
	(segment
		(start 21.947378 -30.92069)
		(end 22.24024 -30.627828)
		(width 0.1651)
		(layer "In11.Cu")
		(net "P5E_PEX0_STN2_TX_DP<45>")
	)
	(segment
		(start 24.940768 -32.790638)
		(end 25.065482 -32.804608)
		(width 0.1651)
		(layer "In11.Cu")
		(net "P5E_PEX0_STN2_TX_DP<45>")
	)
	(segment
		(start 45.73397 -270.38427)
		(end 45.73397 -271.399)
		(width 0.1651)
		(layer "In11.Cu")
		(net "P5E_PEX0_STN2_TX_DP<45>")
	)
	(segment
		(start 24.645874 -32.278066)
		(end 24.631904 -32.40278)
		(width 0.1651)
		(layer "In11.Cu")
		(net "P5E_PEX0_STN2_TX_DP<45>")
	)
	(segment
		(start 46.34992 -278.534368)
		(end 46.34992 -278.799798)
		(width 0.1143)
		(layer "In11.Cu")
		(net "P5E_PEX0_STN2_TX_DP<45>")
	)
	(segment
		(start 37.273484 -78.885796)
		(end 33.641284 -105.217976)
		(width 0.1651)
		(layer "In11.Cu")
		(net "P5E_PEX0_STN2_TX_DP<45>")
	)
	(segment
		(start 38.14699 -63.150242)
		(end 37.273484 -78.885796)
		(width 0.1651)
		(layer "In11.Cu")
		(net "P5E_PEX0_STN2_TX_DP<45>")
	)
	(segment
		(start 25.7937 -33.7185)
		(end 34.840672 -45.07484)
		(width 0.1651)
		(layer "In11.Cu")
		(net "P5E_PEX0_STN2_TX_DP<45>")
	)
	(segment
		(start 33.641284 -105.217976)
		(end 33.640522 -105.23093)
		(width 0.1651)
		(layer "In11.Cu")
		(net "P5E_PEX0_STN2_TX_DP<45>")
	)
	(segment
		(start 37.38372 -50.3682)
		(end 38.14699 -63.150242)
		(width 0.1651)
		(layer "In11.Cu")
		(net "P5E_PEX0_STN2_TX_DP<45>")
	)
	(segment
		(start 25.668732 -33.70453)
		(end 25.7937 -33.7185)
		(width 0.1651)
		(layer "In11.Cu")
		(net "P5E_PEX0_STN2_TX_DP<45>")
	)
	(segment
		(start 45.73397 -271.427448)
		(end 45.77969 -271.473168)
		(width 0.1143)
		(layer "In11.Cu")
		(net "P5E_PEX0_STN2_TX_DP<45>")
	)
	(segment
		(start 33.138618 -116.205762)
		(end 33.540954 -137.987278)
		(width 0.1651)
		(layer "In11.Cu")
		(net "P5E_PEX0_STN2_TX_DP<45>")
	)
	(segment
		(start 25.065482 -32.804608)
		(end 25.374092 -33.191958)
		(width 0.1651)
		(layer "In11.Cu")
		(net "P5E_PEX0_STN2_TX_DP<45>")
	)
	(segment
		(start 45.994828 -278.420068)
		(end 46.23562 -278.420068)
		(width 0.1143)
		(layer "In11.Cu")
		(net "P5E_PEX0_STN2_TX_DP<45>")
	)
	(segment
		(start 22.24024 -30.627828)
		(end 22.245574 -30.62986)
		(width 0.1651)
		(layer "In11.Cu")
		(net "P5E_PEX0_STN2_TX_DP<45>")
	)
	(segment
		(start 45.73397 -271.399)
		(end 45.73397 -271.427448)
		(width 0.1143)
		(layer "In11.Cu")
		(net "P5E_PEX0_STN2_TX_DP<45>")
	)
	(segment
		(start 23.118826 -30.831536)
		(end 24.299418 -31.842964)
		(width 0.1651)
		(layer "In11.Cu")
		(net "P5E_PEX0_STN2_TX_DP<45>")
	)
	(segment
		(start 36.765992 -48.578008)
		(end 37.38372 -50.3682)
		(width 0.1651)
		(layer "In11.Cu")
		(net "P5E_PEX0_STN2_TX_DP<45>")
	)
	(segment
		(start 44.707302 -264.195306)
		(end 45.73397 -270.38427)
		(width 0.1651)
		(layer "In11.Cu")
		(net "P5E_PEX0_STN2_TX_DP<45>")
	)
	(segment
		(start 25.374092 -33.191958)
		(end 25.359868 -33.316926)
		(width 0.1651)
		(layer "In11.Cu")
		(net "P5E_PEX0_STN2_TX_DP<45>")
	)
	(segment
		(start 46.23562 -278.420068)
		(end 46.34992 -278.534368)
		(width 0.1143)
		(layer "In11.Cu")
		(net "P5E_PEX0_STN2_TX_DP<45>")
	)
	(segment
		(start 24.299418 -31.842964)
		(end 24.645874 -32.278066)
		(width 0.1651)
		(layer "In11.Cu")
		(net "P5E_PEX0_STN2_TX_DP<45>")
	)
	(segment
		(start 25.359868 -33.316926)
		(end 25.668732 -33.70453)
		(width 0.1651)
		(layer "In11.Cu")
		(net "P5E_PEX0_STN2_TX_DP<45>")
	)
	(segment
		(start 45.77969 -271.473168)
		(end 45.77969 -278.20493)
		(width 0.1143)
		(layer "In11.Cu")
		(net "P5E_PEX0_STN2_TX_DP<45>")
	)
	(segment
		(start 22.631654 -30.62986)
		(end 23.118826 -30.831536)
		(width 0.1651)
		(layer "In11.Cu")
		(net "P5E_PEX0_STN2_TX_DP<45>")
	)
	(segment
		(start 24.631904 -32.40278)
		(end 24.940768 -32.790638)
		(width 0.1651)
		(layer "In11.Cu")
		(net "P5E_PEX0_STN2_TX_DP<45>")
	)
	(segment
		(start 33.640522 -105.23093)
		(end 33.641538 -105.23093)
		(width 0.1651)
		(layer "In11.Cu")
		(net "P5E_PEX0_STN2_TX_DP<45>")
	)
	(segment
		(start 45.77969 -278.20493)
		(end 45.994828 -278.420068)
		(width 0.1143)
		(layer "In11.Cu")
		(net "P5E_PEX0_STN2_TX_DP<45>")
	)
	(segment
		(start 164.047424 -34.520886)
		(end 163.753038 -34.2265)
		(width 0.13462)
		(layer "F.Cu")
		(net "P5E_PEX1_STN2_TX_DP<43>")
	)
	(segment
		(start 163.121086 -34.2265)
		(end 162.8013 -34.546286)
		(width 0.13462)
		(layer "F.Cu")
		(net "P5E_PEX1_STN2_TX_DP<43>")
	)
	(segment
		(start 163.753038 -34.2265)
		(end 163.121086 -34.2265)
		(width 0.13462)
		(layer "F.Cu")
		(net "P5E_PEX1_STN2_TX_DP<43>")
	)
	(segment
		(start 164.235638 -278.420068)
		(end 164.349938 -278.534368)
		(width 0.1143)
		(layer "In11.Cu")
		(net "P5E_PEX1_STN2_TX_DP<43>")
	)
	(segment
		(start 165.141148 -34.230056)
		(end 166.8399 -35.954716)
		(width 0.1651)
		(layer "In11.Cu")
		(net "P5E_PEX1_STN2_TX_DP<43>")
	)
	(segment
		(start 176.663858 -68.413884)
		(end 166.45255 -95.389446)
		(width 0.1651)
		(layer "In11.Cu")
		(net "P5E_PEX1_STN2_TX_DP<43>")
	)
	(segment
		(start 159.674814 -162.54476)
		(end 163.352988 -265.771376)
		(width 0.1651)
		(layer "In11.Cu")
		(net "P5E_PEX1_STN2_TX_DP<43>")
	)
	(segment
		(start 168.392602 -37.974016)
		(end 168.376346 -38.09873)
		(width 0.1651)
		(layer "In11.Cu")
		(net "P5E_PEX1_STN2_TX_DP<43>")
	)
	(segment
		(start 166.45255 -95.389446)
		(end 164.765482 -101.587808)
		(width 0.1651)
		(layer "In11.Cu")
		(net "P5E_PEX1_STN2_TX_DP<43>")
	)
	(segment
		(start 177.078386 -49.270158)
		(end 177.517552 -50.549048)
		(width 0.1651)
		(layer "In11.Cu")
		(net "P5E_PEX1_STN2_TX_DP<43>")
	)
	(segment
		(start 167.966136 -37.56533)
		(end 168.09085 -37.581586)
		(width 0.1651)
		(layer "In11.Cu")
		(net "P5E_PEX1_STN2_TX_DP<43>")
	)
	(segment
		(start 160.442402 -112.80267)
		(end 158.89732 -115.113054)
		(width 0.1651)
		(layer "In11.Cu")
		(net "P5E_PEX1_STN2_TX_DP<43>")
	)
	(segment
		(start 168.803066 -38.507924)
		(end 177.078386 -49.270158)
		(width 0.1651)
		(layer "In11.Cu")
		(net "P5E_PEX1_STN2_TX_DP<43>")
	)
	(segment
		(start 167.680132 -37.047678)
		(end 167.680386 -37.047678)
		(width 0.1651)
		(layer "In11.Cu")
		(net "P5E_PEX1_STN2_TX_DP<43>")
	)
	(segment
		(start 161.631122 -111.631222)
		(end 160.442402 -112.80267)
		(width 0.1651)
		(layer "In11.Cu")
		(net "P5E_PEX1_STN2_TX_DP<43>")
	)
	(segment
		(start 164.349938 -278.534368)
		(end 164.349938 -278.799798)
		(width 0.1143)
		(layer "In11.Cu")
		(net "P5E_PEX1_STN2_TX_DP<43>")
	)
	(segment
		(start 164.338254 -34.230056)
		(end 165.141148 -34.230056)
		(width 0.1651)
		(layer "In11.Cu")
		(net "P5E_PEX1_STN2_TX_DP<43>")
	)
	(segment
		(start 166.8399 -35.954716)
		(end 167.680132 -37.047678)
		(width 0.1651)
		(layer "In11.Cu")
		(net "P5E_PEX1_STN2_TX_DP<43>")
	)
	(segment
		(start 163.733988 -271.427448)
		(end 163.779708 -271.473168)
		(width 0.1143)
		(layer "In11.Cu")
		(net "P5E_PEX1_STN2_TX_DP<43>")
	)
	(segment
		(start 163.779708 -271.473168)
		(end 163.779708 -278.20493)
		(width 0.1143)
		(layer "In11.Cu")
		(net "P5E_PEX1_STN2_TX_DP<43>")
	)
	(segment
		(start 158.89732 -115.113054)
		(end 158.619444 -116.42979)
		(width 0.1651)
		(layer "In11.Cu")
		(net "P5E_PEX1_STN2_TX_DP<43>")
	)
	(segment
		(start 167.680386 -37.047678)
		(end 167.66413 -37.172392)
		(width 0.1651)
		(layer "In11.Cu")
		(net "P5E_PEX1_STN2_TX_DP<43>")
	)
	(segment
		(start 158.619444 -116.42979)
		(end 158.61157 -146.815048)
		(width 0.1651)
		(layer "In11.Cu")
		(net "P5E_PEX1_STN2_TX_DP<43>")
	)
	(segment
		(start 178.14417 -60.343288)
		(end 176.663858 -68.413884)
		(width 0.1651)
		(layer "In11.Cu")
		(net "P5E_PEX1_STN2_TX_DP<43>")
	)
	(segment
		(start 164.047424 -34.520886)
		(end 164.338254 -34.230056)
		(width 0.1651)
		(layer "In11.Cu")
		(net "P5E_PEX1_STN2_TX_DP<43>")
	)
	(segment
		(start 164.765482 -101.587808)
		(end 161.631122 -111.631222)
		(width 0.1651)
		(layer "In11.Cu")
		(net "P5E_PEX1_STN2_TX_DP<43>")
	)
	(segment
		(start 163.733988 -271.399)
		(end 163.733988 -271.427448)
		(width 0.1143)
		(layer "In11.Cu")
		(net "P5E_PEX1_STN2_TX_DP<43>")
	)
	(segment
		(start 163.733988 -269.63751)
		(end 163.733988 -271.399)
		(width 0.1651)
		(layer "In11.Cu")
		(net "P5E_PEX1_STN2_TX_DP<43>")
	)
	(segment
		(start 163.779708 -278.20493)
		(end 163.994846 -278.420068)
		(width 0.1143)
		(layer "In11.Cu")
		(net "P5E_PEX1_STN2_TX_DP<43>")
	)
	(segment
		(start 168.09085 -37.581586)
		(end 168.392602 -37.974016)
		(width 0.1651)
		(layer "In11.Cu")
		(net "P5E_PEX1_STN2_TX_DP<43>")
	)
	(segment
		(start 168.678606 -38.491668)
		(end 168.803066 -38.507924)
		(width 0.1651)
		(layer "In11.Cu")
		(net "P5E_PEX1_STN2_TX_DP<43>")
	)
	(segment
		(start 163.994846 -278.420068)
		(end 164.235638 -278.420068)
		(width 0.1143)
		(layer "In11.Cu")
		(net "P5E_PEX1_STN2_TX_DP<43>")
	)
	(segment
		(start 167.66413 -37.172392)
		(end 167.966136 -37.56533)
		(width 0.1651)
		(layer "In11.Cu")
		(net "P5E_PEX1_STN2_TX_DP<43>")
	)
	(segment
		(start 163.352988 -265.771376)
		(end 163.733988 -269.63751)
		(width 0.1651)
		(layer "In11.Cu")
		(net "P5E_PEX1_STN2_TX_DP<43>")
	)
	(segment
		(start 177.517552 -50.549048)
		(end 178.14417 -60.343288)
		(width 0.1651)
		(layer "In11.Cu")
		(net "P5E_PEX1_STN2_TX_DP<43>")
	)
	(segment
		(start 168.376346 -38.09873)
		(end 168.678606 -38.491668)
		(width 0.1651)
		(layer "In11.Cu")
		(net "P5E_PEX1_STN2_TX_DP<43>")
	)
	(segment
		(start 158.61157 -146.815048)
		(end 159.674814 -162.54476)
		(width 0.1651)
		(layer "In11.Cu")
		(net "P5E_PEX1_STN2_TX_DP<43>")
	)
	(segment
		(start 267.325602 -122.82424)
		(end 267.619988 -123.11888)
		(width 0.13462)
		(layer "F.Cu")
		(net "P5E_PEX2_STN1_TX_DP<26>")
	)
	(segment
		(start 267.619988 -123.11888)
		(end 268.251686 -123.11888)
		(width 0.13462)
		(layer "F.Cu")
		(net "P5E_PEX2_STN1_TX_DP<26>")
	)
	(segment
		(start 268.251686 -123.11888)
		(end 268.571726 -122.79884)
		(width 0.13462)
		(layer "F.Cu")
		(net "P5E_PEX2_STN1_TX_DP<26>")
	)
	(segment
		(start 262.082534 -132.741162)
		(end 262.082534 -137.017252)
		(width 0.1651)
		(layer "In9.Cu")
		(net "P5E_PEX2_STN1_TX_DP<26>")
	)
	(segment
		(start 300.733968 -271.500346)
		(end 300.779688 -271.546066)
		(width 0.1143)
		(layer "In9.Cu")
		(net "P5E_PEX2_STN1_TX_DP<26>")
	)
	(segment
		(start 300.779688 -278.205184)
		(end 300.994572 -278.420068)
		(width 0.1143)
		(layer "In9.Cu")
		(net "P5E_PEX2_STN1_TX_DP<26>")
	)
	(segment
		(start 266.281662 -123.11507)
		(end 265.919712 -123.47702)
		(width 0.1651)
		(layer "In9.Cu")
		(net "P5E_PEX2_STN1_TX_DP<26>")
	)
	(segment
		(start 301.235364 -278.420068)
		(end 301.349664 -278.534368)
		(width 0.1143)
		(layer "In9.Cu")
		(net "P5E_PEX2_STN1_TX_DP<26>")
	)
	(segment
		(start 301.349664 -278.534368)
		(end 301.349664 -278.799798)
		(width 0.1143)
		(layer "In9.Cu")
		(net "P5E_PEX2_STN1_TX_DP<26>")
	)
	(segment
		(start 264.653776 -143.224758)
		(end 265.385042 -158.085282)
		(width 0.1651)
		(layer "In9.Cu")
		(net "P5E_PEX2_STN1_TX_DP<26>")
	)
	(segment
		(start 300.733968 -263.855962)
		(end 300.733968 -271.471898)
		(width 0.1651)
		(layer "In9.Cu")
		(net "P5E_PEX2_STN1_TX_DP<26>")
	)
	(segment
		(start 267.034772 -123.11507)
		(end 266.281662 -123.11507)
		(width 0.1651)
		(layer "In9.Cu")
		(net "P5E_PEX2_STN1_TX_DP<26>")
	)
	(segment
		(start 300.733968 -271.471898)
		(end 300.733968 -271.500346)
		(width 0.1143)
		(layer "In9.Cu")
		(net "P5E_PEX2_STN1_TX_DP<26>")
	)
	(segment
		(start 267.325602 -122.82424)
		(end 267.034772 -123.11507)
		(width 0.1651)
		(layer "In9.Cu")
		(net "P5E_PEX2_STN1_TX_DP<26>")
	)
	(segment
		(start 300.994572 -278.420068)
		(end 301.235364 -278.420068)
		(width 0.1143)
		(layer "In9.Cu")
		(net "P5E_PEX2_STN1_TX_DP<26>")
	)
	(segment
		(start 262.082534 -137.017252)
		(end 264.653776 -143.224758)
		(width 0.1651)
		(layer "In9.Cu")
		(net "P5E_PEX2_STN1_TX_DP<26>")
	)
	(segment
		(start 300.779688 -271.546066)
		(end 300.779688 -278.205184)
		(width 0.1143)
		(layer "In9.Cu")
		(net "P5E_PEX2_STN1_TX_DP<26>")
	)
	(segment
		(start 265.385042 -158.085282)
		(end 266.033504 -161.345626)
		(width 0.1651)
		(layer "In9.Cu")
		(net "P5E_PEX2_STN1_TX_DP<26>")
	)
	(segment
		(start 266.033504 -161.345626)
		(end 300.733968 -263.855962)
		(width 0.1651)
		(layer "In9.Cu")
		(net "P5E_PEX2_STN1_TX_DP<26>")
	)
	(segment
		(start 265.919712 -123.47702)
		(end 262.082534 -132.741162)
		(width 0.1651)
		(layer "In9.Cu")
		(net "P5E_PEX2_STN1_TX_DP<26>")
	)
	(segment
		(start 270.980662 -355.978206)
		(end 271.300702 -355.658166)
		(width 0.13462)
		(layer "F.Cu")
		(net "P5E_PEX2_STN7_TX_DP<114>")
	)
	(segment
		(start 271.300702 -355.658166)
		(end 271.300702 -355.026722)
		(width 0.13462)
		(layer "F.Cu")
		(net "P5E_PEX2_STN7_TX_DP<114>")
	)
	(segment
		(start 271.300702 -355.026722)
		(end 271.006062 -354.732082)
		(width 0.13462)
		(layer "F.Cu")
		(net "P5E_PEX2_STN7_TX_DP<114>")
	)
	(segment
		(start 255.2446 -307.5432)
		(end 256.939288 -305.634644)
		(width 0.1651)
		(layer "In7.Cu")
		(net "P5E_PEX2_STN7_TX_DP<114>")
	)
	(segment
		(start 250.6472 -323.535294)
		(end 250.6472 -318.122808)
		(width 0.1651)
		(layer "In7.Cu")
		(net "P5E_PEX2_STN7_TX_DP<114>")
	)
	(segment
		(start 272.402554 -341.17915)
		(end 270.848074 -339.498432)
		(width 0.1651)
		(layer "In7.Cu")
		(net "P5E_PEX2_STN7_TX_DP<114>")
	)
	(segment
		(start 250.6472 -318.122808)
		(end 255.2446 -307.5432)
		(width 0.1651)
		(layer "In7.Cu")
		(net "P5E_PEX2_STN7_TX_DP<114>")
	)
	(segment
		(start 274.370038 -303.15535)
		(end 274.370038 -303.385474)
		(width 0.1143)
		(layer "In7.Cu")
		(net "P5E_PEX2_STN7_TX_DP<114>")
	)
	(segment
		(start 257.344926 -305.177698)
		(end 257.344672 -305.177698)
		(width 0.1651)
		(layer "In7.Cu")
		(net "P5E_PEX2_STN7_TX_DP<114>")
	)
	(segment
		(start 256.939288 -305.634644)
		(end 256.939288 -305.63439)
		(width 0.1651)
		(layer "In7.Cu")
		(net "P5E_PEX2_STN7_TX_DP<114>")
	)
	(segment
		(start 274.370038 -303.385474)
		(end 274.484338 -303.499774)
		(width 0.1143)
		(layer "In7.Cu")
		(net "P5E_PEX2_STN7_TX_DP<114>")
	)
	(segment
		(start 271.296892 -353.814126)
		(end 272.851372 -352.259646)
		(width 0.1651)
		(layer "In7.Cu")
		(net "P5E_PEX2_STN7_TX_DP<114>")
	)
	(segment
		(start 259.915406 -303.54524)
		(end 266.632436 -302.883824)
		(width 0.1651)
		(layer "In7.Cu")
		(net "P5E_PEX2_STN7_TX_DP<114>")
	)
	(segment
		(start 256.939288 -305.63439)
		(end 257.344926 -305.177698)
		(width 0.1651)
		(layer "In7.Cu")
		(net "P5E_PEX2_STN7_TX_DP<114>")
	)
	(segment
		(start 272.851372 -352.259646)
		(end 272.851372 -342.324944)
		(width 0.1651)
		(layer "In7.Cu")
		(net "P5E_PEX2_STN7_TX_DP<114>")
	)
	(segment
		(start 257.6957 -304.782474)
		(end 258.617212 -304.151284)
		(width 0.1651)
		(layer "In7.Cu")
		(net "P5E_PEX2_STN7_TX_DP<114>")
	)
	(segment
		(start 270.848074 -339.498432)
		(end 255.284986 -330.636118)
		(width 0.1651)
		(layer "In7.Cu")
		(net "P5E_PEX2_STN7_TX_DP<114>")
	)
	(segment
		(start 272.851372 -342.324944)
		(end 272.402554 -341.17915)
		(width 0.1651)
		(layer "In7.Cu")
		(net "P5E_PEX2_STN7_TX_DP<114>")
	)
	(segment
		(start 258.617212 -304.151284)
		(end 259.915406 -303.54524)
		(width 0.1651)
		(layer "In7.Cu")
		(net "P5E_PEX2_STN7_TX_DP<114>")
	)
	(segment
		(start 267.865352 -302.883824)
		(end 267.8938 -302.883824)
		(width 0.1143)
		(layer "In7.Cu")
		(net "P5E_PEX2_STN7_TX_DP<114>")
	)
	(segment
		(start 267.93952 -302.929544)
		(end 274.144232 -302.929544)
		(width 0.1143)
		(layer "In7.Cu")
		(net "P5E_PEX2_STN7_TX_DP<114>")
	)
	(segment
		(start 267.8938 -302.883824)
		(end 267.93952 -302.929544)
		(width 0.1143)
		(layer "In7.Cu")
		(net "P5E_PEX2_STN7_TX_DP<114>")
	)
	(segment
		(start 266.632436 -302.883824)
		(end 267.865352 -302.883824)
		(width 0.1651)
		(layer "In7.Cu")
		(net "P5E_PEX2_STN7_TX_DP<114>")
	)
	(segment
		(start 257.344672 -305.177698)
		(end 257.6957 -304.782474)
		(width 0.1651)
		(layer "In7.Cu")
		(net "P5E_PEX2_STN7_TX_DP<114>")
	)
	(segment
		(start 274.144232 -302.929544)
		(end 274.370038 -303.15535)
		(width 0.1143)
		(layer "In7.Cu")
		(net "P5E_PEX2_STN7_TX_DP<114>")
	)
	(segment
		(start 255.284986 -330.636118)
		(end 252.086364 -327.010268)
		(width 0.1651)
		(layer "In7.Cu")
		(net "P5E_PEX2_STN7_TX_DP<114>")
	)
	(segment
		(start 252.086364 -327.010268)
		(end 250.6472 -323.535294)
		(width 0.1651)
		(layer "In7.Cu")
		(net "P5E_PEX2_STN7_TX_DP<114>")
	)
	(segment
		(start 274.484338 -303.499774)
		(end 274.749768 -303.499774)
		(width 0.1143)
		(layer "In7.Cu")
		(net "P5E_PEX2_STN7_TX_DP<114>")
	)
	(segment
		(start 271.006062 -354.732082)
		(end 271.296892 -354.441252)
		(width 0.1651)
		(layer "In7.Cu")
		(net "P5E_PEX2_STN7_TX_DP<114>")
	)
	(segment
		(start 271.296892 -354.441252)
		(end 271.296892 -353.814126)
		(width 0.1651)
		(layer "In7.Cu")
		(net "P5E_PEX2_STN7_TX_DP<114>")
	)
	(segment
		(start 384.351784 -108.8898)
		(end 384.671824 -109.20984)
		(width 0.13462)
		(layer "F.Cu")
		(net "P5E_PEX3_STN1_TX_DP<21>")
	)
	(segment
		(start 383.72034 -108.8898)
		(end 384.351784 -108.8898)
		(width 0.13462)
		(layer "F.Cu")
		(net "P5E_PEX3_STN1_TX_DP<21>")
	)
	(segment
		(start 383.4257 -109.18444)
		(end 383.72034 -108.8898)
		(width 0.13462)
		(layer "F.Cu")
		(net "P5E_PEX3_STN1_TX_DP<21>")
	)
	(segment
		(start 378.060458 -117.670326)
		(end 378.019056 -117.570758)
		(width 0.1651)
		(layer "In9.Cu")
		(net "P5E_PEX3_STN1_TX_DP<21>")
	)
	(segment
		(start 373.625872 -137.971022)
		(end 373.625872 -131.318762)
		(width 0.1651)
		(layer "In9.Cu")
		(net "P5E_PEX3_STN1_TX_DP<21>")
	)
	(segment
		(start 378.485908 -116.444268)
		(end 378.675392 -115.986814)
		(width 0.1651)
		(layer "In9.Cu")
		(net "P5E_PEX3_STN1_TX_DP<21>")
	)
	(segment
		(start 379.48108 -114.34064)
		(end 379.419104 -114.191288)
		(width 0.1651)
		(layer "In9.Cu")
		(net "P5E_PEX3_STN1_TX_DP<21>")
	)
	(segment
		(start 378.952506 -115.317778)
		(end 379.14199 -114.860324)
		(width 0.1651)
		(layer "In9.Cu")
		(net "P5E_PEX3_STN1_TX_DP<21>")
	)
	(segment
		(start 380.818898 -110.811818)
		(end 381.008382 -110.354364)
		(width 0.1651)
		(layer "In9.Cu")
		(net "P5E_PEX3_STN1_TX_DP<21>")
	)
	(segment
		(start 412.320232 -271.600168)
		(end 412.365952 -271.554448)
		(width 0.1143)
		(layer "In9.Cu")
		(net "P5E_PEX3_STN1_TX_DP<21>")
	)
	(segment
		(start 412.320232 -280.025856)
		(end 412.320232 -271.600168)
		(width 0.1143)
		(layer "In9.Cu")
		(net "P5E_PEX3_STN1_TX_DP<21>")
	)
	(segment
		(start 373.625872 -131.318762)
		(end 377.185682 -119.582946)
		(width 0.1651)
		(layer "In9.Cu")
		(net "P5E_PEX3_STN1_TX_DP<21>")
	)
	(segment
		(start 412.365952 -271.554448)
		(end 412.365952 -271.526)
		(width 0.1143)
		(layer "In9.Cu")
		(net "P5E_PEX3_STN1_TX_DP<21>")
	)
	(segment
		(start 412.365952 -264.873486)
		(end 377.491752 -161.844736)
		(width 0.1651)
		(layer "In9.Cu")
		(net "P5E_PEX3_STN1_TX_DP<21>")
	)
	(segment
		(start 377.771152 -118.169436)
		(end 377.87072 -118.128288)
		(width 0.1651)
		(layer "In9.Cu")
		(net "P5E_PEX3_STN1_TX_DP<21>")
	)
	(segment
		(start 382.128014 -109.35335)
		(end 382.128014 -109.234732)
		(width 0.1651)
		(layer "In9.Cu")
		(net "P5E_PEX3_STN1_TX_DP<21>")
	)
	(segment
		(start 378.824744 -115.925092)
		(end 379.014482 -115.46713)
		(width 0.1651)
		(layer "In9.Cu")
		(net "P5E_PEX3_STN1_TX_DP<21>")
	)
	(segment
		(start 412.467552 -269.25905)
		(end 412.467552 -268.76375)
		(width 0.1651)
		(layer "In9.Cu")
		(net "P5E_PEX3_STN1_TX_DP<21>")
	)
	(segment
		(start 381.008382 -110.354364)
		(end 381.66802 -109.694726)
		(width 0.1651)
		(layer "In9.Cu")
		(net "P5E_PEX3_STN1_TX_DP<21>")
	)
	(segment
		(start 377.491752 -161.844736)
		(end 376.919236 -158.966408)
		(width 0.1651)
		(layer "In9.Cu")
		(net "P5E_PEX3_STN1_TX_DP<21>")
	)
	(segment
		(start 379.291342 -114.798602)
		(end 379.48108 -114.34064)
		(width 0.1651)
		(layer "In9.Cu")
		(net "P5E_PEX3_STN1_TX_DP<21>")
	)
	(segment
		(start 412.699962 -279.749504)
		(end 412.699962 -280.015188)
		(width 0.1143)
		(layer "In9.Cu")
		(net "P5E_PEX3_STN1_TX_DP<21>")
	)
	(segment
		(start 376.192034 -144.166082)
		(end 373.625872 -137.971022)
		(width 0.1651)
		(layer "In9.Cu")
		(net "P5E_PEX3_STN1_TX_DP<21>")
	)
	(segment
		(start 377.87072 -118.128288)
		(end 378.060458 -117.670326)
		(width 0.1651)
		(layer "In9.Cu")
		(net "P5E_PEX3_STN1_TX_DP<21>")
	)
	(segment
		(start 412.365952 -269.36065)
		(end 412.467552 -269.25905)
		(width 0.1651)
		(layer "In9.Cu")
		(net "P5E_PEX3_STN1_TX_DP<21>")
	)
	(segment
		(start 378.019056 -117.570758)
		(end 378.20854 -117.113304)
		(width 0.1651)
		(layer "In9.Cu")
		(net "P5E_PEX3_STN1_TX_DP<21>")
	)
	(segment
		(start 378.358146 -117.051582)
		(end 378.547884 -116.59362)
		(width 0.1651)
		(layer "In9.Cu")
		(net "P5E_PEX3_STN1_TX_DP<21>")
	)
	(segment
		(start 383.13487 -108.89361)
		(end 383.4257 -109.18444)
		(width 0.1651)
		(layer "In9.Cu")
		(net "P5E_PEX3_STN1_TX_DP<21>")
	)
	(segment
		(start 379.14199 -114.860324)
		(end 379.291342 -114.798602)
		(width 0.1651)
		(layer "In9.Cu")
		(net "P5E_PEX3_STN1_TX_DP<21>")
	)
	(segment
		(start 379.885702 -113.064798)
		(end 380.075186 -112.607344)
		(width 0.1651)
		(layer "In9.Cu")
		(net "P5E_PEX3_STN1_TX_DP<21>")
	)
	(segment
		(start 381.786384 -109.694726)
		(end 382.128014 -109.35335)
		(width 0.1651)
		(layer "In9.Cu")
		(net "P5E_PEX3_STN1_TX_DP<21>")
	)
	(segment
		(start 412.467552 -268.76375)
		(end 412.365952 -268.66215)
		(width 0.1651)
		(layer "In9.Cu")
		(net "P5E_PEX3_STN1_TX_DP<21>")
	)
	(segment
		(start 412.365952 -271.526)
		(end 412.365952 -269.36065)
		(width 0.1651)
		(layer "In9.Cu")
		(net "P5E_PEX3_STN1_TX_DP<21>")
	)
	(segment
		(start 412.585662 -280.129488)
		(end 412.423864 -280.129488)
		(width 0.1143)
		(layer "In9.Cu")
		(net "P5E_PEX3_STN1_TX_DP<21>")
	)
	(segment
		(start 380.414276 -112.08766)
		(end 380.3523 -111.938308)
		(width 0.1651)
		(layer "In9.Cu")
		(net "P5E_PEX3_STN1_TX_DP<21>")
	)
	(segment
		(start 379.608588 -113.733834)
		(end 379.758194 -113.672112)
		(width 0.1651)
		(layer "In9.Cu")
		(net "P5E_PEX3_STN1_TX_DP<21>")
	)
	(segment
		(start 412.365952 -268.66215)
		(end 412.365952 -264.873486)
		(width 0.1651)
		(layer "In9.Cu")
		(net "P5E_PEX3_STN1_TX_DP<21>")
	)
	(segment
		(start 412.699962 -280.015188)
		(end 412.585662 -280.129488)
		(width 0.1143)
		(layer "In9.Cu")
		(net "P5E_PEX3_STN1_TX_DP<21>")
	)
	(segment
		(start 382.469136 -108.89361)
		(end 383.13487 -108.89361)
		(width 0.1651)
		(layer "In9.Cu")
		(net "P5E_PEX3_STN1_TX_DP<21>")
	)
	(segment
		(start 380.880874 -110.96117)
		(end 380.818898 -110.811818)
		(width 0.1651)
		(layer "In9.Cu")
		(net "P5E_PEX3_STN1_TX_DP<21>")
	)
	(segment
		(start 379.419104 -114.191288)
		(end 379.608588 -113.733834)
		(width 0.1651)
		(layer "In9.Cu")
		(net "P5E_PEX3_STN1_TX_DP<21>")
	)
	(segment
		(start 380.541784 -111.480854)
		(end 380.69139 -111.419132)
		(width 0.1651)
		(layer "In9.Cu")
		(net "P5E_PEX3_STN1_TX_DP<21>")
	)
	(segment
		(start 379.947678 -113.21415)
		(end 379.885702 -113.064798)
		(width 0.1651)
		(layer "In9.Cu")
		(net "P5E_PEX3_STN1_TX_DP<21>")
	)
	(segment
		(start 380.224792 -112.545622)
		(end 380.414276 -112.08766)
		(width 0.1651)
		(layer "In9.Cu")
		(net "P5E_PEX3_STN1_TX_DP<21>")
	)
	(segment
		(start 380.075186 -112.607344)
		(end 380.224792 -112.545622)
		(width 0.1651)
		(layer "In9.Cu")
		(net "P5E_PEX3_STN1_TX_DP<21>")
	)
	(segment
		(start 378.675392 -115.986814)
		(end 378.824744 -115.925092)
		(width 0.1651)
		(layer "In9.Cu")
		(net "P5E_PEX3_STN1_TX_DP<21>")
	)
	(segment
		(start 382.128014 -109.234732)
		(end 382.469136 -108.89361)
		(width 0.1651)
		(layer "In9.Cu")
		(net "P5E_PEX3_STN1_TX_DP<21>")
	)
	(segment
		(start 378.20854 -117.113304)
		(end 378.358146 -117.051582)
		(width 0.1651)
		(layer "In9.Cu")
		(net "P5E_PEX3_STN1_TX_DP<21>")
	)
	(segment
		(start 379.758194 -113.672112)
		(end 379.947678 -113.21415)
		(width 0.1651)
		(layer "In9.Cu")
		(net "P5E_PEX3_STN1_TX_DP<21>")
	)
	(segment
		(start 379.014482 -115.46713)
		(end 378.952506 -115.317778)
		(width 0.1651)
		(layer "In9.Cu")
		(net "P5E_PEX3_STN1_TX_DP<21>")
	)
	(segment
		(start 376.919236 -158.966408)
		(end 376.192034 -144.166082)
		(width 0.1651)
		(layer "In9.Cu")
		(net "P5E_PEX3_STN1_TX_DP<21>")
	)
	(segment
		(start 380.3523 -111.938308)
		(end 380.541784 -111.480854)
		(width 0.1651)
		(layer "In9.Cu")
		(net "P5E_PEX3_STN1_TX_DP<21>")
	)
	(segment
		(start 412.423864 -280.129488)
		(end 412.320232 -280.025856)
		(width 0.1143)
		(layer "In9.Cu")
		(net "P5E_PEX3_STN1_TX_DP<21>")
	)
	(segment
		(start 377.185682 -119.582946)
		(end 377.771152 -118.169436)
		(width 0.1651)
		(layer "In9.Cu")
		(net "P5E_PEX3_STN1_TX_DP<21>")
	)
	(segment
		(start 378.547884 -116.59362)
		(end 378.485908 -116.444268)
		(width 0.1651)
		(layer "In9.Cu")
		(net "P5E_PEX3_STN1_TX_DP<21>")
	)
	(segment
		(start 381.66802 -109.694726)
		(end 381.786384 -109.694726)
		(width 0.1651)
		(layer "In9.Cu")
		(net "P5E_PEX3_STN1_TX_DP<21>")
	)
	(segment
		(start 380.69139 -111.419132)
		(end 380.880874 -110.96117)
		(width 0.1651)
		(layer "In9.Cu")
		(net "P5E_PEX3_STN1_TX_DP<21>")
	)
	(segment
		(start 434.460904 -342.73363)
		(end 434.166772 -342.439498)
		(width 0.13462)
		(layer "F.Cu")
		(net "P5E_PEX3_STN7_TX_DP<123>")
	)
	(segment
		(start 434.460904 -343.36609)
		(end 434.460904 -342.73363)
		(width 0.13462)
		(layer "F.Cu")
		(net "P5E_PEX3_STN7_TX_DP<123>")
	)
	(segment
		(start 434.141372 -343.685622)
		(end 434.460904 -343.36609)
		(width 0.13462)
		(layer "F.Cu")
		(net "P5E_PEX3_STN7_TX_DP<123>")
	)
	(segment
		(start 386.479542 -319.988438)
		(end 386.479542 -313.595004)
		(width 0.1143)
		(layer "In11.Cu")
		(net "P5E_PEX3_STN7_TX_DP<123>")
	)
	(segment
		(start 386.694934 -313.379612)
		(end 386.935726 -313.379612)
		(width 0.1143)
		(layer "In11.Cu")
		(net "P5E_PEX3_STN7_TX_DP<123>")
	)
	(segment
		(start 386.433822 -320.034158)
		(end 386.479542 -319.988438)
		(width 0.1143)
		(layer "In11.Cu")
		(net "P5E_PEX3_STN7_TX_DP<123>")
	)
	(segment
		(start 388.225284 -324.362064)
		(end 386.570728 -322.707508)
		(width 0.1651)
		(layer "In11.Cu")
		(net "P5E_PEX3_STN7_TX_DP<123>")
	)
	(segment
		(start 386.479542 -313.595004)
		(end 386.694934 -313.379612)
		(width 0.1143)
		(layer "In11.Cu")
		(net "P5E_PEX3_STN7_TX_DP<123>")
	)
	(segment
		(start 434.457602 -342.148668)
		(end 434.457602 -341.711026)
		(width 0.1651)
		(layer "In11.Cu")
		(net "P5E_PEX3_STN7_TX_DP<123>")
	)
	(segment
		(start 386.935726 -313.379612)
		(end 387.050026 -313.265312)
		(width 0.1143)
		(layer "In11.Cu")
		(net "P5E_PEX3_STN7_TX_DP<123>")
	)
	(segment
		(start 434.166772 -342.439498)
		(end 434.457602 -342.148668)
		(width 0.1651)
		(layer "In11.Cu")
		(net "P5E_PEX3_STN7_TX_DP<123>")
	)
	(segment
		(start 386.433822 -320.056256)
		(end 386.433822 -320.034158)
		(width 0.1143)
		(layer "In11.Cu")
		(net "P5E_PEX3_STN7_TX_DP<123>")
	)
	(segment
		(start 387.050026 -313.265312)
		(end 387.050026 -312.999882)
		(width 0.1143)
		(layer "In11.Cu")
		(net "P5E_PEX3_STN7_TX_DP<123>")
	)
	(segment
		(start 433.419504 -339.97519)
		(end 424.25747 -333.867506)
		(width 0.1651)
		(layer "In11.Cu")
		(net "P5E_PEX3_STN7_TX_DP<123>")
	)
	(segment
		(start 386.570728 -322.707508)
		(end 386.433822 -322.377054)
		(width 0.1651)
		(layer "In11.Cu")
		(net "P5E_PEX3_STN7_TX_DP<123>")
	)
	(segment
		(start 424.25747 -333.867506)
		(end 388.225284 -324.362064)
		(width 0.1651)
		(layer "In11.Cu")
		(net "P5E_PEX3_STN7_TX_DP<123>")
	)
	(segment
		(start 434.457602 -341.711026)
		(end 433.419504 -339.97519)
		(width 0.1651)
		(layer "In11.Cu")
		(net "P5E_PEX3_STN7_TX_DP<123>")
	)
	(segment
		(start 386.433822 -322.377054)
		(end 386.433822 -320.056256)
		(width 0.1651)
		(layer "In11.Cu")
		(net "P5E_PEX3_STN7_TX_DP<123>")
	)
	(segment
		(start 83.703922 -342.734138)
		(end 83.998562 -342.439498)
		(width 0.13462)
		(layer "F.Cu")
		(net "P5E_PEX0_STN5_TX_DN<90>")
	)
	(segment
		(start 84.023962 -343.685622)
		(end 83.703922 -343.365582)
		(width 0.13462)
		(layer "F.Cu")
		(net "P5E_PEX0_STN5_TX_DN<90>")
	)
	(segment
		(start 83.703922 -343.365582)
		(end 83.703922 -342.734138)
		(width 0.13462)
		(layer "F.Cu")
		(net "P5E_PEX0_STN5_TX_DN<90>")
	)
	(segment
		(start 83.707732 -342.148668)
		(end 83.707732 -340.9442)
		(width 0.1651)
		(layer "In7.Cu")
		(net "P5E_PEX0_STN5_TX_DN<90>")
	)
	(segment
		(start 67.865752 -321.40779)
		(end 67.865752 -319.916048)
		(width 0.1651)
		(layer "In7.Cu")
		(net "P5E_PEX0_STN5_TX_DN<90>")
	)
	(segment
		(start 67.820032 -311.784492)
		(end 67.934332 -311.670192)
		(width 0.1143)
		(layer "In7.Cu")
		(net "P5E_PEX0_STN5_TX_DN<90>")
	)
	(segment
		(start 67.934332 -311.670192)
		(end 68.085462 -311.670192)
		(width 0.1143)
		(layer "In7.Cu")
		(net "P5E_PEX0_STN5_TX_DN<90>")
	)
	(segment
		(start 67.865752 -319.916048)
		(end 67.865752 -319.8876)
		(width 0.1143)
		(layer "In7.Cu")
		(net "P5E_PEX0_STN5_TX_DN<90>")
	)
	(segment
		(start 67.865752 -319.8876)
		(end 67.820032 -319.84188)
		(width 0.1143)
		(layer "In7.Cu")
		(net "P5E_PEX0_STN5_TX_DN<90>")
	)
	(segment
		(start 83.296506 -339.951568)
		(end 74.632566 -329.394566)
		(width 0.1651)
		(layer "In7.Cu")
		(net "P5E_PEX0_STN5_TX_DN<90>")
	)
	(segment
		(start 74.632566 -329.394566)
		(end 69.481192 -324.243192)
		(width 0.1651)
		(layer "In7.Cu")
		(net "P5E_PEX0_STN5_TX_DN<90>")
	)
	(segment
		(start 68.321174 -322.507356)
		(end 67.865752 -321.40779)
		(width 0.1651)
		(layer "In7.Cu")
		(net "P5E_PEX0_STN5_TX_DN<90>")
	)
	(segment
		(start 68.085462 -311.670192)
		(end 68.199762 -311.784492)
		(width 0.1143)
		(layer "In7.Cu")
		(net "P5E_PEX0_STN5_TX_DN<90>")
	)
	(segment
		(start 83.707732 -340.9442)
		(end 83.296506 -339.951568)
		(width 0.1651)
		(layer "In7.Cu")
		(net "P5E_PEX0_STN5_TX_DN<90>")
	)
	(segment
		(start 83.998562 -342.439498)
		(end 83.707732 -342.148668)
		(width 0.1651)
		(layer "In7.Cu")
		(net "P5E_PEX0_STN5_TX_DN<90>")
	)
	(segment
		(start 69.481192 -324.243192)
		(end 68.321174 -322.507356)
		(width 0.1651)
		(layer "In7.Cu")
		(net "P5E_PEX0_STN5_TX_DN<90>")
	)
	(segment
		(start 68.199762 -311.784492)
		(end 68.199762 -312.049922)
		(width 0.1143)
		(layer "In7.Cu")
		(net "P5E_PEX0_STN5_TX_DN<90>")
	)
	(segment
		(start 67.820032 -319.84188)
		(end 67.820032 -311.784492)
		(width 0.1143)
		(layer "In7.Cu")
		(net "P5E_PEX0_STN5_TX_DN<90>")
	)
	(segment
		(start 140.411708 -349.511874)
		(end 140.411708 -348.88043)
		(width 0.13462)
		(layer "F.Cu")
		(net "P5E_PEX1_STN5_TX_DN<93>")
	)
	(segment
		(start 140.411708 -348.88043)
		(end 140.706348 -348.58579)
		(width 0.13462)
		(layer "F.Cu")
		(net "P5E_PEX1_STN5_TX_DN<93>")
	)
	(segment
		(start 140.731748 -349.831914)
		(end 140.411708 -349.511874)
		(width 0.13462)
		(layer "F.Cu")
		(net "P5E_PEX1_STN5_TX_DN<93>")
	)
	(segment
		(start 187.149994 -313.684412)
		(end 187.035694 -313.570112)
		(width 0.1143)
		(layer "In13.Cu")
		(net "P5E_PEX1_STN5_TX_DN<93>")
	)
	(segment
		(start 147.446492 -340.164928)
		(end 143.487902 -340.164928)
		(width 0.1651)
		(layer "In13.Cu")
		(net "P5E_PEX1_STN5_TX_DN<93>")
	)
	(segment
		(start 143.143224 -340.307676)
		(end 141.969998 -341.480902)
		(width 0.1651)
		(layer "In13.Cu")
		(net "P5E_PEX1_STN5_TX_DN<93>")
	)
	(segment
		(start 187.035694 -313.570112)
		(end 186.873896 -313.570112)
		(width 0.1143)
		(layer "In13.Cu")
		(net "P5E_PEX1_STN5_TX_DN<93>")
	)
	(segment
		(start 143.487902 -340.164928)
		(end 143.143224 -340.307676)
		(width 0.1651)
		(layer "In13.Cu")
		(net "P5E_PEX1_STN5_TX_DN<93>")
	)
	(segment
		(start 186.873896 -313.570112)
		(end 186.770264 -313.673744)
		(width 0.1143)
		(layer "In13.Cu")
		(net "P5E_PEX1_STN5_TX_DN<93>")
	)
	(segment
		(start 176.180496 -329.54849)
		(end 165.460934 -334.161384)
		(width 0.1651)
		(layer "In13.Cu")
		(net "P5E_PEX1_STN5_TX_DN<93>")
	)
	(segment
		(start 186.484514 -322.984622)
		(end 185.172096 -324.297548)
		(width 0.1651)
		(layer "In13.Cu")
		(net "P5E_PEX1_STN5_TX_DN<93>")
	)
	(segment
		(start 141.969998 -341.480902)
		(end 141.969998 -346.069412)
		(width 0.1651)
		(layer "In13.Cu")
		(net "P5E_PEX1_STN5_TX_DN<93>")
	)
	(segment
		(start 186.770264 -319.995296)
		(end 186.815984 -320.041016)
		(width 0.1143)
		(layer "In13.Cu")
		(net "P5E_PEX1_STN5_TX_DN<93>")
	)
	(segment
		(start 181.836822 -326.52462)
		(end 176.180496 -329.54849)
		(width 0.1651)
		(layer "In13.Cu")
		(net "P5E_PEX1_STN5_TX_DN<93>")
	)
	(segment
		(start 186.815984 -322.184014)
		(end 186.484514 -322.984622)
		(width 0.1651)
		(layer "In13.Cu")
		(net "P5E_PEX1_STN5_TX_DN<93>")
	)
	(segment
		(start 165.460934 -334.161384)
		(end 147.446492 -340.164928)
		(width 0.1651)
		(layer "In13.Cu")
		(net "P5E_PEX1_STN5_TX_DN<93>")
	)
	(segment
		(start 187.149994 -313.949842)
		(end 187.149994 -313.684412)
		(width 0.1143)
		(layer "In13.Cu")
		(net "P5E_PEX1_STN5_TX_DN<93>")
	)
	(segment
		(start 140.415518 -347.623892)
		(end 140.415518 -348.29496)
		(width 0.1651)
		(layer "In13.Cu")
		(net "P5E_PEX1_STN5_TX_DN<93>")
	)
	(segment
		(start 186.815984 -320.063114)
		(end 186.815984 -322.184014)
		(width 0.1651)
		(layer "In13.Cu")
		(net "P5E_PEX1_STN5_TX_DN<93>")
	)
	(segment
		(start 186.770264 -313.673744)
		(end 186.770264 -319.995296)
		(width 0.1143)
		(layer "In13.Cu")
		(net "P5E_PEX1_STN5_TX_DN<93>")
	)
	(segment
		(start 186.815984 -320.041016)
		(end 186.815984 -320.063114)
		(width 0.1143)
		(layer "In13.Cu")
		(net "P5E_PEX1_STN5_TX_DN<93>")
	)
	(segment
		(start 141.969998 -346.069412)
		(end 140.415518 -347.623892)
		(width 0.1651)
		(layer "In13.Cu")
		(net "P5E_PEX1_STN5_TX_DN<93>")
	)
	(segment
		(start 140.415518 -348.29496)
		(end 140.706348 -348.58579)
		(width 0.1651)
		(layer "In13.Cu")
		(net "P5E_PEX1_STN5_TX_DN<93>")
	)
	(segment
		(start 185.172096 -324.297548)
		(end 181.836822 -326.52462)
		(width 0.1651)
		(layer "In13.Cu")
		(net "P5E_PEX1_STN5_TX_DN<93>")
	)
	(segment
		(start 312.800238 -133.7945)
		(end 312.48604 -133.480302)
		(width 0.13462)
		(layer "F.Cu")
		(net "P5E_PEX2_STN0_TX_DN<6>")
	)
	(segment
		(start 313.443366 -133.7945)
		(end 312.800238 -133.7945)
		(width 0.13462)
		(layer "F.Cu")
		(net "P5E_PEX2_STN0_TX_DN<6>")
	)
	(segment
		(start 313.732164 -133.505702)
		(end 313.443366 -133.7945)
		(width 0.13462)
		(layer "F.Cu")
		(net "P5E_PEX2_STN0_TX_DN<6>")
	)
	(segment
		(start 326.565006 -153.928572)
		(end 326.565006 -158.997904)
		(width 0.1651)
		(layer "In9.Cu")
		(net "P5E_PEX2_STN0_TX_DN<6>")
	)
	(segment
		(start 327.043796 -271.584166)
		(end 326.26808 -273.714718)
		(width 0.1651)
		(layer "In9.Cu")
		(net "P5E_PEX2_STN0_TX_DN<6>")
	)
	(segment
		(start 318.59601 -135.339328)
		(end 322.58762 -144.97558)
		(width 0.1651)
		(layer "In9.Cu")
		(net "P5E_PEX2_STN0_TX_DN<6>")
	)
	(segment
		(start 309.520082 -282.323794)
		(end 309.520082 -282.485592)
		(width 0.1143)
		(layer "In9.Cu")
		(net "P5E_PEX2_STN0_TX_DN<6>")
	)
	(segment
		(start 317.814706 -134.558024)
		(end 318.59601 -135.339328)
		(width 0.1651)
		(layer "In9.Cu")
		(net "P5E_PEX2_STN0_TX_DN<6>")
	)
	(segment
		(start 316.08903 -282.265882)
		(end 316.04331 -282.220162)
		(width 0.1143)
		(layer "In9.Cu")
		(net "P5E_PEX2_STN0_TX_DN<6>")
	)
	(segment
		(start 313.012836 -221.640654)
		(end 315.615066 -251.430536)
		(width 0.1651)
		(layer "In9.Cu")
		(net "P5E_PEX2_STN0_TX_DN<6>")
	)
	(segment
		(start 323.046852 -145.434812)
		(end 326.565006 -153.928572)
		(width 0.1651)
		(layer "In9.Cu")
		(net "P5E_PEX2_STN0_TX_DN<6>")
	)
	(segment
		(start 316.813438 -178.200304)
		(end 313.012836 -221.640654)
		(width 0.1651)
		(layer "In9.Cu")
		(net "P5E_PEX2_STN0_TX_DN<6>")
	)
	(segment
		(start 316.04331 -282.220162)
		(end 309.623714 -282.220162)
		(width 0.1143)
		(layer "In9.Cu")
		(net "P5E_PEX2_STN0_TX_DN<6>")
	)
	(segment
		(start 318.34836 -281.634438)
		(end 316.823598 -282.265882)
		(width 0.1651)
		(layer "In9.Cu")
		(net "P5E_PEX2_STN0_TX_DN<6>")
	)
	(segment
		(start 309.520082 -282.485592)
		(end 309.634382 -282.599892)
		(width 0.1143)
		(layer "In9.Cu")
		(net "P5E_PEX2_STN0_TX_DN<6>")
	)
	(segment
		(start 313.732164 -133.505702)
		(end 314.022994 -133.796532)
		(width 0.1651)
		(layer "In9.Cu")
		(net "P5E_PEX2_STN0_TX_DN<6>")
	)
	(segment
		(start 316.823598 -282.265882)
		(end 316.117478 -282.265882)
		(width 0.1651)
		(layer "In9.Cu")
		(net "P5E_PEX2_STN0_TX_DN<6>")
	)
	(segment
		(start 322.58762 -144.97558)
		(end 323.046852 -145.434812)
		(width 0.1651)
		(layer "In9.Cu")
		(net "P5E_PEX2_STN0_TX_DN<6>")
	)
	(segment
		(start 326.26808 -273.714718)
		(end 318.34836 -281.634438)
		(width 0.1651)
		(layer "In9.Cu")
		(net "P5E_PEX2_STN0_TX_DN<6>")
	)
	(segment
		(start 309.623714 -282.220162)
		(end 309.520082 -282.323794)
		(width 0.1143)
		(layer "In9.Cu")
		(net "P5E_PEX2_STN0_TX_DN<6>")
	)
	(segment
		(start 317.969138 -173.890686)
		(end 316.813438 -178.200304)
		(width 0.1651)
		(layer "In9.Cu")
		(net "P5E_PEX2_STN0_TX_DN<6>")
	)
	(segment
		(start 309.634382 -282.599892)
		(end 309.899812 -282.599892)
		(width 0.1143)
		(layer "In9.Cu")
		(net "P5E_PEX2_STN0_TX_DN<6>")
	)
	(segment
		(start 316.117478 -282.265882)
		(end 316.08903 -282.265882)
		(width 0.1143)
		(layer "In9.Cu")
		(net "P5E_PEX2_STN0_TX_DN<6>")
	)
	(segment
		(start 314.022994 -133.796532)
		(end 315.976254 -133.796532)
		(width 0.1651)
		(layer "In9.Cu")
		(net "P5E_PEX2_STN0_TX_DN<6>")
	)
	(segment
		(start 326.565006 -158.997904)
		(end 317.969138 -173.890686)
		(width 0.1651)
		(layer "In9.Cu")
		(net "P5E_PEX2_STN0_TX_DN<6>")
	)
	(segment
		(start 326.79132 -268.704568)
		(end 327.043796 -271.584166)
		(width 0.1651)
		(layer "In9.Cu")
		(net "P5E_PEX2_STN0_TX_DN<6>")
	)
	(segment
		(start 315.615066 -251.430536)
		(end 326.194928 -267.264388)
		(width 0.1651)
		(layer "In9.Cu")
		(net "P5E_PEX2_STN0_TX_DN<6>")
	)
	(segment
		(start 326.194928 -267.264388)
		(end 326.79132 -268.704568)
		(width 0.1651)
		(layer "In9.Cu")
		(net "P5E_PEX2_STN0_TX_DN<6>")
	)
	(segment
		(start 315.976254 -133.796532)
		(end 317.814706 -134.558024)
		(width 0.1651)
		(layer "In9.Cu")
		(net "P5E_PEX2_STN0_TX_DN<6>")
	)
	(segment
		(start 318.695324 -355.978206)
		(end 319.015364 -355.658166)
		(width 0.13462)
		(layer "F.Cu")
		(net "P5E_PEX2_STN6_TX_DP<108>")
	)
	(segment
		(start 319.015364 -355.658166)
		(end 319.015364 -355.026722)
		(width 0.13462)
		(layer "F.Cu")
		(net "P5E_PEX2_STN6_TX_DP<108>")
	)
	(segment
		(start 319.015364 -355.026722)
		(end 318.720724 -354.732082)
		(width 0.13462)
		(layer "F.Cu")
		(net "P5E_PEX2_STN6_TX_DP<108>")
	)
	(segment
		(start 319.90284 -340.64829)
		(end 313.955938 -337.8835)
		(width 0.1651)
		(layer "In13.Cu")
		(net "P5E_PEX2_STN6_TX_DP<108>")
	)
	(segment
		(start 319.011554 -353.814126)
		(end 320.566034 -352.259646)
		(width 0.1651)
		(layer "In13.Cu")
		(net "P5E_PEX2_STN6_TX_DP<108>")
	)
	(segment
		(start 277.933912 -319.966848)
		(end 277.979632 -319.921128)
		(width 0.1143)
		(layer "In13.Cu")
		(net "P5E_PEX2_STN6_TX_DP<108>")
	)
	(segment
		(start 278.549862 -313.265312)
		(end 278.549862 -312.999882)
		(width 0.1143)
		(layer "In13.Cu")
		(net "P5E_PEX2_STN6_TX_DP<108>")
	)
	(segment
		(start 320.566034 -352.259646)
		(end 320.566034 -342.097868)
		(width 0.1651)
		(layer "In13.Cu")
		(net "P5E_PEX2_STN6_TX_DP<108>")
	)
	(segment
		(start 319.011554 -354.441252)
		(end 319.011554 -353.814126)
		(width 0.1651)
		(layer "In13.Cu")
		(net "P5E_PEX2_STN6_TX_DP<108>")
	)
	(segment
		(start 278.957532 -327.463912)
		(end 277.933912 -324.992746)
		(width 0.1651)
		(layer "In13.Cu")
		(net "P5E_PEX2_STN6_TX_DP<108>")
	)
	(segment
		(start 320.566034 -342.097868)
		(end 319.90284 -340.64829)
		(width 0.1651)
		(layer "In13.Cu")
		(net "P5E_PEX2_STN6_TX_DP<108>")
	)
	(segment
		(start 318.720724 -354.732082)
		(end 319.011554 -354.441252)
		(width 0.1651)
		(layer "In13.Cu")
		(net "P5E_PEX2_STN6_TX_DP<108>")
	)
	(segment
		(start 277.979632 -313.59475)
		(end 278.19477 -313.379612)
		(width 0.1143)
		(layer "In13.Cu")
		(net "P5E_PEX2_STN6_TX_DP<108>")
	)
	(segment
		(start 277.979632 -319.921128)
		(end 277.979632 -313.59475)
		(width 0.1143)
		(layer "In13.Cu")
		(net "P5E_PEX2_STN6_TX_DP<108>")
	)
	(segment
		(start 278.435562 -313.379612)
		(end 278.549862 -313.265312)
		(width 0.1143)
		(layer "In13.Cu")
		(net "P5E_PEX2_STN6_TX_DP<108>")
	)
	(segment
		(start 278.19477 -313.379612)
		(end 278.435562 -313.379612)
		(width 0.1143)
		(layer "In13.Cu")
		(net "P5E_PEX2_STN6_TX_DP<108>")
	)
	(segment
		(start 277.933912 -319.995296)
		(end 277.933912 -319.966848)
		(width 0.1143)
		(layer "In13.Cu")
		(net "P5E_PEX2_STN6_TX_DP<108>")
	)
	(segment
		(start 283.341318 -331.847698)
		(end 278.957532 -327.463912)
		(width 0.1651)
		(layer "In13.Cu")
		(net "P5E_PEX2_STN6_TX_DP<108>")
	)
	(segment
		(start 313.955938 -337.8835)
		(end 283.341318 -331.847698)
		(width 0.1651)
		(layer "In13.Cu")
		(net "P5E_PEX2_STN6_TX_DP<108>")
	)
	(segment
		(start 277.933912 -324.992746)
		(end 277.933912 -319.995296)
		(width 0.1651)
		(layer "In13.Cu")
		(net "P5E_PEX2_STN6_TX_DP<108>")
	)
	(segment
		(start 386.067808 -102.914196)
		(end 386.358892 -103.20528)
		(width 0.13462)
		(layer "F.Cu")
		(net "P5E_PEX3_STN1_TX_DP<18>")
	)
	(segment
		(start 386.358892 -103.20528)
		(end 386.997448 -103.20528)
		(width 0.13462)
		(layer "F.Cu")
		(net "P5E_PEX3_STN1_TX_DP<18>")
	)
	(segment
		(start 386.997448 -103.20528)
		(end 387.313932 -102.888796)
		(width 0.13462)
		(layer "F.Cu")
		(net "P5E_PEX3_STN1_TX_DP<18>")
	)
	(segment
		(start 382.82245 -103.672386)
		(end 381.867156 -104.068118)
		(width 0.1651)
		(layer "In9.Cu")
		(net "P5E_PEX3_STN1_TX_DP<18>")
	)
	(segment
		(start 370.440712 -138.693652)
		(end 373.016526 -144.912588)
		(width 0.1651)
		(layer "In9.Cu")
		(net "P5E_PEX3_STN1_TX_DP<18>")
	)
	(segment
		(start 409.735274 -278.420068)
		(end 409.849574 -278.534368)
		(width 0.1143)
		(layer "In9.Cu")
		(net "P5E_PEX3_STN1_TX_DP<18>")
	)
	(segment
		(start 383.950718 -103.205026)
		(end 382.822196 -103.672386)
		(width 0.1651)
		(layer "In9.Cu")
		(net "P5E_PEX3_STN1_TX_DP<18>")
	)
	(segment
		(start 381.867156 -104.068118)
		(end 378.255022 -107.680252)
		(width 0.1651)
		(layer "In9.Cu")
		(net "P5E_PEX3_STN1_TX_DP<18>")
	)
	(segment
		(start 409.279598 -278.205184)
		(end 409.494482 -278.420068)
		(width 0.1143)
		(layer "In9.Cu")
		(net "P5E_PEX3_STN1_TX_DP<18>")
	)
	(segment
		(start 409.233878 -265.558016)
		(end 409.233878 -271.471898)
		(width 0.1651)
		(layer "In9.Cu")
		(net "P5E_PEX3_STN1_TX_DP<18>")
	)
	(segment
		(start 409.279598 -271.546066)
		(end 409.279598 -278.205184)
		(width 0.1143)
		(layer "In9.Cu")
		(net "P5E_PEX3_STN1_TX_DP<18>")
	)
	(segment
		(start 382.822196 -103.672386)
		(end 382.82245 -103.672386)
		(width 0.1651)
		(layer "In9.Cu")
		(net "P5E_PEX3_STN1_TX_DP<18>")
	)
	(segment
		(start 409.233878 -271.471898)
		(end 409.233878 -271.500346)
		(width 0.1143)
		(layer "In9.Cu")
		(net "P5E_PEX3_STN1_TX_DP<18>")
	)
	(segment
		(start 385.776978 -103.205026)
		(end 383.950718 -103.205026)
		(width 0.1651)
		(layer "In9.Cu")
		(net "P5E_PEX3_STN1_TX_DP<18>")
	)
	(segment
		(start 386.067808 -102.914196)
		(end 385.776978 -103.205026)
		(width 0.1651)
		(layer "In9.Cu")
		(net "P5E_PEX3_STN1_TX_DP<18>")
	)
	(segment
		(start 373.55272 -155.81503)
		(end 373.732044 -159.462978)
		(width 0.1651)
		(layer "In9.Cu")
		(net "P5E_PEX3_STN1_TX_DP<18>")
	)
	(segment
		(start 409.494482 -278.420068)
		(end 409.735274 -278.420068)
		(width 0.1143)
		(layer "In9.Cu")
		(net "P5E_PEX3_STN1_TX_DP<18>")
	)
	(segment
		(start 373.016526 -144.912588)
		(end 373.55272 -155.81503)
		(width 0.1651)
		(layer "In9.Cu")
		(net "P5E_PEX3_STN1_TX_DP<18>")
	)
	(segment
		(start 370.440712 -130.948938)
		(end 370.440712 -138.693652)
		(width 0.1651)
		(layer "In9.Cu")
		(net "P5E_PEX3_STN1_TX_DP<18>")
	)
	(segment
		(start 374.315482 -162.39617)
		(end 409.233878 -265.558016)
		(width 0.1651)
		(layer "In9.Cu")
		(net "P5E_PEX3_STN1_TX_DP<18>")
	)
	(segment
		(start 409.849574 -278.534368)
		(end 409.849574 -278.799798)
		(width 0.1143)
		(layer "In9.Cu")
		(net "P5E_PEX3_STN1_TX_DP<18>")
	)
	(segment
		(start 409.233878 -271.500346)
		(end 409.279598 -271.546066)
		(width 0.1143)
		(layer "In9.Cu")
		(net "P5E_PEX3_STN1_TX_DP<18>")
	)
	(segment
		(start 375.431304 -114.497612)
		(end 370.440712 -130.948938)
		(width 0.1651)
		(layer "In9.Cu")
		(net "P5E_PEX3_STN1_TX_DP<18>")
	)
	(segment
		(start 378.255022 -107.680252)
		(end 375.431304 -114.497612)
		(width 0.1651)
		(layer "In9.Cu")
		(net "P5E_PEX3_STN1_TX_DP<18>")
	)
	(segment
		(start 373.732044 -159.462978)
		(end 374.315482 -162.39617)
		(width 0.1651)
		(layer "In9.Cu")
		(net "P5E_PEX3_STN1_TX_DP<18>")
	)
	(segment
		(start 374.591072 -355.658674)
		(end 374.591072 -355.026214)
		(width 0.13462)
		(layer "F.Cu")
		(net "P5E_PEX3_STN6_TX_DP<101>")
	)
	(segment
		(start 374.591072 -355.026214)
		(end 374.29694 -354.732082)
		(width 0.13462)
		(layer "F.Cu")
		(net "P5E_PEX3_STN6_TX_DP<101>")
	)
	(segment
		(start 374.27154 -355.978206)
		(end 374.591072 -355.658674)
		(width 0.13462)
		(layer "F.Cu")
		(net "P5E_PEX3_STN6_TX_DP<101>")
	)
	(segment
		(start 400.683984 -319.960752)
		(end 400.729704 -319.915032)
		(width 0.1143)
		(layer "In7.Cu")
		(net "P5E_PEX3_STN6_TX_DP<101>")
	)
	(segment
		(start 400.95551 -311.479692)
		(end 401.185634 -311.479692)
		(width 0.1143)
		(layer "In7.Cu")
		(net "P5E_PEX3_STN6_TX_DP<101>")
	)
	(segment
		(start 374.58777 -353.814126)
		(end 376.14225 -352.259646)
		(width 0.1651)
		(layer "In7.Cu")
		(net "P5E_PEX3_STN6_TX_DP<101>")
	)
	(segment
		(start 376.14225 -341.59444)
		(end 399.052542 -322.576698)
		(width 0.1651)
		(layer "In7.Cu")
		(net "P5E_PEX3_STN6_TX_DP<101>")
	)
	(segment
		(start 376.14225 -352.259646)
		(end 376.14225 -341.59444)
		(width 0.1651)
		(layer "In7.Cu")
		(net "P5E_PEX3_STN6_TX_DP<101>")
	)
	(segment
		(start 400.729704 -311.705498)
		(end 400.95551 -311.479692)
		(width 0.1143)
		(layer "In7.Cu")
		(net "P5E_PEX3_STN6_TX_DP<101>")
	)
	(segment
		(start 400.729704 -319.915032)
		(end 400.729704 -311.705498)
		(width 0.1143)
		(layer "In7.Cu")
		(net "P5E_PEX3_STN6_TX_DP<101>")
	)
	(segment
		(start 401.299934 -311.365392)
		(end 401.299934 -311.099962)
		(width 0.1143)
		(layer "In7.Cu")
		(net "P5E_PEX3_STN6_TX_DP<101>")
	)
	(segment
		(start 374.29694 -354.732082)
		(end 374.58777 -354.441252)
		(width 0.1651)
		(layer "In7.Cu")
		(net "P5E_PEX3_STN6_TX_DP<101>")
	)
	(segment
		(start 400.683984 -320.54292)
		(end 400.683984 -319.9892)
		(width 0.1651)
		(layer "In7.Cu")
		(net "P5E_PEX3_STN6_TX_DP<101>")
	)
	(segment
		(start 400.683984 -319.9892)
		(end 400.683984 -319.960752)
		(width 0.1143)
		(layer "In7.Cu")
		(net "P5E_PEX3_STN6_TX_DP<101>")
	)
	(segment
		(start 374.58777 -354.441252)
		(end 374.58777 -353.814126)
		(width 0.1651)
		(layer "In7.Cu")
		(net "P5E_PEX3_STN6_TX_DP<101>")
	)
	(segment
		(start 401.185634 -311.479692)
		(end 401.299934 -311.365392)
		(width 0.1143)
		(layer "In7.Cu")
		(net "P5E_PEX3_STN6_TX_DP<101>")
	)
	(segment
		(start 400.39925 -321.22999)
		(end 400.683984 -320.54292)
		(width 0.1651)
		(layer "In7.Cu")
		(net "P5E_PEX3_STN6_TX_DP<101>")
	)
	(segment
		(start 399.052542 -322.576698)
		(end 400.39925 -321.22999)
		(width 0.1651)
		(layer "In7.Cu")
		(net "P5E_PEX3_STN6_TX_DP<101>")
	)
	(segment
		(start 180.839872 -345.465146)
		(end 181.134512 -345.170506)
		(width 0.13462)
		(layer "F.Cu")
		(net "P5E_PEX1_STN7_TX_C_DN<121>")
	)
	(segment
		(start 181.134512 -344.539062)
		(end 180.814472 -344.219022)
		(width 0.13462)
		(layer "F.Cu")
		(net "P5E_PEX1_STN7_TX_C_DN<121>")
	)
	(segment
		(start 181.134512 -345.170506)
		(end 181.134512 -344.539062)
		(width 0.13462)
		(layer "F.Cu")
		(net "P5E_PEX1_STN7_TX_C_DN<121>")
	)
	(segment
		(start 176.676812 -361.244134)
		(end 176.551082 -361.244134)
		(width 0.1651)
		(layer "In11.Cu")
		(net "P5E_PEX1_STN7_TX_C_DN<121>")
	)
	(segment
		(start 177.853086 -359.94213)
		(end 177.853086 -360.06786)
		(width 0.1651)
		(layer "In11.Cu")
		(net "P5E_PEX1_STN7_TX_C_DN<121>")
	)
	(segment
		(start 164.638736 -366.8522)
		(end 162.916616 -368.57432)
		(width 0.1651)
		(layer "In11.Cu")
		(net "P5E_PEX1_STN7_TX_C_DN<121>")
	)
	(segment
		(start 162.236912 -375.999248)
		(end 162.109912 -375.872248)
		(width 0.1651)
		(layer "In11.Cu")
		(net "P5E_PEX1_STN7_TX_C_DN<121>")
	)
	(segment
		(start 181.130702 -345.755976)
		(end 181.130702 -346.308934)
		(width 0.1651)
		(layer "In11.Cu")
		(net "P5E_PEX1_STN7_TX_C_DN<121>")
	)
	(segment
		(start 162.109912 -375.872248)
		(end 162.109912 -375.490232)
		(width 0.1651)
		(layer "In11.Cu")
		(net "P5E_PEX1_STN7_TX_C_DN<121>")
	)
	(segment
		(start 177.503074 -360.417872)
		(end 177.377344 -360.417872)
		(width 0.1651)
		(layer "In11.Cu")
		(net "P5E_PEX1_STN7_TX_C_DN<121>")
	)
	(segment
		(start 178.679348 -359.241598)
		(end 178.329336 -359.59161)
		(width 0.1651)
		(layer "In11.Cu")
		(net "P5E_PEX1_STN7_TX_C_DN<121>")
	)
	(segment
		(start 176.200562 -361.720384)
		(end 175.720756 -362.20019)
		(width 0.1651)
		(layer "In11.Cu")
		(net "P5E_PEX1_STN7_TX_C_DN<121>")
	)
	(segment
		(start 177.377344 -360.417872)
		(end 177.026824 -360.768392)
		(width 0.1651)
		(layer "In11.Cu")
		(net "P5E_PEX1_STN7_TX_C_DN<121>")
	)
	(segment
		(start 177.026824 -360.768392)
		(end 177.026824 -360.894122)
		(width 0.1651)
		(layer "In11.Cu")
		(net "P5E_PEX1_STN7_TX_C_DN<121>")
	)
	(segment
		(start 162.916616 -368.57432)
		(end 162.916616 -375.541032)
		(width 0.1651)
		(layer "In11.Cu")
		(net "P5E_PEX1_STN7_TX_C_DN<121>")
	)
	(segment
		(start 179.576222 -347.863414)
		(end 179.576222 -358.344724)
		(width 0.1651)
		(layer "In11.Cu")
		(net "P5E_PEX1_STN7_TX_C_DN<121>")
	)
	(segment
		(start 179.155598 -358.765348)
		(end 179.029868 -358.765348)
		(width 0.1651)
		(layer "In11.Cu")
		(net "P5E_PEX1_STN7_TX_C_DN<121>")
	)
	(segment
		(start 180.839872 -345.465146)
		(end 181.130702 -345.755976)
		(width 0.1651)
		(layer "In11.Cu")
		(net "P5E_PEX1_STN7_TX_C_DN<121>")
	)
	(segment
		(start 175.720756 -362.20019)
		(end 175.264064 -362.391706)
		(width 0.1651)
		(layer "In11.Cu")
		(net "P5E_PEX1_STN7_TX_C_DN<121>")
	)
	(segment
		(start 162.4584 -375.999248)
		(end 162.236912 -375.999248)
		(width 0.1651)
		(layer "In11.Cu")
		(net "P5E_PEX1_STN7_TX_C_DN<121>")
	)
	(segment
		(start 178.679348 -359.115868)
		(end 178.679348 -359.241598)
		(width 0.1651)
		(layer "In11.Cu")
		(net "P5E_PEX1_STN7_TX_C_DN<121>")
	)
	(segment
		(start 177.026824 -360.894122)
		(end 176.676812 -361.244134)
		(width 0.1651)
		(layer "In11.Cu")
		(net "P5E_PEX1_STN7_TX_C_DN<121>")
	)
	(segment
		(start 176.551082 -361.244134)
		(end 176.200562 -361.594654)
		(width 0.1651)
		(layer "In11.Cu")
		(net "P5E_PEX1_STN7_TX_C_DN<121>")
	)
	(segment
		(start 175.264064 -362.391706)
		(end 175.164496 -362.351066)
		(width 0.1651)
		(layer "In11.Cu")
		(net "P5E_PEX1_STN7_TX_C_DN<121>")
	)
	(segment
		(start 177.853086 -360.06786)
		(end 177.503074 -360.417872)
		(width 0.1651)
		(layer "In11.Cu")
		(net "P5E_PEX1_STN7_TX_C_DN<121>")
	)
	(segment
		(start 181.130702 -346.308934)
		(end 179.576222 -347.863414)
		(width 0.1651)
		(layer "In11.Cu")
		(net "P5E_PEX1_STN7_TX_C_DN<121>")
	)
	(segment
		(start 175.164496 -362.351066)
		(end 174.70755 -362.54309)
		(width 0.1651)
		(layer "In11.Cu")
		(net "P5E_PEX1_STN7_TX_C_DN<121>")
	)
	(segment
		(start 179.576222 -358.344724)
		(end 179.155598 -358.765348)
		(width 0.1651)
		(layer "In11.Cu")
		(net "P5E_PEX1_STN7_TX_C_DN<121>")
	)
	(segment
		(start 174.666656 -362.642658)
		(end 164.638736 -366.8522)
		(width 0.1651)
		(layer "In11.Cu")
		(net "P5E_PEX1_STN7_TX_C_DN<121>")
	)
	(segment
		(start 162.916616 -375.541032)
		(end 162.4584 -375.999248)
		(width 0.1651)
		(layer "In11.Cu")
		(net "P5E_PEX1_STN7_TX_C_DN<121>")
	)
	(segment
		(start 178.329336 -359.59161)
		(end 178.203606 -359.59161)
		(width 0.1651)
		(layer "In11.Cu")
		(net "P5E_PEX1_STN7_TX_C_DN<121>")
	)
	(segment
		(start 178.203606 -359.59161)
		(end 177.853086 -359.94213)
		(width 0.1651)
		(layer "In11.Cu")
		(net "P5E_PEX1_STN7_TX_C_DN<121>")
	)
	(segment
		(start 176.200562 -361.594654)
		(end 176.200562 -361.720384)
		(width 0.1651)
		(layer "In11.Cu")
		(net "P5E_PEX1_STN7_TX_C_DN<121>")
	)
	(segment
		(start 174.70755 -362.54309)
		(end 174.666656 -362.642658)
		(width 0.1651)
		(layer "In11.Cu")
		(net "P5E_PEX1_STN7_TX_C_DN<121>")
	)
	(segment
		(start 179.029868 -358.765348)
		(end 178.679348 -359.115868)
		(width 0.1651)
		(layer "In11.Cu")
		(net "P5E_PEX1_STN7_TX_C_DN<121>")
	)
	(segment
		(start 77.806042 -355.978206)
		(end 77.486002 -355.658166)
		(width 0.13462)
		(layer "F.Cu")
		(net "P5E_PEX0_STN5_TX_DN<88>")
	)
	(segment
		(start 77.486002 -355.658166)
		(end 77.486002 -355.026722)
		(width 0.13462)
		(layer "F.Cu")
		(net "P5E_PEX0_STN5_TX_DN<88>")
	)
	(segment
		(start 77.486002 -355.026722)
		(end 77.780642 -354.732082)
		(width 0.13462)
		(layer "F.Cu")
		(net "P5E_PEX0_STN5_TX_DN<88>")
	)
	(segment
		(start 77.489812 -353.942142)
		(end 79.044292 -352.387662)
		(width 0.1651)
		(layer "In7.Cu")
		(net "P5E_PEX0_STN5_TX_DN<88>")
	)
	(segment
		(start 77.489812 -354.441252)
		(end 77.489812 -353.942142)
		(width 0.1651)
		(layer "In7.Cu")
		(net "P5E_PEX0_STN5_TX_DN<88>")
	)
	(segment
		(start 65.965832 -319.8876)
		(end 65.920112 -319.84188)
		(width 0.1143)
		(layer "In7.Cu")
		(net "P5E_PEX0_STN5_TX_DN<88>")
	)
	(segment
		(start 66.034412 -311.670192)
		(end 66.185542 -311.670192)
		(width 0.1143)
		(layer "In7.Cu")
		(net "P5E_PEX0_STN5_TX_DN<88>")
	)
	(segment
		(start 65.965832 -322.047616)
		(end 65.965832 -319.916048)
		(width 0.1651)
		(layer "In7.Cu")
		(net "P5E_PEX0_STN5_TX_DN<88>")
	)
	(segment
		(start 79.044292 -341.003128)
		(end 77.535786 -337.362292)
		(width 0.1651)
		(layer "In7.Cu")
		(net "P5E_PEX0_STN5_TX_DN<88>")
	)
	(segment
		(start 65.920112 -319.84188)
		(end 65.920112 -311.784492)
		(width 0.1143)
		(layer "In7.Cu")
		(net "P5E_PEX0_STN5_TX_DN<88>")
	)
	(segment
		(start 65.920112 -311.784492)
		(end 66.034412 -311.670192)
		(width 0.1143)
		(layer "In7.Cu")
		(net "P5E_PEX0_STN5_TX_DN<88>")
	)
	(segment
		(start 66.299842 -311.784492)
		(end 66.299842 -312.049922)
		(width 0.1143)
		(layer "In7.Cu")
		(net "P5E_PEX0_STN5_TX_DN<88>")
	)
	(segment
		(start 67.897502 -325.618094)
		(end 66.431414 -323.172074)
		(width 0.1651)
		(layer "In7.Cu")
		(net "P5E_PEX0_STN5_TX_DN<88>")
	)
	(segment
		(start 66.431414 -323.172074)
		(end 65.965832 -322.047616)
		(width 0.1651)
		(layer "In7.Cu")
		(net "P5E_PEX0_STN5_TX_DN<88>")
	)
	(segment
		(start 77.535786 -337.362292)
		(end 67.897502 -325.618094)
		(width 0.1651)
		(layer "In7.Cu")
		(net "P5E_PEX0_STN5_TX_DN<88>")
	)
	(segment
		(start 65.965832 -319.916048)
		(end 65.965832 -319.8876)
		(width 0.1143)
		(layer "In7.Cu")
		(net "P5E_PEX0_STN5_TX_DN<88>")
	)
	(segment
		(start 79.044292 -352.387662)
		(end 79.044292 -341.003128)
		(width 0.1651)
		(layer "In7.Cu")
		(net "P5E_PEX0_STN5_TX_DN<88>")
	)
	(segment
		(start 77.780642 -354.732082)
		(end 77.489812 -354.441252)
		(width 0.1651)
		(layer "In7.Cu")
		(net "P5E_PEX0_STN5_TX_DN<88>")
	)
	(segment
		(start 66.185542 -311.670192)
		(end 66.299842 -311.784492)
		(width 0.1143)
		(layer "In7.Cu")
		(net "P5E_PEX0_STN5_TX_DN<88>")
	)
	(segment
		(start 133.919468 -343.365582)
		(end 133.919468 -342.734138)
		(width 0.13462)
		(layer "F.Cu")
		(net "P5E_PEX1_STN5_TX_DP<82>")
	)
	(segment
		(start 133.599428 -343.685622)
		(end 133.919468 -343.365582)
		(width 0.13462)
		(layer "F.Cu")
		(net "P5E_PEX1_STN5_TX_DP<82>")
	)
	(segment
		(start 133.919468 -342.734138)
		(end 133.624828 -342.439498)
		(width 0.13462)
		(layer "F.Cu")
		(net "P5E_PEX1_STN5_TX_DP<82>")
	)
	(segment
		(start 133.915658 -341.122762)
		(end 134.725664 -340.312756)
		(width 0.1651)
		(layer "In7.Cu")
		(net "P5E_PEX1_STN5_TX_DP<82>")
	)
	(segment
		(start 136.093708 -339.49259)
		(end 152.852882 -334.408526)
		(width 0.1651)
		(layer "In7.Cu")
		(net "P5E_PEX1_STN5_TX_DP<82>")
	)
	(segment
		(start 176.083976 -323.13245)
		(end 176.083976 -320.016886)
		(width 0.1651)
		(layer "In7.Cu")
		(net "P5E_PEX1_STN5_TX_DP<82>")
	)
	(segment
		(start 133.915658 -342.148668)
		(end 133.915658 -341.122762)
		(width 0.1651)
		(layer "In7.Cu")
		(net "P5E_PEX1_STN5_TX_DP<82>")
	)
	(segment
		(start 176.699926 -311.365392)
		(end 176.699926 -311.099962)
		(width 0.1143)
		(layer "In7.Cu")
		(net "P5E_PEX1_STN5_TX_DP<82>")
	)
	(segment
		(start 134.725664 -340.312756)
		(end 136.093708 -339.49259)
		(width 0.1651)
		(layer "In7.Cu")
		(net "P5E_PEX1_STN5_TX_DP<82>")
	)
	(segment
		(start 176.585626 -311.479692)
		(end 176.699926 -311.365392)
		(width 0.1143)
		(layer "In7.Cu")
		(net "P5E_PEX1_STN5_TX_DP<82>")
	)
	(segment
		(start 176.129696 -311.705498)
		(end 176.355502 -311.479692)
		(width 0.1143)
		(layer "In7.Cu")
		(net "P5E_PEX1_STN5_TX_DP<82>")
	)
	(segment
		(start 169.545254 -329.34529)
		(end 173.163992 -327.176384)
		(width 0.1651)
		(layer "In7.Cu")
		(net "P5E_PEX1_STN5_TX_DP<82>")
	)
	(segment
		(start 152.852882 -334.40878)
		(end 169.545254 -329.34529)
		(width 0.1651)
		(layer "In7.Cu")
		(net "P5E_PEX1_STN5_TX_DP<82>")
	)
	(segment
		(start 173.163992 -327.176384)
		(end 175.28921 -325.051166)
		(width 0.1651)
		(layer "In7.Cu")
		(net "P5E_PEX1_STN5_TX_DP<82>")
	)
	(segment
		(start 176.083976 -320.016886)
		(end 176.083976 -319.988438)
		(width 0.1143)
		(layer "In7.Cu")
		(net "P5E_PEX1_STN5_TX_DP<82>")
	)
	(segment
		(start 133.624828 -342.439498)
		(end 133.915658 -342.148668)
		(width 0.1651)
		(layer "In7.Cu")
		(net "P5E_PEX1_STN5_TX_DP<82>")
	)
	(segment
		(start 176.355502 -311.479692)
		(end 176.585626 -311.479692)
		(width 0.1143)
		(layer "In7.Cu")
		(net "P5E_PEX1_STN5_TX_DP<82>")
	)
	(segment
		(start 152.852882 -334.408526)
		(end 152.852882 -334.40878)
		(width 0.1651)
		(layer "In7.Cu")
		(net "P5E_PEX1_STN5_TX_DP<82>")
	)
	(segment
		(start 176.129696 -319.942718)
		(end 176.129696 -311.705498)
		(width 0.1143)
		(layer "In7.Cu")
		(net "P5E_PEX1_STN5_TX_DP<82>")
	)
	(segment
		(start 175.28921 -325.051166)
		(end 176.083976 -323.13245)
		(width 0.1651)
		(layer "In7.Cu")
		(net "P5E_PEX1_STN5_TX_DP<82>")
	)
	(segment
		(start 176.083976 -319.988438)
		(end 176.129696 -319.942718)
		(width 0.1143)
		(layer "In7.Cu")
		(net "P5E_PEX1_STN5_TX_DP<82>")
	)
	(segment
		(start 270.259048 -124.92228)
		(end 270.897096 -124.92228)
		(width 0.13462)
		(layer "F.Cu")
		(net "P5E_PEX2_STN1_TX_DN<27>")
	)
	(segment
		(start 269.96771 -124.630942)
		(end 270.259048 -124.92228)
		(width 0.13462)
		(layer "F.Cu")
		(net "P5E_PEX2_STN1_TX_DN<27>")
	)
	(segment
		(start 270.897096 -124.92228)
		(end 271.213834 -124.605542)
		(width 0.13462)
		(layer "F.Cu")
		(net "P5E_PEX2_STN1_TX_DN<27>")
	)
	(segment
		(start 301.683928 -271.526)
		(end 301.683928 -263.64311)
		(width 0.1651)
		(layer "In9.Cu")
		(net "P5E_PEX2_STN1_TX_DN<27>")
	)
	(segment
		(start 302.185578 -280.319988)
		(end 301.944786 -280.319988)
		(width 0.1143)
		(layer "In9.Cu")
		(net "P5E_PEX2_STN1_TX_DN<27>")
	)
	(segment
		(start 302.299878 -280.434288)
		(end 302.185578 -280.319988)
		(width 0.1143)
		(layer "In9.Cu")
		(net "P5E_PEX2_STN1_TX_DN<27>")
	)
	(segment
		(start 301.729648 -271.600168)
		(end 301.683928 -271.554448)
		(width 0.1143)
		(layer "In9.Cu")
		(net "P5E_PEX2_STN1_TX_DN<27>")
	)
	(segment
		(start 301.683928 -263.64311)
		(end 267.217652 -161.825178)
		(width 0.1651)
		(layer "In9.Cu")
		(net "P5E_PEX2_STN1_TX_DN<27>")
	)
	(segment
		(start 263.881362 -132.062728)
		(end 267.969746 -125.944376)
		(width 0.1651)
		(layer "In9.Cu")
		(net "P5E_PEX2_STN1_TX_DN<27>")
	)
	(segment
		(start 301.944786 -280.319988)
		(end 301.729648 -280.10485)
		(width 0.1143)
		(layer "In9.Cu")
		(net "P5E_PEX2_STN1_TX_DN<27>")
	)
	(segment
		(start 302.299878 -280.699718)
		(end 302.299878 -280.434288)
		(width 0.1143)
		(layer "In9.Cu")
		(net "P5E_PEX2_STN1_TX_DN<27>")
	)
	(segment
		(start 301.683928 -271.554448)
		(end 301.683928 -271.526)
		(width 0.1143)
		(layer "In9.Cu")
		(net "P5E_PEX2_STN1_TX_DN<27>")
	)
	(segment
		(start 266.332716 -157.375606)
		(end 265.62812 -143.053816)
		(width 0.1651)
		(layer "In9.Cu")
		(net "P5E_PEX2_STN1_TX_DN<27>")
	)
	(segment
		(start 265.62812 -143.053816)
		(end 263.050274 -136.830562)
		(width 0.1651)
		(layer "In9.Cu")
		(net "P5E_PEX2_STN1_TX_DN<27>")
	)
	(segment
		(start 301.729648 -280.10485)
		(end 301.729648 -271.600168)
		(width 0.1143)
		(layer "In9.Cu")
		(net "P5E_PEX2_STN1_TX_DN<27>")
	)
	(segment
		(start 267.217652 -161.825178)
		(end 266.332716 -157.375606)
		(width 0.1651)
		(layer "In9.Cu")
		(net "P5E_PEX2_STN1_TX_DN<27>")
	)
	(segment
		(start 268.99235 -124.921772)
		(end 269.67688 -124.921772)
		(width 0.1651)
		(layer "In9.Cu")
		(net "P5E_PEX2_STN1_TX_DN<27>")
	)
	(segment
		(start 263.050274 -136.830562)
		(end 263.050274 -134.069582)
		(width 0.1651)
		(layer "In9.Cu")
		(net "P5E_PEX2_STN1_TX_DN<27>")
	)
	(segment
		(start 267.969746 -125.944376)
		(end 268.99235 -124.921772)
		(width 0.1651)
		(layer "In9.Cu")
		(net "P5E_PEX2_STN1_TX_DN<27>")
	)
	(segment
		(start 263.050274 -134.069582)
		(end 263.881362 -132.062728)
		(width 0.1651)
		(layer "In9.Cu")
		(net "P5E_PEX2_STN1_TX_DN<27>")
	)
	(segment
		(start 269.67688 -124.921772)
		(end 269.96771 -124.630942)
		(width 0.1651)
		(layer "In9.Cu")
		(net "P5E_PEX2_STN1_TX_DN<27>")
	)
	(segment
		(start 343.567004 -343.685622)
		(end 343.887044 -343.365582)
		(width 0.13462)
		(layer "F.Cu")
		(net "P5E_PEX2_STN6_TX_DP<97>")
	)
	(segment
		(start 343.887044 -343.365582)
		(end 343.887044 -342.734138)
		(width 0.13462)
		(layer "F.Cu")
		(net "P5E_PEX2_STN6_TX_DP<97>")
	)
	(segment
		(start 343.887044 -342.734138)
		(end 343.592404 -342.439498)
		(width 0.13462)
		(layer "F.Cu")
		(net "P5E_PEX2_STN6_TX_DP<97>")
	)
	(segment
		(start 336.047334 -335.396078)
		(end 315.051694 -325.924926)
		(width 0.1651)
		(layer "In13.Cu")
		(net "P5E_PEX2_STN6_TX_DP<97>")
	)
	(segment
		(start 315.051694 -325.924926)
		(end 291.254942 -321.261486)
		(width 0.1651)
		(layer "In13.Cu")
		(net "P5E_PEX2_STN6_TX_DP<97>")
	)
	(segment
		(start 289.073082 -320.962528)
		(end 288.76752 -320.81089)
		(width 0.1651)
		(layer "In13.Cu")
		(net "P5E_PEX2_STN6_TX_DP<97>")
	)
	(segment
		(start 288.429446 -319.921128)
		(end 288.429446 -311.695084)
		(width 0.1143)
		(layer "In13.Cu")
		(net "P5E_PEX2_STN6_TX_DP<97>")
	)
	(segment
		(start 288.383726 -320.426842)
		(end 288.383726 -319.995296)
		(width 0.1651)
		(layer "In13.Cu")
		(net "P5E_PEX2_STN6_TX_DP<97>")
	)
	(segment
		(start 343.592404 -342.439498)
		(end 343.883234 -342.148668)
		(width 0.1651)
		(layer "In13.Cu")
		(net "P5E_PEX2_STN6_TX_DP<97>")
	)
	(segment
		(start 288.76752 -320.81089)
		(end 288.383726 -320.426842)
		(width 0.1651)
		(layer "In13.Cu")
		(net "P5E_PEX2_STN6_TX_DP<97>")
	)
	(segment
		(start 288.429446 -311.695084)
		(end 288.644838 -311.479692)
		(width 0.1143)
		(layer "In13.Cu")
		(net "P5E_PEX2_STN6_TX_DP<97>")
	)
	(segment
		(start 288.99993 -311.365392)
		(end 288.99993 -311.099962)
		(width 0.1143)
		(layer "In13.Cu")
		(net "P5E_PEX2_STN6_TX_DP<97>")
	)
	(segment
		(start 288.88563 -311.479692)
		(end 288.99993 -311.365392)
		(width 0.1143)
		(layer "In13.Cu")
		(net "P5E_PEX2_STN6_TX_DP<97>")
	)
	(segment
		(start 288.383726 -319.966848)
		(end 288.429446 -319.921128)
		(width 0.1143)
		(layer "In13.Cu")
		(net "P5E_PEX2_STN6_TX_DP<97>")
	)
	(segment
		(start 291.254942 -321.261486)
		(end 289.073082 -320.962528)
		(width 0.1651)
		(layer "In13.Cu")
		(net "P5E_PEX2_STN6_TX_DP<97>")
	)
	(segment
		(start 343.606374 -341.317326)
		(end 343.60612 -341.317072)
		(width 0.1651)
		(layer "In13.Cu")
		(net "P5E_PEX2_STN6_TX_DP<97>")
	)
	(segment
		(start 288.644838 -311.479692)
		(end 288.88563 -311.479692)
		(width 0.1143)
		(layer "In13.Cu")
		(net "P5E_PEX2_STN6_TX_DP<97>")
	)
	(segment
		(start 343.60612 -341.317072)
		(end 336.047334 -335.396078)
		(width 0.1651)
		(layer "In13.Cu")
		(net "P5E_PEX2_STN6_TX_DP<97>")
	)
	(segment
		(start 343.883234 -342.148668)
		(end 343.883234 -341.720678)
		(width 0.1651)
		(layer "In13.Cu")
		(net "P5E_PEX2_STN6_TX_DP<97>")
	)
	(segment
		(start 343.883234 -341.720678)
		(end 343.606374 -341.317326)
		(width 0.1651)
		(layer "In13.Cu")
		(net "P5E_PEX2_STN6_TX_DP<97>")
	)
	(segment
		(start 288.383726 -319.995296)
		(end 288.383726 -319.966848)
		(width 0.1143)
		(layer "In13.Cu")
		(net "P5E_PEX2_STN6_TX_DP<97>")
	)
	(segment
		(start 386.997194 -124.92228)
		(end 387.313932 -124.605542)
		(width 0.13462)
		(layer "F.Cu")
		(net "P5E_PEX3_STN1_TX_DN<27>")
	)
	(segment
		(start 386.067808 -124.630942)
		(end 386.359146 -124.92228)
		(width 0.13462)
		(layer "F.Cu")
		(net "P5E_PEX3_STN1_TX_DN<27>")
	)
	(segment
		(start 386.359146 -124.92228)
		(end 386.997194 -124.92228)
		(width 0.13462)
		(layer "F.Cu")
		(net "P5E_PEX3_STN1_TX_DN<27>")
	)
	(segment
		(start 379.150372 -136.830562)
		(end 379.150372 -134.069582)
		(width 0.1651)
		(layer "In9.Cu")
		(net "P5E_PEX3_STN1_TX_DN<27>")
	)
	(segment
		(start 417.784026 -263.64311)
		(end 383.31775 -161.825178)
		(width 0.1651)
		(layer "In9.Cu")
		(net "P5E_PEX3_STN1_TX_DN<27>")
	)
	(segment
		(start 418.399976 -280.434288)
		(end 418.285676 -280.319988)
		(width 0.1143)
		(layer "In9.Cu")
		(net "P5E_PEX3_STN1_TX_DN<27>")
	)
	(segment
		(start 418.399976 -280.699718)
		(end 418.399976 -280.434288)
		(width 0.1143)
		(layer "In9.Cu")
		(net "P5E_PEX3_STN1_TX_DN<27>")
	)
	(segment
		(start 418.285676 -280.319988)
		(end 418.044884 -280.319988)
		(width 0.1143)
		(layer "In9.Cu")
		(net "P5E_PEX3_STN1_TX_DN<27>")
	)
	(segment
		(start 382.432814 -157.375606)
		(end 381.728218 -143.053816)
		(width 0.1651)
		(layer "In9.Cu")
		(net "P5E_PEX3_STN1_TX_DN<27>")
	)
	(segment
		(start 379.150372 -134.069582)
		(end 379.98146 -132.062728)
		(width 0.1651)
		(layer "In9.Cu")
		(net "P5E_PEX3_STN1_TX_DN<27>")
	)
	(segment
		(start 385.092448 -124.921772)
		(end 385.776978 -124.921772)
		(width 0.1651)
		(layer "In9.Cu")
		(net "P5E_PEX3_STN1_TX_DN<27>")
	)
	(segment
		(start 379.98146 -132.062728)
		(end 384.069844 -125.944376)
		(width 0.1651)
		(layer "In9.Cu")
		(net "P5E_PEX3_STN1_TX_DN<27>")
	)
	(segment
		(start 417.829746 -271.600168)
		(end 417.784026 -271.554448)
		(width 0.1143)
		(layer "In9.Cu")
		(net "P5E_PEX3_STN1_TX_DN<27>")
	)
	(segment
		(start 417.784026 -271.554448)
		(end 417.784026 -271.526)
		(width 0.1143)
		(layer "In9.Cu")
		(net "P5E_PEX3_STN1_TX_DN<27>")
	)
	(segment
		(start 383.31775 -161.825178)
		(end 382.432814 -157.375606)
		(width 0.1651)
		(layer "In9.Cu")
		(net "P5E_PEX3_STN1_TX_DN<27>")
	)
	(segment
		(start 381.728218 -143.053816)
		(end 379.150372 -136.830562)
		(width 0.1651)
		(layer "In9.Cu")
		(net "P5E_PEX3_STN1_TX_DN<27>")
	)
	(segment
		(start 384.069844 -125.944376)
		(end 385.092448 -124.921772)
		(width 0.1651)
		(layer "In9.Cu")
		(net "P5E_PEX3_STN1_TX_DN<27>")
	)
	(segment
		(start 418.044884 -280.319988)
		(end 417.829746 -280.10485)
		(width 0.1143)
		(layer "In9.Cu")
		(net "P5E_PEX3_STN1_TX_DN<27>")
	)
	(segment
		(start 385.776978 -124.921772)
		(end 386.067808 -124.630942)
		(width 0.1651)
		(layer "In9.Cu")
		(net "P5E_PEX3_STN1_TX_DN<27>")
	)
	(segment
		(start 417.784026 -271.526)
		(end 417.784026 -263.64311)
		(width 0.1651)
		(layer "In9.Cu")
		(net "P5E_PEX3_STN1_TX_DN<27>")
	)
	(segment
		(start 417.829746 -280.10485)
		(end 417.829746 -271.600168)
		(width 0.1143)
		(layer "In9.Cu")
		(net "P5E_PEX3_STN1_TX_DN<27>")
	)
	(segment
		(start 380.808992 -349.512382)
		(end 380.808992 -348.879922)
		(width 0.13462)
		(layer "F.Cu")
		(net "P5E_PEX3_STN6_TX_DP<107>")
	)
	(segment
		(start 380.48946 -349.831914)
		(end 380.808992 -349.512382)
		(width 0.13462)
		(layer "F.Cu")
		(net "P5E_PEX3_STN6_TX_DP<107>")
	)
	(segment
		(start 380.808992 -348.879922)
		(end 380.51486 -348.58579)
		(width 0.13462)
		(layer "F.Cu")
		(net "P5E_PEX3_STN6_TX_DP<107>")
	)
	(segment
		(start 390.022334 -330.17206)
		(end 393.451588 -324.664324)
		(width 0.1651)
		(layer "In13.Cu")
		(net "P5E_PEX3_STN6_TX_DP<107>")
	)
	(segment
		(start 395.244828 -311.479692)
		(end 395.48562 -311.479692)
		(width 0.1143)
		(layer "In13.Cu")
		(net "P5E_PEX3_STN6_TX_DP<107>")
	)
	(segment
		(start 394.98397 -320.046096)
		(end 394.98397 -320.017648)
		(width 0.1143)
		(layer "In13.Cu")
		(net "P5E_PEX3_STN6_TX_DP<107>")
	)
	(segment
		(start 394.98397 -321.609466)
		(end 394.98397 -320.046096)
		(width 0.1651)
		(layer "In13.Cu")
		(net "P5E_PEX3_STN6_TX_DP<107>")
	)
	(segment
		(start 386.592318 -335.68005)
		(end 390.02208 -330.17206)
		(width 0.1651)
		(layer "In13.Cu")
		(net "P5E_PEX3_STN6_TX_DP<107>")
	)
	(segment
		(start 382.36017 -346.113354)
		(end 382.36017 -342.12022)
		(width 0.1651)
		(layer "In13.Cu")
		(net "P5E_PEX3_STN6_TX_DP<107>")
	)
	(segment
		(start 382.618742 -341.101426)
		(end 386.592318 -335.68005)
		(width 0.1651)
		(layer "In13.Cu")
		(net "P5E_PEX3_STN6_TX_DP<107>")
	)
	(segment
		(start 395.02969 -311.69483)
		(end 395.244828 -311.479692)
		(width 0.1143)
		(layer "In13.Cu")
		(net "P5E_PEX3_STN6_TX_DP<107>")
	)
	(segment
		(start 395.48562 -311.479692)
		(end 395.59992 -311.365392)
		(width 0.1143)
		(layer "In13.Cu")
		(net "P5E_PEX3_STN6_TX_DP<107>")
	)
	(segment
		(start 394.98397 -320.017648)
		(end 395.02969 -319.971928)
		(width 0.1143)
		(layer "In13.Cu")
		(net "P5E_PEX3_STN6_TX_DP<107>")
	)
	(segment
		(start 390.02208 -330.17206)
		(end 390.022334 -330.17206)
		(width 0.1651)
		(layer "In13.Cu")
		(net "P5E_PEX3_STN6_TX_DP<107>")
	)
	(segment
		(start 395.02969 -319.971928)
		(end 395.02969 -311.69483)
		(width 0.1143)
		(layer "In13.Cu")
		(net "P5E_PEX3_STN6_TX_DP<107>")
	)
	(segment
		(start 380.80569 -347.667834)
		(end 382.36017 -346.113354)
		(width 0.1651)
		(layer "In13.Cu")
		(net "P5E_PEX3_STN6_TX_DP<107>")
	)
	(segment
		(start 382.36017 -342.12022)
		(end 382.618742 -341.101426)
		(width 0.1651)
		(layer "In13.Cu")
		(net "P5E_PEX3_STN6_TX_DP<107>")
	)
	(segment
		(start 395.59992 -311.365392)
		(end 395.59992 -311.099962)
		(width 0.1143)
		(layer "In13.Cu")
		(net "P5E_PEX3_STN6_TX_DP<107>")
	)
	(segment
		(start 394.741908 -322.193666)
		(end 394.98397 -321.609466)
		(width 0.1651)
		(layer "In13.Cu")
		(net "P5E_PEX3_STN6_TX_DP<107>")
	)
	(segment
		(start 380.51486 -348.58579)
		(end 380.80569 -348.29496)
		(width 0.1651)
		(layer "In13.Cu")
		(net "P5E_PEX3_STN6_TX_DP<107>")
	)
	(segment
		(start 380.80569 -348.29496)
		(end 380.80569 -347.667834)
		(width 0.1651)
		(layer "In13.Cu")
		(net "P5E_PEX3_STN6_TX_DP<107>")
	)
	(segment
		(start 393.451588 -324.664324)
		(end 394.741908 -322.193666)
		(width 0.1651)
		(layer "In13.Cu")
		(net "P5E_PEX3_STN6_TX_DP<107>")
	)
	(segment
		(start 71.305166 -29.114242)
		(end 71.019924 -28.829)
		(width 0.13462)
		(layer "F.Cu")
		(net "P5E_PEX0_STN2_TX_DP<36>")
	)
	(segment
		(start 70.369684 -28.829)
		(end 70.059042 -29.139642)
		(width 0.13462)
		(layer "F.Cu")
		(net "P5E_PEX0_STN2_TX_DP<36>")
	)
	(segment
		(start 71.019924 -28.829)
		(end 70.369684 -28.829)
		(width 0.13462)
		(layer "F.Cu")
		(net "P5E_PEX0_STN2_TX_DP<36>")
	)
	(segment
		(start 76.69657 -30.852872)
		(end 77.04709 -31.203392)
		(width 0.1651)
		(layer "In11.Cu")
		(net "P5E_PEX0_STN2_TX_DP<36>")
	)
	(segment
		(start 89.875868 -47.726854)
		(end 90.992198 -58.452766)
		(width 0.1651)
		(layer "In11.Cu")
		(net "P5E_PEX0_STN2_TX_DP<36>")
	)
	(segment
		(start 62.343284 -116.64442)
		(end 61.825378 -120.93321)
		(width 0.1651)
		(layer "In11.Cu")
		(net "P5E_PEX0_STN2_TX_DP<36>")
	)
	(segment
		(start 61.825378 -120.93321)
		(end 54.283864 -263.41705)
		(width 0.1651)
		(layer "In11.Cu")
		(net "P5E_PEX0_STN2_TX_DP<36>")
	)
	(segment
		(start 54.544722 -280.319988)
		(end 54.785514 -280.319988)
		(width 0.1143)
		(layer "In11.Cu")
		(net "P5E_PEX0_STN2_TX_DP<36>")
	)
	(segment
		(start 76.69657 -30.727142)
		(end 76.69657 -30.852872)
		(width 0.1651)
		(layer "In11.Cu")
		(net "P5E_PEX0_STN2_TX_DP<36>")
	)
	(segment
		(start 54.899814 -280.434288)
		(end 54.899814 -280.699718)
		(width 0.1143)
		(layer "In11.Cu")
		(net "P5E_PEX0_STN2_TX_DP<36>")
	)
	(segment
		(start 54.329584 -280.10485)
		(end 54.544722 -280.319988)
		(width 0.1143)
		(layer "In11.Cu")
		(net "P5E_PEX0_STN2_TX_DP<36>")
	)
	(segment
		(start 54.329584 -271.473168)
		(end 54.329584 -280.10485)
		(width 0.1143)
		(layer "In11.Cu")
		(net "P5E_PEX0_STN2_TX_DP<36>")
	)
	(segment
		(start 54.283864 -271.427448)
		(end 54.329584 -271.473168)
		(width 0.1143)
		(layer "In11.Cu")
		(net "P5E_PEX0_STN2_TX_DP<36>")
	)
	(segment
		(start 54.785514 -280.319988)
		(end 54.899814 -280.434288)
		(width 0.1143)
		(layer "In11.Cu")
		(net "P5E_PEX0_STN2_TX_DP<36>")
	)
	(segment
		(start 54.283864 -263.41705)
		(end 54.283864 -271.399)
		(width 0.1651)
		(layer "In11.Cu")
		(net "P5E_PEX0_STN2_TX_DP<36>")
	)
	(segment
		(start 76.220828 -30.37713)
		(end 76.346558 -30.37713)
		(width 0.1651)
		(layer "In11.Cu")
		(net "P5E_PEX0_STN2_TX_DP<36>")
	)
	(segment
		(start 71.305166 -29.114242)
		(end 71.595996 -28.823412)
		(width 0.1651)
		(layer "In11.Cu")
		(net "P5E_PEX0_STN2_TX_DP<36>")
	)
	(segment
		(start 90.992198 -60.556902)
		(end 90.362532 -62.898274)
		(width 0.1651)
		(layer "In11.Cu")
		(net "P5E_PEX0_STN2_TX_DP<36>")
	)
	(segment
		(start 83.020916 -39.897558)
		(end 89.875868 -47.726854)
		(width 0.1651)
		(layer "In11.Cu")
		(net "P5E_PEX0_STN2_TX_DP<36>")
	)
	(segment
		(start 75.870308 -29.90088)
		(end 75.870308 -30.02661)
		(width 0.1651)
		(layer "In11.Cu")
		(net "P5E_PEX0_STN2_TX_DP<36>")
	)
	(segment
		(start 75.415648 -29.445966)
		(end 75.870308 -29.90088)
		(width 0.1651)
		(layer "In11.Cu")
		(net "P5E_PEX0_STN2_TX_DP<36>")
	)
	(segment
		(start 67.15633 -93.902784)
		(end 63.974218 -108.054394)
		(width 0.1651)
		(layer "In11.Cu")
		(net "P5E_PEX0_STN2_TX_DP<36>")
	)
	(segment
		(start 77.04709 -31.203392)
		(end 77.17282 -31.203392)
		(width 0.1651)
		(layer "In11.Cu")
		(net "P5E_PEX0_STN2_TX_DP<36>")
	)
	(segment
		(start 90.362532 -62.898274)
		(end 89.391744 -64.855598)
		(width 0.1651)
		(layer "In11.Cu")
		(net "P5E_PEX0_STN2_TX_DP<36>")
	)
	(segment
		(start 75.870308 -30.02661)
		(end 76.220828 -30.37713)
		(width 0.1651)
		(layer "In11.Cu")
		(net "P5E_PEX0_STN2_TX_DP<36>")
	)
	(segment
		(start 76.346558 -30.37713)
		(end 76.69657 -30.727142)
		(width 0.1651)
		(layer "In11.Cu")
		(net "P5E_PEX0_STN2_TX_DP<36>")
	)
	(segment
		(start 54.283864 -271.399)
		(end 54.283864 -271.427448)
		(width 0.1143)
		(layer "In11.Cu")
		(net "P5E_PEX0_STN2_TX_DP<36>")
	)
	(segment
		(start 90.992198 -58.452766)
		(end 90.992198 -60.556902)
		(width 0.1651)
		(layer "In11.Cu")
		(net "P5E_PEX0_STN2_TX_DP<36>")
	)
	(segment
		(start 71.595996 -28.823412)
		(end 73.915524 -28.823412)
		(width 0.1651)
		(layer "In11.Cu")
		(net "P5E_PEX0_STN2_TX_DP<36>")
	)
	(segment
		(start 77.17282 -31.203392)
		(end 78.03261 -32.063182)
		(width 0.1651)
		(layer "In11.Cu")
		(net "P5E_PEX0_STN2_TX_DP<36>")
	)
	(segment
		(start 63.974218 -108.054394)
		(end 62.343284 -116.64442)
		(width 0.1651)
		(layer "In11.Cu")
		(net "P5E_PEX0_STN2_TX_DP<36>")
	)
	(segment
		(start 73.915524 -28.823412)
		(end 75.415648 -29.445966)
		(width 0.1651)
		(layer "In11.Cu")
		(net "P5E_PEX0_STN2_TX_DP<36>")
	)
	(segment
		(start 89.391744 -64.855598)
		(end 67.15633 -93.902784)
		(width 0.1651)
		(layer "In11.Cu")
		(net "P5E_PEX0_STN2_TX_DP<36>")
	)
	(segment
		(start 78.03261 -32.063182)
		(end 83.020916 -39.897558)
		(width 0.1651)
		(layer "In11.Cu")
		(net "P5E_PEX0_STN2_TX_DP<36>")
	)
	(segment
		(start 143.246348 -355.026722)
		(end 142.951708 -354.732082)
		(width 0.13462)
		(layer "F.Cu")
		(net "P5E_PEX1_STN5_TX_DP<95>")
	)
	(segment
		(start 142.926308 -355.978206)
		(end 143.246348 -355.658166)
		(width 0.13462)
		(layer "F.Cu")
		(net "P5E_PEX1_STN5_TX_DP<95>")
	)
	(segment
		(start 143.246348 -355.658166)
		(end 143.246348 -355.026722)
		(width 0.13462)
		(layer "F.Cu")
		(net "P5E_PEX1_STN5_TX_DP<95>")
	)
	(segment
		(start 143.242538 -354.441252)
		(end 143.242538 -353.699826)
		(width 0.1651)
		(layer "In13.Cu")
		(net "P5E_PEX1_STN5_TX_DP<95>")
	)
	(segment
		(start 188.479684 -313.59475)
		(end 188.694822 -313.379612)
		(width 0.1143)
		(layer "In13.Cu")
		(net "P5E_PEX1_STN5_TX_DP<95>")
	)
	(segment
		(start 188.433964 -320.041016)
		(end 188.479684 -319.995296)
		(width 0.1143)
		(layer "In13.Cu")
		(net "P5E_PEX1_STN5_TX_DP<95>")
	)
	(segment
		(start 182.207662 -328.250804)
		(end 186.188096 -325.591678)
		(width 0.1651)
		(layer "In13.Cu")
		(net "P5E_PEX1_STN5_TX_DP<95>")
	)
	(segment
		(start 188.433964 -322.613782)
		(end 188.433964 -320.063114)
		(width 0.1651)
		(layer "In13.Cu")
		(net "P5E_PEX1_STN5_TX_DP<95>")
	)
	(segment
		(start 189.049914 -313.265312)
		(end 189.049914 -312.999882)
		(width 0.1143)
		(layer "In13.Cu")
		(net "P5E_PEX1_STN5_TX_DP<95>")
	)
	(segment
		(start 143.242538 -353.699826)
		(end 146.045428 -350.896936)
		(width 0.1651)
		(layer "In13.Cu")
		(net "P5E_PEX1_STN5_TX_DP<95>")
	)
	(segment
		(start 142.951708 -354.732082)
		(end 143.242538 -354.441252)
		(width 0.1651)
		(layer "In13.Cu")
		(net "P5E_PEX1_STN5_TX_DP<95>")
	)
	(segment
		(start 188.935614 -313.379612)
		(end 189.049914 -313.265312)
		(width 0.1143)
		(layer "In13.Cu")
		(net "P5E_PEX1_STN5_TX_DP<95>")
	)
	(segment
		(start 187.916566 -323.863208)
		(end 188.433964 -322.613782)
		(width 0.1651)
		(layer "In13.Cu")
		(net "P5E_PEX1_STN5_TX_DP<95>")
	)
	(segment
		(start 178.690524 -330.130912)
		(end 182.207662 -328.250804)
		(width 0.1651)
		(layer "In13.Cu")
		(net "P5E_PEX1_STN5_TX_DP<95>")
	)
	(segment
		(start 186.188096 -325.591678)
		(end 187.916566 -323.863208)
		(width 0.1651)
		(layer "In13.Cu")
		(net "P5E_PEX1_STN5_TX_DP<95>")
	)
	(segment
		(start 146.045428 -350.896936)
		(end 178.690524 -330.130912)
		(width 0.1651)
		(layer "In13.Cu")
		(net "P5E_PEX1_STN5_TX_DP<95>")
	)
	(segment
		(start 188.433964 -320.063114)
		(end 188.433964 -320.041016)
		(width 0.1143)
		(layer "In13.Cu")
		(net "P5E_PEX1_STN5_TX_DP<95>")
	)
	(segment
		(start 188.479684 -319.995296)
		(end 188.479684 -313.59475)
		(width 0.1143)
		(layer "In13.Cu")
		(net "P5E_PEX1_STN5_TX_DP<95>")
	)
	(segment
		(start 188.694822 -313.379612)
		(end 188.935614 -313.379612)
		(width 0.1143)
		(layer "In13.Cu")
		(net "P5E_PEX1_STN5_TX_DP<95>")
	)
	(segment
		(start 270.890492 -106.81208)
		(end 271.213834 -106.488738)
		(width 0.13462)
		(layer "F.Cu")
		(net "P5E_PEX2_STN1_TX_DP<20>")
	)
	(segment
		(start 270.265652 -106.81208)
		(end 270.890492 -106.81208)
		(width 0.13462)
		(layer "F.Cu")
		(net "P5E_PEX2_STN1_TX_DP<20>")
	)
	(segment
		(start 269.96771 -106.514138)
		(end 270.265652 -106.81208)
		(width 0.13462)
		(layer "F.Cu")
		(net "P5E_PEX2_STN1_TX_DP<20>")
	)
	(segment
		(start 295.64965 -278.534368)
		(end 295.64965 -278.799798)
		(width 0.1143)
		(layer "In9.Cu")
		(net "P5E_PEX2_STN1_TX_DP<20>")
	)
	(segment
		(start 295.079674 -278.205184)
		(end 295.294558 -278.420068)
		(width 0.1143)
		(layer "In9.Cu")
		(net "P5E_PEX2_STN1_TX_DP<20>")
	)
	(segment
		(start 263.774174 -109.540548)
		(end 260.274816 -117.988842)
		(width 0.1651)
		(layer "In9.Cu")
		(net "P5E_PEX2_STN1_TX_DP<20>")
	)
	(segment
		(start 269.67688 -106.804968)
		(end 267.764514 -106.804968)
		(width 0.1651)
		(layer "In9.Cu")
		(net "P5E_PEX2_STN1_TX_DP<20>")
	)
	(segment
		(start 295.079674 -271.546066)
		(end 295.079674 -278.205184)
		(width 0.1143)
		(layer "In9.Cu")
		(net "P5E_PEX2_STN1_TX_DP<20>")
	)
	(segment
		(start 269.96771 -106.514138)
		(end 269.67688 -106.804968)
		(width 0.1651)
		(layer "In9.Cu")
		(net "P5E_PEX2_STN1_TX_DP<20>")
	)
	(segment
		(start 295.033954 -271.471898)
		(end 295.033954 -271.500346)
		(width 0.1143)
		(layer "In9.Cu")
		(net "P5E_PEX2_STN1_TX_DP<20>")
	)
	(segment
		(start 265.622532 -107.69219)
		(end 263.774174 -109.540548)
		(width 0.1651)
		(layer "In9.Cu")
		(net "P5E_PEX2_STN1_TX_DP<20>")
	)
	(segment
		(start 267.764514 -106.804968)
		(end 265.622532 -107.69219)
		(width 0.1651)
		(layer "In9.Cu")
		(net "P5E_PEX2_STN1_TX_DP<20>")
	)
	(segment
		(start 260.274816 -117.988842)
		(end 256.276094 -131.172458)
		(width 0.1651)
		(layer "In9.Cu")
		(net "P5E_PEX2_STN1_TX_DP<20>")
	)
	(segment
		(start 259.58292 -159.221678)
		(end 260.150864 -162.077146)
		(width 0.1651)
		(layer "In9.Cu")
		(net "P5E_PEX2_STN1_TX_DP<20>")
	)
	(segment
		(start 256.276094 -138.253978)
		(end 258.858512 -144.488662)
		(width 0.1651)
		(layer "In9.Cu")
		(net "P5E_PEX2_STN1_TX_DP<20>")
	)
	(segment
		(start 256.276094 -131.172458)
		(end 256.276094 -138.253978)
		(width 0.1651)
		(layer "In9.Cu")
		(net "P5E_PEX2_STN1_TX_DP<20>")
	)
	(segment
		(start 295.294558 -278.420068)
		(end 295.53535 -278.420068)
		(width 0.1143)
		(layer "In9.Cu")
		(net "P5E_PEX2_STN1_TX_DP<20>")
	)
	(segment
		(start 295.033954 -265.13282)
		(end 295.033954 -271.471898)
		(width 0.1651)
		(layer "In9.Cu")
		(net "P5E_PEX2_STN1_TX_DP<20>")
	)
	(segment
		(start 295.53535 -278.420068)
		(end 295.64965 -278.534368)
		(width 0.1143)
		(layer "In9.Cu")
		(net "P5E_PEX2_STN1_TX_DP<20>")
	)
	(segment
		(start 295.033954 -271.500346)
		(end 295.079674 -271.546066)
		(width 0.1143)
		(layer "In9.Cu")
		(net "P5E_PEX2_STN1_TX_DP<20>")
	)
	(segment
		(start 258.858512 -144.488662)
		(end 259.58292 -159.221678)
		(width 0.1651)
		(layer "In9.Cu")
		(net "P5E_PEX2_STN1_TX_DP<20>")
	)
	(segment
		(start 260.150864 -162.077146)
		(end 295.033954 -265.13282)
		(width 0.1651)
		(layer "In9.Cu")
		(net "P5E_PEX2_STN1_TX_DP<20>")
	)
	(segment
		(start 296.172382 -343.365582)
		(end 296.172382 -342.734138)
		(width 0.13462)
		(layer "F.Cu")
		(net "P5E_PEX2_STN7_TX_DP<125>")
	)
	(segment
		(start 295.852342 -343.685622)
		(end 296.172382 -343.365582)
		(width 0.13462)
		(layer "F.Cu")
		(net "P5E_PEX2_STN7_TX_DP<125>")
	)
	(segment
		(start 296.172382 -342.734138)
		(end 295.877742 -342.439498)
		(width 0.13462)
		(layer "F.Cu")
		(net "P5E_PEX2_STN7_TX_DP<125>")
	)
	(segment
		(start 273.035522 -322.633848)
		(end 272.757392 -322.355718)
		(width 0.1651)
		(layer "In7.Cu")
		(net "P5E_PEX2_STN7_TX_DP<125>")
	)
	(segment
		(start 272.233898 -321.091814)
		(end 272.233898 -319.916048)
		(width 0.1651)
		(layer "In7.Cu")
		(net "P5E_PEX2_STN7_TX_DP<125>")
	)
	(segment
		(start 296.168572 -341.600028)
		(end 295.772332 -341.08136)
		(width 0.1651)
		(layer "In7.Cu")
		(net "P5E_PEX2_STN7_TX_DP<125>")
	)
	(segment
		(start 272.233898 -319.8876)
		(end 272.279618 -319.84188)
		(width 0.1143)
		(layer "In7.Cu")
		(net "P5E_PEX2_STN7_TX_DP<125>")
	)
	(segment
		(start 295.3766 -340.5632)
		(end 273.035522 -322.633848)
		(width 0.1651)
		(layer "In7.Cu")
		(net "P5E_PEX2_STN7_TX_DP<125>")
	)
	(segment
		(start 272.279618 -319.84188)
		(end 272.279618 -313.605418)
		(width 0.1143)
		(layer "In7.Cu")
		(net "P5E_PEX2_STN7_TX_DP<125>")
	)
	(segment
		(start 295.772332 -341.08136)
		(end 295.772586 -341.08136)
		(width 0.1651)
		(layer "In7.Cu")
		(net "P5E_PEX2_STN7_TX_DP<125>")
	)
	(segment
		(start 272.757392 -322.355718)
		(end 272.233898 -321.091814)
		(width 0.1651)
		(layer "In7.Cu")
		(net "P5E_PEX2_STN7_TX_DP<125>")
	)
	(segment
		(start 296.168572 -342.148668)
		(end 296.168572 -341.600028)
		(width 0.1651)
		(layer "In7.Cu")
		(net "P5E_PEX2_STN7_TX_DP<125>")
	)
	(segment
		(start 295.877742 -342.439498)
		(end 296.168572 -342.148668)
		(width 0.1651)
		(layer "In7.Cu")
		(net "P5E_PEX2_STN7_TX_DP<125>")
	)
	(segment
		(start 295.772586 -341.08136)
		(end 295.3766 -340.5632)
		(width 0.1651)
		(layer "In7.Cu")
		(net "P5E_PEX2_STN7_TX_DP<125>")
	)
	(segment
		(start 272.279618 -313.605418)
		(end 272.505424 -313.379612)
		(width 0.1143)
		(layer "In7.Cu")
		(net "P5E_PEX2_STN7_TX_DP<125>")
	)
	(segment
		(start 272.735548 -313.379612)
		(end 272.849848 -313.265312)
		(width 0.1143)
		(layer "In7.Cu")
		(net "P5E_PEX2_STN7_TX_DP<125>")
	)
	(segment
		(start 272.233898 -319.916048)
		(end 272.233898 -319.8876)
		(width 0.1143)
		(layer "In7.Cu")
		(net "P5E_PEX2_STN7_TX_DP<125>")
	)
	(segment
		(start 272.849848 -313.265312)
		(end 272.849848 -312.999882)
		(width 0.1143)
		(layer "In7.Cu")
		(net "P5E_PEX2_STN7_TX_DP<125>")
	)
	(segment
		(start 272.505424 -313.379612)
		(end 272.735548 -313.379612)
		(width 0.1143)
		(layer "In7.Cu")
		(net "P5E_PEX2_STN7_TX_DP<125>")
	)
	(segment
		(start 384.33629 -130.9878)
		(end 384.671824 -131.323334)
		(width 0.13462)
		(layer "F.Cu")
		(net "P5E_PEX3_STN1_TX_DN<28>")
	)
	(segment
		(start 383.4257 -131.297934)
		(end 383.735834 -130.9878)
		(width 0.13462)
		(layer "F.Cu")
		(net "P5E_PEX3_STN1_TX_DN<28>")
	)
	(segment
		(start 383.735834 -130.9878)
		(end 384.33629 -130.9878)
		(width 0.13462)
		(layer "F.Cu")
		(net "P5E_PEX3_STN1_TX_DN<28>")
	)
	(segment
		(start 381.545084 -132.56387)
		(end 381.513588 -132.40512)
		(width 0.1651)
		(layer "In9.Cu")
		(net "P5E_PEX3_STN1_TX_DN<28>")
	)
	(segment
		(start 380.918974 -136.948418)
		(end 380.734316 -136.50214)
		(width 0.1651)
		(layer "In9.Cu")
		(net "P5E_PEX3_STN1_TX_DN<28>")
	)
	(segment
		(start 383.984246 -158.72333)
		(end 384.074162 -158.588964)
		(width 0.1651)
		(layer "In9.Cu")
		(net "P5E_PEX3_STN1_TX_DN<28>")
	)
	(segment
		(start 380.643892 -133.707124)
		(end 381.118364 -132.99694)
		(width 0.1651)
		(layer "In9.Cu")
		(net "P5E_PEX3_STN1_TX_DN<28>")
	)
	(segment
		(start 383.751328 -157.55239)
		(end 382.999742 -142.270734)
		(width 0.1651)
		(layer "In9.Cu")
		(net "P5E_PEX3_STN1_TX_DN<28>")
	)
	(segment
		(start 380.734316 -136.50214)
		(end 380.58471 -136.440418)
		(width 0.1651)
		(layer "In9.Cu")
		(net "P5E_PEX3_STN1_TX_DN<28>")
	)
	(segment
		(start 419.073584 -278.229568)
		(end 418.970206 -278.12619)
		(width 0.1143)
		(layer "In9.Cu")
		(net "P5E_PEX3_STN1_TX_DN<28>")
	)
	(segment
		(start 381.77089 -139.304014)
		(end 381.832866 -139.154662)
		(width 0.1651)
		(layer "In9.Cu")
		(net "P5E_PEX3_STN1_TX_DN<28>")
	)
	(segment
		(start 382.41224 -140.852906)
		(end 382.227836 -140.407136)
		(width 0.1651)
		(layer "In9.Cu")
		(net "P5E_PEX3_STN1_TX_DN<28>")
	)
	(segment
		(start 382.746504 -141.360906)
		(end 382.561846 -140.914882)
		(width 0.1651)
		(layer "In9.Cu")
		(net "P5E_PEX3_STN1_TX_DN<28>")
	)
	(segment
		(start 419.349682 -278.115268)
		(end 419.235382 -278.229568)
		(width 0.1143)
		(layer "In9.Cu")
		(net "P5E_PEX3_STN1_TX_DN<28>")
	)
	(segment
		(start 418.970206 -278.12619)
		(end 418.970206 -271.546066)
		(width 0.1143)
		(layer "In9.Cu")
		(net "P5E_PEX3_STN1_TX_DN<28>")
	)
	(segment
		(start 382.227836 -140.407136)
		(end 382.289558 -140.257784)
		(width 0.1651)
		(layer "In9.Cu")
		(net "P5E_PEX3_STN1_TX_DN<28>")
	)
	(segment
		(start 381.191262 -137.605262)
		(end 381.041656 -137.54354)
		(width 0.1651)
		(layer "In9.Cu")
		(net "P5E_PEX3_STN1_TX_DN<28>")
	)
	(segment
		(start 419.015926 -263.383776)
		(end 384.549396 -161.566352)
		(width 0.1651)
		(layer "In9.Cu")
		(net "P5E_PEX3_STN1_TX_DN<28>")
	)
	(segment
		(start 381.940054 -131.972558)
		(end 382.208532 -131.570984)
		(width 0.1651)
		(layer "In9.Cu")
		(net "P5E_PEX3_STN1_TX_DN<28>")
	)
	(segment
		(start 419.015926 -271.471898)
		(end 419.015926 -263.383776)
		(width 0.1651)
		(layer "In9.Cu")
		(net "P5E_PEX3_STN1_TX_DN<28>")
	)
	(segment
		(start 382.999742 -142.270734)
		(end 382.684782 -141.510258)
		(width 0.1651)
		(layer "In9.Cu")
		(net "P5E_PEX3_STN1_TX_DN<28>")
	)
	(segment
		(start 381.118364 -132.99694)
		(end 381.27686 -132.96519)
		(width 0.1651)
		(layer "In9.Cu")
		(net "P5E_PEX3_STN1_TX_DN<28>")
	)
	(segment
		(start 383.979928 -158.115508)
		(end 383.845308 -158.025592)
		(width 0.1651)
		(layer "In9.Cu")
		(net "P5E_PEX3_STN1_TX_DN<28>")
	)
	(segment
		(start 380.400052 -134.295642)
		(end 380.643892 -133.707124)
		(width 0.1651)
		(layer "In9.Cu")
		(net "P5E_PEX3_STN1_TX_DN<28>")
	)
	(segment
		(start 381.648208 -138.708384)
		(end 381.498602 -138.646662)
		(width 0.1651)
		(layer "In9.Cu")
		(net "P5E_PEX3_STN1_TX_DN<28>")
	)
	(segment
		(start 382.385062 -131.101084)
		(end 382.56083 -131.007104)
		(width 0.1651)
		(layer "In9.Cu")
		(net "P5E_PEX3_STN1_TX_DN<28>")
	)
	(segment
		(start 419.235382 -278.229568)
		(end 419.073584 -278.229568)
		(width 0.1143)
		(layer "In9.Cu")
		(net "P5E_PEX3_STN1_TX_DN<28>")
	)
	(segment
		(start 382.1049 -139.811506)
		(end 381.955548 -139.749784)
		(width 0.1651)
		(layer "In9.Cu")
		(net "P5E_PEX3_STN1_TX_DN<28>")
	)
	(segment
		(start 381.955548 -139.749784)
		(end 381.77089 -139.304014)
		(width 0.1651)
		(layer "In9.Cu")
		(net "P5E_PEX3_STN1_TX_DN<28>")
	)
	(segment
		(start 383.845308 -158.025592)
		(end 383.845562 -158.025592)
		(width 0.1651)
		(layer "In9.Cu")
		(net "P5E_PEX3_STN1_TX_DN<28>")
	)
	(segment
		(start 380.856998 -137.09777)
		(end 380.918974 -136.948418)
		(width 0.1651)
		(layer "In9.Cu")
		(net "P5E_PEX3_STN1_TX_DN<28>")
	)
	(segment
		(start 381.041656 -137.54354)
		(end 380.856998 -137.09777)
		(width 0.1651)
		(layer "In9.Cu")
		(net "P5E_PEX3_STN1_TX_DN<28>")
	)
	(segment
		(start 419.349682 -277.849838)
		(end 419.349682 -278.115268)
		(width 0.1143)
		(layer "In9.Cu")
		(net "P5E_PEX3_STN1_TX_DN<28>")
	)
	(segment
		(start 384.549396 -161.566352)
		(end 384.266694 -160.144714)
		(width 0.1651)
		(layer "In9.Cu")
		(net "P5E_PEX3_STN1_TX_DN<28>")
	)
	(segment
		(start 382.208532 -131.570984)
		(end 382.177036 -131.412488)
		(width 0.1651)
		(layer "In9.Cu")
		(net "P5E_PEX3_STN1_TX_DN<28>")
	)
	(segment
		(start 381.27686 -132.96519)
		(end 381.545084 -132.56387)
		(width 0.1651)
		(layer "In9.Cu")
		(net "P5E_PEX3_STN1_TX_DN<28>")
	)
	(segment
		(start 380.400052 -135.994648)
		(end 380.400052 -134.295642)
		(width 0.1651)
		(layer "In9.Cu")
		(net "P5E_PEX3_STN1_TX_DN<28>")
	)
	(segment
		(start 381.832866 -139.154662)
		(end 381.648208 -138.708384)
		(width 0.1651)
		(layer "In9.Cu")
		(net "P5E_PEX3_STN1_TX_DN<28>")
	)
	(segment
		(start 382.684782 -141.510258)
		(end 382.746504 -141.360906)
		(width 0.1651)
		(layer "In9.Cu")
		(net "P5E_PEX3_STN1_TX_DN<28>")
	)
	(segment
		(start 381.781558 -132.004054)
		(end 381.940054 -131.972558)
		(width 0.1651)
		(layer "In9.Cu")
		(net "P5E_PEX3_STN1_TX_DN<28>")
	)
	(segment
		(start 382.56083 -131.007104)
		(end 383.13487 -131.007104)
		(width 0.1651)
		(layer "In9.Cu")
		(net "P5E_PEX3_STN1_TX_DN<28>")
	)
	(segment
		(start 383.845562 -158.025592)
		(end 383.751328 -157.55239)
		(width 0.1651)
		(layer "In9.Cu")
		(net "P5E_PEX3_STN1_TX_DN<28>")
	)
	(segment
		(start 384.074162 -158.588964)
		(end 383.979928 -158.115508)
		(width 0.1651)
		(layer "In9.Cu")
		(net "P5E_PEX3_STN1_TX_DN<28>")
	)
	(segment
		(start 382.561846 -140.914882)
		(end 382.41224 -140.852906)
		(width 0.1651)
		(layer "In9.Cu")
		(net "P5E_PEX3_STN1_TX_DN<28>")
	)
	(segment
		(start 381.513588 -132.40512)
		(end 381.781558 -132.004054)
		(width 0.1651)
		(layer "In9.Cu")
		(net "P5E_PEX3_STN1_TX_DN<28>")
	)
	(segment
		(start 384.266694 -160.144714)
		(end 383.984246 -158.72333)
		(width 0.1651)
		(layer "In9.Cu")
		(net "P5E_PEX3_STN1_TX_DN<28>")
	)
	(segment
		(start 381.313944 -138.200892)
		(end 381.37592 -138.05154)
		(width 0.1651)
		(layer "In9.Cu")
		(net "P5E_PEX3_STN1_TX_DN<28>")
	)
	(segment
		(start 383.13487 -131.007104)
		(end 383.4257 -131.297934)
		(width 0.1651)
		(layer "In9.Cu")
		(net "P5E_PEX3_STN1_TX_DN<28>")
	)
	(segment
		(start 381.37592 -138.05154)
		(end 381.191262 -137.605262)
		(width 0.1651)
		(layer "In9.Cu")
		(net "P5E_PEX3_STN1_TX_DN<28>")
	)
	(segment
		(start 381.498602 -138.646662)
		(end 381.313944 -138.200892)
		(width 0.1651)
		(layer "In9.Cu")
		(net "P5E_PEX3_STN1_TX_DN<28>")
	)
	(segment
		(start 382.289558 -140.257784)
		(end 382.1049 -139.811506)
		(width 0.1651)
		(layer "In9.Cu")
		(net "P5E_PEX3_STN1_TX_DN<28>")
	)
	(segment
		(start 419.015926 -271.500346)
		(end 419.015926 -271.471898)
		(width 0.1143)
		(layer "In9.Cu")
		(net "P5E_PEX3_STN1_TX_DN<28>")
	)
	(segment
		(start 380.58471 -136.440418)
		(end 380.400052 -135.994648)
		(width 0.1651)
		(layer "In9.Cu")
		(net "P5E_PEX3_STN1_TX_DN<28>")
	)
	(segment
		(start 418.970206 -271.546066)
		(end 419.015926 -271.500346)
		(width 0.1143)
		(layer "In9.Cu")
		(net "P5E_PEX3_STN1_TX_DN<28>")
	)
	(segment
		(start 382.177036 -131.412488)
		(end 382.385062 -131.101084)
		(width 0.1651)
		(layer "In9.Cu")
		(net "P5E_PEX3_STN1_TX_DN<28>")
	)
	(segment
		(start 371.482112 -342.73363)
		(end 371.18798 -342.439498)
		(width 0.13462)
		(layer "F.Cu")
		(net "P5E_PEX3_STN6_TX_DP<111>")
	)
	(segment
		(start 371.16258 -343.685622)
		(end 371.482112 -343.36609)
		(width 0.13462)
		(layer "F.Cu")
		(net "P5E_PEX3_STN6_TX_DP<111>")
	)
	(segment
		(start 371.482112 -343.36609)
		(end 371.482112 -342.73363)
		(width 0.13462)
		(layer "F.Cu")
		(net "P5E_PEX3_STN6_TX_DP<111>")
	)
	(segment
		(start 391.071608 -320.698368)
		(end 391.183876 -320.427858)
		(width 0.1651)
		(layer "In13.Cu")
		(net "P5E_PEX3_STN6_TX_DP<111>")
	)
	(segment
		(start 371.47881 -342.148668)
		(end 371.47881 -341.123778)
		(width 0.1651)
		(layer "In13.Cu")
		(net "P5E_PEX3_STN6_TX_DP<111>")
	)
	(segment
		(start 391.183876 -320.427858)
		(end 391.183876 -319.94602)
		(width 0.1651)
		(layer "In13.Cu")
		(net "P5E_PEX3_STN6_TX_DP<111>")
	)
	(segment
		(start 391.444734 -311.479692)
		(end 391.685526 -311.479692)
		(width 0.1143)
		(layer "In13.Cu")
		(net "P5E_PEX3_STN6_TX_DP<111>")
	)
	(segment
		(start 391.183876 -319.923922)
		(end 391.229596 -319.878202)
		(width 0.1143)
		(layer "In13.Cu")
		(net "P5E_PEX3_STN6_TX_DP<111>")
	)
	(segment
		(start 390.496806 -321.57162)
		(end 391.071608 -320.698368)
		(width 0.1651)
		(layer "In13.Cu")
		(net "P5E_PEX3_STN6_TX_DP<111>")
	)
	(segment
		(start 391.229596 -319.878202)
		(end 391.229596 -311.69483)
		(width 0.1143)
		(layer "In13.Cu")
		(net "P5E_PEX3_STN6_TX_DP<111>")
	)
	(segment
		(start 371.47881 -341.123778)
		(end 390.496806 -321.57162)
		(width 0.1651)
		(layer "In13.Cu")
		(net "P5E_PEX3_STN6_TX_DP<111>")
	)
	(segment
		(start 391.183876 -319.94602)
		(end 391.183876 -319.923922)
		(width 0.1143)
		(layer "In13.Cu")
		(net "P5E_PEX3_STN6_TX_DP<111>")
	)
	(segment
		(start 391.799826 -311.365392)
		(end 391.799826 -311.099962)
		(width 0.1143)
		(layer "In13.Cu")
		(net "P5E_PEX3_STN6_TX_DP<111>")
	)
	(segment
		(start 391.229596 -311.69483)
		(end 391.444734 -311.479692)
		(width 0.1143)
		(layer "In13.Cu")
		(net "P5E_PEX3_STN6_TX_DP<111>")
	)
	(segment
		(start 371.18798 -342.439498)
		(end 371.47881 -342.148668)
		(width 0.1651)
		(layer "In13.Cu")
		(net "P5E_PEX3_STN6_TX_DP<111>")
	)
	(segment
		(start 391.685526 -311.479692)
		(end 391.799826 -311.365392)
		(width 0.1143)
		(layer "In13.Cu")
		(net "P5E_PEX3_STN6_TX_DP<111>")
	)
	(segment
		(start 133.919468 -350.685354)
		(end 133.599428 -350.365314)
		(width 0.13462)
		(layer "F.Cu")
		(net "P5E_PEX1_STN5_TX_C_DP<90>")
	)
	(segment
		(start 133.624828 -351.611438)
		(end 133.919468 -351.316798)
		(width 0.13462)
		(layer "F.Cu")
		(net "P5E_PEX1_STN5_TX_C_DP<90>")
	)
	(segment
		(start 133.919468 -351.316798)
		(end 133.919468 -350.685354)
		(width 0.13462)
		(layer "F.Cu")
		(net "P5E_PEX1_STN5_TX_C_DP<90>")
	)
	(segment
		(start 132.361178 -358.260904)
		(end 131.75107 -359.558844)
		(width 0.1651)
		(layer "In13.Cu")
		(net "P5E_PEX1_STN5_TX_C_DP<90>")
	)
	(segment
		(start 120.437148 -378.79909)
		(end 120.310148 -378.67209)
		(width 0.1651)
		(layer "In13.Cu")
		(net "P5E_PEX1_STN5_TX_C_DP<90>")
	)
	(segment
		(start 127.617728 -362.986574)
		(end 127.236474 -363.30255)
		(width 0.1651)
		(layer "In13.Cu")
		(net "P5E_PEX1_STN5_TX_C_DP<90>")
	)
	(segment
		(start 120.658636 -378.79909)
		(end 120.437148 -378.79909)
		(width 0.1651)
		(layer "In13.Cu")
		(net "P5E_PEX1_STN5_TX_C_DP<90>")
	)
	(segment
		(start 133.915658 -351.902268)
		(end 133.915658 -352.513138)
		(width 0.1651)
		(layer "In13.Cu")
		(net "P5E_PEX1_STN5_TX_C_DP<90>")
	)
	(segment
		(start 126.71806 -363.732572)
		(end 121.595896 -367.980214)
		(width 0.1651)
		(layer "In13.Cu")
		(net "P5E_PEX1_STN5_TX_C_DP<90>")
	)
	(segment
		(start 128.528826 -362.115354)
		(end 128.517142 -362.240576)
		(width 0.1651)
		(layer "In13.Cu")
		(net "P5E_PEX1_STN5_TX_C_DP<90>")
	)
	(segment
		(start 131.75107 -359.558844)
		(end 129.035556 -361.810554)
		(width 0.1651)
		(layer "In13.Cu")
		(net "P5E_PEX1_STN5_TX_C_DP<90>")
	)
	(segment
		(start 128.517142 -362.240576)
		(end 128.135888 -362.556552)
		(width 0.1651)
		(layer "In13.Cu")
		(net "P5E_PEX1_STN5_TX_C_DP<90>")
	)
	(segment
		(start 127.629412 -362.861352)
		(end 127.617728 -362.986574)
		(width 0.1651)
		(layer "In13.Cu")
		(net "P5E_PEX1_STN5_TX_C_DP<90>")
	)
	(segment
		(start 133.915658 -352.513138)
		(end 132.361178 -354.067618)
		(width 0.1651)
		(layer "In13.Cu")
		(net "P5E_PEX1_STN5_TX_C_DP<90>")
	)
	(segment
		(start 127.236474 -363.30255)
		(end 127.111252 -363.290866)
		(width 0.1651)
		(layer "In13.Cu")
		(net "P5E_PEX1_STN5_TX_C_DP<90>")
	)
	(segment
		(start 121.184924 -378.272802)
		(end 120.658636 -378.79909)
		(width 0.1651)
		(layer "In13.Cu")
		(net "P5E_PEX1_STN5_TX_C_DP<90>")
	)
	(segment
		(start 133.624828 -351.611438)
		(end 133.915658 -351.902268)
		(width 0.1651)
		(layer "In13.Cu")
		(net "P5E_PEX1_STN5_TX_C_DP<90>")
	)
	(segment
		(start 126.729744 -363.60735)
		(end 126.71806 -363.732572)
		(width 0.1651)
		(layer "In13.Cu")
		(net "P5E_PEX1_STN5_TX_C_DP<90>")
	)
	(segment
		(start 121.184924 -368.85499)
		(end 121.184924 -378.272802)
		(width 0.1651)
		(layer "In13.Cu")
		(net "P5E_PEX1_STN5_TX_C_DP<90>")
	)
	(segment
		(start 128.135888 -362.556552)
		(end 128.01092 -362.544868)
		(width 0.1651)
		(layer "In13.Cu")
		(net "P5E_PEX1_STN5_TX_C_DP<90>")
	)
	(segment
		(start 128.910334 -361.79887)
		(end 128.528826 -362.115354)
		(width 0.1651)
		(layer "In13.Cu")
		(net "P5E_PEX1_STN5_TX_C_DP<90>")
	)
	(segment
		(start 128.01092 -362.544868)
		(end 127.629412 -362.861352)
		(width 0.1651)
		(layer "In13.Cu")
		(net "P5E_PEX1_STN5_TX_C_DP<90>")
	)
	(segment
		(start 129.035556 -361.810554)
		(end 128.910334 -361.79887)
		(width 0.1651)
		(layer "In13.Cu")
		(net "P5E_PEX1_STN5_TX_C_DP<90>")
	)
	(segment
		(start 120.310148 -378.67209)
		(end 120.310148 -378.290074)
		(width 0.1651)
		(layer "In13.Cu")
		(net "P5E_PEX1_STN5_TX_C_DP<90>")
	)
	(segment
		(start 132.361178 -354.067618)
		(end 132.361178 -358.260904)
		(width 0.1651)
		(layer "In13.Cu")
		(net "P5E_PEX1_STN5_TX_C_DP<90>")
	)
	(segment
		(start 121.595896 -367.980214)
		(end 121.184924 -368.85499)
		(width 0.1651)
		(layer "In13.Cu")
		(net "P5E_PEX1_STN5_TX_C_DP<90>")
	)
	(segment
		(start 127.111252 -363.290866)
		(end 126.729744 -363.60735)
		(width 0.1651)
		(layer "In13.Cu")
		(net "P5E_PEX1_STN5_TX_C_DP<90>")
	)
	(segment
		(start 73.02246 -30.353)
		(end 72.70115 -30.03169)
		(width 0.13462)
		(layer "F.Cu")
		(net "P5E_PEX0_STN2_TX_DN<37>")
	)
	(segment
		(start 73.947274 -30.05709)
		(end 73.651364 -30.353)
		(width 0.13462)
		(layer "F.Cu")
		(net "P5E_PEX0_STN2_TX_DN<37>")
	)
	(segment
		(start 73.651364 -30.353)
		(end 73.02246 -30.353)
		(width 0.13462)
		(layer "F.Cu")
		(net "P5E_PEX0_STN2_TX_DN<37>")
	)
	(segment
		(start 73.947274 -30.05709)
		(end 74.238104 -30.34792)
		(width 0.1651)
		(layer "In11.Cu")
		(net "P5E_PEX0_STN2_TX_DN<37>")
	)
	(segment
		(start 90.271346 -58.532522)
		(end 90.271346 -60.458604)
		(width 0.1651)
		(layer "In11.Cu")
		(net "P5E_PEX0_STN2_TX_DN<37>")
	)
	(segment
		(start 77.692504 -32.913066)
		(end 82.419952 -40.511984)
		(width 0.1651)
		(layer "In11.Cu")
		(net "P5E_PEX0_STN2_TX_DN<37>")
	)
	(segment
		(start 89.672414 -62.700916)
		(end 88.717374 -64.616076)
		(width 0.1651)
		(layer "In11.Cu")
		(net "P5E_PEX0_STN2_TX_DN<37>")
	)
	(segment
		(start 61.113924 -120.76176)
		(end 53.615844 -263.306306)
		(width 0.1651)
		(layer "In11.Cu")
		(net "P5E_PEX0_STN2_TX_DN<37>")
	)
	(segment
		(start 53.570124 -278.125936)
		(end 53.673756 -278.229568)
		(width 0.1143)
		(layer "In11.Cu")
		(net "P5E_PEX0_STN2_TX_DN<37>")
	)
	(segment
		(start 53.615844 -263.306306)
		(end 53.615844 -271.399)
		(width 0.1651)
		(layer "In11.Cu")
		(net "P5E_PEX0_STN2_TX_DN<37>")
	)
	(segment
		(start 53.615844 -271.399)
		(end 53.615844 -271.427448)
		(width 0.1143)
		(layer "In11.Cu")
		(net "P5E_PEX0_STN2_TX_DN<37>")
	)
	(segment
		(start 66.53276 -93.609922)
		(end 63.236094 -107.879896)
		(width 0.1651)
		(layer "In11.Cu")
		(net "P5E_PEX0_STN2_TX_DN<37>")
	)
	(segment
		(start 88.717374 -64.616076)
		(end 66.53276 -93.609922)
		(width 0.1651)
		(layer "In11.Cu")
		(net "P5E_PEX0_STN2_TX_DN<37>")
	)
	(segment
		(start 53.615844 -271.427448)
		(end 53.570124 -271.473168)
		(width 0.1143)
		(layer "In11.Cu")
		(net "P5E_PEX0_STN2_TX_DN<37>")
	)
	(segment
		(start 75.279504 -30.500066)
		(end 77.692504 -32.913066)
		(width 0.1651)
		(layer "In11.Cu")
		(net "P5E_PEX0_STN2_TX_DN<37>")
	)
	(segment
		(start 74.91222 -30.34792)
		(end 75.279504 -30.500066)
		(width 0.1651)
		(layer "In11.Cu")
		(net "P5E_PEX0_STN2_TX_DN<37>")
	)
	(segment
		(start 53.570124 -271.473168)
		(end 53.570124 -278.125936)
		(width 0.1143)
		(layer "In11.Cu")
		(net "P5E_PEX0_STN2_TX_DN<37>")
	)
	(segment
		(start 63.236094 -107.879896)
		(end 61.791596 -115.272058)
		(width 0.1651)
		(layer "In11.Cu")
		(net "P5E_PEX0_STN2_TX_DN<37>")
	)
	(segment
		(start 53.949854 -278.115268)
		(end 53.949854 -277.849838)
		(width 0.1143)
		(layer "In11.Cu")
		(net "P5E_PEX0_STN2_TX_DN<37>")
	)
	(segment
		(start 82.419952 -40.511984)
		(end 89.205054 -48.032416)
		(width 0.1651)
		(layer "In11.Cu")
		(net "P5E_PEX0_STN2_TX_DN<37>")
	)
	(segment
		(start 90.271346 -60.458604)
		(end 89.672414 -62.700916)
		(width 0.1651)
		(layer "In11.Cu")
		(net "P5E_PEX0_STN2_TX_DN<37>")
	)
	(segment
		(start 53.673756 -278.229568)
		(end 53.835554 -278.229568)
		(width 0.1143)
		(layer "In11.Cu")
		(net "P5E_PEX0_STN2_TX_DN<37>")
	)
	(segment
		(start 74.238104 -30.34792)
		(end 74.91222 -30.34792)
		(width 0.1651)
		(layer "In11.Cu")
		(net "P5E_PEX0_STN2_TX_DN<37>")
	)
	(segment
		(start 53.835554 -278.229568)
		(end 53.949854 -278.115268)
		(width 0.1143)
		(layer "In11.Cu")
		(net "P5E_PEX0_STN2_TX_DN<37>")
	)
	(segment
		(start 61.791596 -115.272058)
		(end 61.113924 -120.76176)
		(width 0.1651)
		(layer "In11.Cu")
		(net "P5E_PEX0_STN2_TX_DN<37>")
	)
	(segment
		(start 89.205054 -48.032416)
		(end 90.271346 -58.532522)
		(width 0.1651)
		(layer "In11.Cu")
		(net "P5E_PEX0_STN2_TX_DN<37>")
	)
	(segment
		(start 187.405264 -31.850584)
		(end 187.119768 -32.13608)
		(width 0.13462)
		(layer "F.Cu")
		(net "P5E_PEX1_STN2_TX_DN<38>")
	)
	(segment
		(start 187.119768 -32.13608)
		(end 186.470036 -32.13608)
		(width 0.13462)
		(layer "F.Cu")
		(net "P5E_PEX1_STN2_TX_DN<38>")
	)
	(segment
		(start 186.470036 -32.13608)
		(end 186.15914 -31.825184)
		(width 0.13462)
		(layer "F.Cu")
		(net "P5E_PEX1_STN2_TX_DN<38>")
	)
	(segment
		(start 197.612 -41.298876)
		(end 204.313536 -48.575468)
		(width 0.1651)
		(layer "In11.Cu")
		(net "P5E_PEX1_STN2_TX_DN<38>")
	)
	(segment
		(start 181.748684 -93.193108)
		(end 178.401472 -107.679744)
		(width 0.1651)
		(layer "In11.Cu")
		(net "P5E_PEX1_STN2_TX_DN<38>")
	)
	(segment
		(start 168.765982 -271.427448)
		(end 168.720262 -271.473168)
		(width 0.1143)
		(layer "In11.Cu")
		(net "P5E_PEX1_STN2_TX_DN<38>")
	)
	(segment
		(start 193.461894 -34.539936)
		(end 197.612 -41.298876)
		(width 0.1651)
		(layer "In11.Cu")
		(net "P5E_PEX1_STN2_TX_DN<38>")
	)
	(segment
		(start 187.696094 -32.141414)
		(end 189.864746 -32.141414)
		(width 0.1651)
		(layer "In11.Cu")
		(net "P5E_PEX1_STN2_TX_DN<38>")
	)
	(segment
		(start 191.65062 -32.78378)
		(end 193.461894 -34.539936)
		(width 0.1651)
		(layer "In11.Cu")
		(net "P5E_PEX1_STN2_TX_DN<38>")
	)
	(segment
		(start 168.985692 -280.129488)
		(end 169.099992 -280.015188)
		(width 0.1143)
		(layer "In11.Cu")
		(net "P5E_PEX1_STN2_TX_DN<38>")
	)
	(segment
		(start 168.765982 -263.18337)
		(end 168.765982 -271.399)
		(width 0.1651)
		(layer "In11.Cu")
		(net "P5E_PEX1_STN2_TX_DN<38>")
	)
	(segment
		(start 168.765982 -271.399)
		(end 168.765982 -271.427448)
		(width 0.1143)
		(layer "In11.Cu")
		(net "P5E_PEX1_STN2_TX_DN<38>")
	)
	(segment
		(start 176.191164 -121.058686)
		(end 168.765982 -263.18337)
		(width 0.1651)
		(layer "In11.Cu")
		(net "P5E_PEX1_STN2_TX_DN<38>")
	)
	(segment
		(start 204.313536 -48.575468)
		(end 205.34376 -58.49747)
		(width 0.1651)
		(layer "In11.Cu")
		(net "P5E_PEX1_STN2_TX_DN<38>")
	)
	(segment
		(start 169.099992 -280.015188)
		(end 169.099992 -279.749504)
		(width 0.1143)
		(layer "In11.Cu")
		(net "P5E_PEX1_STN2_TX_DN<38>")
	)
	(segment
		(start 187.405264 -31.850584)
		(end 187.696094 -32.141414)
		(width 0.1651)
		(layer "In11.Cu")
		(net "P5E_PEX1_STN2_TX_DN<38>")
	)
	(segment
		(start 205.34376 -60.348876)
		(end 204.806296 -62.36716)
		(width 0.1651)
		(layer "In11.Cu")
		(net "P5E_PEX1_STN2_TX_DN<38>")
	)
	(segment
		(start 168.823894 -280.129488)
		(end 168.985692 -280.129488)
		(width 0.1143)
		(layer "In11.Cu")
		(net "P5E_PEX1_STN2_TX_DN<38>")
	)
	(segment
		(start 203.890626 -64.219836)
		(end 181.748684 -93.193108)
		(width 0.1651)
		(layer "In11.Cu")
		(net "P5E_PEX1_STN2_TX_DN<38>")
	)
	(segment
		(start 205.34376 -58.49747)
		(end 205.34376 -60.348876)
		(width 0.1651)
		(layer "In11.Cu")
		(net "P5E_PEX1_STN2_TX_DN<38>")
	)
	(segment
		(start 189.864746 -32.141414)
		(end 191.65062 -32.78378)
		(width 0.1651)
		(layer "In11.Cu")
		(net "P5E_PEX1_STN2_TX_DN<38>")
	)
	(segment
		(start 176.881536 -115.457732)
		(end 176.191164 -121.058686)
		(width 0.1651)
		(layer "In11.Cu")
		(net "P5E_PEX1_STN2_TX_DN<38>")
	)
	(segment
		(start 168.720262 -271.473168)
		(end 168.720262 -280.025856)
		(width 0.1143)
		(layer "In11.Cu")
		(net "P5E_PEX1_STN2_TX_DN<38>")
	)
	(segment
		(start 204.806296 -62.36716)
		(end 203.890626 -64.219836)
		(width 0.1651)
		(layer "In11.Cu")
		(net "P5E_PEX1_STN2_TX_DN<38>")
	)
	(segment
		(start 178.401472 -107.679744)
		(end 176.881536 -115.457732)
		(width 0.1651)
		(layer "In11.Cu")
		(net "P5E_PEX1_STN2_TX_DN<38>")
	)
	(segment
		(start 168.720262 -280.025856)
		(end 168.823894 -280.129488)
		(width 0.1143)
		(layer "In11.Cu")
		(net "P5E_PEX1_STN2_TX_DN<38>")
	)
	(segment
		(start 312.802016 -118.9863)
		(end 312.48604 -118.670324)
		(width 0.13462)
		(layer "F.Cu")
		(net "P5E_PEX2_STN0_TX_DN<0>")
	)
	(segment
		(start 313.732164 -118.695724)
		(end 313.441588 -118.9863)
		(width 0.13462)
		(layer "F.Cu")
		(net "P5E_PEX2_STN0_TX_DN<0>")
	)
	(segment
		(start 313.441588 -118.9863)
		(end 312.802016 -118.9863)
		(width 0.13462)
		(layer "F.Cu")
		(net "P5E_PEX2_STN0_TX_DN<0>")
	)
	(segment
		(start 316.117478 -287.965896)
		(end 316.08903 -287.965896)
		(width 0.1143)
		(layer "In9.Cu")
		(net "P5E_PEX2_STN0_TX_DN<0>")
	)
	(segment
		(start 309.520082 -288.185606)
		(end 309.634382 -288.299906)
		(width 0.1143)
		(layer "In9.Cu")
		(net "P5E_PEX2_STN0_TX_DN<0>")
	)
	(segment
		(start 309.520082 -288.023808)
		(end 309.520082 -288.185606)
		(width 0.1143)
		(layer "In9.Cu")
		(net "P5E_PEX2_STN0_TX_DN<0>")
	)
	(segment
		(start 316.08903 -287.965896)
		(end 316.04331 -287.920176)
		(width 0.1143)
		(layer "In9.Cu")
		(net "P5E_PEX2_STN0_TX_DN<0>")
	)
	(segment
		(start 332.661006 -269.973044)
		(end 332.902306 -272.746978)
		(width 0.1651)
		(layer "In9.Cu")
		(net "P5E_PEX2_STN0_TX_DN<0>")
	)
	(segment
		(start 332.902306 -272.746978)
		(end 331.176376 -276.912578)
		(width 0.1651)
		(layer "In9.Cu")
		(net "P5E_PEX2_STN0_TX_DN<0>")
	)
	(segment
		(start 332.371446 -151.905462)
		(end 332.371446 -159.966914)
		(width 0.1651)
		(layer "In9.Cu")
		(net "P5E_PEX2_STN0_TX_DN<0>")
	)
	(segment
		(start 318.878458 -221.785942)
		(end 321.278504 -249.289316)
		(width 0.1651)
		(layer "In9.Cu")
		(net "P5E_PEX2_STN0_TX_DN<0>")
	)
	(segment
		(start 323.746876 -131.084574)
		(end 332.371446 -151.905462)
		(width 0.1651)
		(layer "In9.Cu")
		(net "P5E_PEX2_STN0_TX_DN<0>")
	)
	(segment
		(start 332.371446 -159.966914)
		(end 332.02118 -161.278062)
		(width 0.1651)
		(layer "In9.Cu")
		(net "P5E_PEX2_STN0_TX_DN<0>")
	)
	(segment
		(start 309.634382 -288.299906)
		(end 309.899812 -288.299906)
		(width 0.1143)
		(layer "In9.Cu")
		(net "P5E_PEX2_STN0_TX_DN<0>")
	)
	(segment
		(start 309.623714 -287.920176)
		(end 309.520082 -288.023808)
		(width 0.1143)
		(layer "In9.Cu")
		(net "P5E_PEX2_STN0_TX_DN<0>")
	)
	(segment
		(start 323.449188 -176.133252)
		(end 322.600828 -179.242212)
		(width 0.1651)
		(layer "In9.Cu")
		(net "P5E_PEX2_STN0_TX_DN<0>")
	)
	(segment
		(start 316.42177 -118.986554)
		(end 319.36563 -120.953276)
		(width 0.1651)
		(layer "In9.Cu")
		(net "P5E_PEX2_STN0_TX_DN<0>")
	)
	(segment
		(start 313.732164 -118.695724)
		(end 314.022994 -118.986554)
		(width 0.1651)
		(layer "In9.Cu")
		(net "P5E_PEX2_STN0_TX_DN<0>")
	)
	(segment
		(start 331.176376 -276.912578)
		(end 321.596766 -286.492188)
		(width 0.1651)
		(layer "In9.Cu")
		(net "P5E_PEX2_STN0_TX_DN<0>")
	)
	(segment
		(start 332.02118 -161.278062)
		(end 323.449188 -176.133252)
		(width 0.1651)
		(layer "In9.Cu")
		(net "P5E_PEX2_STN0_TX_DN<0>")
	)
	(segment
		(start 331.732636 -265.560556)
		(end 332.421738 -267.224002)
		(width 0.1651)
		(layer "In9.Cu")
		(net "P5E_PEX2_STN0_TX_DN<0>")
	)
	(segment
		(start 314.022994 -118.986554)
		(end 316.42177 -118.986554)
		(width 0.1651)
		(layer "In9.Cu")
		(net "P5E_PEX2_STN0_TX_DN<0>")
	)
	(segment
		(start 319.36563 -120.953276)
		(end 323.431408 -130.769106)
		(width 0.1651)
		(layer "In9.Cu")
		(net "P5E_PEX2_STN0_TX_DN<0>")
	)
	(segment
		(start 332.421738 -267.224002)
		(end 332.661006 -269.973044)
		(width 0.1651)
		(layer "In9.Cu")
		(net "P5E_PEX2_STN0_TX_DN<0>")
	)
	(segment
		(start 321.596766 -286.492188)
		(end 318.038734 -287.965896)
		(width 0.1651)
		(layer "In9.Cu")
		(net "P5E_PEX2_STN0_TX_DN<0>")
	)
	(segment
		(start 323.431408 -130.769106)
		(end 323.746876 -131.084574)
		(width 0.1651)
		(layer "In9.Cu")
		(net "P5E_PEX2_STN0_TX_DN<0>")
	)
	(segment
		(start 331.049376 -263.91108)
		(end 331.732636 -265.560556)
		(width 0.1651)
		(layer "In9.Cu")
		(net "P5E_PEX2_STN0_TX_DN<0>")
	)
	(segment
		(start 318.038734 -287.965896)
		(end 316.117478 -287.965896)
		(width 0.1651)
		(layer "In9.Cu")
		(net "P5E_PEX2_STN0_TX_DN<0>")
	)
	(segment
		(start 316.04331 -287.920176)
		(end 309.623714 -287.920176)
		(width 0.1143)
		(layer "In9.Cu")
		(net "P5E_PEX2_STN0_TX_DN<0>")
	)
	(segment
		(start 321.278504 -249.289316)
		(end 331.049376 -263.91108)
		(width 0.1651)
		(layer "In9.Cu")
		(net "P5E_PEX2_STN0_TX_DN<0>")
	)
	(segment
		(start 322.600828 -179.242212)
		(end 318.878458 -221.785942)
		(width 0.1651)
		(layer "In9.Cu")
		(net "P5E_PEX2_STN0_TX_DN<0>")
	)
	(segment
		(start 325.507604 -355.658166)
		(end 325.507604 -355.026722)
		(width 0.13462)
		(layer "F.Cu")
		(net "P5E_PEX2_STN6_TX_DN<105>")
	)
	(segment
		(start 325.827644 -355.978206)
		(end 325.507604 -355.658166)
		(width 0.13462)
		(layer "F.Cu")
		(net "P5E_PEX2_STN6_TX_DN<105>")
	)
	(segment
		(start 325.507604 -355.026722)
		(end 325.802244 -354.732082)
		(width 0.13462)
		(layer "F.Cu")
		(net "P5E_PEX2_STN6_TX_DN<105>")
	)
	(segment
		(start 327.065894 -352.376486)
		(end 327.065894 -342.1634)
		(width 0.1651)
		(layer "In13.Cu")
		(net "P5E_PEX2_STN6_TX_DN<105>")
	)
	(segment
		(start 281.399742 -311.784492)
		(end 281.399742 -312.049922)
		(width 0.1143)
		(layer "In13.Cu")
		(net "P5E_PEX2_STN6_TX_DN<105>")
	)
	(segment
		(start 327.065894 -342.1634)
		(end 326.6694 -341.0712)
		(width 0.1651)
		(layer "In13.Cu")
		(net "P5E_PEX2_STN6_TX_DN<105>")
	)
	(segment
		(start 281.020012 -319.921128)
		(end 281.020012 -311.787794)
		(width 0.1143)
		(layer "In13.Cu")
		(net "P5E_PEX2_STN6_TX_DN<105>")
	)
	(segment
		(start 284.789118 -328.578718)
		(end 282.881832 -326.671432)
		(width 0.1651)
		(layer "In13.Cu")
		(net "P5E_PEX2_STN6_TX_DN<105>")
	)
	(segment
		(start 324.735444 -338.895436)
		(end 315.051186 -334.549242)
		(width 0.1651)
		(layer "In13.Cu")
		(net "P5E_PEX2_STN6_TX_DN<105>")
	)
	(segment
		(start 281.065732 -323.944996)
		(end 281.065732 -319.995296)
		(width 0.1651)
		(layer "In13.Cu")
		(net "P5E_PEX2_STN6_TX_DN<105>")
	)
	(segment
		(start 325.802244 -354.732082)
		(end 325.511414 -354.441252)
		(width 0.1651)
		(layer "In13.Cu")
		(net "P5E_PEX2_STN6_TX_DN<105>")
	)
	(segment
		(start 282.881832 -326.671432)
		(end 282.881832 -326.509888)
		(width 0.1651)
		(layer "In13.Cu")
		(net "P5E_PEX2_STN6_TX_DN<105>")
	)
	(segment
		(start 281.065732 -319.966848)
		(end 281.020012 -319.921128)
		(width 0.1143)
		(layer "In13.Cu")
		(net "P5E_PEX2_STN6_TX_DN<105>")
	)
	(segment
		(start 281.137614 -311.670192)
		(end 281.285442 -311.670192)
		(width 0.1143)
		(layer "In13.Cu")
		(net "P5E_PEX2_STN6_TX_DN<105>")
	)
	(segment
		(start 281.020012 -311.787794)
		(end 281.137614 -311.670192)
		(width 0.1143)
		(layer "In13.Cu")
		(net "P5E_PEX2_STN6_TX_DN<105>")
	)
	(segment
		(start 282.881832 -326.509888)
		(end 282.531312 -326.159368)
		(width 0.1651)
		(layer "In13.Cu")
		(net "P5E_PEX2_STN6_TX_DN<105>")
	)
	(segment
		(start 282.369768 -326.159368)
		(end 281.709368 -325.498968)
		(width 0.1651)
		(layer "In13.Cu")
		(net "P5E_PEX2_STN6_TX_DN<105>")
	)
	(segment
		(start 281.285442 -311.670192)
		(end 281.399742 -311.784492)
		(width 0.1143)
		(layer "In13.Cu")
		(net "P5E_PEX2_STN6_TX_DN<105>")
	)
	(segment
		(start 315.051186 -334.549242)
		(end 284.789118 -328.578718)
		(width 0.1651)
		(layer "In13.Cu")
		(net "P5E_PEX2_STN6_TX_DN<105>")
	)
	(segment
		(start 281.065732 -319.995296)
		(end 281.065732 -319.966848)
		(width 0.1143)
		(layer "In13.Cu")
		(net "P5E_PEX2_STN6_TX_DN<105>")
	)
	(segment
		(start 325.511414 -353.930966)
		(end 327.065894 -352.376486)
		(width 0.1651)
		(layer "In13.Cu")
		(net "P5E_PEX2_STN6_TX_DN<105>")
	)
	(segment
		(start 282.531312 -326.159368)
		(end 282.369768 -326.159368)
		(width 0.1651)
		(layer "In13.Cu")
		(net "P5E_PEX2_STN6_TX_DN<105>")
	)
	(segment
		(start 281.709368 -325.498968)
		(end 281.065732 -323.944996)
		(width 0.1651)
		(layer "In13.Cu")
		(net "P5E_PEX2_STN6_TX_DN<105>")
	)
	(segment
		(start 326.6694 -341.0712)
		(end 324.735444 -338.895436)
		(width 0.1651)
		(layer "In13.Cu")
		(net "P5E_PEX2_STN6_TX_DN<105>")
	)
	(segment
		(start 325.511414 -354.441252)
		(end 325.511414 -353.930966)
		(width 0.1651)
		(layer "In13.Cu")
		(net "P5E_PEX2_STN6_TX_DN<105>")
	)
	(segment
		(start 432.47437 -124.102114)
		(end 432.179984 -124.3965)
		(width 0.13462)
		(layer "F.Cu")
		(net "P5E_PEX3_STN0_TX_DN<3>")
	)
	(segment
		(start 432.179984 -124.3965)
		(end 431.548032 -124.3965)
		(width 0.13462)
		(layer "F.Cu")
		(net "P5E_PEX3_STN0_TX_DN<3>")
	)
	(segment
		(start 431.548032 -124.3965)
		(end 431.228246 -124.076714)
		(width 0.13462)
		(layer "F.Cu")
		(net "P5E_PEX3_STN0_TX_DN<3>")
	)
	(segment
		(start 435.772306 -178.830478)
		(end 432.02733 -221.628208)
		(width 0.1651)
		(layer "In9.Cu")
		(net "P5E_PEX3_STN0_TX_DN<3>")
	)
	(segment
		(start 434.230526 -126.538228)
		(end 436.653686 -132.285486)
		(width 0.1651)
		(layer "In9.Cu")
		(net "P5E_PEX3_STN0_TX_DN<3>")
	)
	(segment
		(start 433.970684 -125.230636)
		(end 434.230526 -126.538228)
		(width 0.1651)
		(layer "In9.Cu")
		(net "P5E_PEX3_STN0_TX_DN<3>")
	)
	(segment
		(start 433.762404 -124.72797)
		(end 433.970684 -125.230636)
		(width 0.1651)
		(layer "In9.Cu")
		(net "P5E_PEX3_STN0_TX_DN<3>")
	)
	(segment
		(start 436.757318 -175.158908)
		(end 435.772306 -178.830478)
		(width 0.1651)
		(layer "In9.Cu")
		(net "P5E_PEX3_STN0_TX_DN<3>")
	)
	(segment
		(start 444.798704 -265.745722)
		(end 445.70269 -267.928344)
		(width 0.1651)
		(layer "In9.Cu")
		(net "P5E_PEX3_STN0_TX_DN<3>")
	)
	(segment
		(start 445.70269 -267.928344)
		(end 445.892174 -270.102838)
		(width 0.1651)
		(layer "In9.Cu")
		(net "P5E_PEX3_STN0_TX_DN<3>")
	)
	(segment
		(start 433.427378 -124.392944)
		(end 433.762404 -124.72797)
		(width 0.1651)
		(layer "In9.Cu")
		(net "P5E_PEX3_STN0_TX_DN<3>")
	)
	(segment
		(start 444.846202 -275.289772)
		(end 436.072534 -284.06344)
		(width 0.1651)
		(layer "In9.Cu")
		(net "P5E_PEX3_STN0_TX_DN<3>")
	)
	(segment
		(start 445.568324 -153.132536)
		(end 445.568324 -159.583628)
		(width 0.1651)
		(layer "In9.Cu")
		(net "P5E_PEX3_STN0_TX_DN<3>")
	)
	(segment
		(start 432.1937 -285.115508)
		(end 432.165252 -285.115508)
		(width 0.1143)
		(layer "In9.Cu")
		(net "P5E_PEX3_STN0_TX_DN<3>")
	)
	(segment
		(start 423.834306 -285.449772)
		(end 424.09999 -285.449772)
		(width 0.1143)
		(layer "In9.Cu")
		(net "P5E_PEX3_STN0_TX_DN<3>")
	)
	(segment
		(start 434.538374 -250.391168)
		(end 444.798704 -265.745722)
		(width 0.1651)
		(layer "In9.Cu")
		(net "P5E_PEX3_STN0_TX_DN<3>")
	)
	(segment
		(start 432.7652 -124.392944)
		(end 433.427378 -124.392944)
		(width 0.1651)
		(layer "In9.Cu")
		(net "P5E_PEX3_STN0_TX_DN<3>")
	)
	(segment
		(start 445.415416 -160.15589)
		(end 436.757318 -175.158908)
		(width 0.1651)
		(layer "In9.Cu")
		(net "P5E_PEX3_STN0_TX_DN<3>")
	)
	(segment
		(start 423.720006 -285.335472)
		(end 423.834306 -285.449772)
		(width 0.1143)
		(layer "In9.Cu")
		(net "P5E_PEX3_STN0_TX_DN<3>")
	)
	(segment
		(start 432.02733 -221.628208)
		(end 434.538374 -250.391168)
		(width 0.1651)
		(layer "In9.Cu")
		(net "P5E_PEX3_STN0_TX_DN<3>")
	)
	(segment
		(start 436.072534 -284.06344)
		(end 433.532788 -285.115508)
		(width 0.1651)
		(layer "In9.Cu")
		(net "P5E_PEX3_STN0_TX_DN<3>")
	)
	(segment
		(start 423.823892 -285.069788)
		(end 423.720006 -285.173674)
		(width 0.1143)
		(layer "In9.Cu")
		(net "P5E_PEX3_STN0_TX_DN<3>")
	)
	(segment
		(start 423.720006 -285.173674)
		(end 423.720006 -285.335472)
		(width 0.1143)
		(layer "In9.Cu")
		(net "P5E_PEX3_STN0_TX_DN<3>")
	)
	(segment
		(start 446.08369 -272.302224)
		(end 444.846202 -275.289772)
		(width 0.1651)
		(layer "In9.Cu")
		(net "P5E_PEX3_STN0_TX_DN<3>")
	)
	(segment
		(start 432.165252 -285.115508)
		(end 432.119532 -285.069788)
		(width 0.1143)
		(layer "In9.Cu")
		(net "P5E_PEX3_STN0_TX_DN<3>")
	)
	(segment
		(start 436.653686 -132.285486)
		(end 437.13146 -132.763514)
		(width 0.1651)
		(layer "In9.Cu")
		(net "P5E_PEX3_STN0_TX_DN<3>")
	)
	(segment
		(start 433.532788 -285.115508)
		(end 432.1937 -285.115508)
		(width 0.1651)
		(layer "In9.Cu")
		(net "P5E_PEX3_STN0_TX_DN<3>")
	)
	(segment
		(start 445.568324 -159.583628)
		(end 445.415416 -160.15589)
		(width 0.1651)
		(layer "In9.Cu")
		(net "P5E_PEX3_STN0_TX_DN<3>")
	)
	(segment
		(start 437.13146 -132.763514)
		(end 445.568324 -153.132536)
		(width 0.1651)
		(layer "In9.Cu")
		(net "P5E_PEX3_STN0_TX_DN<3>")
	)
	(segment
		(start 445.892174 -270.102838)
		(end 446.08369 -272.302224)
		(width 0.1651)
		(layer "In9.Cu")
		(net "P5E_PEX3_STN0_TX_DN<3>")
	)
	(segment
		(start 432.47437 -124.102114)
		(end 432.7652 -124.392944)
		(width 0.1651)
		(layer "In9.Cu")
		(net "P5E_PEX3_STN0_TX_DN<3>")
	)
	(segment
		(start 432.119532 -285.069788)
		(end 423.823892 -285.069788)
		(width 0.1143)
		(layer "In9.Cu")
		(net "P5E_PEX3_STN0_TX_DN<3>")
	)
	(segment
		(start 422.025064 -342.73363)
		(end 421.730932 -342.439498)
		(width 0.13462)
		(layer "F.Cu")
		(net "P5E_PEX3_STN7_TX_DP<117>")
	)
	(segment
		(start 421.705532 -343.685622)
		(end 422.025064 -343.36609)
		(width 0.13462)
		(layer "F.Cu")
		(net "P5E_PEX3_STN7_TX_DP<117>")
	)
	(segment
		(start 422.025064 -343.36609)
		(end 422.025064 -342.73363)
		(width 0.13462)
		(layer "F.Cu")
		(net "P5E_PEX3_STN7_TX_DP<117>")
	)
	(segment
		(start 418.609526 -338.401152)
		(end 375.371868 -328.714608)
		(width 0.1651)
		(layer "In11.Cu")
		(net "P5E_PEX3_STN7_TX_DP<117>")
	)
	(segment
		(start 392.154918 -305.779678)
		(end 392.370056 -305.994816)
		(width 0.1143)
		(layer "In11.Cu")
		(net "P5E_PEX3_STN7_TX_DP<117>")
	)
	(segment
		(start 392.370056 -306.235608)
		(end 392.484356 -306.349908)
		(width 0.1143)
		(layer "In11.Cu")
		(net "P5E_PEX3_STN7_TX_DP<117>")
	)
	(segment
		(start 392.370056 -305.994816)
		(end 392.370056 -306.235608)
		(width 0.1143)
		(layer "In11.Cu")
		(net "P5E_PEX3_STN7_TX_DP<117>")
	)
	(segment
		(start 379.78588 -306.70754)
		(end 382.136142 -305.733958)
		(width 0.1651)
		(layer "In11.Cu")
		(net "P5E_PEX3_STN7_TX_DP<117>")
	)
	(segment
		(start 421.730932 -342.439498)
		(end 422.021762 -342.148668)
		(width 0.1651)
		(layer "In11.Cu")
		(net "P5E_PEX3_STN7_TX_DP<117>")
	)
	(segment
		(start 422.021762 -342.148668)
		(end 422.021762 -341.691214)
		(width 0.1651)
		(layer "In11.Cu")
		(net "P5E_PEX3_STN7_TX_DP<117>")
	)
	(segment
		(start 370.885974 -325.486014)
		(end 369.51666 -322.180204)
		(width 0.1651)
		(layer "In11.Cu")
		(net "P5E_PEX3_STN7_TX_DP<117>")
	)
	(segment
		(start 421.46347 -340.392766)
		(end 418.609526 -338.401152)
		(width 0.1651)
		(layer "In11.Cu")
		(net "P5E_PEX3_STN7_TX_DP<117>")
	)
	(segment
		(start 383.949448 -305.733958)
		(end 383.995168 -305.779678)
		(width 0.1143)
		(layer "In11.Cu")
		(net "P5E_PEX3_STN7_TX_DP<117>")
	)
	(segment
		(start 375.371868 -328.714608)
		(end 372.577614 -327.177654)
		(width 0.1651)
		(layer "In11.Cu")
		(net "P5E_PEX3_STN7_TX_DP<117>")
	)
	(segment
		(start 422.021762 -341.691214)
		(end 421.46347 -340.392766)
		(width 0.1651)
		(layer "In11.Cu")
		(net "P5E_PEX3_STN7_TX_DP<117>")
	)
	(segment
		(start 392.484356 -306.349908)
		(end 392.749786 -306.349908)
		(width 0.1143)
		(layer "In11.Cu")
		(net "P5E_PEX3_STN7_TX_DP<117>")
	)
	(segment
		(start 383.995168 -305.779678)
		(end 392.154918 -305.779678)
		(width 0.1143)
		(layer "In11.Cu")
		(net "P5E_PEX3_STN7_TX_DP<117>")
	)
	(segment
		(start 369.51666 -322.180204)
		(end 369.51666 -319.222882)
		(width 0.1651)
		(layer "In11.Cu")
		(net "P5E_PEX3_STN7_TX_DP<117>")
	)
	(segment
		(start 369.51666 -319.222882)
		(end 369.722654 -318.725296)
		(width 0.1651)
		(layer "In11.Cu")
		(net "P5E_PEX3_STN7_TX_DP<117>")
	)
	(segment
		(start 383.921 -305.733958)
		(end 383.949448 -305.733958)
		(width 0.1143)
		(layer "In11.Cu")
		(net "P5E_PEX3_STN7_TX_DP<117>")
	)
	(segment
		(start 369.722654 -318.725296)
		(end 369.917726 -318.254126)
		(width 0.1651)
		(layer "In11.Cu")
		(net "P5E_PEX3_STN7_TX_DP<117>")
	)
	(segment
		(start 369.917726 -318.254126)
		(end 373.298466 -313.194954)
		(width 0.1651)
		(layer "In11.Cu")
		(net "P5E_PEX3_STN7_TX_DP<117>")
	)
	(segment
		(start 382.136142 -305.733958)
		(end 383.921 -305.733958)
		(width 0.1651)
		(layer "In11.Cu")
		(net "P5E_PEX3_STN7_TX_DP<117>")
	)
	(segment
		(start 373.298466 -313.194954)
		(end 379.78588 -306.70754)
		(width 0.1651)
		(layer "In11.Cu")
		(net "P5E_PEX3_STN7_TX_DP<117>")
	)
	(segment
		(start 372.577614 -327.177654)
		(end 370.885974 -325.486014)
		(width 0.1651)
		(layer "In11.Cu")
		(net "P5E_PEX3_STN7_TX_DP<117>")
	)
	(segment
		(start 130.515868 -357.75773)
		(end 130.810508 -357.46309)
		(width 0.13462)
		(layer "F.Cu")
		(net "P5E_PEX1_STN5_TX_C_DP<89>")
	)
	(segment
		(start 130.810508 -357.46309)
		(end 130.810508 -356.831646)
		(width 0.13462)
		(layer "F.Cu")
		(net "P5E_PEX1_STN5_TX_C_DP<89>")
	)
	(segment
		(start 130.810508 -356.831646)
		(end 130.490468 -356.511606)
		(width 0.13462)
		(layer "F.Cu")
		(net "P5E_PEX1_STN5_TX_C_DP<89>")
	)
	(segment
		(start 118.11 -379.772164)
		(end 118.11 -379.390148)
		(width 0.1651)
		(layer "In13.Cu")
		(net "P5E_PEX1_STN5_TX_C_DP<89>")
	)
	(segment
		(start 130.627374 -358.996234)
		(end 127.768604 -361.375706)
		(width 0.1651)
		(layer "In13.Cu")
		(net "P5E_PEX1_STN5_TX_C_DP<89>")
	)
	(segment
		(start 127.27051 -361.790234)
		(end 119.362474 -368.37239)
		(width 0.1651)
		(layer "In13.Cu")
		(net "P5E_PEX1_STN5_TX_C_DP<89>")
	)
	(segment
		(start 118.984776 -369.262914)
		(end 118.984776 -379.372876)
		(width 0.1651)
		(layer "In13.Cu")
		(net "P5E_PEX1_STN5_TX_C_DP<89>")
	)
	(segment
		(start 130.806698 -358.613964)
		(end 130.627374 -358.996234)
		(width 0.1651)
		(layer "In13.Cu")
		(net "P5E_PEX1_STN5_TX_C_DP<89>")
	)
	(segment
		(start 118.237 -379.899164)
		(end 118.11 -379.772164)
		(width 0.1651)
		(layer "In13.Cu")
		(net "P5E_PEX1_STN5_TX_C_DP<89>")
	)
	(segment
		(start 130.806698 -358.04856)
		(end 130.806698 -358.613964)
		(width 0.1651)
		(layer "In13.Cu")
		(net "P5E_PEX1_STN5_TX_C_DP<89>")
	)
	(segment
		(start 127.661416 -361.3658)
		(end 127.280416 -361.683046)
		(width 0.1651)
		(layer "In13.Cu")
		(net "P5E_PEX1_STN5_TX_C_DP<89>")
	)
	(segment
		(start 127.768604 -361.375706)
		(end 127.661416 -361.3658)
		(width 0.1651)
		(layer "In13.Cu")
		(net "P5E_PEX1_STN5_TX_C_DP<89>")
	)
	(segment
		(start 130.515868 -357.75773)
		(end 130.806698 -358.04856)
		(width 0.1651)
		(layer "In13.Cu")
		(net "P5E_PEX1_STN5_TX_C_DP<89>")
	)
	(segment
		(start 127.280416 -361.683046)
		(end 127.27051 -361.790234)
		(width 0.1651)
		(layer "In13.Cu")
		(net "P5E_PEX1_STN5_TX_C_DP<89>")
	)
	(segment
		(start 118.458488 -379.899164)
		(end 118.237 -379.899164)
		(width 0.1651)
		(layer "In13.Cu")
		(net "P5E_PEX1_STN5_TX_C_DP<89>")
	)
	(segment
		(start 118.984776 -379.372876)
		(end 118.458488 -379.899164)
		(width 0.1651)
		(layer "In13.Cu")
		(net "P5E_PEX1_STN5_TX_C_DP<89>")
	)
	(segment
		(start 119.362474 -368.37239)
		(end 118.984776 -369.262914)
		(width 0.1651)
		(layer "In13.Cu")
		(net "P5E_PEX1_STN5_TX_C_DP<89>")
	)
	(segment
		(start 70.388226 -32.4104)
		(end 70.059042 -32.739584)
		(width 0.13462)
		(layer "F.Cu")
		(net "P5E_PEX0_STN2_TX_DP<38>")
	)
	(segment
		(start 71.305166 -32.714184)
		(end 71.001382 -32.4104)
		(width 0.13462)
		(layer "F.Cu")
		(net "P5E_PEX0_STN2_TX_DP<38>")
	)
	(segment
		(start 71.001382 -32.4104)
		(end 70.388226 -32.4104)
		(width 0.13462)
		(layer "F.Cu")
		(net "P5E_PEX0_STN2_TX_DP<38>")
	)
	(segment
		(start 52.999894 -280.434288)
		(end 52.885594 -280.319988)
		(width 0.1143)
		(layer "In11.Cu")
		(net "P5E_PEX0_STN2_TX_DP<38>")
	)
	(segment
		(start 72.44715 -32.524954)
		(end 72.34555 -32.423354)
		(width 0.1651)
		(layer "In11.Cu")
		(net "P5E_PEX0_STN2_TX_DP<38>")
	)
	(segment
		(start 72.94245 -32.524954)
		(end 72.44715 -32.524954)
		(width 0.1651)
		(layer "In11.Cu")
		(net "P5E_PEX0_STN2_TX_DP<38>")
	)
	(segment
		(start 65.387474 -93.070426)
		(end 87.549736 -64.07023)
		(width 0.1651)
		(layer "In11.Cu")
		(net "P5E_PEX0_STN2_TX_DP<38>")
	)
	(segment
		(start 52.999894 -280.699718)
		(end 52.999894 -280.434288)
		(width 0.1143)
		(layer "In11.Cu")
		(net "P5E_PEX0_STN2_TX_DP<38>")
	)
	(segment
		(start 87.94242 -48.697642)
		(end 81.285842 -41.469818)
		(width 0.1651)
		(layer "In11.Cu")
		(net "P5E_PEX0_STN2_TX_DP<38>")
	)
	(segment
		(start 62.02553 -107.62107)
		(end 65.387474 -93.070426)
		(width 0.1651)
		(layer "In11.Cu")
		(net "P5E_PEX0_STN2_TX_DP<38>")
	)
	(segment
		(start 52.429664 -271.473168)
		(end 52.383944 -271.427448)
		(width 0.1143)
		(layer "In11.Cu")
		(net "P5E_PEX0_STN2_TX_DP<38>")
	)
	(segment
		(start 71.595996 -32.423354)
		(end 71.305166 -32.714184)
		(width 0.1651)
		(layer "In11.Cu")
		(net "P5E_PEX0_STN2_TX_DP<38>")
	)
	(segment
		(start 75.397868 -33.028636)
		(end 73.715372 -32.423354)
		(width 0.1651)
		(layer "In11.Cu")
		(net "P5E_PEX0_STN2_TX_DP<38>")
	)
	(segment
		(start 88.961722 -58.512202)
		(end 87.94242 -48.697642)
		(width 0.1651)
		(layer "In11.Cu")
		(net "P5E_PEX0_STN2_TX_DP<38>")
	)
	(segment
		(start 52.383944 -271.427448)
		(end 52.383944 -271.399)
		(width 0.1143)
		(layer "In11.Cu")
		(net "P5E_PEX0_STN2_TX_DP<38>")
	)
	(segment
		(start 73.715372 -32.423354)
		(end 73.04405 -32.423354)
		(width 0.1651)
		(layer "In11.Cu")
		(net "P5E_PEX0_STN2_TX_DP<38>")
	)
	(segment
		(start 52.429664 -280.10485)
		(end 52.429664 -271.473168)
		(width 0.1143)
		(layer "In11.Cu")
		(net "P5E_PEX0_STN2_TX_DP<38>")
	)
	(segment
		(start 73.04405 -32.423354)
		(end 72.94245 -32.524954)
		(width 0.1651)
		(layer "In11.Cu")
		(net "P5E_PEX0_STN2_TX_DP<38>")
	)
	(segment
		(start 52.383944 -263.176004)
		(end 59.809888 -121.034048)
		(width 0.1651)
		(layer "In11.Cu")
		(net "P5E_PEX0_STN2_TX_DP<38>")
	)
	(segment
		(start 88.961722 -60.311792)
		(end 88.961722 -58.512202)
		(width 0.1651)
		(layer "In11.Cu")
		(net "P5E_PEX0_STN2_TX_DP<38>")
	)
	(segment
		(start 77.140054 -34.717736)
		(end 75.397868 -33.028636)
		(width 0.1651)
		(layer "In11.Cu")
		(net "P5E_PEX0_STN2_TX_DP<38>")
	)
	(segment
		(start 52.644802 -280.319988)
		(end 52.429664 -280.10485)
		(width 0.1143)
		(layer "In11.Cu")
		(net "P5E_PEX0_STN2_TX_DP<38>")
	)
	(segment
		(start 52.885594 -280.319988)
		(end 52.644802 -280.319988)
		(width 0.1143)
		(layer "In11.Cu")
		(net "P5E_PEX0_STN2_TX_DP<38>")
	)
	(segment
		(start 88.440768 -62.267338)
		(end 88.961722 -60.311792)
		(width 0.1651)
		(layer "In11.Cu")
		(net "P5E_PEX0_STN2_TX_DP<38>")
	)
	(segment
		(start 81.285842 -41.469818)
		(end 77.140054 -34.717736)
		(width 0.1651)
		(layer "In11.Cu")
		(net "P5E_PEX0_STN2_TX_DP<38>")
	)
	(segment
		(start 52.383944 -271.399)
		(end 52.383944 -263.176004)
		(width 0.1651)
		(layer "In11.Cu")
		(net "P5E_PEX0_STN2_TX_DP<38>")
	)
	(segment
		(start 72.34555 -32.423354)
		(end 71.595996 -32.423354)
		(width 0.1651)
		(layer "In11.Cu")
		(net "P5E_PEX0_STN2_TX_DP<38>")
	)
	(segment
		(start 59.809888 -121.034048)
		(end 60.5028 -115.413282)
		(width 0.1651)
		(layer "In11.Cu")
		(net "P5E_PEX0_STN2_TX_DP<38>")
	)
	(segment
		(start 60.5028 -115.413282)
		(end 62.02553 -107.62107)
		(width 0.1651)
		(layer "In11.Cu")
		(net "P5E_PEX0_STN2_TX_DP<38>")
	)
	(segment
		(start 87.549736 -64.07023)
		(end 88.440768 -62.267338)
		(width 0.1651)
		(layer "In11.Cu")
		(net "P5E_PEX0_STN2_TX_DP<38>")
	)
	(segment
		(start 135.120126 -28.829)
		(end 134.469886 -28.829)
		(width 0.13462)
		(layer "F.Cu")
		(net "P5E_PEX1_STN2_TX_DP<44>")
	)
	(segment
		(start 134.469886 -28.829)
		(end 134.159244 -29.139642)
		(width 0.13462)
		(layer "F.Cu")
		(net "P5E_PEX1_STN2_TX_DP<44>")
	)
	(segment
		(start 135.405368 -29.114242)
		(end 135.120126 -28.829)
		(width 0.13462)
		(layer "F.Cu")
		(net "P5E_PEX1_STN2_TX_DP<44>")
	)
	(segment
		(start 140.201142 -30.121606)
		(end 140.509244 -30.510226)
		(width 0.1651)
		(layer "In11.Cu")
		(net "P5E_PEX1_STN2_TX_DP<44>")
	)
	(segment
		(start 155.205938 -62.140338)
		(end 155.563062 -135.957056)
		(width 0.1651)
		(layer "In11.Cu")
		(net "P5E_PEX1_STN2_TX_DP<44>")
	)
	(segment
		(start 135.698484 -28.821126)
		(end 135.70458 -28.823412)
		(width 0.1651)
		(layer "In11.Cu")
		(net "P5E_PEX1_STN2_TX_DP<44>")
	)
	(segment
		(start 162.829748 -280.10485)
		(end 163.044886 -280.319988)
		(width 0.1143)
		(layer "In11.Cu")
		(net "P5E_PEX1_STN2_TX_DP<44>")
	)
	(segment
		(start 135.405368 -29.114242)
		(end 135.698484 -28.821126)
		(width 0.1651)
		(layer "In11.Cu")
		(net "P5E_PEX1_STN2_TX_DP<44>")
	)
	(segment
		(start 154.634438 -145.379948)
		(end 161.895028 -264.61212)
		(width 0.1651)
		(layer "In11.Cu")
		(net "P5E_PEX1_STN2_TX_DP<44>")
	)
	(segment
		(start 140.509244 -30.510226)
		(end 140.633958 -30.52445)
		(width 0.1651)
		(layer "In11.Cu")
		(net "P5E_PEX1_STN2_TX_DP<44>")
	)
	(segment
		(start 155.563062 -135.957056)
		(end 154.634438 -145.379948)
		(width 0.1651)
		(layer "In11.Cu")
		(net "P5E_PEX1_STN2_TX_DP<44>")
	)
	(segment
		(start 136.78535 -28.912312)
		(end 137.28065 -28.912312)
		(width 0.1651)
		(layer "In11.Cu")
		(net "P5E_PEX1_STN2_TX_DP<44>")
	)
	(segment
		(start 153.77922 -48.256952)
		(end 154.507184 -50.411126)
		(width 0.1651)
		(layer "In11.Cu")
		(net "P5E_PEX1_STN2_TX_DP<44>")
	)
	(segment
		(start 139.826238 -29.505402)
		(end 140.21562 -29.996892)
		(width 0.1651)
		(layer "In11.Cu")
		(net "P5E_PEX1_STN2_TX_DP<44>")
	)
	(segment
		(start 137.36955 -28.823412)
		(end 138.17346 -28.823412)
		(width 0.1651)
		(layer "In11.Cu")
		(net "P5E_PEX1_STN2_TX_DP<44>")
	)
	(segment
		(start 162.784028 -271.399)
		(end 162.784028 -271.427448)
		(width 0.1143)
		(layer "In11.Cu")
		(net "P5E_PEX1_STN2_TX_DP<44>")
	)
	(segment
		(start 163.285678 -280.319988)
		(end 163.399978 -280.434288)
		(width 0.1143)
		(layer "In11.Cu")
		(net "P5E_PEX1_STN2_TX_DP<44>")
	)
	(segment
		(start 161.895028 -264.61212)
		(end 162.784028 -270.748252)
		(width 0.1651)
		(layer "In11.Cu")
		(net "P5E_PEX1_STN2_TX_DP<44>")
	)
	(segment
		(start 163.044886 -280.319988)
		(end 163.285678 -280.319988)
		(width 0.1143)
		(layer "In11.Cu")
		(net "P5E_PEX1_STN2_TX_DP<44>")
	)
	(segment
		(start 163.399978 -280.434288)
		(end 163.399978 -280.699718)
		(width 0.1143)
		(layer "In11.Cu")
		(net "P5E_PEX1_STN2_TX_DP<44>")
	)
	(segment
		(start 140.21562 -29.996892)
		(end 140.201142 -30.121606)
		(width 0.1651)
		(layer "In11.Cu")
		(net "P5E_PEX1_STN2_TX_DP<44>")
	)
	(segment
		(start 162.829748 -271.473168)
		(end 162.829748 -280.10485)
		(width 0.1143)
		(layer "In11.Cu")
		(net "P5E_PEX1_STN2_TX_DP<44>")
	)
	(segment
		(start 154.507184 -50.411126)
		(end 155.205938 -62.140338)
		(width 0.1651)
		(layer "In11.Cu")
		(net "P5E_PEX1_STN2_TX_DP<44>")
	)
	(segment
		(start 162.784028 -271.427448)
		(end 162.829748 -271.473168)
		(width 0.1143)
		(layer "In11.Cu")
		(net "P5E_PEX1_STN2_TX_DP<44>")
	)
	(segment
		(start 138.17346 -28.823412)
		(end 139.826238 -29.505402)
		(width 0.1651)
		(layer "In11.Cu")
		(net "P5E_PEX1_STN2_TX_DP<44>")
	)
	(segment
		(start 151.79167 -44.601638)
		(end 153.77922 -48.256952)
		(width 0.1651)
		(layer "In11.Cu")
		(net "P5E_PEX1_STN2_TX_DP<44>")
	)
	(segment
		(start 135.70458 -28.823412)
		(end 136.69645 -28.823412)
		(width 0.1651)
		(layer "In11.Cu")
		(net "P5E_PEX1_STN2_TX_DP<44>")
	)
	(segment
		(start 137.28065 -28.912312)
		(end 137.36955 -28.823412)
		(width 0.1651)
		(layer "In11.Cu")
		(net "P5E_PEX1_STN2_TX_DP<44>")
	)
	(segment
		(start 140.633958 -30.52445)
		(end 151.79167 -44.601638)
		(width 0.1651)
		(layer "In11.Cu")
		(net "P5E_PEX1_STN2_TX_DP<44>")
	)
	(segment
		(start 136.69645 -28.823412)
		(end 136.78535 -28.912312)
		(width 0.1651)
		(layer "In11.Cu")
		(net "P5E_PEX1_STN2_TX_DP<44>")
	)
	(segment
		(start 162.784028 -270.748252)
		(end 162.784028 -271.399)
		(width 0.1651)
		(layer "In11.Cu")
		(net "P5E_PEX1_STN2_TX_DP<44>")
	)
	(segment
		(start 315.448442 -155.7909)
		(end 315.128148 -156.111194)
		(width 0.13462)
		(layer "F.Cu")
		(net "P5E_PEX2_STN0_TX_DP<15>")
	)
	(segment
		(start 316.079378 -155.7909)
		(end 315.448442 -155.7909)
		(width 0.13462)
		(layer "F.Cu")
		(net "P5E_PEX2_STN0_TX_DP<15>")
	)
	(segment
		(start 316.374272 -156.085794)
		(end 316.079378 -155.7909)
		(width 0.13462)
		(layer "F.Cu")
		(net "P5E_PEX2_STN0_TX_DP<15>")
	)
	(segment
		(start 317.575184 -156.096208)
		(end 317.575184 -156.49575)
		(width 0.1651)
		(layer "In9.Cu")
		(net "P5E_PEX2_STN0_TX_DP<15>")
	)
	(segment
		(start 316.179454 -158.913068)
		(end 309.111396 -171.156122)
		(width 0.1651)
		(layer "In9.Cu")
		(net "P5E_PEX2_STN0_TX_DP<15>")
	)
	(segment
		(start 316.763654 -157.901132)
		(end 316.516258 -158.329884)
		(width 0.1651)
		(layer "In9.Cu")
		(net "P5E_PEX2_STN0_TX_DP<15>")
	)
	(segment
		(start 307.049678 -278.534368)
		(end 307.049678 -278.799798)
		(width 0.1143)
		(layer "In9.Cu")
		(net "P5E_PEX2_STN0_TX_DP<15>")
	)
	(segment
		(start 307.590952 -176.846738)
		(end 303.779682 -220.410278)
		(width 0.1651)
		(layer "In9.Cu")
		(net "P5E_PEX2_STN0_TX_DP<15>")
	)
	(segment
		(start 316.146688 -158.791656)
		(end 316.179454 -158.913068)
		(width 0.1651)
		(layer "In9.Cu")
		(net "P5E_PEX2_STN0_TX_DP<15>")
	)
	(segment
		(start 316.979046 -157.350714)
		(end 316.731142 -157.77972)
		(width 0.1651)
		(layer "In9.Cu")
		(net "P5E_PEX2_STN0_TX_DP<15>")
	)
	(segment
		(start 316.731142 -157.77972)
		(end 316.763654 -157.901132)
		(width 0.1651)
		(layer "In9.Cu")
		(net "P5E_PEX2_STN0_TX_DP<15>")
	)
	(segment
		(start 317.27394 -155.794964)
		(end 317.575184 -156.096208)
		(width 0.1651)
		(layer "In9.Cu")
		(net "P5E_PEX2_STN0_TX_DP<15>")
	)
	(segment
		(start 303.779682 -220.410278)
		(end 304.663856 -230.515922)
		(width 0.1651)
		(layer "In9.Cu")
		(net "P5E_PEX2_STN0_TX_DP<15>")
	)
	(segment
		(start 306.433982 -271.471898)
		(end 306.433982 -271.500346)
		(width 0.1143)
		(layer "In9.Cu")
		(net "P5E_PEX2_STN0_TX_DP<15>")
	)
	(segment
		(start 316.394592 -158.362396)
		(end 316.146688 -158.791656)
		(width 0.1651)
		(layer "In9.Cu")
		(net "P5E_PEX2_STN0_TX_DP<15>")
	)
	(segment
		(start 316.516258 -158.329884)
		(end 316.394592 -158.362396)
		(width 0.1651)
		(layer "In9.Cu")
		(net "P5E_PEX2_STN0_TX_DP<15>")
	)
	(segment
		(start 307.590698 -176.846738)
		(end 307.590952 -176.846738)
		(width 0.1651)
		(layer "In9.Cu")
		(net "P5E_PEX2_STN0_TX_DP<15>")
	)
	(segment
		(start 306.935378 -278.420068)
		(end 307.049678 -278.534368)
		(width 0.1143)
		(layer "In9.Cu")
		(net "P5E_PEX2_STN0_TX_DP<15>")
	)
	(segment
		(start 307.30825 -267.41755)
		(end 306.433982 -269.528798)
		(width 0.1651)
		(layer "In9.Cu")
		(net "P5E_PEX2_STN0_TX_DP<15>")
	)
	(segment
		(start 316.374272 -156.085794)
		(end 316.665102 -155.794964)
		(width 0.1651)
		(layer "In9.Cu")
		(net "P5E_PEX2_STN0_TX_DP<15>")
	)
	(segment
		(start 307.30825 -260.7437)
		(end 307.30825 -267.41755)
		(width 0.1651)
		(layer "In9.Cu")
		(net "P5E_PEX2_STN0_TX_DP<15>")
	)
	(segment
		(start 307.592984 -176.821846)
		(end 307.590698 -176.846738)
		(width 0.1651)
		(layer "In9.Cu")
		(net "P5E_PEX2_STN0_TX_DP<15>")
	)
	(segment
		(start 306.433982 -269.528798)
		(end 306.433982 -271.471898)
		(width 0.1651)
		(layer "In9.Cu")
		(net "P5E_PEX2_STN0_TX_DP<15>")
	)
	(segment
		(start 316.665102 -155.794964)
		(end 317.27394 -155.794964)
		(width 0.1651)
		(layer "In9.Cu")
		(net "P5E_PEX2_STN0_TX_DP<15>")
	)
	(segment
		(start 306.479702 -271.546066)
		(end 306.479702 -278.205184)
		(width 0.1143)
		(layer "In9.Cu")
		(net "P5E_PEX2_STN0_TX_DP<15>")
	)
	(segment
		(start 317.100458 -157.317948)
		(end 316.979046 -157.350714)
		(width 0.1651)
		(layer "In9.Cu")
		(net "P5E_PEX2_STN0_TX_DP<15>")
	)
	(segment
		(start 309.111396 -171.156122)
		(end 307.592984 -176.821846)
		(width 0.1651)
		(layer "In9.Cu")
		(net "P5E_PEX2_STN0_TX_DP<15>")
	)
	(segment
		(start 306.479702 -278.205184)
		(end 306.694586 -278.420068)
		(width 0.1143)
		(layer "In9.Cu")
		(net "P5E_PEX2_STN0_TX_DP<15>")
	)
	(segment
		(start 304.663856 -230.515922)
		(end 307.30825 -260.7437)
		(width 0.1651)
		(layer "In9.Cu")
		(net "P5E_PEX2_STN0_TX_DP<15>")
	)
	(segment
		(start 306.694586 -278.420068)
		(end 306.935378 -278.420068)
		(width 0.1143)
		(layer "In9.Cu")
		(net "P5E_PEX2_STN0_TX_DP<15>")
	)
	(segment
		(start 306.433982 -271.500346)
		(end 306.479702 -271.546066)
		(width 0.1143)
		(layer "In9.Cu")
		(net "P5E_PEX2_STN0_TX_DP<15>")
	)
	(segment
		(start 317.575184 -156.49575)
		(end 317.100458 -157.317948)
		(width 0.1651)
		(layer "In9.Cu")
		(net "P5E_PEX2_STN0_TX_DP<15>")
	)
	(segment
		(start 337.943444 -342.734138)
		(end 338.238084 -342.439498)
		(width 0.13462)
		(layer "F.Cu")
		(net "P5E_PEX2_STN6_TX_DN<100>")
	)
	(segment
		(start 338.263484 -343.685622)
		(end 337.943444 -343.365582)
		(width 0.13462)
		(layer "F.Cu")
		(net "P5E_PEX2_STN6_TX_DN<100>")
	)
	(segment
		(start 337.943444 -343.365582)
		(end 337.943444 -342.734138)
		(width 0.13462)
		(layer "F.Cu")
		(net "P5E_PEX2_STN6_TX_DN<100>")
	)
	(segment
		(start 338.238084 -342.439498)
		(end 337.947254 -342.148668)
		(width 0.1651)
		(layer "In13.Cu")
		(net "P5E_PEX2_STN6_TX_DN<100>")
	)
	(segment
		(start 297.359832 -325.381112)
		(end 296.873422 -325.286116)
		(width 0.1651)
		(layer "In13.Cu")
		(net "P5E_PEX2_STN6_TX_DN<100>")
	)
	(segment
		(start 285.770066 -313.673744)
		(end 285.873698 -313.570112)
		(width 0.1143)
		(layer "In13.Cu")
		(net "P5E_PEX2_STN6_TX_DN<100>")
	)
	(segment
		(start 296.873422 -325.286116)
		(end 296.754296 -325.366126)
		(width 0.1651)
		(layer "In13.Cu")
		(net "P5E_PEX2_STN6_TX_DN<100>")
	)
	(segment
		(start 297.440096 -325.500746)
		(end 297.359832 -325.381112)
		(width 0.1651)
		(layer "In13.Cu")
		(net "P5E_PEX2_STN6_TX_DN<100>")
	)
	(segment
		(start 337.947254 -342.148668)
		(end 337.947254 -341.633302)
		(width 0.1651)
		(layer "In13.Cu")
		(net "P5E_PEX2_STN6_TX_DN<100>")
	)
	(segment
		(start 286.149796 -313.684412)
		(end 286.149796 -313.949842)
		(width 0.1143)
		(layer "In13.Cu")
		(net "P5E_PEX2_STN6_TX_DN<100>")
	)
	(segment
		(start 286.096456 -322.72351)
		(end 285.815786 -322.04279)
		(width 0.1651)
		(layer "In13.Cu")
		(net "P5E_PEX2_STN6_TX_DN<100>")
	)
	(segment
		(start 286.035496 -313.570112)
		(end 286.149796 -313.684412)
		(width 0.1143)
		(layer "In13.Cu")
		(net "P5E_PEX2_STN6_TX_DN<100>")
	)
	(segment
		(start 337.882484 -341.554816)
		(end 337.882484 -341.55507)
		(width 0.1651)
		(layer "In13.Cu")
		(net "P5E_PEX2_STN6_TX_DN<100>")
	)
	(segment
		(start 296.754296 -325.366126)
		(end 286.786828 -323.413628)
		(width 0.1651)
		(layer "In13.Cu")
		(net "P5E_PEX2_STN6_TX_DN<100>")
	)
	(segment
		(start 285.815786 -322.04279)
		(end 285.815786 -319.995296)
		(width 0.1651)
		(layer "In13.Cu")
		(net "P5E_PEX2_STN6_TX_DN<100>")
	)
	(segment
		(start 315.025786 -328.945748)
		(end 297.440096 -325.500746)
		(width 0.1651)
		(layer "In13.Cu")
		(net "P5E_PEX2_STN6_TX_DN<100>")
	)
	(segment
		(start 285.770066 -319.921128)
		(end 285.770066 -313.673744)
		(width 0.1143)
		(layer "In13.Cu")
		(net "P5E_PEX2_STN6_TX_DN<100>")
	)
	(segment
		(start 337.5533 -341.15756)
		(end 332.9686 -337.058)
		(width 0.1651)
		(layer "In13.Cu")
		(net "P5E_PEX2_STN6_TX_DN<100>")
	)
	(segment
		(start 285.873698 -313.570112)
		(end 286.035496 -313.570112)
		(width 0.1143)
		(layer "In13.Cu")
		(net "P5E_PEX2_STN6_TX_DN<100>")
	)
	(segment
		(start 332.9686 -337.058)
		(end 315.025786 -328.945748)
		(width 0.1651)
		(layer "In13.Cu")
		(net "P5E_PEX2_STN6_TX_DN<100>")
	)
	(segment
		(start 286.786828 -323.413628)
		(end 286.096456 -322.72351)
		(width 0.1651)
		(layer "In13.Cu")
		(net "P5E_PEX2_STN6_TX_DN<100>")
	)
	(segment
		(start 337.882484 -341.55507)
		(end 337.5533 -341.15756)
		(width 0.1651)
		(layer "In13.Cu")
		(net "P5E_PEX2_STN6_TX_DN<100>")
	)
	(segment
		(start 337.947254 -341.633302)
		(end 337.882484 -341.554816)
		(width 0.1651)
		(layer "In13.Cu")
		(net "P5E_PEX2_STN6_TX_DN<100>")
	)
	(segment
		(start 285.815786 -319.966848)
		(end 285.770066 -319.921128)
		(width 0.1143)
		(layer "In13.Cu")
		(net "P5E_PEX2_STN6_TX_DN<100>")
	)
	(segment
		(start 285.815786 -319.995296)
		(end 285.815786 -319.966848)
		(width 0.1143)
		(layer "In13.Cu")
		(net "P5E_PEX2_STN6_TX_DN<100>")
	)
	(segment
		(start 429.538384 -122.865388)
		(end 428.905416 -122.865388)
		(width 0.13462)
		(layer "F.Cu")
		(net "P5E_PEX3_STN0_TX_DP<2>")
	)
	(segment
		(start 429.832262 -123.159266)
		(end 429.538384 -122.865388)
		(width 0.13462)
		(layer "F.Cu")
		(net "P5E_PEX3_STN0_TX_DP<2>")
	)
	(segment
		(start 428.905416 -122.865388)
		(end 428.586138 -123.184666)
		(width 0.13462)
		(layer "F.Cu")
		(net "P5E_PEX3_STN0_TX_DP<2>")
	)
	(segment
		(start 435.793134 -128.145032)
		(end 435.73827 -128.277874)
		(width 0.1651)
		(layer "In9.Cu")
		(net "P5E_PEX3_STN0_TX_DP<2>")
	)
	(segment
		(start 436.473854 -129.788158)
		(end 436.64886 -130.210306)
		(width 0.1651)
		(layer "In9.Cu")
		(net "P5E_PEX3_STN0_TX_DP<2>")
	)
	(segment
		(start 434.882544 -126.2126)
		(end 435.05755 -126.635256)
		(width 0.1651)
		(layer "In9.Cu")
		(net "P5E_PEX3_STN0_TX_DP<2>")
	)
	(segment
		(start 430.123092 -122.868436)
		(end 431.6476 -122.868436)
		(width 0.1651)
		(layer "In9.Cu")
		(net "P5E_PEX3_STN0_TX_DP<2>")
	)
	(segment
		(start 435.485286 -127.66802)
		(end 435.618382 -127.722884)
		(width 0.1651)
		(layer "In9.Cu")
		(net "P5E_PEX3_STN0_TX_DP<2>")
	)
	(segment
		(start 432.2064 -122.970036)
		(end 432.308 -122.868436)
		(width 0.1651)
		(layer "In9.Cu")
		(net "P5E_PEX3_STN0_TX_DP<2>")
	)
	(segment
		(start 438.277 -133.421628)
		(end 446.254124 -152.6794)
		(width 0.1651)
		(layer "In9.Cu")
		(net "P5E_PEX3_STN0_TX_DP<2>")
	)
	(segment
		(start 434.745892 -125.617478)
		(end 434.937408 -126.080012)
		(width 0.1651)
		(layer "In9.Cu")
		(net "P5E_PEX3_STN0_TX_DP<2>")
	)
	(segment
		(start 435.913276 -128.70053)
		(end 436.046372 -128.755394)
		(width 0.1651)
		(layer "In9.Cu")
		(net "P5E_PEX3_STN0_TX_DP<2>")
	)
	(segment
		(start 432.733704 -221.67723)
		(end 432.735736 -221.701614)
		(width 0.1651)
		(layer "In9.Cu")
		(net "P5E_PEX3_STN0_TX_DP<2>")
	)
	(segment
		(start 446.363852 -267.760958)
		(end 446.770506 -272.403824)
		(width 0.1651)
		(layer "In9.Cu")
		(net "P5E_PEX3_STN0_TX_DP<2>")
	)
	(segment
		(start 446.770506 -272.403824)
		(end 445.416686 -275.671534)
		(width 0.1651)
		(layer "In9.Cu")
		(net "P5E_PEX3_STN0_TX_DP<2>")
	)
	(segment
		(start 435.31028 -127.245364)
		(end 435.485286 -127.66802)
		(width 0.1651)
		(layer "In9.Cu")
		(net "P5E_PEX3_STN0_TX_DP<2>")
	)
	(segment
		(start 436.166006 -129.310638)
		(end 436.341012 -129.733294)
		(width 0.1651)
		(layer "In9.Cu")
		(net "P5E_PEX3_STN0_TX_DP<2>")
	)
	(segment
		(start 432.143408 -285.829756)
		(end 425.644818 -285.829756)
		(width 0.1143)
		(layer "In9.Cu")
		(net "P5E_PEX3_STN0_TX_DP<2>")
	)
	(segment
		(start 434.63083 -125.040136)
		(end 434.745892 -125.617478)
		(width 0.1651)
		(layer "In9.Cu")
		(net "P5E_PEX3_STN0_TX_DP<2>")
	)
	(segment
		(start 425.31538 -286.399986)
		(end 425.04995 -286.399986)
		(width 0.1143)
		(layer "In9.Cu")
		(net "P5E_PEX3_STN0_TX_DP<2>")
	)
	(segment
		(start 431.7492 -122.970036)
		(end 432.2064 -122.970036)
		(width 0.1651)
		(layer "In9.Cu")
		(net "P5E_PEX3_STN0_TX_DP<2>")
	)
	(segment
		(start 436.046118 -128.755648)
		(end 436.221124 -129.177796)
		(width 0.1651)
		(layer "In9.Cu")
		(net "P5E_PEX3_STN0_TX_DP<2>")
	)
	(segment
		(start 431.6476 -122.868436)
		(end 431.7492 -122.970036)
		(width 0.1651)
		(layer "In9.Cu")
		(net "P5E_PEX3_STN0_TX_DP<2>")
	)
	(segment
		(start 445.416686 -275.671534)
		(end 436.454296 -284.633924)
		(width 0.1651)
		(layer "In9.Cu")
		(net "P5E_PEX3_STN0_TX_DP<2>")
	)
	(segment
		(start 438.024016 -132.811012)
		(end 437.969152 -132.943854)
		(width 0.1651)
		(layer "In9.Cu")
		(net "P5E_PEX3_STN0_TX_DP<2>")
	)
	(segment
		(start 436.474108 -129.788158)
		(end 436.473854 -129.788158)
		(width 0.1651)
		(layer "In9.Cu")
		(net "P5E_PEX3_STN0_TX_DP<2>")
	)
	(segment
		(start 432.900836 -122.868436)
		(end 434.318918 -124.286518)
		(width 0.1651)
		(layer "In9.Cu")
		(net "P5E_PEX3_STN0_TX_DP<2>")
	)
	(segment
		(start 436.593742 -130.343148)
		(end 436.768748 -130.765804)
		(width 0.1651)
		(layer "In9.Cu")
		(net "P5E_PEX3_STN0_TX_DP<2>")
	)
	(segment
		(start 435.365398 -127.112522)
		(end 435.31028 -127.245364)
		(width 0.1651)
		(layer "In9.Cu")
		(net "P5E_PEX3_STN0_TX_DP<2>")
	)
	(segment
		(start 433.678076 -285.784036)
		(end 432.217576 -285.784036)
		(width 0.1651)
		(layer "In9.Cu")
		(net "P5E_PEX3_STN0_TX_DP<2>")
	)
	(segment
		(start 432.735736 -221.701614)
		(end 432.73599 -221.701614)
		(width 0.1651)
		(layer "In9.Cu")
		(net "P5E_PEX3_STN0_TX_DP<2>")
	)
	(segment
		(start 436.768748 -130.765804)
		(end 436.901844 -130.820668)
		(width 0.1651)
		(layer "In9.Cu")
		(net "P5E_PEX3_STN0_TX_DP<2>")
	)
	(segment
		(start 437.969152 -132.943854)
		(end 438.144158 -133.36651)
		(width 0.1651)
		(layer "In9.Cu")
		(net "P5E_PEX3_STN0_TX_DP<2>")
	)
	(segment
		(start 436.221124 -129.177796)
		(end 436.166006 -129.310638)
		(width 0.1651)
		(layer "In9.Cu")
		(net "P5E_PEX3_STN0_TX_DP<2>")
	)
	(segment
		(start 446.05067 -160.435544)
		(end 437.404256 -175.418242)
		(width 0.1651)
		(layer "In9.Cu")
		(net "P5E_PEX3_STN0_TX_DP<2>")
	)
	(segment
		(start 436.454296 -284.633924)
		(end 433.678076 -285.784036)
		(width 0.1651)
		(layer "In9.Cu")
		(net "P5E_PEX3_STN0_TX_DP<2>")
	)
	(segment
		(start 437.404256 -175.418242)
		(end 436.479442 -178.865784)
		(width 0.1651)
		(layer "In9.Cu")
		(net "P5E_PEX3_STN0_TX_DP<2>")
	)
	(segment
		(start 435.618382 -127.722884)
		(end 435.793134 -128.145032)
		(width 0.1651)
		(layer "In9.Cu")
		(net "P5E_PEX3_STN0_TX_DP<2>")
	)
	(segment
		(start 425.42968 -286.044894)
		(end 425.42968 -286.285686)
		(width 0.1143)
		(layer "In9.Cu")
		(net "P5E_PEX3_STN0_TX_DP<2>")
	)
	(segment
		(start 425.644818 -285.829756)
		(end 425.42968 -286.044894)
		(width 0.1143)
		(layer "In9.Cu")
		(net "P5E_PEX3_STN0_TX_DP<2>")
	)
	(segment
		(start 435.73827 -128.277874)
		(end 435.913276 -128.70053)
		(width 0.1651)
		(layer "In9.Cu")
		(net "P5E_PEX3_STN0_TX_DP<2>")
	)
	(segment
		(start 432.189128 -285.784036)
		(end 432.143408 -285.829756)
		(width 0.1143)
		(layer "In9.Cu")
		(net "P5E_PEX3_STN0_TX_DP<2>")
	)
	(segment
		(start 434.937408 -126.080012)
		(end 434.882544 -126.2126)
		(width 0.1651)
		(layer "In9.Cu")
		(net "P5E_PEX3_STN0_TX_DP<2>")
	)
	(segment
		(start 434.318918 -124.286518)
		(end 434.63083 -125.040136)
		(width 0.1651)
		(layer "In9.Cu")
		(net "P5E_PEX3_STN0_TX_DP<2>")
	)
	(segment
		(start 436.901844 -130.820668)
		(end 437.34101 -131.88061)
		(width 0.1651)
		(layer "In9.Cu")
		(net "P5E_PEX3_STN0_TX_DP<2>")
	)
	(segment
		(start 432.73599 -221.701614)
		(end 435.216808 -250.126246)
		(width 0.1651)
		(layer "In9.Cu")
		(net "P5E_PEX3_STN0_TX_DP<2>")
	)
	(segment
		(start 432.308 -122.868436)
		(end 432.900836 -122.868436)
		(width 0.1651)
		(layer "In9.Cu")
		(net "P5E_PEX3_STN0_TX_DP<2>")
	)
	(segment
		(start 436.046372 -128.755394)
		(end 436.046118 -128.755648)
		(width 0.1651)
		(layer "In9.Cu")
		(net "P5E_PEX3_STN0_TX_DP<2>")
	)
	(segment
		(start 438.144158 -133.36651)
		(end 438.277 -133.421628)
		(width 0.1651)
		(layer "In9.Cu")
		(net "P5E_PEX3_STN0_TX_DP<2>")
	)
	(segment
		(start 432.217576 -285.784036)
		(end 432.189128 -285.784036)
		(width 0.1143)
		(layer "In9.Cu")
		(net "P5E_PEX3_STN0_TX_DP<2>")
	)
	(segment
		(start 446.254124 -152.6794)
		(end 446.254124 -159.674306)
		(width 0.1651)
		(layer "In9.Cu")
		(net "P5E_PEX3_STN0_TX_DP<2>")
	)
	(segment
		(start 445.325246 -265.25347)
		(end 446.363852 -267.760958)
		(width 0.1651)
		(layer "In9.Cu")
		(net "P5E_PEX3_STN0_TX_DP<2>")
	)
	(segment
		(start 425.42968 -286.285686)
		(end 425.31538 -286.399986)
		(width 0.1143)
		(layer "In9.Cu")
		(net "P5E_PEX3_STN0_TX_DP<2>")
	)
	(segment
		(start 429.832262 -123.159266)
		(end 430.123092 -122.868436)
		(width 0.1651)
		(layer "In9.Cu")
		(net "P5E_PEX3_STN0_TX_DP<2>")
	)
	(segment
		(start 436.341012 -129.733294)
		(end 436.474108 -129.788158)
		(width 0.1651)
		(layer "In9.Cu")
		(net "P5E_PEX3_STN0_TX_DP<2>")
	)
	(segment
		(start 437.849264 -132.388864)
		(end 438.024016 -132.811012)
		(width 0.1651)
		(layer "In9.Cu")
		(net "P5E_PEX3_STN0_TX_DP<2>")
	)
	(segment
		(start 436.64886 -130.210306)
		(end 436.593742 -130.343148)
		(width 0.1651)
		(layer "In9.Cu")
		(net "P5E_PEX3_STN0_TX_DP<2>")
	)
	(segment
		(start 436.479442 -178.865784)
		(end 432.733704 -221.67723)
		(width 0.1651)
		(layer "In9.Cu")
		(net "P5E_PEX3_STN0_TX_DP<2>")
	)
	(segment
		(start 446.254124 -159.674306)
		(end 446.05067 -160.435544)
		(width 0.1651)
		(layer "In9.Cu")
		(net "P5E_PEX3_STN0_TX_DP<2>")
	)
	(segment
		(start 435.216808 -250.126246)
		(end 445.325246 -265.25347)
		(width 0.1651)
		(layer "In9.Cu")
		(net "P5E_PEX3_STN0_TX_DP<2>")
	)
	(segment
		(start 437.34101 -131.88061)
		(end 437.849264 -132.388864)
		(width 0.1651)
		(layer "In9.Cu")
		(net "P5E_PEX3_STN0_TX_DP<2>")
	)
	(segment
		(start 435.190392 -126.690374)
		(end 435.365398 -127.112522)
		(width 0.1651)
		(layer "In9.Cu")
		(net "P5E_PEX3_STN0_TX_DP<2>")
	)
	(segment
		(start 435.05755 -126.635256)
		(end 435.190392 -126.690374)
		(width 0.1651)
		(layer "In9.Cu")
		(net "P5E_PEX3_STN0_TX_DP<2>")
	)
	(segment
		(start 428.517304 -343.365074)
		(end 428.517304 -342.734646)
		(width 0.13462)
		(layer "F.Cu")
		(net "P5E_PEX3_STN7_TX_DN<120>")
	)
	(segment
		(start 428.837852 -343.685622)
		(end 428.517304 -343.365074)
		(width 0.13462)
		(layer "F.Cu")
		(net "P5E_PEX3_STN7_TX_DN<120>")
	)
	(segment
		(start 428.517304 -342.734646)
		(end 428.812452 -342.439498)
		(width 0.13462)
		(layer "F.Cu")
		(net "P5E_PEX3_STN7_TX_DN<120>")
	)
	(segment
		(start 382.427988 -309.687722)
		(end 382.427988 -309.561992)
		(width 0.1651)
		(layer "In11.Cu")
		(net "P5E_PEX3_STN7_TX_DN<120>")
	)
	(segment
		(start 382.077722 -326.835516)
		(end 381.594106 -326.72655)
		(width 0.1651)
		(layer "In11.Cu")
		(net "P5E_PEX3_STN7_TX_DN<120>")
	)
	(segment
		(start 373.29999 -319.067434)
		(end 374.060212 -317.929768)
		(width 0.1651)
		(layer "In11.Cu")
		(net "P5E_PEX3_STN7_TX_DN<120>")
	)
	(segment
		(start 390.165336 -309.199788)
		(end 389.899906 -309.199788)
		(width 0.1143)
		(layer "In11.Cu")
		(net "P5E_PEX3_STN7_TX_DN<120>")
	)
	(segment
		(start 424.284902 -338.08924)
		(end 424.284902 -338.089494)
		(width 0.1651)
		(layer "In11.Cu")
		(net "P5E_PEX3_STN7_TX_DN<120>")
	)
	(segment
		(start 383.968752 -308.865778)
		(end 383.9972 -308.865778)
		(width 0.1143)
		(layer "In11.Cu")
		(net "P5E_PEX3_STN7_TX_DN<120>")
	)
	(segment
		(start 390.176004 -308.820058)
		(end 390.279636 -308.92369)
		(width 0.1143)
		(layer "In11.Cu")
		(net "P5E_PEX3_STN7_TX_DN<120>")
	)
	(segment
		(start 382.838198 -309.151782)
		(end 383.528824 -308.865778)
		(width 0.1651)
		(layer "In11.Cu")
		(net "P5E_PEX3_STN7_TX_DN<120>")
	)
	(segment
		(start 374.060212 -317.929768)
		(end 377.175268 -314.814712)
		(width 0.1651)
		(layer "In11.Cu")
		(net "P5E_PEX3_STN7_TX_DN<120>")
	)
	(segment
		(start 424.284902 -338.089494)
		(end 420.735506 -335.643474)
		(width 0.1651)
		(layer "In11.Cu")
		(net "P5E_PEX3_STN7_TX_DN<120>")
	)
	(segment
		(start 381.60198 -310.388)
		(end 381.951992 -310.037988)
		(width 0.1651)
		(layer "In11.Cu")
		(net "P5E_PEX3_STN7_TX_DN<120>")
	)
	(segment
		(start 372.9228 -319.978278)
		(end 373.017288 -319.75044)
		(width 0.1651)
		(layer "In11.Cu")
		(net "P5E_PEX3_STN7_TX_DN<120>")
	)
	(segment
		(start 384.04292 -308.820058)
		(end 390.176004 -308.820058)
		(width 0.1143)
		(layer "In11.Cu")
		(net "P5E_PEX3_STN7_TX_DN<120>")
	)
	(segment
		(start 381.25146 -310.86425)
		(end 381.60198 -310.51373)
		(width 0.1651)
		(layer "In11.Cu")
		(net "P5E_PEX3_STN7_TX_DN<120>")
	)
	(segment
		(start 390.279636 -309.085488)
		(end 390.165336 -309.199788)
		(width 0.1143)
		(layer "In11.Cu")
		(net "P5E_PEX3_STN7_TX_DN<120>")
	)
	(segment
		(start 383.21742 -327.092564)
		(end 382.734058 -326.983598)
		(width 0.1651)
		(layer "In11.Cu")
		(net "P5E_PEX3_STN7_TX_DN<120>")
	)
	(segment
		(start 377.651518 -314.464192)
		(end 377.651518 -314.338462)
		(width 0.1651)
		(layer "In11.Cu")
		(net "P5E_PEX3_STN7_TX_DN<120>")
	)
	(segment
		(start 381.48768 -326.79386)
		(end 376.546872 -325.679816)
		(width 0.1651)
		(layer "In11.Cu")
		(net "P5E_PEX3_STN7_TX_DN<120>")
	)
	(segment
		(start 428.521622 -341.633048)
		(end 427.8376 -340.5378)
		(width 0.1651)
		(layer "In11.Cu")
		(net "P5E_PEX3_STN7_TX_DN<120>")
	)
	(segment
		(start 372.9228 -321.925188)
		(end 372.9228 -319.978278)
		(width 0.1651)
		(layer "In11.Cu")
		(net "P5E_PEX3_STN7_TX_DN<120>")
	)
	(segment
		(start 382.144778 -326.941942)
		(end 382.077722 -326.835516)
		(width 0.1651)
		(layer "In11.Cu")
		(net "P5E_PEX3_STN7_TX_DN<120>")
	)
	(segment
		(start 381.594106 -326.72655)
		(end 381.487934 -326.793606)
		(width 0.1651)
		(layer "In11.Cu")
		(net "P5E_PEX3_STN7_TX_DN<120>")
	)
	(segment
		(start 428.812452 -342.439498)
		(end 428.521622 -342.148668)
		(width 0.1651)
		(layer "In11.Cu")
		(net "P5E_PEX3_STN7_TX_DN<120>")
	)
	(segment
		(start 376.546872 -325.679816)
		(end 374.672098 -324.646798)
		(width 0.1651)
		(layer "In11.Cu")
		(net "P5E_PEX3_STN7_TX_DN<120>")
	)
	(segment
		(start 381.60198 -310.51373)
		(end 381.60198 -310.388)
		(width 0.1651)
		(layer "In11.Cu")
		(net "P5E_PEX3_STN7_TX_DN<120>")
	)
	(segment
		(start 378.12726 -313.98845)
		(end 378.47778 -313.63793)
		(width 0.1651)
		(layer "In11.Cu")
		(net "P5E_PEX3_STN7_TX_DN<120>")
	)
	(segment
		(start 382.734058 -326.983598)
		(end 382.627886 -327.050654)
		(width 0.1651)
		(layer "In11.Cu")
		(net "P5E_PEX3_STN7_TX_DN<120>")
	)
	(segment
		(start 381.487934 -326.793606)
		(end 381.48768 -326.79386)
		(width 0.1651)
		(layer "In11.Cu")
		(net "P5E_PEX3_STN7_TX_DN<120>")
	)
	(segment
		(start 382.077722 -310.037988)
		(end 382.427988 -309.687722)
		(width 0.1651)
		(layer "In11.Cu")
		(net "P5E_PEX3_STN7_TX_DN<120>")
	)
	(segment
		(start 420.735506 -335.643474)
		(end 383.28473 -327.19899)
		(width 0.1651)
		(layer "In11.Cu")
		(net "P5E_PEX3_STN7_TX_DN<120>")
	)
	(segment
		(start 378.47778 -313.5122)
		(end 378.827792 -313.162188)
		(width 0.1651)
		(layer "In11.Cu")
		(net "P5E_PEX3_STN7_TX_DN<120>")
	)
	(segment
		(start 373.017288 -319.75044)
		(end 373.29999 -319.067434)
		(width 0.1651)
		(layer "In11.Cu")
		(net "P5E_PEX3_STN7_TX_DN<120>")
	)
	(segment
		(start 382.627886 -327.050654)
		(end 382.144778 -326.941942)
		(width 0.1651)
		(layer "In11.Cu")
		(net "P5E_PEX3_STN7_TX_DN<120>")
	)
	(segment
		(start 377.175268 -314.814712)
		(end 377.300998 -314.814712)
		(width 0.1651)
		(layer "In11.Cu")
		(net "P5E_PEX3_STN7_TX_DN<120>")
	)
	(segment
		(start 378.00153 -313.98845)
		(end 378.12726 -313.98845)
		(width 0.1651)
		(layer "In11.Cu")
		(net "P5E_PEX3_STN7_TX_DN<120>")
	)
	(segment
		(start 378.953522 -313.162188)
		(end 379.303788 -312.811922)
		(width 0.1651)
		(layer "In11.Cu")
		(net "P5E_PEX3_STN7_TX_DN<120>")
	)
	(segment
		(start 382.427988 -309.561992)
		(end 382.838198 -309.151782)
		(width 0.1651)
		(layer "In11.Cu")
		(net "P5E_PEX3_STN7_TX_DN<120>")
	)
	(segment
		(start 377.300998 -314.814712)
		(end 377.651518 -314.464192)
		(width 0.1651)
		(layer "In11.Cu")
		(net "P5E_PEX3_STN7_TX_DN<120>")
	)
	(segment
		(start 378.827792 -313.162188)
		(end 378.953522 -313.162188)
		(width 0.1651)
		(layer "In11.Cu")
		(net "P5E_PEX3_STN7_TX_DN<120>")
	)
	(segment
		(start 379.303788 -312.686192)
		(end 381.12573 -310.86425)
		(width 0.1651)
		(layer "In11.Cu")
		(net "P5E_PEX3_STN7_TX_DN<120>")
	)
	(segment
		(start 377.651518 -314.338462)
		(end 378.00153 -313.98845)
		(width 0.1651)
		(layer "In11.Cu")
		(net "P5E_PEX3_STN7_TX_DN<120>")
	)
	(segment
		(start 383.28473 -327.19899)
		(end 383.21742 -327.092564)
		(width 0.1651)
		(layer "In11.Cu")
		(net "P5E_PEX3_STN7_TX_DN<120>")
	)
	(segment
		(start 428.521622 -342.148668)
		(end 428.521622 -341.633048)
		(width 0.1651)
		(layer "In11.Cu")
		(net "P5E_PEX3_STN7_TX_DN<120>")
	)
	(segment
		(start 390.279636 -308.92369)
		(end 390.279636 -309.085488)
		(width 0.1143)
		(layer "In11.Cu")
		(net "P5E_PEX3_STN7_TX_DN<120>")
	)
	(segment
		(start 383.528824 -308.865778)
		(end 383.968752 -308.865778)
		(width 0.1651)
		(layer "In11.Cu")
		(net "P5E_PEX3_STN7_TX_DN<120>")
	)
	(segment
		(start 374.672098 -324.646798)
		(end 373.610378 -323.585078)
		(width 0.1651)
		(layer "In11.Cu")
		(net "P5E_PEX3_STN7_TX_DN<120>")
	)
	(segment
		(start 373.610378 -323.585078)
		(end 372.9228 -321.925188)
		(width 0.1651)
		(layer "In11.Cu")
		(net "P5E_PEX3_STN7_TX_DN<120>")
	)
	(segment
		(start 427.8376 -340.5378)
		(end 424.284902 -338.08924)
		(width 0.1651)
		(layer "In11.Cu")
		(net "P5E_PEX3_STN7_TX_DN<120>")
	)
	(segment
		(start 378.47778 -313.63793)
		(end 378.47778 -313.5122)
		(width 0.1651)
		(layer "In11.Cu")
		(net "P5E_PEX3_STN7_TX_DN<120>")
	)
	(segment
		(start 381.951992 -310.037988)
		(end 382.077722 -310.037988)
		(width 0.1651)
		(layer "In11.Cu")
		(net "P5E_PEX3_STN7_TX_DN<120>")
	)
	(segment
		(start 379.303788 -312.811922)
		(end 379.303788 -312.686192)
		(width 0.1651)
		(layer "In11.Cu")
		(net "P5E_PEX3_STN7_TX_DN<120>")
	)
	(segment
		(start 381.12573 -310.86425)
		(end 381.25146 -310.86425)
		(width 0.1651)
		(layer "In11.Cu")
		(net "P5E_PEX3_STN7_TX_DN<120>")
	)
	(segment
		(start 383.9972 -308.865778)
		(end 384.04292 -308.820058)
		(width 0.1143)
		(layer "In11.Cu")
		(net "P5E_PEX3_STN7_TX_DN<120>")
	)
	(segment
		(start 178.025552 -350.685354)
		(end 177.705512 -350.365314)
		(width 0.13462)
		(layer "F.Cu")
		(net "P5E_PEX1_STN7_TX_C_DP<120>")
	)
	(segment
		(start 177.730912 -351.611438)
		(end 178.025552 -351.316798)
		(width 0.13462)
		(layer "F.Cu")
		(net "P5E_PEX1_STN7_TX_C_DP<120>")
	)
	(segment
		(start 178.025552 -351.316798)
		(end 178.025552 -350.685354)
		(width 0.13462)
		(layer "F.Cu")
		(net "P5E_PEX1_STN7_TX_C_DP<120>")
	)
	(segment
		(start 161.979864 -367.568734)
		(end 161.979864 -367.712498)
		(width 0.1651)
		(layer "In11.Cu")
		(net "P5E_PEX1_STN7_TX_C_DP<120>")
	)
	(segment
		(start 178.021742 -351.902268)
		(end 178.021742 -352.547936)
		(width 0.1651)
		(layer "In11.Cu")
		(net "P5E_PEX1_STN7_TX_C_DP<120>")
	)
	(segment
		(start 178.021742 -352.547936)
		(end 176.467262 -354.102416)
		(width 0.1651)
		(layer "In11.Cu")
		(net "P5E_PEX1_STN7_TX_C_DP<120>")
	)
	(segment
		(start 176.467262 -354.102416)
		(end 176.467262 -359.073196)
		(width 0.1651)
		(layer "In11.Cu")
		(net "P5E_PEX1_STN7_TX_C_DP<120>")
	)
	(segment
		(start 174.284894 -361.1118)
		(end 173.934374 -361.46232)
		(width 0.1651)
		(layer "In11.Cu")
		(net "P5E_PEX1_STN7_TX_C_DP<120>")
	)
	(segment
		(start 174.77867 -360.761788)
		(end 174.428658 -361.1118)
		(width 0.1651)
		(layer "In11.Cu")
		(net "P5E_PEX1_STN7_TX_C_DP<120>")
	)
	(segment
		(start 175.973486 -359.423208)
		(end 175.622966 -359.773728)
		(width 0.1651)
		(layer "In11.Cu")
		(net "P5E_PEX1_STN7_TX_C_DP<120>")
	)
	(segment
		(start 161.135568 -368.556794)
		(end 160.785556 -368.906806)
		(width 0.1651)
		(layer "In11.Cu")
		(net "P5E_PEX1_STN7_TX_C_DP<120>")
	)
	(segment
		(start 173.934374 -361.46232)
		(end 173.934374 -361.606084)
		(width 0.1651)
		(layer "In11.Cu")
		(net "P5E_PEX1_STN7_TX_C_DP<120>")
	)
	(segment
		(start 160.785556 -374.43918)
		(end 160.325562 -374.899174)
		(width 0.1651)
		(layer "In11.Cu")
		(net "P5E_PEX1_STN7_TX_C_DP<120>")
	)
	(segment
		(start 161.979864 -367.712498)
		(end 161.629852 -368.06251)
		(width 0.1651)
		(layer "In11.Cu")
		(net "P5E_PEX1_STN7_TX_C_DP<120>")
	)
	(segment
		(start 173.427898 -362.11256)
		(end 163.348924 -366.343438)
		(width 0.1651)
		(layer "In11.Cu")
		(net "P5E_PEX1_STN7_TX_C_DP<120>")
	)
	(segment
		(start 174.77867 -360.618024)
		(end 174.77867 -360.761788)
		(width 0.1651)
		(layer "In11.Cu")
		(net "P5E_PEX1_STN7_TX_C_DP<120>")
	)
	(segment
		(start 175.622966 -359.917492)
		(end 175.272954 -360.267504)
		(width 0.1651)
		(layer "In11.Cu")
		(net "P5E_PEX1_STN7_TX_C_DP<120>")
	)
	(segment
		(start 161.135568 -368.41303)
		(end 161.135568 -368.556794)
		(width 0.1651)
		(layer "In11.Cu")
		(net "P5E_PEX1_STN7_TX_C_DP<120>")
	)
	(segment
		(start 174.428658 -361.1118)
		(end 174.284894 -361.1118)
		(width 0.1651)
		(layer "In11.Cu")
		(net "P5E_PEX1_STN7_TX_C_DP<120>")
	)
	(segment
		(start 176.11725 -359.423208)
		(end 175.973486 -359.423208)
		(width 0.1651)
		(layer "In11.Cu")
		(net "P5E_PEX1_STN7_TX_C_DP<120>")
	)
	(segment
		(start 160.785556 -368.906806)
		(end 160.785556 -374.43918)
		(width 0.1651)
		(layer "In11.Cu")
		(net "P5E_PEX1_STN7_TX_C_DP<120>")
	)
	(segment
		(start 177.730912 -351.611438)
		(end 178.021742 -351.902268)
		(width 0.1651)
		(layer "In11.Cu")
		(net "P5E_PEX1_STN7_TX_C_DP<120>")
	)
	(segment
		(start 161.629852 -368.06251)
		(end 161.486088 -368.06251)
		(width 0.1651)
		(layer "In11.Cu")
		(net "P5E_PEX1_STN7_TX_C_DP<120>")
	)
	(segment
		(start 162.474148 -367.218214)
		(end 162.330384 -367.218214)
		(width 0.1651)
		(layer "In11.Cu")
		(net "P5E_PEX1_STN7_TX_C_DP<120>")
	)
	(segment
		(start 160.325562 -374.899174)
		(end 160.037018 -374.899174)
		(width 0.1651)
		(layer "In11.Cu")
		(net "P5E_PEX1_STN7_TX_C_DP<120>")
	)
	(segment
		(start 161.486088 -368.06251)
		(end 161.135568 -368.41303)
		(width 0.1651)
		(layer "In11.Cu")
		(net "P5E_PEX1_STN7_TX_C_DP<120>")
	)
	(segment
		(start 159.910018 -374.772174)
		(end 159.910018 -374.390158)
		(width 0.1651)
		(layer "In11.Cu")
		(net "P5E_PEX1_STN7_TX_C_DP<120>")
	)
	(segment
		(start 162.330384 -367.218214)
		(end 161.979864 -367.568734)
		(width 0.1651)
		(layer "In11.Cu")
		(net "P5E_PEX1_STN7_TX_C_DP<120>")
	)
	(segment
		(start 176.467262 -359.073196)
		(end 176.11725 -359.423208)
		(width 0.1651)
		(layer "In11.Cu")
		(net "P5E_PEX1_STN7_TX_C_DP<120>")
	)
	(segment
		(start 175.12919 -360.267504)
		(end 174.77867 -360.618024)
		(width 0.1651)
		(layer "In11.Cu")
		(net "P5E_PEX1_STN7_TX_C_DP<120>")
	)
	(segment
		(start 175.272954 -360.267504)
		(end 175.12919 -360.267504)
		(width 0.1651)
		(layer "In11.Cu")
		(net "P5E_PEX1_STN7_TX_C_DP<120>")
	)
	(segment
		(start 175.622966 -359.773728)
		(end 175.622966 -359.917492)
		(width 0.1651)
		(layer "In11.Cu")
		(net "P5E_PEX1_STN7_TX_C_DP<120>")
	)
	(segment
		(start 173.934374 -361.606084)
		(end 173.427898 -362.11256)
		(width 0.1651)
		(layer "In11.Cu")
		(net "P5E_PEX1_STN7_TX_C_DP<120>")
	)
	(segment
		(start 163.348924 -366.343438)
		(end 162.474148 -367.218214)
		(width 0.1651)
		(layer "In11.Cu")
		(net "P5E_PEX1_STN7_TX_C_DP<120>")
	)
	(segment
		(start 160.037018 -374.899174)
		(end 159.910018 -374.772174)
		(width 0.1651)
		(layer "In11.Cu")
		(net "P5E_PEX1_STN7_TX_C_DP<120>")
	)
	(segment
		(start 189.754002 -30.62732)
		(end 189.120018 -30.62732)
		(width 0.13462)
		(layer "F.Cu")
		(net "P5E_PEX1_STN2_TX_DP<37>")
	)
	(segment
		(start 190.047372 -30.92069)
		(end 189.754002 -30.62732)
		(width 0.13462)
		(layer "F.Cu")
		(net "P5E_PEX1_STN2_TX_DP<37>")
	)
	(segment
		(start 189.120018 -30.62732)
		(end 188.801248 -30.94609)
		(width 0.13462)
		(layer "F.Cu")
		(net "P5E_PEX1_STN2_TX_DP<37>")
	)
	(segment
		(start 192.506346 -32.15132)
		(end 192.856866 -32.50184)
		(width 0.1651)
		(layer "In11.Cu")
		(net "P5E_PEX1_STN2_TX_DP<37>")
	)
	(segment
		(start 206.089504 -58.547)
		(end 206.089504 -60.42152)
		(width 0.1651)
		(layer "In11.Cu")
		(net "P5E_PEX1_STN2_TX_DP<37>")
	)
	(segment
		(start 205.507336 -62.600586)
		(end 204.576934 -64.465962)
		(width 0.1651)
		(layer "In11.Cu")
		(net "P5E_PEX1_STN2_TX_DP<37>")
	)
	(segment
		(start 192.506346 -32.02559)
		(end 192.506346 -32.15132)
		(width 0.1651)
		(layer "In11.Cu")
		(net "P5E_PEX1_STN2_TX_DP<37>")
	)
	(segment
		(start 192.156334 -31.675578)
		(end 192.506346 -32.02559)
		(width 0.1651)
		(layer "In11.Cu")
		(net "P5E_PEX1_STN2_TX_DP<37>")
	)
	(segment
		(start 198.293736 -40.682418)
		(end 205.03388 -48.152812)
		(width 0.1651)
		(layer "In11.Cu")
		(net "P5E_PEX1_STN2_TX_DP<37>")
	)
	(segment
		(start 178.698144 -109.674152)
		(end 178.51755 -110.598458)
		(width 0.1651)
		(layer "In11.Cu")
		(net "P5E_PEX1_STN2_TX_DP<37>")
	)
	(segment
		(start 205.03388 -48.152812)
		(end 206.089504 -58.547)
		(width 0.1651)
		(layer "In11.Cu")
		(net "P5E_PEX1_STN2_TX_DP<37>")
	)
	(segment
		(start 190.338202 -30.62986)
		(end 190.956184 -30.62986)
		(width 0.1651)
		(layer "In11.Cu")
		(net "P5E_PEX1_STN2_TX_DP<37>")
	)
	(segment
		(start 178.51755 -110.598458)
		(end 177.613056 -115.227608)
		(width 0.1651)
		(layer "In11.Cu")
		(net "P5E_PEX1_STN2_TX_DP<37>")
	)
	(segment
		(start 176.932844 -120.737122)
		(end 169.434002 -263.298686)
		(width 0.1651)
		(layer "In11.Cu")
		(net "P5E_PEX1_STN2_TX_DP<37>")
	)
	(segment
		(start 206.089504 -60.42152)
		(end 205.507336 -62.600586)
		(width 0.1651)
		(layer "In11.Cu")
		(net "P5E_PEX1_STN2_TX_DP<37>")
	)
	(segment
		(start 204.576934 -64.465962)
		(end 182.371746 -93.486986)
		(width 0.1651)
		(layer "In11.Cu")
		(net "P5E_PEX1_STN2_TX_DP<37>")
	)
	(segment
		(start 179.060348 -107.821222)
		(end 178.878738 -108.750354)
		(width 0.1651)
		(layer "In11.Cu")
		(net "P5E_PEX1_STN2_TX_DP<37>")
	)
	(segment
		(start 170.049952 -278.534368)
		(end 170.049952 -278.799798)
		(width 0.1143)
		(layer "In11.Cu")
		(net "P5E_PEX1_STN2_TX_DP<37>")
	)
	(segment
		(start 192.030604 -31.675578)
		(end 192.156334 -31.675578)
		(width 0.1651)
		(layer "In11.Cu")
		(net "P5E_PEX1_STN2_TX_DP<37>")
	)
	(segment
		(start 191.680084 -31.325058)
		(end 192.030604 -31.675578)
		(width 0.1651)
		(layer "In11.Cu")
		(net "P5E_PEX1_STN2_TX_DP<37>")
	)
	(segment
		(start 178.878484 -108.750354)
		(end 178.69789 -109.674152)
		(width 0.1651)
		(layer "In11.Cu")
		(net "P5E_PEX1_STN2_TX_DP<37>")
	)
	(segment
		(start 190.956184 -30.62986)
		(end 191.219836 -30.73908)
		(width 0.1651)
		(layer "In11.Cu")
		(net "P5E_PEX1_STN2_TX_DP<37>")
	)
	(segment
		(start 169.479722 -271.473168)
		(end 169.479722 -278.20493)
		(width 0.1143)
		(layer "In11.Cu")
		(net "P5E_PEX1_STN2_TX_DP<37>")
	)
	(segment
		(start 193.570352 -33.089596)
		(end 198.293736 -40.682418)
		(width 0.1651)
		(layer "In11.Cu")
		(net "P5E_PEX1_STN2_TX_DP<37>")
	)
	(segment
		(start 178.878738 -108.750354)
		(end 178.878484 -108.750354)
		(width 0.1651)
		(layer "In11.Cu")
		(net "P5E_PEX1_STN2_TX_DP<37>")
	)
	(segment
		(start 169.434002 -263.298686)
		(end 169.434002 -271.399)
		(width 0.1651)
		(layer "In11.Cu")
		(net "P5E_PEX1_STN2_TX_DP<37>")
	)
	(segment
		(start 169.434002 -271.399)
		(end 169.434002 -271.427448)
		(width 0.1143)
		(layer "In11.Cu")
		(net "P5E_PEX1_STN2_TX_DP<37>")
	)
	(segment
		(start 178.69789 -109.674152)
		(end 178.698144 -109.674152)
		(width 0.1651)
		(layer "In11.Cu")
		(net "P5E_PEX1_STN2_TX_DP<37>")
	)
	(segment
		(start 192.856866 -32.50184)
		(end 192.982596 -32.50184)
		(width 0.1651)
		(layer "In11.Cu")
		(net "P5E_PEX1_STN2_TX_DP<37>")
	)
	(segment
		(start 177.613056 -115.227608)
		(end 176.932844 -120.737122)
		(width 0.1651)
		(layer "In11.Cu")
		(net "P5E_PEX1_STN2_TX_DP<37>")
	)
	(segment
		(start 169.935652 -278.420068)
		(end 170.049952 -278.534368)
		(width 0.1143)
		(layer "In11.Cu")
		(net "P5E_PEX1_STN2_TX_DP<37>")
	)
	(segment
		(start 169.434002 -271.427448)
		(end 169.479722 -271.473168)
		(width 0.1143)
		(layer "In11.Cu")
		(net "P5E_PEX1_STN2_TX_DP<37>")
	)
	(segment
		(start 169.479722 -278.20493)
		(end 169.69486 -278.420068)
		(width 0.1143)
		(layer "In11.Cu")
		(net "P5E_PEX1_STN2_TX_DP<37>")
	)
	(segment
		(start 169.69486 -278.420068)
		(end 169.935652 -278.420068)
		(width 0.1143)
		(layer "In11.Cu")
		(net "P5E_PEX1_STN2_TX_DP<37>")
	)
	(segment
		(start 192.982596 -32.50184)
		(end 193.570352 -33.089596)
		(width 0.1651)
		(layer "In11.Cu")
		(net "P5E_PEX1_STN2_TX_DP<37>")
	)
	(segment
		(start 191.680084 -31.199328)
		(end 191.680084 -31.325058)
		(width 0.1651)
		(layer "In11.Cu")
		(net "P5E_PEX1_STN2_TX_DP<37>")
	)
	(segment
		(start 191.219836 -30.73908)
		(end 191.680084 -31.199328)
		(width 0.1651)
		(layer "In11.Cu")
		(net "P5E_PEX1_STN2_TX_DP<37>")
	)
	(segment
		(start 190.047372 -30.92069)
		(end 190.338202 -30.62986)
		(width 0.1651)
		(layer "In11.Cu")
		(net "P5E_PEX1_STN2_TX_DP<37>")
	)
	(segment
		(start 182.371746 -93.486986)
		(end 179.060348 -107.821222)
		(width 0.1651)
		(layer "In11.Cu")
		(net "P5E_PEX1_STN2_TX_DP<37>")
	)
	(segment
		(start 313.732164 -142.615666)
		(end 313.44235 -142.90548)
		(width 0.13462)
		(layer "F.Cu")
		(net "P5E_PEX2_STN0_TX_DN<8>")
	)
	(segment
		(start 312.801254 -142.90548)
		(end 312.48604 -142.590266)
		(width 0.13462)
		(layer "F.Cu")
		(net "P5E_PEX2_STN0_TX_DN<8>")
	)
	(segment
		(start 313.44235 -142.90548)
		(end 312.801254 -142.90548)
		(width 0.13462)
		(layer "F.Cu")
		(net "P5E_PEX2_STN0_TX_DN<8>")
	)
	(segment
		(start 313.732164 -142.615666)
		(end 314.022994 -142.906496)
		(width 0.1651)
		(layer "In9.Cu")
		(net "P5E_PEX2_STN0_TX_DN<8>")
	)
	(segment
		(start 314.953904 -142.69466)
		(end 315.842904 -142.69466)
		(width 0.1651)
		(layer "In9.Cu")
		(net "P5E_PEX2_STN0_TX_DN<8>")
	)
	(segment
		(start 324.629526 -154.276552)
		(end 324.629526 -158.516574)
		(width 0.1651)
		(layer "In9.Cu")
		(net "P5E_PEX2_STN0_TX_DN<8>")
	)
	(segment
		(start 314.406788 -276.507448)
		(end 314.270136 -276.6441)
		(width 0.1143)
		(layer "In9.Cu")
		(net "P5E_PEX2_STN0_TX_DN<8>")
	)
	(segment
		(start 314.384436 -276.899878)
		(end 314.649866 -276.899878)
		(width 0.1143)
		(layer "In9.Cu")
		(net "P5E_PEX2_STN0_TX_DN<8>")
	)
	(segment
		(start 315.26607 -270.358108)
		(end 315.26607 -271.776952)
		(width 0.1651)
		(layer "In9.Cu")
		(net "P5E_PEX2_STN0_TX_DN<8>")
	)
	(segment
		(start 315.842904 -142.69466)
		(end 317.61938 -143.430498)
		(width 0.1651)
		(layer "In9.Cu")
		(net "P5E_PEX2_STN0_TX_DN<8>")
	)
	(segment
		(start 314.022994 -142.906496)
		(end 314.442094 -142.906496)
		(width 0.1651)
		(layer "In9.Cu")
		(net "P5E_PEX2_STN0_TX_DN<8>")
	)
	(segment
		(start 314.975494 -276.507448)
		(end 314.406788 -276.507448)
		(width 0.1143)
		(layer "In9.Cu")
		(net "P5E_PEX2_STN0_TX_DN<8>")
	)
	(segment
		(start 311.025032 -222.047308)
		(end 314.36437 -260.268466)
		(width 0.1651)
		(layer "In9.Cu")
		(net "P5E_PEX2_STN0_TX_DN<8>")
	)
	(segment
		(start 314.442094 -142.906496)
		(end 314.953904 -142.69466)
		(width 0.1651)
		(layer "In9.Cu")
		(net "P5E_PEX2_STN0_TX_DN<8>")
	)
	(segment
		(start 314.270136 -276.785578)
		(end 314.384436 -276.899878)
		(width 0.1143)
		(layer "In9.Cu")
		(net "P5E_PEX2_STN0_TX_DN<8>")
	)
	(segment
		(start 315.22035 -271.85112)
		(end 315.22035 -276.262592)
		(width 0.1143)
		(layer "In9.Cu")
		(net "P5E_PEX2_STN0_TX_DN<8>")
	)
	(segment
		(start 316.10427 -173.28642)
		(end 314.897262 -177.788062)
		(width 0.1651)
		(layer "In9.Cu")
		(net "P5E_PEX2_STN0_TX_DN<8>")
	)
	(segment
		(start 315.26607 -271.8054)
		(end 315.22035 -271.85112)
		(width 0.1143)
		(layer "In9.Cu")
		(net "P5E_PEX2_STN0_TX_DN<8>")
	)
	(segment
		(start 315.26607 -271.776952)
		(end 315.26607 -271.8054)
		(width 0.1143)
		(layer "In9.Cu")
		(net "P5E_PEX2_STN0_TX_DN<8>")
	)
	(segment
		(start 317.61938 -143.430498)
		(end 321.192398 -147.003516)
		(width 0.1651)
		(layer "In9.Cu")
		(net "P5E_PEX2_STN0_TX_DN<8>")
	)
	(segment
		(start 314.36437 -260.268466)
		(end 314.36437 -261.20217)
		(width 0.1651)
		(layer "In9.Cu")
		(net "P5E_PEX2_STN0_TX_DN<8>")
	)
	(segment
		(start 324.629526 -158.516574)
		(end 316.10427 -173.28642)
		(width 0.1651)
		(layer "In9.Cu")
		(net "P5E_PEX2_STN0_TX_DN<8>")
	)
	(segment
		(start 314.36437 -261.20217)
		(end 315.26607 -270.358108)
		(width 0.1651)
		(layer "In9.Cu")
		(net "P5E_PEX2_STN0_TX_DN<8>")
	)
	(segment
		(start 321.192398 -147.003516)
		(end 322.308982 -148.674074)
		(width 0.1651)
		(layer "In9.Cu")
		(net "P5E_PEX2_STN0_TX_DN<8>")
	)
	(segment
		(start 314.270136 -276.6441)
		(end 314.270136 -276.785578)
		(width 0.1143)
		(layer "In9.Cu")
		(net "P5E_PEX2_STN0_TX_DN<8>")
	)
	(segment
		(start 322.308982 -148.674074)
		(end 324.629526 -154.276552)
		(width 0.1651)
		(layer "In9.Cu")
		(net "P5E_PEX2_STN0_TX_DN<8>")
	)
	(segment
		(start 314.897262 -177.788062)
		(end 311.025032 -222.047308)
		(width 0.1651)
		(layer "In9.Cu")
		(net "P5E_PEX2_STN0_TX_DN<8>")
	)
	(segment
		(start 315.22035 -276.262592)
		(end 314.975494 -276.507448)
		(width 0.1143)
		(layer "In9.Cu")
		(net "P5E_PEX2_STN0_TX_DN<8>")
	)
	(segment
		(start 295.852342 -355.978206)
		(end 296.172382 -355.658166)
		(width 0.13462)
		(layer "F.Cu")
		(net "P5E_PEX2_STN7_TX_DP<126>")
	)
	(segment
		(start 296.172382 -355.658166)
		(end 296.172382 -355.026722)
		(width 0.13462)
		(layer "F.Cu")
		(net "P5E_PEX2_STN7_TX_DP<126>")
	)
	(segment
		(start 296.172382 -355.026722)
		(end 295.877742 -354.732082)
		(width 0.13462)
		(layer "F.Cu")
		(net "P5E_PEX2_STN7_TX_DP<126>")
	)
	(segment
		(start 297.723052 -341.712804)
		(end 297.722798 -341.71255)
		(width 0.1651)
		(layer "In7.Cu")
		(net "P5E_PEX2_STN7_TX_DP<126>")
	)
	(segment
		(start 273.183858 -321.005962)
		(end 273.183858 -319.868296)
		(width 0.1651)
		(layer "In7.Cu")
		(net "P5E_PEX2_STN7_TX_DP<126>")
	)
	(segment
		(start 273.183858 -319.868296)
		(end 273.183858 -319.839848)
		(width 0.1143)
		(layer "In7.Cu")
		(net "P5E_PEX2_STN7_TX_DP<126>")
	)
	(segment
		(start 296.168572 -354.441252)
		(end 296.168572 -353.814126)
		(width 0.1651)
		(layer "In7.Cu")
		(net "P5E_PEX2_STN7_TX_DP<126>")
	)
	(segment
		(start 295.877742 -354.732082)
		(end 296.168572 -354.441252)
		(width 0.1651)
		(layer "In7.Cu")
		(net "P5E_PEX2_STN7_TX_DP<126>")
	)
	(segment
		(start 273.183858 -319.839848)
		(end 273.229578 -319.794128)
		(width 0.1143)
		(layer "In7.Cu")
		(net "P5E_PEX2_STN7_TX_DP<126>")
	)
	(segment
		(start 297.722798 -341.71255)
		(end 297.375072 -341.086948)
		(width 0.1651)
		(layer "In7.Cu")
		(net "P5E_PEX2_STN7_TX_DP<126>")
	)
	(segment
		(start 273.229578 -311.705498)
		(end 273.455384 -311.479692)
		(width 0.1143)
		(layer "In7.Cu")
		(net "P5E_PEX2_STN7_TX_DP<126>")
	)
	(segment
		(start 273.685508 -311.479692)
		(end 273.799808 -311.365392)
		(width 0.1143)
		(layer "In7.Cu")
		(net "P5E_PEX2_STN7_TX_DP<126>")
	)
	(segment
		(start 297.0276 -340.4616)
		(end 273.725386 -321.952366)
		(width 0.1651)
		(layer "In7.Cu")
		(net "P5E_PEX2_STN7_TX_DP<126>")
	)
	(segment
		(start 297.723052 -352.259646)
		(end 297.723052 -341.712804)
		(width 0.1651)
		(layer "In7.Cu")
		(net "P5E_PEX2_STN7_TX_DP<126>")
	)
	(segment
		(start 273.229578 -319.794128)
		(end 273.229578 -311.705498)
		(width 0.1143)
		(layer "In7.Cu")
		(net "P5E_PEX2_STN7_TX_DP<126>")
	)
	(segment
		(start 273.470116 -321.697096)
		(end 273.183858 -321.005962)
		(width 0.1651)
		(layer "In7.Cu")
		(net "P5E_PEX2_STN7_TX_DP<126>")
	)
	(segment
		(start 273.799808 -311.365392)
		(end 273.799808 -311.099962)
		(width 0.1143)
		(layer "In7.Cu")
		(net "P5E_PEX2_STN7_TX_DP<126>")
	)
	(segment
		(start 273.725386 -321.952366)
		(end 273.470116 -321.697096)
		(width 0.1651)
		(layer "In7.Cu")
		(net "P5E_PEX2_STN7_TX_DP<126>")
	)
	(segment
		(start 273.455384 -311.479692)
		(end 273.685508 -311.479692)
		(width 0.1143)
		(layer "In7.Cu")
		(net "P5E_PEX2_STN7_TX_DP<126>")
	)
	(segment
		(start 297.375072 -341.086948)
		(end 297.0276 -340.4616)
		(width 0.1651)
		(layer "In7.Cu")
		(net "P5E_PEX2_STN7_TX_DP<126>")
	)
	(segment
		(start 296.168572 -353.814126)
		(end 297.723052 -352.259646)
		(width 0.1651)
		(layer "In7.Cu")
		(net "P5E_PEX2_STN7_TX_DP<126>")
	)
	(segment
		(start 429.532796 -143.1798)
		(end 428.911004 -143.1798)
		(width 0.13462)
		(layer "F.Cu")
		(net "P5E_PEX3_STN0_TX_DP<8>")
	)
	(segment
		(start 428.911004 -143.1798)
		(end 428.586138 -143.504666)
		(width 0.13462)
		(layer "F.Cu")
		(net "P5E_PEX3_STN0_TX_DP<8>")
	)
	(segment
		(start 429.832262 -143.479266)
		(end 429.532796 -143.1798)
		(width 0.13462)
		(layer "F.Cu")
		(net "P5E_PEX3_STN0_TX_DP<8>")
	)
	(segment
		(start 431.129948 -271.85112)
		(end 431.129948 -276.183598)
		(width 0.1143)
		(layer "In9.Cu")
		(net "P5E_PEX3_STN0_TX_DP<8>")
	)
	(segment
		(start 430.065434 -276.899878)
		(end 429.800004 -276.899878)
		(width 0.1143)
		(layer "In9.Cu")
		(net "P5E_PEX3_STN0_TX_DP<8>")
	)
	(segment
		(start 438.49036 -149.839172)
		(end 438.606438 -149.887178)
		(width 0.1651)
		(layer "In9.Cu")
		(net "P5E_PEX3_STN0_TX_DP<8>")
	)
	(segment
		(start 437.723026 -148.154898)
		(end 437.722772 -148.154898)
		(width 0.1651)
		(layer "In9.Cu")
		(net "P5E_PEX3_STN0_TX_DP<8>")
	)
	(segment
		(start 435.968902 -146.078702)
		(end 436.370222 -146.480022)
		(width 0.1651)
		(layer "In9.Cu")
		(net "P5E_PEX3_STN0_TX_DP<8>")
	)
	(segment
		(start 434.66639 -144.77619)
		(end 434.66639 -144.90192)
		(width 0.1651)
		(layer "In9.Cu")
		(net "P5E_PEX3_STN0_TX_DP<8>")
	)
	(segment
		(start 435.492652 -145.728182)
		(end 435.843172 -146.078702)
		(width 0.1651)
		(layer "In9.Cu")
		(net "P5E_PEX3_STN0_TX_DP<8>")
	)
	(segment
		(start 436.846218 -146.956018)
		(end 437.073548 -147.183348)
		(width 0.1651)
		(layer "In9.Cu")
		(net "P5E_PEX3_STN0_TX_DP<8>")
	)
	(segment
		(start 438.348628 -149.265132)
		(end 438.300368 -149.38121)
		(width 0.1651)
		(layer "In9.Cu")
		(net "P5E_PEX3_STN0_TX_DP<8>")
	)
	(segment
		(start 440.447684 -158.440882)
		(end 431.941478 -173.177454)
		(width 0.1651)
		(layer "In9.Cu")
		(net "P5E_PEX3_STN0_TX_DP<8>")
	)
	(segment
		(start 438.606184 -149.887178)
		(end 440.447684 -154.332686)
		(width 0.1651)
		(layer "In9.Cu")
		(net "P5E_PEX3_STN0_TX_DP<8>")
	)
	(segment
		(start 438.300368 -149.38121)
		(end 438.49036 -149.839172)
		(width 0.1651)
		(layer "In9.Cu")
		(net "P5E_PEX3_STN0_TX_DP<8>")
	)
	(segment
		(start 431.886868 -142.9766)
		(end 432.344322 -143.166084)
		(width 0.1651)
		(layer "In9.Cu")
		(net "P5E_PEX3_STN0_TX_DP<8>")
	)
	(segment
		(start 435.843172 -146.078702)
		(end 435.968902 -146.078702)
		(width 0.1651)
		(layer "In9.Cu")
		(net "P5E_PEX3_STN0_TX_DP<8>")
	)
	(segment
		(start 437.34863 -147.595082)
		(end 437.324246 -147.718272)
		(width 0.1651)
		(layer "In9.Cu")
		(net "P5E_PEX3_STN0_TX_DP<8>")
	)
	(segment
		(start 436.370222 -146.480022)
		(end 436.370222 -146.605752)
		(width 0.1651)
		(layer "In9.Cu")
		(net "P5E_PEX3_STN0_TX_DP<8>")
	)
	(segment
		(start 437.324246 -147.718272)
		(end 437.599582 -148.13026)
		(width 0.1651)
		(layer "In9.Cu")
		(net "P5E_PEX3_STN0_TX_DP<8>")
	)
	(segment
		(start 434.66639 -144.90192)
		(end 435.01691 -145.25244)
		(width 0.1651)
		(layer "In9.Cu")
		(net "P5E_PEX3_STN0_TX_DP<8>")
	)
	(segment
		(start 430.182528 -260.280912)
		(end 430.182528 -261.21614)
		(width 0.1651)
		(layer "In9.Cu")
		(net "P5E_PEX3_STN0_TX_DP<8>")
	)
	(segment
		(start 429.832262 -143.479266)
		(end 430.123092 -143.188436)
		(width 0.1651)
		(layer "In9.Cu")
		(net "P5E_PEX3_STN0_TX_DP<8>")
	)
	(segment
		(start 438.159144 -148.807678)
		(end 438.348628 -149.265132)
		(width 0.1651)
		(layer "In9.Cu")
		(net "P5E_PEX3_STN0_TX_DP<8>")
	)
	(segment
		(start 435.14264 -145.25244)
		(end 435.492652 -145.602452)
		(width 0.1651)
		(layer "In9.Cu")
		(net "P5E_PEX3_STN0_TX_DP<8>")
	)
	(segment
		(start 431.110136 -142.9766)
		(end 431.886868 -142.9766)
		(width 0.1651)
		(layer "In9.Cu")
		(net "P5E_PEX3_STN0_TX_DP<8>")
	)
	(segment
		(start 432.392328 -143.282162)
		(end 432.85029 -143.4719)
		(width 0.1651)
		(layer "In9.Cu")
		(net "P5E_PEX3_STN0_TX_DP<8>")
	)
	(segment
		(start 431.084228 -271.8054)
		(end 431.129948 -271.85112)
		(width 0.1143)
		(layer "In9.Cu")
		(net "P5E_PEX3_STN0_TX_DP<8>")
	)
	(segment
		(start 430.598326 -143.188436)
		(end 431.110136 -142.9766)
		(width 0.1651)
		(layer "In9.Cu")
		(net "P5E_PEX3_STN0_TX_DP<8>")
	)
	(segment
		(start 431.129948 -276.183598)
		(end 430.996598 -276.316948)
		(width 0.1143)
		(layer "In9.Cu")
		(net "P5E_PEX3_STN0_TX_DP<8>")
	)
	(segment
		(start 435.01691 -145.25244)
		(end 435.14264 -145.25244)
		(width 0.1651)
		(layer "In9.Cu")
		(net "P5E_PEX3_STN0_TX_DP<8>")
	)
	(segment
		(start 438.606438 -149.887178)
		(end 438.606184 -149.887178)
		(width 0.1651)
		(layer "In9.Cu")
		(net "P5E_PEX3_STN0_TX_DP<8>")
	)
	(segment
		(start 431.941478 -173.177454)
		(end 430.718468 -177.738786)
		(width 0.1651)
		(layer "In9.Cu")
		(net "P5E_PEX3_STN0_TX_DP<8>")
	)
	(segment
		(start 430.182528 -261.21614)
		(end 431.084228 -270.372078)
		(width 0.1651)
		(layer "In9.Cu")
		(net "P5E_PEX3_STN0_TX_DP<8>")
	)
	(segment
		(start 430.996598 -276.316948)
		(end 430.427892 -276.316948)
		(width 0.1143)
		(layer "In9.Cu")
		(net "P5E_PEX3_STN0_TX_DP<8>")
	)
	(segment
		(start 430.123092 -143.188436)
		(end 430.598326 -143.188436)
		(width 0.1651)
		(layer "In9.Cu")
		(net "P5E_PEX3_STN0_TX_DP<8>")
	)
	(segment
		(start 436.720488 -146.956018)
		(end 436.846218 -146.956018)
		(width 0.1651)
		(layer "In9.Cu")
		(net "P5E_PEX3_STN0_TX_DP<8>")
	)
	(segment
		(start 433.559712 -143.669512)
		(end 434.66639 -144.77619)
		(width 0.1651)
		(layer "In9.Cu")
		(net "P5E_PEX3_STN0_TX_DP<8>")
	)
	(segment
		(start 440.447684 -154.332686)
		(end 440.447684 -158.440882)
		(width 0.1651)
		(layer "In9.Cu")
		(net "P5E_PEX3_STN0_TX_DP<8>")
	)
	(segment
		(start 432.85029 -143.4719)
		(end 432.966368 -143.423894)
		(width 0.1651)
		(layer "In9.Cu")
		(net "P5E_PEX3_STN0_TX_DP<8>")
	)
	(segment
		(start 428.77994 -199.893174)
		(end 428.780194 -199.893174)
		(width 0.1651)
		(layer "In9.Cu")
		(net "P5E_PEX3_STN0_TX_DP<8>")
	)
	(segment
		(start 426.84192 -222.047308)
		(end 430.182528 -260.280912)
		(width 0.1651)
		(layer "In9.Cu")
		(net "P5E_PEX3_STN0_TX_DP<8>")
	)
	(segment
		(start 435.492652 -145.602452)
		(end 435.492652 -145.728182)
		(width 0.1651)
		(layer "In9.Cu")
		(net "P5E_PEX3_STN0_TX_DP<8>")
	)
	(segment
		(start 432.966368 -143.423894)
		(end 433.559712 -143.669512)
		(width 0.1651)
		(layer "In9.Cu")
		(net "P5E_PEX3_STN0_TX_DP<8>")
	)
	(segment
		(start 436.370222 -146.605752)
		(end 436.720488 -146.956018)
		(width 0.1651)
		(layer "In9.Cu")
		(net "P5E_PEX3_STN0_TX_DP<8>")
	)
	(segment
		(start 430.427892 -276.316948)
		(end 430.179734 -276.565106)
		(width 0.1143)
		(layer "In9.Cu")
		(net "P5E_PEX3_STN0_TX_DP<8>")
	)
	(segment
		(start 430.179734 -276.785578)
		(end 430.065434 -276.899878)
		(width 0.1143)
		(layer "In9.Cu")
		(net "P5E_PEX3_STN0_TX_DP<8>")
	)
	(segment
		(start 430.718468 -177.738786)
		(end 428.77994 -199.893174)
		(width 0.1651)
		(layer "In9.Cu")
		(net "P5E_PEX3_STN0_TX_DP<8>")
	)
	(segment
		(start 430.179734 -276.565106)
		(end 430.179734 -276.785578)
		(width 0.1143)
		(layer "In9.Cu")
		(net "P5E_PEX3_STN0_TX_DP<8>")
	)
	(segment
		(start 428.780194 -199.893174)
		(end 426.84192 -222.047308)
		(width 0.1651)
		(layer "In9.Cu")
		(net "P5E_PEX3_STN0_TX_DP<8>")
	)
	(segment
		(start 431.084228 -271.776952)
		(end 431.084228 -271.8054)
		(width 0.1143)
		(layer "In9.Cu")
		(net "P5E_PEX3_STN0_TX_DP<8>")
	)
	(segment
		(start 437.722772 -148.154898)
		(end 438.159144 -148.807678)
		(width 0.1651)
		(layer "In9.Cu")
		(net "P5E_PEX3_STN0_TX_DP<8>")
	)
	(segment
		(start 437.599582 -148.13026)
		(end 437.723026 -148.154898)
		(width 0.1651)
		(layer "In9.Cu")
		(net "P5E_PEX3_STN0_TX_DP<8>")
	)
	(segment
		(start 431.084228 -270.372078)
		(end 431.084228 -271.776952)
		(width 0.1651)
		(layer "In9.Cu")
		(net "P5E_PEX3_STN0_TX_DP<8>")
	)
	(segment
		(start 432.344322 -143.166084)
		(end 432.392328 -143.282162)
		(width 0.1651)
		(layer "In9.Cu")
		(net "P5E_PEX3_STN0_TX_DP<8>")
	)
	(segment
		(start 437.073548 -147.183348)
		(end 437.34863 -147.595082)
		(width 0.1651)
		(layer "In9.Cu")
		(net "P5E_PEX3_STN0_TX_DP<8>")
	)
	(segment
		(start 412.698184 -349.512382)
		(end 412.698184 -348.879922)
		(width 0.13462)
		(layer "F.Cu")
		(net "P5E_PEX3_STN7_TX_DP<113>")
	)
	(segment
		(start 412.698184 -348.879922)
		(end 412.404052 -348.58579)
		(width 0.13462)
		(layer "F.Cu")
		(net "P5E_PEX3_STN7_TX_DP<113>")
	)
	(segment
		(start 412.378652 -349.831914)
		(end 412.698184 -349.512382)
		(width 0.13462)
		(layer "F.Cu")
		(net "P5E_PEX3_STN7_TX_DP<113>")
	)
	(segment
		(start 412.694882 -347.667834)
		(end 414.249362 -346.113354)
		(width 0.1651)
		(layer "In11.Cu")
		(net "P5E_PEX3_STN7_TX_DP<113>")
	)
	(segment
		(start 372.61165 -305.95697)
		(end 375.39295 -303.17567)
		(width 0.1651)
		(layer "In11.Cu")
		(net "P5E_PEX3_STN7_TX_DP<113>")
	)
	(segment
		(start 367.13033 -314.160408)
		(end 372.61165 -305.95697)
		(width 0.1651)
		(layer "In11.Cu")
		(net "P5E_PEX3_STN7_TX_DP<113>")
	)
	(segment
		(start 392.484356 -302.549814)
		(end 392.749786 -302.549814)
		(width 0.1143)
		(layer "In11.Cu")
		(net "P5E_PEX3_STN7_TX_DP<113>")
	)
	(segment
		(start 414.249362 -346.113354)
		(end 414.249362 -342.16467)
		(width 0.1651)
		(layer "In11.Cu")
		(net "P5E_PEX3_STN7_TX_DP<113>")
	)
	(segment
		(start 392.370056 -302.170846)
		(end 392.370056 -302.435514)
		(width 0.1143)
		(layer "In11.Cu")
		(net "P5E_PEX3_STN7_TX_DP<113>")
	)
	(segment
		(start 383.995168 -301.979584)
		(end 392.178794 -301.979584)
		(width 0.1143)
		(layer "In11.Cu")
		(net "P5E_PEX3_STN7_TX_DP<113>")
	)
	(segment
		(start 365.28248 -322.760086)
		(end 365.28248 -318.621918)
		(width 0.1651)
		(layer "In11.Cu")
		(net "P5E_PEX3_STN7_TX_DP<113>")
	)
	(segment
		(start 413.878268 -341.541608)
		(end 413.356298 -341.16518)
		(width 0.1651)
		(layer "In11.Cu")
		(net "P5E_PEX3_STN7_TX_DP<113>")
	)
	(segment
		(start 365.28248 -318.621918)
		(end 367.13033 -314.160408)
		(width 0.1651)
		(layer "In11.Cu")
		(net "P5E_PEX3_STN7_TX_DP<113>")
	)
	(segment
		(start 414.249362 -342.16467)
		(end 413.878268 -341.541608)
		(width 0.1651)
		(layer "In11.Cu")
		(net "P5E_PEX3_STN7_TX_DP<113>")
	)
	(segment
		(start 412.694882 -348.29496)
		(end 412.694882 -347.667834)
		(width 0.1651)
		(layer "In11.Cu")
		(net "P5E_PEX3_STN7_TX_DP<113>")
	)
	(segment
		(start 375.39295 -303.17567)
		(end 378.391166 -301.933864)
		(width 0.1651)
		(layer "In11.Cu")
		(net "P5E_PEX3_STN7_TX_DP<113>")
	)
	(segment
		(start 412.404052 -348.58579)
		(end 412.694882 -348.29496)
		(width 0.1651)
		(layer "In11.Cu")
		(net "P5E_PEX3_STN7_TX_DP<113>")
	)
	(segment
		(start 367.30305 -327.63841)
		(end 365.28248 -322.760086)
		(width 0.1651)
		(layer "In11.Cu")
		(net "P5E_PEX3_STN7_TX_DP<113>")
	)
	(segment
		(start 392.370056 -302.435514)
		(end 392.484356 -302.549814)
		(width 0.1143)
		(layer "In11.Cu")
		(net "P5E_PEX3_STN7_TX_DP<113>")
	)
	(segment
		(start 373.712486 -332.470252)
		(end 370.22786 -330.563474)
		(width 0.1651)
		(layer "In11.Cu")
		(net "P5E_PEX3_STN7_TX_DP<113>")
	)
	(segment
		(start 383.921 -301.933864)
		(end 383.949448 -301.933864)
		(width 0.1143)
		(layer "In11.Cu")
		(net "P5E_PEX3_STN7_TX_DP<113>")
	)
	(segment
		(start 392.178794 -301.979584)
		(end 392.370056 -302.170846)
		(width 0.1143)
		(layer "In11.Cu")
		(net "P5E_PEX3_STN7_TX_DP<113>")
	)
	(segment
		(start 378.391166 -301.933864)
		(end 383.921 -301.933864)
		(width 0.1651)
		(layer "In11.Cu")
		(net "P5E_PEX3_STN7_TX_DP<113>")
	)
	(segment
		(start 370.22786 -330.563474)
		(end 367.30305 -327.63841)
		(width 0.1651)
		(layer "In11.Cu")
		(net "P5E_PEX3_STN7_TX_DP<113>")
	)
	(segment
		(start 383.949448 -301.933864)
		(end 383.995168 -301.979584)
		(width 0.1143)
		(layer "In11.Cu")
		(net "P5E_PEX3_STN7_TX_DP<113>")
	)
	(segment
		(start 413.356298 -341.16518)
		(end 373.712486 -332.470252)
		(width 0.1651)
		(layer "In11.Cu")
		(net "P5E_PEX3_STN7_TX_DP<113>")
	)
	(segment
		(start 133.919468 -349.511874)
		(end 133.919468 -348.88043)
		(width 0.13462)
		(layer "F.Cu")
		(net "P5E_PEX1_STN5_TX_DP<90>")
	)
	(segment
		(start 133.599428 -349.831914)
		(end 133.919468 -349.511874)
		(width 0.13462)
		(layer "F.Cu")
		(net "P5E_PEX1_STN5_TX_DP<90>")
	)
	(segment
		(start 133.919468 -348.88043)
		(end 133.624828 -348.58579)
		(width 0.13462)
		(layer "F.Cu")
		(net "P5E_PEX1_STN5_TX_DP<90>")
	)
	(segment
		(start 181.613556 -322.856098)
		(end 173.27372 -327.314814)
		(width 0.1651)
		(layer "In13.Cu")
		(net "P5E_PEX1_STN5_TX_DP<90>")
	)
	(segment
		(start 184.29986 -311.365392)
		(end 184.18556 -311.479692)
		(width 0.1143)
		(layer "In13.Cu")
		(net "P5E_PEX1_STN5_TX_DP<90>")
	)
	(segment
		(start 183.68391 -320.063114)
		(end 183.68391 -321.293744)
		(width 0.1651)
		(layer "In13.Cu")
		(net "P5E_PEX1_STN5_TX_DP<90>")
	)
	(segment
		(start 135.470138 -345.961716)
		(end 133.915658 -347.516196)
		(width 0.1651)
		(layer "In13.Cu")
		(net "P5E_PEX1_STN5_TX_DP<90>")
	)
	(segment
		(start 137.39495 -338.813902)
		(end 135.470138 -340.738714)
		(width 0.1651)
		(layer "In13.Cu")
		(net "P5E_PEX1_STN5_TX_DP<90>")
	)
	(segment
		(start 141.876526 -336.95767)
		(end 137.39495 -338.813902)
		(width 0.1651)
		(layer "In13.Cu")
		(net "P5E_PEX1_STN5_TX_DP<90>")
	)
	(segment
		(start 143.090646 -336.716116)
		(end 141.876526 -336.95767)
		(width 0.1651)
		(layer "In13.Cu")
		(net "P5E_PEX1_STN5_TX_DP<90>")
	)
	(segment
		(start 184.29986 -311.099962)
		(end 184.29986 -311.365392)
		(width 0.1143)
		(layer "In13.Cu")
		(net "P5E_PEX1_STN5_TX_DP<90>")
	)
	(segment
		(start 183.68391 -320.041016)
		(end 183.68391 -320.063114)
		(width 0.1143)
		(layer "In13.Cu")
		(net "P5E_PEX1_STN5_TX_DP<90>")
	)
	(segment
		(start 173.27372 -327.314814)
		(end 164.543232 -331.071474)
		(width 0.1651)
		(layer "In13.Cu")
		(net "P5E_PEX1_STN5_TX_DP<90>")
	)
	(segment
		(start 133.915658 -347.516196)
		(end 133.915658 -348.29496)
		(width 0.1651)
		(layer "In13.Cu")
		(net "P5E_PEX1_STN5_TX_DP<90>")
	)
	(segment
		(start 183.143398 -321.834256)
		(end 181.613556 -322.856098)
		(width 0.1651)
		(layer "In13.Cu")
		(net "P5E_PEX1_STN5_TX_DP<90>")
	)
	(segment
		(start 183.72963 -319.995296)
		(end 183.68391 -320.041016)
		(width 0.1143)
		(layer "In13.Cu")
		(net "P5E_PEX1_STN5_TX_DP<90>")
	)
	(segment
		(start 183.68391 -321.293744)
		(end 183.143398 -321.834256)
		(width 0.1651)
		(layer "In13.Cu")
		(net "P5E_PEX1_STN5_TX_DP<90>")
	)
	(segment
		(start 183.944768 -311.479692)
		(end 183.72963 -311.69483)
		(width 0.1143)
		(layer "In13.Cu")
		(net "P5E_PEX1_STN5_TX_DP<90>")
	)
	(segment
		(start 135.470138 -340.738714)
		(end 135.470138 -345.961716)
		(width 0.1651)
		(layer "In13.Cu")
		(net "P5E_PEX1_STN5_TX_DP<90>")
	)
	(segment
		(start 147.606512 -336.716116)
		(end 143.090646 -336.716116)
		(width 0.1651)
		(layer "In13.Cu")
		(net "P5E_PEX1_STN5_TX_DP<90>")
	)
	(segment
		(start 133.915658 -348.29496)
		(end 133.624828 -348.58579)
		(width 0.1651)
		(layer "In13.Cu")
		(net "P5E_PEX1_STN5_TX_DP<90>")
	)
	(segment
		(start 184.18556 -311.479692)
		(end 183.944768 -311.479692)
		(width 0.1143)
		(layer "In13.Cu")
		(net "P5E_PEX1_STN5_TX_DP<90>")
	)
	(segment
		(start 183.72963 -311.69483)
		(end 183.72963 -319.995296)
		(width 0.1143)
		(layer "In13.Cu")
		(net "P5E_PEX1_STN5_TX_DP<90>")
	)
	(segment
		(start 164.543232 -331.071474)
		(end 147.606512 -336.716116)
		(width 0.1651)
		(layer "In13.Cu")
		(net "P5E_PEX1_STN5_TX_DP<90>")
	)
	(segment
		(start 267.325602 -134.034276)
		(end 267.611606 -134.32028)
		(width 0.13462)
		(layer "F.Cu")
		(net "P5E_PEX2_STN1_TX_DP<30>")
	)
	(segment
		(start 268.260322 -134.32028)
		(end 268.571726 -134.008876)
		(width 0.13462)
		(layer "F.Cu")
		(net "P5E_PEX2_STN1_TX_DP<30>")
	)
	(segment
		(start 267.611606 -134.32028)
		(end 268.260322 -134.32028)
		(width 0.13462)
		(layer "F.Cu")
		(net "P5E_PEX2_STN1_TX_DP<30>")
	)
	(segment
		(start 304.794412 -278.420068)
		(end 304.579528 -278.205184)
		(width 0.1143)
		(layer "In9.Cu")
		(net "P5E_PEX2_STN1_TX_DP<30>")
	)
	(segment
		(start 305.149504 -278.534368)
		(end 305.035204 -278.420068)
		(width 0.1143)
		(layer "In9.Cu")
		(net "P5E_PEX2_STN1_TX_DP<30>")
	)
	(segment
		(start 266.064492 -134.659116)
		(end 266.398502 -134.325106)
		(width 0.1651)
		(layer "In9.Cu")
		(net "P5E_PEX2_STN1_TX_DP<30>")
	)
	(segment
		(start 265.941302 -135.323072)
		(end 265.941302 -134.956296)
		(width 0.1651)
		(layer "In9.Cu")
		(net "P5E_PEX2_STN1_TX_DP<30>")
	)
	(segment
		(start 304.533808 -271.500346)
		(end 304.533808 -271.471898)
		(width 0.1143)
		(layer "In9.Cu")
		(net "P5E_PEX2_STN1_TX_DP<30>")
	)
	(segment
		(start 268.59992 -139.158218)
		(end 266.773914 -137.332212)
		(width 0.1651)
		(layer "In9.Cu")
		(net "P5E_PEX2_STN1_TX_DP<30>")
	)
	(segment
		(start 267.034772 -134.325106)
		(end 267.325602 -134.034276)
		(width 0.1651)
		(layer "In9.Cu")
		(net "P5E_PEX2_STN1_TX_DP<30>")
	)
	(segment
		(start 305.035204 -278.420068)
		(end 304.794412 -278.420068)
		(width 0.1143)
		(layer "In9.Cu")
		(net "P5E_PEX2_STN1_TX_DP<30>")
	)
	(segment
		(start 268.95298 -140.010642)
		(end 268.59992 -139.158218)
		(width 0.1651)
		(layer "In9.Cu")
		(net "P5E_PEX2_STN1_TX_DP<30>")
	)
	(segment
		(start 305.149504 -278.799798)
		(end 305.149504 -278.534368)
		(width 0.1143)
		(layer "In9.Cu")
		(net "P5E_PEX2_STN1_TX_DP<30>")
	)
	(segment
		(start 304.533808 -262.993378)
		(end 277.548594 -183.275986)
		(width 0.1651)
		(layer "In9.Cu")
		(net "P5E_PEX2_STN1_TX_DP<30>")
	)
	(segment
		(start 304.533808 -271.471898)
		(end 304.533808 -262.993378)
		(width 0.1651)
		(layer "In9.Cu")
		(net "P5E_PEX2_STN1_TX_DP<30>")
	)
	(segment
		(start 304.579528 -278.205184)
		(end 304.579528 -271.546066)
		(width 0.1143)
		(layer "In9.Cu")
		(net "P5E_PEX2_STN1_TX_DP<30>")
	)
	(segment
		(start 266.398502 -134.325106)
		(end 267.034772 -134.325106)
		(width 0.1651)
		(layer "In9.Cu")
		(net "P5E_PEX2_STN1_TX_DP<30>")
	)
	(segment
		(start 265.941302 -134.956296)
		(end 266.064492 -134.659116)
		(width 0.1651)
		(layer "In9.Cu")
		(net "P5E_PEX2_STN1_TX_DP<30>")
	)
	(segment
		(start 304.579528 -271.546066)
		(end 304.533808 -271.500346)
		(width 0.1143)
		(layer "In9.Cu")
		(net "P5E_PEX2_STN1_TX_DP<30>")
	)
	(segment
		(start 277.548594 -183.275986)
		(end 268.95298 -140.010642)
		(width 0.1651)
		(layer "In9.Cu")
		(net "P5E_PEX2_STN1_TX_DP<30>")
	)
	(segment
		(start 266.773914 -137.332212)
		(end 265.941302 -135.323072)
		(width 0.1651)
		(layer "In9.Cu")
		(net "P5E_PEX2_STN1_TX_DP<30>")
	)
	(segment
		(start 275.004022 -349.831914)
		(end 274.683982 -349.511874)
		(width 0.13462)
		(layer "F.Cu")
		(net "P5E_PEX2_STN7_TX_DN<115>")
	)
	(segment
		(start 274.683982 -348.88043)
		(end 274.978622 -348.58579)
		(width 0.13462)
		(layer "F.Cu")
		(net "P5E_PEX2_STN7_TX_DN<115>")
	)
	(segment
		(start 274.683982 -349.511874)
		(end 274.683982 -348.88043)
		(width 0.13462)
		(layer "F.Cu")
		(net "P5E_PEX2_STN7_TX_DN<115>")
	)
	(segment
		(start 254.357124 -312.906156)
		(end 254.559054 -312.454036)
		(width 0.1651)
		(layer "In7.Cu")
		(net "P5E_PEX2_STN7_TX_DN<115>")
	)
	(segment
		(start 253.890526 -313.949842)
		(end 254.092456 -313.497722)
		(width 0.1651)
		(layer "In7.Cu")
		(net "P5E_PEX2_STN7_TX_DN<115>")
	)
	(segment
		(start 274.301712 -339.659214)
		(end 256.147316 -329.645518)
		(width 0.1651)
		(layer "In7.Cu")
		(net "P5E_PEX2_STN7_TX_DN<115>")
	)
	(segment
		(start 257.90144 -306.543456)
		(end 258.008882 -306.534566)
		(width 0.1651)
		(layer "In7.Cu")
		(net "P5E_PEX2_STN7_TX_DN<115>")
	)
	(segment
		(start 254.823722 -311.86247)
		(end 255.025652 -311.41035)
		(width 0.1651)
		(layer "In7.Cu")
		(net "P5E_PEX2_STN7_TX_DN<115>")
	)
	(segment
		(start 255.756918 -309.775098)
		(end 255.958848 -309.322978)
		(width 0.1651)
		(layer "In7.Cu")
		(net "P5E_PEX2_STN7_TX_DN<115>")
	)
	(segment
		(start 256.223516 -308.731412)
		(end 256.425446 -308.279292)
		(width 0.1651)
		(layer "In7.Cu")
		(net "P5E_PEX2_STN7_TX_DN<115>")
	)
	(segment
		(start 258.008882 -306.534566)
		(end 258.330192 -306.157122)
		(width 0.1651)
		(layer "In7.Cu")
		(net "P5E_PEX2_STN7_TX_DN<115>")
	)
	(segment
		(start 274.978622 -348.58579)
		(end 274.687792 -348.29496)
		(width 0.1651)
		(layer "In7.Cu")
		(net "P5E_PEX2_STN7_TX_DN<115>")
	)
	(segment
		(start 258.330192 -306.157122)
		(end 258.321302 -306.04968)
		(width 0.1651)
		(layer "In7.Cu")
		(net "P5E_PEX2_STN7_TX_DN<115>")
	)
	(segment
		(start 255.29032 -310.818784)
		(end 255.49225 -310.366664)
		(width 0.1651)
		(layer "In7.Cu")
		(net "P5E_PEX2_STN7_TX_DN<115>")
	)
	(segment
		(start 253.462282 -315.094112)
		(end 253.423928 -314.993528)
		(width 0.1651)
		(layer "In7.Cu")
		(net "P5E_PEX2_STN7_TX_DN<115>")
	)
	(segment
		(start 258.642104 -305.67249)
		(end 259.247132 -305.284124)
		(width 0.1651)
		(layer "In7.Cu")
		(net "P5E_PEX2_STN7_TX_DN<115>")
	)
	(segment
		(start 276.079458 -304.184304)
		(end 276.079458 -304.335434)
		(width 0.1143)
		(layer "In7.Cu")
		(net "P5E_PEX2_STN7_TX_DN<115>")
	)
	(segment
		(start 258.321302 -306.04968)
		(end 258.48183 -305.860958)
		(width 0.1651)
		(layer "In7.Cu")
		(net "P5E_PEX2_STN7_TX_DN<115>")
	)
	(segment
		(start 254.659638 -312.415428)
		(end 254.862076 -311.963054)
		(width 0.1651)
		(layer "In7.Cu")
		(net "P5E_PEX2_STN7_TX_DN<115>")
	)
	(segment
		(start 256.26187 -308.831996)
		(end 256.223516 -308.731412)
		(width 0.1651)
		(layer "In7.Cu")
		(net "P5E_PEX2_STN7_TX_DN<115>")
	)
	(segment
		(start 276.079458 -304.335434)
		(end 275.965158 -304.449734)
		(width 0.1143)
		(layer "In7.Cu")
		(net "P5E_PEX2_STN7_TX_DN<115>")
	)
	(segment
		(start 256.059432 -309.28437)
		(end 256.26187 -308.831996)
		(width 0.1651)
		(layer "In7.Cu")
		(net "P5E_PEX2_STN7_TX_DN<115>")
	)
	(segment
		(start 252.995684 -316.137798)
		(end 252.95733 -316.037214)
		(width 0.1651)
		(layer "In7.Cu")
		(net "P5E_PEX2_STN7_TX_DN<115>")
	)
	(segment
		(start 255.328674 -310.919368)
		(end 255.29032 -310.818784)
		(width 0.1651)
		(layer "In7.Cu")
		(net "P5E_PEX2_STN7_TX_DN<115>")
	)
	(segment
		(start 262.082026 -304.819304)
		(end 266.823952 -304.115724)
		(width 0.1651)
		(layer "In7.Cu")
		(net "P5E_PEX2_STN7_TX_DN<115>")
	)
	(segment
		(start 254.092456 -313.497722)
		(end 254.19304 -313.459114)
		(width 0.1651)
		(layer "In7.Cu")
		(net "P5E_PEX2_STN7_TX_DN<115>")
	)
	(segment
		(start 258.48183 -305.861212)
		(end 258.482084 -305.860704)
		(width 0.1651)
		(layer "In7.Cu")
		(net "P5E_PEX2_STN7_TX_DN<115>")
	)
	(segment
		(start 255.592834 -310.328056)
		(end 255.795272 -309.875682)
		(width 0.1651)
		(layer "In7.Cu")
		(net "P5E_PEX2_STN7_TX_DN<115>")
	)
	(segment
		(start 253.726442 -314.5028)
		(end 253.92888 -314.050426)
		(width 0.1651)
		(layer "In7.Cu")
		(net "P5E_PEX2_STN7_TX_DN<115>")
	)
	(segment
		(start 267.93952 -304.070004)
		(end 275.965158 -304.070004)
		(width 0.1143)
		(layer "In7.Cu")
		(net "P5E_PEX2_STN7_TX_DN<115>")
	)
	(segment
		(start 274.687792 -348.29496)
		(end 274.687792 -347.784674)
		(width 0.1651)
		(layer "In7.Cu")
		(net "P5E_PEX2_STN7_TX_DN<115>")
	)
	(segment
		(start 259.247132 -305.284124)
		(end 259.887212 -305.035712)
		(width 0.1651)
		(layer "In7.Cu")
		(net "P5E_PEX2_STN7_TX_DN<115>")
	)
	(segment
		(start 255.025652 -311.41035)
		(end 255.126236 -311.371742)
		(width 0.1651)
		(layer "In7.Cu")
		(net "P5E_PEX2_STN7_TX_DN<115>")
	)
	(segment
		(start 254.862076 -311.963054)
		(end 254.823722 -311.86247)
		(width 0.1651)
		(layer "In7.Cu")
		(net "P5E_PEX2_STN7_TX_DN<115>")
	)
	(segment
		(start 251.89434 -318.414146)
		(end 252.692662 -316.62878)
		(width 0.1651)
		(layer "In7.Cu")
		(net "P5E_PEX2_STN7_TX_DN<115>")
	)
	(segment
		(start 257.268218 -307.405532)
		(end 257.589528 -307.028088)
		(width 0.1651)
		(layer "In7.Cu")
		(net "P5E_PEX2_STN7_TX_DN<115>")
	)
	(segment
		(start 255.795272 -309.875682)
		(end 255.756918 -309.775098)
		(width 0.1651)
		(layer "In7.Cu")
		(net "P5E_PEX2_STN7_TX_DN<115>")
	)
	(segment
		(start 258.48183 -305.860958)
		(end 258.48183 -305.861212)
		(width 0.1651)
		(layer "In7.Cu")
		(net "P5E_PEX2_STN7_TX_DN<115>")
	)
	(segment
		(start 253.259844 -315.546486)
		(end 253.462282 -315.094112)
		(width 0.1651)
		(layer "In7.Cu")
		(net "P5E_PEX2_STN7_TX_DN<115>")
	)
	(segment
		(start 275.77288 -341.053674)
		(end 274.301712 -339.659214)
		(width 0.1651)
		(layer "In7.Cu")
		(net "P5E_PEX2_STN7_TX_DN<115>")
	)
	(segment
		(start 275.965158 -304.449734)
		(end 275.699728 -304.449734)
		(width 0.1143)
		(layer "In7.Cu")
		(net "P5E_PEX2_STN7_TX_DN<115>")
	)
	(segment
		(start 259.887212 -305.035712)
		(end 262.082026 -304.819304)
		(width 0.1651)
		(layer "In7.Cu")
		(net "P5E_PEX2_STN7_TX_DN<115>")
	)
	(segment
		(start 253.423928 -314.993528)
		(end 253.625858 -314.541408)
		(width 0.1651)
		(layer "In7.Cu")
		(net "P5E_PEX2_STN7_TX_DN<115>")
	)
	(segment
		(start 274.687792 -347.784674)
		(end 276.242272 -346.230194)
		(width 0.1651)
		(layer "In7.Cu")
		(net "P5E_PEX2_STN7_TX_DN<115>")
	)
	(segment
		(start 266.823952 -304.115724)
		(end 267.865352 -304.115724)
		(width 0.1651)
		(layer "In7.Cu")
		(net "P5E_PEX2_STN7_TX_DN<115>")
	)
	(segment
		(start 254.559054 -312.454036)
		(end 254.659638 -312.415428)
		(width 0.1651)
		(layer "In7.Cu")
		(net "P5E_PEX2_STN7_TX_DN<115>")
	)
	(segment
		(start 257.580638 -306.920646)
		(end 257.90144 -306.543456)
		(width 0.1651)
		(layer "In7.Cu")
		(net "P5E_PEX2_STN7_TX_DN<115>")
	)
	(segment
		(start 256.147316 -329.645518)
		(end 253.259844 -326.416924)
		(width 0.1651)
		(layer "In7.Cu")
		(net "P5E_PEX2_STN7_TX_DN<115>")
	)
	(segment
		(start 253.92888 -314.050426)
		(end 253.890526 -313.949842)
		(width 0.1651)
		(layer "In7.Cu")
		(net "P5E_PEX2_STN7_TX_DN<115>")
	)
	(segment
		(start 267.865352 -304.115724)
		(end 267.8938 -304.115724)
		(width 0.1143)
		(layer "In7.Cu")
		(net "P5E_PEX2_STN7_TX_DN<115>")
	)
	(segment
		(start 252.95733 -316.037214)
		(end 253.15926 -315.585094)
		(width 0.1651)
		(layer "In7.Cu")
		(net "P5E_PEX2_STN7_TX_DN<115>")
	)
	(segment
		(start 251.89434 -323.120766)
		(end 251.89434 -318.414146)
		(width 0.1651)
		(layer "In7.Cu")
		(net "P5E_PEX2_STN7_TX_DN<115>")
	)
	(segment
		(start 258.482084 -305.860704)
		(end 258.642104 -305.67249)
		(width 0.1651)
		(layer "In7.Cu")
		(net "P5E_PEX2_STN7_TX_DN<115>")
	)
	(segment
		(start 255.958848 -309.322978)
		(end 256.059432 -309.28437)
		(width 0.1651)
		(layer "In7.Cu")
		(net "P5E_PEX2_STN7_TX_DN<115>")
	)
	(segment
		(start 252.793246 -316.590172)
		(end 252.995684 -316.137798)
		(width 0.1651)
		(layer "In7.Cu")
		(net "P5E_PEX2_STN7_TX_DN<115>")
	)
	(segment
		(start 252.692662 -316.62878)
		(end 252.793246 -316.590172)
		(width 0.1651)
		(layer "In7.Cu")
		(net "P5E_PEX2_STN7_TX_DN<115>")
	)
	(segment
		(start 256.425446 -308.279292)
		(end 257.160776 -307.414422)
		(width 0.1651)
		(layer "In7.Cu")
		(net "P5E_PEX2_STN7_TX_DN<115>")
	)
	(segment
		(start 254.395478 -313.00674)
		(end 254.357124 -312.906156)
		(width 0.1651)
		(layer "In7.Cu")
		(net "P5E_PEX2_STN7_TX_DN<115>")
	)
	(segment
		(start 257.160776 -307.414422)
		(end 257.268218 -307.405532)
		(width 0.1651)
		(layer "In7.Cu")
		(net "P5E_PEX2_STN7_TX_DN<115>")
	)
	(segment
		(start 253.259844 -326.416924)
		(end 251.89434 -323.120766)
		(width 0.1651)
		(layer "In7.Cu")
		(net "P5E_PEX2_STN7_TX_DN<115>")
	)
	(segment
		(start 255.126236 -311.371742)
		(end 255.328674 -310.919368)
		(width 0.1651)
		(layer "In7.Cu")
		(net "P5E_PEX2_STN7_TX_DN<115>")
	)
	(segment
		(start 276.242272 -346.230194)
		(end 276.242272 -342.145112)
		(width 0.1651)
		(layer "In7.Cu")
		(net "P5E_PEX2_STN7_TX_DN<115>")
	)
	(segment
		(start 253.15926 -315.585094)
		(end 253.259844 -315.546486)
		(width 0.1651)
		(layer "In7.Cu")
		(net "P5E_PEX2_STN7_TX_DN<115>")
	)
	(segment
		(start 276.242272 -342.145112)
		(end 275.77288 -341.053674)
		(width 0.1651)
		(layer "In7.Cu")
		(net "P5E_PEX2_STN7_TX_DN<115>")
	)
	(segment
		(start 253.625858 -314.541408)
		(end 253.726442 -314.5028)
		(width 0.1651)
		(layer "In7.Cu")
		(net "P5E_PEX2_STN7_TX_DN<115>")
	)
	(segment
		(start 267.8938 -304.115724)
		(end 267.93952 -304.070004)
		(width 0.1143)
		(layer "In7.Cu")
		(net "P5E_PEX2_STN7_TX_DN<115>")
	)
	(segment
		(start 275.965158 -304.070004)
		(end 276.079458 -304.184304)
		(width 0.1143)
		(layer "In7.Cu")
		(net "P5E_PEX2_STN7_TX_DN<115>")
	)
	(segment
		(start 255.49225 -310.366664)
		(end 255.592834 -310.328056)
		(width 0.1651)
		(layer "In7.Cu")
		(net "P5E_PEX2_STN7_TX_DN<115>")
	)
	(segment
		(start 257.589528 -307.028088)
		(end 257.580638 -306.920646)
		(width 0.1651)
		(layer "In7.Cu")
		(net "P5E_PEX2_STN7_TX_DN<115>")
	)
	(segment
		(start 254.19304 -313.459114)
		(end 254.395478 -313.00674)
		(width 0.1651)
		(layer "In7.Cu")
		(net "P5E_PEX2_STN7_TX_DN<115>")
	)
	(segment
		(start 383.4257 -119.224298)
		(end 383.713482 -119.51208)
		(width 0.13462)
		(layer "F.Cu")
		(net "P5E_PEX3_STN1_TX_DP<24>")
	)
	(segment
		(start 384.358642 -119.51208)
		(end 384.671824 -119.198898)
		(width 0.13462)
		(layer "F.Cu")
		(net "P5E_PEX3_STN1_TX_DP<24>")
	)
	(segment
		(start 383.713482 -119.51208)
		(end 384.358642 -119.51208)
		(width 0.13462)
		(layer "F.Cu")
		(net "P5E_PEX3_STN1_TX_DP<24>")
	)
	(segment
		(start 415.194496 -278.420068)
		(end 414.979612 -278.205184)
		(width 0.1143)
		(layer "In9.Cu")
		(net "P5E_PEX3_STN1_TX_DP<24>")
	)
	(segment
		(start 415.549588 -278.534368)
		(end 415.435288 -278.420068)
		(width 0.1143)
		(layer "In9.Cu")
		(net "P5E_PEX3_STN1_TX_DP<24>")
	)
	(segment
		(start 380.64313 -121.253758)
		(end 382.38176 -119.515128)
		(width 0.1651)
		(layer "In9.Cu")
		(net "P5E_PEX3_STN1_TX_DP<24>")
	)
	(segment
		(start 383.13487 -119.515128)
		(end 383.4257 -119.224298)
		(width 0.1651)
		(layer "In9.Cu")
		(net "P5E_PEX3_STN1_TX_DP<24>")
	)
	(segment
		(start 382.38176 -119.515128)
		(end 383.13487 -119.515128)
		(width 0.1651)
		(layer "In9.Cu")
		(net "P5E_PEX3_STN1_TX_DP<24>")
	)
	(segment
		(start 376.247152 -137.452608)
		(end 376.247152 -131.866386)
		(width 0.1651)
		(layer "In9.Cu")
		(net "P5E_PEX3_STN1_TX_DP<24>")
	)
	(segment
		(start 414.933892 -264.281666)
		(end 380.121922 -161.439098)
		(width 0.1651)
		(layer "In9.Cu")
		(net "P5E_PEX3_STN1_TX_DP<24>")
	)
	(segment
		(start 415.549588 -278.799798)
		(end 415.549588 -278.534368)
		(width 0.1143)
		(layer "In9.Cu")
		(net "P5E_PEX3_STN1_TX_DP<24>")
	)
	(segment
		(start 414.933892 -271.471898)
		(end 414.933892 -264.281666)
		(width 0.1651)
		(layer "In9.Cu")
		(net "P5E_PEX3_STN1_TX_DP<24>")
	)
	(segment
		(start 415.435288 -278.420068)
		(end 415.194496 -278.420068)
		(width 0.1143)
		(layer "In9.Cu")
		(net "P5E_PEX3_STN1_TX_DP<24>")
	)
	(segment
		(start 378.804678 -143.627094)
		(end 376.247152 -137.452608)
		(width 0.1651)
		(layer "In9.Cu")
		(net "P5E_PEX3_STN1_TX_DP<24>")
	)
	(segment
		(start 414.979612 -271.546066)
		(end 414.933892 -271.500346)
		(width 0.1143)
		(layer "In9.Cu")
		(net "P5E_PEX3_STN1_TX_DP<24>")
	)
	(segment
		(start 414.979612 -278.205184)
		(end 414.979612 -271.546066)
		(width 0.1143)
		(layer "In9.Cu")
		(net "P5E_PEX3_STN1_TX_DP<24>")
	)
	(segment
		(start 376.247152 -131.866386)
		(end 380.64313 -121.253758)
		(width 0.1651)
		(layer "In9.Cu")
		(net "P5E_PEX3_STN1_TX_DP<24>")
	)
	(segment
		(start 414.933892 -271.500346)
		(end 414.933892 -271.471898)
		(width 0.1143)
		(layer "In9.Cu")
		(net "P5E_PEX3_STN1_TX_DP<24>")
	)
	(segment
		(start 380.121922 -161.439098)
		(end 379.53569 -158.49219)
		(width 0.1651)
		(layer "In9.Cu")
		(net "P5E_PEX3_STN1_TX_DP<24>")
	)
	(segment
		(start 379.53569 -158.49219)
		(end 378.804678 -143.627094)
		(width 0.1651)
		(layer "In9.Cu")
		(net "P5E_PEX3_STN1_TX_DP<24>")
	)
	(segment
		(start 415.487612 -355.978206)
		(end 415.807144 -355.658674)
		(width 0.13462)
		(layer "F.Cu")
		(net "P5E_PEX3_STN7_TX_DP<115>")
	)
	(segment
		(start 415.807144 -355.026214)
		(end 415.513012 -354.732082)
		(width 0.13462)
		(layer "F.Cu")
		(net "P5E_PEX3_STN7_TX_DP<115>")
	)
	(segment
		(start 415.807144 -355.658674)
		(end 415.807144 -355.026214)
		(width 0.13462)
		(layer "F.Cu")
		(net "P5E_PEX3_STN7_TX_DP<115>")
	)
	(segment
		(start 368.298222 -316.672468)
		(end 373.568722 -308.784498)
		(width 0.1651)
		(layer "In11.Cu")
		(net "P5E_PEX3_STN7_TX_DP<115>")
	)
	(segment
		(start 416.846512 -341.061802)
		(end 416.688778 -341.02675)
		(width 0.1651)
		(layer "In11.Cu")
		(net "P5E_PEX3_STN7_TX_DP<115>")
	)
	(segment
		(start 367.3602 -318.936878)
		(end 368.298222 -316.672468)
		(width 0.1651)
		(layer "In11.Cu")
		(net "P5E_PEX3_STN7_TX_DP<115>")
	)
	(segment
		(start 392.484356 -304.449734)
		(end 392.749786 -304.449734)
		(width 0.1143)
		(layer "In11.Cu")
		(net "P5E_PEX3_STN7_TX_DP<115>")
	)
	(segment
		(start 379.529086 -304.089816)
		(end 379.52934 -304.089308)
		(width 0.1651)
		(layer "In11.Cu")
		(net "P5E_PEX3_STN7_TX_DP<115>")
	)
	(segment
		(start 379.52934 -304.089308)
		(end 380.145798 -303.833784)
		(width 0.1651)
		(layer "In11.Cu")
		(net "P5E_PEX3_STN7_TX_DP<115>")
	)
	(segment
		(start 417.358068 -341.864696)
		(end 416.846512 -341.061802)
		(width 0.1651)
		(layer "In11.Cu")
		(net "P5E_PEX3_STN7_TX_DP<115>")
	)
	(segment
		(start 369.094512 -326.541892)
		(end 367.3602 -322.354702)
		(width 0.1651)
		(layer "In11.Cu")
		(net "P5E_PEX3_STN7_TX_DP<115>")
	)
	(segment
		(start 383.995168 -303.879504)
		(end 392.154918 -303.879504)
		(width 0.1143)
		(layer "In11.Cu")
		(net "P5E_PEX3_STN7_TX_DP<115>")
	)
	(segment
		(start 383.921 -303.833784)
		(end 383.949448 -303.833784)
		(width 0.1143)
		(layer "In11.Cu")
		(net "P5E_PEX3_STN7_TX_DP<115>")
	)
	(segment
		(start 416.688778 -341.02675)
		(end 416.422332 -340.60892)
		(width 0.1651)
		(layer "In11.Cu")
		(net "P5E_PEX3_STN7_TX_DP<115>")
	)
	(segment
		(start 415.803842 -354.441252)
		(end 415.803842 -353.814126)
		(width 0.1651)
		(layer "In11.Cu")
		(net "P5E_PEX3_STN7_TX_DP<115>")
	)
	(segment
		(start 383.949448 -303.833784)
		(end 383.995168 -303.879504)
		(width 0.1143)
		(layer "In11.Cu")
		(net "P5E_PEX3_STN7_TX_DP<115>")
	)
	(segment
		(start 367.3602 -322.354702)
		(end 367.3602 -318.936878)
		(width 0.1651)
		(layer "In11.Cu")
		(net "P5E_PEX3_STN7_TX_DP<115>")
	)
	(segment
		(start 415.803842 -353.814126)
		(end 417.358322 -352.259646)
		(width 0.1651)
		(layer "In11.Cu")
		(net "P5E_PEX3_STN7_TX_DP<115>")
	)
	(segment
		(start 392.370056 -304.335434)
		(end 392.484356 -304.449734)
		(width 0.1143)
		(layer "In11.Cu")
		(net "P5E_PEX3_STN7_TX_DP<115>")
	)
	(segment
		(start 377.368562 -304.984658)
		(end 379.529086 -304.089816)
		(width 0.1651)
		(layer "In11.Cu")
		(net "P5E_PEX3_STN7_TX_DP<115>")
	)
	(segment
		(start 417.358322 -352.259646)
		(end 417.358322 -341.86495)
		(width 0.1651)
		(layer "In11.Cu")
		(net "P5E_PEX3_STN7_TX_DP<115>")
	)
	(segment
		(start 416.45713 -340.451186)
		(end 416.047174 -339.80755)
		(width 0.1651)
		(layer "In11.Cu")
		(net "P5E_PEX3_STN7_TX_DP<115>")
	)
	(segment
		(start 415.513012 -354.732082)
		(end 415.803842 -354.441252)
		(width 0.1651)
		(layer "In11.Cu")
		(net "P5E_PEX3_STN7_TX_DP<115>")
	)
	(segment
		(start 392.370056 -304.094642)
		(end 392.370056 -304.335434)
		(width 0.1143)
		(layer "In11.Cu")
		(net "P5E_PEX3_STN7_TX_DP<115>")
	)
	(segment
		(start 416.422332 -340.60892)
		(end 416.45713 -340.451186)
		(width 0.1651)
		(layer "In11.Cu")
		(net "P5E_PEX3_STN7_TX_DP<115>")
	)
	(segment
		(start 374.466612 -330.49083)
		(end 371.303042 -328.750676)
		(width 0.1651)
		(layer "In11.Cu")
		(net "P5E_PEX3_STN7_TX_DP<115>")
	)
	(segment
		(start 373.568722 -308.784498)
		(end 377.368562 -304.984658)
		(width 0.1651)
		(layer "In11.Cu")
		(net "P5E_PEX3_STN7_TX_DP<115>")
	)
	(segment
		(start 371.303042 -328.750676)
		(end 369.094512 -326.541892)
		(width 0.1651)
		(layer "In11.Cu")
		(net "P5E_PEX3_STN7_TX_DP<115>")
	)
	(segment
		(start 392.154918 -303.879504)
		(end 392.370056 -304.094642)
		(width 0.1143)
		(layer "In11.Cu")
		(net "P5E_PEX3_STN7_TX_DP<115>")
	)
	(segment
		(start 417.358322 -341.86495)
		(end 417.358068 -341.864696)
		(width 0.1651)
		(layer "In11.Cu")
		(net "P5E_PEX3_STN7_TX_DP<115>")
	)
	(segment
		(start 416.047174 -339.80755)
		(end 374.466612 -330.49083)
		(width 0.1651)
		(layer "In11.Cu")
		(net "P5E_PEX3_STN7_TX_DP<115>")
	)
	(segment
		(start 380.145798 -303.833784)
		(end 383.921 -303.833784)
		(width 0.1651)
		(layer "In11.Cu")
		(net "P5E_PEX3_STN7_TX_DP<115>")
	)
	(segment
		(start 187.057792 -357.733854)
		(end 187.352432 -357.439214)
		(width 0.13462)
		(layer "F.Cu")
		(net "P5E_PEX1_STN7_TX_C_DP<125>")
	)
	(segment
		(start 187.352432 -356.80777)
		(end 187.032392 -356.48773)
		(width 0.13462)
		(layer "F.Cu")
		(net "P5E_PEX1_STN7_TX_C_DP<125>")
	)
	(segment
		(start 187.352432 -357.439214)
		(end 187.352432 -356.80777)
		(width 0.13462)
		(layer "F.Cu")
		(net "P5E_PEX1_STN7_TX_C_DP<125>")
	)
	(segment
		(start 172.762164 -367.822988)
		(end 171.785534 -368.799618)
		(width 0.1651)
		(layer "In11.Cu")
		(net "P5E_PEX1_STN7_TX_C_DP<125>")
	)
	(segment
		(start 184.119266 -362.178346)
		(end 183.768746 -362.528866)
		(width 0.1651)
		(layer "In11.Cu")
		(net "P5E_PEX1_STN7_TX_C_DP<125>")
	)
	(segment
		(start 170.909996 -375.872248)
		(end 170.909996 -375.490232)
		(width 0.1651)
		(layer "In11.Cu")
		(net "P5E_PEX1_STN7_TX_C_DP<125>")
	)
	(segment
		(start 183.768746 -362.528866)
		(end 183.768746 -362.672376)
		(width 0.1651)
		(layer "In11.Cu")
		(net "P5E_PEX1_STN7_TX_C_DP<125>")
	)
	(segment
		(start 171.258484 -375.999248)
		(end 171.036996 -375.999248)
		(width 0.1651)
		(layer "In11.Cu")
		(net "P5E_PEX1_STN7_TX_C_DP<125>")
	)
	(segment
		(start 187.348622 -359.0925)
		(end 184.262776 -362.178346)
		(width 0.1651)
		(layer "In11.Cu")
		(net "P5E_PEX1_STN7_TX_C_DP<125>")
	)
	(segment
		(start 187.348622 -358.024684)
		(end 187.348622 -359.0925)
		(width 0.1651)
		(layer "In11.Cu")
		(net "P5E_PEX1_STN7_TX_C_DP<125>")
	)
	(segment
		(start 183.768746 -362.672376)
		(end 182.854854 -363.586268)
		(width 0.1651)
		(layer "In11.Cu")
		(net "P5E_PEX1_STN7_TX_C_DP<125>")
	)
	(segment
		(start 184.262776 -362.178346)
		(end 184.119266 -362.178346)
		(width 0.1651)
		(layer "In11.Cu")
		(net "P5E_PEX1_STN7_TX_C_DP<125>")
	)
	(segment
		(start 171.785534 -375.472198)
		(end 171.258484 -375.999248)
		(width 0.1651)
		(layer "In11.Cu")
		(net "P5E_PEX1_STN7_TX_C_DP<125>")
	)
	(segment
		(start 171.785534 -368.799618)
		(end 171.785534 -375.472198)
		(width 0.1651)
		(layer "In11.Cu")
		(net "P5E_PEX1_STN7_TX_C_DP<125>")
	)
	(segment
		(start 171.036996 -375.999248)
		(end 170.909996 -375.872248)
		(width 0.1651)
		(layer "In11.Cu")
		(net "P5E_PEX1_STN7_TX_C_DP<125>")
	)
	(segment
		(start 182.854854 -363.586268)
		(end 172.762164 -367.822988)
		(width 0.1651)
		(layer "In11.Cu")
		(net "P5E_PEX1_STN7_TX_C_DP<125>")
	)
	(segment
		(start 187.057792 -357.733854)
		(end 187.348622 -358.024684)
		(width 0.1651)
		(layer "In11.Cu")
		(net "P5E_PEX1_STN7_TX_C_DP<125>")
	)
	(segment
		(start 189.739778 -33.96488)
		(end 189.134242 -33.96488)
		(width 0.13462)
		(layer "F.Cu")
		(net "P5E_PEX1_STN2_TX_DN<39>")
	)
	(segment
		(start 189.134242 -33.96488)
		(end 188.801248 -33.631886)
		(width 0.13462)
		(layer "F.Cu")
		(net "P5E_PEX1_STN2_TX_DN<39>")
	)
	(segment
		(start 190.047372 -33.657286)
		(end 189.739778 -33.96488)
		(width 0.13462)
		(layer "F.Cu")
		(net "P5E_PEX1_STN2_TX_DN<39>")
	)
	(segment
		(start 202.982576 -63.834518)
		(end 180.730906 -92.81541)
		(width 0.1651)
		(layer "In11.Cu")
		(net "P5E_PEX1_STN2_TX_DN<39>")
	)
	(segment
		(start 167.770302 -278.125936)
		(end 167.873934 -278.229568)
		(width 0.1143)
		(layer "In11.Cu")
		(net "P5E_PEX1_STN2_TX_DN<39>")
	)
	(segment
		(start 168.150032 -278.115268)
		(end 168.150032 -277.849838)
		(width 0.1143)
		(layer "In11.Cu")
		(net "P5E_PEX1_STN2_TX_DN<39>")
	)
	(segment
		(start 167.770302 -271.473168)
		(end 167.770302 -278.125936)
		(width 0.1143)
		(layer "In11.Cu")
		(net "P5E_PEX1_STN2_TX_DN<39>")
	)
	(segment
		(start 203.876402 -62.053724)
		(end 202.982576 -63.834518)
		(width 0.1651)
		(layer "In11.Cu")
		(net "P5E_PEX1_STN2_TX_DN<39>")
	)
	(segment
		(start 191.471296 -34.181034)
		(end 193.126106 -35.848798)
		(width 0.1651)
		(layer "In11.Cu")
		(net "P5E_PEX1_STN2_TX_DN<39>")
	)
	(segment
		(start 167.816022 -262.799068)
		(end 167.816022 -271.399)
		(width 0.1651)
		(layer "In11.Cu")
		(net "P5E_PEX1_STN2_TX_DN<39>")
	)
	(segment
		(start 175.278288 -120.544336)
		(end 175.16602 -121.457974)
		(width 0.1651)
		(layer "In11.Cu")
		(net "P5E_PEX1_STN2_TX_DN<39>")
	)
	(segment
		(start 193.126106 -35.848798)
		(end 196.795136 -41.84396)
		(width 0.1651)
		(layer "In11.Cu")
		(net "P5E_PEX1_STN2_TX_DN<39>")
	)
	(segment
		(start 204.377036 -58.541412)
		(end 204.377036 -60.165234)
		(width 0.1651)
		(layer "In11.Cu")
		(net "P5E_PEX1_STN2_TX_DN<39>")
	)
	(segment
		(start 180.730906 -92.81541)
		(end 177.446178 -107.220512)
		(width 0.1651)
		(layer "In11.Cu")
		(net "P5E_PEX1_STN2_TX_DN<39>")
	)
	(segment
		(start 177.446178 -107.220512)
		(end 176.025556 -114.480086)
		(width 0.1651)
		(layer "In11.Cu")
		(net "P5E_PEX1_STN2_TX_DN<39>")
	)
	(segment
		(start 175.16602 -121.457974)
		(end 167.816022 -262.799068)
		(width 0.1651)
		(layer "In11.Cu")
		(net "P5E_PEX1_STN2_TX_DN<39>")
	)
	(segment
		(start 190.338202 -33.948116)
		(end 190.911988 -33.948116)
		(width 0.1651)
		(layer "In11.Cu")
		(net "P5E_PEX1_STN2_TX_DN<39>")
	)
	(segment
		(start 190.911988 -33.948116)
		(end 191.471296 -34.181034)
		(width 0.1651)
		(layer "In11.Cu")
		(net "P5E_PEX1_STN2_TX_DN<39>")
	)
	(segment
		(start 168.035732 -278.229568)
		(end 168.150032 -278.115268)
		(width 0.1143)
		(layer "In11.Cu")
		(net "P5E_PEX1_STN2_TX_DN<39>")
	)
	(segment
		(start 167.873934 -278.229568)
		(end 168.035732 -278.229568)
		(width 0.1143)
		(layer "In11.Cu")
		(net "P5E_PEX1_STN2_TX_DN<39>")
	)
	(segment
		(start 176.025556 -114.480086)
		(end 175.278796 -120.544336)
		(width 0.1651)
		(layer "In11.Cu")
		(net "P5E_PEX1_STN2_TX_DN<39>")
	)
	(segment
		(start 204.377036 -60.165234)
		(end 203.876402 -62.053724)
		(width 0.1651)
		(layer "In11.Cu")
		(net "P5E_PEX1_STN2_TX_DN<39>")
	)
	(segment
		(start 175.278796 -120.544336)
		(end 175.278288 -120.544336)
		(width 0.1651)
		(layer "In11.Cu")
		(net "P5E_PEX1_STN2_TX_DN<39>")
	)
	(segment
		(start 196.795136 -41.84396)
		(end 203.382372 -49.033938)
		(width 0.1651)
		(layer "In11.Cu")
		(net "P5E_PEX1_STN2_TX_DN<39>")
	)
	(segment
		(start 203.382372 -49.033938)
		(end 204.377036 -58.541412)
		(width 0.1651)
		(layer "In11.Cu")
		(net "P5E_PEX1_STN2_TX_DN<39>")
	)
	(segment
		(start 190.047372 -33.657286)
		(end 190.338202 -33.948116)
		(width 0.1651)
		(layer "In11.Cu")
		(net "P5E_PEX1_STN2_TX_DN<39>")
	)
	(segment
		(start 167.816022 -271.399)
		(end 167.816022 -271.427448)
		(width 0.1143)
		(layer "In11.Cu")
		(net "P5E_PEX1_STN2_TX_DN<39>")
	)
	(segment
		(start 167.816022 -271.427448)
		(end 167.770302 -271.473168)
		(width 0.1143)
		(layer "In11.Cu")
		(net "P5E_PEX1_STN2_TX_DN<39>")
	)
	(segment
		(start 316.080902 -148.31568)
		(end 315.446918 -148.31568)
		(width 0.13462)
		(layer "F.Cu")
		(net "P5E_PEX2_STN0_TX_DN<11>")
	)
	(segment
		(start 315.446918 -148.31568)
		(end 315.128148 -147.99691)
		(width 0.13462)
		(layer "F.Cu")
		(net "P5E_PEX2_STN0_TX_DN<11>")
	)
	(segment
		(start 316.374272 -148.02231)
		(end 316.080902 -148.31568)
		(width 0.13462)
		(layer "F.Cu")
		(net "P5E_PEX2_STN0_TX_DN<11>")
	)
	(segment
		(start 319.00876 -149.859746)
		(end 320.58991 -152.22601)
		(width 0.1651)
		(layer "In9.Cu")
		(net "P5E_PEX2_STN0_TX_DN<11>")
	)
	(segment
		(start 310.470042 -271.546066)
		(end 310.470042 -278.12619)
		(width 0.1143)
		(layer "In9.Cu")
		(net "P5E_PEX2_STN0_TX_DN<11>")
	)
	(segment
		(start 310.849518 -278.115268)
		(end 310.849518 -277.849838)
		(width 0.1143)
		(layer "In9.Cu")
		(net "P5E_PEX2_STN0_TX_DN<11>")
	)
	(segment
		(start 310.515762 -271.500346)
		(end 310.470042 -271.546066)
		(width 0.1143)
		(layer "In9.Cu")
		(net "P5E_PEX2_STN0_TX_DN<11>")
	)
	(segment
		(start 311.46115 -268.64691)
		(end 310.515762 -270.929608)
		(width 0.1651)
		(layer "In9.Cu")
		(net "P5E_PEX2_STN0_TX_DN<11>")
	)
	(segment
		(start 319.00876 -149.852126)
		(end 319.00876 -149.859746)
		(width 0.1651)
		(layer "In9.Cu")
		(net "P5E_PEX2_STN0_TX_DN<11>")
	)
	(segment
		(start 312.00471 -177.303684)
		(end 308.082696 -222.13189)
		(width 0.1651)
		(layer "In9.Cu")
		(net "P5E_PEX2_STN0_TX_DN<11>")
	)
	(segment
		(start 310.57342 -278.229568)
		(end 310.735218 -278.229568)
		(width 0.1143)
		(layer "In9.Cu")
		(net "P5E_PEX2_STN0_TX_DN<11>")
	)
	(segment
		(start 310.515762 -271.471898)
		(end 310.515762 -271.500346)
		(width 0.1143)
		(layer "In9.Cu")
		(net "P5E_PEX2_STN0_TX_DN<11>")
	)
	(segment
		(start 308.082696 -222.13189)
		(end 311.46115 -260.775704)
		(width 0.1651)
		(layer "In9.Cu")
		(net "P5E_PEX2_STN0_TX_DN<11>")
	)
	(segment
		(start 316.665102 -148.31314)
		(end 317.469774 -148.31314)
		(width 0.1651)
		(layer "In9.Cu")
		(net "P5E_PEX2_STN0_TX_DN<11>")
	)
	(segment
		(start 311.46115 -260.775704)
		(end 311.46115 -268.64691)
		(width 0.1651)
		(layer "In9.Cu")
		(net "P5E_PEX2_STN0_TX_DN<11>")
	)
	(segment
		(start 310.735218 -278.229568)
		(end 310.849518 -278.115268)
		(width 0.1143)
		(layer "In9.Cu")
		(net "P5E_PEX2_STN0_TX_DN<11>")
	)
	(segment
		(start 316.374272 -148.02231)
		(end 316.665102 -148.31314)
		(width 0.1651)
		(layer "In9.Cu")
		(net "P5E_PEX2_STN0_TX_DN<11>")
	)
	(segment
		(start 320.58991 -152.22601)
		(end 321.722242 -154.959558)
		(width 0.1651)
		(layer "In9.Cu")
		(net "P5E_PEX2_STN0_TX_DN<11>")
	)
	(segment
		(start 310.470042 -278.12619)
		(end 310.57342 -278.229568)
		(width 0.1143)
		(layer "In9.Cu")
		(net "P5E_PEX2_STN0_TX_DN<11>")
	)
	(segment
		(start 317.469774 -148.31314)
		(end 319.00876 -149.852126)
		(width 0.1651)
		(layer "In9.Cu")
		(net "P5E_PEX2_STN0_TX_DN<11>")
	)
	(segment
		(start 313.360562 -172.248576)
		(end 312.00471 -177.303684)
		(width 0.1651)
		(layer "In9.Cu")
		(net "P5E_PEX2_STN0_TX_DN<11>")
	)
	(segment
		(start 310.515762 -270.929608)
		(end 310.515762 -271.471898)
		(width 0.1651)
		(layer "In9.Cu")
		(net "P5E_PEX2_STN0_TX_DN<11>")
	)
	(segment
		(start 321.722242 -154.959558)
		(end 321.722242 -157.763464)
		(width 0.1651)
		(layer "In9.Cu")
		(net "P5E_PEX2_STN0_TX_DN<11>")
	)
	(segment
		(start 321.722242 -157.763464)
		(end 313.360562 -172.248576)
		(width 0.1651)
		(layer "In9.Cu")
		(net "P5E_PEX2_STN0_TX_DN<11>")
	)
	(segment
		(start 296.766742 -343.685622)
		(end 296.446702 -343.365582)
		(width 0.13462)
		(layer "F.Cu")
		(net "P5E_PEX2_STN7_TX_DN<125>")
	)
	(segment
		(start 296.446702 -342.734138)
		(end 296.741342 -342.439498)
		(width 0.13462)
		(layer "F.Cu")
		(net "P5E_PEX2_STN7_TX_DN<125>")
	)
	(segment
		(start 296.446702 -343.365582)
		(end 296.446702 -342.734138)
		(width 0.13462)
		(layer "F.Cu")
		(net "P5E_PEX2_STN7_TX_DN<125>")
	)
	(segment
		(start 272.584418 -313.570112)
		(end 272.735548 -313.570112)
		(width 0.1143)
		(layer "In7.Cu")
		(net "P5E_PEX2_STN7_TX_DN<125>")
	)
	(segment
		(start 272.515838 -319.8876)
		(end 272.470118 -319.84188)
		(width 0.1143)
		(layer "In7.Cu")
		(net "P5E_PEX2_STN7_TX_DN<125>")
	)
	(segment
		(start 272.470118 -319.84188)
		(end 272.470118 -313.684412)
		(width 0.1143)
		(layer "In7.Cu")
		(net "P5E_PEX2_STN7_TX_DN<125>")
	)
	(segment
		(start 272.849848 -313.684412)
		(end 272.849848 -313.949842)
		(width 0.1143)
		(layer "In7.Cu")
		(net "P5E_PEX2_STN7_TX_DN<125>")
	)
	(segment
		(start 296.450512 -342.148668)
		(end 296.450512 -341.504524)
		(width 0.1651)
		(layer "In7.Cu")
		(net "P5E_PEX2_STN7_TX_DN<125>")
	)
	(segment
		(start 296.450512 -341.504524)
		(end 295.580054 -340.364572)
		(width 0.1651)
		(layer "In7.Cu")
		(net "P5E_PEX2_STN7_TX_DN<125>")
	)
	(segment
		(start 296.741342 -342.439498)
		(end 296.450512 -342.148668)
		(width 0.1651)
		(layer "In7.Cu")
		(net "P5E_PEX2_STN7_TX_DN<125>")
	)
	(segment
		(start 272.470118 -313.684412)
		(end 272.584418 -313.570112)
		(width 0.1143)
		(layer "In7.Cu")
		(net "P5E_PEX2_STN7_TX_DN<125>")
	)
	(segment
		(start 272.515838 -321.03568)
		(end 272.515838 -319.916048)
		(width 0.1651)
		(layer "In7.Cu")
		(net "P5E_PEX2_STN7_TX_DN<125>")
	)
	(segment
		(start 295.580054 -340.364572)
		(end 273.22399 -322.423536)
		(width 0.1651)
		(layer "In7.Cu")
		(net "P5E_PEX2_STN7_TX_DN<125>")
	)
	(segment
		(start 273.22399 -322.423536)
		(end 272.996406 -322.195952)
		(width 0.1651)
		(layer "In7.Cu")
		(net "P5E_PEX2_STN7_TX_DN<125>")
	)
	(segment
		(start 272.735548 -313.570112)
		(end 272.849848 -313.684412)
		(width 0.1143)
		(layer "In7.Cu")
		(net "P5E_PEX2_STN7_TX_DN<125>")
	)
	(segment
		(start 272.515838 -319.916048)
		(end 272.515838 -319.8876)
		(width 0.1143)
		(layer "In7.Cu")
		(net "P5E_PEX2_STN7_TX_DN<125>")
	)
	(segment
		(start 272.996406 -322.195952)
		(end 272.515838 -321.03568)
		(width 0.1651)
		(layer "In7.Cu")
		(net "P5E_PEX2_STN7_TX_DN<125>")
	)
	(segment
		(start 386.366004 -103.4796)
		(end 386.990336 -103.4796)
		(width 0.13462)
		(layer "F.Cu")
		(net "P5E_PEX3_STN1_TX_DN<18>")
	)
	(segment
		(start 386.990336 -103.4796)
		(end 387.313932 -103.803196)
		(width 0.13462)
		(layer "F.Cu")
		(net "P5E_PEX3_STN1_TX_DN<18>")
	)
	(segment
		(start 386.067808 -103.777796)
		(end 386.366004 -103.4796)
		(width 0.13462)
		(layer "F.Cu")
		(net "P5E_PEX3_STN1_TX_DN<18>")
	)
	(segment
		(start 409.515818 -271.500346)
		(end 409.515818 -271.471898)
		(width 0.1143)
		(layer "In9.Cu")
		(net "P5E_PEX3_STN1_TX_DN<18>")
	)
	(segment
		(start 379.494034 -106.84002)
		(end 379.655578 -106.84002)
		(width 0.1651)
		(layer "In9.Cu")
		(net "P5E_PEX3_STN1_TX_DN<18>")
	)
	(segment
		(start 382.82245 -103.977694)
		(end 382.971802 -104.039416)
		(width 0.1651)
		(layer "In9.Cu")
		(net "P5E_PEX3_STN1_TX_DN<18>")
	)
	(segment
		(start 378.494036 -107.840018)
		(end 379.494034 -106.84002)
		(width 0.1651)
		(layer "In9.Cu")
		(net "P5E_PEX3_STN1_TX_DN<18>")
	)
	(segment
		(start 384.406394 -103.486966)
		(end 384.520694 -103.601266)
		(width 0.1651)
		(layer "In9.Cu")
		(net "P5E_PEX3_STN1_TX_DN<18>")
	)
	(segment
		(start 385.117594 -103.486966)
		(end 385.776978 -103.486966)
		(width 0.1651)
		(layer "In9.Cu")
		(net "P5E_PEX3_STN1_TX_DN<18>")
	)
	(segment
		(start 378.145294 -108.682028)
		(end 378.494036 -107.840018)
		(width 0.1651)
		(layer "In9.Cu")
		(net "P5E_PEX3_STN1_TX_DN<18>")
	)
	(segment
		(start 377.551188 -110.415832)
		(end 377.740672 -109.95787)
		(width 0.1651)
		(layer "In9.Cu")
		(net "P5E_PEX3_STN1_TX_DN<18>")
	)
	(segment
		(start 378.017786 -109.289088)
		(end 378.20727 -108.83138)
		(width 0.1651)
		(layer "In9.Cu")
		(net "P5E_PEX3_STN1_TX_DN<18>")
	)
	(segment
		(start 377.212098 -110.935008)
		(end 377.401582 -110.477554)
		(width 0.1651)
		(layer "In9.Cu")
		(net "P5E_PEX3_STN1_TX_DN<18>")
	)
	(segment
		(start 409.735274 -278.229568)
		(end 409.573476 -278.229568)
		(width 0.1143)
		(layer "In9.Cu")
		(net "P5E_PEX3_STN1_TX_DN<18>")
	)
	(segment
		(start 380.841504 -105.654094)
		(end 380.841504 -105.49255)
		(width 0.1651)
		(layer "In9.Cu")
		(net "P5E_PEX3_STN1_TX_DN<18>")
	)
	(segment
		(start 382.026922 -104.307132)
		(end 382.82245 -103.977694)
		(width 0.1651)
		(layer "In9.Cu")
		(net "P5E_PEX3_STN1_TX_DN<18>")
	)
	(segment
		(start 379.997208 -106.336846)
		(end 380.33833 -105.995724)
		(width 0.1651)
		(layer "In9.Cu")
		(net "P5E_PEX3_STN1_TX_DN<18>")
	)
	(segment
		(start 384.520694 -103.601266)
		(end 385.003294 -103.601266)
		(width 0.1651)
		(layer "In9.Cu")
		(net "P5E_PEX3_STN1_TX_DN<18>")
	)
	(segment
		(start 385.776978 -103.486966)
		(end 386.067808 -103.777796)
		(width 0.1651)
		(layer "In9.Cu")
		(net "P5E_PEX3_STN1_TX_DN<18>")
	)
	(segment
		(start 383.479802 -103.70566)
		(end 384.006852 -103.486966)
		(width 0.1651)
		(layer "In9.Cu")
		(net "P5E_PEX3_STN1_TX_DN<18>")
	)
	(segment
		(start 409.515818 -271.471898)
		(end 409.515818 -265.511534)
		(width 0.1651)
		(layer "In9.Cu")
		(net "P5E_PEX3_STN1_TX_DN<18>")
	)
	(segment
		(start 381.34417 -105.151428)
		(end 381.6858 -104.809798)
		(width 0.1651)
		(layer "In9.Cu")
		(net "P5E_PEX3_STN1_TX_DN<18>")
	)
	(segment
		(start 370.722652 -130.990848)
		(end 375.697242 -114.592862)
		(width 0.1651)
		(layer "In9.Cu")
		(net "P5E_PEX3_STN1_TX_DN<18>")
	)
	(segment
		(start 409.470098 -278.12619)
		(end 409.470098 -271.546066)
		(width 0.1143)
		(layer "In9.Cu")
		(net "P5E_PEX3_STN1_TX_DN<18>")
	)
	(segment
		(start 373.295926 -144.84985)
		(end 370.722652 -138.637518)
		(width 0.1651)
		(layer "In9.Cu")
		(net "P5E_PEX3_STN1_TX_DN<18>")
	)
	(segment
		(start 374.588532 -162.323272)
		(end 374.012714 -159.428434)
		(width 0.1651)
		(layer "In9.Cu")
		(net "P5E_PEX3_STN1_TX_DN<18>")
	)
	(segment
		(start 378.20727 -108.83138)
		(end 378.145294 -108.682028)
		(width 0.1651)
		(layer "In9.Cu")
		(net "P5E_PEX3_STN1_TX_DN<18>")
	)
	(segment
		(start 409.849574 -277.849838)
		(end 409.849574 -278.115268)
		(width 0.1143)
		(layer "In9.Cu")
		(net "P5E_PEX3_STN1_TX_DN<18>")
	)
	(segment
		(start 409.573476 -278.229568)
		(end 409.470098 -278.12619)
		(width 0.1143)
		(layer "In9.Cu")
		(net "P5E_PEX3_STN1_TX_DN<18>")
	)
	(segment
		(start 380.841504 -105.49255)
		(end 381.182626 -105.151428)
		(width 0.1651)
		(layer "In9.Cu")
		(net "P5E_PEX3_STN1_TX_DN<18>")
	)
	(segment
		(start 377.86818 -109.351064)
		(end 378.017786 -109.289088)
		(width 0.1651)
		(layer "In9.Cu")
		(net "P5E_PEX3_STN1_TX_DN<18>")
	)
	(segment
		(start 377.401582 -110.477554)
		(end 377.551188 -110.415832)
		(width 0.1651)
		(layer "In9.Cu")
		(net "P5E_PEX3_STN1_TX_DN<18>")
	)
	(segment
		(start 384.006852 -103.486966)
		(end 384.406394 -103.486966)
		(width 0.1651)
		(layer "In9.Cu")
		(net "P5E_PEX3_STN1_TX_DN<18>")
	)
	(segment
		(start 381.182626 -105.151428)
		(end 381.34417 -105.151428)
		(width 0.1651)
		(layer "In9.Cu")
		(net "P5E_PEX3_STN1_TX_DN<18>")
	)
	(segment
		(start 377.08459 -111.542322)
		(end 377.274074 -111.08436)
		(width 0.1651)
		(layer "In9.Cu")
		(net "P5E_PEX3_STN1_TX_DN<18>")
	)
	(segment
		(start 382.971802 -104.039416)
		(end 383.417826 -103.854758)
		(width 0.1651)
		(layer "In9.Cu")
		(net "P5E_PEX3_STN1_TX_DN<18>")
	)
	(segment
		(start 377.678696 -109.808518)
		(end 377.86818 -109.351064)
		(width 0.1651)
		(layer "In9.Cu")
		(net "P5E_PEX3_STN1_TX_DN<18>")
	)
	(segment
		(start 380.33833 -105.995724)
		(end 380.499874 -105.995724)
		(width 0.1651)
		(layer "In9.Cu")
		(net "P5E_PEX3_STN1_TX_DN<18>")
	)
	(segment
		(start 374.012714 -159.428434)
		(end 373.295926 -144.84985)
		(width 0.1651)
		(layer "In9.Cu")
		(net "P5E_PEX3_STN1_TX_DN<18>")
	)
	(segment
		(start 376.934984 -111.604044)
		(end 377.08459 -111.542322)
		(width 0.1651)
		(layer "In9.Cu")
		(net "P5E_PEX3_STN1_TX_DN<18>")
	)
	(segment
		(start 377.740672 -109.95787)
		(end 377.678696 -109.808518)
		(width 0.1651)
		(layer "In9.Cu")
		(net "P5E_PEX3_STN1_TX_DN<18>")
	)
	(segment
		(start 381.6858 -104.809798)
		(end 381.6858 -104.648254)
		(width 0.1651)
		(layer "In9.Cu")
		(net "P5E_PEX3_STN1_TX_DN<18>")
	)
	(segment
		(start 383.479802 -103.705152)
		(end 383.479802 -103.70566)
		(width 0.1651)
		(layer "In9.Cu")
		(net "P5E_PEX3_STN1_TX_DN<18>")
	)
	(segment
		(start 383.417826 -103.854758)
		(end 383.479802 -103.705152)
		(width 0.1651)
		(layer "In9.Cu")
		(net "P5E_PEX3_STN1_TX_DN<18>")
	)
	(segment
		(start 385.003294 -103.601266)
		(end 385.117594 -103.486966)
		(width 0.1651)
		(layer "In9.Cu")
		(net "P5E_PEX3_STN1_TX_DN<18>")
	)
	(segment
		(start 370.722652 -138.637518)
		(end 370.722652 -130.990848)
		(width 0.1651)
		(layer "In9.Cu")
		(net "P5E_PEX3_STN1_TX_DN<18>")
	)
	(segment
		(start 379.655578 -106.84002)
		(end 379.997208 -106.49839)
		(width 0.1651)
		(layer "In9.Cu")
		(net "P5E_PEX3_STN1_TX_DN<18>")
	)
	(segment
		(start 375.697242 -114.592862)
		(end 376.934984 -111.604044)
		(width 0.1651)
		(layer "In9.Cu")
		(net "P5E_PEX3_STN1_TX_DN<18>")
	)
	(segment
		(start 379.997208 -106.49839)
		(end 379.997208 -106.336846)
		(width 0.1651)
		(layer "In9.Cu")
		(net "P5E_PEX3_STN1_TX_DN<18>")
	)
	(segment
		(start 377.274074 -111.08436)
		(end 377.212098 -110.935008)
		(width 0.1651)
		(layer "In9.Cu")
		(net "P5E_PEX3_STN1_TX_DN<18>")
	)
	(segment
		(start 380.499874 -105.995724)
		(end 380.841504 -105.654094)
		(width 0.1651)
		(layer "In9.Cu")
		(net "P5E_PEX3_STN1_TX_DN<18>")
	)
	(segment
		(start 409.515818 -265.511534)
		(end 374.588532 -162.323272)
		(width 0.1651)
		(layer "In9.Cu")
		(net "P5E_PEX3_STN1_TX_DN<18>")
	)
	(segment
		(start 409.470098 -271.546066)
		(end 409.515818 -271.500346)
		(width 0.1143)
		(layer "In9.Cu")
		(net "P5E_PEX3_STN1_TX_DN<18>")
	)
	(segment
		(start 381.6858 -104.648254)
		(end 382.026922 -104.307132)
		(width 0.1651)
		(layer "In9.Cu")
		(net "P5E_PEX3_STN1_TX_DN<18>")
	)
	(segment
		(start 409.849574 -278.115268)
		(end 409.735274 -278.229568)
		(width 0.1143)
		(layer "In9.Cu")
		(net "P5E_PEX3_STN1_TX_DN<18>")
	)
	(segment
		(start 383.917952 -343.36609)
		(end 383.917952 -342.73363)
		(width 0.13462)
		(layer "F.Cu")
		(net "P5E_PEX3_STN6_TX_DP<106>")
	)
	(segment
		(start 383.917952 -342.73363)
		(end 383.62382 -342.439498)
		(width 0.13462)
		(layer "F.Cu")
		(net "P5E_PEX3_STN6_TX_DP<106>")
	)
	(segment
		(start 383.59842 -343.685622)
		(end 383.917952 -343.36609)
		(width 0.13462)
		(layer "F.Cu")
		(net "P5E_PEX3_STN6_TX_DP<106>")
	)
	(segment
		(start 394.434314 -325.06666)
		(end 395.63929 -322.729606)
		(width 0.1651)
		(layer "In13.Cu")
		(net "P5E_PEX3_STN6_TX_DP<106>")
	)
	(segment
		(start 395.97965 -319.971928)
		(end 395.97965 -313.59475)
		(width 0.1143)
		(layer "In13.Cu")
		(net "P5E_PEX3_STN6_TX_DP<106>")
	)
	(segment
		(start 396.43558 -313.379612)
		(end 396.54988 -313.265312)
		(width 0.1143)
		(layer "In13.Cu")
		(net "P5E_PEX3_STN6_TX_DP<106>")
	)
	(segment
		(start 395.97965 -313.59475)
		(end 396.194788 -313.379612)
		(width 0.1143)
		(layer "In13.Cu")
		(net "P5E_PEX3_STN6_TX_DP<106>")
	)
	(segment
		(start 395.63929 -322.729606)
		(end 395.93393 -322.01866)
		(width 0.1651)
		(layer "In13.Cu")
		(net "P5E_PEX3_STN6_TX_DP<106>")
	)
	(segment
		(start 383.91465 -342.148668)
		(end 383.91465 -341.557102)
		(width 0.1651)
		(layer "In13.Cu")
		(net "P5E_PEX3_STN6_TX_DP<106>")
	)
	(segment
		(start 384.032506 -341.211916)
		(end 387.54812 -336.31505)
		(width 0.1651)
		(layer "In13.Cu")
		(net "P5E_PEX3_STN6_TX_DP<106>")
	)
	(segment
		(start 383.62382 -342.439498)
		(end 383.91465 -342.148668)
		(width 0.1651)
		(layer "In13.Cu")
		(net "P5E_PEX3_STN6_TX_DP<106>")
	)
	(segment
		(start 396.54988 -313.265312)
		(end 396.54988 -312.999882)
		(width 0.1143)
		(layer "In13.Cu")
		(net "P5E_PEX3_STN6_TX_DP<106>")
	)
	(segment
		(start 395.93393 -320.017648)
		(end 395.97965 -319.971928)
		(width 0.1143)
		(layer "In13.Cu")
		(net "P5E_PEX3_STN6_TX_DP<106>")
	)
	(segment
		(start 395.93393 -320.046096)
		(end 395.93393 -320.017648)
		(width 0.1143)
		(layer "In13.Cu")
		(net "P5E_PEX3_STN6_TX_DP<106>")
	)
	(segment
		(start 395.93393 -322.01866)
		(end 395.93393 -320.046096)
		(width 0.1651)
		(layer "In13.Cu")
		(net "P5E_PEX3_STN6_TX_DP<106>")
	)
	(segment
		(start 396.194788 -313.379612)
		(end 396.43558 -313.379612)
		(width 0.1143)
		(layer "In13.Cu")
		(net "P5E_PEX3_STN6_TX_DP<106>")
	)
	(segment
		(start 383.91465 -341.557102)
		(end 384.032506 -341.211916)
		(width 0.1651)
		(layer "In13.Cu")
		(net "P5E_PEX3_STN6_TX_DP<106>")
	)
	(segment
		(start 387.54812 -336.31505)
		(end 394.434314 -325.06666)
		(width 0.1651)
		(layer "In13.Cu")
		(net "P5E_PEX3_STN6_TX_DP<106>")
	)
	(segment
		(start 35.740848 -345.465146)
		(end 35.446208 -345.170506)
		(width 0.13462)
		(layer "F.Cu")
		(net "P5E_PEX0_STN7_TX_C_DN<119>")
	)
	(segment
		(start 35.446208 -344.539062)
		(end 35.766248 -344.219022)
		(width 0.13462)
		(layer "F.Cu")
		(net "P5E_PEX0_STN7_TX_C_DN<119>")
	)
	(segment
		(start 35.446208 -345.170506)
		(end 35.446208 -344.539062)
		(width 0.13462)
		(layer "F.Cu")
		(net "P5E_PEX0_STN7_TX_C_DN<119>")
	)
	(segment
		(start 33.895538 -348.029022)
		(end 35.450018 -346.474542)
		(width 0.1651)
		(layer "In7.Cu")
		(net "P5E_PEX0_STN7_TX_C_DN<119>")
	)
	(segment
		(start 30.46857 -386.756148)
		(end 27.856434 -385.674108)
		(width 0.1651)
		(layer "In7.Cu")
		(net "P5E_PEX0_STN7_TX_C_DN<119>")
	)
	(segment
		(start 43.310048 -402.408136)
		(end 43.437048 -402.281136)
		(width 0.1651)
		(layer "In7.Cu")
		(net "P5E_PEX0_STN7_TX_C_DN<119>")
	)
	(segment
		(start 26.893774 -369.259358)
		(end 33.472628 -359.414064)
		(width 0.1651)
		(layer "In7.Cu")
		(net "P5E_PEX0_STN7_TX_C_DN<119>")
	)
	(segment
		(start 26.846784 -384.058414)
		(end 26.26868 -374.447816)
		(width 0.1651)
		(layer "In7.Cu")
		(net "P5E_PEX0_STN7_TX_C_DN<119>")
	)
	(segment
		(start 30.978348 -386.756148)
		(end 30.46857 -386.756148)
		(width 0.1651)
		(layer "In7.Cu")
		(net "P5E_PEX0_STN7_TX_C_DN<119>")
	)
	(segment
		(start 33.895538 -358.019096)
		(end 33.895538 -348.029022)
		(width 0.1651)
		(layer "In7.Cu")
		(net "P5E_PEX0_STN7_TX_C_DN<119>")
	)
	(segment
		(start 35.450018 -346.474542)
		(end 35.450018 -345.755976)
		(width 0.1651)
		(layer "In7.Cu")
		(net "P5E_PEX0_STN7_TX_C_DN<119>")
	)
	(segment
		(start 33.472628 -359.414064)
		(end 33.895538 -358.019096)
		(width 0.1651)
		(layer "In7.Cu")
		(net "P5E_PEX0_STN7_TX_C_DN<119>")
	)
	(segment
		(start 26.26868 -372.401846)
		(end 26.893774 -369.259358)
		(width 0.1651)
		(layer "In7.Cu")
		(net "P5E_PEX0_STN7_TX_C_DN<119>")
	)
	(segment
		(start 27.342084 -385.159758)
		(end 26.846784 -384.058414)
		(width 0.1651)
		(layer "In7.Cu")
		(net "P5E_PEX0_STN7_TX_C_DN<119>")
	)
	(segment
		(start 44.48429 -401.96643)
		(end 44.48429 -394.54709)
		(width 0.1651)
		(layer "In7.Cu")
		(net "P5E_PEX0_STN7_TX_C_DN<119>")
	)
	(segment
		(start 35.450018 -345.755976)
		(end 35.740848 -345.465146)
		(width 0.1651)
		(layer "In7.Cu")
		(net "P5E_PEX0_STN7_TX_C_DN<119>")
	)
	(segment
		(start 44.169584 -402.281136)
		(end 44.48429 -401.96643)
		(width 0.1651)
		(layer "In7.Cu")
		(net "P5E_PEX0_STN7_TX_C_DN<119>")
	)
	(segment
		(start 40.736266 -390.799066)
		(end 30.978348 -386.756148)
		(width 0.1651)
		(layer "In7.Cu")
		(net "P5E_PEX0_STN7_TX_C_DN<119>")
	)
	(segment
		(start 44.48429 -394.54709)
		(end 40.736266 -390.799066)
		(width 0.1651)
		(layer "In7.Cu")
		(net "P5E_PEX0_STN7_TX_C_DN<119>")
	)
	(segment
		(start 43.310048 -402.790152)
		(end 43.310048 -402.408136)
		(width 0.1651)
		(layer "In7.Cu")
		(net "P5E_PEX0_STN7_TX_C_DN<119>")
	)
	(segment
		(start 27.856434 -385.674108)
		(end 27.342084 -385.159758)
		(width 0.1651)
		(layer "In7.Cu")
		(net "P5E_PEX0_STN7_TX_C_DN<119>")
	)
	(segment
		(start 26.26868 -374.447816)
		(end 26.26868 -372.401846)
		(width 0.1651)
		(layer "In7.Cu")
		(net "P5E_PEX0_STN7_TX_C_DN<119>")
	)
	(segment
		(start 43.437048 -402.281136)
		(end 44.169584 -402.281136)
		(width 0.1651)
		(layer "In7.Cu")
		(net "P5E_PEX0_STN7_TX_C_DN<119>")
	)
	(segment
		(start 181.134512 -357.46309)
		(end 181.134512 -356.831646)
		(width 0.13462)
		(layer "F.Cu")
		(net "P5E_PEX1_STN7_TX_C_DN<122>")
	)
	(segment
		(start 181.134512 -356.831646)
		(end 180.814472 -356.511606)
		(width 0.13462)
		(layer "F.Cu")
		(net "P5E_PEX1_STN7_TX_C_DN<122>")
	)
	(segment
		(start 180.839872 -357.75773)
		(end 181.134512 -357.46309)
		(width 0.13462)
		(layer "F.Cu")
		(net "P5E_PEX1_STN7_TX_C_DN<122>")
	)
	(segment
		(start 180.268372 -359.751884)
		(end 180.618892 -359.401364)
		(width 0.1651)
		(layer "In11.Cu")
		(net "P5E_PEX1_STN7_TX_C_DN<122>")
	)
	(segment
		(start 174.763176 -363.718602)
		(end 175.220122 -363.527086)
		(width 0.1651)
		(layer "In11.Cu")
		(net "P5E_PEX1_STN7_TX_C_DN<122>")
	)
	(segment
		(start 177.479706 -362.702348)
		(end 178.543712 -361.638342)
		(width 0.1651)
		(layer "In11.Cu")
		(net "P5E_PEX1_STN7_TX_C_DN<122>")
	)
	(segment
		(start 165.53561 -368.111532)
		(end 165.88613 -367.761012)
		(width 0.1651)
		(layer "In11.Cu")
		(net "P5E_PEX1_STN7_TX_C_DN<122>")
	)
	(segment
		(start 164.658548 -374.899174)
		(end 165.185598 -374.372124)
		(width 0.1651)
		(layer "In11.Cu")
		(net "P5E_PEX1_STN7_TX_C_DN<122>")
	)
	(segment
		(start 179.756562 -360.263694)
		(end 179.91836 -360.263694)
		(width 0.1651)
		(layer "In11.Cu")
		(net "P5E_PEX1_STN7_TX_C_DN<122>")
	)
	(segment
		(start 165.185598 -374.372124)
		(end 165.185598 -368.623342)
		(width 0.1651)
		(layer "In11.Cu")
		(net "P5E_PEX1_STN7_TX_C_DN<122>")
	)
	(segment
		(start 165.88613 -367.761012)
		(end 166.047928 -367.761012)
		(width 0.1651)
		(layer "In11.Cu")
		(net "P5E_PEX1_STN7_TX_C_DN<122>")
	)
	(segment
		(start 178.894232 -361.126024)
		(end 179.05603 -361.126024)
		(width 0.1651)
		(layer "In11.Cu")
		(net "P5E_PEX1_STN7_TX_C_DN<122>")
	)
	(segment
		(start 165.53561 -368.27333)
		(end 165.53561 -368.111532)
		(width 0.1651)
		(layer "In11.Cu")
		(net "P5E_PEX1_STN7_TX_C_DN<122>")
	)
	(segment
		(start 175.220122 -363.527086)
		(end 175.369728 -363.588046)
		(width 0.1651)
		(layer "In11.Cu")
		(net "P5E_PEX1_STN7_TX_C_DN<122>")
	)
	(segment
		(start 179.406042 -360.614214)
		(end 179.756562 -360.263694)
		(width 0.1651)
		(layer "In11.Cu")
		(net "P5E_PEX1_STN7_TX_C_DN<122>")
	)
	(segment
		(start 179.406042 -360.776012)
		(end 179.406042 -360.614214)
		(width 0.1651)
		(layer "In11.Cu")
		(net "P5E_PEX1_STN7_TX_C_DN<122>")
	)
	(segment
		(start 181.130702 -358.04856)
		(end 180.839872 -357.75773)
		(width 0.1651)
		(layer "In11.Cu")
		(net "P5E_PEX1_STN7_TX_C_DN<122>")
	)
	(segment
		(start 166.495476 -367.313464)
		(end 174.702216 -363.868208)
		(width 0.1651)
		(layer "In11.Cu")
		(net "P5E_PEX1_STN7_TX_C_DN<122>")
	)
	(segment
		(start 175.369728 -363.588046)
		(end 175.82642 -363.39653)
		(width 0.1651)
		(layer "In11.Cu")
		(net "P5E_PEX1_STN7_TX_C_DN<122>")
	)
	(segment
		(start 176.493932 -363.116114)
		(end 177.479706 -362.702348)
		(width 0.1651)
		(layer "In11.Cu")
		(net "P5E_PEX1_STN7_TX_C_DN<122>")
	)
	(segment
		(start 178.543712 -361.476544)
		(end 178.894232 -361.126024)
		(width 0.1651)
		(layer "In11.Cu")
		(net "P5E_PEX1_STN7_TX_C_DN<122>")
	)
	(segment
		(start 164.31006 -374.772174)
		(end 164.43706 -374.899174)
		(width 0.1651)
		(layer "In11.Cu")
		(net "P5E_PEX1_STN7_TX_C_DN<122>")
	)
	(segment
		(start 164.31006 -374.390158)
		(end 164.31006 -374.772174)
		(width 0.1651)
		(layer "In11.Cu")
		(net "P5E_PEX1_STN7_TX_C_DN<122>")
	)
	(segment
		(start 165.185598 -368.623342)
		(end 165.53561 -368.27333)
		(width 0.1651)
		(layer "In11.Cu")
		(net "P5E_PEX1_STN7_TX_C_DN<122>")
	)
	(segment
		(start 179.91836 -360.263694)
		(end 180.268372 -359.913682)
		(width 0.1651)
		(layer "In11.Cu")
		(net "P5E_PEX1_STN7_TX_C_DN<122>")
	)
	(segment
		(start 176.344326 -363.0549)
		(end 176.493932 -363.116114)
		(width 0.1651)
		(layer "In11.Cu")
		(net "P5E_PEX1_STN7_TX_C_DN<122>")
	)
	(segment
		(start 174.702216 -363.868462)
		(end 174.763176 -363.718602)
		(width 0.1651)
		(layer "In11.Cu")
		(net "P5E_PEX1_STN7_TX_C_DN<122>")
	)
	(segment
		(start 164.43706 -374.899174)
		(end 164.658548 -374.899174)
		(width 0.1651)
		(layer "In11.Cu")
		(net "P5E_PEX1_STN7_TX_C_DN<122>")
	)
	(segment
		(start 166.047928 -367.761012)
		(end 166.495476 -367.313464)
		(width 0.1651)
		(layer "In11.Cu")
		(net "P5E_PEX1_STN7_TX_C_DN<122>")
	)
	(segment
		(start 175.88738 -363.24667)
		(end 176.344326 -363.0549)
		(width 0.1651)
		(layer "In11.Cu")
		(net "P5E_PEX1_STN7_TX_C_DN<122>")
	)
	(segment
		(start 175.82642 -363.39653)
		(end 175.88738 -363.24667)
		(width 0.1651)
		(layer "In11.Cu")
		(net "P5E_PEX1_STN7_TX_C_DN<122>")
	)
	(segment
		(start 180.78069 -359.401364)
		(end 181.130702 -359.051352)
		(width 0.1651)
		(layer "In11.Cu")
		(net "P5E_PEX1_STN7_TX_C_DN<122>")
	)
	(segment
		(start 179.05603 -361.126024)
		(end 179.406042 -360.776012)
		(width 0.1651)
		(layer "In11.Cu")
		(net "P5E_PEX1_STN7_TX_C_DN<122>")
	)
	(segment
		(start 180.618892 -359.401364)
		(end 180.78069 -359.401364)
		(width 0.1651)
		(layer "In11.Cu")
		(net "P5E_PEX1_STN7_TX_C_DN<122>")
	)
	(segment
		(start 178.543712 -361.638342)
		(end 178.543712 -361.476544)
		(width 0.1651)
		(layer "In11.Cu")
		(net "P5E_PEX1_STN7_TX_C_DN<122>")
	)
	(segment
		(start 181.130702 -359.051352)
		(end 181.130702 -358.04856)
		(width 0.1651)
		(layer "In11.Cu")
		(net "P5E_PEX1_STN7_TX_C_DN<122>")
	)
	(segment
		(start 174.702216 -363.868208)
		(end 174.702216 -363.868462)
		(width 0.1651)
		(layer "In11.Cu")
		(net "P5E_PEX1_STN7_TX_C_DN<122>")
	)
	(segment
		(start 180.268372 -359.913682)
		(end 180.268372 -359.751884)
		(width 0.1651)
		(layer "In11.Cu")
		(net "P5E_PEX1_STN7_TX_C_DN<122>")
	)
	(segment
		(start 213.405212 -28.250642)
		(end 213.101174 -28.55468)
		(width 0.13462)
		(layer "F.Cu")
		(net "P5E_PEX1_STN2_TX_DN<32>")
	)
	(segment
		(start 212.488526 -28.55468)
		(end 212.159088 -28.225242)
		(width 0.13462)
		(layer "F.Cu")
		(net "P5E_PEX1_STN2_TX_DN<32>")
	)
	(segment
		(start 213.101174 -28.55468)
		(end 212.488526 -28.55468)
		(width 0.13462)
		(layer "F.Cu")
		(net "P5E_PEX1_STN2_TX_DN<32>")
	)
	(segment
		(start 220.087952 -31.675832)
		(end 224.531936 -39.806626)
		(width 0.1651)
		(layer "In11.Cu")
		(net "P5E_PEX1_STN2_TX_DN<32>")
	)
	(segment
		(start 213.405212 -28.250642)
		(end 213.5759 -28.42133)
		(width 0.1651)
		(layer "In11.Cu")
		(net "P5E_PEX1_STN2_TX_DN<32>")
	)
	(segment
		(start 174.465996 -271.427448)
		(end 174.420276 -271.473168)
		(width 0.1143)
		(layer "In11.Cu")
		(net "P5E_PEX1_STN2_TX_DN<32>")
	)
	(segment
		(start 219.831666 -76.754482)
		(end 213.181692 -80.362044)
		(width 0.1651)
		(layer "In11.Cu")
		(net "P5E_PEX1_STN2_TX_DN<32>")
	)
	(segment
		(start 225.523044 -56.971184)
		(end 223.213422 -68.765928)
		(width 0.1651)
		(layer "In11.Cu")
		(net "P5E_PEX1_STN2_TX_DN<32>")
	)
	(segment
		(start 194.724782 -153.867612)
		(end 193.77025 -161.05886)
		(width 0.1651)
		(layer "In11.Cu")
		(net "P5E_PEX1_STN2_TX_DN<32>")
	)
	(segment
		(start 211.558378 -81.985358)
		(end 198.041006 -106.033316)
		(width 0.1651)
		(layer "In11.Cu")
		(net "P5E_PEX1_STN2_TX_DN<32>")
	)
	(segment
		(start 174.420276 -280.025856)
		(end 174.523908 -280.129488)
		(width 0.1143)
		(layer "In11.Cu")
		(net "P5E_PEX1_STN2_TX_DN<32>")
	)
	(segment
		(start 198.041006 -106.033316)
		(end 196.556376 -117.98173)
		(width 0.1651)
		(layer "In11.Cu")
		(net "P5E_PEX1_STN2_TX_DN<32>")
	)
	(segment
		(start 220.793564 -75.5142)
		(end 219.831666 -76.754482)
		(width 0.1651)
		(layer "In11.Cu")
		(net "P5E_PEX1_STN2_TX_DN<32>")
	)
	(segment
		(start 213.5759 -28.42133)
		(end 213.866222 -28.541472)
		(width 0.1651)
		(layer "In11.Cu")
		(net "P5E_PEX1_STN2_TX_DN<32>")
	)
	(segment
		(start 174.685706 -280.129488)
		(end 174.800006 -280.015188)
		(width 0.1143)
		(layer "In11.Cu")
		(net "P5E_PEX1_STN2_TX_DN<32>")
	)
	(segment
		(start 223.213422 -68.765928)
		(end 220.793564 -75.5142)
		(width 0.1651)
		(layer "In11.Cu")
		(net "P5E_PEX1_STN2_TX_DN<32>")
	)
	(segment
		(start 174.465996 -271.399)
		(end 174.465996 -271.427448)
		(width 0.1143)
		(layer "In11.Cu")
		(net "P5E_PEX1_STN2_TX_DN<32>")
	)
	(segment
		(start 195.350638 -146.260566)
		(end 194.724782 -153.867612)
		(width 0.1651)
		(layer "In11.Cu")
		(net "P5E_PEX1_STN2_TX_DN<32>")
	)
	(segment
		(start 195.797932 -135.769604)
		(end 195.797932 -140.798042)
		(width 0.1651)
		(layer "In11.Cu")
		(net "P5E_PEX1_STN2_TX_DN<32>")
	)
	(segment
		(start 193.77025 -161.05886)
		(end 174.465996 -266.089638)
		(width 0.1651)
		(layer "In11.Cu")
		(net "P5E_PEX1_STN2_TX_DN<32>")
	)
	(segment
		(start 225.233738 -42.446194)
		(end 225.523044 -56.971184)
		(width 0.1651)
		(layer "In11.Cu")
		(net "P5E_PEX1_STN2_TX_DN<32>")
	)
	(segment
		(start 195.797932 -140.798042)
		(end 195.53555 -141.928088)
		(width 0.1651)
		(layer "In11.Cu")
		(net "P5E_PEX1_STN2_TX_DN<32>")
	)
	(segment
		(start 224.531936 -39.806626)
		(end 225.233738 -42.446194)
		(width 0.1651)
		(layer "In11.Cu")
		(net "P5E_PEX1_STN2_TX_DN<32>")
	)
	(segment
		(start 215.51392 -28.541472)
		(end 217.911934 -29.49448)
		(width 0.1651)
		(layer "In11.Cu")
		(net "P5E_PEX1_STN2_TX_DN<32>")
	)
	(segment
		(start 213.181692 -80.362044)
		(end 211.558378 -81.985358)
		(width 0.1651)
		(layer "In11.Cu")
		(net "P5E_PEX1_STN2_TX_DN<32>")
	)
	(segment
		(start 174.420276 -271.473168)
		(end 174.420276 -280.025856)
		(width 0.1143)
		(layer "In11.Cu")
		(net "P5E_PEX1_STN2_TX_DN<32>")
	)
	(segment
		(start 195.53555 -141.928088)
		(end 195.350638 -146.260566)
		(width 0.1651)
		(layer "In11.Cu")
		(net "P5E_PEX1_STN2_TX_DN<32>")
	)
	(segment
		(start 213.866222 -28.541472)
		(end 215.51392 -28.541472)
		(width 0.1651)
		(layer "In11.Cu")
		(net "P5E_PEX1_STN2_TX_DN<32>")
	)
	(segment
		(start 174.800006 -280.015188)
		(end 174.800006 -279.749504)
		(width 0.1143)
		(layer "In11.Cu")
		(net "P5E_PEX1_STN2_TX_DN<32>")
	)
	(segment
		(start 174.465996 -266.089638)
		(end 174.465996 -271.399)
		(width 0.1651)
		(layer "In11.Cu")
		(net "P5E_PEX1_STN2_TX_DN<32>")
	)
	(segment
		(start 196.556376 -117.98173)
		(end 195.797932 -135.769604)
		(width 0.1651)
		(layer "In11.Cu")
		(net "P5E_PEX1_STN2_TX_DN<32>")
	)
	(segment
		(start 174.523908 -280.129488)
		(end 174.685706 -280.129488)
		(width 0.1143)
		(layer "In11.Cu")
		(net "P5E_PEX1_STN2_TX_DN<32>")
	)
	(segment
		(start 217.911934 -29.49448)
		(end 220.087952 -31.675832)
		(width 0.1651)
		(layer "In11.Cu")
		(net "P5E_PEX1_STN2_TX_DN<32>")
	)
	(segment
		(start 267.325602 -112.784382)
		(end 267.613384 -112.4966)
		(width 0.13462)
		(layer "F.Cu")
		(net "P5E_PEX2_STN1_TX_DP<23>")
	)
	(segment
		(start 267.613384 -112.4966)
		(end 268.258544 -112.4966)
		(width 0.13462)
		(layer "F.Cu")
		(net "P5E_PEX2_STN1_TX_DP<23>")
	)
	(segment
		(start 268.258544 -112.4966)
		(end 268.571726 -112.809782)
		(width 0.13462)
		(layer "F.Cu")
		(net "P5E_PEX2_STN1_TX_DP<23>")
	)
	(segment
		(start 264.725658 -116.7638)
		(end 264.536174 -117.221762)
		(width 0.1651)
		(layer "In9.Cu")
		(net "P5E_PEX2_STN1_TX_DP<23>")
	)
	(segment
		(start 298.165774 -264.448036)
		(end 298.165774 -271.526)
		(width 0.1651)
		(layer "In9.Cu")
		(net "P5E_PEX2_STN1_TX_DP<23>")
	)
	(segment
		(start 263.792462 -119.01678)
		(end 263.602978 -119.474742)
		(width 0.1651)
		(layer "In9.Cu")
		(net "P5E_PEX2_STN1_TX_DP<23>")
	)
	(segment
		(start 262.859266 -121.26976)
		(end 262.669782 -121.727722)
		(width 0.1651)
		(layer "In9.Cu")
		(net "P5E_PEX2_STN1_TX_DP<23>")
	)
	(segment
		(start 298.120054 -280.025856)
		(end 298.223686 -280.129488)
		(width 0.1143)
		(layer "In9.Cu")
		(net "P5E_PEX2_STN1_TX_DP<23>")
	)
	(segment
		(start 298.165774 -271.554448)
		(end 298.120054 -271.600168)
		(width 0.1143)
		(layer "In9.Cu")
		(net "P5E_PEX2_STN1_TX_DP<23>")
	)
	(segment
		(start 265.935968 -113.842292)
		(end 265.786362 -113.904014)
		(width 0.1651)
		(layer "In9.Cu")
		(net "P5E_PEX2_STN1_TX_DP<23>")
	)
	(segment
		(start 262.520176 -121.789444)
		(end 262.270494 -122.392186)
		(width 0.1651)
		(layer "In9.Cu")
		(net "P5E_PEX2_STN1_TX_DP<23>")
	)
	(segment
		(start 264.663682 -116.614448)
		(end 264.725658 -116.7638)
		(width 0.1651)
		(layer "In9.Cu")
		(net "P5E_PEX2_STN1_TX_DP<23>")
	)
	(segment
		(start 263.263888 -119.993918)
		(end 263.325864 -120.14327)
		(width 0.1651)
		(layer "In9.Cu")
		(net "P5E_PEX2_STN1_TX_DP<23>")
	)
	(segment
		(start 263.327134 -161.525712)
		(end 298.165774 -264.448036)
		(width 0.1651)
		(layer "In9.Cu")
		(net "P5E_PEX2_STN1_TX_DP<23>")
	)
	(segment
		(start 266.452096 -112.493552)
		(end 266.312904 -112.632744)
		(width 0.1651)
		(layer "In9.Cu")
		(net "P5E_PEX2_STN1_TX_DP<23>")
	)
	(segment
		(start 263.325864 -120.14327)
		(end 263.13638 -120.601232)
		(width 0.1651)
		(layer "In9.Cu")
		(net "P5E_PEX2_STN1_TX_DP<23>")
	)
	(segment
		(start 265.46937 -114.968782)
		(end 265.319764 -115.030504)
		(width 0.1651)
		(layer "In9.Cu")
		(net "P5E_PEX2_STN1_TX_DP<23>")
	)
	(segment
		(start 266.063476 -113.234978)
		(end 266.125452 -113.38433)
		(width 0.1651)
		(layer "In9.Cu")
		(net "P5E_PEX2_STN1_TX_DP<23>")
	)
	(segment
		(start 263.730486 -118.867428)
		(end 263.792462 -119.01678)
		(width 0.1651)
		(layer "In9.Cu")
		(net "P5E_PEX2_STN1_TX_DP<23>")
	)
	(segment
		(start 259.461254 -137.570718)
		(end 262.019542 -143.746474)
		(width 0.1651)
		(layer "In9.Cu")
		(net "P5E_PEX2_STN1_TX_DP<23>")
	)
	(segment
		(start 266.125452 -113.38433)
		(end 265.935968 -113.842292)
		(width 0.1651)
		(layer "In9.Cu")
		(net "P5E_PEX2_STN1_TX_DP<23>")
	)
	(segment
		(start 264.197084 -117.740938)
		(end 264.25906 -117.89029)
		(width 0.1651)
		(layer "In9.Cu")
		(net "P5E_PEX2_STN1_TX_DP<23>")
	)
	(segment
		(start 264.386568 -117.283484)
		(end 264.197084 -117.740938)
		(width 0.1651)
		(layer "In9.Cu")
		(net "P5E_PEX2_STN1_TX_DP<23>")
	)
	(segment
		(start 259.461254 -131.652518)
		(end 259.461254 -137.570718)
		(width 0.1651)
		(layer "In9.Cu")
		(net "P5E_PEX2_STN1_TX_DP<23>")
	)
	(segment
		(start 264.069576 -118.348252)
		(end 263.91997 -118.409974)
		(width 0.1651)
		(layer "In9.Cu")
		(net "P5E_PEX2_STN1_TX_DP<23>")
	)
	(segment
		(start 265.192256 -115.63731)
		(end 265.002772 -116.095272)
		(width 0.1651)
		(layer "In9.Cu")
		(net "P5E_PEX2_STN1_TX_DP<23>")
	)
	(segment
		(start 265.319764 -115.030504)
		(end 265.13028 -115.487958)
		(width 0.1651)
		(layer "In9.Cu")
		(net "P5E_PEX2_STN1_TX_DP<23>")
	)
	(segment
		(start 262.669782 -121.727722)
		(end 262.520176 -121.789444)
		(width 0.1651)
		(layer "In9.Cu")
		(net "P5E_PEX2_STN1_TX_DP<23>")
	)
	(segment
		(start 264.536174 -117.221762)
		(end 264.386568 -117.283484)
		(width 0.1651)
		(layer "In9.Cu")
		(net "P5E_PEX2_STN1_TX_DP<23>")
	)
	(segment
		(start 265.786362 -113.904014)
		(end 265.596878 -114.361468)
		(width 0.1651)
		(layer "In9.Cu")
		(net "P5E_PEX2_STN1_TX_DP<23>")
	)
	(segment
		(start 298.165774 -271.526)
		(end 298.165774 -271.554448)
		(width 0.1143)
		(layer "In9.Cu")
		(net "P5E_PEX2_STN1_TX_DP<23>")
	)
	(segment
		(start 263.13638 -120.601232)
		(end 262.986774 -120.662954)
		(width 0.1651)
		(layer "In9.Cu")
		(net "P5E_PEX2_STN1_TX_DP<23>")
	)
	(segment
		(start 263.453372 -119.536464)
		(end 263.263888 -119.993918)
		(width 0.1651)
		(layer "In9.Cu")
		(net "P5E_PEX2_STN1_TX_DP<23>")
	)
	(segment
		(start 262.019542 -143.746474)
		(end 262.750554 -158.62681)
		(width 0.1651)
		(layer "In9.Cu")
		(net "P5E_PEX2_STN1_TX_DP<23>")
	)
	(segment
		(start 266.312904 -112.632744)
		(end 266.063476 -113.234978)
		(width 0.1651)
		(layer "In9.Cu")
		(net "P5E_PEX2_STN1_TX_DP<23>")
	)
	(segment
		(start 262.750554 -158.62681)
		(end 263.327134 -161.525712)
		(width 0.1651)
		(layer "In9.Cu")
		(net "P5E_PEX2_STN1_TX_DP<23>")
	)
	(segment
		(start 298.385484 -280.129488)
		(end 298.499784 -280.015188)
		(width 0.1143)
		(layer "In9.Cu")
		(net "P5E_PEX2_STN1_TX_DP<23>")
	)
	(segment
		(start 262.79729 -121.120408)
		(end 262.859266 -121.26976)
		(width 0.1651)
		(layer "In9.Cu")
		(net "P5E_PEX2_STN1_TX_DP<23>")
	)
	(segment
		(start 298.223686 -280.129488)
		(end 298.385484 -280.129488)
		(width 0.1143)
		(layer "In9.Cu")
		(net "P5E_PEX2_STN1_TX_DP<23>")
	)
	(segment
		(start 263.91997 -118.409974)
		(end 263.730486 -118.867428)
		(width 0.1651)
		(layer "In9.Cu")
		(net "P5E_PEX2_STN1_TX_DP<23>")
	)
	(segment
		(start 265.002772 -116.095272)
		(end 264.853166 -116.156994)
		(width 0.1651)
		(layer "In9.Cu")
		(net "P5E_PEX2_STN1_TX_DP<23>")
	)
	(segment
		(start 264.25906 -117.89029)
		(end 264.069576 -118.348252)
		(width 0.1651)
		(layer "In9.Cu")
		(net "P5E_PEX2_STN1_TX_DP<23>")
	)
	(segment
		(start 267.034772 -112.493552)
		(end 266.452096 -112.493552)
		(width 0.1651)
		(layer "In9.Cu")
		(net "P5E_PEX2_STN1_TX_DP<23>")
	)
	(segment
		(start 262.270494 -122.392186)
		(end 259.461254 -131.652518)
		(width 0.1651)
		(layer "In9.Cu")
		(net "P5E_PEX2_STN1_TX_DP<23>")
	)
	(segment
		(start 298.120054 -271.600168)
		(end 298.120054 -280.025856)
		(width 0.1143)
		(layer "In9.Cu")
		(net "P5E_PEX2_STN1_TX_DP<23>")
	)
	(segment
		(start 265.658854 -114.51082)
		(end 265.46937 -114.968782)
		(width 0.1651)
		(layer "In9.Cu")
		(net "P5E_PEX2_STN1_TX_DP<23>")
	)
	(segment
		(start 264.853166 -116.156994)
		(end 264.663682 -116.614448)
		(width 0.1651)
		(layer "In9.Cu")
		(net "P5E_PEX2_STN1_TX_DP<23>")
	)
	(segment
		(start 265.596878 -114.361468)
		(end 265.658854 -114.51082)
		(width 0.1651)
		(layer "In9.Cu")
		(net "P5E_PEX2_STN1_TX_DP<23>")
	)
	(segment
		(start 263.602978 -119.474742)
		(end 263.453372 -119.536464)
		(width 0.1651)
		(layer "In9.Cu")
		(net "P5E_PEX2_STN1_TX_DP<23>")
	)
	(segment
		(start 298.499784 -280.015188)
		(end 298.499784 -279.749504)
		(width 0.1143)
		(layer "In9.Cu")
		(net "P5E_PEX2_STN1_TX_DP<23>")
	)
	(segment
		(start 267.325602 -112.784382)
		(end 267.034772 -112.493552)
		(width 0.1651)
		(layer "In9.Cu")
		(net "P5E_PEX2_STN1_TX_DP<23>")
	)
	(segment
		(start 265.13028 -115.487958)
		(end 265.192256 -115.63731)
		(width 0.1651)
		(layer "In9.Cu")
		(net "P5E_PEX2_STN1_TX_DP<23>")
	)
	(segment
		(start 262.986774 -120.662954)
		(end 262.79729 -121.120408)
		(width 0.1651)
		(layer "In9.Cu")
		(net "P5E_PEX2_STN1_TX_DP<23>")
	)
	(segment
		(start 331.131164 -343.685622)
		(end 331.451204 -343.365582)
		(width 0.13462)
		(layer "F.Cu")
		(net "P5E_PEX2_STN6_TX_DP<103>")
	)
	(segment
		(start 331.451204 -343.365582)
		(end 331.451204 -342.734138)
		(width 0.13462)
		(layer "F.Cu")
		(net "P5E_PEX2_STN6_TX_DP<103>")
	)
	(segment
		(start 331.451204 -342.734138)
		(end 331.156564 -342.439498)
		(width 0.13462)
		(layer "F.Cu")
		(net "P5E_PEX2_STN6_TX_DP<103>")
	)
	(segment
		(start 283.299916 -311.365392)
		(end 283.299916 -311.099962)
		(width 0.1143)
		(layer "In13.Cu")
		(net "P5E_PEX2_STN6_TX_DP<103>")
	)
	(segment
		(start 331.447394 -342.148668)
		(end 331.447394 -341.731092)
		(width 0.1651)
		(layer "In13.Cu")
		(net "P5E_PEX2_STN6_TX_DP<103>")
	)
	(segment
		(start 282.944824 -311.479692)
		(end 283.185616 -311.479692)
		(width 0.1143)
		(layer "In13.Cu")
		(net "P5E_PEX2_STN6_TX_DP<103>")
	)
	(segment
		(start 283.185616 -311.479692)
		(end 283.299916 -311.365392)
		(width 0.1143)
		(layer "In13.Cu")
		(net "P5E_PEX2_STN6_TX_DP<103>")
	)
	(segment
		(start 285.456884 -326.775064)
		(end 283.16301 -324.48119)
		(width 0.1651)
		(layer "In13.Cu")
		(net "P5E_PEX2_STN6_TX_DP<103>")
	)
	(segment
		(start 314.834778 -332.528418)
		(end 285.456884 -326.775064)
		(width 0.1651)
		(layer "In13.Cu")
		(net "P5E_PEX2_STN6_TX_DP<103>")
	)
	(segment
		(start 283.16301 -324.48119)
		(end 282.683966 -323.324728)
		(width 0.1651)
		(layer "In13.Cu")
		(net "P5E_PEX2_STN6_TX_DP<103>")
	)
	(segment
		(start 282.683966 -319.995296)
		(end 282.683966 -319.966848)
		(width 0.1143)
		(layer "In13.Cu")
		(net "P5E_PEX2_STN6_TX_DP<103>")
	)
	(segment
		(start 331.156564 -342.439498)
		(end 331.447394 -342.148668)
		(width 0.1651)
		(layer "In13.Cu")
		(net "P5E_PEX2_STN6_TX_DP<103>")
	)
	(segment
		(start 331.447394 -341.731092)
		(end 329.386184 -339.1154)
		(width 0.1651)
		(layer "In13.Cu")
		(net "P5E_PEX2_STN6_TX_DP<103>")
	)
	(segment
		(start 282.683966 -319.966848)
		(end 282.729686 -319.921128)
		(width 0.1143)
		(layer "In13.Cu")
		(net "P5E_PEX2_STN6_TX_DP<103>")
	)
	(segment
		(start 282.729686 -319.921128)
		(end 282.729686 -311.69483)
		(width 0.1143)
		(layer "In13.Cu")
		(net "P5E_PEX2_STN6_TX_DP<103>")
	)
	(segment
		(start 329.386184 -339.1154)
		(end 314.834778 -332.528418)
		(width 0.1651)
		(layer "In13.Cu")
		(net "P5E_PEX2_STN6_TX_DP<103>")
	)
	(segment
		(start 282.683966 -323.324728)
		(end 282.683966 -319.995296)
		(width 0.1651)
		(layer "In13.Cu")
		(net "P5E_PEX2_STN6_TX_DP<103>")
	)
	(segment
		(start 282.729686 -311.69483)
		(end 282.944824 -311.479692)
		(width 0.1143)
		(layer "In13.Cu")
		(net "P5E_PEX2_STN6_TX_DP<103>")
	)
	(segment
		(start 429.537876 -130.47472)
		(end 428.905924 -130.47472)
		(width 0.13462)
		(layer "F.Cu")
		(net "P5E_PEX3_STN0_TX_DP<4>")
	)
	(segment
		(start 429.832262 -130.769106)
		(end 429.537876 -130.47472)
		(width 0.13462)
		(layer "F.Cu")
		(net "P5E_PEX3_STN0_TX_DP<4>")
	)
	(segment
		(start 428.905924 -130.47472)
		(end 428.586138 -130.794506)
		(width 0.13462)
		(layer "F.Cu")
		(net "P5E_PEX3_STN0_TX_DP<4>")
	)
	(segment
		(start 432.217576 -283.883862)
		(end 433.273708 -283.883862)
		(width 0.1651)
		(layer "In9.Cu")
		(net "P5E_PEX3_STN0_TX_DP<4>")
	)
	(segment
		(start 425.42968 -284.14472)
		(end 425.644818 -283.929582)
		(width 0.1143)
		(layer "In9.Cu")
		(net "P5E_PEX3_STN0_TX_DP<4>")
	)
	(segment
		(start 430.123092 -130.478276)
		(end 429.832262 -130.769106)
		(width 0.1651)
		(layer "In9.Cu")
		(net "P5E_PEX3_STN0_TX_DP<4>")
	)
	(segment
		(start 443.71387 -266.38123)
		(end 433.321968 -250.828302)
		(width 0.1651)
		(layer "In9.Cu")
		(net "P5E_PEX3_STN0_TX_DP<4>")
	)
	(segment
		(start 444.487554 -268.2494)
		(end 443.71387 -266.38123)
		(width 0.1651)
		(layer "In9.Cu")
		(net "P5E_PEX3_STN0_TX_DP<4>")
	)
	(segment
		(start 436.410862 -134.860792)
		(end 436.465726 -134.72795)
		(width 0.1651)
		(layer "In9.Cu")
		(net "P5E_PEX3_STN0_TX_DP<4>")
	)
	(segment
		(start 435.590188 -174.663862)
		(end 444.258446 -159.64408)
		(width 0.1651)
		(layer "In9.Cu")
		(net "P5E_PEX3_STN0_TX_DP<4>")
	)
	(segment
		(start 435.135528 -132.545328)
		(end 434.991764 -132.545328)
		(width 0.1651)
		(layer "In9.Cu")
		(net "P5E_PEX3_STN0_TX_DP<4>")
	)
	(segment
		(start 437.266334 -136.92632)
		(end 437.321198 -136.793478)
		(width 0.1651)
		(layer "In9.Cu")
		(net "P5E_PEX3_STN0_TX_DP<4>")
	)
	(segment
		(start 437.013604 -136.316212)
		(end 436.838598 -135.893556)
		(width 0.1651)
		(layer "In9.Cu")
		(net "P5E_PEX3_STN0_TX_DP<4>")
	)
	(segment
		(start 431.66665 -130.567176)
		(end 431.17135 -130.567176)
		(width 0.1651)
		(layer "In9.Cu")
		(net "P5E_PEX3_STN0_TX_DP<4>")
	)
	(segment
		(start 435.983126 -133.828028)
		(end 436.03799 -133.695186)
		(width 0.1651)
		(layer "In9.Cu")
		(net "P5E_PEX3_STN0_TX_DP<4>")
	)
	(segment
		(start 434.668168 -132.077968)
		(end 434.34508 -131.75488)
		(width 0.1651)
		(layer "In9.Cu")
		(net "P5E_PEX3_STN0_TX_DP<4>")
	)
	(segment
		(start 436.290974 -134.305802)
		(end 436.158132 -134.250684)
		(width 0.1651)
		(layer "In9.Cu")
		(net "P5E_PEX3_STN0_TX_DP<4>")
	)
	(segment
		(start 436.893462 -135.760714)
		(end 436.71871 -135.338566)
		(width 0.1651)
		(layer "In9.Cu")
		(net "P5E_PEX3_STN0_TX_DP<4>")
	)
	(segment
		(start 444.318644 -159.418782)
		(end 444.318644 -153.442416)
		(width 0.1651)
		(layer "In9.Cu")
		(net "P5E_PEX3_STN0_TX_DP<4>")
	)
	(segment
		(start 425.04995 -284.499812)
		(end 425.31538 -284.499812)
		(width 0.1143)
		(layer "In9.Cu")
		(net "P5E_PEX3_STN0_TX_DP<4>")
	)
	(segment
		(start 437.146446 -136.37133)
		(end 437.013604 -136.316212)
		(width 0.1651)
		(layer "In9.Cu")
		(net "P5E_PEX3_STN0_TX_DP<4>")
	)
	(segment
		(start 431.08245 -130.478276)
		(end 430.123092 -130.478276)
		(width 0.1651)
		(layer "In9.Cu")
		(net "P5E_PEX3_STN0_TX_DP<4>")
	)
	(segment
		(start 433.321968 -250.828302)
		(end 432.04384 -236.187234)
		(width 0.1651)
		(layer "In9.Cu")
		(net "P5E_PEX3_STN0_TX_DP<4>")
	)
	(segment
		(start 436.71871 -135.338566)
		(end 436.585868 -135.283448)
		(width 0.1651)
		(layer "In9.Cu")
		(net "P5E_PEX3_STN0_TX_DP<4>")
	)
	(segment
		(start 434.201316 -131.75488)
		(end 433.87772 -131.431284)
		(width 0.1651)
		(layer "In9.Cu")
		(net "P5E_PEX3_STN0_TX_DP<4>")
	)
	(segment
		(start 443.796166 -274.590002)
		(end 444.824612 -272.107406)
		(width 0.1651)
		(layer "In9.Cu")
		(net "P5E_PEX3_STN0_TX_DP<4>")
	)
	(segment
		(start 444.824612 -272.107406)
		(end 444.487554 -268.2494)
		(width 0.1651)
		(layer "In9.Cu")
		(net "P5E_PEX3_STN0_TX_DP<4>")
	)
	(segment
		(start 434.991764 -132.545328)
		(end 434.668168 -132.221732)
		(width 0.1651)
		(layer "In9.Cu")
		(net "P5E_PEX3_STN0_TX_DP<4>")
	)
	(segment
		(start 437.44134 -137.348976)
		(end 437.266334 -136.92632)
		(width 0.1651)
		(layer "In9.Cu")
		(net "P5E_PEX3_STN0_TX_DP<4>")
	)
	(segment
		(start 434.52923 -178.621436)
		(end 435.590188 -174.663862)
		(width 0.1651)
		(layer "In9.Cu")
		(net "P5E_PEX3_STN0_TX_DP<4>")
	)
	(segment
		(start 433.273708 -283.883862)
		(end 435.37124 -283.014928)
		(width 0.1651)
		(layer "In9.Cu")
		(net "P5E_PEX3_STN0_TX_DP<4>")
	)
	(segment
		(start 432.189128 -283.883862)
		(end 432.217576 -283.883862)
		(width 0.1143)
		(layer "In9.Cu")
		(net "P5E_PEX3_STN0_TX_DP<4>")
	)
	(segment
		(start 436.158132 -134.250684)
		(end 435.983126 -133.828028)
		(width 0.1651)
		(layer "In9.Cu")
		(net "P5E_PEX3_STN0_TX_DP<4>")
	)
	(segment
		(start 433.87772 -131.431284)
		(end 433.87772 -131.28752)
		(width 0.1651)
		(layer "In9.Cu")
		(net "P5E_PEX3_STN0_TX_DP<4>")
	)
	(segment
		(start 436.03799 -133.695186)
		(end 435.863238 -133.273038)
		(width 0.1651)
		(layer "In9.Cu")
		(net "P5E_PEX3_STN0_TX_DP<4>")
	)
	(segment
		(start 433.467764 -130.877564)
		(end 432.504088 -130.478276)
		(width 0.1651)
		(layer "In9.Cu")
		(net "P5E_PEX3_STN0_TX_DP<4>")
	)
	(segment
		(start 425.31538 -284.499812)
		(end 425.42968 -284.385512)
		(width 0.1143)
		(layer "In9.Cu")
		(net "P5E_PEX3_STN0_TX_DP<4>")
	)
	(segment
		(start 437.574182 -137.404094)
		(end 437.44134 -137.348976)
		(width 0.1651)
		(layer "In9.Cu")
		(net "P5E_PEX3_STN0_TX_DP<4>")
	)
	(segment
		(start 425.42968 -284.385512)
		(end 425.42968 -284.14472)
		(width 0.1143)
		(layer "In9.Cu")
		(net "P5E_PEX3_STN0_TX_DP<4>")
	)
	(segment
		(start 436.465726 -134.72795)
		(end 436.290974 -134.305802)
		(width 0.1651)
		(layer "In9.Cu")
		(net "P5E_PEX3_STN0_TX_DP<4>")
	)
	(segment
		(start 435.37124 -283.014928)
		(end 443.796166 -274.590002)
		(width 0.1651)
		(layer "In9.Cu")
		(net "P5E_PEX3_STN0_TX_DP<4>")
	)
	(segment
		(start 435.863238 -133.273038)
		(end 435.135528 -132.545328)
		(width 0.1651)
		(layer "In9.Cu")
		(net "P5E_PEX3_STN0_TX_DP<4>")
	)
	(segment
		(start 440.65952 -144.60855)
		(end 440.487308 -144.436338)
		(width 0.1651)
		(layer "In9.Cu")
		(net "P5E_PEX3_STN0_TX_DP<4>")
	)
	(segment
		(start 434.34508 -131.75488)
		(end 434.201316 -131.75488)
		(width 0.1651)
		(layer "In9.Cu")
		(net "P5E_PEX3_STN0_TX_DP<4>")
	)
	(segment
		(start 430.769522 -221.593156)
		(end 434.52923 -178.621436)
		(width 0.1651)
		(layer "In9.Cu")
		(net "P5E_PEX3_STN0_TX_DP<4>")
	)
	(segment
		(start 436.838598 -135.893556)
		(end 436.893462 -135.760714)
		(width 0.1651)
		(layer "In9.Cu")
		(net "P5E_PEX3_STN0_TX_DP<4>")
	)
	(segment
		(start 432.143408 -283.929582)
		(end 432.189128 -283.883862)
		(width 0.1143)
		(layer "In9.Cu")
		(net "P5E_PEX3_STN0_TX_DP<4>")
	)
	(segment
		(start 431.75555 -130.478276)
		(end 431.66665 -130.567176)
		(width 0.1651)
		(layer "In9.Cu")
		(net "P5E_PEX3_STN0_TX_DP<4>")
	)
	(segment
		(start 444.258446 -159.64408)
		(end 444.318644 -159.418782)
		(width 0.1651)
		(layer "In9.Cu")
		(net "P5E_PEX3_STN0_TX_DP<4>")
	)
	(segment
		(start 425.644818 -283.929582)
		(end 432.143408 -283.929582)
		(width 0.1143)
		(layer "In9.Cu")
		(net "P5E_PEX3_STN0_TX_DP<4>")
	)
	(segment
		(start 431.17135 -130.567176)
		(end 431.08245 -130.478276)
		(width 0.1651)
		(layer "In9.Cu")
		(net "P5E_PEX3_STN0_TX_DP<4>")
	)
	(segment
		(start 440.487308 -144.436338)
		(end 437.574182 -137.404094)
		(width 0.1651)
		(layer "In9.Cu")
		(net "P5E_PEX3_STN0_TX_DP<4>")
	)
	(segment
		(start 432.504088 -130.478276)
		(end 431.75555 -130.478276)
		(width 0.1651)
		(layer "In9.Cu")
		(net "P5E_PEX3_STN0_TX_DP<4>")
	)
	(segment
		(start 434.668168 -132.221732)
		(end 434.668168 -132.077968)
		(width 0.1651)
		(layer "In9.Cu")
		(net "P5E_PEX3_STN0_TX_DP<4>")
	)
	(segment
		(start 436.585868 -135.283448)
		(end 436.410862 -134.860792)
		(width 0.1651)
		(layer "In9.Cu")
		(net "P5E_PEX3_STN0_TX_DP<4>")
	)
	(segment
		(start 437.321198 -136.793478)
		(end 437.146446 -136.37133)
		(width 0.1651)
		(layer "In9.Cu")
		(net "P5E_PEX3_STN0_TX_DP<4>")
	)
	(segment
		(start 432.04384 -236.187234)
		(end 430.769522 -221.593156)
		(width 0.1651)
		(layer "In9.Cu")
		(net "P5E_PEX3_STN0_TX_DP<4>")
	)
	(segment
		(start 444.318644 -153.442416)
		(end 440.65952 -144.60855)
		(width 0.1651)
		(layer "In9.Cu")
		(net "P5E_PEX3_STN0_TX_DP<4>")
	)
	(segment
		(start 433.87772 -131.28752)
		(end 433.467764 -130.877564)
		(width 0.1651)
		(layer "In9.Cu")
		(net "P5E_PEX3_STN0_TX_DP<4>")
	)
	(segment
		(start 371.482112 -348.879922)
		(end 371.18798 -348.58579)
		(width 0.13462)
		(layer "F.Cu")
		(net "P5E_PEX3_STN6_TX_DP<103>")
	)
	(segment
		(start 371.482112 -349.512382)
		(end 371.482112 -348.879922)
		(width 0.13462)
		(layer "F.Cu")
		(net "P5E_PEX3_STN6_TX_DP<103>")
	)
	(segment
		(start 371.16258 -349.831914)
		(end 371.482112 -349.512382)
		(width 0.13462)
		(layer "F.Cu")
		(net "P5E_PEX3_STN6_TX_DP<103>")
	)
	(segment
		(start 399.05559 -311.479692)
		(end 399.285714 -311.479692)
		(width 0.1143)
		(layer "In7.Cu")
		(net "P5E_PEX3_STN6_TX_DP<103>")
	)
	(segment
		(start 399.400014 -311.365392)
		(end 399.400014 -311.099962)
		(width 0.1143)
		(layer "In7.Cu")
		(net "P5E_PEX3_STN6_TX_DP<103>")
	)
	(segment
		(start 371.18798 -348.58579)
		(end 371.47881 -348.29496)
		(width 0.1651)
		(layer "In7.Cu")
		(net "P5E_PEX3_STN6_TX_DP<103>")
	)
	(segment
		(start 399.285714 -311.479692)
		(end 399.400014 -311.365392)
		(width 0.1143)
		(layer "In7.Cu")
		(net "P5E_PEX3_STN6_TX_DP<103>")
	)
	(segment
		(start 398.829784 -319.90284)
		(end 398.829784 -311.705498)
		(width 0.1143)
		(layer "In7.Cu")
		(net "P5E_PEX3_STN6_TX_DP<103>")
	)
	(segment
		(start 371.47881 -347.667834)
		(end 373.03329 -346.113354)
		(width 0.1651)
		(layer "In7.Cu")
		(net "P5E_PEX3_STN6_TX_DP<103>")
	)
	(segment
		(start 398.784064 -319.977008)
		(end 398.784064 -319.94856)
		(width 0.1143)
		(layer "In7.Cu")
		(net "P5E_PEX3_STN6_TX_DP<103>")
	)
	(segment
		(start 371.47881 -348.29496)
		(end 371.47881 -347.667834)
		(width 0.1651)
		(layer "In7.Cu")
		(net "P5E_PEX3_STN6_TX_DP<103>")
	)
	(segment
		(start 398.784064 -320.082926)
		(end 398.784064 -319.977008)
		(width 0.1651)
		(layer "In7.Cu")
		(net "P5E_PEX3_STN6_TX_DP<103>")
	)
	(segment
		(start 398.784064 -319.94856)
		(end 398.829784 -319.90284)
		(width 0.1143)
		(layer "In7.Cu")
		(net "P5E_PEX3_STN6_TX_DP<103>")
	)
	(segment
		(start 397.613886 -321.253104)
		(end 398.784064 -320.082926)
		(width 0.1651)
		(layer "In7.Cu")
		(net "P5E_PEX3_STN6_TX_DP<103>")
	)
	(segment
		(start 373.03329 -341.201248)
		(end 397.613886 -321.253104)
		(width 0.1651)
		(layer "In7.Cu")
		(net "P5E_PEX3_STN6_TX_DP<103>")
	)
	(segment
		(start 373.03329 -346.113354)
		(end 373.03329 -341.201248)
		(width 0.1651)
		(layer "In7.Cu")
		(net "P5E_PEX3_STN6_TX_DP<103>")
	)
	(segment
		(start 398.829784 -311.705498)
		(end 399.05559 -311.479692)
		(width 0.1143)
		(layer "In7.Cu")
		(net "P5E_PEX3_STN6_TX_DP<103>")
	)
	(segment
		(start 137.028428 -349.511874)
		(end 137.028428 -348.88043)
		(width 0.13462)
		(layer "F.Cu")
		(net "P5E_PEX1_STN5_TX_DP<84>")
	)
	(segment
		(start 136.708388 -349.831914)
		(end 137.028428 -349.511874)
		(width 0.13462)
		(layer "F.Cu")
		(net "P5E_PEX1_STN5_TX_DP<84>")
	)
	(segment
		(start 137.028428 -348.88043)
		(end 136.733788 -348.58579)
		(width 0.13462)
		(layer "F.Cu")
		(net "P5E_PEX1_STN5_TX_DP<84>")
	)
	(segment
		(start 139.13231 -340.567772)
		(end 139.132564 -340.567772)
		(width 0.1651)
		(layer "In7.Cu")
		(net "P5E_PEX1_STN5_TX_DP<84>")
	)
	(segment
		(start 137.024618 -348.29496)
		(end 137.024618 -347.620082)
		(width 0.1651)
		(layer "In7.Cu")
		(net "P5E_PEX1_STN5_TX_DP<84>")
	)
	(segment
		(start 177.983896 -319.988438)
		(end 178.029616 -319.942718)
		(width 0.1143)
		(layer "In7.Cu")
		(net "P5E_PEX1_STN5_TX_DP<84>")
	)
	(segment
		(start 174.350934 -328.69251)
		(end 177.056288 -325.987156)
		(width 0.1651)
		(layer "In7.Cu")
		(net "P5E_PEX1_STN5_TX_DP<84>")
	)
	(segment
		(start 138.579098 -341.22106)
		(end 139.043664 -340.594696)
		(width 0.1651)
		(layer "In7.Cu")
		(net "P5E_PEX1_STN5_TX_DP<84>")
	)
	(segment
		(start 177.983896 -323.747892)
		(end 177.983896 -320.016886)
		(width 0.1651)
		(layer "In7.Cu")
		(net "P5E_PEX1_STN5_TX_DP<84>")
	)
	(segment
		(start 138.579098 -346.065602)
		(end 138.579098 -341.22106)
		(width 0.1651)
		(layer "In7.Cu")
		(net "P5E_PEX1_STN5_TX_DP<84>")
	)
	(segment
		(start 178.485546 -311.479692)
		(end 178.599846 -311.365392)
		(width 0.1143)
		(layer "In7.Cu")
		(net "P5E_PEX1_STN5_TX_DP<84>")
	)
	(segment
		(start 178.255422 -311.479692)
		(end 178.485546 -311.479692)
		(width 0.1143)
		(layer "In7.Cu")
		(net "P5E_PEX1_STN5_TX_DP<84>")
	)
	(segment
		(start 139.043664 -340.594696)
		(end 139.13231 -340.567772)
		(width 0.1651)
		(layer "In7.Cu")
		(net "P5E_PEX1_STN5_TX_DP<84>")
	)
	(segment
		(start 139.132564 -340.567772)
		(end 170.325034 -331.10551)
		(width 0.1651)
		(layer "In7.Cu")
		(net "P5E_PEX1_STN5_TX_DP<84>")
	)
	(segment
		(start 177.056288 -325.987156)
		(end 177.983896 -323.747892)
		(width 0.1651)
		(layer "In7.Cu")
		(net "P5E_PEX1_STN5_TX_DP<84>")
	)
	(segment
		(start 170.325034 -331.10551)
		(end 174.350934 -328.69251)
		(width 0.1651)
		(layer "In7.Cu")
		(net "P5E_PEX1_STN5_TX_DP<84>")
	)
	(segment
		(start 137.024618 -347.620082)
		(end 138.579098 -346.065602)
		(width 0.1651)
		(layer "In7.Cu")
		(net "P5E_PEX1_STN5_TX_DP<84>")
	)
	(segment
		(start 178.029616 -319.942718)
		(end 178.029616 -311.705498)
		(width 0.1143)
		(layer "In7.Cu")
		(net "P5E_PEX1_STN5_TX_DP<84>")
	)
	(segment
		(start 178.029616 -311.705498)
		(end 178.255422 -311.479692)
		(width 0.1143)
		(layer "In7.Cu")
		(net "P5E_PEX1_STN5_TX_DP<84>")
	)
	(segment
		(start 136.733788 -348.58579)
		(end 137.024618 -348.29496)
		(width 0.1651)
		(layer "In7.Cu")
		(net "P5E_PEX1_STN5_TX_DP<84>")
	)
	(segment
		(start 178.599846 -311.365392)
		(end 178.599846 -311.099962)
		(width 0.1143)
		(layer "In7.Cu")
		(net "P5E_PEX1_STN5_TX_DP<84>")
	)
	(segment
		(start 177.983896 -320.016886)
		(end 177.983896 -319.988438)
		(width 0.1143)
		(layer "In7.Cu")
		(net "P5E_PEX1_STN5_TX_DP<84>")
	)
	(segment
		(start 267.325602 -131.297934)
		(end 267.628878 -130.994658)
		(width 0.13462)
		(layer "F.Cu")
		(net "P5E_PEX2_STN1_TX_DN<28>")
	)
	(segment
		(start 268.24305 -130.994658)
		(end 268.571726 -131.323334)
		(width 0.13462)
		(layer "F.Cu")
		(net "P5E_PEX2_STN1_TX_DN<28>")
	)
	(segment
		(start 267.628878 -130.994658)
		(end 268.24305 -130.994658)
		(width 0.13462)
		(layer "F.Cu")
		(net "P5E_PEX2_STN1_TX_DN<28>")
	)
	(segment
		(start 265.68146 -132.004054)
		(end 265.839956 -131.972558)
		(width 0.1651)
		(layer "In9.Cu")
		(net "P5E_PEX2_STN1_TX_DN<28>")
	)
	(segment
		(start 264.941558 -137.54354)
		(end 264.7569 -137.09777)
		(width 0.1651)
		(layer "In9.Cu")
		(net "P5E_PEX2_STN1_TX_DN<28>")
	)
	(segment
		(start 302.870108 -278.12619)
		(end 302.870108 -271.546066)
		(width 0.1143)
		(layer "In9.Cu")
		(net "P5E_PEX2_STN1_TX_DN<28>")
	)
	(segment
		(start 266.127738 -140.407136)
		(end 266.18946 -140.257784)
		(width 0.1651)
		(layer "In9.Cu")
		(net "P5E_PEX2_STN1_TX_DN<28>")
	)
	(segment
		(start 268.166596 -160.144714)
		(end 267.884148 -158.72333)
		(width 0.1651)
		(layer "In9.Cu")
		(net "P5E_PEX2_STN1_TX_DN<28>")
	)
	(segment
		(start 265.732768 -139.154662)
		(end 265.54811 -138.708384)
		(width 0.1651)
		(layer "In9.Cu")
		(net "P5E_PEX2_STN1_TX_DN<28>")
	)
	(segment
		(start 266.461748 -140.914882)
		(end 266.312142 -140.852906)
		(width 0.1651)
		(layer "In9.Cu")
		(net "P5E_PEX2_STN1_TX_DN<28>")
	)
	(segment
		(start 264.634218 -136.50214)
		(end 264.484612 -136.440418)
		(width 0.1651)
		(layer "In9.Cu")
		(net "P5E_PEX2_STN1_TX_DN<28>")
	)
	(segment
		(start 265.275822 -138.05154)
		(end 265.091164 -137.605262)
		(width 0.1651)
		(layer "In9.Cu")
		(net "P5E_PEX2_STN1_TX_DN<28>")
	)
	(segment
		(start 268.449298 -161.566352)
		(end 268.166596 -160.144714)
		(width 0.1651)
		(layer "In9.Cu")
		(net "P5E_PEX2_STN1_TX_DN<28>")
	)
	(segment
		(start 266.899644 -142.270734)
		(end 266.584684 -141.510258)
		(width 0.1651)
		(layer "In9.Cu")
		(net "P5E_PEX2_STN1_TX_DN<28>")
	)
	(segment
		(start 267.974064 -158.588964)
		(end 267.87983 -158.115508)
		(width 0.1651)
		(layer "In9.Cu")
		(net "P5E_PEX2_STN1_TX_DN<28>")
	)
	(segment
		(start 265.839956 -131.972558)
		(end 266.108434 -131.570984)
		(width 0.1651)
		(layer "In9.Cu")
		(net "P5E_PEX2_STN1_TX_DN<28>")
	)
	(segment
		(start 265.85545 -139.749784)
		(end 265.670792 -139.304014)
		(width 0.1651)
		(layer "In9.Cu")
		(net "P5E_PEX2_STN1_TX_DN<28>")
	)
	(segment
		(start 266.108434 -131.570984)
		(end 266.076938 -131.412488)
		(width 0.1651)
		(layer "In9.Cu")
		(net "P5E_PEX2_STN1_TX_DN<28>")
	)
	(segment
		(start 265.670792 -139.304014)
		(end 265.732768 -139.154662)
		(width 0.1651)
		(layer "In9.Cu")
		(net "P5E_PEX2_STN1_TX_DN<28>")
	)
	(segment
		(start 265.398504 -138.646662)
		(end 265.213846 -138.200892)
		(width 0.1651)
		(layer "In9.Cu")
		(net "P5E_PEX2_STN1_TX_DN<28>")
	)
	(segment
		(start 267.745464 -158.025592)
		(end 267.65123 -157.55239)
		(width 0.1651)
		(layer "In9.Cu")
		(net "P5E_PEX2_STN1_TX_DN<28>")
	)
	(segment
		(start 303.249584 -277.849838)
		(end 303.249584 -278.115268)
		(width 0.1143)
		(layer "In9.Cu")
		(net "P5E_PEX2_STN1_TX_DN<28>")
	)
	(segment
		(start 264.543794 -133.707124)
		(end 265.018266 -132.99694)
		(width 0.1651)
		(layer "In9.Cu")
		(net "P5E_PEX2_STN1_TX_DN<28>")
	)
	(segment
		(start 267.884148 -158.72333)
		(end 267.974064 -158.588964)
		(width 0.1651)
		(layer "In9.Cu")
		(net "P5E_PEX2_STN1_TX_DN<28>")
	)
	(segment
		(start 302.973486 -278.229568)
		(end 302.870108 -278.12619)
		(width 0.1143)
		(layer "In9.Cu")
		(net "P5E_PEX2_STN1_TX_DN<28>")
	)
	(segment
		(start 302.915828 -271.500346)
		(end 302.915828 -271.471898)
		(width 0.1143)
		(layer "In9.Cu")
		(net "P5E_PEX2_STN1_TX_DN<28>")
	)
	(segment
		(start 265.176762 -132.96519)
		(end 265.444986 -132.56387)
		(width 0.1651)
		(layer "In9.Cu")
		(net "P5E_PEX2_STN1_TX_DN<28>")
	)
	(segment
		(start 265.444986 -132.56387)
		(end 265.41349 -132.40512)
		(width 0.1651)
		(layer "In9.Cu")
		(net "P5E_PEX2_STN1_TX_DN<28>")
	)
	(segment
		(start 267.034772 -131.007104)
		(end 267.325602 -131.297934)
		(width 0.1651)
		(layer "In9.Cu")
		(net "P5E_PEX2_STN1_TX_DN<28>")
	)
	(segment
		(start 266.312142 -140.852906)
		(end 266.127738 -140.407136)
		(width 0.1651)
		(layer "In9.Cu")
		(net "P5E_PEX2_STN1_TX_DN<28>")
	)
	(segment
		(start 303.135284 -278.229568)
		(end 302.973486 -278.229568)
		(width 0.1143)
		(layer "In9.Cu")
		(net "P5E_PEX2_STN1_TX_DN<28>")
	)
	(segment
		(start 302.915828 -263.383776)
		(end 268.449298 -161.566352)
		(width 0.1651)
		(layer "In9.Cu")
		(net "P5E_PEX2_STN1_TX_DN<28>")
	)
	(segment
		(start 265.54811 -138.708384)
		(end 265.398504 -138.646662)
		(width 0.1651)
		(layer "In9.Cu")
		(net "P5E_PEX2_STN1_TX_DN<28>")
	)
	(segment
		(start 266.646406 -141.360906)
		(end 266.461748 -140.914882)
		(width 0.1651)
		(layer "In9.Cu")
		(net "P5E_PEX2_STN1_TX_DN<28>")
	)
	(segment
		(start 265.091164 -137.605262)
		(end 264.941558 -137.54354)
		(width 0.1651)
		(layer "In9.Cu")
		(net "P5E_PEX2_STN1_TX_DN<28>")
	)
	(segment
		(start 302.915828 -271.471898)
		(end 302.915828 -263.383776)
		(width 0.1651)
		(layer "In9.Cu")
		(net "P5E_PEX2_STN1_TX_DN<28>")
	)
	(segment
		(start 264.818876 -136.948418)
		(end 264.634218 -136.50214)
		(width 0.1651)
		(layer "In9.Cu")
		(net "P5E_PEX2_STN1_TX_DN<28>")
	)
	(segment
		(start 267.74521 -158.025592)
		(end 267.745464 -158.025592)
		(width 0.1651)
		(layer "In9.Cu")
		(net "P5E_PEX2_STN1_TX_DN<28>")
	)
	(segment
		(start 266.460732 -131.007104)
		(end 267.034772 -131.007104)
		(width 0.1651)
		(layer "In9.Cu")
		(net "P5E_PEX2_STN1_TX_DN<28>")
	)
	(segment
		(start 266.076938 -131.412488)
		(end 266.284964 -131.101084)
		(width 0.1651)
		(layer "In9.Cu")
		(net "P5E_PEX2_STN1_TX_DN<28>")
	)
	(segment
		(start 266.004802 -139.811506)
		(end 265.85545 -139.749784)
		(width 0.1651)
		(layer "In9.Cu")
		(net "P5E_PEX2_STN1_TX_DN<28>")
	)
	(segment
		(start 265.213846 -138.200892)
		(end 265.275822 -138.05154)
		(width 0.1651)
		(layer "In9.Cu")
		(net "P5E_PEX2_STN1_TX_DN<28>")
	)
	(segment
		(start 302.870108 -271.546066)
		(end 302.915828 -271.500346)
		(width 0.1143)
		(layer "In9.Cu")
		(net "P5E_PEX2_STN1_TX_DN<28>")
	)
	(segment
		(start 267.65123 -157.55239)
		(end 266.899644 -142.270734)
		(width 0.1651)
		(layer "In9.Cu")
		(net "P5E_PEX2_STN1_TX_DN<28>")
	)
	(segment
		(start 264.299954 -135.994648)
		(end 264.299954 -134.295642)
		(width 0.1651)
		(layer "In9.Cu")
		(net "P5E_PEX2_STN1_TX_DN<28>")
	)
	(segment
		(start 265.41349 -132.40512)
		(end 265.68146 -132.004054)
		(width 0.1651)
		(layer "In9.Cu")
		(net "P5E_PEX2_STN1_TX_DN<28>")
	)
	(segment
		(start 266.18946 -140.257784)
		(end 266.004802 -139.811506)
		(width 0.1651)
		(layer "In9.Cu")
		(net "P5E_PEX2_STN1_TX_DN<28>")
	)
	(segment
		(start 267.87983 -158.115508)
		(end 267.74521 -158.025592)
		(width 0.1651)
		(layer "In9.Cu")
		(net "P5E_PEX2_STN1_TX_DN<28>")
	)
	(segment
		(start 264.7569 -137.09777)
		(end 264.818876 -136.948418)
		(width 0.1651)
		(layer "In9.Cu")
		(net "P5E_PEX2_STN1_TX_DN<28>")
	)
	(segment
		(start 266.584684 -141.510258)
		(end 266.646406 -141.360906)
		(width 0.1651)
		(layer "In9.Cu")
		(net "P5E_PEX2_STN1_TX_DN<28>")
	)
	(segment
		(start 265.018266 -132.99694)
		(end 265.176762 -132.96519)
		(width 0.1651)
		(layer "In9.Cu")
		(net "P5E_PEX2_STN1_TX_DN<28>")
	)
	(segment
		(start 266.284964 -131.101084)
		(end 266.460732 -131.007104)
		(width 0.1651)
		(layer "In9.Cu")
		(net "P5E_PEX2_STN1_TX_DN<28>")
	)
	(segment
		(start 264.484612 -136.440418)
		(end 264.299954 -135.994648)
		(width 0.1651)
		(layer "In9.Cu")
		(net "P5E_PEX2_STN1_TX_DN<28>")
	)
	(segment
		(start 303.249584 -278.115268)
		(end 303.135284 -278.229568)
		(width 0.1143)
		(layer "In9.Cu")
		(net "P5E_PEX2_STN1_TX_DN<28>")
	)
	(segment
		(start 264.299954 -134.295642)
		(end 264.543794 -133.707124)
		(width 0.1651)
		(layer "In9.Cu")
		(net "P5E_PEX2_STN1_TX_DN<28>")
	)
	(segment
		(start 280.307542 -349.831914)
		(end 280.627582 -349.511874)
		(width 0.13462)
		(layer "F.Cu")
		(net "P5E_PEX2_STN7_TX_DP<118>")
	)
	(segment
		(start 280.627582 -348.88043)
		(end 280.332942 -348.58579)
		(width 0.13462)
		(layer "F.Cu")
		(net "P5E_PEX2_STN7_TX_DP<118>")
	)
	(segment
		(start 280.627582 -349.511874)
		(end 280.627582 -348.88043)
		(width 0.13462)
		(layer "F.Cu")
		(net "P5E_PEX2_STN7_TX_DP<118>")
	)
	(segment
		(start 261.652512 -309.14086)
		(end 262.94461 -309.14086)
		(width 0.1651)
		(layer "In7.Cu")
		(net "P5E_PEX2_STN7_TX_DP<118>")
	)
	(segment
		(start 267.13815 -306.730908)
		(end 267.374878 -306.683918)
		(width 0.1651)
		(layer "In7.Cu")
		(net "P5E_PEX2_STN7_TX_DP<118>")
	)
	(segment
		(start 255.462532 -324.685152)
		(end 254.508 -322.380102)
		(width 0.1651)
		(layer "In7.Cu")
		(net "P5E_PEX2_STN7_TX_DP<118>")
	)
	(segment
		(start 260.384544 -309.678324)
		(end 261.152894 -309.266082)
		(width 0.1651)
		(layer "In7.Cu")
		(net "P5E_PEX2_STN7_TX_DP<118>")
	)
	(segment
		(start 280.623772 -347.667834)
		(end 282.178252 -346.113354)
		(width 0.1651)
		(layer "In7.Cu")
		(net "P5E_PEX2_STN7_TX_DP<118>")
	)
	(segment
		(start 282.091892 -341.672164)
		(end 275.9583 -337.105752)
		(width 0.1651)
		(layer "In7.Cu")
		(net "P5E_PEX2_STN7_TX_DP<118>")
	)
	(segment
		(start 267.374878 -306.683918)
		(end 267.814552 -306.683918)
		(width 0.1651)
		(layer "In7.Cu")
		(net "P5E_PEX2_STN7_TX_DP<118>")
	)
	(segment
		(start 280.623772 -348.29496)
		(end 280.623772 -347.667834)
		(width 0.1651)
		(layer "In7.Cu")
		(net "P5E_PEX2_STN7_TX_DP<118>")
	)
	(segment
		(start 282.178252 -346.113354)
		(end 282.178252 -341.82939)
		(width 0.1651)
		(layer "In7.Cu")
		(net "P5E_PEX2_STN7_TX_DP<118>")
	)
	(segment
		(start 274.144232 -306.729638)
		(end 274.370038 -306.955444)
		(width 0.1143)
		(layer "In7.Cu")
		(net "P5E_PEX2_STN7_TX_DP<118>")
	)
	(segment
		(start 282.178252 -341.82939)
		(end 282.091892 -341.672164)
		(width 0.1651)
		(layer "In7.Cu")
		(net "P5E_PEX2_STN7_TX_DP<118>")
	)
	(segment
		(start 261.152894 -309.266082)
		(end 261.652512 -309.14086)
		(width 0.1651)
		(layer "In7.Cu")
		(net "P5E_PEX2_STN7_TX_DP<118>")
	)
	(segment
		(start 262.94461 -309.14086)
		(end 262.975852 -309.13451)
		(width 0.1651)
		(layer "In7.Cu")
		(net "P5E_PEX2_STN7_TX_DP<118>")
	)
	(segment
		(start 267.843 -306.683918)
		(end 267.88872 -306.729638)
		(width 0.1143)
		(layer "In7.Cu")
		(net "P5E_PEX2_STN7_TX_DP<118>")
	)
	(segment
		(start 275.9583 -337.105752)
		(end 257.75412 -327.228962)
		(width 0.1651)
		(layer "In7.Cu")
		(net "P5E_PEX2_STN7_TX_DP<118>")
	)
	(segment
		(start 274.370038 -306.955444)
		(end 274.370038 -307.185568)
		(width 0.1143)
		(layer "In7.Cu")
		(net "P5E_PEX2_STN7_TX_DP<118>")
	)
	(segment
		(start 255.65227 -316.818264)
		(end 260.384544 -309.678324)
		(width 0.1651)
		(layer "In7.Cu")
		(net "P5E_PEX2_STN7_TX_DP<118>")
	)
	(segment
		(start 254.508 -319.405)
		(end 255.65227 -316.818264)
		(width 0.1651)
		(layer "In7.Cu")
		(net "P5E_PEX2_STN7_TX_DP<118>")
	)
	(segment
		(start 262.975852 -309.13451)
		(end 263.194546 -309.091076)
		(width 0.1651)
		(layer "In7.Cu")
		(net "P5E_PEX2_STN7_TX_DP<118>")
	)
	(segment
		(start 254.508 -322.380102)
		(end 254.508 -319.405)
		(width 0.1651)
		(layer "In7.Cu")
		(net "P5E_PEX2_STN7_TX_DP<118>")
	)
	(segment
		(start 267.814552 -306.683918)
		(end 267.843 -306.683918)
		(width 0.1143)
		(layer "In7.Cu")
		(net "P5E_PEX2_STN7_TX_DP<118>")
	)
	(segment
		(start 274.484338 -307.299868)
		(end 274.749768 -307.299868)
		(width 0.1143)
		(layer "In7.Cu")
		(net "P5E_PEX2_STN7_TX_DP<118>")
	)
	(segment
		(start 257.75412 -327.228962)
		(end 255.462532 -324.685152)
		(width 0.1651)
		(layer "In7.Cu")
		(net "P5E_PEX2_STN7_TX_DP<118>")
	)
	(segment
		(start 265.41222 -307.445918)
		(end 267.13815 -306.730908)
		(width 0.1651)
		(layer "In7.Cu")
		(net "P5E_PEX2_STN7_TX_DP<118>")
	)
	(segment
		(start 274.370038 -307.185568)
		(end 274.484338 -307.299868)
		(width 0.1143)
		(layer "In7.Cu")
		(net "P5E_PEX2_STN7_TX_DP<118>")
	)
	(segment
		(start 280.332942 -348.58579)
		(end 280.623772 -348.29496)
		(width 0.1651)
		(layer "In7.Cu")
		(net "P5E_PEX2_STN7_TX_DP<118>")
	)
	(segment
		(start 267.88872 -306.729638)
		(end 274.144232 -306.729638)
		(width 0.1143)
		(layer "In7.Cu")
		(net "P5E_PEX2_STN7_TX_DP<118>")
	)
	(segment
		(start 263.194546 -309.091076)
		(end 265.41222 -307.445918)
		(width 0.1651)
		(layer "In7.Cu")
		(net "P5E_PEX2_STN7_TX_DP<118>")
	)
	(segment
		(start 432.187096 -155.79852)
		(end 431.54092 -155.79852)
		(width 0.13462)
		(layer "F.Cu")
		(net "P5E_PEX3_STN0_TX_DP<15>")
	)
	(segment
		(start 432.47437 -156.085794)
		(end 432.187096 -155.79852)
		(width 0.13462)
		(layer "F.Cu")
		(net "P5E_PEX3_STN0_TX_DP<15>")
	)
	(segment
		(start 431.54092 -155.79852)
		(end 431.228246 -156.111194)
		(width 0.13462)
		(layer "F.Cu")
		(net "P5E_PEX3_STN0_TX_DP<15>")
	)
	(segment
		(start 432.83124 -157.77972)
		(end 432.863752 -157.901132)
		(width 0.1651)
		(layer "In9.Cu")
		(net "P5E_PEX3_STN0_TX_DP<15>")
	)
	(segment
		(start 432.279552 -158.913068)
		(end 425.211494 -171.156122)
		(width 0.1651)
		(layer "In9.Cu")
		(net "P5E_PEX3_STN0_TX_DP<15>")
	)
	(segment
		(start 433.675282 -156.49575)
		(end 433.200556 -157.317948)
		(width 0.1651)
		(layer "In9.Cu")
		(net "P5E_PEX3_STN0_TX_DP<15>")
	)
	(segment
		(start 422.5798 -271.546066)
		(end 422.5798 -278.205184)
		(width 0.1143)
		(layer "In9.Cu")
		(net "P5E_PEX3_STN0_TX_DP<15>")
	)
	(segment
		(start 423.035476 -278.420068)
		(end 423.149776 -278.534368)
		(width 0.1143)
		(layer "In9.Cu")
		(net "P5E_PEX3_STN0_TX_DP<15>")
	)
	(segment
		(start 422.53408 -269.528798)
		(end 422.53408 -271.471898)
		(width 0.1651)
		(layer "In9.Cu")
		(net "P5E_PEX3_STN0_TX_DP<15>")
	)
	(segment
		(start 423.408348 -260.7437)
		(end 423.408348 -267.41755)
		(width 0.1651)
		(layer "In9.Cu")
		(net "P5E_PEX3_STN0_TX_DP<15>")
	)
	(segment
		(start 432.863752 -157.901132)
		(end 432.616356 -158.329884)
		(width 0.1651)
		(layer "In9.Cu")
		(net "P5E_PEX3_STN0_TX_DP<15>")
	)
	(segment
		(start 423.408348 -267.41755)
		(end 422.53408 -269.528798)
		(width 0.1651)
		(layer "In9.Cu")
		(net "P5E_PEX3_STN0_TX_DP<15>")
	)
	(segment
		(start 423.69105 -176.846738)
		(end 419.87978 -220.410278)
		(width 0.1651)
		(layer "In9.Cu")
		(net "P5E_PEX3_STN0_TX_DP<15>")
	)
	(segment
		(start 420.763954 -230.515922)
		(end 423.408348 -260.7437)
		(width 0.1651)
		(layer "In9.Cu")
		(net "P5E_PEX3_STN0_TX_DP<15>")
	)
	(segment
		(start 432.246786 -158.791656)
		(end 432.279552 -158.913068)
		(width 0.1651)
		(layer "In9.Cu")
		(net "P5E_PEX3_STN0_TX_DP<15>")
	)
	(segment
		(start 422.5798 -278.205184)
		(end 422.794684 -278.420068)
		(width 0.1143)
		(layer "In9.Cu")
		(net "P5E_PEX3_STN0_TX_DP<15>")
	)
	(segment
		(start 423.149776 -278.534368)
		(end 423.149776 -278.799798)
		(width 0.1143)
		(layer "In9.Cu")
		(net "P5E_PEX3_STN0_TX_DP<15>")
	)
	(segment
		(start 422.53408 -271.500346)
		(end 422.5798 -271.546066)
		(width 0.1143)
		(layer "In9.Cu")
		(net "P5E_PEX3_STN0_TX_DP<15>")
	)
	(segment
		(start 432.7652 -155.794964)
		(end 433.374038 -155.794964)
		(width 0.1651)
		(layer "In9.Cu")
		(net "P5E_PEX3_STN0_TX_DP<15>")
	)
	(segment
		(start 423.690796 -176.846738)
		(end 423.69105 -176.846738)
		(width 0.1651)
		(layer "In9.Cu")
		(net "P5E_PEX3_STN0_TX_DP<15>")
	)
	(segment
		(start 419.87978 -220.410278)
		(end 420.763954 -230.515922)
		(width 0.1651)
		(layer "In9.Cu")
		(net "P5E_PEX3_STN0_TX_DP<15>")
	)
	(segment
		(start 422.53408 -271.471898)
		(end 422.53408 -271.500346)
		(width 0.1143)
		(layer "In9.Cu")
		(net "P5E_PEX3_STN0_TX_DP<15>")
	)
	(segment
		(start 432.616356 -158.329884)
		(end 432.49469 -158.362396)
		(width 0.1651)
		(layer "In9.Cu")
		(net "P5E_PEX3_STN0_TX_DP<15>")
	)
	(segment
		(start 433.079144 -157.350714)
		(end 432.83124 -157.77972)
		(width 0.1651)
		(layer "In9.Cu")
		(net "P5E_PEX3_STN0_TX_DP<15>")
	)
	(segment
		(start 423.693082 -176.821846)
		(end 423.690796 -176.846738)
		(width 0.1651)
		(layer "In9.Cu")
		(net "P5E_PEX3_STN0_TX_DP<15>")
	)
	(segment
		(start 425.211494 -171.156122)
		(end 423.693082 -176.821846)
		(width 0.1651)
		(layer "In9.Cu")
		(net "P5E_PEX3_STN0_TX_DP<15>")
	)
	(segment
		(start 433.374038 -155.794964)
		(end 433.675282 -156.096208)
		(width 0.1651)
		(layer "In9.Cu")
		(net "P5E_PEX3_STN0_TX_DP<15>")
	)
	(segment
		(start 432.47437 -156.085794)
		(end 432.7652 -155.794964)
		(width 0.1651)
		(layer "In9.Cu")
		(net "P5E_PEX3_STN0_TX_DP<15>")
	)
	(segment
		(start 432.49469 -158.362396)
		(end 432.246786 -158.791656)
		(width 0.1651)
		(layer "In9.Cu")
		(net "P5E_PEX3_STN0_TX_DP<15>")
	)
	(segment
		(start 433.675282 -156.096208)
		(end 433.675282 -156.49575)
		(width 0.1651)
		(layer "In9.Cu")
		(net "P5E_PEX3_STN0_TX_DP<15>")
	)
	(segment
		(start 433.200556 -157.317948)
		(end 433.079144 -157.350714)
		(width 0.1651)
		(layer "In9.Cu")
		(net "P5E_PEX3_STN0_TX_DP<15>")
	)
	(segment
		(start 422.794684 -278.420068)
		(end 423.035476 -278.420068)
		(width 0.1143)
		(layer "In9.Cu")
		(net "P5E_PEX3_STN0_TX_DP<15>")
	)
	(segment
		(start 304.015902 -383.604262)
		(end 304.015902 -369.105942)
		(width 0.1651)
		(layer "In5.Cu")
		(net "P5E_PEX2_STN7_RX_DN<127>")
	)
	(segment
		(start 302.265334 -348.835218)
		(end 302.25746 -348.339918)
		(width 0.1651)
		(layer "In5.Cu")
		(net "P5E_PEX2_STN7_RX_DN<127>")
	)
	(segment
		(start 276.226524 -326.88403)
		(end 274.84832 -325.352918)
		(width 0.1651)
		(layer "In5.Cu")
		(net "P5E_PEX2_STN7_RX_DN<127>")
	)
	(segment
		(start 274.415758 -320.0146)
		(end 274.370038 -319.96888)
		(width 0.1143)
		(layer "In5.Cu")
		(net "P5E_PEX2_STN7_RX_DN<127>")
	)
	(segment
		(start 274.370038 -318.434466)
		(end 274.484338 -318.320166)
		(width 0.1143)
		(layer "In5.Cu")
		(net "P5E_PEX2_STN7_RX_DN<127>")
	)
	(segment
		(start 302.25746 -348.339918)
		(end 302.19269 -348.277434)
		(width 0.1651)
		(layer "In5.Cu")
		(net "P5E_PEX2_STN7_RX_DN<127>")
	)
	(segment
		(start 274.484338 -318.320166)
		(end 274.635468 -318.320166)
		(width 0.1143)
		(layer "In5.Cu")
		(net "P5E_PEX2_STN7_RX_DN<127>")
	)
	(segment
		(start 301.288704 -340.538054)
		(end 277.815802 -327.888854)
		(width 0.1651)
		(layer "In5.Cu")
		(net "P5E_PEX2_STN7_RX_DN<127>")
	)
	(segment
		(start 302.619156 -362.512356)
		(end 302.383698 -360.421174)
		(width 0.1651)
		(layer "In5.Cu")
		(net "P5E_PEX2_STN7_RX_DN<127>")
	)
	(segment
		(start 303.777396 -383.843022)
		(end 303.777396 -383.842768)
		(width 0.1651)
		(layer "In5.Cu")
		(net "P5E_PEX2_STN7_RX_DN<127>")
	)
	(segment
		(start 274.635468 -318.320166)
		(end 274.749768 -318.434466)
		(width 0.1143)
		(layer "In5.Cu")
		(net "P5E_PEX2_STN7_RX_DN<127>")
	)
	(segment
		(start 277.815802 -327.888854)
		(end 276.226524 -326.88403)
		(width 0.1651)
		(layer "In5.Cu")
		(net "P5E_PEX2_STN7_RX_DN<127>")
	)
	(segment
		(start 274.749768 -318.434466)
		(end 274.749768 -318.699896)
		(width 0.1143)
		(layer "In5.Cu")
		(net "P5E_PEX2_STN7_RX_DN<127>")
	)
	(segment
		(start 303.777396 -383.842768)
		(end 304.015902 -383.604262)
		(width 0.1651)
		(layer "In5.Cu")
		(net "P5E_PEX2_STN7_RX_DN<127>")
	)
	(segment
		(start 274.370038 -319.96888)
		(end 274.370038 -318.434466)
		(width 0.1143)
		(layer "In5.Cu")
		(net "P5E_PEX2_STN7_RX_DN<127>")
	)
	(segment
		(start 301.873412 -341.426038)
		(end 301.288704 -340.538054)
		(width 0.1651)
		(layer "In5.Cu")
		(net "P5E_PEX2_STN7_RX_DN<127>")
	)
	(segment
		(start 302.383698 -360.421174)
		(end 302.20285 -348.899734)
		(width 0.1651)
		(layer "In5.Cu")
		(net "P5E_PEX2_STN7_RX_DN<127>")
	)
	(segment
		(start 302.192944 -348.277434)
		(end 302.096678 -342.1507)
		(width 0.1651)
		(layer "In5.Cu")
		(net "P5E_PEX2_STN7_RX_DN<127>")
	)
	(segment
		(start 302.096678 -342.1507)
		(end 301.873412 -341.426038)
		(width 0.1651)
		(layer "In5.Cu")
		(net "P5E_PEX2_STN7_RX_DN<127>")
	)
	(segment
		(start 302.88992 -384.590036)
		(end 302.88992 -384.20802)
		(width 0.1651)
		(layer "In5.Cu")
		(net "P5E_PEX2_STN7_RX_DN<127>")
	)
	(segment
		(start 274.84832 -325.352918)
		(end 274.415758 -324.30847)
		(width 0.1651)
		(layer "In5.Cu")
		(net "P5E_PEX2_STN7_RX_DN<127>")
	)
	(segment
		(start 304.015902 -369.105942)
		(end 302.619156 -362.512356)
		(width 0.1651)
		(layer "In5.Cu")
		(net "P5E_PEX2_STN7_RX_DN<127>")
	)
	(segment
		(start 302.19269 -348.277434)
		(end 302.192944 -348.277434)
		(width 0.1651)
		(layer "In5.Cu")
		(net "P5E_PEX2_STN7_RX_DN<127>")
	)
	(segment
		(start 303.506632 -384.08102)
		(end 303.539652 -384.070098)
		(width 0.1651)
		(layer "In5.Cu")
		(net "P5E_PEX2_STN7_RX_DN<127>")
	)
	(segment
		(start 303.547272 -384.066034)
		(end 303.58334 -384.036824)
		(width 0.1651)
		(layer "In5.Cu")
		(net "P5E_PEX2_STN7_RX_DN<127>")
	)
	(segment
		(start 303.01692 -384.08102)
		(end 303.506632 -384.08102)
		(width 0.1651)
		(layer "In5.Cu")
		(net "P5E_PEX2_STN7_RX_DN<127>")
	)
	(segment
		(start 274.415758 -324.30847)
		(end 274.415758 -320.043048)
		(width 0.1651)
		(layer "In5.Cu")
		(net "P5E_PEX2_STN7_RX_DN<127>")
	)
	(segment
		(start 302.20285 -348.899734)
		(end 302.265334 -348.835218)
		(width 0.1651)
		(layer "In5.Cu")
		(net "P5E_PEX2_STN7_RX_DN<127>")
	)
	(segment
		(start 303.539652 -384.070098)
		(end 303.547272 -384.066034)
		(width 0.1651)
		(layer "In5.Cu")
		(net "P5E_PEX2_STN7_RX_DN<127>")
	)
	(segment
		(start 274.415758 -320.043048)
		(end 274.415758 -320.0146)
		(width 0.1143)
		(layer "In5.Cu")
		(net "P5E_PEX2_STN7_RX_DN<127>")
	)
	(segment
		(start 302.88992 -384.20802)
		(end 303.01692 -384.08102)
		(width 0.1651)
		(layer "In5.Cu")
		(net "P5E_PEX2_STN7_RX_DN<127>")
	)
	(segment
		(start 303.58334 -384.036824)
		(end 303.777396 -383.843022)
		(width 0.1651)
		(layer "In5.Cu")
		(net "P5E_PEX2_STN7_RX_DN<127>")
	)
	(segment
		(start 131.084828 -356.831646)
		(end 131.404868 -356.511606)
		(width 0.13462)
		(layer "F.Cu")
		(net "P5E_PEX1_STN5_TX_C_DN<89>")
	)
	(segment
		(start 131.084828 -357.46309)
		(end 131.084828 -356.831646)
		(width 0.13462)
		(layer "F.Cu")
		(net "P5E_PEX1_STN5_TX_C_DN<89>")
	)
	(segment
		(start 131.379468 -357.75773)
		(end 131.084828 -357.46309)
		(width 0.13462)
		(layer "F.Cu")
		(net "P5E_PEX1_STN5_TX_C_DN<89>")
	)
	(segment
		(start 118.575328 -380.181104)
		(end 118.237 -380.181104)
		(width 0.1651)
		(layer "In13.Cu")
		(net "P5E_PEX1_STN5_TX_C_DN<89>")
	)
	(segment
		(start 131.088638 -358.04856)
		(end 131.088638 -358.676956)
		(width 0.1651)
		(layer "In13.Cu")
		(net "P5E_PEX1_STN5_TX_C_DN<89>")
	)
	(segment
		(start 119.595392 -368.545364)
		(end 119.266716 -369.320318)
		(width 0.1651)
		(layer "In13.Cu")
		(net "P5E_PEX1_STN5_TX_C_DN<89>")
	)
	(segment
		(start 119.266716 -369.320318)
		(end 119.266716 -379.489716)
		(width 0.1651)
		(layer "In13.Cu")
		(net "P5E_PEX1_STN5_TX_C_DN<89>")
	)
	(segment
		(start 130.856228 -359.173018)
		(end 119.595392 -368.545364)
		(width 0.1651)
		(layer "In13.Cu")
		(net "P5E_PEX1_STN5_TX_C_DN<89>")
	)
	(segment
		(start 118.237 -380.181104)
		(end 118.11 -380.308104)
		(width 0.1651)
		(layer "In13.Cu")
		(net "P5E_PEX1_STN5_TX_C_DN<89>")
	)
	(segment
		(start 131.088638 -358.676956)
		(end 130.856228 -359.173018)
		(width 0.1651)
		(layer "In13.Cu")
		(net "P5E_PEX1_STN5_TX_C_DN<89>")
	)
	(segment
		(start 118.11 -380.308104)
		(end 118.11 -380.69012)
		(width 0.1651)
		(layer "In13.Cu")
		(net "P5E_PEX1_STN5_TX_C_DN<89>")
	)
	(segment
		(start 131.379468 -357.75773)
		(end 131.088638 -358.04856)
		(width 0.1651)
		(layer "In13.Cu")
		(net "P5E_PEX1_STN5_TX_C_DN<89>")
	)
	(segment
		(start 119.266716 -379.489716)
		(end 118.575328 -380.181104)
		(width 0.1651)
		(layer "In13.Cu")
		(net "P5E_PEX1_STN5_TX_C_DN<89>")
	)
	(segment
		(start 143.246348 -348.88043)
		(end 142.951708 -348.58579)
		(width 0.13462)
		(layer "F.Cu")
		(net "P5E_PEX1_STN5_TX_DP<87>")
	)
	(segment
		(start 143.246348 -349.511874)
		(end 143.246348 -348.88043)
		(width 0.13462)
		(layer "F.Cu")
		(net "P5E_PEX1_STN5_TX_DP<87>")
	)
	(segment
		(start 142.926308 -349.831914)
		(end 143.246348 -349.511874)
		(width 0.13462)
		(layer "F.Cu")
		(net "P5E_PEX1_STN5_TX_DP<87>")
	)
	(segment
		(start 181.33568 -313.379612)
		(end 181.44998 -313.265312)
		(width 0.1143)
		(layer "In7.Cu")
		(net "P5E_PEX1_STN5_TX_DP<87>")
	)
	(segment
		(start 143.242538 -347.620082)
		(end 143.695166 -347.167454)
		(width 0.1651)
		(layer "In7.Cu")
		(net "P5E_PEX1_STN5_TX_DP<87>")
	)
	(segment
		(start 181.44998 -313.265312)
		(end 181.44998 -312.999882)
		(width 0.1143)
		(layer "In7.Cu")
		(net "P5E_PEX1_STN5_TX_DP<87>")
	)
	(segment
		(start 143.242538 -348.29496)
		(end 143.242538 -347.620082)
		(width 0.1651)
		(layer "In7.Cu")
		(net "P5E_PEX1_STN5_TX_DP<87>")
	)
	(segment
		(start 181.105556 -313.379612)
		(end 181.33568 -313.379612)
		(width 0.1143)
		(layer "In7.Cu")
		(net "P5E_PEX1_STN5_TX_DP<87>")
	)
	(segment
		(start 143.717264 -347.15704)
		(end 171.676568 -333.933038)
		(width 0.1651)
		(layer "In7.Cu")
		(net "P5E_PEX1_STN5_TX_DP<87>")
	)
	(segment
		(start 176.157128 -330.93914)
		(end 179.798472 -327.297796)
		(width 0.1651)
		(layer "In7.Cu")
		(net "P5E_PEX1_STN5_TX_DP<87>")
	)
	(segment
		(start 180.83403 -319.97396)
		(end 180.87975 -319.92824)
		(width 0.1143)
		(layer "In7.Cu")
		(net "P5E_PEX1_STN5_TX_DP<87>")
	)
	(segment
		(start 180.87975 -319.92824)
		(end 180.87975 -313.605418)
		(width 0.1143)
		(layer "In7.Cu")
		(net "P5E_PEX1_STN5_TX_DP<87>")
	)
	(segment
		(start 171.676568 -333.933038)
		(end 176.157128 -330.93914)
		(width 0.1651)
		(layer "In7.Cu")
		(net "P5E_PEX1_STN5_TX_DP<87>")
	)
	(segment
		(start 142.951708 -348.58579)
		(end 143.242538 -348.29496)
		(width 0.1651)
		(layer "In7.Cu")
		(net "P5E_PEX1_STN5_TX_DP<87>")
	)
	(segment
		(start 180.83403 -320.002408)
		(end 180.83403 -319.97396)
		(width 0.1143)
		(layer "In7.Cu")
		(net "P5E_PEX1_STN5_TX_DP<87>")
	)
	(segment
		(start 143.695166 -347.167454)
		(end 143.717264 -347.15704)
		(width 0.1651)
		(layer "In7.Cu")
		(net "P5E_PEX1_STN5_TX_DP<87>")
	)
	(segment
		(start 179.798472 -327.297796)
		(end 180.83403 -324.797674)
		(width 0.1651)
		(layer "In7.Cu")
		(net "P5E_PEX1_STN5_TX_DP<87>")
	)
	(segment
		(start 180.83403 -324.797674)
		(end 180.83403 -320.002408)
		(width 0.1651)
		(layer "In7.Cu")
		(net "P5E_PEX1_STN5_TX_DP<87>")
	)
	(segment
		(start 180.87975 -313.605418)
		(end 181.105556 -313.379612)
		(width 0.1143)
		(layer "In7.Cu")
		(net "P5E_PEX1_STN5_TX_DP<87>")
	)
	(segment
		(start 267.935202 -101.120702)
		(end 268.21638 -101.40188)
		(width 0.13462)
		(layer "F.Cu")
		(net "P5E_PEX2_STN1_TX_DN<17>")
	)
	(segment
		(start 268.21638 -101.40188)
		(end 268.874748 -101.40188)
		(width 0.13462)
		(layer "F.Cu")
		(net "P5E_PEX2_STN1_TX_DN<17>")
	)
	(segment
		(start 268.874748 -101.40188)
		(end 269.181326 -101.095302)
		(width 0.13462)
		(layer "F.Cu")
		(net "P5E_PEX2_STN1_TX_DN<17>")
	)
	(segment
		(start 261.305802 -106.82732)
		(end 261.305802 -106.8578)
		(width 0.1651)
		(layer "In9.Cu")
		(net "P5E_PEX2_STN1_TX_DN<17>")
	)
	(segment
		(start 292.18382 -271.526)
		(end 292.18382 -271.554448)
		(width 0.1143)
		(layer "In9.Cu")
		(net "P5E_PEX2_STN1_TX_DN<17>")
	)
	(segment
		(start 266.425172 -101.70795)
		(end 261.305802 -106.82732)
		(width 0.1651)
		(layer "In9.Cu")
		(net "P5E_PEX2_STN1_TX_DN<17>")
	)
	(segment
		(start 292.444678 -280.319988)
		(end 292.68547 -280.319988)
		(width 0.1143)
		(layer "In9.Cu")
		(net "P5E_PEX2_STN1_TX_DN<17>")
	)
	(segment
		(start 256.675128 -159.677608)
		(end 257.24739 -162.555174)
		(width 0.1651)
		(layer "In9.Cu")
		(net "P5E_PEX2_STN1_TX_DN<17>")
	)
	(segment
		(start 261.305802 -106.8578)
		(end 258.825746 -112.84458)
		(width 0.1651)
		(layer "In9.Cu")
		(net "P5E_PEX2_STN1_TX_DN<17>")
	)
	(segment
		(start 255.959864 -145.126456)
		(end 256.675128 -159.677608)
		(width 0.1651)
		(layer "In9.Cu")
		(net "P5E_PEX2_STN1_TX_DN<17>")
	)
	(segment
		(start 292.22954 -280.10485)
		(end 292.444678 -280.319988)
		(width 0.1143)
		(layer "In9.Cu")
		(net "P5E_PEX2_STN1_TX_DN<17>")
	)
	(segment
		(start 292.22954 -271.600168)
		(end 292.22954 -280.10485)
		(width 0.1143)
		(layer "In9.Cu")
		(net "P5E_PEX2_STN1_TX_DN<17>")
	)
	(segment
		(start 292.18382 -271.554448)
		(end 292.22954 -271.600168)
		(width 0.1143)
		(layer "In9.Cu")
		(net "P5E_PEX2_STN1_TX_DN<17>")
	)
	(segment
		(start 267.935202 -101.120702)
		(end 267.644372 -101.411532)
		(width 0.1651)
		(layer "In9.Cu")
		(net "P5E_PEX2_STN1_TX_DN<17>")
	)
	(segment
		(start 253.372874 -130.82016)
		(end 253.372874 -138.880088)
		(width 0.1651)
		(layer "In9.Cu")
		(net "P5E_PEX2_STN1_TX_DN<17>")
	)
	(segment
		(start 292.79977 -280.434288)
		(end 292.79977 -280.699718)
		(width 0.1143)
		(layer "In9.Cu")
		(net "P5E_PEX2_STN1_TX_DN<17>")
	)
	(segment
		(start 292.18382 -265.771122)
		(end 292.18382 -271.526)
		(width 0.1651)
		(layer "In9.Cu")
		(net "P5E_PEX2_STN1_TX_DN<17>")
	)
	(segment
		(start 292.68547 -280.319988)
		(end 292.79977 -280.434288)
		(width 0.1143)
		(layer "In9.Cu")
		(net "P5E_PEX2_STN1_TX_DN<17>")
	)
	(segment
		(start 267.644372 -101.411532)
		(end 267.14069 -101.411532)
		(width 0.1651)
		(layer "In9.Cu")
		(net "P5E_PEX2_STN1_TX_DN<17>")
	)
	(segment
		(start 257.24739 -162.555174)
		(end 292.18382 -265.771122)
		(width 0.1651)
		(layer "In9.Cu")
		(net "P5E_PEX2_STN1_TX_DN<17>")
	)
	(segment
		(start 258.825746 -112.84458)
		(end 253.372874 -130.82016)
		(width 0.1651)
		(layer "In9.Cu")
		(net "P5E_PEX2_STN1_TX_DN<17>")
	)
	(segment
		(start 253.372874 -138.880088)
		(end 255.959864 -145.126456)
		(width 0.1651)
		(layer "In9.Cu")
		(net "P5E_PEX2_STN1_TX_DN<17>")
	)
	(segment
		(start 267.14069 -101.411532)
		(end 266.425172 -101.70795)
		(width 0.1651)
		(layer "In9.Cu")
		(net "P5E_PEX2_STN1_TX_DN<17>")
	)
	(segment
		(start 332.045564 -355.978206)
		(end 331.725524 -355.658166)
		(width 0.13462)
		(layer "F.Cu")
		(net "P5E_PEX2_STN6_TX_DN<102>")
	)
	(segment
		(start 331.725524 -355.658166)
		(end 331.725524 -355.026722)
		(width 0.13462)
		(layer "F.Cu")
		(net "P5E_PEX2_STN6_TX_DN<102>")
	)
	(segment
		(start 331.725524 -355.026722)
		(end 332.020164 -354.732082)
		(width 0.13462)
		(layer "F.Cu")
		(net "P5E_PEX2_STN6_TX_DN<102>")
	)
	(segment
		(start 283.915866 -323.051424)
		(end 284.17139 -323.66839)
		(width 0.1651)
		(layer "In13.Cu")
		(net "P5E_PEX2_STN6_TX_DN<102>")
	)
	(segment
		(start 332.74 -340.8426)
		(end 333.283814 -342.275414)
		(width 0.1651)
		(layer "In13.Cu")
		(net "P5E_PEX2_STN6_TX_DN<102>")
	)
	(segment
		(start 295.025826 -327.258934)
		(end 314.806584 -331.132942)
		(width 0.1651)
		(layer "In13.Cu")
		(net "P5E_PEX2_STN6_TX_DN<102>")
	)
	(segment
		(start 283.870146 -313.673744)
		(end 283.870146 -319.921128)
		(width 0.1143)
		(layer "In13.Cu")
		(net "P5E_PEX2_STN6_TX_DN<102>")
	)
	(segment
		(start 285.992824 -325.489824)
		(end 294.340026 -327.124568)
		(width 0.1651)
		(layer "In13.Cu")
		(net "P5E_PEX2_STN6_TX_DN<102>")
	)
	(segment
		(start 314.806584 -331.132942)
		(end 330.4286 -338.0486)
		(width 0.1651)
		(layer "In13.Cu")
		(net "P5E_PEX2_STN6_TX_DN<102>")
	)
	(segment
		(start 294.459406 -327.044304)
		(end 294.945816 -327.139554)
		(width 0.1651)
		(layer "In13.Cu")
		(net "P5E_PEX2_STN6_TX_DN<102>")
	)
	(segment
		(start 331.729334 -353.930966)
		(end 331.729334 -354.441252)
		(width 0.1651)
		(layer "In13.Cu")
		(net "P5E_PEX2_STN6_TX_DN<102>")
	)
	(segment
		(start 283.973778 -313.570112)
		(end 283.870146 -313.673744)
		(width 0.1143)
		(layer "In13.Cu")
		(net "P5E_PEX2_STN6_TX_DN<102>")
	)
	(segment
		(start 283.915866 -319.966848)
		(end 283.915866 -319.995296)
		(width 0.1143)
		(layer "In13.Cu")
		(net "P5E_PEX2_STN6_TX_DN<102>")
	)
	(segment
		(start 284.249876 -313.949842)
		(end 284.249876 -313.684412)
		(width 0.1143)
		(layer "In13.Cu")
		(net "P5E_PEX2_STN6_TX_DN<102>")
	)
	(segment
		(start 332.570074 -340.637368)
		(end 332.74 -340.8426)
		(width 0.1651)
		(layer "In13.Cu")
		(net "P5E_PEX2_STN6_TX_DN<102>")
	)
	(segment
		(start 284.17139 -323.66839)
		(end 285.992824 -325.489824)
		(width 0.1651)
		(layer "In13.Cu")
		(net "P5E_PEX2_STN6_TX_DN<102>")
	)
	(segment
		(start 283.915866 -319.995296)
		(end 283.915866 -323.051424)
		(width 0.1651)
		(layer "In13.Cu")
		(net "P5E_PEX2_STN6_TX_DN<102>")
	)
	(segment
		(start 294.340026 -327.124568)
		(end 294.459406 -327.044304)
		(width 0.1651)
		(layer "In13.Cu")
		(net "P5E_PEX2_STN6_TX_DN<102>")
	)
	(segment
		(start 333.283814 -352.376486)
		(end 331.729334 -353.930966)
		(width 0.1651)
		(layer "In13.Cu")
		(net "P5E_PEX2_STN6_TX_DN<102>")
	)
	(segment
		(start 294.945816 -327.139554)
		(end 295.025826 -327.258934)
		(width 0.1651)
		(layer "In13.Cu")
		(net "P5E_PEX2_STN6_TX_DN<102>")
	)
	(segment
		(start 330.4286 -338.0486)
		(end 332.570074 -340.637368)
		(width 0.1651)
		(layer "In13.Cu")
		(net "P5E_PEX2_STN6_TX_DN<102>")
	)
	(segment
		(start 333.283814 -342.275414)
		(end 333.283814 -352.376486)
		(width 0.1651)
		(layer "In13.Cu")
		(net "P5E_PEX2_STN6_TX_DN<102>")
	)
	(segment
		(start 284.249876 -313.684412)
		(end 284.135576 -313.570112)
		(width 0.1143)
		(layer "In13.Cu")
		(net "P5E_PEX2_STN6_TX_DN<102>")
	)
	(segment
		(start 283.870146 -319.921128)
		(end 283.915866 -319.966848)
		(width 0.1143)
		(layer "In13.Cu")
		(net "P5E_PEX2_STN6_TX_DN<102>")
	)
	(segment
		(start 331.729334 -354.441252)
		(end 332.020164 -354.732082)
		(width 0.1651)
		(layer "In13.Cu")
		(net "P5E_PEX2_STN6_TX_DN<102>")
	)
	(segment
		(start 284.135576 -313.570112)
		(end 283.973778 -313.570112)
		(width 0.1143)
		(layer "In13.Cu")
		(net "P5E_PEX2_STN6_TX_DN<102>")
	)
	(segment
		(start 432.47437 -145.285714)
		(end 432.179476 -144.99082)
		(width 0.13462)
		(layer "F.Cu")
		(net "P5E_PEX3_STN0_TX_DP<9>")
	)
	(segment
		(start 431.54854 -144.99082)
		(end 431.228246 -145.311114)
		(width 0.13462)
		(layer "F.Cu")
		(net "P5E_PEX3_STN0_TX_DP<9>")
	)
	(segment
		(start 432.179476 -144.99082)
		(end 431.54854 -144.99082)
		(width 0.13462)
		(layer "F.Cu")
		(net "P5E_PEX3_STN0_TX_DP<9>")
	)
	(segment
		(start 428.494698 -278.420068)
		(end 428.73549 -278.420068)
		(width 0.1143)
		(layer "In9.Cu")
		(net "P5E_PEX3_STN0_TX_DP<9>")
	)
	(segment
		(start 433.356004 -144.994884)
		(end 433.840636 -145.479516)
		(width 0.1651)
		(layer "In9.Cu")
		(net "P5E_PEX3_STN0_TX_DP<9>")
	)
	(segment
		(start 429.214788 -268.933168)
		(end 428.234094 -271.30121)
		(width 0.1651)
		(layer "In9.Cu")
		(net "P5E_PEX3_STN0_TX_DP<9>")
	)
	(segment
		(start 428.73549 -278.420068)
		(end 428.84979 -278.534368)
		(width 0.1143)
		(layer "In9.Cu")
		(net "P5E_PEX3_STN0_TX_DP<9>")
	)
	(segment
		(start 435.68747 -147.46478)
		(end 435.662832 -147.58797)
		(width 0.1651)
		(layer "In9.Cu")
		(net "P5E_PEX3_STN0_TX_DP<9>")
	)
	(segment
		(start 432.7652 -144.994884)
		(end 433.356004 -144.994884)
		(width 0.1651)
		(layer "In9.Cu")
		(net "P5E_PEX3_STN0_TX_DP<9>")
	)
	(segment
		(start 428.84979 -278.534368)
		(end 428.84979 -278.799798)
		(width 0.1143)
		(layer "In9.Cu")
		(net "P5E_PEX3_STN0_TX_DP<9>")
	)
	(segment
		(start 428.234094 -271.500346)
		(end 428.279814 -271.546066)
		(width 0.1143)
		(layer "In9.Cu")
		(net "P5E_PEX3_STN0_TX_DP<9>")
	)
	(segment
		(start 425.852336 -221.85376)
		(end 429.214788 -260.32714)
		(width 0.1651)
		(layer "In9.Cu")
		(net "P5E_PEX3_STN0_TX_DP<9>")
	)
	(segment
		(start 439.479944 -154.64917)
		(end 439.479944 -158.199328)
		(width 0.1651)
		(layer "In9.Cu")
		(net "P5E_PEX3_STN0_TX_DP<9>")
	)
	(segment
		(start 436.061612 -148.024596)
		(end 436.061358 -148.024596)
		(width 0.1651)
		(layer "In9.Cu")
		(net "P5E_PEX3_STN0_TX_DP<9>")
	)
	(segment
		(start 434.300884 -145.939764)
		(end 435.408578 -147.047458)
		(width 0.1651)
		(layer "In9.Cu")
		(net "P5E_PEX3_STN0_TX_DP<9>")
	)
	(segment
		(start 436.061358 -148.024596)
		(end 437.835548 -150.679658)
		(width 0.1651)
		(layer "In9.Cu")
		(net "P5E_PEX3_STN0_TX_DP<9>")
	)
	(segment
		(start 431.015648 -172.862748)
		(end 429.71974 -177.694844)
		(width 0.1651)
		(layer "In9.Cu")
		(net "P5E_PEX3_STN0_TX_DP<9>")
	)
	(segment
		(start 435.938168 -148.000212)
		(end 436.061612 -148.024596)
		(width 0.1651)
		(layer "In9.Cu")
		(net "P5E_PEX3_STN0_TX_DP<9>")
	)
	(segment
		(start 428.279814 -278.205184)
		(end 428.494698 -278.420068)
		(width 0.1143)
		(layer "In9.Cu")
		(net "P5E_PEX3_STN0_TX_DP<9>")
	)
	(segment
		(start 435.662832 -147.58797)
		(end 435.938168 -148.000212)
		(width 0.1651)
		(layer "In9.Cu")
		(net "P5E_PEX3_STN0_TX_DP<9>")
	)
	(segment
		(start 435.408578 -147.047458)
		(end 435.68747 -147.46478)
		(width 0.1651)
		(layer "In9.Cu")
		(net "P5E_PEX3_STN0_TX_DP<9>")
	)
	(segment
		(start 432.47437 -145.285714)
		(end 432.7652 -144.994884)
		(width 0.1651)
		(layer "In9.Cu")
		(net "P5E_PEX3_STN0_TX_DP<9>")
	)
	(segment
		(start 428.234094 -271.471898)
		(end 428.234094 -271.500346)
		(width 0.1143)
		(layer "In9.Cu")
		(net "P5E_PEX3_STN0_TX_DP<9>")
	)
	(segment
		(start 433.840636 -145.479516)
		(end 433.840636 -145.616168)
		(width 0.1651)
		(layer "In9.Cu")
		(net "P5E_PEX3_STN0_TX_DP<9>")
	)
	(segment
		(start 437.835548 -150.679658)
		(end 439.479944 -154.64917)
		(width 0.1651)
		(layer "In9.Cu")
		(net "P5E_PEX3_STN0_TX_DP<9>")
	)
	(segment
		(start 429.214788 -260.32714)
		(end 429.214788 -268.933168)
		(width 0.1651)
		(layer "In9.Cu")
		(net "P5E_PEX3_STN0_TX_DP<9>")
	)
	(segment
		(start 428.234094 -271.30121)
		(end 428.234094 -271.471898)
		(width 0.1651)
		(layer "In9.Cu")
		(net "P5E_PEX3_STN0_TX_DP<9>")
	)
	(segment
		(start 433.840636 -145.616168)
		(end 434.164232 -145.939764)
		(width 0.1651)
		(layer "In9.Cu")
		(net "P5E_PEX3_STN0_TX_DP<9>")
	)
	(segment
		(start 434.164232 -145.939764)
		(end 434.300884 -145.939764)
		(width 0.1651)
		(layer "In9.Cu")
		(net "P5E_PEX3_STN0_TX_DP<9>")
	)
	(segment
		(start 429.71974 -177.694844)
		(end 425.852336 -221.85376)
		(width 0.1651)
		(layer "In9.Cu")
		(net "P5E_PEX3_STN0_TX_DP<9>")
	)
	(segment
		(start 428.279814 -271.546066)
		(end 428.279814 -278.205184)
		(width 0.1143)
		(layer "In9.Cu")
		(net "P5E_PEX3_STN0_TX_DP<9>")
	)
	(segment
		(start 439.479944 -158.199328)
		(end 431.015648 -172.862748)
		(width 0.1651)
		(layer "In9.Cu")
		(net "P5E_PEX3_STN0_TX_DP<9>")
	)
	(segment
		(start 291.505132 -358.107996)
		(end 291.505132 -342.058244)
		(width 0.1651)
		(layer "In5.Cu")
		(net "P5E_PEX2_STN7_RX_DP<123>")
	)
	(segment
		(start 293.925244 -366.025176)
		(end 293.999158 -365.881412)
		(width 0.1651)
		(layer "In5.Cu")
		(net "P5E_PEX2_STN7_RX_DP<123>")
	)
	(segment
		(start 292.191948 -360.623104)
		(end 292.040564 -360.151172)
		(width 0.1651)
		(layer "In5.Cu")
		(net "P5E_PEX2_STN7_RX_DP<123>")
	)
	(segment
		(start 270.795496 -327.19645)
		(end 270.333978 -325.923656)
		(width 0.1651)
		(layer "In5.Cu")
		(net "P5E_PEX2_STN7_RX_DP<123>")
	)
	(segment
		(start 270.333978 -320.043048)
		(end 270.333978 -320.0146)
		(width 0.1143)
		(layer "In5.Cu")
		(net "P5E_PEX2_STN7_RX_DP<123>")
	)
	(segment
		(start 292.114478 -360.007408)
		(end 291.505132 -358.107996)
		(width 0.1651)
		(layer "In5.Cu")
		(net "P5E_PEX2_STN7_RX_DP<123>")
	)
	(segment
		(start 290.244022 -339.889846)
		(end 275.937726 -331.908658)
		(width 0.1651)
		(layer "In5.Cu")
		(net "P5E_PEX2_STN7_RX_DP<123>")
	)
	(segment
		(start 294.220646 -366.571022)
		(end 294.076628 -366.497108)
		(width 0.1651)
		(layer "In5.Cu")
		(net "P5E_PEX2_STN7_RX_DP<123>")
	)
	(segment
		(start 294.076628 -366.497108)
		(end 293.925244 -366.025176)
		(width 0.1651)
		(layer "In5.Cu")
		(net "P5E_PEX2_STN7_RX_DP<123>")
	)
	(segment
		(start 293.70401 -365.336074)
		(end 293.552626 -364.864142)
		(width 0.1651)
		(layer "In5.Cu")
		(net "P5E_PEX2_STN7_RX_DP<123>")
	)
	(segment
		(start 294.089836 -383.67208)
		(end 294.216836 -383.79908)
		(width 0.1651)
		(layer "In5.Cu")
		(net "P5E_PEX2_STN7_RX_DP<123>")
	)
	(segment
		(start 270.379698 -319.96888)
		(end 270.379698 -318.355472)
		(width 0.1143)
		(layer "In5.Cu")
		(net "P5E_PEX2_STN7_RX_DP<123>")
	)
	(segment
		(start 293.847774 -365.409988)
		(end 293.848028 -365.409988)
		(width 0.1651)
		(layer "In5.Cu")
		(net "P5E_PEX2_STN7_RX_DP<123>")
	)
	(segment
		(start 270.949928 -318.015366)
		(end 270.949928 -317.749936)
		(width 0.1143)
		(layer "In5.Cu")
		(net "P5E_PEX2_STN7_RX_DP<123>")
	)
	(segment
		(start 270.333978 -325.923656)
		(end 270.333978 -320.043048)
		(width 0.1651)
		(layer "In5.Cu")
		(net "P5E_PEX2_STN7_RX_DP<123>")
	)
	(segment
		(start 294.216836 -383.79908)
		(end 294.647112 -383.79908)
		(width 0.1651)
		(layer "In5.Cu")
		(net "P5E_PEX2_STN7_RX_DP<123>")
	)
	(segment
		(start 270.333978 -320.0146)
		(end 270.379698 -319.96888)
		(width 0.1143)
		(layer "In5.Cu")
		(net "P5E_PEX2_STN7_RX_DP<123>")
	)
	(segment
		(start 293.552626 -364.864142)
		(end 293.62654 -364.720378)
		(width 0.1651)
		(layer "In5.Cu")
		(net "P5E_PEX2_STN7_RX_DP<123>")
	)
	(segment
		(start 294.647112 -383.79908)
		(end 294.933878 -383.512314)
		(width 0.1651)
		(layer "In5.Cu")
		(net "P5E_PEX2_STN7_RX_DP<123>")
	)
	(segment
		(start 275.937726 -331.908658)
		(end 273.229324 -330.092304)
		(width 0.1651)
		(layer "In5.Cu")
		(net "P5E_PEX2_STN7_RX_DP<123>")
	)
	(segment
		(start 270.379698 -318.355472)
		(end 270.605504 -318.129666)
		(width 0.1143)
		(layer "In5.Cu")
		(net "P5E_PEX2_STN7_RX_DP<123>")
	)
	(segment
		(start 292.335712 -360.697018)
		(end 292.335966 -360.697018)
		(width 0.1651)
		(layer "In5.Cu")
		(net "P5E_PEX2_STN7_RX_DP<123>")
	)
	(segment
		(start 292.335966 -360.697018)
		(end 292.191948 -360.623104)
		(width 0.1651)
		(layer "In5.Cu")
		(net "P5E_PEX2_STN7_RX_DP<123>")
	)
	(segment
		(start 270.835628 -318.129666)
		(end 270.949928 -318.015366)
		(width 0.1143)
		(layer "In5.Cu")
		(net "P5E_PEX2_STN7_RX_DP<123>")
	)
	(segment
		(start 294.089836 -383.290064)
		(end 294.089836 -383.67208)
		(width 0.1651)
		(layer "In5.Cu")
		(net "P5E_PEX2_STN7_RX_DP<123>")
	)
	(segment
		(start 291.505132 -342.058244)
		(end 291.166296 -341.173308)
		(width 0.1651)
		(layer "In5.Cu")
		(net "P5E_PEX2_STN7_RX_DP<123>")
	)
	(segment
		(start 293.998904 -365.881412)
		(end 293.847774 -365.409988)
		(width 0.1651)
		(layer "In5.Cu")
		(net "P5E_PEX2_STN7_RX_DP<123>")
	)
	(segment
		(start 292.040564 -360.151172)
		(end 292.114478 -360.007408)
		(width 0.1651)
		(layer "In5.Cu")
		(net "P5E_PEX2_STN7_RX_DP<123>")
	)
	(segment
		(start 291.166296 -341.173308)
		(end 290.244022 -339.889846)
		(width 0.1651)
		(layer "In5.Cu")
		(net "P5E_PEX2_STN7_RX_DP<123>")
	)
	(segment
		(start 294.933878 -383.512314)
		(end 294.933878 -368.794538)
		(width 0.1651)
		(layer "In5.Cu")
		(net "P5E_PEX2_STN7_RX_DP<123>")
	)
	(segment
		(start 293.62654 -364.720378)
		(end 292.335712 -360.697018)
		(width 0.1651)
		(layer "In5.Cu")
		(net "P5E_PEX2_STN7_RX_DP<123>")
	)
	(segment
		(start 294.933878 -368.794538)
		(end 294.220392 -366.571022)
		(width 0.1651)
		(layer "In5.Cu")
		(net "P5E_PEX2_STN7_RX_DP<123>")
	)
	(segment
		(start 273.229324 -330.092304)
		(end 270.795496 -327.19645)
		(width 0.1651)
		(layer "In5.Cu")
		(net "P5E_PEX2_STN7_RX_DP<123>")
	)
	(segment
		(start 294.220392 -366.571022)
		(end 294.220646 -366.571022)
		(width 0.1651)
		(layer "In5.Cu")
		(net "P5E_PEX2_STN7_RX_DP<123>")
	)
	(segment
		(start 293.999158 -365.881412)
		(end 293.998904 -365.881412)
		(width 0.1651)
		(layer "In5.Cu")
		(net "P5E_PEX2_STN7_RX_DP<123>")
	)
	(segment
		(start 270.605504 -318.129666)
		(end 270.835628 -318.129666)
		(width 0.1143)
		(layer "In5.Cu")
		(net "P5E_PEX2_STN7_RX_DP<123>")
	)
	(segment
		(start 293.848028 -365.409988)
		(end 293.70401 -365.336074)
		(width 0.1651)
		(layer "In5.Cu")
		(net "P5E_PEX2_STN7_RX_DP<123>")
	)
	(segment
		(start 34.877248 -345.465146)
		(end 35.171888 -345.170506)
		(width 0.13462)
		(layer "F.Cu")
		(net "P5E_PEX0_STN7_TX_C_DP<119>")
	)
	(segment
		(start 35.171888 -345.170506)
		(end 35.171888 -344.539062)
		(width 0.13462)
		(layer "F.Cu")
		(net "P5E_PEX0_STN7_TX_C_DP<119>")
	)
	(segment
		(start 35.171888 -344.539062)
		(end 34.851848 -344.219022)
		(width 0.13462)
		(layer "F.Cu")
		(net "P5E_PEX0_STN7_TX_C_DP<119>")
	)
	(segment
		(start 41.580308 -392.167618)
		(end 41.229788 -391.817098)
		(width 0.1651)
		(layer "In7.Cu")
		(net "P5E_PEX0_STN7_TX_C_DP<119>")
	)
	(segment
		(start 41.229788 -391.691368)
		(end 40.5765 -391.03808)
		(width 0.1651)
		(layer "In7.Cu")
		(net "P5E_PEX0_STN7_TX_C_DP<119>")
	)
	(segment
		(start 40.5765 -391.03808)
		(end 40.119046 -390.848596)
		(width 0.1651)
		(layer "In7.Cu")
		(net "P5E_PEX0_STN7_TX_C_DP<119>")
	)
	(segment
		(start 42.40657 -392.99388)
		(end 42.05605 -392.64336)
		(width 0.1651)
		(layer "In7.Cu")
		(net "P5E_PEX0_STN7_TX_C_DP<119>")
	)
	(segment
		(start 42.882312 -393.343892)
		(end 42.5323 -392.99388)
		(width 0.1651)
		(layer "In7.Cu")
		(net "P5E_PEX0_STN7_TX_C_DP<119>")
	)
	(segment
		(start 42.5323 -392.99388)
		(end 42.40657 -392.99388)
		(width 0.1651)
		(layer "In7.Cu")
		(net "P5E_PEX0_STN7_TX_C_DP<119>")
	)
	(segment
		(start 43.358308 -393.819888)
		(end 43.232578 -393.819888)
		(width 0.1651)
		(layer "In7.Cu")
		(net "P5E_PEX0_STN7_TX_C_DP<119>")
	)
	(segment
		(start 39.039546 -390.401302)
		(end 38.923468 -390.449308)
		(width 0.1651)
		(layer "In7.Cu")
		(net "P5E_PEX0_STN7_TX_C_DP<119>")
	)
	(segment
		(start 33.613598 -357.977186)
		(end 33.613598 -347.912182)
		(width 0.1651)
		(layer "In7.Cu")
		(net "P5E_PEX0_STN7_TX_C_DP<119>")
	)
	(segment
		(start 42.05605 -392.64336)
		(end 42.05605 -392.51763)
		(width 0.1651)
		(layer "In7.Cu")
		(net "P5E_PEX0_STN7_TX_C_DP<119>")
	)
	(segment
		(start 38.465506 -390.25957)
		(end 38.4175 -390.143492)
		(width 0.1651)
		(layer "In7.Cu")
		(net "P5E_PEX0_STN7_TX_C_DP<119>")
	)
	(segment
		(start 43.437048 -401.999196)
		(end 44.052744 -401.999196)
		(width 0.1651)
		(layer "In7.Cu")
		(net "P5E_PEX0_STN7_TX_C_DP<119>")
	)
	(segment
		(start 33.214818 -359.292144)
		(end 33.613598 -357.977186)
		(width 0.1651)
		(layer "In7.Cu")
		(net "P5E_PEX0_STN7_TX_C_DP<119>")
	)
	(segment
		(start 25.98674 -372.373906)
		(end 26.62809 -369.149376)
		(width 0.1651)
		(layer "In7.Cu")
		(net "P5E_PEX0_STN7_TX_C_DP<119>")
	)
	(segment
		(start 26.62809 -369.149376)
		(end 33.214818 -359.292144)
		(width 0.1651)
		(layer "In7.Cu")
		(net "P5E_PEX0_STN7_TX_C_DP<119>")
	)
	(segment
		(start 39.497 -390.590786)
		(end 39.039546 -390.401302)
		(width 0.1651)
		(layer "In7.Cu")
		(net "P5E_PEX0_STN7_TX_C_DP<119>")
	)
	(segment
		(start 38.923468 -390.449308)
		(end 38.465506 -390.25957)
		(width 0.1651)
		(layer "In7.Cu")
		(net "P5E_PEX0_STN7_TX_C_DP<119>")
	)
	(segment
		(start 27.106118 -385.322572)
		(end 26.5684 -384.126994)
		(width 0.1651)
		(layer "In7.Cu")
		(net "P5E_PEX0_STN7_TX_C_DP<119>")
	)
	(segment
		(start 44.052744 -401.999196)
		(end 44.20235 -401.84959)
		(width 0.1651)
		(layer "In7.Cu")
		(net "P5E_PEX0_STN7_TX_C_DP<119>")
	)
	(segment
		(start 38.417246 -390.143492)
		(end 30.922214 -387.038088)
		(width 0.1651)
		(layer "In7.Cu")
		(net "P5E_PEX0_STN7_TX_C_DP<119>")
	)
	(segment
		(start 40.002968 -390.896602)
		(end 39.545006 -390.706864)
		(width 0.1651)
		(layer "In7.Cu")
		(net "P5E_PEX0_STN7_TX_C_DP<119>")
	)
	(segment
		(start 42.882312 -393.469622)
		(end 42.882312 -393.343892)
		(width 0.1651)
		(layer "In7.Cu")
		(net "P5E_PEX0_STN7_TX_C_DP<119>")
	)
	(segment
		(start 30.412436 -387.038088)
		(end 27.696668 -385.913122)
		(width 0.1651)
		(layer "In7.Cu")
		(net "P5E_PEX0_STN7_TX_C_DP<119>")
	)
	(segment
		(start 33.613598 -347.912182)
		(end 35.168078 -346.357702)
		(width 0.1651)
		(layer "In7.Cu")
		(net "P5E_PEX0_STN7_TX_C_DP<119>")
	)
	(segment
		(start 44.20235 -394.66393)
		(end 43.358308 -393.819888)
		(width 0.1651)
		(layer "In7.Cu")
		(net "P5E_PEX0_STN7_TX_C_DP<119>")
	)
	(segment
		(start 43.310048 -401.872196)
		(end 43.437048 -401.999196)
		(width 0.1651)
		(layer "In7.Cu")
		(net "P5E_PEX0_STN7_TX_C_DP<119>")
	)
	(segment
		(start 38.4175 -390.143492)
		(end 38.417246 -390.143492)
		(width 0.1651)
		(layer "In7.Cu")
		(net "P5E_PEX0_STN7_TX_C_DP<119>")
	)
	(segment
		(start 42.05605 -392.51763)
		(end 41.706038 -392.167618)
		(width 0.1651)
		(layer "In7.Cu")
		(net "P5E_PEX0_STN7_TX_C_DP<119>")
	)
	(segment
		(start 41.706038 -392.167618)
		(end 41.580308 -392.167618)
		(width 0.1651)
		(layer "In7.Cu")
		(net "P5E_PEX0_STN7_TX_C_DP<119>")
	)
	(segment
		(start 44.20235 -401.84959)
		(end 44.20235 -394.66393)
		(width 0.1651)
		(layer "In7.Cu")
		(net "P5E_PEX0_STN7_TX_C_DP<119>")
	)
	(segment
		(start 41.229788 -391.817098)
		(end 41.229788 -391.691368)
		(width 0.1651)
		(layer "In7.Cu")
		(net "P5E_PEX0_STN7_TX_C_DP<119>")
	)
	(segment
		(start 26.5684 -384.126994)
		(end 25.98674 -374.456452)
		(width 0.1651)
		(layer "In7.Cu")
		(net "P5E_PEX0_STN7_TX_C_DP<119>")
	)
	(segment
		(start 39.545006 -390.706864)
		(end 39.497 -390.590786)
		(width 0.1651)
		(layer "In7.Cu")
		(net "P5E_PEX0_STN7_TX_C_DP<119>")
	)
	(segment
		(start 27.696668 -385.913122)
		(end 27.106118 -385.322572)
		(width 0.1651)
		(layer "In7.Cu")
		(net "P5E_PEX0_STN7_TX_C_DP<119>")
	)
	(segment
		(start 35.168078 -346.357702)
		(end 35.168078 -345.755976)
		(width 0.1651)
		(layer "In7.Cu")
		(net "P5E_PEX0_STN7_TX_C_DP<119>")
	)
	(segment
		(start 30.922214 -387.038088)
		(end 30.412436 -387.038088)
		(width 0.1651)
		(layer "In7.Cu")
		(net "P5E_PEX0_STN7_TX_C_DP<119>")
	)
	(segment
		(start 40.119046 -390.848596)
		(end 40.002968 -390.896602)
		(width 0.1651)
		(layer "In7.Cu")
		(net "P5E_PEX0_STN7_TX_C_DP<119>")
	)
	(segment
		(start 43.232578 -393.819888)
		(end 42.882312 -393.469622)
		(width 0.1651)
		(layer "In7.Cu")
		(net "P5E_PEX0_STN7_TX_C_DP<119>")
	)
	(segment
		(start 35.168078 -345.755976)
		(end 34.877248 -345.465146)
		(width 0.1651)
		(layer "In7.Cu")
		(net "P5E_PEX0_STN7_TX_C_DP<119>")
	)
	(segment
		(start 25.98674 -374.456452)
		(end 25.98674 -372.373906)
		(width 0.1651)
		(layer "In7.Cu")
		(net "P5E_PEX0_STN7_TX_C_DP<119>")
	)
	(segment
		(start 43.310048 -401.49018)
		(end 43.310048 -401.872196)
		(width 0.1651)
		(layer "In7.Cu")
		(net "P5E_PEX0_STN7_TX_C_DP<119>")
	)
	(segment
		(start 136.733788 -357.75773)
		(end 137.028428 -357.46309)
		(width 0.13462)
		(layer "F.Cu")
		(net "P5E_PEX1_STN5_TX_C_DP<92>")
	)
	(segment
		(start 137.028428 -357.46309)
		(end 137.028428 -356.831646)
		(width 0.13462)
		(layer "F.Cu")
		(net "P5E_PEX1_STN5_TX_C_DP<92>")
	)
	(segment
		(start 137.028428 -356.831646)
		(end 136.708388 -356.511606)
		(width 0.13462)
		(layer "F.Cu")
		(net "P5E_PEX1_STN5_TX_C_DP<92>")
	)
	(segment
		(start 129.308098 -365.053372)
		(end 129.69748 -364.74654)
		(width 0.1651)
		(layer "In13.Cu")
		(net "P5E_PEX1_STN5_TX_C_DP<92>")
	)
	(segment
		(start 124.71019 -378.67209)
		(end 124.83719 -378.79909)
		(width 0.1651)
		(layer "In13.Cu")
		(net "P5E_PEX1_STN5_TX_C_DP<92>")
	)
	(segment
		(start 130.226054 -364.330234)
		(end 130.615182 -364.023402)
		(width 0.1651)
		(layer "In13.Cu")
		(net "P5E_PEX1_STN5_TX_C_DP<92>")
	)
	(segment
		(start 124.83719 -378.79909)
		(end 125.058678 -378.79909)
		(width 0.1651)
		(layer "In13.Cu")
		(net "P5E_PEX1_STN5_TX_C_DP<92>")
	)
	(segment
		(start 137.024618 -358.608884)
		(end 137.024618 -358.04856)
		(width 0.1651)
		(layer "In13.Cu")
		(net "P5E_PEX1_STN5_TX_C_DP<92>")
	)
	(segment
		(start 125.584966 -378.272802)
		(end 125.584966 -368.69624)
		(width 0.1651)
		(layer "In13.Cu")
		(net "P5E_PEX1_STN5_TX_C_DP<92>")
	)
	(segment
		(start 125.584966 -368.69624)
		(end 126.053342 -367.730786)
		(width 0.1651)
		(layer "In13.Cu")
		(net "P5E_PEX1_STN5_TX_C_DP<92>")
	)
	(segment
		(start 129.822194 -364.761526)
		(end 130.211068 -364.455202)
		(width 0.1651)
		(layer "In13.Cu")
		(net "P5E_PEX1_STN5_TX_C_DP<92>")
	)
	(segment
		(start 130.211068 -364.455202)
		(end 130.226054 -364.330234)
		(width 0.1651)
		(layer "In13.Cu")
		(net "P5E_PEX1_STN5_TX_C_DP<92>")
	)
	(segment
		(start 129.293366 -365.17834)
		(end 129.308098 -365.053372)
		(width 0.1651)
		(layer "In13.Cu")
		(net "P5E_PEX1_STN5_TX_C_DP<92>")
	)
	(segment
		(start 136.648444 -359.383584)
		(end 137.024618 -358.608884)
		(width 0.1651)
		(layer "In13.Cu")
		(net "P5E_PEX1_STN5_TX_C_DP<92>")
	)
	(segment
		(start 124.71019 -378.290074)
		(end 124.71019 -378.67209)
		(width 0.1651)
		(layer "In13.Cu")
		(net "P5E_PEX1_STN5_TX_C_DP<92>")
	)
	(segment
		(start 137.024618 -358.04856)
		(end 136.733788 -357.75773)
		(width 0.1651)
		(layer "In13.Cu")
		(net "P5E_PEX1_STN5_TX_C_DP<92>")
	)
	(segment
		(start 126.053342 -367.730786)
		(end 129.293366 -365.17834)
		(width 0.1651)
		(layer "In13.Cu")
		(net "P5E_PEX1_STN5_TX_C_DP<92>")
	)
	(segment
		(start 131.129024 -363.732064)
		(end 131.14401 -363.607096)
		(width 0.1651)
		(layer "In13.Cu")
		(net "P5E_PEX1_STN5_TX_C_DP<92>")
	)
	(segment
		(start 131.658106 -363.31525)
		(end 136.648444 -359.383584)
		(width 0.1651)
		(layer "In13.Cu")
		(net "P5E_PEX1_STN5_TX_C_DP<92>")
	)
	(segment
		(start 131.14401 -363.607096)
		(end 131.533138 -363.300264)
		(width 0.1651)
		(layer "In13.Cu")
		(net "P5E_PEX1_STN5_TX_C_DP<92>")
	)
	(segment
		(start 131.533138 -363.300264)
		(end 131.658106 -363.31525)
		(width 0.1651)
		(layer "In13.Cu")
		(net "P5E_PEX1_STN5_TX_C_DP<92>")
	)
	(segment
		(start 130.74015 -364.038388)
		(end 131.129024 -363.732064)
		(width 0.1651)
		(layer "In13.Cu")
		(net "P5E_PEX1_STN5_TX_C_DP<92>")
	)
	(segment
		(start 125.058678 -378.79909)
		(end 125.584966 -378.272802)
		(width 0.1651)
		(layer "In13.Cu")
		(net "P5E_PEX1_STN5_TX_C_DP<92>")
	)
	(segment
		(start 129.69748 -364.74654)
		(end 129.822194 -364.761526)
		(width 0.1651)
		(layer "In13.Cu")
		(net "P5E_PEX1_STN5_TX_C_DP<92>")
	)
	(segment
		(start 130.615182 -364.023402)
		(end 130.74015 -364.038388)
		(width 0.1651)
		(layer "In13.Cu")
		(net "P5E_PEX1_STN5_TX_C_DP<92>")
	)
	(segment
		(start 130.490468 -355.978206)
		(end 130.810508 -355.658166)
		(width 0.13462)
		(layer "F.Cu")
		(net "P5E_PEX1_STN5_TX_DP<89>")
	)
	(segment
		(start 130.810508 -355.658166)
		(end 130.810508 -355.026722)
		(width 0.13462)
		(layer "F.Cu")
		(net "P5E_PEX1_STN5_TX_DP<89>")
	)
	(segment
		(start 130.810508 -355.026722)
		(end 130.515868 -354.732082)
		(width 0.13462)
		(layer "F.Cu")
		(net "P5E_PEX1_STN5_TX_DP<89>")
	)
	(segment
		(start 164.08654 -330.200254)
		(end 147.442936 -335.747106)
		(width 0.1651)
		(layer "In13.Cu")
		(net "P5E_PEX1_STN5_TX_DP<89>")
	)
	(segment
		(start 132.361178 -341.461598)
		(end 132.361178 -352.239326)
		(width 0.1651)
		(layer "In13.Cu")
		(net "P5E_PEX1_STN5_TX_DP<89>")
	)
	(segment
		(start 182.547514 -321.073018)
		(end 181.58841 -321.713606)
		(width 0.1651)
		(layer "In13.Cu")
		(net "P5E_PEX1_STN5_TX_DP<89>")
	)
	(segment
		(start 183.3499 -313.265312)
		(end 183.2356 -313.379612)
		(width 0.1143)
		(layer "In13.Cu")
		(net "P5E_PEX1_STN5_TX_DP<89>")
	)
	(segment
		(start 182.73395 -320.041016)
		(end 182.73395 -320.063114)
		(width 0.1143)
		(layer "In13.Cu")
		(net "P5E_PEX1_STN5_TX_DP<89>")
	)
	(segment
		(start 182.73395 -320.063114)
		(end 182.73395 -320.886582)
		(width 0.1651)
		(layer "In13.Cu")
		(net "P5E_PEX1_STN5_TX_DP<89>")
	)
	(segment
		(start 181.58841 -321.713606)
		(end 172.428662 -326.610726)
		(width 0.1651)
		(layer "In13.Cu")
		(net "P5E_PEX1_STN5_TX_DP<89>")
	)
	(segment
		(start 182.77967 -319.995296)
		(end 182.73395 -320.041016)
		(width 0.1143)
		(layer "In13.Cu")
		(net "P5E_PEX1_STN5_TX_DP<89>")
	)
	(segment
		(start 130.806698 -354.441252)
		(end 130.515868 -354.732082)
		(width 0.1651)
		(layer "In13.Cu")
		(net "P5E_PEX1_STN5_TX_DP<89>")
	)
	(segment
		(start 135.100314 -338.722462)
		(end 132.361178 -341.461598)
		(width 0.1651)
		(layer "In13.Cu")
		(net "P5E_PEX1_STN5_TX_DP<89>")
	)
	(segment
		(start 142.283434 -335.747106)
		(end 135.100314 -338.722462)
		(width 0.1651)
		(layer "In13.Cu")
		(net "P5E_PEX1_STN5_TX_DP<89>")
	)
	(segment
		(start 172.428662 -326.610726)
		(end 164.08654 -330.200254)
		(width 0.1651)
		(layer "In13.Cu")
		(net "P5E_PEX1_STN5_TX_DP<89>")
	)
	(segment
		(start 183.2356 -313.379612)
		(end 182.994808 -313.379612)
		(width 0.1143)
		(layer "In13.Cu")
		(net "P5E_PEX1_STN5_TX_DP<89>")
	)
	(segment
		(start 147.442936 -335.747106)
		(end 142.283434 -335.747106)
		(width 0.1651)
		(layer "In13.Cu")
		(net "P5E_PEX1_STN5_TX_DP<89>")
	)
	(segment
		(start 183.3499 -312.999882)
		(end 183.3499 -313.265312)
		(width 0.1143)
		(layer "In13.Cu")
		(net "P5E_PEX1_STN5_TX_DP<89>")
	)
	(segment
		(start 182.73395 -320.886582)
		(end 182.547514 -321.073018)
		(width 0.1651)
		(layer "In13.Cu")
		(net "P5E_PEX1_STN5_TX_DP<89>")
	)
	(segment
		(start 130.806698 -353.793806)
		(end 130.806698 -354.441252)
		(width 0.1651)
		(layer "In13.Cu")
		(net "P5E_PEX1_STN5_TX_DP<89>")
	)
	(segment
		(start 132.361178 -352.239326)
		(end 130.806698 -353.793806)
		(width 0.1651)
		(layer "In13.Cu")
		(net "P5E_PEX1_STN5_TX_DP<89>")
	)
	(segment
		(start 182.77967 -313.59475)
		(end 182.77967 -319.995296)
		(width 0.1143)
		(layer "In13.Cu")
		(net "P5E_PEX1_STN5_TX_DP<89>")
	)
	(segment
		(start 182.994808 -313.379612)
		(end 182.77967 -313.59475)
		(width 0.1143)
		(layer "In13.Cu")
		(net "P5E_PEX1_STN5_TX_DP<89>")
	)
	(segment
		(start 312.81497 -150.11908)
		(end 312.48604 -149.79015)
		(width 0.13462)
		(layer "F.Cu")
		(net "P5E_PEX2_STN0_TX_DP<12>")
	)
	(segment
		(start 313.732164 -149.81555)
		(end 313.428634 -150.11908)
		(width 0.13462)
		(layer "F.Cu")
		(net "P5E_PEX2_STN0_TX_DP<12>")
	)
	(segment
		(start 313.428634 -150.11908)
		(end 312.81497 -150.11908)
		(width 0.13462)
		(layer "F.Cu")
		(net "P5E_PEX2_STN0_TX_DP<12>")
	)
	(segment
		(start 309.899812 -280.015188)
		(end 309.899812 -279.749504)
		(width 0.1143)
		(layer "In9.Cu")
		(net "P5E_PEX2_STN0_TX_DP<12>")
	)
	(segment
		(start 309.565802 -271.526)
		(end 309.565802 -271.554448)
		(width 0.1143)
		(layer "In9.Cu")
		(net "P5E_PEX2_STN0_TX_DP<12>")
	)
	(segment
		(start 309.565802 -270.37284)
		(end 309.565802 -271.526)
		(width 0.1651)
		(layer "In9.Cu")
		(net "P5E_PEX2_STN0_TX_DP<12>")
	)
	(segment
		(start 311.041542 -177.137568)
		(end 307.108098 -222.097346)
		(width 0.1651)
		(layer "In9.Cu")
		(net "P5E_PEX2_STN0_TX_DP<12>")
	)
	(segment
		(start 310.49341 -268.133068)
		(end 309.565802 -270.37284)
		(width 0.1651)
		(layer "In9.Cu")
		(net "P5E_PEX2_STN0_TX_DP<12>")
	)
	(segment
		(start 309.565802 -271.554448)
		(end 309.520082 -271.600168)
		(width 0.1143)
		(layer "In9.Cu")
		(net "P5E_PEX2_STN0_TX_DP<12>")
	)
	(segment
		(start 316.472062 -150.10638)
		(end 317.816484 -150.663402)
		(width 0.1651)
		(layer "In9.Cu")
		(net "P5E_PEX2_STN0_TX_DP<12>")
	)
	(segment
		(start 314.022994 -150.10638)
		(end 316.472062 -150.10638)
		(width 0.1651)
		(layer "In9.Cu")
		(net "P5E_PEX2_STN0_TX_DP<12>")
	)
	(segment
		(start 309.520082 -280.025856)
		(end 309.623714 -280.129488)
		(width 0.1143)
		(layer "In9.Cu")
		(net "P5E_PEX2_STN0_TX_DP<12>")
	)
	(segment
		(start 309.520082 -271.600168)
		(end 309.520082 -280.025856)
		(width 0.1143)
		(layer "In9.Cu")
		(net "P5E_PEX2_STN0_TX_DP<12>")
	)
	(segment
		(start 313.732164 -149.81555)
		(end 314.022994 -150.10638)
		(width 0.1651)
		(layer "In9.Cu")
		(net "P5E_PEX2_STN0_TX_DP<12>")
	)
	(segment
		(start 320.23304 -153.9113)
		(end 320.758566 -155.180792)
		(width 0.1651)
		(layer "In9.Cu")
		(net "P5E_PEX2_STN0_TX_DP<12>")
	)
	(segment
		(start 307.108098 -222.097346)
		(end 310.49341 -260.81736)
		(width 0.1651)
		(layer "In9.Cu")
		(net "P5E_PEX2_STN0_TX_DP<12>")
	)
	(segment
		(start 310.49341 -260.81736)
		(end 310.49341 -268.133068)
		(width 0.1651)
		(layer "In9.Cu")
		(net "P5E_PEX2_STN0_TX_DP<12>")
	)
	(segment
		(start 317.816484 -150.663402)
		(end 318.55791 -151.404828)
		(width 0.1651)
		(layer "In9.Cu")
		(net "P5E_PEX2_STN0_TX_DP<12>")
	)
	(segment
		(start 309.785512 -280.129488)
		(end 309.899812 -280.015188)
		(width 0.1143)
		(layer "In9.Cu")
		(net "P5E_PEX2_STN0_TX_DP<12>")
	)
	(segment
		(start 320.758566 -157.417516)
		(end 312.48604 -171.747942)
		(width 0.1651)
		(layer "In9.Cu")
		(net "P5E_PEX2_STN0_TX_DP<12>")
	)
	(segment
		(start 309.623714 -280.129488)
		(end 309.785512 -280.129488)
		(width 0.1143)
		(layer "In9.Cu")
		(net "P5E_PEX2_STN0_TX_DP<12>")
	)
	(segment
		(start 318.55791 -151.404828)
		(end 320.23304 -153.9113)
		(width 0.1651)
		(layer "In9.Cu")
		(net "P5E_PEX2_STN0_TX_DP<12>")
	)
	(segment
		(start 312.48604 -171.747942)
		(end 311.041542 -177.137568)
		(width 0.1651)
		(layer "In9.Cu")
		(net "P5E_PEX2_STN0_TX_DP<12>")
	)
	(segment
		(start 320.758566 -155.180792)
		(end 320.758566 -157.417516)
		(width 0.1651)
		(layer "In9.Cu")
		(net "P5E_PEX2_STN0_TX_DP<12>")
	)
	(segment
		(start 277.518622 -342.734138)
		(end 277.223982 -342.439498)
		(width 0.13462)
		(layer "F.Cu")
		(net "P5E_PEX2_STN7_TX_DP<116>")
	)
	(segment
		(start 277.518622 -343.365582)
		(end 277.518622 -342.734138)
		(width 0.13462)
		(layer "F.Cu")
		(net "P5E_PEX2_STN7_TX_DP<116>")
	)
	(segment
		(start 277.198582 -343.685622)
		(end 277.518622 -343.365582)
		(width 0.13462)
		(layer "F.Cu")
		(net "P5E_PEX2_STN7_TX_DP<116>")
	)
	(segment
		(start 257.8354 -308.356)
		(end 257.866642 -308.325266)
		(width 0.1651)
		(layer "In7.Cu")
		(net "P5E_PEX2_STN7_TX_DP<116>")
	)
	(segment
		(start 267.93952 -304.829718)
		(end 274.144232 -304.829718)
		(width 0.1143)
		(layer "In7.Cu")
		(net "P5E_PEX2_STN7_TX_DP<116>")
	)
	(segment
		(start 259.504942 -306.715922)
		(end 260.070346 -306.153566)
		(width 0.1651)
		(layer "In7.Cu")
		(net "P5E_PEX2_STN7_TX_DP<116>")
	)
	(segment
		(start 253.767844 -325.78675)
		(end 252.57506 -322.906898)
		(width 0.1651)
		(layer "In7.Cu")
		(net "P5E_PEX2_STN7_TX_DP<116>")
	)
	(segment
		(start 274.144232 -304.829718)
		(end 274.370038 -305.055524)
		(width 0.1143)
		(layer "In7.Cu")
		(net "P5E_PEX2_STN7_TX_DP<116>")
	)
	(segment
		(start 259.505196 -306.715922)
		(end 259.504942 -306.715922)
		(width 0.1651)
		(layer "In7.Cu")
		(net "P5E_PEX2_STN7_TX_DP<116>")
	)
	(segment
		(start 257.866642 -308.325266)
		(end 257.866896 -308.325266)
		(width 0.1651)
		(layer "In7.Cu")
		(net "P5E_PEX2_STN7_TX_DP<116>")
	)
	(segment
		(start 266.95527 -304.783998)
		(end 267.865352 -304.783998)
		(width 0.1651)
		(layer "In7.Cu")
		(net "P5E_PEX2_STN7_TX_DP<116>")
	)
	(segment
		(start 257.866896 -308.325266)
		(end 259.505196 -306.715922)
		(width 0.1651)
		(layer "In7.Cu")
		(net "P5E_PEX2_STN7_TX_DP<116>")
	)
	(segment
		(start 274.370038 -305.055524)
		(end 274.370038 -305.285648)
		(width 0.1143)
		(layer "In7.Cu")
		(net "P5E_PEX2_STN7_TX_DP<116>")
	)
	(segment
		(start 274.484338 -305.399948)
		(end 274.749768 -305.399948)
		(width 0.1143)
		(layer "In7.Cu")
		(net "P5E_PEX2_STN7_TX_DP<116>")
	)
	(segment
		(start 267.865352 -304.783998)
		(end 267.8938 -304.783998)
		(width 0.1143)
		(layer "In7.Cu")
		(net "P5E_PEX2_STN7_TX_DP<116>")
	)
	(segment
		(start 277.514812 -342.148668)
		(end 277.514812 -341.62492)
		(width 0.1651)
		(layer "In7.Cu")
		(net "P5E_PEX2_STN7_TX_DP<116>")
	)
	(segment
		(start 260.070346 -306.153566)
		(end 266.95527 -304.783998)
		(width 0.1651)
		(layer "In7.Cu")
		(net "P5E_PEX2_STN7_TX_DP<116>")
	)
	(segment
		(start 252.57506 -322.906898)
		(end 252.57506 -319.00622)
		(width 0.1651)
		(layer "In7.Cu")
		(net "P5E_PEX2_STN7_TX_DP<116>")
	)
	(segment
		(start 277.514812 -341.62492)
		(end 277.438358 -341.483696)
		(width 0.1651)
		(layer "In7.Cu")
		(net "P5E_PEX2_STN7_TX_DP<116>")
	)
	(segment
		(start 275.489162 -339.506814)
		(end 256.613914 -328.983594)
		(width 0.1651)
		(layer "In7.Cu")
		(net "P5E_PEX2_STN7_TX_DP<116>")
	)
	(segment
		(start 253.808738 -315.999114)
		(end 255.815084 -312.190892)
		(width 0.1651)
		(layer "In7.Cu")
		(net "P5E_PEX2_STN7_TX_DP<116>")
	)
	(segment
		(start 274.370038 -305.285648)
		(end 274.484338 -305.399948)
		(width 0.1143)
		(layer "In7.Cu")
		(net "P5E_PEX2_STN7_TX_DP<116>")
	)
	(segment
		(start 252.57506 -319.00622)
		(end 253.808738 -315.999114)
		(width 0.1651)
		(layer "In7.Cu")
		(net "P5E_PEX2_STN7_TX_DP<116>")
	)
	(segment
		(start 256.613914 -328.983594)
		(end 253.767844 -325.78675)
		(width 0.1651)
		(layer "In7.Cu")
		(net "P5E_PEX2_STN7_TX_DP<116>")
	)
	(segment
		(start 267.8938 -304.783998)
		(end 267.93952 -304.829718)
		(width 0.1143)
		(layer "In7.Cu")
		(net "P5E_PEX2_STN7_TX_DP<116>")
	)
	(segment
		(start 277.438358 -341.483696)
		(end 275.489162 -339.506814)
		(width 0.1651)
		(layer "In7.Cu")
		(net "P5E_PEX2_STN7_TX_DP<116>")
	)
	(segment
		(start 255.815084 -312.190892)
		(end 257.8354 -308.356)
		(width 0.1651)
		(layer "In7.Cu")
		(net "P5E_PEX2_STN7_TX_DP<116>")
	)
	(segment
		(start 277.223982 -342.439498)
		(end 277.514812 -342.148668)
		(width 0.1651)
		(layer "In7.Cu")
		(net "P5E_PEX2_STN7_TX_DP<116>")
	)
	(segment
		(start 432.47437 -120.502172)
		(end 432.174142 -120.8024)
		(width 0.13462)
		(layer "F.Cu")
		(net "P5E_PEX3_STN0_TX_DN<1>")
	)
	(segment
		(start 431.553874 -120.8024)
		(end 431.228246 -120.476772)
		(width 0.13462)
		(layer "F.Cu")
		(net "P5E_PEX3_STN0_TX_DN<1>")
	)
	(segment
		(start 432.174142 -120.8024)
		(end 431.553874 -120.8024)
		(width 0.13462)
		(layer "F.Cu")
		(net "P5E_PEX3_STN0_TX_DN<1>")
	)
	(segment
		(start 432.1937 -287.015682)
		(end 432.165252 -287.015682)
		(width 0.1143)
		(layer "In9.Cu")
		(net "P5E_PEX3_STN0_TX_DN<1>")
	)
	(segment
		(start 433.433728 -120.793002)
		(end 434.79593 -122.155204)
		(width 0.1651)
		(layer "In9.Cu")
		(net "P5E_PEX3_STN0_TX_DN<1>")
	)
	(segment
		(start 432.119532 -286.969962)
		(end 423.823892 -286.969962)
		(width 0.1143)
		(layer "In9.Cu")
		(net "P5E_PEX3_STN0_TX_DN<1>")
	)
	(segment
		(start 437.15559 -285.682436)
		(end 433.937156 -287.015682)
		(width 0.1651)
		(layer "In9.Cu")
		(net "P5E_PEX3_STN0_TX_DN<1>")
	)
	(segment
		(start 432.7652 -120.793002)
		(end 433.433728 -120.793002)
		(width 0.1651)
		(layer "In9.Cu")
		(net "P5E_PEX3_STN0_TX_DN<1>")
	)
	(segment
		(start 434.79593 -122.155204)
		(end 438.585864 -131.30403)
		(width 0.1651)
		(layer "In9.Cu")
		(net "P5E_PEX3_STN0_TX_DN<1>")
	)
	(segment
		(start 438.600342 -175.832008)
		(end 437.7055 -179.166774)
		(width 0.1651)
		(layer "In9.Cu")
		(net "P5E_PEX3_STN0_TX_DN<1>")
	)
	(segment
		(start 447.223388 -160.888934)
		(end 438.600342 -175.832008)
		(width 0.1651)
		(layer "In9.Cu")
		(net "P5E_PEX3_STN0_TX_DN<1>")
	)
	(segment
		(start 438.585864 -131.30403)
		(end 438.856374 -131.57454)
		(width 0.1651)
		(layer "In9.Cu")
		(net "P5E_PEX3_STN0_TX_DN<1>")
	)
	(segment
		(start 423.834306 -287.349946)
		(end 424.09999 -287.349946)
		(width 0.1143)
		(layer "In9.Cu")
		(net "P5E_PEX3_STN0_TX_DN<1>")
	)
	(segment
		(start 447.57975 -267.461492)
		(end 448.029584 -272.597372)
		(width 0.1651)
		(layer "In9.Cu")
		(net "P5E_PEX3_STN0_TX_DN<1>")
	)
	(segment
		(start 448.029584 -272.597372)
		(end 446.466214 -276.371812)
		(width 0.1651)
		(layer "In9.Cu")
		(net "P5E_PEX3_STN0_TX_DN<1>")
	)
	(segment
		(start 432.47437 -120.502172)
		(end 432.7652 -120.793002)
		(width 0.1651)
		(layer "In9.Cu")
		(net "P5E_PEX3_STN0_TX_DN<1>")
	)
	(segment
		(start 447.503804 -159.839152)
		(end 447.223388 -160.888934)
		(width 0.1651)
		(layer "In9.Cu")
		(net "P5E_PEX3_STN0_TX_DN<1>")
	)
	(segment
		(start 447.503804 -152.451308)
		(end 447.503804 -159.839152)
		(width 0.1651)
		(layer "In9.Cu")
		(net "P5E_PEX3_STN0_TX_DN<1>")
	)
	(segment
		(start 438.856374 -131.57454)
		(end 447.503804 -152.451308)
		(width 0.1651)
		(layer "In9.Cu")
		(net "P5E_PEX3_STN0_TX_DN<1>")
	)
	(segment
		(start 446.466214 -276.371812)
		(end 437.15559 -285.682436)
		(width 0.1651)
		(layer "In9.Cu")
		(net "P5E_PEX3_STN0_TX_DN<1>")
	)
	(segment
		(start 433.992274 -221.611444)
		(end 436.437532 -249.630438)
		(width 0.1651)
		(layer "In9.Cu")
		(net "P5E_PEX3_STN0_TX_DN<1>")
	)
	(segment
		(start 436.437532 -249.630438)
		(end 446.319148 -264.418572)
		(width 0.1651)
		(layer "In9.Cu")
		(net "P5E_PEX3_STN0_TX_DN<1>")
	)
	(segment
		(start 446.319148 -264.418572)
		(end 447.57975 -267.461492)
		(width 0.1651)
		(layer "In9.Cu")
		(net "P5E_PEX3_STN0_TX_DN<1>")
	)
	(segment
		(start 437.7055 -179.166774)
		(end 433.992274 -221.611444)
		(width 0.1651)
		(layer "In9.Cu")
		(net "P5E_PEX3_STN0_TX_DN<1>")
	)
	(segment
		(start 423.720006 -287.073848)
		(end 423.720006 -287.235646)
		(width 0.1143)
		(layer "In9.Cu")
		(net "P5E_PEX3_STN0_TX_DN<1>")
	)
	(segment
		(start 423.720006 -287.235646)
		(end 423.834306 -287.349946)
		(width 0.1143)
		(layer "In9.Cu")
		(net "P5E_PEX3_STN0_TX_DN<1>")
	)
	(segment
		(start 423.823892 -286.969962)
		(end 423.720006 -287.073848)
		(width 0.1143)
		(layer "In9.Cu")
		(net "P5E_PEX3_STN0_TX_DN<1>")
	)
	(segment
		(start 433.937156 -287.015682)
		(end 432.1937 -287.015682)
		(width 0.1651)
		(layer "In9.Cu")
		(net "P5E_PEX3_STN0_TX_DN<1>")
	)
	(segment
		(start 432.165252 -287.015682)
		(end 432.119532 -286.969962)
		(width 0.1143)
		(layer "In9.Cu")
		(net "P5E_PEX3_STN0_TX_DN<1>")
	)
	(segment
		(start 134.193788 -342.734138)
		(end 134.488428 -342.439498)
		(width 0.13462)
		(layer "F.Cu")
		(net "P5E_PEX1_STN5_TX_DN<82>")
	)
	(segment
		(start 134.193788 -343.365582)
		(end 134.193788 -342.734138)
		(width 0.13462)
		(layer "F.Cu")
		(net "P5E_PEX1_STN5_TX_DN<82>")
	)
	(segment
		(start 134.513828 -343.685622)
		(end 134.193788 -343.365582)
		(width 0.13462)
		(layer "F.Cu")
		(net "P5E_PEX1_STN5_TX_DN<82>")
	)
	(segment
		(start 173.338744 -327.400412)
		(end 175.528224 -325.210932)
		(width 0.1651)
		(layer "In7.Cu")
		(net "P5E_PEX1_STN5_TX_DN<82>")
	)
	(segment
		(start 176.434496 -311.670192)
		(end 176.585626 -311.670192)
		(width 0.1143)
		(layer "In7.Cu")
		(net "P5E_PEX1_STN5_TX_DN<82>")
	)
	(segment
		(start 176.585626 -311.670192)
		(end 176.699926 -311.784492)
		(width 0.1143)
		(layer "In7.Cu")
		(net "P5E_PEX1_STN5_TX_DN<82>")
	)
	(segment
		(start 176.365916 -323.188584)
		(end 176.365916 -320.016886)
		(width 0.1651)
		(layer "In7.Cu")
		(net "P5E_PEX1_STN5_TX_DN<82>")
	)
	(segment
		(start 176.320196 -319.942718)
		(end 176.320196 -311.784492)
		(width 0.1143)
		(layer "In7.Cu")
		(net "P5E_PEX1_STN5_TX_DN<82>")
	)
	(segment
		(start 134.488428 -342.439498)
		(end 134.197598 -342.148668)
		(width 0.1651)
		(layer "In7.Cu")
		(net "P5E_PEX1_STN5_TX_DN<82>")
	)
	(segment
		(start 134.197598 -341.239602)
		(end 134.900416 -340.536784)
		(width 0.1651)
		(layer "In7.Cu")
		(net "P5E_PEX1_STN5_TX_DN<82>")
	)
	(segment
		(start 176.365916 -319.988438)
		(end 176.320196 -319.942718)
		(width 0.1143)
		(layer "In7.Cu")
		(net "P5E_PEX1_STN5_TX_DN<82>")
	)
	(segment
		(start 134.197598 -342.148668)
		(end 134.197598 -341.239602)
		(width 0.1651)
		(layer "In7.Cu")
		(net "P5E_PEX1_STN5_TX_DN<82>")
	)
	(segment
		(start 169.66057 -329.605132)
		(end 173.338744 -327.400412)
		(width 0.1651)
		(layer "In7.Cu")
		(net "P5E_PEX1_STN5_TX_DN<82>")
	)
	(segment
		(start 176.699926 -311.784492)
		(end 176.699926 -312.049922)
		(width 0.1143)
		(layer "In7.Cu")
		(net "P5E_PEX1_STN5_TX_DN<82>")
	)
	(segment
		(start 176.365916 -320.016886)
		(end 176.365916 -319.988438)
		(width 0.1143)
		(layer "In7.Cu")
		(net "P5E_PEX1_STN5_TX_DN<82>")
	)
	(segment
		(start 136.209024 -339.752432)
		(end 169.66057 -329.605132)
		(width 0.1651)
		(layer "In7.Cu")
		(net "P5E_PEX1_STN5_TX_DN<82>")
	)
	(segment
		(start 176.320196 -311.784492)
		(end 176.434496 -311.670192)
		(width 0.1143)
		(layer "In7.Cu")
		(net "P5E_PEX1_STN5_TX_DN<82>")
	)
	(segment
		(start 134.900416 -340.536784)
		(end 136.209024 -339.752432)
		(width 0.1651)
		(layer "In7.Cu")
		(net "P5E_PEX1_STN5_TX_DN<82>")
	)
	(segment
		(start 175.528224 -325.210932)
		(end 176.365916 -323.188584)
		(width 0.1651)
		(layer "In7.Cu")
		(net "P5E_PEX1_STN5_TX_DN<82>")
	)
	(segment
		(start 270.265652 -125.1966)
		(end 270.890492 -125.1966)
		(width 0.13462)
		(layer "F.Cu")
		(net "P5E_PEX2_STN1_TX_DP<27>")
	)
	(segment
		(start 269.96771 -125.494542)
		(end 270.265652 -125.1966)
		(width 0.13462)
		(layer "F.Cu")
		(net "P5E_PEX2_STN1_TX_DP<27>")
	)
	(segment
		(start 270.890492 -125.1966)
		(end 271.213834 -125.519942)
		(width 0.13462)
		(layer "F.Cu")
		(net "P5E_PEX2_STN1_TX_DP<27>")
	)
	(segment
		(start 265.205972 -141.06525)
		(end 265.39571 -141.523212)
		(width 0.1651)
		(layer "In9.Cu")
		(net "P5E_PEX2_STN1_TX_DP<27>")
	)
	(segment
		(start 264.90041 -140.55979)
		(end 265.089894 -141.017244)
		(width 0.1651)
		(layer "In9.Cu")
		(net "P5E_PEX2_STN1_TX_DP<27>")
	)
	(segment
		(start 267.264388 -127.667512)
		(end 267.140944 -127.69215)
		(width 0.1651)
		(layer "In9.Cu")
		(net "P5E_PEX2_STN1_TX_DP<27>")
	)
	(segment
		(start 269.67688 -125.203712)
		(end 269.10919 -125.203712)
		(width 0.1651)
		(layer "In9.Cu")
		(net "P5E_PEX2_STN1_TX_DP<27>")
	)
	(segment
		(start 265.613388 -130.184144)
		(end 265.338052 -130.596132)
		(width 0.1651)
		(layer "In9.Cu")
		(net "P5E_PEX2_STN1_TX_DP<27>")
	)
	(segment
		(start 264.156698 -138.764264)
		(end 264.306304 -138.82624)
		(width 0.1651)
		(layer "In9.Cu")
		(net "P5E_PEX2_STN1_TX_DP<27>")
	)
	(segment
		(start 269.10919 -125.203712)
		(end 268.188694 -126.124208)
		(width 0.1651)
		(layer "In9.Cu")
		(net "P5E_PEX2_STN1_TX_DP<27>")
	)
	(segment
		(start 302.185578 -280.129488)
		(end 302.299878 -280.015188)
		(width 0.1143)
		(layer "In9.Cu")
		(net "P5E_PEX2_STN1_TX_DP<27>")
	)
	(segment
		(start 264.962386 -140.410438)
		(end 264.90041 -140.55979)
		(width 0.1651)
		(layer "In9.Cu")
		(net "P5E_PEX2_STN1_TX_DP<27>")
	)
	(segment
		(start 265.179556 -130.627628)
		(end 264.904474 -131.039362)
		(width 0.1651)
		(layer "In9.Cu")
		(net "P5E_PEX2_STN1_TX_DP<27>")
	)
	(segment
		(start 265.089894 -141.017244)
		(end 265.205972 -141.06525)
		(width 0.1651)
		(layer "In9.Cu")
		(net "P5E_PEX2_STN1_TX_DP<27>")
	)
	(segment
		(start 267.490702 -161.75228)
		(end 301.965868 -263.596628)
		(width 0.1651)
		(layer "In9.Cu")
		(net "P5E_PEX2_STN1_TX_DP<27>")
	)
	(segment
		(start 265.347704 -141.63929)
		(end 265.90752 -142.991078)
		(width 0.1651)
		(layer "In9.Cu")
		(net "P5E_PEX2_STN1_TX_DP<27>")
	)
	(segment
		(start 266.873228 -128.092962)
		(end 266.897866 -128.216152)
		(width 0.1651)
		(layer "In9.Cu")
		(net "P5E_PEX2_STN1_TX_DP<27>")
	)
	(segment
		(start 265.581892 -130.025648)
		(end 265.613388 -130.184144)
		(width 0.1651)
		(layer "In9.Cu")
		(net "P5E_PEX2_STN1_TX_DP<27>")
	)
	(segment
		(start 263.332214 -136.774428)
		(end 263.689846 -137.637774)
		(width 0.1651)
		(layer "In9.Cu")
		(net "P5E_PEX2_STN1_TX_DP<27>")
	)
	(segment
		(start 264.660634 -131.609846)
		(end 264.502138 -131.641342)
		(width 0.1651)
		(layer "In9.Cu")
		(net "P5E_PEX2_STN1_TX_DP<27>")
	)
	(segment
		(start 269.96771 -125.494542)
		(end 269.67688 -125.203712)
		(width 0.1651)
		(layer "In9.Cu")
		(net "P5E_PEX2_STN1_TX_DP<27>")
	)
	(segment
		(start 266.613386 -157.341062)
		(end 267.490702 -161.75228)
		(width 0.1651)
		(layer "In9.Cu")
		(net "P5E_PEX2_STN1_TX_DP<27>")
	)
	(segment
		(start 265.338052 -130.596132)
		(end 265.179556 -130.627628)
		(width 0.1651)
		(layer "In9.Cu")
		(net "P5E_PEX2_STN1_TX_DP<27>")
	)
	(segment
		(start 265.39571 -141.523212)
		(end 265.347704 -141.63929)
		(width 0.1651)
		(layer "In9.Cu")
		(net "P5E_PEX2_STN1_TX_DP<27>")
	)
	(segment
		(start 264.772902 -139.95273)
		(end 264.962386 -140.410438)
		(width 0.1651)
		(layer "In9.Cu")
		(net "P5E_PEX2_STN1_TX_DP<27>")
	)
	(segment
		(start 301.920148 -271.600168)
		(end 301.920148 -280.025856)
		(width 0.1143)
		(layer "In9.Cu")
		(net "P5E_PEX2_STN1_TX_DP<27>")
	)
	(segment
		(start 267.480034 -127.184912)
		(end 267.504418 -127.308356)
		(width 0.1651)
		(layer "In9.Cu")
		(net "P5E_PEX2_STN1_TX_DP<27>")
	)
	(segment
		(start 267.140944 -127.69215)
		(end 266.873228 -128.092962)
		(width 0.1651)
		(layer "In9.Cu")
		(net "P5E_PEX2_STN1_TX_DP<27>")
	)
	(segment
		(start 264.495788 -139.283948)
		(end 264.433812 -139.4333)
		(width 0.1651)
		(layer "In9.Cu")
		(net "P5E_PEX2_STN1_TX_DP<27>")
	)
	(segment
		(start 301.965868 -263.596628)
		(end 301.965868 -271.526)
		(width 0.1651)
		(layer "In9.Cu")
		(net "P5E_PEX2_STN1_TX_DP<27>")
	)
	(segment
		(start 264.306304 -138.82624)
		(end 264.495788 -139.283948)
		(width 0.1651)
		(layer "In9.Cu")
		(net "P5E_PEX2_STN1_TX_DP<27>")
	)
	(segment
		(start 302.299878 -280.015188)
		(end 302.299878 -279.749504)
		(width 0.1143)
		(layer "In9.Cu")
		(net "P5E_PEX2_STN1_TX_DP<27>")
	)
	(segment
		(start 266.290806 -129.170176)
		(end 266.01547 -129.582164)
		(width 0.1651)
		(layer "In9.Cu")
		(net "P5E_PEX2_STN1_TX_DP<27>")
	)
	(segment
		(start 264.131298 -132.196332)
		(end 263.332214 -134.125716)
		(width 0.1651)
		(layer "In9.Cu")
		(net "P5E_PEX2_STN1_TX_DP<27>")
	)
	(segment
		(start 302.02378 -280.129488)
		(end 302.185578 -280.129488)
		(width 0.1143)
		(layer "In9.Cu")
		(net "P5E_PEX2_STN1_TX_DP<27>")
	)
	(segment
		(start 263.839452 -137.69975)
		(end 264.028936 -138.157458)
		(width 0.1651)
		(layer "In9.Cu")
		(net "P5E_PEX2_STN1_TX_DP<27>")
	)
	(segment
		(start 268.188694 -126.124208)
		(end 267.480034 -127.184912)
		(width 0.1651)
		(layer "In9.Cu")
		(net "P5E_PEX2_STN1_TX_DP<27>")
	)
	(segment
		(start 264.502138 -131.641342)
		(end 264.131298 -132.196332)
		(width 0.1651)
		(layer "In9.Cu")
		(net "P5E_PEX2_STN1_TX_DP<27>")
	)
	(segment
		(start 266.25931 -129.01168)
		(end 266.290806 -129.170176)
		(width 0.1651)
		(layer "In9.Cu")
		(net "P5E_PEX2_STN1_TX_DP<27>")
	)
	(segment
		(start 266.657582 -128.575562)
		(end 266.534392 -128.599946)
		(width 0.1651)
		(layer "In9.Cu")
		(net "P5E_PEX2_STN1_TX_DP<27>")
	)
	(segment
		(start 266.01547 -129.582164)
		(end 265.856974 -129.613914)
		(width 0.1651)
		(layer "In9.Cu")
		(net "P5E_PEX2_STN1_TX_DP<27>")
	)
	(segment
		(start 301.965868 -271.526)
		(end 301.965868 -271.554448)
		(width 0.1143)
		(layer "In9.Cu")
		(net "P5E_PEX2_STN1_TX_DP<27>")
	)
	(segment
		(start 263.689846 -137.637774)
		(end 263.839452 -137.69975)
		(width 0.1651)
		(layer "In9.Cu")
		(net "P5E_PEX2_STN1_TX_DP<27>")
	)
	(segment
		(start 264.028936 -138.157458)
		(end 263.967214 -138.30681)
		(width 0.1651)
		(layer "In9.Cu")
		(net "P5E_PEX2_STN1_TX_DP<27>")
	)
	(segment
		(start 263.967214 -138.30681)
		(end 264.156698 -138.764264)
		(width 0.1651)
		(layer "In9.Cu")
		(net "P5E_PEX2_STN1_TX_DP<27>")
	)
	(segment
		(start 266.534392 -128.599946)
		(end 266.25931 -129.01168)
		(width 0.1651)
		(layer "In9.Cu")
		(net "P5E_PEX2_STN1_TX_DP<27>")
	)
	(segment
		(start 264.904474 -131.039362)
		(end 264.93597 -131.197858)
		(width 0.1651)
		(layer "In9.Cu")
		(net "P5E_PEX2_STN1_TX_DP<27>")
	)
	(segment
		(start 265.90752 -142.991078)
		(end 266.262104 -150.200614)
		(width 0.1651)
		(layer "In9.Cu")
		(net "P5E_PEX2_STN1_TX_DP<27>")
	)
	(segment
		(start 264.93597 -131.197858)
		(end 264.660634 -131.609846)
		(width 0.1651)
		(layer "In9.Cu")
		(net "P5E_PEX2_STN1_TX_DP<27>")
	)
	(segment
		(start 266.897866 -128.216152)
		(end 266.657582 -128.575562)
		(width 0.1651)
		(layer "In9.Cu")
		(net "P5E_PEX2_STN1_TX_DP<27>")
	)
	(segment
		(start 267.504418 -127.308356)
		(end 267.264388 -127.667512)
		(width 0.1651)
		(layer "In9.Cu")
		(net "P5E_PEX2_STN1_TX_DP<27>")
	)
	(segment
		(start 263.332214 -134.125716)
		(end 263.332214 -136.774428)
		(width 0.1651)
		(layer "In9.Cu")
		(net "P5E_PEX2_STN1_TX_DP<27>")
	)
	(segment
		(start 264.623296 -139.890754)
		(end 264.772902 -139.95273)
		(width 0.1651)
		(layer "In9.Cu")
		(net "P5E_PEX2_STN1_TX_DP<27>")
	)
	(segment
		(start 266.262104 -150.200614)
		(end 266.613386 -157.341062)
		(width 0.1651)
		(layer "In9.Cu")
		(net "P5E_PEX2_STN1_TX_DP<27>")
	)
	(segment
		(start 265.856974 -129.613914)
		(end 265.581892 -130.025648)
		(width 0.1651)
		(layer "In9.Cu")
		(net "P5E_PEX2_STN1_TX_DP<27>")
	)
	(segment
		(start 264.433812 -139.4333)
		(end 264.623296 -139.890754)
		(width 0.1651)
		(layer "In9.Cu")
		(net "P5E_PEX2_STN1_TX_DP<27>")
	)
	(segment
		(start 301.920148 -280.025856)
		(end 302.02378 -280.129488)
		(width 0.1143)
		(layer "In9.Cu")
		(net "P5E_PEX2_STN1_TX_DP<27>")
	)
	(segment
		(start 301.965868 -271.554448)
		(end 301.920148 -271.600168)
		(width 0.1143)
		(layer "In9.Cu")
		(net "P5E_PEX2_STN1_TX_DP<27>")
	)
	(segment
		(start 268.466062 -349.511874)
		(end 268.466062 -348.88043)
		(width 0.13462)
		(layer "F.Cu")
		(net "P5E_PEX2_STN7_TX_DN<112>")
	)
	(segment
		(start 268.466062 -348.88043)
		(end 268.760702 -348.58579)
		(width 0.13462)
		(layer "F.Cu")
		(net "P5E_PEX2_STN7_TX_DN<112>")
	)
	(segment
		(start 268.786102 -349.831914)
		(end 268.466062 -349.511874)
		(width 0.13462)
		(layer "F.Cu")
		(net "P5E_PEX2_STN7_TX_DN<112>")
	)
	(segment
		(start 252.778006 -308.535832)
		(end 252.934978 -308.177946)
		(width 0.1651)
		(layer "In7.Cu")
		(net "P5E_PEX2_STN7_TX_DN<112>")
	)
	(segment
		(start 251.689362 -310.69534)
		(end 251.789946 -310.656224)
		(width 0.1651)
		(layer "In7.Cu")
		(net "P5E_PEX2_STN7_TX_DN<112>")
	)
	(segment
		(start 252.934978 -308.177946)
		(end 252.868938 -308.008528)
		(width 0.1651)
		(layer "In7.Cu")
		(net "P5E_PEX2_STN7_TX_DN<112>")
	)
	(segment
		(start 267.93952 -301.220124)
		(end 274.065238 -301.220124)
		(width 0.1143)
		(layer "In7.Cu")
		(net "P5E_PEX2_STN7_TX_DN<112>")
	)
	(segment
		(start 274.179538 -301.485554)
		(end 274.065238 -301.599854)
		(width 0.1143)
		(layer "In7.Cu")
		(net "P5E_PEX2_STN7_TX_DN<112>")
	)
	(segment
		(start 250.770644 -312.788808)
		(end 250.870974 -312.749692)
		(width 0.1651)
		(layer "In7.Cu")
		(net "P5E_PEX2_STN7_TX_DN<112>")
	)
	(segment
		(start 259.860542 -338.384642)
		(end 250.794774 -328.381868)
		(width 0.1651)
		(layer "In7.Cu")
		(net "P5E_PEX2_STN7_TX_DN<112>")
	)
	(segment
		(start 267.865352 -301.265844)
		(end 267.8938 -301.265844)
		(width 0.1143)
		(layer "In7.Cu")
		(net "P5E_PEX2_STN7_TX_DN<112>")
	)
	(segment
		(start 250.610878 -313.342528)
		(end 250.571762 -313.242198)
		(width 0.1651)
		(layer "In7.Cu")
		(net "P5E_PEX2_STN7_TX_DN<112>")
	)
	(segment
		(start 252.448568 -309.155592)
		(end 252.409452 -309.055262)
		(width 0.1651)
		(layer "In7.Cu")
		(net "P5E_PEX2_STN7_TX_DN<112>")
	)
	(segment
		(start 249.393202 -315.92901)
		(end 249.392948 -315.92901)
		(width 0.1651)
		(layer "In7.Cu")
		(net "P5E_PEX2_STN7_TX_DN<112>")
	)
	(segment
		(start 253.16815 -307.516022)
		(end 253.36754 -307.062124)
		(width 0.1651)
		(layer "In7.Cu")
		(net "P5E_PEX2_STN7_TX_DN<112>")
	)
	(segment
		(start 250.411742 -313.796426)
		(end 250.610878 -313.342528)
		(width 0.1651)
		(layer "In7.Cu")
		(net "P5E_PEX2_STN7_TX_DN<112>")
	)
	(segment
		(start 251.229876 -311.742074)
		(end 251.33046 -311.702958)
		(width 0.1651)
		(layer "In7.Cu")
		(net "P5E_PEX2_STN7_TX_DN<112>")
	)
	(segment
		(start 250.151646 -314.389262)
		(end 250.11253 -314.288932)
		(width 0.1651)
		(layer "In7.Cu")
		(net "P5E_PEX2_STN7_TX_DN<112>")
	)
	(segment
		(start 251.33046 -311.702958)
		(end 251.529596 -311.24906)
		(width 0.1651)
		(layer "In7.Cu")
		(net "P5E_PEX2_STN7_TX_DN<112>")
	)
	(segment
		(start 267.8938 -301.265844)
		(end 267.93952 -301.220124)
		(width 0.1143)
		(layer "In7.Cu")
		(net "P5E_PEX2_STN7_TX_DN<112>")
	)
	(segment
		(start 253.527814 -306.507388)
		(end 257.132328 -302.73498)
		(width 0.1651)
		(layer "In7.Cu")
		(net "P5E_PEX2_STN7_TX_DN<112>")
	)
	(segment
		(start 249.392948 -315.92901)
		(end 249.493278 -315.889894)
		(width 0.1651)
		(layer "In7.Cu")
		(net "P5E_PEX2_STN7_TX_DN<112>")
	)
	(segment
		(start 250.571762 -313.242198)
		(end 250.57227 -313.242198)
		(width 0.1651)
		(layer "In7.Cu")
		(net "P5E_PEX2_STN7_TX_DN<112>")
	)
	(segment
		(start 249.653552 -315.33592)
		(end 249.852434 -314.88253)
		(width 0.1651)
		(layer "In7.Cu")
		(net "P5E_PEX2_STN7_TX_DN<112>")
	)
	(segment
		(start 274.065238 -301.220124)
		(end 274.179538 -301.334424)
		(width 0.1143)
		(layer "In7.Cu")
		(net "P5E_PEX2_STN7_TX_DN<112>")
	)
	(segment
		(start 252.409452 -309.055262)
		(end 252.608334 -308.601872)
		(width 0.1651)
		(layer "In7.Cu")
		(net "P5E_PEX2_STN7_TX_DN<112>")
	)
	(segment
		(start 251.95022 -310.10225)
		(end 252.149356 -309.649114)
		(width 0.1651)
		(layer "In7.Cu")
		(net "P5E_PEX2_STN7_TX_DN<112>")
	)
	(segment
		(start 249.85218 -314.882276)
		(end 249.95251 -314.84316)
		(width 0.1651)
		(layer "In7.Cu")
		(net "P5E_PEX2_STN7_TX_DN<112>")
	)
	(segment
		(start 268.469872 -348.29496)
		(end 268.469872 -347.556836)
		(width 0.1651)
		(layer "In7.Cu")
		(net "P5E_PEX2_STN7_TX_DN<112>")
	)
	(segment
		(start 249.692414 -315.435996)
		(end 249.653298 -315.335666)
		(width 0.1651)
		(layer "In7.Cu")
		(net "P5E_PEX2_STN7_TX_DN<112>")
	)
	(segment
		(start 251.529596 -311.24906)
		(end 251.49048 -311.14873)
		(width 0.1651)
		(layer "In7.Cu")
		(net "P5E_PEX2_STN7_TX_DN<112>")
	)
	(segment
		(start 252.148848 -309.648606)
		(end 252.249432 -309.60949)
		(width 0.1651)
		(layer "In7.Cu")
		(net "P5E_PEX2_STN7_TX_DN<112>")
	)
	(segment
		(start 250.870974 -312.749692)
		(end 251.07011 -312.295794)
		(width 0.1651)
		(layer "In7.Cu")
		(net "P5E_PEX2_STN7_TX_DN<112>")
	)
	(segment
		(start 274.065238 -301.599854)
		(end 273.799808 -301.599854)
		(width 0.1143)
		(layer "In7.Cu")
		(net "P5E_PEX2_STN7_TX_DN<112>")
	)
	(segment
		(start 248.82094 -323.617336)
		(end 248.82094 -317.233046)
		(width 0.1651)
		(layer "In7.Cu")
		(net "P5E_PEX2_STN7_TX_DN<112>")
	)
	(segment
		(start 250.771152 -312.789316)
		(end 250.770644 -312.788808)
		(width 0.1651)
		(layer "In7.Cu")
		(net "P5E_PEX2_STN7_TX_DN<112>")
	)
	(segment
		(start 249.653298 -315.335666)
		(end 249.653552 -315.33592)
		(width 0.1651)
		(layer "In7.Cu")
		(net "P5E_PEX2_STN7_TX_DN<112>")
	)
	(segment
		(start 253.36754 -307.062124)
		(end 253.328424 -306.961794)
		(width 0.1651)
		(layer "In7.Cu")
		(net "P5E_PEX2_STN7_TX_DN<112>")
	)
	(segment
		(start 251.989082 -310.202326)
		(end 251.949966 -310.101996)
		(width 0.1651)
		(layer "In7.Cu")
		(net "P5E_PEX2_STN7_TX_DN<112>")
	)
	(segment
		(start 251.49048 -311.14873)
		(end 251.490988 -311.14873)
		(width 0.1651)
		(layer "In7.Cu")
		(net "P5E_PEX2_STN7_TX_DN<112>")
	)
	(segment
		(start 252.868938 -308.008528)
		(end 253.06782 -307.555138)
		(width 0.1651)
		(layer "In7.Cu")
		(net "P5E_PEX2_STN7_TX_DN<112>")
	)
	(segment
		(start 250.11253 -314.288932)
		(end 250.113038 -314.288932)
		(width 0.1651)
		(layer "In7.Cu")
		(net "P5E_PEX2_STN7_TX_DN<112>")
	)
	(segment
		(start 251.030994 -312.195464)
		(end 251.031756 -312.195718)
		(width 0.1651)
		(layer "In7.Cu")
		(net "P5E_PEX2_STN7_TX_DN<112>")
	)
	(segment
		(start 251.07011 -312.295794)
		(end 251.030994 -312.195464)
		(width 0.1651)
		(layer "In7.Cu")
		(net "P5E_PEX2_STN7_TX_DN<112>")
	)
	(segment
		(start 251.68987 -310.695848)
		(end 251.689362 -310.69534)
		(width 0.1651)
		(layer "In7.Cu")
		(net "P5E_PEX2_STN7_TX_DN<112>")
	)
	(segment
		(start 252.249432 -309.60949)
		(end 252.448568 -309.155592)
		(width 0.1651)
		(layer "In7.Cu")
		(net "P5E_PEX2_STN7_TX_DN<112>")
	)
	(segment
		(start 249.493278 -315.889894)
		(end 249.692414 -315.435996)
		(width 0.1651)
		(layer "In7.Cu")
		(net "P5E_PEX2_STN7_TX_DN<112>")
	)
	(segment
		(start 251.230638 -311.742582)
		(end 251.229876 -311.742074)
		(width 0.1651)
		(layer "In7.Cu")
		(net "P5E_PEX2_STN7_TX_DN<112>")
	)
	(segment
		(start 251.949966 -310.101996)
		(end 251.95022 -310.10225)
		(width 0.1651)
		(layer "In7.Cu")
		(net "P5E_PEX2_STN7_TX_DN<112>")
	)
	(segment
		(start 250.311412 -313.835542)
		(end 250.411742 -313.796426)
		(width 0.1651)
		(layer "In7.Cu")
		(net "P5E_PEX2_STN7_TX_DN<112>")
	)
	(segment
		(start 251.789946 -310.656224)
		(end 251.989082 -310.202326)
		(width 0.1651)
		(layer "In7.Cu")
		(net "P5E_PEX2_STN7_TX_DN<112>")
	)
	(segment
		(start 249.852434 -314.88253)
		(end 249.85218 -314.882276)
		(width 0.1651)
		(layer "In7.Cu")
		(net "P5E_PEX2_STN7_TX_DN<112>")
	)
	(segment
		(start 257.132328 -302.73498)
		(end 259.353304 -301.934626)
		(width 0.1651)
		(layer "In7.Cu")
		(net "P5E_PEX2_STN7_TX_DN<112>")
	)
	(segment
		(start 253.328424 -306.961794)
		(end 253.527306 -306.508404)
		(width 0.1651)
		(layer "In7.Cu")
		(net "P5E_PEX2_STN7_TX_DN<112>")
	)
	(segment
		(start 268.469872 -347.556836)
		(end 260.961886 -339.485986)
		(width 0.1651)
		(layer "In7.Cu")
		(net "P5E_PEX2_STN7_TX_DN<112>")
	)
	(segment
		(start 250.57227 -313.242198)
		(end 250.771152 -312.789316)
		(width 0.1651)
		(layer "In7.Cu")
		(net "P5E_PEX2_STN7_TX_DN<112>")
	)
	(segment
		(start 252.608334 -308.601872)
		(end 252.778006 -308.535832)
		(width 0.1651)
		(layer "In7.Cu")
		(net "P5E_PEX2_STN7_TX_DN<112>")
	)
	(segment
		(start 268.760702 -348.58579)
		(end 268.469872 -348.29496)
		(width 0.1651)
		(layer "In7.Cu")
		(net "P5E_PEX2_STN7_TX_DN<112>")
	)
	(segment
		(start 251.490988 -311.14873)
		(end 251.68987 -310.695848)
		(width 0.1651)
		(layer "In7.Cu")
		(net "P5E_PEX2_STN7_TX_DN<112>")
	)
	(segment
		(start 274.179538 -301.334424)
		(end 274.179538 -301.485554)
		(width 0.1143)
		(layer "In7.Cu")
		(net "P5E_PEX2_STN7_TX_DN<112>")
	)
	(segment
		(start 250.113038 -314.288932)
		(end 250.312174 -313.835796)
		(width 0.1651)
		(layer "In7.Cu")
		(net "P5E_PEX2_STN7_TX_DN<112>")
	)
	(segment
		(start 259.353304 -301.934626)
		(end 266.14374 -301.265844)
		(width 0.1651)
		(layer "In7.Cu")
		(net "P5E_PEX2_STN7_TX_DN<112>")
	)
	(segment
		(start 250.794774 -328.381868)
		(end 248.82094 -323.617336)
		(width 0.1651)
		(layer "In7.Cu")
		(net "P5E_PEX2_STN7_TX_DN<112>")
	)
	(segment
		(start 253.527306 -306.508404)
		(end 253.527814 -306.507388)
		(width 0.1651)
		(layer "In7.Cu")
		(net "P5E_PEX2_STN7_TX_DN<112>")
	)
	(segment
		(start 266.14374 -301.265844)
		(end 267.865352 -301.265844)
		(width 0.1651)
		(layer "In7.Cu")
		(net "P5E_PEX2_STN7_TX_DN<112>")
	)
	(segment
		(start 260.961886 -339.485986)
		(end 259.860542 -338.384642)
		(width 0.1651)
		(layer "In7.Cu")
		(net "P5E_PEX2_STN7_TX_DN<112>")
	)
	(segment
		(start 248.82094 -317.233046)
		(end 249.393202 -315.92901)
		(width 0.1651)
		(layer "In7.Cu")
		(net "P5E_PEX2_STN7_TX_DN<112>")
	)
	(segment
		(start 249.95251 -314.84316)
		(end 250.151646 -314.389262)
		(width 0.1651)
		(layer "In7.Cu")
		(net "P5E_PEX2_STN7_TX_DN<112>")
	)
	(segment
		(start 250.312174 -313.835796)
		(end 250.311412 -313.835542)
		(width 0.1651)
		(layer "In7.Cu")
		(net "P5E_PEX2_STN7_TX_DN<112>")
	)
	(segment
		(start 252.149356 -309.649114)
		(end 252.148848 -309.648606)
		(width 0.1651)
		(layer "In7.Cu")
		(net "P5E_PEX2_STN7_TX_DN<112>")
	)
	(segment
		(start 251.031756 -312.195718)
		(end 251.230638 -311.742582)
		(width 0.1651)
		(layer "In7.Cu")
		(net "P5E_PEX2_STN7_TX_DN<112>")
	)
	(segment
		(start 253.06782 -307.555138)
		(end 253.16815 -307.516022)
		(width 0.1651)
		(layer "In7.Cu")
		(net "P5E_PEX2_STN7_TX_DN<112>")
	)
	(segment
		(start 386.067808 -132.240782)
		(end 386.369306 -132.54228)
		(width 0.13462)
		(layer "F.Cu")
		(net "P5E_PEX3_STN1_TX_DN<29>")
	)
	(segment
		(start 386.987034 -132.54228)
		(end 387.313932 -132.215382)
		(width 0.13462)
		(layer "F.Cu")
		(net "P5E_PEX3_STN1_TX_DN<29>")
	)
	(segment
		(start 386.369306 -132.54228)
		(end 386.987034 -132.54228)
		(width 0.13462)
		(layer "F.Cu")
		(net "P5E_PEX3_STN1_TX_DN<29>")
	)
	(segment
		(start 383.533396 -132.531612)
		(end 385.776978 -132.531612)
		(width 0.1651)
		(layer "In9.Cu")
		(net "P5E_PEX3_STN1_TX_DN<29>")
	)
	(segment
		(start 419.944804 -280.319988)
		(end 419.729666 -280.10485)
		(width 0.1143)
		(layer "In9.Cu")
		(net "P5E_PEX3_STN1_TX_DN<29>")
	)
	(segment
		(start 419.729666 -271.600168)
		(end 419.683946 -271.554448)
		(width 0.1143)
		(layer "In9.Cu")
		(net "P5E_PEX3_STN1_TX_DN<29>")
	)
	(segment
		(start 382.470152 -132.972048)
		(end 383.533396 -132.531612)
		(width 0.1651)
		(layer "In9.Cu")
		(net "P5E_PEX3_STN1_TX_DN<29>")
	)
	(segment
		(start 384.404616 -156.69641)
		(end 383.671826 -141.801342)
		(width 0.1651)
		(layer "In9.Cu")
		(net "P5E_PEX3_STN1_TX_DN<29>")
	)
	(segment
		(start 383.671826 -141.801342)
		(end 381.07366 -135.529828)
		(width 0.1651)
		(layer "In9.Cu")
		(net "P5E_PEX3_STN1_TX_DN<29>")
	)
	(segment
		(start 385.515612 -162.281108)
		(end 384.404616 -156.69641)
		(width 0.1651)
		(layer "In9.Cu")
		(net "P5E_PEX3_STN1_TX_DN<29>")
	)
	(segment
		(start 385.776978 -132.531612)
		(end 386.067808 -132.240782)
		(width 0.1651)
		(layer "In9.Cu")
		(net "P5E_PEX3_STN1_TX_DN<29>")
	)
	(segment
		(start 419.683946 -271.554448)
		(end 419.683946 -271.526)
		(width 0.1143)
		(layer "In9.Cu")
		(net "P5E_PEX3_STN1_TX_DN<29>")
	)
	(segment
		(start 381.338836 -134.103364)
		(end 382.470152 -132.972048)
		(width 0.1651)
		(layer "In9.Cu")
		(net "P5E_PEX3_STN1_TX_DN<29>")
	)
	(segment
		(start 420.185596 -280.319988)
		(end 419.944804 -280.319988)
		(width 0.1143)
		(layer "In9.Cu")
		(net "P5E_PEX3_STN1_TX_DN<29>")
	)
	(segment
		(start 420.299896 -280.434288)
		(end 420.185596 -280.319988)
		(width 0.1143)
		(layer "In9.Cu")
		(net "P5E_PEX3_STN1_TX_DN<29>")
	)
	(segment
		(start 419.683946 -271.526)
		(end 419.683946 -263.217406)
		(width 0.1651)
		(layer "In9.Cu")
		(net "P5E_PEX3_STN1_TX_DN<29>")
	)
	(segment
		(start 419.683946 -263.217406)
		(end 385.515612 -162.281108)
		(width 0.1651)
		(layer "In9.Cu")
		(net "P5E_PEX3_STN1_TX_DN<29>")
	)
	(segment
		(start 381.07366 -134.743444)
		(end 381.338836 -134.103364)
		(width 0.1651)
		(layer "In9.Cu")
		(net "P5E_PEX3_STN1_TX_DN<29>")
	)
	(segment
		(start 419.729666 -280.10485)
		(end 419.729666 -271.600168)
		(width 0.1143)
		(layer "In9.Cu")
		(net "P5E_PEX3_STN1_TX_DN<29>")
	)
	(segment
		(start 420.299896 -280.699718)
		(end 420.299896 -280.434288)
		(width 0.1143)
		(layer "In9.Cu")
		(net "P5E_PEX3_STN1_TX_DN<29>")
	)
	(segment
		(start 381.07366 -135.529828)
		(end 381.07366 -134.743444)
		(width 0.1651)
		(layer "In9.Cu")
		(net "P5E_PEX3_STN1_TX_DN<29>")
	)
	(segment
		(start 332.616048 -369.242086)
		(end 330.174854 -358.789478)
		(width 0.1651)
		(layer "In5.Cu")
		(net "P5E_PEX2_STN5_RX_DN<88>")
	)
	(segment
		(start 299.07484 -324.106794)
		(end 298.165774 -321.91198)
		(width 0.1651)
		(layer "In5.Cu")
		(net "P5E_PEX2_STN5_RX_DN<88>")
	)
	(segment
		(start 298.165774 -319.992248)
		(end 298.165774 -319.9638)
		(width 0.1143)
		(layer "In5.Cu")
		(net "P5E_PEX2_STN5_RX_DN<88>")
	)
	(segment
		(start 298.120054 -316.534292)
		(end 298.234354 -316.419992)
		(width 0.1143)
		(layer "In5.Cu")
		(net "P5E_PEX2_STN5_RX_DN<88>")
	)
	(segment
		(start 332.616048 -370.829332)
		(end 332.616048 -369.242086)
		(width 0.1651)
		(layer "In5.Cu")
		(net "P5E_PEX2_STN5_RX_DN<88>")
	)
	(segment
		(start 330.174854 -358.789478)
		(end 330.174854 -341.751158)
		(width 0.1651)
		(layer "In5.Cu")
		(net "P5E_PEX2_STN5_RX_DN<88>")
	)
	(segment
		(start 331.617066 -371.281198)
		(end 332.164182 -371.281198)
		(width 0.1651)
		(layer "In5.Cu")
		(net "P5E_PEX2_STN5_RX_DN<88>")
	)
	(segment
		(start 298.234354 -316.419992)
		(end 298.385484 -316.419992)
		(width 0.1143)
		(layer "In5.Cu")
		(net "P5E_PEX2_STN5_RX_DN<88>")
	)
	(segment
		(start 298.165774 -319.9638)
		(end 298.120054 -319.91808)
		(width 0.1143)
		(layer "In5.Cu")
		(net "P5E_PEX2_STN5_RX_DN<88>")
	)
	(segment
		(start 298.499784 -316.534292)
		(end 298.499784 -316.799722)
		(width 0.1143)
		(layer "In5.Cu")
		(net "P5E_PEX2_STN5_RX_DN<88>")
	)
	(segment
		(start 332.164182 -371.281198)
		(end 332.616048 -370.829332)
		(width 0.1651)
		(layer "In5.Cu")
		(net "P5E_PEX2_STN5_RX_DN<88>")
	)
	(segment
		(start 302.210978 -327.242932)
		(end 299.07484 -324.106794)
		(width 0.1651)
		(layer "In5.Cu")
		(net "P5E_PEX2_STN5_RX_DN<88>")
	)
	(segment
		(start 331.490066 -371.790214)
		(end 331.490066 -371.408198)
		(width 0.1651)
		(layer "In5.Cu")
		(net "P5E_PEX2_STN5_RX_DN<88>")
	)
	(segment
		(start 298.165774 -321.91198)
		(end 298.165774 -319.992248)
		(width 0.1651)
		(layer "In5.Cu")
		(net "P5E_PEX2_STN5_RX_DN<88>")
	)
	(segment
		(start 330.174854 -341.751158)
		(end 328.865992 -340.442296)
		(width 0.1651)
		(layer "In5.Cu")
		(net "P5E_PEX2_STN5_RX_DN<88>")
	)
	(segment
		(start 298.385484 -316.419992)
		(end 298.499784 -316.534292)
		(width 0.1143)
		(layer "In5.Cu")
		(net "P5E_PEX2_STN5_RX_DN<88>")
	)
	(segment
		(start 298.120054 -319.91808)
		(end 298.120054 -316.534292)
		(width 0.1143)
		(layer "In5.Cu")
		(net "P5E_PEX2_STN5_RX_DN<88>")
	)
	(segment
		(start 328.865992 -340.442296)
		(end 302.210978 -327.242932)
		(width 0.1651)
		(layer "In5.Cu")
		(net "P5E_PEX2_STN5_RX_DN<88>")
	)
	(segment
		(start 331.490066 -371.408198)
		(end 331.617066 -371.281198)
		(width 0.1651)
		(layer "In5.Cu")
		(net "P5E_PEX2_STN5_RX_DN<88>")
	)
	(segment
		(start 178.594512 -351.611438)
		(end 178.299872 -351.316798)
		(width 0.13462)
		(layer "F.Cu")
		(net "P5E_PEX1_STN7_TX_C_DN<120>")
	)
	(segment
		(start 178.299872 -351.316798)
		(end 178.299872 -350.685354)
		(width 0.13462)
		(layer "F.Cu")
		(net "P5E_PEX1_STN7_TX_C_DN<120>")
	)
	(segment
		(start 178.299872 -350.685354)
		(end 178.619912 -350.365314)
		(width 0.13462)
		(layer "F.Cu")
		(net "P5E_PEX1_STN7_TX_C_DN<120>")
	)
	(segment
		(start 160.037018 -375.181114)
		(end 160.442402 -375.181114)
		(width 0.1651)
		(layer "In11.Cu")
		(net "P5E_PEX1_STN7_TX_C_DN<120>")
	)
	(segment
		(start 178.303682 -352.664776)
		(end 178.303682 -351.902268)
		(width 0.1651)
		(layer "In11.Cu")
		(net "P5E_PEX1_STN7_TX_C_DN<120>")
	)
	(segment
		(start 161.067496 -374.55602)
		(end 161.067496 -369.023646)
		(width 0.1651)
		(layer "In11.Cu")
		(net "P5E_PEX1_STN7_TX_C_DN<120>")
	)
	(segment
		(start 159.910018 -375.69013)
		(end 159.910018 -375.308114)
		(width 0.1651)
		(layer "In11.Cu")
		(net "P5E_PEX1_STN7_TX_C_DN<120>")
	)
	(segment
		(start 173.588172 -362.351066)
		(end 176.749202 -359.190036)
		(width 0.1651)
		(layer "In11.Cu")
		(net "P5E_PEX1_STN7_TX_C_DN<120>")
	)
	(segment
		(start 163.509198 -366.581944)
		(end 173.588172 -362.351066)
		(width 0.1651)
		(layer "In11.Cu")
		(net "P5E_PEX1_STN7_TX_C_DN<120>")
	)
	(segment
		(start 176.749202 -354.219256)
		(end 178.303682 -352.664776)
		(width 0.1651)
		(layer "In11.Cu")
		(net "P5E_PEX1_STN7_TX_C_DN<120>")
	)
	(segment
		(start 178.303682 -351.902268)
		(end 178.594512 -351.611438)
		(width 0.1651)
		(layer "In11.Cu")
		(net "P5E_PEX1_STN7_TX_C_DN<120>")
	)
	(segment
		(start 159.910018 -375.308114)
		(end 160.037018 -375.181114)
		(width 0.1651)
		(layer "In11.Cu")
		(net "P5E_PEX1_STN7_TX_C_DN<120>")
	)
	(segment
		(start 176.749202 -359.190036)
		(end 176.749202 -354.219256)
		(width 0.1651)
		(layer "In11.Cu")
		(net "P5E_PEX1_STN7_TX_C_DN<120>")
	)
	(segment
		(start 161.067496 -369.023646)
		(end 163.509198 -366.581944)
		(width 0.1651)
		(layer "In11.Cu")
		(net "P5E_PEX1_STN7_TX_C_DN<120>")
	)
	(segment
		(start 160.442402 -375.181114)
		(end 161.067496 -374.55602)
		(width 0.1651)
		(layer "In11.Cu")
		(net "P5E_PEX1_STN7_TX_C_DN<120>")
	)
	(segment
		(start 130.490468 -349.831914)
		(end 130.810508 -349.511874)
		(width 0.13462)
		(layer "F.Cu")
		(net "P5E_PEX1_STN5_TX_DP<81>")
	)
	(segment
		(start 130.810508 -348.88043)
		(end 130.515868 -348.58579)
		(width 0.13462)
		(layer "F.Cu")
		(net "P5E_PEX1_STN5_TX_DP<81>")
	)
	(segment
		(start 130.810508 -349.511874)
		(end 130.810508 -348.88043)
		(width 0.13462)
		(layer "F.Cu")
		(net "P5E_PEX1_STN5_TX_DP<81>")
	)
	(segment
		(start 175.635666 -313.379612)
		(end 175.749966 -313.265312)
		(width 0.1143)
		(layer "In7.Cu")
		(net "P5E_PEX1_STN5_TX_DP<81>")
	)
	(segment
		(start 152.464008 -333.528162)
		(end 169.156634 -328.464418)
		(width 0.1651)
		(layer "In7.Cu")
		(net "P5E_PEX1_STN5_TX_DP<81>")
	)
	(segment
		(start 135.704326 -338.612226)
		(end 152.464008 -333.528162)
		(width 0.1651)
		(layer "In7.Cu")
		(net "P5E_PEX1_STN5_TX_DP<81>")
	)
	(segment
		(start 175.749966 -313.265312)
		(end 175.749966 -312.999882)
		(width 0.1143)
		(layer "In7.Cu")
		(net "P5E_PEX1_STN5_TX_DP<81>")
	)
	(segment
		(start 132.361178 -346.065602)
		(end 132.361178 -341.094822)
		(width 0.1651)
		(layer "In7.Cu")
		(net "P5E_PEX1_STN5_TX_DP<81>")
	)
	(segment
		(start 130.515868 -348.58579)
		(end 130.806698 -348.29496)
		(width 0.1651)
		(layer "In7.Cu")
		(net "P5E_PEX1_STN5_TX_DP<81>")
	)
	(segment
		(start 133.55574 -339.90026)
		(end 135.704326 -338.612226)
		(width 0.1651)
		(layer "In7.Cu")
		(net "P5E_PEX1_STN5_TX_DP<81>")
	)
	(segment
		(start 175.405542 -313.379612)
		(end 175.635666 -313.379612)
		(width 0.1143)
		(layer "In7.Cu")
		(net "P5E_PEX1_STN5_TX_DP<81>")
	)
	(segment
		(start 175.134016 -319.97396)
		(end 175.179736 -319.92824)
		(width 0.1143)
		(layer "In7.Cu")
		(net "P5E_PEX1_STN5_TX_DP<81>")
	)
	(segment
		(start 175.134016 -320.002408)
		(end 175.134016 -319.97396)
		(width 0.1143)
		(layer "In7.Cu")
		(net "P5E_PEX1_STN5_TX_DP<81>")
	)
	(segment
		(start 174.386748 -324.602348)
		(end 175.134016 -322.798186)
		(width 0.1651)
		(layer "In7.Cu")
		(net "P5E_PEX1_STN5_TX_DP<81>")
	)
	(segment
		(start 172.571918 -326.417178)
		(end 174.386748 -324.602348)
		(width 0.1651)
		(layer "In7.Cu")
		(net "P5E_PEX1_STN5_TX_DP<81>")
	)
	(segment
		(start 175.179736 -319.92824)
		(end 175.179736 -313.605418)
		(width 0.1143)
		(layer "In7.Cu")
		(net "P5E_PEX1_STN5_TX_DP<81>")
	)
	(segment
		(start 175.134016 -322.798186)
		(end 175.134016 -320.002408)
		(width 0.1651)
		(layer "In7.Cu")
		(net "P5E_PEX1_STN5_TX_DP<81>")
	)
	(segment
		(start 130.806698 -348.29496)
		(end 130.806698 -347.620082)
		(width 0.1651)
		(layer "In7.Cu")
		(net "P5E_PEX1_STN5_TX_DP<81>")
	)
	(segment
		(start 130.806698 -347.620082)
		(end 132.361178 -346.065602)
		(width 0.1651)
		(layer "In7.Cu")
		(net "P5E_PEX1_STN5_TX_DP<81>")
	)
	(segment
		(start 132.361178 -341.094822)
		(end 133.55574 -339.90026)
		(width 0.1651)
		(layer "In7.Cu")
		(net "P5E_PEX1_STN5_TX_DP<81>")
	)
	(segment
		(start 175.179736 -313.605418)
		(end 175.405542 -313.379612)
		(width 0.1143)
		(layer "In7.Cu")
		(net "P5E_PEX1_STN5_TX_DP<81>")
	)
	(segment
		(start 169.156634 -328.464418)
		(end 172.571918 -326.417178)
		(width 0.1651)
		(layer "In7.Cu")
		(net "P5E_PEX1_STN5_TX_DP<81>")
	)
	(segment
		(start 269.96771 -107.377738)
		(end 270.259048 -107.0864)
		(width 0.13462)
		(layer "F.Cu")
		(net "P5E_PEX2_STN1_TX_DN<20>")
	)
	(segment
		(start 270.897096 -107.0864)
		(end 271.213834 -107.403138)
		(width 0.13462)
		(layer "F.Cu")
		(net "P5E_PEX2_STN1_TX_DN<20>")
	)
	(segment
		(start 270.259048 -107.0864)
		(end 270.897096 -107.0864)
		(width 0.13462)
		(layer "F.Cu")
		(net "P5E_PEX2_STN1_TX_DN<20>")
	)
	(segment
		(start 263.167876 -112.040416)
		(end 263.352534 -111.594392)
		(width 0.1651)
		(layer "In9.Cu")
		(net "P5E_PEX2_STN1_TX_DN<20>")
	)
	(segment
		(start 261.368286 -116.085874)
		(end 261.644638 -115.418616)
		(width 0.1651)
		(layer "In9.Cu")
		(net "P5E_PEX2_STN1_TX_DN<20>")
	)
	(segment
		(start 262.55853 -113.212372)
		(end 262.707882 -113.15065)
		(width 0.1651)
		(layer "In9.Cu")
		(net "P5E_PEX2_STN1_TX_DN<20>")
	)
	(segment
		(start 262.373872 -113.658142)
		(end 262.55853 -113.212372)
		(width 0.1651)
		(layer "In9.Cu")
		(net "P5E_PEX2_STN1_TX_DN<20>")
	)
	(segment
		(start 263.352534 -111.594392)
		(end 263.290558 -111.44504)
		(width 0.1651)
		(layer "In9.Cu")
		(net "P5E_PEX2_STN1_TX_DN<20>")
	)
	(segment
		(start 264.938002 -108.7755)
		(end 265.099546 -108.7755)
		(width 0.1651)
		(layer "In9.Cu")
		(net "P5E_PEX2_STN1_TX_DN<20>")
	)
	(segment
		(start 261.794244 -115.35664)
		(end 261.978902 -114.910616)
		(width 0.1651)
		(layer "In9.Cu")
		(net "P5E_PEX2_STN1_TX_DN<20>")
	)
	(segment
		(start 295.53535 -278.229568)
		(end 295.373552 -278.229568)
		(width 0.1143)
		(layer "In9.Cu")
		(net "P5E_PEX2_STN1_TX_DN<20>")
	)
	(segment
		(start 261.245604 -116.68125)
		(end 261.430262 -116.235226)
		(width 0.1651)
		(layer "In9.Cu")
		(net "P5E_PEX2_STN1_TX_DN<20>")
	)
	(segment
		(start 259.137912 -144.425924)
		(end 256.558034 -138.197844)
		(width 0.1651)
		(layer "In9.Cu")
		(net "P5E_PEX2_STN1_TX_DN<20>")
	)
	(segment
		(start 262.25119 -114.253518)
		(end 262.435848 -113.807494)
		(width 0.1651)
		(layer "In9.Cu")
		(net "P5E_PEX2_STN1_TX_DN<20>")
	)
	(segment
		(start 295.270174 -278.12619)
		(end 295.270174 -271.546066)
		(width 0.1143)
		(layer "In9.Cu")
		(net "P5E_PEX2_STN1_TX_DN<20>")
	)
	(segment
		(start 295.64965 -277.849838)
		(end 295.64965 -278.115268)
		(width 0.1143)
		(layer "In9.Cu")
		(net "P5E_PEX2_STN1_TX_DN<20>")
	)
	(segment
		(start 262.830818 -112.555274)
		(end 263.01827 -112.102392)
		(width 0.1651)
		(layer "In9.Cu")
		(net "P5E_PEX2_STN1_TX_DN<20>")
	)
	(segment
		(start 261.430262 -116.235226)
		(end 261.368286 -116.085874)
		(width 0.1651)
		(layer "In9.Cu")
		(net "P5E_PEX2_STN1_TX_DN<20>")
	)
	(segment
		(start 259.86359 -159.187134)
		(end 259.137912 -144.425924)
		(width 0.1651)
		(layer "In9.Cu")
		(net "P5E_PEX2_STN1_TX_DN<20>")
	)
	(segment
		(start 262.101584 -114.315494)
		(end 262.25119 -114.253518)
		(width 0.1651)
		(layer "In9.Cu")
		(net "P5E_PEX2_STN1_TX_DN<20>")
	)
	(segment
		(start 261.978902 -114.910616)
		(end 261.916926 -114.761264)
		(width 0.1651)
		(layer "In9.Cu")
		(net "P5E_PEX2_STN1_TX_DN<20>")
	)
	(segment
		(start 295.315894 -265.086338)
		(end 260.423914 -162.004248)
		(width 0.1651)
		(layer "In9.Cu")
		(net "P5E_PEX2_STN1_TX_DN<20>")
	)
	(segment
		(start 260.423914 -162.004248)
		(end 259.86359 -159.187134)
		(width 0.1651)
		(layer "In9.Cu")
		(net "P5E_PEX2_STN1_TX_DN<20>")
	)
	(segment
		(start 265.099546 -108.7755)
		(end 265.441176 -108.43387)
		(width 0.1651)
		(layer "In9.Cu")
		(net "P5E_PEX2_STN1_TX_DN<20>")
	)
	(segment
		(start 267.820648 -107.086908)
		(end 268.303502 -107.086908)
		(width 0.1651)
		(layer "In9.Cu")
		(net "P5E_PEX2_STN1_TX_DN<20>")
	)
	(segment
		(start 261.916926 -114.761264)
		(end 262.101584 -114.315494)
		(width 0.1651)
		(layer "In9.Cu")
		(net "P5E_PEX2_STN1_TX_DN<20>")
	)
	(segment
		(start 265.782298 -107.931204)
		(end 267.820648 -107.086908)
		(width 0.1651)
		(layer "In9.Cu")
		(net "P5E_PEX2_STN1_TX_DN<20>")
	)
	(segment
		(start 256.558034 -138.197844)
		(end 256.558034 -131.214368)
		(width 0.1651)
		(layer "In9.Cu")
		(net "P5E_PEX2_STN1_TX_DN<20>")
	)
	(segment
		(start 268.303502 -107.086908)
		(end 268.417802 -107.201208)
		(width 0.1651)
		(layer "In9.Cu")
		(net "P5E_PEX2_STN1_TX_DN<20>")
	)
	(segment
		(start 264.013188 -109.700314)
		(end 264.938002 -108.7755)
		(width 0.1651)
		(layer "In9.Cu")
		(net "P5E_PEX2_STN1_TX_DN<20>")
	)
	(segment
		(start 263.80948 -110.49127)
		(end 263.747504 -110.341918)
		(width 0.1651)
		(layer "In9.Cu")
		(net "P5E_PEX2_STN1_TX_DN<20>")
	)
	(segment
		(start 262.892794 -112.704626)
		(end 262.830818 -112.555274)
		(width 0.1651)
		(layer "In9.Cu")
		(net "P5E_PEX2_STN1_TX_DN<20>")
	)
	(segment
		(start 263.747504 -110.341918)
		(end 264.013188 -109.700314)
		(width 0.1651)
		(layer "In9.Cu")
		(net "P5E_PEX2_STN1_TX_DN<20>")
	)
	(segment
		(start 295.315894 -271.471898)
		(end 295.315894 -265.086338)
		(width 0.1651)
		(layer "In9.Cu")
		(net "P5E_PEX2_STN1_TX_DN<20>")
	)
	(segment
		(start 263.624822 -110.937294)
		(end 263.80948 -110.49127)
		(width 0.1651)
		(layer "In9.Cu")
		(net "P5E_PEX2_STN1_TX_DN<20>")
	)
	(segment
		(start 265.441176 -108.43387)
		(end 265.441176 -108.272326)
		(width 0.1651)
		(layer "In9.Cu")
		(net "P5E_PEX2_STN1_TX_DN<20>")
	)
	(segment
		(start 261.644638 -115.418616)
		(end 261.794244 -115.35664)
		(width 0.1651)
		(layer "In9.Cu")
		(net "P5E_PEX2_STN1_TX_DN<20>")
	)
	(segment
		(start 263.290558 -111.44504)
		(end 263.475216 -110.99927)
		(width 0.1651)
		(layer "In9.Cu")
		(net "P5E_PEX2_STN1_TX_DN<20>")
	)
	(segment
		(start 269.014702 -107.086908)
		(end 269.67688 -107.086908)
		(width 0.1651)
		(layer "In9.Cu")
		(net "P5E_PEX2_STN1_TX_DN<20>")
	)
	(segment
		(start 263.01827 -112.102392)
		(end 263.167876 -112.040416)
		(width 0.1651)
		(layer "In9.Cu")
		(net "P5E_PEX2_STN1_TX_DN<20>")
	)
	(segment
		(start 295.270174 -271.546066)
		(end 295.315894 -271.500346)
		(width 0.1143)
		(layer "In9.Cu")
		(net "P5E_PEX2_STN1_TX_DN<20>")
	)
	(segment
		(start 269.67688 -107.086908)
		(end 269.96771 -107.377738)
		(width 0.1651)
		(layer "In9.Cu")
		(net "P5E_PEX2_STN1_TX_DN<20>")
	)
	(segment
		(start 260.540754 -118.084092)
		(end 261.095998 -116.743226)
		(width 0.1651)
		(layer "In9.Cu")
		(net "P5E_PEX2_STN1_TX_DN<20>")
	)
	(segment
		(start 268.900402 -107.201208)
		(end 269.014702 -107.086908)
		(width 0.1651)
		(layer "In9.Cu")
		(net "P5E_PEX2_STN1_TX_DN<20>")
	)
	(segment
		(start 256.558034 -131.214368)
		(end 260.540754 -118.084092)
		(width 0.1651)
		(layer "In9.Cu")
		(net "P5E_PEX2_STN1_TX_DN<20>")
	)
	(segment
		(start 261.095998 -116.743226)
		(end 261.245604 -116.68125)
		(width 0.1651)
		(layer "In9.Cu")
		(net "P5E_PEX2_STN1_TX_DN<20>")
	)
	(segment
		(start 262.707882 -113.15065)
		(end 262.892794 -112.704626)
		(width 0.1651)
		(layer "In9.Cu")
		(net "P5E_PEX2_STN1_TX_DN<20>")
	)
	(segment
		(start 262.435848 -113.807494)
		(end 262.373872 -113.658142)
		(width 0.1651)
		(layer "In9.Cu")
		(net "P5E_PEX2_STN1_TX_DN<20>")
	)
	(segment
		(start 295.373552 -278.229568)
		(end 295.270174 -278.12619)
		(width 0.1143)
		(layer "In9.Cu")
		(net "P5E_PEX2_STN1_TX_DN<20>")
	)
	(segment
		(start 263.475216 -110.99927)
		(end 263.624822 -110.937294)
		(width 0.1651)
		(layer "In9.Cu")
		(net "P5E_PEX2_STN1_TX_DN<20>")
	)
	(segment
		(start 295.64965 -278.115268)
		(end 295.53535 -278.229568)
		(width 0.1143)
		(layer "In9.Cu")
		(net "P5E_PEX2_STN1_TX_DN<20>")
	)
	(segment
		(start 268.417802 -107.201208)
		(end 268.900402 -107.201208)
		(width 0.1651)
		(layer "In9.Cu")
		(net "P5E_PEX2_STN1_TX_DN<20>")
	)
	(segment
		(start 295.315894 -271.500346)
		(end 295.315894 -271.471898)
		(width 0.1143)
		(layer "In9.Cu")
		(net "P5E_PEX2_STN1_TX_DN<20>")
	)
	(segment
		(start 265.441176 -108.272326)
		(end 265.782298 -107.931204)
		(width 0.1651)
		(layer "In9.Cu")
		(net "P5E_PEX2_STN1_TX_DN<20>")
	)
	(segment
		(start 328.342244 -348.88043)
		(end 328.047604 -348.58579)
		(width 0.13462)
		(layer "F.Cu")
		(net "P5E_PEX2_STN6_TX_DP<104>")
	)
	(segment
		(start 328.022204 -349.831914)
		(end 328.342244 -349.511874)
		(width 0.13462)
		(layer "F.Cu")
		(net "P5E_PEX2_STN6_TX_DP<104>")
	)
	(segment
		(start 328.342244 -349.511874)
		(end 328.342244 -348.88043)
		(width 0.13462)
		(layer "F.Cu")
		(net "P5E_PEX2_STN6_TX_DP<104>")
	)
	(segment
		(start 328.338434 -347.667834)
		(end 329.892914 -346.113354)
		(width 0.1651)
		(layer "In13.Cu")
		(net "P5E_PEX2_STN6_TX_DP<104>")
	)
	(segment
		(start 281.733752 -319.995296)
		(end 281.733752 -319.966848)
		(width 0.1143)
		(layer "In13.Cu")
		(net "P5E_PEX2_STN6_TX_DP<104>")
	)
	(segment
		(start 281.733752 -319.966848)
		(end 281.779472 -319.921128)
		(width 0.1143)
		(layer "In13.Cu")
		(net "P5E_PEX2_STN6_TX_DP<104>")
	)
	(segment
		(start 329.892914 -346.113354)
		(end 329.892914 -342.193626)
		(width 0.1651)
		(layer "In13.Cu")
		(net "P5E_PEX2_STN6_TX_DP<104>")
	)
	(segment
		(start 281.733752 -323.661532)
		(end 281.733752 -319.995296)
		(width 0.1651)
		(layer "In13.Cu")
		(net "P5E_PEX2_STN6_TX_DP<104>")
	)
	(segment
		(start 281.779472 -313.59475)
		(end 281.99461 -313.379612)
		(width 0.1143)
		(layer "In13.Cu")
		(net "P5E_PEX2_STN6_TX_DP<104>")
	)
	(segment
		(start 282.235402 -313.379612)
		(end 282.349702 -313.265312)
		(width 0.1143)
		(layer "In13.Cu")
		(net "P5E_PEX2_STN6_TX_DP<104>")
	)
	(segment
		(start 285.149036 -327.821036)
		(end 282.26004 -324.93204)
		(width 0.1651)
		(layer "In13.Cu")
		(net "P5E_PEX2_STN6_TX_DP<104>")
	)
	(segment
		(start 329.443588 -341.475314)
		(end 327.216262 -339.198458)
		(width 0.1651)
		(layer "In13.Cu")
		(net "P5E_PEX2_STN6_TX_DP<104>")
	)
	(segment
		(start 327.216262 -339.198458)
		(end 314.914788 -333.67472)
		(width 0.1651)
		(layer "In13.Cu")
		(net "P5E_PEX2_STN6_TX_DP<104>")
	)
	(segment
		(start 282.26004 -324.93204)
		(end 281.733752 -323.661532)
		(width 0.1651)
		(layer "In13.Cu")
		(net "P5E_PEX2_STN6_TX_DP<104>")
	)
	(segment
		(start 314.914788 -333.67472)
		(end 285.149036 -327.821036)
		(width 0.1651)
		(layer "In13.Cu")
		(net "P5E_PEX2_STN6_TX_DP<104>")
	)
	(segment
		(start 328.047604 -348.58579)
		(end 328.338434 -348.29496)
		(width 0.1651)
		(layer "In13.Cu")
		(net "P5E_PEX2_STN6_TX_DP<104>")
	)
	(segment
		(start 281.779472 -319.921128)
		(end 281.779472 -313.59475)
		(width 0.1143)
		(layer "In13.Cu")
		(net "P5E_PEX2_STN6_TX_DP<104>")
	)
	(segment
		(start 328.338434 -348.29496)
		(end 328.338434 -347.667834)
		(width 0.1651)
		(layer "In13.Cu")
		(net "P5E_PEX2_STN6_TX_DP<104>")
	)
	(segment
		(start 281.99461 -313.379612)
		(end 282.235402 -313.379612)
		(width 0.1143)
		(layer "In13.Cu")
		(net "P5E_PEX2_STN6_TX_DP<104>")
	)
	(segment
		(start 282.349702 -313.265312)
		(end 282.349702 -312.999882)
		(width 0.1143)
		(layer "In13.Cu")
		(net "P5E_PEX2_STN6_TX_DP<104>")
	)
	(segment
		(start 329.892914 -342.193626)
		(end 329.443588 -341.475314)
		(width 0.1651)
		(layer "In13.Cu")
		(net "P5E_PEX2_STN6_TX_DP<104>")
	)
	(segment
		(start 429.528732 -150.11908)
		(end 428.915068 -150.11908)
		(width 0.13462)
		(layer "F.Cu")
		(net "P5E_PEX3_STN0_TX_DP<12>")
	)
	(segment
		(start 428.915068 -150.11908)
		(end 428.586138 -149.79015)
		(width 0.13462)
		(layer "F.Cu")
		(net "P5E_PEX3_STN0_TX_DP<12>")
	)
	(segment
		(start 429.832262 -149.81555)
		(end 429.528732 -150.11908)
		(width 0.13462)
		(layer "F.Cu")
		(net "P5E_PEX3_STN0_TX_DP<12>")
	)
	(segment
		(start 432.57216 -150.10638)
		(end 433.916582 -150.663402)
		(width 0.1651)
		(layer "In9.Cu")
		(net "P5E_PEX3_STN0_TX_DP<12>")
	)
	(segment
		(start 436.858664 -155.180792)
		(end 436.858664 -157.417516)
		(width 0.1651)
		(layer "In9.Cu")
		(net "P5E_PEX3_STN0_TX_DP<12>")
	)
	(segment
		(start 425.99991 -280.015188)
		(end 425.99991 -279.749504)
		(width 0.1143)
		(layer "In9.Cu")
		(net "P5E_PEX3_STN0_TX_DP<12>")
	)
	(segment
		(start 429.832262 -149.81555)
		(end 430.123092 -150.10638)
		(width 0.1651)
		(layer "In9.Cu")
		(net "P5E_PEX3_STN0_TX_DP<12>")
	)
	(segment
		(start 425.62018 -280.025856)
		(end 425.723812 -280.129488)
		(width 0.1143)
		(layer "In9.Cu")
		(net "P5E_PEX3_STN0_TX_DP<12>")
	)
	(segment
		(start 430.123092 -150.10638)
		(end 432.57216 -150.10638)
		(width 0.1651)
		(layer "In9.Cu")
		(net "P5E_PEX3_STN0_TX_DP<12>")
	)
	(segment
		(start 433.916582 -150.663402)
		(end 434.658008 -151.404828)
		(width 0.1651)
		(layer "In9.Cu")
		(net "P5E_PEX3_STN0_TX_DP<12>")
	)
	(segment
		(start 426.593508 -268.133068)
		(end 425.6659 -270.37284)
		(width 0.1651)
		(layer "In9.Cu")
		(net "P5E_PEX3_STN0_TX_DP<12>")
	)
	(segment
		(start 434.658008 -151.404828)
		(end 436.333138 -153.9113)
		(width 0.1651)
		(layer "In9.Cu")
		(net "P5E_PEX3_STN0_TX_DP<12>")
	)
	(segment
		(start 436.858664 -157.417516)
		(end 428.586138 -171.747942)
		(width 0.1651)
		(layer "In9.Cu")
		(net "P5E_PEX3_STN0_TX_DP<12>")
	)
	(segment
		(start 425.6659 -271.526)
		(end 425.6659 -271.554448)
		(width 0.1143)
		(layer "In9.Cu")
		(net "P5E_PEX3_STN0_TX_DP<12>")
	)
	(segment
		(start 423.208196 -222.097346)
		(end 426.593508 -260.81736)
		(width 0.1651)
		(layer "In9.Cu")
		(net "P5E_PEX3_STN0_TX_DP<12>")
	)
	(segment
		(start 426.593508 -260.81736)
		(end 426.593508 -268.133068)
		(width 0.1651)
		(layer "In9.Cu")
		(net "P5E_PEX3_STN0_TX_DP<12>")
	)
	(segment
		(start 436.333138 -153.9113)
		(end 436.858664 -155.180792)
		(width 0.1651)
		(layer "In9.Cu")
		(net "P5E_PEX3_STN0_TX_DP<12>")
	)
	(segment
		(start 425.88561 -280.129488)
		(end 425.99991 -280.015188)
		(width 0.1143)
		(layer "In9.Cu")
		(net "P5E_PEX3_STN0_TX_DP<12>")
	)
	(segment
		(start 425.62018 -271.600168)
		(end 425.62018 -280.025856)
		(width 0.1143)
		(layer "In9.Cu")
		(net "P5E_PEX3_STN0_TX_DP<12>")
	)
	(segment
		(start 425.6659 -270.37284)
		(end 425.6659 -271.526)
		(width 0.1651)
		(layer "In9.Cu")
		(net "P5E_PEX3_STN0_TX_DP<12>")
	)
	(segment
		(start 425.6659 -271.554448)
		(end 425.62018 -271.600168)
		(width 0.1143)
		(layer "In9.Cu")
		(net "P5E_PEX3_STN0_TX_DP<12>")
	)
	(segment
		(start 425.723812 -280.129488)
		(end 425.88561 -280.129488)
		(width 0.1143)
		(layer "In9.Cu")
		(net "P5E_PEX3_STN0_TX_DP<12>")
	)
	(segment
		(start 428.586138 -171.747942)
		(end 427.14164 -177.137568)
		(width 0.1651)
		(layer "In9.Cu")
		(net "P5E_PEX3_STN0_TX_DP<12>")
	)
	(segment
		(start 427.14164 -177.137568)
		(end 423.208196 -222.097346)
		(width 0.1651)
		(layer "In9.Cu")
		(net "P5E_PEX3_STN0_TX_DP<12>")
	)
	(segment
		(start 137.302748 -357.46309)
		(end 137.302748 -356.831646)
		(width 0.13462)
		(layer "F.Cu")
		(net "P5E_PEX1_STN5_TX_C_DN<92>")
	)
	(segment
		(start 137.597388 -357.75773)
		(end 137.302748 -357.46309)
		(width 0.13462)
		(layer "F.Cu")
		(net "P5E_PEX1_STN5_TX_C_DN<92>")
	)
	(segment
		(start 137.302748 -356.831646)
		(end 137.622788 -356.511606)
		(width 0.13462)
		(layer "F.Cu")
		(net "P5E_PEX1_STN5_TX_C_DN<92>")
	)
	(segment
		(start 124.71019 -379.590046)
		(end 124.71019 -379.20803)
		(width 0.1651)
		(layer "In13.Cu")
		(net "P5E_PEX1_STN5_TX_C_DN<92>")
	)
	(segment
		(start 125.866906 -368.761264)
		(end 126.278894 -367.912396)
		(width 0.1651)
		(layer "In13.Cu")
		(net "P5E_PEX1_STN5_TX_C_DN<92>")
	)
	(segment
		(start 124.83719 -379.08103)
		(end 125.175518 -379.08103)
		(width 0.1651)
		(layer "In13.Cu")
		(net "P5E_PEX1_STN5_TX_C_DN<92>")
	)
	(segment
		(start 124.71019 -379.20803)
		(end 124.83719 -379.08103)
		(width 0.1651)
		(layer "In13.Cu")
		(net "P5E_PEX1_STN5_TX_C_DN<92>")
	)
	(segment
		(start 125.866906 -378.389642)
		(end 125.866906 -368.761264)
		(width 0.1651)
		(layer "In13.Cu")
		(net "P5E_PEX1_STN5_TX_C_DN<92>")
	)
	(segment
		(start 137.306558 -358.673908)
		(end 137.306558 -358.04856)
		(width 0.1651)
		(layer "In13.Cu")
		(net "P5E_PEX1_STN5_TX_C_DN<92>")
	)
	(segment
		(start 125.175518 -379.08103)
		(end 125.866906 -378.389642)
		(width 0.1651)
		(layer "In13.Cu")
		(net "P5E_PEX1_STN5_TX_C_DN<92>")
	)
	(segment
		(start 136.873996 -359.565194)
		(end 137.306558 -358.673908)
		(width 0.1651)
		(layer "In13.Cu")
		(net "P5E_PEX1_STN5_TX_C_DN<92>")
	)
	(segment
		(start 137.306558 -358.04856)
		(end 137.597388 -357.75773)
		(width 0.1651)
		(layer "In13.Cu")
		(net "P5E_PEX1_STN5_TX_C_DN<92>")
	)
	(segment
		(start 126.278894 -367.912396)
		(end 136.873996 -359.565194)
		(width 0.1651)
		(layer "In13.Cu")
		(net "P5E_PEX1_STN5_TX_C_DN<92>")
	)
	(segment
		(start 137.121646 -33.95218)
		(end 136.801352 -33.631886)
		(width 0.13462)
		(layer "F.Cu")
		(net "P5E_PEX1_STN2_TX_DN<47>")
	)
	(segment
		(start 138.047476 -33.657286)
		(end 137.752582 -33.95218)
		(width 0.13462)
		(layer "F.Cu")
		(net "P5E_PEX1_STN2_TX_DN<47>")
	)
	(segment
		(start 137.752582 -33.95218)
		(end 137.121646 -33.95218)
		(width 0.13462)
		(layer "F.Cu")
		(net "P5E_PEX1_STN2_TX_DN<47>")
	)
	(segment
		(start 138.470386 -33.948116)
		(end 138.873484 -33.948116)
		(width 0.1651)
		(layer "In11.Cu")
		(net "P5E_PEX1_STN2_TX_DN<47>")
	)
	(segment
		(start 152.518618 -62.636908)
		(end 151.659082 -78.909926)
		(width 0.1651)
		(layer "In11.Cu")
		(net "P5E_PEX1_STN2_TX_DN<47>")
	)
	(segment
		(start 159.18307 -264.507726)
		(end 160.215834 -270.728694)
		(width 0.1651)
		(layer "In11.Cu")
		(net "P5E_PEX1_STN2_TX_DN<47>")
	)
	(segment
		(start 138.873484 -33.948116)
		(end 139.296648 -34.151316)
		(width 0.1651)
		(layer "In11.Cu")
		(net "P5E_PEX1_STN2_TX_DN<47>")
	)
	(segment
		(start 138.047476 -33.657286)
		(end 138.245088 -33.854898)
		(width 0.1651)
		(layer "In11.Cu")
		(net "P5E_PEX1_STN2_TX_DN<47>")
	)
	(segment
		(start 151.840184 -50.623724)
		(end 152.518618 -62.636908)
		(width 0.1651)
		(layer "In11.Cu")
		(net "P5E_PEX1_STN2_TX_DN<47>")
	)
	(segment
		(start 160.273746 -278.229568)
		(end 160.435544 -278.229568)
		(width 0.1143)
		(layer "In11.Cu")
		(net "P5E_PEX1_STN2_TX_DN<47>")
	)
	(segment
		(start 160.215834 -271.427448)
		(end 160.170114 -271.473168)
		(width 0.1143)
		(layer "In11.Cu")
		(net "P5E_PEX1_STN2_TX_DN<47>")
	)
	(segment
		(start 147.983956 -138.226292)
		(end 159.18307 -264.507726)
		(width 0.1651)
		(layer "In11.Cu")
		(net "P5E_PEX1_STN2_TX_DN<47>")
	)
	(segment
		(start 160.215834 -270.728694)
		(end 160.215834 -271.399)
		(width 0.1651)
		(layer "In11.Cu")
		(net "P5E_PEX1_STN2_TX_DN<47>")
	)
	(segment
		(start 147.470368 -117.07495)
		(end 147.983956 -138.226292)
		(width 0.1651)
		(layer "In11.Cu")
		(net "P5E_PEX1_STN2_TX_DN<47>")
	)
	(segment
		(start 151.659082 -78.909926)
		(end 148.143214 -104.589834)
		(width 0.1651)
		(layer "In11.Cu")
		(net "P5E_PEX1_STN2_TX_DN<47>")
	)
	(segment
		(start 148.143214 -104.589834)
		(end 147.470368 -117.07495)
		(width 0.1651)
		(layer "In11.Cu")
		(net "P5E_PEX1_STN2_TX_DN<47>")
	)
	(segment
		(start 160.435544 -278.229568)
		(end 160.549844 -278.115268)
		(width 0.1143)
		(layer "In11.Cu")
		(net "P5E_PEX1_STN2_TX_DN<47>")
	)
	(segment
		(start 151.3459 -49.197768)
		(end 151.840184 -50.623724)
		(width 0.1651)
		(layer "In11.Cu")
		(net "P5E_PEX1_STN2_TX_DN<47>")
	)
	(segment
		(start 160.170114 -271.473168)
		(end 160.170114 -278.125936)
		(width 0.1143)
		(layer "In11.Cu")
		(net "P5E_PEX1_STN2_TX_DN<47>")
	)
	(segment
		(start 160.170114 -278.125936)
		(end 160.273746 -278.229568)
		(width 0.1143)
		(layer "In11.Cu")
		(net "P5E_PEX1_STN2_TX_DN<47>")
	)
	(segment
		(start 139.296648 -34.151316)
		(end 140.594334 -35.183572)
		(width 0.1651)
		(layer "In11.Cu")
		(net "P5E_PEX1_STN2_TX_DN<47>")
	)
	(segment
		(start 160.215834 -271.399)
		(end 160.215834 -271.427448)
		(width 0.1143)
		(layer "In11.Cu")
		(net "P5E_PEX1_STN2_TX_DN<47>")
	)
	(segment
		(start 160.549844 -278.115268)
		(end 160.549844 -277.849838)
		(width 0.1143)
		(layer "In11.Cu")
		(net "P5E_PEX1_STN2_TX_DN<47>")
	)
	(segment
		(start 138.245088 -33.854898)
		(end 138.470386 -33.948116)
		(width 0.1651)
		(layer "In11.Cu")
		(net "P5E_PEX1_STN2_TX_DN<47>")
	)
	(segment
		(start 150.321772 -47.342298)
		(end 151.3459 -49.197768)
		(width 0.1651)
		(layer "In11.Cu")
		(net "P5E_PEX1_STN2_TX_DN<47>")
	)
	(segment
		(start 140.594334 -35.183572)
		(end 150.321772 -47.342298)
		(width 0.1651)
		(layer "In11.Cu")
		(net "P5E_PEX1_STN2_TX_DN<47>")
	)
	(segment
		(start 315.43752 -121.0818)
		(end 315.128148 -121.391172)
		(width 0.13462)
		(layer "F.Cu")
		(net "P5E_PEX2_STN0_TX_DP<1>")
	)
	(segment
		(start 316.374272 -121.365772)
		(end 316.0903 -121.0818)
		(width 0.13462)
		(layer "F.Cu")
		(net "P5E_PEX2_STN0_TX_DP<1>")
	)
	(segment
		(start 316.0903 -121.0818)
		(end 315.43752 -121.0818)
		(width 0.13462)
		(layer "F.Cu")
		(net "P5E_PEX2_STN0_TX_DP<1>")
	)
	(segment
		(start 317.21679 -121.074942)
		(end 317.66637 -121.524522)
		(width 0.1651)
		(layer "In9.Cu")
		(net "P5E_PEX2_STN0_TX_DP<1>")
	)
	(segment
		(start 307.6448 -286.779462)
		(end 307.429408 -286.994854)
		(width 0.1143)
		(layer "In9.Cu")
		(net "P5E_PEX2_STN0_TX_DP<1>")
	)
	(segment
		(start 320.059558 -126.18466)
		(end 320.004694 -126.317502)
		(width 0.1651)
		(layer "In9.Cu")
		(net "P5E_PEX2_STN0_TX_DP<1>")
	)
	(segment
		(start 318.576706 -122.86996)
		(end 318.751712 -123.292616)
		(width 0.1651)
		(layer "In9.Cu")
		(net "P5E_PEX2_STN0_TX_DP<1>")
	)
	(segment
		(start 317.611252 -221.635828)
		(end 320.062606 -249.726958)
		(width 0.1651)
		(layer "In9.Cu")
		(net "P5E_PEX2_STN0_TX_DP<1>")
	)
	(segment
		(start 322.517262 -131.734306)
		(end 322.517008 -131.734306)
		(width 0.1651)
		(layer "In9.Cu")
		(net "P5E_PEX2_STN0_TX_DP<1>")
	)
	(segment
		(start 320.740532 -127.827786)
		(end 320.915284 -128.249934)
		(width 0.1651)
		(layer "In9.Cu")
		(net "P5E_PEX2_STN0_TX_DP<1>")
	)
	(segment
		(start 316.093602 -286.733742)
		(end 316.065154 -286.733742)
		(width 0.1143)
		(layer "In9.Cu")
		(net "P5E_PEX2_STN0_TX_DP<1>")
	)
	(segment
		(start 317.780924 -286.733742)
		(end 316.093602 -286.733742)
		(width 0.1651)
		(layer "In9.Cu")
		(net "P5E_PEX2_STN0_TX_DP<1>")
	)
	(segment
		(start 316.665102 -121.074942)
		(end 317.21679 -121.074942)
		(width 0.1651)
		(layer "In9.Cu")
		(net "P5E_PEX2_STN0_TX_DP<1>")
	)
	(segment
		(start 320.487548 -127.21717)
		(end 320.432684 -127.350012)
		(width 0.1651)
		(layer "In9.Cu")
		(net "P5E_PEX2_STN0_TX_DP<1>")
	)
	(segment
		(start 320.004694 -126.317502)
		(end 320.1797 -126.740158)
		(width 0.1651)
		(layer "In9.Cu")
		(net "P5E_PEX2_STN0_TX_DP<1>")
	)
	(segment
		(start 330.8604 -160.780222)
		(end 322.237354 -175.723042)
		(width 0.1651)
		(layer "In9.Cu")
		(net "P5E_PEX2_STN0_TX_DP<1>")
	)
	(segment
		(start 317.608966 -221.611444)
		(end 317.610998 -221.635828)
		(width 0.1651)
		(layer "In9.Cu")
		(net "P5E_PEX2_STN0_TX_DP<1>")
	)
	(segment
		(start 320.312796 -126.795022)
		(end 320.312542 -126.795022)
		(width 0.1651)
		(layer "In9.Cu")
		(net "P5E_PEX2_STN0_TX_DP<1>")
	)
	(segment
		(start 319.631822 -125.15215)
		(end 319.576958 -125.284738)
		(width 0.1651)
		(layer "In9.Cu")
		(net "P5E_PEX2_STN0_TX_DP<1>")
	)
	(segment
		(start 331.121766 -152.507442)
		(end 331.121766 -159.802068)
		(width 0.1651)
		(layer "In9.Cu")
		(net "P5E_PEX2_STN0_TX_DP<1>")
	)
	(segment
		(start 330.127102 -276.212046)
		(end 320.895726 -285.443422)
		(width 0.1651)
		(layer "In9.Cu")
		(net "P5E_PEX2_STN0_TX_DP<1>")
	)
	(segment
		(start 320.312542 -126.795022)
		(end 320.487294 -127.21717)
		(width 0.1651)
		(layer "In9.Cu")
		(net "P5E_PEX2_STN0_TX_DP<1>")
	)
	(segment
		(start 322.246752 -131.463796)
		(end 322.517262 -131.734306)
		(width 0.1651)
		(layer "In9.Cu")
		(net "P5E_PEX2_STN0_TX_DP<1>")
	)
	(segment
		(start 319.751964 -125.707394)
		(end 319.88506 -125.762512)
		(width 0.1651)
		(layer "In9.Cu")
		(net "P5E_PEX2_STN0_TX_DP<1>")
	)
	(segment
		(start 330.585826 -266.04087)
		(end 331.202538 -267.52931)
		(width 0.1651)
		(layer "In9.Cu")
		(net "P5E_PEX2_STN0_TX_DP<1>")
	)
	(segment
		(start 316.374272 -121.365772)
		(end 316.665102 -121.074942)
		(width 0.1651)
		(layer "In9.Cu")
		(net "P5E_PEX2_STN0_TX_DP<1>")
	)
	(segment
		(start 320.487294 -127.21717)
		(end 320.487548 -127.21717)
		(width 0.1651)
		(layer "In9.Cu")
		(net "P5E_PEX2_STN0_TX_DP<1>")
	)
	(segment
		(start 318.63157 -122.737118)
		(end 318.576706 -122.86996)
		(width 0.1651)
		(layer "In9.Cu")
		(net "P5E_PEX2_STN0_TX_DP<1>")
	)
	(segment
		(start 331.121766 -159.802068)
		(end 330.8604 -160.780222)
		(width 0.1651)
		(layer "In9.Cu")
		(net "P5E_PEX2_STN0_TX_DP<1>")
	)
	(segment
		(start 316.019434 -286.779462)
		(end 307.6448 -286.779462)
		(width 0.1143)
		(layer "In9.Cu")
		(net "P5E_PEX2_STN0_TX_DP<1>")
	)
	(segment
		(start 322.517008 -131.734306)
		(end 331.121766 -152.507442)
		(width 0.1651)
		(layer "In9.Cu")
		(net "P5E_PEX2_STN0_TX_DP<1>")
	)
	(segment
		(start 307.315108 -287.349946)
		(end 307.049678 -287.349946)
		(width 0.1143)
		(layer "In9.Cu")
		(net "P5E_PEX2_STN0_TX_DP<1>")
	)
	(segment
		(start 320.86042 -128.382776)
		(end 321.035426 -128.805432)
		(width 0.1651)
		(layer "In9.Cu")
		(net "P5E_PEX2_STN0_TX_DP<1>")
	)
	(segment
		(start 329.969114 -264.552176)
		(end 330.585826 -266.04087)
		(width 0.1651)
		(layer "In9.Cu")
		(net "P5E_PEX2_STN0_TX_DP<1>")
	)
	(segment
		(start 321.596004 -129.89306)
		(end 322.246752 -131.463796)
		(width 0.1651)
		(layer "In9.Cu")
		(net "P5E_PEX2_STN0_TX_DP<1>")
	)
	(segment
		(start 307.429408 -286.994854)
		(end 307.429408 -287.235646)
		(width 0.1143)
		(layer "In9.Cu")
		(net "P5E_PEX2_STN0_TX_DP<1>")
	)
	(segment
		(start 318.456818 -122.31497)
		(end 318.63157 -122.737118)
		(width 0.1651)
		(layer "In9.Cu")
		(net "P5E_PEX2_STN0_TX_DP<1>")
	)
	(segment
		(start 320.432684 -127.350012)
		(end 320.60769 -127.772668)
		(width 0.1651)
		(layer "In9.Cu")
		(net "P5E_PEX2_STN0_TX_DP<1>")
	)
	(segment
		(start 318.884554 -123.347734)
		(end 319.631822 -125.15215)
		(width 0.1651)
		(layer "In9.Cu")
		(net "P5E_PEX2_STN0_TX_DP<1>")
	)
	(segment
		(start 320.895726 -285.443422)
		(end 317.780924 -286.733742)
		(width 0.1651)
		(layer "In9.Cu")
		(net "P5E_PEX2_STN0_TX_DP<1>")
	)
	(segment
		(start 319.884806 -125.762512)
		(end 320.059558 -126.18466)
		(width 0.1651)
		(layer "In9.Cu")
		(net "P5E_PEX2_STN0_TX_DP<1>")
	)
	(segment
		(start 319.88506 -125.762512)
		(end 319.884806 -125.762512)
		(width 0.1651)
		(layer "In9.Cu")
		(net "P5E_PEX2_STN0_TX_DP<1>")
	)
	(segment
		(start 331.202538 -267.52931)
		(end 331.642466 -272.553176)
		(width 0.1651)
		(layer "In9.Cu")
		(net "P5E_PEX2_STN0_TX_DP<1>")
	)
	(segment
		(start 321.288156 -129.41554)
		(end 321.463162 -129.838196)
		(width 0.1651)
		(layer "In9.Cu")
		(net "P5E_PEX2_STN0_TX_DP<1>")
	)
	(segment
		(start 319.576958 -125.284738)
		(end 319.751964 -125.707394)
		(width 0.1651)
		(layer "In9.Cu")
		(net "P5E_PEX2_STN0_TX_DP<1>")
	)
	(segment
		(start 317.66637 -121.668286)
		(end 317.989966 -121.991882)
		(width 0.1651)
		(layer "In9.Cu")
		(net "P5E_PEX2_STN0_TX_DP<1>")
	)
	(segment
		(start 318.13373 -121.991882)
		(end 318.456818 -122.31497)
		(width 0.1651)
		(layer "In9.Cu")
		(net "P5E_PEX2_STN0_TX_DP<1>")
	)
	(segment
		(start 320.1797 -126.740158)
		(end 320.312796 -126.795022)
		(width 0.1651)
		(layer "In9.Cu")
		(net "P5E_PEX2_STN0_TX_DP<1>")
	)
	(segment
		(start 307.429408 -287.235646)
		(end 307.315108 -287.349946)
		(width 0.1143)
		(layer "In9.Cu")
		(net "P5E_PEX2_STN0_TX_DP<1>")
	)
	(segment
		(start 316.065154 -286.733742)
		(end 316.019434 -286.779462)
		(width 0.1143)
		(layer "In9.Cu")
		(net "P5E_PEX2_STN0_TX_DP<1>")
	)
	(segment
		(start 321.34302 -129.282698)
		(end 321.288156 -129.41554)
		(width 0.1651)
		(layer "In9.Cu")
		(net "P5E_PEX2_STN0_TX_DP<1>")
	)
	(segment
		(start 317.610998 -221.635828)
		(end 317.611252 -221.635828)
		(width 0.1651)
		(layer "In9.Cu")
		(net "P5E_PEX2_STN0_TX_DP<1>")
	)
	(segment
		(start 321.035426 -128.805432)
		(end 321.168268 -128.86055)
		(width 0.1651)
		(layer "In9.Cu")
		(net "P5E_PEX2_STN0_TX_DP<1>")
	)
	(segment
		(start 321.168268 -128.86055)
		(end 321.34302 -129.282698)
		(width 0.1651)
		(layer "In9.Cu")
		(net "P5E_PEX2_STN0_TX_DP<1>")
	)
	(segment
		(start 320.915284 -128.249934)
		(end 320.86042 -128.382776)
		(width 0.1651)
		(layer "In9.Cu")
		(net "P5E_PEX2_STN0_TX_DP<1>")
	)
	(segment
		(start 321.596258 -129.89306)
		(end 321.596004 -129.89306)
		(width 0.1651)
		(layer "In9.Cu")
		(net "P5E_PEX2_STN0_TX_DP<1>")
	)
	(segment
		(start 317.989966 -121.991882)
		(end 318.13373 -121.991882)
		(width 0.1651)
		(layer "In9.Cu")
		(net "P5E_PEX2_STN0_TX_DP<1>")
	)
	(segment
		(start 317.66637 -121.524522)
		(end 317.66637 -121.668286)
		(width 0.1651)
		(layer "In9.Cu")
		(net "P5E_PEX2_STN0_TX_DP<1>")
	)
	(segment
		(start 320.062606 -249.726958)
		(end 329.969114 -264.552176)
		(width 0.1651)
		(layer "In9.Cu")
		(net "P5E_PEX2_STN0_TX_DP<1>")
	)
	(segment
		(start 318.751712 -123.292616)
		(end 318.884554 -123.347734)
		(width 0.1651)
		(layer "In9.Cu")
		(net "P5E_PEX2_STN0_TX_DP<1>")
	)
	(segment
		(start 321.463162 -129.838196)
		(end 321.596258 -129.89306)
		(width 0.1651)
		(layer "In9.Cu")
		(net "P5E_PEX2_STN0_TX_DP<1>")
	)
	(segment
		(start 331.642466 -272.553176)
		(end 330.127102 -276.212046)
		(width 0.1651)
		(layer "In9.Cu")
		(net "P5E_PEX2_STN0_TX_DP<1>")
	)
	(segment
		(start 321.32651 -179.117498)
		(end 317.608966 -221.611444)
		(width 0.1651)
		(layer "In9.Cu")
		(net "P5E_PEX2_STN0_TX_DP<1>")
	)
	(segment
		(start 320.60769 -127.772668)
		(end 320.740532 -127.827786)
		(width 0.1651)
		(layer "In9.Cu")
		(net "P5E_PEX2_STN0_TX_DP<1>")
	)
	(segment
		(start 322.237354 -175.723042)
		(end 321.32651 -179.117498)
		(width 0.1651)
		(layer "In9.Cu")
		(net "P5E_PEX2_STN0_TX_DP<1>")
	)
	(segment
		(start 280.901902 -349.511874)
		(end 280.901902 -348.88043)
		(width 0.13462)
		(layer "F.Cu")
		(net "P5E_PEX2_STN7_TX_DN<118>")
	)
	(segment
		(start 280.901902 -348.88043)
		(end 281.196542 -348.58579)
		(width 0.13462)
		(layer "F.Cu")
		(net "P5E_PEX2_STN7_TX_DN<118>")
	)
	(segment
		(start 281.221942 -349.831914)
		(end 280.901902 -349.511874)
		(width 0.13462)
		(layer "F.Cu")
		(net "P5E_PEX2_STN7_TX_DN<118>")
	)
	(segment
		(start 256.314956 -316.32906)
		(end 256.44094 -316.303406)
		(width 0.1651)
		(layer "In7.Cu")
		(net "P5E_PEX2_STN7_TX_DN<118>")
	)
	(segment
		(start 256.44094 -316.303406)
		(end 256.74066 -315.851286)
		(width 0.1651)
		(layer "In7.Cu")
		(net "P5E_PEX2_STN7_TX_DN<118>")
	)
	(segment
		(start 275.00453 -336.267552)
		(end 274.964398 -336.131916)
		(width 0.1651)
		(layer "In7.Cu")
		(net "P5E_PEX2_STN7_TX_DN<118>")
	)
	(segment
		(start 257.37312 -314.903104)
		(end 257.346704 -314.772548)
		(width 0.1651)
		(layer "In7.Cu")
		(net "P5E_PEX2_STN7_TX_DN<118>")
	)
	(segment
		(start 256.715006 -315.725302)
		(end 256.988564 -315.312552)
		(width 0.1651)
		(layer "In7.Cu")
		(net "P5E_PEX2_STN7_TX_DN<118>")
	)
	(segment
		(start 267.402818 -306.965858)
		(end 267.814552 -306.965858)
		(width 0.1651)
		(layer "In7.Cu")
		(net "P5E_PEX2_STN7_TX_DN<118>")
	)
	(segment
		(start 259.98551 -310.79186)
		(end 260.580632 -309.893462)
		(width 0.1651)
		(layer "In7.Cu")
		(net "P5E_PEX2_STN7_TX_DN<118>")
	)
	(segment
		(start 255.900682 -316.954154)
		(end 256.314956 -316.32906)
		(width 0.1651)
		(layer "In7.Cu")
		(net "P5E_PEX2_STN7_TX_DN<118>")
	)
	(segment
		(start 257.620262 -314.359798)
		(end 257.760978 -314.33135)
		(width 0.1651)
		(layer "In7.Cu")
		(net "P5E_PEX2_STN7_TX_DN<118>")
	)
	(segment
		(start 260.580632 -309.893462)
		(end 260.58114 -309.892954)
		(width 0.1651)
		(layer "In7.Cu")
		(net "P5E_PEX2_STN7_TX_DN<118>")
	)
	(segment
		(start 258.939792 -312.369454)
		(end 258.939538 -312.369454)
		(width 0.1651)
		(layer "In7.Cu")
		(net "P5E_PEX2_STN7_TX_DN<118>")
	)
	(segment
		(start 274.065238 -307.299868)
		(end 273.799808 -307.299868)
		(width 0.1143)
		(layer "In7.Cu")
		(net "P5E_PEX2_STN7_TX_DN<118>")
	)
	(segment
		(start 255.704594 -324.532244)
		(end 254.78994 -322.323968)
		(width 0.1651)
		(layer "In7.Cu")
		(net "P5E_PEX2_STN7_TX_DN<118>")
	)
	(segment
		(start 274.503642 -335.881726)
		(end 274.368006 -335.922112)
		(width 0.1651)
		(layer "In7.Cu")
		(net "P5E_PEX2_STN7_TX_DN<118>")
	)
	(segment
		(start 280.905712 -347.784674)
		(end 282.460192 -346.230194)
		(width 0.1651)
		(layer "In7.Cu")
		(net "P5E_PEX2_STN7_TX_DN<118>")
	)
	(segment
		(start 258.66598 -312.782458)
		(end 258.939792 -312.369454)
		(width 0.1651)
		(layer "In7.Cu")
		(net "P5E_PEX2_STN7_TX_DN<118>")
	)
	(segment
		(start 260.013958 -310.93283)
		(end 259.98551 -310.79186)
		(width 0.1651)
		(layer "In7.Cu")
		(net "P5E_PEX2_STN7_TX_DN<118>")
	)
	(segment
		(start 259.59943 -311.374536)
		(end 259.599176 -311.374282)
		(width 0.1651)
		(layer "In7.Cu")
		(net "P5E_PEX2_STN7_TX_DN<118>")
	)
	(segment
		(start 257.760978 -314.33135)
		(end 258.035044 -313.918092)
		(width 0.1651)
		(layer "In7.Cu")
		(net "P5E_PEX2_STN7_TX_DN<118>")
	)
	(segment
		(start 259.325872 -311.787032)
		(end 259.59943 -311.374536)
		(width 0.1651)
		(layer "In7.Cu")
		(net "P5E_PEX2_STN7_TX_DN<118>")
	)
	(segment
		(start 274.179538 -307.185568)
		(end 274.065238 -307.299868)
		(width 0.1143)
		(layer "In7.Cu")
		(net "P5E_PEX2_STN7_TX_DN<118>")
	)
	(segment
		(start 259.080254 -312.341006)
		(end 259.35432 -311.927748)
		(width 0.1651)
		(layer "In7.Cu")
		(net "P5E_PEX2_STN7_TX_DN<118>")
	)
	(segment
		(start 258.006342 -313.777376)
		(end 258.2799 -313.364626)
		(width 0.1651)
		(layer "In7.Cu")
		(net "P5E_PEX2_STN7_TX_DN<118>")
	)
	(segment
		(start 267.814552 -306.965858)
		(end 267.843 -306.965858)
		(width 0.1143)
		(layer "In7.Cu")
		(net "P5E_PEX2_STN7_TX_DN<118>")
	)
	(segment
		(start 267.220446 -307.00218)
		(end 267.402818 -306.965858)
		(width 0.1651)
		(layer "In7.Cu")
		(net "P5E_PEX2_STN7_TX_DN<118>")
	)
	(segment
		(start 280.905712 -348.29496)
		(end 280.905712 -347.784674)
		(width 0.1651)
		(layer "In7.Cu")
		(net "P5E_PEX2_STN7_TX_DN<118>")
	)
	(segment
		(start 256.988564 -315.312552)
		(end 257.11912 -315.286136)
		(width 0.1651)
		(layer "In7.Cu")
		(net "P5E_PEX2_STN7_TX_DN<118>")
	)
	(segment
		(start 258.420616 -313.336178)
		(end 258.694682 -312.92292)
		(width 0.1651)
		(layer "In7.Cu")
		(net "P5E_PEX2_STN7_TX_DN<118>")
	)
	(segment
		(start 257.931158 -327.004172)
		(end 255.704594 -324.532244)
		(width 0.1651)
		(layer "In7.Cu")
		(net "P5E_PEX2_STN7_TX_DN<118>")
	)
	(segment
		(start 267.88872 -306.920138)
		(end 274.065238 -306.920138)
		(width 0.1143)
		(layer "In7.Cu")
		(net "P5E_PEX2_STN7_TX_DN<118>")
	)
	(segment
		(start 254.78994 -322.323968)
		(end 254.78994 -319.46469)
		(width 0.1651)
		(layer "In7.Cu")
		(net "P5E_PEX2_STN7_TX_DN<118>")
	)
	(segment
		(start 282.460192 -341.757)
		(end 282.30957 -341.48268)
		(width 0.1651)
		(layer "In7.Cu")
		(net "P5E_PEX2_STN7_TX_DN<118>")
	)
	(segment
		(start 281.196542 -348.58579)
		(end 280.905712 -348.29496)
		(width 0.1651)
		(layer "In7.Cu")
		(net "P5E_PEX2_STN7_TX_DN<118>")
	)
	(segment
		(start 261.25551 -309.531258)
		(end 261.68731 -309.4228)
		(width 0.1651)
		(layer "In7.Cu")
		(net "P5E_PEX2_STN7_TX_DN<118>")
	)
	(segment
		(start 257.346704 -314.772548)
		(end 257.620262 -314.359798)
		(width 0.1651)
		(layer "In7.Cu")
		(net "P5E_PEX2_STN7_TX_DN<118>")
	)
	(segment
		(start 259.740146 -311.345834)
		(end 260.013958 -310.93283)
		(width 0.1651)
		(layer "In7.Cu")
		(net "P5E_PEX2_STN7_TX_DN<118>")
	)
	(segment
		(start 265.552428 -307.693314)
		(end 267.220446 -307.00218)
		(width 0.1651)
		(layer "In7.Cu")
		(net "P5E_PEX2_STN7_TX_DN<118>")
	)
	(segment
		(start 259.35432 -311.927748)
		(end 259.325618 -311.787032)
		(width 0.1651)
		(layer "In7.Cu")
		(net "P5E_PEX2_STN7_TX_DN<118>")
	)
	(segment
		(start 258.939538 -312.369454)
		(end 259.080254 -312.341006)
		(width 0.1651)
		(layer "In7.Cu")
		(net "P5E_PEX2_STN7_TX_DN<118>")
	)
	(segment
		(start 256.74066 -315.851286)
		(end 256.715006 -315.725302)
		(width 0.1651)
		(layer "In7.Cu")
		(net "P5E_PEX2_STN7_TX_DN<118>")
	)
	(segment
		(start 282.30957 -341.48268)
		(end 276.110446 -336.8675)
		(width 0.1651)
		(layer "In7.Cu")
		(net "P5E_PEX2_STN7_TX_DN<118>")
	)
	(segment
		(start 260.58114 -309.892954)
		(end 261.25551 -309.531258)
		(width 0.1651)
		(layer "In7.Cu")
		(net "P5E_PEX2_STN7_TX_DN<118>")
	)
	(segment
		(start 267.843 -306.965858)
		(end 267.88872 -306.920138)
		(width 0.1143)
		(layer "In7.Cu")
		(net "P5E_PEX2_STN7_TX_DN<118>")
	)
	(segment
		(start 258.694682 -312.92292)
		(end 258.66598 -312.782458)
		(width 0.1651)
		(layer "In7.Cu")
		(net "P5E_PEX2_STN7_TX_DN<118>")
	)
	(segment
		(start 261.68731 -309.4228)
		(end 262.97255 -309.4228)
		(width 0.1651)
		(layer "In7.Cu")
		(net "P5E_PEX2_STN7_TX_DN<118>")
	)
	(segment
		(start 254.78994 -319.46469)
		(end 255.900682 -316.954154)
		(width 0.1651)
		(layer "In7.Cu")
		(net "P5E_PEX2_STN7_TX_DN<118>")
	)
	(segment
		(start 274.964398 -336.131916)
		(end 274.503642 -335.881726)
		(width 0.1651)
		(layer "In7.Cu")
		(net "P5E_PEX2_STN7_TX_DN<118>")
	)
	(segment
		(start 276.110446 -336.8675)
		(end 275.00453 -336.267552)
		(width 0.1651)
		(layer "In7.Cu")
		(net "P5E_PEX2_STN7_TX_DN<118>")
	)
	(segment
		(start 257.11912 -315.286136)
		(end 257.37312 -314.903104)
		(width 0.1651)
		(layer "In7.Cu")
		(net "P5E_PEX2_STN7_TX_DN<118>")
	)
	(segment
		(start 262.97255 -309.4228)
		(end 263.31164 -309.35549)
		(width 0.1651)
		(layer "In7.Cu")
		(net "P5E_PEX2_STN7_TX_DN<118>")
	)
	(segment
		(start 259.599176 -311.374282)
		(end 259.740146 -311.345834)
		(width 0.1651)
		(layer "In7.Cu")
		(net "P5E_PEX2_STN7_TX_DN<118>")
	)
	(segment
		(start 259.325618 -311.787032)
		(end 259.325872 -311.787032)
		(width 0.1651)
		(layer "In7.Cu")
		(net "P5E_PEX2_STN7_TX_DN<118>")
	)
	(segment
		(start 274.065238 -306.920138)
		(end 274.179538 -307.034438)
		(width 0.1143)
		(layer "In7.Cu")
		(net "P5E_PEX2_STN7_TX_DN<118>")
	)
	(segment
		(start 274.368006 -335.922112)
		(end 257.931158 -327.004172)
		(width 0.1651)
		(layer "In7.Cu")
		(net "P5E_PEX2_STN7_TX_DN<118>")
	)
	(segment
		(start 258.2799 -313.364626)
		(end 258.420616 -313.336178)
		(width 0.1651)
		(layer "In7.Cu")
		(net "P5E_PEX2_STN7_TX_DN<118>")
	)
	(segment
		(start 274.179538 -307.034438)
		(end 274.179538 -307.185568)
		(width 0.1143)
		(layer "In7.Cu")
		(net "P5E_PEX2_STN7_TX_DN<118>")
	)
	(segment
		(start 282.460192 -346.230194)
		(end 282.460192 -341.757)
		(width 0.1651)
		(layer "In7.Cu")
		(net "P5E_PEX2_STN7_TX_DN<118>")
	)
	(segment
		(start 263.31164 -309.35549)
		(end 265.552428 -307.693314)
		(width 0.1651)
		(layer "In7.Cu")
		(net "P5E_PEX2_STN7_TX_DN<118>")
	)
	(segment
		(start 258.035044 -313.918092)
		(end 258.006342 -313.777376)
		(width 0.1651)
		(layer "In7.Cu")
		(net "P5E_PEX2_STN7_TX_DN<118>")
	)
	(segment
		(start 429.832262 -118.695724)
		(end 429.541686 -118.9863)
		(width 0.13462)
		(layer "F.Cu")
		(net "P5E_PEX3_STN0_TX_DN<0>")
	)
	(segment
		(start 428.902114 -118.9863)
		(end 428.586138 -118.670324)
		(width 0.13462)
		(layer "F.Cu")
		(net "P5E_PEX3_STN0_TX_DN<0>")
	)
	(segment
		(start 429.541686 -118.9863)
		(end 428.902114 -118.9863)
		(width 0.13462)
		(layer "F.Cu")
		(net "P5E_PEX3_STN0_TX_DN<0>")
	)
	(segment
		(start 434.978556 -221.785942)
		(end 437.378602 -249.289316)
		(width 0.1651)
		(layer "In9.Cu")
		(net "P5E_PEX3_STN0_TX_DN<0>")
	)
	(segment
		(start 439.846974 -131.084574)
		(end 448.471544 -151.905462)
		(width 0.1651)
		(layer "In9.Cu")
		(net "P5E_PEX3_STN0_TX_DN<0>")
	)
	(segment
		(start 425.62018 -288.185606)
		(end 425.73448 -288.299906)
		(width 0.1143)
		(layer "In9.Cu")
		(net "P5E_PEX3_STN0_TX_DN<0>")
	)
	(segment
		(start 448.121278 -161.278062)
		(end 439.549286 -176.133252)
		(width 0.1651)
		(layer "In9.Cu")
		(net "P5E_PEX3_STN0_TX_DN<0>")
	)
	(segment
		(start 448.471544 -159.966914)
		(end 448.121278 -161.278062)
		(width 0.1651)
		(layer "In9.Cu")
		(net "P5E_PEX3_STN0_TX_DN<0>")
	)
	(segment
		(start 430.123092 -118.986554)
		(end 432.521868 -118.986554)
		(width 0.1651)
		(layer "In9.Cu")
		(net "P5E_PEX3_STN0_TX_DN<0>")
	)
	(segment
		(start 425.723812 -287.920176)
		(end 425.62018 -288.023808)
		(width 0.1143)
		(layer "In9.Cu")
		(net "P5E_PEX3_STN0_TX_DN<0>")
	)
	(segment
		(start 425.73448 -288.299906)
		(end 425.99991 -288.299906)
		(width 0.1143)
		(layer "In9.Cu")
		(net "P5E_PEX3_STN0_TX_DN<0>")
	)
	(segment
		(start 438.700926 -179.242212)
		(end 434.978556 -221.785942)
		(width 0.1651)
		(layer "In9.Cu")
		(net "P5E_PEX3_STN0_TX_DN<0>")
	)
	(segment
		(start 432.217576 -287.965896)
		(end 432.189128 -287.965896)
		(width 0.1143)
		(layer "In9.Cu")
		(net "P5E_PEX3_STN0_TX_DN<0>")
	)
	(segment
		(start 434.138832 -287.965896)
		(end 432.217576 -287.965896)
		(width 0.1651)
		(layer "In9.Cu")
		(net "P5E_PEX3_STN0_TX_DN<0>")
	)
	(segment
		(start 447.149474 -263.91108)
		(end 447.832734 -265.560556)
		(width 0.1651)
		(layer "In9.Cu")
		(net "P5E_PEX3_STN0_TX_DN<0>")
	)
	(segment
		(start 437.378602 -249.289316)
		(end 447.149474 -263.91108)
		(width 0.1651)
		(layer "In9.Cu")
		(net "P5E_PEX3_STN0_TX_DN<0>")
	)
	(segment
		(start 432.143408 -287.920176)
		(end 425.723812 -287.920176)
		(width 0.1143)
		(layer "In9.Cu")
		(net "P5E_PEX3_STN0_TX_DN<0>")
	)
	(segment
		(start 425.62018 -288.023808)
		(end 425.62018 -288.185606)
		(width 0.1143)
		(layer "In9.Cu")
		(net "P5E_PEX3_STN0_TX_DN<0>")
	)
	(segment
		(start 435.465728 -120.953276)
		(end 439.531506 -130.769106)
		(width 0.1651)
		(layer "In9.Cu")
		(net "P5E_PEX3_STN0_TX_DN<0>")
	)
	(segment
		(start 439.549286 -176.133252)
		(end 438.700926 -179.242212)
		(width 0.1651)
		(layer "In9.Cu")
		(net "P5E_PEX3_STN0_TX_DN<0>")
	)
	(segment
		(start 449.002404 -272.746978)
		(end 447.276474 -276.912578)
		(width 0.1651)
		(layer "In9.Cu")
		(net "P5E_PEX3_STN0_TX_DN<0>")
	)
	(segment
		(start 437.696864 -286.492188)
		(end 434.138832 -287.965896)
		(width 0.1651)
		(layer "In9.Cu")
		(net "P5E_PEX3_STN0_TX_DN<0>")
	)
	(segment
		(start 432.189128 -287.965896)
		(end 432.143408 -287.920176)
		(width 0.1143)
		(layer "In9.Cu")
		(net "P5E_PEX3_STN0_TX_DN<0>")
	)
	(segment
		(start 448.471544 -151.905462)
		(end 448.471544 -159.966914)
		(width 0.1651)
		(layer "In9.Cu")
		(net "P5E_PEX3_STN0_TX_DN<0>")
	)
	(segment
		(start 447.832734 -265.560556)
		(end 448.521836 -267.224002)
		(width 0.1651)
		(layer "In9.Cu")
		(net "P5E_PEX3_STN0_TX_DN<0>")
	)
	(segment
		(start 429.832262 -118.695724)
		(end 430.123092 -118.986554)
		(width 0.1651)
		(layer "In9.Cu")
		(net "P5E_PEX3_STN0_TX_DN<0>")
	)
	(segment
		(start 439.531506 -130.769106)
		(end 439.846974 -131.084574)
		(width 0.1651)
		(layer "In9.Cu")
		(net "P5E_PEX3_STN0_TX_DN<0>")
	)
	(segment
		(start 432.521868 -118.986554)
		(end 435.465728 -120.953276)
		(width 0.1651)
		(layer "In9.Cu")
		(net "P5E_PEX3_STN0_TX_DN<0>")
	)
	(segment
		(start 448.521836 -267.224002)
		(end 448.761104 -269.973044)
		(width 0.1651)
		(layer "In9.Cu")
		(net "P5E_PEX3_STN0_TX_DN<0>")
	)
	(segment
		(start 448.761104 -269.973044)
		(end 449.002404 -272.746978)
		(width 0.1651)
		(layer "In9.Cu")
		(net "P5E_PEX3_STN0_TX_DN<0>")
	)
	(segment
		(start 447.276474 -276.912578)
		(end 437.696864 -286.492188)
		(width 0.1651)
		(layer "In9.Cu")
		(net "P5E_PEX3_STN0_TX_DN<0>")
	)
	(segment
		(start 273.420078 -319.96888)
		(end 273.420078 -316.534292)
		(width 0.1143)
		(layer "In5.Cu")
		(net "P5E_PEX2_STN7_RX_DN<126>")
	)
	(segment
		(start 273.420078 -316.534292)
		(end 273.534378 -316.419992)
		(width 0.1143)
		(layer "In5.Cu")
		(net "P5E_PEX2_STN7_RX_DN<126>")
	)
	(segment
		(start 288.82594 -334.971136)
		(end 277.159212 -328.73188)
		(width 0.1651)
		(layer "In5.Cu")
		(net "P5E_PEX2_STN7_RX_DN<126>")
	)
	(segment
		(start 300.689772 -383.1082)
		(end 300.816772 -382.9812)
		(width 0.1651)
		(layer "In5.Cu")
		(net "P5E_PEX2_STN7_RX_DN<126>")
	)
	(segment
		(start 273.465798 -324.767448)
		(end 273.465798 -320.043048)
		(width 0.1651)
		(layer "In5.Cu")
		(net "P5E_PEX2_STN7_RX_DN<126>")
	)
	(segment
		(start 273.685508 -316.419992)
		(end 273.799808 -316.534292)
		(width 0.1143)
		(layer "In5.Cu")
		(net "P5E_PEX2_STN7_RX_DN<126>")
	)
	(segment
		(start 301.208694 -354.437696)
		(end 301.27194 -354.373942)
		(width 0.1651)
		(layer "In5.Cu")
		(net "P5E_PEX2_STN7_RX_DN<126>")
	)
	(segment
		(start 300.689772 -383.490216)
		(end 300.689772 -383.1082)
		(width 0.1651)
		(layer "In5.Cu")
		(net "P5E_PEX2_STN7_RX_DN<126>")
	)
	(segment
		(start 300.816772 -382.9812)
		(end 301.363888 -382.9812)
		(width 0.1651)
		(layer "In5.Cu")
		(net "P5E_PEX2_STN7_RX_DN<126>")
	)
	(segment
		(start 277.159212 -328.73188)
		(end 275.312886 -327.4568)
		(width 0.1651)
		(layer "In5.Cu")
		(net "P5E_PEX2_STN7_RX_DN<126>")
	)
	(segment
		(start 301.815754 -382.529334)
		(end 301.815754 -367.919)
		(width 0.1651)
		(layer "In5.Cu")
		(net "P5E_PEX2_STN7_RX_DN<126>")
	)
	(segment
		(start 273.87296 -325.720964)
		(end 273.465798 -324.767448)
		(width 0.1651)
		(layer "In5.Cu")
		(net "P5E_PEX2_STN7_RX_DN<126>")
	)
	(segment
		(start 301.268638 -353.878388)
		(end 301.204376 -353.815396)
		(width 0.1651)
		(layer "In5.Cu")
		(net "P5E_PEX2_STN7_RX_DN<126>")
	)
	(segment
		(start 300.569122 -341.251286)
		(end 288.82594 -334.970882)
		(width 0.1651)
		(layer "In5.Cu")
		(net "P5E_PEX2_STN7_RX_DN<126>")
	)
	(segment
		(start 273.465798 -320.0146)
		(end 273.420078 -319.96888)
		(width 0.1143)
		(layer "In5.Cu")
		(net "P5E_PEX2_STN7_RX_DN<126>")
	)
	(segment
		(start 273.534378 -316.419992)
		(end 273.685508 -316.419992)
		(width 0.1143)
		(layer "In5.Cu")
		(net "P5E_PEX2_STN7_RX_DN<126>")
	)
	(segment
		(start 301.27194 -354.373942)
		(end 301.268638 -353.878388)
		(width 0.1651)
		(layer "In5.Cu")
		(net "P5E_PEX2_STN7_RX_DN<126>")
	)
	(segment
		(start 300.932088 -341.795354)
		(end 300.569122 -341.251286)
		(width 0.1651)
		(layer "In5.Cu")
		(net "P5E_PEX2_STN7_RX_DN<126>")
	)
	(segment
		(start 273.799808 -316.534292)
		(end 273.799808 -316.799722)
		(width 0.1143)
		(layer "In5.Cu")
		(net "P5E_PEX2_STN7_RX_DN<126>")
	)
	(segment
		(start 301.253652 -361.32516)
		(end 301.208694 -354.437696)
		(width 0.1651)
		(layer "In5.Cu")
		(net "P5E_PEX2_STN7_RX_DN<126>")
	)
	(segment
		(start 273.465798 -320.043048)
		(end 273.465798 -320.0146)
		(width 0.1143)
		(layer "In5.Cu")
		(net "P5E_PEX2_STN7_RX_DN<126>")
	)
	(segment
		(start 301.363888 -382.9812)
		(end 301.815754 -382.529334)
		(width 0.1651)
		(layer "In5.Cu")
		(net "P5E_PEX2_STN7_RX_DN<126>")
	)
	(segment
		(start 288.82594 -334.970882)
		(end 288.82594 -334.971136)
		(width 0.1651)
		(layer "In5.Cu")
		(net "P5E_PEX2_STN7_RX_DN<126>")
	)
	(segment
		(start 301.130208 -342.441276)
		(end 300.932088 -341.795354)
		(width 0.1651)
		(layer "In5.Cu")
		(net "P5E_PEX2_STN7_RX_DN<126>")
	)
	(segment
		(start 275.312886 -327.4568)
		(end 273.87296 -325.720964)
		(width 0.1651)
		(layer "In5.Cu")
		(net "P5E_PEX2_STN7_RX_DN<126>")
	)
	(segment
		(start 301.204376 -353.815396)
		(end 301.20463 -353.815396)
		(width 0.1651)
		(layer "In5.Cu")
		(net "P5E_PEX2_STN7_RX_DN<126>")
	)
	(segment
		(start 301.815754 -367.919)
		(end 301.253652 -361.32516)
		(width 0.1651)
		(layer "In5.Cu")
		(net "P5E_PEX2_STN7_RX_DN<126>")
	)
	(segment
		(start 301.20463 -353.815396)
		(end 301.130208 -342.441276)
		(width 0.1651)
		(layer "In5.Cu")
		(net "P5E_PEX2_STN7_RX_DN<126>")
	)
	(segment
		(start 135.405368 -32.714184)
		(end 135.101584 -32.4104)
		(width 0.13462)
		(layer "F.Cu")
		(net "P5E_PEX1_STN2_TX_DP<46>")
	)
	(segment
		(start 135.101584 -32.4104)
		(end 134.488428 -32.4104)
		(width 0.13462)
		(layer "F.Cu")
		(net "P5E_PEX1_STN2_TX_DP<46>")
	)
	(segment
		(start 134.488428 -32.4104)
		(end 134.159244 -32.739584)
		(width 0.13462)
		(layer "F.Cu")
		(net "P5E_PEX1_STN2_TX_DP<46>")
	)
	(segment
		(start 160.884108 -271.427448)
		(end 160.929828 -271.473168)
		(width 0.1143)
		(layer "In11.Cu")
		(net "P5E_PEX1_STN2_TX_DP<46>")
	)
	(segment
		(start 137.042144 -32.423354)
		(end 137.42924 -32.423354)
		(width 0.1651)
		(layer "In11.Cu")
		(net "P5E_PEX1_STN2_TX_DP<46>")
	)
	(segment
		(start 136.953244 -32.512254)
		(end 137.042144 -32.423354)
		(width 0.1651)
		(layer "In11.Cu")
		(net "P5E_PEX1_STN2_TX_DP<46>")
	)
	(segment
		(start 160.884108 -271.399)
		(end 160.884108 -271.427448)
		(width 0.1143)
		(layer "In11.Cu")
		(net "P5E_PEX1_STN2_TX_DP<46>")
	)
	(segment
		(start 151.967184 -48.925734)
		(end 152.519888 -50.504344)
		(width 0.1651)
		(layer "In11.Cu")
		(net "P5E_PEX1_STN2_TX_DP<46>")
	)
	(segment
		(start 150.657814 -46.559216)
		(end 151.967184 -48.925734)
		(width 0.1651)
		(layer "In11.Cu")
		(net "P5E_PEX1_STN2_TX_DP<46>")
	)
	(segment
		(start 160.929828 -271.473168)
		(end 160.929828 -280.10485)
		(width 0.1143)
		(layer "In11.Cu")
		(net "P5E_PEX1_STN2_TX_DP<46>")
	)
	(segment
		(start 161.500058 -280.434288)
		(end 161.500058 -280.699718)
		(width 0.1143)
		(layer "In11.Cu")
		(net "P5E_PEX1_STN2_TX_DP<46>")
	)
	(segment
		(start 160.884108 -270.220948)
		(end 160.884108 -271.399)
		(width 0.1651)
		(layer "In11.Cu")
		(net "P5E_PEX1_STN2_TX_DP<46>")
	)
	(segment
		(start 137.42924 -32.423354)
		(end 140.322046 -33.620456)
		(width 0.1651)
		(layer "In11.Cu")
		(net "P5E_PEX1_STN2_TX_DP<46>")
	)
	(segment
		(start 153.261822 -62.965838)
		(end 152.37714 -78.744572)
		(width 0.1651)
		(layer "In11.Cu")
		(net "P5E_PEX1_STN2_TX_DP<46>")
	)
	(segment
		(start 152.37714 -78.744572)
		(end 148.798788 -104.937814)
		(width 0.1651)
		(layer "In11.Cu")
		(net "P5E_PEX1_STN2_TX_DP<46>")
	)
	(segment
		(start 161.385758 -280.319988)
		(end 161.500058 -280.434288)
		(width 0.1143)
		(layer "In11.Cu")
		(net "P5E_PEX1_STN2_TX_DP<46>")
	)
	(segment
		(start 148.195792 -116.818664)
		(end 148.658834 -138.17854)
		(width 0.1651)
		(layer "In11.Cu")
		(net "P5E_PEX1_STN2_TX_DP<46>")
	)
	(segment
		(start 136.369044 -32.423354)
		(end 136.457944 -32.512254)
		(width 0.1651)
		(layer "In11.Cu")
		(net "P5E_PEX1_STN2_TX_DP<46>")
	)
	(segment
		(start 140.322046 -33.620456)
		(end 150.657814 -46.559216)
		(width 0.1651)
		(layer "In11.Cu")
		(net "P5E_PEX1_STN2_TX_DP<46>")
	)
	(segment
		(start 148.798788 -104.937814)
		(end 148.195792 -116.818664)
		(width 0.1651)
		(layer "In11.Cu")
		(net "P5E_PEX1_STN2_TX_DP<46>")
	)
	(segment
		(start 159.878522 -264.559288)
		(end 160.884108 -270.220948)
		(width 0.1651)
		(layer "In11.Cu")
		(net "P5E_PEX1_STN2_TX_DP<46>")
	)
	(segment
		(start 136.457944 -32.512254)
		(end 136.953244 -32.512254)
		(width 0.1651)
		(layer "In11.Cu")
		(net "P5E_PEX1_STN2_TX_DP<46>")
	)
	(segment
		(start 161.144966 -280.319988)
		(end 161.385758 -280.319988)
		(width 0.1143)
		(layer "In11.Cu")
		(net "P5E_PEX1_STN2_TX_DP<46>")
	)
	(segment
		(start 148.658834 -138.17854)
		(end 159.878522 -264.559288)
		(width 0.1651)
		(layer "In11.Cu")
		(net "P5E_PEX1_STN2_TX_DP<46>")
	)
	(segment
		(start 135.405368 -32.714184)
		(end 135.696198 -32.423354)
		(width 0.1651)
		(layer "In11.Cu")
		(net "P5E_PEX1_STN2_TX_DP<46>")
	)
	(segment
		(start 152.519888 -50.504344)
		(end 153.261822 -62.965838)
		(width 0.1651)
		(layer "In11.Cu")
		(net "P5E_PEX1_STN2_TX_DP<46>")
	)
	(segment
		(start 160.929828 -280.10485)
		(end 161.144966 -280.319988)
		(width 0.1143)
		(layer "In11.Cu")
		(net "P5E_PEX1_STN2_TX_DP<46>")
	)
	(segment
		(start 135.696198 -32.423354)
		(end 136.369044 -32.423354)
		(width 0.1651)
		(layer "In11.Cu")
		(net "P5E_PEX1_STN2_TX_DP<46>")
	)
	(segment
		(start 127.381508 -349.831914)
		(end 127.701548 -349.511874)
		(width 0.13462)
		(layer "F.Cu")
		(net "P5E_PEX1_STN6_TX_DP<104>")
	)
	(segment
		(start 127.701548 -349.511874)
		(end 127.701548 -348.88043)
		(width 0.13462)
		(layer "F.Cu")
		(net "P5E_PEX1_STN6_TX_DP<104>")
	)
	(segment
		(start 127.701548 -348.88043)
		(end 127.406908 -348.58579)
		(width 0.13462)
		(layer "F.Cu")
		(net "P5E_PEX1_STN6_TX_DP<104>")
	)
	(segment
		(start 141.980158 -333.285338)
		(end 132.561584 -337.186524)
		(width 0.1651)
		(layer "In13.Cu")
		(net "P5E_PEX1_STN6_TX_DP<104>")
	)
	(segment
		(start 165.633908 -320.063114)
		(end 165.633908 -323.107304)
		(width 0.1651)
		(layer "In13.Cu")
		(net "P5E_PEX1_STN6_TX_DP<104>")
	)
	(segment
		(start 127.697738 -347.541342)
		(end 127.697738 -348.29496)
		(width 0.1651)
		(layer "In13.Cu")
		(net "P5E_PEX1_STN6_TX_DP<104>")
	)
	(segment
		(start 162.378644 -326.362568)
		(end 158.32836 -328.790554)
		(width 0.1651)
		(layer "In13.Cu")
		(net "P5E_PEX1_STN6_TX_DP<104>")
	)
	(segment
		(start 166.135558 -313.379612)
		(end 165.894766 -313.379612)
		(width 0.1143)
		(layer "In13.Cu")
		(net "P5E_PEX1_STN6_TX_DP<104>")
	)
	(segment
		(start 145.938748 -333.285338)
		(end 141.980158 -333.285338)
		(width 0.1651)
		(layer "In13.Cu")
		(net "P5E_PEX1_STN6_TX_DP<104>")
	)
	(segment
		(start 165.679628 -313.59475)
		(end 165.679628 -319.995296)
		(width 0.1143)
		(layer "In13.Cu")
		(net "P5E_PEX1_STN6_TX_DP<104>")
	)
	(segment
		(start 165.633908 -323.107304)
		(end 162.378644 -326.362568)
		(width 0.1651)
		(layer "In13.Cu")
		(net "P5E_PEX1_STN6_TX_DP<104>")
	)
	(segment
		(start 129.252218 -345.986862)
		(end 127.697738 -347.541342)
		(width 0.1651)
		(layer "In13.Cu")
		(net "P5E_PEX1_STN6_TX_DP<104>")
	)
	(segment
		(start 158.32836 -328.790554)
		(end 148.892768 -332.698852)
		(width 0.1651)
		(layer "In13.Cu")
		(net "P5E_PEX1_STN6_TX_DP<104>")
	)
	(segment
		(start 127.697738 -348.29496)
		(end 127.406908 -348.58579)
		(width 0.1651)
		(layer "In13.Cu")
		(net "P5E_PEX1_STN6_TX_DP<104>")
	)
	(segment
		(start 165.633908 -320.041016)
		(end 165.633908 -320.063114)
		(width 0.1143)
		(layer "In13.Cu")
		(net "P5E_PEX1_STN6_TX_DP<104>")
	)
	(segment
		(start 166.249858 -312.999882)
		(end 166.249858 -313.265312)
		(width 0.1143)
		(layer "In13.Cu")
		(net "P5E_PEX1_STN6_TX_DP<104>")
	)
	(segment
		(start 132.561584 -337.186524)
		(end 129.252218 -340.49589)
		(width 0.1651)
		(layer "In13.Cu")
		(net "P5E_PEX1_STN6_TX_DP<104>")
	)
	(segment
		(start 129.252218 -340.49589)
		(end 129.252218 -345.986862)
		(width 0.1651)
		(layer "In13.Cu")
		(net "P5E_PEX1_STN6_TX_DP<104>")
	)
	(segment
		(start 166.249858 -313.265312)
		(end 166.135558 -313.379612)
		(width 0.1143)
		(layer "In13.Cu")
		(net "P5E_PEX1_STN6_TX_DP<104>")
	)
	(segment
		(start 165.679628 -319.995296)
		(end 165.633908 -320.041016)
		(width 0.1143)
		(layer "In13.Cu")
		(net "P5E_PEX1_STN6_TX_DP<104>")
	)
	(segment
		(start 165.894766 -313.379612)
		(end 165.679628 -313.59475)
		(width 0.1143)
		(layer "In13.Cu")
		(net "P5E_PEX1_STN6_TX_DP<104>")
	)
	(segment
		(start 148.892768 -332.698852)
		(end 145.938748 -333.285338)
		(width 0.1651)
		(layer "In13.Cu")
		(net "P5E_PEX1_STN6_TX_DP<104>")
	)
	(segment
		(start 316.374272 -120.502172)
		(end 316.068964 -120.80748)
		(width 0.13462)
		(layer "F.Cu")
		(net "P5E_PEX2_STN0_TX_DN<1>")
	)
	(segment
		(start 315.458856 -120.80748)
		(end 315.128148 -120.476772)
		(width 0.13462)
		(layer "F.Cu")
		(net "P5E_PEX2_STN0_TX_DN<1>")
	)
	(segment
		(start 316.068964 -120.80748)
		(end 315.458856 -120.80748)
		(width 0.13462)
		(layer "F.Cu")
		(net "P5E_PEX2_STN0_TX_DN<1>")
	)
	(segment
		(start 320.337434 -249.630438)
		(end 330.21905 -264.418572)
		(width 0.1651)
		(layer "In9.Cu")
		(net "P5E_PEX2_STN0_TX_DN<1>")
	)
	(segment
		(start 331.12329 -160.888934)
		(end 322.500244 -175.832008)
		(width 0.1651)
		(layer "In9.Cu")
		(net "P5E_PEX2_STN0_TX_DN<1>")
	)
	(segment
		(start 307.619908 -287.073848)
		(end 307.619908 -287.235646)
		(width 0.1143)
		(layer "In9.Cu")
		(net "P5E_PEX2_STN0_TX_DN<1>")
	)
	(segment
		(start 317.33363 -120.793002)
		(end 318.695832 -122.155204)
		(width 0.1651)
		(layer "In9.Cu")
		(net "P5E_PEX2_STN0_TX_DN<1>")
	)
	(segment
		(start 321.055492 -285.682436)
		(end 317.837058 -287.015682)
		(width 0.1651)
		(layer "In9.Cu")
		(net "P5E_PEX2_STN0_TX_DN<1>")
	)
	(segment
		(start 322.500244 -175.832008)
		(end 321.605402 -179.166774)
		(width 0.1651)
		(layer "In9.Cu")
		(net "P5E_PEX2_STN0_TX_DN<1>")
	)
	(segment
		(start 331.929486 -272.597372)
		(end 330.366116 -276.371812)
		(width 0.1651)
		(layer "In9.Cu")
		(net "P5E_PEX2_STN0_TX_DN<1>")
	)
	(segment
		(start 316.019434 -286.969962)
		(end 307.723794 -286.969962)
		(width 0.1143)
		(layer "In9.Cu")
		(net "P5E_PEX2_STN0_TX_DN<1>")
	)
	(segment
		(start 307.723794 -286.969962)
		(end 307.619908 -287.073848)
		(width 0.1143)
		(layer "In9.Cu")
		(net "P5E_PEX2_STN0_TX_DN<1>")
	)
	(segment
		(start 331.479652 -267.461492)
		(end 331.929486 -272.597372)
		(width 0.1651)
		(layer "In9.Cu")
		(net "P5E_PEX2_STN0_TX_DN<1>")
	)
	(segment
		(start 318.695832 -122.155204)
		(end 322.485766 -131.30403)
		(width 0.1651)
		(layer "In9.Cu")
		(net "P5E_PEX2_STN0_TX_DN<1>")
	)
	(segment
		(start 330.366116 -276.371812)
		(end 321.055492 -285.682436)
		(width 0.1651)
		(layer "In9.Cu")
		(net "P5E_PEX2_STN0_TX_DN<1>")
	)
	(segment
		(start 316.065154 -287.015682)
		(end 316.019434 -286.969962)
		(width 0.1143)
		(layer "In9.Cu")
		(net "P5E_PEX2_STN0_TX_DN<1>")
	)
	(segment
		(start 330.21905 -264.418572)
		(end 331.479652 -267.461492)
		(width 0.1651)
		(layer "In9.Cu")
		(net "P5E_PEX2_STN0_TX_DN<1>")
	)
	(segment
		(start 317.892176 -221.611444)
		(end 320.337434 -249.630438)
		(width 0.1651)
		(layer "In9.Cu")
		(net "P5E_PEX2_STN0_TX_DN<1>")
	)
	(segment
		(start 317.837058 -287.015682)
		(end 316.093602 -287.015682)
		(width 0.1651)
		(layer "In9.Cu")
		(net "P5E_PEX2_STN0_TX_DN<1>")
	)
	(segment
		(start 322.756276 -131.57454)
		(end 331.403706 -152.451308)
		(width 0.1651)
		(layer "In9.Cu")
		(net "P5E_PEX2_STN0_TX_DN<1>")
	)
	(segment
		(start 321.605402 -179.166774)
		(end 317.892176 -221.611444)
		(width 0.1651)
		(layer "In9.Cu")
		(net "P5E_PEX2_STN0_TX_DN<1>")
	)
	(segment
		(start 322.485766 -131.30403)
		(end 322.756276 -131.57454)
		(width 0.1651)
		(layer "In9.Cu")
		(net "P5E_PEX2_STN0_TX_DN<1>")
	)
	(segment
		(start 307.734208 -287.349946)
		(end 307.999892 -287.349946)
		(width 0.1143)
		(layer "In9.Cu")
		(net "P5E_PEX2_STN0_TX_DN<1>")
	)
	(segment
		(start 316.374272 -120.502172)
		(end 316.665102 -120.793002)
		(width 0.1651)
		(layer "In9.Cu")
		(net "P5E_PEX2_STN0_TX_DN<1>")
	)
	(segment
		(start 331.403706 -152.451308)
		(end 331.403706 -159.839152)
		(width 0.1651)
		(layer "In9.Cu")
		(net "P5E_PEX2_STN0_TX_DN<1>")
	)
	(segment
		(start 307.619908 -287.235646)
		(end 307.734208 -287.349946)
		(width 0.1143)
		(layer "In9.Cu")
		(net "P5E_PEX2_STN0_TX_DN<1>")
	)
	(segment
		(start 316.665102 -120.793002)
		(end 317.33363 -120.793002)
		(width 0.1651)
		(layer "In9.Cu")
		(net "P5E_PEX2_STN0_TX_DN<1>")
	)
	(segment
		(start 331.403706 -159.839152)
		(end 331.12329 -160.888934)
		(width 0.1651)
		(layer "In9.Cu")
		(net "P5E_PEX2_STN0_TX_DN<1>")
	)
	(segment
		(start 316.093602 -287.015682)
		(end 316.065154 -287.015682)
		(width 0.1143)
		(layer "In9.Cu")
		(net "P5E_PEX2_STN0_TX_DN<1>")
	)
	(segment
		(start 322.124324 -348.88043)
		(end 321.829684 -348.58579)
		(width 0.13462)
		(layer "F.Cu")
		(net "P5E_PEX2_STN6_TX_DP<107>")
	)
	(segment
		(start 322.124324 -349.511874)
		(end 322.124324 -348.88043)
		(width 0.13462)
		(layer "F.Cu")
		(net "P5E_PEX2_STN6_TX_DP<107>")
	)
	(segment
		(start 321.804284 -349.831914)
		(end 322.124324 -349.511874)
		(width 0.13462)
		(layer "F.Cu")
		(net "P5E_PEX2_STN6_TX_DP<107>")
	)
	(segment
		(start 314.388246 -336.870294)
		(end 283.749242 -330.833222)
		(width 0.1651)
		(layer "In13.Cu")
		(net "P5E_PEX2_STN6_TX_DP<107>")
	)
	(segment
		(start 283.749242 -330.833222)
		(end 279.818084 -326.902064)
		(width 0.1651)
		(layer "In13.Cu")
		(net "P5E_PEX2_STN6_TX_DP<107>")
	)
	(segment
		(start 323.674994 -342.17737)
		(end 322.596764 -340.660736)
		(width 0.1651)
		(layer "In13.Cu")
		(net "P5E_PEX2_STN6_TX_DP<107>")
	)
	(segment
		(start 278.883872 -324.646798)
		(end 278.883872 -319.995296)
		(width 0.1651)
		(layer "In13.Cu")
		(net "P5E_PEX2_STN6_TX_DP<107>")
	)
	(segment
		(start 322.596764 -340.660736)
		(end 314.388246 -336.870294)
		(width 0.1651)
		(layer "In13.Cu")
		(net "P5E_PEX2_STN6_TX_DP<107>")
	)
	(segment
		(start 321.829684 -348.58579)
		(end 322.120514 -348.29496)
		(width 0.1651)
		(layer "In13.Cu")
		(net "P5E_PEX2_STN6_TX_DP<107>")
	)
	(segment
		(start 278.929592 -319.921128)
		(end 278.929592 -311.69483)
		(width 0.1143)
		(layer "In13.Cu")
		(net "P5E_PEX2_STN6_TX_DP<107>")
	)
	(segment
		(start 279.14473 -311.479692)
		(end 279.385522 -311.479692)
		(width 0.1143)
		(layer "In13.Cu")
		(net "P5E_PEX2_STN6_TX_DP<107>")
	)
	(segment
		(start 278.883872 -319.966848)
		(end 278.929592 -319.921128)
		(width 0.1143)
		(layer "In13.Cu")
		(net "P5E_PEX2_STN6_TX_DP<107>")
	)
	(segment
		(start 279.499822 -311.365392)
		(end 279.499822 -311.099962)
		(width 0.1143)
		(layer "In13.Cu")
		(net "P5E_PEX2_STN6_TX_DP<107>")
	)
	(segment
		(start 279.818084 -326.902064)
		(end 278.883872 -324.646798)
		(width 0.1651)
		(layer "In13.Cu")
		(net "P5E_PEX2_STN6_TX_DP<107>")
	)
	(segment
		(start 278.929592 -311.69483)
		(end 279.14473 -311.479692)
		(width 0.1143)
		(layer "In13.Cu")
		(net "P5E_PEX2_STN6_TX_DP<107>")
	)
	(segment
		(start 322.120514 -348.29496)
		(end 322.120514 -347.667834)
		(width 0.1651)
		(layer "In13.Cu")
		(net "P5E_PEX2_STN6_TX_DP<107>")
	)
	(segment
		(start 322.120514 -347.667834)
		(end 323.674994 -346.113354)
		(width 0.1651)
		(layer "In13.Cu")
		(net "P5E_PEX2_STN6_TX_DP<107>")
	)
	(segment
		(start 279.385522 -311.479692)
		(end 279.499822 -311.365392)
		(width 0.1143)
		(layer "In13.Cu")
		(net "P5E_PEX2_STN6_TX_DP<107>")
	)
	(segment
		(start 278.883872 -319.995296)
		(end 278.883872 -319.966848)
		(width 0.1143)
		(layer "In13.Cu")
		(net "P5E_PEX2_STN6_TX_DP<107>")
	)
	(segment
		(start 323.674994 -346.113354)
		(end 323.674994 -342.17737)
		(width 0.1651)
		(layer "In13.Cu")
		(net "P5E_PEX2_STN6_TX_DP<107>")
	)
	(segment
		(start 384.947922 -101.6762)
		(end 385.281424 -102.009702)
		(width 0.13462)
		(layer "F.Cu")
		(net "P5E_PEX3_STN1_TX_DP<17>")
	)
	(segment
		(start 384.0353 -101.984302)
		(end 384.343402 -101.6762)
		(width 0.13462)
		(layer "F.Cu")
		(net "P5E_PEX3_STN1_TX_DP<17>")
	)
	(segment
		(start 384.343402 -101.6762)
		(end 384.947922 -101.6762)
		(width 0.13462)
		(layer "F.Cu")
		(net "P5E_PEX3_STN1_TX_DP<17>")
	)
	(segment
		(start 408.565858 -271.526)
		(end 408.565858 -265.72464)
		(width 0.1651)
		(layer "In9.Cu")
		(net "P5E_PEX3_STN1_TX_DP<17>")
	)
	(segment
		(start 382.18618 -102.57155)
		(end 382.18618 -102.44582)
		(width 0.1651)
		(layer "In9.Cu")
		(net "P5E_PEX3_STN1_TX_DP<17>")
	)
	(segment
		(start 377.042172 -108.472478)
		(end 377.175014 -108.417614)
		(width 0.1651)
		(layer "In9.Cu")
		(net "P5E_PEX3_STN1_TX_DP<17>")
	)
	(segment
		(start 408.520138 -271.600168)
		(end 408.565858 -271.554448)
		(width 0.1143)
		(layer "In9.Cu")
		(net "P5E_PEX3_STN1_TX_DP<17>")
	)
	(segment
		(start 372.339362 -145.063718)
		(end 369.754912 -138.823954)
		(width 0.1651)
		(layer "In9.Cu")
		(net "P5E_PEX3_STN1_TX_DP<17>")
	)
	(segment
		(start 383.296922 -101.693472)
		(end 383.74447 -101.693472)
		(width 0.1651)
		(layer "In9.Cu")
		(net "P5E_PEX3_STN1_TX_DP<17>")
	)
	(segment
		(start 377.309634 -107.827064)
		(end 377.666504 -106.965496)
		(width 0.1651)
		(layer "In9.Cu")
		(net "P5E_PEX3_STN1_TX_DP<17>")
	)
	(segment
		(start 383.74447 -101.693472)
		(end 384.0353 -101.984302)
		(width 0.1651)
		(layer "In9.Cu")
		(net "P5E_PEX3_STN1_TX_DP<17>")
	)
	(segment
		(start 377.364752 -107.959652)
		(end 377.309634 -107.827064)
		(width 0.1651)
		(layer "In9.Cu")
		(net "P5E_PEX3_STN1_TX_DP<17>")
	)
	(segment
		(start 381.71882 -102.91318)
		(end 381.84455 -102.91318)
		(width 0.1651)
		(layer "In9.Cu")
		(net "P5E_PEX3_STN1_TX_DP<17>")
	)
	(segment
		(start 375.671334 -111.782098)
		(end 375.803922 -111.72698)
		(width 0.1651)
		(layer "In9.Cu")
		(net "P5E_PEX3_STN1_TX_DP<17>")
	)
	(segment
		(start 381.377698 -103.254302)
		(end 381.71882 -102.91318)
		(width 0.1651)
		(layer "In9.Cu")
		(net "P5E_PEX3_STN1_TX_DP<17>")
	)
	(segment
		(start 373.055896 -159.643064)
		(end 372.339362 -145.063718)
		(width 0.1651)
		(layer "In9.Cu")
		(net "P5E_PEX3_STN1_TX_DP<17>")
	)
	(segment
		(start 380.066296 -104.565704)
		(end 380.21006 -104.565704)
		(width 0.1651)
		(layer "In9.Cu")
		(net "P5E_PEX3_STN1_TX_DP<17>")
	)
	(segment
		(start 376.395742 -110.033308)
		(end 376.585226 -109.575854)
		(width 0.1651)
		(layer "In9.Cu")
		(net "P5E_PEX3_STN1_TX_DP<17>")
	)
	(segment
		(start 408.899868 -279.749504)
		(end 408.899868 -280.015188)
		(width 0.1143)
		(layer "In9.Cu")
		(net "P5E_PEX3_STN1_TX_DP<17>")
	)
	(segment
		(start 379.716284 -104.915716)
		(end 380.066296 -104.565704)
		(width 0.1651)
		(layer "In9.Cu")
		(net "P5E_PEX3_STN1_TX_DP<17>")
	)
	(segment
		(start 377.042172 -108.472732)
		(end 377.042172 -108.472478)
		(width 0.1651)
		(layer "In9.Cu")
		(net "P5E_PEX3_STN1_TX_DP<17>")
	)
	(segment
		(start 379.716284 -105.05948)
		(end 379.716284 -104.915716)
		(width 0.1651)
		(layer "In9.Cu")
		(net "P5E_PEX3_STN1_TX_DP<17>")
	)
	(segment
		(start 376.12828 -110.678976)
		(end 376.260868 -110.623858)
		(width 0.1651)
		(layer "In9.Cu")
		(net "P5E_PEX3_STN1_TX_DP<17>")
	)
	(segment
		(start 381.377698 -103.380032)
		(end 381.377698 -103.254302)
		(width 0.1651)
		(layer "In9.Cu")
		(net "P5E_PEX3_STN1_TX_DP<17>")
	)
	(segment
		(start 382.685036 -101.946964)
		(end 383.296922 -101.693472)
		(width 0.1651)
		(layer "In9.Cu")
		(net "P5E_PEX3_STN1_TX_DP<17>")
	)
	(segment
		(start 376.585226 -109.575854)
		(end 376.717814 -109.520736)
		(width 0.1651)
		(layer "In9.Cu")
		(net "P5E_PEX3_STN1_TX_DP<17>")
	)
	(segment
		(start 379.222 -105.41)
		(end 379.365764 -105.41)
		(width 0.1651)
		(layer "In9.Cu")
		(net "P5E_PEX3_STN1_TX_DP<17>")
	)
	(segment
		(start 379.365764 -105.41)
		(end 379.716284 -105.05948)
		(width 0.1651)
		(layer "In9.Cu")
		(net "P5E_PEX3_STN1_TX_DP<17>")
	)
	(segment
		(start 378.871988 -105.903776)
		(end 378.871988 -105.760012)
		(width 0.1651)
		(layer "In9.Cu")
		(net "P5E_PEX3_STN1_TX_DP<17>")
	)
	(segment
		(start 380.56058 -104.215184)
		(end 380.56058 -104.07142)
		(width 0.1651)
		(layer "In9.Cu")
		(net "P5E_PEX3_STN1_TX_DP<17>")
	)
	(segment
		(start 381.036068 -103.721408)
		(end 381.377698 -103.380032)
		(width 0.1651)
		(layer "In9.Cu")
		(net "P5E_PEX3_STN1_TX_DP<17>")
	)
	(segment
		(start 369.754912 -138.823954)
		(end 369.754912 -130.86207)
		(width 0.1651)
		(layer "In9.Cu")
		(net "P5E_PEX3_STN1_TX_DP<17>")
	)
	(segment
		(start 408.520138 -280.025856)
		(end 408.520138 -271.600168)
		(width 0.1143)
		(layer "In9.Cu")
		(net "P5E_PEX3_STN1_TX_DP<17>")
	)
	(segment
		(start 408.565858 -265.72464)
		(end 373.620538 -162.482276)
		(width 0.1651)
		(layer "In9.Cu")
		(net "P5E_PEX3_STN1_TX_DP<17>")
	)
	(segment
		(start 376.45086 -110.16615)
		(end 376.395742 -110.033308)
		(width 0.1651)
		(layer "In9.Cu")
		(net "P5E_PEX3_STN1_TX_DP<17>")
	)
	(segment
		(start 375.938796 -111.13643)
		(end 376.12828 -110.678976)
		(width 0.1651)
		(layer "In9.Cu")
		(net "P5E_PEX3_STN1_TX_DP<17>")
	)
	(segment
		(start 376.260868 -110.623858)
		(end 376.45086 -110.16615)
		(width 0.1651)
		(layer "In9.Cu")
		(net "P5E_PEX3_STN1_TX_DP<17>")
	)
	(segment
		(start 376.907806 -109.063028)
		(end 376.852688 -108.930186)
		(width 0.1651)
		(layer "In9.Cu")
		(net "P5E_PEX3_STN1_TX_DP<17>")
	)
	(segment
		(start 369.754912 -130.86207)
		(end 375.191782 -112.93983)
		(width 0.1651)
		(layer "In9.Cu")
		(net "P5E_PEX3_STN1_TX_DP<17>")
	)
	(segment
		(start 377.666504 -106.965496)
		(end 378.377704 -106.254296)
		(width 0.1651)
		(layer "In9.Cu")
		(net "P5E_PEX3_STN1_TX_DP<17>")
	)
	(segment
		(start 382.18618 -102.44582)
		(end 382.685036 -101.946964)
		(width 0.1651)
		(layer "In9.Cu")
		(net "P5E_PEX3_STN1_TX_DP<17>")
	)
	(segment
		(start 377.175014 -108.417614)
		(end 377.364752 -107.959652)
		(width 0.1651)
		(layer "In9.Cu")
		(net "P5E_PEX3_STN1_TX_DP<17>")
	)
	(segment
		(start 378.521468 -106.254296)
		(end 378.871988 -105.903776)
		(width 0.1651)
		(layer "In9.Cu")
		(net "P5E_PEX3_STN1_TX_DP<17>")
	)
	(segment
		(start 375.803922 -111.72698)
		(end 375.993914 -111.269272)
		(width 0.1651)
		(layer "In9.Cu")
		(net "P5E_PEX3_STN1_TX_DP<17>")
	)
	(segment
		(start 376.852688 -108.930186)
		(end 377.042172 -108.472732)
		(width 0.1651)
		(layer "In9.Cu")
		(net "P5E_PEX3_STN1_TX_DP<17>")
	)
	(segment
		(start 376.717814 -109.520736)
		(end 376.907806 -109.063028)
		(width 0.1651)
		(layer "In9.Cu")
		(net "P5E_PEX3_STN1_TX_DP<17>")
	)
	(segment
		(start 381.84455 -102.91318)
		(end 382.18618 -102.57155)
		(width 0.1651)
		(layer "In9.Cu")
		(net "P5E_PEX3_STN1_TX_DP<17>")
	)
	(segment
		(start 378.871988 -105.760012)
		(end 379.222 -105.41)
		(width 0.1651)
		(layer "In9.Cu")
		(net "P5E_PEX3_STN1_TX_DP<17>")
	)
	(segment
		(start 373.620538 -162.482276)
		(end 373.055896 -159.643064)
		(width 0.1651)
		(layer "In9.Cu")
		(net "P5E_PEX3_STN1_TX_DP<17>")
	)
	(segment
		(start 380.21006 -104.565704)
		(end 380.56058 -104.215184)
		(width 0.1651)
		(layer "In9.Cu")
		(net "P5E_PEX3_STN1_TX_DP<17>")
	)
	(segment
		(start 408.62377 -280.129488)
		(end 408.520138 -280.025856)
		(width 0.1143)
		(layer "In9.Cu")
		(net "P5E_PEX3_STN1_TX_DP<17>")
	)
	(segment
		(start 375.191782 -112.93983)
		(end 375.671334 -111.782098)
		(width 0.1651)
		(layer "In9.Cu")
		(net "P5E_PEX3_STN1_TX_DP<17>")
	)
	(segment
		(start 380.56058 -104.07142)
		(end 380.910592 -103.721408)
		(width 0.1651)
		(layer "In9.Cu")
		(net "P5E_PEX3_STN1_TX_DP<17>")
	)
	(segment
		(start 378.377704 -106.254296)
		(end 378.521468 -106.254296)
		(width 0.1651)
		(layer "In9.Cu")
		(net "P5E_PEX3_STN1_TX_DP<17>")
	)
	(segment
		(start 375.993914 -111.269272)
		(end 375.938796 -111.13643)
		(width 0.1651)
		(layer "In9.Cu")
		(net "P5E_PEX3_STN1_TX_DP<17>")
	)
	(segment
		(start 408.785568 -280.129488)
		(end 408.62377 -280.129488)
		(width 0.1143)
		(layer "In9.Cu")
		(net "P5E_PEX3_STN1_TX_DP<17>")
	)
	(segment
		(start 408.899868 -280.015188)
		(end 408.785568 -280.129488)
		(width 0.1143)
		(layer "In9.Cu")
		(net "P5E_PEX3_STN1_TX_DP<17>")
	)
	(segment
		(start 380.910592 -103.721408)
		(end 381.036068 -103.721408)
		(width 0.1651)
		(layer "In9.Cu")
		(net "P5E_PEX3_STN1_TX_DP<17>")
	)
	(segment
		(start 408.565858 -271.554448)
		(end 408.565858 -271.526)
		(width 0.1143)
		(layer "In9.Cu")
		(net "P5E_PEX3_STN1_TX_DP<17>")
	)
	(segment
		(start 290.815776 -368.709448)
		(end 290.815776 -383.629154)
		(width 0.1651)
		(layer "In5.Cu")
		(net "P5E_PEX2_STN7_RX_DP<121>")
	)
	(segment
		(start 289.816794 -384.08102)
		(end 289.689794 -384.20802)
		(width 0.1651)
		(layer "In5.Cu")
		(net "P5E_PEX2_STN7_RX_DP<121>")
	)
	(segment
		(start 267.589 -317.792608)
		(end 268.14272 -320.496438)
		(width 0.1651)
		(layer "In5.Cu")
		(net "P5E_PEX2_STN7_RX_DP<121>")
	)
	(segment
		(start 284.99308 -340.35746)
		(end 285.569152 -341.79256)
		(width 0.1651)
		(layer "In5.Cu")
		(net "P5E_PEX2_STN7_RX_DP<121>")
	)
	(segment
		(start 272.249646 -331.759814)
		(end 284.99308 -340.35746)
		(width 0.1651)
		(layer "In5.Cu")
		(net "P5E_PEX2_STN7_RX_DP<121>")
	)
	(segment
		(start 269.619984 -310.264048)
		(end 269.619984 -310.494172)
		(width 0.1143)
		(layer "In5.Cu")
		(net "P5E_PEX2_STN7_RX_DP<121>")
	)
	(segment
		(start 285.569152 -341.79256)
		(end 285.569152 -358.05364)
		(width 0.1651)
		(layer "In5.Cu")
		(net "P5E_PEX2_STN7_RX_DP<121>")
	)
	(segment
		(start 268.602206 -310.85155)
		(end 268.602206 -310.916574)
		(width 0.1143)
		(layer "In5.Cu")
		(net "P5E_PEX2_STN7_RX_DP<121>")
	)
	(segment
		(start 268.58214 -310.93664)
		(end 267.589 -311.92978)
		(width 0.1651)
		(layer "In5.Cu")
		(net "P5E_PEX2_STN7_RX_DP<121>")
	)
	(segment
		(start 267.589 -311.92978)
		(end 267.589 -317.792608)
		(width 0.1651)
		(layer "In5.Cu")
		(net "P5E_PEX2_STN7_RX_DP<121>")
	)
	(segment
		(start 285.569152 -358.05364)
		(end 290.815776 -368.709448)
		(width 0.1651)
		(layer "In5.Cu")
		(net "P5E_PEX2_STN7_RX_DP<121>")
	)
	(segment
		(start 289.689794 -384.20802)
		(end 289.689794 -384.590036)
		(width 0.1651)
		(layer "In5.Cu")
		(net "P5E_PEX2_STN7_RX_DP<121>")
	)
	(segment
		(start 269.619984 -310.494172)
		(end 269.394178 -310.719978)
		(width 0.1143)
		(layer "In5.Cu")
		(net "P5E_PEX2_STN7_RX_DP<121>")
	)
	(segment
		(start 268.733778 -310.719978)
		(end 268.602206 -310.85155)
		(width 0.1143)
		(layer "In5.Cu")
		(net "P5E_PEX2_STN7_RX_DP<121>")
	)
	(segment
		(start 269.999714 -310.149748)
		(end 269.734284 -310.149748)
		(width 0.1143)
		(layer "In5.Cu")
		(net "P5E_PEX2_STN7_RX_DP<121>")
	)
	(segment
		(start 269.734284 -310.149748)
		(end 269.619984 -310.264048)
		(width 0.1143)
		(layer "In5.Cu")
		(net "P5E_PEX2_STN7_RX_DP<121>")
	)
	(segment
		(start 290.36391 -384.08102)
		(end 289.816794 -384.08102)
		(width 0.1651)
		(layer "In5.Cu")
		(net "P5E_PEX2_STN7_RX_DP<121>")
	)
	(segment
		(start 269.394178 -310.719978)
		(end 268.733778 -310.719978)
		(width 0.1143)
		(layer "In5.Cu")
		(net "P5E_PEX2_STN7_RX_DP<121>")
	)
	(segment
		(start 269.554198 -328.61504)
		(end 272.249646 -331.759814)
		(width 0.1651)
		(layer "In5.Cu")
		(net "P5E_PEX2_STN7_RX_DP<121>")
	)
	(segment
		(start 268.602206 -310.916574)
		(end 268.58214 -310.93664)
		(width 0.1143)
		(layer "In5.Cu")
		(net "P5E_PEX2_STN7_RX_DP<121>")
	)
	(segment
		(start 268.14272 -325.265796)
		(end 269.554198 -328.61504)
		(width 0.1651)
		(layer "In5.Cu")
		(net "P5E_PEX2_STN7_RX_DP<121>")
	)
	(segment
		(start 290.815776 -383.629154)
		(end 290.36391 -384.08102)
		(width 0.1651)
		(layer "In5.Cu")
		(net "P5E_PEX2_STN7_RX_DP<121>")
	)
	(segment
		(start 268.14272 -320.496438)
		(end 268.14272 -325.265796)
		(width 0.1651)
		(layer "In5.Cu")
		(net "P5E_PEX2_STN7_RX_DP<121>")
	)
	(segment
		(start 134.193788 -355.026722)
		(end 134.488428 -354.732082)
		(width 0.13462)
		(layer "F.Cu")
		(net "P5E_PEX1_STN5_TX_DN<83>")
	)
	(segment
		(start 134.193788 -355.658166)
		(end 134.193788 -355.026722)
		(width 0.13462)
		(layer "F.Cu")
		(net "P5E_PEX1_STN5_TX_DN<83>")
	)
	(segment
		(start 134.513828 -355.978206)
		(end 134.193788 -355.658166)
		(width 0.13462)
		(layer "F.Cu")
		(net "P5E_PEX1_STN5_TX_DN<83>")
	)
	(segment
		(start 177.384456 -313.570112)
		(end 177.535586 -313.570112)
		(width 0.1143)
		(layer "In7.Cu")
		(net "P5E_PEX1_STN5_TX_DN<83>")
	)
	(segment
		(start 177.649886 -313.684412)
		(end 177.649886 -313.949842)
		(width 0.1143)
		(layer "In7.Cu")
		(net "P5E_PEX1_STN5_TX_DN<83>")
	)
	(segment
		(start 173.932088 -328.158602)
		(end 176.408842 -325.681848)
		(width 0.1651)
		(layer "In7.Cu")
		(net "P5E_PEX1_STN5_TX_DN<83>")
	)
	(segment
		(start 135.752078 -352.268282)
		(end 135.752078 -341.430102)
		(width 0.1651)
		(layer "In7.Cu")
		(net "P5E_PEX1_STN5_TX_DN<83>")
	)
	(segment
		(start 134.197598 -354.441252)
		(end 134.197598 -353.822762)
		(width 0.1651)
		(layer "In7.Cu")
		(net "P5E_PEX1_STN5_TX_DN<83>")
	)
	(segment
		(start 177.315876 -323.492114)
		(end 177.315876 -320.002408)
		(width 0.1651)
		(layer "In7.Cu")
		(net "P5E_PEX1_STN5_TX_DN<83>")
	)
	(segment
		(start 136.952736 -340.5251)
		(end 153.468324 -335.515204)
		(width 0.1651)
		(layer "In7.Cu")
		(net "P5E_PEX1_STN5_TX_DN<83>")
	)
	(segment
		(start 177.315876 -320.002408)
		(end 177.315876 -319.97396)
		(width 0.1143)
		(layer "In7.Cu")
		(net "P5E_PEX1_STN5_TX_DN<83>")
	)
	(segment
		(start 135.752078 -341.430102)
		(end 136.214612 -340.967568)
		(width 0.1651)
		(layer "In7.Cu")
		(net "P5E_PEX1_STN5_TX_DN<83>")
	)
	(segment
		(start 176.408842 -325.681848)
		(end 177.315876 -323.492114)
		(width 0.1651)
		(layer "In7.Cu")
		(net "P5E_PEX1_STN5_TX_DN<83>")
	)
	(segment
		(start 170.05046 -330.485242)
		(end 173.932088 -328.158602)
		(width 0.1651)
		(layer "In7.Cu")
		(net "P5E_PEX1_STN5_TX_DN<83>")
	)
	(segment
		(start 153.46807 -335.515204)
		(end 170.05046 -330.485242)
		(width 0.1651)
		(layer "In7.Cu")
		(net "P5E_PEX1_STN5_TX_DN<83>")
	)
	(segment
		(start 136.214612 -340.967568)
		(end 136.952736 -340.5251)
		(width 0.1651)
		(layer "In7.Cu")
		(net "P5E_PEX1_STN5_TX_DN<83>")
	)
	(segment
		(start 177.535586 -313.570112)
		(end 177.649886 -313.684412)
		(width 0.1143)
		(layer "In7.Cu")
		(net "P5E_PEX1_STN5_TX_DN<83>")
	)
	(segment
		(start 177.270156 -313.684412)
		(end 177.384456 -313.570112)
		(width 0.1143)
		(layer "In7.Cu")
		(net "P5E_PEX1_STN5_TX_DN<83>")
	)
	(segment
		(start 134.488428 -354.732082)
		(end 134.197598 -354.441252)
		(width 0.1651)
		(layer "In7.Cu")
		(net "P5E_PEX1_STN5_TX_DN<83>")
	)
	(segment
		(start 177.270156 -319.92824)
		(end 177.270156 -313.684412)
		(width 0.1143)
		(layer "In7.Cu")
		(net "P5E_PEX1_STN5_TX_DN<83>")
	)
	(segment
		(start 153.468324 -335.515204)
		(end 153.46807 -335.515204)
		(width 0.1651)
		(layer "In7.Cu")
		(net "P5E_PEX1_STN5_TX_DN<83>")
	)
	(segment
		(start 177.315876 -319.97396)
		(end 177.270156 -319.92824)
		(width 0.1143)
		(layer "In7.Cu")
		(net "P5E_PEX1_STN5_TX_DN<83>")
	)
	(segment
		(start 134.197598 -353.822762)
		(end 135.752078 -352.268282)
		(width 0.1651)
		(layer "In7.Cu")
		(net "P5E_PEX1_STN5_TX_DN<83>")
	)
	(segment
		(start 187.352432 -343.365582)
		(end 187.352432 -342.734138)
		(width 0.13462)
		(layer "F.Cu")
		(net "P5E_PEX1_STN7_TX_DP<124>")
	)
	(segment
		(start 187.032392 -343.685622)
		(end 187.352432 -343.365582)
		(width 0.13462)
		(layer "F.Cu")
		(net "P5E_PEX1_STN7_TX_DP<124>")
	)
	(segment
		(start 187.352432 -342.734138)
		(end 187.057792 -342.439498)
		(width 0.13462)
		(layer "F.Cu")
		(net "P5E_PEX1_STN7_TX_DP<124>")
	)
	(segment
		(start 155.62961 -322.48475)
		(end 155.184094 -321.521836)
		(width 0.1651)
		(layer "In11.Cu")
		(net "P5E_PEX1_STN7_TX_DP<124>")
	)
	(segment
		(start 157.474666 -324.409816)
		(end 155.62961 -322.48475)
		(width 0.1651)
		(layer "In11.Cu")
		(net "P5E_PEX1_STN7_TX_DP<124>")
	)
	(segment
		(start 155.800044 -311.390792)
		(end 155.800044 -311.099962)
		(width 0.1143)
		(layer "In11.Cu")
		(net "P5E_PEX1_STN7_TX_DP<124>")
	)
	(segment
		(start 155.229814 -311.749186)
		(end 155.499308 -311.479692)
		(width 0.1143)
		(layer "In11.Cu")
		(net "P5E_PEX1_STN7_TX_DP<124>")
	)
	(segment
		(start 187.057792 -342.439498)
		(end 187.348622 -342.148668)
		(width 0.1651)
		(layer "In11.Cu")
		(net "P5E_PEX1_STN7_TX_DP<124>")
	)
	(segment
		(start 182.467504 -337.734656)
		(end 175.441864 -333.685896)
		(width 0.1651)
		(layer "In11.Cu")
		(net "P5E_PEX1_STN7_TX_DP<124>")
	)
	(segment
		(start 155.184094 -321.521836)
		(end 155.184094 -320.043048)
		(width 0.1651)
		(layer "In11.Cu")
		(net "P5E_PEX1_STN7_TX_DP<124>")
	)
	(segment
		(start 187.348622 -341.550244)
		(end 186.853068 -340.890098)
		(width 0.1651)
		(layer "In11.Cu")
		(net "P5E_PEX1_STN7_TX_DP<124>")
	)
	(segment
		(start 155.184094 -320.043048)
		(end 155.184094 -320.02095)
		(width 0.1143)
		(layer "In11.Cu")
		(net "P5E_PEX1_STN7_TX_DP<124>")
	)
	(segment
		(start 186.853068 -340.890098)
		(end 182.467504 -337.734656)
		(width 0.1651)
		(layer "In11.Cu")
		(net "P5E_PEX1_STN7_TX_DP<124>")
	)
	(segment
		(start 155.711144 -311.479692)
		(end 155.800044 -311.390792)
		(width 0.1143)
		(layer "In11.Cu")
		(net "P5E_PEX1_STN7_TX_DP<124>")
	)
	(segment
		(start 155.184094 -320.02095)
		(end 155.229814 -319.97523)
		(width 0.1143)
		(layer "In11.Cu")
		(net "P5E_PEX1_STN7_TX_DP<124>")
	)
	(segment
		(start 175.441864 -333.685896)
		(end 157.474666 -324.409816)
		(width 0.1651)
		(layer "In11.Cu")
		(net "P5E_PEX1_STN7_TX_DP<124>")
	)
	(segment
		(start 187.348622 -342.148668)
		(end 187.348622 -341.550244)
		(width 0.1651)
		(layer "In11.Cu")
		(net "P5E_PEX1_STN7_TX_DP<124>")
	)
	(segment
		(start 155.499308 -311.479692)
		(end 155.711144 -311.479692)
		(width 0.1143)
		(layer "In11.Cu")
		(net "P5E_PEX1_STN7_TX_DP<124>")
	)
	(segment
		(start 155.229814 -319.97523)
		(end 155.229814 -311.749186)
		(width 0.1143)
		(layer "In11.Cu")
		(net "P5E_PEX1_STN7_TX_DP<124>")
	)
	(segment
		(start 316.084458 -124.6759)
		(end 315.443362 -124.6759)
		(width 0.13462)
		(layer "F.Cu")
		(net "P5E_PEX2_STN0_TX_DP<3>")
	)
	(segment
		(start 316.374272 -124.965714)
		(end 316.084458 -124.6759)
		(width 0.13462)
		(layer "F.Cu")
		(net "P5E_PEX2_STN0_TX_DP<3>")
	)
	(segment
		(start 315.443362 -124.6759)
		(end 315.128148 -124.991114)
		(width 0.13462)
		(layer "F.Cu")
		(net "P5E_PEX2_STN0_TX_DP<3>")
	)
	(segment
		(start 318.163448 -250.487688)
		(end 328.44867 -265.879326)
		(width 0.1651)
		(layer "In9.Cu")
		(net "P5E_PEX2_STN0_TX_DP<3>")
	)
	(segment
		(start 329.325478 -267.996162)
		(end 329.696572 -272.258028)
		(width 0.1651)
		(layer "In9.Cu")
		(net "P5E_PEX2_STN0_TX_DP<3>")
	)
	(segment
		(start 319.81267 -283.824426)
		(end 317.376556 -284.833568)
		(width 0.1651)
		(layer "In9.Cu")
		(net "P5E_PEX2_STN0_TX_DP<3>")
	)
	(segment
		(start 317.423292 -124.887736)
		(end 317.599314 -125.312932)
		(width 0.1651)
		(layer "In9.Cu")
		(net "P5E_PEX2_STN0_TX_DP<3>")
	)
	(segment
		(start 316.093602 -284.833568)
		(end 316.065154 -284.833568)
		(width 0.1143)
		(layer "In9.Cu")
		(net "P5E_PEX2_STN0_TX_DP<3>")
	)
	(segment
		(start 319.596516 -130.74142)
		(end 319.774062 -131.162552)
		(width 0.1651)
		(layer "In9.Cu")
		(net "P5E_PEX2_STN0_TX_DP<3>")
	)
	(segment
		(start 319.463166 -130.687318)
		(end 319.596516 -130.74142)
		(width 0.1651)
		(layer "In9.Cu")
		(net "P5E_PEX2_STN0_TX_DP<3>")
	)
	(segment
		(start 315.644022 -221.628208)
		(end 318.163448 -250.487688)
		(width 0.1651)
		(layer "In9.Cu")
		(net "P5E_PEX2_STN0_TX_DP<3>")
	)
	(segment
		(start 320.972434 -133.358636)
		(end 320.91757 -133.491224)
		(width 0.1651)
		(layer "In9.Cu")
		(net "P5E_PEX2_STN0_TX_DP<3>")
	)
	(segment
		(start 320.39433 -175.049942)
		(end 319.393316 -178.781202)
		(width 0.1651)
		(layer "In9.Cu")
		(net "P5E_PEX2_STN0_TX_DP<3>")
	)
	(segment
		(start 307.429408 -285.335472)
		(end 307.315108 -285.449772)
		(width 0.1143)
		(layer "In9.Cu")
		(net "P5E_PEX2_STN0_TX_DP<3>")
	)
	(segment
		(start 319.16243 -129.711196)
		(end 319.162176 -129.71145)
		(width 0.1651)
		(layer "In9.Cu")
		(net "P5E_PEX2_STN0_TX_DP<3>")
	)
	(segment
		(start 317.21044 -124.674884)
		(end 317.423292 -124.887736)
		(width 0.1651)
		(layer "In9.Cu")
		(net "P5E_PEX2_STN0_TX_DP<3>")
	)
	(segment
		(start 318.1604 -127.597154)
		(end 318.29375 -127.651256)
		(width 0.1651)
		(layer "In9.Cu")
		(net "P5E_PEX2_STN0_TX_DP<3>")
	)
	(segment
		(start 319.339722 -130.132582)
		(end 319.28562 -130.265678)
		(width 0.1651)
		(layer "In9.Cu")
		(net "P5E_PEX2_STN0_TX_DP<3>")
	)
	(segment
		(start 316.019434 -284.879288)
		(end 307.6448 -284.879288)
		(width 0.1143)
		(layer "In9.Cu")
		(net "P5E_PEX2_STN0_TX_DP<3>")
	)
	(segment
		(start 316.665102 -124.674884)
		(end 317.21044 -124.674884)
		(width 0.1651)
		(layer "In9.Cu")
		(net "P5E_PEX2_STN0_TX_DP<3>")
	)
	(segment
		(start 321.092576 -133.91388)
		(end 321.225418 -133.968998)
		(width 0.1651)
		(layer "In9.Cu")
		(net "P5E_PEX2_STN0_TX_DP<3>")
	)
	(segment
		(start 319.897506 -131.717288)
		(end 320.030856 -131.77139)
		(width 0.1651)
		(layer "In9.Cu")
		(net "P5E_PEX2_STN0_TX_DP<3>")
	)
	(segment
		(start 318.851534 -129.235454)
		(end 319.02908 -129.657094)
		(width 0.1651)
		(layer "In9.Cu")
		(net "P5E_PEX2_STN0_TX_DP<3>")
	)
	(segment
		(start 307.315108 -285.449772)
		(end 307.049678 -285.449772)
		(width 0.1143)
		(layer "In9.Cu")
		(net "P5E_PEX2_STN0_TX_DP<3>")
	)
	(segment
		(start 328.44867 -265.879326)
		(end 329.325478 -267.996162)
		(width 0.1651)
		(layer "In9.Cu")
		(net "P5E_PEX2_STN0_TX_DP<3>")
	)
	(segment
		(start 307.6448 -284.879288)
		(end 307.429408 -285.09468)
		(width 0.1143)
		(layer "In9.Cu")
		(net "P5E_PEX2_STN0_TX_DP<3>")
	)
	(segment
		(start 320.91757 -133.491224)
		(end 321.092576 -133.91388)
		(width 0.1651)
		(layer "In9.Cu")
		(net "P5E_PEX2_STN0_TX_DP<3>")
	)
	(segment
		(start 321.345306 -134.523988)
		(end 321.520312 -134.946644)
		(width 0.1651)
		(layer "In9.Cu")
		(net "P5E_PEX2_STN0_TX_DP<3>")
	)
	(segment
		(start 316.374272 -124.965714)
		(end 316.665102 -124.674884)
		(width 0.1651)
		(layer "In9.Cu")
		(net "P5E_PEX2_STN0_TX_DP<3>")
	)
	(segment
		(start 318.036956 -127.042418)
		(end 317.982854 -127.175514)
		(width 0.1651)
		(layer "In9.Cu")
		(net "P5E_PEX2_STN0_TX_DP<3>")
	)
	(segment
		(start 318.72809 -128.681226)
		(end 318.727836 -128.681226)
		(width 0.1651)
		(layer "In9.Cu")
		(net "P5E_PEX2_STN0_TX_DP<3>")
	)
	(segment
		(start 318.293496 -127.651256)
		(end 318.471042 -128.072388)
		(width 0.1651)
		(layer "In9.Cu")
		(net "P5E_PEX2_STN0_TX_DP<3>")
	)
	(segment
		(start 329.696572 -272.258028)
		(end 328.50709 -275.130006)
		(width 0.1651)
		(layer "In9.Cu")
		(net "P5E_PEX2_STN0_TX_DP<3>")
	)
	(segment
		(start 318.471296 -128.072388)
		(end 318.417194 -128.205484)
		(width 0.1651)
		(layer "In9.Cu")
		(net "P5E_PEX2_STN0_TX_DP<3>")
	)
	(segment
		(start 318.727836 -128.681226)
		(end 318.905382 -129.102358)
		(width 0.1651)
		(layer "In9.Cu")
		(net "P5E_PEX2_STN0_TX_DP<3>")
	)
	(segment
		(start 329.052428 -160.047178)
		(end 320.39433 -175.049942)
		(width 0.1651)
		(layer "In9.Cu")
		(net "P5E_PEX2_STN0_TX_DP<3>")
	)
	(segment
		(start 320.792348 -132.92328)
		(end 320.972434 -133.358636)
		(width 0.1651)
		(layer "In9.Cu")
		(net "P5E_PEX2_STN0_TX_DP<3>")
	)
	(segment
		(start 318.29375 -127.651256)
		(end 318.293496 -127.651256)
		(width 0.1651)
		(layer "In9.Cu")
		(net "P5E_PEX2_STN0_TX_DP<3>")
	)
	(segment
		(start 307.429408 -285.09468)
		(end 307.429408 -285.335472)
		(width 0.1143)
		(layer "In9.Cu")
		(net "P5E_PEX2_STN0_TX_DP<3>")
	)
	(segment
		(start 316.065154 -284.833568)
		(end 316.019434 -284.879288)
		(width 0.1143)
		(layer "In9.Cu")
		(net "P5E_PEX2_STN0_TX_DP<3>")
	)
	(segment
		(start 328.50709 -275.130006)
		(end 319.81267 -283.824426)
		(width 0.1651)
		(layer "In9.Cu")
		(net "P5E_PEX2_STN0_TX_DP<3>")
	)
	(segment
		(start 321.40017 -134.391146)
		(end 321.345306 -134.523988)
		(width 0.1651)
		(layer "In9.Cu")
		(net "P5E_PEX2_STN0_TX_DP<3>")
	)
	(segment
		(start 319.393316 -178.781202)
		(end 315.644022 -221.628208)
		(width 0.1651)
		(layer "In9.Cu")
		(net "P5E_PEX2_STN0_TX_DP<3>")
	)
	(segment
		(start 318.471042 -128.072388)
		(end 318.471296 -128.072388)
		(width 0.1651)
		(layer "In9.Cu")
		(net "P5E_PEX2_STN0_TX_DP<3>")
	)
	(segment
		(start 321.225418 -133.968998)
		(end 321.40017 -134.391146)
		(width 0.1651)
		(layer "In9.Cu")
		(net "P5E_PEX2_STN0_TX_DP<3>")
	)
	(segment
		(start 319.28562 -130.265678)
		(end 319.463166 -130.687318)
		(width 0.1651)
		(layer "In9.Cu")
		(net "P5E_PEX2_STN0_TX_DP<3>")
	)
	(segment
		(start 319.162176 -129.71145)
		(end 319.339722 -130.132582)
		(width 0.1651)
		(layer "In9.Cu")
		(net "P5E_PEX2_STN0_TX_DP<3>")
	)
	(segment
		(start 317.376556 -284.833568)
		(end 316.093602 -284.833568)
		(width 0.1651)
		(layer "In9.Cu")
		(net "P5E_PEX2_STN0_TX_DP<3>")
	)
	(segment
		(start 318.905636 -129.102358)
		(end 318.851534 -129.235454)
		(width 0.1651)
		(layer "In9.Cu")
		(net "P5E_PEX2_STN0_TX_DP<3>")
	)
	(segment
		(start 317.982854 -127.175514)
		(end 318.1604 -127.597154)
		(width 0.1651)
		(layer "In9.Cu")
		(net "P5E_PEX2_STN0_TX_DP<3>")
	)
	(segment
		(start 318.59474 -128.627124)
		(end 318.72809 -128.681226)
		(width 0.1651)
		(layer "In9.Cu")
		(net "P5E_PEX2_STN0_TX_DP<3>")
	)
	(segment
		(start 317.85941 -126.621286)
		(end 318.036956 -127.042418)
		(width 0.1651)
		(layer "In9.Cu")
		(net "P5E_PEX2_STN0_TX_DP<3>")
	)
	(segment
		(start 320.315082 -132.44576)
		(end 320.792348 -132.92328)
		(width 0.1651)
		(layer "In9.Cu")
		(net "P5E_PEX2_STN0_TX_DP<3>")
	)
	(segment
		(start 329.186286 -153.18867)
		(end 329.186286 -159.546544)
		(width 0.1651)
		(layer "In9.Cu")
		(net "P5E_PEX2_STN0_TX_DP<3>")
	)
	(segment
		(start 318.417194 -128.205484)
		(end 318.59474 -128.627124)
		(width 0.1651)
		(layer "In9.Cu")
		(net "P5E_PEX2_STN0_TX_DP<3>")
	)
	(segment
		(start 317.599314 -125.312932)
		(end 317.85941 -126.621286)
		(width 0.1651)
		(layer "In9.Cu")
		(net "P5E_PEX2_STN0_TX_DP<3>")
	)
	(segment
		(start 321.653154 -135.001762)
		(end 329.186286 -153.18867)
		(width 0.1651)
		(layer "In9.Cu")
		(net "P5E_PEX2_STN0_TX_DP<3>")
	)
	(segment
		(start 319.02908 -129.657094)
		(end 319.16243 -129.711196)
		(width 0.1651)
		(layer "In9.Cu")
		(net "P5E_PEX2_STN0_TX_DP<3>")
	)
	(segment
		(start 319.71996 -131.295648)
		(end 319.897506 -131.717288)
		(width 0.1651)
		(layer "In9.Cu")
		(net "P5E_PEX2_STN0_TX_DP<3>")
	)
	(segment
		(start 329.186286 -159.546544)
		(end 329.052428 -160.047178)
		(width 0.1651)
		(layer "In9.Cu")
		(net "P5E_PEX2_STN0_TX_DP<3>")
	)
	(segment
		(start 321.520312 -134.946644)
		(end 321.653154 -135.001762)
		(width 0.1651)
		(layer "In9.Cu")
		(net "P5E_PEX2_STN0_TX_DP<3>")
	)
	(segment
		(start 318.905382 -129.102358)
		(end 318.905636 -129.102358)
		(width 0.1651)
		(layer "In9.Cu")
		(net "P5E_PEX2_STN0_TX_DP<3>")
	)
	(segment
		(start 320.030856 -131.77139)
		(end 320.315082 -132.44576)
		(width 0.1651)
		(layer "In9.Cu")
		(net "P5E_PEX2_STN0_TX_DP<3>")
	)
	(segment
		(start 319.774062 -131.162552)
		(end 319.71996 -131.295648)
		(width 0.1651)
		(layer "In9.Cu")
		(net "P5E_PEX2_STN0_TX_DP<3>")
	)
	(segment
		(start 274.409662 -349.511874)
		(end 274.409662 -348.88043)
		(width 0.13462)
		(layer "F.Cu")
		(net "P5E_PEX2_STN7_TX_DP<115>")
	)
	(segment
		(start 274.409662 -348.88043)
		(end 274.115022 -348.58579)
		(width 0.13462)
		(layer "F.Cu")
		(net "P5E_PEX2_STN7_TX_DP<115>")
	)
	(segment
		(start 274.089622 -349.831914)
		(end 274.409662 -349.511874)
		(width 0.13462)
		(layer "F.Cu")
		(net "P5E_PEX2_STN7_TX_DP<115>")
	)
	(segment
		(start 267.865352 -303.833784)
		(end 267.8938 -303.833784)
		(width 0.1143)
		(layer "In7.Cu")
		(net "P5E_PEX2_STN7_TX_DP<115>")
	)
	(segment
		(start 251.6124 -323.1769)
		(end 251.6124 -318.353948)
		(width 0.1651)
		(layer "In7.Cu")
		(net "P5E_PEX2_STN7_TX_DP<115>")
	)
	(segment
		(start 256.1844 -308.1274)
		(end 258.454398 -305.457606)
		(width 0.1651)
		(layer "In7.Cu")
		(net "P5E_PEX2_STN7_TX_DP<115>")
	)
	(segment
		(start 253.017528 -326.569324)
		(end 252.316488 -324.876414)
		(width 0.1651)
		(layer "In7.Cu")
		(net "P5E_PEX2_STN7_TX_DP<115>")
	)
	(segment
		(start 259.821172 -304.758852)
		(end 262.047482 -304.539396)
		(width 0.1651)
		(layer "In7.Cu")
		(net "P5E_PEX2_STN7_TX_DP<115>")
	)
	(segment
		(start 267.93952 -303.879504)
		(end 276.044152 -303.879504)
		(width 0.1143)
		(layer "In7.Cu")
		(net "P5E_PEX2_STN7_TX_DP<115>")
	)
	(segment
		(start 275.53666 -341.21852)
		(end 274.133818 -339.88883)
		(width 0.1651)
		(layer "In7.Cu")
		(net "P5E_PEX2_STN7_TX_DP<115>")
	)
	(segment
		(start 276.269958 -304.10531)
		(end 276.269958 -304.335434)
		(width 0.1143)
		(layer "In7.Cu")
		(net "P5E_PEX2_STN7_TX_DP<115>")
	)
	(segment
		(start 262.047482 -304.539396)
		(end 266.803124 -303.833784)
		(width 0.1651)
		(layer "In7.Cu")
		(net "P5E_PEX2_STN7_TX_DP<115>")
	)
	(segment
		(start 255.969008 -329.869292)
		(end 253.017528 -326.569324)
		(width 0.1651)
		(layer "In7.Cu")
		(net "P5E_PEX2_STN7_TX_DP<115>")
	)
	(segment
		(start 275.960332 -342.203278)
		(end 275.53666 -341.21852)
		(width 0.1651)
		(layer "In7.Cu")
		(net "P5E_PEX2_STN7_TX_DP<115>")
	)
	(segment
		(start 252.31598 -324.876414)
		(end 251.6124 -323.1769)
		(width 0.1651)
		(layer "In7.Cu")
		(net "P5E_PEX2_STN7_TX_DP<115>")
	)
	(segment
		(start 276.044152 -303.879504)
		(end 276.269958 -304.10531)
		(width 0.1143)
		(layer "In7.Cu")
		(net "P5E_PEX2_STN7_TX_DP<115>")
	)
	(segment
		(start 274.405852 -348.29496)
		(end 274.405852 -347.667834)
		(width 0.1651)
		(layer "In7.Cu")
		(net "P5E_PEX2_STN7_TX_DP<115>")
	)
	(segment
		(start 252.316488 -324.876414)
		(end 252.31598 -324.876414)
		(width 0.1651)
		(layer "In7.Cu")
		(net "P5E_PEX2_STN7_TX_DP<115>")
	)
	(segment
		(start 275.960332 -346.113354)
		(end 275.960332 -342.203278)
		(width 0.1651)
		(layer "In7.Cu")
		(net "P5E_PEX2_STN7_TX_DP<115>")
	)
	(segment
		(start 274.405852 -347.667834)
		(end 275.960332 -346.113354)
		(width 0.1651)
		(layer "In7.Cu")
		(net "P5E_PEX2_STN7_TX_DP<115>")
	)
	(segment
		(start 258.454398 -305.457606)
		(end 258.792472 -305.24069)
		(width 0.1651)
		(layer "In7.Cu")
		(net "P5E_PEX2_STN7_TX_DP<115>")
	)
	(segment
		(start 266.803124 -303.833784)
		(end 267.865352 -303.833784)
		(width 0.1651)
		(layer "In7.Cu")
		(net "P5E_PEX2_STN7_TX_DP<115>")
	)
	(segment
		(start 258.792472 -305.24069)
		(end 259.118608 -305.031394)
		(width 0.1651)
		(layer "In7.Cu")
		(net "P5E_PEX2_STN7_TX_DP<115>")
	)
	(segment
		(start 267.8938 -303.833784)
		(end 267.93952 -303.879504)
		(width 0.1143)
		(layer "In7.Cu")
		(net "P5E_PEX2_STN7_TX_DP<115>")
	)
	(segment
		(start 259.118608 -305.031394)
		(end 259.821172 -304.758852)
		(width 0.1651)
		(layer "In7.Cu")
		(net "P5E_PEX2_STN7_TX_DP<115>")
	)
	(segment
		(start 276.384258 -304.449734)
		(end 276.649688 -304.449734)
		(width 0.1143)
		(layer "In7.Cu")
		(net "P5E_PEX2_STN7_TX_DP<115>")
	)
	(segment
		(start 251.6124 -318.353948)
		(end 256.1844 -308.1274)
		(width 0.1651)
		(layer "In7.Cu")
		(net "P5E_PEX2_STN7_TX_DP<115>")
	)
	(segment
		(start 274.133818 -339.88883)
		(end 255.969008 -329.869292)
		(width 0.1651)
		(layer "In7.Cu")
		(net "P5E_PEX2_STN7_TX_DP<115>")
	)
	(segment
		(start 276.269958 -304.335434)
		(end 276.384258 -304.449734)
		(width 0.1143)
		(layer "In7.Cu")
		(net "P5E_PEX2_STN7_TX_DP<115>")
	)
	(segment
		(start 274.115022 -348.58579)
		(end 274.405852 -348.29496)
		(width 0.1651)
		(layer "In7.Cu")
		(net "P5E_PEX2_STN7_TX_DP<115>")
	)
	(segment
		(start 383.4257 -112.784382)
		(end 383.713482 -112.4966)
		(width 0.13462)
		(layer "F.Cu")
		(net "P5E_PEX3_STN1_TX_DP<23>")
	)
	(segment
		(start 383.713482 -112.4966)
		(end 384.358642 -112.4966)
		(width 0.13462)
		(layer "F.Cu")
		(net "P5E_PEX3_STN1_TX_DP<23>")
	)
	(segment
		(start 384.358642 -112.4966)
		(end 384.671824 -112.809782)
		(width 0.13462)
		(layer "F.Cu")
		(net "P5E_PEX3_STN1_TX_DP<23>")
	)
	(segment
		(start 414.265872 -264.448036)
		(end 414.265872 -271.526)
		(width 0.1651)
		(layer "In9.Cu")
		(net "P5E_PEX3_STN1_TX_DP<23>")
	)
	(segment
		(start 379.425962 -120.14327)
		(end 379.236478 -120.601232)
		(width 0.1651)
		(layer "In9.Cu")
		(net "P5E_PEX3_STN1_TX_DP<23>")
	)
	(segment
		(start 380.359158 -117.89029)
		(end 380.169674 -118.348252)
		(width 0.1651)
		(layer "In9.Cu")
		(net "P5E_PEX3_STN1_TX_DP<23>")
	)
	(segment
		(start 414.485582 -280.129488)
		(end 414.599882 -280.015188)
		(width 0.1143)
		(layer "In9.Cu")
		(net "P5E_PEX3_STN1_TX_DP<23>")
	)
	(segment
		(start 379.89256 -119.01678)
		(end 379.703076 -119.474742)
		(width 0.1651)
		(layer "In9.Cu")
		(net "P5E_PEX3_STN1_TX_DP<23>")
	)
	(segment
		(start 380.825756 -116.7638)
		(end 380.636272 -117.221762)
		(width 0.1651)
		(layer "In9.Cu")
		(net "P5E_PEX3_STN1_TX_DP<23>")
	)
	(segment
		(start 380.953264 -116.156994)
		(end 380.76378 -116.614448)
		(width 0.1651)
		(layer "In9.Cu")
		(net "P5E_PEX3_STN1_TX_DP<23>")
	)
	(segment
		(start 375.561352 -131.652518)
		(end 375.561352 -137.570718)
		(width 0.1651)
		(layer "In9.Cu")
		(net "P5E_PEX3_STN1_TX_DP<23>")
	)
	(segment
		(start 381.569468 -114.968782)
		(end 381.419862 -115.030504)
		(width 0.1651)
		(layer "In9.Cu")
		(net "P5E_PEX3_STN1_TX_DP<23>")
	)
	(segment
		(start 378.76988 -121.727722)
		(end 378.620274 -121.789444)
		(width 0.1651)
		(layer "In9.Cu")
		(net "P5E_PEX3_STN1_TX_DP<23>")
	)
	(segment
		(start 378.897388 -121.120408)
		(end 378.959364 -121.26976)
		(width 0.1651)
		(layer "In9.Cu")
		(net "P5E_PEX3_STN1_TX_DP<23>")
	)
	(segment
		(start 380.636272 -117.221762)
		(end 380.486666 -117.283484)
		(width 0.1651)
		(layer "In9.Cu")
		(net "P5E_PEX3_STN1_TX_DP<23>")
	)
	(segment
		(start 378.959364 -121.26976)
		(end 378.76988 -121.727722)
		(width 0.1651)
		(layer "In9.Cu")
		(net "P5E_PEX3_STN1_TX_DP<23>")
	)
	(segment
		(start 381.419862 -115.030504)
		(end 381.230378 -115.487958)
		(width 0.1651)
		(layer "In9.Cu")
		(net "P5E_PEX3_STN1_TX_DP<23>")
	)
	(segment
		(start 379.363986 -119.993918)
		(end 379.425962 -120.14327)
		(width 0.1651)
		(layer "In9.Cu")
		(net "P5E_PEX3_STN1_TX_DP<23>")
	)
	(segment
		(start 383.4257 -112.784382)
		(end 383.13487 -112.493552)
		(width 0.1651)
		(layer "In9.Cu")
		(net "P5E_PEX3_STN1_TX_DP<23>")
	)
	(segment
		(start 381.696976 -114.361468)
		(end 381.758952 -114.51082)
		(width 0.1651)
		(layer "In9.Cu")
		(net "P5E_PEX3_STN1_TX_DP<23>")
	)
	(segment
		(start 379.703076 -119.474742)
		(end 379.55347 -119.536464)
		(width 0.1651)
		(layer "In9.Cu")
		(net "P5E_PEX3_STN1_TX_DP<23>")
	)
	(segment
		(start 378.370592 -122.392186)
		(end 375.561352 -131.652518)
		(width 0.1651)
		(layer "In9.Cu")
		(net "P5E_PEX3_STN1_TX_DP<23>")
	)
	(segment
		(start 379.086872 -120.662954)
		(end 378.897388 -121.120408)
		(width 0.1651)
		(layer "In9.Cu")
		(net "P5E_PEX3_STN1_TX_DP<23>")
	)
	(segment
		(start 381.230378 -115.487958)
		(end 381.292354 -115.63731)
		(width 0.1651)
		(layer "In9.Cu")
		(net "P5E_PEX3_STN1_TX_DP<23>")
	)
	(segment
		(start 378.11964 -143.746474)
		(end 378.850652 -158.62681)
		(width 0.1651)
		(layer "In9.Cu")
		(net "P5E_PEX3_STN1_TX_DP<23>")
	)
	(segment
		(start 379.830584 -118.867428)
		(end 379.89256 -119.01678)
		(width 0.1651)
		(layer "In9.Cu")
		(net "P5E_PEX3_STN1_TX_DP<23>")
	)
	(segment
		(start 382.552194 -112.493552)
		(end 382.413002 -112.632744)
		(width 0.1651)
		(layer "In9.Cu")
		(net "P5E_PEX3_STN1_TX_DP<23>")
	)
	(segment
		(start 382.163574 -113.234978)
		(end 382.22555 -113.38433)
		(width 0.1651)
		(layer "In9.Cu")
		(net "P5E_PEX3_STN1_TX_DP<23>")
	)
	(segment
		(start 381.292354 -115.63731)
		(end 381.10287 -116.095272)
		(width 0.1651)
		(layer "In9.Cu")
		(net "P5E_PEX3_STN1_TX_DP<23>")
	)
	(segment
		(start 379.55347 -119.536464)
		(end 379.363986 -119.993918)
		(width 0.1651)
		(layer "In9.Cu")
		(net "P5E_PEX3_STN1_TX_DP<23>")
	)
	(segment
		(start 381.10287 -116.095272)
		(end 380.953264 -116.156994)
		(width 0.1651)
		(layer "In9.Cu")
		(net "P5E_PEX3_STN1_TX_DP<23>")
	)
	(segment
		(start 381.758952 -114.51082)
		(end 381.569468 -114.968782)
		(width 0.1651)
		(layer "In9.Cu")
		(net "P5E_PEX3_STN1_TX_DP<23>")
	)
	(segment
		(start 382.22555 -113.38433)
		(end 382.036066 -113.842292)
		(width 0.1651)
		(layer "In9.Cu")
		(net "P5E_PEX3_STN1_TX_DP<23>")
	)
	(segment
		(start 380.020068 -118.409974)
		(end 379.830584 -118.867428)
		(width 0.1651)
		(layer "In9.Cu")
		(net "P5E_PEX3_STN1_TX_DP<23>")
	)
	(segment
		(start 380.486666 -117.283484)
		(end 380.297182 -117.740938)
		(width 0.1651)
		(layer "In9.Cu")
		(net "P5E_PEX3_STN1_TX_DP<23>")
	)
	(segment
		(start 414.599882 -280.015188)
		(end 414.599882 -279.749504)
		(width 0.1143)
		(layer "In9.Cu")
		(net "P5E_PEX3_STN1_TX_DP<23>")
	)
	(segment
		(start 382.036066 -113.842292)
		(end 381.88646 -113.904014)
		(width 0.1651)
		(layer "In9.Cu")
		(net "P5E_PEX3_STN1_TX_DP<23>")
	)
	(segment
		(start 378.620274 -121.789444)
		(end 378.370592 -122.392186)
		(width 0.1651)
		(layer "In9.Cu")
		(net "P5E_PEX3_STN1_TX_DP<23>")
	)
	(segment
		(start 382.413002 -112.632744)
		(end 382.163574 -113.234978)
		(width 0.1651)
		(layer "In9.Cu")
		(net "P5E_PEX3_STN1_TX_DP<23>")
	)
	(segment
		(start 380.169674 -118.348252)
		(end 380.020068 -118.409974)
		(width 0.1651)
		(layer "In9.Cu")
		(net "P5E_PEX3_STN1_TX_DP<23>")
	)
	(segment
		(start 414.323784 -280.129488)
		(end 414.485582 -280.129488)
		(width 0.1143)
		(layer "In9.Cu")
		(net "P5E_PEX3_STN1_TX_DP<23>")
	)
	(segment
		(start 414.265872 -271.526)
		(end 414.265872 -271.554448)
		(width 0.1143)
		(layer "In9.Cu")
		(net "P5E_PEX3_STN1_TX_DP<23>")
	)
	(segment
		(start 379.236478 -120.601232)
		(end 379.086872 -120.662954)
		(width 0.1651)
		(layer "In9.Cu")
		(net "P5E_PEX3_STN1_TX_DP<23>")
	)
	(segment
		(start 379.427232 -161.525712)
		(end 414.265872 -264.448036)
		(width 0.1651)
		(layer "In9.Cu")
		(net "P5E_PEX3_STN1_TX_DP<23>")
	)
	(segment
		(start 380.76378 -116.614448)
		(end 380.825756 -116.7638)
		(width 0.1651)
		(layer "In9.Cu")
		(net "P5E_PEX3_STN1_TX_DP<23>")
	)
	(segment
		(start 380.297182 -117.740938)
		(end 380.359158 -117.89029)
		(width 0.1651)
		(layer "In9.Cu")
		(net "P5E_PEX3_STN1_TX_DP<23>")
	)
	(segment
		(start 375.561352 -137.570718)
		(end 378.11964 -143.746474)
		(width 0.1651)
		(layer "In9.Cu")
		(net "P5E_PEX3_STN1_TX_DP<23>")
	)
	(segment
		(start 414.220152 -280.025856)
		(end 414.323784 -280.129488)
		(width 0.1143)
		(layer "In9.Cu")
		(net "P5E_PEX3_STN1_TX_DP<23>")
	)
	(segment
		(start 383.13487 -112.493552)
		(end 382.552194 -112.493552)
		(width 0.1651)
		(layer "In9.Cu")
		(net "P5E_PEX3_STN1_TX_DP<23>")
	)
	(segment
		(start 414.220152 -271.600168)
		(end 414.220152 -280.025856)
		(width 0.1143)
		(layer "In9.Cu")
		(net "P5E_PEX3_STN1_TX_DP<23>")
	)
	(segment
		(start 378.850652 -158.62681)
		(end 379.427232 -161.525712)
		(width 0.1651)
		(layer "In9.Cu")
		(net "P5E_PEX3_STN1_TX_DP<23>")
	)
	(segment
		(start 414.265872 -271.554448)
		(end 414.220152 -271.600168)
		(width 0.1143)
		(layer "In9.Cu")
		(net "P5E_PEX3_STN1_TX_DP<23>")
	)
	(segment
		(start 381.88646 -113.904014)
		(end 381.696976 -114.361468)
		(width 0.1651)
		(layer "In9.Cu")
		(net "P5E_PEX3_STN1_TX_DP<23>")
	)
	(segment
		(start 137.028428 -355.658166)
		(end 137.028428 -355.026722)
		(width 0.13462)
		(layer "F.Cu")
		(net "P5E_PEX1_STN5_TX_DP<92>")
	)
	(segment
		(start 136.708388 -355.978206)
		(end 137.028428 -355.658166)
		(width 0.13462)
		(layer "F.Cu")
		(net "P5E_PEX1_STN5_TX_DP<92>")
	)
	(segment
		(start 137.028428 -355.026722)
		(end 136.733788 -354.732082)
		(width 0.13462)
		(layer "F.Cu")
		(net "P5E_PEX1_STN5_TX_DP<92>")
	)
	(segment
		(start 185.844942 -311.479692)
		(end 185.629804 -311.69483)
		(width 0.1143)
		(layer "In13.Cu")
		(net "P5E_PEX1_STN5_TX_DP<92>")
	)
	(segment
		(start 175.05934 -328.672444)
		(end 164.97681 -333.01051)
		(width 0.1651)
		(layer "In13.Cu")
		(net "P5E_PEX1_STN5_TX_DP<92>")
	)
	(segment
		(start 181.664356 -325.141336)
		(end 175.05934 -328.672444)
		(width 0.1651)
		(layer "In13.Cu")
		(net "P5E_PEX1_STN5_TX_DP<92>")
	)
	(segment
		(start 138.579098 -352.192082)
		(end 137.024618 -353.746562)
		(width 0.1651)
		(layer "In13.Cu")
		(net "P5E_PEX1_STN5_TX_DP<92>")
	)
	(segment
		(start 186.200034 -311.365392)
		(end 186.085734 -311.479692)
		(width 0.1143)
		(layer "In13.Cu")
		(net "P5E_PEX1_STN5_TX_DP<92>")
	)
	(segment
		(start 185.629804 -311.69483)
		(end 185.629804 -319.995296)
		(width 0.1143)
		(layer "In13.Cu")
		(net "P5E_PEX1_STN5_TX_DP<92>")
	)
	(segment
		(start 186.200034 -311.099962)
		(end 186.200034 -311.365392)
		(width 0.1143)
		(layer "In13.Cu")
		(net "P5E_PEX1_STN5_TX_DP<92>")
	)
	(segment
		(start 186.085734 -311.479692)
		(end 185.844942 -311.479692)
		(width 0.1143)
		(layer "In13.Cu")
		(net "P5E_PEX1_STN5_TX_DP<92>")
	)
	(segment
		(start 185.584084 -320.063114)
		(end 185.584084 -321.918838)
		(width 0.1651)
		(layer "In13.Cu")
		(net "P5E_PEX1_STN5_TX_DP<92>")
	)
	(segment
		(start 185.584084 -321.918838)
		(end 185.437272 -322.273168)
		(width 0.1651)
		(layer "In13.Cu")
		(net "P5E_PEX1_STN5_TX_DP<92>")
	)
	(segment
		(start 139.586208 -340.356952)
		(end 138.579098 -341.364062)
		(width 0.1651)
		(layer "In13.Cu")
		(net "P5E_PEX1_STN5_TX_DP<92>")
	)
	(segment
		(start 185.629804 -319.995296)
		(end 185.584084 -320.041016)
		(width 0.1143)
		(layer "In13.Cu")
		(net "P5E_PEX1_STN5_TX_DP<92>")
	)
	(segment
		(start 142.905988 -338.981796)
		(end 139.586208 -340.356952)
		(width 0.1651)
		(layer "In13.Cu")
		(net "P5E_PEX1_STN5_TX_DP<92>")
	)
	(segment
		(start 138.579098 -341.364062)
		(end 138.579098 -352.192082)
		(width 0.1651)
		(layer "In13.Cu")
		(net "P5E_PEX1_STN5_TX_DP<92>")
	)
	(segment
		(start 184.38876 -323.32168)
		(end 181.664356 -325.141336)
		(width 0.1651)
		(layer "In13.Cu")
		(net "P5E_PEX1_STN5_TX_DP<92>")
	)
	(segment
		(start 137.024618 -353.746562)
		(end 137.024618 -354.441252)
		(width 0.1651)
		(layer "In13.Cu")
		(net "P5E_PEX1_STN5_TX_DP<92>")
	)
	(segment
		(start 164.97681 -333.01051)
		(end 147.78228 -338.741004)
		(width 0.1651)
		(layer "In13.Cu")
		(net "P5E_PEX1_STN5_TX_DP<92>")
	)
	(segment
		(start 144.11706 -338.741004)
		(end 142.905988 -338.981796)
		(width 0.1651)
		(layer "In13.Cu")
		(net "P5E_PEX1_STN5_TX_DP<92>")
	)
	(segment
		(start 185.584084 -320.041016)
		(end 185.584084 -320.063114)
		(width 0.1143)
		(layer "In13.Cu")
		(net "P5E_PEX1_STN5_TX_DP<92>")
	)
	(segment
		(start 137.024618 -354.441252)
		(end 136.733788 -354.732082)
		(width 0.1651)
		(layer "In13.Cu")
		(net "P5E_PEX1_STN5_TX_DP<92>")
	)
	(segment
		(start 185.437272 -322.273168)
		(end 184.38876 -323.32168)
		(width 0.1651)
		(layer "In13.Cu")
		(net "P5E_PEX1_STN5_TX_DP<92>")
	)
	(segment
		(start 147.78228 -338.741004)
		(end 144.11706 -338.741004)
		(width 0.1651)
		(layer "In13.Cu")
		(net "P5E_PEX1_STN5_TX_DP<92>")
	)
	(segment
		(start 184.517792 -348.88043)
		(end 184.812432 -348.58579)
		(width 0.13462)
		(layer "F.Cu")
		(net "P5E_PEX1_STN7_TX_DN<123>")
	)
	(segment
		(start 184.837832 -349.831914)
		(end 184.517792 -349.511874)
		(width 0.13462)
		(layer "F.Cu")
		(net "P5E_PEX1_STN7_TX_DN<123>")
	)
	(segment
		(start 184.517792 -349.511874)
		(end 184.517792 -348.88043)
		(width 0.13462)
		(layer "F.Cu")
		(net "P5E_PEX1_STN7_TX_DN<123>")
	)
	(segment
		(start 154.470354 -313.718194)
		(end 154.618436 -313.570112)
		(width 0.1143)
		(layer "In11.Cu")
		(net "P5E_PEX1_STN7_TX_DN<123>")
	)
	(segment
		(start 154.761184 -313.570112)
		(end 154.850084 -313.659012)
		(width 0.1143)
		(layer "In11.Cu")
		(net "P5E_PEX1_STN7_TX_DN<123>")
	)
	(segment
		(start 154.516074 -320.02095)
		(end 154.470354 -319.97523)
		(width 0.1143)
		(layer "In11.Cu")
		(net "P5E_PEX1_STN7_TX_DN<123>")
	)
	(segment
		(start 181.948836 -338.241132)
		(end 176.93894 -335.354168)
		(width 0.1651)
		(layer "In11.Cu")
		(net "P5E_PEX1_STN7_TX_DN<123>")
	)
	(segment
		(start 154.618436 -313.570112)
		(end 154.761184 -313.570112)
		(width 0.1143)
		(layer "In11.Cu")
		(net "P5E_PEX1_STN7_TX_DN<123>")
	)
	(segment
		(start 154.516074 -321.832732)
		(end 154.516074 -320.043048)
		(width 0.1651)
		(layer "In11.Cu")
		(net "P5E_PEX1_STN7_TX_DN<123>")
	)
	(segment
		(start 154.516074 -320.043048)
		(end 154.516074 -320.02095)
		(width 0.1143)
		(layer "In11.Cu")
		(net "P5E_PEX1_STN7_TX_DN<123>")
	)
	(segment
		(start 185.004456 -340.440264)
		(end 181.948836 -338.241132)
		(width 0.1651)
		(layer "In11.Cu")
		(net "P5E_PEX1_STN7_TX_DN<123>")
	)
	(segment
		(start 184.521602 -348.29496)
		(end 184.521602 -347.695266)
		(width 0.1651)
		(layer "In11.Cu")
		(net "P5E_PEX1_STN7_TX_DN<123>")
	)
	(segment
		(start 184.812432 -348.58579)
		(end 184.521602 -348.29496)
		(width 0.1651)
		(layer "In11.Cu")
		(net "P5E_PEX1_STN7_TX_DN<123>")
	)
	(segment
		(start 186.076082 -341.86749)
		(end 185.004456 -340.440264)
		(width 0.1651)
		(layer "In11.Cu")
		(net "P5E_PEX1_STN7_TX_DN<123>")
	)
	(segment
		(start 157.255464 -325.18985)
		(end 154.964384 -322.79844)
		(width 0.1651)
		(layer "In11.Cu")
		(net "P5E_PEX1_STN7_TX_DN<123>")
	)
	(segment
		(start 154.850084 -313.659012)
		(end 154.850084 -313.949842)
		(width 0.1143)
		(layer "In11.Cu")
		(net "P5E_PEX1_STN7_TX_DN<123>")
	)
	(segment
		(start 186.076082 -346.140786)
		(end 186.076082 -341.86749)
		(width 0.1651)
		(layer "In11.Cu")
		(net "P5E_PEX1_STN7_TX_DN<123>")
	)
	(segment
		(start 154.964384 -322.79844)
		(end 154.516074 -321.832732)
		(width 0.1651)
		(layer "In11.Cu")
		(net "P5E_PEX1_STN7_TX_DN<123>")
	)
	(segment
		(start 184.521602 -347.695266)
		(end 186.076082 -346.140786)
		(width 0.1651)
		(layer "In11.Cu")
		(net "P5E_PEX1_STN7_TX_DN<123>")
	)
	(segment
		(start 154.470354 -319.97523)
		(end 154.470354 -313.718194)
		(width 0.1143)
		(layer "In11.Cu")
		(net "P5E_PEX1_STN7_TX_DN<123>")
	)
	(segment
		(start 176.93894 -335.354168)
		(end 157.255464 -325.18985)
		(width 0.1651)
		(layer "In11.Cu")
		(net "P5E_PEX1_STN7_TX_DN<123>")
	)
	(segment
		(start 313.43346 -119.26062)
		(end 312.810144 -119.26062)
		(width 0.13462)
		(layer "F.Cu")
		(net "P5E_PEX2_STN0_TX_DP<0>")
	)
	(segment
		(start 312.810144 -119.26062)
		(end 312.48604 -119.584724)
		(width 0.13462)
		(layer "F.Cu")
		(net "P5E_PEX2_STN0_TX_DP<0>")
	)
	(segment
		(start 313.732164 -119.559324)
		(end 313.43346 -119.26062)
		(width 0.13462)
		(layer "F.Cu")
		(net "P5E_PEX2_STN0_TX_DP<0>")
	)
	(segment
		(start 314.022994 -119.268494)
		(end 315.218318 -119.268494)
		(width 0.1651)
		(layer "In9.Cu")
		(net "P5E_PEX2_STN0_TX_DP<0>")
	)
	(segment
		(start 319.641474 -122.356118)
		(end 319.816226 -122.77852)
		(width 0.1651)
		(layer "In9.Cu")
		(net "P5E_PEX2_STN0_TX_DP<0>")
	)
	(segment
		(start 332.089506 -151.961596)
		(end 332.089506 -159.92983)
		(width 0.1651)
		(layer "In9.Cu")
		(net "P5E_PEX2_STN0_TX_DP<0>")
	)
	(segment
		(start 316.08903 -287.683956)
		(end 316.04331 -287.729676)
		(width 0.1143)
		(layer "In9.Cu")
		(net "P5E_PEX2_STN0_TX_DP<0>")
	)
	(segment
		(start 317.9826 -287.683956)
		(end 316.117478 -287.683956)
		(width 0.1651)
		(layer "In9.Cu")
		(net "P5E_PEX2_STN0_TX_DP<0>")
	)
	(segment
		(start 332.144624 -267.29182)
		(end 332.615286 -272.702782)
		(width 0.1651)
		(layer "In9.Cu")
		(net "P5E_PEX2_STN0_TX_DP<0>")
	)
	(segment
		(start 315.218318 -119.268494)
		(end 315.319918 -119.370094)
		(width 0.1651)
		(layer "In9.Cu")
		(net "P5E_PEX2_STN0_TX_DP<0>")
	)
	(segment
		(start 321.193414 -126.10338)
		(end 321.13855 -126.236222)
		(width 0.1651)
		(layer "In9.Cu")
		(net "P5E_PEX2_STN0_TX_DP<0>")
	)
	(segment
		(start 315.878718 -119.268494)
		(end 316.335918 -119.268494)
		(width 0.1651)
		(layer "In9.Cu")
		(net "P5E_PEX2_STN0_TX_DP<0>")
	)
	(segment
		(start 315.319918 -119.370094)
		(end 315.777118 -119.370094)
		(width 0.1651)
		(layer "In9.Cu")
		(net "P5E_PEX2_STN0_TX_DP<0>")
	)
	(segment
		(start 322.321936 -179.192428)
		(end 318.595248 -221.785942)
		(width 0.1651)
		(layer "In9.Cu")
		(net "P5E_PEX2_STN0_TX_DP<0>")
	)
	(segment
		(start 320.616834 -124.976636)
		(end 320.79184 -125.399292)
		(width 0.1651)
		(layer "In9.Cu")
		(net "P5E_PEX2_STN0_TX_DP<0>")
	)
	(segment
		(start 319.137792 -121.14022)
		(end 319.38849 -121.745756)
		(width 0.1651)
		(layer "In9.Cu")
		(net "P5E_PEX2_STN0_TX_DP<0>")
	)
	(segment
		(start 318.629538 -120.800876)
		(end 319.137792 -121.14022)
		(width 0.1651)
		(layer "In9.Cu")
		(net "P5E_PEX2_STN0_TX_DP<0>")
	)
	(segment
		(start 316.04331 -287.729676)
		(end 309.54472 -287.729676)
		(width 0.1143)
		(layer "In9.Cu")
		(net "P5E_PEX2_STN0_TX_DP<0>")
	)
	(segment
		(start 330.937362 -276.752812)
		(end 321.437 -286.253174)
		(width 0.1651)
		(layer "In9.Cu")
		(net "P5E_PEX2_STN0_TX_DP<0>")
	)
	(segment
		(start 330.79944 -264.044684)
		(end 332.144624 -267.29182)
		(width 0.1651)
		(layer "In9.Cu")
		(net "P5E_PEX2_STN0_TX_DP<0>")
	)
	(segment
		(start 320.924682 -125.45441)
		(end 321.193414 -126.10338)
		(width 0.1651)
		(layer "In9.Cu")
		(net "P5E_PEX2_STN0_TX_DP<0>")
	)
	(segment
		(start 318.10833 -120.574562)
		(end 318.488568 -120.828816)
		(width 0.1651)
		(layer "In9.Cu")
		(net "P5E_PEX2_STN0_TX_DP<0>")
	)
	(segment
		(start 309.215282 -288.299906)
		(end 308.949852 -288.299906)
		(width 0.1143)
		(layer "In9.Cu")
		(net "P5E_PEX2_STN0_TX_DP<0>")
	)
	(segment
		(start 323.507862 -131.24434)
		(end 332.089506 -151.961596)
		(width 0.1651)
		(layer "In9.Cu")
		(net "P5E_PEX2_STN0_TX_DP<0>")
	)
	(segment
		(start 315.777118 -119.370094)
		(end 315.878718 -119.268494)
		(width 0.1651)
		(layer "In9.Cu")
		(net "P5E_PEX2_STN0_TX_DP<0>")
	)
	(segment
		(start 313.732164 -119.559324)
		(end 314.022994 -119.268494)
		(width 0.1651)
		(layer "In9.Cu")
		(net "P5E_PEX2_STN0_TX_DP<0>")
	)
	(segment
		(start 320.243962 -123.811284)
		(end 320.189098 -123.943872)
		(width 0.1651)
		(layer "In9.Cu")
		(net "P5E_PEX2_STN0_TX_DP<0>")
	)
	(segment
		(start 316.335918 -119.268494)
		(end 318.080136 -120.433592)
		(width 0.1651)
		(layer "In9.Cu")
		(net "P5E_PEX2_STN0_TX_DP<0>")
	)
	(segment
		(start 318.595248 -221.785942)
		(end 321.003676 -249.385836)
		(width 0.1651)
		(layer "In9.Cu")
		(net "P5E_PEX2_STN0_TX_DP<0>")
	)
	(segment
		(start 319.508632 -122.301254)
		(end 319.641474 -122.356118)
		(width 0.1651)
		(layer "In9.Cu")
		(net "P5E_PEX2_STN0_TX_DP<0>")
	)
	(segment
		(start 320.189098 -123.943872)
		(end 320.364104 -124.366528)
		(width 0.1651)
		(layer "In9.Cu")
		(net "P5E_PEX2_STN0_TX_DP<0>")
	)
	(segment
		(start 309.329582 -288.185606)
		(end 309.215282 -288.299906)
		(width 0.1143)
		(layer "In9.Cu")
		(net "P5E_PEX2_STN0_TX_DP<0>")
	)
	(segment
		(start 316.117478 -287.683956)
		(end 316.08903 -287.683956)
		(width 0.1143)
		(layer "In9.Cu")
		(net "P5E_PEX2_STN0_TX_DP<0>")
	)
	(segment
		(start 319.38849 -121.745756)
		(end 319.333626 -121.878598)
		(width 0.1651)
		(layer "In9.Cu")
		(net "P5E_PEX2_STN0_TX_DP<0>")
	)
	(segment
		(start 309.329582 -287.944814)
		(end 309.329582 -288.185606)
		(width 0.1143)
		(layer "In9.Cu")
		(net "P5E_PEX2_STN0_TX_DP<0>")
	)
	(segment
		(start 332.615286 -272.702782)
		(end 330.937362 -276.752812)
		(width 0.1651)
		(layer "In9.Cu")
		(net "P5E_PEX2_STN0_TX_DP<0>")
	)
	(segment
		(start 321.313556 -126.658878)
		(end 321.446398 -126.713996)
		(width 0.1651)
		(layer "In9.Cu")
		(net "P5E_PEX2_STN0_TX_DP<0>")
	)
	(segment
		(start 331.75829 -161.16935)
		(end 323.186806 -176.023778)
		(width 0.1651)
		(layer "In9.Cu")
		(net "P5E_PEX2_STN0_TX_DP<0>")
	)
	(segment
		(start 320.79184 -125.399292)
		(end 320.924682 -125.45441)
		(width 0.1651)
		(layer "In9.Cu")
		(net "P5E_PEX2_STN0_TX_DP<0>")
	)
	(segment
		(start 319.816226 -122.77852)
		(end 319.761362 -122.911108)
		(width 0.1651)
		(layer "In9.Cu")
		(net "P5E_PEX2_STN0_TX_DP<0>")
	)
	(segment
		(start 318.080136 -120.433592)
		(end 318.10833 -120.574562)
		(width 0.1651)
		(layer "In9.Cu")
		(net "P5E_PEX2_STN0_TX_DP<0>")
	)
	(segment
		(start 323.186806 -176.023778)
		(end 322.321936 -179.192428)
		(width 0.1651)
		(layer "In9.Cu")
		(net "P5E_PEX2_STN0_TX_DP<0>")
	)
	(segment
		(start 319.333626 -121.878598)
		(end 319.508632 -122.301254)
		(width 0.1651)
		(layer "In9.Cu")
		(net "P5E_PEX2_STN0_TX_DP<0>")
	)
	(segment
		(start 321.003676 -249.385836)
		(end 330.79944 -264.044684)
		(width 0.1651)
		(layer "In9.Cu")
		(net "P5E_PEX2_STN0_TX_DP<0>")
	)
	(segment
		(start 320.671698 -124.843794)
		(end 320.616834 -124.976636)
		(width 0.1651)
		(layer "In9.Cu")
		(net "P5E_PEX2_STN0_TX_DP<0>")
	)
	(segment
		(start 321.437 -286.253174)
		(end 317.9826 -287.683956)
		(width 0.1651)
		(layer "In9.Cu")
		(net "P5E_PEX2_STN0_TX_DP<0>")
	)
	(segment
		(start 321.446398 -126.713996)
		(end 323.192394 -130.928872)
		(width 0.1651)
		(layer "In9.Cu")
		(net "P5E_PEX2_STN0_TX_DP<0>")
	)
	(segment
		(start 319.761362 -122.911108)
		(end 319.936368 -123.333764)
		(width 0.1651)
		(layer "In9.Cu")
		(net "P5E_PEX2_STN0_TX_DP<0>")
	)
	(segment
		(start 320.06921 -123.388882)
		(end 320.243962 -123.811284)
		(width 0.1651)
		(layer "In9.Cu")
		(net "P5E_PEX2_STN0_TX_DP<0>")
	)
	(segment
		(start 309.54472 -287.729676)
		(end 309.329582 -287.944814)
		(width 0.1143)
		(layer "In9.Cu")
		(net "P5E_PEX2_STN0_TX_DP<0>")
	)
	(segment
		(start 318.488568 -120.828816)
		(end 318.629538 -120.800876)
		(width 0.1651)
		(layer "In9.Cu")
		(net "P5E_PEX2_STN0_TX_DP<0>")
	)
	(segment
		(start 320.364104 -124.366528)
		(end 320.496946 -124.421646)
		(width 0.1651)
		(layer "In9.Cu")
		(net "P5E_PEX2_STN0_TX_DP<0>")
	)
	(segment
		(start 323.192394 -130.928872)
		(end 323.507862 -131.24434)
		(width 0.1651)
		(layer "In9.Cu")
		(net "P5E_PEX2_STN0_TX_DP<0>")
	)
	(segment
		(start 332.089506 -159.92983)
		(end 331.75829 -161.16935)
		(width 0.1651)
		(layer "In9.Cu")
		(net "P5E_PEX2_STN0_TX_DP<0>")
	)
	(segment
		(start 321.13855 -126.236222)
		(end 321.313556 -126.658878)
		(width 0.1651)
		(layer "In9.Cu")
		(net "P5E_PEX2_STN0_TX_DP<0>")
	)
	(segment
		(start 320.496946 -124.421646)
		(end 320.671698 -124.843794)
		(width 0.1651)
		(layer "In9.Cu")
		(net "P5E_PEX2_STN0_TX_DP<0>")
	)
	(segment
		(start 319.936368 -123.333764)
		(end 320.06921 -123.388882)
		(width 0.1651)
		(layer "In9.Cu")
		(net "P5E_PEX2_STN0_TX_DP<0>")
	)
	(segment
		(start 270.980662 -343.685622)
		(end 271.300702 -343.365582)
		(width 0.13462)
		(layer "F.Cu")
		(net "P5E_PEX2_STN7_TX_DP<113>")
	)
	(segment
		(start 271.300702 -342.734138)
		(end 271.006062 -342.439498)
		(width 0.13462)
		(layer "F.Cu")
		(net "P5E_PEX2_STN7_TX_DP<113>")
	)
	(segment
		(start 271.300702 -343.365582)
		(end 271.300702 -342.734138)
		(width 0.13462)
		(layer "F.Cu")
		(net "P5E_PEX2_STN7_TX_DP<113>")
	)
	(segment
		(start 276.384258 -302.549814)
		(end 276.649688 -302.549814)
		(width 0.1143)
		(layer "In7.Cu")
		(net "P5E_PEX2_STN7_TX_DP<113>")
	)
	(segment
		(start 271.296892 -341.616284)
		(end 269.776194 -340.026244)
		(width 0.1651)
		(layer "In7.Cu")
		(net "P5E_PEX2_STN7_TX_DP<113>")
	)
	(segment
		(start 267.8938 -301.933864)
		(end 267.93952 -301.979584)
		(width 0.1143)
		(layer "In7.Cu")
		(net "P5E_PEX2_STN7_TX_DP<113>")
	)
	(segment
		(start 259.629402 -302.612806)
		(end 266.521184 -301.933864)
		(width 0.1651)
		(layer "In7.Cu")
		(net "P5E_PEX2_STN7_TX_DP<113>")
	)
	(segment
		(start 271.296892 -342.148668)
		(end 271.296892 -341.616284)
		(width 0.1651)
		(layer "In7.Cu")
		(net "P5E_PEX2_STN7_TX_DP<113>")
	)
	(segment
		(start 269.776194 -340.026244)
		(end 254.558546 -331.33411)
		(width 0.1651)
		(layer "In7.Cu")
		(net "P5E_PEX2_STN7_TX_DP<113>")
	)
	(segment
		(start 254.558546 -331.33411)
		(end 251.240544 -327.56856)
		(width 0.1651)
		(layer "In7.Cu")
		(net "P5E_PEX2_STN7_TX_DP<113>")
	)
	(segment
		(start 276.269958 -302.435514)
		(end 276.384258 -302.549814)
		(width 0.1143)
		(layer "In7.Cu")
		(net "P5E_PEX2_STN7_TX_DP<113>")
	)
	(segment
		(start 267.865352 -301.933864)
		(end 267.8938 -301.933864)
		(width 0.1143)
		(layer "In7.Cu")
		(net "P5E_PEX2_STN7_TX_DP<113>")
	)
	(segment
		(start 267.93952 -301.979584)
		(end 276.044152 -301.979584)
		(width 0.1143)
		(layer "In7.Cu")
		(net "P5E_PEX2_STN7_TX_DP<113>")
	)
	(segment
		(start 254.324866 -306.931822)
		(end 256.537206 -304.520092)
		(width 0.1651)
		(layer "In7.Cu")
		(net "P5E_PEX2_STN7_TX_DP<113>")
	)
	(segment
		(start 251.240544 -327.56856)
		(end 249.65406 -323.737478)
		(width 0.1651)
		(layer "In7.Cu")
		(net "P5E_PEX2_STN7_TX_DP<113>")
	)
	(segment
		(start 266.521184 -301.933864)
		(end 267.865352 -301.933864)
		(width 0.1651)
		(layer "In7.Cu")
		(net "P5E_PEX2_STN7_TX_DP<113>")
	)
	(segment
		(start 276.044152 -301.979584)
		(end 276.269958 -302.20539)
		(width 0.1143)
		(layer "In7.Cu")
		(net "P5E_PEX2_STN7_TX_DP<113>")
	)
	(segment
		(start 249.65406 -323.737478)
		(end 249.65406 -317.686944)
		(width 0.1651)
		(layer "In7.Cu")
		(net "P5E_PEX2_STN7_TX_DP<113>")
	)
	(segment
		(start 257.684778 -303.372774)
		(end 259.629402 -302.612806)
		(width 0.1651)
		(layer "In7.Cu")
		(net "P5E_PEX2_STN7_TX_DP<113>")
	)
	(segment
		(start 256.537206 -304.520092)
		(end 257.684778 -303.372774)
		(width 0.1651)
		(layer "In7.Cu")
		(net "P5E_PEX2_STN7_TX_DP<113>")
	)
	(segment
		(start 276.269958 -302.20539)
		(end 276.269958 -302.435514)
		(width 0.1143)
		(layer "In7.Cu")
		(net "P5E_PEX2_STN7_TX_DP<113>")
	)
	(segment
		(start 271.006062 -342.439498)
		(end 271.296892 -342.148668)
		(width 0.1651)
		(layer "In7.Cu")
		(net "P5E_PEX2_STN7_TX_DP<113>")
	)
	(segment
		(start 249.65406 -317.686944)
		(end 254.324866 -306.931822)
		(width 0.1651)
		(layer "In7.Cu")
		(net "P5E_PEX2_STN7_TX_DP<113>")
	)
	(segment
		(start 384.343148 -134.5946)
		(end 384.671824 -134.923276)
		(width 0.13462)
		(layer "F.Cu")
		(net "P5E_PEX3_STN1_TX_DN<30>")
	)
	(segment
		(start 383.728976 -134.5946)
		(end 384.343148 -134.5946)
		(width 0.13462)
		(layer "F.Cu")
		(net "P5E_PEX3_STN1_TX_DN<30>")
	)
	(segment
		(start 383.4257 -134.897876)
		(end 383.728976 -134.5946)
		(width 0.13462)
		(layer "F.Cu")
		(net "P5E_PEX3_STN1_TX_DN<30>")
	)
	(segment
		(start 382.403604 -134.818882)
		(end 382.32334 -135.01243)
		(width 0.1651)
		(layer "In9.Cu")
		(net "P5E_PEX3_STN1_TX_DN<30>")
	)
	(segment
		(start 386.371592 -145.197322)
		(end 386.506466 -145.287238)
		(width 0.1651)
		(layer "In9.Cu")
		(net "P5E_PEX3_STN1_TX_DN<30>")
	)
	(segment
		(start 385.65836 -141.609826)
		(end 385.793234 -141.699742)
		(width 0.1651)
		(layer "In9.Cu")
		(net "P5E_PEX3_STN1_TX_DN<30>")
	)
	(segment
		(start 385.562094 -141.124178)
		(end 385.65836 -141.609826)
		(width 0.1651)
		(layer "In9.Cu")
		(net "P5E_PEX3_STN1_TX_DN<30>")
	)
	(segment
		(start 383.615692 -137.513568)
		(end 383.957322 -137.855198)
		(width 0.1651)
		(layer "In9.Cu")
		(net "P5E_PEX3_STN1_TX_DN<30>")
	)
	(segment
		(start 385.896104 -142.805658)
		(end 386.030978 -142.895574)
		(width 0.1651)
		(layer "In9.Cu")
		(net "P5E_PEX3_STN1_TX_DN<30>")
	)
	(segment
		(start 385.32435 -139.928346)
		(end 385.420616 -140.413994)
		(width 0.1651)
		(layer "In9.Cu")
		(net "P5E_PEX3_STN1_TX_DN<30>")
	)
	(segment
		(start 382.32334 -135.266938)
		(end 382.507998 -135.711946)
		(width 0.1651)
		(layer "In9.Cu")
		(net "P5E_PEX3_STN1_TX_DN<30>")
	)
	(segment
		(start 386.750814 -147.103846)
		(end 393.921742 -183.203088)
		(width 0.1651)
		(layer "In9.Cu")
		(net "P5E_PEX3_STN1_TX_DN<30>")
	)
	(segment
		(start 385.65201 -140.989812)
		(end 385.562094 -141.124178)
		(width 0.1651)
		(layer "In9.Cu")
		(net "P5E_PEX3_STN1_TX_DN<30>")
	)
	(segment
		(start 420.973504 -278.229568)
		(end 421.135302 -278.229568)
		(width 0.1143)
		(layer "In9.Cu")
		(net "P5E_PEX3_STN1_TX_DN<30>")
	)
	(segment
		(start 386.506466 -145.287238)
		(end 386.602732 -145.77314)
		(width 0.1651)
		(layer "In9.Cu")
		(net "P5E_PEX3_STN1_TX_DN<30>")
	)
	(segment
		(start 382.657604 -135.773922)
		(end 382.842262 -136.2202)
		(width 0.1651)
		(layer "In9.Cu")
		(net "P5E_PEX3_STN1_TX_DN<30>")
	)
	(segment
		(start 386.275326 -144.711674)
		(end 386.371592 -145.197322)
		(width 0.1651)
		(layer "In9.Cu")
		(net "P5E_PEX3_STN1_TX_DN<30>")
	)
	(segment
		(start 386.609336 -146.393408)
		(end 386.743956 -146.483324)
		(width 0.1651)
		(layer "In9.Cu")
		(net "P5E_PEX3_STN1_TX_DN<30>")
	)
	(segment
		(start 385.420616 -140.413994)
		(end 385.55549 -140.50391)
		(width 0.1651)
		(layer "In9.Cu")
		(net "P5E_PEX3_STN1_TX_DN<30>")
	)
	(segment
		(start 383.4257 -134.897876)
		(end 383.13487 -134.607046)
		(width 0.1651)
		(layer "In9.Cu")
		(net "P5E_PEX3_STN1_TX_DN<30>")
	)
	(segment
		(start 382.32334 -135.01243)
		(end 382.32334 -135.266938)
		(width 0.1651)
		(layer "In9.Cu")
		(net "P5E_PEX3_STN1_TX_DN<30>")
	)
	(segment
		(start 420.915846 -262.946896)
		(end 420.915846 -271.471898)
		(width 0.1651)
		(layer "In9.Cu")
		(net "P5E_PEX3_STN1_TX_DN<30>")
	)
	(segment
		(start 382.507998 -135.711946)
		(end 382.507998 -135.7122)
		(width 0.1651)
		(layer "In9.Cu")
		(net "P5E_PEX3_STN1_TX_DN<30>")
	)
	(segment
		(start 385.889754 -142.185644)
		(end 385.799838 -142.32001)
		(width 0.1651)
		(layer "In9.Cu")
		(net "P5E_PEX3_STN1_TX_DN<30>")
	)
	(segment
		(start 383.957322 -138.016742)
		(end 384.939032 -138.998452)
		(width 0.1651)
		(layer "In9.Cu")
		(net "P5E_PEX3_STN1_TX_DN<30>")
	)
	(segment
		(start 420.870126 -271.546066)
		(end 420.870126 -278.12619)
		(width 0.1143)
		(layer "In9.Cu")
		(net "P5E_PEX3_STN1_TX_DN<30>")
	)
	(segment
		(start 420.870126 -278.12619)
		(end 420.973504 -278.229568)
		(width 0.1143)
		(layer "In9.Cu")
		(net "P5E_PEX3_STN1_TX_DN<30>")
	)
	(segment
		(start 420.915846 -271.471898)
		(end 420.915846 -271.500346)
		(width 0.1143)
		(layer "In9.Cu")
		(net "P5E_PEX3_STN1_TX_DN<30>")
	)
	(segment
		(start 385.799838 -142.32001)
		(end 385.896104 -142.805658)
		(width 0.1651)
		(layer "In9.Cu")
		(net "P5E_PEX3_STN1_TX_DN<30>")
	)
	(segment
		(start 385.793234 -141.699742)
		(end 385.889754 -142.185644)
		(width 0.1651)
		(layer "In9.Cu")
		(net "P5E_PEX3_STN1_TX_DN<30>")
	)
	(segment
		(start 386.037582 -143.515842)
		(end 386.133848 -144.00149)
		(width 0.1651)
		(layer "In9.Cu")
		(net "P5E_PEX3_STN1_TX_DN<30>")
	)
	(segment
		(start 382.507998 -135.7122)
		(end 382.657604 -135.773922)
		(width 0.1651)
		(layer "In9.Cu")
		(net "P5E_PEX3_STN1_TX_DN<30>")
	)
	(segment
		(start 393.921742 -183.203088)
		(end 420.915846 -262.946896)
		(width 0.1651)
		(layer "In9.Cu")
		(net "P5E_PEX3_STN1_TX_DN<30>")
	)
	(segment
		(start 383.957322 -137.855198)
		(end 383.957322 -138.016742)
		(width 0.1651)
		(layer "In9.Cu")
		(net "P5E_PEX3_STN1_TX_DN<30>")
	)
	(segment
		(start 420.915846 -271.500346)
		(end 420.870126 -271.546066)
		(width 0.1143)
		(layer "In9.Cu")
		(net "P5E_PEX3_STN1_TX_DN<30>")
	)
	(segment
		(start 386.51307 -145.90776)
		(end 386.609336 -146.393408)
		(width 0.1651)
		(layer "In9.Cu")
		(net "P5E_PEX3_STN1_TX_DN<30>")
	)
	(segment
		(start 383.113026 -137.172446)
		(end 383.454148 -137.513568)
		(width 0.1651)
		(layer "In9.Cu")
		(net "P5E_PEX3_STN1_TX_DN<30>")
	)
	(segment
		(start 421.249602 -278.115268)
		(end 421.249602 -277.849838)
		(width 0.1143)
		(layer "In9.Cu")
		(net "P5E_PEX3_STN1_TX_DN<30>")
	)
	(segment
		(start 382.61544 -134.607046)
		(end 382.403604 -134.818882)
		(width 0.1651)
		(layer "In9.Cu")
		(net "P5E_PEX3_STN1_TX_DN<30>")
	)
	(segment
		(start 421.135302 -278.229568)
		(end 421.249602 -278.115268)
		(width 0.1143)
		(layer "In9.Cu")
		(net "P5E_PEX3_STN1_TX_DN<30>")
	)
	(segment
		(start 386.127244 -143.381476)
		(end 386.037582 -143.515842)
		(width 0.1651)
		(layer "In9.Cu")
		(net "P5E_PEX3_STN1_TX_DN<30>")
	)
	(segment
		(start 383.13487 -134.607046)
		(end 382.61544 -134.607046)
		(width 0.1651)
		(layer "In9.Cu")
		(net "P5E_PEX3_STN1_TX_DN<30>")
	)
	(segment
		(start 386.268722 -144.091406)
		(end 386.364988 -144.577308)
		(width 0.1651)
		(layer "In9.Cu")
		(net "P5E_PEX3_STN1_TX_DN<30>")
	)
	(segment
		(start 382.842262 -136.2202)
		(end 382.780286 -136.369552)
		(width 0.1651)
		(layer "In9.Cu")
		(net "P5E_PEX3_STN1_TX_DN<30>")
	)
	(segment
		(start 384.939032 -138.998452)
		(end 385.32435 -139.928346)
		(width 0.1651)
		(layer "In9.Cu")
		(net "P5E_PEX3_STN1_TX_DN<30>")
	)
	(segment
		(start 386.840476 -146.969226)
		(end 386.750814 -147.103846)
		(width 0.1651)
		(layer "In9.Cu")
		(net "P5E_PEX3_STN1_TX_DN<30>")
	)
	(segment
		(start 383.454148 -137.513568)
		(end 383.615692 -137.513568)
		(width 0.1651)
		(layer "In9.Cu")
		(net "P5E_PEX3_STN1_TX_DN<30>")
	)
	(segment
		(start 386.364988 -144.577308)
		(end 386.275326 -144.711674)
		(width 0.1651)
		(layer "In9.Cu")
		(net "P5E_PEX3_STN1_TX_DN<30>")
	)
	(segment
		(start 385.55549 -140.50391)
		(end 385.65201 -140.989812)
		(width 0.1651)
		(layer "In9.Cu")
		(net "P5E_PEX3_STN1_TX_DN<30>")
	)
	(segment
		(start 386.133848 -144.00149)
		(end 386.268722 -144.091406)
		(width 0.1651)
		(layer "In9.Cu")
		(net "P5E_PEX3_STN1_TX_DN<30>")
	)
	(segment
		(start 386.602732 -145.77314)
		(end 386.51307 -145.90776)
		(width 0.1651)
		(layer "In9.Cu")
		(net "P5E_PEX3_STN1_TX_DN<30>")
	)
	(segment
		(start 386.030978 -142.895574)
		(end 386.127244 -143.381476)
		(width 0.1651)
		(layer "In9.Cu")
		(net "P5E_PEX3_STN1_TX_DN<30>")
	)
	(segment
		(start 386.743956 -146.483324)
		(end 386.840476 -146.969226)
		(width 0.1651)
		(layer "In9.Cu")
		(net "P5E_PEX3_STN1_TX_DN<30>")
	)
	(segment
		(start 382.780286 -136.369552)
		(end 383.113026 -137.172446)
		(width 0.1651)
		(layer "In9.Cu")
		(net "P5E_PEX3_STN1_TX_DN<30>")
	)
	(segment
		(start 187.626752 -344.539062)
		(end 187.946792 -344.219022)
		(width 0.13462)
		(layer "F.Cu")
		(net "P5E_PEX1_STN7_TX_C_DN<124>")
	)
	(segment
		(start 187.921392 -345.465146)
		(end 187.626752 -345.170506)
		(width 0.13462)
		(layer "F.Cu")
		(net "P5E_PEX1_STN7_TX_C_DN<124>")
	)
	(segment
		(start 187.626752 -345.170506)
		(end 187.626752 -344.539062)
		(width 0.13462)
		(layer "F.Cu")
		(net "P5E_PEX1_STN7_TX_C_DN<124>")
	)
	(segment
		(start 187.630562 -346.499688)
		(end 187.630562 -345.755976)
		(width 0.1651)
		(layer "In11.Cu")
		(net "P5E_PEX1_STN7_TX_C_DN<124>")
	)
	(segment
		(start 171.096432 -367.783872)
		(end 181.16677 -363.556296)
		(width 0.1651)
		(layer "In11.Cu")
		(net "P5E_PEX1_STN7_TX_C_DN<124>")
	)
	(segment
		(start 186.076082 -348.054168)
		(end 187.630562 -346.499688)
		(width 0.1651)
		(layer "In11.Cu")
		(net "P5E_PEX1_STN7_TX_C_DN<124>")
	)
	(segment
		(start 169.17543 -375.181114)
		(end 169.86758 -374.488964)
		(width 0.1651)
		(layer "In11.Cu")
		(net "P5E_PEX1_STN7_TX_C_DN<124>")
	)
	(segment
		(start 186.076082 -358.646984)
		(end 186.076082 -348.054168)
		(width 0.1651)
		(layer "In11.Cu")
		(net "P5E_PEX1_STN7_TX_C_DN<124>")
	)
	(segment
		(start 169.86758 -374.488964)
		(end 169.86758 -369.012724)
		(width 0.1651)
		(layer "In11.Cu")
		(net "P5E_PEX1_STN7_TX_C_DN<124>")
	)
	(segment
		(start 181.16677 -363.556296)
		(end 186.076082 -358.646984)
		(width 0.1651)
		(layer "In11.Cu")
		(net "P5E_PEX1_STN7_TX_C_DN<124>")
	)
	(segment
		(start 168.837102 -375.181114)
		(end 169.17543 -375.181114)
		(width 0.1651)
		(layer "In11.Cu")
		(net "P5E_PEX1_STN7_TX_C_DN<124>")
	)
	(segment
		(start 187.630562 -345.755976)
		(end 187.921392 -345.465146)
		(width 0.1651)
		(layer "In11.Cu")
		(net "P5E_PEX1_STN7_TX_C_DN<124>")
	)
	(segment
		(start 168.710102 -375.69013)
		(end 168.710102 -375.308114)
		(width 0.1651)
		(layer "In11.Cu")
		(net "P5E_PEX1_STN7_TX_C_DN<124>")
	)
	(segment
		(start 169.86758 -369.012724)
		(end 171.096432 -367.783872)
		(width 0.1651)
		(layer "In11.Cu")
		(net "P5E_PEX1_STN7_TX_C_DN<124>")
	)
	(segment
		(start 168.710102 -375.308114)
		(end 168.837102 -375.181114)
		(width 0.1651)
		(layer "In11.Cu")
		(net "P5E_PEX1_STN7_TX_C_DN<124>")
	)
	(segment
		(start 138.047476 -30.92069)
		(end 137.754106 -30.62732)
		(width 0.13462)
		(layer "F.Cu")
		(net "P5E_PEX1_STN2_TX_DP<45>")
	)
	(segment
		(start 137.120122 -30.62732)
		(end 136.801352 -30.94609)
		(width 0.13462)
		(layer "F.Cu")
		(net "P5E_PEX1_STN2_TX_DP<45>")
	)
	(segment
		(start 137.754106 -30.62732)
		(end 137.120122 -30.62732)
		(width 0.13462)
		(layer "F.Cu")
		(net "P5E_PEX1_STN2_TX_DP<45>")
	)
	(segment
		(start 149.741636 -105.23093)
		(end 149.238716 -116.205762)
		(width 0.1651)
		(layer "In11.Cu")
		(net "P5E_PEX1_STN2_TX_DP<45>")
	)
	(segment
		(start 141.757908 -33.69056)
		(end 141.882876 -33.70453)
		(width 0.1651)
		(layer "In11.Cu")
		(net "P5E_PEX1_STN2_TX_DP<45>")
	)
	(segment
		(start 162.450018 -278.534368)
		(end 162.450018 -278.799798)
		(width 0.1143)
		(layer "In11.Cu")
		(net "P5E_PEX1_STN2_TX_DP<45>")
	)
	(segment
		(start 154.247088 -63.150242)
		(end 153.373582 -78.885796)
		(width 0.1651)
		(layer "In11.Cu")
		(net "P5E_PEX1_STN2_TX_DP<45>")
	)
	(segment
		(start 141.449044 -33.302956)
		(end 141.757908 -33.69056)
		(width 0.1651)
		(layer "In11.Cu")
		(net "P5E_PEX1_STN2_TX_DP<45>")
	)
	(segment
		(start 141.154658 -32.790638)
		(end 141.463268 -33.177988)
		(width 0.1651)
		(layer "In11.Cu")
		(net "P5E_PEX1_STN2_TX_DP<45>")
	)
	(segment
		(start 149.238716 -116.205762)
		(end 149.641052 -137.987278)
		(width 0.1651)
		(layer "In11.Cu")
		(net "P5E_PEX1_STN2_TX_DP<45>")
	)
	(segment
		(start 152.86609 -48.578008)
		(end 153.483818 -50.3682)
		(width 0.1651)
		(layer "In11.Cu")
		(net "P5E_PEX1_STN2_TX_DP<45>")
	)
	(segment
		(start 141.882876 -33.70453)
		(end 141.882622 -33.704784)
		(width 0.1651)
		(layer "In11.Cu")
		(net "P5E_PEX1_STN2_TX_DP<45>")
	)
	(segment
		(start 140.734796 -32.264096)
		(end 140.720826 -32.389064)
		(width 0.1651)
		(layer "In11.Cu")
		(net "P5E_PEX1_STN2_TX_DP<45>")
	)
	(segment
		(start 149.741382 -105.217976)
		(end 149.74062 -105.23093)
		(width 0.1651)
		(layer "In11.Cu")
		(net "P5E_PEX1_STN2_TX_DP<45>")
	)
	(segment
		(start 162.335718 -278.420068)
		(end 162.450018 -278.534368)
		(width 0.1143)
		(layer "In11.Cu")
		(net "P5E_PEX1_STN2_TX_DP<45>")
	)
	(segment
		(start 138.345672 -30.62986)
		(end 138.731752 -30.62986)
		(width 0.1651)
		(layer "In11.Cu")
		(net "P5E_PEX1_STN2_TX_DP<45>")
	)
	(segment
		(start 153.483818 -50.3682)
		(end 154.247088 -63.150242)
		(width 0.1651)
		(layer "In11.Cu")
		(net "P5E_PEX1_STN2_TX_DP<45>")
	)
	(segment
		(start 141.463268 -33.177988)
		(end 141.449044 -33.302956)
		(width 0.1651)
		(layer "In11.Cu")
		(net "P5E_PEX1_STN2_TX_DP<45>")
	)
	(segment
		(start 161.834068 -271.427448)
		(end 161.879788 -271.473168)
		(width 0.1143)
		(layer "In11.Cu")
		(net "P5E_PEX1_STN2_TX_DP<45>")
	)
	(segment
		(start 138.047476 -30.92069)
		(end 138.340338 -30.627828)
		(width 0.1651)
		(layer "In11.Cu")
		(net "P5E_PEX1_STN2_TX_DP<45>")
	)
	(segment
		(start 161.834068 -270.38427)
		(end 161.834068 -271.399)
		(width 0.1651)
		(layer "In11.Cu")
		(net "P5E_PEX1_STN2_TX_DP<45>")
	)
	(segment
		(start 141.02969 -32.776668)
		(end 141.154658 -32.790638)
		(width 0.1651)
		(layer "In11.Cu")
		(net "P5E_PEX1_STN2_TX_DP<45>")
	)
	(segment
		(start 138.731752 -30.62986)
		(end 139.218924 -30.831536)
		(width 0.1651)
		(layer "In11.Cu")
		(net "P5E_PEX1_STN2_TX_DP<45>")
	)
	(segment
		(start 160.8074 -264.195306)
		(end 161.834068 -270.38427)
		(width 0.1651)
		(layer "In11.Cu")
		(net "P5E_PEX1_STN2_TX_DP<45>")
	)
	(segment
		(start 140.399516 -31.842964)
		(end 140.734796 -32.264096)
		(width 0.1651)
		(layer "In11.Cu")
		(net "P5E_PEX1_STN2_TX_DP<45>")
	)
	(segment
		(start 138.340338 -30.627828)
		(end 138.345672 -30.62986)
		(width 0.1651)
		(layer "In11.Cu")
		(net "P5E_PEX1_STN2_TX_DP<45>")
	)
	(segment
		(start 140.720826 -32.389064)
		(end 141.02969 -32.776668)
		(width 0.1651)
		(layer "In11.Cu")
		(net "P5E_PEX1_STN2_TX_DP<45>")
	)
	(segment
		(start 149.74062 -105.23093)
		(end 149.741636 -105.23093)
		(width 0.1651)
		(layer "In11.Cu")
		(net "P5E_PEX1_STN2_TX_DP<45>")
	)
	(segment
		(start 161.879788 -271.473168)
		(end 161.879788 -278.20493)
		(width 0.1143)
		(layer "In11.Cu")
		(net "P5E_PEX1_STN2_TX_DP<45>")
	)
	(segment
		(start 150.94077 -45.07484)
		(end 152.86609 -48.578008)
		(width 0.1651)
		(layer "In11.Cu")
		(net "P5E_PEX1_STN2_TX_DP<45>")
	)
	(segment
		(start 153.373582 -78.885796)
		(end 149.741382 -105.217976)
		(width 0.1651)
		(layer "In11.Cu")
		(net "P5E_PEX1_STN2_TX_DP<45>")
	)
	(segment
		(start 161.834068 -271.399)
		(end 161.834068 -271.427448)
		(width 0.1143)
		(layer "In11.Cu")
		(net "P5E_PEX1_STN2_TX_DP<45>")
	)
	(segment
		(start 139.218924 -30.831536)
		(end 140.399516 -31.842964)
		(width 0.1651)
		(layer "In11.Cu")
		(net "P5E_PEX1_STN2_TX_DP<45>")
	)
	(segment
		(start 141.882622 -33.704784)
		(end 150.94077 -45.07484)
		(width 0.1651)
		(layer "In11.Cu")
		(net "P5E_PEX1_STN2_TX_DP<45>")
	)
	(segment
		(start 162.094926 -278.420068)
		(end 162.335718 -278.420068)
		(width 0.1143)
		(layer "In11.Cu")
		(net "P5E_PEX1_STN2_TX_DP<45>")
	)
	(segment
		(start 149.641052 -137.987278)
		(end 160.8074 -264.195306)
		(width 0.1651)
		(layer "In11.Cu")
		(net "P5E_PEX1_STN2_TX_DP<45>")
	)
	(segment
		(start 161.879788 -278.20493)
		(end 162.094926 -278.420068)
		(width 0.1143)
		(layer "In11.Cu")
		(net "P5E_PEX1_STN2_TX_DP<45>")
	)
	(segment
		(start 168.378632 -343.685622)
		(end 168.698672 -343.365582)
		(width 0.13462)
		(layer "F.Cu")
		(net "P5E_PEX1_STN7_TX_DP<115>")
	)
	(segment
		(start 168.698672 -343.365582)
		(end 168.698672 -342.734138)
		(width 0.13462)
		(layer "F.Cu")
		(net "P5E_PEX1_STN7_TX_DP<115>")
	)
	(segment
		(start 168.698672 -342.734138)
		(end 168.404032 -342.439498)
		(width 0.13462)
		(layer "F.Cu")
		(net "P5E_PEX1_STN7_TX_DP<115>")
	)
	(segment
		(start 168.694862 -341.614252)
		(end 168.559734 -341.420196)
		(width 0.1651)
		(layer "In11.Cu")
		(net "P5E_PEX1_STN7_TX_DP<115>")
	)
	(segment
		(start 137.54608 -313.922918)
		(end 141.446504 -308.674262)
		(width 0.1651)
		(layer "In11.Cu")
		(net "P5E_PEX1_STN7_TX_DP<115>")
	)
	(segment
		(start 168.694862 -342.148668)
		(end 168.694862 -341.614252)
		(width 0.1651)
		(layer "In11.Cu")
		(net "P5E_PEX1_STN7_TX_DP<115>")
	)
	(segment
		(start 135.501634 -319.79108)
		(end 135.85825 -317.993522)
		(width 0.1651)
		(layer "In11.Cu")
		(net "P5E_PEX1_STN7_TX_DP<115>")
	)
	(segment
		(start 160.170114 -304.360834)
		(end 160.259014 -304.449734)
		(width 0.1143)
		(layer "In11.Cu")
		(net "P5E_PEX1_STN7_TX_DP<115>")
	)
	(segment
		(start 135.85825 -317.993522)
		(end 137.54608 -313.922918)
		(width 0.1651)
		(layer "In11.Cu")
		(net "P5E_PEX1_STN7_TX_DP<115>")
	)
	(segment
		(start 147.519136 -303.833784)
		(end 151.55672 -303.833784)
		(width 0.1651)
		(layer "In11.Cu")
		(net "P5E_PEX1_STN7_TX_DP<115>")
	)
	(segment
		(start 160.170114 -304.15611)
		(end 160.170114 -304.360834)
		(width 0.1143)
		(layer "In11.Cu")
		(net "P5E_PEX1_STN7_TX_DP<115>")
	)
	(segment
		(start 151.578818 -303.833784)
		(end 151.624538 -303.879504)
		(width 0.1143)
		(layer "In11.Cu")
		(net "P5E_PEX1_STN7_TX_DP<115>")
	)
	(segment
		(start 160.259014 -304.449734)
		(end 160.549844 -304.449734)
		(width 0.1143)
		(layer "In11.Cu")
		(net "P5E_PEX1_STN7_TX_DP<115>")
	)
	(segment
		(start 147.594066 -333.647034)
		(end 143.696182 -331.86751)
		(width 0.1651)
		(layer "In11.Cu")
		(net "P5E_PEX1_STN7_TX_DP<115>")
	)
	(segment
		(start 135.501634 -322.572888)
		(end 135.501634 -319.79108)
		(width 0.1651)
		(layer "In11.Cu")
		(net "P5E_PEX1_STN7_TX_DP<115>")
	)
	(segment
		(start 141.446504 -308.674262)
		(end 145.41627 -304.70475)
		(width 0.1651)
		(layer "In11.Cu")
		(net "P5E_PEX1_STN7_TX_DP<115>")
	)
	(segment
		(start 138.201654 -328.10577)
		(end 136.33069 -325.30796)
		(width 0.1651)
		(layer "In11.Cu")
		(net "P5E_PEX1_STN7_TX_DP<115>")
	)
	(segment
		(start 143.696182 -331.86751)
		(end 139.154916 -328.922888)
		(width 0.1651)
		(layer "In11.Cu")
		(net "P5E_PEX1_STN7_TX_DP<115>")
	)
	(segment
		(start 151.624538 -303.879504)
		(end 159.893508 -303.879504)
		(width 0.1143)
		(layer "In11.Cu")
		(net "P5E_PEX1_STN7_TX_DP<115>")
	)
	(segment
		(start 168.559734 -341.420196)
		(end 147.594066 -333.647034)
		(width 0.1651)
		(layer "In11.Cu")
		(net "P5E_PEX1_STN7_TX_DP<115>")
	)
	(segment
		(start 136.33069 -325.30796)
		(end 135.501634 -322.572888)
		(width 0.1651)
		(layer "In11.Cu")
		(net "P5E_PEX1_STN7_TX_DP<115>")
	)
	(segment
		(start 139.154916 -328.922888)
		(end 138.201654 -328.10577)
		(width 0.1651)
		(layer "In11.Cu")
		(net "P5E_PEX1_STN7_TX_DP<115>")
	)
	(segment
		(start 159.893508 -303.879504)
		(end 160.170114 -304.15611)
		(width 0.1143)
		(layer "In11.Cu")
		(net "P5E_PEX1_STN7_TX_DP<115>")
	)
	(segment
		(start 145.41627 -304.70475)
		(end 147.519136 -303.833784)
		(width 0.1651)
		(layer "In11.Cu")
		(net "P5E_PEX1_STN7_TX_DP<115>")
	)
	(segment
		(start 168.404032 -342.439498)
		(end 168.694862 -342.148668)
		(width 0.1651)
		(layer "In11.Cu")
		(net "P5E_PEX1_STN7_TX_DP<115>")
	)
	(segment
		(start 151.55672 -303.833784)
		(end 151.578818 -303.833784)
		(width 0.1143)
		(layer "In11.Cu")
		(net "P5E_PEX1_STN7_TX_DP<115>")
	)
	(segment
		(start 315.4426 -152.1968)
		(end 315.128148 -152.511252)
		(width 0.13462)
		(layer "F.Cu")
		(net "P5E_PEX2_STN0_TX_DP<13>")
	)
	(segment
		(start 316.374272 -152.485852)
		(end 316.08522 -152.1968)
		(width 0.13462)
		(layer "F.Cu")
		(net "P5E_PEX2_STN0_TX_DP<13>")
	)
	(segment
		(start 316.08522 -152.1968)
		(end 315.4426 -152.1968)
		(width 0.13462)
		(layer "F.Cu")
		(net "P5E_PEX2_STN0_TX_DP<13>")
	)
	(segment
		(start 308.379622 -278.205184)
		(end 308.379622 -271.546066)
		(width 0.1143)
		(layer "In9.Cu")
		(net "P5E_PEX2_STN0_TX_DP<13>")
	)
	(segment
		(start 308.835298 -278.420068)
		(end 308.594506 -278.420068)
		(width 0.1143)
		(layer "In9.Cu")
		(net "P5E_PEX2_STN0_TX_DP<13>")
	)
	(segment
		(start 318.448436 -153.873454)
		(end 318.47663 -153.732484)
		(width 0.1651)
		(layer "In9.Cu")
		(net "P5E_PEX2_STN0_TX_DP<13>")
	)
	(segment
		(start 317.911988 -152.88768)
		(end 317.686436 -152.54986)
		(width 0.1651)
		(layer "In9.Cu")
		(net "P5E_PEX2_STN0_TX_DP<13>")
	)
	(segment
		(start 308.949598 -278.799798)
		(end 308.949598 -278.534368)
		(width 0.1143)
		(layer "In9.Cu")
		(net "P5E_PEX2_STN0_TX_DP<13>")
	)
	(segment
		(start 318.815466 -154.239468)
		(end 318.674496 -154.211528)
		(width 0.1651)
		(layer "In9.Cu")
		(net "P5E_PEX2_STN0_TX_DP<13>")
	)
	(segment
		(start 309.24373 -267.79093)
		(end 309.24373 -260.763004)
		(width 0.1651)
		(layer "In9.Cu")
		(net "P5E_PEX2_STN0_TX_DP<13>")
	)
	(segment
		(start 319.508886 -157.023562)
		(end 319.508886 -155.632658)
		(width 0.1651)
		(layer "In9.Cu")
		(net "P5E_PEX2_STN0_TX_DP<13>")
	)
	(segment
		(start 308.379622 -271.546066)
		(end 308.333902 -271.500346)
		(width 0.1143)
		(layer "In9.Cu")
		(net "P5E_PEX2_STN0_TX_DP<13>")
	)
	(segment
		(start 319.508886 -155.632658)
		(end 319.12179 -154.697938)
		(width 0.1651)
		(layer "In9.Cu")
		(net "P5E_PEX2_STN0_TX_DP<13>")
	)
	(segment
		(start 318.250824 -153.394664)
		(end 318.251078 -153.394664)
		(width 0.1651)
		(layer "In9.Cu")
		(net "P5E_PEX2_STN0_TX_DP<13>")
	)
	(segment
		(start 318.251078 -153.394664)
		(end 318.110108 -153.366724)
		(width 0.1651)
		(layer "In9.Cu")
		(net "P5E_PEX2_STN0_TX_DP<13>")
	)
	(segment
		(start 318.47663 -153.732484)
		(end 318.250824 -153.394664)
		(width 0.1651)
		(layer "In9.Cu")
		(net "P5E_PEX2_STN0_TX_DP<13>")
	)
	(segment
		(start 308.333902 -269.98803)
		(end 309.24373 -267.79093)
		(width 0.1651)
		(layer "In9.Cu")
		(net "P5E_PEX2_STN0_TX_DP<13>")
	)
	(segment
		(start 311.138316 -171.523152)
		(end 319.508886 -157.023562)
		(width 0.1651)
		(layer "In9.Cu")
		(net "P5E_PEX2_STN0_TX_DP<13>")
	)
	(segment
		(start 308.333902 -271.471898)
		(end 308.333902 -269.98803)
		(width 0.1651)
		(layer "In9.Cu")
		(net "P5E_PEX2_STN0_TX_DP<13>")
	)
	(segment
		(start 305.797458 -221.36227)
		(end 309.683404 -176.952402)
		(width 0.1651)
		(layer "In9.Cu")
		(net "P5E_PEX2_STN0_TX_DP<13>")
	)
	(segment
		(start 319.12179 -154.697938)
		(end 318.815466 -154.239468)
		(width 0.1651)
		(layer "In9.Cu")
		(net "P5E_PEX2_STN0_TX_DP<13>")
	)
	(segment
		(start 309.24373 -260.763004)
		(end 305.797458 -221.36227)
		(width 0.1651)
		(layer "In9.Cu")
		(net "P5E_PEX2_STN0_TX_DP<13>")
	)
	(segment
		(start 318.110108 -153.366724)
		(end 317.884048 -153.02865)
		(width 0.1651)
		(layer "In9.Cu")
		(net "P5E_PEX2_STN0_TX_DP<13>")
	)
	(segment
		(start 317.884048 -153.02865)
		(end 317.911988 -152.88768)
		(width 0.1651)
		(layer "In9.Cu")
		(net "P5E_PEX2_STN0_TX_DP<13>")
	)
	(segment
		(start 308.333902 -271.500346)
		(end 308.333902 -271.471898)
		(width 0.1143)
		(layer "In9.Cu")
		(net "P5E_PEX2_STN0_TX_DP<13>")
	)
	(segment
		(start 308.949598 -278.534368)
		(end 308.835298 -278.420068)
		(width 0.1143)
		(layer "In9.Cu")
		(net "P5E_PEX2_STN0_TX_DP<13>")
	)
	(segment
		(start 316.665102 -152.195022)
		(end 316.374272 -152.485852)
		(width 0.1651)
		(layer "In9.Cu")
		(net "P5E_PEX2_STN0_TX_DP<13>")
	)
	(segment
		(start 318.674496 -154.211528)
		(end 318.448436 -153.873454)
		(width 0.1651)
		(layer "In9.Cu")
		(net "P5E_PEX2_STN0_TX_DP<13>")
	)
	(segment
		(start 317.686436 -152.54986)
		(end 317.331598 -152.195022)
		(width 0.1651)
		(layer "In9.Cu")
		(net "P5E_PEX2_STN0_TX_DP<13>")
	)
	(segment
		(start 309.683404 -176.952402)
		(end 311.138316 -171.523152)
		(width 0.1651)
		(layer "In9.Cu")
		(net "P5E_PEX2_STN0_TX_DP<13>")
	)
	(segment
		(start 308.594506 -278.420068)
		(end 308.379622 -278.205184)
		(width 0.1143)
		(layer "In9.Cu")
		(net "P5E_PEX2_STN0_TX_DP<13>")
	)
	(segment
		(start 317.331598 -152.195022)
		(end 316.665102 -152.195022)
		(width 0.1651)
		(layer "In9.Cu")
		(net "P5E_PEX2_STN0_TX_DP<13>")
	)
	(segment
		(start 331.725524 -342.734138)
		(end 332.020164 -342.439498)
		(width 0.13462)
		(layer "F.Cu")
		(net "P5E_PEX2_STN6_TX_DN<103>")
	)
	(segment
		(start 332.045564 -343.685622)
		(end 331.725524 -343.365582)
		(width 0.13462)
		(layer "F.Cu")
		(net "P5E_PEX2_STN6_TX_DN<103>")
	)
	(segment
		(start 331.725524 -343.365582)
		(end 331.725524 -342.734138)
		(width 0.13462)
		(layer "F.Cu")
		(net "P5E_PEX2_STN6_TX_DN<103>")
	)
	(segment
		(start 332.020164 -342.439498)
		(end 331.729334 -342.148668)
		(width 0.1651)
		(layer "In13.Cu")
		(net "P5E_PEX2_STN6_TX_DN<103>")
	)
	(segment
		(start 282.965906 -319.966848)
		(end 282.920186 -319.921128)
		(width 0.1143)
		(layer "In13.Cu")
		(net "P5E_PEX2_STN6_TX_DN<103>")
	)
	(segment
		(start 331.729334 -341.633302)
		(end 329.565254 -338.8868)
		(width 0.1651)
		(layer "In13.Cu")
		(net "P5E_PEX2_STN6_TX_DN<103>")
	)
	(segment
		(start 282.965906 -319.995296)
		(end 282.965906 -319.966848)
		(width 0.1143)
		(layer "In13.Cu")
		(net "P5E_PEX2_STN6_TX_DN<103>")
	)
	(segment
		(start 293.464234 -328.055732)
		(end 293.38397 -327.936352)
		(width 0.1651)
		(layer "In13.Cu")
		(net "P5E_PEX2_STN6_TX_DN<103>")
	)
	(segment
		(start 283.023818 -311.670192)
		(end 283.185616 -311.670192)
		(width 0.1143)
		(layer "In13.Cu")
		(net "P5E_PEX2_STN6_TX_DN<103>")
	)
	(segment
		(start 292.89756 -327.841102)
		(end 292.778434 -327.921366)
		(width 0.1651)
		(layer "In13.Cu")
		(net "P5E_PEX2_STN6_TX_DN<103>")
	)
	(segment
		(start 329.565254 -338.8868)
		(end 314.921138 -332.257908)
		(width 0.1651)
		(layer "In13.Cu")
		(net "P5E_PEX2_STN6_TX_DN<103>")
	)
	(segment
		(start 314.921138 -332.257908)
		(end 293.464234 -328.055732)
		(width 0.1651)
		(layer "In13.Cu")
		(net "P5E_PEX2_STN6_TX_DN<103>")
	)
	(segment
		(start 282.920186 -311.773824)
		(end 283.023818 -311.670192)
		(width 0.1143)
		(layer "In13.Cu")
		(net "P5E_PEX2_STN6_TX_DN<103>")
	)
	(segment
		(start 282.965906 -323.268594)
		(end 282.965906 -319.995296)
		(width 0.1651)
		(layer "In13.Cu")
		(net "P5E_PEX2_STN6_TX_DN<103>")
	)
	(segment
		(start 293.38397 -327.936352)
		(end 292.89756 -327.841102)
		(width 0.1651)
		(layer "In13.Cu")
		(net "P5E_PEX2_STN6_TX_DN<103>")
	)
	(segment
		(start 282.920186 -319.921128)
		(end 282.920186 -311.773824)
		(width 0.1143)
		(layer "In13.Cu")
		(net "P5E_PEX2_STN6_TX_DN<103>")
	)
	(segment
		(start 292.778434 -327.921366)
		(end 285.595568 -326.514714)
		(width 0.1651)
		(layer "In13.Cu")
		(net "P5E_PEX2_STN6_TX_DN<103>")
	)
	(segment
		(start 331.729334 -342.148668)
		(end 331.729334 -341.633302)
		(width 0.1651)
		(layer "In13.Cu")
		(net "P5E_PEX2_STN6_TX_DN<103>")
	)
	(segment
		(start 283.402024 -324.321424)
		(end 282.965906 -323.268594)
		(width 0.1651)
		(layer "In13.Cu")
		(net "P5E_PEX2_STN6_TX_DN<103>")
	)
	(segment
		(start 283.185616 -311.670192)
		(end 283.299916 -311.784492)
		(width 0.1143)
		(layer "In13.Cu")
		(net "P5E_PEX2_STN6_TX_DN<103>")
	)
	(segment
		(start 283.299916 -311.784492)
		(end 283.299916 -312.049922)
		(width 0.1143)
		(layer "In13.Cu")
		(net "P5E_PEX2_STN6_TX_DN<103>")
	)
	(segment
		(start 285.595568 -326.514714)
		(end 283.402024 -324.321424)
		(width 0.1651)
		(layer "In13.Cu")
		(net "P5E_PEX2_STN6_TX_DN<103>")
	)
	(segment
		(start 383.727198 -105.283)
		(end 384.344926 -105.283)
		(width 0.13462)
		(layer "F.Cu")
		(net "P5E_PEX3_STN1_TX_DP<19>")
	)
	(segment
		(start 384.344926 -105.283)
		(end 384.671824 -105.609898)
		(width 0.13462)
		(layer "F.Cu")
		(net "P5E_PEX3_STN1_TX_DP<19>")
	)
	(segment
		(start 383.4257 -105.584498)
		(end 383.727198 -105.283)
		(width 0.13462)
		(layer "F.Cu")
		(net "P5E_PEX3_STN1_TX_DP<19>")
	)
	(segment
		(start 381.37719 -106.667808)
		(end 381.02667 -107.018328)
		(width 0.1651)
		(layer "In9.Cu")
		(net "P5E_PEX3_STN1_TX_DP<19>")
	)
	(segment
		(start 410.52369 -280.129488)
		(end 410.685488 -280.129488)
		(width 0.1143)
		(layer "In9.Cu")
		(net "P5E_PEX3_STN1_TX_DP<19>")
	)
	(segment
		(start 374.250204 -144.596358)
		(end 374.965976 -159.178498)
		(width 0.1651)
		(layer "In9.Cu")
		(net "P5E_PEX3_STN1_TX_DP<19>")
	)
	(segment
		(start 377.807474 -112.76457)
		(end 377.61799 -113.222532)
		(width 0.1651)
		(layer "In9.Cu")
		(net "P5E_PEX3_STN1_TX_DP<19>")
	)
	(segment
		(start 410.465778 -271.554448)
		(end 410.420058 -271.600168)
		(width 0.1143)
		(layer "In9.Cu")
		(net "P5E_PEX3_STN1_TX_DP<19>")
	)
	(segment
		(start 410.420058 -280.025856)
		(end 410.52369 -280.129488)
		(width 0.1143)
		(layer "In9.Cu")
		(net "P5E_PEX3_STN1_TX_DP<19>")
	)
	(segment
		(start 381.889 -106.155998)
		(end 381.727202 -106.155998)
		(width 0.1651)
		(layer "In9.Cu")
		(net "P5E_PEX3_STN1_TX_DP<19>")
	)
	(segment
		(start 371.690392 -138.417046)
		(end 374.250204 -144.596358)
		(width 0.1651)
		(layer "In9.Cu")
		(net "P5E_PEX3_STN1_TX_DP<19>")
	)
	(segment
		(start 410.799788 -280.015188)
		(end 410.799788 -279.749504)
		(width 0.1143)
		(layer "In9.Cu")
		(net "P5E_PEX3_STN1_TX_DP<19>")
	)
	(segment
		(start 377.340876 -113.89106)
		(end 377.151392 -114.349022)
		(width 0.1651)
		(layer "In9.Cu")
		(net "P5E_PEX3_STN1_TX_DP<19>")
	)
	(segment
		(start 382.23952 -105.64368)
		(end 382.23952 -105.805478)
		(width 0.1651)
		(layer "In9.Cu")
		(net "P5E_PEX3_STN1_TX_DP<19>")
	)
	(segment
		(start 377.00204 -114.410744)
		(end 376.074178 -116.651278)
		(width 0.1651)
		(layer "In9.Cu")
		(net "P5E_PEX3_STN1_TX_DP<19>")
	)
	(segment
		(start 380.864872 -107.018328)
		(end 380.51486 -107.36834)
		(width 0.1651)
		(layer "In9.Cu")
		(net "P5E_PEX3_STN1_TX_DP<19>")
	)
	(segment
		(start 378.740416 -110.51159)
		(end 378.550932 -110.969552)
		(width 0.1651)
		(layer "In9.Cu")
		(net "P5E_PEX3_STN1_TX_DP<19>")
	)
	(segment
		(start 375.564908 -162.189414)
		(end 410.465778 -265.298682)
		(width 0.1651)
		(layer "In9.Cu")
		(net "P5E_PEX3_STN1_TX_DP<19>")
	)
	(segment
		(start 377.745498 -112.615218)
		(end 377.807474 -112.76457)
		(width 0.1651)
		(layer "In9.Cu")
		(net "P5E_PEX3_STN1_TX_DP<19>")
	)
	(segment
		(start 379.01753 -109.843062)
		(end 378.867924 -109.904784)
		(width 0.1651)
		(layer "In9.Cu")
		(net "P5E_PEX3_STN1_TX_DP<19>")
	)
	(segment
		(start 383.4257 -105.584498)
		(end 383.13487 -105.293668)
		(width 0.1651)
		(layer "In9.Cu")
		(net "P5E_PEX3_STN1_TX_DP<19>")
	)
	(segment
		(start 410.465778 -265.298682)
		(end 410.465778 -271.526)
		(width 0.1651)
		(layer "In9.Cu")
		(net "P5E_PEX3_STN1_TX_DP<19>")
	)
	(segment
		(start 377.468384 -113.284254)
		(end 377.2789 -113.741708)
		(width 0.1651)
		(layer "In9.Cu")
		(net "P5E_PEX3_STN1_TX_DP<19>")
	)
	(segment
		(start 380.16434 -107.862624)
		(end 380.020576 -107.862624)
		(width 0.1651)
		(layer "In9.Cu")
		(net "P5E_PEX3_STN1_TX_DP<19>")
	)
	(segment
		(start 380.51486 -107.36834)
		(end 380.51486 -107.512104)
		(width 0.1651)
		(layer "In9.Cu")
		(net "P5E_PEX3_STN1_TX_DP<19>")
	)
	(segment
		(start 380.51486 -107.512104)
		(end 380.16434 -107.862624)
		(width 0.1651)
		(layer "In9.Cu")
		(net "P5E_PEX3_STN1_TX_DP<19>")
	)
	(segment
		(start 379.497082 -108.385864)
		(end 379.145038 -109.235748)
		(width 0.1651)
		(layer "In9.Cu")
		(net "P5E_PEX3_STN1_TX_DP<19>")
	)
	(segment
		(start 410.685488 -280.129488)
		(end 410.799788 -280.015188)
		(width 0.1143)
		(layer "In9.Cu")
		(net "P5E_PEX3_STN1_TX_DP<19>")
	)
	(segment
		(start 378.40158 -111.031274)
		(end 378.212096 -111.488728)
		(width 0.1651)
		(layer "In9.Cu")
		(net "P5E_PEX3_STN1_TX_DP<19>")
	)
	(segment
		(start 379.207014 -109.3851)
		(end 379.01753 -109.843062)
		(width 0.1651)
		(layer "In9.Cu")
		(net "P5E_PEX3_STN1_TX_DP<19>")
	)
	(segment
		(start 377.934728 -112.157764)
		(end 377.934982 -112.157764)
		(width 0.1651)
		(layer "In9.Cu")
		(net "P5E_PEX3_STN1_TX_DP<19>")
	)
	(segment
		(start 377.61799 -113.222532)
		(end 377.468384 -113.284254)
		(width 0.1651)
		(layer "In9.Cu")
		(net "P5E_PEX3_STN1_TX_DP<19>")
	)
	(segment
		(start 410.420058 -271.600168)
		(end 410.420058 -280.025856)
		(width 0.1143)
		(layer "In9.Cu")
		(net "P5E_PEX3_STN1_TX_DP<19>")
	)
	(segment
		(start 381.02667 -107.018328)
		(end 380.864872 -107.018328)
		(width 0.1651)
		(layer "In9.Cu")
		(net "P5E_PEX3_STN1_TX_DP<19>")
	)
	(segment
		(start 377.001786 -114.410744)
		(end 377.00204 -114.410744)
		(width 0.1651)
		(layer "In9.Cu")
		(net "P5E_PEX3_STN1_TX_DP<19>")
	)
	(segment
		(start 377.934982 -112.157764)
		(end 377.745498 -112.615218)
		(width 0.1651)
		(layer "In9.Cu")
		(net "P5E_PEX3_STN1_TX_DP<19>")
	)
	(segment
		(start 381.37719 -106.50601)
		(end 381.37719 -106.667808)
		(width 0.1651)
		(layer "In9.Cu")
		(net "P5E_PEX3_STN1_TX_DP<19>")
	)
	(segment
		(start 377.151392 -114.349022)
		(end 377.001786 -114.410744)
		(width 0.1651)
		(layer "In9.Cu")
		(net "P5E_PEX3_STN1_TX_DP<19>")
	)
	(segment
		(start 383.13487 -105.293668)
		(end 382.589532 -105.293668)
		(width 0.1651)
		(layer "In9.Cu")
		(net "P5E_PEX3_STN1_TX_DP<19>")
	)
	(segment
		(start 374.965976 -159.178498)
		(end 375.564908 -162.189414)
		(width 0.1651)
		(layer "In9.Cu")
		(net "P5E_PEX3_STN1_TX_DP<19>")
	)
	(segment
		(start 376.074178 -116.651278)
		(end 371.690392 -131.101338)
		(width 0.1651)
		(layer "In9.Cu")
		(net "P5E_PEX3_STN1_TX_DP<19>")
	)
	(segment
		(start 379.145038 -109.235748)
		(end 379.207014 -109.3851)
		(width 0.1651)
		(layer "In9.Cu")
		(net "P5E_PEX3_STN1_TX_DP<19>")
	)
	(segment
		(start 378.550932 -110.969552)
		(end 378.401326 -111.031274)
		(width 0.1651)
		(layer "In9.Cu")
		(net "P5E_PEX3_STN1_TX_DP<19>")
	)
	(segment
		(start 382.23952 -105.805478)
		(end 381.889 -106.155998)
		(width 0.1651)
		(layer "In9.Cu")
		(net "P5E_PEX3_STN1_TX_DP<19>")
	)
	(segment
		(start 378.867924 -109.904784)
		(end 378.67844 -110.362238)
		(width 0.1651)
		(layer "In9.Cu")
		(net "P5E_PEX3_STN1_TX_DP<19>")
	)
	(segment
		(start 371.690392 -131.101338)
		(end 371.690392 -138.417046)
		(width 0.1651)
		(layer "In9.Cu")
		(net "P5E_PEX3_STN1_TX_DP<19>")
	)
	(segment
		(start 380.020576 -107.862624)
		(end 379.497336 -108.385864)
		(width 0.1651)
		(layer "In9.Cu")
		(net "P5E_PEX3_STN1_TX_DP<19>")
	)
	(segment
		(start 410.465778 -271.526)
		(end 410.465778 -271.554448)
		(width 0.1143)
		(layer "In9.Cu")
		(net "P5E_PEX3_STN1_TX_DP<19>")
	)
	(segment
		(start 377.2789 -113.741708)
		(end 377.340876 -113.89106)
		(width 0.1651)
		(layer "In9.Cu")
		(net "P5E_PEX3_STN1_TX_DP<19>")
	)
	(segment
		(start 378.084334 -112.096042)
		(end 377.934728 -112.157764)
		(width 0.1651)
		(layer "In9.Cu")
		(net "P5E_PEX3_STN1_TX_DP<19>")
	)
	(segment
		(start 378.212096 -111.488728)
		(end 378.211842 -111.488728)
		(width 0.1651)
		(layer "In9.Cu")
		(net "P5E_PEX3_STN1_TX_DP<19>")
	)
	(segment
		(start 382.589532 -105.293668)
		(end 382.23952 -105.64368)
		(width 0.1651)
		(layer "In9.Cu")
		(net "P5E_PEX3_STN1_TX_DP<19>")
	)
	(segment
		(start 379.497336 -108.385864)
		(end 379.497082 -108.385864)
		(width 0.1651)
		(layer "In9.Cu")
		(net "P5E_PEX3_STN1_TX_DP<19>")
	)
	(segment
		(start 381.727202 -106.155998)
		(end 381.37719 -106.50601)
		(width 0.1651)
		(layer "In9.Cu")
		(net "P5E_PEX3_STN1_TX_DP<19>")
	)
	(segment
		(start 378.273818 -111.63808)
		(end 378.084334 -112.096042)
		(width 0.1651)
		(layer "In9.Cu")
		(net "P5E_PEX3_STN1_TX_DP<19>")
	)
	(segment
		(start 378.401326 -111.031274)
		(end 378.40158 -111.031274)
		(width 0.1651)
		(layer "In9.Cu")
		(net "P5E_PEX3_STN1_TX_DP<19>")
	)
	(segment
		(start 378.67844 -110.362238)
		(end 378.740416 -110.51159)
		(width 0.1651)
		(layer "In9.Cu")
		(net "P5E_PEX3_STN1_TX_DP<19>")
	)
	(segment
		(start 378.211842 -111.488728)
		(end 378.273818 -111.63808)
		(width 0.1651)
		(layer "In9.Cu")
		(net "P5E_PEX3_STN1_TX_DP<19>")
	)
	(segment
		(start 274.133818 -320.043048)
		(end 274.133818 -320.0146)
		(width 0.1143)
		(layer "In5.Cu")
		(net "P5E_PEX2_STN7_RX_DP<127>")
	)
	(segment
		(start 274.405344 -318.129666)
		(end 274.635468 -318.129666)
		(width 0.1143)
		(layer "In5.Cu")
		(net "P5E_PEX2_STN7_RX_DP<127>")
	)
	(segment
		(start 302.340518 -362.557568)
		(end 302.101758 -360.439208)
		(width 0.1651)
		(layer "In5.Cu")
		(net "P5E_PEX2_STN7_RX_DP<127>")
	)
	(segment
		(start 302.88992 -383.290064)
		(end 302.88992 -383.67208)
		(width 0.1651)
		(layer "In5.Cu")
		(net "P5E_PEX2_STN7_RX_DP<127>")
	)
	(segment
		(start 303.733962 -369.13566)
		(end 303.350422 -367.32591)
		(width 0.1651)
		(layer "In5.Cu")
		(net "P5E_PEX2_STN7_RX_DP<127>")
	)
	(segment
		(start 302.982376 -366.079532)
		(end 302.87976 -365.5949)
		(width 0.1651)
		(layer "In5.Cu")
		(net "P5E_PEX2_STN7_RX_DP<127>")
	)
	(segment
		(start 302.101758 -360.439208)
		(end 301.815246 -342.195404)
		(width 0.1651)
		(layer "In5.Cu")
		(net "P5E_PEX2_STN7_RX_DP<127>")
	)
	(segment
		(start 303.733962 -383.487422)
		(end 303.733962 -369.13566)
		(width 0.1651)
		(layer "In5.Cu")
		(net "P5E_PEX2_STN7_RX_DP<127>")
	)
	(segment
		(start 274.133818 -320.0146)
		(end 274.179538 -319.96888)
		(width 0.1143)
		(layer "In5.Cu")
		(net "P5E_PEX2_STN7_RX_DP<127>")
	)
	(segment
		(start 274.635468 -318.129666)
		(end 274.749768 -318.015366)
		(width 0.1143)
		(layer "In5.Cu")
		(net "P5E_PEX2_STN7_RX_DP<127>")
	)
	(segment
		(start 303.205642 -366.642396)
		(end 303.103026 -366.158018)
		(width 0.1651)
		(layer "In5.Cu")
		(net "P5E_PEX2_STN7_RX_DP<127>")
	)
	(segment
		(start 277.673308 -328.13244)
		(end 276.042882 -327.101708)
		(width 0.1651)
		(layer "In5.Cu")
		(net "P5E_PEX2_STN7_RX_DP<127>")
	)
	(segment
		(start 302.88992 -383.67208)
		(end 303.01692 -383.79908)
		(width 0.1651)
		(layer "In5.Cu")
		(net "P5E_PEX2_STN7_RX_DP<127>")
	)
	(segment
		(start 301.092108 -340.752684)
		(end 277.673308 -328.13244)
		(width 0.1651)
		(layer "In5.Cu")
		(net "P5E_PEX2_STN7_RX_DP<127>")
	)
	(segment
		(start 274.179538 -318.355472)
		(end 274.405344 -318.129666)
		(width 0.1143)
		(layer "In5.Cu")
		(net "P5E_PEX2_STN7_RX_DP<127>")
	)
	(segment
		(start 302.958246 -365.47425)
		(end 302.340518 -362.557568)
		(width 0.1651)
		(layer "In5.Cu")
		(net "P5E_PEX2_STN7_RX_DP<127>")
	)
	(segment
		(start 274.133818 -324.364858)
		(end 274.133818 -320.043048)
		(width 0.1651)
		(layer "In5.Cu")
		(net "P5E_PEX2_STN7_RX_DP<127>")
	)
	(segment
		(start 303.350676 -367.32591)
		(end 303.230026 -367.247678)
		(width 0.1651)
		(layer "In5.Cu")
		(net "P5E_PEX2_STN7_RX_DP<127>")
	)
	(segment
		(start 303.422304 -383.79908)
		(end 303.733962 -383.487422)
		(width 0.1651)
		(layer "In5.Cu")
		(net "P5E_PEX2_STN7_RX_DP<127>")
	)
	(segment
		(start 303.230026 -367.247678)
		(end 303.12741 -366.762792)
		(width 0.1651)
		(layer "In5.Cu")
		(net "P5E_PEX2_STN7_RX_DP<127>")
	)
	(segment
		(start 274.179538 -319.96888)
		(end 274.179538 -318.355472)
		(width 0.1143)
		(layer "In5.Cu")
		(net "P5E_PEX2_STN7_RX_DP<127>")
	)
	(segment
		(start 276.042882 -327.101708)
		(end 274.606258 -325.505572)
		(width 0.1651)
		(layer "In5.Cu")
		(net "P5E_PEX2_STN7_RX_DP<127>")
	)
	(segment
		(start 274.606258 -325.505572)
		(end 274.133818 -324.364858)
		(width 0.1651)
		(layer "In5.Cu")
		(net "P5E_PEX2_STN7_RX_DP<127>")
	)
	(segment
		(start 303.01692 -383.79908)
		(end 303.422304 -383.79908)
		(width 0.1651)
		(layer "In5.Cu")
		(net "P5E_PEX2_STN7_RX_DP<127>")
	)
	(segment
		(start 301.815246 -342.195404)
		(end 301.615602 -341.547704)
		(width 0.1651)
		(layer "In5.Cu")
		(net "P5E_PEX2_STN7_RX_DP<127>")
	)
	(segment
		(start 303.12741 -366.762792)
		(end 303.205642 -366.642396)
		(width 0.1651)
		(layer "In5.Cu")
		(net "P5E_PEX2_STN7_RX_DP<127>")
	)
	(segment
		(start 303.350422 -367.32591)
		(end 303.350676 -367.32591)
		(width 0.1651)
		(layer "In5.Cu")
		(net "P5E_PEX2_STN7_RX_DP<127>")
	)
	(segment
		(start 274.749768 -318.015366)
		(end 274.749768 -317.749936)
		(width 0.1143)
		(layer "In5.Cu")
		(net "P5E_PEX2_STN7_RX_DP<127>")
	)
	(segment
		(start 301.615602 -341.547704)
		(end 301.092108 -340.752684)
		(width 0.1651)
		(layer "In5.Cu")
		(net "P5E_PEX2_STN7_RX_DP<127>")
	)
	(segment
		(start 302.87976 -365.5949)
		(end 302.958246 -365.47425)
		(width 0.1651)
		(layer "In5.Cu")
		(net "P5E_PEX2_STN7_RX_DP<127>")
	)
	(segment
		(start 303.103026 -366.158018)
		(end 302.982376 -366.079532)
		(width 0.1651)
		(layer "In5.Cu")
		(net "P5E_PEX2_STN7_RX_DP<127>")
	)
	(segment
		(start 191.030352 -351.611438)
		(end 190.735712 -351.316798)
		(width 0.13462)
		(layer "F.Cu")
		(net "P5E_PEX1_STN7_TX_C_DN<126>")
	)
	(segment
		(start 190.735712 -350.685354)
		(end 191.055752 -350.365314)
		(width 0.13462)
		(layer "F.Cu")
		(net "P5E_PEX1_STN7_TX_C_DN<126>")
	)
	(segment
		(start 190.735712 -351.316798)
		(end 190.735712 -350.685354)
		(width 0.13462)
		(layer "F.Cu")
		(net "P5E_PEX1_STN7_TX_C_DN<126>")
	)
	(segment
		(start 173.575218 -375.181114)
		(end 174.267368 -374.488964)
		(width 0.1651)
		(layer "In11.Cu")
		(net "P5E_PEX1_STN7_TX_C_DN<126>")
	)
	(segment
		(start 174.953422 -368.25301)
		(end 184.074562 -364.42396)
		(width 0.1651)
		(layer "In11.Cu")
		(net "P5E_PEX1_STN7_TX_C_DN<126>")
	)
	(segment
		(start 173.10989 -375.308114)
		(end 173.23689 -375.181114)
		(width 0.1651)
		(layer "In11.Cu")
		(net "P5E_PEX1_STN7_TX_C_DN<126>")
	)
	(segment
		(start 173.10989 -375.69013)
		(end 173.10989 -375.308114)
		(width 0.1651)
		(layer "In11.Cu")
		(net "P5E_PEX1_STN7_TX_C_DN<126>")
	)
	(segment
		(start 174.267368 -368.939064)
		(end 174.953422 -368.25301)
		(width 0.1651)
		(layer "In11.Cu")
		(net "P5E_PEX1_STN7_TX_C_DN<126>")
	)
	(segment
		(start 174.267368 -374.488964)
		(end 174.267368 -368.939064)
		(width 0.1651)
		(layer "In11.Cu")
		(net "P5E_PEX1_STN7_TX_C_DN<126>")
	)
	(segment
		(start 184.074562 -364.42396)
		(end 190.739522 -357.759)
		(width 0.1651)
		(layer "In11.Cu")
		(net "P5E_PEX1_STN7_TX_C_DN<126>")
	)
	(segment
		(start 190.739522 -357.759)
		(end 190.739522 -351.902268)
		(width 0.1651)
		(layer "In11.Cu")
		(net "P5E_PEX1_STN7_TX_C_DN<126>")
	)
	(segment
		(start 190.739522 -351.902268)
		(end 191.030352 -351.611438)
		(width 0.1651)
		(layer "In11.Cu")
		(net "P5E_PEX1_STN7_TX_C_DN<126>")
	)
	(segment
		(start 173.23689 -375.181114)
		(end 173.575218 -375.181114)
		(width 0.1651)
		(layer "In11.Cu")
		(net "P5E_PEX1_STN7_TX_C_DN<126>")
	)
	(segment
		(start 131.084828 -355.658166)
		(end 131.084828 -355.026722)
		(width 0.13462)
		(layer "F.Cu")
		(net "P5E_PEX1_STN5_TX_DN<89>")
	)
	(segment
		(start 131.084828 -355.026722)
		(end 131.379468 -354.732082)
		(width 0.13462)
		(layer "F.Cu")
		(net "P5E_PEX1_STN5_TX_DN<89>")
	)
	(segment
		(start 131.404868 -355.978206)
		(end 131.084828 -355.658166)
		(width 0.13462)
		(layer "F.Cu")
		(net "P5E_PEX1_STN5_TX_DN<89>")
	)
	(segment
		(start 131.088638 -354.441252)
		(end 131.379468 -354.732082)
		(width 0.1651)
		(layer "In13.Cu")
		(net "P5E_PEX1_STN5_TX_DN<89>")
	)
	(segment
		(start 182.727346 -321.291966)
		(end 181.733698 -321.955922)
		(width 0.1651)
		(layer "In13.Cu")
		(net "P5E_PEX1_STN5_TX_DN<89>")
	)
	(segment
		(start 177.141632 -324.410832)
		(end 177.141378 -324.411086)
		(width 0.1651)
		(layer "In13.Cu")
		(net "P5E_PEX1_STN5_TX_DN<89>")
	)
	(segment
		(start 182.97017 -313.673744)
		(end 182.97017 -319.995296)
		(width 0.1143)
		(layer "In13.Cu")
		(net "P5E_PEX1_STN5_TX_DN<89>")
	)
	(segment
		(start 131.088638 -353.910646)
		(end 131.088638 -354.441252)
		(width 0.1651)
		(layer "In13.Cu")
		(net "P5E_PEX1_STN5_TX_DN<89>")
	)
	(segment
		(start 183.01589 -321.003422)
		(end 182.727346 -321.291966)
		(width 0.1651)
		(layer "In13.Cu")
		(net "P5E_PEX1_STN5_TX_DN<89>")
	)
	(segment
		(start 147.48891 -336.029046)
		(end 142.339568 -336.029046)
		(width 0.1651)
		(layer "In13.Cu")
		(net "P5E_PEX1_STN5_TX_DN<89>")
	)
	(segment
		(start 182.97017 -319.995296)
		(end 183.01589 -320.041016)
		(width 0.1143)
		(layer "In13.Cu")
		(net "P5E_PEX1_STN5_TX_DN<89>")
	)
	(segment
		(start 183.2356 -313.570112)
		(end 183.073802 -313.570112)
		(width 0.1143)
		(layer "In13.Cu")
		(net "P5E_PEX1_STN5_TX_DN<89>")
	)
	(segment
		(start 132.643118 -352.356166)
		(end 131.088638 -353.910646)
		(width 0.1651)
		(layer "In13.Cu")
		(net "P5E_PEX1_STN5_TX_DN<89>")
	)
	(segment
		(start 164.187124 -330.46416)
		(end 147.48891 -336.029046)
		(width 0.1651)
		(layer "In13.Cu")
		(net "P5E_PEX1_STN5_TX_DN<89>")
	)
	(segment
		(start 183.01589 -320.063114)
		(end 183.01589 -321.003422)
		(width 0.1651)
		(layer "In13.Cu")
		(net "P5E_PEX1_STN5_TX_DN<89>")
	)
	(segment
		(start 183.3499 -313.949842)
		(end 183.3499 -313.684412)
		(width 0.1143)
		(layer "In13.Cu")
		(net "P5E_PEX1_STN5_TX_DN<89>")
	)
	(segment
		(start 135.26008 -338.96173)
		(end 135.26008 -338.961476)
		(width 0.1651)
		(layer "In13.Cu")
		(net "P5E_PEX1_STN5_TX_DN<89>")
	)
	(segment
		(start 183.073802 -313.570112)
		(end 182.97017 -313.673744)
		(width 0.1143)
		(layer "In13.Cu")
		(net "P5E_PEX1_STN5_TX_DN<89>")
	)
	(segment
		(start 183.3499 -313.684412)
		(end 183.2356 -313.570112)
		(width 0.1143)
		(layer "In13.Cu")
		(net "P5E_PEX1_STN5_TX_DN<89>")
	)
	(segment
		(start 142.339568 -336.029046)
		(end 135.26008 -338.96173)
		(width 0.1651)
		(layer "In13.Cu")
		(net "P5E_PEX1_STN5_TX_DN<89>")
	)
	(segment
		(start 172.55109 -326.86498)
		(end 164.187124 -330.46416)
		(width 0.1651)
		(layer "In13.Cu")
		(net "P5E_PEX1_STN5_TX_DN<89>")
	)
	(segment
		(start 132.643118 -341.578438)
		(end 132.643118 -352.356166)
		(width 0.1651)
		(layer "In13.Cu")
		(net "P5E_PEX1_STN5_TX_DN<89>")
	)
	(segment
		(start 181.733698 -321.955922)
		(end 177.141632 -324.410832)
		(width 0.1651)
		(layer "In13.Cu")
		(net "P5E_PEX1_STN5_TX_DN<89>")
	)
	(segment
		(start 135.26008 -338.961476)
		(end 132.643118 -341.578438)
		(width 0.1651)
		(layer "In13.Cu")
		(net "P5E_PEX1_STN5_TX_DN<89>")
	)
	(segment
		(start 177.141378 -324.411086)
		(end 172.55109 -326.86498)
		(width 0.1651)
		(layer "In13.Cu")
		(net "P5E_PEX1_STN5_TX_DN<89>")
	)
	(segment
		(start 183.01589 -320.041016)
		(end 183.01589 -320.063114)
		(width 0.1143)
		(layer "In13.Cu")
		(net "P5E_PEX1_STN5_TX_DN<89>")
	)
	(segment
		(start 124.866908 -349.511874)
		(end 124.866908 -348.88043)
		(width 0.13462)
		(layer "F.Cu")
		(net "P5E_PEX1_STN6_TX_DN<97>")
	)
	(segment
		(start 124.866908 -348.88043)
		(end 125.161548 -348.58579)
		(width 0.13462)
		(layer "F.Cu")
		(net "P5E_PEX1_STN6_TX_DN<97>")
	)
	(segment
		(start 125.186948 -349.831914)
		(end 124.866908 -349.511874)
		(width 0.13462)
		(layer "F.Cu")
		(net "P5E_PEX1_STN6_TX_DN<97>")
	)
	(segment
		(start 170.564048 -324.134226)
		(end 171.709588 -322.988686)
		(width 0.1651)
		(layer "In7.Cu")
		(net "P5E_PEX1_STN6_TX_DN<97>")
	)
	(segment
		(start 167.936672 -325.709026)
		(end 170.564048 -324.134226)
		(width 0.1651)
		(layer "In7.Cu")
		(net "P5E_PEX1_STN6_TX_DN<97>")
	)
	(segment
		(start 172.634656 -311.670192)
		(end 172.785786 -311.670192)
		(width 0.1143)
		(layer "In7.Cu")
		(net "P5E_PEX1_STN6_TX_DN<97>")
	)
	(segment
		(start 124.870718 -348.29496)
		(end 124.870718 -347.736922)
		(width 0.1651)
		(layer "In7.Cu")
		(net "P5E_PEX1_STN6_TX_DN<97>")
	)
	(segment
		(start 125.161548 -348.58579)
		(end 124.870718 -348.29496)
		(width 0.1651)
		(layer "In7.Cu")
		(net "P5E_PEX1_STN6_TX_DN<97>")
	)
	(segment
		(start 126.425198 -341.308182)
		(end 128.690878 -339.042502)
		(width 0.1651)
		(layer "In7.Cu")
		(net "P5E_PEX1_STN6_TX_DN<97>")
	)
	(segment
		(start 172.566076 -320.920872)
		(end 172.566076 -320.016886)
		(width 0.1651)
		(layer "In7.Cu")
		(net "P5E_PEX1_STN6_TX_DN<97>")
	)
	(segment
		(start 172.520356 -319.942718)
		(end 172.520356 -311.784492)
		(width 0.1143)
		(layer "In7.Cu")
		(net "P5E_PEX1_STN6_TX_DN<97>")
	)
	(segment
		(start 126.425198 -346.182442)
		(end 126.425198 -341.308182)
		(width 0.1651)
		(layer "In7.Cu")
		(net "P5E_PEX1_STN6_TX_DN<97>")
	)
	(segment
		(start 171.709588 -322.988686)
		(end 172.566076 -320.920872)
		(width 0.1651)
		(layer "In7.Cu")
		(net "P5E_PEX1_STN6_TX_DN<97>")
	)
	(segment
		(start 172.900086 -311.784492)
		(end 172.900086 -312.049922)
		(width 0.1143)
		(layer "In7.Cu")
		(net "P5E_PEX1_STN6_TX_DN<97>")
	)
	(segment
		(start 172.520356 -311.784492)
		(end 172.634656 -311.670192)
		(width 0.1143)
		(layer "In7.Cu")
		(net "P5E_PEX1_STN6_TX_DN<97>")
	)
	(segment
		(start 133.516116 -336.150204)
		(end 167.936672 -325.709026)
		(width 0.1651)
		(layer "In7.Cu")
		(net "P5E_PEX1_STN6_TX_DN<97>")
	)
	(segment
		(start 128.690878 -339.042502)
		(end 133.516116 -336.150204)
		(width 0.1651)
		(layer "In7.Cu")
		(net "P5E_PEX1_STN6_TX_DN<97>")
	)
	(segment
		(start 124.870718 -347.736922)
		(end 126.425198 -346.182442)
		(width 0.1651)
		(layer "In7.Cu")
		(net "P5E_PEX1_STN6_TX_DN<97>")
	)
	(segment
		(start 172.566076 -320.016886)
		(end 172.566076 -319.988438)
		(width 0.1143)
		(layer "In7.Cu")
		(net "P5E_PEX1_STN6_TX_DN<97>")
	)
	(segment
		(start 172.566076 -319.988438)
		(end 172.520356 -319.942718)
		(width 0.1143)
		(layer "In7.Cu")
		(net "P5E_PEX1_STN6_TX_DN<97>")
	)
	(segment
		(start 172.785786 -311.670192)
		(end 172.900086 -311.784492)
		(width 0.1143)
		(layer "In7.Cu")
		(net "P5E_PEX1_STN6_TX_DN<97>")
	)
	(segment
		(start 313.431682 -134.06882)
		(end 312.811922 -134.06882)
		(width 0.13462)
		(layer "F.Cu")
		(net "P5E_PEX2_STN0_TX_DP<6>")
	)
	(segment
		(start 313.732164 -134.369302)
		(end 313.431682 -134.06882)
		(width 0.13462)
		(layer "F.Cu")
		(net "P5E_PEX2_STN0_TX_DP<6>")
	)
	(segment
		(start 312.811922 -134.06882)
		(end 312.48604 -134.394702)
		(width 0.13462)
		(layer "F.Cu")
		(net "P5E_PEX2_STN0_TX_DP<6>")
	)
	(segment
		(start 315.35624 -134.185152)
		(end 315.46292 -134.078472)
		(width 0.1651)
		(layer "In9.Cu")
		(net "P5E_PEX2_STN0_TX_DP<6>")
	)
	(segment
		(start 326.283066 -153.984706)
		(end 326.283066 -158.922212)
		(width 0.1651)
		(layer "In9.Cu")
		(net "P5E_PEX2_STN0_TX_DP<6>")
	)
	(segment
		(start 316.534546 -178.151028)
		(end 312.729626 -221.640654)
		(width 0.1651)
		(layer "In9.Cu")
		(net "P5E_PEX2_STN0_TX_DP<6>")
	)
	(segment
		(start 326.283066 -158.922212)
		(end 317.706248 -173.78172)
		(width 0.1651)
		(layer "In9.Cu")
		(net "P5E_PEX2_STN0_TX_DP<6>")
	)
	(segment
		(start 319.763902 -139.161774)
		(end 319.938908 -139.58443)
		(width 0.1651)
		(layer "In9.Cu")
		(net "P5E_PEX2_STN0_TX_DP<6>")
	)
	(segment
		(start 313.732164 -134.369302)
		(end 314.022994 -134.078472)
		(width 0.1651)
		(layer "In9.Cu")
		(net "P5E_PEX2_STN0_TX_DP<6>")
	)
	(segment
		(start 316.767464 -281.983942)
		(end 316.117478 -281.983942)
		(width 0.1651)
		(layer "In9.Cu")
		(net "P5E_PEX2_STN0_TX_DP<6>")
	)
	(segment
		(start 318.356996 -135.499094)
		(end 318.531748 -135.921242)
		(width 0.1651)
		(layer "In9.Cu")
		(net "P5E_PEX2_STN0_TX_DP<6>")
	)
	(segment
		(start 318.788542 -136.541256)
		(end 318.963294 -136.963404)
		(width 0.1651)
		(layer "In9.Cu")
		(net "P5E_PEX2_STN0_TX_DP<6>")
	)
	(segment
		(start 320.366898 -140.61694)
		(end 320.49974 -140.672058)
		(width 0.1651)
		(layer "In9.Cu")
		(net "P5E_PEX2_STN0_TX_DP<6>")
	)
	(segment
		(start 318.90843 -137.096246)
		(end 319.083436 -137.518902)
		(width 0.1651)
		(layer "In9.Cu")
		(net "P5E_PEX2_STN0_TX_DP<6>")
	)
	(segment
		(start 319.39103 -137.996168)
		(end 319.336166 -138.12901)
		(width 0.1651)
		(layer "In9.Cu")
		(net "P5E_PEX2_STN0_TX_DP<6>")
	)
	(segment
		(start 319.083436 -137.518902)
		(end 319.216278 -137.57402)
		(width 0.1651)
		(layer "In9.Cu")
		(net "P5E_PEX2_STN0_TX_DP<6>")
	)
	(segment
		(start 316.342268 -134.253224)
		(end 316.40018 -134.392924)
		(width 0.1651)
		(layer "In9.Cu")
		(net "P5E_PEX2_STN0_TX_DP<6>")
	)
	(segment
		(start 314.89904 -134.185152)
		(end 315.35624 -134.185152)
		(width 0.1651)
		(layer "In9.Cu")
		(net "P5E_PEX2_STN0_TX_DP<6>")
	)
	(segment
		(start 309.329582 -282.485592)
		(end 309.215282 -282.599892)
		(width 0.1143)
		(layer "In9.Cu")
		(net "P5E_PEX2_STN0_TX_DP<6>")
	)
	(segment
		(start 312.729626 -221.640654)
		(end 312.731658 -221.665038)
		(width 0.1651)
		(layer "In9.Cu")
		(net "P5E_PEX2_STN0_TX_DP<6>")
	)
	(segment
		(start 309.215282 -282.599892)
		(end 308.949852 -282.599892)
		(width 0.1143)
		(layer "In9.Cu")
		(net "P5E_PEX2_STN0_TX_DP<6>")
	)
	(segment
		(start 319.938908 -139.58443)
		(end 320.072004 -139.639294)
		(width 0.1651)
		(layer "In9.Cu")
		(net "P5E_PEX2_STN0_TX_DP<6>")
	)
	(segment
		(start 316.40018 -134.392924)
		(end 316.822836 -134.56793)
		(width 0.1651)
		(layer "In9.Cu")
		(net "P5E_PEX2_STN0_TX_DP<6>")
	)
	(segment
		(start 319.511172 -138.551666)
		(end 319.644014 -138.606784)
		(width 0.1651)
		(layer "In9.Cu")
		(net "P5E_PEX2_STN0_TX_DP<6>")
	)
	(segment
		(start 315.919866 -134.078472)
		(end 316.342268 -134.253478)
		(width 0.1651)
		(layer "In9.Cu")
		(net "P5E_PEX2_STN0_TX_DP<6>")
	)
	(segment
		(start 316.822836 -134.56793)
		(end 316.962282 -134.510272)
		(width 0.1651)
		(layer "In9.Cu")
		(net "P5E_PEX2_STN0_TX_DP<6>")
	)
	(segment
		(start 320.246756 -140.061442)
		(end 320.191892 -140.194284)
		(width 0.1651)
		(layer "In9.Cu")
		(net "P5E_PEX2_STN0_TX_DP<6>")
	)
	(segment
		(start 319.216278 -137.57402)
		(end 319.39103 -137.996168)
		(width 0.1651)
		(layer "In9.Cu")
		(net "P5E_PEX2_STN0_TX_DP<6>")
	)
	(segment
		(start 325.944992 -267.397992)
		(end 326.514206 -268.772386)
		(width 0.1651)
		(layer "In9.Cu")
		(net "P5E_PEX2_STN0_TX_DP<6>")
	)
	(segment
		(start 322.807838 -145.594578)
		(end 326.283066 -153.984706)
		(width 0.1651)
		(layer "In9.Cu")
		(net "P5E_PEX2_STN0_TX_DP<6>")
	)
	(segment
		(start 317.65494 -134.797038)
		(end 318.356996 -135.499094)
		(width 0.1651)
		(layer "In9.Cu")
		(net "P5E_PEX2_STN0_TX_DP<6>")
	)
	(segment
		(start 309.329582 -282.2448)
		(end 309.329582 -282.485592)
		(width 0.1143)
		(layer "In9.Cu")
		(net "P5E_PEX2_STN0_TX_DP<6>")
	)
	(segment
		(start 322.348606 -145.135346)
		(end 322.807838 -145.594578)
		(width 0.1651)
		(layer "In9.Cu")
		(net "P5E_PEX2_STN0_TX_DP<6>")
	)
	(segment
		(start 319.644014 -138.606784)
		(end 319.818766 -139.028932)
		(width 0.1651)
		(layer "In9.Cu")
		(net "P5E_PEX2_STN0_TX_DP<6>")
	)
	(segment
		(start 318.649096 -136.483344)
		(end 318.788796 -136.541256)
		(width 0.1651)
		(layer "In9.Cu")
		(net "P5E_PEX2_STN0_TX_DP<6>")
	)
	(segment
		(start 320.670682 -259.504434)
		(end 325.944992 -267.397992)
		(width 0.1651)
		(layer "In9.Cu")
		(net "P5E_PEX2_STN0_TX_DP<6>")
	)
	(segment
		(start 326.757284 -271.54632)
		(end 326.024494 -273.559524)
		(width 0.1651)
		(layer "In9.Cu")
		(net "P5E_PEX2_STN0_TX_DP<6>")
	)
	(segment
		(start 318.47409 -136.060688)
		(end 318.649096 -136.483344)
		(width 0.1651)
		(layer "In9.Cu")
		(net "P5E_PEX2_STN0_TX_DP<6>")
	)
	(segment
		(start 320.49974 -140.672058)
		(end 322.348606 -145.135346)
		(width 0.1651)
		(layer "In9.Cu")
		(net "P5E_PEX2_STN0_TX_DP<6>")
	)
	(segment
		(start 319.336166 -138.12901)
		(end 319.511172 -138.551666)
		(width 0.1651)
		(layer "In9.Cu")
		(net "P5E_PEX2_STN0_TX_DP<6>")
	)
	(segment
		(start 309.54472 -282.029662)
		(end 309.329582 -282.2448)
		(width 0.1143)
		(layer "In9.Cu")
		(net "P5E_PEX2_STN0_TX_DP<6>")
	)
	(segment
		(start 318.188594 -281.395424)
		(end 316.767464 -281.983942)
		(width 0.1651)
		(layer "In9.Cu")
		(net "P5E_PEX2_STN0_TX_DP<6>")
	)
	(segment
		(start 315.46292 -134.078472)
		(end 315.919866 -134.078472)
		(width 0.1651)
		(layer "In9.Cu")
		(net "P5E_PEX2_STN0_TX_DP<6>")
	)
	(segment
		(start 312.731912 -221.665038)
		(end 315.340238 -251.527056)
		(width 0.1651)
		(layer "In9.Cu")
		(net "P5E_PEX2_STN0_TX_DP<6>")
	)
	(segment
		(start 318.788796 -136.541256)
		(end 318.788542 -136.541256)
		(width 0.1651)
		(layer "In9.Cu")
		(net "P5E_PEX2_STN0_TX_DP<6>")
	)
	(segment
		(start 315.340238 -251.527056)
		(end 320.670682 -259.504434)
		(width 0.1651)
		(layer "In9.Cu")
		(net "P5E_PEX2_STN0_TX_DP<6>")
	)
	(segment
		(start 326.024494 -273.559524)
		(end 318.188594 -281.395424)
		(width 0.1651)
		(layer "In9.Cu")
		(net "P5E_PEX2_STN0_TX_DP<6>")
	)
	(segment
		(start 317.706248 -173.78172)
		(end 316.534546 -178.151028)
		(width 0.1651)
		(layer "In9.Cu")
		(net "P5E_PEX2_STN0_TX_DP<6>")
	)
	(segment
		(start 314.022994 -134.078472)
		(end 314.79236 -134.078472)
		(width 0.1651)
		(layer "In9.Cu")
		(net "P5E_PEX2_STN0_TX_DP<6>")
	)
	(segment
		(start 319.818766 -139.028932)
		(end 319.763902 -139.161774)
		(width 0.1651)
		(layer "In9.Cu")
		(net "P5E_PEX2_STN0_TX_DP<6>")
	)
	(segment
		(start 326.514206 -268.772386)
		(end 326.757284 -271.54632)
		(width 0.1651)
		(layer "In9.Cu")
		(net "P5E_PEX2_STN0_TX_DP<6>")
	)
	(segment
		(start 316.342268 -134.253478)
		(end 316.342268 -134.253224)
		(width 0.1651)
		(layer "In9.Cu")
		(net "P5E_PEX2_STN0_TX_DP<6>")
	)
	(segment
		(start 312.731658 -221.665038)
		(end 312.731912 -221.665038)
		(width 0.1651)
		(layer "In9.Cu")
		(net "P5E_PEX2_STN0_TX_DP<6>")
	)
	(segment
		(start 320.191892 -140.194284)
		(end 320.366898 -140.61694)
		(width 0.1651)
		(layer "In9.Cu")
		(net "P5E_PEX2_STN0_TX_DP<6>")
	)
	(segment
		(start 314.79236 -134.078472)
		(end 314.89904 -134.185152)
		(width 0.1651)
		(layer "In9.Cu")
		(net "P5E_PEX2_STN0_TX_DP<6>")
	)
	(segment
		(start 316.962282 -134.510272)
		(end 317.65494 -134.797038)
		(width 0.1651)
		(layer "In9.Cu")
		(net "P5E_PEX2_STN0_TX_DP<6>")
	)
	(segment
		(start 318.531748 -135.921242)
		(end 318.47409 -136.060688)
		(width 0.1651)
		(layer "In9.Cu")
		(net "P5E_PEX2_STN0_TX_DP<6>")
	)
	(segment
		(start 320.072004 -139.639294)
		(end 320.246756 -140.061442)
		(width 0.1651)
		(layer "In9.Cu")
		(net "P5E_PEX2_STN0_TX_DP<6>")
	)
	(segment
		(start 318.963294 -136.963404)
		(end 318.90843 -137.096246)
		(width 0.1651)
		(layer "In9.Cu")
		(net "P5E_PEX2_STN0_TX_DP<6>")
	)
	(segment
		(start 316.04331 -282.029662)
		(end 309.54472 -282.029662)
		(width 0.1143)
		(layer "In9.Cu")
		(net "P5E_PEX2_STN0_TX_DP<6>")
	)
	(segment
		(start 316.08903 -281.983942)
		(end 316.04331 -282.029662)
		(width 0.1143)
		(layer "In9.Cu")
		(net "P5E_PEX2_STN0_TX_DP<6>")
	)
	(segment
		(start 316.117478 -281.983942)
		(end 316.08903 -281.983942)
		(width 0.1143)
		(layer "In9.Cu")
		(net "P5E_PEX2_STN0_TX_DP<6>")
	)
	(segment
		(start 319.289684 -355.658166)
		(end 319.289684 -355.026722)
		(width 0.13462)
		(layer "F.Cu")
		(net "P5E_PEX2_STN6_TX_DN<108>")
	)
	(segment
		(start 319.289684 -355.026722)
		(end 319.584324 -354.732082)
		(width 0.13462)
		(layer "F.Cu")
		(net "P5E_PEX2_STN6_TX_DN<108>")
	)
	(segment
		(start 319.609724 -355.978206)
		(end 319.289684 -355.658166)
		(width 0.13462)
		(layer "F.Cu")
		(net "P5E_PEX2_STN6_TX_DN<108>")
	)
	(segment
		(start 278.170132 -319.921128)
		(end 278.170132 -313.673744)
		(width 0.1143)
		(layer "In13.Cu")
		(net "P5E_PEX2_STN6_TX_DN<108>")
	)
	(segment
		(start 279.196546 -327.304146)
		(end 278.215852 -324.936612)
		(width 0.1651)
		(layer "In13.Cu")
		(net "P5E_PEX2_STN6_TX_DN<108>")
	)
	(segment
		(start 320.847974 -342.0364)
		(end 320.656712 -341.617808)
		(width 0.1651)
		(layer "In13.Cu")
		(net "P5E_PEX2_STN6_TX_DN<108>")
	)
	(segment
		(start 278.435562 -313.570112)
		(end 278.549862 -313.684412)
		(width 0.1143)
		(layer "In13.Cu")
		(net "P5E_PEX2_STN6_TX_DN<108>")
	)
	(segment
		(start 278.215852 -319.966848)
		(end 278.170132 -319.921128)
		(width 0.1143)
		(layer "In13.Cu")
		(net "P5E_PEX2_STN6_TX_DN<108>")
	)
	(segment
		(start 320.656712 -341.617808)
		(end 320.1162 -340.4362)
		(width 0.1651)
		(layer "In13.Cu")
		(net "P5E_PEX2_STN6_TX_DN<108>")
	)
	(segment
		(start 296.265092 -334.004412)
		(end 295.778936 -333.908654)
		(width 0.1651)
		(layer "In13.Cu")
		(net "P5E_PEX2_STN6_TX_DN<108>")
	)
	(segment
		(start 319.584324 -354.732082)
		(end 319.293494 -354.441252)
		(width 0.1651)
		(layer "In13.Cu")
		(net "P5E_PEX2_STN6_TX_DN<108>")
	)
	(segment
		(start 314.044076 -337.613244)
		(end 296.345356 -334.124046)
		(width 0.1651)
		(layer "In13.Cu")
		(net "P5E_PEX2_STN6_TX_DN<108>")
	)
	(segment
		(start 278.170132 -313.673744)
		(end 278.273764 -313.570112)
		(width 0.1143)
		(layer "In13.Cu")
		(net "P5E_PEX2_STN6_TX_DN<108>")
	)
	(segment
		(start 278.273764 -313.570112)
		(end 278.435562 -313.570112)
		(width 0.1143)
		(layer "In13.Cu")
		(net "P5E_PEX2_STN6_TX_DN<108>")
	)
	(segment
		(start 295.659556 -333.988664)
		(end 283.480002 -331.587602)
		(width 0.1651)
		(layer "In13.Cu")
		(net "P5E_PEX2_STN6_TX_DN<108>")
	)
	(segment
		(start 278.215852 -319.995296)
		(end 278.215852 -319.966848)
		(width 0.1143)
		(layer "In13.Cu")
		(net "P5E_PEX2_STN6_TX_DN<108>")
	)
	(segment
		(start 295.778936 -333.908654)
		(end 295.659556 -333.988664)
		(width 0.1651)
		(layer "In13.Cu")
		(net "P5E_PEX2_STN6_TX_DN<108>")
	)
	(segment
		(start 319.293494 -353.930966)
		(end 320.847974 -352.376486)
		(width 0.1651)
		(layer "In13.Cu")
		(net "P5E_PEX2_STN6_TX_DN<108>")
	)
	(segment
		(start 319.293494 -354.441252)
		(end 319.293494 -353.930966)
		(width 0.1651)
		(layer "In13.Cu")
		(net "P5E_PEX2_STN6_TX_DN<108>")
	)
	(segment
		(start 283.480002 -331.587602)
		(end 279.196546 -327.304146)
		(width 0.1651)
		(layer "In13.Cu")
		(net "P5E_PEX2_STN6_TX_DN<108>")
	)
	(segment
		(start 278.549862 -313.684412)
		(end 278.549862 -313.949842)
		(width 0.1143)
		(layer "In13.Cu")
		(net "P5E_PEX2_STN6_TX_DN<108>")
	)
	(segment
		(start 296.345356 -334.124046)
		(end 296.265092 -334.004412)
		(width 0.1651)
		(layer "In13.Cu")
		(net "P5E_PEX2_STN6_TX_DN<108>")
	)
	(segment
		(start 320.1162 -340.4362)
		(end 314.044076 -337.613244)
		(width 0.1651)
		(layer "In13.Cu")
		(net "P5E_PEX2_STN6_TX_DN<108>")
	)
	(segment
		(start 278.215852 -324.936612)
		(end 278.215852 -319.995296)
		(width 0.1651)
		(layer "In13.Cu")
		(net "P5E_PEX2_STN6_TX_DN<108>")
	)
	(segment
		(start 320.847974 -352.376486)
		(end 320.847974 -342.0364)
		(width 0.1651)
		(layer "In13.Cu")
		(net "P5E_PEX2_STN6_TX_DN<108>")
	)
	(segment
		(start 383.4257 -111.920782)
		(end 383.727198 -112.22228)
		(width 0.13462)
		(layer "F.Cu")
		(net "P5E_PEX3_STN1_TX_DN<23>")
	)
	(segment
		(start 384.344926 -112.22228)
		(end 384.671824 -111.895382)
		(width 0.13462)
		(layer "F.Cu")
		(net "P5E_PEX3_STN1_TX_DN<23>")
	)
	(segment
		(start 383.727198 -112.22228)
		(end 384.344926 -112.22228)
		(width 0.13462)
		(layer "F.Cu")
		(net "P5E_PEX3_STN1_TX_DN<23>")
	)
	(segment
		(start 378.204984 -151.235156)
		(end 377.84024 -143.809212)
		(width 0.1651)
		(layer "In9.Cu")
		(net "P5E_PEX3_STN1_TX_DN<23>")
	)
	(segment
		(start 414.485582 -280.319988)
		(end 414.24479 -280.319988)
		(width 0.1143)
		(layer "In9.Cu")
		(net "P5E_PEX3_STN1_TX_DN<23>")
	)
	(segment
		(start 378.569982 -158.661354)
		(end 378.204984 -151.234902)
		(width 0.1651)
		(layer "In9.Cu")
		(net "P5E_PEX3_STN1_TX_DN<23>")
	)
	(segment
		(start 414.029652 -271.600168)
		(end 413.983932 -271.554448)
		(width 0.1143)
		(layer "In9.Cu")
		(net "P5E_PEX3_STN1_TX_DN<23>")
	)
	(segment
		(start 413.983932 -264.494518)
		(end 379.154182 -161.59861)
		(width 0.1651)
		(layer "In9.Cu")
		(net "P5E_PEX3_STN1_TX_DN<23>")
	)
	(segment
		(start 414.24479 -280.319988)
		(end 414.029652 -280.10485)
		(width 0.1143)
		(layer "In9.Cu")
		(net "P5E_PEX3_STN1_TX_DN<23>")
	)
	(segment
		(start 378.104654 -122.296936)
		(end 382.173988 -112.472978)
		(width 0.1651)
		(layer "In9.Cu")
		(net "P5E_PEX3_STN1_TX_DN<23>")
	)
	(segment
		(start 378.204984 -151.234902)
		(end 378.204984 -151.235156)
		(width 0.1651)
		(layer "In9.Cu")
		(net "P5E_PEX3_STN1_TX_DN<23>")
	)
	(segment
		(start 382.435354 -112.211612)
		(end 383.13487 -112.211612)
		(width 0.1651)
		(layer "In9.Cu")
		(net "P5E_PEX3_STN1_TX_DN<23>")
	)
	(segment
		(start 379.154182 -161.59861)
		(end 378.569982 -158.661354)
		(width 0.1651)
		(layer "In9.Cu")
		(net "P5E_PEX3_STN1_TX_DN<23>")
	)
	(segment
		(start 414.599882 -280.434288)
		(end 414.485582 -280.319988)
		(width 0.1143)
		(layer "In9.Cu")
		(net "P5E_PEX3_STN1_TX_DN<23>")
	)
	(segment
		(start 414.029652 -280.10485)
		(end 414.029652 -271.600168)
		(width 0.1143)
		(layer "In9.Cu")
		(net "P5E_PEX3_STN1_TX_DN<23>")
	)
	(segment
		(start 382.173988 -112.472978)
		(end 382.435354 -112.211612)
		(width 0.1651)
		(layer "In9.Cu")
		(net "P5E_PEX3_STN1_TX_DN<23>")
	)
	(segment
		(start 413.983932 -271.526)
		(end 413.983932 -264.494518)
		(width 0.1651)
		(layer "In9.Cu")
		(net "P5E_PEX3_STN1_TX_DN<23>")
	)
	(segment
		(start 413.983932 -271.554448)
		(end 413.983932 -271.526)
		(width 0.1143)
		(layer "In9.Cu")
		(net "P5E_PEX3_STN1_TX_DN<23>")
	)
	(segment
		(start 414.599882 -280.699718)
		(end 414.599882 -280.434288)
		(width 0.1143)
		(layer "In9.Cu")
		(net "P5E_PEX3_STN1_TX_DN<23>")
	)
	(segment
		(start 383.13487 -112.211612)
		(end 383.4257 -111.920782)
		(width 0.1651)
		(layer "In9.Cu")
		(net "P5E_PEX3_STN1_TX_DN<23>")
	)
	(segment
		(start 377.84024 -143.809212)
		(end 375.279412 -137.626852)
		(width 0.1651)
		(layer "In9.Cu")
		(net "P5E_PEX3_STN1_TX_DN<23>")
	)
	(segment
		(start 375.279412 -131.610608)
		(end 378.104654 -122.296936)
		(width 0.1651)
		(layer "In9.Cu")
		(net "P5E_PEX3_STN1_TX_DN<23>")
	)
	(segment
		(start 375.279412 -137.626852)
		(end 375.279412 -131.610608)
		(width 0.1651)
		(layer "In9.Cu")
		(net "P5E_PEX3_STN1_TX_DN<23>")
	)
	(segment
		(start 164.047424 -30.92069)
		(end 163.754054 -30.62732)
		(width 0.13462)
		(layer "F.Cu")
		(net "P5E_PEX1_STN2_TX_DP<41>")
	)
	(segment
		(start 163.754054 -30.62732)
		(end 163.12007 -30.62732)
		(width 0.13462)
		(layer "F.Cu")
		(net "P5E_PEX1_STN2_TX_DP<41>")
	)
	(segment
		(start 163.12007 -30.62732)
		(end 162.8013 -30.94609)
		(width 0.13462)
		(layer "F.Cu")
		(net "P5E_PEX1_STN2_TX_DP<41>")
	)
	(segment
		(start 165.633908 -269.841726)
		(end 165.633908 -271.399)
		(width 0.1651)
		(layer "In11.Cu")
		(net "P5E_PEX1_STN2_TX_DP<41>")
	)
	(segment
		(start 165.40734 -31.10865)
		(end 165.407848 -31.10865)
		(width 0.1651)
		(layer "In11.Cu")
		(net "P5E_PEX1_STN2_TX_DP<41>")
	)
	(segment
		(start 172.620686 -119.281194)
		(end 172.59427 -119.593868)
		(width 0.1651)
		(layer "In11.Cu")
		(net "P5E_PEX1_STN2_TX_DP<41>")
	)
	(segment
		(start 165.894766 -278.420068)
		(end 166.135558 -278.420068)
		(width 0.1143)
		(layer "In11.Cu")
		(net "P5E_PEX1_STN2_TX_DP<41>")
	)
	(segment
		(start 165.885876 -31.582868)
		(end 166.237412 -31.931356)
		(width 0.1651)
		(layer "In11.Cu")
		(net "P5E_PEX1_STN2_TX_DP<41>")
	)
	(segment
		(start 172.568108 -119.906288)
		(end 172.567854 -119.906288)
		(width 0.1651)
		(layer "In11.Cu")
		(net "P5E_PEX1_STN2_TX_DP<41>")
	)
	(segment
		(start 178.771804 -48.194976)
		(end 179.439062 -50.122074)
		(width 0.1651)
		(layer "In11.Cu")
		(net "P5E_PEX1_STN2_TX_DP<41>")
	)
	(segment
		(start 166.589964 -32.406082)
		(end 166.715694 -32.405574)
		(width 0.1651)
		(layer "In11.Cu")
		(net "P5E_PEX1_STN2_TX_DP<41>")
	)
	(segment
		(start 172.541692 -120.218454)
		(end 172.541692 -120.219724)
		(width 0.1651)
		(layer "In11.Cu")
		(net "P5E_PEX1_STN2_TX_DP<41>")
	)
	(segment
		(start 166.23792 -32.057086)
		(end 166.589964 -32.406082)
		(width 0.1651)
		(layer "In11.Cu")
		(net "P5E_PEX1_STN2_TX_DP<41>")
	)
	(segment
		(start 180.08981 -60.55106)
		(end 179.578254 -69.600318)
		(width 0.1651)
		(layer "In11.Cu")
		(net "P5E_PEX1_STN2_TX_DP<41>")
	)
	(segment
		(start 172.59427 -119.593868)
		(end 172.568108 -119.906288)
		(width 0.1651)
		(layer "In11.Cu")
		(net "P5E_PEX1_STN2_TX_DP<41>")
	)
	(segment
		(start 172.541692 -120.219724)
		(end 171.290488 -135.143494)
		(width 0.1651)
		(layer "In11.Cu")
		(net "P5E_PEX1_STN2_TX_DP<41>")
	)
	(segment
		(start 165.407848 -31.10865)
		(end 165.408356 -31.23438)
		(width 0.1651)
		(layer "In11.Cu")
		(net "P5E_PEX1_STN2_TX_DP<41>")
	)
	(segment
		(start 171.290488 -135.143494)
		(end 164.917628 -252.658372)
		(width 0.1651)
		(layer "In11.Cu")
		(net "P5E_PEX1_STN2_TX_DP<41>")
	)
	(segment
		(start 165.633908 -271.427448)
		(end 165.679628 -271.473168)
		(width 0.1143)
		(layer "In11.Cu")
		(net "P5E_PEX1_STN2_TX_DP<41>")
	)
	(segment
		(start 165.760146 -31.583376)
		(end 165.885876 -31.582868)
		(width 0.1651)
		(layer "In11.Cu")
		(net "P5E_PEX1_STN2_TX_DP<41>")
	)
	(segment
		(start 172.567854 -119.906288)
		(end 172.541692 -120.218454)
		(width 0.1651)
		(layer "In11.Cu")
		(net "P5E_PEX1_STN2_TX_DP<41>")
	)
	(segment
		(start 179.578254 -69.600318)
		(end 172.620686 -119.281194)
		(width 0.1651)
		(layer "In11.Cu")
		(net "P5E_PEX1_STN2_TX_DP<41>")
	)
	(segment
		(start 179.439062 -50.122074)
		(end 180.08981 -60.55106)
		(width 0.1651)
		(layer "In11.Cu")
		(net "P5E_PEX1_STN2_TX_DP<41>")
	)
	(segment
		(start 165.06063 -30.764734)
		(end 165.40734 -31.10865)
		(width 0.1651)
		(layer "In11.Cu")
		(net "P5E_PEX1_STN2_TX_DP<41>")
	)
	(segment
		(start 164.338254 -30.62986)
		(end 164.73297 -30.62986)
		(width 0.1651)
		(layer "In11.Cu")
		(net "P5E_PEX1_STN2_TX_DP<41>")
	)
	(segment
		(start 167.566086 -33.2486)
		(end 168.89476 -35.429444)
		(width 0.1651)
		(layer "In11.Cu")
		(net "P5E_PEX1_STN2_TX_DP<41>")
	)
	(segment
		(start 165.269926 -266.144502)
		(end 165.633908 -269.841726)
		(width 0.1651)
		(layer "In11.Cu")
		(net "P5E_PEX1_STN2_TX_DP<41>")
	)
	(segment
		(start 165.408356 -31.23438)
		(end 165.760146 -31.583376)
		(width 0.1651)
		(layer "In11.Cu")
		(net "P5E_PEX1_STN2_TX_DP<41>")
	)
	(segment
		(start 166.135558 -278.420068)
		(end 166.249858 -278.534368)
		(width 0.1143)
		(layer "In11.Cu")
		(net "P5E_PEX1_STN2_TX_DP<41>")
	)
	(segment
		(start 165.633908 -271.399)
		(end 165.633908 -271.427448)
		(width 0.1143)
		(layer "In11.Cu")
		(net "P5E_PEX1_STN2_TX_DP<41>")
	)
	(segment
		(start 168.89476 -35.429444)
		(end 178.771804 -48.194976)
		(width 0.1651)
		(layer "In11.Cu")
		(net "P5E_PEX1_STN2_TX_DP<41>")
	)
	(segment
		(start 164.73297 -30.62986)
		(end 165.06063 -30.764734)
		(width 0.1651)
		(layer "In11.Cu")
		(net "P5E_PEX1_STN2_TX_DP<41>")
	)
	(segment
		(start 164.917628 -252.658372)
		(end 165.269926 -266.144502)
		(width 0.1651)
		(layer "In11.Cu")
		(net "P5E_PEX1_STN2_TX_DP<41>")
	)
	(segment
		(start 165.679628 -271.473168)
		(end 165.679628 -278.20493)
		(width 0.1143)
		(layer "In11.Cu")
		(net "P5E_PEX1_STN2_TX_DP<41>")
	)
	(segment
		(start 166.249858 -278.534368)
		(end 166.249858 -278.799798)
		(width 0.1143)
		(layer "In11.Cu")
		(net "P5E_PEX1_STN2_TX_DP<41>")
	)
	(segment
		(start 164.047424 -30.92069)
		(end 164.338254 -30.62986)
		(width 0.1651)
		(layer "In11.Cu")
		(net "P5E_PEX1_STN2_TX_DP<41>")
	)
	(segment
		(start 166.715694 -32.405574)
		(end 167.566086 -33.2486)
		(width 0.1651)
		(layer "In11.Cu")
		(net "P5E_PEX1_STN2_TX_DP<41>")
	)
	(segment
		(start 165.679628 -278.20493)
		(end 165.894766 -278.420068)
		(width 0.1143)
		(layer "In11.Cu")
		(net "P5E_PEX1_STN2_TX_DP<41>")
	)
	(segment
		(start 166.237412 -31.931356)
		(end 166.23792 -32.057086)
		(width 0.1651)
		(layer "In11.Cu")
		(net "P5E_PEX1_STN2_TX_DP<41>")
	)
	(segment
		(start 118.969028 -349.831914)
		(end 118.648988 -349.511874)
		(width 0.13462)
		(layer "F.Cu")
		(net "P5E_PEX1_STN6_TX_DN<100>")
	)
	(segment
		(start 118.648988 -349.511874)
		(end 118.648988 -348.88043)
		(width 0.13462)
		(layer "F.Cu")
		(net "P5E_PEX1_STN6_TX_DN<100>")
	)
	(segment
		(start 118.648988 -348.88043)
		(end 118.943628 -348.58579)
		(width 0.13462)
		(layer "F.Cu")
		(net "P5E_PEX1_STN6_TX_DN<100>")
	)
	(segment
		(start 118.652798 -348.29496)
		(end 118.652798 -347.736922)
		(width 0.1651)
		(layer "In7.Cu")
		(net "P5E_PEX1_STN6_TX_DN<100>")
	)
	(segment
		(start 166.76878 -323.067172)
		(end 168.18356 -322.219066)
		(width 0.1651)
		(layer "In7.Cu")
		(net "P5E_PEX1_STN6_TX_DN<100>")
	)
	(segment
		(start 169.715942 -320.002408)
		(end 169.715942 -319.97396)
		(width 0.1143)
		(layer "In7.Cu")
		(net "P5E_PEX1_STN6_TX_DN<100>")
	)
	(segment
		(start 149.03831 -328.445368)
		(end 166.76878 -323.067172)
		(width 0.1651)
		(layer "In7.Cu")
		(net "P5E_PEX1_STN6_TX_DN<100>")
	)
	(segment
		(start 169.935652 -313.570112)
		(end 170.049952 -313.684412)
		(width 0.1143)
		(layer "In7.Cu")
		(net "P5E_PEX1_STN6_TX_DN<100>")
	)
	(segment
		(start 169.670222 -313.684412)
		(end 169.784522 -313.570112)
		(width 0.1143)
		(layer "In7.Cu")
		(net "P5E_PEX1_STN6_TX_DN<100>")
	)
	(segment
		(start 169.670222 -319.92824)
		(end 169.670222 -313.684412)
		(width 0.1143)
		(layer "In7.Cu")
		(net "P5E_PEX1_STN6_TX_DN<100>")
	)
	(segment
		(start 169.352214 -321.050412)
		(end 169.715942 -320.172334)
		(width 0.1651)
		(layer "In7.Cu")
		(net "P5E_PEX1_STN6_TX_DN<100>")
	)
	(segment
		(start 120.207278 -340.896956)
		(end 121.206514 -339.89772)
		(width 0.1651)
		(layer "In7.Cu")
		(net "P5E_PEX1_STN6_TX_DN<100>")
	)
	(segment
		(start 149.038564 -328.445368)
		(end 149.03831 -328.445368)
		(width 0.1651)
		(layer "In7.Cu")
		(net "P5E_PEX1_STN6_TX_DN<100>")
	)
	(segment
		(start 120.207278 -346.182442)
		(end 120.207278 -340.896956)
		(width 0.1651)
		(layer "In7.Cu")
		(net "P5E_PEX1_STN6_TX_DN<100>")
	)
	(segment
		(start 169.784522 -313.570112)
		(end 169.935652 -313.570112)
		(width 0.1143)
		(layer "In7.Cu")
		(net "P5E_PEX1_STN6_TX_DN<100>")
	)
	(segment
		(start 118.943628 -348.58579)
		(end 118.652798 -348.29496)
		(width 0.1651)
		(layer "In7.Cu")
		(net "P5E_PEX1_STN6_TX_DN<100>")
	)
	(segment
		(start 131.374642 -333.803498)
		(end 149.038564 -328.445368)
		(width 0.1651)
		(layer "In7.Cu")
		(net "P5E_PEX1_STN6_TX_DN<100>")
	)
	(segment
		(start 121.206514 -339.89772)
		(end 131.374642 -333.803498)
		(width 0.1651)
		(layer "In7.Cu")
		(net "P5E_PEX1_STN6_TX_DN<100>")
	)
	(segment
		(start 170.049952 -313.684412)
		(end 170.049952 -313.949842)
		(width 0.1143)
		(layer "In7.Cu")
		(net "P5E_PEX1_STN6_TX_DN<100>")
	)
	(segment
		(start 118.652798 -347.736922)
		(end 120.207278 -346.182442)
		(width 0.1651)
		(layer "In7.Cu")
		(net "P5E_PEX1_STN6_TX_DN<100>")
	)
	(segment
		(start 168.18356 -322.219066)
		(end 169.352214 -321.050412)
		(width 0.1651)
		(layer "In7.Cu")
		(net "P5E_PEX1_STN6_TX_DN<100>")
	)
	(segment
		(start 169.715942 -320.172334)
		(end 169.715942 -320.002408)
		(width 0.1651)
		(layer "In7.Cu")
		(net "P5E_PEX1_STN6_TX_DN<100>")
	)
	(segment
		(start 169.715942 -319.97396)
		(end 169.670222 -319.92824)
		(width 0.1143)
		(layer "In7.Cu")
		(net "P5E_PEX1_STN6_TX_DN<100>")
	)
	(segment
		(start 270.88338 -99.8728)
		(end 271.213834 -100.203254)
		(width 0.13462)
		(layer "F.Cu")
		(net "P5E_PEX2_STN1_TX_DN<16>")
	)
	(segment
		(start 269.96771 -100.177854)
		(end 270.272764 -99.8728)
		(width 0.13462)
		(layer "F.Cu")
		(net "P5E_PEX2_STN1_TX_DN<16>")
	)
	(segment
		(start 270.272764 -99.8728)
		(end 270.88338 -99.8728)
		(width 0.13462)
		(layer "F.Cu")
		(net "P5E_PEX2_STN1_TX_DN<16>")
	)
	(segment
		(start 291.5158 -271.500346)
		(end 291.47008 -271.546066)
		(width 0.1143)
		(layer "In9.Cu")
		(net "P5E_PEX2_STN1_TX_DN<16>")
	)
	(segment
		(start 263.37895 -103.628952)
		(end 263.037828 -103.970074)
		(width 0.1651)
		(layer "In9.Cu")
		(net "P5E_PEX2_STN1_TX_DN<16>")
	)
	(segment
		(start 267.559028 -100.4062)
		(end 267.409676 -100.344224)
		(width 0.1651)
		(layer "In9.Cu")
		(net "P5E_PEX2_STN1_TX_DN<16>")
	)
	(segment
		(start 259.890514 -108.160312)
		(end 259.95249 -108.309664)
		(width 0.1651)
		(layer "In9.Cu")
		(net "P5E_PEX2_STN1_TX_DN<16>")
	)
	(segment
		(start 268.067028 -100.071936)
		(end 268.005306 -100.221542)
		(width 0.1651)
		(layer "In9.Cu")
		(net "P5E_PEX2_STN1_TX_DN<16>")
	)
	(segment
		(start 256.5527 -162.641534)
		(end 291.5158 -265.937492)
		(width 0.1651)
		(layer "In9.Cu")
		(net "P5E_PEX2_STN1_TX_DN<16>")
	)
	(segment
		(start 264.38479 -102.784656)
		(end 264.223246 -102.784656)
		(width 0.1651)
		(layer "In9.Cu")
		(net "P5E_PEX2_STN1_TX_DN<16>")
	)
	(segment
		(start 265.570462 -101.43744)
		(end 265.570462 -101.598984)
		(width 0.1651)
		(layer "In9.Cu")
		(net "P5E_PEX2_STN1_TX_DN<16>")
	)
	(segment
		(start 291.47008 -271.546066)
		(end 291.47008 -278.12619)
		(width 0.1143)
		(layer "In9.Cu")
		(net "P5E_PEX2_STN1_TX_DN<16>")
	)
	(segment
		(start 252.687074 -139.08786)
		(end 255.284732 -145.35912)
		(width 0.1651)
		(layer "In9.Cu")
		(net "P5E_PEX2_STN1_TX_DN<16>")
	)
	(segment
		(start 260.229604 -107.641136)
		(end 260.079998 -107.702858)
		(width 0.1651)
		(layer "In9.Cu")
		(net "P5E_PEX2_STN1_TX_DN<16>")
	)
	(segment
		(start 261.690358 -105.317544)
		(end 260.62813 -106.379772)
		(width 0.1651)
		(layer "In9.Cu")
		(net "P5E_PEX2_STN1_TX_DN<16>")
	)
	(segment
		(start 263.037828 -103.970074)
		(end 263.037828 -104.131618)
		(width 0.1651)
		(layer "In9.Cu")
		(net "P5E_PEX2_STN1_TX_DN<16>")
	)
	(segment
		(start 291.47008 -278.12619)
		(end 291.573458 -278.229568)
		(width 0.1143)
		(layer "In9.Cu")
		(net "P5E_PEX2_STN1_TX_DN<16>")
	)
	(segment
		(start 260.62813 -106.379772)
		(end 260.357366 -107.033822)
		(width 0.1651)
		(layer "In9.Cu")
		(net "P5E_PEX2_STN1_TX_DN<16>")
	)
	(segment
		(start 266.136374 -100.871528)
		(end 265.570462 -101.43744)
		(width 0.1651)
		(layer "In9.Cu")
		(net "P5E_PEX2_STN1_TX_DN<16>")
	)
	(segment
		(start 267.409676 -100.344224)
		(end 266.136374 -100.871528)
		(width 0.1651)
		(layer "In9.Cu")
		(net "P5E_PEX2_STN1_TX_DN<16>")
	)
	(segment
		(start 265.067542 -101.94036)
		(end 264.72642 -102.281482)
		(width 0.1651)
		(layer "In9.Cu")
		(net "P5E_PEX2_STN1_TX_DN<16>")
	)
	(segment
		(start 259.763006 -108.767626)
		(end 259.6134 -108.829348)
		(width 0.1651)
		(layer "In9.Cu")
		(net "P5E_PEX2_STN1_TX_DN<16>")
	)
	(segment
		(start 265.229086 -101.94036)
		(end 265.067542 -101.94036)
		(width 0.1651)
		(layer "In9.Cu")
		(net "P5E_PEX2_STN1_TX_DN<16>")
	)
	(segment
		(start 263.882124 -103.287322)
		(end 263.540494 -103.628952)
		(width 0.1651)
		(layer "In9.Cu")
		(net "P5E_PEX2_STN1_TX_DN<16>")
	)
	(segment
		(start 259.95249 -108.309664)
		(end 259.763006 -108.767626)
		(width 0.1651)
		(layer "In9.Cu")
		(net "P5E_PEX2_STN1_TX_DN<16>")
	)
	(segment
		(start 265.570462 -101.598984)
		(end 265.229086 -101.94036)
		(width 0.1651)
		(layer "In9.Cu")
		(net "P5E_PEX2_STN1_TX_DN<16>")
	)
	(segment
		(start 259.6134 -108.829348)
		(end 258.588256 -111.304832)
		(width 0.1651)
		(layer "In9.Cu")
		(net "P5E_PEX2_STN1_TX_DN<16>")
	)
	(segment
		(start 263.037828 -104.131618)
		(end 262.696198 -104.473248)
		(width 0.1651)
		(layer "In9.Cu")
		(net "P5E_PEX2_STN1_TX_DN<16>")
	)
	(segment
		(start 260.079998 -107.702858)
		(end 259.890514 -108.160312)
		(width 0.1651)
		(layer "In9.Cu")
		(net "P5E_PEX2_STN1_TX_DN<16>")
	)
	(segment
		(start 264.72642 -102.281482)
		(end 264.72642 -102.443026)
		(width 0.1651)
		(layer "In9.Cu")
		(net "P5E_PEX2_STN1_TX_DN<16>")
	)
	(segment
		(start 258.588256 -111.304832)
		(end 252.687074 -130.75666)
		(width 0.1651)
		(layer "In9.Cu")
		(net "P5E_PEX2_STN1_TX_DN<16>")
	)
	(segment
		(start 269.96771 -100.177854)
		(end 269.67688 -99.887024)
		(width 0.1651)
		(layer "In9.Cu")
		(net "P5E_PEX2_STN1_TX_DN<16>")
	)
	(segment
		(start 262.534654 -104.473248)
		(end 262.193532 -104.81437)
		(width 0.1651)
		(layer "In9.Cu")
		(net "P5E_PEX2_STN1_TX_DN<16>")
	)
	(segment
		(start 255.995678 -159.841184)
		(end 256.5527 -162.641534)
		(width 0.1651)
		(layer "In9.Cu")
		(net "P5E_PEX2_STN1_TX_DN<16>")
	)
	(segment
		(start 291.849556 -278.115268)
		(end 291.849556 -277.849838)
		(width 0.1143)
		(layer "In9.Cu")
		(net "P5E_PEX2_STN1_TX_DN<16>")
	)
	(segment
		(start 291.573458 -278.229568)
		(end 291.735256 -278.229568)
		(width 0.1143)
		(layer "In9.Cu")
		(net "P5E_PEX2_STN1_TX_DN<16>")
	)
	(segment
		(start 268.005306 -100.221542)
		(end 267.559028 -100.4062)
		(width 0.1651)
		(layer "In9.Cu")
		(net "P5E_PEX2_STN1_TX_DN<16>")
	)
	(segment
		(start 291.735256 -278.229568)
		(end 291.849556 -278.115268)
		(width 0.1143)
		(layer "In9.Cu")
		(net "P5E_PEX2_STN1_TX_DN<16>")
	)
	(segment
		(start 264.72642 -102.443026)
		(end 264.38479 -102.784656)
		(width 0.1651)
		(layer "In9.Cu")
		(net "P5E_PEX2_STN1_TX_DN<16>")
	)
	(segment
		(start 268.514068 -99.887024)
		(end 268.067028 -100.071936)
		(width 0.1651)
		(layer "In9.Cu")
		(net "P5E_PEX2_STN1_TX_DN<16>")
	)
	(segment
		(start 260.357366 -107.033822)
		(end 260.419088 -107.183174)
		(width 0.1651)
		(layer "In9.Cu")
		(net "P5E_PEX2_STN1_TX_DN<16>")
	)
	(segment
		(start 262.193532 -104.81437)
		(end 262.193532 -104.975914)
		(width 0.1651)
		(layer "In9.Cu")
		(net "P5E_PEX2_STN1_TX_DN<16>")
	)
	(segment
		(start 252.687074 -130.75666)
		(end 252.687074 -139.08786)
		(width 0.1651)
		(layer "In9.Cu")
		(net "P5E_PEX2_STN1_TX_DN<16>")
	)
	(segment
		(start 260.419088 -107.183174)
		(end 260.229604 -107.641136)
		(width 0.1651)
		(layer "In9.Cu")
		(net "P5E_PEX2_STN1_TX_DN<16>")
	)
	(segment
		(start 291.5158 -265.937492)
		(end 291.5158 -271.471898)
		(width 0.1651)
		(layer "In9.Cu")
		(net "P5E_PEX2_STN1_TX_DN<16>")
	)
	(segment
		(start 291.5158 -271.471898)
		(end 291.5158 -271.500346)
		(width 0.1143)
		(layer "In9.Cu")
		(net "P5E_PEX2_STN1_TX_DN<16>")
	)
	(segment
		(start 269.67688 -99.887024)
		(end 268.514068 -99.887024)
		(width 0.1651)
		(layer "In9.Cu")
		(net "P5E_PEX2_STN1_TX_DN<16>")
	)
	(segment
		(start 264.223246 -102.784656)
		(end 263.882124 -103.125778)
		(width 0.1651)
		(layer "In9.Cu")
		(net "P5E_PEX2_STN1_TX_DN<16>")
	)
	(segment
		(start 263.882124 -103.125778)
		(end 263.882124 -103.287322)
		(width 0.1651)
		(layer "In9.Cu")
		(net "P5E_PEX2_STN1_TX_DN<16>")
	)
	(segment
		(start 262.193532 -104.975914)
		(end 261.851902 -105.317544)
		(width 0.1651)
		(layer "In9.Cu")
		(net "P5E_PEX2_STN1_TX_DN<16>")
	)
	(segment
		(start 261.851902 -105.317544)
		(end 261.690358 -105.317544)
		(width 0.1651)
		(layer "In9.Cu")
		(net "P5E_PEX2_STN1_TX_DN<16>")
	)
	(segment
		(start 262.696198 -104.473248)
		(end 262.534654 -104.473248)
		(width 0.1651)
		(layer "In9.Cu")
		(net "P5E_PEX2_STN1_TX_DN<16>")
	)
	(segment
		(start 255.284732 -145.35912)
		(end 255.995678 -159.841184)
		(width 0.1651)
		(layer "In9.Cu")
		(net "P5E_PEX2_STN1_TX_DN<16>")
	)
	(segment
		(start 263.540494 -103.628952)
		(end 263.37895 -103.628952)
		(width 0.1651)
		(layer "In9.Cu")
		(net "P5E_PEX2_STN1_TX_DN<16>")
	)
	(segment
		(start 316.180724 -349.511874)
		(end 316.180724 -348.88043)
		(width 0.13462)
		(layer "F.Cu")
		(net "P5E_PEX2_STN6_TX_DN<110>")
	)
	(segment
		(start 316.180724 -348.88043)
		(end 316.475364 -348.58579)
		(width 0.13462)
		(layer "F.Cu")
		(net "P5E_PEX2_STN6_TX_DN<110>")
	)
	(segment
		(start 316.500764 -349.831914)
		(end 316.180724 -349.511874)
		(width 0.13462)
		(layer "F.Cu")
		(net "P5E_PEX2_STN6_TX_DN<110>")
	)
	(segment
		(start 282.618434 -333.621634)
		(end 277.454614 -328.457814)
		(width 0.1651)
		(layer "In13.Cu")
		(net "P5E_PEX2_STN6_TX_DN<110>")
	)
	(segment
		(start 314.630054 -346.113354)
		(end 314.630054 -341.643716)
		(width 0.1651)
		(layer "In13.Cu")
		(net "P5E_PEX2_STN6_TX_DN<110>")
	)
	(segment
		(start 289.135312 -334.800448)
		(end 289.030918 -334.870806)
		(width 0.1651)
		(layer "In13.Cu")
		(net "P5E_PEX2_STN6_TX_DN<110>")
	)
	(segment
		(start 290.282376 -335.024222)
		(end 290.177982 -335.094326)
		(width 0.1651)
		(layer "In13.Cu")
		(net "P5E_PEX2_STN6_TX_DN<110>")
	)
	(segment
		(start 289.621722 -334.89519)
		(end 289.135312 -334.800448)
		(width 0.1651)
		(layer "In13.Cu")
		(net "P5E_PEX2_STN6_TX_DN<110>")
	)
	(segment
		(start 290.768786 -335.118964)
		(end 290.282376 -335.024222)
		(width 0.1651)
		(layer "In13.Cu")
		(net "P5E_PEX2_STN6_TX_DN<110>")
	)
	(segment
		(start 276.269958 -319.921128)
		(end 276.269958 -313.673744)
		(width 0.1143)
		(layer "In13.Cu")
		(net "P5E_PEX2_STN6_TX_DN<110>")
	)
	(segment
		(start 276.315678 -319.995296)
		(end 276.315678 -319.966848)
		(width 0.1143)
		(layer "In13.Cu")
		(net "P5E_PEX2_STN6_TX_DN<110>")
	)
	(segment
		(start 314.630054 -341.643716)
		(end 312.984388 -339.924644)
		(width 0.1651)
		(layer "In13.Cu")
		(net "P5E_PEX2_STN6_TX_DN<110>")
	)
	(segment
		(start 316.475364 -348.58579)
		(end 316.184534 -348.29496)
		(width 0.1651)
		(layer "In13.Cu")
		(net "P5E_PEX2_STN6_TX_DN<110>")
	)
	(segment
		(start 289.030918 -334.870806)
		(end 282.618434 -333.621634)
		(width 0.1651)
		(layer "In13.Cu")
		(net "P5E_PEX2_STN6_TX_DN<110>")
	)
	(segment
		(start 276.269958 -313.673744)
		(end 276.37359 -313.570112)
		(width 0.1143)
		(layer "In13.Cu")
		(net "P5E_PEX2_STN6_TX_DN<110>")
	)
	(segment
		(start 312.984388 -339.924644)
		(end 311.806336 -339.30844)
		(width 0.1651)
		(layer "In13.Cu")
		(net "P5E_PEX2_STN6_TX_DN<110>")
	)
	(segment
		(start 316.184534 -347.667834)
		(end 314.630054 -346.113354)
		(width 0.1651)
		(layer "In13.Cu")
		(net "P5E_PEX2_STN6_TX_DN<110>")
	)
	(segment
		(start 289.691826 -334.999838)
		(end 289.621722 -334.89519)
		(width 0.1651)
		(layer "In13.Cu")
		(net "P5E_PEX2_STN6_TX_DN<110>")
	)
	(segment
		(start 276.37359 -313.570112)
		(end 276.535388 -313.570112)
		(width 0.1143)
		(layer "In13.Cu")
		(net "P5E_PEX2_STN6_TX_DN<110>")
	)
	(segment
		(start 311.806336 -339.30844)
		(end 290.83889 -335.223358)
		(width 0.1651)
		(layer "In13.Cu")
		(net "P5E_PEX2_STN6_TX_DN<110>")
	)
	(segment
		(start 276.649688 -313.684412)
		(end 276.649688 -313.949842)
		(width 0.1143)
		(layer "In13.Cu")
		(net "P5E_PEX2_STN6_TX_DN<110>")
	)
	(segment
		(start 276.535388 -313.570112)
		(end 276.649688 -313.684412)
		(width 0.1143)
		(layer "In13.Cu")
		(net "P5E_PEX2_STN6_TX_DN<110>")
	)
	(segment
		(start 277.454614 -328.457814)
		(end 276.315678 -325.708264)
		(width 0.1651)
		(layer "In13.Cu")
		(net "P5E_PEX2_STN6_TX_DN<110>")
	)
	(segment
		(start 276.315678 -319.966848)
		(end 276.269958 -319.921128)
		(width 0.1143)
		(layer "In13.Cu")
		(net "P5E_PEX2_STN6_TX_DN<110>")
	)
	(segment
		(start 290.177982 -335.094326)
		(end 289.691826 -334.999838)
		(width 0.1651)
		(layer "In13.Cu")
		(net "P5E_PEX2_STN6_TX_DN<110>")
	)
	(segment
		(start 316.184534 -348.29496)
		(end 316.184534 -347.667834)
		(width 0.1651)
		(layer "In13.Cu")
		(net "P5E_PEX2_STN6_TX_DN<110>")
	)
	(segment
		(start 290.83889 -335.223358)
		(end 290.768786 -335.118964)
		(width 0.1651)
		(layer "In13.Cu")
		(net "P5E_PEX2_STN6_TX_DN<110>")
	)
	(segment
		(start 276.315678 -325.708264)
		(end 276.315678 -319.995296)
		(width 0.1651)
		(layer "In13.Cu")
		(net "P5E_PEX2_STN6_TX_DN<110>")
	)
	(segment
		(start 386.067808 -121.030746)
		(end 386.352542 -121.31548)
		(width 0.13462)
		(layer "F.Cu")
		(net "P5E_PEX3_STN1_TX_DN<25>")
	)
	(segment
		(start 387.003798 -121.31548)
		(end 387.313932 -121.005346)
		(width 0.13462)
		(layer "F.Cu")
		(net "P5E_PEX3_STN1_TX_DN<25>")
	)
	(segment
		(start 386.352542 -121.31548)
		(end 387.003798 -121.31548)
		(width 0.13462)
		(layer "F.Cu")
		(net "P5E_PEX3_STN1_TX_DN<25>")
	)
	(segment
		(start 415.883852 -271.526)
		(end 415.883852 -271.554448)
		(width 0.1143)
		(layer "In9.Cu")
		(net "P5E_PEX3_STN1_TX_DN<25>")
	)
	(segment
		(start 381.098552 -161.306002)
		(end 415.883852 -264.068306)
		(width 0.1651)
		(layer "In9.Cu")
		(net "P5E_PEX3_STN1_TX_DN<25>")
	)
	(segment
		(start 415.929572 -271.600168)
		(end 415.929572 -280.10485)
		(width 0.1143)
		(layer "In9.Cu")
		(net "P5E_PEX3_STN1_TX_DN<25>")
	)
	(segment
		(start 415.929572 -280.10485)
		(end 416.14471 -280.319988)
		(width 0.1143)
		(layer "In9.Cu")
		(net "P5E_PEX3_STN1_TX_DN<25>")
	)
	(segment
		(start 386.067808 -121.030746)
		(end 385.776978 -121.321576)
		(width 0.1651)
		(layer "In9.Cu")
		(net "P5E_PEX3_STN1_TX_DN<25>")
	)
	(segment
		(start 385.776978 -121.321576)
		(end 382.637284 -121.321576)
		(width 0.1651)
		(layer "In9.Cu")
		(net "P5E_PEX3_STN1_TX_DN<25>")
	)
	(segment
		(start 415.883852 -271.554448)
		(end 415.929572 -271.600168)
		(width 0.1143)
		(layer "In9.Cu")
		(net "P5E_PEX3_STN1_TX_DN<25>")
	)
	(segment
		(start 382.637284 -121.321576)
		(end 381.161798 -122.797062)
		(width 0.1651)
		(layer "In9.Cu")
		(net "P5E_PEX3_STN1_TX_DN<25>")
	)
	(segment
		(start 379.758956 -143.39316)
		(end 380.488698 -158.240222)
		(width 0.1651)
		(layer "In9.Cu")
		(net "P5E_PEX3_STN1_TX_DN<25>")
	)
	(segment
		(start 415.883852 -264.068306)
		(end 415.883852 -271.526)
		(width 0.1651)
		(layer "In9.Cu")
		(net "P5E_PEX3_STN1_TX_DN<25>")
	)
	(segment
		(start 416.499802 -280.434288)
		(end 416.499802 -280.699718)
		(width 0.1143)
		(layer "In9.Cu")
		(net "P5E_PEX3_STN1_TX_DN<25>")
	)
	(segment
		(start 380.488698 -158.240222)
		(end 381.098552 -161.306002)
		(width 0.1651)
		(layer "In9.Cu")
		(net "P5E_PEX3_STN1_TX_DN<25>")
	)
	(segment
		(start 381.161798 -122.797062)
		(end 377.214892 -132.325872)
		(width 0.1651)
		(layer "In9.Cu")
		(net "P5E_PEX3_STN1_TX_DN<25>")
	)
	(segment
		(start 416.385502 -280.319988)
		(end 416.499802 -280.434288)
		(width 0.1143)
		(layer "In9.Cu")
		(net "P5E_PEX3_STN1_TX_DN<25>")
	)
	(segment
		(start 416.14471 -280.319988)
		(end 416.385502 -280.319988)
		(width 0.1143)
		(layer "In9.Cu")
		(net "P5E_PEX3_STN1_TX_DN<25>")
	)
	(segment
		(start 377.214892 -132.325872)
		(end 377.214892 -137.251186)
		(width 0.1651)
		(layer "In9.Cu")
		(net "P5E_PEX3_STN1_TX_DN<25>")
	)
	(segment
		(start 377.214892 -137.251186)
		(end 379.758956 -143.39316)
		(width 0.1651)
		(layer "In9.Cu")
		(net "P5E_PEX3_STN1_TX_DN<25>")
	)
	(segment
		(start 137.302748 -344.539062)
		(end 137.622788 -344.219022)
		(width 0.13462)
		(layer "F.Cu")
		(net "P5E_PEX1_STN5_TX_C_DN<91>")
	)
	(segment
		(start 137.302748 -345.170506)
		(end 137.302748 -344.539062)
		(width 0.13462)
		(layer "F.Cu")
		(net "P5E_PEX1_STN5_TX_C_DN<91>")
	)
	(segment
		(start 137.597388 -345.465146)
		(end 137.302748 -345.170506)
		(width 0.13462)
		(layer "F.Cu")
		(net "P5E_PEX1_STN5_TX_C_DN<91>")
	)
	(segment
		(start 122.97537 -380.181104)
		(end 123.666758 -379.489716)
		(width 0.1651)
		(layer "In13.Cu")
		(net "P5E_PEX1_STN5_TX_C_DN<91>")
	)
	(segment
		(start 123.666758 -379.489716)
		(end 123.666758 -368.790982)
		(width 0.1651)
		(layer "In13.Cu")
		(net "P5E_PEX1_STN5_TX_C_DN<91>")
	)
	(segment
		(start 123.666758 -368.790982)
		(end 124.199142 -367.698782)
		(width 0.1651)
		(layer "In13.Cu")
		(net "P5E_PEX1_STN5_TX_C_DN<91>")
	)
	(segment
		(start 135.337296 -358.977438)
		(end 135.752078 -358.125776)
		(width 0.1651)
		(layer "In13.Cu")
		(net "P5E_PEX1_STN5_TX_C_DN<91>")
	)
	(segment
		(start 137.306558 -346.400882)
		(end 137.306558 -345.755976)
		(width 0.1651)
		(layer "In13.Cu")
		(net "P5E_PEX1_STN5_TX_C_DN<91>")
	)
	(segment
		(start 124.199142 -367.698782)
		(end 135.337296 -358.977438)
		(width 0.1651)
		(layer "In13.Cu")
		(net "P5E_PEX1_STN5_TX_C_DN<91>")
	)
	(segment
		(start 122.510042 -380.308104)
		(end 122.637042 -380.181104)
		(width 0.1651)
		(layer "In13.Cu")
		(net "P5E_PEX1_STN5_TX_C_DN<91>")
	)
	(segment
		(start 135.752078 -358.125776)
		(end 135.752078 -347.955362)
		(width 0.1651)
		(layer "In13.Cu")
		(net "P5E_PEX1_STN5_TX_C_DN<91>")
	)
	(segment
		(start 137.306558 -345.755976)
		(end 137.597388 -345.465146)
		(width 0.1651)
		(layer "In13.Cu")
		(net "P5E_PEX1_STN5_TX_C_DN<91>")
	)
	(segment
		(start 122.510042 -380.69012)
		(end 122.510042 -380.308104)
		(width 0.1651)
		(layer "In13.Cu")
		(net "P5E_PEX1_STN5_TX_C_DN<91>")
	)
	(segment
		(start 122.637042 -380.181104)
		(end 122.97537 -380.181104)
		(width 0.1651)
		(layer "In13.Cu")
		(net "P5E_PEX1_STN5_TX_C_DN<91>")
	)
	(segment
		(start 135.752078 -347.955362)
		(end 137.306558 -346.400882)
		(width 0.1651)
		(layer "In13.Cu")
		(net "P5E_PEX1_STN5_TX_C_DN<91>")
	)
	(segment
		(start 163.75253 -33.95218)
		(end 163.121594 -33.95218)
		(width 0.13462)
		(layer "F.Cu")
		(net "P5E_PEX1_STN2_TX_DN<43>")
	)
	(segment
		(start 163.121594 -33.95218)
		(end 162.8013 -33.631886)
		(width 0.13462)
		(layer "F.Cu")
		(net "P5E_PEX1_STN2_TX_DN<43>")
	)
	(segment
		(start 164.047424 -33.657286)
		(end 163.75253 -33.95218)
		(width 0.13462)
		(layer "F.Cu")
		(net "P5E_PEX1_STN2_TX_DN<43>")
	)
	(segment
		(start 161.87928 -111.782606)
		(end 160.660842 -112.983264)
		(width 0.1651)
		(layer "In11.Cu")
		(net "P5E_PEX1_STN2_TX_DN<43>")
	)
	(segment
		(start 164.015928 -271.399)
		(end 164.015928 -271.427448)
		(width 0.1143)
		(layer "In11.Cu")
		(net "P5E_PEX1_STN2_TX_DN<43>")
	)
	(segment
		(start 165.036246 -101.666802)
		(end 161.87928 -111.782606)
		(width 0.1651)
		(layer "In11.Cu")
		(net "P5E_PEX1_STN2_TX_DN<43>")
	)
	(segment
		(start 159.9565 -162.530282)
		(end 163.634674 -265.75258)
		(width 0.1651)
		(layer "In11.Cu")
		(net "P5E_PEX1_STN2_TX_DN<43>")
	)
	(segment
		(start 167.053006 -35.769296)
		(end 177.330354 -49.134776)
		(width 0.1651)
		(layer "In11.Cu")
		(net "P5E_PEX1_STN2_TX_DN<43>")
	)
	(segment
		(start 160.660842 -112.983264)
		(end 159.161988 -115.22456)
		(width 0.1651)
		(layer "In11.Cu")
		(net "P5E_PEX1_STN2_TX_DN<43>")
	)
	(segment
		(start 163.970208 -278.125936)
		(end 164.07384 -278.229568)
		(width 0.1143)
		(layer "In11.Cu")
		(net "P5E_PEX1_STN2_TX_DN<43>")
	)
	(segment
		(start 164.349938 -278.115268)
		(end 164.349938 -277.849838)
		(width 0.1143)
		(layer "In11.Cu")
		(net "P5E_PEX1_STN2_TX_DN<43>")
	)
	(segment
		(start 166.721282 -95.476568)
		(end 165.036246 -101.666802)
		(width 0.1651)
		(layer "In11.Cu")
		(net "P5E_PEX1_STN2_TX_DN<43>")
	)
	(segment
		(start 164.047424 -33.657286)
		(end 164.338254 -33.948116)
		(width 0.1651)
		(layer "In11.Cu")
		(net "P5E_PEX1_STN2_TX_DN<43>")
	)
	(segment
		(start 163.634674 -265.75258)
		(end 164.015928 -269.62354)
		(width 0.1651)
		(layer "In11.Cu")
		(net "P5E_PEX1_STN2_TX_DN<43>")
	)
	(segment
		(start 164.07384 -278.229568)
		(end 164.235638 -278.229568)
		(width 0.1143)
		(layer "In11.Cu")
		(net "P5E_PEX1_STN2_TX_DN<43>")
	)
	(segment
		(start 158.893764 -146.80565)
		(end 159.9565 -162.530282)
		(width 0.1651)
		(layer "In11.Cu")
		(net "P5E_PEX1_STN2_TX_DN<43>")
	)
	(segment
		(start 164.015928 -269.62354)
		(end 164.015928 -271.399)
		(width 0.1651)
		(layer "In11.Cu")
		(net "P5E_PEX1_STN2_TX_DN<43>")
	)
	(segment
		(start 176.936654 -68.48983)
		(end 166.721282 -95.476568)
		(width 0.1651)
		(layer "In11.Cu")
		(net "P5E_PEX1_STN2_TX_DN<43>")
	)
	(segment
		(start 177.330354 -49.134776)
		(end 177.796698 -50.493168)
		(width 0.1651)
		(layer "In11.Cu")
		(net "P5E_PEX1_STN2_TX_DN<43>")
	)
	(segment
		(start 159.161988 -115.22456)
		(end 158.901384 -116.459254)
		(width 0.1651)
		(layer "In11.Cu")
		(net "P5E_PEX1_STN2_TX_DN<43>")
	)
	(segment
		(start 177.796698 -50.493168)
		(end 178.427888 -60.360052)
		(width 0.1651)
		(layer "In11.Cu")
		(net "P5E_PEX1_STN2_TX_DN<43>")
	)
	(segment
		(start 164.235638 -278.229568)
		(end 164.349938 -278.115268)
		(width 0.1143)
		(layer "In11.Cu")
		(net "P5E_PEX1_STN2_TX_DN<43>")
	)
	(segment
		(start 163.970208 -271.473168)
		(end 163.970208 -278.125936)
		(width 0.1143)
		(layer "In11.Cu")
		(net "P5E_PEX1_STN2_TX_DN<43>")
	)
	(segment
		(start 178.427888 -60.360052)
		(end 176.936654 -68.48983)
		(width 0.1651)
		(layer "In11.Cu")
		(net "P5E_PEX1_STN2_TX_DN<43>")
	)
	(segment
		(start 164.015928 -271.427448)
		(end 163.970208 -271.473168)
		(width 0.1143)
		(layer "In11.Cu")
		(net "P5E_PEX1_STN2_TX_DN<43>")
	)
	(segment
		(start 165.259258 -33.948116)
		(end 167.053006 -35.769296)
		(width 0.1651)
		(layer "In11.Cu")
		(net "P5E_PEX1_STN2_TX_DN<43>")
	)
	(segment
		(start 164.338254 -33.948116)
		(end 165.259258 -33.948116)
		(width 0.1651)
		(layer "In11.Cu")
		(net "P5E_PEX1_STN2_TX_DN<43>")
	)
	(segment
		(start 158.901384 -116.459254)
		(end 158.893764 -146.80565)
		(width 0.1651)
		(layer "In11.Cu")
		(net "P5E_PEX1_STN2_TX_DN<43>")
	)
	(segment
		(start 168.378632 -355.978206)
		(end 168.698672 -355.658166)
		(width 0.13462)
		(layer "F.Cu")
		(net "P5E_PEX1_STN7_TX_DP<116>")
	)
	(segment
		(start 168.698672 -355.026722)
		(end 168.404032 -354.732082)
		(width 0.13462)
		(layer "F.Cu")
		(net "P5E_PEX1_STN7_TX_DP<116>")
	)
	(segment
		(start 168.698672 -355.658166)
		(end 168.698672 -355.026722)
		(width 0.13462)
		(layer "F.Cu")
		(net "P5E_PEX1_STN7_TX_DP<116>")
	)
	(segment
		(start 139.879578 -328.244708)
		(end 138.87069 -327.380092)
		(width 0.1651)
		(layer "In11.Cu")
		(net "P5E_PEX1_STN7_TX_DP<116>")
	)
	(segment
		(start 168.404032 -354.732082)
		(end 168.694862 -354.441252)
		(width 0.1651)
		(layer "In11.Cu")
		(net "P5E_PEX1_STN7_TX_DP<116>")
	)
	(segment
		(start 167.807132 -339.912706)
		(end 148.091652 -332.602586)
		(width 0.1651)
		(layer "In11.Cu")
		(net "P5E_PEX1_STN7_TX_DP<116>")
	)
	(segment
		(start 138.181334 -314.896246)
		(end 142.50289 -309.080916)
		(width 0.1651)
		(layer "In11.Cu")
		(net "P5E_PEX1_STN7_TX_DP<116>")
	)
	(segment
		(start 148.082254 -332.598268)
		(end 143.049752 -330.30033)
		(width 0.1651)
		(layer "In11.Cu")
		(net "P5E_PEX1_STN7_TX_DP<116>")
	)
	(segment
		(start 142.50289 -309.076344)
		(end 145.919698 -305.65979)
		(width 0.1651)
		(layer "In11.Cu")
		(net "P5E_PEX1_STN7_TX_DP<116>")
	)
	(segment
		(start 168.694862 -353.746562)
		(end 170.249342 -352.192082)
		(width 0.1651)
		(layer "In11.Cu")
		(net "P5E_PEX1_STN7_TX_DP<116>")
	)
	(segment
		(start 169.380662 -340.657434)
		(end 167.807132 -339.912706)
		(width 0.1651)
		(layer "In11.Cu")
		(net "P5E_PEX1_STN7_TX_DP<116>")
	)
	(segment
		(start 148.082 -332.598268)
		(end 148.082254 -332.598268)
		(width 0.1651)
		(layer "In11.Cu")
		(net "P5E_PEX1_STN7_TX_DP<116>")
	)
	(segment
		(start 158.359094 -305.399948)
		(end 158.649924 -305.399948)
		(width 0.1143)
		(layer "In11.Cu")
		(net "P5E_PEX1_STN7_TX_DP<116>")
	)
	(segment
		(start 136.459722 -322.408042)
		(end 136.459722 -319.904618)
		(width 0.1651)
		(layer "In11.Cu")
		(net "P5E_PEX1_STN7_TX_DP<116>")
	)
	(segment
		(start 151.623014 -304.783744)
		(end 151.668734 -304.829464)
		(width 0.1143)
		(layer "In11.Cu")
		(net "P5E_PEX1_STN7_TX_DP<116>")
	)
	(segment
		(start 138.87069 -327.380092)
		(end 137.217404 -324.907148)
		(width 0.1651)
		(layer "In11.Cu")
		(net "P5E_PEX1_STN7_TX_DP<116>")
	)
	(segment
		(start 170.249342 -342.294718)
		(end 169.961306 -341.431372)
		(width 0.1651)
		(layer "In11.Cu")
		(net "P5E_PEX1_STN7_TX_DP<116>")
	)
	(segment
		(start 168.694862 -354.441252)
		(end 168.694862 -353.746562)
		(width 0.1651)
		(layer "In11.Cu")
		(net "P5E_PEX1_STN7_TX_DP<116>")
	)
	(segment
		(start 136.784588 -318.265556)
		(end 138.181334 -314.896246)
		(width 0.1651)
		(layer "In11.Cu")
		(net "P5E_PEX1_STN7_TX_DP<116>")
	)
	(segment
		(start 143.049752 -330.30033)
		(end 139.879578 -328.244708)
		(width 0.1651)
		(layer "In11.Cu")
		(net "P5E_PEX1_STN7_TX_DP<116>")
	)
	(segment
		(start 136.459722 -319.904618)
		(end 136.784588 -318.265556)
		(width 0.1651)
		(layer "In11.Cu")
		(net "P5E_PEX1_STN7_TX_DP<116>")
	)
	(segment
		(start 148.091652 -332.602586)
		(end 148.082 -332.598268)
		(width 0.1651)
		(layer "In11.Cu")
		(net "P5E_PEX1_STN7_TX_DP<116>")
	)
	(segment
		(start 148.034502 -304.783744)
		(end 151.600916 -304.783744)
		(width 0.1651)
		(layer "In11.Cu")
		(net "P5E_PEX1_STN7_TX_DP<116>")
	)
	(segment
		(start 170.249342 -352.192082)
		(end 170.249342 -342.294718)
		(width 0.1651)
		(layer "In11.Cu")
		(net "P5E_PEX1_STN7_TX_DP<116>")
	)
	(segment
		(start 157.993334 -304.829464)
		(end 158.270194 -305.106324)
		(width 0.1143)
		(layer "In11.Cu")
		(net "P5E_PEX1_STN7_TX_DP<116>")
	)
	(segment
		(start 169.961306 -341.431372)
		(end 169.380662 -340.657434)
		(width 0.1651)
		(layer "In11.Cu")
		(net "P5E_PEX1_STN7_TX_DP<116>")
	)
	(segment
		(start 145.919698 -305.65979)
		(end 148.034502 -304.783744)
		(width 0.1651)
		(layer "In11.Cu")
		(net "P5E_PEX1_STN7_TX_DP<116>")
	)
	(segment
		(start 151.600916 -304.783744)
		(end 151.623014 -304.783744)
		(width 0.1143)
		(layer "In11.Cu")
		(net "P5E_PEX1_STN7_TX_DP<116>")
	)
	(segment
		(start 158.270194 -305.311048)
		(end 158.359094 -305.399948)
		(width 0.1143)
		(layer "In11.Cu")
		(net "P5E_PEX1_STN7_TX_DP<116>")
	)
	(segment
		(start 158.270194 -305.106324)
		(end 158.270194 -305.311048)
		(width 0.1143)
		(layer "In11.Cu")
		(net "P5E_PEX1_STN7_TX_DP<116>")
	)
	(segment
		(start 142.50289 -309.080916)
		(end 142.50289 -309.076344)
		(width 0.1651)
		(layer "In11.Cu")
		(net "P5E_PEX1_STN7_TX_DP<116>")
	)
	(segment
		(start 137.217404 -324.907148)
		(end 136.459722 -322.408042)
		(width 0.1651)
		(layer "In11.Cu")
		(net "P5E_PEX1_STN7_TX_DP<116>")
	)
	(segment
		(start 151.668734 -304.829464)
		(end 157.993334 -304.829464)
		(width 0.1143)
		(layer "In11.Cu")
		(net "P5E_PEX1_STN7_TX_DP<116>")
	)
	(segment
		(start 269.96771 -136.704324)
		(end 270.279114 -136.39292)
		(width 0.13462)
		(layer "F.Cu")
		(net "P5E_PEX2_STN1_TX_DP<31>")
	)
	(segment
		(start 270.87703 -136.39292)
		(end 271.213834 -136.729724)
		(width 0.13462)
		(layer "F.Cu")
		(net "P5E_PEX2_STN1_TX_DP<31>")
	)
	(segment
		(start 270.279114 -136.39292)
		(end 270.87703 -136.39292)
		(width 0.13462)
		(layer "F.Cu")
		(net "P5E_PEX2_STN1_TX_DP<31>")
	)
	(segment
		(start 271.987518 -146.94154)
		(end 271.891252 -146.455892)
		(width 0.1651)
		(layer "In9.Cu")
		(net "P5E_PEX2_STN1_TX_DP<31>")
	)
	(segment
		(start 270.824198 -141.08684)
		(end 270.727932 -140.601192)
		(width 0.1651)
		(layer "In9.Cu")
		(net "P5E_PEX2_STN1_TX_DP<31>")
	)
	(segment
		(start 272.361406 -148.822918)
		(end 272.451322 -148.688552)
		(width 0.1651)
		(layer "In9.Cu")
		(net "P5E_PEX2_STN1_TX_DP<31>")
	)
	(segment
		(start 268.839442 -136.641586)
		(end 269.067534 -136.413494)
		(width 0.1651)
		(layer "In9.Cu")
		(net "P5E_PEX2_STN1_TX_DP<31>")
	)
	(segment
		(start 272.123916 -147.626832)
		(end 272.203672 -147.507452)
		(width 0.1651)
		(layer "In9.Cu")
		(net "P5E_PEX2_STN1_TX_DP<31>")
	)
	(segment
		(start 305.719988 -280.025856)
		(end 305.719988 -271.600168)
		(width 0.1143)
		(layer "In9.Cu")
		(net "P5E_PEX2_STN1_TX_DP<31>")
	)
	(segment
		(start 271.409414 -143.50873)
		(end 271.289526 -143.42872)
		(width 0.1651)
		(layer "In9.Cu")
		(net "P5E_PEX2_STN1_TX_DP<31>")
	)
	(segment
		(start 270.034766 -138.307064)
		(end 269.693644 -137.965942)
		(width 0.1651)
		(layer "In9.Cu")
		(net "P5E_PEX2_STN1_TX_DP<31>")
	)
	(segment
		(start 279.597358 -185.260488)
		(end 272.361406 -148.822918)
		(width 0.1651)
		(layer "In9.Cu")
		(net "P5E_PEX2_STN1_TX_DP<31>")
	)
	(segment
		(start 269.67688 -136.413494)
		(end 269.96771 -136.704324)
		(width 0.1651)
		(layer "In9.Cu")
		(net "P5E_PEX2_STN1_TX_DP<31>")
	)
	(segment
		(start 272.107406 -147.02155)
		(end 271.987518 -146.94154)
		(width 0.1651)
		(layer "In9.Cu")
		(net "P5E_PEX2_STN1_TX_DP<31>")
	)
	(segment
		(start 271.891252 -146.455892)
		(end 271.971008 -146.336512)
		(width 0.1651)
		(layer "In9.Cu")
		(net "P5E_PEX2_STN1_TX_DP<31>")
	)
	(segment
		(start 271.056862 -142.25778)
		(end 270.960596 -141.772132)
		(width 0.1651)
		(layer "In9.Cu")
		(net "P5E_PEX2_STN1_TX_DP<31>")
	)
	(segment
		(start 305.765708 -271.554448)
		(end 305.765708 -271.526)
		(width 0.1143)
		(layer "In9.Cu")
		(net "P5E_PEX2_STN1_TX_DP<31>")
	)
	(segment
		(start 306.099718 -279.749504)
		(end 306.099718 -280.015188)
		(width 0.1143)
		(layer "In9.Cu")
		(net "P5E_PEX2_STN1_TX_DP<31>")
	)
	(segment
		(start 271.971008 -146.336512)
		(end 271.874742 -145.85061)
		(width 0.1651)
		(layer "In9.Cu")
		(net "P5E_PEX2_STN1_TX_DP<31>")
	)
	(segment
		(start 271.289526 -143.42872)
		(end 271.19326 -142.943072)
		(width 0.1651)
		(layer "In9.Cu")
		(net "P5E_PEX2_STN1_TX_DP<31>")
	)
	(segment
		(start 269.352014 -137.480802)
		(end 269.208504 -137.480802)
		(width 0.1651)
		(layer "In9.Cu")
		(net "P5E_PEX2_STN1_TX_DP<31>")
	)
	(segment
		(start 271.642078 -144.67967)
		(end 271.52219 -144.59966)
		(width 0.1651)
		(layer "In9.Cu")
		(net "P5E_PEX2_STN1_TX_DP<31>")
	)
	(segment
		(start 271.52219 -144.59966)
		(end 271.425924 -144.114012)
		(width 0.1651)
		(layer "In9.Cu")
		(net "P5E_PEX2_STN1_TX_DP<31>")
	)
	(segment
		(start 271.50568 -143.994632)
		(end 271.409414 -143.50873)
		(width 0.1651)
		(layer "In9.Cu")
		(net "P5E_PEX2_STN1_TX_DP<31>")
	)
	(segment
		(start 270.727932 -140.601192)
		(end 270.807688 -140.481812)
		(width 0.1651)
		(layer "In9.Cu")
		(net "P5E_PEX2_STN1_TX_DP<31>")
	)
	(segment
		(start 305.82362 -280.129488)
		(end 305.719988 -280.025856)
		(width 0.1143)
		(layer "In9.Cu")
		(net "P5E_PEX2_STN1_TX_DP<31>")
	)
	(segment
		(start 271.040352 -141.652752)
		(end 270.944086 -141.16685)
		(width 0.1651)
		(layer "In9.Cu")
		(net "P5E_PEX2_STN1_TX_DP<31>")
	)
	(segment
		(start 271.754854 -145.7706)
		(end 271.658588 -145.284952)
		(width 0.1651)
		(layer "In9.Cu")
		(net "P5E_PEX2_STN1_TX_DP<31>")
	)
	(segment
		(start 271.738344 -145.165572)
		(end 271.642078 -144.67967)
		(width 0.1651)
		(layer "In9.Cu")
		(net "P5E_PEX2_STN1_TX_DP<31>")
	)
	(segment
		(start 270.960596 -141.772132)
		(end 271.040352 -141.652752)
		(width 0.1651)
		(layer "In9.Cu")
		(net "P5E_PEX2_STN1_TX_DP<31>")
	)
	(segment
		(start 305.985418 -280.129488)
		(end 305.82362 -280.129488)
		(width 0.1143)
		(layer "In9.Cu")
		(net "P5E_PEX2_STN1_TX_DP<31>")
	)
	(segment
		(start 305.765708 -262.564118)
		(end 279.597358 -185.260488)
		(width 0.1651)
		(layer "In9.Cu")
		(net "P5E_PEX2_STN1_TX_DP<31>")
	)
	(segment
		(start 272.451322 -148.688552)
		(end 272.354802 -148.202396)
		(width 0.1651)
		(layer "In9.Cu")
		(net "P5E_PEX2_STN1_TX_DP<31>")
	)
	(segment
		(start 269.067534 -136.413494)
		(end 269.67688 -136.413494)
		(width 0.1651)
		(layer "In9.Cu")
		(net "P5E_PEX2_STN1_TX_DP<31>")
	)
	(segment
		(start 270.807688 -140.481812)
		(end 270.713708 -140.008102)
		(width 0.1651)
		(layer "In9.Cu")
		(net "P5E_PEX2_STN1_TX_DP<31>")
	)
	(segment
		(start 271.273016 -142.823692)
		(end 271.17675 -142.33779)
		(width 0.1651)
		(layer "In9.Cu")
		(net "P5E_PEX2_STN1_TX_DP<31>")
	)
	(segment
		(start 270.490696 -139.407392)
		(end 270.034766 -138.307064)
		(width 0.1651)
		(layer "In9.Cu")
		(net "P5E_PEX2_STN1_TX_DP<31>")
	)
	(segment
		(start 270.713708 -140.008102)
		(end 270.594074 -139.928346)
		(width 0.1651)
		(layer "In9.Cu")
		(net "P5E_PEX2_STN1_TX_DP<31>")
	)
	(segment
		(start 272.220182 -148.11248)
		(end 272.123916 -147.626832)
		(width 0.1651)
		(layer "In9.Cu")
		(net "P5E_PEX2_STN1_TX_DP<31>")
	)
	(segment
		(start 271.874742 -145.85061)
		(end 271.754854 -145.7706)
		(width 0.1651)
		(layer "In9.Cu")
		(net "P5E_PEX2_STN1_TX_DP<31>")
	)
	(segment
		(start 305.765708 -271.526)
		(end 305.765708 -262.564118)
		(width 0.1651)
		(layer "In9.Cu")
		(net "P5E_PEX2_STN1_TX_DP<31>")
	)
	(segment
		(start 270.594074 -139.928346)
		(end 270.490696 -139.407392)
		(width 0.1651)
		(layer "In9.Cu")
		(net "P5E_PEX2_STN1_TX_DP<31>")
	)
	(segment
		(start 272.354802 -148.202396)
		(end 272.220182 -148.11248)
		(width 0.1651)
		(layer "In9.Cu")
		(net "P5E_PEX2_STN1_TX_DP<31>")
	)
	(segment
		(start 271.425924 -144.114012)
		(end 271.50568 -143.994632)
		(width 0.1651)
		(layer "In9.Cu")
		(net "P5E_PEX2_STN1_TX_DP<31>")
	)
	(segment
		(start 269.693644 -137.965942)
		(end 269.693644 -137.822178)
		(width 0.1651)
		(layer "In9.Cu")
		(net "P5E_PEX2_STN1_TX_DP<31>")
	)
	(segment
		(start 271.17675 -142.33779)
		(end 271.056862 -142.25778)
		(width 0.1651)
		(layer "In9.Cu")
		(net "P5E_PEX2_STN1_TX_DP<31>")
	)
	(segment
		(start 270.944086 -141.16685)
		(end 270.824198 -141.08684)
		(width 0.1651)
		(layer "In9.Cu")
		(net "P5E_PEX2_STN1_TX_DP<31>")
	)
	(segment
		(start 269.693644 -137.822178)
		(end 269.352014 -137.480802)
		(width 0.1651)
		(layer "In9.Cu")
		(net "P5E_PEX2_STN1_TX_DP<31>")
	)
	(segment
		(start 305.719988 -271.600168)
		(end 305.765708 -271.554448)
		(width 0.1143)
		(layer "In9.Cu")
		(net "P5E_PEX2_STN1_TX_DP<31>")
	)
	(segment
		(start 269.208504 -137.480802)
		(end 268.839442 -137.11174)
		(width 0.1651)
		(layer "In9.Cu")
		(net "P5E_PEX2_STN1_TX_DP<31>")
	)
	(segment
		(start 268.839442 -137.11174)
		(end 268.839442 -136.641586)
		(width 0.1651)
		(layer "In9.Cu")
		(net "P5E_PEX2_STN1_TX_DP<31>")
	)
	(segment
		(start 272.203672 -147.507452)
		(end 272.107406 -147.02155)
		(width 0.1651)
		(layer "In9.Cu")
		(net "P5E_PEX2_STN1_TX_DP<31>")
	)
	(segment
		(start 271.658588 -145.284952)
		(end 271.738344 -145.165572)
		(width 0.1651)
		(layer "In9.Cu")
		(net "P5E_PEX2_STN1_TX_DP<31>")
	)
	(segment
		(start 306.099718 -280.015188)
		(end 305.985418 -280.129488)
		(width 0.1143)
		(layer "In9.Cu")
		(net "P5E_PEX2_STN1_TX_DP<31>")
	)
	(segment
		(start 271.19326 -142.943072)
		(end 271.273016 -142.823692)
		(width 0.1651)
		(layer "In9.Cu")
		(net "P5E_PEX2_STN1_TX_DP<31>")
	)
	(segment
		(start 325.233284 -355.026722)
		(end 324.938644 -354.732082)
		(width 0.13462)
		(layer "F.Cu")
		(net "P5E_PEX2_STN6_TX_DP<105>")
	)
	(segment
		(start 325.233284 -355.658166)
		(end 325.233284 -355.026722)
		(width 0.13462)
		(layer "F.Cu")
		(net "P5E_PEX2_STN6_TX_DP<105>")
	)
	(segment
		(start 324.913244 -355.978206)
		(end 325.233284 -355.658166)
		(width 0.13462)
		(layer "F.Cu")
		(net "P5E_PEX2_STN6_TX_DP<105>")
	)
	(segment
		(start 324.938644 -354.732082)
		(end 325.229474 -354.441252)
		(width 0.1651)
		(layer "In13.Cu")
		(net "P5E_PEX2_STN6_TX_DP<105>")
	)
	(segment
		(start 281.05862 -311.479692)
		(end 281.285442 -311.479692)
		(width 0.1143)
		(layer "In13.Cu")
		(net "P5E_PEX2_STN6_TX_DP<105>")
	)
	(segment
		(start 326.783954 -342.213184)
		(end 326.422766 -341.218266)
		(width 0.1651)
		(layer "In13.Cu")
		(net "P5E_PEX2_STN6_TX_DP<105>")
	)
	(segment
		(start 325.229474 -354.441252)
		(end 325.229474 -353.814126)
		(width 0.1651)
		(layer "In13.Cu")
		(net "P5E_PEX2_STN6_TX_DP<105>")
	)
	(segment
		(start 284.650434 -328.838814)
		(end 281.470354 -325.658734)
		(width 0.1651)
		(layer "In13.Cu")
		(net "P5E_PEX2_STN6_TX_DP<105>")
	)
	(segment
		(start 281.470354 -325.658734)
		(end 280.783792 -324.00113)
		(width 0.1651)
		(layer "In13.Cu")
		(net "P5E_PEX2_STN6_TX_DP<105>")
	)
	(segment
		(start 281.399742 -311.365392)
		(end 281.399742 -311.099962)
		(width 0.1143)
		(layer "In13.Cu")
		(net "P5E_PEX2_STN6_TX_DP<105>")
	)
	(segment
		(start 280.829512 -311.7088)
		(end 281.05862 -311.479692)
		(width 0.1143)
		(layer "In13.Cu")
		(net "P5E_PEX2_STN6_TX_DP<105>")
	)
	(segment
		(start 280.783792 -319.995296)
		(end 280.783792 -319.966848)
		(width 0.1143)
		(layer "In13.Cu")
		(net "P5E_PEX2_STN6_TX_DP<105>")
	)
	(segment
		(start 314.96508 -334.819752)
		(end 284.650434 -328.838814)
		(width 0.1651)
		(layer "In13.Cu")
		(net "P5E_PEX2_STN6_TX_DP<105>")
	)
	(segment
		(start 324.564756 -339.1281)
		(end 314.96508 -334.819752)
		(width 0.1651)
		(layer "In13.Cu")
		(net "P5E_PEX2_STN6_TX_DP<105>")
	)
	(segment
		(start 325.229474 -353.814126)
		(end 326.783954 -352.259646)
		(width 0.1651)
		(layer "In13.Cu")
		(net "P5E_PEX2_STN6_TX_DP<105>")
	)
	(segment
		(start 326.422766 -341.218266)
		(end 324.564756 -339.1281)
		(width 0.1651)
		(layer "In13.Cu")
		(net "P5E_PEX2_STN6_TX_DP<105>")
	)
	(segment
		(start 280.783792 -324.00113)
		(end 280.783792 -319.995296)
		(width 0.1651)
		(layer "In13.Cu")
		(net "P5E_PEX2_STN6_TX_DP<105>")
	)
	(segment
		(start 280.783792 -319.966848)
		(end 280.829512 -319.921128)
		(width 0.1143)
		(layer "In13.Cu")
		(net "P5E_PEX2_STN6_TX_DP<105>")
	)
	(segment
		(start 281.285442 -311.479692)
		(end 281.399742 -311.365392)
		(width 0.1143)
		(layer "In13.Cu")
		(net "P5E_PEX2_STN6_TX_DP<105>")
	)
	(segment
		(start 326.783954 -352.259646)
		(end 326.783954 -342.213184)
		(width 0.1651)
		(layer "In13.Cu")
		(net "P5E_PEX2_STN6_TX_DP<105>")
	)
	(segment
		(start 280.829512 -319.921128)
		(end 280.829512 -311.7088)
		(width 0.1143)
		(layer "In13.Cu")
		(net "P5E_PEX2_STN6_TX_DP<105>")
	)
	(segment
		(start 432.47437 -148.88591)
		(end 432.17846 -148.59)
		(width 0.13462)
		(layer "F.Cu")
		(net "P5E_PEX3_STN0_TX_DP<11>")
	)
	(segment
		(start 432.17846 -148.59)
		(end 431.549556 -148.59)
		(width 0.13462)
		(layer "F.Cu")
		(net "P5E_PEX3_STN0_TX_DP<11>")
	)
	(segment
		(start 431.549556 -148.59)
		(end 431.228246 -148.91131)
		(width 0.13462)
		(layer "F.Cu")
		(net "P5E_PEX3_STN0_TX_DP<11>")
	)
	(segment
		(start 433.453032 -148.59508)
		(end 432.7652 -148.59508)
		(width 0.1651)
		(layer "In9.Cu")
		(net "P5E_PEX3_STN0_TX_DP<11>")
	)
	(segment
		(start 433.803806 -149.089618)
		(end 433.803806 -148.945854)
		(width 0.1651)
		(layer "In9.Cu")
		(net "P5E_PEX3_STN0_TX_DP<11>")
	)
	(segment
		(start 423.899584 -222.13189)
		(end 425.86275 -199.693276)
		(width 0.1651)
		(layer "In9.Cu")
		(net "P5E_PEX3_STN0_TX_DP<11>")
	)
	(segment
		(start 426.33392 -271.500346)
		(end 426.33392 -271.471898)
		(width 0.1143)
		(layer "In9.Cu")
		(net "P5E_PEX3_STN0_TX_DP<11>")
	)
	(segment
		(start 435.818534 -151.429466)
		(end 435.695344 -151.405082)
		(width 0.1651)
		(layer "In9.Cu")
		(net "P5E_PEX3_STN0_TX_DP<11>")
	)
	(segment
		(start 435.695344 -151.405082)
		(end 435.420008 -150.99284)
		(width 0.1651)
		(layer "In9.Cu")
		(net "P5E_PEX3_STN0_TX_DP<11>")
	)
	(segment
		(start 434.874416 -150.016464)
		(end 434.288946 -149.430994)
		(width 0.1651)
		(layer "In9.Cu")
		(net "P5E_PEX3_STN0_TX_DP<11>")
	)
	(segment
		(start 437.5404 -155.015692)
		(end 436.440072 -152.359614)
		(width 0.1651)
		(layer "In9.Cu")
		(net "P5E_PEX3_STN0_TX_DP<11>")
	)
	(segment
		(start 426.949616 -278.799798)
		(end 426.949616 -278.534368)
		(width 0.1143)
		(layer "In9.Cu")
		(net "P5E_PEX3_STN0_TX_DP<11>")
	)
	(segment
		(start 426.37964 -271.546066)
		(end 426.33392 -271.500346)
		(width 0.1143)
		(layer "In9.Cu")
		(net "P5E_PEX3_STN0_TX_DP<11>")
	)
	(segment
		(start 426.594524 -278.420068)
		(end 426.37964 -278.205184)
		(width 0.1143)
		(layer "In9.Cu")
		(net "P5E_PEX3_STN0_TX_DP<11>")
	)
	(segment
		(start 433.803806 -148.945854)
		(end 433.453032 -148.59508)
		(width 0.1651)
		(layer "In9.Cu")
		(net "P5E_PEX3_STN0_TX_DP<11>")
	)
	(segment
		(start 426.33392 -270.873474)
		(end 427.279308 -268.590776)
		(width 0.1651)
		(layer "In9.Cu")
		(net "P5E_PEX3_STN0_TX_DP<11>")
	)
	(segment
		(start 434.145182 -149.430994)
		(end 433.803806 -149.089618)
		(width 0.1651)
		(layer "In9.Cu")
		(net "P5E_PEX3_STN0_TX_DP<11>")
	)
	(segment
		(start 436.440072 -152.359614)
		(end 435.818534 -151.429466)
		(width 0.1651)
		(layer "In9.Cu")
		(net "P5E_PEX3_STN0_TX_DP<11>")
	)
	(segment
		(start 426.37964 -278.205184)
		(end 426.37964 -271.546066)
		(width 0.1143)
		(layer "In9.Cu")
		(net "P5E_PEX3_STN0_TX_DP<11>")
	)
	(segment
		(start 425.86275 -199.693276)
		(end 425.862496 -199.693276)
		(width 0.1651)
		(layer "In9.Cu")
		(net "P5E_PEX3_STN0_TX_DP<11>")
	)
	(segment
		(start 426.33392 -271.471898)
		(end 426.33392 -270.873474)
		(width 0.1651)
		(layer "In9.Cu")
		(net "P5E_PEX3_STN0_TX_DP<11>")
	)
	(segment
		(start 435.420008 -150.99284)
		(end 435.444392 -150.86965)
		(width 0.1651)
		(layer "In9.Cu")
		(net "P5E_PEX3_STN0_TX_DP<11>")
	)
	(segment
		(start 427.279308 -268.590776)
		(end 427.279308 -260.78815)
		(width 0.1651)
		(layer "In9.Cu")
		(net "P5E_PEX3_STN0_TX_DP<11>")
	)
	(segment
		(start 429.19777 -172.13961)
		(end 437.5404 -157.687772)
		(width 0.1651)
		(layer "In9.Cu")
		(net "P5E_PEX3_STN0_TX_DP<11>")
	)
	(segment
		(start 427.825916 -177.254408)
		(end 429.19777 -172.13961)
		(width 0.1651)
		(layer "In9.Cu")
		(net "P5E_PEX3_STN0_TX_DP<11>")
	)
	(segment
		(start 426.949616 -278.534368)
		(end 426.835316 -278.420068)
		(width 0.1143)
		(layer "In9.Cu")
		(net "P5E_PEX3_STN0_TX_DP<11>")
	)
	(segment
		(start 435.444392 -150.86965)
		(end 434.874416 -150.016464)
		(width 0.1651)
		(layer "In9.Cu")
		(net "P5E_PEX3_STN0_TX_DP<11>")
	)
	(segment
		(start 432.7652 -148.59508)
		(end 432.47437 -148.88591)
		(width 0.1651)
		(layer "In9.Cu")
		(net "P5E_PEX3_STN0_TX_DP<11>")
	)
	(segment
		(start 425.862496 -199.693276)
		(end 427.825916 -177.254408)
		(width 0.1651)
		(layer "In9.Cu")
		(net "P5E_PEX3_STN0_TX_DP<11>")
	)
	(segment
		(start 426.835316 -278.420068)
		(end 426.594524 -278.420068)
		(width 0.1143)
		(layer "In9.Cu")
		(net "P5E_PEX3_STN0_TX_DP<11>")
	)
	(segment
		(start 427.279308 -260.78815)
		(end 423.899584 -222.13189)
		(width 0.1651)
		(layer "In9.Cu")
		(net "P5E_PEX3_STN0_TX_DP<11>")
	)
	(segment
		(start 434.288946 -149.430994)
		(end 434.145182 -149.430994)
		(width 0.1651)
		(layer "In9.Cu")
		(net "P5E_PEX3_STN0_TX_DP<11>")
	)
	(segment
		(start 437.5404 -157.687772)
		(end 437.5404 -155.015692)
		(width 0.1651)
		(layer "In9.Cu")
		(net "P5E_PEX3_STN0_TX_DP<11>")
	)
	(segment
		(start 187.405264 -32.714184)
		(end 187.10148 -32.4104)
		(width 0.13462)
		(layer "F.Cu")
		(net "P5E_PEX1_STN2_TX_DP<38>")
	)
	(segment
		(start 186.488324 -32.4104)
		(end 186.15914 -32.739584)
		(width 0.13462)
		(layer "F.Cu")
		(net "P5E_PEX1_STN2_TX_DP<38>")
	)
	(segment
		(start 187.10148 -32.4104)
		(end 186.488324 -32.4104)
		(width 0.13462)
		(layer "F.Cu")
		(net "P5E_PEX1_STN2_TX_DP<38>")
	)
	(segment
		(start 205.06182 -60.311792)
		(end 205.06182 -58.512202)
		(width 0.1651)
		(layer "In11.Cu")
		(net "P5E_PEX1_STN2_TX_DP<38>")
	)
	(segment
		(start 191.497966 -33.028636)
		(end 189.81547 -32.423354)
		(width 0.1651)
		(layer "In11.Cu")
		(net "P5E_PEX1_STN2_TX_DP<38>")
	)
	(segment
		(start 168.529762 -271.473168)
		(end 168.484042 -271.427448)
		(width 0.1143)
		(layer "In11.Cu")
		(net "P5E_PEX1_STN2_TX_DP<38>")
	)
	(segment
		(start 168.985692 -280.319988)
		(end 168.7449 -280.319988)
		(width 0.1143)
		(layer "In11.Cu")
		(net "P5E_PEX1_STN2_TX_DP<38>")
	)
	(segment
		(start 169.099992 -280.699718)
		(end 169.099992 -280.434288)
		(width 0.1143)
		(layer "In11.Cu")
		(net "P5E_PEX1_STN2_TX_DP<38>")
	)
	(segment
		(start 204.540866 -62.267338)
		(end 205.06182 -60.311792)
		(width 0.1651)
		(layer "In11.Cu")
		(net "P5E_PEX1_STN2_TX_DP<38>")
	)
	(segment
		(start 181.487572 -93.070426)
		(end 203.649834 -64.07023)
		(width 0.1651)
		(layer "In11.Cu")
		(net "P5E_PEX1_STN2_TX_DP<38>")
	)
	(segment
		(start 189.19825 -32.423354)
		(end 189.09665 -32.524954)
		(width 0.1651)
		(layer "In11.Cu")
		(net "P5E_PEX1_STN2_TX_DP<38>")
	)
	(segment
		(start 176.602898 -115.413282)
		(end 178.125628 -107.62107)
		(width 0.1651)
		(layer "In11.Cu")
		(net "P5E_PEX1_STN2_TX_DP<38>")
	)
	(segment
		(start 188.60135 -32.524954)
		(end 188.49975 -32.423354)
		(width 0.1651)
		(layer "In11.Cu")
		(net "P5E_PEX1_STN2_TX_DP<38>")
	)
	(segment
		(start 205.06182 -58.512202)
		(end 204.042518 -48.697642)
		(width 0.1651)
		(layer "In11.Cu")
		(net "P5E_PEX1_STN2_TX_DP<38>")
	)
	(segment
		(start 168.7449 -280.319988)
		(end 168.529762 -280.10485)
		(width 0.1143)
		(layer "In11.Cu")
		(net "P5E_PEX1_STN2_TX_DP<38>")
	)
	(segment
		(start 168.484042 -271.427448)
		(end 168.484042 -271.399)
		(width 0.1143)
		(layer "In11.Cu")
		(net "P5E_PEX1_STN2_TX_DP<38>")
	)
	(segment
		(start 175.909986 -121.034048)
		(end 176.602898 -115.413282)
		(width 0.1651)
		(layer "In11.Cu")
		(net "P5E_PEX1_STN2_TX_DP<38>")
	)
	(segment
		(start 168.484042 -263.176004)
		(end 175.909986 -121.034048)
		(width 0.1651)
		(layer "In11.Cu")
		(net "P5E_PEX1_STN2_TX_DP<38>")
	)
	(segment
		(start 188.49975 -32.423354)
		(end 187.696094 -32.423354)
		(width 0.1651)
		(layer "In11.Cu")
		(net "P5E_PEX1_STN2_TX_DP<38>")
	)
	(segment
		(start 187.696094 -32.423354)
		(end 187.405264 -32.714184)
		(width 0.1651)
		(layer "In11.Cu")
		(net "P5E_PEX1_STN2_TX_DP<38>")
	)
	(segment
		(start 193.240152 -34.717736)
		(end 191.497966 -33.028636)
		(width 0.1651)
		(layer "In11.Cu")
		(net "P5E_PEX1_STN2_TX_DP<38>")
	)
	(segment
		(start 168.484042 -271.399)
		(end 168.484042 -263.176004)
		(width 0.1651)
		(layer "In11.Cu")
		(net "P5E_PEX1_STN2_TX_DP<38>")
	)
	(segment
		(start 203.649834 -64.07023)
		(end 204.540866 -62.267338)
		(width 0.1651)
		(layer "In11.Cu")
		(net "P5E_PEX1_STN2_TX_DP<38>")
	)
	(segment
		(start 189.09665 -32.524954)
		(end 188.60135 -32.524954)
		(width 0.1651)
		(layer "In11.Cu")
		(net "P5E_PEX1_STN2_TX_DP<38>")
	)
	(segment
		(start 178.125628 -107.62107)
		(end 181.487572 -93.070426)
		(width 0.1651)
		(layer "In11.Cu")
		(net "P5E_PEX1_STN2_TX_DP<38>")
	)
	(segment
		(start 197.38594 -41.469818)
		(end 193.240152 -34.717736)
		(width 0.1651)
		(layer "In11.Cu")
		(net "P5E_PEX1_STN2_TX_DP<38>")
	)
	(segment
		(start 189.81547 -32.423354)
		(end 189.19825 -32.423354)
		(width 0.1651)
		(layer "In11.Cu")
		(net "P5E_PEX1_STN2_TX_DP<38>")
	)
	(segment
		(start 168.529762 -280.10485)
		(end 168.529762 -271.473168)
		(width 0.1143)
		(layer "In11.Cu")
		(net "P5E_PEX1_STN2_TX_DP<38>")
	)
	(segment
		(start 204.042518 -48.697642)
		(end 197.38594 -41.469818)
		(width 0.1651)
		(layer "In11.Cu")
		(net "P5E_PEX1_STN2_TX_DP<38>")
	)
	(segment
		(start 169.099992 -280.434288)
		(end 168.985692 -280.319988)
		(width 0.1143)
		(layer "In11.Cu")
		(net "P5E_PEX1_STN2_TX_DP<38>")
	)
	(segment
		(start 118.054628 -343.685622)
		(end 118.374668 -343.365582)
		(width 0.13462)
		(layer "F.Cu")
		(net "P5E_PEX1_STN6_TX_DP<109>")
	)
	(segment
		(start 118.374668 -342.734138)
		(end 118.080028 -342.439498)
		(width 0.13462)
		(layer "F.Cu")
		(net "P5E_PEX1_STN6_TX_DP<109>")
	)
	(segment
		(start 118.374668 -343.365582)
		(end 118.374668 -342.734138)
		(width 0.13462)
		(layer "F.Cu")
		(net "P5E_PEX1_STN6_TX_DP<109>")
	)
	(segment
		(start 125.619256 -335.319878)
		(end 121.2596 -338.233258)
		(width 0.1651)
		(layer "In13.Cu")
		(net "P5E_PEX1_STN6_TX_DP<109>")
	)
	(segment
		(start 161.500058 -311.099962)
		(end 161.500058 -311.365392)
		(width 0.1143)
		(layer "In13.Cu")
		(net "P5E_PEX1_STN6_TX_DP<109>")
	)
	(segment
		(start 160.884108 -320.063114)
		(end 160.884108 -320.985134)
		(width 0.1651)
		(layer "In13.Cu")
		(net "P5E_PEX1_STN6_TX_DP<109>")
	)
	(segment
		(start 147.707096 -327.962514)
		(end 145.774156 -328.346308)
		(width 0.1651)
		(layer "In13.Cu")
		(net "P5E_PEX1_STN6_TX_DP<109>")
	)
	(segment
		(start 160.929828 -319.995296)
		(end 160.884108 -320.041016)
		(width 0.1143)
		(layer "In13.Cu")
		(net "P5E_PEX1_STN6_TX_DP<109>")
	)
	(segment
		(start 161.144966 -311.479692)
		(end 160.929828 -311.69483)
		(width 0.1143)
		(layer "In13.Cu")
		(net "P5E_PEX1_STN6_TX_DP<109>")
	)
	(segment
		(start 129.328418 -333.337408)
		(end 125.619256 -335.319878)
		(width 0.1651)
		(layer "In13.Cu")
		(net "P5E_PEX1_STN6_TX_DP<109>")
	)
	(segment
		(start 161.385758 -311.479692)
		(end 161.144966 -311.479692)
		(width 0.1143)
		(layer "In13.Cu")
		(net "P5E_PEX1_STN6_TX_DP<109>")
	)
	(segment
		(start 145.774156 -328.346308)
		(end 141.377924 -328.346308)
		(width 0.1651)
		(layer "In13.Cu")
		(net "P5E_PEX1_STN6_TX_DP<109>")
	)
	(segment
		(start 159.231584 -322.637658)
		(end 156.255466 -324.421754)
		(width 0.1651)
		(layer "In13.Cu")
		(net "P5E_PEX1_STN6_TX_DP<109>")
	)
	(segment
		(start 121.2596 -338.233258)
		(end 118.370858 -341.122)
		(width 0.1651)
		(layer "In13.Cu")
		(net "P5E_PEX1_STN6_TX_DP<109>")
	)
	(segment
		(start 156.255466 -324.421754)
		(end 147.707096 -327.962514)
		(width 0.1651)
		(layer "In13.Cu")
		(net "P5E_PEX1_STN6_TX_DP<109>")
	)
	(segment
		(start 118.370858 -341.122)
		(end 118.370858 -342.148668)
		(width 0.1651)
		(layer "In13.Cu")
		(net "P5E_PEX1_STN6_TX_DP<109>")
	)
	(segment
		(start 160.929828 -311.69483)
		(end 160.929828 -319.995296)
		(width 0.1143)
		(layer "In13.Cu")
		(net "P5E_PEX1_STN6_TX_DP<109>")
	)
	(segment
		(start 161.500058 -311.365392)
		(end 161.385758 -311.479692)
		(width 0.1143)
		(layer "In13.Cu")
		(net "P5E_PEX1_STN6_TX_DP<109>")
	)
	(segment
		(start 141.377924 -328.346308)
		(end 129.328418 -333.337408)
		(width 0.1651)
		(layer "In13.Cu")
		(net "P5E_PEX1_STN6_TX_DP<109>")
	)
	(segment
		(start 118.370858 -342.148668)
		(end 118.080028 -342.439498)
		(width 0.1651)
		(layer "In13.Cu")
		(net "P5E_PEX1_STN6_TX_DP<109>")
	)
	(segment
		(start 160.884108 -320.985134)
		(end 159.231584 -322.637658)
		(width 0.1651)
		(layer "In13.Cu")
		(net "P5E_PEX1_STN6_TX_DP<109>")
	)
	(segment
		(start 160.884108 -320.041016)
		(end 160.884108 -320.063114)
		(width 0.1143)
		(layer "In13.Cu")
		(net "P5E_PEX1_STN6_TX_DP<109>")
	)
	(segment
		(start 313.442858 -130.4798)
		(end 312.800746 -130.4798)
		(width 0.13462)
		(layer "F.Cu")
		(net "P5E_PEX2_STN0_TX_DP<4>")
	)
	(segment
		(start 312.800746 -130.4798)
		(end 312.48604 -130.794506)
		(width 0.13462)
		(layer "F.Cu")
		(net "P5E_PEX2_STN0_TX_DP<4>")
	)
	(segment
		(start 313.732164 -130.769106)
		(end 313.442858 -130.4798)
		(width 0.13462)
		(layer "F.Cu")
		(net "P5E_PEX2_STN0_TX_DP<4>")
	)
	(segment
		(start 316.04331 -283.929582)
		(end 309.54472 -283.929582)
		(width 0.1143)
		(layer "In9.Cu")
		(net "P5E_PEX2_STN0_TX_DP<4>")
	)
	(segment
		(start 316.117478 -283.883862)
		(end 316.08903 -283.883862)
		(width 0.1143)
		(layer "In9.Cu")
		(net "P5E_PEX2_STN0_TX_DP<4>")
	)
	(segment
		(start 316.40399 -130.478276)
		(end 317.367666 -130.877564)
		(width 0.1651)
		(layer "In9.Cu")
		(net "P5E_PEX2_STN0_TX_DP<4>")
	)
	(segment
		(start 314.669424 -221.593156)
		(end 315.943742 -236.187234)
		(width 0.1651)
		(layer "In9.Cu")
		(net "P5E_PEX2_STN0_TX_DP<4>")
	)
	(segment
		(start 314.937902 -130.478276)
		(end 315.039502 -130.579876)
		(width 0.1651)
		(layer "In9.Cu")
		(net "P5E_PEX2_STN0_TX_DP<4>")
	)
	(segment
		(start 313.732164 -130.769106)
		(end 314.022994 -130.478276)
		(width 0.1651)
		(layer "In9.Cu")
		(net "P5E_PEX2_STN0_TX_DP<4>")
	)
	(segment
		(start 328.158348 -159.64408)
		(end 319.49009 -174.663862)
		(width 0.1651)
		(layer "In9.Cu")
		(net "P5E_PEX2_STN0_TX_DP<4>")
	)
	(segment
		(start 321.341242 -137.348976)
		(end 321.474084 -137.404094)
		(width 0.1651)
		(layer "In9.Cu")
		(net "P5E_PEX2_STN0_TX_DP<4>")
	)
	(segment
		(start 321.474084 -137.404094)
		(end 324.38721 -144.436338)
		(width 0.1651)
		(layer "In9.Cu")
		(net "P5E_PEX2_STN0_TX_DP<4>")
	)
	(segment
		(start 320.618612 -135.338566)
		(end 320.793364 -135.760714)
		(width 0.1651)
		(layer "In9.Cu")
		(net "P5E_PEX2_STN0_TX_DP<4>")
	)
	(segment
		(start 318.56807 -132.221732)
		(end 318.891666 -132.545328)
		(width 0.1651)
		(layer "In9.Cu")
		(net "P5E_PEX2_STN0_TX_DP<4>")
	)
	(segment
		(start 319.883028 -133.828028)
		(end 320.058034 -134.250684)
		(width 0.1651)
		(layer "In9.Cu")
		(net "P5E_PEX2_STN0_TX_DP<4>")
	)
	(segment
		(start 328.218546 -159.418782)
		(end 328.158348 -159.64408)
		(width 0.1651)
		(layer "In9.Cu")
		(net "P5E_PEX2_STN0_TX_DP<4>")
	)
	(segment
		(start 315.598302 -130.478276)
		(end 316.40399 -130.478276)
		(width 0.1651)
		(layer "In9.Cu")
		(net "P5E_PEX2_STN0_TX_DP<4>")
	)
	(segment
		(start 319.271142 -283.014928)
		(end 317.17361 -283.883862)
		(width 0.1651)
		(layer "In9.Cu")
		(net "P5E_PEX2_STN0_TX_DP<4>")
	)
	(segment
		(start 321.2211 -136.793478)
		(end 321.166236 -136.92632)
		(width 0.1651)
		(layer "In9.Cu")
		(net "P5E_PEX2_STN0_TX_DP<4>")
	)
	(segment
		(start 320.310764 -134.860792)
		(end 320.48577 -135.283448)
		(width 0.1651)
		(layer "In9.Cu")
		(net "P5E_PEX2_STN0_TX_DP<4>")
	)
	(segment
		(start 318.429132 -178.621436)
		(end 314.669424 -221.593156)
		(width 0.1651)
		(layer "In9.Cu")
		(net "P5E_PEX2_STN0_TX_DP<4>")
	)
	(segment
		(start 320.190876 -134.305802)
		(end 320.365628 -134.72795)
		(width 0.1651)
		(layer "In9.Cu")
		(net "P5E_PEX2_STN0_TX_DP<4>")
	)
	(segment
		(start 318.244982 -131.75488)
		(end 318.56807 -132.077968)
		(width 0.1651)
		(layer "In9.Cu")
		(net "P5E_PEX2_STN0_TX_DP<4>")
	)
	(segment
		(start 317.22187 -250.828302)
		(end 327.613772 -266.38123)
		(width 0.1651)
		(layer "In9.Cu")
		(net "P5E_PEX2_STN0_TX_DP<4>")
	)
	(segment
		(start 328.724514 -272.107406)
		(end 327.696068 -274.590002)
		(width 0.1651)
		(layer "In9.Cu")
		(net "P5E_PEX2_STN0_TX_DP<4>")
	)
	(segment
		(start 320.793364 -135.760714)
		(end 320.7385 -135.893556)
		(width 0.1651)
		(layer "In9.Cu")
		(net "P5E_PEX2_STN0_TX_DP<4>")
	)
	(segment
		(start 318.891666 -132.545328)
		(end 319.03543 -132.545328)
		(width 0.1651)
		(layer "In9.Cu")
		(net "P5E_PEX2_STN0_TX_DP<4>")
	)
	(segment
		(start 309.329582 -284.14472)
		(end 309.329582 -284.385512)
		(width 0.1143)
		(layer "In9.Cu")
		(net "P5E_PEX2_STN0_TX_DP<4>")
	)
	(segment
		(start 309.329582 -284.385512)
		(end 309.215282 -284.499812)
		(width 0.1143)
		(layer "In9.Cu")
		(net "P5E_PEX2_STN0_TX_DP<4>")
	)
	(segment
		(start 314.022994 -130.478276)
		(end 314.937902 -130.478276)
		(width 0.1651)
		(layer "In9.Cu")
		(net "P5E_PEX2_STN0_TX_DP<4>")
	)
	(segment
		(start 320.058034 -134.250684)
		(end 320.190876 -134.305802)
		(width 0.1651)
		(layer "In9.Cu")
		(net "P5E_PEX2_STN0_TX_DP<4>")
	)
	(segment
		(start 316.08903 -283.883862)
		(end 316.04331 -283.929582)
		(width 0.1143)
		(layer "In9.Cu")
		(net "P5E_PEX2_STN0_TX_DP<4>")
	)
	(segment
		(start 317.777622 -131.28752)
		(end 317.777622 -131.431284)
		(width 0.1651)
		(layer "In9.Cu")
		(net "P5E_PEX2_STN0_TX_DP<4>")
	)
	(segment
		(start 320.365628 -134.72795)
		(end 320.310764 -134.860792)
		(width 0.1651)
		(layer "In9.Cu")
		(net "P5E_PEX2_STN0_TX_DP<4>")
	)
	(segment
		(start 319.49009 -174.663862)
		(end 318.429132 -178.621436)
		(width 0.1651)
		(layer "In9.Cu")
		(net "P5E_PEX2_STN0_TX_DP<4>")
	)
	(segment
		(start 320.7385 -135.893556)
		(end 320.913506 -136.316212)
		(width 0.1651)
		(layer "In9.Cu")
		(net "P5E_PEX2_STN0_TX_DP<4>")
	)
	(segment
		(start 324.38721 -144.436338)
		(end 324.559422 -144.60855)
		(width 0.1651)
		(layer "In9.Cu")
		(net "P5E_PEX2_STN0_TX_DP<4>")
	)
	(segment
		(start 328.218546 -153.442416)
		(end 328.218546 -159.418782)
		(width 0.1651)
		(layer "In9.Cu")
		(net "P5E_PEX2_STN0_TX_DP<4>")
	)
	(segment
		(start 318.101218 -131.75488)
		(end 318.244982 -131.75488)
		(width 0.1651)
		(layer "In9.Cu")
		(net "P5E_PEX2_STN0_TX_DP<4>")
	)
	(segment
		(start 317.17361 -283.883862)
		(end 316.117478 -283.883862)
		(width 0.1651)
		(layer "In9.Cu")
		(net "P5E_PEX2_STN0_TX_DP<4>")
	)
	(segment
		(start 317.367666 -130.877564)
		(end 317.777622 -131.28752)
		(width 0.1651)
		(layer "In9.Cu")
		(net "P5E_PEX2_STN0_TX_DP<4>")
	)
	(segment
		(start 327.696068 -274.590002)
		(end 319.271142 -283.014928)
		(width 0.1651)
		(layer "In9.Cu")
		(net "P5E_PEX2_STN0_TX_DP<4>")
	)
	(segment
		(start 309.54472 -283.929582)
		(end 309.329582 -284.14472)
		(width 0.1143)
		(layer "In9.Cu")
		(net "P5E_PEX2_STN0_TX_DP<4>")
	)
	(segment
		(start 319.937892 -133.695186)
		(end 319.883028 -133.828028)
		(width 0.1651)
		(layer "In9.Cu")
		(net "P5E_PEX2_STN0_TX_DP<4>")
	)
	(segment
		(start 320.48577 -135.283448)
		(end 320.618612 -135.338566)
		(width 0.1651)
		(layer "In9.Cu")
		(net "P5E_PEX2_STN0_TX_DP<4>")
	)
	(segment
		(start 315.496702 -130.579876)
		(end 315.598302 -130.478276)
		(width 0.1651)
		(layer "In9.Cu")
		(net "P5E_PEX2_STN0_TX_DP<4>")
	)
	(segment
		(start 315.943742 -236.187234)
		(end 317.22187 -250.828302)
		(width 0.1651)
		(layer "In9.Cu")
		(net "P5E_PEX2_STN0_TX_DP<4>")
	)
	(segment
		(start 328.387456 -268.2494)
		(end 328.724514 -272.107406)
		(width 0.1651)
		(layer "In9.Cu")
		(net "P5E_PEX2_STN0_TX_DP<4>")
	)
	(segment
		(start 317.777622 -131.431284)
		(end 318.101218 -131.75488)
		(width 0.1651)
		(layer "In9.Cu")
		(net "P5E_PEX2_STN0_TX_DP<4>")
	)
	(segment
		(start 318.56807 -132.077968)
		(end 318.56807 -132.221732)
		(width 0.1651)
		(layer "In9.Cu")
		(net "P5E_PEX2_STN0_TX_DP<4>")
	)
	(segment
		(start 320.913506 -136.316212)
		(end 321.046348 -136.37133)
		(width 0.1651)
		(layer "In9.Cu")
		(net "P5E_PEX2_STN0_TX_DP<4>")
	)
	(segment
		(start 327.613772 -266.38123)
		(end 328.387456 -268.2494)
		(width 0.1651)
		(layer "In9.Cu")
		(net "P5E_PEX2_STN0_TX_DP<4>")
	)
	(segment
		(start 309.215282 -284.499812)
		(end 308.949852 -284.499812)
		(width 0.1143)
		(layer "In9.Cu")
		(net "P5E_PEX2_STN0_TX_DP<4>")
	)
	(segment
		(start 319.76314 -133.273038)
		(end 319.937892 -133.695186)
		(width 0.1651)
		(layer "In9.Cu")
		(net "P5E_PEX2_STN0_TX_DP<4>")
	)
	(segment
		(start 321.046348 -136.37133)
		(end 321.2211 -136.793478)
		(width 0.1651)
		(layer "In9.Cu")
		(net "P5E_PEX2_STN0_TX_DP<4>")
	)
	(segment
		(start 321.166236 -136.92632)
		(end 321.341242 -137.348976)
		(width 0.1651)
		(layer "In9.Cu")
		(net "P5E_PEX2_STN0_TX_DP<4>")
	)
	(segment
		(start 324.559422 -144.60855)
		(end 328.218546 -153.442416)
		(width 0.1651)
		(layer "In9.Cu")
		(net "P5E_PEX2_STN0_TX_DP<4>")
	)
	(segment
		(start 319.03543 -132.545328)
		(end 319.76314 -133.273038)
		(width 0.1651)
		(layer "In9.Cu")
		(net "P5E_PEX2_STN0_TX_DP<4>")
	)
	(segment
		(start 315.039502 -130.579876)
		(end 315.496702 -130.579876)
		(width 0.1651)
		(layer "In9.Cu")
		(net "P5E_PEX2_STN0_TX_DP<4>")
	)
	(segment
		(start 290.228782 -342.734138)
		(end 290.523422 -342.439498)
		(width 0.13462)
		(layer "F.Cu")
		(net "P5E_PEX2_STN7_TX_DP<122>")
	)
	(segment
		(start 290.548822 -343.685622)
		(end 290.228782 -343.365582)
		(width 0.13462)
		(layer "F.Cu")
		(net "P5E_PEX2_STN7_TX_DP<122>")
	)
	(segment
		(start 290.228782 -343.365582)
		(end 290.228782 -342.734138)
		(width 0.13462)
		(layer "F.Cu")
		(net "P5E_PEX2_STN7_TX_DP<122>")
	)
	(segment
		(start 268.577568 -315.470032)
		(end 269.394178 -315.470032)
		(width 0.1143)
		(layer "In7.Cu")
		(net "P5E_PEX2_STN7_TX_DP<122>")
	)
	(segment
		(start 290.232592 -342.148668)
		(end 290.232592 -341.633048)
		(width 0.1651)
		(layer "In7.Cu")
		(net "P5E_PEX2_STN7_TX_DP<122>")
	)
	(segment
		(start 267.510768 -317.539624)
		(end 267.510768 -316.601856)
		(width 0.1651)
		(layer "In7.Cu")
		(net "P5E_PEX2_STN7_TX_DP<122>")
	)
	(segment
		(start 269.394178 -315.470032)
		(end 269.619984 -315.244226)
		(width 0.1143)
		(layer "In7.Cu")
		(net "P5E_PEX2_STN7_TX_DP<122>")
	)
	(segment
		(start 290.232592 -341.633048)
		(end 289.881564 -340.995254)
		(width 0.1651)
		(layer "In7.Cu")
		(net "P5E_PEX2_STN7_TX_DP<122>")
	)
	(segment
		(start 267.768324 -318.834262)
		(end 267.510768 -317.539624)
		(width 0.1651)
		(layer "In7.Cu")
		(net "P5E_PEX2_STN7_TX_DP<122>")
	)
	(segment
		(start 269.619984 -315.244226)
		(end 269.619984 -315.014102)
		(width 0.1143)
		(layer "In7.Cu")
		(net "P5E_PEX2_STN7_TX_DP<122>")
	)
	(segment
		(start 290.523422 -342.439498)
		(end 290.232592 -342.148668)
		(width 0.1651)
		(layer "In7.Cu")
		(net "P5E_PEX2_STN7_TX_DP<122>")
	)
	(segment
		(start 268.125448 -315.987176)
		(end 268.145514 -315.96711)
		(width 0.1143)
		(layer "In7.Cu")
		(net "P5E_PEX2_STN7_TX_DP<122>")
	)
	(segment
		(start 269.619984 -315.014102)
		(end 269.734284 -314.899802)
		(width 0.1143)
		(layer "In7.Cu")
		(net "P5E_PEX2_STN7_TX_DP<122>")
	)
	(segment
		(start 268.145514 -315.902086)
		(end 268.577568 -315.470032)
		(width 0.1143)
		(layer "In7.Cu")
		(net "P5E_PEX2_STN7_TX_DP<122>")
	)
	(segment
		(start 268.145514 -315.96711)
		(end 268.145514 -315.902086)
		(width 0.1143)
		(layer "In7.Cu")
		(net "P5E_PEX2_STN7_TX_DP<122>")
	)
	(segment
		(start 289.881564 -340.995254)
		(end 270.618966 -323.987668)
		(width 0.1651)
		(layer "In7.Cu")
		(net "P5E_PEX2_STN7_TX_DP<122>")
	)
	(segment
		(start 270.618966 -323.987668)
		(end 268.913864 -321.600068)
		(width 0.1651)
		(layer "In7.Cu")
		(net "P5E_PEX2_STN7_TX_DP<122>")
	)
	(segment
		(start 267.510768 -316.601856)
		(end 268.125448 -315.987176)
		(width 0.1651)
		(layer "In7.Cu")
		(net "P5E_PEX2_STN7_TX_DP<122>")
	)
	(segment
		(start 268.913864 -321.600068)
		(end 267.768324 -318.834262)
		(width 0.1651)
		(layer "In7.Cu")
		(net "P5E_PEX2_STN7_TX_DP<122>")
	)
	(segment
		(start 269.734284 -314.899802)
		(end 269.999714 -314.899802)
		(width 0.1143)
		(layer "In7.Cu")
		(net "P5E_PEX2_STN7_TX_DP<122>")
	)
	(segment
		(start 431.553874 -151.92248)
		(end 431.228246 -151.596852)
		(width 0.13462)
		(layer "F.Cu")
		(net "P5E_PEX3_STN0_TX_DN<13>")
	)
	(segment
		(start 432.47437 -151.622252)
		(end 432.174142 -151.92248)
		(width 0.13462)
		(layer "F.Cu")
		(net "P5E_PEX3_STN0_TX_DN<13>")
	)
	(segment
		(start 432.174142 -151.92248)
		(end 431.553874 -151.92248)
		(width 0.13462)
		(layer "F.Cu")
		(net "P5E_PEX3_STN0_TX_DN<13>")
	)
	(segment
		(start 435.471824 -154.564334)
		(end 434.005482 -152.370028)
		(width 0.1651)
		(layer "In9.Cu")
		(net "P5E_PEX3_STN0_TX_DN<13>")
	)
	(segment
		(start 434.005482 -152.370028)
		(end 433.548536 -151.913082)
		(width 0.1651)
		(layer "In9.Cu")
		(net "P5E_PEX3_STN0_TX_DN<13>")
	)
	(segment
		(start 427.501304 -171.632118)
		(end 435.890924 -157.099254)
		(width 0.1651)
		(layer "In9.Cu")
		(net "P5E_PEX3_STN0_TX_DN<13>")
	)
	(segment
		(start 424.773598 -278.229568)
		(end 424.67022 -278.12619)
		(width 0.1143)
		(layer "In9.Cu")
		(net "P5E_PEX3_STN0_TX_DN<13>")
	)
	(segment
		(start 424.67022 -271.546066)
		(end 424.71594 -271.500346)
		(width 0.1143)
		(layer "In9.Cu")
		(net "P5E_PEX3_STN0_TX_DN<13>")
	)
	(segment
		(start 424.71594 -271.471898)
		(end 424.71594 -270.044164)
		(width 0.1651)
		(layer "In9.Cu")
		(net "P5E_PEX3_STN0_TX_DN<13>")
	)
	(segment
		(start 432.7652 -151.913082)
		(end 432.47437 -151.622252)
		(width 0.1651)
		(layer "In9.Cu")
		(net "P5E_PEX3_STN0_TX_DN<13>")
	)
	(segment
		(start 424.935396 -278.229568)
		(end 424.773598 -278.229568)
		(width 0.1143)
		(layer "In9.Cu")
		(net "P5E_PEX3_STN0_TX_DN<13>")
	)
	(segment
		(start 435.890924 -155.576524)
		(end 435.471824 -154.564334)
		(width 0.1651)
		(layer "In9.Cu")
		(net "P5E_PEX3_STN0_TX_DN<13>")
	)
	(segment
		(start 435.890924 -157.099254)
		(end 435.890924 -155.576524)
		(width 0.1651)
		(layer "In9.Cu")
		(net "P5E_PEX3_STN0_TX_DN<13>")
	)
	(segment
		(start 424.71594 -270.044164)
		(end 425.625768 -267.847064)
		(width 0.1651)
		(layer "In9.Cu")
		(net "P5E_PEX3_STN0_TX_DN<13>")
	)
	(segment
		(start 425.049696 -278.115268)
		(end 424.935396 -278.229568)
		(width 0.1143)
		(layer "In9.Cu")
		(net "P5E_PEX3_STN0_TX_DN<13>")
	)
	(segment
		(start 433.548536 -151.913082)
		(end 432.7652 -151.913082)
		(width 0.1651)
		(layer "In9.Cu")
		(net "P5E_PEX3_STN0_TX_DN<13>")
	)
	(segment
		(start 422.180766 -221.36227)
		(end 426.062394 -177.001678)
		(width 0.1651)
		(layer "In9.Cu")
		(net "P5E_PEX3_STN0_TX_DN<13>")
	)
	(segment
		(start 425.625768 -267.847064)
		(end 425.625768 -260.750558)
		(width 0.1651)
		(layer "In9.Cu")
		(net "P5E_PEX3_STN0_TX_DN<13>")
	)
	(segment
		(start 425.625768 -260.750558)
		(end 422.180766 -221.36227)
		(width 0.1651)
		(layer "In9.Cu")
		(net "P5E_PEX3_STN0_TX_DN<13>")
	)
	(segment
		(start 425.049696 -277.849838)
		(end 425.049696 -278.115268)
		(width 0.1143)
		(layer "In9.Cu")
		(net "P5E_PEX3_STN0_TX_DN<13>")
	)
	(segment
		(start 424.67022 -278.12619)
		(end 424.67022 -271.546066)
		(width 0.1143)
		(layer "In9.Cu")
		(net "P5E_PEX3_STN0_TX_DN<13>")
	)
	(segment
		(start 424.71594 -271.500346)
		(end 424.71594 -271.471898)
		(width 0.1143)
		(layer "In9.Cu")
		(net "P5E_PEX3_STN0_TX_DN<13>")
	)
	(segment
		(start 426.062394 -177.001678)
		(end 427.501304 -171.632118)
		(width 0.1651)
		(layer "In9.Cu")
		(net "P5E_PEX3_STN0_TX_DN<13>")
	)
	(segment
		(start 143.246348 -344.539062)
		(end 142.926308 -344.219022)
		(width 0.13462)
		(layer "F.Cu")
		(net "P5E_PEX1_STN5_TX_C_DP<94>")
	)
	(segment
		(start 142.951708 -345.465146)
		(end 143.246348 -345.170506)
		(width 0.13462)
		(layer "F.Cu")
		(net "P5E_PEX1_STN5_TX_C_DP<94>")
	)
	(segment
		(start 143.246348 -345.170506)
		(end 143.246348 -344.539062)
		(width 0.13462)
		(layer "F.Cu")
		(net "P5E_PEX1_STN5_TX_C_DP<94>")
	)
	(segment
		(start 134.471918 -364.422944)
		(end 134.080758 -364.726474)
		(width 0.1651)
		(layer "In13.Cu")
		(net "P5E_PEX1_STN5_TX_C_DP<94>")
	)
	(segment
		(start 141.688058 -347.862398)
		(end 141.688058 -358.193086)
		(width 0.1651)
		(layer "In13.Cu")
		(net "P5E_PEX1_STN5_TX_C_DP<94>")
	)
	(segment
		(start 143.242538 -345.755976)
		(end 143.242538 -346.307918)
		(width 0.1651)
		(layer "In13.Cu")
		(net "P5E_PEX1_STN5_TX_C_DP<94>")
	)
	(segment
		(start 143.242538 -346.307918)
		(end 141.688058 -347.862398)
		(width 0.1651)
		(layer "In13.Cu")
		(net "P5E_PEX1_STN5_TX_C_DP<94>")
	)
	(segment
		(start 132.625846 -365.85652)
		(end 130.745992 -367.316258)
		(width 0.1651)
		(layer "In13.Cu")
		(net "P5E_PEX1_STN5_TX_C_DP<94>")
	)
	(segment
		(start 133.956044 -364.710726)
		(end 133.564376 -365.014764)
		(width 0.1651)
		(layer "In13.Cu")
		(net "P5E_PEX1_STN5_TX_C_DP<94>")
	)
	(segment
		(start 134.87908 -363.993938)
		(end 134.487412 -364.297976)
		(width 0.1651)
		(layer "In13.Cu")
		(net "P5E_PEX1_STN5_TX_C_DP<94>")
	)
	(segment
		(start 134.487412 -364.297976)
		(end 134.471918 -364.422944)
		(width 0.1651)
		(layer "In13.Cu")
		(net "P5E_PEX1_STN5_TX_C_DP<94>")
	)
	(segment
		(start 141.688058 -358.193086)
		(end 141.19352 -359.203244)
		(width 0.1651)
		(layer "In13.Cu")
		(net "P5E_PEX1_STN5_TX_C_DP<94>")
	)
	(segment
		(start 133.157722 -365.443262)
		(end 133.033008 -365.427768)
		(width 0.1651)
		(layer "In13.Cu")
		(net "P5E_PEX1_STN5_TX_C_DP<94>")
	)
	(segment
		(start 142.951708 -345.465146)
		(end 143.242538 -345.755976)
		(width 0.1651)
		(layer "In13.Cu")
		(net "P5E_PEX1_STN5_TX_C_DP<94>")
	)
	(segment
		(start 133.564376 -365.014764)
		(end 133.548882 -365.139732)
		(width 0.1651)
		(layer "In13.Cu")
		(net "P5E_PEX1_STN5_TX_C_DP<94>")
	)
	(segment
		(start 134.080758 -364.726474)
		(end 133.956044 -364.710726)
		(width 0.1651)
		(layer "In13.Cu")
		(net "P5E_PEX1_STN5_TX_C_DP<94>")
	)
	(segment
		(start 133.033008 -365.427768)
		(end 132.641594 -365.731806)
		(width 0.1651)
		(layer "In13.Cu")
		(net "P5E_PEX1_STN5_TX_C_DP<94>")
	)
	(segment
		(start 132.641594 -365.731806)
		(end 132.625846 -365.85652)
		(width 0.1651)
		(layer "In13.Cu")
		(net "P5E_PEX1_STN5_TX_C_DP<94>")
	)
	(segment
		(start 135.003794 -364.009686)
		(end 134.87908 -363.993938)
		(width 0.1651)
		(layer "In13.Cu")
		(net "P5E_PEX1_STN5_TX_C_DP<94>")
	)
	(segment
		(start 133.548882 -365.139732)
		(end 133.157722 -365.443262)
		(width 0.1651)
		(layer "In13.Cu")
		(net "P5E_PEX1_STN5_TX_C_DP<94>")
	)
	(segment
		(start 129.109978 -378.67209)
		(end 129.109978 -378.290074)
		(width 0.1651)
		(layer "In13.Cu")
		(net "P5E_PEX1_STN5_TX_C_DP<94>")
	)
	(segment
		(start 130.745992 -367.316258)
		(end 129.984754 -368.871246)
		(width 0.1651)
		(layer "In13.Cu")
		(net "P5E_PEX1_STN5_TX_C_DP<94>")
	)
	(segment
		(start 129.458466 -378.79909)
		(end 129.236978 -378.79909)
		(width 0.1651)
		(layer "In13.Cu")
		(net "P5E_PEX1_STN5_TX_C_DP<94>")
	)
	(segment
		(start 141.19352 -359.203244)
		(end 135.003794 -364.009686)
		(width 0.1651)
		(layer "In13.Cu")
		(net "P5E_PEX1_STN5_TX_C_DP<94>")
	)
	(segment
		(start 129.984754 -368.871246)
		(end 129.984754 -378.272802)
		(width 0.1651)
		(layer "In13.Cu")
		(net "P5E_PEX1_STN5_TX_C_DP<94>")
	)
	(segment
		(start 129.984754 -378.272802)
		(end 129.458466 -378.79909)
		(width 0.1651)
		(layer "In13.Cu")
		(net "P5E_PEX1_STN5_TX_C_DP<94>")
	)
	(segment
		(start 129.236978 -378.79909)
		(end 129.109978 -378.67209)
		(width 0.1651)
		(layer "In13.Cu")
		(net "P5E_PEX1_STN5_TX_C_DP<94>")
	)
	(segment
		(start 127.381508 -355.978206)
		(end 127.701548 -355.658166)
		(width 0.13462)
		(layer "F.Cu")
		(net "P5E_PEX1_STN5_TX_DP<80>")
	)
	(segment
		(start 127.701548 -355.658166)
		(end 127.701548 -355.026722)
		(width 0.13462)
		(layer "F.Cu")
		(net "P5E_PEX1_STN5_TX_DP<80>")
	)
	(segment
		(start 127.701548 -355.026722)
		(end 127.406908 -354.732082)
		(width 0.13462)
		(layer "F.Cu")
		(net "P5E_PEX1_STN5_TX_DP<80>")
	)
	(segment
		(start 174.685706 -311.479692)
		(end 174.800006 -311.365392)
		(width 0.1143)
		(layer "In7.Cu")
		(net "P5E_PEX1_STN5_TX_DP<80>")
	)
	(segment
		(start 174.800006 -311.365392)
		(end 174.800006 -311.099962)
		(width 0.1143)
		(layer "In7.Cu")
		(net "P5E_PEX1_STN5_TX_DP<80>")
	)
	(segment
		(start 174.455582 -311.479692)
		(end 174.685706 -311.479692)
		(width 0.1143)
		(layer "In7.Cu")
		(net "P5E_PEX1_STN5_TX_DP<80>")
	)
	(segment
		(start 174.184056 -322.46189)
		(end 174.184056 -320.016886)
		(width 0.1651)
		(layer "In7.Cu")
		(net "P5E_PEX1_STN5_TX_DP<80>")
	)
	(segment
		(start 171.979844 -325.65848)
		(end 173.482254 -324.15607)
		(width 0.1651)
		(layer "In7.Cu")
		(net "P5E_PEX1_STN5_TX_DP<80>")
	)
	(segment
		(start 168.768522 -327.583292)
		(end 171.979844 -325.65848)
		(width 0.1651)
		(layer "In7.Cu")
		(net "P5E_PEX1_STN5_TX_DP<80>")
	)
	(segment
		(start 173.482254 -324.15607)
		(end 174.184056 -322.46189)
		(width 0.1651)
		(layer "In7.Cu")
		(net "P5E_PEX1_STN5_TX_DP<80>")
	)
	(segment
		(start 174.184056 -319.988438)
		(end 174.229776 -319.942718)
		(width 0.1143)
		(layer "In7.Cu")
		(net "P5E_PEX1_STN5_TX_DP<80>")
	)
	(segment
		(start 127.406908 -354.732082)
		(end 127.697738 -354.441252)
		(width 0.1651)
		(layer "In7.Cu")
		(net "P5E_PEX1_STN5_TX_DP<80>")
	)
	(segment
		(start 130.01752 -340.830154)
		(end 135.053324 -337.811364)
		(width 0.1651)
		(layer "In7.Cu")
		(net "P5E_PEX1_STN5_TX_DP<80>")
	)
	(segment
		(start 174.229776 -319.942718)
		(end 174.229776 -311.705498)
		(width 0.1143)
		(layer "In7.Cu")
		(net "P5E_PEX1_STN5_TX_DP<80>")
	)
	(segment
		(start 127.697738 -354.441252)
		(end 127.697738 -353.705922)
		(width 0.1651)
		(layer "In7.Cu")
		(net "P5E_PEX1_STN5_TX_DP<80>")
	)
	(segment
		(start 174.184056 -320.016886)
		(end 174.184056 -319.988438)
		(width 0.1143)
		(layer "In7.Cu")
		(net "P5E_PEX1_STN5_TX_DP<80>")
	)
	(segment
		(start 129.252218 -352.151442)
		(end 129.252218 -341.595456)
		(width 0.1651)
		(layer "In7.Cu")
		(net "P5E_PEX1_STN5_TX_DP<80>")
	)
	(segment
		(start 174.229776 -311.705498)
		(end 174.455582 -311.479692)
		(width 0.1143)
		(layer "In7.Cu")
		(net "P5E_PEX1_STN5_TX_DP<80>")
	)
	(segment
		(start 135.053324 -337.811364)
		(end 160.339786 -330.14031)
		(width 0.1651)
		(layer "In7.Cu")
		(net "P5E_PEX1_STN5_TX_DP<80>")
	)
	(segment
		(start 160.339786 -330.14031)
		(end 168.768522 -327.583292)
		(width 0.1651)
		(layer "In7.Cu")
		(net "P5E_PEX1_STN5_TX_DP<80>")
	)
	(segment
		(start 127.697738 -353.705922)
		(end 129.252218 -352.151442)
		(width 0.1651)
		(layer "In7.Cu")
		(net "P5E_PEX1_STN5_TX_DP<80>")
	)
	(segment
		(start 129.252218 -341.595456)
		(end 130.01752 -340.830154)
		(width 0.1651)
		(layer "In7.Cu")
		(net "P5E_PEX1_STN5_TX_DP<80>")
	)
	(segment
		(start 193.844672 -342.734138)
		(end 194.139312 -342.439498)
		(width 0.13462)
		(layer "F.Cu")
		(net "P5E_PEX1_STN7_TX_DN<127>")
	)
	(segment
		(start 194.164712 -343.685622)
		(end 193.844672 -343.365582)
		(width 0.13462)
		(layer "F.Cu")
		(net "P5E_PEX1_STN7_TX_DN<127>")
	)
	(segment
		(start 193.844672 -343.365582)
		(end 193.844672 -342.734138)
		(width 0.13462)
		(layer "F.Cu")
		(net "P5E_PEX1_STN7_TX_DN<127>")
	)
	(segment
		(start 158.649924 -313.659012)
		(end 158.649924 -313.949842)
		(width 0.1143)
		(layer "In11.Cu")
		(net "P5E_PEX1_STN7_TX_DN<127>")
	)
	(segment
		(start 158.270194 -313.735212)
		(end 158.435294 -313.570112)
		(width 0.1143)
		(layer "In11.Cu")
		(net "P5E_PEX1_STN7_TX_DN<127>")
	)
	(segment
		(start 171.644056 -327.784206)
		(end 158.69285 -321.08902)
		(width 0.1651)
		(layer "In11.Cu")
		(net "P5E_PEX1_STN7_TX_DN<127>")
	)
	(segment
		(start 158.270194 -319.97523)
		(end 158.270194 -313.735212)
		(width 0.1143)
		(layer "In11.Cu")
		(net "P5E_PEX1_STN7_TX_DN<127>")
	)
	(segment
		(start 158.315914 -320.695574)
		(end 158.315914 -320.043048)
		(width 0.1651)
		(layer "In11.Cu")
		(net "P5E_PEX1_STN7_TX_DN<127>")
	)
	(segment
		(start 194.139312 -342.439498)
		(end 193.848482 -342.148668)
		(width 0.1651)
		(layer "In11.Cu")
		(net "P5E_PEX1_STN7_TX_DN<127>")
	)
	(segment
		(start 158.315914 -320.043048)
		(end 158.315914 -320.02095)
		(width 0.1143)
		(layer "In11.Cu")
		(net "P5E_PEX1_STN7_TX_DN<127>")
	)
	(segment
		(start 193.848482 -341.35568)
		(end 193.32321 -340.655656)
		(width 0.1651)
		(layer "In11.Cu")
		(net "P5E_PEX1_STN7_TX_DN<127>")
	)
	(segment
		(start 158.561024 -313.570112)
		(end 158.649924 -313.659012)
		(width 0.1143)
		(layer "In11.Cu")
		(net "P5E_PEX1_STN7_TX_DN<127>")
	)
	(segment
		(start 193.32321 -340.655656)
		(end 192.09766 -339.570568)
		(width 0.1651)
		(layer "In11.Cu")
		(net "P5E_PEX1_STN7_TX_DN<127>")
	)
	(segment
		(start 158.69285 -321.08902)
		(end 158.315914 -320.695574)
		(width 0.1651)
		(layer "In11.Cu")
		(net "P5E_PEX1_STN7_TX_DN<127>")
	)
	(segment
		(start 158.435294 -313.570112)
		(end 158.561024 -313.570112)
		(width 0.1143)
		(layer "In11.Cu")
		(net "P5E_PEX1_STN7_TX_DN<127>")
	)
	(segment
		(start 193.848482 -342.148668)
		(end 193.848482 -341.35568)
		(width 0.1651)
		(layer "In11.Cu")
		(net "P5E_PEX1_STN7_TX_DN<127>")
	)
	(segment
		(start 181.86146 -333.671926)
		(end 181.861206 -333.671926)
		(width 0.1651)
		(layer "In11.Cu")
		(net "P5E_PEX1_STN7_TX_DN<127>")
	)
	(segment
		(start 192.09766 -339.570568)
		(end 181.86146 -333.671926)
		(width 0.1651)
		(layer "In11.Cu")
		(net "P5E_PEX1_STN7_TX_DN<127>")
	)
	(segment
		(start 181.861206 -333.671926)
		(end 171.644056 -327.784206)
		(width 0.1651)
		(layer "In11.Cu")
		(net "P5E_PEX1_STN7_TX_DN<127>")
	)
	(segment
		(start 158.315914 -320.02095)
		(end 158.270194 -319.97523)
		(width 0.1143)
		(layer "In11.Cu")
		(net "P5E_PEX1_STN7_TX_DN<127>")
	)
	(segment
		(start 269.96771 -102.914196)
		(end 270.258794 -103.20528)
		(width 0.13462)
		(layer "F.Cu")
		(net "P5E_PEX2_STN1_TX_DP<18>")
	)
	(segment
		(start 270.89735 -103.20528)
		(end 271.213834 -102.888796)
		(width 0.13462)
		(layer "F.Cu")
		(net "P5E_PEX2_STN1_TX_DP<18>")
	)
	(segment
		(start 270.258794 -103.20528)
		(end 270.89735 -103.20528)
		(width 0.13462)
		(layer "F.Cu")
		(net "P5E_PEX2_STN1_TX_DP<18>")
	)
	(segment
		(start 266.722098 -103.672386)
		(end 266.722352 -103.672386)
		(width 0.1651)
		(layer "In9.Cu")
		(net "P5E_PEX2_STN1_TX_DP<18>")
	)
	(segment
		(start 258.215384 -162.39617)
		(end 293.13378 -265.558016)
		(width 0.1651)
		(layer "In9.Cu")
		(net "P5E_PEX2_STN1_TX_DP<18>")
	)
	(segment
		(start 293.394384 -278.420068)
		(end 293.635176 -278.420068)
		(width 0.1143)
		(layer "In9.Cu")
		(net "P5E_PEX2_STN1_TX_DP<18>")
	)
	(segment
		(start 269.96771 -102.914196)
		(end 269.67688 -103.205026)
		(width 0.1651)
		(layer "In9.Cu")
		(net "P5E_PEX2_STN1_TX_DP<18>")
	)
	(segment
		(start 256.916428 -144.912588)
		(end 257.452622 -155.81503)
		(width 0.1651)
		(layer "In9.Cu")
		(net "P5E_PEX2_STN1_TX_DP<18>")
	)
	(segment
		(start 293.13378 -265.558016)
		(end 293.13378 -271.471898)
		(width 0.1651)
		(layer "In9.Cu")
		(net "P5E_PEX2_STN1_TX_DP<18>")
	)
	(segment
		(start 293.13378 -271.471898)
		(end 293.13378 -271.500346)
		(width 0.1143)
		(layer "In9.Cu")
		(net "P5E_PEX2_STN1_TX_DP<18>")
	)
	(segment
		(start 293.1795 -278.205184)
		(end 293.394384 -278.420068)
		(width 0.1143)
		(layer "In9.Cu")
		(net "P5E_PEX2_STN1_TX_DP<18>")
	)
	(segment
		(start 267.85062 -103.205026)
		(end 266.722098 -103.672386)
		(width 0.1651)
		(layer "In9.Cu")
		(net "P5E_PEX2_STN1_TX_DP<18>")
	)
	(segment
		(start 254.340614 -130.948938)
		(end 254.340614 -138.693652)
		(width 0.1651)
		(layer "In9.Cu")
		(net "P5E_PEX2_STN1_TX_DP<18>")
	)
	(segment
		(start 254.340614 -138.693652)
		(end 256.916428 -144.912588)
		(width 0.1651)
		(layer "In9.Cu")
		(net "P5E_PEX2_STN1_TX_DP<18>")
	)
	(segment
		(start 293.13378 -271.500346)
		(end 293.1795 -271.546066)
		(width 0.1143)
		(layer "In9.Cu")
		(net "P5E_PEX2_STN1_TX_DP<18>")
	)
	(segment
		(start 257.631946 -159.462978)
		(end 258.215384 -162.39617)
		(width 0.1651)
		(layer "In9.Cu")
		(net "P5E_PEX2_STN1_TX_DP<18>")
	)
	(segment
		(start 262.154924 -107.680252)
		(end 259.331206 -114.497612)
		(width 0.1651)
		(layer "In9.Cu")
		(net "P5E_PEX2_STN1_TX_DP<18>")
	)
	(segment
		(start 259.331206 -114.497612)
		(end 254.340614 -130.948938)
		(width 0.1651)
		(layer "In9.Cu")
		(net "P5E_PEX2_STN1_TX_DP<18>")
	)
	(segment
		(start 269.67688 -103.205026)
		(end 267.85062 -103.205026)
		(width 0.1651)
		(layer "In9.Cu")
		(net "P5E_PEX2_STN1_TX_DP<18>")
	)
	(segment
		(start 257.452622 -155.81503)
		(end 257.631946 -159.462978)
		(width 0.1651)
		(layer "In9.Cu")
		(net "P5E_PEX2_STN1_TX_DP<18>")
	)
	(segment
		(start 265.767058 -104.068118)
		(end 262.154924 -107.680252)
		(width 0.1651)
		(layer "In9.Cu")
		(net "P5E_PEX2_STN1_TX_DP<18>")
	)
	(segment
		(start 293.1795 -271.546066)
		(end 293.1795 -278.205184)
		(width 0.1143)
		(layer "In9.Cu")
		(net "P5E_PEX2_STN1_TX_DP<18>")
	)
	(segment
		(start 293.749476 -278.534368)
		(end 293.749476 -278.799798)
		(width 0.1143)
		(layer "In9.Cu")
		(net "P5E_PEX2_STN1_TX_DP<18>")
	)
	(segment
		(start 266.722352 -103.672386)
		(end 265.767058 -104.068118)
		(width 0.1651)
		(layer "In9.Cu")
		(net "P5E_PEX2_STN1_TX_DP<18>")
	)
	(segment
		(start 293.635176 -278.420068)
		(end 293.749476 -278.534368)
		(width 0.1143)
		(layer "In9.Cu")
		(net "P5E_PEX2_STN1_TX_DP<18>")
	)
	(segment
		(start 289.634422 -355.978206)
		(end 289.954462 -355.658166)
		(width 0.13462)
		(layer "F.Cu")
		(net "P5E_PEX2_STN7_TX_DP<123>")
	)
	(segment
		(start 289.954462 -355.026722)
		(end 289.659822 -354.732082)
		(width 0.13462)
		(layer "F.Cu")
		(net "P5E_PEX2_STN7_TX_DP<123>")
	)
	(segment
		(start 289.954462 -355.658166)
		(end 289.954462 -355.026722)
		(width 0.13462)
		(layer "F.Cu")
		(net "P5E_PEX2_STN7_TX_DP<123>")
	)
	(segment
		(start 270.605504 -313.379612)
		(end 270.835628 -313.379612)
		(width 0.1143)
		(layer "In7.Cu")
		(net "P5E_PEX2_STN7_TX_DP<123>")
	)
	(segment
		(start 270.333978 -321.49796)
		(end 270.333978 -319.916048)
		(width 0.1651)
		(layer "In7.Cu")
		(net "P5E_PEX2_STN7_TX_DP<123>")
	)
	(segment
		(start 270.333978 -319.8876)
		(end 270.379698 -319.84188)
		(width 0.1143)
		(layer "In7.Cu")
		(net "P5E_PEX2_STN7_TX_DP<123>")
	)
	(segment
		(start 270.379698 -319.84188)
		(end 270.379698 -313.605418)
		(width 0.1143)
		(layer "In7.Cu")
		(net "P5E_PEX2_STN7_TX_DP<123>")
	)
	(segment
		(start 270.835628 -313.379612)
		(end 270.949928 -313.265312)
		(width 0.1143)
		(layer "In7.Cu")
		(net "P5E_PEX2_STN7_TX_DP<123>")
	)
	(segment
		(start 290.792662 -340.794848)
		(end 271.523714 -323.865494)
		(width 0.1651)
		(layer "In7.Cu")
		(net "P5E_PEX2_STN7_TX_DP<123>")
	)
	(segment
		(start 291.505132 -352.259646)
		(end 291.505132 -342.327484)
		(width 0.1651)
		(layer "In7.Cu")
		(net "P5E_PEX2_STN7_TX_DP<123>")
	)
	(segment
		(start 270.333978 -319.916048)
		(end 270.333978 -319.8876)
		(width 0.1143)
		(layer "In7.Cu")
		(net "P5E_PEX2_STN7_TX_DP<123>")
	)
	(segment
		(start 271.523714 -323.865494)
		(end 271.16659 -323.50837)
		(width 0.1651)
		(layer "In7.Cu")
		(net "P5E_PEX2_STN7_TX_DP<123>")
	)
	(segment
		(start 289.950652 -353.814126)
		(end 291.505132 -352.259646)
		(width 0.1651)
		(layer "In7.Cu")
		(net "P5E_PEX2_STN7_TX_DP<123>")
	)
	(segment
		(start 289.659822 -354.732082)
		(end 289.950652 -354.441252)
		(width 0.1651)
		(layer "In7.Cu")
		(net "P5E_PEX2_STN7_TX_DP<123>")
	)
	(segment
		(start 270.949928 -313.265312)
		(end 270.949928 -312.999882)
		(width 0.1143)
		(layer "In7.Cu")
		(net "P5E_PEX2_STN7_TX_DP<123>")
	)
	(segment
		(start 289.950652 -354.441252)
		(end 289.950652 -353.814126)
		(width 0.1651)
		(layer "In7.Cu")
		(net "P5E_PEX2_STN7_TX_DP<123>")
	)
	(segment
		(start 291.505132 -342.327484)
		(end 290.792662 -340.794848)
		(width 0.1651)
		(layer "In7.Cu")
		(net "P5E_PEX2_STN7_TX_DP<123>")
	)
	(segment
		(start 271.16659 -323.50837)
		(end 270.333978 -321.49796)
		(width 0.1651)
		(layer "In7.Cu")
		(net "P5E_PEX2_STN7_TX_DP<123>")
	)
	(segment
		(start 270.379698 -313.605418)
		(end 270.605504 -313.379612)
		(width 0.1143)
		(layer "In7.Cu")
		(net "P5E_PEX2_STN7_TX_DP<123>")
	)
	(segment
		(start 406.895046 -96.702372)
		(end 406.895046 -97.718372)
		(width 0.13208)
		(layer "F.Cu")
		(net "RST_HP_NIC7_BUF_N")
	)
	(segment
		(start 407.49982 -94.1578)
		(end 410.95295 -94.1578)
		(width 0.13208)
		(layer "F.Cu")
		(net "RST_HP_NIC7_BUF_N")
	)
	(segment
		(start 413.105854 -94.1578)
		(end 414.643316 -92.620338)
		(width 0.13208)
		(layer "F.Cu")
		(net "RST_HP_NIC7_BUF_N")
	)
	(segment
		(start 428.923704 -86.949026)
		(end 429.939704 -86.949026)
		(width 0.13208)
		(layer "F.Cu")
		(net "RST_HP_NIC7_BUF_N")
	)
	(segment
		(start 427.534578 -86.949026)
		(end 428.923704 -86.949026)
		(width 0.13208)
		(layer "F.Cu")
		(net "RST_HP_NIC7_BUF_N")
	)
	(segment
		(start 430.698656 -87.306658)
		(end 430.341024 -86.949026)
		(width 0.13208)
		(layer "F.Cu")
		(net "RST_HP_NIC7_BUF_N")
	)
	(segment
		(start 406.895046 -96.702372)
		(end 406.895046 -94.762574)
		(width 0.13208)
		(layer "F.Cu")
		(net "RST_HP_NIC7_BUF_N")
	)
	(segment
		(start 406.895046 -94.762574)
		(end 407.49982 -94.1578)
		(width 0.13208)
		(layer "F.Cu")
		(net "RST_HP_NIC7_BUF_N")
	)
	(segment
		(start 429.403764 -92.620338)
		(end 430.698656 -91.325446)
		(width 0.13208)
		(layer "F.Cu")
		(net "RST_HP_NIC7_BUF_N")
	)
	(segment
		(start 410.95295 -94.1578)
		(end 413.105854 -94.1578)
		(width 0.13208)
		(layer "F.Cu")
		(net "RST_HP_NIC7_BUF_N")
	)
	(segment
		(start 414.643316 -92.620338)
		(end 429.403764 -92.620338)
		(width 0.13208)
		(layer "F.Cu")
		(net "RST_HP_NIC7_BUF_N")
	)
	(segment
		(start 430.341024 -86.949026)
		(end 429.939704 -86.949026)
		(width 0.13208)
		(layer "F.Cu")
		(net "RST_HP_NIC7_BUF_N")
	)
	(segment
		(start 430.698656 -91.325446)
		(end 430.698656 -87.306658)
		(width 0.13208)
		(layer "F.Cu")
		(net "RST_HP_NIC7_BUF_N")
	)
	(via
		(at 410.95295 -94.1578)
		(size 0.762)
		(drill 0.381)
		(layers "F.Cu" "B.Cu")
		(net "RST_HP_NIC7_BUF_N")
	)
	(segment
		(start 184.812432 -351.611438)
		(end 184.517792 -351.316798)
		(width 0.13462)
		(layer "F.Cu")
		(net "P5E_PEX1_STN7_TX_C_DN<123>")
	)
	(segment
		(start 184.517792 -351.316798)
		(end 184.517792 -350.685354)
		(width 0.13462)
		(layer "F.Cu")
		(net "P5E_PEX1_STN7_TX_C_DN<123>")
	)
	(segment
		(start 184.517792 -350.685354)
		(end 184.837832 -350.365314)
		(width 0.13462)
		(layer "F.Cu")
		(net "P5E_PEX1_STN7_TX_C_DN<123>")
	)
	(segment
		(start 166.975282 -376.281188)
		(end 167.667432 -375.589038)
		(width 0.1651)
		(layer "In11.Cu")
		(net "P5E_PEX1_STN7_TX_C_DN<123>")
	)
	(segment
		(start 179.282852 -363.303058)
		(end 182.967122 -359.618788)
		(width 0.1651)
		(layer "In11.Cu")
		(net "P5E_PEX1_STN7_TX_C_DN<123>")
	)
	(segment
		(start 166.509954 -376.408188)
		(end 166.636954 -376.281188)
		(width 0.1651)
		(layer "In11.Cu")
		(net "P5E_PEX1_STN7_TX_C_DN<123>")
	)
	(segment
		(start 184.521602 -352.57994)
		(end 184.521602 -351.902268)
		(width 0.1651)
		(layer "In11.Cu")
		(net "P5E_PEX1_STN7_TX_C_DN<123>")
	)
	(segment
		(start 167.667432 -375.589038)
		(end 167.667432 -368.858292)
		(width 0.1651)
		(layer "In11.Cu")
		(net "P5E_PEX1_STN7_TX_C_DN<123>")
	)
	(segment
		(start 182.967122 -359.618788)
		(end 182.967122 -354.13442)
		(width 0.1651)
		(layer "In11.Cu")
		(net "P5E_PEX1_STN7_TX_C_DN<123>")
	)
	(segment
		(start 168.838118 -367.687606)
		(end 179.282852 -363.303058)
		(width 0.1651)
		(layer "In11.Cu")
		(net "P5E_PEX1_STN7_TX_C_DN<123>")
	)
	(segment
		(start 182.967122 -354.13442)
		(end 184.521602 -352.57994)
		(width 0.1651)
		(layer "In11.Cu")
		(net "P5E_PEX1_STN7_TX_C_DN<123>")
	)
	(segment
		(start 167.667432 -368.858292)
		(end 168.838118 -367.687606)
		(width 0.1651)
		(layer "In11.Cu")
		(net "P5E_PEX1_STN7_TX_C_DN<123>")
	)
	(segment
		(start 184.521602 -351.902268)
		(end 184.812432 -351.611438)
		(width 0.1651)
		(layer "In11.Cu")
		(net "P5E_PEX1_STN7_TX_C_DN<123>")
	)
	(segment
		(start 166.636954 -376.281188)
		(end 166.975282 -376.281188)
		(width 0.1651)
		(layer "In11.Cu")
		(net "P5E_PEX1_STN7_TX_C_DN<123>")
	)
	(segment
		(start 166.509954 -376.790204)
		(end 166.509954 -376.408188)
		(width 0.1651)
		(layer "In11.Cu")
		(net "P5E_PEX1_STN7_TX_C_DN<123>")
	)
	(segment
		(start 174.916592 -342.734138)
		(end 174.621952 -342.439498)
		(width 0.13462)
		(layer "F.Cu")
		(net "P5E_PEX1_STN7_TX_DP<118>")
	)
	(segment
		(start 174.916592 -343.365582)
		(end 174.916592 -342.734138)
		(width 0.13462)
		(layer "F.Cu")
		(net "P5E_PEX1_STN7_TX_DP<118>")
	)
	(segment
		(start 174.596552 -343.685622)
		(end 174.916592 -343.365582)
		(width 0.13462)
		(layer "F.Cu")
		(net "P5E_PEX1_STN7_TX_DP<118>")
	)
	(segment
		(start 138.375898 -322.07835)
		(end 138.375898 -320.128138)
		(width 0.1651)
		(layer "In11.Cu")
		(net "P5E_PEX1_STN7_TX_DP<118>")
	)
	(segment
		(start 140.774166 -326.413622)
		(end 140.208762 -325.928736)
		(width 0.1651)
		(layer "In11.Cu")
		(net "P5E_PEX1_STN7_TX_DP<118>")
	)
	(segment
		(start 143.705834 -312.130186)
		(end 145.584418 -310.874918)
		(width 0.1651)
		(layer "In11.Cu")
		(net "P5E_PEX1_STN7_TX_DP<118>")
	)
	(segment
		(start 174.375826 -340.887304)
		(end 167.68953 -337.724242)
		(width 0.1651)
		(layer "In11.Cu")
		(net "P5E_PEX1_STN7_TX_DP<118>")
	)
	(segment
		(start 158.270194 -307.210968)
		(end 158.359094 -307.299868)
		(width 0.1143)
		(layer "In11.Cu")
		(net "P5E_PEX1_STN7_TX_DP<118>")
	)
	(segment
		(start 148.296122 -330.532486)
		(end 143.747236 -328.45629)
		(width 0.1651)
		(layer "In11.Cu")
		(net "P5E_PEX1_STN7_TX_DP<118>")
	)
	(segment
		(start 148.30552 -330.536804)
		(end 148.295868 -330.532486)
		(width 0.1651)
		(layer "In11.Cu")
		(net "P5E_PEX1_STN7_TX_DP<118>")
	)
	(segment
		(start 148.295868 -330.532486)
		(end 148.296122 -330.532486)
		(width 0.1651)
		(layer "In11.Cu")
		(net "P5E_PEX1_STN7_TX_DP<118>")
	)
	(segment
		(start 138.990832 -324.107302)
		(end 138.375898 -322.07835)
		(width 0.1651)
		(layer "In11.Cu")
		(net "P5E_PEX1_STN7_TX_DP<118>")
	)
	(segment
		(start 138.375898 -320.128138)
		(end 138.637264 -318.80937)
		(width 0.1651)
		(layer "In11.Cu")
		(net "P5E_PEX1_STN7_TX_DP<118>")
	)
	(segment
		(start 158.270194 -307.006244)
		(end 158.270194 -307.210968)
		(width 0.1143)
		(layer "In11.Cu")
		(net "P5E_PEX1_STN7_TX_DP<118>")
	)
	(segment
		(start 139.777724 -316.058296)
		(end 143.705834 -312.130186)
		(width 0.1651)
		(layer "In11.Cu")
		(net "P5E_PEX1_STN7_TX_DP<118>")
	)
	(segment
		(start 174.621952 -342.439498)
		(end 174.912782 -342.148668)
		(width 0.1651)
		(layer "In11.Cu")
		(net "P5E_PEX1_STN7_TX_DP<118>")
	)
	(segment
		(start 141.32433 -326.8853)
		(end 140.774166 -326.413622)
		(width 0.1651)
		(layer "In11.Cu")
		(net "P5E_PEX1_STN7_TX_DP<118>")
	)
	(segment
		(start 149.775418 -306.683918)
		(end 151.620728 -306.683918)
		(width 0.1651)
		(layer "In11.Cu")
		(net "P5E_PEX1_STN7_TX_DP<118>")
	)
	(segment
		(start 158.359094 -307.299868)
		(end 158.649924 -307.299868)
		(width 0.1143)
		(layer "In11.Cu")
		(net "P5E_PEX1_STN7_TX_DP<118>")
	)
	(segment
		(start 151.688546 -306.729638)
		(end 157.993588 -306.729638)
		(width 0.1143)
		(layer "In11.Cu")
		(net "P5E_PEX1_STN7_TX_DP<118>")
	)
	(segment
		(start 151.620728 -306.683918)
		(end 151.642826 -306.683918)
		(width 0.1143)
		(layer "In11.Cu")
		(net "P5E_PEX1_STN7_TX_DP<118>")
	)
	(segment
		(start 143.747236 -328.45629)
		(end 141.32433 -326.8853)
		(width 0.1651)
		(layer "In11.Cu")
		(net "P5E_PEX1_STN7_TX_DP<118>")
	)
	(segment
		(start 140.208762 -325.928736)
		(end 138.990832 -324.107302)
		(width 0.1651)
		(layer "In11.Cu")
		(net "P5E_PEX1_STN7_TX_DP<118>")
	)
	(segment
		(start 151.642826 -306.683918)
		(end 151.688546 -306.729638)
		(width 0.1143)
		(layer "In11.Cu")
		(net "P5E_PEX1_STN7_TX_DP<118>")
	)
	(segment
		(start 157.993588 -306.729638)
		(end 158.270194 -307.006244)
		(width 0.1143)
		(layer "In11.Cu")
		(net "P5E_PEX1_STN7_TX_DP<118>")
	)
	(segment
		(start 174.912782 -342.148668)
		(end 174.912782 -341.602822)
		(width 0.1651)
		(layer "In11.Cu")
		(net "P5E_PEX1_STN7_TX_DP<118>")
	)
	(segment
		(start 138.637264 -318.80937)
		(end 139.777724 -316.058296)
		(width 0.1651)
		(layer "In11.Cu")
		(net "P5E_PEX1_STN7_TX_DP<118>")
	)
	(segment
		(start 167.68953 -337.724242)
		(end 148.30552 -330.536804)
		(width 0.1651)
		(layer "In11.Cu")
		(net "P5E_PEX1_STN7_TX_DP<118>")
	)
	(segment
		(start 145.584418 -310.874918)
		(end 149.775418 -306.683918)
		(width 0.1651)
		(layer "In11.Cu")
		(net "P5E_PEX1_STN7_TX_DP<118>")
	)
	(segment
		(start 174.912782 -341.602822)
		(end 174.375826 -340.887304)
		(width 0.1651)
		(layer "In11.Cu")
		(net "P5E_PEX1_STN7_TX_DP<118>")
	)
	(segment
		(start 316.374272 -135.31215)
		(end 316.075822 -135.6106)
		(width 0.13462)
		(layer "F.Cu")
		(net "P5E_PEX2_STN0_TX_DN<7>")
	)
	(segment
		(start 315.451998 -135.6106)
		(end 315.128148 -135.28675)
		(width 0.13462)
		(layer "F.Cu")
		(net "P5E_PEX2_STN0_TX_DN<7>")
	)
	(segment
		(start 316.075822 -135.6106)
		(end 315.451998 -135.6106)
		(width 0.13462)
		(layer "F.Cu")
		(net "P5E_PEX2_STN0_TX_DN<7>")
	)
	(segment
		(start 314.229242 -246.62638)
		(end 316.417198 -271.674336)
		(width 0.1651)
		(layer "In9.Cu")
		(net "P5E_PEX2_STN0_TX_DN<7>")
	)
	(segment
		(start 315.195204 -279.153874)
		(end 314.980828 -279.36825)
		(width 0.1143)
		(layer "In9.Cu")
		(net "P5E_PEX2_STN0_TX_DN<7>")
	)
	(segment
		(start 325.597266 -154.11577)
		(end 325.597266 -158.760414)
		(width 0.1651)
		(layer "In9.Cu")
		(net "P5E_PEX2_STN0_TX_DN<7>")
	)
	(segment
		(start 315.85154 -178.021488)
		(end 312.041032 -221.581218)
		(width 0.1651)
		(layer "In9.Cu")
		(net "P5E_PEX2_STN0_TX_DN<7>")
	)
	(segment
		(start 312.041032 -221.581218)
		(end 314.228988 -246.62638)
		(width 0.1651)
		(layer "In9.Cu")
		(net "P5E_PEX2_STN0_TX_DN<7>")
	)
	(segment
		(start 315.270388 -279.143714)
		(end 315.260228 -279.153874)
		(width 0.1143)
		(layer "In9.Cu")
		(net "P5E_PEX2_STN0_TX_DN<7>")
	)
	(segment
		(start 316.292992 -277.344632)
		(end 315.537088 -278.87676)
		(width 0.1651)
		(layer "In9.Cu")
		(net "P5E_PEX2_STN0_TX_DN<7>")
	)
	(segment
		(start 315.537088 -278.87676)
		(end 315.270388 -279.143714)
		(width 0.1651)
		(layer "In9.Cu")
		(net "P5E_PEX2_STN0_TX_DN<7>")
	)
	(segment
		(start 314.38088 -279.36825)
		(end 314.270136 -279.479248)
		(width 0.1143)
		(layer "In9.Cu")
		(net "P5E_PEX2_STN0_TX_DN<7>")
	)
	(segment
		(start 317.361062 -135.60298)
		(end 317.661036 -135.902954)
		(width 0.1651)
		(layer "In9.Cu")
		(net "P5E_PEX2_STN0_TX_DN<7>")
	)
	(segment
		(start 314.980828 -279.36825)
		(end 314.38088 -279.36825)
		(width 0.1143)
		(layer "In9.Cu")
		(net "P5E_PEX2_STN0_TX_DN<7>")
	)
	(segment
		(start 316.665102 -135.60298)
		(end 317.361062 -135.60298)
		(width 0.1651)
		(layer "In9.Cu")
		(net "P5E_PEX2_STN0_TX_DN<7>")
	)
	(segment
		(start 317.661036 -135.902954)
		(end 321.560698 -145.317464)
		(width 0.1651)
		(layer "In9.Cu")
		(net "P5E_PEX2_STN0_TX_DN<7>")
	)
	(segment
		(start 314.384436 -279.749758)
		(end 314.649866 -279.749758)
		(width 0.1143)
		(layer "In9.Cu")
		(net "P5E_PEX2_STN0_TX_DN<7>")
	)
	(segment
		(start 321.560698 -145.317464)
		(end 322.230242 -145.987008)
		(width 0.1651)
		(layer "In9.Cu")
		(net "P5E_PEX2_STN0_TX_DN<7>")
	)
	(segment
		(start 316.417198 -271.674336)
		(end 316.292992 -277.344632)
		(width 0.1651)
		(layer "In9.Cu")
		(net "P5E_PEX2_STN0_TX_DN<7>")
	)
	(segment
		(start 314.270136 -279.479248)
		(end 314.270136 -279.635458)
		(width 0.1143)
		(layer "In9.Cu")
		(net "P5E_PEX2_STN0_TX_DN<7>")
	)
	(segment
		(start 315.260228 -279.153874)
		(end 315.195204 -279.153874)
		(width 0.1143)
		(layer "In9.Cu")
		(net "P5E_PEX2_STN0_TX_DN<7>")
	)
	(segment
		(start 316.374272 -135.31215)
		(end 316.665102 -135.60298)
		(width 0.1651)
		(layer "In9.Cu")
		(net "P5E_PEX2_STN0_TX_DN<7>")
	)
	(segment
		(start 322.230242 -145.987008)
		(end 325.597266 -154.11577)
		(width 0.1651)
		(layer "In9.Cu")
		(net "P5E_PEX2_STN0_TX_DN<7>")
	)
	(segment
		(start 314.228988 -246.62638)
		(end 314.229242 -246.62638)
		(width 0.1651)
		(layer "In9.Cu")
		(net "P5E_PEX2_STN0_TX_DN<7>")
	)
	(segment
		(start 314.270136 -279.635458)
		(end 314.384436 -279.749758)
		(width 0.1143)
		(layer "In9.Cu")
		(net "P5E_PEX2_STN0_TX_DN<7>")
	)
	(segment
		(start 325.597266 -158.760414)
		(end 317.04153 -173.584108)
		(width 0.1651)
		(layer "In9.Cu")
		(net "P5E_PEX2_STN0_TX_DN<7>")
	)
	(segment
		(start 317.04153 -173.584108)
		(end 315.85154 -178.021488)
		(width 0.1651)
		(layer "In9.Cu")
		(net "P5E_PEX2_STN0_TX_DN<7>")
	)
	(segment
		(start 289.954462 -343.365582)
		(end 289.954462 -342.734138)
		(width 0.13462)
		(layer "F.Cu")
		(net "P5E_PEX2_STN7_TX_DN<122>")
	)
	(segment
		(start 289.954462 -342.734138)
		(end 289.659822 -342.439498)
		(width 0.13462)
		(layer "F.Cu")
		(net "P5E_PEX2_STN7_TX_DN<122>")
	)
	(segment
		(start 289.634422 -343.685622)
		(end 289.954462 -343.365582)
		(width 0.13462)
		(layer "F.Cu")
		(net "P5E_PEX2_STN7_TX_DN<122>")
	)
	(segment
		(start 267.228828 -317.567564)
		(end 267.228828 -316.485016)
		(width 0.1651)
		(layer "In7.Cu")
		(net "P5E_PEX2_STN7_TX_DN<122>")
	)
	(segment
		(start 268.665706 -321.737736)
		(end 267.497052 -318.916558)
		(width 0.1651)
		(layer "In7.Cu")
		(net "P5E_PEX2_STN7_TX_DN<122>")
	)
	(segment
		(start 289.950652 -342.148668)
		(end 289.950652 -341.705692)
		(width 0.1651)
		(layer "In7.Cu")
		(net "P5E_PEX2_STN7_TX_DN<122>")
	)
	(segment
		(start 269.315184 -315.279532)
		(end 269.429484 -315.165232)
		(width 0.1143)
		(layer "In7.Cu")
		(net "P5E_PEX2_STN7_TX_DN<122>")
	)
	(segment
		(start 267.228828 -316.485016)
		(end 267.926058 -315.787786)
		(width 0.1651)
		(layer "In7.Cu")
		(net "P5E_PEX2_STN7_TX_DN<122>")
	)
	(segment
		(start 267.946124 -315.76772)
		(end 268.010132 -315.767974)
		(width 0.1143)
		(layer "In7.Cu")
		(net "P5E_PEX2_STN7_TX_DN<122>")
	)
	(segment
		(start 269.429484 -315.165232)
		(end 269.429484 -315.014102)
		(width 0.1143)
		(layer "In7.Cu")
		(net "P5E_PEX2_STN7_TX_DN<122>")
	)
	(segment
		(start 269.315184 -314.899802)
		(end 269.049754 -314.899802)
		(width 0.1143)
		(layer "In7.Cu")
		(net "P5E_PEX2_STN7_TX_DN<122>")
	)
	(segment
		(start 269.429484 -315.014102)
		(end 269.315184 -314.899802)
		(width 0.1143)
		(layer "In7.Cu")
		(net "P5E_PEX2_STN7_TX_DN<122>")
	)
	(segment
		(start 270.408146 -324.17766)
		(end 268.665706 -321.737736)
		(width 0.1651)
		(layer "In7.Cu")
		(net "P5E_PEX2_STN7_TX_DN<122>")
	)
	(segment
		(start 267.926058 -315.787786)
		(end 267.946124 -315.76772)
		(width 0.1143)
		(layer "In7.Cu")
		(net "P5E_PEX2_STN7_TX_DN<122>")
	)
	(segment
		(start 289.950652 -341.705692)
		(end 289.658044 -341.174324)
		(width 0.1651)
		(layer "In7.Cu")
		(net "P5E_PEX2_STN7_TX_DN<122>")
	)
	(segment
		(start 267.497052 -318.916558)
		(end 267.228828 -317.567564)
		(width 0.1651)
		(layer "In7.Cu")
		(net "P5E_PEX2_STN7_TX_DN<122>")
	)
	(segment
		(start 289.659822 -342.439498)
		(end 289.950652 -342.148668)
		(width 0.1651)
		(layer "In7.Cu")
		(net "P5E_PEX2_STN7_TX_DN<122>")
	)
	(segment
		(start 268.010132 -315.767974)
		(end 268.498574 -315.279532)
		(width 0.1143)
		(layer "In7.Cu")
		(net "P5E_PEX2_STN7_TX_DN<122>")
	)
	(segment
		(start 289.658044 -341.174324)
		(end 270.408146 -324.17766)
		(width 0.1651)
		(layer "In7.Cu")
		(net "P5E_PEX2_STN7_TX_DN<122>")
	)
	(segment
		(start 268.498574 -315.279532)
		(end 269.315184 -315.279532)
		(width 0.1143)
		(layer "In7.Cu")
		(net "P5E_PEX2_STN7_TX_DN<122>")
	)
	(segment
		(start 425.593764 -138.474958)
		(end 415.100008 -138.474958)
		(width 0.13208)
		(layer "F.Cu")
		(net "PRSNT_NIC7_N")
	)
	(segment
		(start 430.022 -159.235648)
		(end 429.23968 -159.235648)
		(width 0.13208)
		(layer "F.Cu")
		(net "PRSNT_NIC7_N")
	)
	(segment
		(start 411.37078 -138.864848)
		(end 410.621988 -138.864848)
		(width 0.13208)
		(layer "F.Cu")
		(net "PRSNT_NIC7_N")
	)
	(segment
		(start 411.57779 -118.331996)
		(end 411.57779 -117.566186)
		(width 0.13208)
		(layer "F.Cu")
		(net "PRSNT_NIC7_N")
	)
	(segment
		(start 429.23968 -138.661648)
		(end 429.542194 -138.359134)
		(width 0.13208)
		(layer "F.Cu")
		(net "PRSNT_NIC7_N")
	)
	(segment
		(start 414.160462 -139.414504)
		(end 411.637988 -139.414504)
		(width 0.13208)
		(layer "F.Cu")
		(net "PRSNT_NIC7_N")
	)
	(segment
		(start 411.37078 -139.147296)
		(end 411.37078 -138.864848)
		(width 0.13208)
		(layer "F.Cu")
		(net "PRSNT_NIC7_N")
	)
	(segment
		(start 429.0314 -139.185396)
		(end 426.304202 -139.185396)
		(width 0.13208)
		(layer "F.Cu")
		(net "PRSNT_NIC7_N")
	)
	(segment
		(start 434.146452 -140.24991)
		(end 434.384196 -140.487654)
		(width 0.13208)
		(layer "F.Cu")
		(net "PRSNT_NIC7_N")
	)
	(segment
		(start 415.100008 -138.474958)
		(end 414.160462 -139.414504)
		(width 0.13208)
		(layer "F.Cu")
		(net "PRSNT_NIC7_N")
	)
	(segment
		(start 434.146452 -139.554966)
		(end 434.146452 -140.24991)
		(width 0.13208)
		(layer "F.Cu")
		(net "PRSNT_NIC7_N")
	)
	(segment
		(start 429.23968 -138.977116)
		(end 429.0314 -139.185396)
		(width 0.13208)
		(layer "F.Cu")
		(net "PRSNT_NIC7_N")
	)
	(segment
		(start 434.90134 -141.004798)
		(end 435.24043 -141.004798)
		(width 0.13208)
		(layer "F.Cu")
		(net "PRSNT_NIC7_N")
	)
	(segment
		(start 429.23968 -138.661648)
		(end 429.23968 -138.977116)
		(width 0.13208)
		(layer "F.Cu")
		(net "PRSNT_NIC7_N")
	)
	(segment
		(start 426.304202 -139.185396)
		(end 425.593764 -138.474958)
		(width 0.13208)
		(layer "F.Cu")
		(net "PRSNT_NIC7_N")
	)
	(segment
		(start 434.384196 -140.487654)
		(end 434.90134 -141.004798)
		(width 0.13208)
		(layer "F.Cu")
		(net "PRSNT_NIC7_N")
	)
	(segment
		(start 429.542194 -138.359134)
		(end 432.95062 -138.359134)
		(width 0.13208)
		(layer "F.Cu")
		(net "PRSNT_NIC7_N")
	)
	(segment
		(start 411.637988 -139.414504)
		(end 411.37078 -139.147296)
		(width 0.13208)
		(layer "F.Cu")
		(net "PRSNT_NIC7_N")
	)
	(segment
		(start 432.95062 -138.359134)
		(end 434.146452 -139.554966)
		(width 0.13208)
		(layer "F.Cu")
		(net "PRSNT_NIC7_N")
	)
	(via
		(at 434.384196 -140.487654)
		(size 0.508)
		(drill 0.254)
		(layers "F.Cu" "B.Cu")
		(net "PRSNT_NIC7_N")
	)
	(via
		(at 411.57779 -118.331996)
		(size 0.508)
		(drill 0.254)
		(layers "F.Cu" "B.Cu")
		(net "PRSNT_NIC7_N")
	)
	(via
		(at 410.621988 -138.864848)
		(size 0.508)
		(drill 0.254)
		(layers "F.Cu" "B.Cu")
		(net "PRSNT_NIC7_N")
	)
	(via
		(at 430.022 -159.235648)
		(size 0.508)
		(drill 0.254)
		(layers "F.Cu" "B.Cu")
		(net "PRSNT_NIC7_N")
	)
	(segment
		(start 430.022 -159.235648)
		(end 431.542698 -159.235648)
		(width 0.15494)
		(layer "In7.Cu")
		(net "PRSNT_NIC7_N")
	)
	(segment
		(start 434.384196 -156.39415)
		(end 434.384196 -140.487654)
		(width 0.15494)
		(layer "In7.Cu")
		(net "PRSNT_NIC7_N")
	)
	(segment
		(start 431.542698 -159.235648)
		(end 434.384196 -156.39415)
		(width 0.15494)
		(layer "In7.Cu")
		(net "PRSNT_NIC7_N")
	)
	(segment
		(start 410.621988 -138.864848)
		(end 411.174184 -138.312652)
		(width 0.15494)
		(layer "In9.Cu")
		(net "PRSNT_NIC7_N")
	)
	(segment
		(start 411.174184 -118.735602)
		(end 411.57779 -118.331996)
		(width 0.15494)
		(layer "In9.Cu")
		(net "PRSNT_NIC7_N")
	)
	(segment
		(start 411.174184 -138.312652)
		(end 411.174184 -118.735602)
		(width 0.15494)
		(layer "In9.Cu")
		(net "PRSNT_NIC7_N")
	)
	(segment
		(start 143.520668 -345.170506)
		(end 143.520668 -344.539062)
		(width 0.13462)
		(layer "F.Cu")
		(net "P5E_PEX1_STN5_TX_C_DN<94>")
	)
	(segment
		(start 143.815308 -345.465146)
		(end 143.520668 -345.170506)
		(width 0.13462)
		(layer "F.Cu")
		(net "P5E_PEX1_STN5_TX_C_DN<94>")
	)
	(segment
		(start 143.520668 -344.539062)
		(end 143.840708 -344.219022)
		(width 0.13462)
		(layer "F.Cu")
		(net "P5E_PEX1_STN5_TX_C_DN<94>")
	)
	(segment
		(start 130.266694 -368.936778)
		(end 130.970528 -367.498884)
		(width 0.1651)
		(layer "In13.Cu")
		(net "P5E_PEX1_STN5_TX_C_DN<94>")
	)
	(segment
		(start 129.236978 -379.08103)
		(end 129.575306 -379.08103)
		(width 0.1651)
		(layer "In13.Cu")
		(net "P5E_PEX1_STN5_TX_C_DN<94>")
	)
	(segment
		(start 141.969998 -358.258618)
		(end 141.969998 -347.979238)
		(width 0.1651)
		(layer "In13.Cu")
		(net "P5E_PEX1_STN5_TX_C_DN<94>")
	)
	(segment
		(start 141.418056 -359.38587)
		(end 141.969998 -358.258618)
		(width 0.1651)
		(layer "In13.Cu")
		(net "P5E_PEX1_STN5_TX_C_DN<94>")
	)
	(segment
		(start 129.575306 -379.08103)
		(end 130.266694 -378.389642)
		(width 0.1651)
		(layer "In13.Cu")
		(net "P5E_PEX1_STN5_TX_C_DN<94>")
	)
	(segment
		(start 143.524478 -346.424758)
		(end 143.524478 -345.755976)
		(width 0.1651)
		(layer "In13.Cu")
		(net "P5E_PEX1_STN5_TX_C_DN<94>")
	)
	(segment
		(start 130.970528 -367.498884)
		(end 141.418056 -359.38587)
		(width 0.1651)
		(layer "In13.Cu")
		(net "P5E_PEX1_STN5_TX_C_DN<94>")
	)
	(segment
		(start 129.109978 -379.590046)
		(end 129.109978 -379.20803)
		(width 0.1651)
		(layer "In13.Cu")
		(net "P5E_PEX1_STN5_TX_C_DN<94>")
	)
	(segment
		(start 141.969998 -347.979238)
		(end 143.524478 -346.424758)
		(width 0.1651)
		(layer "In13.Cu")
		(net "P5E_PEX1_STN5_TX_C_DN<94>")
	)
	(segment
		(start 129.109978 -379.20803)
		(end 129.236978 -379.08103)
		(width 0.1651)
		(layer "In13.Cu")
		(net "P5E_PEX1_STN5_TX_C_DN<94>")
	)
	(segment
		(start 143.524478 -345.755976)
		(end 143.815308 -345.465146)
		(width 0.1651)
		(layer "In13.Cu")
		(net "P5E_PEX1_STN5_TX_C_DN<94>")
	)
	(segment
		(start 130.266694 -378.389642)
		(end 130.266694 -368.936778)
		(width 0.1651)
		(layer "In13.Cu")
		(net "P5E_PEX1_STN5_TX_C_DN<94>")
	)
	(segment
		(start 193.250312 -343.685622)
		(end 193.570352 -343.365582)
		(width 0.13462)
		(layer "F.Cu")
		(net "P5E_PEX1_STN7_TX_DP<127>")
	)
	(segment
		(start 193.570352 -343.365582)
		(end 193.570352 -342.734138)
		(width 0.13462)
		(layer "F.Cu")
		(net "P5E_PEX1_STN7_TX_DP<127>")
	)
	(segment
		(start 193.570352 -342.734138)
		(end 193.275712 -342.439498)
		(width 0.13462)
		(layer "F.Cu")
		(net "P5E_PEX1_STN7_TX_DP<127>")
	)
	(segment
		(start 158.033974 -320.808858)
		(end 158.033974 -320.043048)
		(width 0.1651)
		(layer "In11.Cu")
		(net "P5E_PEX1_STN7_TX_DP<127>")
	)
	(segment
		(start 158.033974 -320.02095)
		(end 158.079694 -319.97523)
		(width 0.1143)
		(layer "In11.Cu")
		(net "P5E_PEX1_STN7_TX_DP<127>")
	)
	(segment
		(start 193.275712 -342.439498)
		(end 193.566542 -342.148668)
		(width 0.1651)
		(layer "In11.Cu")
		(net "P5E_PEX1_STN7_TX_DP<127>")
	)
	(segment
		(start 193.566542 -341.449914)
		(end 193.114676 -340.847934)
		(width 0.1651)
		(layer "In11.Cu")
		(net "P5E_PEX1_STN7_TX_DP<127>")
	)
	(segment
		(start 193.566542 -342.148668)
		(end 193.566542 -341.449914)
		(width 0.1651)
		(layer "In11.Cu")
		(net "P5E_PEX1_STN7_TX_DP<127>")
	)
	(segment
		(start 171.508674 -328.031856)
		(end 158.521654 -321.318128)
		(width 0.1651)
		(layer "In11.Cu")
		(net "P5E_PEX1_STN7_TX_DP<127>")
	)
	(segment
		(start 191.932052 -339.800692)
		(end 171.508674 -328.031856)
		(width 0.1651)
		(layer "In11.Cu")
		(net "P5E_PEX1_STN7_TX_DP<127>")
	)
	(segment
		(start 158.3563 -313.379612)
		(end 158.561024 -313.379612)
		(width 0.1143)
		(layer "In11.Cu")
		(net "P5E_PEX1_STN7_TX_DP<127>")
	)
	(segment
		(start 158.649924 -313.290712)
		(end 158.649924 -312.999882)
		(width 0.1143)
		(layer "In11.Cu")
		(net "P5E_PEX1_STN7_TX_DP<127>")
	)
	(segment
		(start 158.521654 -321.318128)
		(end 158.033974 -320.808858)
		(width 0.1651)
		(layer "In11.Cu")
		(net "P5E_PEX1_STN7_TX_DP<127>")
	)
	(segment
		(start 158.079694 -313.656218)
		(end 158.3563 -313.379612)
		(width 0.1143)
		(layer "In11.Cu")
		(net "P5E_PEX1_STN7_TX_DP<127>")
	)
	(segment
		(start 158.079694 -319.97523)
		(end 158.079694 -313.656218)
		(width 0.1143)
		(layer "In11.Cu")
		(net "P5E_PEX1_STN7_TX_DP<127>")
	)
	(segment
		(start 193.114676 -340.847934)
		(end 191.932052 -339.800692)
		(width 0.1651)
		(layer "In11.Cu")
		(net "P5E_PEX1_STN7_TX_DP<127>")
	)
	(segment
		(start 158.033974 -320.043048)
		(end 158.033974 -320.02095)
		(width 0.1143)
		(layer "In11.Cu")
		(net "P5E_PEX1_STN7_TX_DP<127>")
	)
	(segment
		(start 158.561024 -313.379612)
		(end 158.649924 -313.290712)
		(width 0.1143)
		(layer "In11.Cu")
		(net "P5E_PEX1_STN7_TX_DP<127>")
	)
	(segment
		(start 269.96771 -121.894346)
		(end 270.272256 -121.5898)
		(width 0.13462)
		(layer "F.Cu")
		(net "P5E_PEX2_STN1_TX_DP<25>")
	)
	(segment
		(start 270.883888 -121.5898)
		(end 271.213834 -121.919746)
		(width 0.13462)
		(layer "F.Cu")
		(net "P5E_PEX2_STN1_TX_DP<25>")
	)
	(segment
		(start 270.272256 -121.5898)
		(end 270.883888 -121.5898)
		(width 0.13462)
		(layer "F.Cu")
		(net "P5E_PEX2_STN1_TX_DP<25>")
	)
	(segment
		(start 263.349486 -127.667766)
		(end 263.349486 -127.667512)
		(width 0.1651)
		(layer "In9.Cu")
		(net "P5E_PEX2_STN1_TX_DP<25>")
	)
	(segment
		(start 262.007858 -130.906774)
		(end 262.007858 -130.90652)
		(width 0.1651)
		(layer "In9.Cu")
		(net "P5E_PEX2_STN1_TX_DP<25>")
	)
	(segment
		(start 267.325602 -121.603516)
		(end 267.414502 -121.692416)
		(width 0.1651)
		(layer "In9.Cu")
		(net "P5E_PEX2_STN1_TX_DP<25>")
	)
	(segment
		(start 264.50163 -124.886212)
		(end 264.691114 -124.428758)
		(width 0.1651)
		(layer "In9.Cu")
		(net "P5E_PEX2_STN1_TX_DP<25>")
	)
	(segment
		(start 261.396734 -137.195052)
		(end 261.396734 -132.382006)
		(width 0.1651)
		(layer "In9.Cu")
		(net "P5E_PEX2_STN1_TX_DP<25>")
	)
	(segment
		(start 300.123606 -280.129488)
		(end 300.019974 -280.025856)
		(width 0.1143)
		(layer "In9.Cu")
		(net "P5E_PEX2_STN1_TX_DP<25>")
	)
	(segment
		(start 263.79678 -126.588012)
		(end 263.796526 -126.588012)
		(width 0.1651)
		(layer "In9.Cu")
		(net "P5E_PEX2_STN1_TX_DP<25>")
	)
	(segment
		(start 262.123936 -130.858514)
		(end 262.313928 -130.400552)
		(width 0.1651)
		(layer "In9.Cu")
		(net "P5E_PEX2_STN1_TX_DP<25>")
	)
	(segment
		(start 263.938258 -143.330422)
		(end 261.396734 -137.195052)
		(width 0.1651)
		(layer "In9.Cu")
		(net "P5E_PEX2_STN1_TX_DP<25>")
	)
	(segment
		(start 268.316202 -121.603516)
		(end 268.405102 -121.692416)
		(width 0.1651)
		(layer "In9.Cu")
		(net "P5E_PEX2_STN1_TX_DP<25>")
	)
	(segment
		(start 300.019974 -271.600168)
		(end 300.065694 -271.554448)
		(width 0.1143)
		(layer "In9.Cu")
		(net "P5E_PEX2_STN1_TX_DP<25>")
	)
	(segment
		(start 266.654026 -121.603516)
		(end 267.325602 -121.603516)
		(width 0.1651)
		(layer "In9.Cu")
		(net "P5E_PEX2_STN1_TX_DP<25>")
	)
	(segment
		(start 266.165584 -122.091958)
		(end 266.654026 -121.603516)
		(width 0.1651)
		(layer "In9.Cu")
		(net "P5E_PEX2_STN1_TX_DP<25>")
	)
	(segment
		(start 268.405102 -121.692416)
		(end 268.811502 -121.692416)
		(width 0.1651)
		(layer "In9.Cu")
		(net "P5E_PEX2_STN1_TX_DP<25>")
	)
	(segment
		(start 264.66927 -158.205678)
		(end 263.938258 -143.330422)
		(width 0.1651)
		(layer "In9.Cu")
		(net "P5E_PEX2_STN1_TX_DP<25>")
	)
	(segment
		(start 300.285404 -280.129488)
		(end 300.123606 -280.129488)
		(width 0.1143)
		(layer "In9.Cu")
		(net "P5E_PEX2_STN1_TX_DP<25>")
	)
	(segment
		(start 267.414502 -121.692416)
		(end 267.820902 -121.692416)
		(width 0.1651)
		(layer "In9.Cu")
		(net "P5E_PEX2_STN1_TX_DP<25>")
	)
	(segment
		(start 264.102596 -126.082044)
		(end 264.054336 -125.965966)
		(width 0.1651)
		(layer "In9.Cu")
		(net "P5E_PEX2_STN1_TX_DP<25>")
	)
	(segment
		(start 262.902192 -128.747266)
		(end 263.01827 -128.69926)
		(width 0.1651)
		(layer "In9.Cu")
		(net "P5E_PEX2_STN1_TX_DP<25>")
	)
	(segment
		(start 268.900402 -121.603516)
		(end 269.67688 -121.603516)
		(width 0.1651)
		(layer "In9.Cu")
		(net "P5E_PEX2_STN1_TX_DP<25>")
	)
	(segment
		(start 262.712708 -129.204974)
		(end 262.902192 -128.74752)
		(width 0.1651)
		(layer "In9.Cu")
		(net "P5E_PEX2_STN1_TX_DP<25>")
	)
	(segment
		(start 262.007858 -130.90652)
		(end 262.123936 -130.858514)
		(width 0.1651)
		(layer "In9.Cu")
		(net "P5E_PEX2_STN1_TX_DP<25>")
	)
	(segment
		(start 265.300714 -122.956828)
		(end 265.6713 -122.586242)
		(width 0.1651)
		(layer "In9.Cu")
		(net "P5E_PEX2_STN1_TX_DP<25>")
	)
	(segment
		(start 262.455152 -129.82702)
		(end 262.454898 -129.82702)
		(width 0.1651)
		(layer "In9.Cu")
		(net "P5E_PEX2_STN1_TX_DP<25>")
	)
	(segment
		(start 300.065694 -271.526)
		(end 300.065694 -264.021824)
		(width 0.1651)
		(layer "In9.Cu")
		(net "P5E_PEX2_STN1_TX_DP<25>")
	)
	(segment
		(start 265.6713 -122.586242)
		(end 265.815064 -122.586242)
		(width 0.1651)
		(layer "In9.Cu")
		(net "P5E_PEX2_STN1_TX_DP<25>")
	)
	(segment
		(start 300.019974 -280.025856)
		(end 300.019974 -271.600168)
		(width 0.1143)
		(layer "In9.Cu")
		(net "P5E_PEX2_STN1_TX_DP<25>")
	)
	(segment
		(start 262.313928 -130.400552)
		(end 262.265668 -130.284474)
		(width 0.1651)
		(layer "In9.Cu")
		(net "P5E_PEX2_STN1_TX_DP<25>")
	)
	(segment
		(start 263.655556 -127.161544)
		(end 263.607296 -127.045466)
		(width 0.1651)
		(layer "In9.Cu")
		(net "P5E_PEX2_STN1_TX_DP<25>")
	)
	(segment
		(start 263.912604 -126.540006)
		(end 264.102596 -126.082044)
		(width 0.1651)
		(layer "In9.Cu")
		(net "P5E_PEX2_STN1_TX_DP<25>")
	)
	(segment
		(start 263.796526 -126.588012)
		(end 263.912604 -126.540006)
		(width 0.1651)
		(layer "In9.Cu")
		(net "P5E_PEX2_STN1_TX_DP<25>")
	)
	(segment
		(start 262.265668 -130.284474)
		(end 262.455152 -129.82702)
		(width 0.1651)
		(layer "In9.Cu")
		(net "P5E_PEX2_STN1_TX_DP<25>")
	)
	(segment
		(start 300.065694 -271.554448)
		(end 300.065694 -271.526)
		(width 0.1143)
		(layer "In9.Cu")
		(net "P5E_PEX2_STN1_TX_DP<25>")
	)
	(segment
		(start 263.208262 -128.241298)
		(end 263.160002 -128.12522)
		(width 0.1651)
		(layer "In9.Cu")
		(net "P5E_PEX2_STN1_TX_DP<25>")
	)
	(segment
		(start 265.815064 -122.586242)
		(end 266.165584 -122.235722)
		(width 0.1651)
		(layer "In9.Cu")
		(net "P5E_PEX2_STN1_TX_DP<25>")
	)
	(segment
		(start 263.607296 -127.045466)
		(end 263.79678 -126.588012)
		(width 0.1651)
		(layer "In9.Cu")
		(net "P5E_PEX2_STN1_TX_DP<25>")
	)
	(segment
		(start 300.399704 -279.749504)
		(end 300.399704 -280.015188)
		(width 0.1143)
		(layer "In9.Cu")
		(net "P5E_PEX2_STN1_TX_DP<25>")
	)
	(segment
		(start 266.165584 -122.235722)
		(end 266.165584 -122.091958)
		(width 0.1651)
		(layer "In9.Cu")
		(net "P5E_PEX2_STN1_TX_DP<25>")
	)
	(segment
		(start 264.691114 -124.428758)
		(end 264.691114 -124.428504)
		(width 0.1651)
		(layer "In9.Cu")
		(net "P5E_PEX2_STN1_TX_DP<25>")
	)
	(segment
		(start 269.67688 -121.603516)
		(end 269.96771 -121.894346)
		(width 0.1651)
		(layer "In9.Cu")
		(net "P5E_PEX2_STN1_TX_DP<25>")
	)
	(segment
		(start 264.054336 -125.965966)
		(end 264.24382 -125.508512)
		(width 0.1651)
		(layer "In9.Cu")
		(net "P5E_PEX2_STN1_TX_DP<25>")
	)
	(segment
		(start 300.065694 -264.021824)
		(end 265.271504 -161.233104)
		(width 0.1651)
		(layer "In9.Cu")
		(net "P5E_PEX2_STN1_TX_DP<25>")
	)
	(segment
		(start 262.454898 -129.82702)
		(end 262.570976 -129.779014)
		(width 0.1651)
		(layer "In9.Cu")
		(net "P5E_PEX2_STN1_TX_DP<25>")
	)
	(segment
		(start 263.465564 -127.619506)
		(end 263.655556 -127.161544)
		(width 0.1651)
		(layer "In9.Cu")
		(net "P5E_PEX2_STN1_TX_DP<25>")
	)
	(segment
		(start 265.271504 -161.233104)
		(end 264.66927 -158.205678)
		(width 0.1651)
		(layer "In9.Cu")
		(net "P5E_PEX2_STN1_TX_DP<25>")
	)
	(segment
		(start 263.349486 -127.667512)
		(end 263.465564 -127.619506)
		(width 0.1651)
		(layer "In9.Cu")
		(net "P5E_PEX2_STN1_TX_DP<25>")
	)
	(segment
		(start 264.807192 -124.380498)
		(end 264.99693 -123.92279)
		(width 0.1651)
		(layer "In9.Cu")
		(net "P5E_PEX2_STN1_TX_DP<25>")
	)
	(segment
		(start 261.396734 -132.382006)
		(end 262.007858 -130.906774)
		(width 0.1651)
		(layer "In9.Cu")
		(net "P5E_PEX2_STN1_TX_DP<25>")
	)
	(segment
		(start 268.811502 -121.692416)
		(end 268.900402 -121.603516)
		(width 0.1651)
		(layer "In9.Cu")
		(net "P5E_PEX2_STN1_TX_DP<25>")
	)
	(segment
		(start 263.160002 -128.12522)
		(end 263.349486 -127.667766)
		(width 0.1651)
		(layer "In9.Cu")
		(net "P5E_PEX2_STN1_TX_DP<25>")
	)
	(segment
		(start 300.399704 -280.015188)
		(end 300.285404 -280.129488)
		(width 0.1143)
		(layer "In9.Cu")
		(net "P5E_PEX2_STN1_TX_DP<25>")
	)
	(segment
		(start 264.99693 -123.92279)
		(end 264.948924 -123.806458)
		(width 0.1651)
		(layer "In9.Cu")
		(net "P5E_PEX2_STN1_TX_DP<25>")
	)
	(segment
		(start 264.948924 -123.806458)
		(end 265.300714 -122.956828)
		(width 0.1651)
		(layer "In9.Cu")
		(net "P5E_PEX2_STN1_TX_DP<25>")
	)
	(segment
		(start 262.760968 -129.321052)
		(end 262.712708 -129.204974)
		(width 0.1651)
		(layer "In9.Cu")
		(net "P5E_PEX2_STN1_TX_DP<25>")
	)
	(segment
		(start 267.820902 -121.692416)
		(end 267.909802 -121.603516)
		(width 0.1651)
		(layer "In9.Cu")
		(net "P5E_PEX2_STN1_TX_DP<25>")
	)
	(segment
		(start 264.54989 -125.00229)
		(end 264.50163 -124.886212)
		(width 0.1651)
		(layer "In9.Cu")
		(net "P5E_PEX2_STN1_TX_DP<25>")
	)
	(segment
		(start 267.909802 -121.603516)
		(end 268.316202 -121.603516)
		(width 0.1651)
		(layer "In9.Cu")
		(net "P5E_PEX2_STN1_TX_DP<25>")
	)
	(segment
		(start 264.691114 -124.428504)
		(end 264.807192 -124.380498)
		(width 0.1651)
		(layer "In9.Cu")
		(net "P5E_PEX2_STN1_TX_DP<25>")
	)
	(segment
		(start 262.570976 -129.779014)
		(end 262.760968 -129.321052)
		(width 0.1651)
		(layer "In9.Cu")
		(net "P5E_PEX2_STN1_TX_DP<25>")
	)
	(segment
		(start 263.01827 -128.69926)
		(end 263.208262 -128.241298)
		(width 0.1651)
		(layer "In9.Cu")
		(net "P5E_PEX2_STN1_TX_DP<25>")
	)
	(segment
		(start 262.902192 -128.74752)
		(end 262.902192 -128.747266)
		(width 0.1651)
		(layer "In9.Cu")
		(net "P5E_PEX2_STN1_TX_DP<25>")
	)
	(segment
		(start 264.24382 -125.508512)
		(end 264.24382 -125.508258)
		(width 0.1651)
		(layer "In9.Cu")
		(net "P5E_PEX2_STN1_TX_DP<25>")
	)
	(segment
		(start 264.359898 -125.460252)
		(end 264.54989 -125.00229)
		(width 0.1651)
		(layer "In9.Cu")
		(net "P5E_PEX2_STN1_TX_DP<25>")
	)
	(segment
		(start 264.24382 -125.508258)
		(end 264.359898 -125.460252)
		(width 0.1651)
		(layer "In9.Cu")
		(net "P5E_PEX2_STN1_TX_DP<25>")
	)
	(segment
		(start 337.669124 -343.365582)
		(end 337.669124 -342.734138)
		(width 0.13462)
		(layer "F.Cu")
		(net "P5E_PEX2_STN6_TX_DP<100>")
	)
	(segment
		(start 337.669124 -342.734138)
		(end 337.374484 -342.439498)
		(width 0.13462)
		(layer "F.Cu")
		(net "P5E_PEX2_STN6_TX_DP<100>")
	)
	(segment
		(start 337.349084 -343.685622)
		(end 337.669124 -343.365582)
		(width 0.13462)
		(layer "F.Cu")
		(net "P5E_PEX2_STN6_TX_DP<100>")
	)
	(segment
		(start 285.533846 -319.966848)
		(end 285.579566 -319.921128)
		(width 0.1143)
		(layer "In13.Cu")
		(net "P5E_PEX2_STN6_TX_DP<100>")
	)
	(segment
		(start 286.035496 -313.379612)
		(end 286.149796 -313.265312)
		(width 0.1143)
		(layer "In13.Cu")
		(net "P5E_PEX2_STN6_TX_DP<100>")
	)
	(segment
		(start 314.939426 -329.216258)
		(end 286.648144 -323.673978)
		(width 0.1651)
		(layer "In13.Cu")
		(net "P5E_PEX2_STN6_TX_DP<100>")
	)
	(segment
		(start 285.533846 -322.09867)
		(end 285.533846 -319.995296)
		(width 0.1651)
		(layer "In13.Cu")
		(net "P5E_PEX2_STN6_TX_DP<100>")
	)
	(segment
		(start 285.579566 -313.59475)
		(end 285.794704 -313.379612)
		(width 0.1143)
		(layer "In13.Cu")
		(net "P5E_PEX2_STN6_TX_DP<100>")
	)
	(segment
		(start 337.665314 -342.148668)
		(end 337.665314 -341.734902)
		(width 0.1651)
		(layer "In13.Cu")
		(net "P5E_PEX2_STN6_TX_DP<100>")
	)
	(segment
		(start 337.374484 -342.439498)
		(end 337.665314 -342.148668)
		(width 0.1651)
		(layer "In13.Cu")
		(net "P5E_PEX2_STN6_TX_DP<100>")
	)
	(segment
		(start 337.349592 -341.353648)
		(end 332.812898 -337.297268)
		(width 0.1651)
		(layer "In13.Cu")
		(net "P5E_PEX2_STN6_TX_DP<100>")
	)
	(segment
		(start 337.665314 -341.734902)
		(end 337.349592 -341.353648)
		(width 0.1651)
		(layer "In13.Cu")
		(net "P5E_PEX2_STN6_TX_DP<100>")
	)
	(segment
		(start 286.648144 -323.673978)
		(end 285.857188 -322.883022)
		(width 0.1651)
		(layer "In13.Cu")
		(net "P5E_PEX2_STN6_TX_DP<100>")
	)
	(segment
		(start 285.579566 -319.921128)
		(end 285.579566 -313.59475)
		(width 0.1143)
		(layer "In13.Cu")
		(net "P5E_PEX2_STN6_TX_DP<100>")
	)
	(segment
		(start 285.794704 -313.379612)
		(end 286.035496 -313.379612)
		(width 0.1143)
		(layer "In13.Cu")
		(net "P5E_PEX2_STN6_TX_DP<100>")
	)
	(segment
		(start 286.149796 -313.265312)
		(end 286.149796 -312.999882)
		(width 0.1143)
		(layer "In13.Cu")
		(net "P5E_PEX2_STN6_TX_DP<100>")
	)
	(segment
		(start 285.533846 -319.995296)
		(end 285.533846 -319.966848)
		(width 0.1143)
		(layer "In13.Cu")
		(net "P5E_PEX2_STN6_TX_DP<100>")
	)
	(segment
		(start 332.812898 -337.297268)
		(end 314.939426 -329.216258)
		(width 0.1651)
		(layer "In13.Cu")
		(net "P5E_PEX2_STN6_TX_DP<100>")
	)
	(segment
		(start 285.857188 -322.883022)
		(end 285.533846 -322.09867)
		(width 0.1651)
		(layer "In13.Cu")
		(net "P5E_PEX2_STN6_TX_DP<100>")
	)
	(segment
		(start 294.614092 -342.055958)
		(end 294.253412 -341.347552)
		(width 0.1651)
		(layer "In5.Cu")
		(net "P5E_PEX2_STN7_RX_DP<124>")
	)
	(segment
		(start 296.12082 -364.836456)
		(end 296.187114 -364.729776)
		(width 0.1651)
		(layer "In5.Cu")
		(net "P5E_PEX2_STN7_RX_DP<124>")
	)
	(segment
		(start 296.388536 -365.974122)
		(end 296.454576 -365.867188)
		(width 0.1651)
		(layer "In5.Cu")
		(net "P5E_PEX2_STN7_RX_DP<124>")
	)
	(segment
		(start 297.134026 -368.756692)
		(end 296.608754 -366.522762)
		(width 0.1651)
		(layer "In5.Cu")
		(net "P5E_PEX2_STN7_RX_DP<124>")
	)
	(segment
		(start 296.50182 -366.456468)
		(end 296.388536 -365.974122)
		(width 0.1651)
		(layer "In5.Cu")
		(net "P5E_PEX2_STN7_RX_DP<124>")
	)
	(segment
		(start 273.730466 -329.156568)
		(end 271.670018 -326.717406)
		(width 0.1651)
		(layer "In5.Cu")
		(net "P5E_PEX2_STN7_RX_DP<124>")
	)
	(segment
		(start 296.84726 -382.69926)
		(end 297.134026 -382.412494)
		(width 0.1651)
		(layer "In5.Cu")
		(net "P5E_PEX2_STN7_RX_DP<124>")
	)
	(segment
		(start 271.670018 -326.717406)
		(end 271.283938 -325.681086)
		(width 0.1651)
		(layer "In5.Cu")
		(net "P5E_PEX2_STN7_RX_DP<124>")
	)
	(segment
		(start 295.919652 -363.592364)
		(end 294.614092 -358.037892)
		(width 0.1651)
		(layer "In5.Cu")
		(net "P5E_PEX2_STN7_RX_DP<124>")
	)
	(segment
		(start 296.07383 -364.247684)
		(end 295.966642 -364.181644)
		(width 0.1651)
		(layer "In5.Cu")
		(net "P5E_PEX2_STN7_RX_DP<124>")
	)
	(segment
		(start 295.853358 -363.699044)
		(end 295.919652 -363.592364)
		(width 0.1651)
		(layer "In5.Cu")
		(net "P5E_PEX2_STN7_RX_DP<124>")
	)
	(segment
		(start 296.454576 -365.867188)
		(end 296.341292 -365.385096)
		(width 0.1651)
		(layer "In5.Cu")
		(net "P5E_PEX2_STN7_RX_DP<124>")
	)
	(segment
		(start 276.43582 -331.003402)
		(end 273.730466 -329.156568)
		(width 0.1651)
		(layer "In5.Cu")
		(net "P5E_PEX2_STN7_RX_DP<124>")
	)
	(segment
		(start 271.899888 -316.115192)
		(end 271.899888 -315.849762)
		(width 0.1143)
		(layer "In5.Cu")
		(net "P5E_PEX2_STN7_RX_DP<124>")
	)
	(segment
		(start 294.614092 -358.037892)
		(end 294.614092 -342.055958)
		(width 0.1651)
		(layer "In5.Cu")
		(net "P5E_PEX2_STN7_RX_DP<124>")
	)
	(segment
		(start 271.283938 -320.043048)
		(end 271.283938 -320.0146)
		(width 0.1143)
		(layer "In5.Cu")
		(net "P5E_PEX2_STN7_RX_DP<124>")
	)
	(segment
		(start 296.416984 -382.69926)
		(end 296.84726 -382.69926)
		(width 0.1651)
		(layer "In5.Cu")
		(net "P5E_PEX2_STN7_RX_DP<124>")
	)
	(segment
		(start 271.283938 -325.681086)
		(end 271.283938 -320.043048)
		(width 0.1651)
		(layer "In5.Cu")
		(net "P5E_PEX2_STN7_RX_DP<124>")
	)
	(segment
		(start 295.966642 -364.181644)
		(end 295.853358 -363.699044)
		(width 0.1651)
		(layer "In5.Cu")
		(net "P5E_PEX2_STN7_RX_DP<124>")
	)
	(segment
		(start 296.289984 -382.18999)
		(end 296.289984 -382.57226)
		(width 0.1651)
		(layer "In5.Cu")
		(net "P5E_PEX2_STN7_RX_DP<124>")
	)
	(segment
		(start 296.289984 -382.57226)
		(end 296.416984 -382.69926)
		(width 0.1651)
		(layer "In5.Cu")
		(net "P5E_PEX2_STN7_RX_DP<124>")
	)
	(segment
		(start 271.555464 -316.229492)
		(end 271.785588 -316.229492)
		(width 0.1143)
		(layer "In5.Cu")
		(net "P5E_PEX2_STN7_RX_DP<124>")
	)
	(segment
		(start 296.187114 -364.729776)
		(end 296.07383 -364.247684)
		(width 0.1651)
		(layer "In5.Cu")
		(net "P5E_PEX2_STN7_RX_DP<124>")
	)
	(segment
		(start 296.608754 -366.522762)
		(end 296.609008 -366.522762)
		(width 0.1651)
		(layer "In5.Cu")
		(net "P5E_PEX2_STN7_RX_DP<124>")
	)
	(segment
		(start 271.785588 -316.229492)
		(end 271.899888 -316.115192)
		(width 0.1143)
		(layer "In5.Cu")
		(net "P5E_PEX2_STN7_RX_DP<124>")
	)
	(segment
		(start 296.234104 -365.319056)
		(end 296.12082 -364.836456)
		(width 0.1651)
		(layer "In5.Cu")
		(net "P5E_PEX2_STN7_RX_DP<124>")
	)
	(segment
		(start 296.341292 -365.385096)
		(end 296.234104 -365.319056)
		(width 0.1651)
		(layer "In5.Cu")
		(net "P5E_PEX2_STN7_RX_DP<124>")
	)
	(segment
		(start 293.443406 -340.384892)
		(end 276.43582 -331.003402)
		(width 0.1651)
		(layer "In5.Cu")
		(net "P5E_PEX2_STN7_RX_DP<124>")
	)
	(segment
		(start 294.253412 -341.347552)
		(end 293.443406 -340.384892)
		(width 0.1651)
		(layer "In5.Cu")
		(net "P5E_PEX2_STN7_RX_DP<124>")
	)
	(segment
		(start 296.609008 -366.522762)
		(end 296.50182 -366.456468)
		(width 0.1651)
		(layer "In5.Cu")
		(net "P5E_PEX2_STN7_RX_DP<124>")
	)
	(segment
		(start 271.283938 -320.0146)
		(end 271.329658 -319.96888)
		(width 0.1143)
		(layer "In5.Cu")
		(net "P5E_PEX2_STN7_RX_DP<124>")
	)
	(segment
		(start 271.329658 -316.455298)
		(end 271.555464 -316.229492)
		(width 0.1143)
		(layer "In5.Cu")
		(net "P5E_PEX2_STN7_RX_DP<124>")
	)
	(segment
		(start 271.329658 -319.96888)
		(end 271.329658 -316.455298)
		(width 0.1143)
		(layer "In5.Cu")
		(net "P5E_PEX2_STN7_RX_DP<124>")
	)
	(segment
		(start 297.134026 -382.412494)
		(end 297.134026 -368.756692)
		(width 0.1651)
		(layer "In5.Cu")
		(net "P5E_PEX2_STN7_RX_DP<124>")
	)
	(segment
		(start 429.434498 -79.463646)
		(end 428.84852 -79.463646)
		(width 0.13208)
		(layer "F.Cu")
		(net "HP_NIC7_PWRGD")
	)
	(segment
		(start 428.84852 -79.463646)
		(end 428.330106 -79.98206)
		(width 0.13208)
		(layer "F.Cu")
		(net "HP_NIC7_PWRGD")
	)
	(segment
		(start 428.330106 -79.98206)
		(end 427.614842 -79.98206)
		(width 0.13208)
		(layer "F.Cu")
		(net "HP_NIC7_PWRGD")
	)
	(segment
		(start 427.614842 -80.95996)
		(end 427.614842 -79.98206)
		(width 0.13208)
		(layer "F.Cu")
		(net "HP_NIC7_PWRGD")
	)
	(via
		(at 428.330106 -79.98206)
		(size 0.508)
		(drill 0.254)
		(layers "F.Cu" "B.Cu")
		(net "HP_NIC7_PWRGD")
	)
	(segment
		(start 26.413968 -351.611438)
		(end 26.119328 -351.316798)
		(width 0.13462)
		(layer "F.Cu")
		(net "P5E_PEX0_STN7_TX_C_DN<115>")
	)
	(segment
		(start 26.119328 -351.316798)
		(end 26.119328 -350.685354)
		(width 0.13462)
		(layer "F.Cu")
		(net "P5E_PEX0_STN7_TX_C_DN<115>")
	)
	(segment
		(start 26.119328 -350.685354)
		(end 26.439368 -350.365314)
		(width 0.13462)
		(layer "F.Cu")
		(net "P5E_PEX0_STN7_TX_C_DN<115>")
	)
	(segment
		(start 22.96287 -384.740658)
		(end 22.44852 -376.198638)
		(width 0.1651)
		(layer "In7.Cu")
		(net "P5E_PEX0_STN7_TX_C_DN<115>")
	)
	(segment
		(start 26.123138 -352.552762)
		(end 26.123138 -351.902268)
		(width 0.1651)
		(layer "In7.Cu")
		(net "P5E_PEX0_STN7_TX_C_DN<115>")
	)
	(segment
		(start 33.311084 -392.187684)
		(end 25.895046 -389.115808)
		(width 0.1651)
		(layer "In7.Cu")
		(net "P5E_PEX0_STN7_TX_C_DN<115>")
	)
	(segment
		(start 35.3695 -402.281136)
		(end 35.68446 -401.966176)
		(width 0.1651)
		(layer "In7.Cu")
		(net "P5E_PEX0_STN7_TX_C_DN<115>")
	)
	(segment
		(start 24.568658 -354.107242)
		(end 26.123138 -352.552762)
		(width 0.1651)
		(layer "In7.Cu")
		(net "P5E_PEX0_STN7_TX_C_DN<115>")
	)
	(segment
		(start 22.44852 -376.198638)
		(end 22.44852 -370.69014)
		(width 0.1651)
		(layer "In7.Cu")
		(net "P5E_PEX0_STN7_TX_C_DN<115>")
	)
	(segment
		(start 34.509964 -402.790152)
		(end 34.509964 -402.408136)
		(width 0.1651)
		(layer "In7.Cu")
		(net "P5E_PEX0_STN7_TX_C_DN<115>")
	)
	(segment
		(start 22.853142 -366.58169)
		(end 24.568658 -357.956358)
		(width 0.1651)
		(layer "In7.Cu")
		(net "P5E_PEX0_STN7_TX_C_DN<115>")
	)
	(segment
		(start 22.44852 -370.69014)
		(end 22.853142 -366.58169)
		(width 0.1651)
		(layer "In7.Cu")
		(net "P5E_PEX0_STN7_TX_C_DN<115>")
	)
	(segment
		(start 35.68446 -401.966176)
		(end 35.68446 -394.56106)
		(width 0.1651)
		(layer "In7.Cu")
		(net "P5E_PEX0_STN7_TX_C_DN<115>")
	)
	(segment
		(start 24.143208 -387.36397)
		(end 22.96287 -384.740658)
		(width 0.1651)
		(layer "In7.Cu")
		(net "P5E_PEX0_STN7_TX_C_DN<115>")
	)
	(segment
		(start 35.68446 -394.56106)
		(end 33.311084 -392.187684)
		(width 0.1651)
		(layer "In7.Cu")
		(net "P5E_PEX0_STN7_TX_C_DN<115>")
	)
	(segment
		(start 25.895046 -389.115808)
		(end 24.143208 -387.36397)
		(width 0.1651)
		(layer "In7.Cu")
		(net "P5E_PEX0_STN7_TX_C_DN<115>")
	)
	(segment
		(start 34.509964 -402.408136)
		(end 34.636964 -402.281136)
		(width 0.1651)
		(layer "In7.Cu")
		(net "P5E_PEX0_STN7_TX_C_DN<115>")
	)
	(segment
		(start 34.636964 -402.281136)
		(end 35.3695 -402.281136)
		(width 0.1651)
		(layer "In7.Cu")
		(net "P5E_PEX0_STN7_TX_C_DN<115>")
	)
	(segment
		(start 24.568658 -357.956358)
		(end 24.568658 -354.107242)
		(width 0.1651)
		(layer "In7.Cu")
		(net "P5E_PEX0_STN7_TX_C_DN<115>")
	)
	(segment
		(start 26.123138 -351.902268)
		(end 26.413968 -351.611438)
		(width 0.1651)
		(layer "In7.Cu")
		(net "P5E_PEX0_STN7_TX_C_DN<115>")
	)
	(segment
		(start 121.483628 -342.734138)
		(end 121.188988 -342.439498)
		(width 0.13462)
		(layer "F.Cu")
		(net "P5E_PEX1_STN6_TX_DP<99>")
	)
	(segment
		(start 121.483628 -343.365582)
		(end 121.483628 -342.734138)
		(width 0.13462)
		(layer "F.Cu")
		(net "P5E_PEX1_STN6_TX_DP<99>")
	)
	(segment
		(start 121.163588 -343.685622)
		(end 121.483628 -343.365582)
		(width 0.13462)
		(layer "F.Cu")
		(net "P5E_PEX1_STN6_TX_DP<99>")
	)
	(segment
		(start 167.043862 -323.68744)
		(end 168.938194 -322.55206)
		(width 0.1651)
		(layer "In7.Cu")
		(net "P5E_PEX1_STN6_TX_DP<99>")
	)
	(segment
		(start 121.479818 -340.927182)
		(end 121.778776 -340.628224)
		(width 0.1651)
		(layer "In7.Cu")
		(net "P5E_PEX1_STN6_TX_DP<99>")
	)
	(segment
		(start 170.429682 -319.942718)
		(end 170.429682 -311.705498)
		(width 0.1143)
		(layer "In7.Cu")
		(net "P5E_PEX1_STN6_TX_DP<99>")
	)
	(segment
		(start 170.655488 -311.479692)
		(end 170.885612 -311.479692)
		(width 0.1143)
		(layer "In7.Cu")
		(net "P5E_PEX1_STN6_TX_DP<99>")
	)
	(segment
		(start 149.867112 -328.897742)
		(end 167.043862 -323.68744)
		(width 0.1651)
		(layer "In7.Cu")
		(net "P5E_PEX1_STN6_TX_DP<99>")
	)
	(segment
		(start 121.188988 -342.439498)
		(end 121.479818 -342.148668)
		(width 0.1651)
		(layer "In7.Cu")
		(net "P5E_PEX1_STN6_TX_DP<99>")
	)
	(segment
		(start 170.383962 -320.016886)
		(end 170.383962 -319.988438)
		(width 0.1143)
		(layer "In7.Cu")
		(net "P5E_PEX1_STN6_TX_DP<99>")
	)
	(segment
		(start 170.383962 -319.988438)
		(end 170.429682 -319.942718)
		(width 0.1143)
		(layer "In7.Cu")
		(net "P5E_PEX1_STN6_TX_DP<99>")
	)
	(segment
		(start 170.999912 -311.365392)
		(end 170.999912 -311.099962)
		(width 0.1143)
		(layer "In7.Cu")
		(net "P5E_PEX1_STN6_TX_DP<99>")
	)
	(segment
		(start 170.383962 -320.368422)
		(end 170.383962 -320.016886)
		(width 0.1651)
		(layer "In7.Cu")
		(net "P5E_PEX1_STN6_TX_DP<99>")
	)
	(segment
		(start 170.885612 -311.479692)
		(end 170.999912 -311.365392)
		(width 0.1143)
		(layer "In7.Cu")
		(net "P5E_PEX1_STN6_TX_DP<99>")
	)
	(segment
		(start 168.938194 -322.55206)
		(end 169.862246 -321.628008)
		(width 0.1651)
		(layer "In7.Cu")
		(net "P5E_PEX1_STN6_TX_DP<99>")
	)
	(segment
		(start 169.862246 -321.628008)
		(end 170.383962 -320.368422)
		(width 0.1651)
		(layer "In7.Cu")
		(net "P5E_PEX1_STN6_TX_DP<99>")
	)
	(segment
		(start 132.623306 -334.128364)
		(end 149.867112 -328.897742)
		(width 0.1651)
		(layer "In7.Cu")
		(net "P5E_PEX1_STN6_TX_DP<99>")
	)
	(segment
		(start 121.479818 -342.148668)
		(end 121.479818 -340.927182)
		(width 0.1651)
		(layer "In7.Cu")
		(net "P5E_PEX1_STN6_TX_DP<99>")
	)
	(segment
		(start 170.429682 -311.705498)
		(end 170.655488 -311.479692)
		(width 0.1143)
		(layer "In7.Cu")
		(net "P5E_PEX1_STN6_TX_DP<99>")
	)
	(segment
		(start 121.778776 -340.628224)
		(end 132.623306 -334.128364)
		(width 0.1651)
		(layer "In7.Cu")
		(net "P5E_PEX1_STN6_TX_DP<99>")
	)
	(segment
		(start 267.6271 -119.7864)
		(end 268.244828 -119.7864)
		(width 0.13462)
		(layer "F.Cu")
		(net "P5E_PEX2_STN1_TX_DN<24>")
	)
	(segment
		(start 267.325602 -120.087898)
		(end 267.6271 -119.7864)
		(width 0.13462)
		(layer "F.Cu")
		(net "P5E_PEX2_STN1_TX_DN<24>")
	)
	(segment
		(start 268.244828 -119.7864)
		(end 268.571726 -120.113298)
		(width 0.13462)
		(layer "F.Cu")
		(net "P5E_PEX2_STN1_TX_DN<24>")
	)
	(segment
		(start 261.859268 -128.469644)
		(end 262.043926 -128.023874)
		(width 0.1651)
		(layer "In9.Cu")
		(net "P5E_PEX2_STN1_TX_DN<24>")
	)
	(segment
		(start 263.716262 -158.457646)
		(end 263.351772 -151.045672)
		(width 0.1651)
		(layer "In9.Cu")
		(net "P5E_PEX2_STN1_TX_DN<24>")
	)
	(segment
		(start 261.729728 -129.04851)
		(end 261.914386 -128.602232)
		(width 0.1651)
		(layer "In9.Cu")
		(net "P5E_PEX2_STN1_TX_DN<24>")
	)
	(segment
		(start 299.44949 -277.849838)
		(end 299.44949 -278.115268)
		(width 0.1143)
		(layer "In9.Cu")
		(net "P5E_PEX2_STN1_TX_DN<24>")
	)
	(segment
		(start 261.389368 -129.604516)
		(end 261.596886 -129.103374)
		(width 0.1651)
		(layer "In9.Cu")
		(net "P5E_PEX2_STN1_TX_DN<24>")
	)
	(segment
		(start 263.385554 -124.784866)
		(end 263.51865 -124.730002)
		(width 0.1651)
		(layer "In9.Cu")
		(net "P5E_PEX2_STN1_TX_DN<24>")
	)
	(segment
		(start 299.173392 -278.229568)
		(end 299.070014 -278.12619)
		(width 0.1143)
		(layer "In9.Cu")
		(net "P5E_PEX2_STN1_TX_DN<24>")
	)
	(segment
		(start 263.071356 -125.809502)
		(end 263.256014 -125.363224)
		(width 0.1651)
		(layer "In9.Cu")
		(net "P5E_PEX2_STN1_TX_DN<24>")
	)
	(segment
		(start 262.624316 -126.889002)
		(end 262.808974 -126.442724)
		(width 0.1651)
		(layer "In9.Cu")
		(net "P5E_PEX2_STN1_TX_DN<24>")
	)
	(segment
		(start 261.444486 -129.737104)
		(end 261.389368 -129.604516)
		(width 0.1651)
		(layer "In9.Cu")
		(net "P5E_PEX2_STN1_TX_DN<24>")
	)
	(segment
		(start 265.829796 -120.365774)
		(end 266.398502 -119.797068)
		(width 0.1651)
		(layer "In9.Cu")
		(net "P5E_PEX2_STN1_TX_DN<24>")
	)
	(segment
		(start 263.703308 -124.283724)
		(end 263.64819 -124.151136)
		(width 0.1651)
		(layer "In9.Cu")
		(net "P5E_PEX2_STN1_TX_DN<24>")
	)
	(segment
		(start 262.043926 -128.02362)
		(end 262.177022 -127.968756)
		(width 0.1651)
		(layer "In9.Cu")
		(net "P5E_PEX2_STN1_TX_DN<24>")
	)
	(segment
		(start 267.034772 -119.797068)
		(end 267.325602 -120.087898)
		(width 0.1651)
		(layer "In9.Cu")
		(net "P5E_PEX2_STN1_TX_DN<24>")
	)
	(segment
		(start 262.49122 -126.943866)
		(end 262.624316 -126.889002)
		(width 0.1651)
		(layer "In9.Cu")
		(net "P5E_PEX2_STN1_TX_DN<24>")
	)
	(segment
		(start 263.64819 -124.151136)
		(end 263.832848 -123.705366)
		(width 0.1651)
		(layer "In9.Cu")
		(net "P5E_PEX2_STN1_TX_DN<24>")
	)
	(segment
		(start 261.914386 -128.602232)
		(end 261.859268 -128.469644)
		(width 0.1651)
		(layer "In9.Cu")
		(net "P5E_PEX2_STN1_TX_DN<24>")
	)
	(segment
		(start 299.44949 -278.115268)
		(end 299.33519 -278.229568)
		(width 0.1143)
		(layer "In9.Cu")
		(net "P5E_PEX2_STN1_TX_DN<24>")
	)
	(segment
		(start 299.115734 -271.500346)
		(end 299.115734 -271.471898)
		(width 0.1143)
		(layer "In9.Cu")
		(net "P5E_PEX2_STN1_TX_DN<24>")
	)
	(segment
		(start 265.829796 -120.527318)
		(end 265.829796 -120.365774)
		(width 0.1651)
		(layer "In9.Cu")
		(net "P5E_PEX2_STN1_TX_DN<24>")
	)
	(segment
		(start 262.36168 -127.522478)
		(end 262.306562 -127.38989)
		(width 0.1651)
		(layer "In9.Cu")
		(net "P5E_PEX2_STN1_TX_DN<24>")
	)
	(segment
		(start 265.48842 -120.868694)
		(end 265.829796 -120.527318)
		(width 0.1651)
		(layer "In9.Cu")
		(net "P5E_PEX2_STN1_TX_DN<24>")
	)
	(segment
		(start 260.428994 -137.396474)
		(end 260.428994 -131.92252)
		(width 0.1651)
		(layer "In9.Cu")
		(net "P5E_PEX2_STN1_TX_DN<24>")
	)
	(segment
		(start 299.070014 -271.546066)
		(end 299.115734 -271.500346)
		(width 0.1143)
		(layer "In9.Cu")
		(net "P5E_PEX2_STN1_TX_DN<24>")
	)
	(segment
		(start 260.428994 -131.92252)
		(end 261.126732 -130.238246)
		(width 0.1651)
		(layer "In9.Cu")
		(net "P5E_PEX2_STN1_TX_DN<24>")
	)
	(segment
		(start 264.09523 -123.071636)
		(end 264.279888 -122.625866)
		(width 0.1651)
		(layer "In9.Cu")
		(net "P5E_PEX2_STN1_TX_DN<24>")
	)
	(segment
		(start 262.043926 -128.023874)
		(end 262.043926 -128.02362)
		(width 0.1651)
		(layer "In9.Cu")
		(net "P5E_PEX2_STN1_TX_DN<24>")
	)
	(segment
		(start 261.596886 -129.103374)
		(end 261.596632 -129.103374)
		(width 0.1651)
		(layer "In9.Cu")
		(net "P5E_PEX2_STN1_TX_DN<24>")
	)
	(segment
		(start 261.259574 -130.183382)
		(end 261.444486 -129.737104)
		(width 0.1651)
		(layer "In9.Cu")
		(net "P5E_PEX2_STN1_TX_DN<24>")
	)
	(segment
		(start 263.256014 -125.363224)
		(end 263.200896 -125.230636)
		(width 0.1651)
		(layer "In9.Cu")
		(net "P5E_PEX2_STN1_TX_DN<24>")
	)
	(segment
		(start 262.177022 -127.968756)
		(end 262.36168 -127.522478)
		(width 0.1651)
		(layer "In9.Cu")
		(net "P5E_PEX2_STN1_TX_DN<24>")
	)
	(segment
		(start 262.306562 -127.38989)
		(end 262.49122 -126.94412)
		(width 0.1651)
		(layer "In9.Cu")
		(net "P5E_PEX2_STN1_TX_DN<24>")
	)
	(segment
		(start 262.753856 -126.310136)
		(end 262.938514 -125.864366)
		(width 0.1651)
		(layer "In9.Cu")
		(net "P5E_PEX2_STN1_TX_DN<24>")
	)
	(segment
		(start 263.832848 -123.705366)
		(end 263.832594 -123.705366)
		(width 0.1651)
		(layer "In9.Cu")
		(net "P5E_PEX2_STN1_TX_DN<24>")
	)
	(segment
		(start 299.115734 -271.471898)
		(end 299.115734 -264.235184)
		(width 0.1651)
		(layer "In9.Cu")
		(net "P5E_PEX2_STN1_TX_DN<24>")
	)
	(segment
		(start 299.33519 -278.229568)
		(end 299.173392 -278.229568)
		(width 0.1143)
		(layer "In9.Cu")
		(net "P5E_PEX2_STN1_TX_DN<24>")
	)
	(segment
		(start 264.542524 -121.992136)
		(end 264.782046 -121.413524)
		(width 0.1651)
		(layer "In9.Cu")
		(net "P5E_PEX2_STN1_TX_DN<24>")
	)
	(segment
		(start 262.98398 -143.564356)
		(end 260.428994 -137.396474)
		(width 0.1651)
		(layer "In9.Cu")
		(net "P5E_PEX2_STN1_TX_DN<24>")
	)
	(segment
		(start 263.96569 -123.650502)
		(end 264.150348 -123.204224)
		(width 0.1651)
		(layer "In9.Cu")
		(net "P5E_PEX2_STN1_TX_DN<24>")
	)
	(segment
		(start 263.351772 -151.045672)
		(end 262.98398 -143.564356)
		(width 0.1651)
		(layer "In9.Cu")
		(net "P5E_PEX2_STN1_TX_DN<24>")
	)
	(segment
		(start 266.398502 -119.797068)
		(end 267.034772 -119.797068)
		(width 0.1651)
		(layer "In9.Cu")
		(net "P5E_PEX2_STN1_TX_DN<24>")
	)
	(segment
		(start 264.294874 -161.3662)
		(end 263.716262 -158.457646)
		(width 0.1651)
		(layer "In9.Cu")
		(net "P5E_PEX2_STN1_TX_DN<24>")
	)
	(segment
		(start 264.597388 -122.124724)
		(end 264.542524 -121.992136)
		(width 0.1651)
		(layer "In9.Cu")
		(net "P5E_PEX2_STN1_TX_DN<24>")
	)
	(segment
		(start 262.93826 -125.864366)
		(end 263.071356 -125.809502)
		(width 0.1651)
		(layer "In9.Cu")
		(net "P5E_PEX2_STN1_TX_DN<24>")
	)
	(segment
		(start 263.832594 -123.705366)
		(end 263.96569 -123.650502)
		(width 0.1651)
		(layer "In9.Cu")
		(net "P5E_PEX2_STN1_TX_DN<24>")
	)
	(segment
		(start 299.115734 -264.235184)
		(end 264.294874 -161.3662)
		(width 0.1651)
		(layer "In9.Cu")
		(net "P5E_PEX2_STN1_TX_DN<24>")
	)
	(segment
		(start 261.596632 -129.103374)
		(end 261.729728 -129.04851)
		(width 0.1651)
		(layer "In9.Cu")
		(net "P5E_PEX2_STN1_TX_DN<24>")
	)
	(segment
		(start 262.49122 -126.94412)
		(end 262.49122 -126.943866)
		(width 0.1651)
		(layer "In9.Cu")
		(net "P5E_PEX2_STN1_TX_DN<24>")
	)
	(segment
		(start 264.279888 -122.625866)
		(end 264.41273 -122.571002)
		(width 0.1651)
		(layer "In9.Cu")
		(net "P5E_PEX2_STN1_TX_DN<24>")
	)
	(segment
		(start 265.326876 -120.868694)
		(end 265.48842 -120.868694)
		(width 0.1651)
		(layer "In9.Cu")
		(net "P5E_PEX2_STN1_TX_DN<24>")
	)
	(segment
		(start 264.150348 -123.204224)
		(end 264.09523 -123.071636)
		(width 0.1651)
		(layer "In9.Cu")
		(net "P5E_PEX2_STN1_TX_DN<24>")
	)
	(segment
		(start 263.51865 -124.730002)
		(end 263.703308 -124.283724)
		(width 0.1651)
		(layer "In9.Cu")
		(net "P5E_PEX2_STN1_TX_DN<24>")
	)
	(segment
		(start 264.782046 -121.413524)
		(end 265.326876 -120.868694)
		(width 0.1651)
		(layer "In9.Cu")
		(net "P5E_PEX2_STN1_TX_DN<24>")
	)
	(segment
		(start 262.808974 -126.442724)
		(end 262.753856 -126.310136)
		(width 0.1651)
		(layer "In9.Cu")
		(net "P5E_PEX2_STN1_TX_DN<24>")
	)
	(segment
		(start 299.070014 -278.12619)
		(end 299.070014 -271.546066)
		(width 0.1143)
		(layer "In9.Cu")
		(net "P5E_PEX2_STN1_TX_DN<24>")
	)
	(segment
		(start 261.126732 -130.238246)
		(end 261.259574 -130.183382)
		(width 0.1651)
		(layer "In9.Cu")
		(net "P5E_PEX2_STN1_TX_DN<24>")
	)
	(segment
		(start 264.41273 -122.571002)
		(end 264.597388 -122.124724)
		(width 0.1651)
		(layer "In9.Cu")
		(net "P5E_PEX2_STN1_TX_DN<24>")
	)
	(segment
		(start 263.200896 -125.230636)
		(end 263.385554 -124.784866)
		(width 0.1651)
		(layer "In9.Cu")
		(net "P5E_PEX2_STN1_TX_DN<24>")
	)
	(segment
		(start 262.938514 -125.864366)
		(end 262.93826 -125.864366)
		(width 0.1651)
		(layer "In9.Cu")
		(net "P5E_PEX2_STN1_TX_DN<24>")
	)
	(segment
		(start 324.913244 -343.685622)
		(end 325.233284 -343.365582)
		(width 0.13462)
		(layer "F.Cu")
		(net "P5E_PEX2_STN6_TX_DP<106>")
	)
	(segment
		(start 325.233284 -343.365582)
		(end 325.233284 -342.734138)
		(width 0.13462)
		(layer "F.Cu")
		(net "P5E_PEX2_STN6_TX_DP<106>")
	)
	(segment
		(start 325.233284 -342.734138)
		(end 324.938644 -342.439498)
		(width 0.13462)
		(layer "F.Cu")
		(net "P5E_PEX2_STN6_TX_DP<106>")
	)
	(segment
		(start 323.500242 -339.729318)
		(end 314.612528 -335.842356)
		(width 0.1651)
		(layer "In13.Cu")
		(net "P5E_PEX2_STN6_TX_DP<106>")
	)
	(segment
		(start 325.229474 -342.148668)
		(end 325.229474 -341.73795)
		(width 0.1651)
		(layer "In13.Cu")
		(net "P5E_PEX2_STN6_TX_DP<106>")
	)
	(segment
		(start 279.833832 -324.347078)
		(end 279.833832 -319.995296)
		(width 0.1651)
		(layer "In13.Cu")
		(net "P5E_PEX2_STN6_TX_DP<106>")
	)
	(segment
		(start 280.09469 -313.379612)
		(end 280.335482 -313.379612)
		(width 0.1143)
		(layer "In13.Cu")
		(net "P5E_PEX2_STN6_TX_DP<106>")
	)
	(segment
		(start 279.879552 -313.59475)
		(end 280.09469 -313.379612)
		(width 0.1143)
		(layer "In13.Cu")
		(net "P5E_PEX2_STN6_TX_DP<106>")
	)
	(segment
		(start 324.938644 -342.439498)
		(end 325.229474 -342.148668)
		(width 0.1651)
		(layer "In13.Cu")
		(net "P5E_PEX2_STN6_TX_DP<106>")
	)
	(segment
		(start 314.612528 -335.842356)
		(end 284.196282 -329.832462)
		(width 0.1651)
		(layer "In13.Cu")
		(net "P5E_PEX2_STN6_TX_DP<106>")
	)
	(segment
		(start 280.449782 -313.265312)
		(end 280.449782 -312.999882)
		(width 0.1143)
		(layer "In13.Cu")
		(net "P5E_PEX2_STN6_TX_DP<106>")
	)
	(segment
		(start 325.229474 -341.73795)
		(end 323.500242 -339.729318)
		(width 0.1651)
		(layer "In13.Cu")
		(net "P5E_PEX2_STN6_TX_DP<106>")
	)
	(segment
		(start 284.196282 -329.832462)
		(end 280.627836 -326.264016)
		(width 0.1651)
		(layer "In13.Cu")
		(net "P5E_PEX2_STN6_TX_DP<106>")
	)
	(segment
		(start 279.833832 -319.995296)
		(end 279.833832 -319.966848)
		(width 0.1143)
		(layer "In13.Cu")
		(net "P5E_PEX2_STN6_TX_DP<106>")
	)
	(segment
		(start 279.833832 -319.966848)
		(end 279.879552 -319.921128)
		(width 0.1143)
		(layer "In13.Cu")
		(net "P5E_PEX2_STN6_TX_DP<106>")
	)
	(segment
		(start 280.627836 -326.264016)
		(end 279.833832 -324.347078)
		(width 0.1651)
		(layer "In13.Cu")
		(net "P5E_PEX2_STN6_TX_DP<106>")
	)
	(segment
		(start 279.879552 -319.921128)
		(end 279.879552 -313.59475)
		(width 0.1143)
		(layer "In13.Cu")
		(net "P5E_PEX2_STN6_TX_DP<106>")
	)
	(segment
		(start 280.335482 -313.379612)
		(end 280.449782 -313.265312)
		(width 0.1143)
		(layer "In13.Cu")
		(net "P5E_PEX2_STN6_TX_DP<106>")
	)
	(segment
		(start 292.564058 -382.9812)
		(end 292.016942 -382.9812)
		(width 0.1651)
		(layer "In5.Cu")
		(net "P5E_PEX2_STN7_RX_DP<122>")
	)
	(segment
		(start 293.015924 -382.529334)
		(end 292.564058 -382.9812)
		(width 0.1651)
		(layer "In5.Cu")
		(net "P5E_PEX2_STN7_RX_DP<122>")
	)
	(segment
		(start 288.678112 -342.206326)
		(end 288.678112 -358.031034)
		(width 0.1651)
		(layer "In5.Cu")
		(net "P5E_PEX2_STN7_RX_DP<122>")
	)
	(segment
		(start 288.678112 -358.031034)
		(end 293.015924 -368.625374)
		(width 0.1651)
		(layer "In5.Cu")
		(net "P5E_PEX2_STN7_RX_DP<122>")
	)
	(segment
		(start 288.316416 -341.059262)
		(end 288.678112 -342.206326)
		(width 0.1651)
		(layer "In5.Cu")
		(net "P5E_PEX2_STN7_RX_DP<122>")
	)
	(segment
		(start 269.734284 -316.799722)
		(end 269.619984 -316.914022)
		(width 0.1143)
		(layer "In5.Cu")
		(net "P5E_PEX2_STN7_RX_DP<122>")
	)
	(segment
		(start 291.889942 -383.1082)
		(end 291.889942 -383.490216)
		(width 0.1651)
		(layer "In5.Cu")
		(net "P5E_PEX2_STN7_RX_DP<122>")
	)
	(segment
		(start 269.665704 -319.1256)
		(end 269.665704 -319.154048)
		(width 0.1143)
		(layer "In5.Cu")
		(net "P5E_PEX2_STN7_RX_DP<122>")
	)
	(segment
		(start 292.016942 -382.9812)
		(end 291.889942 -383.1082)
		(width 0.1651)
		(layer "In5.Cu")
		(net "P5E_PEX2_STN7_RX_DP<122>")
	)
	(segment
		(start 269.999714 -316.799722)
		(end 269.734284 -316.799722)
		(width 0.1143)
		(layer "In5.Cu")
		(net "P5E_PEX2_STN7_RX_DP<122>")
	)
	(segment
		(start 270.31188 -327.847198)
		(end 272.844514 -330.766928)
		(width 0.1651)
		(layer "In5.Cu")
		(net "P5E_PEX2_STN7_RX_DP<122>")
	)
	(segment
		(start 275.612098 -332.66634)
		(end 288.316416 -341.059262)
		(width 0.1651)
		(layer "In5.Cu")
		(net "P5E_PEX2_STN7_RX_DP<122>")
	)
	(segment
		(start 272.84807 -330.770992)
		(end 272.850102 -330.773532)
		(width 0.1651)
		(layer "In5.Cu")
		(net "P5E_PEX2_STN7_RX_DP<122>")
	)
	(segment
		(start 272.850102 -330.773532)
		(end 272.852642 -330.776326)
		(width 0.1651)
		(layer "In5.Cu")
		(net "P5E_PEX2_STN7_RX_DP<122>")
	)
	(segment
		(start 272.845784 -330.768452)
		(end 272.84807 -330.770992)
		(width 0.1651)
		(layer "In5.Cu")
		(net "P5E_PEX2_STN7_RX_DP<122>")
	)
	(segment
		(start 293.015924 -368.625374)
		(end 293.015924 -382.529334)
		(width 0.1651)
		(layer "In5.Cu")
		(net "P5E_PEX2_STN7_RX_DP<122>")
	)
	(segment
		(start 272.852642 -330.776326)
		(end 275.612098 -332.66634)
		(width 0.1651)
		(layer "In5.Cu")
		(net "P5E_PEX2_STN7_RX_DP<122>")
	)
	(segment
		(start 272.844514 -330.766928)
		(end 272.845784 -330.768452)
		(width 0.1651)
		(layer "In5.Cu")
		(net "P5E_PEX2_STN7_RX_DP<122>")
	)
	(segment
		(start 269.665704 -319.154048)
		(end 269.665704 -326.262746)
		(width 0.1651)
		(layer "In5.Cu")
		(net "P5E_PEX2_STN7_RX_DP<122>")
	)
	(segment
		(start 269.665704 -326.262746)
		(end 270.31188 -327.847198)
		(width 0.1651)
		(layer "In5.Cu")
		(net "P5E_PEX2_STN7_RX_DP<122>")
	)
	(segment
		(start 269.619984 -319.07988)
		(end 269.665704 -319.1256)
		(width 0.1143)
		(layer "In5.Cu")
		(net "P5E_PEX2_STN7_RX_DP<122>")
	)
	(segment
		(start 269.619984 -316.914022)
		(end 269.619984 -319.07988)
		(width 0.1143)
		(layer "In5.Cu")
		(net "P5E_PEX2_STN7_RX_DP<122>")
	)
	(segment
		(start 131.379468 -345.465146)
		(end 131.084828 -345.170506)
		(width 0.13462)
		(layer "F.Cu")
		(net "P5E_PEX1_STN5_TX_C_DN<88>")
	)
	(segment
		(start 131.084828 -344.539062)
		(end 131.404868 -344.219022)
		(width 0.13462)
		(layer "F.Cu")
		(net "P5E_PEX1_STN5_TX_C_DN<88>")
	)
	(segment
		(start 131.084828 -345.170506)
		(end 131.084828 -344.539062)
		(width 0.13462)
		(layer "F.Cu")
		(net "P5E_PEX1_STN5_TX_C_DN<88>")
	)
	(segment
		(start 131.088638 -345.755976)
		(end 131.379468 -345.465146)
		(width 0.1651)
		(layer "In13.Cu")
		(net "P5E_PEX1_STN5_TX_C_DN<88>")
	)
	(segment
		(start 117.066822 -378.389642)
		(end 117.066822 -369.68938)
		(width 0.1651)
		(layer "In13.Cu")
		(net "P5E_PEX1_STN5_TX_C_DN<88>")
	)
	(segment
		(start 131.088638 -346.537026)
		(end 131.088638 -345.755976)
		(width 0.1651)
		(layer "In13.Cu")
		(net "P5E_PEX1_STN5_TX_C_DN<88>")
	)
	(segment
		(start 117.066822 -369.68938)
		(end 117.067076 -369.689126)
		(width 0.1651)
		(layer "In13.Cu")
		(net "P5E_PEX1_STN5_TX_C_DN<88>")
	)
	(segment
		(start 115.910106 -379.20803)
		(end 116.037106 -379.08103)
		(width 0.1651)
		(layer "In13.Cu")
		(net "P5E_PEX1_STN5_TX_C_DN<88>")
	)
	(segment
		(start 129.534158 -348.091506)
		(end 131.088638 -346.537026)
		(width 0.1651)
		(layer "In13.Cu")
		(net "P5E_PEX1_STN5_TX_C_DN<88>")
	)
	(segment
		(start 117.067076 -369.689126)
		(end 117.529356 -368.696494)
		(width 0.1651)
		(layer "In13.Cu")
		(net "P5E_PEX1_STN5_TX_C_DN<88>")
	)
	(segment
		(start 129.178812 -358.917748)
		(end 129.534158 -358.15524)
		(width 0.1651)
		(layer "In13.Cu")
		(net "P5E_PEX1_STN5_TX_C_DN<88>")
	)
	(segment
		(start 117.529356 -368.696494)
		(end 129.178812 -358.917748)
		(width 0.1651)
		(layer "In13.Cu")
		(net "P5E_PEX1_STN5_TX_C_DN<88>")
	)
	(segment
		(start 116.037106 -379.08103)
		(end 116.375434 -379.08103)
		(width 0.1651)
		(layer "In13.Cu")
		(net "P5E_PEX1_STN5_TX_C_DN<88>")
	)
	(segment
		(start 116.375434 -379.08103)
		(end 117.066822 -378.389642)
		(width 0.1651)
		(layer "In13.Cu")
		(net "P5E_PEX1_STN5_TX_C_DN<88>")
	)
	(segment
		(start 129.534158 -358.15524)
		(end 129.534158 -348.091506)
		(width 0.1651)
		(layer "In13.Cu")
		(net "P5E_PEX1_STN5_TX_C_DN<88>")
	)
	(segment
		(start 115.910106 -379.590046)
		(end 115.910106 -379.20803)
		(width 0.1651)
		(layer "In13.Cu")
		(net "P5E_PEX1_STN5_TX_C_DN<88>")
	)
	(segment
		(start 165.864032 -348.88043)
		(end 166.158672 -348.58579)
		(width 0.13462)
		(layer "F.Cu")
		(net "P5E_PEX1_STN7_TX_DN<114>")
	)
	(segment
		(start 166.184072 -349.831914)
		(end 165.864032 -349.511874)
		(width 0.13462)
		(layer "F.Cu")
		(net "P5E_PEX1_STN7_TX_DN<114>")
	)
	(segment
		(start 165.864032 -349.511874)
		(end 165.864032 -348.88043)
		(width 0.13462)
		(layer "F.Cu")
		(net "P5E_PEX1_STN7_TX_DN<114>")
	)
	(segment
		(start 138.29792 -311.555638)
		(end 138.457686 -311.53227)
		(width 0.1651)
		(layer "In11.Cu")
		(net "P5E_PEX1_STN7_TX_DN<114>")
	)
	(segment
		(start 140.184632 -309.017416)
		(end 140.480288 -308.619906)
		(width 0.1651)
		(layer "In11.Cu")
		(net "P5E_PEX1_STN7_TX_DN<114>")
	)
	(segment
		(start 134.825486 -319.705482)
		(end 135.202422 -317.806324)
		(width 0.1651)
		(layer "In11.Cu")
		(net "P5E_PEX1_STN7_TX_DN<114>")
	)
	(segment
		(start 141.207236 -307.64099)
		(end 141.367256 -307.617368)
		(width 0.1651)
		(layer "In11.Cu")
		(net "P5E_PEX1_STN7_TX_DN<114>")
	)
	(segment
		(start 139.457176 -309.996078)
		(end 139.752832 -309.598314)
		(width 0.1651)
		(layer "In11.Cu")
		(net "P5E_PEX1_STN7_TX_DN<114>")
	)
	(segment
		(start 138.72972 -310.974486)
		(end 138.729974 -310.97474)
		(width 0.1651)
		(layer "In11.Cu")
		(net "P5E_PEX1_STN7_TX_DN<114>")
	)
	(segment
		(start 140.6398 -308.59603)
		(end 140.935456 -308.198266)
		(width 0.1651)
		(layer "In11.Cu")
		(net "P5E_PEX1_STN7_TX_DN<114>")
	)
	(segment
		(start 138.457686 -311.53227)
		(end 138.753342 -311.134252)
		(width 0.1651)
		(layer "In11.Cu")
		(net "P5E_PEX1_STN7_TX_DN<114>")
	)
	(segment
		(start 140.184378 -309.017162)
		(end 140.184632 -309.017416)
		(width 0.1651)
		(layer "In11.Cu")
		(net "P5E_PEX1_STN7_TX_DN<114>")
	)
	(segment
		(start 135.701786 -325.586852)
		(end 134.825486 -322.696332)
		(width 0.1651)
		(layer "In11.Cu")
		(net "P5E_PEX1_STN7_TX_DN<114>")
	)
	(segment
		(start 140.208 -309.176928)
		(end 140.184378 -309.017162)
		(width 0.1651)
		(layer "In11.Cu")
		(net "P5E_PEX1_STN7_TX_DN<114>")
	)
	(segment
		(start 138.753342 -311.134252)
		(end 138.72972 -310.974486)
		(width 0.1651)
		(layer "In11.Cu")
		(net "P5E_PEX1_STN7_TX_DN<114>")
	)
	(segment
		(start 139.025122 -310.576976)
		(end 139.185142 -310.553354)
		(width 0.1651)
		(layer "In11.Cu")
		(net "P5E_PEX1_STN7_TX_DN<114>")
	)
	(segment
		(start 151.51989 -303.165764)
		(end 151.541988 -303.165764)
		(width 0.1143)
		(layer "In11.Cu")
		(net "P5E_PEX1_STN7_TX_DN<114>")
	)
	(segment
		(start 138.002518 -311.953148)
		(end 138.002772 -311.953148)
		(width 0.1651)
		(layer "In11.Cu")
		(net "P5E_PEX1_STN7_TX_DN<114>")
	)
	(segment
		(start 138.729974 -310.97474)
		(end 139.02563 -310.57723)
		(width 0.1651)
		(layer "In11.Cu")
		(net "P5E_PEX1_STN7_TX_DN<114>")
	)
	(segment
		(start 140.911834 -308.0385)
		(end 141.207236 -307.64099)
		(width 0.1651)
		(layer "In11.Cu")
		(net "P5E_PEX1_STN7_TX_DN<114>")
	)
	(segment
		(start 151.587708 -303.120044)
		(end 157.914594 -303.120044)
		(width 0.1143)
		(layer "In11.Cu")
		(net "P5E_PEX1_STN7_TX_DN<114>")
	)
	(segment
		(start 142.856712 -305.421792)
		(end 144.06372 -304.214784)
		(width 0.1651)
		(layer "In11.Cu")
		(net "P5E_PEX1_STN7_TX_DN<114>")
	)
	(segment
		(start 139.02563 -310.57723)
		(end 139.025122 -310.576976)
		(width 0.1651)
		(layer "In11.Cu")
		(net "P5E_PEX1_STN7_TX_DN<114>")
	)
	(segment
		(start 134.825486 -322.696332)
		(end 134.825486 -319.705482)
		(width 0.1651)
		(layer "In11.Cu")
		(net "P5E_PEX1_STN7_TX_DN<114>")
	)
	(segment
		(start 142.094712 -306.638706)
		(end 142.390368 -306.240942)
		(width 0.1651)
		(layer "In11.Cu")
		(net "P5E_PEX1_STN7_TX_DN<114>")
	)
	(segment
		(start 165.305232 -346.908882)
		(end 140.727684 -331.197204)
		(width 0.1651)
		(layer "In11.Cu")
		(net "P5E_PEX1_STN7_TX_DN<114>")
	)
	(segment
		(start 139.752578 -309.598314)
		(end 139.912344 -309.574692)
		(width 0.1651)
		(layer "In11.Cu")
		(net "P5E_PEX1_STN7_TX_DN<114>")
	)
	(segment
		(start 157.914594 -303.120044)
		(end 158.079694 -303.285144)
		(width 0.1143)
		(layer "In11.Cu")
		(net "P5E_PEX1_STN7_TX_DN<114>")
	)
	(segment
		(start 139.912344 -309.574692)
		(end 140.208 -309.176928)
		(width 0.1651)
		(layer "In11.Cu")
		(net "P5E_PEX1_STN7_TX_DN<114>")
	)
	(segment
		(start 165.867842 -348.29496)
		(end 165.867842 -347.716602)
		(width 0.1651)
		(layer "In11.Cu")
		(net "P5E_PEX1_STN7_TX_DN<114>")
	)
	(segment
		(start 138.002772 -311.953148)
		(end 138.298174 -311.555892)
		(width 0.1651)
		(layer "In11.Cu")
		(net "P5E_PEX1_STN7_TX_DN<114>")
	)
	(segment
		(start 151.541988 -303.165764)
		(end 151.587708 -303.120044)
		(width 0.1143)
		(layer "In11.Cu")
		(net "P5E_PEX1_STN7_TX_DN<114>")
	)
	(segment
		(start 140.727684 -331.197204)
		(end 137.744454 -328.64171)
		(width 0.1651)
		(layer "In11.Cu")
		(net "P5E_PEX1_STN7_TX_DN<114>")
	)
	(segment
		(start 138.298174 -311.555892)
		(end 138.29792 -311.555638)
		(width 0.1651)
		(layer "In11.Cu")
		(net "P5E_PEX1_STN7_TX_DN<114>")
	)
	(segment
		(start 166.158672 -348.58579)
		(end 165.867842 -348.29496)
		(width 0.1651)
		(layer "In11.Cu")
		(net "P5E_PEX1_STN7_TX_DN<114>")
	)
	(segment
		(start 141.63929 -307.059838)
		(end 141.934692 -306.662328)
		(width 0.1651)
		(layer "In11.Cu")
		(net "P5E_PEX1_STN7_TX_DN<114>")
	)
	(segment
		(start 137.570718 -312.5343)
		(end 137.730484 -312.510932)
		(width 0.1651)
		(layer "In11.Cu")
		(net "P5E_PEX1_STN7_TX_DN<114>")
	)
	(segment
		(start 140.935456 -308.198266)
		(end 140.911834 -308.0385)
		(width 0.1651)
		(layer "In11.Cu")
		(net "P5E_PEX1_STN7_TX_DN<114>")
	)
	(segment
		(start 141.662912 -307.219604)
		(end 141.63929 -307.059838)
		(width 0.1651)
		(layer "In11.Cu")
		(net "P5E_PEX1_STN7_TX_DN<114>")
	)
	(segment
		(start 142.366746 -306.080922)
		(end 142.856712 -305.421792)
		(width 0.1651)
		(layer "In11.Cu")
		(net "P5E_PEX1_STN7_TX_DN<114>")
	)
	(segment
		(start 139.185142 -310.553354)
		(end 139.480798 -310.15559)
		(width 0.1651)
		(layer "In11.Cu")
		(net "P5E_PEX1_STN7_TX_DN<114>")
	)
	(segment
		(start 139.752832 -309.598314)
		(end 139.752578 -309.598314)
		(width 0.1651)
		(layer "In11.Cu")
		(net "P5E_PEX1_STN7_TX_DN<114>")
	)
	(segment
		(start 138.02614 -312.112914)
		(end 138.002518 -311.953148)
		(width 0.1651)
		(layer "In11.Cu")
		(net "P5E_PEX1_STN7_TX_DN<114>")
	)
	(segment
		(start 158.079694 -303.285144)
		(end 158.079694 -303.410874)
		(width 0.1143)
		(layer "In11.Cu")
		(net "P5E_PEX1_STN7_TX_DN<114>")
	)
	(segment
		(start 144.06372 -304.214784)
		(end 146.5961 -303.165764)
		(width 0.1651)
		(layer "In11.Cu")
		(net "P5E_PEX1_STN7_TX_DN<114>")
	)
	(segment
		(start 137.157968 -313.089798)
		(end 137.570718 -312.5343)
		(width 0.1651)
		(layer "In11.Cu")
		(net "P5E_PEX1_STN7_TX_DN<114>")
	)
	(segment
		(start 140.480288 -308.619906)
		(end 140.47978 -308.619652)
		(width 0.1651)
		(layer "In11.Cu")
		(net "P5E_PEX1_STN7_TX_DN<114>")
	)
	(segment
		(start 135.202422 -317.806324)
		(end 137.157968 -313.089798)
		(width 0.1651)
		(layer "In11.Cu")
		(net "P5E_PEX1_STN7_TX_DN<114>")
	)
	(segment
		(start 141.367256 -307.617368)
		(end 141.662912 -307.219604)
		(width 0.1651)
		(layer "In11.Cu")
		(net "P5E_PEX1_STN7_TX_DN<114>")
	)
	(segment
		(start 141.934692 -306.662328)
		(end 142.094712 -306.638706)
		(width 0.1651)
		(layer "In11.Cu")
		(net "P5E_PEX1_STN7_TX_DN<114>")
	)
	(segment
		(start 137.744454 -328.64171)
		(end 135.701786 -325.586852)
		(width 0.1651)
		(layer "In11.Cu")
		(net "P5E_PEX1_STN7_TX_DN<114>")
	)
	(segment
		(start 146.5961 -303.165764)
		(end 151.51989 -303.165764)
		(width 0.1651)
		(layer "In11.Cu")
		(net "P5E_PEX1_STN7_TX_DN<114>")
	)
	(segment
		(start 165.867842 -347.716602)
		(end 165.305232 -346.908882)
		(width 0.1651)
		(layer "In11.Cu")
		(net "P5E_PEX1_STN7_TX_DN<114>")
	)
	(segment
		(start 137.730484 -312.510932)
		(end 138.02614 -312.112914)
		(width 0.1651)
		(layer "In11.Cu")
		(net "P5E_PEX1_STN7_TX_DN<114>")
	)
	(segment
		(start 140.47978 -308.619652)
		(end 140.6398 -308.59603)
		(width 0.1651)
		(layer "In11.Cu")
		(net "P5E_PEX1_STN7_TX_DN<114>")
	)
	(segment
		(start 142.390368 -306.240942)
		(end 142.366746 -306.080922)
		(width 0.1651)
		(layer "In11.Cu")
		(net "P5E_PEX1_STN7_TX_DN<114>")
	)
	(segment
		(start 139.480798 -310.15559)
		(end 139.457176 -309.996078)
		(width 0.1651)
		(layer "In11.Cu")
		(net "P5E_PEX1_STN7_TX_DN<114>")
	)
	(segment
		(start 158.079694 -303.410874)
		(end 157.990794 -303.499774)
		(width 0.1143)
		(layer "In11.Cu")
		(net "P5E_PEX1_STN7_TX_DN<114>")
	)
	(segment
		(start 157.990794 -303.499774)
		(end 157.699964 -303.499774)
		(width 0.1143)
		(layer "In11.Cu")
		(net "P5E_PEX1_STN7_TX_DN<114>")
	)
	(segment
		(start 316.374272 -131.712208)
		(end 316.0776 -132.00888)
		(width 0.13462)
		(layer "F.Cu")
		(net "P5E_PEX2_STN0_TX_DN<5>")
	)
	(segment
		(start 315.45022 -132.00888)
		(end 315.128148 -131.686808)
		(width 0.13462)
		(layer "F.Cu")
		(net "P5E_PEX2_STN0_TX_DN<5>")
	)
	(segment
		(start 316.0776 -132.00888)
		(end 315.45022 -132.00888)
		(width 0.13462)
		(layer "F.Cu")
		(net "P5E_PEX2_STN0_TX_DN<5>")
	)
	(segment
		(start 323.607938 -144.627092)
		(end 323.99732 -145.016474)
		(width 0.1651)
		(layer "In9.Cu")
		(net "P5E_PEX2_STN0_TX_DN<5>")
	)
	(segment
		(start 319.093342 -133.728206)
		(end 323.607938 -144.627092)
		(width 0.1651)
		(layer "In9.Cu")
		(net "P5E_PEX2_STN0_TX_DN<5>")
	)
	(segment
		(start 318.889634 -282.44419)
		(end 317.02756 -283.215588)
		(width 0.1651)
		(layer "In9.Cu")
		(net "P5E_PEX2_STN0_TX_DN<5>")
	)
	(segment
		(start 316.019434 -283.169868)
		(end 307.723794 -283.169868)
		(width 0.1143)
		(layer "In9.Cu")
		(net "P5E_PEX2_STN0_TX_DN<5>")
	)
	(segment
		(start 327.023476 -266.71778)
		(end 327.725278 -268.412468)
		(width 0.1651)
		(layer "In9.Cu")
		(net "P5E_PEX2_STN0_TX_DN<5>")
	)
	(segment
		(start 327.12533 -274.208494)
		(end 318.889634 -282.44419)
		(width 0.1651)
		(layer "In9.Cu")
		(net "P5E_PEX2_STN0_TX_DN<5>")
	)
	(segment
		(start 327.725278 -268.412468)
		(end 328.039476 -272.00225)
		(width 0.1651)
		(layer "In9.Cu")
		(net "P5E_PEX2_STN0_TX_DN<5>")
	)
	(segment
		(start 313.98591 -221.652592)
		(end 316.553088 -251.048012)
		(width 0.1651)
		(layer "In9.Cu")
		(net "P5E_PEX2_STN0_TX_DN<5>")
	)
	(segment
		(start 307.619908 -283.273754)
		(end 307.619908 -283.435552)
		(width 0.1143)
		(layer "In9.Cu")
		(net "P5E_PEX2_STN0_TX_DN<5>")
	)
	(segment
		(start 323.99732 -145.016474)
		(end 327.532746 -153.55189)
		(width 0.1651)
		(layer "In9.Cu")
		(net "P5E_PEX2_STN0_TX_DN<5>")
	)
	(segment
		(start 317.762636 -178.482244)
		(end 313.98591 -221.652592)
		(width 0.1651)
		(layer "In9.Cu")
		(net "P5E_PEX2_STN0_TX_DN<5>")
	)
	(segment
		(start 316.093602 -283.215588)
		(end 316.065154 -283.215588)
		(width 0.1143)
		(layer "In9.Cu")
		(net "P5E_PEX2_STN0_TX_DN<5>")
	)
	(segment
		(start 307.619908 -283.435552)
		(end 307.734208 -283.549852)
		(width 0.1143)
		(layer "In9.Cu")
		(net "P5E_PEX2_STN0_TX_DN<5>")
	)
	(segment
		(start 328.039476 -272.00225)
		(end 327.12533 -274.208494)
		(width 0.1651)
		(layer "In9.Cu")
		(net "P5E_PEX2_STN0_TX_DN<5>")
	)
	(segment
		(start 317.368174 -132.003038)
		(end 319.093342 -133.728206)
		(width 0.1651)
		(layer "In9.Cu")
		(net "P5E_PEX2_STN0_TX_DN<5>")
	)
	(segment
		(start 318.877188 -174.326042)
		(end 317.762636 -178.482244)
		(width 0.1651)
		(layer "In9.Cu")
		(net "P5E_PEX2_STN0_TX_DN<5>")
	)
	(segment
		(start 316.665102 -132.003038)
		(end 317.368174 -132.003038)
		(width 0.1651)
		(layer "In9.Cu")
		(net "P5E_PEX2_STN0_TX_DN<5>")
	)
	(segment
		(start 307.723794 -283.169868)
		(end 307.619908 -283.273754)
		(width 0.1143)
		(layer "In9.Cu")
		(net "P5E_PEX2_STN0_TX_DN<5>")
	)
	(segment
		(start 327.532746 -153.55189)
		(end 327.532746 -159.328104)
		(width 0.1651)
		(layer "In9.Cu")
		(net "P5E_PEX2_STN0_TX_DN<5>")
	)
	(segment
		(start 316.374272 -131.712208)
		(end 316.665102 -132.003038)
		(width 0.1651)
		(layer "In9.Cu")
		(net "P5E_PEX2_STN0_TX_DN<5>")
	)
	(segment
		(start 327.532746 -159.328104)
		(end 318.877188 -174.326042)
		(width 0.1651)
		(layer "In9.Cu")
		(net "P5E_PEX2_STN0_TX_DN<5>")
	)
	(segment
		(start 307.734208 -283.549852)
		(end 307.999892 -283.549852)
		(width 0.1143)
		(layer "In9.Cu")
		(net "P5E_PEX2_STN0_TX_DN<5>")
	)
	(segment
		(start 316.553088 -251.048012)
		(end 327.023476 -266.71778)
		(width 0.1651)
		(layer "In9.Cu")
		(net "P5E_PEX2_STN0_TX_DN<5>")
	)
	(segment
		(start 316.065154 -283.215588)
		(end 316.019434 -283.169868)
		(width 0.1143)
		(layer "In9.Cu")
		(net "P5E_PEX2_STN0_TX_DN<5>")
	)
	(segment
		(start 317.02756 -283.215588)
		(end 316.093602 -283.215588)
		(width 0.1651)
		(layer "In9.Cu")
		(net "P5E_PEX2_STN0_TX_DN<5>")
	)
	(segment
		(start 344.481404 -355.978206)
		(end 344.161364 -355.658166)
		(width 0.13462)
		(layer "F.Cu")
		(net "P5E_PEX2_STN6_TX_DN<96>")
	)
	(segment
		(start 344.161364 -355.026722)
		(end 344.456004 -354.732082)
		(width 0.13462)
		(layer "F.Cu")
		(net "P5E_PEX2_STN6_TX_DN<96>")
	)
	(segment
		(start 344.161364 -355.658166)
		(end 344.161364 -355.026722)
		(width 0.13462)
		(layer "F.Cu")
		(net "P5E_PEX2_STN6_TX_DN<96>")
	)
	(segment
		(start 289.673792 -313.570112)
		(end 289.83559 -313.570112)
		(width 0.1143)
		(layer "In13.Cu")
		(net "P5E_PEX2_STN6_TX_DN<96>")
	)
	(segment
		(start 345.949016 -346.093796)
		(end 345.690698 -342.362028)
		(width 0.1651)
		(layer "In13.Cu")
		(net "P5E_PEX2_STN6_TX_DN<96>")
	)
	(segment
		(start 289.94989 -313.684412)
		(end 289.94989 -313.949842)
		(width 0.1143)
		(layer "In13.Cu")
		(net "P5E_PEX2_STN6_TX_DN<96>")
	)
	(segment
		(start 289.83559 -313.570112)
		(end 289.94989 -313.684412)
		(width 0.1143)
		(layer "In13.Cu")
		(net "P5E_PEX2_STN6_TX_DN<96>")
	)
	(segment
		(start 289.57016 -313.673744)
		(end 289.673792 -313.570112)
		(width 0.1143)
		(layer "In13.Cu")
		(net "P5E_PEX2_STN6_TX_DN<96>")
	)
	(segment
		(start 289.806126 -320.03238)
		(end 289.57016 -319.796414)
		(width 0.1143)
		(layer "In13.Cu")
		(net "P5E_PEX2_STN6_TX_DN<96>")
	)
	(segment
		(start 315.426598 -324.697598)
		(end 293.979854 -320.415666)
		(width 0.1651)
		(layer "In13.Cu")
		(net "P5E_PEX2_STN6_TX_DN<96>")
	)
	(segment
		(start 290.31692 -319.98666)
		(end 290.288472 -319.98666)
		(width 0.1143)
		(layer "In13.Cu")
		(net "P5E_PEX2_STN6_TX_DN<96>")
	)
	(segment
		(start 291.119814 -319.989708)
		(end 291.116766 -319.98666)
		(width 0.1651)
		(layer "In13.Cu")
		(net "P5E_PEX2_STN6_TX_DN<96>")
	)
	(segment
		(start 336.747104 -334.064102)
		(end 315.426598 -324.697598)
		(width 0.1651)
		(layer "In13.Cu")
		(net "P5E_PEX2_STN6_TX_DN<96>")
	)
	(segment
		(start 345.512898 -352.28403)
		(end 345.821762 -351.785936)
		(width 0.1651)
		(layer "In13.Cu")
		(net "P5E_PEX2_STN6_TX_DN<96>")
	)
	(segment
		(start 345.690698 -342.362028)
		(end 345.48445 -341.090504)
		(width 0.1651)
		(layer "In13.Cu")
		(net "P5E_PEX2_STN6_TX_DN<96>")
	)
	(segment
		(start 290.288472 -319.98666)
		(end 290.242752 -320.03238)
		(width 0.1143)
		(layer "In13.Cu")
		(net "P5E_PEX2_STN6_TX_DN<96>")
	)
	(segment
		(start 344.165174 -354.441252)
		(end 344.165174 -353.967542)
		(width 0.1651)
		(layer "In13.Cu")
		(net "P5E_PEX2_STN6_TX_DN<96>")
	)
	(segment
		(start 291.116766 -319.98666)
		(end 290.31692 -319.98666)
		(width 0.1651)
		(layer "In13.Cu")
		(net "P5E_PEX2_STN6_TX_DN<96>")
	)
	(segment
		(start 345.821762 -351.785936)
		(end 345.949016 -346.093796)
		(width 0.1651)
		(layer "In13.Cu")
		(net "P5E_PEX2_STN6_TX_DN<96>")
	)
	(segment
		(start 345.48445 -341.090504)
		(end 336.747104 -334.064102)
		(width 0.1651)
		(layer "In13.Cu")
		(net "P5E_PEX2_STN6_TX_DN<96>")
	)
	(segment
		(start 289.57016 -319.796414)
		(end 289.57016 -313.673744)
		(width 0.1143)
		(layer "In13.Cu")
		(net "P5E_PEX2_STN6_TX_DN<96>")
	)
	(segment
		(start 344.456004 -354.732082)
		(end 344.165174 -354.441252)
		(width 0.1651)
		(layer "In13.Cu")
		(net "P5E_PEX2_STN6_TX_DN<96>")
	)
	(segment
		(start 293.979854 -320.415666)
		(end 291.119814 -319.989708)
		(width 0.1651)
		(layer "In13.Cu")
		(net "P5E_PEX2_STN6_TX_DN<96>")
	)
	(segment
		(start 290.242752 -320.03238)
		(end 289.806126 -320.03238)
		(width 0.1143)
		(layer "In13.Cu")
		(net "P5E_PEX2_STN6_TX_DN<96>")
	)
	(segment
		(start 344.165174 -353.967542)
		(end 345.512898 -352.28403)
		(width 0.1651)
		(layer "In13.Cu")
		(net "P5E_PEX2_STN6_TX_DN<96>")
	)
	(segment
		(start 423.53992 -81.09966)
		(end 423.189654 -80.749394)
		(width 0.13208)
		(layer "F.Cu")
		(net "HP_NIC7_HSC_PWRGD_N")
	)
	(segment
		(start 421.992552 -80.749394)
		(end 421.9829 -80.739742)
		(width 0.13208)
		(layer "F.Cu")
		(net "HP_NIC7_HSC_PWRGD_N")
	)
	(segment
		(start 423.189654 -80.749394)
		(end 421.992552 -80.749394)
		(width 0.13208)
		(layer "F.Cu")
		(net "HP_NIC7_HSC_PWRGD_N")
	)
	(segment
		(start 423.489374 -80.449674)
		(end 424.457622 -80.449674)
		(width 0.13208)
		(layer "F.Cu")
		(net "HP_NIC7_HSC_PWRGD_N")
	)
	(segment
		(start 424.457622 -81.09966)
		(end 423.53992 -81.09966)
		(width 0.13208)
		(layer "F.Cu")
		(net "HP_NIC7_HSC_PWRGD_N")
	)
	(segment
		(start 423.189654 -80.749394)
		(end 423.489374 -80.449674)
		(width 0.13208)
		(layer "F.Cu")
		(net "HP_NIC7_HSC_PWRGD_N")
	)
	(via
		(at 423.189654 -80.749394)
		(size 0.762)
		(drill 0.381)
		(layers "F.Cu" "B.Cu")
		(net "HP_NIC7_HSC_PWRGD_N")
	)
	(segment
		(start 22.441408 -357.75773)
		(end 22.736048 -357.46309)
		(width 0.13462)
		(layer "F.Cu")
		(net "P5E_PEX0_STN7_TX_C_DP<114>")
	)
	(segment
		(start 22.736048 -356.831646)
		(end 22.416008 -356.511606)
		(width 0.13462)
		(layer "F.Cu")
		(net "P5E_PEX0_STN7_TX_C_DP<114>")
	)
	(segment
		(start 22.736048 -357.46309)
		(end 22.736048 -356.831646)
		(width 0.13462)
		(layer "F.Cu")
		(net "P5E_PEX0_STN7_TX_C_DP<114>")
	)
	(segment
		(start 33.202372 -394.687552)
		(end 33.202372 -400.490436)
		(width 0.1651)
		(layer "In7.Cu")
		(net "P5E_PEX0_STN7_TX_C_DP<114>")
	)
	(segment
		(start 21.700744 -384.950716)
		(end 23.107904 -388.078218)
		(width 0.1651)
		(layer "In7.Cu")
		(net "P5E_PEX0_STN7_TX_C_DP<114>")
	)
	(segment
		(start 32.256222 -393.849098)
		(end 32.363918 -393.849098)
		(width 0.1651)
		(layer "In7.Cu")
		(net "P5E_PEX0_STN7_TX_C_DP<114>")
	)
	(segment
		(start 32.43707 -400.899122)
		(end 32.31007 -400.772122)
		(width 0.1651)
		(layer "In7.Cu")
		(net "P5E_PEX0_STN7_TX_C_DP<114>")
	)
	(segment
		(start 32.363918 -393.849098)
		(end 33.202372 -394.687552)
		(width 0.1651)
		(layer "In7.Cu")
		(net "P5E_PEX0_STN7_TX_C_DP<114>")
	)
	(segment
		(start 33.202372 -400.490436)
		(end 32.793686 -400.899122)
		(width 0.1651)
		(layer "In7.Cu")
		(net "P5E_PEX0_STN7_TX_C_DP<114>")
	)
	(segment
		(start 25.295606 -390.26592)
		(end 31.245302 -392.730482)
		(width 0.1651)
		(layer "In7.Cu")
		(net "P5E_PEX0_STN7_TX_C_DP<114>")
	)
	(segment
		(start 31.905702 -393.390882)
		(end 31.905702 -393.498578)
		(width 0.1651)
		(layer "In7.Cu")
		(net "P5E_PEX0_STN7_TX_C_DP<114>")
	)
	(segment
		(start 32.793686 -400.899122)
		(end 32.43707 -400.899122)
		(width 0.1651)
		(layer "In7.Cu")
		(net "P5E_PEX0_STN7_TX_C_DP<114>")
	)
	(segment
		(start 31.245302 -392.730482)
		(end 31.905702 -393.390882)
		(width 0.1651)
		(layer "In7.Cu")
		(net "P5E_PEX0_STN7_TX_C_DP<114>")
	)
	(segment
		(start 21.565108 -364.924086)
		(end 20.900644 -371.668294)
		(width 0.1651)
		(layer "In7.Cu")
		(net "P5E_PEX0_STN7_TX_C_DP<114>")
	)
	(segment
		(start 20.900644 -371.668294)
		(end 21.700744 -384.950716)
		(width 0.1651)
		(layer "In7.Cu")
		(net "P5E_PEX0_STN7_TX_C_DP<114>")
	)
	(segment
		(start 22.732238 -359.056686)
		(end 21.565108 -364.924086)
		(width 0.1651)
		(layer "In7.Cu")
		(net "P5E_PEX0_STN7_TX_C_DP<114>")
	)
	(segment
		(start 31.905702 -393.498578)
		(end 32.256222 -393.849098)
		(width 0.1651)
		(layer "In7.Cu")
		(net "P5E_PEX0_STN7_TX_C_DP<114>")
	)
	(segment
		(start 32.31007 -400.772122)
		(end 32.31007 -400.390106)
		(width 0.1651)
		(layer "In7.Cu")
		(net "P5E_PEX0_STN7_TX_C_DP<114>")
	)
	(segment
		(start 22.732238 -358.04856)
		(end 22.732238 -359.056686)
		(width 0.1651)
		(layer "In7.Cu")
		(net "P5E_PEX0_STN7_TX_C_DP<114>")
	)
	(segment
		(start 23.107904 -388.078218)
		(end 25.295606 -390.26592)
		(width 0.1651)
		(layer "In7.Cu")
		(net "P5E_PEX0_STN7_TX_C_DP<114>")
	)
	(segment
		(start 22.441408 -357.75773)
		(end 22.732238 -358.04856)
		(width 0.1651)
		(layer "In7.Cu")
		(net "P5E_PEX0_STN7_TX_C_DP<114>")
	)
	(segment
		(start 169.293032 -343.685622)
		(end 168.972992 -343.365582)
		(width 0.13462)
		(layer "F.Cu")
		(net "P5E_PEX1_STN7_TX_DN<115>")
	)
	(segment
		(start 168.972992 -343.365582)
		(end 168.972992 -342.734138)
		(width 0.13462)
		(layer "F.Cu")
		(net "P5E_PEX1_STN7_TX_DN<115>")
	)
	(segment
		(start 168.972992 -342.734138)
		(end 169.267632 -342.439498)
		(width 0.13462)
		(layer "F.Cu")
		(net "P5E_PEX1_STN7_TX_DN<115>")
	)
	(segment
		(start 138.911076 -312.7502)
		(end 139.206732 -312.352436)
		(width 0.1651)
		(layer "In11.Cu")
		(net "P5E_PEX1_STN7_TX_DN<115>")
	)
	(segment
		(start 147.57527 -304.115724)
		(end 151.55672 -304.115724)
		(width 0.1651)
		(layer "In11.Cu")
		(net "P5E_PEX1_STN7_TX_DN<115>")
	)
	(segment
		(start 135.783574 -319.81902)
		(end 136.129522 -318.075818)
		(width 0.1651)
		(layer "In11.Cu")
		(net "P5E_PEX1_STN7_TX_DN<115>")
	)
	(segment
		(start 151.55672 -304.115724)
		(end 151.578818 -304.115724)
		(width 0.1143)
		(layer "In11.Cu")
		(net "P5E_PEX1_STN7_TX_DN<115>")
	)
	(segment
		(start 140.365734 -310.792876)
		(end 140.66139 -310.395112)
		(width 0.1651)
		(layer "In11.Cu")
		(net "P5E_PEX1_STN7_TX_DN<115>")
	)
	(segment
		(start 139.910312 -311.214008)
		(end 140.205714 -310.816498)
		(width 0.1651)
		(layer "In11.Cu")
		(net "P5E_PEX1_STN7_TX_DN<115>")
	)
	(segment
		(start 140.205714 -310.816498)
		(end 140.365734 -310.792876)
		(width 0.1651)
		(layer "In11.Cu")
		(net "P5E_PEX1_STN7_TX_DN<115>")
	)
	(segment
		(start 138.75131 -312.773822)
		(end 138.911076 -312.7502)
		(width 0.1651)
		(layer "In11.Cu")
		(net "P5E_PEX1_STN7_TX_DN<115>")
	)
	(segment
		(start 149.046184 -333.884778)
		(end 148.97862 -333.737458)
		(width 0.1651)
		(layer "In11.Cu")
		(net "P5E_PEX1_STN7_TX_DN<115>")
	)
	(segment
		(start 146.313144 -332.752192)
		(end 146.256502 -332.600554)
		(width 0.1651)
		(layer "In11.Cu")
		(net "P5E_PEX1_STN7_TX_DN<115>")
	)
	(segment
		(start 149.046184 -333.884524)
		(end 149.046184 -333.884778)
		(width 0.1651)
		(layer "In11.Cu")
		(net "P5E_PEX1_STN7_TX_DN<115>")
	)
	(segment
		(start 136.5885 -325.18604)
		(end 135.783574 -322.530978)
		(width 0.1651)
		(layer "In11.Cu")
		(net "P5E_PEX1_STN7_TX_DN<115>")
	)
	(segment
		(start 139.206732 -312.352436)
		(end 139.18311 -312.192924)
		(width 0.1651)
		(layer "In11.Cu")
		(net "P5E_PEX1_STN7_TX_DN<115>")
	)
	(segment
		(start 143.832326 -331.619352)
		(end 139.324334 -328.69632)
		(width 0.1651)
		(layer "In11.Cu")
		(net "P5E_PEX1_STN7_TX_DN<115>")
	)
	(segment
		(start 145.805906 -332.394814)
		(end 145.654268 -332.451202)
		(width 0.1651)
		(layer "In11.Cu")
		(net "P5E_PEX1_STN7_TX_DN<115>")
	)
	(segment
		(start 168.740582 -341.186516)
		(end 149.046184 -333.884524)
		(width 0.1651)
		(layer "In11.Cu")
		(net "P5E_PEX1_STN7_TX_DN<115>")
	)
	(segment
		(start 151.624538 -304.070004)
		(end 159.814514 -304.070004)
		(width 0.1143)
		(layer "In11.Cu")
		(net "P5E_PEX1_STN7_TX_DN<115>")
	)
	(segment
		(start 139.638278 -311.771538)
		(end 139.933934 -311.373774)
		(width 0.1651)
		(layer "In11.Cu")
		(net "P5E_PEX1_STN7_TX_DN<115>")
	)
	(segment
		(start 159.979614 -304.360834)
		(end 159.890714 -304.449734)
		(width 0.1143)
		(layer "In11.Cu")
		(net "P5E_PEX1_STN7_TX_DN<115>")
	)
	(segment
		(start 147.701762 -333.386176)
		(end 146.313144 -332.752192)
		(width 0.1651)
		(layer "In11.Cu")
		(net "P5E_PEX1_STN7_TX_DN<115>")
	)
	(segment
		(start 140.66139 -310.395112)
		(end 140.637768 -310.235346)
		(width 0.1651)
		(layer "In11.Cu")
		(net "P5E_PEX1_STN7_TX_DN<115>")
	)
	(segment
		(start 159.814514 -304.070004)
		(end 159.979614 -304.235104)
		(width 0.1143)
		(layer "In11.Cu")
		(net "P5E_PEX1_STN7_TX_DN<115>")
	)
	(segment
		(start 146.256502 -332.600554)
		(end 145.805906 -332.394814)
		(width 0.1651)
		(layer "In11.Cu")
		(net "P5E_PEX1_STN7_TX_DN<115>")
	)
	(segment
		(start 139.933934 -311.373774)
		(end 139.910312 -311.214008)
		(width 0.1651)
		(layer "In11.Cu")
		(net "P5E_PEX1_STN7_TX_DN<115>")
	)
	(segment
		(start 169.267632 -342.439498)
		(end 168.976802 -342.148668)
		(width 0.1651)
		(layer "In11.Cu")
		(net "P5E_PEX1_STN7_TX_DN<115>")
	)
	(segment
		(start 144.696434 -331.888338)
		(end 144.54505 -331.944726)
		(width 0.1651)
		(layer "In11.Cu")
		(net "P5E_PEX1_STN7_TX_DN<115>")
	)
	(segment
		(start 148.97862 -333.737458)
		(end 148.514054 -333.565246)
		(width 0.1651)
		(layer "In11.Cu")
		(net "P5E_PEX1_STN7_TX_DN<115>")
	)
	(segment
		(start 139.324334 -328.69632)
		(end 138.414506 -327.916794)
		(width 0.1651)
		(layer "In11.Cu")
		(net "P5E_PEX1_STN7_TX_DN<115>")
	)
	(segment
		(start 145.147284 -332.094078)
		(end 144.696434 -331.888338)
		(width 0.1651)
		(layer "In11.Cu")
		(net "P5E_PEX1_STN7_TX_DN<115>")
	)
	(segment
		(start 168.740836 -341.186516)
		(end 168.740582 -341.186516)
		(width 0.1651)
		(layer "In11.Cu")
		(net "P5E_PEX1_STN7_TX_DN<115>")
	)
	(segment
		(start 141.660626 -308.859174)
		(end 145.576036 -304.943764)
		(width 0.1651)
		(layer "In11.Cu")
		(net "P5E_PEX1_STN7_TX_DN<115>")
	)
	(segment
		(start 135.783574 -322.530978)
		(end 135.783574 -319.81902)
		(width 0.1651)
		(layer "In11.Cu")
		(net "P5E_PEX1_STN7_TX_DN<115>")
	)
	(segment
		(start 140.637768 -310.235346)
		(end 140.93317 -309.837836)
		(width 0.1651)
		(layer "In11.Cu")
		(net "P5E_PEX1_STN7_TX_DN<115>")
	)
	(segment
		(start 139.478766 -311.79516)
		(end 139.478512 -311.79516)
		(width 0.1651)
		(layer "In11.Cu")
		(net "P5E_PEX1_STN7_TX_DN<115>")
	)
	(segment
		(start 138.414506 -327.916794)
		(end 136.5885 -325.18604)
		(width 0.1651)
		(layer "In11.Cu")
		(net "P5E_PEX1_STN7_TX_DN<115>")
	)
	(segment
		(start 145.203926 -332.245716)
		(end 145.147284 -332.094078)
		(width 0.1651)
		(layer "In11.Cu")
		(net "P5E_PEX1_STN7_TX_DN<115>")
	)
	(segment
		(start 141.365224 -309.256684)
		(end 141.660626 -308.859174)
		(width 0.1651)
		(layer "In11.Cu")
		(net "P5E_PEX1_STN7_TX_DN<115>")
	)
	(segment
		(start 159.979614 -304.235104)
		(end 159.979614 -304.360834)
		(width 0.1143)
		(layer "In11.Cu")
		(net "P5E_PEX1_STN7_TX_DN<115>")
	)
	(segment
		(start 139.478512 -311.79516)
		(end 139.638278 -311.771538)
		(width 0.1651)
		(layer "In11.Cu")
		(net "P5E_PEX1_STN7_TX_DN<115>")
	)
	(segment
		(start 141.388846 -309.41645)
		(end 141.365224 -309.256684)
		(width 0.1651)
		(layer "In11.Cu")
		(net "P5E_PEX1_STN7_TX_DN<115>")
	)
	(segment
		(start 151.578818 -304.115724)
		(end 151.624538 -304.070004)
		(width 0.1143)
		(layer "In11.Cu")
		(net "P5E_PEX1_STN7_TX_DN<115>")
	)
	(segment
		(start 136.129522 -318.075818)
		(end 137.793222 -314.063126)
		(width 0.1651)
		(layer "In11.Cu")
		(net "P5E_PEX1_STN7_TX_DN<115>")
	)
	(segment
		(start 148.366988 -333.63281)
		(end 147.701762 -333.386176)
		(width 0.1651)
		(layer "In11.Cu")
		(net "P5E_PEX1_STN7_TX_DN<115>")
	)
	(segment
		(start 148.514054 -333.565246)
		(end 148.366988 -333.63281)
		(width 0.1651)
		(layer "In11.Cu")
		(net "P5E_PEX1_STN7_TX_DN<115>")
	)
	(segment
		(start 139.18311 -312.192924)
		(end 139.478766 -311.79516)
		(width 0.1651)
		(layer "In11.Cu")
		(net "P5E_PEX1_STN7_TX_DN<115>")
	)
	(segment
		(start 140.93317 -309.837836)
		(end 141.09319 -309.814214)
		(width 0.1651)
		(layer "In11.Cu")
		(net "P5E_PEX1_STN7_TX_DN<115>")
	)
	(segment
		(start 141.09319 -309.814214)
		(end 141.388846 -309.41645)
		(width 0.1651)
		(layer "In11.Cu")
		(net "P5E_PEX1_STN7_TX_DN<115>")
	)
	(segment
		(start 144.54505 -331.944726)
		(end 143.832326 -331.619352)
		(width 0.1651)
		(layer "In11.Cu")
		(net "P5E_PEX1_STN7_TX_DN<115>")
	)
	(segment
		(start 145.654268 -332.451202)
		(end 145.203926 -332.245716)
		(width 0.1651)
		(layer "In11.Cu")
		(net "P5E_PEX1_STN7_TX_DN<115>")
	)
	(segment
		(start 145.576036 -304.943764)
		(end 147.57527 -304.115724)
		(width 0.1651)
		(layer "In11.Cu")
		(net "P5E_PEX1_STN7_TX_DN<115>")
	)
	(segment
		(start 168.976802 -342.148668)
		(end 168.976802 -341.52586)
		(width 0.1651)
		(layer "In11.Cu")
		(net "P5E_PEX1_STN7_TX_DN<115>")
	)
	(segment
		(start 168.976802 -341.52586)
		(end 168.740836 -341.186516)
		(width 0.1651)
		(layer "In11.Cu")
		(net "P5E_PEX1_STN7_TX_DN<115>")
	)
	(segment
		(start 137.793222 -314.063126)
		(end 138.75131 -312.773822)
		(width 0.1651)
		(layer "In11.Cu")
		(net "P5E_PEX1_STN7_TX_DN<115>")
	)
	(segment
		(start 159.890714 -304.449734)
		(end 159.599884 -304.449734)
		(width 0.1143)
		(layer "In11.Cu")
		(net "P5E_PEX1_STN7_TX_DN<115>")
	)
	(segment
		(start 267.6271 -112.22228)
		(end 268.244828 -112.22228)
		(width 0.13462)
		(layer "F.Cu")
		(net "P5E_PEX2_STN1_TX_DN<23>")
	)
	(segment
		(start 268.244828 -112.22228)
		(end 268.571726 -111.895382)
		(width 0.13462)
		(layer "F.Cu")
		(net "P5E_PEX2_STN1_TX_DN<23>")
	)
	(segment
		(start 267.325602 -111.920782)
		(end 267.6271 -112.22228)
		(width 0.13462)
		(layer "F.Cu")
		(net "P5E_PEX2_STN1_TX_DN<23>")
	)
	(segment
		(start 298.499784 -280.434288)
		(end 298.385484 -280.319988)
		(width 0.1143)
		(layer "In9.Cu")
		(net "P5E_PEX2_STN1_TX_DN<23>")
	)
	(segment
		(start 298.499784 -280.699718)
		(end 298.499784 -280.434288)
		(width 0.1143)
		(layer "In9.Cu")
		(net "P5E_PEX2_STN1_TX_DN<23>")
	)
	(segment
		(start 262.104886 -151.235156)
		(end 261.740142 -143.809212)
		(width 0.1651)
		(layer "In9.Cu")
		(net "P5E_PEX2_STN1_TX_DN<23>")
	)
	(segment
		(start 297.883834 -264.494518)
		(end 263.054084 -161.59861)
		(width 0.1651)
		(layer "In9.Cu")
		(net "P5E_PEX2_STN1_TX_DN<23>")
	)
	(segment
		(start 259.179314 -137.626852)
		(end 259.179314 -131.610608)
		(width 0.1651)
		(layer "In9.Cu")
		(net "P5E_PEX2_STN1_TX_DN<23>")
	)
	(segment
		(start 266.07389 -112.472978)
		(end 266.335256 -112.211612)
		(width 0.1651)
		(layer "In9.Cu")
		(net "P5E_PEX2_STN1_TX_DN<23>")
	)
	(segment
		(start 297.883834 -271.526)
		(end 297.883834 -264.494518)
		(width 0.1651)
		(layer "In9.Cu")
		(net "P5E_PEX2_STN1_TX_DN<23>")
	)
	(segment
		(start 297.929554 -271.600168)
		(end 297.883834 -271.554448)
		(width 0.1143)
		(layer "In9.Cu")
		(net "P5E_PEX2_STN1_TX_DN<23>")
	)
	(segment
		(start 262.104886 -151.234902)
		(end 262.104886 -151.235156)
		(width 0.1651)
		(layer "In9.Cu")
		(net "P5E_PEX2_STN1_TX_DN<23>")
	)
	(segment
		(start 261.740142 -143.809212)
		(end 259.179314 -137.626852)
		(width 0.1651)
		(layer "In9.Cu")
		(net "P5E_PEX2_STN1_TX_DN<23>")
	)
	(segment
		(start 263.054084 -161.59861)
		(end 262.469884 -158.661354)
		(width 0.1651)
		(layer "In9.Cu")
		(net "P5E_PEX2_STN1_TX_DN<23>")
	)
	(segment
		(start 259.179314 -131.610608)
		(end 262.004556 -122.296936)
		(width 0.1651)
		(layer "In9.Cu")
		(net "P5E_PEX2_STN1_TX_DN<23>")
	)
	(segment
		(start 267.034772 -112.211612)
		(end 267.325602 -111.920782)
		(width 0.1651)
		(layer "In9.Cu")
		(net "P5E_PEX2_STN1_TX_DN<23>")
	)
	(segment
		(start 297.883834 -271.554448)
		(end 297.883834 -271.526)
		(width 0.1143)
		(layer "In9.Cu")
		(net "P5E_PEX2_STN1_TX_DN<23>")
	)
	(segment
		(start 262.004556 -122.296936)
		(end 266.07389 -112.472978)
		(width 0.1651)
		(layer "In9.Cu")
		(net "P5E_PEX2_STN1_TX_DN<23>")
	)
	(segment
		(start 297.929554 -280.10485)
		(end 297.929554 -271.600168)
		(width 0.1143)
		(layer "In9.Cu")
		(net "P5E_PEX2_STN1_TX_DN<23>")
	)
	(segment
		(start 298.385484 -280.319988)
		(end 298.144692 -280.319988)
		(width 0.1143)
		(layer "In9.Cu")
		(net "P5E_PEX2_STN1_TX_DN<23>")
	)
	(segment
		(start 262.469884 -158.661354)
		(end 262.104886 -151.234902)
		(width 0.1651)
		(layer "In9.Cu")
		(net "P5E_PEX2_STN1_TX_DN<23>")
	)
	(segment
		(start 266.335256 -112.211612)
		(end 267.034772 -112.211612)
		(width 0.1651)
		(layer "In9.Cu")
		(net "P5E_PEX2_STN1_TX_DN<23>")
	)
	(segment
		(start 298.144692 -280.319988)
		(end 297.929554 -280.10485)
		(width 0.1143)
		(layer "In9.Cu")
		(net "P5E_PEX2_STN1_TX_DN<23>")
	)
	(segment
		(start 319.015364 -342.734138)
		(end 318.720724 -342.439498)
		(width 0.13462)
		(layer "F.Cu")
		(net "P5E_PEX2_STN6_TX_DP<109>")
	)
	(segment
		(start 318.695324 -343.685622)
		(end 319.015364 -343.365582)
		(width 0.13462)
		(layer "F.Cu")
		(net "P5E_PEX2_STN6_TX_DP<109>")
	)
	(segment
		(start 319.015364 -343.365582)
		(end 319.015364 -342.734138)
		(width 0.13462)
		(layer "F.Cu")
		(net "P5E_PEX2_STN6_TX_DP<109>")
	)
	(segment
		(start 277.485602 -311.479692)
		(end 277.599902 -311.365392)
		(width 0.1143)
		(layer "In13.Cu")
		(net "P5E_PEX2_STN6_TX_DP<109>")
	)
	(segment
		(start 313.019694 -338.75091)
		(end 282.988258 -332.917038)
		(width 0.1651)
		(layer "In13.Cu")
		(net "P5E_PEX2_STN6_TX_DP<109>")
	)
	(segment
		(start 276.983952 -325.427086)
		(end 276.983952 -319.995296)
		(width 0.1651)
		(layer "In13.Cu")
		(net "P5E_PEX2_STN6_TX_DP<109>")
	)
	(segment
		(start 278.034496 -327.963276)
		(end 276.983952 -325.427086)
		(width 0.1651)
		(layer "In13.Cu")
		(net "P5E_PEX2_STN6_TX_DP<109>")
	)
	(segment
		(start 276.983952 -319.966848)
		(end 277.029672 -319.921128)
		(width 0.1143)
		(layer "In13.Cu")
		(net "P5E_PEX2_STN6_TX_DP<109>")
	)
	(segment
		(start 277.029672 -319.921128)
		(end 277.029672 -311.7088)
		(width 0.1143)
		(layer "In13.Cu")
		(net "P5E_PEX2_STN6_TX_DP<109>")
	)
	(segment
		(start 276.983952 -319.995296)
		(end 276.983952 -319.966848)
		(width 0.1143)
		(layer "In13.Cu")
		(net "P5E_PEX2_STN6_TX_DP<109>")
	)
	(segment
		(start 277.25878 -311.479692)
		(end 277.485602 -311.479692)
		(width 0.1143)
		(layer "In13.Cu")
		(net "P5E_PEX2_STN6_TX_DP<109>")
	)
	(segment
		(start 319.0113 -341.717884)
		(end 318.771524 -341.355426)
		(width 0.1651)
		(layer "In13.Cu")
		(net "P5E_PEX2_STN6_TX_DP<109>")
	)
	(segment
		(start 319.011554 -342.148668)
		(end 319.011554 -341.718138)
		(width 0.1651)
		(layer "In13.Cu")
		(net "P5E_PEX2_STN6_TX_DP<109>")
	)
	(segment
		(start 318.720724 -342.439498)
		(end 319.011554 -342.148668)
		(width 0.1651)
		(layer "In13.Cu")
		(net "P5E_PEX2_STN6_TX_DP<109>")
	)
	(segment
		(start 282.988258 -332.917038)
		(end 278.034496 -327.963276)
		(width 0.1651)
		(layer "In13.Cu")
		(net "P5E_PEX2_STN6_TX_DP<109>")
	)
	(segment
		(start 318.771524 -341.355426)
		(end 313.019694 -338.75091)
		(width 0.1651)
		(layer "In13.Cu")
		(net "P5E_PEX2_STN6_TX_DP<109>")
	)
	(segment
		(start 277.599902 -311.365392)
		(end 277.599902 -311.099962)
		(width 0.1143)
		(layer "In13.Cu")
		(net "P5E_PEX2_STN6_TX_DP<109>")
	)
	(segment
		(start 277.029672 -311.7088)
		(end 277.25878 -311.479692)
		(width 0.1143)
		(layer "In13.Cu")
		(net "P5E_PEX2_STN6_TX_DP<109>")
	)
	(segment
		(start 319.011554 -341.718138)
		(end 319.0113 -341.717884)
		(width 0.1651)
		(layer "In13.Cu")
		(net "P5E_PEX2_STN6_TX_DP<109>")
	)
	(segment
		(start 199.979534 -155.516834)
		(end 200.274174 -155.222194)
		(width 0.13462)
		(layer "F.Cu")
		(net "P5E_PEX1_STN0_TX_DN<15>")
	)
	(segment
		(start 199.02805 -155.196794)
		(end 199.34809 -155.516834)
		(width 0.13462)
		(layer "F.Cu")
		(net "P5E_PEX1_STN0_TX_DN<15>")
	)
	(segment
		(start 199.34809 -155.516834)
		(end 199.979534 -155.516834)
		(width 0.13462)
		(layer "F.Cu")
		(net "P5E_PEX1_STN0_TX_DN<15>")
	)
	(segment
		(start 190.835534 -278.229568)
		(end 190.949834 -278.115268)
		(width 0.1143)
		(layer "In9.Cu")
		(net "P5E_PEX1_STN0_TX_DN<15>")
	)
	(segment
		(start 200.274174 -155.222194)
		(end 200.565004 -155.513024)
		(width 0.1651)
		(layer "In9.Cu")
		(net "P5E_PEX1_STN0_TX_DN<15>")
	)
	(segment
		(start 187.963048 -220.410278)
		(end 191.490346 -260.731254)
		(width 0.1651)
		(layer "In9.Cu")
		(net "P5E_PEX1_STN0_TX_DN<15>")
	)
	(segment
		(start 190.570358 -271.546066)
		(end 190.570358 -278.12619)
		(width 0.1143)
		(layer "In9.Cu")
		(net "P5E_PEX1_STN0_TX_DN<15>")
	)
	(segment
		(start 201.75728 -156.571442)
		(end 193.274442 -171.265088)
		(width 0.1651)
		(layer "In9.Cu")
		(net "P5E_PEX1_STN0_TX_DN<15>")
	)
	(segment
		(start 191.490346 -260.731254)
		(end 191.490346 -267.473684)
		(width 0.1651)
		(layer "In9.Cu")
		(net "P5E_PEX1_STN0_TX_DN<15>")
	)
	(segment
		(start 190.673736 -278.229568)
		(end 190.835534 -278.229568)
		(width 0.1143)
		(layer "In9.Cu")
		(net "P5E_PEX1_STN0_TX_DN<15>")
	)
	(segment
		(start 201.75728 -155.979368)
		(end 201.75728 -156.571442)
		(width 0.1651)
		(layer "In9.Cu")
		(net "P5E_PEX1_STN0_TX_DN<15>")
	)
	(segment
		(start 190.570358 -278.12619)
		(end 190.673736 -278.229568)
		(width 0.1143)
		(layer "In9.Cu")
		(net "P5E_PEX1_STN0_TX_DN<15>")
	)
	(segment
		(start 190.616078 -271.471898)
		(end 190.616078 -271.500346)
		(width 0.1143)
		(layer "In9.Cu")
		(net "P5E_PEX1_STN0_TX_DN<15>")
	)
	(segment
		(start 193.274442 -171.265088)
		(end 191.772032 -176.871122)
		(width 0.1651)
		(layer "In9.Cu")
		(net "P5E_PEX1_STN0_TX_DN<15>")
	)
	(segment
		(start 191.772032 -176.871122)
		(end 187.963048 -220.410278)
		(width 0.1651)
		(layer "In9.Cu")
		(net "P5E_PEX1_STN0_TX_DN<15>")
	)
	(segment
		(start 190.949834 -278.115268)
		(end 190.949834 -277.849838)
		(width 0.1143)
		(layer "In9.Cu")
		(net "P5E_PEX1_STN0_TX_DN<15>")
	)
	(segment
		(start 190.616078 -271.500346)
		(end 190.570358 -271.546066)
		(width 0.1143)
		(layer "In9.Cu")
		(net "P5E_PEX1_STN0_TX_DN<15>")
	)
	(segment
		(start 201.290936 -155.513024)
		(end 201.75728 -155.979368)
		(width 0.1651)
		(layer "In9.Cu")
		(net "P5E_PEX1_STN0_TX_DN<15>")
	)
	(segment
		(start 200.565004 -155.513024)
		(end 201.290936 -155.513024)
		(width 0.1651)
		(layer "In9.Cu")
		(net "P5E_PEX1_STN0_TX_DN<15>")
	)
	(segment
		(start 191.490346 -267.473684)
		(end 190.616078 -269.584932)
		(width 0.1651)
		(layer "In9.Cu")
		(net "P5E_PEX1_STN0_TX_DN<15>")
	)
	(segment
		(start 190.616078 -269.584932)
		(end 190.616078 -271.471898)
		(width 0.1651)
		(layer "In9.Cu")
		(net "P5E_PEX1_STN0_TX_DN<15>")
	)
	(segment
		(start 174.596552 -355.978206)
		(end 174.916592 -355.658166)
		(width 0.13462)
		(layer "F.Cu")
		(net "P5E_PEX1_STN7_TX_DP<119>")
	)
	(segment
		(start 174.916592 -355.026722)
		(end 174.621952 -354.732082)
		(width 0.13462)
		(layer "F.Cu")
		(net "P5E_PEX1_STN7_TX_DP<119>")
	)
	(segment
		(start 174.916592 -355.658166)
		(end 174.916592 -355.026722)
		(width 0.13462)
		(layer "F.Cu")
		(net "P5E_PEX1_STN7_TX_DP<119>")
	)
	(segment
		(start 139.865862 -323.667628)
		(end 139.333986 -321.913504)
		(width 0.1651)
		(layer "In11.Cu")
		(net "P5E_PEX1_STN7_TX_DP<119>")
	)
	(segment
		(start 174.912782 -354.441252)
		(end 174.912782 -353.719384)
		(width 0.1651)
		(layer "In11.Cu")
		(net "P5E_PEX1_STN7_TX_DP<119>")
	)
	(segment
		(start 139.333986 -321.913504)
		(end 139.333986 -320.24066)
		(width 0.1651)
		(layer "In11.Cu")
		(net "P5E_PEX1_STN7_TX_DP<119>")
	)
	(segment
		(start 149.306534 -329.83551)
		(end 143.694404 -327.27392)
		(width 0.1651)
		(layer "In11.Cu")
		(net "P5E_PEX1_STN7_TX_DP<119>")
	)
	(segment
		(start 160.170114 -307.956204)
		(end 160.170114 -308.160928)
		(width 0.1143)
		(layer "In11.Cu")
		(net "P5E_PEX1_STN7_TX_DP<119>")
	)
	(segment
		(start 175.517302 -340.322408)
		(end 168.110408 -336.807556)
		(width 0.1651)
		(layer "In11.Cu")
		(net "P5E_PEX1_STN7_TX_DP<119>")
	)
	(segment
		(start 176.467008 -341.587836)
		(end 175.517302 -340.322408)
		(width 0.1651)
		(layer "In11.Cu")
		(net "P5E_PEX1_STN7_TX_DP<119>")
	)
	(segment
		(start 151.663654 -307.679598)
		(end 159.893508 -307.679598)
		(width 0.1143)
		(layer "In11.Cu")
		(net "P5E_PEX1_STN7_TX_DP<119>")
	)
	(segment
		(start 142.048484 -326.206612)
		(end 140.877798 -325.203058)
		(width 0.1651)
		(layer "In11.Cu")
		(net "P5E_PEX1_STN7_TX_DP<119>")
	)
	(segment
		(start 140.877798 -325.203058)
		(end 139.8778 -323.707506)
		(width 0.1651)
		(layer "In11.Cu")
		(net "P5E_PEX1_STN7_TX_DP<119>")
	)
	(segment
		(start 160.259014 -308.249828)
		(end 160.549844 -308.249828)
		(width 0.1143)
		(layer "In11.Cu")
		(net "P5E_PEX1_STN7_TX_DP<119>")
	)
	(segment
		(start 174.912782 -353.719384)
		(end 176.467262 -352.164904)
		(width 0.1651)
		(layer "In11.Cu")
		(net "P5E_PEX1_STN7_TX_DP<119>")
	)
	(segment
		(start 174.621952 -354.732082)
		(end 174.912782 -354.441252)
		(width 0.1651)
		(layer "In11.Cu")
		(net "P5E_PEX1_STN7_TX_DP<119>")
	)
	(segment
		(start 139.8778 -323.707506)
		(end 139.865608 -323.667628)
		(width 0.1651)
		(layer "In11.Cu")
		(net "P5E_PEX1_STN7_TX_DP<119>")
	)
	(segment
		(start 159.893508 -307.679598)
		(end 160.170114 -307.956204)
		(width 0.1143)
		(layer "In11.Cu")
		(net "P5E_PEX1_STN7_TX_DP<119>")
	)
	(segment
		(start 160.170114 -308.160928)
		(end 160.259014 -308.249828)
		(width 0.1143)
		(layer "In11.Cu")
		(net "P5E_PEX1_STN7_TX_DP<119>")
	)
	(segment
		(start 176.467262 -352.164904)
		(end 176.467262 -341.58809)
		(width 0.1651)
		(layer "In11.Cu")
		(net "P5E_PEX1_STN7_TX_DP<119>")
	)
	(segment
		(start 139.333986 -320.24066)
		(end 139.424664 -319.78219)
		(width 0.1651)
		(layer "In11.Cu")
		(net "P5E_PEX1_STN7_TX_DP<119>")
	)
	(segment
		(start 176.467262 -341.58809)
		(end 176.467008 -341.587836)
		(width 0.1651)
		(layer "In11.Cu")
		(net "P5E_PEX1_STN7_TX_DP<119>")
	)
	(segment
		(start 140.696696 -316.714124)
		(end 144.494758 -312.916062)
		(width 0.1651)
		(layer "In11.Cu")
		(net "P5E_PEX1_STN7_TX_DP<119>")
	)
	(segment
		(start 145.72361 -312.09488)
		(end 150.184612 -307.633878)
		(width 0.1651)
		(layer "In11.Cu")
		(net "P5E_PEX1_STN7_TX_DP<119>")
	)
	(segment
		(start 168.110408 -336.807556)
		(end 149.306534 -329.83551)
		(width 0.1651)
		(layer "In11.Cu")
		(net "P5E_PEX1_STN7_TX_DP<119>")
	)
	(segment
		(start 144.494758 -312.916062)
		(end 145.72361 -312.09488)
		(width 0.1651)
		(layer "In11.Cu")
		(net "P5E_PEX1_STN7_TX_DP<119>")
	)
	(segment
		(start 143.694404 -327.27392)
		(end 142.048484 -326.206612)
		(width 0.1651)
		(layer "In11.Cu")
		(net "P5E_PEX1_STN7_TX_DP<119>")
	)
	(segment
		(start 151.595836 -307.633878)
		(end 151.617934 -307.633878)
		(width 0.1143)
		(layer "In11.Cu")
		(net "P5E_PEX1_STN7_TX_DP<119>")
	)
	(segment
		(start 139.424664 -319.78219)
		(end 140.696696 -316.714124)
		(width 0.1651)
		(layer "In11.Cu")
		(net "P5E_PEX1_STN7_TX_DP<119>")
	)
	(segment
		(start 139.865608 -323.667628)
		(end 139.865862 -323.667628)
		(width 0.1651)
		(layer "In11.Cu")
		(net "P5E_PEX1_STN7_TX_DP<119>")
	)
	(segment
		(start 150.184612 -307.633878)
		(end 151.595836 -307.633878)
		(width 0.1651)
		(layer "In11.Cu")
		(net "P5E_PEX1_STN7_TX_DP<119>")
	)
	(segment
		(start 151.617934 -307.633878)
		(end 151.663654 -307.679598)
		(width 0.1143)
		(layer "In11.Cu")
		(net "P5E_PEX1_STN7_TX_DP<119>")
	)
	(segment
		(start 270.895572 -132.81152)
		(end 271.213834 -133.129782)
		(width 0.13462)
		(layer "F.Cu")
		(net "P5E_PEX2_STN1_TX_DP<29>")
	)
	(segment
		(start 270.260572 -132.81152)
		(end 270.895572 -132.81152)
		(width 0.13462)
		(layer "F.Cu")
		(net "P5E_PEX2_STN1_TX_DP<29>")
	)
	(segment
		(start 269.96771 -133.104382)
		(end 270.260572 -132.81152)
		(width 0.13462)
		(layer "F.Cu")
		(net "P5E_PEX2_STN1_TX_DP<29>")
	)
	(segment
		(start 268.12748 -145.02511)
		(end 268.103096 -144.530064)
		(width 0.1651)
		(layer "In9.Cu")
		(net "P5E_PEX2_STN1_TX_DP<29>")
	)
	(segment
		(start 268.646402 -132.927852)
		(end 268.760702 -132.813552)
		(width 0.1651)
		(layer "In9.Cu")
		(net "P5E_PEX2_STN1_TX_DP<29>")
	)
	(segment
		(start 267.089636 -139.601448)
		(end 266.94003 -139.539472)
		(width 0.1651)
		(layer "In9.Cu")
		(net "P5E_PEX2_STN1_TX_DP<29>")
	)
	(segment
		(start 268.138656 -147.580604)
		(end 268.247368 -147.460716)
		(width 0.1651)
		(layer "In9.Cu")
		(net "P5E_PEX2_STN1_TX_DP<29>")
	)
	(segment
		(start 269.67688 -132.813552)
		(end 269.96771 -133.104382)
		(width 0.1651)
		(layer "In9.Cu")
		(net "P5E_PEX2_STN1_TX_DP<29>")
	)
	(segment
		(start 268.049502 -132.813552)
		(end 268.163802 -132.927852)
		(width 0.1651)
		(layer "In9.Cu")
		(net "P5E_PEX2_STN1_TX_DP<29>")
	)
	(segment
		(start 266.94003 -139.539472)
		(end 266.750546 -139.082018)
		(width 0.1651)
		(layer "In9.Cu")
		(net "P5E_PEX2_STN1_TX_DP<29>")
	)
	(segment
		(start 304.199798 -279.749504)
		(end 304.199798 -280.015188)
		(width 0.1143)
		(layer "In9.Cu")
		(net "P5E_PEX2_STN1_TX_DP<29>")
	)
	(segment
		(start 268.163802 -132.927852)
		(end 268.646402 -132.927852)
		(width 0.1651)
		(layer "In9.Cu")
		(net "P5E_PEX2_STN1_TX_DP<29>")
	)
	(segment
		(start 303.865788 -271.554448)
		(end 303.865788 -271.526)
		(width 0.1143)
		(layer "In9.Cu")
		(net "P5E_PEX2_STN1_TX_DP<29>")
	)
	(segment
		(start 268.585188 -156.661866)
		(end 268.1986 -148.798534)
		(width 0.1651)
		(layer "In9.Cu")
		(net "P5E_PEX2_STN1_TX_DP<29>")
	)
	(segment
		(start 268.247368 -147.460716)
		(end 268.222984 -146.965924)
		(width 0.1651)
		(layer "In9.Cu")
		(net "P5E_PEX2_STN1_TX_DP<29>")
	)
	(segment
		(start 268.162786 -148.075142)
		(end 268.138656 -147.580604)
		(width 0.1651)
		(layer "In9.Cu")
		(net "P5E_PEX2_STN1_TX_DP<29>")
	)
	(segment
		(start 268.102842 -146.857212)
		(end 268.078712 -146.362674)
		(width 0.1651)
		(layer "In9.Cu")
		(net "P5E_PEX2_STN1_TX_DP<29>")
	)
	(segment
		(start 267.92174 -143.177514)
		(end 267.851128 -141.738604)
		(width 0.1651)
		(layer "In9.Cu")
		(net "P5E_PEX2_STN1_TX_DP<29>")
	)
	(segment
		(start 267.982954 -144.421606)
		(end 267.957554 -143.900652)
		(width 0.1651)
		(layer "In9.Cu")
		(net "P5E_PEX2_STN1_TX_DP<29>")
	)
	(segment
		(start 303.9237 -280.129488)
		(end 303.820068 -280.025856)
		(width 0.1143)
		(layer "In9.Cu")
		(net "P5E_PEX2_STN1_TX_DP<29>")
	)
	(segment
		(start 268.222984 -146.965924)
		(end 268.102842 -146.857212)
		(width 0.1651)
		(layer "In9.Cu")
		(net "P5E_PEX2_STN1_TX_DP<29>")
	)
	(segment
		(start 304.085498 -280.129488)
		(end 303.9237 -280.129488)
		(width 0.1143)
		(layer "In9.Cu")
		(net "P5E_PEX2_STN1_TX_DP<29>")
	)
	(segment
		(start 268.307312 -148.678646)
		(end 268.282928 -148.183854)
		(width 0.1651)
		(layer "In9.Cu")
		(net "P5E_PEX2_STN1_TX_DP<29>")
	)
	(segment
		(start 303.865788 -263.170924)
		(end 269.688564 -162.20821)
		(width 0.1651)
		(layer "In9.Cu")
		(net "P5E_PEX2_STN1_TX_DP<29>")
	)
	(segment
		(start 268.1986 -148.798534)
		(end 268.307312 -148.678646)
		(width 0.1651)
		(layer "In9.Cu")
		(net "P5E_PEX2_STN1_TX_DP<29>")
	)
	(segment
		(start 303.820068 -280.025856)
		(end 303.820068 -271.600168)
		(width 0.1143)
		(layer "In9.Cu")
		(net "P5E_PEX2_STN1_TX_DP<29>")
	)
	(segment
		(start 268.042898 -145.639282)
		(end 268.018768 -145.144744)
		(width 0.1651)
		(layer "In9.Cu")
		(net "P5E_PEX2_STN1_TX_DP<29>")
	)
	(segment
		(start 267.489432 -132.813552)
		(end 268.049502 -132.813552)
		(width 0.1651)
		(layer "In9.Cu")
		(net "P5E_PEX2_STN1_TX_DP<29>")
	)
	(segment
		(start 267.27912 -140.059156)
		(end 267.089636 -139.601448)
		(width 0.1651)
		(layer "In9.Cu")
		(net "P5E_PEX2_STN1_TX_DP<29>")
	)
	(segment
		(start 267.957554 -143.900652)
		(end 268.066266 -143.781018)
		(width 0.1651)
		(layer "In9.Cu")
		(net "P5E_PEX2_STN1_TX_DP<29>")
	)
	(segment
		(start 266.750546 -139.082018)
		(end 266.812268 -138.932666)
		(width 0.1651)
		(layer "In9.Cu")
		(net "P5E_PEX2_STN1_TX_DP<29>")
	)
	(segment
		(start 268.041882 -143.285972)
		(end 267.92174 -143.177514)
		(width 0.1651)
		(layer "In9.Cu")
		(net "P5E_PEX2_STN1_TX_DP<29>")
	)
	(segment
		(start 269.688564 -162.20821)
		(end 268.585188 -156.661866)
		(width 0.1651)
		(layer "In9.Cu")
		(net "P5E_PEX2_STN1_TX_DP<29>")
	)
	(segment
		(start 303.820068 -271.600168)
		(end 303.865788 -271.554448)
		(width 0.1143)
		(layer "In9.Cu")
		(net "P5E_PEX2_STN1_TX_DP<29>")
	)
	(segment
		(start 304.199798 -280.015188)
		(end 304.085498 -280.129488)
		(width 0.1143)
		(layer "In9.Cu")
		(net "P5E_PEX2_STN1_TX_DP<29>")
	)
	(segment
		(start 265.255502 -135.473694)
		(end 265.255502 -134.799578)
		(width 0.1651)
		(layer "In9.Cu")
		(net "P5E_PEX2_STN1_TX_DP<29>")
	)
	(segment
		(start 265.255502 -134.799578)
		(end 265.477752 -134.26313)
		(width 0.1651)
		(layer "In9.Cu")
		(net "P5E_PEX2_STN1_TX_DP<29>")
	)
	(segment
		(start 268.078712 -146.362674)
		(end 268.187424 -146.242786)
		(width 0.1651)
		(layer "In9.Cu")
		(net "P5E_PEX2_STN1_TX_DP<29>")
	)
	(segment
		(start 268.16304 -145.74774)
		(end 268.042898 -145.639282)
		(width 0.1651)
		(layer "In9.Cu")
		(net "P5E_PEX2_STN1_TX_DP<29>")
	)
	(segment
		(start 266.812268 -138.932666)
		(end 266.622784 -138.474704)
		(width 0.1651)
		(layer "In9.Cu")
		(net "P5E_PEX2_STN1_TX_DP<29>")
	)
	(segment
		(start 268.282928 -148.183854)
		(end 268.162786 -148.075142)
		(width 0.1651)
		(layer "In9.Cu")
		(net "P5E_PEX2_STN1_TX_DP<29>")
	)
	(segment
		(start 268.103096 -144.530064)
		(end 267.982954 -144.421606)
		(width 0.1651)
		(layer "In9.Cu")
		(net "P5E_PEX2_STN1_TX_DP<29>")
	)
	(segment
		(start 266.473178 -138.412982)
		(end 265.255502 -135.473694)
		(width 0.1651)
		(layer "In9.Cu")
		(net "P5E_PEX2_STN1_TX_DP<29>")
	)
	(segment
		(start 265.477752 -134.26313)
		(end 266.52982 -133.211062)
		(width 0.1651)
		(layer "In9.Cu")
		(net "P5E_PEX2_STN1_TX_DP<29>")
	)
	(segment
		(start 268.760702 -132.813552)
		(end 269.67688 -132.813552)
		(width 0.1651)
		(layer "In9.Cu")
		(net "P5E_PEX2_STN1_TX_DP<29>")
	)
	(segment
		(start 268.187424 -146.242786)
		(end 268.16304 -145.74774)
		(width 0.1651)
		(layer "In9.Cu")
		(net "P5E_PEX2_STN1_TX_DP<29>")
	)
	(segment
		(start 266.622784 -138.474704)
		(end 266.473178 -138.412982)
		(width 0.1651)
		(layer "In9.Cu")
		(net "P5E_PEX2_STN1_TX_DP<29>")
	)
	(segment
		(start 267.851128 -141.738604)
		(end 267.217398 -140.208508)
		(width 0.1651)
		(layer "In9.Cu")
		(net "P5E_PEX2_STN1_TX_DP<29>")
	)
	(segment
		(start 268.018768 -145.144744)
		(end 268.12748 -145.02511)
		(width 0.1651)
		(layer "In9.Cu")
		(net "P5E_PEX2_STN1_TX_DP<29>")
	)
	(segment
		(start 303.865788 -271.526)
		(end 303.865788 -263.170924)
		(width 0.1651)
		(layer "In9.Cu")
		(net "P5E_PEX2_STN1_TX_DP<29>")
	)
	(segment
		(start 268.066266 -143.781018)
		(end 268.041882 -143.285972)
		(width 0.1651)
		(layer "In9.Cu")
		(net "P5E_PEX2_STN1_TX_DP<29>")
	)
	(segment
		(start 267.217398 -140.208508)
		(end 267.27912 -140.059156)
		(width 0.1651)
		(layer "In9.Cu")
		(net "P5E_PEX2_STN1_TX_DP<29>")
	)
	(segment
		(start 266.52982 -133.211062)
		(end 267.489432 -132.813552)
		(width 0.1651)
		(layer "In9.Cu")
		(net "P5E_PEX2_STN1_TX_DP<29>")
	)
	(segment
		(start 277.518622 -355.026722)
		(end 277.223982 -354.732082)
		(width 0.13462)
		(layer "F.Cu")
		(net "P5E_PEX2_STN7_TX_DP<117>")
	)
	(segment
		(start 277.518622 -355.658166)
		(end 277.518622 -355.026722)
		(width 0.13462)
		(layer "F.Cu")
		(net "P5E_PEX2_STN7_TX_DP<117>")
	)
	(segment
		(start 277.198582 -355.978206)
		(end 277.518622 -355.658166)
		(width 0.13462)
		(layer "F.Cu")
		(net "P5E_PEX2_STN7_TX_DP<117>")
	)
	(segment
		(start 277.514812 -353.814126)
		(end 279.069292 -352.259646)
		(width 0.1651)
		(layer "In7.Cu")
		(net "P5E_PEX2_STN7_TX_DP<117>")
	)
	(segment
		(start 267.839952 -305.733958)
		(end 267.8684 -305.733958)
		(width 0.1143)
		(layer "In7.Cu")
		(net "P5E_PEX2_STN7_TX_DP<117>")
	)
	(segment
		(start 253.54026 -319.217294)
		(end 254.762 -316.3316)
		(width 0.1651)
		(layer "In7.Cu")
		(net "P5E_PEX2_STN7_TX_DP<117>")
	)
	(segment
		(start 276.269958 -306.235608)
		(end 276.384258 -306.349908)
		(width 0.1143)
		(layer "In7.Cu")
		(net "P5E_PEX2_STN7_TX_DP<117>")
	)
	(segment
		(start 278.92756 -341.412576)
		(end 276.587966 -338.897468)
		(width 0.1651)
		(layer "In7.Cu")
		(net "P5E_PEX2_STN7_TX_DP<117>")
	)
	(segment
		(start 267.91412 -305.779678)
		(end 276.044152 -305.779678)
		(width 0.1143)
		(layer "In7.Cu")
		(net "P5E_PEX2_STN7_TX_DP<117>")
	)
	(segment
		(start 277.223982 -354.732082)
		(end 277.514812 -354.441252)
		(width 0.1651)
		(layer "In7.Cu")
		(net "P5E_PEX2_STN7_TX_DP<117>")
	)
	(segment
		(start 254.762 -316.3316)
		(end 256.774696 -312.609992)
		(width 0.1651)
		(layer "In7.Cu")
		(net "P5E_PEX2_STN7_TX_DP<117>")
	)
	(segment
		(start 276.384258 -306.349908)
		(end 276.649688 -306.349908)
		(width 0.1143)
		(layer "In7.Cu")
		(net "P5E_PEX2_STN7_TX_DP<117>")
	)
	(segment
		(start 279.069292 -352.259646)
		(end 279.069292 -341.717884)
		(width 0.1651)
		(layer "In7.Cu")
		(net "P5E_PEX2_STN7_TX_DP<117>")
	)
	(segment
		(start 258.779264 -308.903878)
		(end 259.987288 -307.707284)
		(width 0.1651)
		(layer "In7.Cu")
		(net "P5E_PEX2_STN7_TX_DP<117>")
	)
	(segment
		(start 257.150362 -328.101706)
		(end 254.63119 -325.276464)
		(width 0.1651)
		(layer "In7.Cu")
		(net "P5E_PEX2_STN7_TX_DP<117>")
	)
	(segment
		(start 277.514812 -354.441252)
		(end 277.514812 -353.814126)
		(width 0.1651)
		(layer "In7.Cu")
		(net "P5E_PEX2_STN7_TX_DP<117>")
	)
	(segment
		(start 262.200898 -307.51526)
		(end 262.674862 -307.396642)
		(width 0.1651)
		(layer "In7.Cu")
		(net "P5E_PEX2_STN7_TX_DP<117>")
	)
	(segment
		(start 279.069292 -341.717884)
		(end 278.92756 -341.412576)
		(width 0.1651)
		(layer "In7.Cu")
		(net "P5E_PEX2_STN7_TX_DP<117>")
	)
	(segment
		(start 253.54026 -322.642484)
		(end 253.54026 -319.217294)
		(width 0.1651)
		(layer "In7.Cu")
		(net "P5E_PEX2_STN7_TX_DP<117>")
	)
	(segment
		(start 266.852908 -305.733958)
		(end 267.839952 -305.733958)
		(width 0.1651)
		(layer "In7.Cu")
		(net "P5E_PEX2_STN7_TX_DP<117>")
	)
	(segment
		(start 254.63119 -325.276464)
		(end 253.54026 -322.642484)
		(width 0.1651)
		(layer "In7.Cu")
		(net "P5E_PEX2_STN7_TX_DP<117>")
	)
	(segment
		(start 260.454394 -307.51526)
		(end 262.200898 -307.51526)
		(width 0.1651)
		(layer "In7.Cu")
		(net "P5E_PEX2_STN7_TX_DP<117>")
	)
	(segment
		(start 276.044152 -305.779678)
		(end 276.269958 -306.005484)
		(width 0.1143)
		(layer "In7.Cu")
		(net "P5E_PEX2_STN7_TX_DP<117>")
	)
	(segment
		(start 276.587966 -338.897468)
		(end 257.150362 -328.101706)
		(width 0.1651)
		(layer "In7.Cu")
		(net "P5E_PEX2_STN7_TX_DP<117>")
	)
	(segment
		(start 256.774696 -312.609992)
		(end 256.774442 -312.609992)
		(width 0.1651)
		(layer "In7.Cu")
		(net "P5E_PEX2_STN7_TX_DP<117>")
	)
	(segment
		(start 267.8684 -305.733958)
		(end 267.91412 -305.779678)
		(width 0.1143)
		(layer "In7.Cu")
		(net "P5E_PEX2_STN7_TX_DP<117>")
	)
	(segment
		(start 256.774442 -312.609992)
		(end 258.779264 -308.903878)
		(width 0.1651)
		(layer "In7.Cu")
		(net "P5E_PEX2_STN7_TX_DP<117>")
	)
	(segment
		(start 276.269958 -306.005484)
		(end 276.269958 -306.235608)
		(width 0.1143)
		(layer "In7.Cu")
		(net "P5E_PEX2_STN7_TX_DP<117>")
	)
	(segment
		(start 262.674862 -307.396642)
		(end 264.054844 -306.658518)
		(width 0.1651)
		(layer "In7.Cu")
		(net "P5E_PEX2_STN7_TX_DP<117>")
	)
	(segment
		(start 264.054844 -306.658518)
		(end 266.852908 -305.733958)
		(width 0.1651)
		(layer "In7.Cu")
		(net "P5E_PEX2_STN7_TX_DP<117>")
	)
	(segment
		(start 259.987288 -307.707284)
		(end 260.454394 -307.51526)
		(width 0.1651)
		(layer "In7.Cu")
		(net "P5E_PEX2_STN7_TX_DP<117>")
	)
	(segment
		(start 305.495198 -325.196454)
		(end 305.4477 -325.060818)
		(width 0.1651)
		(layer "In5.Cu")
		(net "P5E_PEX2_STN5_RX_DN<91>")
	)
	(segment
		(start 301.417228 -322.074794)
		(end 301.015908 -321.106038)
		(width 0.1651)
		(layer "In5.Cu")
		(net "P5E_PEX2_STN5_RX_DN<91>")
	)
	(segment
		(start 305.001168 -324.846188)
		(end 304.865532 -324.893686)
		(width 0.1651)
		(layer "In5.Cu")
		(net "P5E_PEX2_STN5_RX_DN<91>")
	)
	(segment
		(start 339.501734 -341.8459)
		(end 338.917026 -341.261192)
		(width 0.1651)
		(layer "In5.Cu")
		(net "P5E_PEX2_STN5_RX_DN<91>")
	)
	(segment
		(start 339.501734 -358.499664)
		(end 339.501734 -341.8459)
		(width 0.1651)
		(layer "In5.Cu")
		(net "P5E_PEX2_STN5_RX_DN<91>")
	)
	(segment
		(start 338.090002 -372.508018)
		(end 338.217002 -372.381018)
		(width 0.1651)
		(layer "In5.Cu")
		(net "P5E_PEX2_STN5_RX_DN<91>")
	)
	(segment
		(start 338.764118 -372.381018)
		(end 339.215984 -371.929152)
		(width 0.1651)
		(layer "In5.Cu")
		(net "P5E_PEX2_STN5_RX_DN<91>")
	)
	(segment
		(start 300.970188 -318.434466)
		(end 301.084488 -318.320166)
		(width 0.1143)
		(layer "In5.Cu")
		(net "P5E_PEX2_STN5_RX_DN<91>")
	)
	(segment
		(start 300.970188 -319.895728)
		(end 300.970188 -318.434466)
		(width 0.1143)
		(layer "In5.Cu")
		(net "P5E_PEX2_STN5_RX_DN<91>")
	)
	(segment
		(start 301.084488 -318.320166)
		(end 301.235618 -318.320166)
		(width 0.1143)
		(layer "In5.Cu")
		(net "P5E_PEX2_STN5_RX_DN<91>")
	)
	(segment
		(start 338.090002 -372.890034)
		(end 338.090002 -372.508018)
		(width 0.1651)
		(layer "In5.Cu")
		(net "P5E_PEX2_STN5_RX_DN<91>")
	)
	(segment
		(start 301.349918 -318.434466)
		(end 301.349918 -318.699896)
		(width 0.1143)
		(layer "In5.Cu")
		(net "P5E_PEX2_STN5_RX_DN<91>")
	)
	(segment
		(start 301.015908 -319.969896)
		(end 301.015908 -319.941448)
		(width 0.1143)
		(layer "In5.Cu")
		(net "P5E_PEX2_STN5_RX_DN<91>")
	)
	(segment
		(start 301.235618 -318.320166)
		(end 301.349918 -318.434466)
		(width 0.1143)
		(layer "In5.Cu")
		(net "P5E_PEX2_STN5_RX_DN<91>")
	)
	(segment
		(start 304.865532 -324.893686)
		(end 303.653698 -324.311264)
		(width 0.1651)
		(layer "In5.Cu")
		(net "P5E_PEX2_STN5_RX_DN<91>")
	)
	(segment
		(start 305.4477 -325.060818)
		(end 305.001168 -324.846188)
		(width 0.1651)
		(layer "In5.Cu")
		(net "P5E_PEX2_STN5_RX_DN<91>")
	)
	(segment
		(start 338.217002 -372.381018)
		(end 338.764118 -372.381018)
		(width 0.1651)
		(layer "In5.Cu")
		(net "P5E_PEX2_STN5_RX_DN<91>")
	)
	(segment
		(start 303.653698 -324.311264)
		(end 301.417228 -322.074794)
		(width 0.1651)
		(layer "In5.Cu")
		(net "P5E_PEX2_STN5_RX_DN<91>")
	)
	(segment
		(start 301.015908 -319.941448)
		(end 300.970188 -319.895728)
		(width 0.1143)
		(layer "In5.Cu")
		(net "P5E_PEX2_STN5_RX_DN<91>")
	)
	(segment
		(start 338.917026 -341.261192)
		(end 305.495198 -325.196454)
		(width 0.1651)
		(layer "In5.Cu")
		(net "P5E_PEX2_STN5_RX_DN<91>")
	)
	(segment
		(start 339.215984 -371.929152)
		(end 339.215984 -368.75847)
		(width 0.1651)
		(layer "In5.Cu")
		(net "P5E_PEX2_STN5_RX_DN<91>")
	)
	(segment
		(start 301.015908 -321.106038)
		(end 301.015908 -319.969896)
		(width 0.1651)
		(layer "In5.Cu")
		(net "P5E_PEX2_STN5_RX_DN<91>")
	)
	(segment
		(start 339.215984 -368.75847)
		(end 339.501734 -358.499664)
		(width 0.1651)
		(layer "In5.Cu")
		(net "P5E_PEX2_STN5_RX_DN<91>")
	)
	(segment
		(start 23.305008 -357.75773)
		(end 23.010368 -357.46309)
		(width 0.13462)
		(layer "F.Cu")
		(net "P5E_PEX0_STN7_TX_C_DN<114>")
	)
	(segment
		(start 23.010368 -357.46309)
		(end 23.010368 -356.831646)
		(width 0.13462)
		(layer "F.Cu")
		(net "P5E_PEX0_STN7_TX_C_DN<114>")
	)
	(segment
		(start 23.010368 -356.831646)
		(end 23.330408 -356.511606)
		(width 0.13462)
		(layer "F.Cu")
		(net "P5E_PEX0_STN7_TX_C_DN<114>")
	)
	(segment
		(start 33.484312 -400.607276)
		(end 33.484312 -394.570712)
		(width 0.1651)
		(layer "In7.Cu")
		(net "P5E_PEX0_STN7_TX_C_DN<114>")
	)
	(segment
		(start 21.979128 -384.882136)
		(end 21.1836 -371.673628)
		(width 0.1651)
		(layer "In7.Cu")
		(net "P5E_PEX0_STN7_TX_C_DN<114>")
	)
	(segment
		(start 23.014178 -359.084626)
		(end 23.014178 -358.04856)
		(width 0.1651)
		(layer "In7.Cu")
		(net "P5E_PEX0_STN7_TX_C_DN<114>")
	)
	(segment
		(start 21.844508 -364.965488)
		(end 23.014178 -359.084626)
		(width 0.1651)
		(layer "In7.Cu")
		(net "P5E_PEX0_STN7_TX_C_DN<114>")
	)
	(segment
		(start 25.455372 -390.026906)
		(end 23.34387 -387.915404)
		(width 0.1651)
		(layer "In7.Cu")
		(net "P5E_PEX0_STN7_TX_C_DN<114>")
	)
	(segment
		(start 31.405068 -392.491468)
		(end 25.455372 -390.026906)
		(width 0.1651)
		(layer "In7.Cu")
		(net "P5E_PEX0_STN7_TX_C_DN<114>")
	)
	(segment
		(start 33.484312 -394.570712)
		(end 31.405068 -392.491468)
		(width 0.1651)
		(layer "In7.Cu")
		(net "P5E_PEX0_STN7_TX_C_DN<114>")
	)
	(segment
		(start 32.910526 -401.181062)
		(end 33.484312 -400.607276)
		(width 0.1651)
		(layer "In7.Cu")
		(net "P5E_PEX0_STN7_TX_C_DN<114>")
	)
	(segment
		(start 21.1836 -371.673628)
		(end 21.844508 -364.965488)
		(width 0.1651)
		(layer "In7.Cu")
		(net "P5E_PEX0_STN7_TX_C_DN<114>")
	)
	(segment
		(start 23.34387 -387.915404)
		(end 21.979128 -384.882136)
		(width 0.1651)
		(layer "In7.Cu")
		(net "P5E_PEX0_STN7_TX_C_DN<114>")
	)
	(segment
		(start 32.43707 -401.181062)
		(end 32.910526 -401.181062)
		(width 0.1651)
		(layer "In7.Cu")
		(net "P5E_PEX0_STN7_TX_C_DN<114>")
	)
	(segment
		(start 32.31007 -401.690078)
		(end 32.31007 -401.308062)
		(width 0.1651)
		(layer "In7.Cu")
		(net "P5E_PEX0_STN7_TX_C_DN<114>")
	)
	(segment
		(start 32.31007 -401.308062)
		(end 32.43707 -401.181062)
		(width 0.1651)
		(layer "In7.Cu")
		(net "P5E_PEX0_STN7_TX_C_DN<114>")
	)
	(segment
		(start 23.014178 -358.04856)
		(end 23.305008 -357.75773)
		(width 0.1651)
		(layer "In7.Cu")
		(net "P5E_PEX0_STN7_TX_C_DN<114>")
	)
	(segment
		(start 134.193788 -350.685354)
		(end 134.513828 -350.365314)
		(width 0.13462)
		(layer "F.Cu")
		(net "P5E_PEX1_STN5_TX_C_DN<90>")
	)
	(segment
		(start 134.488428 -351.611438)
		(end 134.193788 -351.316798)
		(width 0.13462)
		(layer "F.Cu")
		(net "P5E_PEX1_STN5_TX_C_DN<90>")
	)
	(segment
		(start 134.193788 -351.316798)
		(end 134.193788 -350.685354)
		(width 0.13462)
		(layer "F.Cu")
		(net "P5E_PEX1_STN5_TX_C_DN<90>")
	)
	(segment
		(start 121.466864 -378.389642)
		(end 121.466864 -368.917982)
		(width 0.1651)
		(layer "In13.Cu")
		(net "P5E_PEX1_STN5_TX_C_DN<90>")
	)
	(segment
		(start 131.97967 -359.735882)
		(end 132.643118 -358.323896)
		(width 0.1651)
		(layer "In13.Cu")
		(net "P5E_PEX1_STN5_TX_C_DN<90>")
	)
	(segment
		(start 120.775476 -379.08103)
		(end 121.466864 -378.389642)
		(width 0.1651)
		(layer "In13.Cu")
		(net "P5E_PEX1_STN5_TX_C_DN<90>")
	)
	(segment
		(start 132.643118 -358.323896)
		(end 132.643118 -354.184458)
		(width 0.1651)
		(layer "In13.Cu")
		(net "P5E_PEX1_STN5_TX_C_DN<90>")
	)
	(segment
		(start 121.824496 -368.157252)
		(end 131.97967 -359.735882)
		(width 0.1651)
		(layer "In13.Cu")
		(net "P5E_PEX1_STN5_TX_C_DN<90>")
	)
	(segment
		(start 132.643118 -354.184458)
		(end 134.197598 -352.629978)
		(width 0.1651)
		(layer "In13.Cu")
		(net "P5E_PEX1_STN5_TX_C_DN<90>")
	)
	(segment
		(start 134.197598 -352.629978)
		(end 134.197598 -351.902268)
		(width 0.1651)
		(layer "In13.Cu")
		(net "P5E_PEX1_STN5_TX_C_DN<90>")
	)
	(segment
		(start 120.310148 -379.590046)
		(end 120.310148 -379.20803)
		(width 0.1651)
		(layer "In13.Cu")
		(net "P5E_PEX1_STN5_TX_C_DN<90>")
	)
	(segment
		(start 120.310148 -379.20803)
		(end 120.437148 -379.08103)
		(width 0.1651)
		(layer "In13.Cu")
		(net "P5E_PEX1_STN5_TX_C_DN<90>")
	)
	(segment
		(start 120.437148 -379.08103)
		(end 120.775476 -379.08103)
		(width 0.1651)
		(layer "In13.Cu")
		(net "P5E_PEX1_STN5_TX_C_DN<90>")
	)
	(segment
		(start 134.197598 -351.902268)
		(end 134.488428 -351.611438)
		(width 0.1651)
		(layer "In13.Cu")
		(net "P5E_PEX1_STN5_TX_C_DN<90>")
	)
	(segment
		(start 121.466864 -368.917982)
		(end 121.824496 -368.157252)
		(width 0.1651)
		(layer "In13.Cu")
		(net "P5E_PEX1_STN5_TX_C_DN<90>")
	)
	(segment
		(start 151.520144 -108.8898)
		(end 151.225504 -109.18444)
		(width 0.13462)
		(layer "F.Cu")
		(net "P5E_PEX1_STN1_TX_DP<21>")
	)
	(segment
		(start 152.471628 -109.20984)
		(end 152.151588 -108.8898)
		(width 0.13462)
		(layer "F.Cu")
		(net "P5E_PEX1_STN1_TX_DP<21>")
	)
	(segment
		(start 152.151588 -108.8898)
		(end 151.520144 -108.8898)
		(width 0.13462)
		(layer "F.Cu")
		(net "P5E_PEX1_STN1_TX_DP<21>")
	)
	(segment
		(start 141.42593 -137.971022)
		(end 143.992092 -144.166082)
		(width 0.1651)
		(layer "In9.Cu")
		(net "P5E_PEX1_STN1_TX_DP<21>")
	)
	(segment
		(start 145.29181 -161.844736)
		(end 180.16601 -264.873486)
		(width 0.1651)
		(layer "In9.Cu")
		(net "P5E_PEX1_STN1_TX_DP<21>")
	)
	(segment
		(start 147.74291 -112.806734)
		(end 147.743164 -112.806734)
		(width 0.1651)
		(layer "In9.Cu")
		(net "P5E_PEX1_STN1_TX_DP<21>")
	)
	(segment
		(start 151.225504 -109.18444)
		(end 150.934674 -108.89361)
		(width 0.1651)
		(layer "In9.Cu")
		(net "P5E_PEX1_STN1_TX_DP<21>")
	)
	(segment
		(start 147.425918 -113.871502)
		(end 147.276312 -113.933224)
		(width 0.1651)
		(layer "In9.Cu")
		(net "P5E_PEX1_STN1_TX_DP<21>")
	)
	(segment
		(start 146.620484 -115.517168)
		(end 146.62023 -115.517168)
		(width 0.1651)
		(layer "In9.Cu")
		(net "P5E_PEX1_STN1_TX_DP<21>")
	)
	(segment
		(start 145.157444 -119.048784)
		(end 141.42593 -131.350766)
		(width 0.1651)
		(layer "In9.Cu")
		(net "P5E_PEX1_STN1_TX_DP<21>")
	)
	(segment
		(start 145.876518 -117.312694)
		(end 145.687034 -117.770148)
		(width 0.1651)
		(layer "In9.Cu")
		(net "P5E_PEX1_STN1_TX_DP<21>")
	)
	(segment
		(start 147.743164 -112.806734)
		(end 147.55368 -113.264188)
		(width 0.1651)
		(layer "In9.Cu")
		(net "P5E_PEX1_STN1_TX_DP<21>")
	)
	(segment
		(start 180.223922 -280.129488)
		(end 180.38572 -280.129488)
		(width 0.1143)
		(layer "In9.Cu")
		(net "P5E_PEX1_STN1_TX_DP<21>")
	)
	(segment
		(start 180.16601 -271.526)
		(end 180.16601 -271.554448)
		(width 0.1143)
		(layer "In9.Cu")
		(net "P5E_PEX1_STN1_TX_DP<21>")
	)
	(segment
		(start 150.269194 -108.89361)
		(end 149.928072 -109.234732)
		(width 0.1651)
		(layer "In9.Cu")
		(net "P5E_PEX1_STN1_TX_DP<21>")
	)
	(segment
		(start 148.319236 -111.634524)
		(end 148.209762 -111.67999)
		(width 0.1651)
		(layer "In9.Cu")
		(net "P5E_PEX1_STN1_TX_DP<21>")
	)
	(segment
		(start 145.687034 -117.770148)
		(end 145.76171 -117.94998)
		(width 0.1651)
		(layer "In9.Cu")
		(net "P5E_PEX1_STN1_TX_DP<21>")
	)
	(segment
		(start 149.928072 -109.35335)
		(end 149.586442 -109.694726)
		(width 0.1651)
		(layer "In9.Cu")
		(net "P5E_PEX1_STN1_TX_DP<21>")
	)
	(segment
		(start 145.590006 -118.365016)
		(end 145.40992 -118.439184)
		(width 0.1651)
		(layer "In9.Cu")
		(net "P5E_PEX1_STN1_TX_DP<21>")
	)
	(segment
		(start 149.586442 -109.694726)
		(end 149.468078 -109.694726)
		(width 0.1651)
		(layer "In9.Cu")
		(net "P5E_PEX1_STN1_TX_DP<21>")
	)
	(segment
		(start 150.934674 -108.89361)
		(end 150.269194 -108.89361)
		(width 0.1651)
		(layer "In9.Cu")
		(net "P5E_PEX1_STN1_TX_DP<21>")
	)
	(segment
		(start 147.276312 -113.933224)
		(end 147.276566 -113.933224)
		(width 0.1651)
		(layer "In9.Cu")
		(net "P5E_PEX1_STN1_TX_DP<21>")
	)
	(segment
		(start 144.719294 -158.966408)
		(end 145.29181 -161.844736)
		(width 0.1651)
		(layer "In9.Cu")
		(net "P5E_PEX1_STN1_TX_DP<21>")
	)
	(segment
		(start 146.682206 -115.66652)
		(end 146.492722 -116.124482)
		(width 0.1651)
		(layer "In9.Cu")
		(net "P5E_PEX1_STN1_TX_DP<21>")
	)
	(segment
		(start 147.615656 -113.41354)
		(end 147.425918 -113.871502)
		(width 0.1651)
		(layer "In9.Cu")
		(net "P5E_PEX1_STN1_TX_DP<21>")
	)
	(segment
		(start 149.468078 -109.694726)
		(end 148.724366 -110.438184)
		(width 0.1651)
		(layer "In9.Cu")
		(net "P5E_PEX1_STN1_TX_DP<21>")
	)
	(segment
		(start 180.12029 -271.600168)
		(end 180.12029 -280.025856)
		(width 0.1143)
		(layer "In9.Cu")
		(net "P5E_PEX1_STN1_TX_DP<21>")
	)
	(segment
		(start 180.12029 -280.025856)
		(end 180.223922 -280.129488)
		(width 0.1143)
		(layer "In9.Cu")
		(net "P5E_PEX1_STN1_TX_DP<21>")
	)
	(segment
		(start 180.16601 -271.554448)
		(end 180.12029 -271.600168)
		(width 0.1143)
		(layer "In9.Cu")
		(net "P5E_PEX1_STN1_TX_DP<21>")
	)
	(segment
		(start 143.992092 -144.166082)
		(end 144.719294 -158.966408)
		(width 0.1651)
		(layer "In9.Cu")
		(net "P5E_PEX1_STN1_TX_DP<21>")
	)
	(segment
		(start 148.020278 -112.137698)
		(end 148.082254 -112.28705)
		(width 0.1651)
		(layer "In9.Cu")
		(net "P5E_PEX1_STN1_TX_DP<21>")
	)
	(segment
		(start 147.892516 -112.745012)
		(end 147.74291 -112.806734)
		(width 0.1651)
		(layer "In9.Cu")
		(net "P5E_PEX1_STN1_TX_DP<21>")
	)
	(segment
		(start 147.276566 -113.933224)
		(end 147.087082 -114.390678)
		(width 0.1651)
		(layer "In9.Cu")
		(net "P5E_PEX1_STN1_TX_DP<21>")
	)
	(segment
		(start 148.724366 -110.438184)
		(end 148.458936 -111.079026)
		(width 0.1651)
		(layer "In9.Cu")
		(net "P5E_PEX1_STN1_TX_DP<21>")
	)
	(segment
		(start 148.209762 -111.67999)
		(end 148.209762 -111.680498)
		(width 0.1651)
		(layer "In9.Cu")
		(net "P5E_PEX1_STN1_TX_DP<21>")
	)
	(segment
		(start 145.40992 -118.439184)
		(end 145.157444 -119.048784)
		(width 0.1651)
		(layer "In9.Cu")
		(net "P5E_PEX1_STN1_TX_DP<21>")
	)
	(segment
		(start 147.149058 -114.54003)
		(end 146.95932 -114.997992)
		(width 0.1651)
		(layer "In9.Cu")
		(net "P5E_PEX1_STN1_TX_DP<21>")
	)
	(segment
		(start 148.504148 -111.1885)
		(end 148.319236 -111.634524)
		(width 0.1651)
		(layer "In9.Cu")
		(net "P5E_PEX1_STN1_TX_DP<21>")
	)
	(segment
		(start 148.209762 -111.680498)
		(end 148.020278 -112.137698)
		(width 0.1651)
		(layer "In9.Cu")
		(net "P5E_PEX1_STN1_TX_DP<21>")
	)
	(segment
		(start 146.62023 -115.517168)
		(end 146.682206 -115.66652)
		(width 0.1651)
		(layer "In9.Cu")
		(net "P5E_PEX1_STN1_TX_DP<21>")
	)
	(segment
		(start 148.458936 -111.079026)
		(end 148.504148 -111.1885)
		(width 0.1651)
		(layer "In9.Cu")
		(net "P5E_PEX1_STN1_TX_DP<21>")
	)
	(segment
		(start 146.492722 -116.124482)
		(end 146.343116 -116.186204)
		(width 0.1651)
		(layer "In9.Cu")
		(net "P5E_PEX1_STN1_TX_DP<21>")
	)
	(segment
		(start 146.809968 -115.059968)
		(end 146.620484 -115.517168)
		(width 0.1651)
		(layer "In9.Cu")
		(net "P5E_PEX1_STN1_TX_DP<21>")
	)
	(segment
		(start 141.42593 -131.350766)
		(end 141.42593 -137.971022)
		(width 0.1651)
		(layer "In9.Cu")
		(net "P5E_PEX1_STN1_TX_DP<21>")
	)
	(segment
		(start 145.76171 -117.94998)
		(end 145.590006 -118.365016)
		(width 0.1651)
		(layer "In9.Cu")
		(net "P5E_PEX1_STN1_TX_DP<21>")
	)
	(segment
		(start 180.16601 -264.873486)
		(end 180.16601 -271.526)
		(width 0.1651)
		(layer "In9.Cu")
		(net "P5E_PEX1_STN1_TX_DP<21>")
	)
	(segment
		(start 148.082254 -112.28705)
		(end 147.892516 -112.745012)
		(width 0.1651)
		(layer "In9.Cu")
		(net "P5E_PEX1_STN1_TX_DP<21>")
	)
	(segment
		(start 180.38572 -280.129488)
		(end 180.50002 -280.015188)
		(width 0.1143)
		(layer "In9.Cu")
		(net "P5E_PEX1_STN1_TX_DP<21>")
	)
	(segment
		(start 146.343116 -116.186204)
		(end 146.153632 -116.643658)
		(width 0.1651)
		(layer "In9.Cu")
		(net "P5E_PEX1_STN1_TX_DP<21>")
	)
	(segment
		(start 146.228308 -116.82349)
		(end 146.056604 -117.238526)
		(width 0.1651)
		(layer "In9.Cu")
		(net "P5E_PEX1_STN1_TX_DP<21>")
	)
	(segment
		(start 147.55368 -113.264188)
		(end 147.615656 -113.41354)
		(width 0.1651)
		(layer "In9.Cu")
		(net "P5E_PEX1_STN1_TX_DP<21>")
	)
	(segment
		(start 146.809714 -115.059714)
		(end 146.809968 -115.059968)
		(width 0.1651)
		(layer "In9.Cu")
		(net "P5E_PEX1_STN1_TX_DP<21>")
	)
	(segment
		(start 147.087082 -114.390678)
		(end 147.149058 -114.54003)
		(width 0.1651)
		(layer "In9.Cu")
		(net "P5E_PEX1_STN1_TX_DP<21>")
	)
	(segment
		(start 146.153632 -116.643658)
		(end 146.228308 -116.82349)
		(width 0.1651)
		(layer "In9.Cu")
		(net "P5E_PEX1_STN1_TX_DP<21>")
	)
	(segment
		(start 180.50002 -280.015188)
		(end 180.50002 -279.749504)
		(width 0.1143)
		(layer "In9.Cu")
		(net "P5E_PEX1_STN1_TX_DP<21>")
	)
	(segment
		(start 146.056604 -117.238526)
		(end 145.876518 -117.312694)
		(width 0.1651)
		(layer "In9.Cu")
		(net "P5E_PEX1_STN1_TX_DP<21>")
	)
	(segment
		(start 146.95932 -114.997992)
		(end 146.809714 -115.059714)
		(width 0.1651)
		(layer "In9.Cu")
		(net "P5E_PEX1_STN1_TX_DP<21>")
	)
	(segment
		(start 149.928072 -109.234732)
		(end 149.928072 -109.35335)
		(width 0.1651)
		(layer "In9.Cu")
		(net "P5E_PEX1_STN1_TX_DP<21>")
	)
	(segment
		(start 124.272548 -355.978206)
		(end 124.592588 -355.658166)
		(width 0.13462)
		(layer "F.Cu")
		(net "P5E_PEX1_STN6_TX_DP<105>")
	)
	(segment
		(start 124.592588 -355.026722)
		(end 124.297948 -354.732082)
		(width 0.13462)
		(layer "F.Cu")
		(net "P5E_PEX1_STN6_TX_DP<105>")
	)
	(segment
		(start 124.592588 -355.658166)
		(end 124.592588 -355.026722)
		(width 0.13462)
		(layer "F.Cu")
		(net "P5E_PEX1_STN6_TX_DP<105>")
	)
	(segment
		(start 132.060696 -336.356198)
		(end 129.248916 -338.235036)
		(width 0.1651)
		(layer "In13.Cu")
		(net "P5E_PEX1_STN6_TX_DP<105>")
	)
	(segment
		(start 164.729668 -319.995296)
		(end 164.683948 -320.041016)
		(width 0.1143)
		(layer "In13.Cu")
		(net "P5E_PEX1_STN6_TX_DP<105>")
	)
	(segment
		(start 145.885154 -332.312772)
		(end 141.822932 -332.312772)
		(width 0.1651)
		(layer "In13.Cu")
		(net "P5E_PEX1_STN6_TX_DP<105>")
	)
	(segment
		(start 161.727388 -325.63689)
		(end 157.948122 -327.90257)
		(width 0.1651)
		(layer "In13.Cu")
		(net "P5E_PEX1_STN6_TX_DP<105>")
	)
	(segment
		(start 147.244816 -332.042516)
		(end 147.244816 -332.04277)
		(width 0.1651)
		(layer "In13.Cu")
		(net "P5E_PEX1_STN6_TX_DP<105>")
	)
	(segment
		(start 164.683948 -322.68033)
		(end 161.727388 -325.63689)
		(width 0.1651)
		(layer "In13.Cu")
		(net "P5E_PEX1_STN6_TX_DP<105>")
	)
	(segment
		(start 164.683948 -320.041016)
		(end 164.683948 -320.063114)
		(width 0.1143)
		(layer "In13.Cu")
		(net "P5E_PEX1_STN6_TX_DP<105>")
	)
	(segment
		(start 141.822932 -332.312772)
		(end 132.060696 -336.356198)
		(width 0.1651)
		(layer "In13.Cu")
		(net "P5E_PEX1_STN6_TX_DP<105>")
	)
	(segment
		(start 164.683948 -320.063114)
		(end 164.683948 -322.68033)
		(width 0.1651)
		(layer "In13.Cu")
		(net "P5E_PEX1_STN6_TX_DP<105>")
	)
	(segment
		(start 129.248916 -338.235036)
		(end 126.143258 -341.340694)
		(width 0.1651)
		(layer "In13.Cu")
		(net "P5E_PEX1_STN6_TX_DP<105>")
	)
	(segment
		(start 124.588778 -353.731068)
		(end 124.588778 -354.441252)
		(width 0.1651)
		(layer "In13.Cu")
		(net "P5E_PEX1_STN6_TX_DP<105>")
	)
	(segment
		(start 165.299898 -311.365392)
		(end 165.185598 -311.479692)
		(width 0.1143)
		(layer "In13.Cu")
		(net "P5E_PEX1_STN6_TX_DP<105>")
	)
	(segment
		(start 147.244816 -332.04277)
		(end 145.885154 -332.312772)
		(width 0.1651)
		(layer "In13.Cu")
		(net "P5E_PEX1_STN6_TX_DP<105>")
	)
	(segment
		(start 164.729668 -311.7342)
		(end 164.729668 -319.995296)
		(width 0.1143)
		(layer "In13.Cu")
		(net "P5E_PEX1_STN6_TX_DP<105>")
	)
	(segment
		(start 124.588778 -354.441252)
		(end 124.297948 -354.732082)
		(width 0.1651)
		(layer "In13.Cu")
		(net "P5E_PEX1_STN6_TX_DP<105>")
	)
	(segment
		(start 165.299898 -311.099962)
		(end 165.299898 -311.365392)
		(width 0.1143)
		(layer "In13.Cu")
		(net "P5E_PEX1_STN6_TX_DP<105>")
	)
	(segment
		(start 164.984176 -311.479692)
		(end 164.729668 -311.7342)
		(width 0.1143)
		(layer "In13.Cu")
		(net "P5E_PEX1_STN6_TX_DP<105>")
	)
	(segment
		(start 126.143258 -352.176588)
		(end 124.588778 -353.731068)
		(width 0.1651)
		(layer "In13.Cu")
		(net "P5E_PEX1_STN6_TX_DP<105>")
	)
	(segment
		(start 157.948122 -327.90257)
		(end 148.60397 -331.773022)
		(width 0.1651)
		(layer "In13.Cu")
		(net "P5E_PEX1_STN6_TX_DP<105>")
	)
	(segment
		(start 165.185598 -311.479692)
		(end 164.984176 -311.479692)
		(width 0.1143)
		(layer "In13.Cu")
		(net "P5E_PEX1_STN6_TX_DP<105>")
	)
	(segment
		(start 148.60397 -331.773022)
		(end 147.244816 -332.042516)
		(width 0.1651)
		(layer "In13.Cu")
		(net "P5E_PEX1_STN6_TX_DP<105>")
	)
	(segment
		(start 126.143258 -341.340694)
		(end 126.143258 -352.176588)
		(width 0.1651)
		(layer "In13.Cu")
		(net "P5E_PEX1_STN6_TX_DP<105>")
	)
	(segment
		(start 316.081664 -132.2832)
		(end 315.446156 -132.2832)
		(width 0.13462)
		(layer "F.Cu")
		(net "P5E_PEX2_STN0_TX_DP<5>")
	)
	(segment
		(start 316.374272 -132.575808)
		(end 316.081664 -132.2832)
		(width 0.13462)
		(layer "F.Cu")
		(net "P5E_PEX2_STN0_TX_DP<5>")
	)
	(segment
		(start 315.446156 -132.2832)
		(end 315.128148 -132.601208)
		(width 0.13462)
		(layer "F.Cu")
		(net "P5E_PEX2_STN0_TX_DP<5>")
	)
	(segment
		(start 323.758306 -145.17624)
		(end 323.758052 -145.17624)
		(width 0.1651)
		(layer "In9.Cu")
		(net "P5E_PEX2_STN0_TX_DP<5>")
	)
	(segment
		(start 318.854328 -133.887972)
		(end 319.183766 -134.683754)
		(width 0.1651)
		(layer "In9.Cu")
		(net "P5E_PEX2_STN0_TX_DP<5>")
	)
	(segment
		(start 320.587116 -138.33729)
		(end 320.719958 -138.392408)
		(width 0.1651)
		(layer "In9.Cu")
		(net "P5E_PEX2_STN0_TX_DP<5>")
	)
	(segment
		(start 317.483744 -178.432968)
		(end 313.7027 -221.652592)
		(width 0.1651)
		(layer "In9.Cu")
		(net "P5E_PEX2_STN0_TX_DP<5>")
	)
	(segment
		(start 316.374272 -132.575808)
		(end 316.665102 -132.284978)
		(width 0.1651)
		(layer "In9.Cu")
		(net "P5E_PEX2_STN0_TX_DP<5>")
	)
	(segment
		(start 323.368924 -144.786858)
		(end 323.758306 -145.17624)
		(width 0.1651)
		(layer "In9.Cu")
		(net "P5E_PEX2_STN0_TX_DP<5>")
	)
	(segment
		(start 321.014852 -139.370054)
		(end 321.147694 -139.425172)
		(width 0.1651)
		(layer "In9.Cu")
		(net "P5E_PEX2_STN0_TX_DP<5>")
	)
	(segment
		(start 320.41211 -137.914634)
		(end 320.587116 -138.33729)
		(width 0.1651)
		(layer "In9.Cu")
		(net "P5E_PEX2_STN0_TX_DP<5>")
	)
	(segment
		(start 320.292222 -137.359644)
		(end 320.466974 -137.781792)
		(width 0.1651)
		(layer "In9.Cu")
		(net "P5E_PEX2_STN0_TX_DP<5>")
	)
	(segment
		(start 313.7027 -221.652592)
		(end 316.27826 -251.144532)
		(width 0.1651)
		(layer "In9.Cu")
		(net "P5E_PEX2_STN0_TX_DP<5>")
	)
	(segment
		(start 320.039238 -136.749028)
		(end 319.984374 -136.88187)
		(width 0.1651)
		(layer "In9.Cu")
		(net "P5E_PEX2_STN0_TX_DP<5>")
	)
	(segment
		(start 319.984374 -136.88187)
		(end 320.15938 -137.304526)
		(width 0.1651)
		(layer "In9.Cu")
		(net "P5E_PEX2_STN0_TX_DP<5>")
	)
	(segment
		(start 320.15938 -137.304526)
		(end 320.292222 -137.359644)
		(width 0.1651)
		(layer "In9.Cu")
		(net "P5E_PEX2_STN0_TX_DP<5>")
	)
	(segment
		(start 318.206882 -133.240526)
		(end 318.854328 -133.887972)
		(width 0.1651)
		(layer "In9.Cu")
		(net "P5E_PEX2_STN0_TX_DP<5>")
	)
	(segment
		(start 319.43675 -135.294116)
		(end 319.611502 -135.716264)
		(width 0.1651)
		(layer "In9.Cu")
		(net "P5E_PEX2_STN0_TX_DP<5>")
	)
	(segment
		(start 321.575684 -140.457682)
		(end 323.368924 -144.786858)
		(width 0.1651)
		(layer "In9.Cu")
		(net "P5E_PEX2_STN0_TX_DP<5>")
	)
	(segment
		(start 317.739776 -132.77342)
		(end 317.739776 -132.91693)
		(width 0.1651)
		(layer "In9.Cu")
		(net "P5E_PEX2_STN0_TX_DP<5>")
	)
	(segment
		(start 316.093602 -282.933648)
		(end 316.065154 -282.933648)
		(width 0.1143)
		(layer "In9.Cu")
		(net "P5E_PEX2_STN0_TX_DP<5>")
	)
	(segment
		(start 316.971426 -282.933648)
		(end 316.093602 -282.933648)
		(width 0.1651)
		(layer "In9.Cu")
		(net "P5E_PEX2_STN0_TX_DP<5>")
	)
	(segment
		(start 319.611502 -135.716264)
		(end 319.556638 -135.849106)
		(width 0.1651)
		(layer "In9.Cu")
		(net "P5E_PEX2_STN0_TX_DP<5>")
	)
	(segment
		(start 327.250806 -159.252412)
		(end 318.614298 -174.217076)
		(width 0.1651)
		(layer "In9.Cu")
		(net "P5E_PEX2_STN0_TX_DP<5>")
	)
	(segment
		(start 327.448164 -268.480286)
		(end 327.752456 -271.958054)
		(width 0.1651)
		(layer "In9.Cu")
		(net "P5E_PEX2_STN0_TX_DP<5>")
	)
	(segment
		(start 316.27826 -251.144532)
		(end 326.77354 -266.851384)
		(width 0.1651)
		(layer "In9.Cu")
		(net "P5E_PEX2_STN0_TX_DP<5>")
	)
	(segment
		(start 326.77354 -266.851384)
		(end 327.448164 -268.480286)
		(width 0.1651)
		(layer "In9.Cu")
		(net "P5E_PEX2_STN0_TX_DP<5>")
	)
	(segment
		(start 321.267582 -139.980162)
		(end 321.442588 -140.402818)
		(width 0.1651)
		(layer "In9.Cu")
		(net "P5E_PEX2_STN0_TX_DP<5>")
	)
	(segment
		(start 320.719958 -138.392408)
		(end 320.89471 -138.814556)
		(width 0.1651)
		(layer "In9.Cu")
		(net "P5E_PEX2_STN0_TX_DP<5>")
	)
	(segment
		(start 319.556638 -135.849106)
		(end 319.731644 -136.271762)
		(width 0.1651)
		(layer "In9.Cu")
		(net "P5E_PEX2_STN0_TX_DP<5>")
	)
	(segment
		(start 307.429408 -283.19476)
		(end 307.429408 -283.435552)
		(width 0.1143)
		(layer "In9.Cu")
		(net "P5E_PEX2_STN0_TX_DP<5>")
	)
	(segment
		(start 326.886316 -274.048728)
		(end 318.729868 -282.205176)
		(width 0.1651)
		(layer "In9.Cu")
		(net "P5E_PEX2_STN0_TX_DP<5>")
	)
	(segment
		(start 318.063372 -133.240526)
		(end 318.206882 -133.240526)
		(width 0.1651)
		(layer "In9.Cu")
		(net "P5E_PEX2_STN0_TX_DP<5>")
	)
	(segment
		(start 307.6448 -282.979368)
		(end 307.429408 -283.19476)
		(width 0.1143)
		(layer "In9.Cu")
		(net "P5E_PEX2_STN0_TX_DP<5>")
	)
	(segment
		(start 307.429408 -283.435552)
		(end 307.315108 -283.549852)
		(width 0.1143)
		(layer "In9.Cu")
		(net "P5E_PEX2_STN0_TX_DP<5>")
	)
	(segment
		(start 318.729868 -282.205176)
		(end 316.971426 -282.933648)
		(width 0.1651)
		(layer "In9.Cu")
		(net "P5E_PEX2_STN0_TX_DP<5>")
	)
	(segment
		(start 323.758052 -145.17624)
		(end 327.250806 -153.608024)
		(width 0.1651)
		(layer "In9.Cu")
		(net "P5E_PEX2_STN0_TX_DP<5>")
	)
	(segment
		(start 327.250806 -153.608024)
		(end 327.250806 -159.252412)
		(width 0.1651)
		(layer "In9.Cu")
		(net "P5E_PEX2_STN0_TX_DP<5>")
	)
	(segment
		(start 317.739776 -132.91693)
		(end 318.063372 -133.240526)
		(width 0.1651)
		(layer "In9.Cu")
		(net "P5E_PEX2_STN0_TX_DP<5>")
	)
	(segment
		(start 321.322446 -139.84732)
		(end 321.267582 -139.980162)
		(width 0.1651)
		(layer "In9.Cu")
		(net "P5E_PEX2_STN0_TX_DP<5>")
	)
	(segment
		(start 321.147694 -139.425172)
		(end 321.322446 -139.84732)
		(width 0.1651)
		(layer "In9.Cu")
		(net "P5E_PEX2_STN0_TX_DP<5>")
	)
	(segment
		(start 319.128902 -134.816596)
		(end 319.303908 -135.239252)
		(width 0.1651)
		(layer "In9.Cu")
		(net "P5E_PEX2_STN0_TX_DP<5>")
	)
	(segment
		(start 319.303908 -135.239252)
		(end 319.43675 -135.294116)
		(width 0.1651)
		(layer "In9.Cu")
		(net "P5E_PEX2_STN0_TX_DP<5>")
	)
	(segment
		(start 316.019434 -282.979368)
		(end 307.6448 -282.979368)
		(width 0.1143)
		(layer "In9.Cu")
		(net "P5E_PEX2_STN0_TX_DP<5>")
	)
	(segment
		(start 319.731644 -136.271762)
		(end 319.864486 -136.32688)
		(width 0.1651)
		(layer "In9.Cu")
		(net "P5E_PEX2_STN0_TX_DP<5>")
	)
	(segment
		(start 318.614298 -174.217076)
		(end 317.483744 -178.432968)
		(width 0.1651)
		(layer "In9.Cu")
		(net "P5E_PEX2_STN0_TX_DP<5>")
	)
	(segment
		(start 320.839846 -138.947398)
		(end 321.014852 -139.370054)
		(width 0.1651)
		(layer "In9.Cu")
		(net "P5E_PEX2_STN0_TX_DP<5>")
	)
	(segment
		(start 320.89471 -138.814556)
		(end 320.839846 -138.947398)
		(width 0.1651)
		(layer "In9.Cu")
		(net "P5E_PEX2_STN0_TX_DP<5>")
	)
	(segment
		(start 307.315108 -283.549852)
		(end 307.049678 -283.549852)
		(width 0.1143)
		(layer "In9.Cu")
		(net "P5E_PEX2_STN0_TX_DP<5>")
	)
	(segment
		(start 319.864486 -136.32688)
		(end 320.039238 -136.749028)
		(width 0.1651)
		(layer "In9.Cu")
		(net "P5E_PEX2_STN0_TX_DP<5>")
	)
	(segment
		(start 316.065154 -282.933648)
		(end 316.019434 -282.979368)
		(width 0.1143)
		(layer "In9.Cu")
		(net "P5E_PEX2_STN0_TX_DP<5>")
	)
	(segment
		(start 319.183766 -134.683754)
		(end 319.128902 -134.816596)
		(width 0.1651)
		(layer "In9.Cu")
		(net "P5E_PEX2_STN0_TX_DP<5>")
	)
	(segment
		(start 327.752456 -271.958054)
		(end 326.886316 -274.048728)
		(width 0.1651)
		(layer "In9.Cu")
		(net "P5E_PEX2_STN0_TX_DP<5>")
	)
	(segment
		(start 316.665102 -132.284978)
		(end 317.251334 -132.284978)
		(width 0.1651)
		(layer "In9.Cu")
		(net "P5E_PEX2_STN0_TX_DP<5>")
	)
	(segment
		(start 320.466974 -137.781792)
		(end 320.41211 -137.914634)
		(width 0.1651)
		(layer "In9.Cu")
		(net "P5E_PEX2_STN0_TX_DP<5>")
	)
	(segment
		(start 321.442588 -140.402818)
		(end 321.575684 -140.457682)
		(width 0.1651)
		(layer "In9.Cu")
		(net "P5E_PEX2_STN0_TX_DP<5>")
	)
	(segment
		(start 317.251334 -132.284978)
		(end 317.739776 -132.77342)
		(width 0.1651)
		(layer "In9.Cu")
		(net "P5E_PEX2_STN0_TX_DP<5>")
	)
	(segment
		(start 277.792942 -342.734138)
		(end 278.087582 -342.439498)
		(width 0.13462)
		(layer "F.Cu")
		(net "P5E_PEX2_STN7_TX_DN<116>")
	)
	(segment
		(start 277.792942 -343.365582)
		(end 277.792942 -342.734138)
		(width 0.13462)
		(layer "F.Cu")
		(net "P5E_PEX2_STN7_TX_DN<116>")
	)
	(segment
		(start 278.112982 -343.685622)
		(end 277.792942 -343.365582)
		(width 0.13462)
		(layer "F.Cu")
		(net "P5E_PEX2_STN7_TX_DN<116>")
	)
	(segment
		(start 260.821424 -330.919074)
		(end 260.717792 -330.948538)
		(width 0.1651)
		(layer "In7.Cu")
		(net "P5E_PEX2_STN7_TX_DN<116>")
	)
	(segment
		(start 274.065238 -305.020218)
		(end 274.179538 -305.134518)
		(width 0.1143)
		(layer "In7.Cu")
		(net "P5E_PEX2_STN7_TX_DN<116>")
	)
	(segment
		(start 274.065238 -305.399948)
		(end 273.799808 -305.399948)
		(width 0.1143)
		(layer "In7.Cu")
		(net "P5E_PEX2_STN7_TX_DN<116>")
	)
	(segment
		(start 258.886452 -307.825648)
		(end 258.887468 -307.717952)
		(width 0.1651)
		(layer "In7.Cu")
		(net "P5E_PEX2_STN7_TX_DN<116>")
	)
	(segment
		(start 254.06477 -316.118748)
		(end 255.845818 -312.737754)
		(width 0.1651)
		(layer "In7.Cu")
		(net "P5E_PEX2_STN7_TX_DN<116>")
	)
	(segment
		(start 260.20903 -306.413662)
		(end 266.98321 -305.065938)
		(width 0.1651)
		(layer "In7.Cu")
		(net "P5E_PEX2_STN7_TX_DN<116>")
	)
	(segment
		(start 256.37871 -311.726326)
		(end 256.48158 -311.694322)
		(width 0.1651)
		(layer "In7.Cu")
		(net "P5E_PEX2_STN7_TX_DN<116>")
	)
	(segment
		(start 258.532884 -308.17312)
		(end 258.886452 -307.825648)
		(width 0.1651)
		(layer "In7.Cu")
		(net "P5E_PEX2_STN7_TX_DN<116>")
	)
	(segment
		(start 267.8938 -305.065938)
		(end 267.93952 -305.020218)
		(width 0.1143)
		(layer "In7.Cu")
		(net "P5E_PEX2_STN7_TX_DN<116>")
	)
	(segment
		(start 256.71272 -311.255918)
		(end 256.68097 -311.153048)
		(width 0.1651)
		(layer "In7.Cu")
		(net "P5E_PEX2_STN7_TX_DN<116>")
	)
	(segment
		(start 257.213862 -310.14162)
		(end 257.444494 -309.70347)
		(width 0.1651)
		(layer "In7.Cu")
		(net "P5E_PEX2_STN7_TX_DN<116>")
	)
	(segment
		(start 257.059176 -310.668924)
		(end 257.259328 -310.289194)
		(width 0.1651)
		(layer "In7.Cu")
		(net "P5E_PEX2_STN7_TX_DN<116>")
	)
	(segment
		(start 277.796752 -341.5538)
		(end 277.66772 -341.314278)
		(width 0.1651)
		(layer "In7.Cu")
		(net "P5E_PEX2_STN7_TX_DN<116>")
	)
	(segment
		(start 256.68097 -311.153048)
		(end 256.911602 -310.714898)
		(width 0.1651)
		(layer "In7.Cu")
		(net "P5E_PEX2_STN7_TX_DN<116>")
	)
	(segment
		(start 262.252714 -331.717142)
		(end 261.819898 -331.475588)
		(width 0.1651)
		(layer "In7.Cu")
		(net "P5E_PEX2_STN7_TX_DN<116>")
	)
	(segment
		(start 256.48158 -311.694322)
		(end 256.71272 -311.255918)
		(width 0.1651)
		(layer "In7.Cu")
		(net "P5E_PEX2_STN7_TX_DN<116>")
	)
	(segment
		(start 252.857 -322.850764)
		(end 252.857 -319.061846)
		(width 0.1651)
		(layer "In7.Cu")
		(net "P5E_PEX2_STN7_TX_DN<116>")
	)
	(segment
		(start 274.179538 -305.285648)
		(end 274.065238 -305.399948)
		(width 0.1143)
		(layer "In7.Cu")
		(net "P5E_PEX2_STN7_TX_DN<116>")
	)
	(segment
		(start 259.702808 -306.916836)
		(end 260.20903 -306.413662)
		(width 0.1651)
		(layer "In7.Cu")
		(net "P5E_PEX2_STN7_TX_DN<116>")
	)
	(segment
		(start 256.148078 -312.164476)
		(end 256.37871 -311.726326)
		(width 0.1651)
		(layer "In7.Cu")
		(net "P5E_PEX2_STN7_TX_DN<116>")
	)
	(segment
		(start 257.7465 -309.130192)
		(end 258.064508 -308.526434)
		(width 0.1651)
		(layer "In7.Cu")
		(net "P5E_PEX2_STN7_TX_DN<116>")
	)
	(segment
		(start 256.792984 -328.760328)
		(end 254.01016 -325.634858)
		(width 0.1651)
		(layer "In7.Cu")
		(net "P5E_PEX2_STN7_TX_DN<116>")
	)
	(segment
		(start 258.887468 -307.717952)
		(end 259.240528 -307.370988)
		(width 0.1651)
		(layer "In7.Cu")
		(net "P5E_PEX2_STN7_TX_DN<116>")
	)
	(segment
		(start 261.25424 -331.160374)
		(end 260.821424 -330.919074)
		(width 0.1651)
		(layer "In7.Cu")
		(net "P5E_PEX2_STN7_TX_DN<116>")
	)
	(segment
		(start 278.087582 -342.439498)
		(end 277.796752 -342.148668)
		(width 0.1651)
		(layer "In7.Cu")
		(net "P5E_PEX2_STN7_TX_DN<116>")
	)
	(segment
		(start 257.259328 -310.289194)
		(end 257.213862 -310.14162)
		(width 0.1651)
		(layer "In7.Cu")
		(net "P5E_PEX2_STN7_TX_DN<116>")
	)
	(segment
		(start 254.01016 -325.634858)
		(end 252.857 -322.850764)
		(width 0.1651)
		(layer "In7.Cu")
		(net "P5E_PEX2_STN7_TX_DN<116>")
	)
	(segment
		(start 261.716266 -331.505052)
		(end 261.283704 -331.264006)
		(width 0.1651)
		(layer "In7.Cu")
		(net "P5E_PEX2_STN7_TX_DN<116>")
	)
	(segment
		(start 275.661882 -339.279992)
		(end 262.282178 -331.820774)
		(width 0.1651)
		(layer "In7.Cu")
		(net "P5E_PEX2_STN7_TX_DN<116>")
	)
	(segment
		(start 259.240528 -307.370988)
		(end 259.348224 -307.372004)
		(width 0.1651)
		(layer "In7.Cu")
		(net "P5E_PEX2_STN7_TX_DN<116>")
	)
	(segment
		(start 258.425188 -308.172104)
		(end 258.532884 -308.17312)
		(width 0.1651)
		(layer "In7.Cu")
		(net "P5E_PEX2_STN7_TX_DN<116>")
	)
	(segment
		(start 257.58648 -309.659274)
		(end 257.790696 -309.272178)
		(width 0.1651)
		(layer "In7.Cu")
		(net "P5E_PEX2_STN7_TX_DN<116>")
	)
	(segment
		(start 277.66772 -341.314278)
		(end 275.661882 -339.279992)
		(width 0.1651)
		(layer "In7.Cu")
		(net "P5E_PEX2_STN7_TX_DN<116>")
	)
	(segment
		(start 277.796752 -342.148668)
		(end 277.796752 -341.5538)
		(width 0.1651)
		(layer "In7.Cu")
		(net "P5E_PEX2_STN7_TX_DN<116>")
	)
	(segment
		(start 255.845818 -312.737754)
		(end 255.948688 -312.70575)
		(width 0.1651)
		(layer "In7.Cu")
		(net "P5E_PEX2_STN7_TX_DN<116>")
	)
	(segment
		(start 259.701792 -307.024532)
		(end 259.702808 -306.916836)
		(width 0.1651)
		(layer "In7.Cu")
		(net "P5E_PEX2_STN7_TX_DN<116>")
	)
	(segment
		(start 267.93952 -305.020218)
		(end 274.065238 -305.020218)
		(width 0.1143)
		(layer "In7.Cu")
		(net "P5E_PEX2_STN7_TX_DN<116>")
	)
	(segment
		(start 259.348224 -307.372004)
		(end 259.701792 -307.024532)
		(width 0.1651)
		(layer "In7.Cu")
		(net "P5E_PEX2_STN7_TX_DN<116>")
	)
	(segment
		(start 252.857 -319.061846)
		(end 254.06477 -316.118748)
		(width 0.1651)
		(layer "In7.Cu")
		(net "P5E_PEX2_STN7_TX_DN<116>")
	)
	(segment
		(start 258.064508 -308.526434)
		(end 258.425188 -308.172104)
		(width 0.1651)
		(layer "In7.Cu")
		(net "P5E_PEX2_STN7_TX_DN<116>")
	)
	(segment
		(start 260.717792 -330.948538)
		(end 256.792984 -328.760328)
		(width 0.1651)
		(layer "In7.Cu")
		(net "P5E_PEX2_STN7_TX_DN<116>")
	)
	(segment
		(start 261.283704 -331.264006)
		(end 261.25424 -331.160374)
		(width 0.1651)
		(layer "In7.Cu")
		(net "P5E_PEX2_STN7_TX_DN<116>")
	)
	(segment
		(start 257.444494 -309.70347)
		(end 257.58648 -309.659274)
		(width 0.1651)
		(layer "In7.Cu")
		(net "P5E_PEX2_STN7_TX_DN<116>")
	)
	(segment
		(start 274.179538 -305.134518)
		(end 274.179538 -305.285648)
		(width 0.1143)
		(layer "In7.Cu")
		(net "P5E_PEX2_STN7_TX_DN<116>")
	)
	(segment
		(start 257.790696 -309.272178)
		(end 257.7465 -309.130192)
		(width 0.1651)
		(layer "In7.Cu")
		(net "P5E_PEX2_STN7_TX_DN<116>")
	)
	(segment
		(start 256.911602 -310.714898)
		(end 257.059176 -310.668924)
		(width 0.1651)
		(layer "In7.Cu")
		(net "P5E_PEX2_STN7_TX_DN<116>")
	)
	(segment
		(start 267.865352 -305.065938)
		(end 267.8938 -305.065938)
		(width 0.1143)
		(layer "In7.Cu")
		(net "P5E_PEX2_STN7_TX_DN<116>")
	)
	(segment
		(start 261.819898 -331.475588)
		(end 261.716266 -331.505052)
		(width 0.1651)
		(layer "In7.Cu")
		(net "P5E_PEX2_STN7_TX_DN<116>")
	)
	(segment
		(start 255.948688 -312.70575)
		(end 256.179828 -312.267346)
		(width 0.1651)
		(layer "In7.Cu")
		(net "P5E_PEX2_STN7_TX_DN<116>")
	)
	(segment
		(start 266.98321 -305.065938)
		(end 267.865352 -305.065938)
		(width 0.1651)
		(layer "In7.Cu")
		(net "P5E_PEX2_STN7_TX_DN<116>")
	)
	(segment
		(start 256.179828 -312.267346)
		(end 256.148078 -312.164476)
		(width 0.1651)
		(layer "In7.Cu")
		(net "P5E_PEX2_STN7_TX_DN<116>")
	)
	(segment
		(start 262.282178 -331.820774)
		(end 262.252714 -331.717142)
		(width 0.1651)
		(layer "In7.Cu")
		(net "P5E_PEX2_STN7_TX_DN<116>")
	)
	(via
		(at 181.796182 -113.55197)
		(size 0.6604)
		(drill 0.3302)
		(layers "F.Cu" "B.Cu")
		(net "RST_SMB_NIC3_MUX_N")
	)
	(segment
		(start 182.57647 -111.76381)
		(end 182.57647 -111.334042)
		(width 0.13208)
		(layer "B.Cu")
		(net "RST_SMB_NIC3_MUX_N")
	)
	(segment
		(start 181.796182 -113.55197)
		(end 181.796182 -112.544098)
		(width 0.13208)
		(layer "B.Cu")
		(net "RST_SMB_NIC3_MUX_N")
	)
	(segment
		(start 185.092086 -114.021616)
		(end 182.923688 -114.021616)
		(width 0.13208)
		(layer "B.Cu")
		(net "RST_SMB_NIC3_MUX_N")
	)
	(segment
		(start 185.349134 -114.278664)
		(end 185.092086 -114.021616)
		(width 0.13208)
		(layer "B.Cu")
		(net "RST_SMB_NIC3_MUX_N")
	)
	(segment
		(start 182.923688 -114.021616)
		(end 182.454042 -113.55197)
		(width 0.13208)
		(layer "B.Cu")
		(net "RST_SMB_NIC3_MUX_N")
	)
	(segment
		(start 185.349134 -114.713512)
		(end 185.349134 -114.278664)
		(width 0.13208)
		(layer "B.Cu")
		(net "RST_SMB_NIC3_MUX_N")
	)
	(segment
		(start 182.454042 -113.55197)
		(end 181.796182 -113.55197)
		(width 0.13208)
		(layer "B.Cu")
		(net "RST_SMB_NIC3_MUX_N")
	)
	(segment
		(start 181.796182 -112.544098)
		(end 182.57647 -111.76381)
		(width 0.13208)
		(layer "B.Cu")
		(net "RST_SMB_NIC3_MUX_N")
	)
	(segment
		(start 154.793696 -103.483156)
		(end 154.162252 -103.483156)
		(width 0.13462)
		(layer "F.Cu")
		(net "P5E_PEX1_STN1_TX_DN<18>")
	)
	(segment
		(start 155.113736 -103.803196)
		(end 154.793696 -103.483156)
		(width 0.13462)
		(layer "F.Cu")
		(net "P5E_PEX1_STN1_TX_DN<18>")
	)
	(segment
		(start 154.162252 -103.483156)
		(end 153.867612 -103.777796)
		(width 0.13462)
		(layer "F.Cu")
		(net "P5E_PEX1_STN1_TX_DN<18>")
	)
	(segment
		(start 177.649632 -278.115268)
		(end 177.649632 -277.849838)
		(width 0.1143)
		(layer "In9.Cu")
		(net "P5E_PEX1_STN1_TX_DN<18>")
	)
	(segment
		(start 147.797266 -106.336846)
		(end 147.797266 -106.49839)
		(width 0.1651)
		(layer "In9.Cu")
		(net "P5E_PEX1_STN1_TX_DN<18>")
	)
	(segment
		(start 144.684496 -111.933736)
		(end 144.53489 -111.995712)
		(width 0.1651)
		(layer "In9.Cu")
		(net "P5E_PEX1_STN1_TX_DN<18>")
	)
	(segment
		(start 146.229324 -107.904788)
		(end 145.948146 -108.58373)
		(width 0.1651)
		(layer "In9.Cu")
		(net "P5E_PEX1_STN1_TX_DN<18>")
	)
	(segment
		(start 151.80691 -103.486966)
		(end 151.27986 -103.70566)
		(width 0.1651)
		(layer "In9.Cu")
		(net "P5E_PEX1_STN1_TX_DN<18>")
	)
	(segment
		(start 153.576782 -103.486966)
		(end 152.917652 -103.486966)
		(width 0.1651)
		(layer "In9.Cu")
		(net "P5E_PEX1_STN1_TX_DN<18>")
	)
	(segment
		(start 145.256504 -110.552738)
		(end 145.106898 -110.614714)
		(width 0.1651)
		(layer "In9.Cu")
		(net "P5E_PEX1_STN1_TX_DN<18>")
	)
	(segment
		(start 145.441162 -110.106714)
		(end 145.256504 -110.552738)
		(width 0.1651)
		(layer "In9.Cu")
		(net "P5E_PEX1_STN1_TX_DN<18>")
	)
	(segment
		(start 144.807178 -111.33836)
		(end 144.869154 -111.487712)
		(width 0.1651)
		(layer "In9.Cu")
		(net "P5E_PEX1_STN1_TX_DN<18>")
	)
	(segment
		(start 150.77186 -104.039416)
		(end 150.622508 -103.977694)
		(width 0.1651)
		(layer "In9.Cu")
		(net "P5E_PEX1_STN1_TX_DN<18>")
	)
	(segment
		(start 151.27986 -103.70566)
		(end 151.27986 -103.705152)
		(width 0.1651)
		(layer "In9.Cu")
		(net "P5E_PEX1_STN1_TX_DN<18>")
	)
	(segment
		(start 149.485858 -104.809798)
		(end 149.144228 -105.151428)
		(width 0.1651)
		(layer "In9.Cu")
		(net "P5E_PEX1_STN1_TX_DN<18>")
	)
	(segment
		(start 148.982684 -105.151428)
		(end 148.641562 -105.49255)
		(width 0.1651)
		(layer "In9.Cu")
		(net "P5E_PEX1_STN1_TX_DN<18>")
	)
	(segment
		(start 141.812772 -159.428434)
		(end 142.38859 -162.323272)
		(width 0.1651)
		(layer "In9.Cu")
		(net "P5E_PEX1_STN1_TX_DN<18>")
	)
	(segment
		(start 152.320752 -103.601266)
		(end 152.206452 -103.486966)
		(width 0.1651)
		(layer "In9.Cu")
		(net "P5E_PEX1_STN1_TX_DN<18>")
	)
	(segment
		(start 145.106898 -110.614714)
		(end 144.807178 -111.33836)
		(width 0.1651)
		(layer "In9.Cu")
		(net "P5E_PEX1_STN1_TX_DN<18>")
	)
	(segment
		(start 146.010122 -108.733082)
		(end 145.825464 -109.17936)
		(width 0.1651)
		(layer "In9.Cu")
		(net "P5E_PEX1_STN1_TX_DN<18>")
	)
	(segment
		(start 148.299932 -105.995724)
		(end 148.138388 -105.995724)
		(width 0.1651)
		(layer "In9.Cu")
		(net "P5E_PEX1_STN1_TX_DN<18>")
	)
	(segment
		(start 138.52271 -138.637518)
		(end 141.095984 -144.84985)
		(width 0.1651)
		(layer "In9.Cu")
		(net "P5E_PEX1_STN1_TX_DN<18>")
	)
	(segment
		(start 143.600678 -114.250724)
		(end 138.52271 -130.990848)
		(width 0.1651)
		(layer "In9.Cu")
		(net "P5E_PEX1_STN1_TX_DN<18>")
	)
	(segment
		(start 151.27986 -103.705152)
		(end 151.217884 -103.854758)
		(width 0.1651)
		(layer "In9.Cu")
		(net "P5E_PEX1_STN1_TX_DN<18>")
	)
	(segment
		(start 148.138388 -105.995724)
		(end 147.797266 -106.336846)
		(width 0.1651)
		(layer "In9.Cu")
		(net "P5E_PEX1_STN1_TX_DN<18>")
	)
	(segment
		(start 147.455636 -106.84002)
		(end 147.294092 -106.84002)
		(width 0.1651)
		(layer "In9.Cu")
		(net "P5E_PEX1_STN1_TX_DN<18>")
	)
	(segment
		(start 141.095984 -144.84985)
		(end 141.812772 -159.428434)
		(width 0.1651)
		(layer "In9.Cu")
		(net "P5E_PEX1_STN1_TX_DN<18>")
	)
	(segment
		(start 138.52271 -130.990848)
		(end 138.52271 -138.637518)
		(width 0.1651)
		(layer "In9.Cu")
		(net "P5E_PEX1_STN1_TX_DN<18>")
	)
	(segment
		(start 177.270156 -271.546066)
		(end 177.270156 -278.12619)
		(width 0.1143)
		(layer "In9.Cu")
		(net "P5E_PEX1_STN1_TX_DN<18>")
	)
	(segment
		(start 177.315876 -265.511534)
		(end 177.315876 -271.471898)
		(width 0.1651)
		(layer "In9.Cu")
		(net "P5E_PEX1_STN1_TX_DN<18>")
	)
	(segment
		(start 147.797266 -106.49839)
		(end 147.455636 -106.84002)
		(width 0.1651)
		(layer "In9.Cu")
		(net "P5E_PEX1_STN1_TX_DN<18>")
	)
	(segment
		(start 152.803352 -103.601266)
		(end 152.320752 -103.601266)
		(width 0.1651)
		(layer "In9.Cu")
		(net "P5E_PEX1_STN1_TX_DN<18>")
	)
	(segment
		(start 144.53489 -111.995712)
		(end 143.600678 -114.250724)
		(width 0.1651)
		(layer "In9.Cu")
		(net "P5E_PEX1_STN1_TX_DN<18>")
	)
	(segment
		(start 149.144228 -105.151428)
		(end 148.982684 -105.151428)
		(width 0.1651)
		(layer "In9.Cu")
		(net "P5E_PEX1_STN1_TX_DN<18>")
	)
	(segment
		(start 152.917652 -103.486966)
		(end 152.803352 -103.601266)
		(width 0.1651)
		(layer "In9.Cu")
		(net "P5E_PEX1_STN1_TX_DN<18>")
	)
	(segment
		(start 145.379186 -109.957362)
		(end 145.441162 -110.106714)
		(width 0.1651)
		(layer "In9.Cu")
		(net "P5E_PEX1_STN1_TX_DN<18>")
	)
	(segment
		(start 177.270156 -278.12619)
		(end 177.373534 -278.229568)
		(width 0.1143)
		(layer "In9.Cu")
		(net "P5E_PEX1_STN1_TX_DN<18>")
	)
	(segment
		(start 145.675858 -109.241082)
		(end 145.379186 -109.957362)
		(width 0.1651)
		(layer "In9.Cu")
		(net "P5E_PEX1_STN1_TX_DN<18>")
	)
	(segment
		(start 177.315876 -271.500346)
		(end 177.270156 -271.546066)
		(width 0.1143)
		(layer "In9.Cu")
		(net "P5E_PEX1_STN1_TX_DN<18>")
	)
	(segment
		(start 149.485858 -104.648254)
		(end 149.485858 -104.809798)
		(width 0.1651)
		(layer "In9.Cu")
		(net "P5E_PEX1_STN1_TX_DN<18>")
	)
	(segment
		(start 145.948146 -108.58373)
		(end 146.010122 -108.733082)
		(width 0.1651)
		(layer "In9.Cu")
		(net "P5E_PEX1_STN1_TX_DN<18>")
	)
	(segment
		(start 148.641562 -105.49255)
		(end 148.641562 -105.654094)
		(width 0.1651)
		(layer "In9.Cu")
		(net "P5E_PEX1_STN1_TX_DN<18>")
	)
	(segment
		(start 177.535332 -278.229568)
		(end 177.649632 -278.115268)
		(width 0.1143)
		(layer "In9.Cu")
		(net "P5E_PEX1_STN1_TX_DN<18>")
	)
	(segment
		(start 177.373534 -278.229568)
		(end 177.535332 -278.229568)
		(width 0.1143)
		(layer "In9.Cu")
		(net "P5E_PEX1_STN1_TX_DN<18>")
	)
	(segment
		(start 153.867612 -103.777796)
		(end 153.576782 -103.486966)
		(width 0.1651)
		(layer "In9.Cu")
		(net "P5E_PEX1_STN1_TX_DN<18>")
	)
	(segment
		(start 145.825464 -109.17936)
		(end 145.675858 -109.241082)
		(width 0.1651)
		(layer "In9.Cu")
		(net "P5E_PEX1_STN1_TX_DN<18>")
	)
	(segment
		(start 144.869154 -111.487712)
		(end 144.684496 -111.933736)
		(width 0.1651)
		(layer "In9.Cu")
		(net "P5E_PEX1_STN1_TX_DN<18>")
	)
	(segment
		(start 151.217884 -103.854758)
		(end 150.77186 -104.039416)
		(width 0.1651)
		(layer "In9.Cu")
		(net "P5E_PEX1_STN1_TX_DN<18>")
	)
	(segment
		(start 149.82698 -104.307132)
		(end 149.485858 -104.648254)
		(width 0.1651)
		(layer "In9.Cu")
		(net "P5E_PEX1_STN1_TX_DN<18>")
	)
	(segment
		(start 177.315876 -271.471898)
		(end 177.315876 -271.500346)
		(width 0.1143)
		(layer "In9.Cu")
		(net "P5E_PEX1_STN1_TX_DN<18>")
	)
	(segment
		(start 147.294092 -106.84002)
		(end 146.229324 -107.904788)
		(width 0.1651)
		(layer "In9.Cu")
		(net "P5E_PEX1_STN1_TX_DN<18>")
	)
	(segment
		(start 150.622508 -103.977694)
		(end 149.82698 -104.307132)
		(width 0.1651)
		(layer "In9.Cu")
		(net "P5E_PEX1_STN1_TX_DN<18>")
	)
	(segment
		(start 148.641562 -105.654094)
		(end 148.299932 -105.995724)
		(width 0.1651)
		(layer "In9.Cu")
		(net "P5E_PEX1_STN1_TX_DN<18>")
	)
	(segment
		(start 152.206452 -103.486966)
		(end 151.80691 -103.486966)
		(width 0.1651)
		(layer "In9.Cu")
		(net "P5E_PEX1_STN1_TX_DN<18>")
	)
	(segment
		(start 142.38859 -162.323272)
		(end 177.315876 -265.511534)
		(width 0.1651)
		(layer "In9.Cu")
		(net "P5E_PEX1_STN1_TX_DN<18>")
	)
	(segment
		(start 180.814472 -355.978206)
		(end 181.134512 -355.658166)
		(width 0.13462)
		(layer "F.Cu")
		(net "P5E_PEX1_STN7_TX_DN<122>")
	)
	(segment
		(start 181.134512 -355.658166)
		(end 181.134512 -355.026722)
		(width 0.13462)
		(layer "F.Cu")
		(net "P5E_PEX1_STN7_TX_DN<122>")
	)
	(segment
		(start 181.134512 -355.026722)
		(end 180.839872 -354.732082)
		(width 0.13462)
		(layer "F.Cu")
		(net "P5E_PEX1_STN7_TX_DN<122>")
	)
	(segment
		(start 152.314402 -315.553598)
		(end 152.588468 -315.279532)
		(width 0.1143)
		(layer "In11.Cu")
		(net "P5E_PEX1_STN7_TX_DN<122>")
	)
	(segment
		(start 151.02713 -316.775846)
		(end 152.233884 -315.569092)
		(width 0.1651)
		(layer "In11.Cu")
		(net "P5E_PEX1_STN7_TX_DN<122>")
	)
	(segment
		(start 153.16454 -315.279532)
		(end 153.32964 -315.114432)
		(width 0.1143)
		(layer "In11.Cu")
		(net "P5E_PEX1_STN7_TX_DN<122>")
	)
	(segment
		(start 181.130702 -354.441252)
		(end 181.130702 -353.683062)
		(width 0.1651)
		(layer "In11.Cu")
		(net "P5E_PEX1_STN7_TX_DN<122>")
	)
	(segment
		(start 152.588468 -315.279532)
		(end 153.16454 -315.279532)
		(width 0.1143)
		(layer "In11.Cu")
		(net "P5E_PEX1_STN7_TX_DN<122>")
	)
	(segment
		(start 174.40402 -335.453228)
		(end 156.433266 -326.173592)
		(width 0.1651)
		(layer "In11.Cu")
		(net "P5E_PEX1_STN7_TX_DN<122>")
	)
	(segment
		(start 156.433266 -326.173592)
		(end 152.307036 -321.86626)
		(width 0.1651)
		(layer "In11.Cu")
		(net "P5E_PEX1_STN7_TX_DN<122>")
	)
	(segment
		(start 182.685182 -341.308182)
		(end 180.555392 -338.999576)
		(width 0.1651)
		(layer "In11.Cu")
		(net "P5E_PEX1_STN7_TX_DN<122>")
	)
	(segment
		(start 152.307036 -321.86626)
		(end 151.02713 -317.64859)
		(width 0.1651)
		(layer "In11.Cu")
		(net "P5E_PEX1_STN7_TX_DN<122>")
	)
	(segment
		(start 182.685182 -352.128582)
		(end 182.685182 -341.308182)
		(width 0.1651)
		(layer "In11.Cu")
		(net "P5E_PEX1_STN7_TX_DN<122>")
	)
	(segment
		(start 153.24074 -314.899802)
		(end 152.94991 -314.899802)
		(width 0.1143)
		(layer "In11.Cu")
		(net "P5E_PEX1_STN7_TX_DN<122>")
	)
	(segment
		(start 180.839872 -354.732082)
		(end 181.130702 -354.441252)
		(width 0.1651)
		(layer "In11.Cu")
		(net "P5E_PEX1_STN7_TX_DN<122>")
	)
	(segment
		(start 152.249378 -315.553598)
		(end 152.314402 -315.553598)
		(width 0.1143)
		(layer "In11.Cu")
		(net "P5E_PEX1_STN7_TX_DN<122>")
	)
	(segment
		(start 181.130702 -353.683062)
		(end 182.685182 -352.128582)
		(width 0.1651)
		(layer "In11.Cu")
		(net "P5E_PEX1_STN7_TX_DN<122>")
	)
	(segment
		(start 180.555392 -338.999576)
		(end 174.40402 -335.453228)
		(width 0.1651)
		(layer "In11.Cu")
		(net "P5E_PEX1_STN7_TX_DN<122>")
	)
	(segment
		(start 151.02713 -317.64859)
		(end 151.02713 -316.775846)
		(width 0.1651)
		(layer "In11.Cu")
		(net "P5E_PEX1_STN7_TX_DN<122>")
	)
	(segment
		(start 153.32964 -315.114432)
		(end 153.32964 -314.988702)
		(width 0.1143)
		(layer "In11.Cu")
		(net "P5E_PEX1_STN7_TX_DN<122>")
	)
	(segment
		(start 153.32964 -314.988702)
		(end 153.24074 -314.899802)
		(width 0.1143)
		(layer "In11.Cu")
		(net "P5E_PEX1_STN7_TX_DN<122>")
	)
	(segment
		(start 152.233884 -315.569092)
		(end 152.249378 -315.553598)
		(width 0.1143)
		(layer "In11.Cu")
		(net "P5E_PEX1_STN7_TX_DN<122>")
	)
	(segment
		(start 267.935202 -101.984302)
		(end 268.243304 -101.6762)
		(width 0.13462)
		(layer "F.Cu")
		(net "P5E_PEX2_STN1_TX_DP<17>")
	)
	(segment
		(start 268.847824 -101.6762)
		(end 269.181326 -102.009702)
		(width 0.13462)
		(layer "F.Cu")
		(net "P5E_PEX2_STN1_TX_DP<17>")
	)
	(segment
		(start 268.243304 -101.6762)
		(end 268.847824 -101.6762)
		(width 0.13462)
		(layer "F.Cu")
		(net "P5E_PEX2_STN1_TX_DP<17>")
	)
	(segment
		(start 266.086082 -102.44582)
		(end 266.584938 -101.946964)
		(width 0.1651)
		(layer "In9.Cu")
		(net "P5E_PEX2_STN1_TX_DP<17>")
	)
	(segment
		(start 292.79977 -279.749504)
		(end 292.79977 -280.015188)
		(width 0.1143)
		(layer "In9.Cu")
		(net "P5E_PEX2_STN1_TX_DP<17>")
	)
	(segment
		(start 259.703824 -111.72698)
		(end 259.893816 -111.269272)
		(width 0.1651)
		(layer "In9.Cu")
		(net "P5E_PEX2_STN1_TX_DP<17>")
	)
	(segment
		(start 260.295644 -110.033308)
		(end 260.485128 -109.575854)
		(width 0.1651)
		(layer "In9.Cu")
		(net "P5E_PEX2_STN1_TX_DP<17>")
	)
	(segment
		(start 263.121902 -105.41)
		(end 263.265666 -105.41)
		(width 0.1651)
		(layer "In9.Cu")
		(net "P5E_PEX2_STN1_TX_DP<17>")
	)
	(segment
		(start 265.2776 -103.380032)
		(end 265.2776 -103.254302)
		(width 0.1651)
		(layer "In9.Cu")
		(net "P5E_PEX2_STN1_TX_DP<17>")
	)
	(segment
		(start 257.52044 -162.482276)
		(end 256.955798 -159.643064)
		(width 0.1651)
		(layer "In9.Cu")
		(net "P5E_PEX2_STN1_TX_DP<17>")
	)
	(segment
		(start 264.460482 -104.07142)
		(end 264.810494 -103.721408)
		(width 0.1651)
		(layer "In9.Cu")
		(net "P5E_PEX2_STN1_TX_DP<17>")
	)
	(segment
		(start 262.77189 -105.760012)
		(end 263.121902 -105.41)
		(width 0.1651)
		(layer "In9.Cu")
		(net "P5E_PEX2_STN1_TX_DP<17>")
	)
	(segment
		(start 263.616186 -104.915716)
		(end 263.966198 -104.565704)
		(width 0.1651)
		(layer "In9.Cu")
		(net "P5E_PEX2_STN1_TX_DP<17>")
	)
	(segment
		(start 260.942074 -108.472478)
		(end 261.074916 -108.417614)
		(width 0.1651)
		(layer "In9.Cu")
		(net "P5E_PEX2_STN1_TX_DP<17>")
	)
	(segment
		(start 292.42004 -280.025856)
		(end 292.42004 -271.600168)
		(width 0.1143)
		(layer "In9.Cu")
		(net "P5E_PEX2_STN1_TX_DP<17>")
	)
	(segment
		(start 260.350762 -110.16615)
		(end 260.295644 -110.033308)
		(width 0.1651)
		(layer "In9.Cu")
		(net "P5E_PEX2_STN1_TX_DP<17>")
	)
	(segment
		(start 292.46576 -265.72464)
		(end 257.52044 -162.482276)
		(width 0.1651)
		(layer "In9.Cu")
		(net "P5E_PEX2_STN1_TX_DP<17>")
	)
	(segment
		(start 260.16077 -110.623858)
		(end 260.350762 -110.16615)
		(width 0.1651)
		(layer "In9.Cu")
		(net "P5E_PEX2_STN1_TX_DP<17>")
	)
	(segment
		(start 263.966198 -104.565704)
		(end 264.109962 -104.565704)
		(width 0.1651)
		(layer "In9.Cu")
		(net "P5E_PEX2_STN1_TX_DP<17>")
	)
	(segment
		(start 261.209536 -107.827064)
		(end 261.566406 -106.965496)
		(width 0.1651)
		(layer "In9.Cu")
		(net "P5E_PEX2_STN1_TX_DP<17>")
	)
	(segment
		(start 262.277606 -106.254296)
		(end 262.42137 -106.254296)
		(width 0.1651)
		(layer "In9.Cu")
		(net "P5E_PEX2_STN1_TX_DP<17>")
	)
	(segment
		(start 292.523672 -280.129488)
		(end 292.42004 -280.025856)
		(width 0.1143)
		(layer "In9.Cu")
		(net "P5E_PEX2_STN1_TX_DP<17>")
	)
	(segment
		(start 263.616186 -105.05948)
		(end 263.616186 -104.915716)
		(width 0.1651)
		(layer "In9.Cu")
		(net "P5E_PEX2_STN1_TX_DP<17>")
	)
	(segment
		(start 266.086082 -102.57155)
		(end 266.086082 -102.44582)
		(width 0.1651)
		(layer "In9.Cu")
		(net "P5E_PEX2_STN1_TX_DP<17>")
	)
	(segment
		(start 263.265666 -105.41)
		(end 263.616186 -105.05948)
		(width 0.1651)
		(layer "In9.Cu")
		(net "P5E_PEX2_STN1_TX_DP<17>")
	)
	(segment
		(start 260.75259 -108.930186)
		(end 260.942074 -108.472732)
		(width 0.1651)
		(layer "In9.Cu")
		(net "P5E_PEX2_STN1_TX_DP<17>")
	)
	(segment
		(start 262.77189 -105.903776)
		(end 262.77189 -105.760012)
		(width 0.1651)
		(layer "In9.Cu")
		(net "P5E_PEX2_STN1_TX_DP<17>")
	)
	(segment
		(start 260.942074 -108.472732)
		(end 260.942074 -108.472478)
		(width 0.1651)
		(layer "In9.Cu")
		(net "P5E_PEX2_STN1_TX_DP<17>")
	)
	(segment
		(start 265.2776 -103.254302)
		(end 265.618722 -102.91318)
		(width 0.1651)
		(layer "In9.Cu")
		(net "P5E_PEX2_STN1_TX_DP<17>")
	)
	(segment
		(start 264.460482 -104.215184)
		(end 264.460482 -104.07142)
		(width 0.1651)
		(layer "In9.Cu")
		(net "P5E_PEX2_STN1_TX_DP<17>")
	)
	(segment
		(start 292.79977 -280.015188)
		(end 292.68547 -280.129488)
		(width 0.1143)
		(layer "In9.Cu")
		(net "P5E_PEX2_STN1_TX_DP<17>")
	)
	(segment
		(start 261.264654 -107.959652)
		(end 261.209536 -107.827064)
		(width 0.1651)
		(layer "In9.Cu")
		(net "P5E_PEX2_STN1_TX_DP<17>")
	)
	(segment
		(start 292.46576 -271.526)
		(end 292.46576 -265.72464)
		(width 0.1651)
		(layer "In9.Cu")
		(net "P5E_PEX2_STN1_TX_DP<17>")
	)
	(segment
		(start 259.838698 -111.13643)
		(end 260.028182 -110.678976)
		(width 0.1651)
		(layer "In9.Cu")
		(net "P5E_PEX2_STN1_TX_DP<17>")
	)
	(segment
		(start 264.109962 -104.565704)
		(end 264.460482 -104.215184)
		(width 0.1651)
		(layer "In9.Cu")
		(net "P5E_PEX2_STN1_TX_DP<17>")
	)
	(segment
		(start 261.566406 -106.965496)
		(end 262.277606 -106.254296)
		(width 0.1651)
		(layer "In9.Cu")
		(net "P5E_PEX2_STN1_TX_DP<17>")
	)
	(segment
		(start 267.196824 -101.693472)
		(end 267.644372 -101.693472)
		(width 0.1651)
		(layer "In9.Cu")
		(net "P5E_PEX2_STN1_TX_DP<17>")
	)
	(segment
		(start 267.644372 -101.693472)
		(end 267.935202 -101.984302)
		(width 0.1651)
		(layer "In9.Cu")
		(net "P5E_PEX2_STN1_TX_DP<17>")
	)
	(segment
		(start 256.955798 -159.643064)
		(end 256.239264 -145.063718)
		(width 0.1651)
		(layer "In9.Cu")
		(net "P5E_PEX2_STN1_TX_DP<17>")
	)
	(segment
		(start 261.074916 -108.417614)
		(end 261.264654 -107.959652)
		(width 0.1651)
		(layer "In9.Cu")
		(net "P5E_PEX2_STN1_TX_DP<17>")
	)
	(segment
		(start 253.654814 -130.86207)
		(end 259.091684 -112.93983)
		(width 0.1651)
		(layer "In9.Cu")
		(net "P5E_PEX2_STN1_TX_DP<17>")
	)
	(segment
		(start 292.46576 -271.554448)
		(end 292.46576 -271.526)
		(width 0.1143)
		(layer "In9.Cu")
		(net "P5E_PEX2_STN1_TX_DP<17>")
	)
	(segment
		(start 260.485128 -109.575854)
		(end 260.617716 -109.520736)
		(width 0.1651)
		(layer "In9.Cu")
		(net "P5E_PEX2_STN1_TX_DP<17>")
	)
	(segment
		(start 253.654814 -138.823954)
		(end 253.654814 -130.86207)
		(width 0.1651)
		(layer "In9.Cu")
		(net "P5E_PEX2_STN1_TX_DP<17>")
	)
	(segment
		(start 292.42004 -271.600168)
		(end 292.46576 -271.554448)
		(width 0.1143)
		(layer "In9.Cu")
		(net "P5E_PEX2_STN1_TX_DP<17>")
	)
	(segment
		(start 260.617716 -109.520736)
		(end 260.807708 -109.063028)
		(width 0.1651)
		(layer "In9.Cu")
		(net "P5E_PEX2_STN1_TX_DP<17>")
	)
	(segment
		(start 259.091684 -112.93983)
		(end 259.571236 -111.782098)
		(width 0.1651)
		(layer "In9.Cu")
		(net "P5E_PEX2_STN1_TX_DP<17>")
	)
	(segment
		(start 259.571236 -111.782098)
		(end 259.703824 -111.72698)
		(width 0.1651)
		(layer "In9.Cu")
		(net "P5E_PEX2_STN1_TX_DP<17>")
	)
	(segment
		(start 264.810494 -103.721408)
		(end 264.93597 -103.721408)
		(width 0.1651)
		(layer "In9.Cu")
		(net "P5E_PEX2_STN1_TX_DP<17>")
	)
	(segment
		(start 260.028182 -110.678976)
		(end 260.16077 -110.623858)
		(width 0.1651)
		(layer "In9.Cu")
		(net "P5E_PEX2_STN1_TX_DP<17>")
	)
	(segment
		(start 259.893816 -111.269272)
		(end 259.838698 -111.13643)
		(width 0.1651)
		(layer "In9.Cu")
		(net "P5E_PEX2_STN1_TX_DP<17>")
	)
	(segment
		(start 262.42137 -106.254296)
		(end 262.77189 -105.903776)
		(width 0.1651)
		(layer "In9.Cu")
		(net "P5E_PEX2_STN1_TX_DP<17>")
	)
	(segment
		(start 266.584938 -101.946964)
		(end 267.196824 -101.693472)
		(width 0.1651)
		(layer "In9.Cu")
		(net "P5E_PEX2_STN1_TX_DP<17>")
	)
	(segment
		(start 265.744452 -102.91318)
		(end 266.086082 -102.57155)
		(width 0.1651)
		(layer "In9.Cu")
		(net "P5E_PEX2_STN1_TX_DP<17>")
	)
	(segment
		(start 264.93597 -103.721408)
		(end 265.2776 -103.380032)
		(width 0.1651)
		(layer "In9.Cu")
		(net "P5E_PEX2_STN1_TX_DP<17>")
	)
	(segment
		(start 292.68547 -280.129488)
		(end 292.523672 -280.129488)
		(width 0.1143)
		(layer "In9.Cu")
		(net "P5E_PEX2_STN1_TX_DP<17>")
	)
	(segment
		(start 265.618722 -102.91318)
		(end 265.744452 -102.91318)
		(width 0.1651)
		(layer "In9.Cu")
		(net "P5E_PEX2_STN1_TX_DP<17>")
	)
	(segment
		(start 260.807708 -109.063028)
		(end 260.75259 -108.930186)
		(width 0.1651)
		(layer "In9.Cu")
		(net "P5E_PEX2_STN1_TX_DP<17>")
	)
	(segment
		(start 256.239264 -145.063718)
		(end 253.654814 -138.823954)
		(width 0.1651)
		(layer "In9.Cu")
		(net "P5E_PEX2_STN1_TX_DP<17>")
	)
	(segment
		(start 325.507604 -342.734138)
		(end 325.802244 -342.439498)
		(width 0.13462)
		(layer "F.Cu")
		(net "P5E_PEX2_STN6_TX_DN<106>")
	)
	(segment
		(start 325.827644 -343.685622)
		(end 325.507604 -343.365582)
		(width 0.13462)
		(layer "F.Cu")
		(net "P5E_PEX2_STN6_TX_DN<106>")
	)
	(segment
		(start 325.507604 -343.365582)
		(end 325.507604 -342.734138)
		(width 0.13462)
		(layer "F.Cu")
		(net "P5E_PEX2_STN6_TX_DN<106>")
	)
	(segment
		(start 280.173684 -313.570112)
		(end 280.070052 -313.673744)
		(width 0.1143)
		(layer "In13.Cu")
		(net "P5E_PEX2_STN6_TX_DN<106>")
	)
	(segment
		(start 280.115772 -319.995296)
		(end 280.115772 -324.290944)
		(width 0.1651)
		(layer "In13.Cu")
		(net "P5E_PEX2_STN6_TX_DN<106>")
	)
	(segment
		(start 290.878768 -330.761594)
		(end 290.958778 -330.881228)
		(width 0.1651)
		(layer "In13.Cu")
		(net "P5E_PEX2_STN6_TX_DN<106>")
	)
	(segment
		(start 280.86685 -326.10425)
		(end 284.334966 -329.572366)
		(width 0.1651)
		(layer "In13.Cu")
		(net "P5E_PEX2_STN6_TX_DN<106>")
	)
	(segment
		(start 280.449782 -313.949842)
		(end 280.449782 -313.684412)
		(width 0.1143)
		(layer "In13.Cu")
		(net "P5E_PEX2_STN6_TX_DN<106>")
	)
	(segment
		(start 280.115772 -319.966848)
		(end 280.115772 -319.995296)
		(width 0.1143)
		(layer "In13.Cu")
		(net "P5E_PEX2_STN6_TX_DN<106>")
	)
	(segment
		(start 325.511414 -341.633302)
		(end 325.511414 -342.148668)
		(width 0.1651)
		(layer "In13.Cu")
		(net "P5E_PEX2_STN6_TX_DN<106>")
	)
	(segment
		(start 280.335482 -313.570112)
		(end 280.173684 -313.570112)
		(width 0.1143)
		(layer "In13.Cu")
		(net "P5E_PEX2_STN6_TX_DN<106>")
	)
	(segment
		(start 280.070052 -313.673744)
		(end 280.070052 -319.921128)
		(width 0.1143)
		(layer "In13.Cu")
		(net "P5E_PEX2_STN6_TX_DN<106>")
	)
	(segment
		(start 280.070052 -319.921128)
		(end 280.115772 -319.966848)
		(width 0.1143)
		(layer "In13.Cu")
		(net "P5E_PEX2_STN6_TX_DN<106>")
	)
	(segment
		(start 323.6722 -339.4964)
		(end 325.511414 -341.633302)
		(width 0.1651)
		(layer "In13.Cu")
		(net "P5E_PEX2_STN6_TX_DN<106>")
	)
	(segment
		(start 325.511414 -342.148668)
		(end 325.802244 -342.439498)
		(width 0.1651)
		(layer "In13.Cu")
		(net "P5E_PEX2_STN6_TX_DN<106>")
	)
	(segment
		(start 280.115772 -324.290944)
		(end 280.86685 -326.10425)
		(width 0.1651)
		(layer "In13.Cu")
		(net "P5E_PEX2_STN6_TX_DN<106>")
	)
	(segment
		(start 290.392612 -330.665582)
		(end 290.878768 -330.761594)
		(width 0.1651)
		(layer "In13.Cu")
		(net "P5E_PEX2_STN6_TX_DN<106>")
	)
	(segment
		(start 280.449782 -313.684412)
		(end 280.335482 -313.570112)
		(width 0.1143)
		(layer "In13.Cu")
		(net "P5E_PEX2_STN6_TX_DN<106>")
	)
	(segment
		(start 314.697364 -335.571592)
		(end 323.6722 -339.4964)
		(width 0.1651)
		(layer "In13.Cu")
		(net "P5E_PEX2_STN6_TX_DN<106>")
	)
	(segment
		(start 284.334966 -329.572366)
		(end 290.273232 -330.745592)
		(width 0.1651)
		(layer "In13.Cu")
		(net "P5E_PEX2_STN6_TX_DN<106>")
	)
	(segment
		(start 290.958778 -330.881228)
		(end 314.697364 -335.571592)
		(width 0.1651)
		(layer "In13.Cu")
		(net "P5E_PEX2_STN6_TX_DN<106>")
	)
	(segment
		(start 290.273232 -330.745592)
		(end 290.392612 -330.665582)
		(width 0.1651)
		(layer "In13.Cu")
		(net "P5E_PEX2_STN6_TX_DN<106>")
	)
	(segment
		(start 341.89416 -341.11184)
		(end 342.610694 -341.828374)
		(width 0.1651)
		(layer "In5.Cu")
		(net "P5E_PEX2_STN5_RX_DN<92>")
	)
	(segment
		(start 342.610694 -358.688386)
		(end 341.557102 -370.688362)
		(width 0.1651)
		(layer "In5.Cu")
		(net "P5E_PEX2_STN5_RX_DN<92>")
	)
	(segment
		(start 306.091844 -324.15353)
		(end 306.140612 -324.288658)
		(width 0.1651)
		(layer "In5.Cu")
		(net "P5E_PEX2_STN5_RX_DN<92>")
	)
	(segment
		(start 341.557102 -370.688362)
		(end 340.964266 -371.281198)
		(width 0.1651)
		(layer "In5.Cu")
		(net "P5E_PEX2_STN5_RX_DN<92>")
	)
	(segment
		(start 302.299878 -316.534292)
		(end 302.185578 -316.419992)
		(width 0.1143)
		(layer "In5.Cu")
		(net "P5E_PEX2_STN5_RX_DN<92>")
	)
	(segment
		(start 340.29015 -371.408198)
		(end 340.29015 -371.790214)
		(width 0.1651)
		(layer "In5.Cu")
		(net "P5E_PEX2_STN5_RX_DN<92>")
	)
	(segment
		(start 340.41715 -371.281198)
		(end 340.29015 -371.408198)
		(width 0.1651)
		(layer "In5.Cu")
		(net "P5E_PEX2_STN5_RX_DN<92>")
	)
	(segment
		(start 303.96307 -323.264022)
		(end 305.508406 -323.99097)
		(width 0.1651)
		(layer "In5.Cu")
		(net "P5E_PEX2_STN5_RX_DN<92>")
	)
	(segment
		(start 301.965868 -319.941448)
		(end 301.965868 -319.969896)
		(width 0.1143)
		(layer "In5.Cu")
		(net "P5E_PEX2_STN5_RX_DN<92>")
	)
	(segment
		(start 302.185578 -316.419992)
		(end 302.034448 -316.419992)
		(width 0.1143)
		(layer "In5.Cu")
		(net "P5E_PEX2_STN5_RX_DN<92>")
	)
	(segment
		(start 302.32858 -321.629532)
		(end 303.96307 -323.264022)
		(width 0.1651)
		(layer "In5.Cu")
		(net "P5E_PEX2_STN5_RX_DN<92>")
	)
	(segment
		(start 302.299878 -316.799722)
		(end 302.299878 -316.534292)
		(width 0.1143)
		(layer "In5.Cu")
		(net "P5E_PEX2_STN5_RX_DN<92>")
	)
	(segment
		(start 342.610694 -341.828374)
		(end 342.610694 -358.688386)
		(width 0.1651)
		(layer "In5.Cu")
		(net "P5E_PEX2_STN5_RX_DN<92>")
	)
	(segment
		(start 306.140612 -324.288404)
		(end 341.89416 -341.11184)
		(width 0.1651)
		(layer "In5.Cu")
		(net "P5E_PEX2_STN5_RX_DN<92>")
	)
	(segment
		(start 301.965868 -320.753994)
		(end 302.32858 -321.629532)
		(width 0.1651)
		(layer "In5.Cu")
		(net "P5E_PEX2_STN5_RX_DN<92>")
	)
	(segment
		(start 340.964266 -371.281198)
		(end 340.41715 -371.281198)
		(width 0.1651)
		(layer "In5.Cu")
		(net "P5E_PEX2_STN5_RX_DN<92>")
	)
	(segment
		(start 305.643534 -323.942456)
		(end 306.091844 -324.15353)
		(width 0.1651)
		(layer "In5.Cu")
		(net "P5E_PEX2_STN5_RX_DN<92>")
	)
	(segment
		(start 302.034448 -316.419992)
		(end 301.920148 -316.534292)
		(width 0.1143)
		(layer "In5.Cu")
		(net "P5E_PEX2_STN5_RX_DN<92>")
	)
	(segment
		(start 305.508406 -323.99097)
		(end 305.643534 -323.942456)
		(width 0.1651)
		(layer "In5.Cu")
		(net "P5E_PEX2_STN5_RX_DN<92>")
	)
	(segment
		(start 301.920148 -319.895728)
		(end 301.965868 -319.941448)
		(width 0.1143)
		(layer "In5.Cu")
		(net "P5E_PEX2_STN5_RX_DN<92>")
	)
	(segment
		(start 301.965868 -319.969896)
		(end 301.965868 -320.753994)
		(width 0.1651)
		(layer "In5.Cu")
		(net "P5E_PEX2_STN5_RX_DN<92>")
	)
	(segment
		(start 301.920148 -316.534292)
		(end 301.920148 -319.895728)
		(width 0.1143)
		(layer "In5.Cu")
		(net "P5E_PEX2_STN5_RX_DN<92>")
	)
	(segment
		(start 306.140612 -324.288658)
		(end 306.140612 -324.288404)
		(width 0.1651)
		(layer "In5.Cu")
		(net "P5E_PEX2_STN5_RX_DN<92>")
	)
	(segment
		(start 179.496974 -112.510824)
		(end 180.284374 -112.510824)
		(width 0.13208)
		(layer "F.Cu")
		(net "RST_SMB_NIC3_MUX_ISO_N")
	)
	(segment
		(start 179.377594 -115.283742)
		(end 179.377594 -114.267742)
		(width 0.13208)
		(layer "F.Cu")
		(net "RST_SMB_NIC3_MUX_ISO_N")
	)
	(segment
		(start 179.377594 -112.630204)
		(end 179.496974 -112.510824)
		(width 0.13208)
		(layer "F.Cu")
		(net "RST_SMB_NIC3_MUX_ISO_N")
	)
	(segment
		(start 179.377594 -114.267742)
		(end 179.377594 -113.251742)
		(width 0.13208)
		(layer "F.Cu")
		(net "RST_SMB_NIC3_MUX_ISO_N")
	)
	(segment
		(start 179.377594 -113.251742)
		(end 179.377594 -112.630204)
		(width 0.13208)
		(layer "F.Cu")
		(net "RST_SMB_NIC3_MUX_ISO_N")
	)
	(via
		(at 180.284374 -112.510824)
		(size 0.508)
		(drill 0.254)
		(layers "F.Cu" "B.Cu")
		(net "RST_SMB_NIC3_MUX_ISO_N")
	)
	(segment
		(start 180.259228 -112.53597)
		(end 180.259228 -114.840766)
		(width 0.13208)
		(layer "B.Cu")
		(net "RST_SMB_NIC3_MUX_ISO_N")
	)
	(segment
		(start 184.478422 -115.816634)
		(end 184.599072 -115.937284)
		(width 0.13208)
		(layer "B.Cu")
		(net "RST_SMB_NIC3_MUX_ISO_N")
	)
	(segment
		(start 184.599072 -115.937284)
		(end 184.599072 -116.513356)
		(width 0.13208)
		(layer "B.Cu")
		(net "RST_SMB_NIC3_MUX_ISO_N")
	)
	(segment
		(start 180.259228 -114.840766)
		(end 181.235096 -115.816634)
		(width 0.13208)
		(layer "B.Cu")
		(net "RST_SMB_NIC3_MUX_ISO_N")
	)
	(segment
		(start 181.235096 -115.816634)
		(end 184.478422 -115.816634)
		(width 0.13208)
		(layer "B.Cu")
		(net "RST_SMB_NIC3_MUX_ISO_N")
	)
	(segment
		(start 180.284374 -112.510824)
		(end 180.259228 -112.53597)
		(width 0.13208)
		(layer "B.Cu")
		(net "RST_SMB_NIC3_MUX_ISO_N")
	)
	(segment
		(start 22.736048 -344.539062)
		(end 22.416008 -344.219022)
		(width 0.13462)
		(layer "F.Cu")
		(net "P5E_PEX0_STN7_TX_C_DP<113>")
	)
	(segment
		(start 22.441408 -345.465146)
		(end 22.736048 -345.170506)
		(width 0.13462)
		(layer "F.Cu")
		(net "P5E_PEX0_STN7_TX_C_DP<113>")
	)
	(segment
		(start 22.736048 -345.170506)
		(end 22.736048 -344.539062)
		(width 0.13462)
		(layer "F.Cu")
		(net "P5E_PEX0_STN7_TX_C_DP<113>")
	)
	(segment
		(start 30.236922 -401.999196)
		(end 30.852618 -401.999196)
		(width 0.1651)
		(layer "In7.Cu")
		(net "P5E_PEX0_STN7_TX_C_DP<113>")
	)
	(segment
		(start 22.308566 -388.629652)
		(end 20.753578 -385.173982)
		(width 0.1651)
		(layer "In7.Cu")
		(net "P5E_PEX0_STN7_TX_C_DP<113>")
	)
	(segment
		(start 22.732238 -345.755976)
		(end 22.441408 -345.465146)
		(width 0.1651)
		(layer "In7.Cu")
		(net "P5E_PEX0_STN7_TX_C_DP<113>")
	)
	(segment
		(start 31.002478 -401.849336)
		(end 31.002478 -394.824458)
		(width 0.1651)
		(layer "In7.Cu")
		(net "P5E_PEX0_STN7_TX_C_DP<113>")
	)
	(segment
		(start 19.910552 -371.178582)
		(end 20.522946 -358.715056)
		(width 0.1651)
		(layer "In7.Cu")
		(net "P5E_PEX0_STN7_TX_C_DP<113>")
	)
	(segment
		(start 30.852618 -401.999196)
		(end 31.002478 -401.849336)
		(width 0.1651)
		(layer "In7.Cu")
		(net "P5E_PEX0_STN7_TX_C_DP<113>")
	)
	(segment
		(start 30.109922 -401.872196)
		(end 30.236922 -401.999196)
		(width 0.1651)
		(layer "In7.Cu")
		(net "P5E_PEX0_STN7_TX_C_DP<113>")
	)
	(segment
		(start 29.10459 -392.92657)
		(end 24.838152 -391.159238)
		(width 0.1651)
		(layer "In7.Cu")
		(net "P5E_PEX0_STN7_TX_C_DP<113>")
	)
	(segment
		(start 21.177758 -347.912182)
		(end 22.732238 -346.357702)
		(width 0.1651)
		(layer "In7.Cu")
		(net "P5E_PEX0_STN7_TX_C_DP<113>")
	)
	(segment
		(start 31.002478 -394.824458)
		(end 29.10459 -392.92657)
		(width 0.1651)
		(layer "In7.Cu")
		(net "P5E_PEX0_STN7_TX_C_DP<113>")
	)
	(segment
		(start 24.838152 -391.159238)
		(end 22.308566 -388.629652)
		(width 0.1651)
		(layer "In7.Cu")
		(net "P5E_PEX0_STN7_TX_C_DP<113>")
	)
	(segment
		(start 30.109922 -401.49018)
		(end 30.109922 -401.872196)
		(width 0.1651)
		(layer "In7.Cu")
		(net "P5E_PEX0_STN7_TX_C_DP<113>")
	)
	(segment
		(start 20.522946 -358.715056)
		(end 21.177758 -352.066606)
		(width 0.1651)
		(layer "In7.Cu")
		(net "P5E_PEX0_STN7_TX_C_DP<113>")
	)
	(segment
		(start 20.753578 -385.173982)
		(end 19.910552 -371.178582)
		(width 0.1651)
		(layer "In7.Cu")
		(net "P5E_PEX0_STN7_TX_C_DP<113>")
	)
	(segment
		(start 22.732238 -346.357702)
		(end 22.732238 -345.755976)
		(width 0.1651)
		(layer "In7.Cu")
		(net "P5E_PEX0_STN7_TX_C_DP<113>")
	)
	(segment
		(start 21.177758 -352.066606)
		(end 21.177758 -347.912182)
		(width 0.1651)
		(layer "In7.Cu")
		(net "P5E_PEX0_STN7_TX_C_DP<113>")
	)
	(segment
		(start 143.246348 -357.46309)
		(end 143.246348 -356.831646)
		(width 0.13462)
		(layer "F.Cu")
		(net "P5E_PEX1_STN5_TX_C_DP<95>")
	)
	(segment
		(start 142.951708 -357.75773)
		(end 143.246348 -357.46309)
		(width 0.13462)
		(layer "F.Cu")
		(net "P5E_PEX1_STN5_TX_C_DP<95>")
	)
	(segment
		(start 143.246348 -356.831646)
		(end 142.926308 -356.511606)
		(width 0.13462)
		(layer "F.Cu")
		(net "P5E_PEX1_STN5_TX_C_DP<95>")
	)
	(segment
		(start 135.05815 -365.52378)
		(end 135.165338 -365.535972)
		(width 0.1651)
		(layer "In13.Cu")
		(net "P5E_PEX1_STN5_TX_C_DP<95>")
	)
	(segment
		(start 143.242538 -358.04856)
		(end 142.951708 -357.75773)
		(width 0.1651)
		(layer "In13.Cu")
		(net "P5E_PEX1_STN5_TX_C_DP<95>")
	)
	(segment
		(start 131.310126 -379.390148)
		(end 131.310126 -379.772164)
		(width 0.1651)
		(layer "In13.Cu")
		(net "P5E_PEX1_STN5_TX_C_DP<95>")
	)
	(segment
		(start 134.670546 -365.832644)
		(end 135.05815 -365.52378)
		(width 0.1651)
		(layer "In13.Cu")
		(net "P5E_PEX1_STN5_TX_C_DP<95>")
	)
	(segment
		(start 131.310126 -379.772164)
		(end 131.437126 -379.899164)
		(width 0.1651)
		(layer "In13.Cu")
		(net "P5E_PEX1_STN5_TX_C_DP<95>")
	)
	(segment
		(start 134.658608 -365.939832)
		(end 134.670546 -365.832644)
		(width 0.1651)
		(layer "In13.Cu")
		(net "P5E_PEX1_STN5_TX_C_DP<95>")
	)
	(segment
		(start 132.184902 -368.959638)
		(end 133.005576 -367.256568)
		(width 0.1651)
		(layer "In13.Cu")
		(net "P5E_PEX1_STN5_TX_C_DP<95>")
	)
	(segment
		(start 131.437126 -379.899164)
		(end 131.658614 -379.899164)
		(width 0.1651)
		(layer "In13.Cu")
		(net "P5E_PEX1_STN5_TX_C_DP<95>")
	)
	(segment
		(start 142.818866 -359.438702)
		(end 143.242538 -358.56037)
		(width 0.1651)
		(layer "In13.Cu")
		(net "P5E_PEX1_STN5_TX_C_DP<95>")
	)
	(segment
		(start 132.184902 -379.372876)
		(end 132.184902 -368.959638)
		(width 0.1651)
		(layer "In13.Cu")
		(net "P5E_PEX1_STN5_TX_C_DP<95>")
	)
	(segment
		(start 135.165338 -365.535972)
		(end 142.818866 -359.438702)
		(width 0.1651)
		(layer "In13.Cu")
		(net "P5E_PEX1_STN5_TX_C_DP<95>")
	)
	(segment
		(start 143.242538 -358.56037)
		(end 143.242538 -358.04856)
		(width 0.1651)
		(layer "In13.Cu")
		(net "P5E_PEX1_STN5_TX_C_DP<95>")
	)
	(segment
		(start 131.658614 -379.899164)
		(end 132.184902 -379.372876)
		(width 0.1651)
		(layer "In13.Cu")
		(net "P5E_PEX1_STN5_TX_C_DP<95>")
	)
	(segment
		(start 133.005576 -367.256568)
		(end 134.658608 -365.939832)
		(width 0.1651)
		(layer "In13.Cu")
		(net "P5E_PEX1_STN5_TX_C_DP<95>")
	)
	(segment
		(start 197.337426 -143.184626)
		(end 197.632066 -143.479266)
		(width 0.13462)
		(layer "F.Cu")
		(net "P5E_PEX1_STN0_TX_DP<8>")
	)
	(segment
		(start 196.705982 -143.184626)
		(end 197.337426 -143.184626)
		(width 0.13462)
		(layer "F.Cu")
		(net "P5E_PEX1_STN0_TX_DP<8>")
	)
	(segment
		(start 196.385942 -143.504666)
		(end 196.705982 -143.184626)
		(width 0.13462)
		(layer "F.Cu")
		(net "P5E_PEX1_STN0_TX_DP<8>")
	)
	(segment
		(start 202.816968 -145.25244)
		(end 202.942698 -145.25244)
		(width 0.1651)
		(layer "In9.Cu")
		(net "P5E_PEX1_STN0_TX_DP<8>")
	)
	(segment
		(start 198.398384 -143.188436)
		(end 198.910194 -142.9766)
		(width 0.1651)
		(layer "In9.Cu")
		(net "P5E_PEX1_STN0_TX_DP<8>")
	)
	(segment
		(start 202.942698 -145.25244)
		(end 203.29271 -145.602452)
		(width 0.1651)
		(layer "In9.Cu")
		(net "P5E_PEX1_STN0_TX_DP<8>")
	)
	(segment
		(start 200.766426 -143.423894)
		(end 201.35977 -143.669512)
		(width 0.1651)
		(layer "In9.Cu")
		(net "P5E_PEX1_STN0_TX_DP<8>")
	)
	(segment
		(start 204.873606 -147.183348)
		(end 205.148688 -147.595082)
		(width 0.1651)
		(layer "In9.Cu")
		(net "P5E_PEX1_STN0_TX_DP<8>")
	)
	(segment
		(start 200.14438 -143.166084)
		(end 200.192386 -143.282162)
		(width 0.1651)
		(layer "In9.Cu")
		(net "P5E_PEX1_STN0_TX_DP<8>")
	)
	(segment
		(start 202.466448 -144.90192)
		(end 202.816968 -145.25244)
		(width 0.1651)
		(layer "In9.Cu")
		(net "P5E_PEX1_STN0_TX_DP<8>")
	)
	(segment
		(start 203.76896 -146.078702)
		(end 204.17028 -146.480022)
		(width 0.1651)
		(layer "In9.Cu")
		(net "P5E_PEX1_STN0_TX_DP<8>")
	)
	(segment
		(start 204.17028 -146.480022)
		(end 204.17028 -146.605752)
		(width 0.1651)
		(layer "In9.Cu")
		(net "P5E_PEX1_STN0_TX_DP<8>")
	)
	(segment
		(start 206.148686 -149.265132)
		(end 206.100426 -149.38121)
		(width 0.1651)
		(layer "In9.Cu")
		(net "P5E_PEX1_STN0_TX_DP<8>")
	)
	(segment
		(start 200.192386 -143.282162)
		(end 200.650348 -143.4719)
		(width 0.1651)
		(layer "In9.Cu")
		(net "P5E_PEX1_STN0_TX_DP<8>")
	)
	(segment
		(start 205.52283 -148.154898)
		(end 205.959202 -148.807678)
		(width 0.1651)
		(layer "In9.Cu")
		(net "P5E_PEX1_STN0_TX_DP<8>")
	)
	(segment
		(start 199.686926 -142.9766)
		(end 200.14438 -143.166084)
		(width 0.1651)
		(layer "In9.Cu")
		(net "P5E_PEX1_STN0_TX_DP<8>")
	)
	(segment
		(start 198.884286 -271.776952)
		(end 198.884286 -271.8054)
		(width 0.1143)
		(layer "In9.Cu")
		(net "P5E_PEX1_STN0_TX_DP<8>")
	)
	(segment
		(start 199.741536 -173.177454)
		(end 198.518526 -177.738786)
		(width 0.1651)
		(layer "In9.Cu")
		(net "P5E_PEX1_STN0_TX_DP<8>")
	)
	(segment
		(start 198.884286 -271.8054)
		(end 198.930006 -271.85112)
		(width 0.1143)
		(layer "In9.Cu")
		(net "P5E_PEX1_STN0_TX_DP<8>")
	)
	(segment
		(start 198.930006 -276.183598)
		(end 198.796656 -276.316948)
		(width 0.1143)
		(layer "In9.Cu")
		(net "P5E_PEX1_STN0_TX_DP<8>")
	)
	(segment
		(start 197.922896 -143.188436)
		(end 198.398384 -143.188436)
		(width 0.1651)
		(layer "In9.Cu")
		(net "P5E_PEX1_STN0_TX_DP<8>")
	)
	(segment
		(start 206.290418 -149.839172)
		(end 206.406496 -149.887178)
		(width 0.1651)
		(layer "In9.Cu")
		(net "P5E_PEX1_STN0_TX_DP<8>")
	)
	(segment
		(start 205.39964 -148.13026)
		(end 205.523084 -148.154898)
		(width 0.1651)
		(layer "In9.Cu")
		(net "P5E_PEX1_STN0_TX_DP<8>")
	)
	(segment
		(start 197.982586 -260.280912)
		(end 197.982586 -261.21614)
		(width 0.1651)
		(layer "In9.Cu")
		(net "P5E_PEX1_STN0_TX_DP<8>")
	)
	(segment
		(start 204.520546 -146.956018)
		(end 204.646276 -146.956018)
		(width 0.1651)
		(layer "In9.Cu")
		(net "P5E_PEX1_STN0_TX_DP<8>")
	)
	(segment
		(start 196.579998 -199.893174)
		(end 196.580252 -199.893174)
		(width 0.1651)
		(layer "In9.Cu")
		(net "P5E_PEX1_STN0_TX_DP<8>")
	)
	(segment
		(start 197.979792 -276.565106)
		(end 197.979792 -276.785578)
		(width 0.1143)
		(layer "In9.Cu")
		(net "P5E_PEX1_STN0_TX_DP<8>")
	)
	(segment
		(start 194.641978 -222.047308)
		(end 197.982586 -260.280912)
		(width 0.1651)
		(layer "In9.Cu")
		(net "P5E_PEX1_STN0_TX_DP<8>")
	)
	(segment
		(start 196.580252 -199.893174)
		(end 194.641978 -222.047308)
		(width 0.1651)
		(layer "In9.Cu")
		(net "P5E_PEX1_STN0_TX_DP<8>")
	)
	(segment
		(start 206.100426 -149.38121)
		(end 206.290418 -149.839172)
		(width 0.1651)
		(layer "In9.Cu")
		(net "P5E_PEX1_STN0_TX_DP<8>")
	)
	(segment
		(start 205.523084 -148.154898)
		(end 205.52283 -148.154898)
		(width 0.1651)
		(layer "In9.Cu")
		(net "P5E_PEX1_STN0_TX_DP<8>")
	)
	(segment
		(start 198.796656 -276.316948)
		(end 198.22795 -276.316948)
		(width 0.1143)
		(layer "In9.Cu")
		(net "P5E_PEX1_STN0_TX_DP<8>")
	)
	(segment
		(start 204.646276 -146.956018)
		(end 204.873606 -147.183348)
		(width 0.1651)
		(layer "In9.Cu")
		(net "P5E_PEX1_STN0_TX_DP<8>")
	)
	(segment
		(start 197.865492 -276.899878)
		(end 197.600062 -276.899878)
		(width 0.1143)
		(layer "In9.Cu")
		(net "P5E_PEX1_STN0_TX_DP<8>")
	)
	(segment
		(start 198.930006 -271.85112)
		(end 198.930006 -276.183598)
		(width 0.1143)
		(layer "In9.Cu")
		(net "P5E_PEX1_STN0_TX_DP<8>")
	)
	(segment
		(start 200.650348 -143.4719)
		(end 200.766426 -143.423894)
		(width 0.1651)
		(layer "In9.Cu")
		(net "P5E_PEX1_STN0_TX_DP<8>")
	)
	(segment
		(start 201.35977 -143.669512)
		(end 202.466448 -144.77619)
		(width 0.1651)
		(layer "In9.Cu")
		(net "P5E_PEX1_STN0_TX_DP<8>")
	)
	(segment
		(start 206.406496 -149.887178)
		(end 206.406242 -149.887178)
		(width 0.1651)
		(layer "In9.Cu")
		(net "P5E_PEX1_STN0_TX_DP<8>")
	)
	(segment
		(start 205.148688 -147.595082)
		(end 205.124304 -147.718272)
		(width 0.1651)
		(layer "In9.Cu")
		(net "P5E_PEX1_STN0_TX_DP<8>")
	)
	(segment
		(start 197.982586 -261.21614)
		(end 198.884286 -270.372078)
		(width 0.1651)
		(layer "In9.Cu")
		(net "P5E_PEX1_STN0_TX_DP<8>")
	)
	(segment
		(start 206.406242 -149.887178)
		(end 208.247742 -154.332686)
		(width 0.1651)
		(layer "In9.Cu")
		(net "P5E_PEX1_STN0_TX_DP<8>")
	)
	(segment
		(start 198.518526 -177.738786)
		(end 196.579998 -199.893174)
		(width 0.1651)
		(layer "In9.Cu")
		(net "P5E_PEX1_STN0_TX_DP<8>")
	)
	(segment
		(start 203.64323 -146.078702)
		(end 203.76896 -146.078702)
		(width 0.1651)
		(layer "In9.Cu")
		(net "P5E_PEX1_STN0_TX_DP<8>")
	)
	(segment
		(start 204.17028 -146.605752)
		(end 204.520546 -146.956018)
		(width 0.1651)
		(layer "In9.Cu")
		(net "P5E_PEX1_STN0_TX_DP<8>")
	)
	(segment
		(start 203.29271 -145.602452)
		(end 203.29271 -145.728182)
		(width 0.1651)
		(layer "In9.Cu")
		(net "P5E_PEX1_STN0_TX_DP<8>")
	)
	(segment
		(start 208.247742 -158.440882)
		(end 199.741536 -173.177454)
		(width 0.1651)
		(layer "In9.Cu")
		(net "P5E_PEX1_STN0_TX_DP<8>")
	)
	(segment
		(start 205.959202 -148.807678)
		(end 206.148686 -149.265132)
		(width 0.1651)
		(layer "In9.Cu")
		(net "P5E_PEX1_STN0_TX_DP<8>")
	)
	(segment
		(start 203.29271 -145.728182)
		(end 203.64323 -146.078702)
		(width 0.1651)
		(layer "In9.Cu")
		(net "P5E_PEX1_STN0_TX_DP<8>")
	)
	(segment
		(start 198.884286 -270.372078)
		(end 198.884286 -271.776952)
		(width 0.1651)
		(layer "In9.Cu")
		(net "P5E_PEX1_STN0_TX_DP<8>")
	)
	(segment
		(start 205.124304 -147.718272)
		(end 205.39964 -148.13026)
		(width 0.1651)
		(layer "In9.Cu")
		(net "P5E_PEX1_STN0_TX_DP<8>")
	)
	(segment
		(start 198.910194 -142.9766)
		(end 199.686926 -142.9766)
		(width 0.1651)
		(layer "In9.Cu")
		(net "P5E_PEX1_STN0_TX_DP<8>")
	)
	(segment
		(start 208.247742 -154.332686)
		(end 208.247742 -158.440882)
		(width 0.1651)
		(layer "In9.Cu")
		(net "P5E_PEX1_STN0_TX_DP<8>")
	)
	(segment
		(start 198.22795 -276.316948)
		(end 197.979792 -276.565106)
		(width 0.1143)
		(layer "In9.Cu")
		(net "P5E_PEX1_STN0_TX_DP<8>")
	)
	(segment
		(start 197.979792 -276.785578)
		(end 197.865492 -276.899878)
		(width 0.1143)
		(layer "In9.Cu")
		(net "P5E_PEX1_STN0_TX_DP<8>")
	)
	(segment
		(start 202.466448 -144.77619)
		(end 202.466448 -144.90192)
		(width 0.1651)
		(layer "In9.Cu")
		(net "P5E_PEX1_STN0_TX_DP<8>")
	)
	(segment
		(start 197.632066 -143.479266)
		(end 197.922896 -143.188436)
		(width 0.1651)
		(layer "In9.Cu")
		(net "P5E_PEX1_STN0_TX_DP<8>")
	)
	(segment
		(start 115.540028 -349.511874)
		(end 115.540028 -348.88043)
		(width 0.13462)
		(layer "F.Cu")
		(net "P5E_PEX1_STN6_TX_DN<110>")
	)
	(segment
		(start 115.860068 -349.831914)
		(end 115.540028 -349.511874)
		(width 0.13462)
		(layer "F.Cu")
		(net "P5E_PEX1_STN6_TX_DN<110>")
	)
	(segment
		(start 115.540028 -348.88043)
		(end 115.834668 -348.58579)
		(width 0.13462)
		(layer "F.Cu")
		(net "P5E_PEX1_STN6_TX_DN<110>")
	)
	(segment
		(start 160.170114 -319.995296)
		(end 160.215834 -320.041016)
		(width 0.1143)
		(layer "In13.Cu")
		(net "P5E_PEX1_STN6_TX_DN<110>")
	)
	(segment
		(start 160.549844 -313.684412)
		(end 160.435544 -313.570112)
		(width 0.1143)
		(layer "In13.Cu")
		(net "P5E_PEX1_STN6_TX_DN<110>")
	)
	(segment
		(start 160.170114 -313.666886)
		(end 160.170114 -319.995296)
		(width 0.1143)
		(layer "In13.Cu")
		(net "P5E_PEX1_STN6_TX_DN<110>")
	)
	(segment
		(start 160.435544 -313.570112)
		(end 160.266888 -313.570112)
		(width 0.1143)
		(layer "In13.Cu")
		(net "P5E_PEX1_STN6_TX_DN<110>")
	)
	(segment
		(start 160.215834 -320.063114)
		(end 160.215834 -320.689732)
		(width 0.1651)
		(layer "In13.Cu")
		(net "P5E_PEX1_STN6_TX_DN<110>")
	)
	(segment
		(start 129.033524 -332.727046)
		(end 120.559068 -337.257136)
		(width 0.1651)
		(layer "In13.Cu")
		(net "P5E_PEX1_STN6_TX_DN<110>")
	)
	(segment
		(start 117.96141 -339.729318)
		(end 117.287548 -340.853268)
		(width 0.1651)
		(layer "In13.Cu")
		(net "P5E_PEX1_STN6_TX_DN<110>")
	)
	(segment
		(start 115.543838 -347.692218)
		(end 115.543838 -348.29496)
		(width 0.1651)
		(layer "In13.Cu")
		(net "P5E_PEX1_STN6_TX_DN<110>")
	)
	(segment
		(start 145.659348 -327.659492)
		(end 141.267434 -327.659492)
		(width 0.1651)
		(layer "In13.Cu")
		(net "P5E_PEX1_STN6_TX_DN<110>")
	)
	(segment
		(start 117.098318 -346.137738)
		(end 115.543838 -347.692218)
		(width 0.1651)
		(layer "In13.Cu")
		(net "P5E_PEX1_STN6_TX_DN<110>")
	)
	(segment
		(start 117.098318 -341.537036)
		(end 117.098318 -346.137738)
		(width 0.1651)
		(layer "In13.Cu")
		(net "P5E_PEX1_STN6_TX_DN<110>")
	)
	(segment
		(start 160.215834 -320.689732)
		(end 158.810706 -322.09486)
		(width 0.1651)
		(layer "In13.Cu")
		(net "P5E_PEX1_STN6_TX_DN<110>")
	)
	(segment
		(start 120.559068 -337.257136)
		(end 117.96141 -339.729318)
		(width 0.1651)
		(layer "In13.Cu")
		(net "P5E_PEX1_STN6_TX_DN<110>")
	)
	(segment
		(start 147.56511 -327.281286)
		(end 145.659348 -327.659492)
		(width 0.1651)
		(layer "In13.Cu")
		(net "P5E_PEX1_STN6_TX_DN<110>")
	)
	(segment
		(start 160.549844 -313.949842)
		(end 160.549844 -313.684412)
		(width 0.1143)
		(layer "In13.Cu")
		(net "P5E_PEX1_STN6_TX_DN<110>")
	)
	(segment
		(start 117.287548 -340.853268)
		(end 117.098318 -341.537036)
		(width 0.1651)
		(layer "In13.Cu")
		(net "P5E_PEX1_STN6_TX_DN<110>")
	)
	(segment
		(start 141.267434 -327.659492)
		(end 129.033524 -332.727046)
		(width 0.1651)
		(layer "In13.Cu")
		(net "P5E_PEX1_STN6_TX_DN<110>")
	)
	(segment
		(start 115.543838 -348.29496)
		(end 115.834668 -348.58579)
		(width 0.1651)
		(layer "In13.Cu")
		(net "P5E_PEX1_STN6_TX_DN<110>")
	)
	(segment
		(start 158.810706 -322.09486)
		(end 155.959556 -323.80428)
		(width 0.1651)
		(layer "In13.Cu")
		(net "P5E_PEX1_STN6_TX_DN<110>")
	)
	(segment
		(start 155.959556 -323.80428)
		(end 147.56511 -327.281286)
		(width 0.1651)
		(layer "In13.Cu")
		(net "P5E_PEX1_STN6_TX_DN<110>")
	)
	(segment
		(start 160.266888 -313.570112)
		(end 160.170114 -313.666886)
		(width 0.1143)
		(layer "In13.Cu")
		(net "P5E_PEX1_STN6_TX_DN<110>")
	)
	(segment
		(start 160.215834 -320.041016)
		(end 160.215834 -320.063114)
		(width 0.1143)
		(layer "In13.Cu")
		(net "P5E_PEX1_STN6_TX_DN<110>")
	)
	(segment
		(start 269.96771 -110.114334)
		(end 270.267176 -110.4138)
		(width 0.13462)
		(layer "F.Cu")
		(net "P5E_PEX2_STN1_TX_DP<22>")
	)
	(segment
		(start 270.267176 -110.4138)
		(end 270.888968 -110.4138)
		(width 0.13462)
		(layer "F.Cu")
		(net "P5E_PEX2_STN1_TX_DP<22>")
	)
	(segment
		(start 270.888968 -110.4138)
		(end 271.213834 -110.088934)
		(width 0.13462)
		(layer "F.Cu")
		(net "P5E_PEX2_STN1_TX_DP<22>")
	)
	(segment
		(start 260.783578 -144.015714)
		(end 258.211574 -137.806684)
		(width 0.1651)
		(layer "In9.Cu")
		(net "P5E_PEX2_STN1_TX_DP<22>")
	)
	(segment
		(start 261.330186 -155.152598)
		(end 260.783578 -144.015714)
		(width 0.1651)
		(layer "In9.Cu")
		(net "P5E_PEX2_STN1_TX_DP<22>")
	)
	(segment
		(start 296.933874 -271.500346)
		(end 296.933874 -271.471898)
		(width 0.1143)
		(layer "In9.Cu")
		(net "P5E_PEX2_STN1_TX_DP<22>")
	)
	(segment
		(start 258.211574 -131.45135)
		(end 261.43966 -120.810782)
		(width 0.1651)
		(layer "In9.Cu")
		(net "P5E_PEX2_STN1_TX_DP<22>")
	)
	(segment
		(start 297.194478 -278.420068)
		(end 296.979594 -278.205184)
		(width 0.1143)
		(layer "In9.Cu")
		(net "P5E_PEX2_STN1_TX_DP<22>")
	)
	(segment
		(start 261.43966 -120.810782)
		(end 265.29665 -111.497872)
		(width 0.1651)
		(layer "In9.Cu")
		(net "P5E_PEX2_STN1_TX_DP<22>")
	)
	(segment
		(start 296.979594 -271.546066)
		(end 296.933874 -271.500346)
		(width 0.1143)
		(layer "In9.Cu")
		(net "P5E_PEX2_STN1_TX_DP<22>")
	)
	(segment
		(start 266.46124 -110.838742)
		(end 267.507974 -110.405164)
		(width 0.1651)
		(layer "In9.Cu")
		(net "P5E_PEX2_STN1_TX_DP<22>")
	)
	(segment
		(start 258.211574 -137.806684)
		(end 258.211574 -131.45135)
		(width 0.1651)
		(layer "In9.Cu")
		(net "P5E_PEX2_STN1_TX_DP<22>")
	)
	(segment
		(start 265.598148 -111.196374)
		(end 266.460986 -110.838742)
		(width 0.1651)
		(layer "In9.Cu")
		(net "P5E_PEX2_STN1_TX_DP<22>")
	)
	(segment
		(start 261.51332 -158.879032)
		(end 261.330186 -155.152598)
		(width 0.1651)
		(layer "In9.Cu")
		(net "P5E_PEX2_STN1_TX_DP<22>")
	)
	(segment
		(start 262.085836 -161.757614)
		(end 261.51332 -158.879032)
		(width 0.1651)
		(layer "In9.Cu")
		(net "P5E_PEX2_STN1_TX_DP<22>")
	)
	(segment
		(start 296.933874 -264.707116)
		(end 262.085836 -161.757614)
		(width 0.1651)
		(layer "In9.Cu")
		(net "P5E_PEX2_STN1_TX_DP<22>")
	)
	(segment
		(start 265.29665 -111.497872)
		(end 265.598148 -111.196374)
		(width 0.1651)
		(layer "In9.Cu")
		(net "P5E_PEX2_STN1_TX_DP<22>")
	)
	(segment
		(start 266.460986 -110.838742)
		(end 266.46124 -110.838742)
		(width 0.1651)
		(layer "In9.Cu")
		(net "P5E_PEX2_STN1_TX_DP<22>")
	)
	(segment
		(start 297.43527 -278.420068)
		(end 297.194478 -278.420068)
		(width 0.1143)
		(layer "In9.Cu")
		(net "P5E_PEX2_STN1_TX_DP<22>")
	)
	(segment
		(start 267.507974 -110.405164)
		(end 269.67688 -110.405164)
		(width 0.1651)
		(layer "In9.Cu")
		(net "P5E_PEX2_STN1_TX_DP<22>")
	)
	(segment
		(start 296.933874 -271.471898)
		(end 296.933874 -264.707116)
		(width 0.1651)
		(layer "In9.Cu")
		(net "P5E_PEX2_STN1_TX_DP<22>")
	)
	(segment
		(start 296.979594 -278.205184)
		(end 296.979594 -271.546066)
		(width 0.1143)
		(layer "In9.Cu")
		(net "P5E_PEX2_STN1_TX_DP<22>")
	)
	(segment
		(start 297.54957 -278.534368)
		(end 297.43527 -278.420068)
		(width 0.1143)
		(layer "In9.Cu")
		(net "P5E_PEX2_STN1_TX_DP<22>")
	)
	(segment
		(start 269.67688 -110.405164)
		(end 269.96771 -110.114334)
		(width 0.1651)
		(layer "In9.Cu")
		(net "P5E_PEX2_STN1_TX_DP<22>")
	)
	(segment
		(start 297.54957 -278.799798)
		(end 297.54957 -278.534368)
		(width 0.1143)
		(layer "In9.Cu")
		(net "P5E_PEX2_STN1_TX_DP<22>")
	)
	(segment
		(start 290.228782 -355.026722)
		(end 290.523422 -354.732082)
		(width 0.13462)
		(layer "F.Cu")
		(net "P5E_PEX2_STN7_TX_DN<123>")
	)
	(segment
		(start 290.228782 -355.658166)
		(end 290.228782 -355.026722)
		(width 0.13462)
		(layer "F.Cu")
		(net "P5E_PEX2_STN7_TX_DN<123>")
	)
	(segment
		(start 290.548822 -355.978206)
		(end 290.228782 -355.658166)
		(width 0.13462)
		(layer "F.Cu")
		(net "P5E_PEX2_STN7_TX_DN<123>")
	)
	(segment
		(start 270.835628 -313.570112)
		(end 270.949928 -313.684412)
		(width 0.1143)
		(layer "In7.Cu")
		(net "P5E_PEX2_STN7_TX_DN<123>")
	)
	(segment
		(start 270.615918 -321.441826)
		(end 270.615918 -319.916048)
		(width 0.1651)
		(layer "In7.Cu")
		(net "P5E_PEX2_STN7_TX_DN<123>")
	)
	(segment
		(start 291.787072 -352.376486)
		(end 291.787072 -342.265)
		(width 0.1651)
		(layer "In7.Cu")
		(net "P5E_PEX2_STN7_TX_DN<123>")
	)
	(segment
		(start 271.716754 -323.659754)
		(end 271.405604 -323.348604)
		(width 0.1651)
		(layer "In7.Cu")
		(net "P5E_PEX2_STN7_TX_DN<123>")
	)
	(segment
		(start 290.523422 -354.732082)
		(end 290.232592 -354.441252)
		(width 0.1651)
		(layer "In7.Cu")
		(net "P5E_PEX2_STN7_TX_DN<123>")
	)
	(segment
		(start 270.570198 -319.84188)
		(end 270.570198 -313.684412)
		(width 0.1143)
		(layer "In7.Cu")
		(net "P5E_PEX2_STN7_TX_DN<123>")
	)
	(segment
		(start 271.405604 -323.348604)
		(end 270.615918 -321.441826)
		(width 0.1651)
		(layer "In7.Cu")
		(net "P5E_PEX2_STN7_TX_DN<123>")
	)
	(segment
		(start 270.615918 -319.916048)
		(end 270.615918 -319.8876)
		(width 0.1143)
		(layer "In7.Cu")
		(net "P5E_PEX2_STN7_TX_DN<123>")
	)
	(segment
		(start 270.615918 -319.8876)
		(end 270.570198 -319.84188)
		(width 0.1143)
		(layer "In7.Cu")
		(net "P5E_PEX2_STN7_TX_DN<123>")
	)
	(segment
		(start 290.232592 -354.441252)
		(end 290.232592 -353.930966)
		(width 0.1651)
		(layer "In7.Cu")
		(net "P5E_PEX2_STN7_TX_DN<123>")
	)
	(segment
		(start 290.232592 -353.930966)
		(end 291.787072 -352.376486)
		(width 0.1651)
		(layer "In7.Cu")
		(net "P5E_PEX2_STN7_TX_DN<123>")
	)
	(segment
		(start 270.684498 -313.570112)
		(end 270.835628 -313.570112)
		(width 0.1143)
		(layer "In7.Cu")
		(net "P5E_PEX2_STN7_TX_DN<123>")
	)
	(segment
		(start 270.570198 -313.684412)
		(end 270.684498 -313.570112)
		(width 0.1143)
		(layer "In7.Cu")
		(net "P5E_PEX2_STN7_TX_DN<123>")
	)
	(segment
		(start 291.023294 -340.622128)
		(end 271.716754 -323.659754)
		(width 0.1651)
		(layer "In7.Cu")
		(net "P5E_PEX2_STN7_TX_DN<123>")
	)
	(segment
		(start 270.949928 -313.684412)
		(end 270.949928 -313.949842)
		(width 0.1143)
		(layer "In7.Cu")
		(net "P5E_PEX2_STN7_TX_DN<123>")
	)
	(segment
		(start 291.787072 -342.265)
		(end 291.023294 -340.622128)
		(width 0.1651)
		(layer "In7.Cu")
		(net "P5E_PEX2_STN7_TX_DN<123>")
	)
	(segment
		(start 344.725752 -340.824566)
		(end 345.45143 -341.54364)
		(width 0.1651)
		(layer "In5.Cu")
		(net "P5E_PEX2_STN5_RX_DN<93>")
	)
	(segment
		(start 302.915828 -320.509646)
		(end 303.135538 -321.039744)
		(width 0.1651)
		(layer "In5.Cu")
		(net "P5E_PEX2_STN5_RX_DN<93>")
	)
	(segment
		(start 342.490044 -372.508018)
		(end 342.490044 -372.890034)
		(width 0.1651)
		(layer "In5.Cu")
		(net "P5E_PEX2_STN5_RX_DN<93>")
	)
	(segment
		(start 303.249838 -318.699896)
		(end 303.249838 -318.434466)
		(width 0.1143)
		(layer "In5.Cu")
		(net "P5E_PEX2_STN5_RX_DN<93>")
	)
	(segment
		(start 302.915828 -319.941448)
		(end 302.915828 -319.969896)
		(width 0.1143)
		(layer "In5.Cu")
		(net "P5E_PEX2_STN5_RX_DN<93>")
	)
	(segment
		(start 303.249838 -318.434466)
		(end 303.135538 -318.320166)
		(width 0.1143)
		(layer "In5.Cu")
		(net "P5E_PEX2_STN5_RX_DN<93>")
	)
	(segment
		(start 302.915828 -319.969896)
		(end 302.915828 -320.509646)
		(width 0.1651)
		(layer "In5.Cu")
		(net "P5E_PEX2_STN5_RX_DN<93>")
	)
	(segment
		(start 345.955112 -342.75649)
		(end 345.780106 -357.602028)
		(width 0.1651)
		(layer "In5.Cu")
		(net "P5E_PEX2_STN5_RX_DN<93>")
	)
	(segment
		(start 304.334164 -322.238624)
		(end 344.725752 -340.824566)
		(width 0.1651)
		(layer "In5.Cu")
		(net "P5E_PEX2_STN5_RX_DN<93>")
	)
	(segment
		(start 302.984408 -318.320166)
		(end 302.870108 -318.434466)
		(width 0.1143)
		(layer "In5.Cu")
		(net "P5E_PEX2_STN5_RX_DN<93>")
	)
	(segment
		(start 343.616026 -369.857274)
		(end 343.616026 -371.929152)
		(width 0.1651)
		(layer "In5.Cu")
		(net "P5E_PEX2_STN5_RX_DN<93>")
	)
	(segment
		(start 345.45143 -341.54364)
		(end 345.955112 -342.75649)
		(width 0.1651)
		(layer "In5.Cu")
		(net "P5E_PEX2_STN5_RX_DN<93>")
	)
	(segment
		(start 303.135538 -321.039744)
		(end 304.334164 -322.238624)
		(width 0.1651)
		(layer "In5.Cu")
		(net "P5E_PEX2_STN5_RX_DN<93>")
	)
	(segment
		(start 343.16416 -372.381018)
		(end 342.617044 -372.381018)
		(width 0.1651)
		(layer "In5.Cu")
		(net "P5E_PEX2_STN5_RX_DN<93>")
	)
	(segment
		(start 302.870108 -319.895728)
		(end 302.915828 -319.941448)
		(width 0.1143)
		(layer "In5.Cu")
		(net "P5E_PEX2_STN5_RX_DN<93>")
	)
	(segment
		(start 342.617044 -372.381018)
		(end 342.490044 -372.508018)
		(width 0.1651)
		(layer "In5.Cu")
		(net "P5E_PEX2_STN5_RX_DN<93>")
	)
	(segment
		(start 343.616026 -371.929152)
		(end 343.16416 -372.381018)
		(width 0.1651)
		(layer "In5.Cu")
		(net "P5E_PEX2_STN5_RX_DN<93>")
	)
	(segment
		(start 303.135538 -318.320166)
		(end 302.984408 -318.320166)
		(width 0.1143)
		(layer "In5.Cu")
		(net "P5E_PEX2_STN5_RX_DN<93>")
	)
	(segment
		(start 345.780106 -357.602028)
		(end 343.616026 -369.857274)
		(width 0.1651)
		(layer "In5.Cu")
		(net "P5E_PEX2_STN5_RX_DN<93>")
	)
	(segment
		(start 302.870108 -318.434466)
		(end 302.870108 -319.895728)
		(width 0.1143)
		(layer "In5.Cu")
		(net "P5E_PEX2_STN5_RX_DN<93>")
	)
	(via
		(at 54.737 -138.176)
		(size 0.6604)
		(drill 0.3302)
		(layers "F.Cu" "B.Cu")
		(net "RST_SMB_NIC0_MUX_N")
	)
	(segment
		(start 54.737 -137.414)
		(end 55.09895 -137.05205)
		(width 0.13208)
		(layer "B.Cu")
		(net "RST_SMB_NIC0_MUX_N")
	)
	(segment
		(start 55.09895 -137.05205)
		(end 56.007 -137.05205)
		(width 0.13208)
		(layer "B.Cu")
		(net "RST_SMB_NIC0_MUX_N")
	)
	(segment
		(start 54.737 -140.804138)
		(end 54.737 -138.176)
		(width 0.13208)
		(layer "B.Cu")
		(net "RST_SMB_NIC0_MUX_N")
	)
	(segment
		(start 54.61 -140.931138)
		(end 54.737 -140.804138)
		(width 0.13208)
		(layer "B.Cu")
		(net "RST_SMB_NIC0_MUX_N")
	)
	(segment
		(start 53.96484 -140.931138)
		(end 54.61 -140.931138)
		(width 0.13208)
		(layer "B.Cu")
		(net "RST_SMB_NIC0_MUX_N")
	)
	(segment
		(start 54.737 -138.176)
		(end 54.737 -137.414)
		(width 0.13208)
		(layer "B.Cu")
		(net "RST_SMB_NIC0_MUX_N")
	)
	(segment
		(start 154.793696 -136.409684)
		(end 154.162252 -136.409684)
		(width 0.13462)
		(layer "F.Cu")
		(net "P5E_PEX1_STN1_TX_DP<31>")
	)
	(segment
		(start 155.113736 -136.729724)
		(end 154.793696 -136.409684)
		(width 0.13462)
		(layer "F.Cu")
		(net "P5E_PEX1_STN1_TX_DP<31>")
	)
	(segment
		(start 154.162252 -136.409684)
		(end 153.867612 -136.704324)
		(width 0.13462)
		(layer "F.Cu")
		(net "P5E_PEX1_STN1_TX_DP<31>")
	)
	(segment
		(start 156.150056 -148.263356)
		(end 156.232352 -148.31822)
		(width 0.1651)
		(layer "In9.Cu")
		(net "P5E_PEX1_STN1_TX_DP<31>")
	)
	(segment
		(start 155.430982 -144.055084)
		(end 155.341066 -144.18945)
		(width 0.1651)
		(layer "In9.Cu")
		(net "P5E_PEX1_STN1_TX_DP<31>")
	)
	(segment
		(start 152.739598 -137.11174)
		(end 153.10866 -137.480802)
		(width 0.1651)
		(layer "In9.Cu")
		(net "P5E_PEX1_STN1_TX_DP<31>")
	)
	(segment
		(start 156.05379 -147.777708)
		(end 156.150056 -148.263356)
		(width 0.1651)
		(layer "In9.Cu")
		(net "P5E_PEX1_STN1_TX_DP<31>")
	)
	(segment
		(start 152.739598 -136.641586)
		(end 152.739598 -137.11174)
		(width 0.1651)
		(layer "In9.Cu")
		(net "P5E_PEX1_STN1_TX_DP<31>")
	)
	(segment
		(start 154.962098 -142.282926)
		(end 155.096718 -142.372842)
		(width 0.1651)
		(layer "In9.Cu")
		(net "P5E_PEX1_STN1_TX_DP<31>")
	)
	(segment
		(start 153.577036 -136.413748)
		(end 153.577036 -136.413494)
		(width 0.1651)
		(layer "In9.Cu")
		(net "P5E_PEX1_STN1_TX_DP<31>")
	)
	(segment
		(start 189.885574 -280.129488)
		(end 189.999874 -280.015188)
		(width 0.1143)
		(layer "In9.Cu")
		(net "P5E_PEX1_STN1_TX_DP<31>")
	)
	(segment
		(start 152.96769 -136.413494)
		(end 152.739598 -136.641586)
		(width 0.1651)
		(layer "In9.Cu")
		(net "P5E_PEX1_STN1_TX_DP<31>")
	)
	(segment
		(start 155.668472 -145.25117)
		(end 155.578556 -145.385536)
		(width 0.1651)
		(layer "In9.Cu")
		(net "P5E_PEX1_STN1_TX_DP<31>")
	)
	(segment
		(start 154.707844 -140.481812)
		(end 154.628088 -140.601192)
		(width 0.1651)
		(layer "In9.Cu")
		(net "P5E_PEX1_STN1_TX_DP<31>")
	)
	(segment
		(start 155.578556 -145.385536)
		(end 155.674822 -145.871184)
		(width 0.1651)
		(layer "In9.Cu")
		(net "P5E_PEX1_STN1_TX_DP<31>")
	)
	(segment
		(start 155.437332 -144.675098)
		(end 155.571952 -144.765014)
		(width 0.1651)
		(layer "In9.Cu")
		(net "P5E_PEX1_STN1_TX_DP<31>")
	)
	(segment
		(start 163.497514 -185.260488)
		(end 189.665864 -262.564118)
		(width 0.1651)
		(layer "In9.Cu")
		(net "P5E_PEX1_STN1_TX_DP<31>")
	)
	(segment
		(start 155.905962 -146.447256)
		(end 155.816046 -146.581622)
		(width 0.1651)
		(layer "In9.Cu")
		(net "P5E_PEX1_STN1_TX_DP<31>")
	)
	(segment
		(start 189.620144 -271.600168)
		(end 189.620144 -280.025856)
		(width 0.1143)
		(layer "In9.Cu")
		(net "P5E_PEX1_STN1_TX_DP<31>")
	)
	(segment
		(start 155.809442 -145.9611)
		(end 155.905962 -146.447256)
		(width 0.1651)
		(layer "In9.Cu")
		(net "P5E_PEX1_STN1_TX_DP<31>")
	)
	(segment
		(start 156.232352 -148.31822)
		(end 156.346144 -148.891752)
		(width 0.1651)
		(layer "In9.Cu")
		(net "P5E_PEX1_STN1_TX_DP<31>")
	)
	(segment
		(start 153.867612 -136.704324)
		(end 153.577036 -136.413748)
		(width 0.1651)
		(layer "In9.Cu")
		(net "P5E_PEX1_STN1_TX_DP<31>")
	)
	(segment
		(start 153.934922 -138.307064)
		(end 154.390852 -139.407392)
		(width 0.1651)
		(layer "In9.Cu")
		(net "P5E_PEX1_STN1_TX_DP<31>")
	)
	(segment
		(start 153.5938 -137.965942)
		(end 153.934922 -138.307064)
		(width 0.1651)
		(layer "In9.Cu")
		(net "P5E_PEX1_STN1_TX_DP<31>")
	)
	(segment
		(start 156.346144 -148.891752)
		(end 156.29128 -148.973794)
		(width 0.1651)
		(layer "In9.Cu")
		(net "P5E_PEX1_STN1_TX_DP<31>")
	)
	(segment
		(start 189.620144 -280.025856)
		(end 189.723776 -280.129488)
		(width 0.1143)
		(layer "In9.Cu")
		(net "P5E_PEX1_STN1_TX_DP<31>")
	)
	(segment
		(start 155.816046 -146.581622)
		(end 155.912312 -147.06727)
		(width 0.1651)
		(layer "In9.Cu")
		(net "P5E_PEX1_STN1_TX_DP<31>")
	)
	(segment
		(start 155.571952 -144.765014)
		(end 155.668472 -145.25117)
		(width 0.1651)
		(layer "In9.Cu")
		(net "P5E_PEX1_STN1_TX_DP<31>")
	)
	(segment
		(start 189.665864 -262.564118)
		(end 189.665864 -271.526)
		(width 0.1651)
		(layer "In9.Cu")
		(net "P5E_PEX1_STN1_TX_DP<31>")
	)
	(segment
		(start 153.577036 -136.413494)
		(end 152.96769 -136.413494)
		(width 0.1651)
		(layer "In9.Cu")
		(net "P5E_PEX1_STN1_TX_DP<31>")
	)
	(segment
		(start 153.10866 -137.480802)
		(end 153.25217 -137.480802)
		(width 0.1651)
		(layer "In9.Cu")
		(net "P5E_PEX1_STN1_TX_DP<31>")
	)
	(segment
		(start 155.912312 -147.06727)
		(end 156.046932 -147.157186)
		(width 0.1651)
		(layer "In9.Cu")
		(net "P5E_PEX1_STN1_TX_DP<31>")
	)
	(segment
		(start 155.103576 -142.993364)
		(end 155.199842 -143.479012)
		(width 0.1651)
		(layer "In9.Cu")
		(net "P5E_PEX1_STN1_TX_DP<31>")
	)
	(segment
		(start 154.613864 -140.008102)
		(end 154.707844 -140.481812)
		(width 0.1651)
		(layer "In9.Cu")
		(net "P5E_PEX1_STN1_TX_DP<31>")
	)
	(segment
		(start 189.999874 -280.015188)
		(end 189.999874 -279.749504)
		(width 0.1143)
		(layer "In9.Cu")
		(net "P5E_PEX1_STN1_TX_DP<31>")
	)
	(segment
		(start 154.955494 -141.662912)
		(end 154.865832 -141.797278)
		(width 0.1651)
		(layer "In9.Cu")
		(net "P5E_PEX1_STN1_TX_DP<31>")
	)
	(segment
		(start 155.193238 -142.858998)
		(end 155.103576 -142.993364)
		(width 0.1651)
		(layer "In9.Cu")
		(net "P5E_PEX1_STN1_TX_DP<31>")
	)
	(segment
		(start 156.143452 -147.643342)
		(end 156.05379 -147.777708)
		(width 0.1651)
		(layer "In9.Cu")
		(net "P5E_PEX1_STN1_TX_DP<31>")
	)
	(segment
		(start 155.341066 -144.18945)
		(end 155.437332 -144.675098)
		(width 0.1651)
		(layer "In9.Cu")
		(net "P5E_PEX1_STN1_TX_DP<31>")
	)
	(segment
		(start 153.25217 -137.480802)
		(end 153.5938 -137.822178)
		(width 0.1651)
		(layer "In9.Cu")
		(net "P5E_PEX1_STN1_TX_DP<31>")
	)
	(segment
		(start 155.334462 -143.568928)
		(end 155.430982 -144.055084)
		(width 0.1651)
		(layer "In9.Cu")
		(net "P5E_PEX1_STN1_TX_DP<31>")
	)
	(segment
		(start 154.865832 -141.797278)
		(end 154.962098 -142.282926)
		(width 0.1651)
		(layer "In9.Cu")
		(net "P5E_PEX1_STN1_TX_DP<31>")
	)
	(segment
		(start 154.390852 -139.407392)
		(end 154.49423 -139.928346)
		(width 0.1651)
		(layer "In9.Cu")
		(net "P5E_PEX1_STN1_TX_DP<31>")
	)
	(segment
		(start 156.29128 -148.973794)
		(end 163.497514 -185.260488)
		(width 0.1651)
		(layer "In9.Cu")
		(net "P5E_PEX1_STN1_TX_DP<31>")
	)
	(segment
		(start 155.096718 -142.372842)
		(end 155.193238 -142.858998)
		(width 0.1651)
		(layer "In9.Cu")
		(net "P5E_PEX1_STN1_TX_DP<31>")
	)
	(segment
		(start 153.5938 -137.822178)
		(end 153.5938 -137.965942)
		(width 0.1651)
		(layer "In9.Cu")
		(net "P5E_PEX1_STN1_TX_DP<31>")
	)
	(segment
		(start 154.724354 -141.08684)
		(end 154.858974 -141.176756)
		(width 0.1651)
		(layer "In9.Cu")
		(net "P5E_PEX1_STN1_TX_DP<31>")
	)
	(segment
		(start 189.723776 -280.129488)
		(end 189.885574 -280.129488)
		(width 0.1143)
		(layer "In9.Cu")
		(net "P5E_PEX1_STN1_TX_DP<31>")
	)
	(segment
		(start 154.628088 -140.601192)
		(end 154.724354 -141.08684)
		(width 0.1651)
		(layer "In9.Cu")
		(net "P5E_PEX1_STN1_TX_DP<31>")
	)
	(segment
		(start 154.858974 -141.176756)
		(end 154.955494 -141.662912)
		(width 0.1651)
		(layer "In9.Cu")
		(net "P5E_PEX1_STN1_TX_DP<31>")
	)
	(segment
		(start 155.199842 -143.479012)
		(end 155.334462 -143.568928)
		(width 0.1651)
		(layer "In9.Cu")
		(net "P5E_PEX1_STN1_TX_DP<31>")
	)
	(segment
		(start 155.674822 -145.871184)
		(end 155.809442 -145.9611)
		(width 0.1651)
		(layer "In9.Cu")
		(net "P5E_PEX1_STN1_TX_DP<31>")
	)
	(segment
		(start 154.49423 -139.928346)
		(end 154.613864 -140.008102)
		(width 0.1651)
		(layer "In9.Cu")
		(net "P5E_PEX1_STN1_TX_DP<31>")
	)
	(segment
		(start 189.665864 -271.554448)
		(end 189.620144 -271.600168)
		(width 0.1143)
		(layer "In9.Cu")
		(net "P5E_PEX1_STN1_TX_DP<31>")
	)
	(segment
		(start 156.046932 -147.157186)
		(end 156.143452 -147.643342)
		(width 0.1651)
		(layer "In9.Cu")
		(net "P5E_PEX1_STN1_TX_DP<31>")
	)
	(segment
		(start 189.665864 -271.526)
		(end 189.665864 -271.554448)
		(width 0.1143)
		(layer "In9.Cu")
		(net "P5E_PEX1_STN1_TX_DP<31>")
	)
	(segment
		(start 115.265708 -349.511874)
		(end 115.265708 -348.88043)
		(width 0.13462)
		(layer "F.Cu")
		(net "P5E_PEX1_STN6_TX_DP<110>")
	)
	(segment
		(start 115.265708 -348.88043)
		(end 114.971068 -348.58579)
		(width 0.13462)
		(layer "F.Cu")
		(net "P5E_PEX1_STN6_TX_DP<110>")
	)
	(segment
		(start 114.945668 -349.831914)
		(end 115.265708 -349.511874)
		(width 0.13462)
		(layer "F.Cu")
		(net "P5E_PEX1_STN6_TX_DP<110>")
	)
	(segment
		(start 147.482814 -327.010014)
		(end 145.631408 -327.377552)
		(width 0.1651)
		(layer "In13.Cu")
		(net "P5E_PEX1_STN6_TX_DP<110>")
	)
	(segment
		(start 160.187894 -313.379612)
		(end 159.979614 -313.587892)
		(width 0.1143)
		(layer "In13.Cu")
		(net "P5E_PEX1_STN6_TX_DP<110>")
	)
	(segment
		(start 155.832302 -323.55155)
		(end 153.745184 -324.41642)
		(width 0.1651)
		(layer "In13.Cu")
		(net "P5E_PEX1_STN6_TX_DP<110>")
	)
	(segment
		(start 153.745184 -324.41642)
		(end 153.74493 -324.416166)
		(width 0.1651)
		(layer "In13.Cu")
		(net "P5E_PEX1_STN6_TX_DP<110>")
	)
	(segment
		(start 117.73916 -339.551264)
		(end 117.025928 -340.741254)
		(width 0.1651)
		(layer "In13.Cu")
		(net "P5E_PEX1_STN6_TX_DP<110>")
	)
	(segment
		(start 158.635954 -321.870832)
		(end 155.832302 -323.55155)
		(width 0.1651)
		(layer "In13.Cu")
		(net "P5E_PEX1_STN6_TX_DP<110>")
	)
	(segment
		(start 115.261898 -348.29496)
		(end 114.971068 -348.58579)
		(width 0.1651)
		(layer "In13.Cu")
		(net "P5E_PEX1_STN6_TX_DP<110>")
	)
	(segment
		(start 159.933894 -320.572892)
		(end 158.635954 -321.870832)
		(width 0.1651)
		(layer "In13.Cu")
		(net "P5E_PEX1_STN6_TX_DP<110>")
	)
	(segment
		(start 160.435544 -313.379612)
		(end 160.187894 -313.379612)
		(width 0.1143)
		(layer "In13.Cu")
		(net "P5E_PEX1_STN6_TX_DP<110>")
	)
	(segment
		(start 151.657558 -325.280782)
		(end 151.657812 -325.281036)
		(width 0.1651)
		(layer "In13.Cu")
		(net "P5E_PEX1_STN6_TX_DP<110>")
	)
	(segment
		(start 115.261898 -347.575378)
		(end 115.261898 -348.29496)
		(width 0.1651)
		(layer "In13.Cu")
		(net "P5E_PEX1_STN6_TX_DP<110>")
	)
	(segment
		(start 141.2113 -327.377552)
		(end 128.912874 -332.471776)
		(width 0.1651)
		(layer "In13.Cu")
		(net "P5E_PEX1_STN6_TX_DP<110>")
	)
	(segment
		(start 159.933894 -320.041016)
		(end 159.933894 -320.063114)
		(width 0.1143)
		(layer "In13.Cu")
		(net "P5E_PEX1_STN6_TX_DP<110>")
	)
	(segment
		(start 119.065548 -338.289138)
		(end 119.065294 -338.289138)
		(width 0.1651)
		(layer "In13.Cu")
		(net "P5E_PEX1_STN6_TX_DP<110>")
	)
	(segment
		(start 119.065294 -338.289138)
		(end 117.73916 -339.551264)
		(width 0.1651)
		(layer "In13.Cu")
		(net "P5E_PEX1_STN6_TX_DP<110>")
	)
	(segment
		(start 159.979614 -313.587892)
		(end 159.979614 -319.995296)
		(width 0.1143)
		(layer "In13.Cu")
		(net "P5E_PEX1_STN6_TX_DP<110>")
	)
	(segment
		(start 116.816378 -346.020898)
		(end 115.261898 -347.575378)
		(width 0.1651)
		(layer "In13.Cu")
		(net "P5E_PEX1_STN6_TX_DP<110>")
	)
	(segment
		(start 117.025928 -340.741254)
		(end 116.816378 -341.498682)
		(width 0.1651)
		(layer "In13.Cu")
		(net "P5E_PEX1_STN6_TX_DP<110>")
	)
	(segment
		(start 160.549844 -312.999882)
		(end 160.549844 -313.265312)
		(width 0.1143)
		(layer "In13.Cu")
		(net "P5E_PEX1_STN6_TX_DP<110>")
	)
	(segment
		(start 128.912874 -332.471776)
		(end 120.39219 -337.02625)
		(width 0.1651)
		(layer "In13.Cu")
		(net "P5E_PEX1_STN6_TX_DP<110>")
	)
	(segment
		(start 160.549844 -313.265312)
		(end 160.435544 -313.379612)
		(width 0.1143)
		(layer "In13.Cu")
		(net "P5E_PEX1_STN6_TX_DP<110>")
	)
	(segment
		(start 120.39219 -337.02625)
		(end 119.065548 -338.289138)
		(width 0.1651)
		(layer "In13.Cu")
		(net "P5E_PEX1_STN6_TX_DP<110>")
	)
	(segment
		(start 116.816378 -341.498682)
		(end 116.816378 -346.020898)
		(width 0.1651)
		(layer "In13.Cu")
		(net "P5E_PEX1_STN6_TX_DP<110>")
	)
	(segment
		(start 145.631408 -327.377552)
		(end 141.2113 -327.377552)
		(width 0.1651)
		(layer "In13.Cu")
		(net "P5E_PEX1_STN6_TX_DP<110>")
	)
	(segment
		(start 159.979614 -319.995296)
		(end 159.933894 -320.041016)
		(width 0.1143)
		(layer "In13.Cu")
		(net "P5E_PEX1_STN6_TX_DP<110>")
	)
	(segment
		(start 153.74493 -324.416166)
		(end 151.657558 -325.280782)
		(width 0.1651)
		(layer "In13.Cu")
		(net "P5E_PEX1_STN6_TX_DP<110>")
	)
	(segment
		(start 159.933894 -320.063114)
		(end 159.933894 -320.572892)
		(width 0.1651)
		(layer "In13.Cu")
		(net "P5E_PEX1_STN6_TX_DP<110>")
	)
	(segment
		(start 151.657812 -325.281036)
		(end 147.482814 -327.010014)
		(width 0.1651)
		(layer "In13.Cu")
		(net "P5E_PEX1_STN6_TX_DP<110>")
	)
	(segment
		(start 267.325602 -108.32084)
		(end 267.620242 -108.61548)
		(width 0.13462)
		(layer "F.Cu")
		(net "P5E_PEX2_STN1_TX_DN<21>")
	)
	(segment
		(start 268.251686 -108.61548)
		(end 268.571726 -108.29544)
		(width 0.13462)
		(layer "F.Cu")
		(net "P5E_PEX2_STN1_TX_DN<21>")
	)
	(segment
		(start 267.620242 -108.61548)
		(end 268.251686 -108.61548)
		(width 0.13462)
		(layer "F.Cu")
		(net "P5E_PEX2_STN1_TX_DN<21>")
	)
	(segment
		(start 260.538468 -159.000952)
		(end 261.118604 -161.917634)
		(width 0.1651)
		(layer "In9.Cu")
		(net "P5E_PEX2_STN1_TX_DN<21>")
	)
	(segment
		(start 296.029634 -271.600168)
		(end 296.029634 -280.10485)
		(width 0.1143)
		(layer "In9.Cu")
		(net "P5E_PEX2_STN1_TX_DN<21>")
	)
	(segment
		(start 295.983914 -264.919968)
		(end 295.983914 -271.526)
		(width 0.1651)
		(layer "In9.Cu")
		(net "P5E_PEX2_STN1_TX_DN<21>")
	)
	(segment
		(start 296.599864 -280.434288)
		(end 296.599864 -280.699718)
		(width 0.1143)
		(layer "In9.Cu")
		(net "P5E_PEX2_STN1_TX_DN<21>")
	)
	(segment
		(start 295.983914 -271.526)
		(end 295.983914 -271.554448)
		(width 0.1143)
		(layer "In9.Cu")
		(net "P5E_PEX2_STN1_TX_DN<21>")
	)
	(segment
		(start 296.244772 -280.319988)
		(end 296.485564 -280.319988)
		(width 0.1143)
		(layer "In9.Cu")
		(net "P5E_PEX2_STN1_TX_DN<21>")
	)
	(segment
		(start 257.243834 -138.027156)
		(end 259.812536 -144.22882)
		(width 0.1651)
		(layer "In9.Cu")
		(net "P5E_PEX2_STN1_TX_DN<21>")
	)
	(segment
		(start 259.812536 -144.22882)
		(end 260.35635 -155.297378)
		(width 0.1651)
		(layer "In9.Cu")
		(net "P5E_PEX2_STN1_TX_DN<21>")
	)
	(segment
		(start 264.64768 -110.216188)
		(end 264.64768 -110.246668)
		(width 0.1651)
		(layer "In9.Cu")
		(net "P5E_PEX2_STN1_TX_DN<21>")
	)
	(segment
		(start 295.983914 -271.554448)
		(end 296.029634 -271.600168)
		(width 0.1143)
		(layer "In9.Cu")
		(net "P5E_PEX2_STN1_TX_DN<21>")
	)
	(segment
		(start 264.64768 -110.246668)
		(end 260.819646 -119.487696)
		(width 0.1651)
		(layer "In9.Cu")
		(net "P5E_PEX2_STN1_TX_DN<21>")
	)
	(segment
		(start 267.325602 -108.32084)
		(end 267.034772 -108.61167)
		(width 0.1651)
		(layer "In9.Cu")
		(net "P5E_PEX2_STN1_TX_DN<21>")
	)
	(segment
		(start 260.819646 -119.487696)
		(end 257.243834 -131.276852)
		(width 0.1651)
		(layer "In9.Cu")
		(net "P5E_PEX2_STN1_TX_DN<21>")
	)
	(segment
		(start 267.034772 -108.61167)
		(end 266.252198 -108.61167)
		(width 0.1651)
		(layer "In9.Cu")
		(net "P5E_PEX2_STN1_TX_DN<21>")
	)
	(segment
		(start 296.485564 -280.319988)
		(end 296.599864 -280.434288)
		(width 0.1143)
		(layer "In9.Cu")
		(net "P5E_PEX2_STN1_TX_DN<21>")
	)
	(segment
		(start 257.243834 -131.276852)
		(end 257.243834 -138.027156)
		(width 0.1651)
		(layer "In9.Cu")
		(net "P5E_PEX2_STN1_TX_DN<21>")
	)
	(segment
		(start 260.35635 -155.297378)
		(end 260.538468 -159.000952)
		(width 0.1651)
		(layer "In9.Cu")
		(net "P5E_PEX2_STN1_TX_DN<21>")
	)
	(segment
		(start 261.118604 -161.917634)
		(end 295.983914 -264.919968)
		(width 0.1651)
		(layer "In9.Cu")
		(net "P5E_PEX2_STN1_TX_DN<21>")
	)
	(segment
		(start 296.029634 -280.10485)
		(end 296.244772 -280.319988)
		(width 0.1143)
		(layer "In9.Cu")
		(net "P5E_PEX2_STN1_TX_DN<21>")
	)
	(segment
		(start 266.252198 -108.61167)
		(end 264.64768 -110.216188)
		(width 0.1651)
		(layer "In9.Cu")
		(net "P5E_PEX2_STN1_TX_DN<21>")
	)
	(segment
		(start 299.555662 -349.511874)
		(end 299.555662 -348.88043)
		(width 0.13462)
		(layer "F.Cu")
		(net "P5E_PEX2_STN7_TX_DN<127>")
	)
	(segment
		(start 299.555662 -348.88043)
		(end 299.850302 -348.58579)
		(width 0.13462)
		(layer "F.Cu")
		(net "P5E_PEX2_STN7_TX_DN<127>")
	)
	(segment
		(start 299.875702 -349.831914)
		(end 299.555662 -349.511874)
		(width 0.13462)
		(layer "F.Cu")
		(net "P5E_PEX2_STN7_TX_DN<127>")
	)
	(segment
		(start 274.484338 -313.570112)
		(end 274.635468 -313.570112)
		(width 0.1143)
		(layer "In7.Cu")
		(net "P5E_PEX2_STN7_TX_DN<127>")
	)
	(segment
		(start 274.370038 -313.684412)
		(end 274.484338 -313.570112)
		(width 0.1143)
		(layer "In7.Cu")
		(net "P5E_PEX2_STN7_TX_DN<127>")
	)
	(segment
		(start 274.415758 -320.729864)
		(end 274.415758 -319.969896)
		(width 0.1651)
		(layer "In7.Cu")
		(net "P5E_PEX2_STN7_TX_DN<127>")
	)
	(segment
		(start 274.749768 -313.684412)
		(end 274.749768 -313.949842)
		(width 0.1143)
		(layer "In7.Cu")
		(net "P5E_PEX2_STN7_TX_DN<127>")
	)
	(segment
		(start 299.559472 -348.29496)
		(end 299.559472 -347.784674)
		(width 0.1651)
		(layer "In7.Cu")
		(net "P5E_PEX2_STN7_TX_DN<127>")
	)
	(segment
		(start 274.635468 -313.570112)
		(end 274.749768 -313.684412)
		(width 0.1143)
		(layer "In7.Cu")
		(net "P5E_PEX2_STN7_TX_DN<127>")
	)
	(segment
		(start 299.850302 -348.58579)
		(end 299.559472 -348.29496)
		(width 0.1651)
		(layer "In7.Cu")
		(net "P5E_PEX2_STN7_TX_DN<127>")
	)
	(segment
		(start 274.516342 -320.972942)
		(end 274.415758 -320.729864)
		(width 0.1651)
		(layer "In7.Cu")
		(net "P5E_PEX2_STN7_TX_DN<127>")
	)
	(segment
		(start 274.370038 -319.895728)
		(end 274.370038 -313.684412)
		(width 0.1143)
		(layer "In7.Cu")
		(net "P5E_PEX2_STN7_TX_DN<127>")
	)
	(segment
		(start 274.415758 -319.969896)
		(end 274.415758 -319.941448)
		(width 0.1143)
		(layer "In7.Cu")
		(net "P5E_PEX2_STN7_TX_DN<127>")
	)
	(segment
		(start 274.415758 -319.941448)
		(end 274.370038 -319.895728)
		(width 0.1143)
		(layer "In7.Cu")
		(net "P5E_PEX2_STN7_TX_DN<127>")
	)
	(segment
		(start 301.113952 -346.230194)
		(end 301.113952 -341.879428)
		(width 0.1651)
		(layer "In7.Cu")
		(net "P5E_PEX2_STN7_TX_DN<127>")
	)
	(segment
		(start 301.113952 -341.879428)
		(end 300.823376 -341.165942)
		(width 0.1651)
		(layer "In7.Cu")
		(net "P5E_PEX2_STN7_TX_DN<127>")
	)
	(segment
		(start 299.559472 -347.784674)
		(end 301.113952 -346.230194)
		(width 0.1651)
		(layer "In7.Cu")
		(net "P5E_PEX2_STN7_TX_DN<127>")
	)
	(segment
		(start 274.635468 -321.092068)
		(end 274.516342 -320.972942)
		(width 0.1651)
		(layer "In7.Cu")
		(net "P5E_PEX2_STN7_TX_DN<127>")
	)
	(segment
		(start 300.823376 -341.165942)
		(end 299.905674 -340.248494)
		(width 0.1651)
		(layer "In7.Cu")
		(net "P5E_PEX2_STN7_TX_DN<127>")
	)
	(segment
		(start 299.905674 -340.248494)
		(end 274.635468 -321.092068)
		(width 0.1651)
		(layer "In7.Cu")
		(net "P5E_PEX2_STN7_TX_DN<127>")
	)
	(segment
		(start 345.915488 -365.590328)
		(end 345.820238 -365.67237)
		(width 0.1651)
		(layer "In5.Cu")
		(net "P5E_PEX2_STN5_RX_DP<94>")
	)
	(segment
		(start 346.49283 -357.683054)
		(end 346.257372 -360.909616)
		(width 0.1651)
		(layer "In5.Cu")
		(net "P5E_PEX2_STN5_RX_DP<94>")
	)
	(segment
		(start 303.583848 -319.941448)
		(end 303.583848 -319.969896)
		(width 0.1143)
		(layer "In5.Cu")
		(net "P5E_PEX2_STN5_RX_DP<94>")
	)
	(segment
		(start 303.583848 -319.969896)
		(end 303.583848 -320.490342)
		(width 0.1651)
		(layer "In5.Cu")
		(net "P5E_PEX2_STN5_RX_DP<94>")
	)
	(segment
		(start 345.542362 -370.70411)
		(end 345.247214 -370.999258)
		(width 0.1651)
		(layer "In5.Cu")
		(net "P5E_PEX2_STN5_RX_DP<94>")
	)
	(segment
		(start 303.855374 -316.229492)
		(end 303.629568 -316.455298)
		(width 0.1143)
		(layer "In5.Cu")
		(net "P5E_PEX2_STN5_RX_DP<94>")
	)
	(segment
		(start 344.689938 -370.872258)
		(end 344.689938 -370.489988)
		(width 0.1651)
		(layer "In5.Cu")
		(net "P5E_PEX2_STN5_RX_DP<94>")
	)
	(segment
		(start 346.395548 -341.445596)
		(end 346.663772 -342.001856)
		(width 0.1651)
		(layer "In5.Cu")
		(net "P5E_PEX2_STN5_RX_DP<94>")
	)
	(segment
		(start 345.247214 -370.999258)
		(end 344.816938 -370.999258)
		(width 0.1651)
		(layer "In5.Cu")
		(net "P5E_PEX2_STN5_RX_DP<94>")
	)
	(segment
		(start 346.208096 -361.581192)
		(end 346.172282 -362.074968)
		(width 0.1651)
		(layer "In5.Cu")
		(net "P5E_PEX2_STN5_RX_DP<94>")
	)
	(segment
		(start 303.629568 -316.455298)
		(end 303.629568 -319.895728)
		(width 0.1143)
		(layer "In5.Cu")
		(net "P5E_PEX2_STN5_RX_DP<94>")
	)
	(segment
		(start 346.123006 -362.746544)
		(end 345.915488 -365.590328)
		(width 0.1651)
		(layer "In5.Cu")
		(net "P5E_PEX2_STN5_RX_DP<94>")
	)
	(segment
		(start 346.04071 -362.651294)
		(end 346.123006 -362.746544)
		(width 0.1651)
		(layer "In5.Cu")
		(net "P5E_PEX2_STN5_RX_DP<94>")
	)
	(segment
		(start 346.663772 -342.001856)
		(end 346.49283 -357.683054)
		(width 0.1651)
		(layer "In5.Cu")
		(net "P5E_PEX2_STN5_RX_DP<94>")
	)
	(segment
		(start 345.745562 -367.921032)
		(end 345.650312 -368.003074)
		(width 0.1651)
		(layer "In5.Cu")
		(net "P5E_PEX2_STN5_RX_DP<94>")
	)
	(segment
		(start 345.650312 -368.003074)
		(end 345.614244 -368.497358)
		(width 0.1651)
		(layer "In5.Cu")
		(net "P5E_PEX2_STN5_RX_DP<94>")
	)
	(segment
		(start 304.085498 -316.229492)
		(end 303.855374 -316.229492)
		(width 0.1143)
		(layer "In5.Cu")
		(net "P5E_PEX2_STN5_RX_DP<94>")
	)
	(segment
		(start 346.172282 -362.074968)
		(end 346.076778 -362.15701)
		(width 0.1651)
		(layer "In5.Cu")
		(net "P5E_PEX2_STN5_RX_DP<94>")
	)
	(segment
		(start 304.559716 -321.46621)
		(end 345.07043 -340.120224)
		(width 0.1651)
		(layer "In5.Cu")
		(net "P5E_PEX2_STN5_RX_DP<94>")
	)
	(segment
		(start 345.696286 -368.592608)
		(end 345.542362 -370.70411)
		(width 0.1651)
		(layer "In5.Cu")
		(net "P5E_PEX2_STN5_RX_DP<94>")
	)
	(segment
		(start 303.629568 -319.895728)
		(end 303.583848 -319.941448)
		(width 0.1143)
		(layer "In5.Cu")
		(net "P5E_PEX2_STN5_RX_DP<94>")
	)
	(segment
		(start 345.830398 -366.75568)
		(end 345.830652 -366.75568)
		(width 0.1651)
		(layer "In5.Cu")
		(net "P5E_PEX2_STN5_RX_DP<94>")
	)
	(segment
		(start 346.13088 -361.491784)
		(end 346.208096 -361.581192)
		(width 0.1651)
		(layer "In5.Cu")
		(net "P5E_PEX2_STN5_RX_DP<94>")
	)
	(segment
		(start 345.866466 -366.261904)
		(end 345.830398 -366.75568)
		(width 0.1651)
		(layer "In5.Cu")
		(net "P5E_PEX2_STN5_RX_DP<94>")
	)
	(segment
		(start 344.816938 -370.999258)
		(end 344.689938 -370.872258)
		(width 0.1651)
		(layer "In5.Cu")
		(net "P5E_PEX2_STN5_RX_DP<94>")
	)
	(segment
		(start 345.78417 -366.166654)
		(end 345.866466 -366.261904)
		(width 0.1651)
		(layer "In5.Cu")
		(net "P5E_PEX2_STN5_RX_DP<94>")
	)
	(segment
		(start 346.257372 -360.909616)
		(end 346.167964 -360.986832)
		(width 0.1651)
		(layer "In5.Cu")
		(net "P5E_PEX2_STN5_RX_DP<94>")
	)
	(segment
		(start 303.583848 -320.490342)
		(end 304.559716 -321.46621)
		(width 0.1651)
		(layer "In5.Cu")
		(net "P5E_PEX2_STN5_RX_DP<94>")
	)
	(segment
		(start 345.07043 -340.120224)
		(end 346.395548 -341.445596)
		(width 0.1651)
		(layer "In5.Cu")
		(net "P5E_PEX2_STN5_RX_DP<94>")
	)
	(segment
		(start 346.167964 -360.986832)
		(end 346.13088 -361.491784)
		(width 0.1651)
		(layer "In5.Cu")
		(net "P5E_PEX2_STN5_RX_DP<94>")
	)
	(segment
		(start 345.820238 -365.67237)
		(end 345.78417 -366.166654)
		(width 0.1651)
		(layer "In5.Cu")
		(net "P5E_PEX2_STN5_RX_DP<94>")
	)
	(segment
		(start 304.199798 -316.115192)
		(end 304.085498 -316.229492)
		(width 0.1143)
		(layer "In5.Cu")
		(net "P5E_PEX2_STN5_RX_DP<94>")
	)
	(segment
		(start 345.699334 -367.332006)
		(end 345.781376 -367.427256)
		(width 0.1651)
		(layer "In5.Cu")
		(net "P5E_PEX2_STN5_RX_DP<94>")
	)
	(segment
		(start 345.735402 -366.837722)
		(end 345.699334 -367.332006)
		(width 0.1651)
		(layer "In5.Cu")
		(net "P5E_PEX2_STN5_RX_DP<94>")
	)
	(segment
		(start 304.199798 -315.849762)
		(end 304.199798 -316.115192)
		(width 0.1143)
		(layer "In5.Cu")
		(net "P5E_PEX2_STN5_RX_DP<94>")
	)
	(segment
		(start 345.830652 -366.75568)
		(end 345.735402 -366.837722)
		(width 0.1651)
		(layer "In5.Cu")
		(net "P5E_PEX2_STN5_RX_DP<94>")
	)
	(segment
		(start 345.614244 -368.497358)
		(end 345.696286 -368.592608)
		(width 0.1651)
		(layer "In5.Cu")
		(net "P5E_PEX2_STN5_RX_DP<94>")
	)
	(segment
		(start 346.076778 -362.15701)
		(end 346.04071 -362.651294)
		(width 0.1651)
		(layer "In5.Cu")
		(net "P5E_PEX2_STN5_RX_DP<94>")
	)
	(segment
		(start 345.781376 -367.427256)
		(end 345.745562 -367.921032)
		(width 0.1651)
		(layer "In5.Cu")
		(net "P5E_PEX2_STN5_RX_DP<94>")
	)
	(segment
		(start 58.46445 -140.6398)
		(end 58.46445 -141.6558)
		(width 0.13208)
		(layer "F.Cu")
		(net "RST_SMB_NIC0_MUX_ISO_N")
	)
	(segment
		(start 58.46445 -142.57655)
		(end 56.769 -144.272)
		(width 0.13208)
		(layer "F.Cu")
		(net "RST_SMB_NIC0_MUX_ISO_N")
	)
	(segment
		(start 58.46445 -139.6238)
		(end 58.46445 -140.6398)
		(width 0.13208)
		(layer "F.Cu")
		(net "RST_SMB_NIC0_MUX_ISO_N")
	)
	(segment
		(start 58.46445 -141.6558)
		(end 58.46445 -142.57655)
		(width 0.13208)
		(layer "F.Cu")
		(net "RST_SMB_NIC0_MUX_ISO_N")
	)
	(via
		(at 56.769 -144.272)
		(size 0.508)
		(drill 0.254)
		(layers "F.Cu" "B.Cu")
		(net "RST_SMB_NIC0_MUX_ISO_N")
	)
	(segment
		(start 56.769 -144.272)
		(end 55.764684 -143.267684)
		(width 0.13208)
		(layer "B.Cu")
		(net "RST_SMB_NIC0_MUX_ISO_N")
	)
	(segment
		(start 55.764684 -143.267684)
		(end 55.764684 -141.6812)
		(width 0.13208)
		(layer "B.Cu")
		(net "RST_SMB_NIC0_MUX_ISO_N")
	)
	(segment
		(start 23.010368 -345.170506)
		(end 23.010368 -344.539062)
		(width 0.13462)
		(layer "F.Cu")
		(net "P5E_PEX0_STN7_TX_C_DN<113>")
	)
	(segment
		(start 23.305008 -345.465146)
		(end 23.010368 -345.170506)
		(width 0.13462)
		(layer "F.Cu")
		(net "P5E_PEX0_STN7_TX_C_DN<113>")
	)
	(segment
		(start 23.010368 -344.539062)
		(end 23.330408 -344.219022)
		(width 0.13462)
		(layer "F.Cu")
		(net "P5E_PEX0_STN7_TX_C_DN<113>")
	)
	(segment
		(start 31.284418 -401.966176)
		(end 31.284418 -394.707618)
		(width 0.1651)
		(layer "In7.Cu")
		(net "P5E_PEX0_STN7_TX_C_DN<113>")
	)
	(segment
		(start 30.969458 -402.281136)
		(end 31.284418 -401.966176)
		(width 0.1651)
		(layer "In7.Cu")
		(net "P5E_PEX0_STN7_TX_C_DN<113>")
	)
	(segment
		(start 30.236922 -402.281136)
		(end 30.969458 -402.281136)
		(width 0.1651)
		(layer "In7.Cu")
		(net "P5E_PEX0_STN7_TX_C_DN<113>")
	)
	(segment
		(start 24.997918 -390.920224)
		(end 22.544532 -388.466838)
		(width 0.1651)
		(layer "In7.Cu")
		(net "P5E_PEX0_STN7_TX_C_DN<113>")
	)
	(segment
		(start 30.109922 -402.790152)
		(end 30.109922 -402.408136)
		(width 0.1651)
		(layer "In7.Cu")
		(net "P5E_PEX0_STN7_TX_C_DN<113>")
	)
	(segment
		(start 21.459698 -352.080576)
		(end 21.459698 -348.029022)
		(width 0.1651)
		(layer "In7.Cu")
		(net "P5E_PEX0_STN7_TX_C_DN<113>")
	)
	(segment
		(start 31.284418 -394.707618)
		(end 29.264356 -392.687556)
		(width 0.1651)
		(layer "In7.Cu")
		(net "P5E_PEX0_STN7_TX_C_DN<113>")
	)
	(segment
		(start 30.109922 -402.408136)
		(end 30.236922 -402.281136)
		(width 0.1651)
		(layer "In7.Cu")
		(net "P5E_PEX0_STN7_TX_C_DN<113>")
	)
	(segment
		(start 22.544532 -388.466838)
		(end 21.031962 -385.105402)
		(width 0.1651)
		(layer "In7.Cu")
		(net "P5E_PEX0_STN7_TX_C_DN<113>")
	)
	(segment
		(start 23.014178 -345.755976)
		(end 23.305008 -345.465146)
		(width 0.1651)
		(layer "In7.Cu")
		(net "P5E_PEX0_STN7_TX_C_DN<113>")
	)
	(segment
		(start 23.014178 -346.474542)
		(end 23.014178 -345.755976)
		(width 0.1651)
		(layer "In7.Cu")
		(net "P5E_PEX0_STN7_TX_C_DN<113>")
	)
	(segment
		(start 29.264356 -392.687556)
		(end 24.997918 -390.920224)
		(width 0.1651)
		(layer "In7.Cu")
		(net "P5E_PEX0_STN7_TX_C_DN<113>")
	)
	(segment
		(start 21.031962 -385.105402)
		(end 20.193 -371.177058)
		(width 0.1651)
		(layer "In7.Cu")
		(net "P5E_PEX0_STN7_TX_C_DN<113>")
	)
	(segment
		(start 21.459698 -348.029022)
		(end 23.014178 -346.474542)
		(width 0.1651)
		(layer "In7.Cu")
		(net "P5E_PEX0_STN7_TX_C_DN<113>")
	)
	(segment
		(start 20.193 -371.177058)
		(end 20.804378 -358.735884)
		(width 0.1651)
		(layer "In7.Cu")
		(net "P5E_PEX0_STN7_TX_C_DN<113>")
	)
	(segment
		(start 20.804378 -358.735884)
		(end 21.459698 -352.080576)
		(width 0.1651)
		(layer "In7.Cu")
		(net "P5E_PEX0_STN7_TX_C_DN<113>")
	)
	(segment
		(start 181.408832 -344.539062)
		(end 181.728872 -344.219022)
		(width 0.13462)
		(layer "F.Cu")
		(net "P5E_PEX1_STN7_TX_C_DP<121>")
	)
	(segment
		(start 181.408832 -345.170506)
		(end 181.408832 -344.539062)
		(width 0.13462)
		(layer "F.Cu")
		(net "P5E_PEX1_STN7_TX_C_DP<121>")
	)
	(segment
		(start 181.703472 -345.465146)
		(end 181.408832 -345.170506)
		(width 0.13462)
		(layer "F.Cu")
		(net "P5E_PEX1_STN7_TX_C_DP<121>")
	)
	(segment
		(start 162.109912 -376.408188)
		(end 162.236912 -376.281188)
		(width 0.1651)
		(layer "In11.Cu")
		(net "P5E_PEX1_STN7_TX_C_DP<121>")
	)
	(segment
		(start 179.858162 -358.461564)
		(end 179.858162 -347.980254)
		(width 0.1651)
		(layer "In11.Cu")
		(net "P5E_PEX1_STN7_TX_C_DP<121>")
	)
	(segment
		(start 175.88103 -362.438696)
		(end 179.858162 -358.461564)
		(width 0.1651)
		(layer "In11.Cu")
		(net "P5E_PEX1_STN7_TX_C_DP<121>")
	)
	(segment
		(start 162.236912 -376.281188)
		(end 162.57524 -376.281188)
		(width 0.1651)
		(layer "In11.Cu")
		(net "P5E_PEX1_STN7_TX_C_DP<121>")
	)
	(segment
		(start 181.412642 -346.425774)
		(end 181.412642 -345.755976)
		(width 0.1651)
		(layer "In11.Cu")
		(net "P5E_PEX1_STN7_TX_C_DP<121>")
	)
	(segment
		(start 163.198556 -368.69116)
		(end 164.79901 -367.090706)
		(width 0.1651)
		(layer "In11.Cu")
		(net "P5E_PEX1_STN7_TX_C_DP<121>")
	)
	(segment
		(start 162.57524 -376.281188)
		(end 163.198556 -375.657872)
		(width 0.1651)
		(layer "In11.Cu")
		(net "P5E_PEX1_STN7_TX_C_DP<121>")
	)
	(segment
		(start 181.412642 -345.755976)
		(end 181.703472 -345.465146)
		(width 0.1651)
		(layer "In11.Cu")
		(net "P5E_PEX1_STN7_TX_C_DP<121>")
	)
	(segment
		(start 162.109912 -376.790204)
		(end 162.109912 -376.408188)
		(width 0.1651)
		(layer "In11.Cu")
		(net "P5E_PEX1_STN7_TX_C_DP<121>")
	)
	(segment
		(start 179.858162 -347.980254)
		(end 181.412642 -346.425774)
		(width 0.1651)
		(layer "In11.Cu")
		(net "P5E_PEX1_STN7_TX_C_DP<121>")
	)
	(segment
		(start 164.79901 -367.090706)
		(end 175.88103 -362.438696)
		(width 0.1651)
		(layer "In11.Cu")
		(net "P5E_PEX1_STN7_TX_C_DP<121>")
	)
	(segment
		(start 163.198556 -375.657872)
		(end 163.198556 -368.69116)
		(width 0.1651)
		(layer "In11.Cu")
		(net "P5E_PEX1_STN7_TX_C_DP<121>")
	)
	(segment
		(start 199.02805 -147.99691)
		(end 199.34809 -148.31695)
		(width 0.13462)
		(layer "F.Cu")
		(net "P5E_PEX1_STN0_TX_DN<11>")
	)
	(segment
		(start 199.34809 -148.31695)
		(end 199.979534 -148.31695)
		(width 0.13462)
		(layer "F.Cu")
		(net "P5E_PEX1_STN0_TX_DN<11>")
	)
	(segment
		(start 199.979534 -148.31695)
		(end 200.274174 -148.02231)
		(width 0.13462)
		(layer "F.Cu")
		(net "P5E_PEX1_STN0_TX_DN<11>")
	)
	(segment
		(start 195.361306 -268.64691)
		(end 194.415918 -270.929608)
		(width 0.1651)
		(layer "In9.Cu")
		(net "P5E_PEX1_STN0_TX_DN<11>")
	)
	(segment
		(start 194.415918 -271.500346)
		(end 194.370198 -271.546066)
		(width 0.1143)
		(layer "In9.Cu")
		(net "P5E_PEX1_STN0_TX_DN<11>")
	)
	(segment
		(start 194.749674 -278.115268)
		(end 194.749674 -277.849838)
		(width 0.1143)
		(layer "In9.Cu")
		(net "P5E_PEX1_STN0_TX_DN<11>")
	)
	(segment
		(start 195.904866 -177.303684)
		(end 191.982852 -222.13189)
		(width 0.1651)
		(layer "In9.Cu")
		(net "P5E_PEX1_STN0_TX_DN<11>")
	)
	(segment
		(start 194.415918 -271.471898)
		(end 194.415918 -271.500346)
		(width 0.1143)
		(layer "In9.Cu")
		(net "P5E_PEX1_STN0_TX_DN<11>")
	)
	(segment
		(start 191.982852 -222.13189)
		(end 195.361306 -260.775704)
		(width 0.1651)
		(layer "In9.Cu")
		(net "P5E_PEX1_STN0_TX_DN<11>")
	)
	(segment
		(start 205.622398 -154.959558)
		(end 205.622398 -157.763464)
		(width 0.1651)
		(layer "In9.Cu")
		(net "P5E_PEX1_STN0_TX_DN<11>")
	)
	(segment
		(start 194.370198 -271.546066)
		(end 194.370198 -278.12619)
		(width 0.1143)
		(layer "In9.Cu")
		(net "P5E_PEX1_STN0_TX_DN<11>")
	)
	(segment
		(start 200.274174 -148.02231)
		(end 200.565004 -148.31314)
		(width 0.1651)
		(layer "In9.Cu")
		(net "P5E_PEX1_STN0_TX_DN<11>")
	)
	(segment
		(start 203.658724 -150.981664)
		(end 204.490066 -152.22601)
		(width 0.1651)
		(layer "In9.Cu")
		(net "P5E_PEX1_STN0_TX_DN<11>")
	)
	(segment
		(start 194.473576 -278.229568)
		(end 194.635374 -278.229568)
		(width 0.1143)
		(layer "In9.Cu")
		(net "P5E_PEX1_STN0_TX_DN<11>")
	)
	(segment
		(start 202.893422 -149.836632)
		(end 203.65847 -150.98141)
		(width 0.1651)
		(layer "In9.Cu")
		(net "P5E_PEX1_STN0_TX_DN<11>")
	)
	(segment
		(start 195.361306 -260.775704)
		(end 195.361306 -268.64691)
		(width 0.1651)
		(layer "In9.Cu")
		(net "P5E_PEX1_STN0_TX_DN<11>")
	)
	(segment
		(start 205.622398 -157.763464)
		(end 197.260718 -172.248576)
		(width 0.1651)
		(layer "In9.Cu")
		(net "P5E_PEX1_STN0_TX_DN<11>")
	)
	(segment
		(start 194.635374 -278.229568)
		(end 194.749674 -278.115268)
		(width 0.1143)
		(layer "In9.Cu")
		(net "P5E_PEX1_STN0_TX_DN<11>")
	)
	(segment
		(start 194.370198 -278.12619)
		(end 194.473576 -278.229568)
		(width 0.1143)
		(layer "In9.Cu")
		(net "P5E_PEX1_STN0_TX_DN<11>")
	)
	(segment
		(start 203.65847 -150.98141)
		(end 203.658724 -150.981664)
		(width 0.1651)
		(layer "In9.Cu")
		(net "P5E_PEX1_STN0_TX_DN<11>")
	)
	(segment
		(start 201.36993 -148.31314)
		(end 202.893422 -149.836632)
		(width 0.1651)
		(layer "In9.Cu")
		(net "P5E_PEX1_STN0_TX_DN<11>")
	)
	(segment
		(start 197.260718 -172.248576)
		(end 195.904866 -177.303684)
		(width 0.1651)
		(layer "In9.Cu")
		(net "P5E_PEX1_STN0_TX_DN<11>")
	)
	(segment
		(start 194.415918 -270.929608)
		(end 194.415918 -271.471898)
		(width 0.1651)
		(layer "In9.Cu")
		(net "P5E_PEX1_STN0_TX_DN<11>")
	)
	(segment
		(start 204.490066 -152.22601)
		(end 205.622398 -154.959558)
		(width 0.1651)
		(layer "In9.Cu")
		(net "P5E_PEX1_STN0_TX_DN<11>")
	)
	(segment
		(start 200.565004 -148.31314)
		(end 201.36993 -148.31314)
		(width 0.1651)
		(layer "In9.Cu")
		(net "P5E_PEX1_STN0_TX_DN<11>")
	)
	(segment
		(start 175.190912 -355.026722)
		(end 175.485552 -354.732082)
		(width 0.13462)
		(layer "F.Cu")
		(net "P5E_PEX1_STN7_TX_DN<119>")
	)
	(segment
		(start 175.190912 -355.658166)
		(end 175.190912 -355.026722)
		(width 0.13462)
		(layer "F.Cu")
		(net "P5E_PEX1_STN7_TX_DN<119>")
	)
	(segment
		(start 175.510952 -355.978206)
		(end 175.190912 -355.658166)
		(width 0.13462)
		(layer "F.Cu")
		(net "P5E_PEX1_STN7_TX_DN<119>")
	)
	(segment
		(start 151.595836 -307.915818)
		(end 151.617934 -307.915818)
		(width 0.1143)
		(layer "In11.Cu")
		(net "P5E_PEX1_STN7_TX_DN<119>")
	)
	(segment
		(start 151.663654 -307.870098)
		(end 159.814514 -307.870098)
		(width 0.1143)
		(layer "In11.Cu")
		(net "P5E_PEX1_STN7_TX_DN<119>")
	)
	(segment
		(start 139.615926 -321.871594)
		(end 139.615926 -320.268346)
		(width 0.1651)
		(layer "In11.Cu")
		(net "P5E_PEX1_STN7_TX_DN<119>")
	)
	(segment
		(start 175.194722 -353.836224)
		(end 176.749202 -352.281744)
		(width 0.1651)
		(layer "In11.Cu")
		(net "P5E_PEX1_STN7_TX_DN<119>")
	)
	(segment
		(start 143.065246 -314.744354)
		(end 143.415258 -314.394342)
		(width 0.1651)
		(layer "In11.Cu")
		(net "P5E_PEX1_STN7_TX_DN<119>")
	)
	(segment
		(start 159.890714 -308.249828)
		(end 159.599884 -308.249828)
		(width 0.1143)
		(layer "In11.Cu")
		(net "P5E_PEX1_STN7_TX_DN<119>")
	)
	(segment
		(start 159.814514 -307.870098)
		(end 159.979614 -308.035198)
		(width 0.1143)
		(layer "In11.Cu")
		(net "P5E_PEX1_STN7_TX_DN<119>")
	)
	(segment
		(start 143.909542 -313.900058)
		(end 144.67459 -313.13501)
		(width 0.1651)
		(layer "In11.Cu")
		(net "P5E_PEX1_STN7_TX_DN<119>")
	)
	(segment
		(start 146.74342 -311.47385)
		(end 146.88693 -311.47385)
		(width 0.1651)
		(layer "In11.Cu")
		(net "P5E_PEX1_STN7_TX_DN<119>")
	)
	(segment
		(start 144.67459 -313.13501)
		(end 145.903442 -312.313828)
		(width 0.1651)
		(layer "In11.Cu")
		(net "P5E_PEX1_STN7_TX_DN<119>")
	)
	(segment
		(start 143.830548 -327.025762)
		(end 142.217902 -325.980044)
		(width 0.1651)
		(layer "In11.Cu")
		(net "P5E_PEX1_STN7_TX_DN<119>")
	)
	(segment
		(start 147.587462 -310.629808)
		(end 147.731226 -310.629808)
		(width 0.1651)
		(layer "In11.Cu")
		(net "P5E_PEX1_STN7_TX_DN<119>")
	)
	(segment
		(start 175.194722 -354.441252)
		(end 175.194722 -353.836224)
		(width 0.1651)
		(layer "In11.Cu")
		(net "P5E_PEX1_STN7_TX_DN<119>")
	)
	(segment
		(start 176.749202 -341.493602)
		(end 175.701198 -340.097364)
		(width 0.1651)
		(layer "In11.Cu")
		(net "P5E_PEX1_STN7_TX_DN<119>")
	)
	(segment
		(start 143.909542 -314.043822)
		(end 143.909542 -313.900058)
		(width 0.1651)
		(layer "In11.Cu")
		(net "P5E_PEX1_STN7_TX_DN<119>")
	)
	(segment
		(start 145.903442 -312.313828)
		(end 146.74342 -311.47385)
		(width 0.1651)
		(layer "In11.Cu")
		(net "P5E_PEX1_STN7_TX_DN<119>")
	)
	(segment
		(start 159.979614 -308.160928)
		(end 159.890714 -308.249828)
		(width 0.1143)
		(layer "In11.Cu")
		(net "P5E_PEX1_STN7_TX_DN<119>")
	)
	(segment
		(start 140.13561 -323.585586)
		(end 139.615926 -321.871594)
		(width 0.1651)
		(layer "In11.Cu")
		(net "P5E_PEX1_STN7_TX_DN<119>")
	)
	(segment
		(start 141.09065 -325.014082)
		(end 140.13561 -323.585586)
		(width 0.1651)
		(layer "In11.Cu")
		(net "P5E_PEX1_STN7_TX_DN<119>")
	)
	(segment
		(start 149.419818 -308.941216)
		(end 149.770338 -308.590696)
		(width 0.1651)
		(layer "In11.Cu")
		(net "P5E_PEX1_STN7_TX_DN<119>")
	)
	(segment
		(start 148.926042 -309.291228)
		(end 149.276054 -308.941216)
		(width 0.1651)
		(layer "In11.Cu")
		(net "P5E_PEX1_STN7_TX_DN<119>")
	)
	(segment
		(start 143.559022 -314.394342)
		(end 143.909542 -314.043822)
		(width 0.1651)
		(layer "In11.Cu")
		(net "P5E_PEX1_STN7_TX_DN<119>")
	)
	(segment
		(start 147.23745 -311.12333)
		(end 147.23745 -310.97982)
		(width 0.1651)
		(layer "In11.Cu")
		(net "P5E_PEX1_STN7_TX_DN<119>")
	)
	(segment
		(start 151.617934 -307.915818)
		(end 151.663654 -307.870098)
		(width 0.1143)
		(layer "In11.Cu")
		(net "P5E_PEX1_STN7_TX_DN<119>")
	)
	(segment
		(start 139.695936 -319.864486)
		(end 140.93571 -316.87389)
		(width 0.1651)
		(layer "In11.Cu")
		(net "P5E_PEX1_STN7_TX_DN<119>")
	)
	(segment
		(start 148.575522 -309.785512)
		(end 148.926042 -309.434992)
		(width 0.1651)
		(layer "In11.Cu")
		(net "P5E_PEX1_STN7_TX_DN<119>")
	)
	(segment
		(start 139.615926 -320.268346)
		(end 139.695936 -319.864486)
		(width 0.1651)
		(layer "In11.Cu")
		(net "P5E_PEX1_STN7_TX_DN<119>")
	)
	(segment
		(start 175.485552 -354.732082)
		(end 175.194722 -354.441252)
		(width 0.1651)
		(layer "In11.Cu")
		(net "P5E_PEX1_STN7_TX_DN<119>")
	)
	(segment
		(start 149.276054 -308.941216)
		(end 149.419818 -308.941216)
		(width 0.1651)
		(layer "In11.Cu")
		(net "P5E_PEX1_STN7_TX_DN<119>")
	)
	(segment
		(start 148.926042 -309.434992)
		(end 148.926042 -309.291228)
		(width 0.1651)
		(layer "In11.Cu")
		(net "P5E_PEX1_STN7_TX_DN<119>")
	)
	(segment
		(start 149.770338 -308.446932)
		(end 150.301452 -307.915818)
		(width 0.1651)
		(layer "In11.Cu")
		(net "P5E_PEX1_STN7_TX_DN<119>")
	)
	(segment
		(start 142.714726 -315.256672)
		(end 143.065246 -314.906152)
		(width 0.1651)
		(layer "In11.Cu")
		(net "P5E_PEX1_STN7_TX_DN<119>")
	)
	(segment
		(start 148.431758 -309.785512)
		(end 148.575522 -309.785512)
		(width 0.1651)
		(layer "In11.Cu")
		(net "P5E_PEX1_STN7_TX_DN<119>")
	)
	(segment
		(start 168.220136 -336.54746)
		(end 149.41423 -329.574652)
		(width 0.1651)
		(layer "In11.Cu")
		(net "P5E_PEX1_STN7_TX_DN<119>")
	)
	(segment
		(start 146.88693 -311.47385)
		(end 147.23745 -311.12333)
		(width 0.1651)
		(layer "In11.Cu")
		(net "P5E_PEX1_STN7_TX_DN<119>")
	)
	(segment
		(start 148.081746 -310.279288)
		(end 148.081746 -310.135524)
		(width 0.1651)
		(layer "In11.Cu")
		(net "P5E_PEX1_STN7_TX_DN<119>")
	)
	(segment
		(start 147.23745 -310.97982)
		(end 147.587462 -310.629808)
		(width 0.1651)
		(layer "In11.Cu")
		(net "P5E_PEX1_STN7_TX_DN<119>")
	)
	(segment
		(start 142.552928 -315.256672)
		(end 142.714726 -315.256672)
		(width 0.1651)
		(layer "In11.Cu")
		(net "P5E_PEX1_STN7_TX_DN<119>")
	)
	(segment
		(start 175.701198 -340.097364)
		(end 168.220136 -336.54746)
		(width 0.1651)
		(layer "In11.Cu")
		(net "P5E_PEX1_STN7_TX_DN<119>")
	)
	(segment
		(start 140.93571 -316.87389)
		(end 142.552928 -315.256672)
		(width 0.1651)
		(layer "In11.Cu")
		(net "P5E_PEX1_STN7_TX_DN<119>")
	)
	(segment
		(start 142.217902 -325.980044)
		(end 141.09065 -325.014082)
		(width 0.1651)
		(layer "In11.Cu")
		(net "P5E_PEX1_STN7_TX_DN<119>")
	)
	(segment
		(start 143.065246 -314.906152)
		(end 143.065246 -314.744354)
		(width 0.1651)
		(layer "In11.Cu")
		(net "P5E_PEX1_STN7_TX_DN<119>")
	)
	(segment
		(start 159.979614 -308.035198)
		(end 159.979614 -308.160928)
		(width 0.1143)
		(layer "In11.Cu")
		(net "P5E_PEX1_STN7_TX_DN<119>")
	)
	(segment
		(start 147.731226 -310.629808)
		(end 148.081746 -310.279288)
		(width 0.1651)
		(layer "In11.Cu")
		(net "P5E_PEX1_STN7_TX_DN<119>")
	)
	(segment
		(start 150.301452 -307.915818)
		(end 151.595836 -307.915818)
		(width 0.1651)
		(layer "In11.Cu")
		(net "P5E_PEX1_STN7_TX_DN<119>")
	)
	(segment
		(start 149.41423 -329.574652)
		(end 143.830548 -327.025762)
		(width 0.1651)
		(layer "In11.Cu")
		(net "P5E_PEX1_STN7_TX_DN<119>")
	)
	(segment
		(start 149.770338 -308.590696)
		(end 149.770338 -308.446932)
		(width 0.1651)
		(layer "In11.Cu")
		(net "P5E_PEX1_STN7_TX_DN<119>")
	)
	(segment
		(start 148.081746 -310.135524)
		(end 148.431758 -309.785512)
		(width 0.1651)
		(layer "In11.Cu")
		(net "P5E_PEX1_STN7_TX_DN<119>")
	)
	(segment
		(start 176.749202 -352.281744)
		(end 176.749202 -341.493602)
		(width 0.1651)
		(layer "In11.Cu")
		(net "P5E_PEX1_STN7_TX_DN<119>")
	)
	(segment
		(start 143.415258 -314.394342)
		(end 143.559022 -314.394342)
		(width 0.1651)
		(layer "In11.Cu")
		(net "P5E_PEX1_STN7_TX_DN<119>")
	)
	(segment
		(start 270.252444 -121.31548)
		(end 270.9037 -121.31548)
		(width 0.13462)
		(layer "F.Cu")
		(net "P5E_PEX2_STN1_TX_DN<25>")
	)
	(segment
		(start 269.96771 -121.030746)
		(end 270.252444 -121.31548)
		(width 0.13462)
		(layer "F.Cu")
		(net "P5E_PEX2_STN1_TX_DN<25>")
	)
	(segment
		(start 270.9037 -121.31548)
		(end 271.213834 -121.005346)
		(width 0.13462)
		(layer "F.Cu")
		(net "P5E_PEX2_STN1_TX_DN<25>")
	)
	(segment
		(start 264.3886 -158.240222)
		(end 264.998454 -161.306002)
		(width 0.1651)
		(layer "In9.Cu")
		(net "P5E_PEX2_STN1_TX_DN<25>")
	)
	(segment
		(start 269.96771 -121.030746)
		(end 269.67688 -121.321576)
		(width 0.1651)
		(layer "In9.Cu")
		(net "P5E_PEX2_STN1_TX_DN<25>")
	)
	(segment
		(start 266.537186 -121.321576)
		(end 265.0617 -122.797062)
		(width 0.1651)
		(layer "In9.Cu")
		(net "P5E_PEX2_STN1_TX_DN<25>")
	)
	(segment
		(start 264.998454 -161.306002)
		(end 299.783754 -264.068306)
		(width 0.1651)
		(layer "In9.Cu")
		(net "P5E_PEX2_STN1_TX_DN<25>")
	)
	(segment
		(start 261.114794 -137.251186)
		(end 263.658858 -143.39316)
		(width 0.1651)
		(layer "In9.Cu")
		(net "P5E_PEX2_STN1_TX_DN<25>")
	)
	(segment
		(start 299.783754 -271.554448)
		(end 299.829474 -271.600168)
		(width 0.1143)
		(layer "In9.Cu")
		(net "P5E_PEX2_STN1_TX_DN<25>")
	)
	(segment
		(start 300.399704 -280.434288)
		(end 300.399704 -280.699718)
		(width 0.1143)
		(layer "In9.Cu")
		(net "P5E_PEX2_STN1_TX_DN<25>")
	)
	(segment
		(start 299.783754 -271.526)
		(end 299.783754 -271.554448)
		(width 0.1143)
		(layer "In9.Cu")
		(net "P5E_PEX2_STN1_TX_DN<25>")
	)
	(segment
		(start 299.783754 -264.068306)
		(end 299.783754 -271.526)
		(width 0.1651)
		(layer "In9.Cu")
		(net "P5E_PEX2_STN1_TX_DN<25>")
	)
	(segment
		(start 269.67688 -121.321576)
		(end 266.537186 -121.321576)
		(width 0.1651)
		(layer "In9.Cu")
		(net "P5E_PEX2_STN1_TX_DN<25>")
	)
	(segment
		(start 300.044612 -280.319988)
		(end 300.285404 -280.319988)
		(width 0.1143)
		(layer "In9.Cu")
		(net "P5E_PEX2_STN1_TX_DN<25>")
	)
	(segment
		(start 299.829474 -280.10485)
		(end 300.044612 -280.319988)
		(width 0.1143)
		(layer "In9.Cu")
		(net "P5E_PEX2_STN1_TX_DN<25>")
	)
	(segment
		(start 265.0617 -122.797062)
		(end 261.114794 -132.325872)
		(width 0.1651)
		(layer "In9.Cu")
		(net "P5E_PEX2_STN1_TX_DN<25>")
	)
	(segment
		(start 261.114794 -132.325872)
		(end 261.114794 -137.251186)
		(width 0.1651)
		(layer "In9.Cu")
		(net "P5E_PEX2_STN1_TX_DN<25>")
	)
	(segment
		(start 263.658858 -143.39316)
		(end 264.3886 -158.240222)
		(width 0.1651)
		(layer "In9.Cu")
		(net "P5E_PEX2_STN1_TX_DN<25>")
	)
	(segment
		(start 300.285404 -280.319988)
		(end 300.399704 -280.434288)
		(width 0.1143)
		(layer "In9.Cu")
		(net "P5E_PEX2_STN1_TX_DN<25>")
	)
	(segment
		(start 299.829474 -271.600168)
		(end 299.829474 -280.10485)
		(width 0.1143)
		(layer "In9.Cu")
		(net "P5E_PEX2_STN1_TX_DN<25>")
	)
	(segment
		(start 299.281342 -349.511874)
		(end 299.281342 -348.88043)
		(width 0.13462)
		(layer "F.Cu")
		(net "P5E_PEX2_STN7_TX_DP<127>")
	)
	(segment
		(start 298.961302 -349.831914)
		(end 299.281342 -349.511874)
		(width 0.13462)
		(layer "F.Cu")
		(net "P5E_PEX2_STN7_TX_DP<127>")
	)
	(segment
		(start 299.281342 -348.88043)
		(end 298.986702 -348.58579)
		(width 0.13462)
		(layer "F.Cu")
		(net "P5E_PEX2_STN7_TX_DP<127>")
	)
	(segment
		(start 300.832012 -346.113354)
		(end 300.832012 -341.9348)
		(width 0.1651)
		(layer "In7.Cu")
		(net "P5E_PEX2_STN7_TX_DP<127>")
	)
	(segment
		(start 274.277328 -321.132708)
		(end 274.133818 -320.785998)
		(width 0.1651)
		(layer "In7.Cu")
		(net "P5E_PEX2_STN7_TX_DP<127>")
	)
	(segment
		(start 300.832012 -341.9348)
		(end 300.707806 -341.63)
		(width 0.1651)
		(layer "In7.Cu")
		(net "P5E_PEX2_STN7_TX_DP<127>")
	)
	(segment
		(start 299.277532 -347.667834)
		(end 300.832012 -346.113354)
		(width 0.1651)
		(layer "In7.Cu")
		(net "P5E_PEX2_STN7_TX_DP<127>")
	)
	(segment
		(start 274.635468 -313.379612)
		(end 274.749768 -313.265312)
		(width 0.1143)
		(layer "In7.Cu")
		(net "P5E_PEX2_STN7_TX_DP<127>")
	)
	(segment
		(start 300.707806 -341.63)
		(end 300.5836 -341.324946)
		(width 0.1651)
		(layer "In7.Cu")
		(net "P5E_PEX2_STN7_TX_DP<127>")
	)
	(segment
		(start 299.277532 -348.29496)
		(end 299.277532 -347.667834)
		(width 0.1651)
		(layer "In7.Cu")
		(net "P5E_PEX2_STN7_TX_DP<127>")
	)
	(segment
		(start 274.133818 -319.941448)
		(end 274.179538 -319.895728)
		(width 0.1143)
		(layer "In7.Cu")
		(net "P5E_PEX2_STN7_TX_DP<127>")
	)
	(segment
		(start 274.133818 -319.969896)
		(end 274.133818 -319.941448)
		(width 0.1143)
		(layer "In7.Cu")
		(net "P5E_PEX2_STN7_TX_DP<127>")
	)
	(segment
		(start 274.749768 -313.265312)
		(end 274.749768 -312.999882)
		(width 0.1143)
		(layer "In7.Cu")
		(net "P5E_PEX2_STN7_TX_DP<127>")
	)
	(segment
		(start 300.5836 -341.324946)
		(end 299.72 -340.4616)
		(width 0.1651)
		(layer "In7.Cu")
		(net "P5E_PEX2_STN7_TX_DP<127>")
	)
	(segment
		(start 274.179538 -319.895728)
		(end 274.179538 -313.605418)
		(width 0.1143)
		(layer "In7.Cu")
		(net "P5E_PEX2_STN7_TX_DP<127>")
	)
	(segment
		(start 299.72 -340.4616)
		(end 274.449794 -321.305174)
		(width 0.1651)
		(layer "In7.Cu")
		(net "P5E_PEX2_STN7_TX_DP<127>")
	)
	(segment
		(start 274.179538 -313.605418)
		(end 274.405344 -313.379612)
		(width 0.1143)
		(layer "In7.Cu")
		(net "P5E_PEX2_STN7_TX_DP<127>")
	)
	(segment
		(start 298.986702 -348.58579)
		(end 299.277532 -348.29496)
		(width 0.1651)
		(layer "In7.Cu")
		(net "P5E_PEX2_STN7_TX_DP<127>")
	)
	(segment
		(start 274.449794 -321.305174)
		(end 274.277328 -321.132708)
		(width 0.1651)
		(layer "In7.Cu")
		(net "P5E_PEX2_STN7_TX_DP<127>")
	)
	(segment
		(start 274.405344 -313.379612)
		(end 274.635468 -313.379612)
		(width 0.1143)
		(layer "In7.Cu")
		(net "P5E_PEX2_STN7_TX_DP<127>")
	)
	(segment
		(start 274.133818 -320.785998)
		(end 274.133818 -319.969896)
		(width 0.1651)
		(layer "In7.Cu")
		(net "P5E_PEX2_STN7_TX_DP<127>")
	)
	(via
		(at 403.03704 -138.176)
		(size 0.6604)
		(drill 0.3302)
		(layers "F.Cu" "B.Cu")
		(net "RST_SMB_NIC6_MUX_N")
	)
	(segment
		(start 403.03704 -137.414)
		(end 403.39899 -137.05205)
		(width 0.13208)
		(layer "B.Cu")
		(net "RST_SMB_NIC6_MUX_N")
	)
	(segment
		(start 403.03704 -138.176)
		(end 403.03704 -137.414)
		(width 0.13208)
		(layer "B.Cu")
		(net "RST_SMB_NIC6_MUX_N")
	)
	(segment
		(start 403.39899 -137.05205)
		(end 404.30704 -137.05205)
		(width 0.13208)
		(layer "B.Cu")
		(net "RST_SMB_NIC6_MUX_N")
	)
	(segment
		(start 402.26488 -140.931138)
		(end 402.91004 -140.931138)
		(width 0.13208)
		(layer "B.Cu")
		(net "RST_SMB_NIC6_MUX_N")
	)
	(segment
		(start 403.03704 -140.804138)
		(end 403.03704 -138.176)
		(width 0.13208)
		(layer "B.Cu")
		(net "RST_SMB_NIC6_MUX_N")
	)
	(segment
		(start 402.91004 -140.931138)
		(end 403.03704 -140.804138)
		(width 0.13208)
		(layer "B.Cu")
		(net "RST_SMB_NIC6_MUX_N")
	)
	(segment
		(start 80.93964 -138.661648)
		(end 80.93964 -139.058396)
		(width 0.13208)
		(layer "F.Cu")
		(net "PRSNT_NIC1_N")
	)
	(segment
		(start 86.94039 -141.004798)
		(end 88.108282 -141.004798)
		(width 0.13208)
		(layer "F.Cu")
		(net "PRSNT_NIC1_N")
	)
	(segment
		(start 77.293724 -138.474958)
		(end 66.799968 -138.474958)
		(width 0.13208)
		(layer "F.Cu")
		(net "PRSNT_NIC1_N")
	)
	(segment
		(start 88.346026 -141.242542)
		(end 88.346026 -155.886658)
		(width 0.13208)
		(layer "F.Cu")
		(net "PRSNT_NIC1_N")
	)
	(segment
		(start 62.321948 -138.864848)
		(end 63.07074 -138.864848)
		(width 0.13208)
		(layer "F.Cu")
		(net "PRSNT_NIC1_N")
	)
	(segment
		(start 84.948776 -139.0142)
		(end 84.29371 -138.359134)
		(width 0.13208)
		(layer "F.Cu")
		(net "PRSNT_NIC1_N")
	)
	(segment
		(start 86.94039 -141.004798)
		(end 86.94039 -140.330682)
		(width 0.13208)
		(layer "F.Cu")
		(net "PRSNT_NIC1_N")
	)
	(segment
		(start 86.94039 -140.330682)
		(end 85.623908 -139.0142)
		(width 0.13208)
		(layer "F.Cu")
		(net "PRSNT_NIC1_N")
	)
	(segment
		(start 66.799968 -138.474958)
		(end 65.860422 -139.414504)
		(width 0.13208)
		(layer "F.Cu")
		(net "PRSNT_NIC1_N")
	)
	(segment
		(start 63.19774 -139.414504)
		(end 63.07074 -139.287504)
		(width 0.13208)
		(layer "F.Cu")
		(net "PRSNT_NIC1_N")
	)
	(segment
		(start 81.242154 -138.359134)
		(end 80.93964 -138.661648)
		(width 0.13208)
		(layer "F.Cu")
		(net "PRSNT_NIC1_N")
	)
	(segment
		(start 88.108282 -141.004798)
		(end 88.346026 -141.242542)
		(width 0.13208)
		(layer "F.Cu")
		(net "PRSNT_NIC1_N")
	)
	(segment
		(start 65.860422 -139.414504)
		(end 63.19774 -139.414504)
		(width 0.13208)
		(layer "F.Cu")
		(net "PRSNT_NIC1_N")
	)
	(segment
		(start 88.346026 -155.886658)
		(end 84.997036 -159.235648)
		(width 0.13208)
		(layer "F.Cu")
		(net "PRSNT_NIC1_N")
	)
	(segment
		(start 84.29371 -138.359134)
		(end 81.242154 -138.359134)
		(width 0.13208)
		(layer "F.Cu")
		(net "PRSNT_NIC1_N")
	)
	(segment
		(start 78.004162 -139.185396)
		(end 77.293724 -138.474958)
		(width 0.13208)
		(layer "F.Cu")
		(net "PRSNT_NIC1_N")
	)
	(segment
		(start 84.997036 -159.235648)
		(end 80.93964 -159.235648)
		(width 0.13208)
		(layer "F.Cu")
		(net "PRSNT_NIC1_N")
	)
	(segment
		(start 85.623908 -139.0142)
		(end 84.948776 -139.0142)
		(width 0.13208)
		(layer "F.Cu")
		(net "PRSNT_NIC1_N")
	)
	(segment
		(start 63.07074 -139.287504)
		(end 63.07074 -138.864848)
		(width 0.13208)
		(layer "F.Cu")
		(net "PRSNT_NIC1_N")
	)
	(segment
		(start 63.27775 -118.331996)
		(end 63.27775 -117.566186)
		(width 0.13208)
		(layer "F.Cu")
		(net "PRSNT_NIC1_N")
	)
	(segment
		(start 80.81264 -139.185396)
		(end 78.004162 -139.185396)
		(width 0.13208)
		(layer "F.Cu")
		(net "PRSNT_NIC1_N")
	)
	(segment
		(start 80.93964 -139.058396)
		(end 80.81264 -139.185396)
		(width 0.13208)
		(layer "F.Cu")
		(net "PRSNT_NIC1_N")
	)
	(via
		(at 63.27775 -118.331996)
		(size 0.508)
		(drill 0.254)
		(layers "F.Cu" "B.Cu")
		(net "PRSNT_NIC1_N")
	)
	(via
		(at 62.321948 -138.864848)
		(size 0.508)
		(drill 0.254)
		(layers "F.Cu" "B.Cu")
		(net "PRSNT_NIC1_N")
	)
	(segment
		(start 62.321948 -138.864848)
		(end 62.874144 -138.312652)
		(width 0.15494)
		(layer "In9.Cu")
		(net "PRSNT_NIC1_N")
	)
	(segment
		(start 62.874144 -138.312652)
		(end 62.874144 -119.479568)
		(width 0.15494)
		(layer "In9.Cu")
		(net "PRSNT_NIC1_N")
	)
	(segment
		(start 62.874144 -119.479568)
		(end 63.27775 -119.075962)
		(width 0.15494)
		(layer "In9.Cu")
		(net "PRSNT_NIC1_N")
	)
	(segment
		(start 63.27775 -119.075962)
		(end 63.27775 -118.331996)
		(width 0.15494)
		(layer "In9.Cu")
		(net "PRSNT_NIC1_N")
	)
	(segment
		(start 196.385942 -142.590266)
		(end 196.705982 -142.910306)
		(width 0.13462)
		(layer "F.Cu")
		(net "P5E_PEX1_STN0_TX_DN<8>")
	)
	(segment
		(start 197.337426 -142.910306)
		(end 197.632066 -142.615666)
		(width 0.13462)
		(layer "F.Cu")
		(net "P5E_PEX1_STN0_TX_DN<8>")
	)
	(segment
		(start 196.705982 -142.910306)
		(end 197.337426 -142.910306)
		(width 0.13462)
		(layer "F.Cu")
		(net "P5E_PEX1_STN0_TX_DN<8>")
	)
	(segment
		(start 198.87565 -276.507448)
		(end 198.306944 -276.507448)
		(width 0.1143)
		(layer "In9.Cu")
		(net "P5E_PEX1_STN0_TX_DN<8>")
	)
	(segment
		(start 198.306944 -276.507448)
		(end 198.170292 -276.6441)
		(width 0.1143)
		(layer "In9.Cu")
		(net "P5E_PEX1_STN0_TX_DN<8>")
	)
	(segment
		(start 197.922896 -142.906496)
		(end 198.34225 -142.906496)
		(width 0.1651)
		(layer "In9.Cu")
		(net "P5E_PEX1_STN0_TX_DN<8>")
	)
	(segment
		(start 200.004426 -173.28642)
		(end 198.797418 -177.788062)
		(width 0.1651)
		(layer "In9.Cu")
		(net "P5E_PEX1_STN0_TX_DN<8>")
	)
	(segment
		(start 201.519536 -143.430498)
		(end 205.092554 -147.003516)
		(width 0.1651)
		(layer "In9.Cu")
		(net "P5E_PEX1_STN0_TX_DN<8>")
	)
	(segment
		(start 199.166226 -271.776952)
		(end 199.166226 -271.8054)
		(width 0.1143)
		(layer "In9.Cu")
		(net "P5E_PEX1_STN0_TX_DN<8>")
	)
	(segment
		(start 205.092554 -147.003516)
		(end 206.209138 -148.674074)
		(width 0.1651)
		(layer "In9.Cu")
		(net "P5E_PEX1_STN0_TX_DN<8>")
	)
	(segment
		(start 194.925188 -222.047308)
		(end 198.264526 -260.268466)
		(width 0.1651)
		(layer "In9.Cu")
		(net "P5E_PEX1_STN0_TX_DN<8>")
	)
	(segment
		(start 198.34225 -142.906496)
		(end 198.85406 -142.69466)
		(width 0.1651)
		(layer "In9.Cu")
		(net "P5E_PEX1_STN0_TX_DN<8>")
	)
	(segment
		(start 199.120506 -271.85112)
		(end 199.120506 -276.262592)
		(width 0.1143)
		(layer "In9.Cu")
		(net "P5E_PEX1_STN0_TX_DN<8>")
	)
	(segment
		(start 198.264526 -260.268466)
		(end 198.264526 -261.20217)
		(width 0.1651)
		(layer "In9.Cu")
		(net "P5E_PEX1_STN0_TX_DN<8>")
	)
	(segment
		(start 199.166226 -271.8054)
		(end 199.120506 -271.85112)
		(width 0.1143)
		(layer "In9.Cu")
		(net "P5E_PEX1_STN0_TX_DN<8>")
	)
	(segment
		(start 198.170292 -276.785578)
		(end 198.284592 -276.899878)
		(width 0.1143)
		(layer "In9.Cu")
		(net "P5E_PEX1_STN0_TX_DN<8>")
	)
	(segment
		(start 199.74306 -142.69466)
		(end 201.519536 -143.430498)
		(width 0.1651)
		(layer "In9.Cu")
		(net "P5E_PEX1_STN0_TX_DN<8>")
	)
	(segment
		(start 198.284592 -276.899878)
		(end 198.550022 -276.899878)
		(width 0.1143)
		(layer "In9.Cu")
		(net "P5E_PEX1_STN0_TX_DN<8>")
	)
	(segment
		(start 199.120506 -276.262592)
		(end 198.87565 -276.507448)
		(width 0.1143)
		(layer "In9.Cu")
		(net "P5E_PEX1_STN0_TX_DN<8>")
	)
	(segment
		(start 208.529682 -158.516574)
		(end 200.004426 -173.28642)
		(width 0.1651)
		(layer "In9.Cu")
		(net "P5E_PEX1_STN0_TX_DN<8>")
	)
	(segment
		(start 206.209138 -148.674074)
		(end 208.529682 -154.276552)
		(width 0.1651)
		(layer "In9.Cu")
		(net "P5E_PEX1_STN0_TX_DN<8>")
	)
	(segment
		(start 198.170292 -276.6441)
		(end 198.170292 -276.785578)
		(width 0.1143)
		(layer "In9.Cu")
		(net "P5E_PEX1_STN0_TX_DN<8>")
	)
	(segment
		(start 198.85406 -142.69466)
		(end 199.74306 -142.69466)
		(width 0.1651)
		(layer "In9.Cu")
		(net "P5E_PEX1_STN0_TX_DN<8>")
	)
	(segment
		(start 198.797418 -177.788062)
		(end 194.925188 -222.047308)
		(width 0.1651)
		(layer "In9.Cu")
		(net "P5E_PEX1_STN0_TX_DN<8>")
	)
	(segment
		(start 198.264526 -261.20217)
		(end 199.166226 -270.358108)
		(width 0.1651)
		(layer "In9.Cu")
		(net "P5E_PEX1_STN0_TX_DN<8>")
	)
	(segment
		(start 208.529682 -154.276552)
		(end 208.529682 -158.516574)
		(width 0.1651)
		(layer "In9.Cu")
		(net "P5E_PEX1_STN0_TX_DN<8>")
	)
	(segment
		(start 199.166226 -270.358108)
		(end 199.166226 -271.776952)
		(width 0.1651)
		(layer "In9.Cu")
		(net "P5E_PEX1_STN0_TX_DN<8>")
	)
	(segment
		(start 197.632066 -142.615666)
		(end 197.922896 -142.906496)
		(width 0.1651)
		(layer "In9.Cu")
		(net "P5E_PEX1_STN0_TX_DN<8>")
	)
	(segment
		(start 112.431068 -349.511874)
		(end 112.431068 -348.88043)
		(width 0.13462)
		(layer "F.Cu")
		(net "P5E_PEX1_STN6_TX_DN<103>")
	)
	(segment
		(start 112.431068 -348.88043)
		(end 112.725708 -348.58579)
		(width 0.13462)
		(layer "F.Cu")
		(net "P5E_PEX1_STN6_TX_DN<103>")
	)
	(segment
		(start 112.751108 -349.831914)
		(end 112.431068 -349.511874)
		(width 0.13462)
		(layer "F.Cu")
		(net "P5E_PEX1_STN6_TX_DN<103>")
	)
	(segment
		(start 165.35908 -320.038476)
		(end 165.358826 -319.974468)
		(width 0.1143)
		(layer "In7.Cu")
		(net "P5E_PEX1_STN6_TX_DN<103>")
	)
	(segment
		(start 166.934642 -311.670192)
		(end 167.085772 -311.670192)
		(width 0.1143)
		(layer "In7.Cu")
		(net "P5E_PEX1_STN6_TX_DN<103>")
	)
	(segment
		(start 112.434878 -347.736922)
		(end 113.989358 -346.182442)
		(width 0.1651)
		(layer "In7.Cu")
		(net "P5E_PEX1_STN6_TX_DN<103>")
	)
	(segment
		(start 130.217926 -331.086206)
		(end 164.802058 -320.595498)
		(width 0.1651)
		(layer "In7.Cu")
		(net "P5E_PEX1_STN6_TX_DN<103>")
	)
	(segment
		(start 115.457224 -339.933534)
		(end 130.217926 -331.086206)
		(width 0.1651)
		(layer "In7.Cu")
		(net "P5E_PEX1_STN6_TX_DN<103>")
	)
	(segment
		(start 113.989358 -341.4014)
		(end 115.457224 -339.933534)
		(width 0.1651)
		(layer "In7.Cu")
		(net "P5E_PEX1_STN6_TX_DN<103>")
	)
	(segment
		(start 167.200072 -311.784492)
		(end 167.200072 -312.049922)
		(width 0.1143)
		(layer "In7.Cu")
		(net "P5E_PEX1_STN6_TX_DN<103>")
	)
	(segment
		(start 166.531036 -319.2653)
		(end 166.820342 -318.975994)
		(width 0.1143)
		(layer "In7.Cu")
		(net "P5E_PEX1_STN6_TX_DN<103>")
	)
	(segment
		(start 165.358826 -319.974468)
		(end 166.067994 -319.2653)
		(width 0.1143)
		(layer "In7.Cu")
		(net "P5E_PEX1_STN6_TX_DN<103>")
	)
	(segment
		(start 164.802058 -320.595498)
		(end 165.339014 -320.058542)
		(width 0.1651)
		(layer "In7.Cu")
		(net "P5E_PEX1_STN6_TX_DN<103>")
	)
	(segment
		(start 112.434878 -348.29496)
		(end 112.434878 -347.736922)
		(width 0.1651)
		(layer "In7.Cu")
		(net "P5E_PEX1_STN6_TX_DN<103>")
	)
	(segment
		(start 166.067994 -319.2653)
		(end 166.531036 -319.2653)
		(width 0.1143)
		(layer "In7.Cu")
		(net "P5E_PEX1_STN6_TX_DN<103>")
	)
	(segment
		(start 113.989358 -346.182442)
		(end 113.989358 -341.4014)
		(width 0.1651)
		(layer "In7.Cu")
		(net "P5E_PEX1_STN6_TX_DN<103>")
	)
	(segment
		(start 166.820342 -311.784492)
		(end 166.934642 -311.670192)
		(width 0.1143)
		(layer "In7.Cu")
		(net "P5E_PEX1_STN6_TX_DN<103>")
	)
	(segment
		(start 166.820342 -318.975994)
		(end 166.820342 -311.784492)
		(width 0.1143)
		(layer "In7.Cu")
		(net "P5E_PEX1_STN6_TX_DN<103>")
	)
	(segment
		(start 112.725708 -348.58579)
		(end 112.434878 -348.29496)
		(width 0.1651)
		(layer "In7.Cu")
		(net "P5E_PEX1_STN6_TX_DN<103>")
	)
	(segment
		(start 165.339014 -320.058542)
		(end 165.35908 -320.038476)
		(width 0.1143)
		(layer "In7.Cu")
		(net "P5E_PEX1_STN6_TX_DN<103>")
	)
	(segment
		(start 167.085772 -311.670192)
		(end 167.200072 -311.784492)
		(width 0.1143)
		(layer "In7.Cu")
		(net "P5E_PEX1_STN6_TX_DN<103>")
	)
	(segment
		(start 316.374272 -124.102114)
		(end 316.074806 -124.40158)
		(width 0.13462)
		(layer "F.Cu")
		(net "P5E_PEX2_STN0_TX_DN<3>")
	)
	(segment
		(start 315.453014 -124.40158)
		(end 315.128148 -124.076714)
		(width 0.13462)
		(layer "F.Cu")
		(net "P5E_PEX2_STN0_TX_DN<3>")
	)
	(segment
		(start 316.074806 -124.40158)
		(end 315.453014 -124.40158)
		(width 0.13462)
		(layer "F.Cu")
		(net "P5E_PEX2_STN0_TX_DN<3>")
	)
	(segment
		(start 319.972436 -284.06344)
		(end 317.43269 -285.115508)
		(width 0.1651)
		(layer "In9.Cu")
		(net "P5E_PEX2_STN0_TX_DN<3>")
	)
	(segment
		(start 317.43269 -285.115508)
		(end 316.093602 -285.115508)
		(width 0.1651)
		(layer "In9.Cu")
		(net "P5E_PEX2_STN0_TX_DN<3>")
	)
	(segment
		(start 329.468226 -153.132536)
		(end 329.468226 -159.583628)
		(width 0.1651)
		(layer "In9.Cu")
		(net "P5E_PEX2_STN0_TX_DN<3>")
	)
	(segment
		(start 317.32728 -124.392944)
		(end 317.662306 -124.72797)
		(width 0.1651)
		(layer "In9.Cu")
		(net "P5E_PEX2_STN0_TX_DN<3>")
	)
	(segment
		(start 329.792076 -270.102838)
		(end 329.983592 -272.302224)
		(width 0.1651)
		(layer "In9.Cu")
		(net "P5E_PEX2_STN0_TX_DN<3>")
	)
	(segment
		(start 307.734208 -285.449772)
		(end 307.999892 -285.449772)
		(width 0.1143)
		(layer "In9.Cu")
		(net "P5E_PEX2_STN0_TX_DN<3>")
	)
	(segment
		(start 316.665102 -124.392944)
		(end 317.32728 -124.392944)
		(width 0.1651)
		(layer "In9.Cu")
		(net "P5E_PEX2_STN0_TX_DN<3>")
	)
	(segment
		(start 319.672208 -178.830478)
		(end 315.927232 -221.628208)
		(width 0.1651)
		(layer "In9.Cu")
		(net "P5E_PEX2_STN0_TX_DN<3>")
	)
	(segment
		(start 329.983592 -272.302224)
		(end 328.746104 -275.289772)
		(width 0.1651)
		(layer "In9.Cu")
		(net "P5E_PEX2_STN0_TX_DN<3>")
	)
	(segment
		(start 316.093602 -285.115508)
		(end 316.065154 -285.115508)
		(width 0.1143)
		(layer "In9.Cu")
		(net "P5E_PEX2_STN0_TX_DN<3>")
	)
	(segment
		(start 321.031362 -132.763514)
		(end 329.468226 -153.132536)
		(width 0.1651)
		(layer "In9.Cu")
		(net "P5E_PEX2_STN0_TX_DN<3>")
	)
	(segment
		(start 316.374272 -124.102114)
		(end 316.665102 -124.392944)
		(width 0.1651)
		(layer "In9.Cu")
		(net "P5E_PEX2_STN0_TX_DN<3>")
	)
	(segment
		(start 316.019434 -285.069788)
		(end 307.723794 -285.069788)
		(width 0.1143)
		(layer "In9.Cu")
		(net "P5E_PEX2_STN0_TX_DN<3>")
	)
	(segment
		(start 329.602592 -267.928344)
		(end 329.792076 -270.102838)
		(width 0.1651)
		(layer "In9.Cu")
		(net "P5E_PEX2_STN0_TX_DN<3>")
	)
	(segment
		(start 307.619908 -285.335472)
		(end 307.734208 -285.449772)
		(width 0.1143)
		(layer "In9.Cu")
		(net "P5E_PEX2_STN0_TX_DN<3>")
	)
	(segment
		(start 320.553588 -132.285486)
		(end 321.031362 -132.763514)
		(width 0.1651)
		(layer "In9.Cu")
		(net "P5E_PEX2_STN0_TX_DN<3>")
	)
	(segment
		(start 329.468226 -159.583628)
		(end 329.315318 -160.15589)
		(width 0.1651)
		(layer "In9.Cu")
		(net "P5E_PEX2_STN0_TX_DN<3>")
	)
	(segment
		(start 315.927232 -221.628208)
		(end 318.438276 -250.391168)
		(width 0.1651)
		(layer "In9.Cu")
		(net "P5E_PEX2_STN0_TX_DN<3>")
	)
	(segment
		(start 328.698606 -265.745722)
		(end 329.602592 -267.928344)
		(width 0.1651)
		(layer "In9.Cu")
		(net "P5E_PEX2_STN0_TX_DN<3>")
	)
	(segment
		(start 318.438276 -250.391168)
		(end 328.698606 -265.745722)
		(width 0.1651)
		(layer "In9.Cu")
		(net "P5E_PEX2_STN0_TX_DN<3>")
	)
	(segment
		(start 329.315318 -160.15589)
		(end 320.65722 -175.158908)
		(width 0.1651)
		(layer "In9.Cu")
		(net "P5E_PEX2_STN0_TX_DN<3>")
	)
	(segment
		(start 317.870586 -125.230636)
		(end 318.130428 -126.538228)
		(width 0.1651)
		(layer "In9.Cu")
		(net "P5E_PEX2_STN0_TX_DN<3>")
	)
	(segment
		(start 307.723794 -285.069788)
		(end 307.619908 -285.173674)
		(width 0.1143)
		(layer "In9.Cu")
		(net "P5E_PEX2_STN0_TX_DN<3>")
	)
	(segment
		(start 316.065154 -285.115508)
		(end 316.019434 -285.069788)
		(width 0.1143)
		(layer "In9.Cu")
		(net "P5E_PEX2_STN0_TX_DN<3>")
	)
	(segment
		(start 318.130428 -126.538228)
		(end 320.553588 -132.285486)
		(width 0.1651)
		(layer "In9.Cu")
		(net "P5E_PEX2_STN0_TX_DN<3>")
	)
	(segment
		(start 317.662306 -124.72797)
		(end 317.870586 -125.230636)
		(width 0.1651)
		(layer "In9.Cu")
		(net "P5E_PEX2_STN0_TX_DN<3>")
	)
	(segment
		(start 328.746104 -275.289772)
		(end 319.972436 -284.06344)
		(width 0.1651)
		(layer "In9.Cu")
		(net "P5E_PEX2_STN0_TX_DN<3>")
	)
	(segment
		(start 320.65722 -175.158908)
		(end 319.672208 -178.830478)
		(width 0.1651)
		(layer "In9.Cu")
		(net "P5E_PEX2_STN0_TX_DN<3>")
	)
	(segment
		(start 307.619908 -285.173674)
		(end 307.619908 -285.335472)
		(width 0.1143)
		(layer "In9.Cu")
		(net "P5E_PEX2_STN0_TX_DN<3>")
	)
	(segment
		(start 340.778084 -349.511874)
		(end 340.778084 -348.88043)
		(width 0.13462)
		(layer "F.Cu")
		(net "P5E_PEX2_STN6_TX_DP<98>")
	)
	(segment
		(start 340.458044 -349.831914)
		(end 340.778084 -349.511874)
		(width 0.13462)
		(layer "F.Cu")
		(net "P5E_PEX2_STN6_TX_DP<98>")
	)
	(segment
		(start 340.778084 -348.88043)
		(end 340.483444 -348.58579)
		(width 0.13462)
		(layer "F.Cu")
		(net "P5E_PEX2_STN6_TX_DP<98>")
	)
	(segment
		(start 342.328754 -346.113354)
		(end 342.328754 -342.174322)
		(width 0.1651)
		(layer "In13.Cu")
		(net "P5E_PEX2_STN6_TX_DP<98>")
	)
	(segment
		(start 288.049716 -313.265312)
		(end 288.049716 -312.999882)
		(width 0.1143)
		(layer "In13.Cu")
		(net "P5E_PEX2_STN6_TX_DP<98>")
	)
	(segment
		(start 341.72652 -341.29218)
		(end 335.006188 -336.056732)
		(width 0.1651)
		(layer "In13.Cu")
		(net "P5E_PEX2_STN6_TX_DP<98>")
	)
	(segment
		(start 287.433766 -321.08648)
		(end 287.433766 -320.046096)
		(width 0.1651)
		(layer "In13.Cu")
		(net "P5E_PEX2_STN6_TX_DP<98>")
	)
	(segment
		(start 287.951926 -321.716146)
		(end 287.433766 -321.08648)
		(width 0.1651)
		(layer "In13.Cu")
		(net "P5E_PEX2_STN6_TX_DP<98>")
	)
	(segment
		(start 287.433766 -320.046096)
		(end 287.433766 -320.017648)
		(width 0.1143)
		(layer "In13.Cu")
		(net "P5E_PEX2_STN6_TX_DP<98>")
	)
	(segment
		(start 314.974478 -327.019412)
		(end 287.951926 -321.716146)
		(width 0.1651)
		(layer "In13.Cu")
		(net "P5E_PEX2_STN6_TX_DP<98>")
	)
	(segment
		(start 287.433766 -320.017648)
		(end 287.479486 -319.971928)
		(width 0.1143)
		(layer "In13.Cu")
		(net "P5E_PEX2_STN6_TX_DP<98>")
	)
	(segment
		(start 287.479486 -319.971928)
		(end 287.479486 -313.59475)
		(width 0.1143)
		(layer "In13.Cu")
		(net "P5E_PEX2_STN6_TX_DP<98>")
	)
	(segment
		(start 340.774274 -347.667834)
		(end 342.328754 -346.113354)
		(width 0.1651)
		(layer "In13.Cu")
		(net "P5E_PEX2_STN6_TX_DP<98>")
	)
	(segment
		(start 340.483444 -348.58579)
		(end 340.774274 -348.29496)
		(width 0.1651)
		(layer "In13.Cu")
		(net "P5E_PEX2_STN6_TX_DP<98>")
	)
	(segment
		(start 342.328754 -342.174322)
		(end 341.72652 -341.29218)
		(width 0.1651)
		(layer "In13.Cu")
		(net "P5E_PEX2_STN6_TX_DP<98>")
	)
	(segment
		(start 340.774274 -348.29496)
		(end 340.774274 -347.667834)
		(width 0.1651)
		(layer "In13.Cu")
		(net "P5E_PEX2_STN6_TX_DP<98>")
	)
	(segment
		(start 335.006188 -336.056732)
		(end 314.974478 -327.019412)
		(width 0.1651)
		(layer "In13.Cu")
		(net "P5E_PEX2_STN6_TX_DP<98>")
	)
	(segment
		(start 287.479486 -313.59475)
		(end 287.694624 -313.379612)
		(width 0.1143)
		(layer "In13.Cu")
		(net "P5E_PEX2_STN6_TX_DP<98>")
	)
	(segment
		(start 287.694624 -313.379612)
		(end 287.935416 -313.379612)
		(width 0.1143)
		(layer "In13.Cu")
		(net "P5E_PEX2_STN6_TX_DP<98>")
	)
	(segment
		(start 287.935416 -313.379612)
		(end 288.049716 -313.265312)
		(width 0.1143)
		(layer "In13.Cu")
		(net "P5E_PEX2_STN6_TX_DP<98>")
	)
	(segment
		(start 406.76449 -142.57655)
		(end 406.76449 -141.6558)
		(width 0.13208)
		(layer "F.Cu")
		(net "RST_SMB_NIC6_MUX_ISO_N")
	)
	(segment
		(start 406.76449 -139.6238)
		(end 406.76449 -140.6398)
		(width 0.13208)
		(layer "F.Cu")
		(net "RST_SMB_NIC6_MUX_ISO_N")
	)
	(segment
		(start 405.06904 -144.272)
		(end 406.76449 -142.57655)
		(width 0.13208)
		(layer "F.Cu")
		(net "RST_SMB_NIC6_MUX_ISO_N")
	)
	(segment
		(start 406.76449 -140.6398)
		(end 406.76449 -141.6558)
		(width 0.13208)
		(layer "F.Cu")
		(net "RST_SMB_NIC6_MUX_ISO_N")
	)
	(via
		(at 405.06904 -144.272)
		(size 0.508)
		(drill 0.254)
		(layers "F.Cu" "B.Cu")
		(net "RST_SMB_NIC6_MUX_ISO_N")
	)
	(segment
		(start 405.06904 -144.272)
		(end 404.064724 -143.267684)
		(width 0.13208)
		(layer "B.Cu")
		(net "RST_SMB_NIC6_MUX_ISO_N")
	)
	(segment
		(start 404.064724 -143.267684)
		(end 404.064724 -141.6812)
		(width 0.13208)
		(layer "B.Cu")
		(net "RST_SMB_NIC6_MUX_ISO_N")
	)
	(segment
		(start 76.157582 -80.449674)
		(end 75.189334 -80.449674)
		(width 0.13208)
		(layer "F.Cu")
		(net "HP_NIC1_HSC_PWRGD_N")
	)
	(segment
		(start 75.189334 -80.449674)
		(end 74.889614 -80.749394)
		(width 0.13208)
		(layer "F.Cu")
		(net "HP_NIC1_HSC_PWRGD_N")
	)
	(segment
		(start 75.23988 -81.09966)
		(end 74.889614 -80.749394)
		(width 0.13208)
		(layer "F.Cu")
		(net "HP_NIC1_HSC_PWRGD_N")
	)
	(segment
		(start 76.157582 -81.09966)
		(end 75.23988 -81.09966)
		(width 0.13208)
		(layer "F.Cu")
		(net "HP_NIC1_HSC_PWRGD_N")
	)
	(segment
		(start 73.68286 -80.739742)
		(end 73.692512 -80.749394)
		(width 0.13208)
		(layer "F.Cu")
		(net "HP_NIC1_HSC_PWRGD_N")
	)
	(segment
		(start 73.692512 -80.749394)
		(end 74.889614 -80.749394)
		(width 0.13208)
		(layer "F.Cu")
		(net "HP_NIC1_HSC_PWRGD_N")
	)
	(via
		(at 74.889614 -80.749394)
		(size 0.762)
		(drill 0.381)
		(layers "F.Cu" "B.Cu")
		(net "HP_NIC1_HSC_PWRGD_N")
	)
	(segment
		(start 197.337426 -153.710386)
		(end 197.632066 -153.415746)
		(width 0.13462)
		(layer "F.Cu")
		(net "P5E_PEX1_STN0_TX_DP<14>")
	)
	(segment
		(start 196.385942 -153.390346)
		(end 196.705982 -153.710386)
		(width 0.13462)
		(layer "F.Cu")
		(net "P5E_PEX1_STN0_TX_DP<14>")
	)
	(segment
		(start 196.705982 -153.710386)
		(end 197.337426 -153.710386)
		(width 0.13462)
		(layer "F.Cu")
		(net "P5E_PEX1_STN0_TX_DP<14>")
	)
	(segment
		(start 192.677034 -179.342288)
		(end 189.011052 -221.249748)
		(width 0.1651)
		(layer "In9.Cu")
		(net "P5E_PEX1_STN0_TX_DP<14>")
	)
	(segment
		(start 192.458086 -260.666992)
		(end 192.458086 -267.660374)
		(width 0.1651)
		(layer "In9.Cu")
		(net "P5E_PEX1_STN0_TX_DP<14>")
	)
	(segment
		(start 202.723242 -155.81249)
		(end 202.723242 -156.835856)
		(width 0.1651)
		(layer "In9.Cu")
		(net "P5E_PEX1_STN0_TX_DP<14>")
	)
	(segment
		(start 201.037698 -153.706576)
		(end 202.426062 -155.09494)
		(width 0.1651)
		(layer "In9.Cu")
		(net "P5E_PEX1_STN0_TX_DP<14>")
	)
	(segment
		(start 191.566038 -271.526)
		(end 191.566038 -271.554448)
		(width 0.1143)
		(layer "In9.Cu")
		(net "P5E_PEX1_STN0_TX_DP<14>")
	)
	(segment
		(start 192.708022 -178.988974)
		(end 192.677288 -179.342288)
		(width 0.1651)
		(layer "In9.Cu")
		(net "P5E_PEX1_STN0_TX_DP<14>")
	)
	(segment
		(start 194.387978 -171.27347)
		(end 194.387978 -171.273724)
		(width 0.1651)
		(layer "In9.Cu")
		(net "P5E_PEX1_STN0_TX_DP<14>")
	)
	(segment
		(start 191.79413 -269.263876)
		(end 191.566038 -269.814548)
		(width 0.1651)
		(layer "In9.Cu")
		(net "P5E_PEX1_STN0_TX_DP<14>")
	)
	(segment
		(start 202.723242 -156.835856)
		(end 194.387978 -171.27347)
		(width 0.1651)
		(layer "In9.Cu")
		(net "P5E_PEX1_STN0_TX_DP<14>")
	)
	(segment
		(start 192.083436 -268.764766)
		(end 191.893444 -269.222728)
		(width 0.1651)
		(layer "In9.Cu")
		(net "P5E_PEX1_STN0_TX_DP<14>")
	)
	(segment
		(start 202.426062 -155.09494)
		(end 202.723242 -155.81249)
		(width 0.1651)
		(layer "In9.Cu")
		(net "P5E_PEX1_STN0_TX_DP<14>")
	)
	(segment
		(start 191.900048 -280.015188)
		(end 191.900048 -279.749504)
		(width 0.1143)
		(layer "In9.Cu")
		(net "P5E_PEX1_STN0_TX_DP<14>")
	)
	(segment
		(start 189.011052 -221.249748)
		(end 192.458086 -260.666992)
		(width 0.1651)
		(layer "In9.Cu")
		(net "P5E_PEX1_STN0_TX_DP<14>")
	)
	(segment
		(start 191.566038 -271.554448)
		(end 191.520318 -271.600168)
		(width 0.1143)
		(layer "In9.Cu")
		(net "P5E_PEX1_STN0_TX_DP<14>")
	)
	(segment
		(start 192.042034 -268.665198)
		(end 192.083436 -268.764766)
		(width 0.1651)
		(layer "In9.Cu")
		(net "P5E_PEX1_STN0_TX_DP<14>")
	)
	(segment
		(start 191.520318 -280.025856)
		(end 191.62395 -280.129488)
		(width 0.1143)
		(layer "In9.Cu")
		(net "P5E_PEX1_STN0_TX_DP<14>")
	)
	(segment
		(start 197.632066 -153.415746)
		(end 197.922896 -153.706576)
		(width 0.1651)
		(layer "In9.Cu")
		(net "P5E_PEX1_STN0_TX_DP<14>")
	)
	(segment
		(start 191.520318 -271.600168)
		(end 191.520318 -280.025856)
		(width 0.1143)
		(layer "In9.Cu")
		(net "P5E_PEX1_STN0_TX_DP<14>")
	)
	(segment
		(start 197.922896 -153.706576)
		(end 201.037698 -153.706576)
		(width 0.1651)
		(layer "In9.Cu")
		(net "P5E_PEX1_STN0_TX_DP<14>")
	)
	(segment
		(start 194.387978 -171.273724)
		(end 192.895728 -176.843436)
		(width 0.1651)
		(layer "In9.Cu")
		(net "P5E_PEX1_STN0_TX_DP<14>")
	)
	(segment
		(start 191.893444 -269.222728)
		(end 191.79413 -269.263876)
		(width 0.1651)
		(layer "In9.Cu")
		(net "P5E_PEX1_STN0_TX_DP<14>")
	)
	(segment
		(start 192.895728 -176.843436)
		(end 192.708022 -178.988974)
		(width 0.1651)
		(layer "In9.Cu")
		(net "P5E_PEX1_STN0_TX_DP<14>")
	)
	(segment
		(start 191.785748 -280.129488)
		(end 191.900048 -280.015188)
		(width 0.1143)
		(layer "In9.Cu")
		(net "P5E_PEX1_STN0_TX_DP<14>")
	)
	(segment
		(start 192.458086 -267.660374)
		(end 192.042034 -268.665198)
		(width 0.1651)
		(layer "In9.Cu")
		(net "P5E_PEX1_STN0_TX_DP<14>")
	)
	(segment
		(start 191.62395 -280.129488)
		(end 191.785748 -280.129488)
		(width 0.1143)
		(layer "In9.Cu")
		(net "P5E_PEX1_STN0_TX_DP<14>")
	)
	(segment
		(start 191.566038 -269.814548)
		(end 191.566038 -271.526)
		(width 0.1651)
		(layer "In9.Cu")
		(net "P5E_PEX1_STN0_TX_DP<14>")
	)
	(segment
		(start 192.677288 -179.342288)
		(end 192.677034 -179.342288)
		(width 0.1651)
		(layer "In9.Cu")
		(net "P5E_PEX1_STN0_TX_DP<14>")
	)
	(segment
		(start 162.480752 -355.658166)
		(end 162.480752 -355.026722)
		(width 0.13462)
		(layer "F.Cu")
		(net "P5E_PEX1_STN7_TX_DP<113>")
	)
	(segment
		(start 162.160712 -355.978206)
		(end 162.480752 -355.658166)
		(width 0.13462)
		(layer "F.Cu")
		(net "P5E_PEX1_STN7_TX_DP<113>")
	)
	(segment
		(start 162.480752 -355.026722)
		(end 162.186112 -354.732082)
		(width 0.13462)
		(layer "F.Cu")
		(net "P5E_PEX1_STN7_TX_DP<113>")
	)
	(segment
		(start 133.585458 -322.903596)
		(end 133.585458 -319.564004)
		(width 0.1651)
		(layer "In11.Cu")
		(net "P5E_PEX1_STN7_TX_DP<113>")
	)
	(segment
		(start 143.521684 -302.97501)
		(end 146.035268 -301.933864)
		(width 0.1651)
		(layer "In11.Cu")
		(net "P5E_PEX1_STN7_TX_DP<113>")
	)
	(segment
		(start 162.306508 -353.649788)
		(end 162.07867 -353.42449)
		(width 0.1651)
		(layer "In11.Cu")
		(net "P5E_PEX1_STN7_TX_DP<113>")
	)
	(segment
		(start 136.849612 -329.537822)
		(end 134.557262 -326.109584)
		(width 0.1651)
		(layer "In11.Cu")
		(net "P5E_PEX1_STN7_TX_DP<113>")
	)
	(segment
		(start 162.186112 -354.732082)
		(end 162.476942 -354.441252)
		(width 0.1651)
		(layer "In11.Cu")
		(net "P5E_PEX1_STN7_TX_DP<113>")
	)
	(segment
		(start 141.354556 -305.141884)
		(end 143.521684 -302.97501)
		(width 0.1651)
		(layer "In11.Cu")
		(net "P5E_PEX1_STN7_TX_DP<113>")
	)
	(segment
		(start 136.275572 -311.976262)
		(end 141.354556 -305.141884)
		(width 0.1651)
		(layer "In11.Cu")
		(net "P5E_PEX1_STN7_TX_DP<113>")
	)
	(segment
		(start 160.170114 -302.460914)
		(end 160.259014 -302.549814)
		(width 0.1143)
		(layer "In11.Cu")
		(net "P5E_PEX1_STN7_TX_DP<113>")
	)
	(segment
		(start 162.476942 -354.441252)
		(end 162.476942 -354.05695)
		(width 0.1651)
		(layer "In11.Cu")
		(net "P5E_PEX1_STN7_TX_DP<113>")
	)
	(segment
		(start 134.557262 -326.109584)
		(end 133.585458 -322.903596)
		(width 0.1651)
		(layer "In11.Cu")
		(net "P5E_PEX1_STN7_TX_DP<113>")
	)
	(segment
		(start 160.170114 -302.232314)
		(end 160.170114 -302.460914)
		(width 0.1143)
		(layer "In11.Cu")
		(net "P5E_PEX1_STN7_TX_DP<113>")
	)
	(segment
		(start 160.259014 -302.549814)
		(end 160.549844 -302.549814)
		(width 0.1143)
		(layer "In11.Cu")
		(net "P5E_PEX1_STN7_TX_DP<113>")
	)
	(segment
		(start 162.476942 -354.05695)
		(end 162.306508 -353.649788)
		(width 0.1651)
		(layer "In11.Cu")
		(net "P5E_PEX1_STN7_TX_DP<113>")
	)
	(segment
		(start 133.585458 -319.564004)
		(end 134.00405 -317.454788)
		(width 0.1651)
		(layer "In11.Cu")
		(net "P5E_PEX1_STN7_TX_DP<113>")
	)
	(segment
		(start 151.605234 -301.933864)
		(end 151.650954 -301.979584)
		(width 0.1143)
		(layer "In11.Cu")
		(net "P5E_PEX1_STN7_TX_DP<113>")
	)
	(segment
		(start 146.035268 -301.933864)
		(end 151.583136 -301.933864)
		(width 0.1651)
		(layer "In11.Cu")
		(net "P5E_PEX1_STN7_TX_DP<113>")
	)
	(segment
		(start 151.650954 -301.979584)
		(end 159.917384 -301.979584)
		(width 0.1143)
		(layer "In11.Cu")
		(net "P5E_PEX1_STN7_TX_DP<113>")
	)
	(segment
		(start 159.917384 -301.979584)
		(end 160.170114 -302.232314)
		(width 0.1143)
		(layer "In11.Cu")
		(net "P5E_PEX1_STN7_TX_DP<113>")
	)
	(segment
		(start 134.00405 -317.454788)
		(end 136.275572 -311.976262)
		(width 0.1651)
		(layer "In11.Cu")
		(net "P5E_PEX1_STN7_TX_DP<113>")
	)
	(segment
		(start 162.07867 -353.42449)
		(end 136.849612 -329.537822)
		(width 0.1651)
		(layer "In11.Cu")
		(net "P5E_PEX1_STN7_TX_DP<113>")
	)
	(segment
		(start 151.583136 -301.933864)
		(end 151.605234 -301.933864)
		(width 0.1143)
		(layer "In11.Cu")
		(net "P5E_PEX1_STN7_TX_DP<113>")
	)
	(segment
		(start 316.374272 -155.222194)
		(end 316.079886 -155.51658)
		(width 0.13462)
		(layer "F.Cu")
		(net "P5E_PEX2_STN0_TX_DN<15>")
	)
	(segment
		(start 315.447934 -155.51658)
		(end 315.128148 -155.196794)
		(width 0.13462)
		(layer "F.Cu")
		(net "P5E_PEX2_STN0_TX_DN<15>")
	)
	(segment
		(start 316.079886 -155.51658)
		(end 315.447934 -155.51658)
		(width 0.13462)
		(layer "F.Cu")
		(net "P5E_PEX2_STN0_TX_DN<15>")
	)
	(segment
		(start 307.049678 -278.115268)
		(end 307.049678 -277.849838)
		(width 0.1143)
		(layer "In9.Cu")
		(net "P5E_PEX2_STN0_TX_DN<15>")
	)
	(segment
		(start 304.062892 -220.410278)
		(end 307.59019 -260.731254)
		(width 0.1651)
		(layer "In9.Cu")
		(net "P5E_PEX2_STN0_TX_DN<15>")
	)
	(segment
		(start 309.374286 -171.265088)
		(end 307.871876 -176.871122)
		(width 0.1651)
		(layer "In9.Cu")
		(net "P5E_PEX2_STN0_TX_DN<15>")
	)
	(segment
		(start 307.59019 -260.731254)
		(end 307.59019 -267.473684)
		(width 0.1651)
		(layer "In9.Cu")
		(net "P5E_PEX2_STN0_TX_DN<15>")
	)
	(segment
		(start 316.374272 -155.222194)
		(end 316.665102 -155.513024)
		(width 0.1651)
		(layer "In9.Cu")
		(net "P5E_PEX2_STN0_TX_DN<15>")
	)
	(segment
		(start 306.715922 -271.471898)
		(end 306.715922 -271.500346)
		(width 0.1143)
		(layer "In9.Cu")
		(net "P5E_PEX2_STN0_TX_DN<15>")
	)
	(segment
		(start 306.670202 -278.12619)
		(end 306.77358 -278.229568)
		(width 0.1143)
		(layer "In9.Cu")
		(net "P5E_PEX2_STN0_TX_DN<15>")
	)
	(segment
		(start 306.935378 -278.229568)
		(end 307.049678 -278.115268)
		(width 0.1143)
		(layer "In9.Cu")
		(net "P5E_PEX2_STN0_TX_DN<15>")
	)
	(segment
		(start 306.670202 -271.546066)
		(end 306.670202 -278.12619)
		(width 0.1143)
		(layer "In9.Cu")
		(net "P5E_PEX2_STN0_TX_DN<15>")
	)
	(segment
		(start 307.871876 -176.871122)
		(end 304.062892 -220.410278)
		(width 0.1651)
		(layer "In9.Cu")
		(net "P5E_PEX2_STN0_TX_DN<15>")
	)
	(segment
		(start 306.715922 -271.500346)
		(end 306.670202 -271.546066)
		(width 0.1143)
		(layer "In9.Cu")
		(net "P5E_PEX2_STN0_TX_DN<15>")
	)
	(segment
		(start 316.665102 -155.513024)
		(end 317.39078 -155.513024)
		(width 0.1651)
		(layer "In9.Cu")
		(net "P5E_PEX2_STN0_TX_DN<15>")
	)
	(segment
		(start 317.857124 -156.571442)
		(end 309.374286 -171.265088)
		(width 0.1651)
		(layer "In9.Cu")
		(net "P5E_PEX2_STN0_TX_DN<15>")
	)
	(segment
		(start 317.857124 -155.979368)
		(end 317.857124 -156.571442)
		(width 0.1651)
		(layer "In9.Cu")
		(net "P5E_PEX2_STN0_TX_DN<15>")
	)
	(segment
		(start 317.39078 -155.513024)
		(end 317.857124 -155.979368)
		(width 0.1651)
		(layer "In9.Cu")
		(net "P5E_PEX2_STN0_TX_DN<15>")
	)
	(segment
		(start 306.715922 -269.584932)
		(end 306.715922 -271.471898)
		(width 0.1651)
		(layer "In9.Cu")
		(net "P5E_PEX2_STN0_TX_DN<15>")
	)
	(segment
		(start 307.59019 -267.473684)
		(end 306.715922 -269.584932)
		(width 0.1651)
		(layer "In9.Cu")
		(net "P5E_PEX2_STN0_TX_DN<15>")
	)
	(segment
		(start 306.77358 -278.229568)
		(end 306.935378 -278.229568)
		(width 0.1143)
		(layer "In9.Cu")
		(net "P5E_PEX2_STN0_TX_DN<15>")
	)
	(segment
		(start 271.575022 -355.658166)
		(end 271.575022 -355.026722)
		(width 0.13462)
		(layer "F.Cu")
		(net "P5E_PEX2_STN7_TX_DN<114>")
	)
	(segment
		(start 271.575022 -355.026722)
		(end 271.869662 -354.732082)
		(width 0.13462)
		(layer "F.Cu")
		(net "P5E_PEX2_STN7_TX_DN<114>")
	)
	(segment
		(start 271.895062 -355.978206)
		(end 271.575022 -355.658166)
		(width 0.13462)
		(layer "F.Cu")
		(net "P5E_PEX2_STN7_TX_DN<114>")
	)
	(segment
		(start 267.935456 -337.5152)
		(end 255.46558 -330.414122)
		(width 0.1651)
		(layer "In7.Cu")
		(net "P5E_PEX2_STN7_TX_DN<114>")
	)
	(segment
		(start 254.352044 -310.304434)
		(end 254.352298 -310.304434)
		(width 0.1651)
		(layer "In7.Cu")
		(net "P5E_PEX2_STN7_TX_DN<114>")
	)
	(segment
		(start 253.480316 -312.501788)
		(end 253.440692 -312.401458)
		(width 0.1651)
		(layer "In7.Cu")
		(net "P5E_PEX2_STN7_TX_DN<114>")
	)
	(segment
		(start 253.896368 -311.352946)
		(end 253.896622 -311.352946)
		(width 0.1651)
		(layer "In7.Cu")
		(net "P5E_PEX2_STN7_TX_DN<114>")
	)
	(segment
		(start 256.797556 -306.218844)
		(end 256.905252 -306.212494)
		(width 0.1651)
		(layer "In7.Cu")
		(net "P5E_PEX2_STN7_TX_DN<114>")
	)
	(segment
		(start 256.46888 -306.589176)
		(end 256.797556 -306.218844)
		(width 0.1651)
		(layer "In7.Cu")
		(net "P5E_PEX2_STN7_TX_DN<114>")
	)
	(segment
		(start 256.47523 -306.696872)
		(end 256.46888 -306.589176)
		(width 0.1651)
		(layer "In7.Cu")
		(net "P5E_PEX2_STN7_TX_DN<114>")
	)
	(segment
		(start 266.646406 -303.165764)
		(end 267.865352 -303.165764)
		(width 0.1651)
		(layer "In7.Cu")
		(net "P5E_PEX2_STN7_TX_DN<114>")
	)
	(segment
		(start 257.234182 -305.841908)
		(end 257.227832 -305.734466)
		(width 0.1651)
		(layer "In7.Cu")
		(net "P5E_PEX2_STN7_TX_DN<114>")
	)
	(segment
		(start 268.039342 -337.486498)
		(end 267.935456 -337.5152)
		(width 0.1651)
		(layer "In7.Cu")
		(net "P5E_PEX2_STN7_TX_DN<114>")
	)
	(segment
		(start 253.896622 -311.352946)
		(end 254.09398 -310.898794)
		(width 0.1651)
		(layer "In7.Cu")
		(net "P5E_PEX2_STN7_TX_DN<114>")
	)
	(segment
		(start 253.182628 -312.996072)
		(end 253.182374 -312.995818)
		(width 0.1651)
		(layer "In7.Cu")
		(net "P5E_PEX2_STN7_TX_DN<114>")
	)
	(segment
		(start 255.26365 -308.20741)
		(end 255.485392 -307.69687)
		(width 0.1651)
		(layer "In7.Cu")
		(net "P5E_PEX2_STN7_TX_DN<114>")
	)
	(segment
		(start 271.578832 -353.930966)
		(end 273.133312 -352.376486)
		(width 0.1651)
		(layer "In7.Cu")
		(net "P5E_PEX2_STN7_TX_DN<114>")
	)
	(segment
		(start 256.905252 -306.212494)
		(end 257.234182 -305.841908)
		(width 0.1651)
		(layer "In7.Cu")
		(net "P5E_PEX2_STN7_TX_DN<114>")
	)
	(segment
		(start 255.005078 -308.80177)
		(end 255.105408 -308.7624)
		(width 0.1651)
		(layer "In7.Cu")
		(net "P5E_PEX2_STN7_TX_DN<114>")
	)
	(segment
		(start 271.02562 -339.274912)
		(end 270.485362 -338.967318)
		(width 0.1651)
		(layer "In7.Cu")
		(net "P5E_PEX2_STN7_TX_DN<114>")
	)
	(segment
		(start 274.179538 -303.234344)
		(end 274.179538 -303.385474)
		(width 0.1143)
		(layer "In7.Cu")
		(net "P5E_PEX2_STN7_TX_DN<114>")
	)
	(segment
		(start 254.847344 -309.356252)
		(end 254.80772 -309.255922)
		(width 0.1651)
		(layer "In7.Cu")
		(net "P5E_PEX2_STN7_TX_DN<114>")
	)
	(segment
		(start 250.92914 -318.181482)
		(end 253.182628 -312.996072)
		(width 0.1651)
		(layer "In7.Cu")
		(net "P5E_PEX2_STN7_TX_DN<114>")
	)
	(segment
		(start 273.133312 -342.271604)
		(end 272.645886 -341.02675)
		(width 0.1651)
		(layer "In7.Cu")
		(net "P5E_PEX2_STN7_TX_DN<114>")
	)
	(segment
		(start 252.328934 -326.858884)
		(end 250.92914 -323.47916)
		(width 0.1651)
		(layer "In7.Cu")
		(net "P5E_PEX2_STN7_TX_DN<114>")
	)
	(segment
		(start 274.065238 -303.499774)
		(end 273.799808 -303.499774)
		(width 0.1143)
		(layer "In7.Cu")
		(net "P5E_PEX2_STN7_TX_DN<114>")
	)
	(segment
		(start 271.869662 -354.732082)
		(end 271.578832 -354.441252)
		(width 0.1651)
		(layer "In7.Cu")
		(net "P5E_PEX2_STN7_TX_DN<114>")
	)
	(segment
		(start 271.578832 -354.441252)
		(end 271.578832 -353.930966)
		(width 0.1651)
		(layer "In7.Cu")
		(net "P5E_PEX2_STN7_TX_DN<114>")
	)
	(segment
		(start 253.182374 -312.995818)
		(end 253.282704 -312.956194)
		(width 0.1651)
		(layer "In7.Cu")
		(net "P5E_PEX2_STN7_TX_DN<114>")
	)
	(segment
		(start 270.485362 -338.967318)
		(end 270.456914 -338.863432)
		(width 0.1651)
		(layer "In7.Cu")
		(net "P5E_PEX2_STN7_TX_DN<114>")
	)
	(segment
		(start 256.146046 -307.067458)
		(end 256.47523 -306.696872)
		(width 0.1651)
		(layer "In7.Cu")
		(net "P5E_PEX2_STN7_TX_DN<114>")
	)
	(segment
		(start 254.09398 -310.898794)
		(end 254.093726 -310.898794)
		(width 0.1651)
		(layer "In7.Cu")
		(net "P5E_PEX2_STN7_TX_DN<114>")
	)
	(segment
		(start 257.555492 -305.36515)
		(end 257.88366 -304.99558)
		(width 0.1651)
		(layer "In7.Cu")
		(net "P5E_PEX2_STN7_TX_DN<114>")
	)
	(segment
		(start 253.638304 -311.94756)
		(end 253.63805 -311.947306)
		(width 0.1651)
		(layer "In7.Cu")
		(net "P5E_PEX2_STN7_TX_DN<114>")
	)
	(segment
		(start 269.032736 -338.052156)
		(end 268.92885 -338.080858)
		(width 0.1651)
		(layer "In7.Cu")
		(net "P5E_PEX2_STN7_TX_DN<114>")
	)
	(segment
		(start 267.865352 -303.165764)
		(end 267.8938 -303.165764)
		(width 0.1143)
		(layer "In7.Cu")
		(net "P5E_PEX2_STN7_TX_DN<114>")
	)
	(segment
		(start 254.549656 -309.850282)
		(end 254.549402 -309.850282)
		(width 0.1651)
		(layer "In7.Cu")
		(net "P5E_PEX2_STN7_TX_DN<114>")
	)
	(segment
		(start 270.456914 -338.863432)
		(end 270.02613 -338.618068)
		(width 0.1651)
		(layer "In7.Cu")
		(net "P5E_PEX2_STN7_TX_DN<114>")
	)
	(segment
		(start 257.555746 -305.36515)
		(end 257.555492 -305.36515)
		(width 0.1651)
		(layer "In7.Cu")
		(net "P5E_PEX2_STN7_TX_DN<114>")
	)
	(segment
		(start 257.88366 -304.99558)
		(end 258.757674 -304.397156)
		(width 0.1651)
		(layer "In7.Cu")
		(net "P5E_PEX2_STN7_TX_DN<114>")
	)
	(segment
		(start 254.352298 -310.304434)
		(end 254.549656 -309.850282)
		(width 0.1651)
		(layer "In7.Cu")
		(net "P5E_PEX2_STN7_TX_DN<114>")
	)
	(segment
		(start 270.02613 -338.618068)
		(end 269.922244 -338.646516)
		(width 0.1651)
		(layer "In7.Cu")
		(net "P5E_PEX2_STN7_TX_DN<114>")
	)
	(segment
		(start 254.80772 -309.255922)
		(end 254.807974 -309.255922)
		(width 0.1651)
		(layer "In7.Cu")
		(net "P5E_PEX2_STN7_TX_DN<114>")
	)
	(segment
		(start 268.92885 -338.080858)
		(end 268.498574 -337.836002)
		(width 0.1651)
		(layer "In7.Cu")
		(net "P5E_PEX2_STN7_TX_DN<114>")
	)
	(segment
		(start 273.133312 -352.376486)
		(end 273.133312 -342.271604)
		(width 0.1651)
		(layer "In7.Cu")
		(net "P5E_PEX2_STN7_TX_DN<114>")
	)
	(segment
		(start 257.227832 -305.734466)
		(end 257.555746 -305.36515)
		(width 0.1651)
		(layer "In7.Cu")
		(net "P5E_PEX2_STN7_TX_DN<114>")
	)
	(segment
		(start 274.065238 -303.120044)
		(end 274.179538 -303.234344)
		(width 0.1143)
		(layer "In7.Cu")
		(net "P5E_PEX2_STN7_TX_DN<114>")
	)
	(segment
		(start 253.63805 -311.947306)
		(end 253.73838 -311.907682)
		(width 0.1651)
		(layer "In7.Cu")
		(net "P5E_PEX2_STN7_TX_DN<114>")
	)
	(segment
		(start 254.194056 -310.85917)
		(end 254.391668 -310.404764)
		(width 0.1651)
		(layer "In7.Cu")
		(net "P5E_PEX2_STN7_TX_DN<114>")
	)
	(segment
		(start 254.549402 -309.850282)
		(end 254.649732 -309.810658)
		(width 0.1651)
		(layer "In7.Cu")
		(net "P5E_PEX2_STN7_TX_DN<114>")
	)
	(segment
		(start 269.46352 -338.29752)
		(end 269.032736 -338.052156)
		(width 0.1651)
		(layer "In7.Cu")
		(net "P5E_PEX2_STN7_TX_DN<114>")
	)
	(segment
		(start 253.282704 -312.956194)
		(end 253.480316 -312.501788)
		(width 0.1651)
		(layer "In7.Cu")
		(net "P5E_PEX2_STN7_TX_DN<114>")
	)
	(segment
		(start 256.038604 -307.073808)
		(end 256.146046 -307.067458)
		(width 0.1651)
		(layer "In7.Cu")
		(net "P5E_PEX2_STN7_TX_DN<114>")
	)
	(segment
		(start 254.807974 -309.255922)
		(end 255.005332 -308.80177)
		(width 0.1651)
		(layer "In7.Cu")
		(net "P5E_PEX2_STN7_TX_DN<114>")
	)
	(segment
		(start 255.105408 -308.7624)
		(end 255.30302 -308.30774)
		(width 0.1651)
		(layer "In7.Cu")
		(net "P5E_PEX2_STN7_TX_DN<114>")
	)
	(segment
		(start 274.179538 -303.385474)
		(end 274.065238 -303.499774)
		(width 0.1143)
		(layer "In7.Cu")
		(net "P5E_PEX2_STN7_TX_DN<114>")
	)
	(segment
		(start 254.649732 -309.810658)
		(end 254.847344 -309.356252)
		(width 0.1651)
		(layer "In7.Cu")
		(net "P5E_PEX2_STN7_TX_DN<114>")
	)
	(segment
		(start 267.93952 -303.120044)
		(end 274.065238 -303.120044)
		(width 0.1143)
		(layer "In7.Cu")
		(net "P5E_PEX2_STN7_TX_DN<114>")
	)
	(segment
		(start 254.391668 -310.404764)
		(end 254.352044 -310.304434)
		(width 0.1651)
		(layer "In7.Cu")
		(net "P5E_PEX2_STN7_TX_DN<114>")
	)
	(segment
		(start 259.991098 -303.821338)
		(end 266.646406 -303.165764)
		(width 0.1651)
		(layer "In7.Cu")
		(net "P5E_PEX2_STN7_TX_DN<114>")
	)
	(segment
		(start 269.491968 -338.40166)
		(end 269.46352 -338.29752)
		(width 0.1651)
		(layer "In7.Cu")
		(net "P5E_PEX2_STN7_TX_DN<114>")
	)
	(segment
		(start 255.30302 -308.30774)
		(end 255.26365 -308.20741)
		(width 0.1651)
		(layer "In7.Cu")
		(net "P5E_PEX2_STN7_TX_DN<114>")
	)
	(segment
		(start 268.470126 -337.731862)
		(end 268.039342 -337.486498)
		(width 0.1651)
		(layer "In7.Cu")
		(net "P5E_PEX2_STN7_TX_DN<114>")
	)
	(segment
		(start 272.645886 -341.02675)
		(end 271.02562 -339.274912)
		(width 0.1651)
		(layer "In7.Cu")
		(net "P5E_PEX2_STN7_TX_DN<114>")
	)
	(segment
		(start 255.485392 -307.69687)
		(end 256.038604 -307.073808)
		(width 0.1651)
		(layer "In7.Cu")
		(net "P5E_PEX2_STN7_TX_DN<114>")
	)
	(segment
		(start 253.935992 -311.453276)
		(end 253.896368 -311.352946)
		(width 0.1651)
		(layer "In7.Cu")
		(net "P5E_PEX2_STN7_TX_DN<114>")
	)
	(segment
		(start 269.922244 -338.646516)
		(end 269.491968 -338.40166)
		(width 0.1651)
		(layer "In7.Cu")
		(net "P5E_PEX2_STN7_TX_DN<114>")
	)
	(segment
		(start 250.92914 -323.47916)
		(end 250.92914 -318.181482)
		(width 0.1651)
		(layer "In7.Cu")
		(net "P5E_PEX2_STN7_TX_DN<114>")
	)
	(segment
		(start 253.440692 -312.401458)
		(end 253.440946 -312.401458)
		(width 0.1651)
		(layer "In7.Cu")
		(net "P5E_PEX2_STN7_TX_DN<114>")
	)
	(segment
		(start 258.757674 -304.397156)
		(end 259.991098 -303.821338)
		(width 0.1651)
		(layer "In7.Cu")
		(net "P5E_PEX2_STN7_TX_DN<114>")
	)
	(segment
		(start 255.46558 -330.414122)
		(end 252.328934 -326.858884)
		(width 0.1651)
		(layer "In7.Cu")
		(net "P5E_PEX2_STN7_TX_DN<114>")
	)
	(segment
		(start 268.498574 -337.836002)
		(end 268.470126 -337.731862)
		(width 0.1651)
		(layer "In7.Cu")
		(net "P5E_PEX2_STN7_TX_DN<114>")
	)
	(segment
		(start 267.8938 -303.165764)
		(end 267.93952 -303.120044)
		(width 0.1143)
		(layer "In7.Cu")
		(net "P5E_PEX2_STN7_TX_DN<114>")
	)
	(segment
		(start 253.440946 -312.401458)
		(end 253.638304 -311.94756)
		(width 0.1651)
		(layer "In7.Cu")
		(net "P5E_PEX2_STN7_TX_DN<114>")
	)
	(segment
		(start 253.73838 -311.907682)
		(end 253.935992 -311.453276)
		(width 0.1651)
		(layer "In7.Cu")
		(net "P5E_PEX2_STN7_TX_DN<114>")
	)
	(segment
		(start 255.005332 -308.80177)
		(end 255.005078 -308.80177)
		(width 0.1651)
		(layer "In7.Cu")
		(net "P5E_PEX2_STN7_TX_DN<114>")
	)
	(segment
		(start 254.093726 -310.898794)
		(end 254.194056 -310.85917)
		(width 0.1651)
		(layer "In7.Cu")
		(net "P5E_PEX2_STN7_TX_DN<114>")
	)
	(segment
		(start 282.13431 -178.378358)
		(end 282.889198 -178.378358)
		(width 0.13208)
		(layer "F.Cu")
		(net "HP_NIC4_HSC_PWRGD_N")
	)
	(segment
		(start 283.539184 -179.175156)
		(end 283.19857 -179.51577)
		(width 0.13208)
		(layer "F.Cu")
		(net "HP_NIC4_HSC_PWRGD_N")
	)
	(segment
		(start 281.714702 -180.049678)
		(end 281.714702 -179.552854)
		(width 0.13208)
		(layer "F.Cu")
		(net "HP_NIC4_HSC_PWRGD_N")
	)
	(segment
		(start 281.714702 -178.797966)
		(end 282.13431 -178.378358)
		(width 0.13208)
		(layer "F.Cu")
		(net "HP_NIC4_HSC_PWRGD_N")
	)
	(segment
		(start 283.19857 -179.51577)
		(end 283.19857 -180.372766)
		(width 0.13208)
		(layer "F.Cu")
		(net "HP_NIC4_HSC_PWRGD_N")
	)
	(segment
		(start 281.714702 -179.552854)
		(end 281.714702 -178.797966)
		(width 0.13208)
		(layer "F.Cu")
		(net "HP_NIC4_HSC_PWRGD_N")
	)
	(segment
		(start 282.03779 -180.372766)
		(end 281.714702 -180.049678)
		(width 0.13208)
		(layer "F.Cu")
		(net "HP_NIC4_HSC_PWRGD_N")
	)
	(segment
		(start 283.539184 -178.378358)
		(end 283.539184 -179.175156)
		(width 0.13208)
		(layer "F.Cu")
		(net "HP_NIC4_HSC_PWRGD_N")
	)
	(segment
		(start 283.19857 -180.372766)
		(end 282.03779 -180.372766)
		(width 0.13208)
		(layer "F.Cu")
		(net "HP_NIC4_HSC_PWRGD_N")
	)
	(via
		(at 281.714702 -179.552854)
		(size 0.762)
		(drill 0.381)
		(layers "F.Cu" "B.Cu")
		(net "HP_NIC4_HSC_PWRGD_N")
	)
	(segment
		(start 77.715364 -88.956642)
		(end 74.014584 -88.956642)
		(width 0.13208)
		(layer "F.Cu")
		(net "RST_HP_NIC1_BUF_N")
	)
	(segment
		(start 81.639664 -86.949026)
		(end 80.623664 -86.949026)
		(width 0.13208)
		(layer "F.Cu")
		(net "RST_HP_NIC1_BUF_N")
	)
	(segment
		(start 78.075536 -87.837518)
		(end 78.075536 -88.59647)
		(width 0.13208)
		(layer "F.Cu")
		(net "RST_HP_NIC1_BUF_N")
	)
	(segment
		(start 58.595006 -96.702372)
		(end 58.595006 -94.762574)
		(width 0.13208)
		(layer "F.Cu")
		(net "RST_HP_NIC1_BUF_N")
	)
	(segment
		(start 64.805814 -94.1578)
		(end 70.006972 -88.956642)
		(width 0.13208)
		(layer "F.Cu")
		(net "RST_HP_NIC1_BUF_N")
	)
	(segment
		(start 80.623664 -86.949026)
		(end 79.234538 -86.949026)
		(width 0.13208)
		(layer "F.Cu")
		(net "RST_HP_NIC1_BUF_N")
	)
	(segment
		(start 79.234538 -86.949026)
		(end 78.964028 -86.949026)
		(width 0.13208)
		(layer "F.Cu")
		(net "RST_HP_NIC1_BUF_N")
	)
	(segment
		(start 78.075536 -88.59647)
		(end 77.715364 -88.956642)
		(width 0.13208)
		(layer "F.Cu")
		(net "RST_HP_NIC1_BUF_N")
	)
	(segment
		(start 59.19978 -94.1578)
		(end 64.805814 -94.1578)
		(width 0.13208)
		(layer "F.Cu")
		(net "RST_HP_NIC1_BUF_N")
	)
	(segment
		(start 70.006972 -88.956642)
		(end 74.014584 -88.956642)
		(width 0.13208)
		(layer "F.Cu")
		(net "RST_HP_NIC1_BUF_N")
	)
	(segment
		(start 58.595006 -94.762574)
		(end 59.19978 -94.1578)
		(width 0.13208)
		(layer "F.Cu")
		(net "RST_HP_NIC1_BUF_N")
	)
	(segment
		(start 78.964028 -86.949026)
		(end 78.075536 -87.837518)
		(width 0.13208)
		(layer "F.Cu")
		(net "RST_HP_NIC1_BUF_N")
	)
	(segment
		(start 58.595006 -97.718372)
		(end 58.595006 -96.702372)
		(width 0.13208)
		(layer "F.Cu")
		(net "RST_HP_NIC1_BUF_N")
	)
	(via
		(at 74.014584 -88.956642)
		(size 0.508)
		(drill 0.254)
		(layers "F.Cu" "B.Cu")
		(net "RST_HP_NIC1_BUF_N")
	)
	(segment
		(start 193.570352 -345.170506)
		(end 193.570352 -344.539062)
		(width 0.13462)
		(layer "F.Cu")
		(net "P5E_PEX1_STN7_TX_C_DP<127>")
	)
	(segment
		(start 193.275712 -345.465146)
		(end 193.570352 -345.170506)
		(width 0.13462)
		(layer "F.Cu")
		(net "P5E_PEX1_STN7_TX_C_DP<127>")
	)
	(segment
		(start 193.570352 -344.539062)
		(end 193.250312 -344.219022)
		(width 0.13462)
		(layer "F.Cu")
		(net "P5E_PEX1_STN7_TX_C_DP<127>")
	)
	(segment
		(start 192.012062 -347.970094)
		(end 192.012062 -357.768144)
		(width 0.1651)
		(layer "In11.Cu")
		(net "P5E_PEX1_STN7_TX_C_DP<127>")
	)
	(segment
		(start 192.012062 -357.768144)
		(end 186.297062 -363.483144)
		(width 0.1651)
		(layer "In11.Cu")
		(net "P5E_PEX1_STN7_TX_C_DP<127>")
	)
	(segment
		(start 176.96053 -368.14887)
		(end 176.185576 -368.923824)
		(width 0.1651)
		(layer "In11.Cu")
		(net "P5E_PEX1_STN7_TX_C_DP<127>")
	)
	(segment
		(start 186.297062 -363.483144)
		(end 186.135264 -363.483144)
		(width 0.1651)
		(layer "In11.Cu")
		(net "P5E_PEX1_STN7_TX_C_DP<127>")
	)
	(segment
		(start 185.784744 -363.995462)
		(end 185.010806 -364.7694)
		(width 0.1651)
		(layer "In11.Cu")
		(net "P5E_PEX1_STN7_TX_C_DP<127>")
	)
	(segment
		(start 175.658526 -375.999248)
		(end 175.437038 -375.999248)
		(width 0.1651)
		(layer "In11.Cu")
		(net "P5E_PEX1_STN7_TX_C_DP<127>")
	)
	(segment
		(start 193.566542 -346.415614)
		(end 192.012062 -347.970094)
		(width 0.1651)
		(layer "In11.Cu")
		(net "P5E_PEX1_STN7_TX_C_DP<127>")
	)
	(segment
		(start 185.010806 -364.7694)
		(end 176.96053 -368.14887)
		(width 0.1651)
		(layer "In11.Cu")
		(net "P5E_PEX1_STN7_TX_C_DP<127>")
	)
	(segment
		(start 186.135264 -363.483144)
		(end 185.784744 -363.833664)
		(width 0.1651)
		(layer "In11.Cu")
		(net "P5E_PEX1_STN7_TX_C_DP<127>")
	)
	(segment
		(start 175.437038 -375.999248)
		(end 175.310038 -375.872248)
		(width 0.1651)
		(layer "In11.Cu")
		(net "P5E_PEX1_STN7_TX_C_DP<127>")
	)
	(segment
		(start 175.310038 -375.872248)
		(end 175.310038 -375.490232)
		(width 0.1651)
		(layer "In11.Cu")
		(net "P5E_PEX1_STN7_TX_C_DP<127>")
	)
	(segment
		(start 176.185576 -375.472198)
		(end 175.658526 -375.999248)
		(width 0.1651)
		(layer "In11.Cu")
		(net "P5E_PEX1_STN7_TX_C_DP<127>")
	)
	(segment
		(start 185.784744 -363.833664)
		(end 185.784744 -363.995462)
		(width 0.1651)
		(layer "In11.Cu")
		(net "P5E_PEX1_STN7_TX_C_DP<127>")
	)
	(segment
		(start 193.566542 -345.755976)
		(end 193.566542 -346.415614)
		(width 0.1651)
		(layer "In11.Cu")
		(net "P5E_PEX1_STN7_TX_C_DP<127>")
	)
	(segment
		(start 193.275712 -345.465146)
		(end 193.566542 -345.755976)
		(width 0.1651)
		(layer "In11.Cu")
		(net "P5E_PEX1_STN7_TX_C_DP<127>")
	)
	(segment
		(start 176.185576 -368.923824)
		(end 176.185576 -375.472198)
		(width 0.1651)
		(layer "In11.Cu")
		(net "P5E_PEX1_STN7_TX_C_DP<127>")
	)
	(segment
		(start 152.151588 -105.289858)
		(end 151.520144 -105.289858)
		(width 0.13462)
		(layer "F.Cu")
		(net "P5E_PEX1_STN1_TX_DP<19>")
	)
	(segment
		(start 152.471628 -105.609898)
		(end 152.151588 -105.289858)
		(width 0.13462)
		(layer "F.Cu")
		(net "P5E_PEX1_STN1_TX_DP<19>")
	)
	(segment
		(start 151.520144 -105.289858)
		(end 151.225504 -105.584498)
		(width 0.13462)
		(layer "F.Cu")
		(net "P5E_PEX1_STN1_TX_DP<19>")
	)
	(segment
		(start 139.49045 -138.417046)
		(end 142.050262 -144.596358)
		(width 0.1651)
		(layer "In9.Cu")
		(net "P5E_PEX1_STN1_TX_DP<19>")
	)
	(segment
		(start 143.364966 -162.189414)
		(end 178.265836 -265.298682)
		(width 0.1651)
		(layer "In9.Cu")
		(net "P5E_PEX1_STN1_TX_DP<19>")
	)
	(segment
		(start 151.225504 -105.584498)
		(end 150.934674 -105.293668)
		(width 0.1651)
		(layer "In9.Cu")
		(net "P5E_PEX1_STN1_TX_DP<19>")
	)
	(segment
		(start 178.485546 -280.129488)
		(end 178.599846 -280.015188)
		(width 0.1143)
		(layer "In9.Cu")
		(net "P5E_PEX1_STN1_TX_DP<19>")
	)
	(segment
		(start 178.220116 -271.600168)
		(end 178.220116 -280.025856)
		(width 0.1143)
		(layer "In9.Cu")
		(net "P5E_PEX1_STN1_TX_DP<19>")
	)
	(segment
		(start 146.906488 -109.436662)
		(end 146.756882 -109.498384)
		(width 0.1651)
		(layer "In9.Cu")
		(net "P5E_PEX1_STN1_TX_DP<19>")
	)
	(segment
		(start 148.048218 -107.796838)
		(end 147.88642 -107.796838)
		(width 0.1651)
		(layer "In9.Cu")
		(net "P5E_PEX1_STN1_TX_DP<19>")
	)
	(segment
		(start 178.265836 -265.298682)
		(end 178.265836 -271.526)
		(width 0.1651)
		(layer "In9.Cu")
		(net "P5E_PEX1_STN1_TX_DP<19>")
	)
	(segment
		(start 148.74875 -106.934508)
		(end 148.398738 -107.28452)
		(width 0.1651)
		(layer "In9.Cu")
		(net "P5E_PEX1_STN1_TX_DP<19>")
	)
	(segment
		(start 178.265836 -271.526)
		(end 178.265836 -271.554448)
		(width 0.1143)
		(layer "In9.Cu")
		(net "P5E_PEX1_STN1_TX_DP<19>")
	)
	(segment
		(start 145.22958 -113.484914)
		(end 145.040096 -113.942876)
		(width 0.1651)
		(layer "In9.Cu")
		(net "P5E_PEX1_STN1_TX_DP<19>")
	)
	(segment
		(start 144.701006 -114.462052)
		(end 144.738598 -114.552476)
		(width 0.1651)
		(layer "In9.Cu")
		(net "P5E_PEX1_STN1_TX_DP<19>")
	)
	(segment
		(start 144.092168 -115.932712)
		(end 139.49045 -131.101338)
		(width 0.1651)
		(layer "In9.Cu")
		(net "P5E_PEX1_STN1_TX_DP<19>")
	)
	(segment
		(start 150.38959 -105.293668)
		(end 150.024338 -105.65892)
		(width 0.1651)
		(layer "In9.Cu")
		(net "P5E_PEX1_STN1_TX_DP<19>")
	)
	(segment
		(start 144.424146 -115.131342)
		(end 144.092168 -115.932712)
		(width 0.1651)
		(layer "In9.Cu")
		(net "P5E_PEX1_STN1_TX_DP<19>")
	)
	(segment
		(start 150.934674 -105.293668)
		(end 150.38959 -105.293668)
		(width 0.1651)
		(layer "In9.Cu")
		(net "P5E_PEX1_STN1_TX_DP<19>")
	)
	(segment
		(start 145.634202 -112.209072)
		(end 145.696178 -112.358424)
		(width 0.1651)
		(layer "In9.Cu")
		(net "P5E_PEX1_STN1_TX_DP<19>")
	)
	(segment
		(start 147.88642 -107.796838)
		(end 147.16125 -108.522008)
		(width 0.1651)
		(layer "In9.Cu")
		(net "P5E_PEX1_STN1_TX_DP<19>")
	)
	(segment
		(start 148.874226 -106.934508)
		(end 148.74875 -106.934508)
		(width 0.1651)
		(layer "In9.Cu")
		(net "P5E_PEX1_STN1_TX_DP<19>")
	)
	(segment
		(start 145.823686 -111.751618)
		(end 145.634202 -112.209072)
		(width 0.1651)
		(layer "In9.Cu")
		(net "P5E_PEX1_STN1_TX_DP<19>")
	)
	(segment
		(start 150.024338 -105.78465)
		(end 149.682708 -106.12628)
		(width 0.1651)
		(layer "In9.Cu")
		(net "P5E_PEX1_STN1_TX_DP<19>")
	)
	(segment
		(start 146.756882 -109.498384)
		(end 146.567398 -109.955838)
		(width 0.1651)
		(layer "In9.Cu")
		(net "P5E_PEX1_STN1_TX_DP<19>")
	)
	(segment
		(start 144.423892 -115.131088)
		(end 144.424146 -115.131342)
		(width 0.1651)
		(layer "In9.Cu")
		(net "P5E_PEX1_STN1_TX_DP<19>")
	)
	(segment
		(start 147.095972 -108.9787)
		(end 146.906488 -109.436662)
		(width 0.1651)
		(layer "In9.Cu")
		(net "P5E_PEX1_STN1_TX_DP<19>")
	)
	(segment
		(start 144.890744 -114.004598)
		(end 144.70126 -114.462052)
		(width 0.1651)
		(layer "In9.Cu")
		(net "P5E_PEX1_STN1_TX_DP<19>")
	)
	(segment
		(start 146.567398 -109.955838)
		(end 146.629374 -110.10519)
		(width 0.1651)
		(layer "In9.Cu")
		(net "P5E_PEX1_STN1_TX_DP<19>")
	)
	(segment
		(start 146.629374 -110.10519)
		(end 146.43989 -110.563152)
		(width 0.1651)
		(layer "In9.Cu")
		(net "P5E_PEX1_STN1_TX_DP<19>")
	)
	(segment
		(start 142.766034 -159.178498)
		(end 143.364966 -162.189414)
		(width 0.1651)
		(layer "In9.Cu")
		(net "P5E_PEX1_STN1_TX_DP<19>")
	)
	(segment
		(start 144.51457 -115.09375)
		(end 144.423892 -115.131088)
		(width 0.1651)
		(layer "In9.Cu")
		(net "P5E_PEX1_STN1_TX_DP<19>")
	)
	(segment
		(start 147.033996 -108.829348)
		(end 147.095972 -108.9787)
		(width 0.1651)
		(layer "In9.Cu")
		(net "P5E_PEX1_STN1_TX_DP<19>")
	)
	(segment
		(start 145.973292 -111.689896)
		(end 145.823686 -111.751618)
		(width 0.1651)
		(layer "In9.Cu")
		(net "P5E_PEX1_STN1_TX_DP<19>")
	)
	(segment
		(start 148.398738 -107.28452)
		(end 148.398738 -107.446318)
		(width 0.1651)
		(layer "In9.Cu")
		(net "P5E_PEX1_STN1_TX_DP<19>")
	)
	(segment
		(start 146.162776 -111.231934)
		(end 145.973292 -111.689896)
		(width 0.1651)
		(layer "In9.Cu")
		(net "P5E_PEX1_STN1_TX_DP<19>")
	)
	(segment
		(start 178.323748 -280.129488)
		(end 178.485546 -280.129488)
		(width 0.1143)
		(layer "In9.Cu")
		(net "P5E_PEX1_STN1_TX_DP<19>")
	)
	(segment
		(start 145.040096 -113.942876)
		(end 144.89049 -114.004598)
		(width 0.1651)
		(layer "In9.Cu")
		(net "P5E_PEX1_STN1_TX_DP<19>")
	)
	(segment
		(start 142.050262 -144.596358)
		(end 142.766034 -159.178498)
		(width 0.1651)
		(layer "In9.Cu")
		(net "P5E_PEX1_STN1_TX_DP<19>")
	)
	(segment
		(start 144.70126 -114.462052)
		(end 144.701006 -114.462052)
		(width 0.1651)
		(layer "In9.Cu")
		(net "P5E_PEX1_STN1_TX_DP<19>")
	)
	(segment
		(start 146.290284 -110.624874)
		(end 146.290284 -110.625128)
		(width 0.1651)
		(layer "In9.Cu")
		(net "P5E_PEX1_STN1_TX_DP<19>")
	)
	(segment
		(start 147.066 -108.752386)
		(end 147.033996 -108.829348)
		(width 0.1651)
		(layer "In9.Cu")
		(net "P5E_PEX1_STN1_TX_DP<19>")
	)
	(segment
		(start 148.398738 -107.446318)
		(end 148.048218 -107.796838)
		(width 0.1651)
		(layer "In9.Cu")
		(net "P5E_PEX1_STN1_TX_DP<19>")
	)
	(segment
		(start 149.215856 -106.467402)
		(end 149.215856 -106.593132)
		(width 0.1651)
		(layer "In9.Cu")
		(net "P5E_PEX1_STN1_TX_DP<19>")
	)
	(segment
		(start 145.506694 -112.816386)
		(end 145.357088 -112.878108)
		(width 0.1651)
		(layer "In9.Cu")
		(net "P5E_PEX1_STN1_TX_DP<19>")
	)
	(segment
		(start 178.599846 -280.015188)
		(end 178.599846 -279.749504)
		(width 0.1143)
		(layer "In9.Cu")
		(net "P5E_PEX1_STN1_TX_DP<19>")
	)
	(segment
		(start 149.682708 -106.12628)
		(end 149.556978 -106.12628)
		(width 0.1651)
		(layer "In9.Cu")
		(net "P5E_PEX1_STN1_TX_DP<19>")
	)
	(segment
		(start 150.024338 -105.65892)
		(end 150.024338 -105.78465)
		(width 0.1651)
		(layer "In9.Cu")
		(net "P5E_PEX1_STN1_TX_DP<19>")
	)
	(segment
		(start 178.220116 -280.025856)
		(end 178.323748 -280.129488)
		(width 0.1143)
		(layer "In9.Cu")
		(net "P5E_PEX1_STN1_TX_DP<19>")
	)
	(segment
		(start 139.49045 -131.101338)
		(end 139.49045 -138.417046)
		(width 0.1651)
		(layer "In9.Cu")
		(net "P5E_PEX1_STN1_TX_DP<19>")
	)
	(segment
		(start 149.215856 -106.593132)
		(end 148.874226 -106.934508)
		(width 0.1651)
		(layer "In9.Cu")
		(net "P5E_PEX1_STN1_TX_DP<19>")
	)
	(segment
		(start 149.556978 -106.12628)
		(end 149.215856 -106.467402)
		(width 0.1651)
		(layer "In9.Cu")
		(net "P5E_PEX1_STN1_TX_DP<19>")
	)
	(segment
		(start 147.16125 -108.522008)
		(end 147.066 -108.752132)
		(width 0.1651)
		(layer "In9.Cu")
		(net "P5E_PEX1_STN1_TX_DP<19>")
	)
	(segment
		(start 145.357088 -112.878108)
		(end 145.167604 -113.335562)
		(width 0.1651)
		(layer "In9.Cu")
		(net "P5E_PEX1_STN1_TX_DP<19>")
	)
	(segment
		(start 146.43989 -110.563152)
		(end 146.290284 -110.624874)
		(width 0.1651)
		(layer "In9.Cu")
		(net "P5E_PEX1_STN1_TX_DP<19>")
	)
	(segment
		(start 144.89049 -114.004598)
		(end 144.890744 -114.004598)
		(width 0.1651)
		(layer "In9.Cu")
		(net "P5E_PEX1_STN1_TX_DP<19>")
	)
	(segment
		(start 146.1008 -111.082582)
		(end 146.162776 -111.231934)
		(width 0.1651)
		(layer "In9.Cu")
		(net "P5E_PEX1_STN1_TX_DP<19>")
	)
	(segment
		(start 144.738598 -114.552476)
		(end 144.51457 -115.09375)
		(width 0.1651)
		(layer "In9.Cu")
		(net "P5E_PEX1_STN1_TX_DP<19>")
	)
	(segment
		(start 145.696178 -112.358424)
		(end 145.506694 -112.816386)
		(width 0.1651)
		(layer "In9.Cu")
		(net "P5E_PEX1_STN1_TX_DP<19>")
	)
	(segment
		(start 145.167604 -113.335562)
		(end 145.22958 -113.484914)
		(width 0.1651)
		(layer "In9.Cu")
		(net "P5E_PEX1_STN1_TX_DP<19>")
	)
	(segment
		(start 178.265836 -271.554448)
		(end 178.220116 -271.600168)
		(width 0.1143)
		(layer "In9.Cu")
		(net "P5E_PEX1_STN1_TX_DP<19>")
	)
	(segment
		(start 146.290284 -110.625128)
		(end 146.1008 -111.082582)
		(width 0.1651)
		(layer "In9.Cu")
		(net "P5E_PEX1_STN1_TX_DP<19>")
	)
	(segment
		(start 147.066 -108.752132)
		(end 147.066 -108.752386)
		(width 0.1651)
		(layer "In9.Cu")
		(net "P5E_PEX1_STN1_TX_DP<19>")
	)
	(segment
		(start 178.025552 -349.511874)
		(end 178.025552 -348.88043)
		(width 0.13462)
		(layer "F.Cu")
		(net "P5E_PEX1_STN7_TX_DP<120>")
	)
	(segment
		(start 177.705512 -349.831914)
		(end 178.025552 -349.511874)
		(width 0.13462)
		(layer "F.Cu")
		(net "P5E_PEX1_STN7_TX_DP<120>")
	)
	(segment
		(start 178.025552 -348.88043)
		(end 177.730912 -348.58579)
		(width 0.13462)
		(layer "F.Cu")
		(net "P5E_PEX1_STN7_TX_DP<120>")
	)
	(segment
		(start 144.719802 -314.219082)
		(end 145.901918 -313.429142)
		(width 0.1651)
		(layer "In11.Cu")
		(net "P5E_PEX1_STN7_TX_DP<120>")
	)
	(segment
		(start 151.664924 -308.583838)
		(end 151.687022 -308.583838)
		(width 0.1143)
		(layer "In11.Cu")
		(net "P5E_PEX1_STN7_TX_DP<120>")
	)
	(segment
		(start 158.270194 -309.110888)
		(end 158.359094 -309.199788)
		(width 0.1143)
		(layer "In11.Cu")
		(net "P5E_PEX1_STN7_TX_DP<120>")
	)
	(segment
		(start 158.270194 -308.88686)
		(end 158.270194 -309.110888)
		(width 0.1143)
		(layer "In11.Cu")
		(net "P5E_PEX1_STN7_TX_DP<120>")
	)
	(segment
		(start 158.359094 -309.199788)
		(end 158.649924 -309.199788)
		(width 0.1143)
		(layer "In11.Cu")
		(net "P5E_PEX1_STN7_TX_DP<120>")
	)
	(segment
		(start 151.687022 -308.583838)
		(end 151.732742 -308.629558)
		(width 0.1143)
		(layer "In11.Cu")
		(net "P5E_PEX1_STN7_TX_DP<120>")
	)
	(segment
		(start 142.771622 -325.527416)
		(end 141.546834 -324.47738)
		(width 0.1651)
		(layer "In11.Cu")
		(net "P5E_PEX1_STN7_TX_DP<120>")
	)
	(segment
		(start 141.546834 -324.47738)
		(end 140.764768 -323.307456)
		(width 0.1651)
		(layer "In11.Cu")
		(net "P5E_PEX1_STN7_TX_DP<120>")
	)
	(segment
		(start 178.021742 -348.29496)
		(end 178.021742 -347.579696)
		(width 0.1651)
		(layer "In11.Cu")
		(net "P5E_PEX1_STN7_TX_DP<120>")
	)
	(segment
		(start 140.764768 -323.307456)
		(end 140.292074 -321.748658)
		(width 0.1651)
		(layer "In11.Cu")
		(net "P5E_PEX1_STN7_TX_DP<120>")
	)
	(segment
		(start 178.021742 -347.579696)
		(end 179.576222 -346.025216)
		(width 0.1651)
		(layer "In11.Cu")
		(net "P5E_PEX1_STN7_TX_DP<120>")
	)
	(segment
		(start 143.873728 -326.241918)
		(end 142.771622 -325.527416)
		(width 0.1651)
		(layer "In11.Cu")
		(net "P5E_PEX1_STN7_TX_DP<120>")
	)
	(segment
		(start 140.292074 -321.748658)
		(end 140.292074 -320.349372)
		(width 0.1651)
		(layer "In11.Cu")
		(net "P5E_PEX1_STN7_TX_DP<120>")
	)
	(segment
		(start 177.730912 -348.58579)
		(end 178.021742 -348.29496)
		(width 0.1651)
		(layer "In11.Cu")
		(net "P5E_PEX1_STN7_TX_DP<120>")
	)
	(segment
		(start 151.732742 -308.629558)
		(end 158.012892 -308.629558)
		(width 0.1143)
		(layer "In11.Cu")
		(net "P5E_PEX1_STN7_TX_DP<120>")
	)
	(segment
		(start 178.605942 -340.713314)
		(end 168.108122 -335.733898)
		(width 0.1651)
		(layer "In11.Cu")
		(net "P5E_PEX1_STN7_TX_DP<120>")
	)
	(segment
		(start 179.576222 -346.025216)
		(end 179.576222 -342.004142)
		(width 0.1651)
		(layer "In11.Cu")
		(net "P5E_PEX1_STN7_TX_DP<120>")
	)
	(segment
		(start 150.747222 -308.583838)
		(end 151.664924 -308.583838)
		(width 0.1651)
		(layer "In11.Cu")
		(net "P5E_PEX1_STN7_TX_DP<120>")
	)
	(segment
		(start 168.108122 -335.733898)
		(end 149.783546 -328.939906)
		(width 0.1651)
		(layer "In11.Cu")
		(net "P5E_PEX1_STN7_TX_DP<120>")
	)
	(segment
		(start 179.576222 -342.004142)
		(end 178.605942 -340.713314)
		(width 0.1651)
		(layer "In11.Cu")
		(net "P5E_PEX1_STN7_TX_DP<120>")
	)
	(segment
		(start 145.901918 -313.429142)
		(end 150.747222 -308.583838)
		(width 0.1651)
		(layer "In11.Cu")
		(net "P5E_PEX1_STN7_TX_DP<120>")
	)
	(segment
		(start 149.783546 -328.939906)
		(end 143.873728 -326.241918)
		(width 0.1651)
		(layer "In11.Cu")
		(net "P5E_PEX1_STN7_TX_DP<120>")
	)
	(segment
		(start 140.292074 -320.349372)
		(end 141.49705 -317.441834)
		(width 0.1651)
		(layer "In11.Cu")
		(net "P5E_PEX1_STN7_TX_DP<120>")
	)
	(segment
		(start 141.49705 -317.441834)
		(end 144.719802 -314.219082)
		(width 0.1651)
		(layer "In11.Cu")
		(net "P5E_PEX1_STN7_TX_DP<120>")
	)
	(segment
		(start 158.012892 -308.629558)
		(end 158.270194 -308.88686)
		(width 0.1143)
		(layer "In11.Cu")
		(net "P5E_PEX1_STN7_TX_DP<120>")
	)
	(segment
		(start 267.325602 -123.68784)
		(end 267.620242 -123.3932)
		(width 0.13462)
		(layer "F.Cu")
		(net "P5E_PEX2_STN1_TX_DN<26>")
	)
	(segment
		(start 267.620242 -123.3932)
		(end 268.251686 -123.3932)
		(width 0.13462)
		(layer "F.Cu")
		(net "P5E_PEX2_STN1_TX_DN<26>")
	)
	(segment
		(start 268.251686 -123.3932)
		(end 268.571726 -123.71324)
		(width 0.13462)
		(layer "F.Cu")
		(net "P5E_PEX2_STN1_TX_DN<26>")
	)
	(segment
		(start 301.015908 -271.471898)
		(end 301.015908 -271.500346)
		(width 0.1143)
		(layer "In9.Cu")
		(net "P5E_PEX2_STN1_TX_DN<26>")
	)
	(segment
		(start 266.149328 -159.960564)
		(end 266.069318 -160.079944)
		(width 0.1651)
		(layer "In9.Cu")
		(net "P5E_PEX2_STN1_TX_DN<26>")
	)
	(segment
		(start 264.155428 -128.772412)
		(end 263.97077 -129.218436)
		(width 0.1651)
		(layer "In9.Cu")
		(net "P5E_PEX2_STN1_TX_DN<26>")
	)
	(segment
		(start 262.598916 -132.232146)
		(end 262.364474 -132.797296)
		(width 0.1651)
		(layer "In9.Cu")
		(net "P5E_PEX2_STN1_TX_DN<26>")
	)
	(segment
		(start 263.513824 -130.321558)
		(end 263.364218 -130.383534)
		(width 0.1651)
		(layer "In9.Cu")
		(net "P5E_PEX2_STN1_TX_DN<26>")
	)
	(segment
		(start 266.398502 -123.39701)
		(end 266.158726 -123.636786)
		(width 0.1651)
		(layer "In9.Cu")
		(net "P5E_PEX2_STN1_TX_DN<26>")
	)
	(segment
		(start 265.983212 -124.35967)
		(end 265.798554 -124.805694)
		(width 0.1651)
		(layer "In9.Cu")
		(net "P5E_PEX2_STN1_TX_DN<26>")
	)
	(segment
		(start 263.364218 -130.383534)
		(end 263.364218 -130.383788)
		(width 0.1651)
		(layer "In9.Cu")
		(net "P5E_PEX2_STN1_TX_DN<26>")
	)
	(segment
		(start 265.648948 -124.86767)
		(end 265.46429 -125.31344)
		(width 0.1651)
		(layer "In9.Cu")
		(net "P5E_PEX2_STN1_TX_DN<26>")
	)
	(segment
		(start 264.884662 -127.011938)
		(end 264.735056 -127.073914)
		(width 0.1651)
		(layer "In9.Cu")
		(net "P5E_PEX2_STN1_TX_DN<26>")
	)
	(segment
		(start 265.192002 -125.970792)
		(end 265.007344 -126.416562)
		(width 0.1651)
		(layer "In9.Cu")
		(net "P5E_PEX2_STN1_TX_DN<26>")
	)
	(segment
		(start 264.427716 -128.115314)
		(end 264.27811 -128.17729)
		(width 0.1651)
		(layer "In9.Cu")
		(net "P5E_PEX2_STN1_TX_DN<26>")
	)
	(segment
		(start 263.821164 -129.280412)
		(end 263.636506 -129.726182)
		(width 0.1651)
		(layer "In9.Cu")
		(net "P5E_PEX2_STN1_TX_DN<26>")
	)
	(segment
		(start 266.069318 -160.079944)
		(end 266.306554 -161.272474)
		(width 0.1651)
		(layer "In9.Cu")
		(net "P5E_PEX2_STN1_TX_DN<26>")
	)
	(segment
		(start 264.550398 -127.519938)
		(end 264.612374 -127.66929)
		(width 0.1651)
		(layer "In9.Cu")
		(net "P5E_PEX2_STN1_TX_DN<26>")
	)
	(segment
		(start 264.27811 -128.17729)
		(end 264.093452 -128.62306)
		(width 0.1651)
		(layer "In9.Cu")
		(net "P5E_PEX2_STN1_TX_DN<26>")
	)
	(segment
		(start 262.364474 -132.797296)
		(end 262.364474 -136.961118)
		(width 0.1651)
		(layer "In9.Cu")
		(net "P5E_PEX2_STN1_TX_DN<26>")
	)
	(segment
		(start 301.015908 -263.80948)
		(end 301.015908 -271.471898)
		(width 0.1651)
		(layer "In9.Cu")
		(net "P5E_PEX2_STN1_TX_DN<26>")
	)
	(segment
		(start 267.325602 -123.68784)
		(end 267.034772 -123.39701)
		(width 0.1651)
		(layer "In9.Cu")
		(net "P5E_PEX2_STN1_TX_DN<26>")
	)
	(segment
		(start 264.612374 -127.66929)
		(end 264.427716 -128.115314)
		(width 0.1651)
		(layer "In9.Cu")
		(net "P5E_PEX2_STN1_TX_DN<26>")
	)
	(segment
		(start 301.073566 -278.229568)
		(end 301.235364 -278.229568)
		(width 0.1143)
		(layer "In9.Cu")
		(net "P5E_PEX2_STN1_TX_DN<26>")
	)
	(segment
		(start 262.598662 -132.232146)
		(end 262.598916 -132.232146)
		(width 0.1651)
		(layer "In9.Cu")
		(net "P5E_PEX2_STN1_TX_DN<26>")
	)
	(segment
		(start 264.933176 -143.16202)
		(end 265.665712 -158.050738)
		(width 0.1651)
		(layer "In9.Cu")
		(net "P5E_PEX2_STN1_TX_DN<26>")
	)
	(segment
		(start 264.735056 -127.073914)
		(end 264.735056 -127.074168)
		(width 0.1651)
		(layer "In9.Cu")
		(net "P5E_PEX2_STN1_TX_DN<26>")
	)
	(segment
		(start 267.034772 -123.39701)
		(end 266.398502 -123.39701)
		(width 0.1651)
		(layer "In9.Cu")
		(net "P5E_PEX2_STN1_TX_DN<26>")
	)
	(segment
		(start 263.104884 -131.010152)
		(end 263.16686 -131.159504)
		(width 0.1651)
		(layer "In9.Cu")
		(net "P5E_PEX2_STN1_TX_DN<26>")
	)
	(segment
		(start 262.832342 -131.66725)
		(end 262.832596 -131.66725)
		(width 0.1651)
		(layer "In9.Cu")
		(net "P5E_PEX2_STN1_TX_DN<26>")
	)
	(segment
		(start 262.832596 -131.66725)
		(end 262.598662 -132.232146)
		(width 0.1651)
		(layer "In9.Cu")
		(net "P5E_PEX2_STN1_TX_DN<26>")
	)
	(segment
		(start 266.306554 -161.272474)
		(end 301.015908 -263.80948)
		(width 0.1651)
		(layer "In9.Cu")
		(net "P5E_PEX2_STN1_TX_DN<26>")
	)
	(segment
		(start 266.158726 -123.636786)
		(end 265.921236 -124.210318)
		(width 0.1651)
		(layer "In9.Cu")
		(net "P5E_PEX2_STN1_TX_DN<26>")
	)
	(segment
		(start 301.015908 -271.500346)
		(end 300.970188 -271.546066)
		(width 0.1143)
		(layer "In9.Cu")
		(net "P5E_PEX2_STN1_TX_DN<26>")
	)
	(segment
		(start 300.970188 -278.12619)
		(end 301.073566 -278.229568)
		(width 0.1143)
		(layer "In9.Cu")
		(net "P5E_PEX2_STN1_TX_DN<26>")
	)
	(segment
		(start 265.341608 -125.908816)
		(end 265.192002 -125.970792)
		(width 0.1651)
		(layer "In9.Cu")
		(net "P5E_PEX2_STN1_TX_DN<26>")
	)
	(segment
		(start 301.235364 -278.229568)
		(end 301.349664 -278.115268)
		(width 0.1143)
		(layer "In9.Cu")
		(net "P5E_PEX2_STN1_TX_DN<26>")
	)
	(segment
		(start 263.16686 -131.159504)
		(end 262.981948 -131.605528)
		(width 0.1651)
		(layer "In9.Cu")
		(net "P5E_PEX2_STN1_TX_DN<26>")
	)
	(segment
		(start 265.921236 -124.210318)
		(end 265.983212 -124.35967)
		(width 0.1651)
		(layer "In9.Cu")
		(net "P5E_PEX2_STN1_TX_DN<26>")
	)
	(segment
		(start 266.055094 -159.487108)
		(end 266.149328 -159.960564)
		(width 0.1651)
		(layer "In9.Cu")
		(net "P5E_PEX2_STN1_TX_DN<26>")
	)
	(segment
		(start 265.526266 -125.462792)
		(end 265.341608 -125.908816)
		(width 0.1651)
		(layer "In9.Cu")
		(net "P5E_PEX2_STN1_TX_DN<26>")
	)
	(segment
		(start 265.798554 -124.805694)
		(end 265.648948 -124.86767)
		(width 0.1651)
		(layer "In9.Cu")
		(net "P5E_PEX2_STN1_TX_DN<26>")
	)
	(segment
		(start 265.46429 -125.31344)
		(end 265.526266 -125.462792)
		(width 0.1651)
		(layer "In9.Cu")
		(net "P5E_PEX2_STN1_TX_DN<26>")
	)
	(segment
		(start 265.06932 -126.565914)
		(end 264.884662 -127.011938)
		(width 0.1651)
		(layer "In9.Cu")
		(net "P5E_PEX2_STN1_TX_DN<26>")
	)
	(segment
		(start 264.093452 -128.62306)
		(end 264.155428 -128.772412)
		(width 0.1651)
		(layer "In9.Cu")
		(net "P5E_PEX2_STN1_TX_DN<26>")
	)
	(segment
		(start 263.97077 -129.218436)
		(end 263.821164 -129.280412)
		(width 0.1651)
		(layer "In9.Cu")
		(net "P5E_PEX2_STN1_TX_DN<26>")
	)
	(segment
		(start 262.981948 -131.605528)
		(end 262.832342 -131.66725)
		(width 0.1651)
		(layer "In9.Cu")
		(net "P5E_PEX2_STN1_TX_DN<26>")
	)
	(segment
		(start 263.698482 -129.875534)
		(end 263.513824 -130.321558)
		(width 0.1651)
		(layer "In9.Cu")
		(net "P5E_PEX2_STN1_TX_DN<26>")
	)
	(segment
		(start 300.970188 -271.546066)
		(end 300.970188 -278.12619)
		(width 0.1143)
		(layer "In9.Cu")
		(net "P5E_PEX2_STN1_TX_DN<26>")
	)
	(segment
		(start 263.636506 -129.726182)
		(end 263.698482 -129.875534)
		(width 0.1651)
		(layer "In9.Cu")
		(net "P5E_PEX2_STN1_TX_DN<26>")
	)
	(segment
		(start 301.349664 -278.115268)
		(end 301.349664 -277.849838)
		(width 0.1143)
		(layer "In9.Cu")
		(net "P5E_PEX2_STN1_TX_DN<26>")
	)
	(segment
		(start 265.93546 -159.407098)
		(end 266.055094 -159.487108)
		(width 0.1651)
		(layer "In9.Cu")
		(net "P5E_PEX2_STN1_TX_DN<26>")
	)
	(segment
		(start 265.007344 -126.416562)
		(end 265.06932 -126.565914)
		(width 0.1651)
		(layer "In9.Cu")
		(net "P5E_PEX2_STN1_TX_DN<26>")
	)
	(segment
		(start 263.364218 -130.383788)
		(end 263.104884 -131.010152)
		(width 0.1651)
		(layer "In9.Cu")
		(net "P5E_PEX2_STN1_TX_DN<26>")
	)
	(segment
		(start 264.735056 -127.074168)
		(end 264.550398 -127.519938)
		(width 0.1651)
		(layer "In9.Cu")
		(net "P5E_PEX2_STN1_TX_DN<26>")
	)
	(segment
		(start 265.665712 -158.050738)
		(end 265.93546 -159.407098)
		(width 0.1651)
		(layer "In9.Cu")
		(net "P5E_PEX2_STN1_TX_DN<26>")
	)
	(segment
		(start 262.364474 -136.961118)
		(end 264.933176 -143.16202)
		(width 0.1651)
		(layer "In9.Cu")
		(net "P5E_PEX2_STN1_TX_DN<26>")
	)
	(segment
		(start 344.161364 -343.365582)
		(end 344.161364 -342.734138)
		(width 0.13462)
		(layer "F.Cu")
		(net "P5E_PEX2_STN6_TX_DN<97>")
	)
	(segment
		(start 344.481404 -343.685622)
		(end 344.161364 -343.365582)
		(width 0.13462)
		(layer "F.Cu")
		(net "P5E_PEX2_STN6_TX_DN<97>")
	)
	(segment
		(start 344.161364 -342.734138)
		(end 344.456004 -342.439498)
		(width 0.13462)
		(layer "F.Cu")
		(net "P5E_PEX2_STN6_TX_DN<97>")
	)
	(segment
		(start 288.665666 -319.966848)
		(end 288.619946 -319.921128)
		(width 0.1143)
		(layer "In13.Cu")
		(net "P5E_PEX2_STN6_TX_DN<97>")
	)
	(segment
		(start 340.000336 -338.133944)
		(end 336.1944 -335.153)
		(width 0.1651)
		(layer "In13.Cu")
		(net "P5E_PEX2_STN6_TX_DN<97>")
	)
	(segment
		(start 343.8144 -341.122)
		(end 340.000336 -338.134198)
		(width 0.1651)
		(layer "In13.Cu")
		(net "P5E_PEX2_STN6_TX_DN<97>")
	)
	(segment
		(start 315.1378 -325.654416)
		(end 295.703244 -321.845686)
		(width 0.1651)
		(layer "In13.Cu")
		(net "P5E_PEX2_STN6_TX_DN<97>")
	)
	(segment
		(start 288.665666 -320.310002)
		(end 288.665666 -319.995296)
		(width 0.1651)
		(layer "In13.Cu")
		(net "P5E_PEX2_STN6_TX_DN<97>")
	)
	(segment
		(start 294.416988 -321.477132)
		(end 293.930578 -321.381882)
		(width 0.1651)
		(layer "In13.Cu")
		(net "P5E_PEX2_STN6_TX_DN<97>")
	)
	(segment
		(start 291.30117 -320.983102)
		(end 289.157156 -320.689224)
		(width 0.1651)
		(layer "In13.Cu")
		(net "P5E_PEX2_STN6_TX_DN<97>")
	)
	(segment
		(start 288.665666 -319.995296)
		(end 288.665666 -319.966848)
		(width 0.1143)
		(layer "In13.Cu")
		(net "P5E_PEX2_STN6_TX_DN<97>")
	)
	(segment
		(start 295.703244 -321.845686)
		(end 295.629584 -321.73545)
		(width 0.1651)
		(layer "In13.Cu")
		(net "P5E_PEX2_STN6_TX_DN<97>")
	)
	(segment
		(start 344.456004 -342.439498)
		(end 344.165174 -342.148668)
		(width 0.1651)
		(layer "In13.Cu")
		(net "P5E_PEX2_STN6_TX_DN<97>")
	)
	(segment
		(start 288.99993 -311.784492)
		(end 288.99993 -312.049922)
		(width 0.1143)
		(layer "In13.Cu")
		(net "P5E_PEX2_STN6_TX_DN<97>")
	)
	(segment
		(start 288.723832 -311.670192)
		(end 288.88563 -311.670192)
		(width 0.1143)
		(layer "In13.Cu")
		(net "P5E_PEX2_STN6_TX_DN<97>")
	)
	(segment
		(start 295.103296 -321.632326)
		(end 294.99306 -321.706748)
		(width 0.1651)
		(layer "In13.Cu")
		(net "P5E_PEX2_STN6_TX_DN<97>")
	)
	(segment
		(start 288.934398 -320.578734)
		(end 288.665666 -320.310002)
		(width 0.1651)
		(layer "In13.Cu")
		(net "P5E_PEX2_STN6_TX_DN<97>")
	)
	(segment
		(start 340.000336 -338.134198)
		(end 340.000336 -338.133944)
		(width 0.1651)
		(layer "In13.Cu")
		(net "P5E_PEX2_STN6_TX_DN<97>")
	)
	(segment
		(start 288.619946 -319.921128)
		(end 288.619946 -311.774078)
		(width 0.1143)
		(layer "In13.Cu")
		(net "P5E_PEX2_STN6_TX_DN<97>")
	)
	(segment
		(start 295.629584 -321.73545)
		(end 295.103296 -321.632326)
		(width 0.1651)
		(layer "In13.Cu")
		(net "P5E_PEX2_STN6_TX_DN<97>")
	)
	(segment
		(start 293.930578 -321.381882)
		(end 293.796466 -321.472052)
		(width 0.1651)
		(layer "In13.Cu")
		(net "P5E_PEX2_STN6_TX_DN<97>")
	)
	(segment
		(start 344.165174 -341.633048)
		(end 343.8144 -341.122)
		(width 0.1651)
		(layer "In13.Cu")
		(net "P5E_PEX2_STN6_TX_DN<97>")
	)
	(segment
		(start 336.1944 -335.153)
		(end 315.1378 -325.654416)
		(width 0.1651)
		(layer "In13.Cu")
		(net "P5E_PEX2_STN6_TX_DN<97>")
	)
	(segment
		(start 288.619946 -311.774078)
		(end 288.723832 -311.670192)
		(width 0.1143)
		(layer "In13.Cu")
		(net "P5E_PEX2_STN6_TX_DN<97>")
	)
	(segment
		(start 344.165174 -342.148668)
		(end 344.165174 -341.633048)
		(width 0.1651)
		(layer "In13.Cu")
		(net "P5E_PEX2_STN6_TX_DN<97>")
	)
	(segment
		(start 293.796466 -321.472052)
		(end 291.30117 -320.983102)
		(width 0.1651)
		(layer "In13.Cu")
		(net "P5E_PEX2_STN6_TX_DN<97>")
	)
	(segment
		(start 289.157156 -320.689224)
		(end 288.934398 -320.578734)
		(width 0.1651)
		(layer "In13.Cu")
		(net "P5E_PEX2_STN6_TX_DN<97>")
	)
	(segment
		(start 294.99306 -321.706748)
		(end 294.507158 -321.611498)
		(width 0.1651)
		(layer "In13.Cu")
		(net "P5E_PEX2_STN6_TX_DN<97>")
	)
	(segment
		(start 294.507158 -321.611498)
		(end 294.416988 -321.477132)
		(width 0.1651)
		(layer "In13.Cu")
		(net "P5E_PEX2_STN6_TX_DN<97>")
	)
	(segment
		(start 288.88563 -311.670192)
		(end 288.99993 -311.784492)
		(width 0.1143)
		(layer "In13.Cu")
		(net "P5E_PEX2_STN6_TX_DN<97>")
	)
	(segment
		(start 304.884328 -318.320166)
		(end 305.035458 -318.320166)
		(width 0.1143)
		(layer "In5.Cu")
		(net "P5E_PEX2_STN5_RX_DN<95>")
	)
	(segment
		(start 348.038928 -341.402924)
		(end 347.66631 -340.503002)
		(width 0.1651)
		(layer "In5.Cu")
		(net "P5E_PEX2_STN5_RX_DN<95>")
	)
	(segment
		(start 306.313078 -320.728848)
		(end 306.257198 -320.576956)
		(width 0.1651)
		(layer "In5.Cu")
		(net "P5E_PEX2_STN5_RX_DN<95>")
	)
	(segment
		(start 347.66631 -340.503002)
		(end 346.01023 -339.00618)
		(width 0.1651)
		(layer "In5.Cu")
		(net "P5E_PEX2_STN5_RX_DN<95>")
	)
	(segment
		(start 305.035458 -318.320166)
		(end 305.149758 -318.434466)
		(width 0.1143)
		(layer "In5.Cu")
		(net "P5E_PEX2_STN5_RX_DN<95>")
	)
	(segment
		(start 304.815748 -319.961768)
		(end 304.815748 -319.916048)
		(width 0.1651)
		(layer "In5.Cu")
		(net "P5E_PEX2_STN5_RX_DN<95>")
	)
	(segment
		(start 346.890086 -372.890034)
		(end 346.890086 -372.508018)
		(width 0.1651)
		(layer "In5.Cu")
		(net "P5E_PEX2_STN5_RX_DN<95>")
	)
	(segment
		(start 346.01023 -339.00618)
		(end 306.313078 -320.728848)
		(width 0.1651)
		(layer "In5.Cu")
		(net "P5E_PEX2_STN5_RX_DN<95>")
	)
	(segment
		(start 304.96002 -320.105786)
		(end 304.815748 -319.961768)
		(width 0.1651)
		(layer "In5.Cu")
		(net "P5E_PEX2_STN5_RX_DN<95>")
	)
	(segment
		(start 347.824044 -361.903264)
		(end 348.038928 -341.402924)
		(width 0.1651)
		(layer "In5.Cu")
		(net "P5E_PEX2_STN5_RX_DN<95>")
	)
	(segment
		(start 305.149758 -318.434466)
		(end 305.149758 -318.699896)
		(width 0.1143)
		(layer "In5.Cu")
		(net "P5E_PEX2_STN5_RX_DN<95>")
	)
	(segment
		(start 305.80711 -320.369946)
		(end 305.655472 -320.425826)
		(width 0.1651)
		(layer "In5.Cu")
		(net "P5E_PEX2_STN5_RX_DN<95>")
	)
	(segment
		(start 348.016068 -367.669826)
		(end 347.824044 -361.903264)
		(width 0.1651)
		(layer "In5.Cu")
		(net "P5E_PEX2_STN5_RX_DN<95>")
	)
	(segment
		(start 304.815748 -319.8876)
		(end 304.770028 -319.84188)
		(width 0.1143)
		(layer "In5.Cu")
		(net "P5E_PEX2_STN5_RX_DN<95>")
	)
	(segment
		(start 305.655472 -320.425826)
		(end 304.96002 -320.105786)
		(width 0.1651)
		(layer "In5.Cu")
		(net "P5E_PEX2_STN5_RX_DN<95>")
	)
	(segment
		(start 347.564202 -372.381018)
		(end 348.016068 -371.929152)
		(width 0.1651)
		(layer "In5.Cu")
		(net "P5E_PEX2_STN5_RX_DN<95>")
	)
	(segment
		(start 304.815748 -319.916048)
		(end 304.815748 -319.8876)
		(width 0.1143)
		(layer "In5.Cu")
		(net "P5E_PEX2_STN5_RX_DN<95>")
	)
	(segment
		(start 304.770028 -318.434466)
		(end 304.884328 -318.320166)
		(width 0.1143)
		(layer "In5.Cu")
		(net "P5E_PEX2_STN5_RX_DN<95>")
	)
	(segment
		(start 304.770028 -319.84188)
		(end 304.770028 -318.434466)
		(width 0.1143)
		(layer "In5.Cu")
		(net "P5E_PEX2_STN5_RX_DN<95>")
	)
	(segment
		(start 306.257198 -320.576956)
		(end 305.80711 -320.369946)
		(width 0.1651)
		(layer "In5.Cu")
		(net "P5E_PEX2_STN5_RX_DN<95>")
	)
	(segment
		(start 346.890086 -372.508018)
		(end 347.017086 -372.381018)
		(width 0.1651)
		(layer "In5.Cu")
		(net "P5E_PEX2_STN5_RX_DN<95>")
	)
	(segment
		(start 347.017086 -372.381018)
		(end 347.564202 -372.381018)
		(width 0.1651)
		(layer "In5.Cu")
		(net "P5E_PEX2_STN5_RX_DN<95>")
	)
	(segment
		(start 348.016068 -371.929152)
		(end 348.016068 -367.669826)
		(width 0.1651)
		(layer "In5.Cu")
		(net "P5E_PEX2_STN5_RX_DN<95>")
	)
	(segment
		(start 288.581592 -157.8356)
		(end 288.581592 -158.8516)
		(width 0.13208)
		(layer "F.Cu")
		(net "RST_HP_NIC4_BUF_N")
	)
	(segment
		(start 288.002726 -164.698934)
		(end 288.581592 -164.120068)
		(width 0.13208)
		(layer "F.Cu")
		(net "RST_HP_NIC4_BUF_N")
	)
	(segment
		(start 284.264354 -166.702994)
		(end 283.248354 -166.702994)
		(width 0.13208)
		(layer "F.Cu")
		(net "RST_HP_NIC4_BUF_N")
	)
	(segment
		(start 282.448254 -165.902894)
		(end 281.859228 -165.902894)
		(width 0.13208)
		(layer "F.Cu")
		(net "RST_HP_NIC4_BUF_N")
	)
	(segment
		(start 285.998666 -166.702994)
		(end 288.002726 -164.698934)
		(width 0.13208)
		(layer "F.Cu")
		(net "RST_HP_NIC4_BUF_N")
	)
	(segment
		(start 282.70327 -166.15791)
		(end 282.448254 -165.902894)
		(width 0.13208)
		(layer "F.Cu")
		(net "RST_HP_NIC4_BUF_N")
	)
	(segment
		(start 284.264354 -166.702994)
		(end 285.998666 -166.702994)
		(width 0.13208)
		(layer "F.Cu")
		(net "RST_HP_NIC4_BUF_N")
	)
	(segment
		(start 288.581592 -164.120068)
		(end 288.581592 -158.8516)
		(width 0.13208)
		(layer "F.Cu")
		(net "RST_HP_NIC4_BUF_N")
	)
	(segment
		(start 282.70327 -166.595298)
		(end 282.70327 -166.15791)
		(width 0.13208)
		(layer "F.Cu")
		(net "RST_HP_NIC4_BUF_N")
	)
	(segment
		(start 283.248354 -166.702994)
		(end 282.810966 -166.702994)
		(width 0.13208)
		(layer "F.Cu")
		(net "RST_HP_NIC4_BUF_N")
	)
	(segment
		(start 282.810966 -166.702994)
		(end 282.70327 -166.595298)
		(width 0.13208)
		(layer "F.Cu")
		(net "RST_HP_NIC4_BUF_N")
	)
	(via
		(at 288.002726 -164.698934)
		(size 0.762)
		(drill 0.381)
		(layers "F.Cu" "B.Cu")
		(net "RST_HP_NIC4_BUF_N")
	)
	(segment
		(start 80.54848 -79.463646)
		(end 80.030066 -79.98206)
		(width 0.13208)
		(layer "F.Cu")
		(net "HP_NIC1_PWRGD")
	)
	(segment
		(start 80.030066 -79.98206)
		(end 79.314802 -79.98206)
		(width 0.13208)
		(layer "F.Cu")
		(net "HP_NIC1_PWRGD")
	)
	(segment
		(start 81.134458 -79.463646)
		(end 80.54848 -79.463646)
		(width 0.13208)
		(layer "F.Cu")
		(net "HP_NIC1_PWRGD")
	)
	(segment
		(start 79.314802 -80.95996)
		(end 79.314802 -79.98206)
		(width 0.13208)
		(layer "F.Cu")
		(net "HP_NIC1_PWRGD")
	)
	(via
		(at 80.030066 -79.98206)
		(size 0.508)
		(drill 0.254)
		(layers "F.Cu" "B.Cu")
		(net "HP_NIC1_PWRGD")
	)
	(segment
		(start 199.02805 -148.91131)
		(end 199.34809 -148.59127)
		(width 0.13462)
		(layer "F.Cu")
		(net "P5E_PEX1_STN0_TX_DP<11>")
	)
	(segment
		(start 199.34809 -148.59127)
		(end 199.979534 -148.59127)
		(width 0.13462)
		(layer "F.Cu")
		(net "P5E_PEX1_STN0_TX_DP<11>")
	)
	(segment
		(start 199.979534 -148.59127)
		(end 200.274174 -148.88591)
		(width 0.13462)
		(layer "F.Cu")
		(net "P5E_PEX1_STN0_TX_DP<11>")
	)
	(segment
		(start 191.699642 -222.13189)
		(end 195.079366 -260.78815)
		(width 0.1651)
		(layer "In9.Cu")
		(net "P5E_PEX1_STN0_TX_DP<11>")
	)
	(segment
		(start 195.625974 -177.254408)
		(end 193.662554 -199.693276)
		(width 0.1651)
		(layer "In9.Cu")
		(net "P5E_PEX1_STN0_TX_DP<11>")
	)
	(segment
		(start 203.107798 -150.66518)
		(end 203.079858 -150.80615)
		(width 0.1651)
		(layer "In9.Cu")
		(net "P5E_PEX1_STN0_TX_DP<11>")
	)
	(segment
		(start 193.662808 -199.693276)
		(end 191.699642 -222.13189)
		(width 0.1651)
		(layer "In9.Cu")
		(net "P5E_PEX1_STN0_TX_DP<11>")
	)
	(segment
		(start 200.274174 -148.88591)
		(end 200.565004 -148.59508)
		(width 0.1651)
		(layer "In9.Cu")
		(net "P5E_PEX1_STN0_TX_DP<11>")
	)
	(segment
		(start 202.089004 -149.430994)
		(end 202.674474 -150.016464)
		(width 0.1651)
		(layer "In9.Cu")
		(net "P5E_PEX1_STN0_TX_DP<11>")
	)
	(segment
		(start 205.340458 -155.015692)
		(end 205.340458 -157.687772)
		(width 0.1651)
		(layer "In9.Cu")
		(net "P5E_PEX1_STN0_TX_DP<11>")
	)
	(segment
		(start 194.133978 -271.471898)
		(end 194.133978 -271.500346)
		(width 0.1143)
		(layer "In9.Cu")
		(net "P5E_PEX1_STN0_TX_DP<11>")
	)
	(segment
		(start 204.24013 -152.359614)
		(end 205.340458 -155.015692)
		(width 0.1651)
		(layer "In9.Cu")
		(net "P5E_PEX1_STN0_TX_DP<11>")
	)
	(segment
		(start 201.94524 -149.430994)
		(end 202.089004 -149.430994)
		(width 0.1651)
		(layer "In9.Cu")
		(net "P5E_PEX1_STN0_TX_DP<11>")
	)
	(segment
		(start 203.489052 -151.235664)
		(end 204.24013 -152.359614)
		(width 0.1651)
		(layer "In9.Cu")
		(net "P5E_PEX1_STN0_TX_DP<11>")
	)
	(segment
		(start 203.348082 -151.207724)
		(end 203.489052 -151.235664)
		(width 0.1651)
		(layer "In9.Cu")
		(net "P5E_PEX1_STN0_TX_DP<11>")
	)
	(segment
		(start 194.749674 -278.534368)
		(end 194.749674 -278.799798)
		(width 0.1143)
		(layer "In9.Cu")
		(net "P5E_PEX1_STN0_TX_DP<11>")
	)
	(segment
		(start 205.340458 -157.687772)
		(end 196.997828 -172.13961)
		(width 0.1651)
		(layer "In9.Cu")
		(net "P5E_PEX1_STN0_TX_DP<11>")
	)
	(segment
		(start 201.603864 -148.945854)
		(end 201.603864 -149.089618)
		(width 0.1651)
		(layer "In9.Cu")
		(net "P5E_PEX1_STN0_TX_DP<11>")
	)
	(segment
		(start 193.662554 -199.693276)
		(end 193.662808 -199.693276)
		(width 0.1651)
		(layer "In9.Cu")
		(net "P5E_PEX1_STN0_TX_DP<11>")
	)
	(segment
		(start 202.674474 -150.016464)
		(end 203.107798 -150.66518)
		(width 0.1651)
		(layer "In9.Cu")
		(net "P5E_PEX1_STN0_TX_DP<11>")
	)
	(segment
		(start 201.603864 -149.089618)
		(end 201.94524 -149.430994)
		(width 0.1651)
		(layer "In9.Cu")
		(net "P5E_PEX1_STN0_TX_DP<11>")
	)
	(segment
		(start 194.133978 -271.500346)
		(end 194.179698 -271.546066)
		(width 0.1143)
		(layer "In9.Cu")
		(net "P5E_PEX1_STN0_TX_DP<11>")
	)
	(segment
		(start 194.635374 -278.420068)
		(end 194.749674 -278.534368)
		(width 0.1143)
		(layer "In9.Cu")
		(net "P5E_PEX1_STN0_TX_DP<11>")
	)
	(segment
		(start 196.997828 -172.13961)
		(end 195.625974 -177.254408)
		(width 0.1651)
		(layer "In9.Cu")
		(net "P5E_PEX1_STN0_TX_DP<11>")
	)
	(segment
		(start 195.079366 -260.78815)
		(end 195.079366 -268.590776)
		(width 0.1651)
		(layer "In9.Cu")
		(net "P5E_PEX1_STN0_TX_DP<11>")
	)
	(segment
		(start 194.394582 -278.420068)
		(end 194.635374 -278.420068)
		(width 0.1143)
		(layer "In9.Cu")
		(net "P5E_PEX1_STN0_TX_DP<11>")
	)
	(segment
		(start 201.25309 -148.59508)
		(end 201.603864 -148.945854)
		(width 0.1651)
		(layer "In9.Cu")
		(net "P5E_PEX1_STN0_TX_DP<11>")
	)
	(segment
		(start 200.565004 -148.59508)
		(end 201.25309 -148.59508)
		(width 0.1651)
		(layer "In9.Cu")
		(net "P5E_PEX1_STN0_TX_DP<11>")
	)
	(segment
		(start 194.133978 -270.873474)
		(end 194.133978 -271.471898)
		(width 0.1651)
		(layer "In9.Cu")
		(net "P5E_PEX1_STN0_TX_DP<11>")
	)
	(segment
		(start 195.079366 -268.590776)
		(end 194.133978 -270.873474)
		(width 0.1651)
		(layer "In9.Cu")
		(net "P5E_PEX1_STN0_TX_DP<11>")
	)
	(segment
		(start 203.079858 -150.80615)
		(end 203.348082 -151.207724)
		(width 0.1651)
		(layer "In9.Cu")
		(net "P5E_PEX1_STN0_TX_DP<11>")
	)
	(segment
		(start 194.179698 -278.205184)
		(end 194.394582 -278.420068)
		(width 0.1143)
		(layer "In9.Cu")
		(net "P5E_PEX1_STN0_TX_DP<11>")
	)
	(segment
		(start 194.179698 -271.546066)
		(end 194.179698 -278.205184)
		(width 0.1143)
		(layer "In9.Cu")
		(net "P5E_PEX1_STN0_TX_DP<11>")
	)
	(segment
		(start 121.483628 -355.658166)
		(end 121.483628 -355.026722)
		(width 0.13462)
		(layer "F.Cu")
		(net "P5E_PEX1_STN6_TX_DP<98>")
	)
	(segment
		(start 121.483628 -355.026722)
		(end 121.188988 -354.732082)
		(width 0.13462)
		(layer "F.Cu")
		(net "P5E_PEX1_STN6_TX_DP<98>")
	)
	(segment
		(start 121.163588 -355.978206)
		(end 121.483628 -355.658166)
		(width 0.13462)
		(layer "F.Cu")
		(net "P5E_PEX1_STN6_TX_DP<98>")
	)
	(segment
		(start 150.255986 -329.778614)
		(end 167.435022 -324.567042)
		(width 0.1651)
		(layer "In7.Cu")
		(net "P5E_PEX1_STN6_TX_DP<98>")
	)
	(segment
		(start 171.333922 -320.002408)
		(end 171.333922 -319.97396)
		(width 0.1143)
		(layer "In7.Cu")
		(net "P5E_PEX1_STN6_TX_DP<98>")
	)
	(segment
		(start 171.835572 -313.379612)
		(end 171.949872 -313.265312)
		(width 0.1143)
		(layer "In7.Cu")
		(net "P5E_PEX1_STN6_TX_DP<98>")
	)
	(segment
		(start 169.770298 -323.167248)
		(end 170.638216 -322.29933)
		(width 0.1651)
		(layer "In7.Cu")
		(net "P5E_PEX1_STN6_TX_DP<98>")
	)
	(segment
		(start 133.009894 -335.010506)
		(end 150.255986 -329.778614)
		(width 0.1651)
		(layer "In7.Cu")
		(net "P5E_PEX1_STN6_TX_DP<98>")
	)
	(segment
		(start 171.333922 -319.97396)
		(end 171.379642 -319.92824)
		(width 0.1143)
		(layer "In7.Cu")
		(net "P5E_PEX1_STN6_TX_DP<98>")
	)
	(segment
		(start 121.188988 -354.732082)
		(end 121.479818 -354.441252)
		(width 0.1651)
		(layer "In7.Cu")
		(net "P5E_PEX1_STN6_TX_DP<98>")
	)
	(segment
		(start 167.435022 -324.567042)
		(end 169.770298 -323.167248)
		(width 0.1651)
		(layer "In7.Cu")
		(net "P5E_PEX1_STN6_TX_DP<98>")
	)
	(segment
		(start 171.333922 -320.619628)
		(end 171.333922 -320.002408)
		(width 0.1651)
		(layer "In7.Cu")
		(net "P5E_PEX1_STN6_TX_DP<98>")
	)
	(segment
		(start 171.949872 -313.265312)
		(end 171.949872 -312.999882)
		(width 0.1143)
		(layer "In7.Cu")
		(net "P5E_PEX1_STN6_TX_DP<98>")
	)
	(segment
		(start 171.379642 -313.605418)
		(end 171.605448 -313.379612)
		(width 0.1143)
		(layer "In7.Cu")
		(net "P5E_PEX1_STN6_TX_DP<98>")
	)
	(segment
		(start 121.479818 -354.441252)
		(end 121.479818 -353.705922)
		(width 0.1651)
		(layer "In7.Cu")
		(net "P5E_PEX1_STN6_TX_DP<98>")
	)
	(segment
		(start 171.605448 -313.379612)
		(end 171.835572 -313.379612)
		(width 0.1143)
		(layer "In7.Cu")
		(net "P5E_PEX1_STN6_TX_DP<98>")
	)
	(segment
		(start 121.479818 -353.705922)
		(end 123.034298 -352.151442)
		(width 0.1651)
		(layer "In7.Cu")
		(net "P5E_PEX1_STN6_TX_DP<98>")
	)
	(segment
		(start 170.638216 -322.29933)
		(end 171.333922 -320.619628)
		(width 0.1651)
		(layer "In7.Cu")
		(net "P5E_PEX1_STN6_TX_DP<98>")
	)
	(segment
		(start 123.034298 -341.735156)
		(end 124.893832 -339.875622)
		(width 0.1651)
		(layer "In7.Cu")
		(net "P5E_PEX1_STN6_TX_DP<98>")
	)
	(segment
		(start 171.379642 -319.92824)
		(end 171.379642 -313.605418)
		(width 0.1143)
		(layer "In7.Cu")
		(net "P5E_PEX1_STN6_TX_DP<98>")
	)
	(segment
		(start 124.893832 -339.875622)
		(end 133.009894 -335.010506)
		(width 0.1651)
		(layer "In7.Cu")
		(net "P5E_PEX1_STN6_TX_DP<98>")
	)
	(segment
		(start 123.034298 -352.151442)
		(end 123.034298 -341.735156)
		(width 0.1651)
		(layer "In7.Cu")
		(net "P5E_PEX1_STN6_TX_DP<98>")
	)
	(segment
		(start 270.265906 -103.4796)
		(end 270.890238 -103.4796)
		(width 0.13462)
		(layer "F.Cu")
		(net "P5E_PEX2_STN1_TX_DN<18>")
	)
	(segment
		(start 269.96771 -103.777796)
		(end 270.265906 -103.4796)
		(width 0.13462)
		(layer "F.Cu")
		(net "P5E_PEX2_STN1_TX_DN<18>")
	)
	(segment
		(start 270.890238 -103.4796)
		(end 271.213834 -103.803196)
		(width 0.13462)
		(layer "F.Cu")
		(net "P5E_PEX2_STN1_TX_DN<18>")
	)
	(segment
		(start 260.834886 -111.604044)
		(end 260.984492 -111.542322)
		(width 0.1651)
		(layer "In9.Cu")
		(net "P5E_PEX2_STN1_TX_DN<18>")
	)
	(segment
		(start 265.926824 -104.307132)
		(end 266.722352 -103.977694)
		(width 0.1651)
		(layer "In9.Cu")
		(net "P5E_PEX2_STN1_TX_DN<18>")
	)
	(segment
		(start 261.578598 -109.808518)
		(end 261.768082 -109.351064)
		(width 0.1651)
		(layer "In9.Cu")
		(net "P5E_PEX2_STN1_TX_DN<18>")
	)
	(segment
		(start 265.585702 -104.809798)
		(end 265.585702 -104.648254)
		(width 0.1651)
		(layer "In9.Cu")
		(net "P5E_PEX2_STN1_TX_DN<18>")
	)
	(segment
		(start 258.488434 -162.323272)
		(end 257.912616 -159.428434)
		(width 0.1651)
		(layer "In9.Cu")
		(net "P5E_PEX2_STN1_TX_DN<18>")
	)
	(segment
		(start 267.906754 -103.486966)
		(end 268.306296 -103.486966)
		(width 0.1651)
		(layer "In9.Cu")
		(net "P5E_PEX2_STN1_TX_DN<18>")
	)
	(segment
		(start 268.420596 -103.601266)
		(end 268.903196 -103.601266)
		(width 0.1651)
		(layer "In9.Cu")
		(net "P5E_PEX2_STN1_TX_DN<18>")
	)
	(segment
		(start 263.89711 -106.49839)
		(end 263.89711 -106.336846)
		(width 0.1651)
		(layer "In9.Cu")
		(net "P5E_PEX2_STN1_TX_DN<18>")
	)
	(segment
		(start 259.597144 -114.592862)
		(end 260.834886 -111.604044)
		(width 0.1651)
		(layer "In9.Cu")
		(net "P5E_PEX2_STN1_TX_DN<18>")
	)
	(segment
		(start 269.67688 -103.486966)
		(end 269.96771 -103.777796)
		(width 0.1651)
		(layer "In9.Cu")
		(net "P5E_PEX2_STN1_TX_DN<18>")
	)
	(segment
		(start 262.393938 -107.840018)
		(end 263.393936 -106.84002)
		(width 0.1651)
		(layer "In9.Cu")
		(net "P5E_PEX2_STN1_TX_DN<18>")
	)
	(segment
		(start 262.045196 -108.682028)
		(end 262.393938 -107.840018)
		(width 0.1651)
		(layer "In9.Cu")
		(net "P5E_PEX2_STN1_TX_DN<18>")
	)
	(segment
		(start 268.306296 -103.486966)
		(end 268.420596 -103.601266)
		(width 0.1651)
		(layer "In9.Cu")
		(net "P5E_PEX2_STN1_TX_DN<18>")
	)
	(segment
		(start 261.173976 -111.08436)
		(end 261.112 -110.935008)
		(width 0.1651)
		(layer "In9.Cu")
		(net "P5E_PEX2_STN1_TX_DN<18>")
	)
	(segment
		(start 262.107172 -108.83138)
		(end 262.045196 -108.682028)
		(width 0.1651)
		(layer "In9.Cu")
		(net "P5E_PEX2_STN1_TX_DN<18>")
	)
	(segment
		(start 293.37 -271.546066)
		(end 293.41572 -271.500346)
		(width 0.1143)
		(layer "In9.Cu")
		(net "P5E_PEX2_STN1_TX_DN<18>")
	)
	(segment
		(start 261.917688 -109.289088)
		(end 262.107172 -108.83138)
		(width 0.1651)
		(layer "In9.Cu")
		(net "P5E_PEX2_STN1_TX_DN<18>")
	)
	(segment
		(start 254.622554 -138.637518)
		(end 254.622554 -130.990848)
		(width 0.1651)
		(layer "In9.Cu")
		(net "P5E_PEX2_STN1_TX_DN<18>")
	)
	(segment
		(start 266.871704 -104.039416)
		(end 267.317728 -103.854758)
		(width 0.1651)
		(layer "In9.Cu")
		(net "P5E_PEX2_STN1_TX_DN<18>")
	)
	(segment
		(start 268.903196 -103.601266)
		(end 269.017496 -103.486966)
		(width 0.1651)
		(layer "In9.Cu")
		(net "P5E_PEX2_STN1_TX_DN<18>")
	)
	(segment
		(start 257.912616 -159.428434)
		(end 257.195828 -144.84985)
		(width 0.1651)
		(layer "In9.Cu")
		(net "P5E_PEX2_STN1_TX_DN<18>")
	)
	(segment
		(start 267.379704 -103.705152)
		(end 267.379704 -103.70566)
		(width 0.1651)
		(layer "In9.Cu")
		(net "P5E_PEX2_STN1_TX_DN<18>")
	)
	(segment
		(start 267.379704 -103.70566)
		(end 267.906754 -103.486966)
		(width 0.1651)
		(layer "In9.Cu")
		(net "P5E_PEX2_STN1_TX_DN<18>")
	)
	(segment
		(start 293.635176 -278.229568)
		(end 293.473378 -278.229568)
		(width 0.1143)
		(layer "In9.Cu")
		(net "P5E_PEX2_STN1_TX_DN<18>")
	)
	(segment
		(start 265.082528 -105.151428)
		(end 265.244072 -105.151428)
		(width 0.1651)
		(layer "In9.Cu")
		(net "P5E_PEX2_STN1_TX_DN<18>")
	)
	(segment
		(start 265.585702 -104.648254)
		(end 265.926824 -104.307132)
		(width 0.1651)
		(layer "In9.Cu")
		(net "P5E_PEX2_STN1_TX_DN<18>")
	)
	(segment
		(start 264.741406 -105.49255)
		(end 265.082528 -105.151428)
		(width 0.1651)
		(layer "In9.Cu")
		(net "P5E_PEX2_STN1_TX_DN<18>")
	)
	(segment
		(start 293.41572 -265.511534)
		(end 258.488434 -162.323272)
		(width 0.1651)
		(layer "In9.Cu")
		(net "P5E_PEX2_STN1_TX_DN<18>")
	)
	(segment
		(start 260.984492 -111.542322)
		(end 261.173976 -111.08436)
		(width 0.1651)
		(layer "In9.Cu")
		(net "P5E_PEX2_STN1_TX_DN<18>")
	)
	(segment
		(start 263.89711 -106.336846)
		(end 264.238232 -105.995724)
		(width 0.1651)
		(layer "In9.Cu")
		(net "P5E_PEX2_STN1_TX_DN<18>")
	)
	(segment
		(start 293.41572 -271.500346)
		(end 293.41572 -271.471898)
		(width 0.1143)
		(layer "In9.Cu")
		(net "P5E_PEX2_STN1_TX_DN<18>")
	)
	(segment
		(start 269.017496 -103.486966)
		(end 269.67688 -103.486966)
		(width 0.1651)
		(layer "In9.Cu")
		(net "P5E_PEX2_STN1_TX_DN<18>")
	)
	(segment
		(start 264.238232 -105.995724)
		(end 264.399776 -105.995724)
		(width 0.1651)
		(layer "In9.Cu")
		(net "P5E_PEX2_STN1_TX_DN<18>")
	)
	(segment
		(start 293.749476 -277.849838)
		(end 293.749476 -278.115268)
		(width 0.1143)
		(layer "In9.Cu")
		(net "P5E_PEX2_STN1_TX_DN<18>")
	)
	(segment
		(start 261.768082 -109.351064)
		(end 261.917688 -109.289088)
		(width 0.1651)
		(layer "In9.Cu")
		(net "P5E_PEX2_STN1_TX_DN<18>")
	)
	(segment
		(start 265.244072 -105.151428)
		(end 265.585702 -104.809798)
		(width 0.1651)
		(layer "In9.Cu")
		(net "P5E_PEX2_STN1_TX_DN<18>")
	)
	(segment
		(start 293.37 -278.12619)
		(end 293.37 -271.546066)
		(width 0.1143)
		(layer "In9.Cu")
		(net "P5E_PEX2_STN1_TX_DN<18>")
	)
	(segment
		(start 266.722352 -103.977694)
		(end 266.871704 -104.039416)
		(width 0.1651)
		(layer "In9.Cu")
		(net "P5E_PEX2_STN1_TX_DN<18>")
	)
	(segment
		(start 293.473378 -278.229568)
		(end 293.37 -278.12619)
		(width 0.1143)
		(layer "In9.Cu")
		(net "P5E_PEX2_STN1_TX_DN<18>")
	)
	(segment
		(start 264.741406 -105.654094)
		(end 264.741406 -105.49255)
		(width 0.1651)
		(layer "In9.Cu")
		(net "P5E_PEX2_STN1_TX_DN<18>")
	)
	(segment
		(start 261.301484 -110.477554)
		(end 261.45109 -110.415832)
		(width 0.1651)
		(layer "In9.Cu")
		(net "P5E_PEX2_STN1_TX_DN<18>")
	)
	(segment
		(start 263.55548 -106.84002)
		(end 263.89711 -106.49839)
		(width 0.1651)
		(layer "In9.Cu")
		(net "P5E_PEX2_STN1_TX_DN<18>")
	)
	(segment
		(start 267.317728 -103.854758)
		(end 267.379704 -103.705152)
		(width 0.1651)
		(layer "In9.Cu")
		(net "P5E_PEX2_STN1_TX_DN<18>")
	)
	(segment
		(start 264.399776 -105.995724)
		(end 264.741406 -105.654094)
		(width 0.1651)
		(layer "In9.Cu")
		(net "P5E_PEX2_STN1_TX_DN<18>")
	)
	(segment
		(start 261.45109 -110.415832)
		(end 261.640574 -109.95787)
		(width 0.1651)
		(layer "In9.Cu")
		(net "P5E_PEX2_STN1_TX_DN<18>")
	)
	(segment
		(start 293.749476 -278.115268)
		(end 293.635176 -278.229568)
		(width 0.1143)
		(layer "In9.Cu")
		(net "P5E_PEX2_STN1_TX_DN<18>")
	)
	(segment
		(start 254.622554 -130.990848)
		(end 259.597144 -114.592862)
		(width 0.1651)
		(layer "In9.Cu")
		(net "P5E_PEX2_STN1_TX_DN<18>")
	)
	(segment
		(start 263.393936 -106.84002)
		(end 263.55548 -106.84002)
		(width 0.1651)
		(layer "In9.Cu")
		(net "P5E_PEX2_STN1_TX_DN<18>")
	)
	(segment
		(start 293.41572 -271.471898)
		(end 293.41572 -265.511534)
		(width 0.1651)
		(layer "In9.Cu")
		(net "P5E_PEX2_STN1_TX_DN<18>")
	)
	(segment
		(start 257.195828 -144.84985)
		(end 254.622554 -138.637518)
		(width 0.1651)
		(layer "In9.Cu")
		(net "P5E_PEX2_STN1_TX_DN<18>")
	)
	(segment
		(start 261.640574 -109.95787)
		(end 261.578598 -109.808518)
		(width 0.1651)
		(layer "In9.Cu")
		(net "P5E_PEX2_STN1_TX_DN<18>")
	)
	(segment
		(start 261.112 -110.935008)
		(end 261.301484 -110.477554)
		(width 0.1651)
		(layer "In9.Cu")
		(net "P5E_PEX2_STN1_TX_DN<18>")
	)
	(segment
		(start 341.052404 -348.88043)
		(end 341.347044 -348.58579)
		(width 0.13462)
		(layer "F.Cu")
		(net "P5E_PEX2_STN6_TX_DN<98>")
	)
	(segment
		(start 341.372444 -349.831914)
		(end 341.052404 -349.511874)
		(width 0.13462)
		(layer "F.Cu")
		(net "P5E_PEX2_STN6_TX_DN<98>")
	)
	(segment
		(start 341.052404 -349.511874)
		(end 341.052404 -348.88043)
		(width 0.13462)
		(layer "F.Cu")
		(net "P5E_PEX2_STN6_TX_DN<98>")
	)
	(segment
		(start 341.9348 -341.0966)
		(end 342.610694 -342.0872)
		(width 0.1651)
		(layer "In13.Cu")
		(net "P5E_PEX2_STN6_TX_DN<98>")
	)
	(segment
		(start 287.715706 -320.046096)
		(end 287.715706 -320.985388)
		(width 0.1651)
		(layer "In13.Cu")
		(net "P5E_PEX2_STN6_TX_DN<98>")
	)
	(segment
		(start 339.274404 -339.024214)
		(end 340.639654 -340.087966)
		(width 0.1651)
		(layer "In13.Cu")
		(net "P5E_PEX2_STN6_TX_DN<98>")
	)
	(segment
		(start 342.610694 -346.230194)
		(end 341.056214 -347.784674)
		(width 0.1651)
		(layer "In13.Cu")
		(net "P5E_PEX2_STN6_TX_DN<98>")
	)
	(segment
		(start 288.105342 -321.458844)
		(end 298.059348 -323.412104)
		(width 0.1651)
		(layer "In13.Cu")
		(net "P5E_PEX2_STN6_TX_DN<98>")
	)
	(segment
		(start 341.056214 -347.784674)
		(end 341.056214 -348.29496)
		(width 0.1651)
		(layer "In13.Cu")
		(net "P5E_PEX2_STN6_TX_DN<98>")
	)
	(segment
		(start 298.178474 -323.332094)
		(end 298.664884 -323.427344)
		(width 0.1651)
		(layer "In13.Cu")
		(net "P5E_PEX2_STN6_TX_DN<98>")
	)
	(segment
		(start 299.230796 -323.642228)
		(end 299.350176 -323.562218)
		(width 0.1651)
		(layer "In13.Cu")
		(net "P5E_PEX2_STN6_TX_DN<98>")
	)
	(segment
		(start 342.610694 -342.0872)
		(end 342.610694 -346.230194)
		(width 0.1651)
		(layer "In13.Cu")
		(net "P5E_PEX2_STN6_TX_DN<98>")
	)
	(segment
		(start 341.056214 -348.29496)
		(end 341.347044 -348.58579)
		(width 0.1651)
		(layer "In13.Cu")
		(net "P5E_PEX2_STN6_TX_DN<98>")
	)
	(segment
		(start 335.153 -335.8134)
		(end 339.274404 -339.024468)
		(width 0.1651)
		(layer "In13.Cu")
		(net "P5E_PEX2_STN6_TX_DN<98>")
	)
	(segment
		(start 287.935416 -313.570112)
		(end 287.773618 -313.570112)
		(width 0.1143)
		(layer "In13.Cu")
		(net "P5E_PEX2_STN6_TX_DN<98>")
	)
	(segment
		(start 288.049716 -313.949842)
		(end 288.049716 -313.684412)
		(width 0.1143)
		(layer "In13.Cu")
		(net "P5E_PEX2_STN6_TX_DN<98>")
	)
	(segment
		(start 287.773618 -313.570112)
		(end 287.669986 -313.673744)
		(width 0.1143)
		(layer "In13.Cu")
		(net "P5E_PEX2_STN6_TX_DN<98>")
	)
	(segment
		(start 287.669986 -313.673744)
		(end 287.669986 -319.971928)
		(width 0.1143)
		(layer "In13.Cu")
		(net "P5E_PEX2_STN6_TX_DN<98>")
	)
	(segment
		(start 287.669986 -319.971928)
		(end 287.715706 -320.017648)
		(width 0.1143)
		(layer "In13.Cu")
		(net "P5E_PEX2_STN6_TX_DN<98>")
	)
	(segment
		(start 288.049716 -313.684412)
		(end 287.935416 -313.570112)
		(width 0.1143)
		(layer "In13.Cu")
		(net "P5E_PEX2_STN6_TX_DN<98>")
	)
	(segment
		(start 298.664884 -323.427344)
		(end 298.744894 -323.546978)
		(width 0.1651)
		(layer "In13.Cu")
		(net "P5E_PEX2_STN6_TX_DN<98>")
	)
	(segment
		(start 298.744894 -323.546978)
		(end 299.230796 -323.642228)
		(width 0.1651)
		(layer "In13.Cu")
		(net "P5E_PEX2_STN6_TX_DN<98>")
	)
	(segment
		(start 339.274404 -339.024468)
		(end 339.274404 -339.024214)
		(width 0.1651)
		(layer "In13.Cu")
		(net "P5E_PEX2_STN6_TX_DN<98>")
	)
	(segment
		(start 340.639654 -340.087966)
		(end 340.639908 -340.087966)
		(width 0.1651)
		(layer "In13.Cu")
		(net "P5E_PEX2_STN6_TX_DN<98>")
	)
	(segment
		(start 299.836332 -323.657468)
		(end 299.916596 -323.777102)
		(width 0.1651)
		(layer "In13.Cu")
		(net "P5E_PEX2_STN6_TX_DN<98>")
	)
	(segment
		(start 315.060838 -326.748902)
		(end 335.153 -335.8134)
		(width 0.1651)
		(layer "In13.Cu")
		(net "P5E_PEX2_STN6_TX_DN<98>")
	)
	(segment
		(start 287.715706 -320.985388)
		(end 288.105342 -321.458844)
		(width 0.1651)
		(layer "In13.Cu")
		(net "P5E_PEX2_STN6_TX_DN<98>")
	)
	(segment
		(start 299.916596 -323.776594)
		(end 315.060838 -326.748902)
		(width 0.1651)
		(layer "In13.Cu")
		(net "P5E_PEX2_STN6_TX_DN<98>")
	)
	(segment
		(start 298.059348 -323.412104)
		(end 298.178474 -323.332094)
		(width 0.1651)
		(layer "In13.Cu")
		(net "P5E_PEX2_STN6_TX_DN<98>")
	)
	(segment
		(start 299.350176 -323.562218)
		(end 299.836332 -323.657468)
		(width 0.1651)
		(layer "In13.Cu")
		(net "P5E_PEX2_STN6_TX_DN<98>")
	)
	(segment
		(start 340.639908 -340.087966)
		(end 341.9348 -341.0966)
		(width 0.1651)
		(layer "In13.Cu")
		(net "P5E_PEX2_STN6_TX_DN<98>")
	)
	(segment
		(start 299.916596 -323.777102)
		(end 299.916596 -323.776594)
		(width 0.1651)
		(layer "In13.Cu")
		(net "P5E_PEX2_STN6_TX_DN<98>")
	)
	(segment
		(start 287.715706 -320.017648)
		(end 287.715706 -320.046096)
		(width 0.1143)
		(layer "In13.Cu")
		(net "P5E_PEX2_STN6_TX_DN<98>")
	)
	(segment
		(start 293.571422 -175.182276)
		(end 296.167302 -172.586396)
		(width 0.13208)
		(layer "F.Cu")
		(net "HP_NIC4_PWRGD")
	)
	(segment
		(start 295.848024 -170.157902)
		(end 295.848024 -170.920918)
		(width 0.13208)
		(layer "F.Cu")
		(net "HP_NIC4_PWRGD")
	)
	(segment
		(start 285.04515 -175.182276)
		(end 287.26638 -175.182276)
		(width 0.13208)
		(layer "F.Cu")
		(net "HP_NIC4_PWRGD")
	)
	(segment
		(start 296.167302 -171.240196)
		(end 296.167302 -171.675806)
		(width 0.13208)
		(layer "F.Cu")
		(net "HP_NIC4_PWRGD")
	)
	(segment
		(start 295.848024 -170.920918)
		(end 296.167302 -171.240196)
		(width 0.13208)
		(layer "F.Cu")
		(net "HP_NIC4_PWRGD")
	)
	(segment
		(start 287.26638 -175.182276)
		(end 293.571422 -175.182276)
		(width 0.13208)
		(layer "F.Cu")
		(net "HP_NIC4_PWRGD")
	)
	(segment
		(start 296.167302 -172.586396)
		(end 296.167302 -171.675806)
		(width 0.13208)
		(layer "F.Cu")
		(net "HP_NIC4_PWRGD")
	)
	(via
		(at 287.26638 -175.182276)
		(size 0.762)
		(drill 0.381)
		(layers "F.Cu" "B.Cu")
		(net "HP_NIC4_PWRGD")
	)
	(segment
		(start 193.844672 -344.539062)
		(end 194.164712 -344.219022)
		(width 0.13462)
		(layer "F.Cu")
		(net "P5E_PEX1_STN7_TX_C_DN<127>")
	)
	(segment
		(start 193.844672 -345.170506)
		(end 193.844672 -344.539062)
		(width 0.13462)
		(layer "F.Cu")
		(net "P5E_PEX1_STN7_TX_C_DN<127>")
	)
	(segment
		(start 194.139312 -345.465146)
		(end 193.844672 -345.170506)
		(width 0.13462)
		(layer "F.Cu")
		(net "P5E_PEX1_STN7_TX_C_DN<127>")
	)
	(segment
		(start 175.310038 -376.790204)
		(end 175.310038 -376.408188)
		(width 0.1651)
		(layer "In11.Cu")
		(net "P5E_PEX1_STN7_TX_C_DN<127>")
	)
	(segment
		(start 185.17108 -365.007906)
		(end 192.294002 -357.884984)
		(width 0.1651)
		(layer "In11.Cu")
		(net "P5E_PEX1_STN7_TX_C_DN<127>")
	)
	(segment
		(start 192.294002 -357.884984)
		(end 192.294002 -348.086934)
		(width 0.1651)
		(layer "In11.Cu")
		(net "P5E_PEX1_STN7_TX_C_DN<127>")
	)
	(segment
		(start 177.120804 -368.387376)
		(end 185.17108 -365.007906)
		(width 0.1651)
		(layer "In11.Cu")
		(net "P5E_PEX1_STN7_TX_C_DN<127>")
	)
	(segment
		(start 175.310038 -376.408188)
		(end 175.437038 -376.281188)
		(width 0.1651)
		(layer "In11.Cu")
		(net "P5E_PEX1_STN7_TX_C_DN<127>")
	)
	(segment
		(start 193.848482 -346.532454)
		(end 193.848482 -345.755976)
		(width 0.1651)
		(layer "In11.Cu")
		(net "P5E_PEX1_STN7_TX_C_DN<127>")
	)
	(segment
		(start 192.294002 -348.086934)
		(end 193.848482 -346.532454)
		(width 0.1651)
		(layer "In11.Cu")
		(net "P5E_PEX1_STN7_TX_C_DN<127>")
	)
	(segment
		(start 175.775366 -376.281188)
		(end 176.467516 -375.589038)
		(width 0.1651)
		(layer "In11.Cu")
		(net "P5E_PEX1_STN7_TX_C_DN<127>")
	)
	(segment
		(start 175.437038 -376.281188)
		(end 175.775366 -376.281188)
		(width 0.1651)
		(layer "In11.Cu")
		(net "P5E_PEX1_STN7_TX_C_DN<127>")
	)
	(segment
		(start 176.467516 -369.040664)
		(end 177.120804 -368.387376)
		(width 0.1651)
		(layer "In11.Cu")
		(net "P5E_PEX1_STN7_TX_C_DN<127>")
	)
	(segment
		(start 176.467516 -375.589038)
		(end 176.467516 -369.040664)
		(width 0.1651)
		(layer "In11.Cu")
		(net "P5E_PEX1_STN7_TX_C_DN<127>")
	)
	(segment
		(start 193.848482 -345.755976)
		(end 194.139312 -345.465146)
		(width 0.1651)
		(layer "In11.Cu")
		(net "P5E_PEX1_STN7_TX_C_DN<127>")
	)
	(segment
		(start 155.113736 -133.129782)
		(end 154.793696 -132.809742)
		(width 0.13462)
		(layer "F.Cu")
		(net "P5E_PEX1_STN1_TX_DP<29>")
	)
	(segment
		(start 154.793696 -132.809742)
		(end 154.162252 -132.809742)
		(width 0.13462)
		(layer "F.Cu")
		(net "P5E_PEX1_STN1_TX_DP<29>")
	)
	(segment
		(start 154.162252 -132.809742)
		(end 153.867612 -133.104382)
		(width 0.13462)
		(layer "F.Cu")
		(net "P5E_PEX1_STN1_TX_DP<29>")
	)
	(segment
		(start 150.993856 -139.910566)
		(end 151.143462 -139.972288)
		(width 0.1651)
		(layer "In9.Cu")
		(net "P5E_PEX1_STN1_TX_DP<29>")
	)
	(segment
		(start 151.811228 -142.956534)
		(end 151.835358 -143.451072)
		(width 0.1651)
		(layer "In9.Cu")
		(net "P5E_PEX1_STN1_TX_DP<29>")
	)
	(segment
		(start 151.99106 -146.610324)
		(end 152.01519 -147.104862)
		(width 0.1651)
		(layer "In9.Cu")
		(net "P5E_PEX1_STN1_TX_DP<29>")
	)
	(segment
		(start 151.955246 -145.886932)
		(end 152.075388 -145.99539)
		(width 0.1651)
		(layer "In9.Cu")
		(net "P5E_PEX1_STN1_TX_DP<29>")
	)
	(segment
		(start 188.099954 -280.015188)
		(end 188.099954 -279.749504)
		(width 0.1143)
		(layer "In9.Cu")
		(net "P5E_PEX1_STN1_TX_DP<29>")
	)
	(segment
		(start 152.135332 -147.213574)
		(end 152.159716 -147.708366)
		(width 0.1651)
		(layer "In9.Cu")
		(net "P5E_PEX1_STN1_TX_DP<29>")
	)
	(segment
		(start 152.099772 -146.490436)
		(end 151.99106 -146.610324)
		(width 0.1651)
		(layer "In9.Cu")
		(net "P5E_PEX1_STN1_TX_DP<29>")
	)
	(segment
		(start 187.765944 -271.554448)
		(end 187.720224 -271.600168)
		(width 0.1143)
		(layer "In9.Cu")
		(net "P5E_PEX1_STN1_TX_DP<29>")
	)
	(segment
		(start 151.931116 -145.392394)
		(end 151.955246 -145.886932)
		(width 0.1651)
		(layer "In9.Cu")
		(net "P5E_PEX1_STN1_TX_DP<29>")
	)
	(segment
		(start 151.895556 -142.3416)
		(end 151.91994 -142.836646)
		(width 0.1651)
		(layer "In9.Cu")
		(net "P5E_PEX1_STN1_TX_DP<29>")
	)
	(segment
		(start 151.775414 -142.233142)
		(end 151.895556 -142.3416)
		(width 0.1651)
		(layer "In9.Cu")
		(net "P5E_PEX1_STN1_TX_DP<29>")
	)
	(segment
		(start 187.720224 -271.600168)
		(end 187.720224 -280.025856)
		(width 0.1143)
		(layer "In9.Cu")
		(net "P5E_PEX1_STN1_TX_DP<29>")
	)
	(segment
		(start 152.546558 -132.927852)
		(end 152.063958 -132.927852)
		(width 0.1651)
		(layer "In9.Cu")
		(net "P5E_PEX1_STN1_TX_DP<29>")
	)
	(segment
		(start 152.660858 -132.813552)
		(end 152.546558 -132.927852)
		(width 0.1651)
		(layer "In9.Cu")
		(net "P5E_PEX1_STN1_TX_DP<29>")
	)
	(segment
		(start 152.051004 -147.828254)
		(end 152.485344 -156.661866)
		(width 0.1651)
		(layer "In9.Cu")
		(net "P5E_PEX1_STN1_TX_DP<29>")
	)
	(segment
		(start 150.866348 -139.30376)
		(end 150.804372 -139.453112)
		(width 0.1651)
		(layer "In9.Cu")
		(net "P5E_PEX1_STN1_TX_DP<29>")
	)
	(segment
		(start 151.949658 -132.813552)
		(end 151.389588 -132.813552)
		(width 0.1651)
		(layer "In9.Cu")
		(net "P5E_PEX1_STN1_TX_DP<29>")
	)
	(segment
		(start 153.576782 -132.813552)
		(end 152.660858 -132.813552)
		(width 0.1651)
		(layer "In9.Cu")
		(net "P5E_PEX1_STN1_TX_DP<29>")
	)
	(segment
		(start 151.871172 -144.174464)
		(end 151.895302 -144.669002)
		(width 0.1651)
		(layer "In9.Cu")
		(net "P5E_PEX1_STN1_TX_DP<29>")
	)
	(segment
		(start 151.895302 -144.669002)
		(end 152.015444 -144.77746)
		(width 0.1651)
		(layer "In9.Cu")
		(net "P5E_PEX1_STN1_TX_DP<29>")
	)
	(segment
		(start 152.039828 -145.272506)
		(end 151.931116 -145.392394)
		(width 0.1651)
		(layer "In9.Cu")
		(net "P5E_PEX1_STN1_TX_DP<29>")
	)
	(segment
		(start 187.720224 -280.025856)
		(end 187.823856 -280.129488)
		(width 0.1143)
		(layer "In9.Cu")
		(net "P5E_PEX1_STN1_TX_DP<29>")
	)
	(segment
		(start 152.01519 -147.104862)
		(end 152.135332 -147.213574)
		(width 0.1651)
		(layer "In9.Cu")
		(net "P5E_PEX1_STN1_TX_DP<29>")
	)
	(segment
		(start 151.9555 -143.55953)
		(end 151.979884 -144.054576)
		(width 0.1651)
		(layer "In9.Cu")
		(net "P5E_PEX1_STN1_TX_DP<29>")
	)
	(segment
		(start 187.823856 -280.129488)
		(end 187.985654 -280.129488)
		(width 0.1143)
		(layer "In9.Cu")
		(net "P5E_PEX1_STN1_TX_DP<29>")
	)
	(segment
		(start 187.985654 -280.129488)
		(end 188.099954 -280.015188)
		(width 0.1143)
		(layer "In9.Cu")
		(net "P5E_PEX1_STN1_TX_DP<29>")
	)
	(segment
		(start 151.751284 -141.738604)
		(end 151.775414 -142.233142)
		(width 0.1651)
		(layer "In9.Cu")
		(net "P5E_PEX1_STN1_TX_DP<29>")
	)
	(segment
		(start 187.765944 -263.170924)
		(end 187.765944 -271.526)
		(width 0.1651)
		(layer "In9.Cu")
		(net "P5E_PEX1_STN1_TX_DP<29>")
	)
	(segment
		(start 151.389588 -132.813552)
		(end 150.429976 -133.211062)
		(width 0.1651)
		(layer "In9.Cu")
		(net "P5E_PEX1_STN1_TX_DP<29>")
	)
	(segment
		(start 153.867612 -133.104382)
		(end 153.576782 -132.813552)
		(width 0.1651)
		(layer "In9.Cu")
		(net "P5E_PEX1_STN1_TX_DP<29>")
	)
	(segment
		(start 187.765944 -271.526)
		(end 187.765944 -271.554448)
		(width 0.1143)
		(layer "In9.Cu")
		(net "P5E_PEX1_STN1_TX_DP<29>")
	)
	(segment
		(start 153.58872 -162.20821)
		(end 187.765944 -263.170924)
		(width 0.1651)
		(layer "In9.Cu")
		(net "P5E_PEX1_STN1_TX_DP<29>")
	)
	(segment
		(start 149.155658 -134.799578)
		(end 149.155658 -135.473694)
		(width 0.1651)
		(layer "In9.Cu")
		(net "P5E_PEX1_STN1_TX_DP<29>")
	)
	(segment
		(start 151.332946 -140.43025)
		(end 151.271224 -140.579602)
		(width 0.1651)
		(layer "In9.Cu")
		(net "P5E_PEX1_STN1_TX_DP<29>")
	)
	(segment
		(start 151.835358 -143.451072)
		(end 151.9555 -143.55953)
		(width 0.1651)
		(layer "In9.Cu")
		(net "P5E_PEX1_STN1_TX_DP<29>")
	)
	(segment
		(start 152.159716 -147.708366)
		(end 152.051004 -147.828254)
		(width 0.1651)
		(layer "In9.Cu")
		(net "P5E_PEX1_STN1_TX_DP<29>")
	)
	(segment
		(start 151.979884 -144.054576)
		(end 151.871172 -144.174464)
		(width 0.1651)
		(layer "In9.Cu")
		(net "P5E_PEX1_STN1_TX_DP<29>")
	)
	(segment
		(start 150.429976 -133.211062)
		(end 149.377908 -134.26313)
		(width 0.1651)
		(layer "In9.Cu")
		(net "P5E_PEX1_STN1_TX_DP<29>")
	)
	(segment
		(start 151.91994 -142.836646)
		(end 151.811228 -142.956534)
		(width 0.1651)
		(layer "In9.Cu")
		(net "P5E_PEX1_STN1_TX_DP<29>")
	)
	(segment
		(start 151.143462 -139.972288)
		(end 151.332946 -140.43025)
		(width 0.1651)
		(layer "In9.Cu")
		(net "P5E_PEX1_STN1_TX_DP<29>")
	)
	(segment
		(start 150.676864 -138.846052)
		(end 150.866348 -139.30376)
		(width 0.1651)
		(layer "In9.Cu")
		(net "P5E_PEX1_STN1_TX_DP<29>")
	)
	(segment
		(start 149.377908 -134.26313)
		(end 149.155658 -134.799578)
		(width 0.1651)
		(layer "In9.Cu")
		(net "P5E_PEX1_STN1_TX_DP<29>")
	)
	(segment
		(start 152.063958 -132.927852)
		(end 151.949658 -132.813552)
		(width 0.1651)
		(layer "In9.Cu")
		(net "P5E_PEX1_STN1_TX_DP<29>")
	)
	(segment
		(start 151.271224 -140.579602)
		(end 151.751284 -141.738604)
		(width 0.1651)
		(layer "In9.Cu")
		(net "P5E_PEX1_STN1_TX_DP<29>")
	)
	(segment
		(start 152.485344 -156.661866)
		(end 153.58872 -162.20821)
		(width 0.1651)
		(layer "In9.Cu")
		(net "P5E_PEX1_STN1_TX_DP<29>")
	)
	(segment
		(start 150.804372 -139.453112)
		(end 150.993856 -139.910566)
		(width 0.1651)
		(layer "In9.Cu")
		(net "P5E_PEX1_STN1_TX_DP<29>")
	)
	(segment
		(start 149.155658 -135.473694)
		(end 150.527258 -138.784076)
		(width 0.1651)
		(layer "In9.Cu")
		(net "P5E_PEX1_STN1_TX_DP<29>")
	)
	(segment
		(start 152.075388 -145.99539)
		(end 152.099772 -146.490436)
		(width 0.1651)
		(layer "In9.Cu")
		(net "P5E_PEX1_STN1_TX_DP<29>")
	)
	(segment
		(start 152.015444 -144.77746)
		(end 152.039828 -145.272506)
		(width 0.1651)
		(layer "In9.Cu")
		(net "P5E_PEX1_STN1_TX_DP<29>")
	)
	(segment
		(start 150.527258 -138.784076)
		(end 150.676864 -138.846052)
		(width 0.1651)
		(layer "In9.Cu")
		(net "P5E_PEX1_STN1_TX_DP<29>")
	)
	(segment
		(start 118.648988 -343.365582)
		(end 118.648988 -342.734138)
		(width 0.13462)
		(layer "F.Cu")
		(net "P5E_PEX1_STN6_TX_DN<109>")
	)
	(segment
		(start 118.648988 -342.734138)
		(end 118.943628 -342.439498)
		(width 0.13462)
		(layer "F.Cu")
		(net "P5E_PEX1_STN6_TX_DN<109>")
	)
	(segment
		(start 118.969028 -343.685622)
		(end 118.648988 -343.365582)
		(width 0.13462)
		(layer "F.Cu")
		(net "P5E_PEX1_STN6_TX_DN<109>")
	)
	(segment
		(start 145.802096 -328.628248)
		(end 141.434058 -328.628248)
		(width 0.1651)
		(layer "In13.Cu")
		(net "P5E_PEX1_STN6_TX_DN<109>")
	)
	(segment
		(start 161.500058 -312.049922)
		(end 161.500058 -311.784492)
		(width 0.1143)
		(layer "In13.Cu")
		(net "P5E_PEX1_STN6_TX_DN<109>")
	)
	(segment
		(start 159.406336 -322.861686)
		(end 156.38272 -324.674484)
		(width 0.1651)
		(layer "In13.Cu")
		(net "P5E_PEX1_STN6_TX_DN<109>")
	)
	(segment
		(start 141.434058 -328.628248)
		(end 129.449068 -333.592678)
		(width 0.1651)
		(layer "In13.Cu")
		(net "P5E_PEX1_STN6_TX_DN<109>")
	)
	(segment
		(start 152.089104 -326.452992)
		(end 147.789392 -328.233786)
		(width 0.1651)
		(layer "In13.Cu")
		(net "P5E_PEX1_STN6_TX_DN<109>")
	)
	(segment
		(start 152.08885 -326.452738)
		(end 152.089104 -326.452992)
		(width 0.1651)
		(layer "In13.Cu")
		(net "P5E_PEX1_STN6_TX_DN<109>")
	)
	(segment
		(start 161.385758 -311.670192)
		(end 161.22396 -311.670192)
		(width 0.1143)
		(layer "In13.Cu")
		(net "P5E_PEX1_STN6_TX_DN<109>")
	)
	(segment
		(start 161.166048 -320.063114)
		(end 161.166048 -321.101974)
		(width 0.1651)
		(layer "In13.Cu")
		(net "P5E_PEX1_STN6_TX_DN<109>")
	)
	(segment
		(start 161.120328 -311.773824)
		(end 161.120328 -319.995296)
		(width 0.1143)
		(layer "In13.Cu")
		(net "P5E_PEX1_STN6_TX_DN<109>")
	)
	(segment
		(start 161.166048 -321.101974)
		(end 159.406336 -322.861686)
		(width 0.1651)
		(layer "In13.Cu")
		(net "P5E_PEX1_STN6_TX_DN<109>")
	)
	(segment
		(start 156.38272 -324.674484)
		(end 152.08885 -326.452738)
		(width 0.1651)
		(layer "In13.Cu")
		(net "P5E_PEX1_STN6_TX_DN<109>")
	)
	(segment
		(start 161.120328 -319.995296)
		(end 161.166048 -320.041016)
		(width 0.1143)
		(layer "In13.Cu")
		(net "P5E_PEX1_STN6_TX_DN<109>")
	)
	(segment
		(start 121.439432 -338.452206)
		(end 118.652798 -341.23884)
		(width 0.1651)
		(layer "In13.Cu")
		(net "P5E_PEX1_STN6_TX_DN<109>")
	)
	(segment
		(start 147.789392 -328.233786)
		(end 145.802096 -328.628248)
		(width 0.1651)
		(layer "In13.Cu")
		(net "P5E_PEX1_STN6_TX_DN<109>")
	)
	(segment
		(start 161.22396 -311.670192)
		(end 161.120328 -311.773824)
		(width 0.1143)
		(layer "In13.Cu")
		(net "P5E_PEX1_STN6_TX_DN<109>")
	)
	(segment
		(start 161.166048 -320.041016)
		(end 161.166048 -320.063114)
		(width 0.1143)
		(layer "In13.Cu")
		(net "P5E_PEX1_STN6_TX_DN<109>")
	)
	(segment
		(start 118.652798 -341.23884)
		(end 118.652798 -342.148668)
		(width 0.1651)
		(layer "In13.Cu")
		(net "P5E_PEX1_STN6_TX_DN<109>")
	)
	(segment
		(start 125.764544 -335.562194)
		(end 121.439432 -338.452206)
		(width 0.1651)
		(layer "In13.Cu")
		(net "P5E_PEX1_STN6_TX_DN<109>")
	)
	(segment
		(start 118.652798 -342.148668)
		(end 118.943628 -342.439498)
		(width 0.1651)
		(layer "In13.Cu")
		(net "P5E_PEX1_STN6_TX_DN<109>")
	)
	(segment
		(start 161.500058 -311.784492)
		(end 161.385758 -311.670192)
		(width 0.1143)
		(layer "In13.Cu")
		(net "P5E_PEX1_STN6_TX_DN<109>")
	)
	(segment
		(start 129.449068 -333.592678)
		(end 125.764544 -335.562194)
		(width 0.1651)
		(layer "In13.Cu")
		(net "P5E_PEX1_STN6_TX_DN<109>")
	)
	(segment
		(start 313.732164 -147.079208)
		(end 313.439556 -146.7866)
		(width 0.13462)
		(layer "F.Cu")
		(net "P5E_PEX2_STN0_TX_DP<10>")
	)
	(segment
		(start 312.804048 -146.7866)
		(end 312.48604 -147.104608)
		(width 0.13462)
		(layer "F.Cu")
		(net "P5E_PEX2_STN0_TX_DP<10>")
	)
	(segment
		(start 313.439556 -146.7866)
		(end 312.804048 -146.7866)
		(width 0.13462)
		(layer "F.Cu")
		(net "P5E_PEX2_STN0_TX_DP<10>")
	)
	(segment
		(start 319.56375 -149.41677)
		(end 319.83934 -149.829012)
		(width 0.1651)
		(layer "In9.Cu")
		(net "P5E_PEX2_STN0_TX_DP<10>")
	)
	(segment
		(start 311.183782 -271.554448)
		(end 311.229502 -271.600168)
		(width 0.1143)
		(layer "In9.Cu")
		(net "P5E_PEX2_STN0_TX_DP<10>")
	)
	(segment
		(start 312.14695 -268.773402)
		(end 311.183782 -271.09928)
		(width 0.1651)
		(layer "In9.Cu")
		(net "P5E_PEX2_STN0_TX_DP<10>")
	)
	(segment
		(start 312.14695 -260.76529)
		(end 312.14695 -268.773402)
		(width 0.1651)
		(layer "In9.Cu")
		(net "P5E_PEX2_STN0_TX_DP<10>")
	)
	(segment
		(start 312.672222 -177.504852)
		(end 312.672476 -177.504852)
		(width 0.1651)
		(layer "In9.Cu")
		(net "P5E_PEX2_STN0_TX_DP<10>")
	)
	(segment
		(start 311.183782 -271.09928)
		(end 311.183782 -271.526)
		(width 0.1651)
		(layer "In9.Cu")
		(net "P5E_PEX2_STN0_TX_DP<10>")
	)
	(segment
		(start 320.212974 -150.38832)
		(end 320.48831 -150.800562)
		(width 0.1651)
		(layer "In9.Cu")
		(net "P5E_PEX2_STN0_TX_DP<10>")
	)
	(segment
		(start 320.237612 -150.26513)
		(end 320.212974 -150.38832)
		(width 0.1651)
		(layer "In9.Cu")
		(net "P5E_PEX2_STN0_TX_DP<10>")
	)
	(segment
		(start 322.412106 -157.940248)
		(end 314.011818 -172.492162)
		(width 0.1651)
		(layer "In9.Cu")
		(net "P5E_PEX2_STN0_TX_DP<10>")
	)
	(segment
		(start 316.14237 -146.788378)
		(end 317.981584 -147.550124)
		(width 0.1651)
		(layer "In9.Cu")
		(net "P5E_PEX2_STN0_TX_DP<10>")
	)
	(segment
		(start 311.44464 -280.319988)
		(end 311.685432 -280.319988)
		(width 0.1143)
		(layer "In9.Cu")
		(net "P5E_PEX2_STN0_TX_DP<10>")
	)
	(segment
		(start 313.732164 -147.079208)
		(end 314.022994 -146.788378)
		(width 0.1651)
		(layer "In9.Cu")
		(net "P5E_PEX2_STN0_TX_DP<10>")
	)
	(segment
		(start 320.611754 -150.824946)
		(end 320.977006 -151.371808)
		(width 0.1651)
		(layer "In9.Cu")
		(net "P5E_PEX2_STN0_TX_DP<10>")
	)
	(segment
		(start 319.96253 -149.853396)
		(end 320.237612 -150.26513)
		(width 0.1651)
		(layer "In9.Cu")
		(net "P5E_PEX2_STN0_TX_DP<10>")
	)
	(segment
		(start 314.022994 -146.788378)
		(end 316.14237 -146.788378)
		(width 0.1651)
		(layer "In9.Cu")
		(net "P5E_PEX2_STN0_TX_DP<10>")
	)
	(segment
		(start 319.588388 -149.29358)
		(end 319.56375 -149.41677)
		(width 0.1651)
		(layer "In9.Cu")
		(net "P5E_PEX2_STN0_TX_DP<10>")
	)
	(segment
		(start 311.229502 -280.10485)
		(end 311.44464 -280.319988)
		(width 0.1143)
		(layer "In9.Cu")
		(net "P5E_PEX2_STN0_TX_DP<10>")
	)
	(segment
		(start 320.977006 -151.371808)
		(end 322.412106 -154.836622)
		(width 0.1651)
		(layer "In9.Cu")
		(net "P5E_PEX2_STN0_TX_DP<10>")
	)
	(segment
		(start 320.48831 -150.800562)
		(end 320.611754 -150.824946)
		(width 0.1651)
		(layer "In9.Cu")
		(net "P5E_PEX2_STN0_TX_DP<10>")
	)
	(segment
		(start 311.229502 -271.600168)
		(end 311.229502 -280.10485)
		(width 0.1143)
		(layer "In9.Cu")
		(net "P5E_PEX2_STN0_TX_DP<10>")
	)
	(segment
		(start 312.672476 -177.504852)
		(end 308.766718 -222.099124)
		(width 0.1651)
		(layer "In9.Cu")
		(net "P5E_PEX2_STN0_TX_DP<10>")
	)
	(segment
		(start 314.011818 -172.492162)
		(end 312.674508 -177.47996)
		(width 0.1651)
		(layer "In9.Cu")
		(net "P5E_PEX2_STN0_TX_DP<10>")
	)
	(segment
		(start 319.313306 -148.881846)
		(end 319.588388 -149.29358)
		(width 0.1651)
		(layer "In9.Cu")
		(net "P5E_PEX2_STN0_TX_DP<10>")
	)
	(segment
		(start 322.412106 -154.836622)
		(end 322.412106 -157.940248)
		(width 0.1651)
		(layer "In9.Cu")
		(net "P5E_PEX2_STN0_TX_DP<10>")
	)
	(segment
		(start 308.766718 -222.099124)
		(end 312.14695 -260.76529)
		(width 0.1651)
		(layer "In9.Cu")
		(net "P5E_PEX2_STN0_TX_DP<10>")
	)
	(segment
		(start 319.83934 -149.829012)
		(end 319.96253 -149.853396)
		(width 0.1651)
		(layer "In9.Cu")
		(net "P5E_PEX2_STN0_TX_DP<10>")
	)
	(segment
		(start 317.981584 -147.550124)
		(end 319.313306 -148.881846)
		(width 0.1651)
		(layer "In9.Cu")
		(net "P5E_PEX2_STN0_TX_DP<10>")
	)
	(segment
		(start 311.183782 -271.526)
		(end 311.183782 -271.554448)
		(width 0.1143)
		(layer "In9.Cu")
		(net "P5E_PEX2_STN0_TX_DP<10>")
	)
	(segment
		(start 312.674508 -177.47996)
		(end 312.672222 -177.504852)
		(width 0.1651)
		(layer "In9.Cu")
		(net "P5E_PEX2_STN0_TX_DP<10>")
	)
	(segment
		(start 311.799732 -280.434288)
		(end 311.799732 -280.699718)
		(width 0.1143)
		(layer "In9.Cu")
		(net "P5E_PEX2_STN0_TX_DP<10>")
	)
	(segment
		(start 311.685432 -280.319988)
		(end 311.799732 -280.434288)
		(width 0.1143)
		(layer "In9.Cu")
		(net "P5E_PEX2_STN0_TX_DP<10>")
	)
	(segment
		(start 315.906404 -348.88043)
		(end 315.611764 -348.58579)
		(width 0.13462)
		(layer "F.Cu")
		(net "P5E_PEX2_STN6_TX_DP<110>")
	)
	(segment
		(start 315.906404 -349.511874)
		(end 315.906404 -348.88043)
		(width 0.13462)
		(layer "F.Cu")
		(net "P5E_PEX2_STN6_TX_DP<110>")
	)
	(segment
		(start 315.586364 -349.831914)
		(end 315.906404 -349.511874)
		(width 0.13462)
		(layer "F.Cu")
		(net "P5E_PEX2_STN6_TX_DP<110>")
	)
	(segment
		(start 276.079458 -319.921128)
		(end 276.079458 -313.59475)
		(width 0.1143)
		(layer "In13.Cu")
		(net "P5E_PEX2_STN6_TX_DP<110>")
	)
	(segment
		(start 315.902594 -348.29496)
		(end 315.902594 -347.784674)
		(width 0.1651)
		(layer "In13.Cu")
		(net "P5E_PEX2_STN6_TX_DP<110>")
	)
	(segment
		(start 276.033738 -325.764398)
		(end 276.033738 -319.995296)
		(width 0.1651)
		(layer "In13.Cu")
		(net "P5E_PEX2_STN6_TX_DP<110>")
	)
	(segment
		(start 276.649688 -313.265312)
		(end 276.649688 -312.999882)
		(width 0.1143)
		(layer "In13.Cu")
		(net "P5E_PEX2_STN6_TX_DP<110>")
	)
	(segment
		(start 312.812684 -340.153244)
		(end 311.712102 -339.577426)
		(width 0.1651)
		(layer "In13.Cu")
		(net "P5E_PEX2_STN6_TX_DP<110>")
	)
	(segment
		(start 315.611764 -348.58579)
		(end 315.902594 -348.29496)
		(width 0.1651)
		(layer "In13.Cu")
		(net "P5E_PEX2_STN6_TX_DP<110>")
	)
	(segment
		(start 277.2156 -328.61758)
		(end 276.033738 -325.764398)
		(width 0.1651)
		(layer "In13.Cu")
		(net "P5E_PEX2_STN6_TX_DP<110>")
	)
	(segment
		(start 276.079458 -313.59475)
		(end 276.294596 -313.379612)
		(width 0.1143)
		(layer "In13.Cu")
		(net "P5E_PEX2_STN6_TX_DP<110>")
	)
	(segment
		(start 276.033738 -319.995296)
		(end 276.033738 -319.966848)
		(width 0.1143)
		(layer "In13.Cu")
		(net "P5E_PEX2_STN6_TX_DP<110>")
	)
	(segment
		(start 276.294596 -313.379612)
		(end 276.535388 -313.379612)
		(width 0.1143)
		(layer "In13.Cu")
		(net "P5E_PEX2_STN6_TX_DP<110>")
	)
	(segment
		(start 282.480004 -333.881984)
		(end 277.2156 -328.61758)
		(width 0.1651)
		(layer "In13.Cu")
		(net "P5E_PEX2_STN6_TX_DP<110>")
	)
	(segment
		(start 314.348114 -341.757)
		(end 312.812684 -340.153244)
		(width 0.1651)
		(layer "In13.Cu")
		(net "P5E_PEX2_STN6_TX_DP<110>")
	)
	(segment
		(start 314.348114 -346.230194)
		(end 314.348114 -341.757)
		(width 0.1651)
		(layer "In13.Cu")
		(net "P5E_PEX2_STN6_TX_DP<110>")
	)
	(segment
		(start 311.712102 -339.577426)
		(end 282.480004 -333.881984)
		(width 0.1651)
		(layer "In13.Cu")
		(net "P5E_PEX2_STN6_TX_DP<110>")
	)
	(segment
		(start 315.902594 -347.784674)
		(end 314.348114 -346.230194)
		(width 0.1651)
		(layer "In13.Cu")
		(net "P5E_PEX2_STN6_TX_DP<110>")
	)
	(segment
		(start 276.535388 -313.379612)
		(end 276.649688 -313.265312)
		(width 0.1143)
		(layer "In13.Cu")
		(net "P5E_PEX2_STN6_TX_DP<110>")
	)
	(segment
		(start 276.033738 -319.966848)
		(end 276.079458 -319.921128)
		(width 0.1143)
		(layer "In13.Cu")
		(net "P5E_PEX2_STN6_TX_DP<110>")
	)
	(segment
		(start 343.334086 -371.812312)
		(end 343.334086 -369.832382)
		(width 0.1651)
		(layer "In5.Cu")
		(net "P5E_PEX2_STN5_RX_DP<93>")
	)
	(segment
		(start 345.49842 -357.575612)
		(end 345.67241 -342.8111)
		(width 0.1651)
		(layer "In5.Cu")
		(net "P5E_PEX2_STN5_RX_DP<93>")
	)
	(segment
		(start 302.633888 -319.969896)
		(end 302.633888 -319.941448)
		(width 0.1143)
		(layer "In5.Cu")
		(net "P5E_PEX2_STN5_RX_DP<93>")
	)
	(segment
		(start 302.679608 -319.895728)
		(end 302.679608 -318.355472)
		(width 0.1143)
		(layer "In5.Cu")
		(net "P5E_PEX2_STN5_RX_DP<93>")
	)
	(segment
		(start 344.815668 -361.442)
		(end 345.49842 -357.575612)
		(width 0.1651)
		(layer "In5.Cu")
		(net "P5E_PEX2_STN5_RX_DP<93>")
	)
	(segment
		(start 342.490044 -371.590062)
		(end 342.490044 -371.972078)
		(width 0.1651)
		(layer "In5.Cu")
		(net "P5E_PEX2_STN5_RX_DP<93>")
	)
	(segment
		(start 343.334086 -369.832382)
		(end 343.668858 -367.935764)
		(width 0.1651)
		(layer "In5.Cu")
		(net "P5E_PEX2_STN5_RX_DP<93>")
	)
	(segment
		(start 345.21267 -341.704168)
		(end 344.56243 -341.060024)
		(width 0.1651)
		(layer "In5.Cu")
		(net "P5E_PEX2_STN5_RX_DP<93>")
	)
	(segment
		(start 304.170334 -322.473828)
		(end 302.896524 -321.19951)
		(width 0.1651)
		(layer "In5.Cu")
		(net "P5E_PEX2_STN5_RX_DP<93>")
	)
	(segment
		(start 343.87663 -366.759998)
		(end 343.79408 -366.642396)
		(width 0.1651)
		(layer "In5.Cu")
		(net "P5E_PEX2_STN5_RX_DP<93>")
	)
	(segment
		(start 344.64117 -361.99191)
		(end 344.727276 -361.503976)
		(width 0.1651)
		(layer "In5.Cu")
		(net "P5E_PEX2_STN5_RX_DP<93>")
	)
	(segment
		(start 303.249838 -318.015366)
		(end 303.249838 -317.749936)
		(width 0.1143)
		(layer "In5.Cu")
		(net "P5E_PEX2_STN5_RX_DP<93>")
	)
	(segment
		(start 302.679608 -318.355472)
		(end 302.905414 -318.129666)
		(width 0.1143)
		(layer "In5.Cu")
		(net "P5E_PEX2_STN5_RX_DP<93>")
	)
	(segment
		(start 344.727276 -361.503976)
		(end 344.815668 -361.442)
		(width 0.1651)
		(layer "In5.Cu")
		(net "P5E_PEX2_STN5_RX_DP<93>")
	)
	(segment
		(start 302.905414 -318.129666)
		(end 303.135538 -318.129666)
		(width 0.1143)
		(layer "In5.Cu")
		(net "P5E_PEX2_STN5_RX_DP<93>")
	)
	(segment
		(start 343.672668 -367.330228)
		(end 343.790524 -367.247678)
		(width 0.1651)
		(layer "In5.Cu")
		(net "P5E_PEX2_STN5_RX_DP<93>")
	)
	(segment
		(start 343.880186 -366.154208)
		(end 343.998296 -366.071912)
		(width 0.1651)
		(layer "In5.Cu")
		(net "P5E_PEX2_STN5_RX_DP<93>")
	)
	(segment
		(start 343.79408 -366.642396)
		(end 343.880186 -366.154208)
		(width 0.1651)
		(layer "In5.Cu")
		(net "P5E_PEX2_STN5_RX_DP<93>")
	)
	(segment
		(start 342.490044 -371.972078)
		(end 342.617044 -372.099078)
		(width 0.1651)
		(layer "In5.Cu")
		(net "P5E_PEX2_STN5_RX_DP<93>")
	)
	(segment
		(start 342.617044 -372.099078)
		(end 343.04732 -372.099078)
		(width 0.1651)
		(layer "In5.Cu")
		(net "P5E_PEX2_STN5_RX_DP<93>")
	)
	(segment
		(start 343.586562 -367.818162)
		(end 343.672668 -367.330228)
		(width 0.1651)
		(layer "In5.Cu")
		(net "P5E_PEX2_STN5_RX_DP<93>")
	)
	(segment
		(start 344.702892 -362.080302)
		(end 344.64117 -361.99191)
		(width 0.1651)
		(layer "In5.Cu")
		(net "P5E_PEX2_STN5_RX_DP<93>")
	)
	(segment
		(start 343.04732 -372.099078)
		(end 343.334086 -371.812312)
		(width 0.1651)
		(layer "In5.Cu")
		(net "P5E_PEX2_STN5_RX_DP<93>")
	)
	(segment
		(start 343.668858 -367.935764)
		(end 343.586562 -367.818162)
		(width 0.1651)
		(layer "In5.Cu")
		(net "P5E_PEX2_STN5_RX_DP<93>")
	)
	(segment
		(start 302.633888 -319.941448)
		(end 302.679608 -319.895728)
		(width 0.1143)
		(layer "In5.Cu")
		(net "P5E_PEX2_STN5_RX_DP<93>")
	)
	(segment
		(start 303.135538 -318.129666)
		(end 303.249838 -318.015366)
		(width 0.1143)
		(layer "In5.Cu")
		(net "P5E_PEX2_STN5_RX_DP<93>")
	)
	(segment
		(start 343.998296 -366.071912)
		(end 343.998042 -366.071912)
		(width 0.1651)
		(layer "In5.Cu")
		(net "P5E_PEX2_STN5_RX_DP<93>")
	)
	(segment
		(start 302.633888 -320.56578)
		(end 302.633888 -319.969896)
		(width 0.1651)
		(layer "In5.Cu")
		(net "P5E_PEX2_STN5_RX_DP<93>")
	)
	(segment
		(start 344.56243 -341.060024)
		(end 304.170334 -322.473828)
		(width 0.1651)
		(layer "In5.Cu")
		(net "P5E_PEX2_STN5_RX_DP<93>")
	)
	(segment
		(start 302.896524 -321.19951)
		(end 302.633888 -320.56578)
		(width 0.1651)
		(layer "In5.Cu")
		(net "P5E_PEX2_STN5_RX_DP<93>")
	)
	(segment
		(start 343.790524 -367.247678)
		(end 343.87663 -366.759998)
		(width 0.1651)
		(layer "In5.Cu")
		(net "P5E_PEX2_STN5_RX_DP<93>")
	)
	(segment
		(start 343.998042 -366.071912)
		(end 344.702892 -362.080302)
		(width 0.1651)
		(layer "In5.Cu")
		(net "P5E_PEX2_STN5_RX_DP<93>")
	)
	(segment
		(start 345.67241 -342.8111)
		(end 345.21267 -341.704168)
		(width 0.1651)
		(layer "In5.Cu")
		(net "P5E_PEX2_STN5_RX_DP<93>")
	)
	(segment
		(start 270.062452 -116.7384)
		(end 270.560292 -116.7384)
		(width 0.13208)
		(layer "F.Cu")
		(net "PRSNT_NIC4_N")
	)
	(segment
		(start 265.205972 -118.0592)
		(end 264.517632 -117.37086)
		(width 0.13208)
		(layer "F.Cu")
		(net "PRSNT_NIC4_N")
	)
	(segment
		(start 284.699964 -116.92509)
		(end 285.850838 -115.774216)
		(width 0.13208)
		(layer "F.Cu")
		(net "PRSNT_NIC4_N")
	)
	(segment
		(start 270.751808 -116.214652)
		(end 273.49577 -116.214652)
		(width 0.13208)
		(layer "F.Cu")
		(net "PRSNT_NIC4_N")
	)
	(segment
		(start 288.479992 -137.414)
		(end 288.606992 -137.287)
		(width 0.13208)
		(layer "F.Cu")
		(net "PRSNT_NIC4_N")
	)
	(segment
		(start 273.49577 -116.214652)
		(end 274.206208 -116.92509)
		(width 0.13208)
		(layer "F.Cu")
		(net "PRSNT_NIC4_N")
	)
	(segment
		(start 285.850838 -115.774216)
		(end 288.429192 -115.774216)
		(width 0.13208)
		(layer "F.Cu")
		(net "PRSNT_NIC4_N")
	)
	(segment
		(start 268.522958 -118.0592)
		(end 265.205972 -118.0592)
		(width 0.13208)
		(layer "F.Cu")
		(net "PRSNT_NIC4_N")
	)
	(segment
		(start 264.517632 -117.37086)
		(end 264.517632 -115.736624)
		(width 0.13208)
		(layer "F.Cu")
		(net "PRSNT_NIC4_N")
	)
	(segment
		(start 270.560292 -116.7384)
		(end 270.560292 -116.406168)
		(width 0.13208)
		(layer "F.Cu")
		(net "PRSNT_NIC4_N")
	)
	(segment
		(start 288.429192 -115.774216)
		(end 288.429192 -116.5352)
		(width 0.13208)
		(layer "F.Cu")
		(net "PRSNT_NIC4_N")
	)
	(segment
		(start 269.836646 -116.512594)
		(end 270.062452 -116.7384)
		(width 0.13208)
		(layer "F.Cu")
		(net "PRSNT_NIC4_N")
	)
	(segment
		(start 288.606992 -137.287)
		(end 289.349942 -137.287)
		(width 0.13208)
		(layer "F.Cu")
		(net "PRSNT_NIC4_N")
	)
	(segment
		(start 270.560292 -116.406168)
		(end 270.751808 -116.214652)
		(width 0.13208)
		(layer "F.Cu")
		(net "PRSNT_NIC4_N")
	)
	(segment
		(start 274.206208 -116.92509)
		(end 284.699964 -116.92509)
		(width 0.13208)
		(layer "F.Cu")
		(net "PRSNT_NIC4_N")
	)
	(segment
		(start 269.807436 -96.1644)
		(end 270.560292 -96.1644)
		(width 0.13208)
		(layer "F.Cu")
		(net "PRSNT_NIC4_N")
	)
	(segment
		(start 269.836646 -116.536978)
		(end 269.485618 -116.888006)
		(width 0.13208)
		(layer "F.Cu")
		(net "PRSNT_NIC4_N")
	)
	(segment
		(start 269.836646 -116.512594)
		(end 269.836646 -116.536978)
		(width 0.13208)
		(layer "F.Cu")
		(net "PRSNT_NIC4_N")
	)
	(segment
		(start 269.485618 -116.888006)
		(end 269.485618 -117.09654)
		(width 0.13208)
		(layer "F.Cu")
		(net "PRSNT_NIC4_N")
	)
	(segment
		(start 269.485618 -117.09654)
		(end 268.522958 -118.0592)
		(width 0.13208)
		(layer "F.Cu")
		(net "PRSNT_NIC4_N")
	)
	(segment
		(start 288.479992 -138.6332)
		(end 288.479992 -137.414)
		(width 0.13208)
		(layer "F.Cu")
		(net "PRSNT_NIC4_N")
	)
	(via
		(at 269.836646 -116.512594)
		(size 0.508)
		(drill 0.254)
		(layers "F.Cu" "B.Cu")
		(net "PRSNT_NIC4_N")
	)
	(via
		(at 269.807436 -96.1644)
		(size 0.508)
		(drill 0.254)
		(layers "F.Cu" "B.Cu")
		(net "PRSNT_NIC4_N")
	)
	(via
		(at 289.349942 -137.287)
		(size 0.508)
		(drill 0.254)
		(layers "F.Cu" "B.Cu")
		(net "PRSNT_NIC4_N")
	)
	(via
		(at 288.429192 -115.774216)
		(size 0.508)
		(drill 0.254)
		(layers "F.Cu" "B.Cu")
		(net "PRSNT_NIC4_N")
	)
	(segment
		(start 288.206942 -136.144)
		(end 289.349942 -137.287)
		(width 0.15494)
		(layer "In9.Cu")
		(net "PRSNT_NIC4_N")
	)
	(segment
		(start 271.483328 -97.840292)
		(end 269.807436 -96.1644)
		(width 0.15494)
		(layer "In9.Cu")
		(net "PRSNT_NIC4_N")
	)
	(segment
		(start 288.429192 -116.616988)
		(end 289.967416 -118.155212)
		(width 0.15494)
		(layer "In9.Cu")
		(net "PRSNT_NIC4_N")
	)
	(segment
		(start 289.967416 -118.155212)
		(end 289.967416 -132.47878)
		(width 0.15494)
		(layer "In9.Cu")
		(net "PRSNT_NIC4_N")
	)
	(segment
		(start 269.836646 -116.512594)
		(end 270.423132 -116.512594)
		(width 0.15494)
		(layer "In9.Cu")
		(net "PRSNT_NIC4_N")
	)
	(segment
		(start 288.429192 -115.774216)
		(end 288.429192 -116.616988)
		(width 0.15494)
		(layer "In9.Cu")
		(net "PRSNT_NIC4_N")
	)
	(segment
		(start 271.483328 -115.452398)
		(end 271.483328 -97.840292)
		(width 0.15494)
		(layer "In9.Cu")
		(net "PRSNT_NIC4_N")
	)
	(segment
		(start 270.423132 -116.512594)
		(end 271.483328 -115.452398)
		(width 0.15494)
		(layer "In9.Cu")
		(net "PRSNT_NIC4_N")
	)
	(segment
		(start 289.967416 -132.47878)
		(end 288.206942 -134.239254)
		(width 0.15494)
		(layer "In9.Cu")
		(net "PRSNT_NIC4_N")
	)
	(segment
		(start 288.206942 -134.239254)
		(end 288.206942 -136.144)
		(width 0.15494)
		(layer "In9.Cu")
		(net "PRSNT_NIC4_N")
	)
	(segment
		(start 199.979534 -144.716754)
		(end 200.274174 -144.422114)
		(width 0.13462)
		(layer "F.Cu")
		(net "P5E_PEX1_STN0_TX_DN<9>")
	)
	(segment
		(start 199.34809 -144.716754)
		(end 199.979534 -144.716754)
		(width 0.13462)
		(layer "F.Cu")
		(net "P5E_PEX1_STN0_TX_DN<9>")
	)
	(segment
		(start 199.02805 -144.396714)
		(end 199.34809 -144.716754)
		(width 0.13462)
		(layer "F.Cu")
		(net "P5E_PEX1_STN0_TX_DN<9>")
	)
	(segment
		(start 196.316092 -271.357344)
		(end 196.316092 -271.471898)
		(width 0.1651)
		(layer "In9.Cu")
		(net "P5E_PEX1_STN0_TX_DN<9>")
	)
	(segment
		(start 196.270372 -278.12619)
		(end 196.37375 -278.229568)
		(width 0.1143)
		(layer "In9.Cu")
		(net "P5E_PEX1_STN0_TX_DN<9>")
	)
	(segment
		(start 199.078596 -172.971714)
		(end 197.79869 -177.74412)
		(width 0.1651)
		(layer "In9.Cu")
		(net "P5E_PEX1_STN0_TX_DN<9>")
	)
	(segment
		(start 196.535548 -278.229568)
		(end 196.649848 -278.115268)
		(width 0.1143)
		(layer "In9.Cu")
		(net "P5E_PEX1_STN0_TX_DN<9>")
	)
	(segment
		(start 196.316092 -271.471898)
		(end 196.316092 -271.500346)
		(width 0.1143)
		(layer "In9.Cu")
		(net "P5E_PEX1_STN0_TX_DN<9>")
	)
	(segment
		(start 207.561942 -158.27502)
		(end 199.078596 -172.971714)
		(width 0.1651)
		(layer "In9.Cu")
		(net "P5E_PEX1_STN0_TX_DN<9>")
	)
	(segment
		(start 196.270372 -271.546066)
		(end 196.270372 -278.12619)
		(width 0.1143)
		(layer "In9.Cu")
		(net "P5E_PEX1_STN0_TX_DN<9>")
	)
	(segment
		(start 196.649848 -278.115268)
		(end 196.649848 -277.849838)
		(width 0.1143)
		(layer "In9.Cu")
		(net "P5E_PEX1_STN0_TX_DN<9>")
	)
	(segment
		(start 197.296786 -260.314694)
		(end 197.296786 -268.989302)
		(width 0.1651)
		(layer "In9.Cu")
		(net "P5E_PEX1_STN0_TX_DN<9>")
	)
	(segment
		(start 197.79869 -177.74412)
		(end 193.935604 -221.85376)
		(width 0.1651)
		(layer "In9.Cu")
		(net "P5E_PEX1_STN0_TX_DN<9>")
	)
	(segment
		(start 196.37375 -278.229568)
		(end 196.535548 -278.229568)
		(width 0.1143)
		(layer "In9.Cu")
		(net "P5E_PEX1_STN0_TX_DN<9>")
	)
	(segment
		(start 207.561942 -154.593036)
		(end 207.561942 -158.27502)
		(width 0.1651)
		(layer "In9.Cu")
		(net "P5E_PEX1_STN0_TX_DN<9>")
	)
	(segment
		(start 205.885542 -150.546054)
		(end 207.561942 -154.593036)
		(width 0.1651)
		(layer "In9.Cu")
		(net "P5E_PEX1_STN0_TX_DN<9>")
	)
	(segment
		(start 203.427584 -146.867626)
		(end 205.885542 -150.546054)
		(width 0.1651)
		(layer "In9.Cu")
		(net "P5E_PEX1_STN0_TX_DN<9>")
	)
	(segment
		(start 196.316092 -271.500346)
		(end 196.270372 -271.546066)
		(width 0.1143)
		(layer "In9.Cu")
		(net "P5E_PEX1_STN0_TX_DN<9>")
	)
	(segment
		(start 197.296786 -268.989302)
		(end 196.316092 -271.357344)
		(width 0.1651)
		(layer "In9.Cu")
		(net "P5E_PEX1_STN0_TX_DN<9>")
	)
	(segment
		(start 193.935604 -221.85376)
		(end 197.296786 -260.314694)
		(width 0.1651)
		(layer "In9.Cu")
		(net "P5E_PEX1_STN0_TX_DN<9>")
	)
	(segment
		(start 200.274174 -144.422114)
		(end 200.565004 -144.712944)
		(width 0.1651)
		(layer "In9.Cu")
		(net "P5E_PEX1_STN0_TX_DN<9>")
	)
	(segment
		(start 201.272902 -144.712944)
		(end 203.427584 -146.867626)
		(width 0.1651)
		(layer "In9.Cu")
		(net "P5E_PEX1_STN0_TX_DN<9>")
	)
	(segment
		(start 200.565004 -144.712944)
		(end 201.272902 -144.712944)
		(width 0.1651)
		(layer "In9.Cu")
		(net "P5E_PEX1_STN0_TX_DN<9>")
	)
	(segment
		(start 168.972992 -355.658166)
		(end 168.972992 -355.026722)
		(width 0.13462)
		(layer "F.Cu")
		(net "P5E_PEX1_STN7_TX_DN<116>")
	)
	(segment
		(start 169.293032 -355.978206)
		(end 168.972992 -355.658166)
		(width 0.13462)
		(layer "F.Cu")
		(net "P5E_PEX1_STN7_TX_DN<116>")
	)
	(segment
		(start 168.972992 -355.026722)
		(end 169.267632 -354.732082)
		(width 0.13462)
		(layer "F.Cu")
		(net "P5E_PEX1_STN7_TX_DN<116>")
	)
	(segment
		(start 142.032228 -310.187086)
		(end 142.156434 -310.168544)
		(width 0.1651)
		(layer "In11.Cu")
		(net "P5E_PEX1_STN7_TX_DN<116>")
	)
	(segment
		(start 140.342874 -312.46064)
		(end 140.638276 -312.06313)
		(width 0.1651)
		(layer "In11.Cu")
		(net "P5E_PEX1_STN7_TX_DN<116>")
	)
	(segment
		(start 169.267632 -354.732082)
		(end 168.976802 -354.441252)
		(width 0.1651)
		(layer "In11.Cu")
		(net "P5E_PEX1_STN7_TX_DN<116>")
	)
	(segment
		(start 168.976802 -354.441252)
		(end 168.976802 -353.863402)
		(width 0.1651)
		(layer "In11.Cu")
		(net "P5E_PEX1_STN7_TX_DN<116>")
	)
	(segment
		(start 143.256 -308.722268)
		(end 143.399764 -308.722268)
		(width 0.1651)
		(layer "In11.Cu")
		(net "P5E_PEX1_STN7_TX_DN<116>")
	)
	(segment
		(start 143.185896 -330.052172)
		(end 140.048996 -328.01814)
		(width 0.1651)
		(layer "In11.Cu")
		(net "P5E_PEX1_STN7_TX_DN<116>")
	)
	(segment
		(start 143.399764 -308.722268)
		(end 143.750284 -308.371748)
		(width 0.1651)
		(layer "In11.Cu")
		(net "P5E_PEX1_STN7_TX_DN<116>")
	)
	(segment
		(start 158.079694 -305.185318)
		(end 158.079694 -305.311048)
		(width 0.1143)
		(layer "In11.Cu")
		(net "P5E_PEX1_STN7_TX_DN<116>")
	)
	(segment
		(start 141.736826 -310.584596)
		(end 142.032228 -310.187086)
		(width 0.1651)
		(layer "In11.Cu")
		(net "P5E_PEX1_STN7_TX_DN<116>")
	)
	(segment
		(start 146.544284 -305.706272)
		(end 146.677126 -305.76139)
		(width 0.1651)
		(layer "In11.Cu")
		(net "P5E_PEX1_STN7_TX_DN<116>")
	)
	(segment
		(start 158.079694 -305.311048)
		(end 157.990794 -305.399948)
		(width 0.1143)
		(layer "In11.Cu")
		(net "P5E_PEX1_STN7_TX_DN<116>")
	)
	(segment
		(start 148.199348 -332.341728)
		(end 143.185896 -330.052172)
		(width 0.1651)
		(layer "In11.Cu")
		(net "P5E_PEX1_STN7_TX_DN<116>")
	)
	(segment
		(start 157.91434 -305.019964)
		(end 158.079694 -305.185318)
		(width 0.1143)
		(layer "In11.Cu")
		(net "P5E_PEX1_STN7_TX_DN<116>")
	)
	(segment
		(start 141.459458 -311.106566)
		(end 141.755368 -310.708802)
		(width 0.1651)
		(layer "In11.Cu")
		(net "P5E_PEX1_STN7_TX_DN<116>")
	)
	(segment
		(start 141.335252 -311.125108)
		(end 141.459458 -311.106566)
		(width 0.1651)
		(layer "In11.Cu")
		(net "P5E_PEX1_STN7_TX_DN<116>")
	)
	(segment
		(start 144.100296 -307.877972)
		(end 144.24406 -307.877972)
		(width 0.1651)
		(layer "In11.Cu")
		(net "P5E_PEX1_STN7_TX_DN<116>")
	)
	(segment
		(start 157.990794 -305.399948)
		(end 157.699964 -305.399948)
		(width 0.1143)
		(layer "In11.Cu")
		(net "P5E_PEX1_STN7_TX_DN<116>")
	)
	(segment
		(start 146.079464 -305.898804)
		(end 146.544284 -305.706272)
		(width 0.1651)
		(layer "In11.Cu")
		(net "P5E_PEX1_STN7_TX_DN<116>")
	)
	(segment
		(start 168.976802 -353.863402)
		(end 170.531282 -352.308922)
		(width 0.1651)
		(layer "In11.Cu")
		(net "P5E_PEX1_STN7_TX_DN<116>")
	)
	(segment
		(start 141.058392 -311.646824)
		(end 141.03985 -311.522618)
		(width 0.1651)
		(layer "In11.Cu")
		(net "P5E_PEX1_STN7_TX_DN<116>")
	)
	(segment
		(start 136.741662 -322.366132)
		(end 136.741662 -319.932304)
		(width 0.1651)
		(layer "In11.Cu")
		(net "P5E_PEX1_STN7_TX_DN<116>")
	)
	(segment
		(start 145.088356 -307.033676)
		(end 145.438876 -306.683156)
		(width 0.1651)
		(layer "In11.Cu")
		(net "P5E_PEX1_STN7_TX_DN<116>")
	)
	(segment
		(start 141.755368 -310.708802)
		(end 141.736826 -310.584596)
		(width 0.1651)
		(layer "In11.Cu")
		(net "P5E_PEX1_STN7_TX_DN<116>")
	)
	(segment
		(start 151.668734 -305.019964)
		(end 157.91434 -305.019964)
		(width 0.1143)
		(layer "In11.Cu")
		(net "P5E_PEX1_STN7_TX_DN<116>")
	)
	(segment
		(start 141.03985 -311.522618)
		(end 141.335252 -311.125108)
		(width 0.1651)
		(layer "In11.Cu")
		(net "P5E_PEX1_STN7_TX_DN<116>")
	)
	(segment
		(start 146.677126 -305.76139)
		(end 147.134834 -305.571398)
		(width 0.1651)
		(layer "In11.Cu")
		(net "P5E_PEX1_STN7_TX_DN<116>")
	)
	(segment
		(start 140.048996 -328.01814)
		(end 139.083542 -327.191116)
		(width 0.1651)
		(layer "In11.Cu")
		(net "P5E_PEX1_STN7_TX_DN<116>")
	)
	(segment
		(start 170.531282 -352.308922)
		(end 170.531282 -342.248744)
		(width 0.1651)
		(layer "In11.Cu")
		(net "P5E_PEX1_STN7_TX_DN<116>")
	)
	(segment
		(start 147.189952 -305.43881)
		(end 148.090636 -305.065684)
		(width 0.1651)
		(layer "In11.Cu")
		(net "P5E_PEX1_STN7_TX_DN<116>")
	)
	(segment
		(start 144.24406 -307.877972)
		(end 144.59458 -307.527452)
		(width 0.1651)
		(layer "In11.Cu")
		(net "P5E_PEX1_STN7_TX_DN<116>")
	)
	(segment
		(start 140.363956 -312.602626)
		(end 140.342874 -312.46064)
		(width 0.1651)
		(layer "In11.Cu")
		(net "P5E_PEX1_STN7_TX_DN<116>")
	)
	(segment
		(start 145.438876 -306.539392)
		(end 146.079464 -305.898804)
		(width 0.1651)
		(layer "In11.Cu")
		(net "P5E_PEX1_STN7_TX_DN<116>")
	)
	(segment
		(start 142.433802 -309.646574)
		(end 142.729204 -309.249064)
		(width 0.1651)
		(layer "In11.Cu")
		(net "P5E_PEX1_STN7_TX_DN<116>")
	)
	(segment
		(start 138.428476 -315.036454)
		(end 139.92606 -313.021472)
		(width 0.1651)
		(layer "In11.Cu")
		(net "P5E_PEX1_STN7_TX_DN<116>")
	)
	(segment
		(start 137.05586 -318.347852)
		(end 138.428476 -315.036454)
		(width 0.1651)
		(layer "In11.Cu")
		(net "P5E_PEX1_STN7_TX_DN<116>")
	)
	(segment
		(start 148.090636 -305.065684)
		(end 151.600916 -305.065684)
		(width 0.1651)
		(layer "In11.Cu")
		(net "P5E_PEX1_STN7_TX_DN<116>")
	)
	(segment
		(start 137.475214 -324.785228)
		(end 136.741662 -322.366132)
		(width 0.1651)
		(layer "In11.Cu")
		(net "P5E_PEX1_STN7_TX_DN<116>")
	)
	(segment
		(start 143.750284 -308.371748)
		(end 143.750284 -308.227984)
		(width 0.1651)
		(layer "In11.Cu")
		(net "P5E_PEX1_STN7_TX_DN<116>")
	)
	(segment
		(start 144.59458 -307.527452)
		(end 144.59458 -307.383688)
		(width 0.1651)
		(layer "In11.Cu")
		(net "P5E_PEX1_STN7_TX_DN<116>")
	)
	(segment
		(start 142.729204 -309.249064)
		(end 143.256 -308.722268)
		(width 0.1651)
		(layer "In11.Cu")
		(net "P5E_PEX1_STN7_TX_DN<116>")
	)
	(segment
		(start 142.156434 -310.168544)
		(end 142.452344 -309.77078)
		(width 0.1651)
		(layer "In11.Cu")
		(net "P5E_PEX1_STN7_TX_DN<116>")
	)
	(segment
		(start 140.638276 -312.06313)
		(end 140.762482 -312.044588)
		(width 0.1651)
		(layer "In11.Cu")
		(net "P5E_PEX1_STN7_TX_DN<116>")
	)
	(segment
		(start 136.741662 -319.932304)
		(end 137.05586 -318.347852)
		(width 0.1651)
		(layer "In11.Cu")
		(net "P5E_PEX1_STN7_TX_DN<116>")
	)
	(segment
		(start 144.59458 -307.383688)
		(end 144.944592 -307.033676)
		(width 0.1651)
		(layer "In11.Cu")
		(net "P5E_PEX1_STN7_TX_DN<116>")
	)
	(segment
		(start 143.750284 -308.227984)
		(end 144.100296 -307.877972)
		(width 0.1651)
		(layer "In11.Cu")
		(net "P5E_PEX1_STN7_TX_DN<116>")
	)
	(segment
		(start 139.083542 -327.191116)
		(end 137.475214 -324.785228)
		(width 0.1651)
		(layer "In11.Cu")
		(net "P5E_PEX1_STN7_TX_DN<116>")
	)
	(segment
		(start 170.214544 -341.298784)
		(end 169.564558 -340.432136)
		(width 0.1651)
		(layer "In11.Cu")
		(net "P5E_PEX1_STN7_TX_DN<116>")
	)
	(segment
		(start 169.564558 -340.432136)
		(end 167.91686 -339.652356)
		(width 0.1651)
		(layer "In11.Cu")
		(net "P5E_PEX1_STN7_TX_DN<116>")
	)
	(segment
		(start 147.134834 -305.571398)
		(end 147.189952 -305.43881)
		(width 0.1651)
		(layer "In11.Cu")
		(net "P5E_PEX1_STN7_TX_DN<116>")
	)
	(segment
		(start 170.531282 -342.248744)
		(end 170.214544 -341.298784)
		(width 0.1651)
		(layer "In11.Cu")
		(net "P5E_PEX1_STN7_TX_DN<116>")
	)
	(segment
		(start 151.623014 -305.065684)
		(end 151.668734 -305.019964)
		(width 0.1143)
		(layer "In11.Cu")
		(net "P5E_PEX1_STN7_TX_DN<116>")
	)
	(segment
		(start 139.92606 -313.021472)
		(end 140.0683 -313.00039)
		(width 0.1651)
		(layer "In11.Cu")
		(net "P5E_PEX1_STN7_TX_DN<116>")
	)
	(segment
		(start 145.438876 -306.683156)
		(end 145.438876 -306.539392)
		(width 0.1651)
		(layer "In11.Cu")
		(net "P5E_PEX1_STN7_TX_DN<116>")
	)
	(segment
		(start 151.600916 -305.065684)
		(end 151.623014 -305.065684)
		(width 0.1143)
		(layer "In11.Cu")
		(net "P5E_PEX1_STN7_TX_DN<116>")
	)
	(segment
		(start 167.91686 -339.652356)
		(end 148.199348 -332.341728)
		(width 0.1651)
		(layer "In11.Cu")
		(net "P5E_PEX1_STN7_TX_DN<116>")
	)
	(segment
		(start 140.0683 -313.00039)
		(end 140.363956 -312.602626)
		(width 0.1651)
		(layer "In11.Cu")
		(net "P5E_PEX1_STN7_TX_DN<116>")
	)
	(segment
		(start 144.944592 -307.033676)
		(end 145.088356 -307.033676)
		(width 0.1651)
		(layer "In11.Cu")
		(net "P5E_PEX1_STN7_TX_DN<116>")
	)
	(segment
		(start 140.762482 -312.044588)
		(end 141.058392 -311.646824)
		(width 0.1651)
		(layer "In11.Cu")
		(net "P5E_PEX1_STN7_TX_DN<116>")
	)
	(segment
		(start 142.452344 -309.77078)
		(end 142.433802 -309.646574)
		(width 0.1651)
		(layer "In11.Cu")
		(net "P5E_PEX1_STN7_TX_DN<116>")
	)
	(segment
		(start 269.96771 -110.977934)
		(end 270.257524 -110.68812)
		(width 0.13462)
		(layer "F.Cu")
		(net "P5E_PEX2_STN1_TX_DN<22>")
	)
	(segment
		(start 270.257524 -110.68812)
		(end 270.89862 -110.68812)
		(width 0.13462)
		(layer "F.Cu")
		(net "P5E_PEX2_STN1_TX_DN<22>")
	)
	(segment
		(start 270.89862 -110.68812)
		(end 271.213834 -111.003334)
		(width 0.13462)
		(layer "F.Cu")
		(net "P5E_PEX2_STN1_TX_DN<22>")
	)
	(segment
		(start 262.794242 -118.276878)
		(end 262.943848 -118.214902)
		(width 0.1651)
		(layer "In9.Cu")
		(net "P5E_PEX2_STN1_TX_DN<22>")
	)
	(segment
		(start 267.118338 -110.871762)
		(end 267.564108 -110.687104)
		(width 0.1651)
		(layer "In9.Cu")
		(net "P5E_PEX2_STN1_TX_DN<22>")
	)
	(segment
		(start 264.49909 -114.459512)
		(end 264.437368 -114.31016)
		(width 0.1651)
		(layer "In9.Cu")
		(net "P5E_PEX2_STN1_TX_DN<22>")
	)
	(segment
		(start 264.042144 -115.562634)
		(end 263.980422 -115.413282)
		(width 0.1651)
		(layer "In9.Cu")
		(net "P5E_PEX2_STN1_TX_DN<22>")
	)
	(segment
		(start 262.794242 -118.277386)
		(end 262.794242 -118.276878)
		(width 0.1651)
		(layer "In9.Cu")
		(net "P5E_PEX2_STN1_TX_DN<22>")
	)
	(segment
		(start 267.564108 -110.687104)
		(end 268.379702 -110.687104)
		(width 0.1651)
		(layer "In9.Cu")
		(net "P5E_PEX2_STN1_TX_DN<22>")
	)
	(segment
		(start 263.066784 -117.619526)
		(end 263.251188 -117.173756)
		(width 0.1651)
		(layer "In9.Cu")
		(net "P5E_PEX2_STN1_TX_DN<22>")
	)
	(segment
		(start 265.412982 -112.25276)
		(end 265.35126 -112.103408)
		(width 0.1651)
		(layer "In9.Cu")
		(net "P5E_PEX2_STN1_TX_DN<22>")
	)
	(segment
		(start 263.523476 -116.516404)
		(end 263.708134 -116.070634)
		(width 0.1651)
		(layer "In9.Cu")
		(net "P5E_PEX2_STN1_TX_DN<22>")
	)
	(segment
		(start 264.437368 -114.31016)
		(end 264.621772 -113.86439)
		(width 0.1651)
		(layer "In9.Cu")
		(net "P5E_PEX2_STN1_TX_DN<22>")
	)
	(segment
		(start 264.956036 -113.356136)
		(end 264.894314 -113.206784)
		(width 0.1651)
		(layer "In9.Cu")
		(net "P5E_PEX2_STN1_TX_DN<22>")
	)
	(segment
		(start 258.493514 -131.49326)
		(end 261.705598 -120.906032)
		(width 0.1651)
		(layer "In9.Cu")
		(net "P5E_PEX2_STN1_TX_DN<22>")
	)
	(segment
		(start 269.090902 -110.687104)
		(end 269.67688 -110.687104)
		(width 0.1651)
		(layer "In9.Cu")
		(net "P5E_PEX2_STN1_TX_DN<22>")
	)
	(segment
		(start 265.078718 -112.761014)
		(end 265.078718 -112.76076)
		(width 0.1651)
		(layer "In9.Cu")
		(net "P5E_PEX2_STN1_TX_DN<22>")
	)
	(segment
		(start 268.379702 -110.687104)
		(end 268.494002 -110.801404)
		(width 0.1651)
		(layer "In9.Cu")
		(net "P5E_PEX2_STN1_TX_DN<22>")
	)
	(segment
		(start 297.215814 -271.500346)
		(end 297.215814 -271.471898)
		(width 0.1143)
		(layer "In9.Cu")
		(net "P5E_PEX2_STN1_TX_DN<22>")
	)
	(segment
		(start 261.705598 -120.906032)
		(end 262.794242 -118.277386)
		(width 0.1651)
		(layer "In9.Cu")
		(net "P5E_PEX2_STN1_TX_DN<22>")
	)
	(segment
		(start 268.976602 -110.801404)
		(end 269.090902 -110.687104)
		(width 0.1651)
		(layer "In9.Cu")
		(net "P5E_PEX2_STN1_TX_DN<22>")
	)
	(segment
		(start 263.400794 -117.11178)
		(end 263.585452 -116.665756)
		(width 0.1651)
		(layer "In9.Cu")
		(net "P5E_PEX2_STN1_TX_DN<22>")
	)
	(segment
		(start 264.621772 -113.86439)
		(end 264.621772 -113.864136)
		(width 0.1651)
		(layer "In9.Cu")
		(net "P5E_PEX2_STN1_TX_DN<22>")
	)
	(segment
		(start 265.078718 -112.76076)
		(end 265.228324 -112.698784)
		(width 0.1651)
		(layer "In9.Cu")
		(net "P5E_PEX2_STN1_TX_DN<22>")
	)
	(segment
		(start 263.980422 -115.413282)
		(end 264.164826 -114.967512)
		(width 0.1651)
		(layer "In9.Cu")
		(net "P5E_PEX2_STN1_TX_DN<22>")
	)
	(segment
		(start 297.54957 -278.115268)
		(end 297.43527 -278.229568)
		(width 0.1143)
		(layer "In9.Cu")
		(net "P5E_PEX2_STN1_TX_DN<22>")
	)
	(segment
		(start 266.610338 -111.206026)
		(end 267.056616 -111.021368)
		(width 0.1651)
		(layer "In9.Cu")
		(net "P5E_PEX2_STN1_TX_DN<22>")
	)
	(segment
		(start 297.170094 -271.546066)
		(end 297.215814 -271.500346)
		(width 0.1143)
		(layer "In9.Cu")
		(net "P5E_PEX2_STN1_TX_DN<22>")
	)
	(segment
		(start 267.056616 -111.021368)
		(end 267.118338 -110.871762)
		(width 0.1651)
		(layer "In9.Cu")
		(net "P5E_PEX2_STN1_TX_DN<22>")
	)
	(segment
		(start 263.70788 -116.070634)
		(end 263.857486 -116.008658)
		(width 0.1651)
		(layer "In9.Cu")
		(net "P5E_PEX2_STN1_TX_DN<22>")
	)
	(segment
		(start 269.67688 -110.687104)
		(end 269.96771 -110.977934)
		(width 0.1651)
		(layer "In9.Cu")
		(net "P5E_PEX2_STN1_TX_DN<22>")
	)
	(segment
		(start 263.585452 -116.665756)
		(end 263.523476 -116.516404)
		(width 0.1651)
		(layer "In9.Cu")
		(net "P5E_PEX2_STN1_TX_DN<22>")
	)
	(segment
		(start 264.314432 -114.905536)
		(end 264.49909 -114.459512)
		(width 0.1651)
		(layer "In9.Cu")
		(net "P5E_PEX2_STN1_TX_DN<22>")
	)
	(segment
		(start 263.128506 -117.768878)
		(end 263.066784 -117.619526)
		(width 0.1651)
		(layer "In9.Cu")
		(net "P5E_PEX2_STN1_TX_DN<22>")
	)
	(segment
		(start 264.771378 -113.80216)
		(end 264.956036 -113.356136)
		(width 0.1651)
		(layer "In9.Cu")
		(net "P5E_PEX2_STN1_TX_DN<22>")
	)
	(segment
		(start 261.79399 -158.844488)
		(end 261.430008 -151.43353)
		(width 0.1651)
		(layer "In9.Cu")
		(net "P5E_PEX2_STN1_TX_DN<22>")
	)
	(segment
		(start 266.460986 -111.14405)
		(end 266.610338 -111.206026)
		(width 0.1651)
		(layer "In9.Cu")
		(net "P5E_PEX2_STN1_TX_DN<22>")
	)
	(segment
		(start 263.251188 -117.173756)
		(end 263.400794 -117.11178)
		(width 0.1651)
		(layer "In9.Cu")
		(net "P5E_PEX2_STN1_TX_DN<22>")
	)
	(segment
		(start 265.35126 -112.103408)
		(end 265.535664 -111.657638)
		(width 0.1651)
		(layer "In9.Cu")
		(net "P5E_PEX2_STN1_TX_DN<22>")
	)
	(segment
		(start 297.43527 -278.229568)
		(end 297.273472 -278.229568)
		(width 0.1143)
		(layer "In9.Cu")
		(net "P5E_PEX2_STN1_TX_DN<22>")
	)
	(segment
		(start 297.54957 -277.849838)
		(end 297.54957 -278.115268)
		(width 0.1143)
		(layer "In9.Cu")
		(net "P5E_PEX2_STN1_TX_DN<22>")
	)
	(segment
		(start 297.273472 -278.229568)
		(end 297.170094 -278.12619)
		(width 0.1143)
		(layer "In9.Cu")
		(net "P5E_PEX2_STN1_TX_DN<22>")
	)
	(segment
		(start 261.430008 -151.433276)
		(end 261.062978 -143.952976)
		(width 0.1651)
		(layer "In9.Cu")
		(net "P5E_PEX2_STN1_TX_DN<22>")
	)
	(segment
		(start 265.535664 -111.657638)
		(end 265.757914 -111.435388)
		(width 0.1651)
		(layer "In9.Cu")
		(net "P5E_PEX2_STN1_TX_DN<22>")
	)
	(segment
		(start 297.215814 -271.471898)
		(end 297.215814 -264.660634)
		(width 0.1651)
		(layer "In9.Cu")
		(net "P5E_PEX2_STN1_TX_DN<22>")
	)
	(segment
		(start 265.228324 -112.698784)
		(end 265.412982 -112.25276)
		(width 0.1651)
		(layer "In9.Cu")
		(net "P5E_PEX2_STN1_TX_DN<22>")
	)
	(segment
		(start 297.215814 -264.660634)
		(end 262.358886 -161.684716)
		(width 0.1651)
		(layer "In9.Cu")
		(net "P5E_PEX2_STN1_TX_DN<22>")
	)
	(segment
		(start 262.943848 -118.214902)
		(end 263.128506 -117.768878)
		(width 0.1651)
		(layer "In9.Cu")
		(net "P5E_PEX2_STN1_TX_DN<22>")
	)
	(segment
		(start 263.857486 -116.008658)
		(end 264.042144 -115.562634)
		(width 0.1651)
		(layer "In9.Cu")
		(net "P5E_PEX2_STN1_TX_DN<22>")
	)
	(segment
		(start 265.757914 -111.435388)
		(end 266.460986 -111.14405)
		(width 0.1651)
		(layer "In9.Cu")
		(net "P5E_PEX2_STN1_TX_DN<22>")
	)
	(segment
		(start 258.493514 -137.75055)
		(end 258.493514 -131.49326)
		(width 0.1651)
		(layer "In9.Cu")
		(net "P5E_PEX2_STN1_TX_DN<22>")
	)
	(segment
		(start 297.170094 -278.12619)
		(end 297.170094 -271.546066)
		(width 0.1143)
		(layer "In9.Cu")
		(net "P5E_PEX2_STN1_TX_DN<22>")
	)
	(segment
		(start 264.894314 -113.206784)
		(end 265.078718 -112.761014)
		(width 0.1651)
		(layer "In9.Cu")
		(net "P5E_PEX2_STN1_TX_DN<22>")
	)
	(segment
		(start 262.358886 -161.684716)
		(end 261.79399 -158.844488)
		(width 0.1651)
		(layer "In9.Cu")
		(net "P5E_PEX2_STN1_TX_DN<22>")
	)
	(segment
		(start 264.621772 -113.864136)
		(end 264.771378 -113.80216)
		(width 0.1651)
		(layer "In9.Cu")
		(net "P5E_PEX2_STN1_TX_DN<22>")
	)
	(segment
		(start 268.494002 -110.801404)
		(end 268.976602 -110.801404)
		(width 0.1651)
		(layer "In9.Cu")
		(net "P5E_PEX2_STN1_TX_DN<22>")
	)
	(segment
		(start 263.708134 -116.070634)
		(end 263.70788 -116.070634)
		(width 0.1651)
		(layer "In9.Cu")
		(net "P5E_PEX2_STN1_TX_DN<22>")
	)
	(segment
		(start 261.062978 -143.952976)
		(end 258.493514 -137.75055)
		(width 0.1651)
		(layer "In9.Cu")
		(net "P5E_PEX2_STN1_TX_DN<22>")
	)
	(segment
		(start 261.430008 -151.43353)
		(end 261.430008 -151.433276)
		(width 0.1651)
		(layer "In9.Cu")
		(net "P5E_PEX2_STN1_TX_DN<22>")
	)
	(segment
		(start 264.164826 -114.967512)
		(end 264.314432 -114.905536)
		(width 0.1651)
		(layer "In9.Cu")
		(net "P5E_PEX2_STN1_TX_DN<22>")
	)
	(segment
		(start 322.398644 -348.88043)
		(end 322.693284 -348.58579)
		(width 0.13462)
		(layer "F.Cu")
		(net "P5E_PEX2_STN6_TX_DN<107>")
	)
	(segment
		(start 322.718684 -349.831914)
		(end 322.398644 -349.511874)
		(width 0.13462)
		(layer "F.Cu")
		(net "P5E_PEX2_STN6_TX_DN<107>")
	)
	(segment
		(start 322.398644 -349.511874)
		(end 322.398644 -348.88043)
		(width 0.13462)
		(layer "F.Cu")
		(net "P5E_PEX2_STN6_TX_DN<107>")
	)
	(segment
		(start 323.956934 -342.0872)
		(end 322.7832 -340.4362)
		(width 0.1651)
		(layer "In13.Cu")
		(net "P5E_PEX2_STN6_TX_DN<107>")
	)
	(segment
		(start 283.887926 -330.573126)
		(end 280.057098 -326.742298)
		(width 0.1651)
		(layer "In13.Cu")
		(net "P5E_PEX2_STN6_TX_DN<107>")
	)
	(segment
		(start 322.693284 -348.58579)
		(end 322.402454 -348.29496)
		(width 0.1651)
		(layer "In13.Cu")
		(net "P5E_PEX2_STN6_TX_DN<107>")
	)
	(segment
		(start 322.402454 -348.29496)
		(end 322.402454 -347.784674)
		(width 0.1651)
		(layer "In13.Cu")
		(net "P5E_PEX2_STN6_TX_DN<107>")
	)
	(segment
		(start 322.402454 -347.784674)
		(end 323.956934 -346.230194)
		(width 0.1651)
		(layer "In13.Cu")
		(net "P5E_PEX2_STN6_TX_DN<107>")
	)
	(segment
		(start 314.475876 -336.600038)
		(end 288.43351 -331.46873)
		(width 0.1651)
		(layer "In13.Cu")
		(net "P5E_PEX2_STN6_TX_DN<107>")
	)
	(segment
		(start 280.057098 -326.742298)
		(end 279.165812 -324.590664)
		(width 0.1651)
		(layer "In13.Cu")
		(net "P5E_PEX2_STN6_TX_DN<107>")
	)
	(segment
		(start 279.499822 -311.784492)
		(end 279.499822 -312.049922)
		(width 0.1143)
		(layer "In13.Cu")
		(net "P5E_PEX2_STN6_TX_DN<107>")
	)
	(segment
		(start 322.7832 -340.4362)
		(end 314.475876 -336.600038)
		(width 0.1651)
		(layer "In13.Cu")
		(net "P5E_PEX2_STN6_TX_DN<107>")
	)
	(segment
		(start 279.165812 -319.966848)
		(end 279.120092 -319.921128)
		(width 0.1143)
		(layer "In13.Cu")
		(net "P5E_PEX2_STN6_TX_DN<107>")
	)
	(segment
		(start 287.747964 -331.333602)
		(end 283.887926 -330.573126)
		(width 0.1651)
		(layer "In13.Cu")
		(net "P5E_PEX2_STN6_TX_DN<107>")
	)
	(segment
		(start 279.385522 -311.670192)
		(end 279.499822 -311.784492)
		(width 0.1143)
		(layer "In13.Cu")
		(net "P5E_PEX2_STN6_TX_DN<107>")
	)
	(segment
		(start 288.43351 -331.468984)
		(end 288.3535 -331.34935)
		(width 0.1651)
		(layer "In13.Cu")
		(net "P5E_PEX2_STN6_TX_DN<107>")
	)
	(segment
		(start 287.867344 -331.253592)
		(end 287.747964 -331.333602)
		(width 0.1651)
		(layer "In13.Cu")
		(net "P5E_PEX2_STN6_TX_DN<107>")
	)
	(segment
		(start 279.120092 -319.921128)
		(end 279.120092 -311.773824)
		(width 0.1143)
		(layer "In13.Cu")
		(net "P5E_PEX2_STN6_TX_DN<107>")
	)
	(segment
		(start 288.3535 -331.34935)
		(end 287.867344 -331.253592)
		(width 0.1651)
		(layer "In13.Cu")
		(net "P5E_PEX2_STN6_TX_DN<107>")
	)
	(segment
		(start 279.165812 -324.590664)
		(end 279.165812 -319.995296)
		(width 0.1651)
		(layer "In13.Cu")
		(net "P5E_PEX2_STN6_TX_DN<107>")
	)
	(segment
		(start 279.120092 -311.773824)
		(end 279.223724 -311.670192)
		(width 0.1143)
		(layer "In13.Cu")
		(net "P5E_PEX2_STN6_TX_DN<107>")
	)
	(segment
		(start 279.223724 -311.670192)
		(end 279.385522 -311.670192)
		(width 0.1143)
		(layer "In13.Cu")
		(net "P5E_PEX2_STN6_TX_DN<107>")
	)
	(segment
		(start 279.165812 -319.995296)
		(end 279.165812 -319.966848)
		(width 0.1143)
		(layer "In13.Cu")
		(net "P5E_PEX2_STN6_TX_DN<107>")
	)
	(segment
		(start 323.956934 -346.230194)
		(end 323.956934 -342.0872)
		(width 0.1651)
		(layer "In13.Cu")
		(net "P5E_PEX2_STN6_TX_DN<107>")
	)
	(segment
		(start 288.43351 -331.46873)
		(end 288.43351 -331.468984)
		(width 0.1651)
		(layer "In13.Cu")
		(net "P5E_PEX2_STN6_TX_DN<107>")
	)
	(segment
		(start 277.011892 -328.97318)
		(end 275.120608 -327.666858)
		(width 0.1651)
		(layer "In5.Cu")
		(net "P5E_PEX2_STN7_RX_DP<126>")
	)
	(segment
		(start 301.247048 -382.69926)
		(end 301.533814 -382.412494)
		(width 0.1651)
		(layer "In5.Cu")
		(net "P5E_PEX2_STN7_RX_DP<126>")
	)
	(segment
		(start 300.674532 -341.917528)
		(end 300.373796 -341.466678)
		(width 0.1651)
		(layer "In5.Cu")
		(net "P5E_PEX2_STN7_RX_DP<126>")
	)
	(segment
		(start 273.183858 -320.0146)
		(end 273.229578 -319.96888)
		(width 0.1143)
		(layer "In5.Cu")
		(net "P5E_PEX2_STN7_RX_DP<126>")
	)
	(segment
		(start 301.204884 -365.421418)
		(end 301.309024 -365.297974)
		(width 0.1651)
		(layer "In5.Cu")
		(net "P5E_PEX2_STN7_RX_DP<126>")
	)
	(segment
		(start 301.308516 -366.6363)
		(end 301.412656 -366.512856)
		(width 0.1651)
		(layer "In5.Cu")
		(net "P5E_PEX2_STN7_RX_DP<126>")
	)
	(segment
		(start 273.183858 -320.043048)
		(end 273.183858 -320.0146)
		(width 0.1143)
		(layer "In5.Cu")
		(net "P5E_PEX2_STN7_RX_DP<126>")
	)
	(segment
		(start 300.689772 -382.18999)
		(end 300.689772 -382.57226)
		(width 0.1651)
		(layer "In5.Cu")
		(net "P5E_PEX2_STN7_RX_DP<126>")
	)
	(segment
		(start 301.267114 -364.804706)
		(end 301.143162 -364.700312)
		(width 0.1651)
		(layer "In5.Cu")
		(net "P5E_PEX2_STN7_RX_DP<126>")
	)
	(segment
		(start 301.412656 -366.512856)
		(end 301.370746 -366.019588)
		(width 0.1651)
		(layer "In5.Cu")
		(net "P5E_PEX2_STN7_RX_DP<126>")
	)
	(segment
		(start 301.474378 -367.234216)
		(end 301.474632 -367.234216)
		(width 0.1651)
		(layer "In5.Cu")
		(net "P5E_PEX2_STN7_RX_DP<126>")
	)
	(segment
		(start 301.370746 -366.019588)
		(end 301.246794 -365.915194)
		(width 0.1651)
		(layer "In5.Cu")
		(net "P5E_PEX2_STN7_RX_DP<126>")
	)
	(segment
		(start 301.101252 -364.206536)
		(end 301.205392 -364.083092)
		(width 0.1651)
		(layer "In5.Cu")
		(net "P5E_PEX2_STN7_RX_DP<126>")
	)
	(segment
		(start 300.971712 -361.338114)
		(end 300.848522 -342.484456)
		(width 0.1651)
		(layer "In5.Cu")
		(net "P5E_PEX2_STN7_RX_DP<126>")
	)
	(segment
		(start 273.685508 -316.229492)
		(end 273.799808 -316.115192)
		(width 0.1143)
		(layer "In5.Cu")
		(net "P5E_PEX2_STN7_RX_DP<126>")
	)
	(segment
		(start 301.35068 -367.130076)
		(end 301.308516 -366.6363)
		(width 0.1651)
		(layer "In5.Cu")
		(net "P5E_PEX2_STN7_RX_DP<126>")
	)
	(segment
		(start 273.455384 -316.229492)
		(end 273.685508 -316.229492)
		(width 0.1143)
		(layer "In5.Cu")
		(net "P5E_PEX2_STN7_RX_DP<126>")
	)
	(segment
		(start 301.533814 -367.931192)
		(end 301.474378 -367.234216)
		(width 0.1651)
		(layer "In5.Cu")
		(net "P5E_PEX2_STN7_RX_DP<126>")
	)
	(segment
		(start 273.629628 -325.869554)
		(end 273.183858 -324.82536)
		(width 0.1651)
		(layer "In5.Cu")
		(net "P5E_PEX2_STN7_RX_DP<126>")
	)
	(segment
		(start 275.120608 -327.666858)
		(end 273.629628 -325.869554)
		(width 0.1651)
		(layer "In5.Cu")
		(net "P5E_PEX2_STN7_RX_DP<126>")
	)
	(segment
		(start 300.689772 -382.57226)
		(end 300.816772 -382.69926)
		(width 0.1651)
		(layer "In5.Cu")
		(net "P5E_PEX2_STN7_RX_DP<126>")
	)
	(segment
		(start 301.533814 -382.412494)
		(end 301.533814 -367.931192)
		(width 0.1651)
		(layer "In5.Cu")
		(net "P5E_PEX2_STN7_RX_DP<126>")
	)
	(segment
		(start 273.229578 -316.455298)
		(end 273.455384 -316.229492)
		(width 0.1143)
		(layer "In5.Cu")
		(net "P5E_PEX2_STN7_RX_DP<126>")
	)
	(segment
		(start 301.474632 -367.234216)
		(end 301.35068 -367.130076)
		(width 0.1651)
		(layer "In5.Cu")
		(net "P5E_PEX2_STN7_RX_DP<126>")
	)
	(segment
		(start 301.246794 -365.915194)
		(end 301.204884 -365.421418)
		(width 0.1651)
		(layer "In5.Cu")
		(net "P5E_PEX2_STN7_RX_DP<126>")
	)
	(segment
		(start 300.816772 -382.69926)
		(end 301.247048 -382.69926)
		(width 0.1651)
		(layer "In5.Cu")
		(net "P5E_PEX2_STN7_RX_DP<126>")
	)
	(segment
		(start 301.143162 -364.700312)
		(end 301.101252 -364.206536)
		(width 0.1651)
		(layer "In5.Cu")
		(net "P5E_PEX2_STN7_RX_DP<126>")
	)
	(segment
		(start 273.799808 -316.115192)
		(end 273.799808 -315.849762)
		(width 0.1143)
		(layer "In5.Cu")
		(net "P5E_PEX2_STN7_RX_DP<126>")
	)
	(segment
		(start 300.848522 -342.484456)
		(end 300.674532 -341.917528)
		(width 0.1651)
		(layer "In5.Cu")
		(net "P5E_PEX2_STN7_RX_DP<126>")
	)
	(segment
		(start 301.309024 -365.297974)
		(end 301.267114 -364.804706)
		(width 0.1651)
		(layer "In5.Cu")
		(net "P5E_PEX2_STN7_RX_DP<126>")
	)
	(segment
		(start 300.373796 -341.466678)
		(end 277.011892 -328.97318)
		(width 0.1651)
		(layer "In5.Cu")
		(net "P5E_PEX2_STN7_RX_DP<126>")
	)
	(segment
		(start 273.229578 -319.96888)
		(end 273.229578 -316.455298)
		(width 0.1143)
		(layer "In5.Cu")
		(net "P5E_PEX2_STN7_RX_DP<126>")
	)
	(segment
		(start 301.205392 -364.083092)
		(end 300.971712 -361.338114)
		(width 0.1651)
		(layer "In5.Cu")
		(net "P5E_PEX2_STN7_RX_DP<126>")
	)
	(segment
		(start 273.183858 -324.82536)
		(end 273.183858 -320.043048)
		(width 0.1651)
		(layer "In5.Cu")
		(net "P5E_PEX2_STN7_RX_DP<126>")
	)
	(segment
		(start 151.520144 -131.003294)
		(end 151.225504 -131.297934)
		(width 0.13462)
		(layer "F.Cu")
		(net "P5E_PEX1_STN1_TX_DN<28>")
	)
	(segment
		(start 152.471628 -131.323334)
		(end 152.151588 -131.003294)
		(width 0.13462)
		(layer "F.Cu")
		(net "P5E_PEX1_STN1_TX_DN<28>")
	)
	(segment
		(start 152.151588 -131.003294)
		(end 151.520144 -131.003294)
		(width 0.13462)
		(layer "F.Cu")
		(net "P5E_PEX1_STN1_TX_DN<28>")
	)
	(segment
		(start 149.345142 -132.56387)
		(end 149.076918 -132.96519)
		(width 0.1651)
		(layer "In9.Cu")
		(net "P5E_PEX1_STN1_TX_DN<28>")
	)
	(segment
		(start 148.384768 -136.440418)
		(end 148.534374 -136.50214)
		(width 0.1651)
		(layer "In9.Cu")
		(net "P5E_PEX1_STN1_TX_DN<28>")
	)
	(segment
		(start 148.20011 -135.994648)
		(end 148.384768 -136.440418)
		(width 0.1651)
		(layer "In9.Cu")
		(net "P5E_PEX1_STN1_TX_DN<28>")
	)
	(segment
		(start 149.581616 -132.004054)
		(end 149.313646 -132.40512)
		(width 0.1651)
		(layer "In9.Cu")
		(net "P5E_PEX1_STN1_TX_DN<28>")
	)
	(segment
		(start 148.657056 -137.09777)
		(end 148.841714 -137.54354)
		(width 0.1651)
		(layer "In9.Cu")
		(net "P5E_PEX1_STN1_TX_DN<28>")
	)
	(segment
		(start 149.114002 -138.200892)
		(end 149.29866 -138.646662)
		(width 0.1651)
		(layer "In9.Cu")
		(net "P5E_PEX1_STN1_TX_DN<28>")
	)
	(segment
		(start 151.87422 -158.588964)
		(end 151.784304 -158.72333)
		(width 0.1651)
		(layer "In9.Cu")
		(net "P5E_PEX1_STN1_TX_DN<28>")
	)
	(segment
		(start 151.551386 -157.55239)
		(end 151.64562 -158.025592)
		(width 0.1651)
		(layer "In9.Cu")
		(net "P5E_PEX1_STN1_TX_DN<28>")
	)
	(segment
		(start 150.361904 -140.914882)
		(end 150.546562 -141.360906)
		(width 0.1651)
		(layer "In9.Cu")
		(net "P5E_PEX1_STN1_TX_DN<28>")
	)
	(segment
		(start 148.99132 -137.605262)
		(end 149.175978 -138.05154)
		(width 0.1651)
		(layer "In9.Cu")
		(net "P5E_PEX1_STN1_TX_DN<28>")
	)
	(segment
		(start 186.815984 -271.500346)
		(end 186.770264 -271.546066)
		(width 0.1143)
		(layer "In9.Cu")
		(net "P5E_PEX1_STN1_TX_DN<28>")
	)
	(segment
		(start 151.225504 -131.297934)
		(end 150.934674 -131.007104)
		(width 0.1651)
		(layer "In9.Cu")
		(net "P5E_PEX1_STN1_TX_DN<28>")
	)
	(segment
		(start 149.448266 -138.708384)
		(end 149.632924 -139.154662)
		(width 0.1651)
		(layer "In9.Cu")
		(net "P5E_PEX1_STN1_TX_DN<28>")
	)
	(segment
		(start 186.815984 -263.383776)
		(end 186.815984 -271.471898)
		(width 0.1651)
		(layer "In9.Cu")
		(net "P5E_PEX1_STN1_TX_DN<28>")
	)
	(segment
		(start 149.29866 -138.646662)
		(end 149.448266 -138.708384)
		(width 0.1651)
		(layer "In9.Cu")
		(net "P5E_PEX1_STN1_TX_DN<28>")
	)
	(segment
		(start 150.48484 -141.510258)
		(end 150.7998 -142.270734)
		(width 0.1651)
		(layer "In9.Cu")
		(net "P5E_PEX1_STN1_TX_DN<28>")
	)
	(segment
		(start 149.175978 -138.05154)
		(end 149.114002 -138.200892)
		(width 0.1651)
		(layer "In9.Cu")
		(net "P5E_PEX1_STN1_TX_DN<28>")
	)
	(segment
		(start 151.645366 -158.025592)
		(end 151.779986 -158.115508)
		(width 0.1651)
		(layer "In9.Cu")
		(net "P5E_PEX1_STN1_TX_DN<28>")
	)
	(segment
		(start 150.027894 -140.407136)
		(end 150.212298 -140.852906)
		(width 0.1651)
		(layer "In9.Cu")
		(net "P5E_PEX1_STN1_TX_DN<28>")
	)
	(segment
		(start 149.632924 -139.154662)
		(end 149.570948 -139.304014)
		(width 0.1651)
		(layer "In9.Cu")
		(net "P5E_PEX1_STN1_TX_DN<28>")
	)
	(segment
		(start 148.20011 -134.295642)
		(end 148.20011 -135.994648)
		(width 0.1651)
		(layer "In9.Cu")
		(net "P5E_PEX1_STN1_TX_DN<28>")
	)
	(segment
		(start 151.779986 -158.115508)
		(end 151.87422 -158.588964)
		(width 0.1651)
		(layer "In9.Cu")
		(net "P5E_PEX1_STN1_TX_DN<28>")
	)
	(segment
		(start 186.770264 -271.546066)
		(end 186.770264 -278.12619)
		(width 0.1143)
		(layer "In9.Cu")
		(net "P5E_PEX1_STN1_TX_DN<28>")
	)
	(segment
		(start 186.770264 -278.12619)
		(end 186.873642 -278.229568)
		(width 0.1143)
		(layer "In9.Cu")
		(net "P5E_PEX1_STN1_TX_DN<28>")
	)
	(segment
		(start 149.570948 -139.304014)
		(end 149.755606 -139.749784)
		(width 0.1651)
		(layer "In9.Cu")
		(net "P5E_PEX1_STN1_TX_DN<28>")
	)
	(segment
		(start 148.918422 -132.99694)
		(end 148.44395 -133.707124)
		(width 0.1651)
		(layer "In9.Cu")
		(net "P5E_PEX1_STN1_TX_DN<28>")
	)
	(segment
		(start 150.212298 -140.852906)
		(end 150.361904 -140.914882)
		(width 0.1651)
		(layer "In9.Cu")
		(net "P5E_PEX1_STN1_TX_DN<28>")
	)
	(segment
		(start 151.784304 -158.72333)
		(end 152.066752 -160.144714)
		(width 0.1651)
		(layer "In9.Cu")
		(net "P5E_PEX1_STN1_TX_DN<28>")
	)
	(segment
		(start 187.14974 -278.115268)
		(end 187.14974 -277.849838)
		(width 0.1143)
		(layer "In9.Cu")
		(net "P5E_PEX1_STN1_TX_DN<28>")
	)
	(segment
		(start 186.815984 -271.471898)
		(end 186.815984 -271.500346)
		(width 0.1143)
		(layer "In9.Cu")
		(net "P5E_PEX1_STN1_TX_DN<28>")
	)
	(segment
		(start 150.7998 -142.270734)
		(end 151.551386 -157.55239)
		(width 0.1651)
		(layer "In9.Cu")
		(net "P5E_PEX1_STN1_TX_DN<28>")
	)
	(segment
		(start 149.755606 -139.749784)
		(end 149.904958 -139.811506)
		(width 0.1651)
		(layer "In9.Cu")
		(net "P5E_PEX1_STN1_TX_DN<28>")
	)
	(segment
		(start 151.64562 -158.025592)
		(end 151.645366 -158.025592)
		(width 0.1651)
		(layer "In9.Cu")
		(net "P5E_PEX1_STN1_TX_DN<28>")
	)
	(segment
		(start 150.546562 -141.360906)
		(end 150.48484 -141.510258)
		(width 0.1651)
		(layer "In9.Cu")
		(net "P5E_PEX1_STN1_TX_DN<28>")
	)
	(segment
		(start 152.066752 -160.144714)
		(end 152.349454 -161.566352)
		(width 0.1651)
		(layer "In9.Cu")
		(net "P5E_PEX1_STN1_TX_DN<28>")
	)
	(segment
		(start 186.873642 -278.229568)
		(end 187.03544 -278.229568)
		(width 0.1143)
		(layer "In9.Cu")
		(net "P5E_PEX1_STN1_TX_DN<28>")
	)
	(segment
		(start 148.841714 -137.54354)
		(end 148.99132 -137.605262)
		(width 0.1651)
		(layer "In9.Cu")
		(net "P5E_PEX1_STN1_TX_DN<28>")
	)
	(segment
		(start 187.03544 -278.229568)
		(end 187.14974 -278.115268)
		(width 0.1143)
		(layer "In9.Cu")
		(net "P5E_PEX1_STN1_TX_DN<28>")
	)
	(segment
		(start 148.719032 -136.948418)
		(end 148.657056 -137.09777)
		(width 0.1651)
		(layer "In9.Cu")
		(net "P5E_PEX1_STN1_TX_DN<28>")
	)
	(segment
		(start 150.00859 -131.570984)
		(end 149.740112 -131.972558)
		(width 0.1651)
		(layer "In9.Cu")
		(net "P5E_PEX1_STN1_TX_DN<28>")
	)
	(segment
		(start 150.089616 -140.257784)
		(end 150.027894 -140.407136)
		(width 0.1651)
		(layer "In9.Cu")
		(net "P5E_PEX1_STN1_TX_DN<28>")
	)
	(segment
		(start 149.313646 -132.40512)
		(end 149.345142 -132.56387)
		(width 0.1651)
		(layer "In9.Cu")
		(net "P5E_PEX1_STN1_TX_DN<28>")
	)
	(segment
		(start 152.349454 -161.566352)
		(end 186.815984 -263.383776)
		(width 0.1651)
		(layer "In9.Cu")
		(net "P5E_PEX1_STN1_TX_DN<28>")
	)
	(segment
		(start 149.904958 -139.811506)
		(end 150.089616 -140.257784)
		(width 0.1651)
		(layer "In9.Cu")
		(net "P5E_PEX1_STN1_TX_DN<28>")
	)
	(segment
		(start 150.934674 -131.007104)
		(end 150.360888 -131.007104)
		(width 0.1651)
		(layer "In9.Cu")
		(net "P5E_PEX1_STN1_TX_DN<28>")
	)
	(segment
		(start 149.977094 -131.412488)
		(end 150.00859 -131.570984)
		(width 0.1651)
		(layer "In9.Cu")
		(net "P5E_PEX1_STN1_TX_DN<28>")
	)
	(segment
		(start 149.740112 -131.972558)
		(end 149.581616 -132.004054)
		(width 0.1651)
		(layer "In9.Cu")
		(net "P5E_PEX1_STN1_TX_DN<28>")
	)
	(segment
		(start 148.534374 -136.50214)
		(end 148.719032 -136.948418)
		(width 0.1651)
		(layer "In9.Cu")
		(net "P5E_PEX1_STN1_TX_DN<28>")
	)
	(segment
		(start 148.44395 -133.707124)
		(end 148.20011 -134.295642)
		(width 0.1651)
		(layer "In9.Cu")
		(net "P5E_PEX1_STN1_TX_DN<28>")
	)
	(segment
		(start 149.076918 -132.96519)
		(end 148.918422 -132.99694)
		(width 0.1651)
		(layer "In9.Cu")
		(net "P5E_PEX1_STN1_TX_DN<28>")
	)
	(segment
		(start 150.18512 -131.101084)
		(end 149.977094 -131.412488)
		(width 0.1651)
		(layer "In9.Cu")
		(net "P5E_PEX1_STN1_TX_DN<28>")
	)
	(segment
		(start 150.360888 -131.007104)
		(end 150.18512 -131.101084)
		(width 0.1651)
		(layer "In9.Cu")
		(net "P5E_PEX1_STN1_TX_DN<28>")
	)
	(segment
		(start 127.975868 -343.365582)
		(end 127.975868 -342.734138)
		(width 0.13462)
		(layer "F.Cu")
		(net "P5E_PEX1_STN6_TX_DN<96>")
	)
	(segment
		(start 128.295908 -343.685622)
		(end 127.975868 -343.365582)
		(width 0.13462)
		(layer "F.Cu")
		(net "P5E_PEX1_STN6_TX_DN<96>")
	)
	(segment
		(start 127.975868 -342.734138)
		(end 128.270508 -342.439498)
		(width 0.13462)
		(layer "F.Cu")
		(net "P5E_PEX1_STN6_TX_DN<96>")
	)
	(segment
		(start 127.979678 -342.148668)
		(end 127.979678 -341.150702)
		(width 0.1651)
		(layer "In7.Cu")
		(net "P5E_PEX1_STN6_TX_DN<96>")
	)
	(segment
		(start 127.979678 -341.150702)
		(end 129.39776 -339.73262)
		(width 0.1651)
		(layer "In7.Cu")
		(net "P5E_PEX1_STN6_TX_DN<96>")
	)
	(segment
		(start 173.470316 -319.92824)
		(end 173.470316 -313.684412)
		(width 0.1143)
		(layer "In7.Cu")
		(net "P5E_PEX1_STN6_TX_DN<96>")
	)
	(segment
		(start 173.584616 -313.570112)
		(end 173.735746 -313.570112)
		(width 0.1143)
		(layer "In7.Cu")
		(net "P5E_PEX1_STN6_TX_DN<96>")
	)
	(segment
		(start 168.326562 -326.589136)
		(end 171.311062 -324.800214)
		(width 0.1651)
		(layer "In7.Cu")
		(net "P5E_PEX1_STN6_TX_DN<96>")
	)
	(segment
		(start 133.906006 -337.030568)
		(end 168.326562 -326.589136)
		(width 0.1651)
		(layer "In7.Cu")
		(net "P5E_PEX1_STN6_TX_DN<96>")
	)
	(segment
		(start 128.270508 -342.439498)
		(end 127.979678 -342.148668)
		(width 0.1651)
		(layer "In7.Cu")
		(net "P5E_PEX1_STN6_TX_DN<96>")
	)
	(segment
		(start 173.516036 -321.195446)
		(end 173.516036 -320.002408)
		(width 0.1651)
		(layer "In7.Cu")
		(net "P5E_PEX1_STN6_TX_DN<96>")
	)
	(segment
		(start 173.470316 -313.684412)
		(end 173.584616 -313.570112)
		(width 0.1143)
		(layer "In7.Cu")
		(net "P5E_PEX1_STN6_TX_DN<96>")
	)
	(segment
		(start 171.311062 -324.800214)
		(end 172.526198 -323.585078)
		(width 0.1651)
		(layer "In7.Cu")
		(net "P5E_PEX1_STN6_TX_DN<96>")
	)
	(segment
		(start 173.516036 -320.002408)
		(end 173.516036 -319.97396)
		(width 0.1143)
		(layer "In7.Cu")
		(net "P5E_PEX1_STN6_TX_DN<96>")
	)
	(segment
		(start 129.39776 -339.73262)
		(end 133.906006 -337.030568)
		(width 0.1651)
		(layer "In7.Cu")
		(net "P5E_PEX1_STN6_TX_DN<96>")
	)
	(segment
		(start 173.516036 -319.97396)
		(end 173.470316 -319.92824)
		(width 0.1143)
		(layer "In7.Cu")
		(net "P5E_PEX1_STN6_TX_DN<96>")
	)
	(segment
		(start 173.735746 -313.570112)
		(end 173.850046 -313.684412)
		(width 0.1143)
		(layer "In7.Cu")
		(net "P5E_PEX1_STN6_TX_DN<96>")
	)
	(segment
		(start 172.526198 -323.585078)
		(end 173.516036 -321.195446)
		(width 0.1651)
		(layer "In7.Cu")
		(net "P5E_PEX1_STN6_TX_DN<96>")
	)
	(segment
		(start 173.850046 -313.684412)
		(end 173.850046 -313.949842)
		(width 0.1143)
		(layer "In7.Cu")
		(net "P5E_PEX1_STN6_TX_DN<96>")
	)
	(segment
		(start 313.427618 -153.9748)
		(end 312.815986 -153.9748)
		(width 0.13462)
		(layer "F.Cu")
		(net "P5E_PEX2_STN0_TX_DN<14>")
	)
	(segment
		(start 313.732164 -154.279346)
		(end 313.427618 -153.9748)
		(width 0.13462)
		(layer "F.Cu")
		(net "P5E_PEX2_STN0_TX_DN<14>")
	)
	(segment
		(start 312.815986 -153.9748)
		(end 312.48604 -154.304746)
		(width 0.13462)
		(layer "F.Cu")
		(net "P5E_PEX2_STN0_TX_DN<14>")
	)
	(segment
		(start 318.286892 -155.254706)
		(end 318.541146 -155.868624)
		(width 0.1651)
		(layer "In9.Cu")
		(net "P5E_PEX2_STN0_TX_DN<14>")
	)
	(segment
		(start 304.827686 -221.249748)
		(end 308.27599 -260.679438)
		(width 0.1651)
		(layer "In9.Cu")
		(net "P5E_PEX2_STN0_TX_DN<14>")
	)
	(segment
		(start 308.71668 -176.794414)
		(end 308.666388 -177.371248)
		(width 0.1651)
		(layer "In9.Cu")
		(net "P5E_PEX2_STN0_TX_DN<14>")
	)
	(segment
		(start 308.391814 -179.193698)
		(end 308.4957 -179.317396)
		(width 0.1651)
		(layer "In9.Cu")
		(net "P5E_PEX2_STN0_TX_DN<14>")
	)
	(segment
		(start 307.999892 -280.434288)
		(end 307.999892 -280.699718)
		(width 0.1143)
		(layer "In9.Cu")
		(net "P5E_PEX2_STN0_TX_DN<14>")
	)
	(segment
		(start 308.4957 -179.317396)
		(end 308.495954 -179.31765)
		(width 0.1651)
		(layer "In9.Cu")
		(net "P5E_PEX2_STN0_TX_DN<14>")
	)
	(segment
		(start 307.383942 -271.526)
		(end 307.383942 -271.554448)
		(width 0.1143)
		(layer "In9.Cu")
		(net "P5E_PEX2_STN0_TX_DN<14>")
	)
	(segment
		(start 308.542182 -177.475134)
		(end 308.500272 -177.95621)
		(width 0.1651)
		(layer "In9.Cu")
		(net "P5E_PEX2_STN0_TX_DN<14>")
	)
	(segment
		(start 307.383942 -271.554448)
		(end 307.429662 -271.600168)
		(width 0.1143)
		(layer "In9.Cu")
		(net "P5E_PEX2_STN0_TX_DN<14>")
	)
	(segment
		(start 307.429662 -280.10485)
		(end 307.6448 -280.319988)
		(width 0.1143)
		(layer "In9.Cu")
		(net "P5E_PEX2_STN0_TX_DN<14>")
	)
	(segment
		(start 308.604158 -178.080162)
		(end 308.55793 -178.608736)
		(width 0.1651)
		(layer "In9.Cu")
		(net "P5E_PEX2_STN0_TX_DN<14>")
	)
	(segment
		(start 308.500272 -177.95621)
		(end 308.604158 -178.080162)
		(width 0.1651)
		(layer "In9.Cu")
		(net "P5E_PEX2_STN0_TX_DN<14>")
	)
	(segment
		(start 308.55793 -178.608736)
		(end 308.433978 -178.712622)
		(width 0.1651)
		(layer "In9.Cu")
		(net "P5E_PEX2_STN0_TX_DN<14>")
	)
	(segment
		(start 308.666388 -177.371248)
		(end 308.542182 -177.475134)
		(width 0.1651)
		(layer "In9.Cu")
		(net "P5E_PEX2_STN0_TX_DN<14>")
	)
	(segment
		(start 308.27599 -267.60424)
		(end 307.383942 -269.758414)
		(width 0.1651)
		(layer "In9.Cu")
		(net "P5E_PEX2_STN0_TX_DN<14>")
	)
	(segment
		(start 307.885592 -280.319988)
		(end 307.999892 -280.434288)
		(width 0.1143)
		(layer "In9.Cu")
		(net "P5E_PEX2_STN0_TX_DN<14>")
	)
	(segment
		(start 314.022994 -153.988516)
		(end 317.020702 -153.988516)
		(width 0.1651)
		(layer "In9.Cu")
		(net "P5E_PEX2_STN0_TX_DN<14>")
	)
	(segment
		(start 308.495954 -179.31765)
		(end 304.827686 -221.249748)
		(width 0.1651)
		(layer "In9.Cu")
		(net "P5E_PEX2_STN0_TX_DN<14>")
	)
	(segment
		(start 307.429662 -271.600168)
		(end 307.429662 -280.10485)
		(width 0.1143)
		(layer "In9.Cu")
		(net "P5E_PEX2_STN0_TX_DN<14>")
	)
	(segment
		(start 307.383942 -269.758414)
		(end 307.383942 -271.526)
		(width 0.1651)
		(layer "In9.Cu")
		(net "P5E_PEX2_STN0_TX_DN<14>")
	)
	(segment
		(start 307.6448 -280.319988)
		(end 307.885592 -280.319988)
		(width 0.1143)
		(layer "In9.Cu")
		(net "P5E_PEX2_STN0_TX_DN<14>")
	)
	(segment
		(start 318.541146 -155.868624)
		(end 318.541146 -156.760164)
		(width 0.1651)
		(layer "In9.Cu")
		(net "P5E_PEX2_STN0_TX_DN<14>")
	)
	(segment
		(start 317.020702 -153.988516)
		(end 318.286892 -155.254706)
		(width 0.1651)
		(layer "In9.Cu")
		(net "P5E_PEX2_STN0_TX_DN<14>")
	)
	(segment
		(start 308.433978 -178.712622)
		(end 308.391814 -179.193698)
		(width 0.1651)
		(layer "In9.Cu")
		(net "P5E_PEX2_STN0_TX_DN<14>")
	)
	(segment
		(start 310.224932 -171.164758)
		(end 308.71668 -176.794414)
		(width 0.1651)
		(layer "In9.Cu")
		(net "P5E_PEX2_STN0_TX_DN<14>")
	)
	(segment
		(start 313.732164 -154.279346)
		(end 314.022994 -153.988516)
		(width 0.1651)
		(layer "In9.Cu")
		(net "P5E_PEX2_STN0_TX_DN<14>")
	)
	(segment
		(start 308.27599 -260.679438)
		(end 308.27599 -267.60424)
		(width 0.1651)
		(layer "In9.Cu")
		(net "P5E_PEX2_STN0_TX_DN<14>")
	)
	(segment
		(start 318.541146 -156.760164)
		(end 310.224932 -171.164758)
		(width 0.1651)
		(layer "In9.Cu")
		(net "P5E_PEX2_STN0_TX_DN<14>")
	)
	(segment
		(start 286.845502 -349.511874)
		(end 286.845502 -348.88043)
		(width 0.13462)
		(layer "F.Cu")
		(net "P5E_PEX2_STN7_TX_DN<121>")
	)
	(segment
		(start 286.845502 -348.88043)
		(end 286.550862 -348.58579)
		(width 0.13462)
		(layer "F.Cu")
		(net "P5E_PEX2_STN7_TX_DN<121>")
	)
	(segment
		(start 286.525462 -349.831914)
		(end 286.845502 -349.511874)
		(width 0.13462)
		(layer "F.Cu")
		(net "P5E_PEX2_STN7_TX_DN<121>")
	)
	(segment
		(start 266.492482 -319.303654)
		(end 266.08786 -317.269114)
		(width 0.1651)
		(layer "In7.Cu")
		(net "P5E_PEX2_STN7_TX_DN<121>")
	)
	(segment
		(start 267.628624 -322.0466)
		(end 266.492482 -319.303654)
		(width 0.1651)
		(layer "In7.Cu")
		(net "P5E_PEX2_STN7_TX_DN<121>")
	)
	(segment
		(start 266.08786 -317.269114)
		(end 266.08786 -316.667896)
		(width 0.1651)
		(layer "In7.Cu")
		(net "P5E_PEX2_STN7_TX_DN<121>")
	)
	(segment
		(start 286.841692 -347.667834)
		(end 288.396172 -346.113354)
		(width 0.1651)
		(layer "In7.Cu")
		(net "P5E_PEX2_STN7_TX_DN<121>")
	)
	(segment
		(start 287.97631 -341.275162)
		(end 269.229586 -324.442582)
		(width 0.1651)
		(layer "In7.Cu")
		(net "P5E_PEX2_STN7_TX_DN<121>")
	)
	(segment
		(start 268.200124 -312.89752)
		(end 268.264132 -312.897774)
		(width 0.1143)
		(layer "In7.Cu")
		(net "P5E_PEX2_STN7_TX_DN<121>")
	)
	(segment
		(start 267.260832 -313.836812)
		(end 268.180058 -312.917586)
		(width 0.1651)
		(layer "In7.Cu")
		(net "P5E_PEX2_STN7_TX_DN<121>")
	)
	(segment
		(start 269.315184 -312.429652)
		(end 269.429484 -312.315352)
		(width 0.1143)
		(layer "In7.Cu")
		(net "P5E_PEX2_STN7_TX_DN<121>")
	)
	(segment
		(start 268.180058 -312.917586)
		(end 268.200124 -312.89752)
		(width 0.1143)
		(layer "In7.Cu")
		(net "P5E_PEX2_STN7_TX_DN<121>")
	)
	(segment
		(start 286.841692 -348.29496)
		(end 286.841692 -347.667834)
		(width 0.1651)
		(layer "In7.Cu")
		(net "P5E_PEX2_STN7_TX_DN<121>")
	)
	(segment
		(start 268.264132 -312.897774)
		(end 268.732254 -312.429652)
		(width 0.1143)
		(layer "In7.Cu")
		(net "P5E_PEX2_STN7_TX_DN<121>")
	)
	(segment
		(start 286.550862 -348.58579)
		(end 286.841692 -348.29496)
		(width 0.1651)
		(layer "In7.Cu")
		(net "P5E_PEX2_STN7_TX_DN<121>")
	)
	(segment
		(start 269.229586 -324.442582)
		(end 267.628624 -322.0466)
		(width 0.1651)
		(layer "In7.Cu")
		(net "P5E_PEX2_STN7_TX_DN<121>")
	)
	(segment
		(start 288.396172 -346.113354)
		(end 288.396172 -342.392508)
		(width 0.1651)
		(layer "In7.Cu")
		(net "P5E_PEX2_STN7_TX_DN<121>")
	)
	(segment
		(start 269.429484 -312.315352)
		(end 269.429484 -312.164222)
		(width 0.1143)
		(layer "In7.Cu")
		(net "P5E_PEX2_STN7_TX_DN<121>")
	)
	(segment
		(start 269.315184 -312.049922)
		(end 269.049754 -312.049922)
		(width 0.1143)
		(layer "In7.Cu")
		(net "P5E_PEX2_STN7_TX_DN<121>")
	)
	(segment
		(start 269.429484 -312.164222)
		(end 269.315184 -312.049922)
		(width 0.1143)
		(layer "In7.Cu")
		(net "P5E_PEX2_STN7_TX_DN<121>")
	)
	(segment
		(start 268.732254 -312.429652)
		(end 269.315184 -312.429652)
		(width 0.1143)
		(layer "In7.Cu")
		(net "P5E_PEX2_STN7_TX_DN<121>")
	)
	(segment
		(start 288.396172 -342.392508)
		(end 287.97631 -341.275162)
		(width 0.1651)
		(layer "In7.Cu")
		(net "P5E_PEX2_STN7_TX_DN<121>")
	)
	(segment
		(start 266.08786 -316.667896)
		(end 267.260832 -313.836812)
		(width 0.1651)
		(layer "In7.Cu")
		(net "P5E_PEX2_STN7_TX_DN<121>")
	)
	(segment
		(start 336.234278 -362.120434)
		(end 336.204814 -361.625642)
		(width 0.1651)
		(layer "In5.Cu")
		(net "P5E_PEX2_STN5_RX_DP<90>")
	)
	(segment
		(start 335.890108 -370.872258)
		(end 336.017108 -370.999258)
		(width 0.1651)
		(layer "In5.Cu")
		(net "P5E_PEX2_STN5_RX_DP<90>")
	)
	(segment
		(start 335.890108 -370.489988)
		(end 335.890108 -370.872258)
		(width 0.1651)
		(layer "In5.Cu")
		(net "P5E_PEX2_STN5_RX_DP<90>")
	)
	(segment
		(start 299.829474 -319.895728)
		(end 299.829474 -316.455298)
		(width 0.1143)
		(layer "In5.Cu")
		(net "P5E_PEX2_STN5_RX_DP<90>")
	)
	(segment
		(start 300.285404 -316.229492)
		(end 300.399704 -316.115192)
		(width 0.1143)
		(layer "In5.Cu")
		(net "P5E_PEX2_STN5_RX_DP<90>")
	)
	(segment
		(start 335.31556 -340.98738)
		(end 304.31613 -326.15505)
		(width 0.1651)
		(layer "In5.Cu")
		(net "P5E_PEX2_STN5_RX_DP<90>")
	)
	(segment
		(start 336.666586 -367.899696)
		(end 336.66684 -367.899696)
		(width 0.1651)
		(layer "In5.Cu")
		(net "P5E_PEX2_STN5_RX_DP<90>")
	)
	(segment
		(start 336.164936 -360.953812)
		(end 336.135726 -360.459274)
		(width 0.1651)
		(layer "In5.Cu")
		(net "P5E_PEX2_STN5_RX_DP<90>")
	)
	(segment
		(start 299.829474 -316.455298)
		(end 300.05528 -316.229492)
		(width 0.1143)
		(layer "In5.Cu")
		(net "P5E_PEX2_STN5_RX_DP<90>")
	)
	(segment
		(start 336.488024 -364.894876)
		(end 336.328512 -362.203746)
		(width 0.1651)
		(layer "In5.Cu")
		(net "P5E_PEX2_STN5_RX_DP<90>")
	)
	(segment
		(start 336.328512 -362.203746)
		(end 336.234278 -362.120434)
		(width 0.1651)
		(layer "In5.Cu")
		(net "P5E_PEX2_STN5_RX_DP<90>")
	)
	(segment
		(start 336.528156 -365.56696)
		(end 336.433922 -365.483394)
		(width 0.1651)
		(layer "In5.Cu")
		(net "P5E_PEX2_STN5_RX_DP<90>")
	)
	(segment
		(start 336.433922 -365.483394)
		(end 336.404458 -364.988856)
		(width 0.1651)
		(layer "In5.Cu")
		(net "P5E_PEX2_STN5_RX_DP<90>")
	)
	(segment
		(start 304.31613 -326.15505)
		(end 304.31613 -326.154796)
		(width 0.1651)
		(layer "In5.Cu")
		(net "P5E_PEX2_STN5_RX_DP<90>")
	)
	(segment
		(start 336.110834 -358.537256)
		(end 336.110834 -341.782654)
		(width 0.1651)
		(layer "In5.Cu")
		(net "P5E_PEX2_STN5_RX_DP<90>")
	)
	(segment
		(start 336.404458 -364.988856)
		(end 336.488024 -364.894876)
		(width 0.1651)
		(layer "In5.Cu")
		(net "P5E_PEX2_STN5_RX_DP<90>")
	)
	(segment
		(start 336.017108 -370.999258)
		(end 336.447384 -370.999258)
		(width 0.1651)
		(layer "In5.Cu")
		(net "P5E_PEX2_STN5_RX_DP<90>")
	)
	(segment
		(start 300.05528 -316.229492)
		(end 300.285404 -316.229492)
		(width 0.1143)
		(layer "In5.Cu")
		(net "P5E_PEX2_STN5_RX_DP<90>")
	)
	(segment
		(start 300.465236 -323.068696)
		(end 299.783754 -321.423538)
		(width 0.1651)
		(layer "In5.Cu")
		(net "P5E_PEX2_STN5_RX_DP<90>")
	)
	(segment
		(start 336.503264 -366.649762)
		(end 336.4738 -366.155224)
		(width 0.1651)
		(layer "In5.Cu")
		(net "P5E_PEX2_STN5_RX_DP<90>")
	)
	(segment
		(start 336.110834 -341.782654)
		(end 335.31556 -340.98738)
		(width 0.1651)
		(layer "In5.Cu")
		(net "P5E_PEX2_STN5_RX_DP<90>")
	)
	(segment
		(start 336.25917 -361.037378)
		(end 336.164936 -360.953812)
		(width 0.1651)
		(layer "In5.Cu")
		(net "P5E_PEX2_STN5_RX_DP<90>")
	)
	(segment
		(start 336.219038 -360.36504)
		(end 336.110834 -358.537256)
		(width 0.1651)
		(layer "In5.Cu")
		(net "P5E_PEX2_STN5_RX_DP<90>")
	)
	(segment
		(start 336.66684 -367.899696)
		(end 336.572606 -367.816384)
		(width 0.1651)
		(layer "In5.Cu")
		(net "P5E_PEX2_STN5_RX_DP<90>")
	)
	(segment
		(start 336.4738 -366.155224)
		(end 336.557366 -366.061244)
		(width 0.1651)
		(layer "In5.Cu")
		(net "P5E_PEX2_STN5_RX_DP<90>")
	)
	(segment
		(start 336.28838 -361.531662)
		(end 336.25917 -361.037378)
		(width 0.1651)
		(layer "In5.Cu")
		(net "P5E_PEX2_STN5_RX_DP<90>")
	)
	(segment
		(start 304.31613 -326.154796)
		(end 302.849534 -325.453248)
		(width 0.1651)
		(layer "In5.Cu")
		(net "P5E_PEX2_STN5_RX_DP<90>")
	)
	(segment
		(start 336.135726 -360.459274)
		(end 336.219038 -360.36504)
		(width 0.1651)
		(layer "In5.Cu")
		(net "P5E_PEX2_STN5_RX_DP<90>")
	)
	(segment
		(start 299.783754 -319.969896)
		(end 299.783754 -319.941448)
		(width 0.1143)
		(layer "In5.Cu")
		(net "P5E_PEX2_STN5_RX_DP<90>")
	)
	(segment
		(start 336.204814 -361.625642)
		(end 336.28838 -361.531662)
		(width 0.1651)
		(layer "In5.Cu")
		(net "P5E_PEX2_STN5_RX_DP<90>")
	)
	(segment
		(start 336.626708 -367.227612)
		(end 336.597498 -366.733328)
		(width 0.1651)
		(layer "In5.Cu")
		(net "P5E_PEX2_STN5_RX_DP<90>")
	)
	(segment
		(start 336.73415 -370.712492)
		(end 336.73415 -369.03533)
		(width 0.1651)
		(layer "In5.Cu")
		(net "P5E_PEX2_STN5_RX_DP<90>")
	)
	(segment
		(start 336.557366 -366.061244)
		(end 336.528156 -365.56696)
		(width 0.1651)
		(layer "In5.Cu")
		(net "P5E_PEX2_STN5_RX_DP<90>")
	)
	(segment
		(start 336.572606 -367.816384)
		(end 336.543142 -367.321592)
		(width 0.1651)
		(layer "In5.Cu")
		(net "P5E_PEX2_STN5_RX_DP<90>")
	)
	(segment
		(start 299.783754 -321.423538)
		(end 299.783754 -319.969896)
		(width 0.1651)
		(layer "In5.Cu")
		(net "P5E_PEX2_STN5_RX_DP<90>")
	)
	(segment
		(start 336.447384 -370.999258)
		(end 336.73415 -370.712492)
		(width 0.1651)
		(layer "In5.Cu")
		(net "P5E_PEX2_STN5_RX_DP<90>")
	)
	(segment
		(start 300.399704 -316.115192)
		(end 300.399704 -315.849762)
		(width 0.1143)
		(layer "In5.Cu")
		(net "P5E_PEX2_STN5_RX_DP<90>")
	)
	(segment
		(start 302.849534 -325.453248)
		(end 300.465236 -323.068696)
		(width 0.1651)
		(layer "In5.Cu")
		(net "P5E_PEX2_STN5_RX_DP<90>")
	)
	(segment
		(start 299.783754 -319.941448)
		(end 299.829474 -319.895728)
		(width 0.1143)
		(layer "In5.Cu")
		(net "P5E_PEX2_STN5_RX_DP<90>")
	)
	(segment
		(start 336.543142 -367.321592)
		(end 336.626708 -367.227612)
		(width 0.1651)
		(layer "In5.Cu")
		(net "P5E_PEX2_STN5_RX_DP<90>")
	)
	(segment
		(start 336.597498 -366.733328)
		(end 336.503264 -366.649762)
		(width 0.1651)
		(layer "In5.Cu")
		(net "P5E_PEX2_STN5_RX_DP<90>")
	)
	(segment
		(start 336.73415 -369.03533)
		(end 336.666586 -367.899696)
		(width 0.1651)
		(layer "In5.Cu")
		(net "P5E_PEX2_STN5_RX_DP<90>")
	)
	(segment
		(start 196.385942 -123.184666)
		(end 196.705982 -122.864626)
		(width 0.13462)
		(layer "F.Cu")
		(net "P5E_PEX1_STN0_TX_DP<2>")
	)
	(segment
		(start 197.337426 -122.864626)
		(end 197.632066 -123.159266)
		(width 0.13462)
		(layer "F.Cu")
		(net "P5E_PEX1_STN0_TX_DP<2>")
	)
	(segment
		(start 196.705982 -122.864626)
		(end 197.337426 -122.864626)
		(width 0.13462)
		(layer "F.Cu")
		(net "P5E_PEX1_STN0_TX_DP<2>")
	)
	(segment
		(start 199.989186 -285.784036)
		(end 199.943466 -285.829756)
		(width 0.1143)
		(layer "In9.Cu")
		(net "P5E_PEX1_STN0_TX_DP<2>")
	)
	(segment
		(start 203.84643 -128.755394)
		(end 203.846176 -128.755648)
		(width 0.1651)
		(layer "In9.Cu")
		(net "P5E_PEX1_STN0_TX_DP<2>")
	)
	(segment
		(start 213.125304 -265.25347)
		(end 214.16391 -267.760958)
		(width 0.1651)
		(layer "In9.Cu")
		(net "P5E_PEX1_STN0_TX_DP<2>")
	)
	(segment
		(start 205.944216 -133.36651)
		(end 206.077058 -133.421628)
		(width 0.1651)
		(layer "In9.Cu")
		(net "P5E_PEX1_STN0_TX_DP<2>")
	)
	(segment
		(start 202.118976 -124.286518)
		(end 202.430888 -125.040136)
		(width 0.1651)
		(layer "In9.Cu")
		(net "P5E_PEX1_STN0_TX_DP<2>")
	)
	(segment
		(start 202.99045 -126.690374)
		(end 203.165456 -127.112522)
		(width 0.1651)
		(layer "In9.Cu")
		(net "P5E_PEX1_STN0_TX_DP<2>")
	)
	(segment
		(start 202.682602 -126.2126)
		(end 202.857608 -126.635256)
		(width 0.1651)
		(layer "In9.Cu")
		(net "P5E_PEX1_STN0_TX_DP<2>")
	)
	(segment
		(start 202.857608 -126.635256)
		(end 202.99045 -126.690374)
		(width 0.1651)
		(layer "In9.Cu")
		(net "P5E_PEX1_STN0_TX_DP<2>")
	)
	(segment
		(start 214.054182 -152.6794)
		(end 214.054182 -159.674306)
		(width 0.1651)
		(layer "In9.Cu")
		(net "P5E_PEX1_STN0_TX_DP<2>")
	)
	(segment
		(start 204.254354 -284.633924)
		(end 201.478134 -285.784036)
		(width 0.1651)
		(layer "In9.Cu")
		(net "P5E_PEX1_STN0_TX_DP<2>")
	)
	(segment
		(start 204.274166 -129.788158)
		(end 204.273912 -129.788158)
		(width 0.1651)
		(layer "In9.Cu")
		(net "P5E_PEX1_STN0_TX_DP<2>")
	)
	(segment
		(start 204.3938 -130.343148)
		(end 204.568806 -130.765804)
		(width 0.1651)
		(layer "In9.Cu")
		(net "P5E_PEX1_STN0_TX_DP<2>")
	)
	(segment
		(start 203.016866 -250.126246)
		(end 213.125304 -265.25347)
		(width 0.1651)
		(layer "In9.Cu")
		(net "P5E_PEX1_STN0_TX_DP<2>")
	)
	(segment
		(start 200.108058 -122.868436)
		(end 200.700894 -122.868436)
		(width 0.1651)
		(layer "In9.Cu")
		(net "P5E_PEX1_STN0_TX_DP<2>")
	)
	(segment
		(start 202.54595 -125.617478)
		(end 202.737466 -126.080012)
		(width 0.1651)
		(layer "In9.Cu")
		(net "P5E_PEX1_STN0_TX_DP<2>")
	)
	(segment
		(start 203.713334 -128.70053)
		(end 203.84643 -128.755394)
		(width 0.1651)
		(layer "In9.Cu")
		(net "P5E_PEX1_STN0_TX_DP<2>")
	)
	(segment
		(start 203.110338 -127.245364)
		(end 203.285344 -127.66802)
		(width 0.1651)
		(layer "In9.Cu")
		(net "P5E_PEX1_STN0_TX_DP<2>")
	)
	(segment
		(start 213.850728 -160.435544)
		(end 205.204314 -175.418242)
		(width 0.1651)
		(layer "In9.Cu")
		(net "P5E_PEX1_STN0_TX_DP<2>")
	)
	(segment
		(start 213.216744 -275.671534)
		(end 204.254354 -284.633924)
		(width 0.1651)
		(layer "In9.Cu")
		(net "P5E_PEX1_STN0_TX_DP<2>")
	)
	(segment
		(start 200.536048 -221.701614)
		(end 203.016866 -250.126246)
		(width 0.1651)
		(layer "In9.Cu")
		(net "P5E_PEX1_STN0_TX_DP<2>")
	)
	(segment
		(start 204.2795 -178.865784)
		(end 200.533762 -221.67723)
		(width 0.1651)
		(layer "In9.Cu")
		(net "P5E_PEX1_STN0_TX_DP<2>")
	)
	(segment
		(start 203.966064 -129.310638)
		(end 204.14107 -129.733294)
		(width 0.1651)
		(layer "In9.Cu")
		(net "P5E_PEX1_STN0_TX_DP<2>")
	)
	(segment
		(start 197.922896 -122.868436)
		(end 199.447658 -122.868436)
		(width 0.1651)
		(layer "In9.Cu")
		(net "P5E_PEX1_STN0_TX_DP<2>")
	)
	(segment
		(start 214.16391 -267.760958)
		(end 214.570564 -272.403824)
		(width 0.1651)
		(layer "In9.Cu")
		(net "P5E_PEX1_STN0_TX_DP<2>")
	)
	(segment
		(start 203.41844 -127.722884)
		(end 203.593192 -128.145032)
		(width 0.1651)
		(layer "In9.Cu")
		(net "P5E_PEX1_STN0_TX_DP<2>")
	)
	(segment
		(start 203.593192 -128.145032)
		(end 203.538328 -128.277874)
		(width 0.1651)
		(layer "In9.Cu")
		(net "P5E_PEX1_STN0_TX_DP<2>")
	)
	(segment
		(start 193.229738 -286.044894)
		(end 193.229738 -286.285686)
		(width 0.1143)
		(layer "In9.Cu")
		(net "P5E_PEX1_STN0_TX_DP<2>")
	)
	(segment
		(start 204.021182 -129.177796)
		(end 203.966064 -129.310638)
		(width 0.1651)
		(layer "In9.Cu")
		(net "P5E_PEX1_STN0_TX_DP<2>")
	)
	(segment
		(start 203.846176 -128.755648)
		(end 204.021182 -129.177796)
		(width 0.1651)
		(layer "In9.Cu")
		(net "P5E_PEX1_STN0_TX_DP<2>")
	)
	(segment
		(start 197.632066 -123.159266)
		(end 197.922896 -122.868436)
		(width 0.1651)
		(layer "In9.Cu")
		(net "P5E_PEX1_STN0_TX_DP<2>")
	)
	(segment
		(start 193.115438 -286.399986)
		(end 192.850008 -286.399986)
		(width 0.1143)
		(layer "In9.Cu")
		(net "P5E_PEX1_STN0_TX_DP<2>")
	)
	(segment
		(start 201.478134 -285.784036)
		(end 200.017634 -285.784036)
		(width 0.1651)
		(layer "In9.Cu")
		(net "P5E_PEX1_STN0_TX_DP<2>")
	)
	(segment
		(start 214.054182 -159.674306)
		(end 213.850728 -160.435544)
		(width 0.1651)
		(layer "In9.Cu")
		(net "P5E_PEX1_STN0_TX_DP<2>")
	)
	(segment
		(start 204.448918 -130.210306)
		(end 204.3938 -130.343148)
		(width 0.1651)
		(layer "In9.Cu")
		(net "P5E_PEX1_STN0_TX_DP<2>")
	)
	(segment
		(start 200.006458 -122.970036)
		(end 200.108058 -122.868436)
		(width 0.1651)
		(layer "In9.Cu")
		(net "P5E_PEX1_STN0_TX_DP<2>")
	)
	(segment
		(start 199.447658 -122.868436)
		(end 199.549258 -122.970036)
		(width 0.1651)
		(layer "In9.Cu")
		(net "P5E_PEX1_STN0_TX_DP<2>")
	)
	(segment
		(start 205.649322 -132.388864)
		(end 205.824074 -132.811012)
		(width 0.1651)
		(layer "In9.Cu")
		(net "P5E_PEX1_STN0_TX_DP<2>")
	)
	(segment
		(start 193.444876 -285.829756)
		(end 193.229738 -286.044894)
		(width 0.1143)
		(layer "In9.Cu")
		(net "P5E_PEX1_STN0_TX_DP<2>")
	)
	(segment
		(start 202.737466 -126.080012)
		(end 202.682602 -126.2126)
		(width 0.1651)
		(layer "In9.Cu")
		(net "P5E_PEX1_STN0_TX_DP<2>")
	)
	(segment
		(start 204.14107 -129.733294)
		(end 204.274166 -129.788158)
		(width 0.1651)
		(layer "In9.Cu")
		(net "P5E_PEX1_STN0_TX_DP<2>")
	)
	(segment
		(start 199.943466 -285.829756)
		(end 193.444876 -285.829756)
		(width 0.1143)
		(layer "In9.Cu")
		(net "P5E_PEX1_STN0_TX_DP<2>")
	)
	(segment
		(start 203.285344 -127.66802)
		(end 203.41844 -127.722884)
		(width 0.1651)
		(layer "In9.Cu")
		(net "P5E_PEX1_STN0_TX_DP<2>")
	)
	(segment
		(start 200.535794 -221.701614)
		(end 200.536048 -221.701614)
		(width 0.1651)
		(layer "In9.Cu")
		(net "P5E_PEX1_STN0_TX_DP<2>")
	)
	(segment
		(start 205.204314 -175.418242)
		(end 204.2795 -178.865784)
		(width 0.1651)
		(layer "In9.Cu")
		(net "P5E_PEX1_STN0_TX_DP<2>")
	)
	(segment
		(start 200.017634 -285.784036)
		(end 199.989186 -285.784036)
		(width 0.1143)
		(layer "In9.Cu")
		(net "P5E_PEX1_STN0_TX_DP<2>")
	)
	(segment
		(start 205.141068 -131.88061)
		(end 205.649322 -132.388864)
		(width 0.1651)
		(layer "In9.Cu")
		(net "P5E_PEX1_STN0_TX_DP<2>")
	)
	(segment
		(start 205.824074 -132.811012)
		(end 205.76921 -132.943854)
		(width 0.1651)
		(layer "In9.Cu")
		(net "P5E_PEX1_STN0_TX_DP<2>")
	)
	(segment
		(start 193.229738 -286.285686)
		(end 193.115438 -286.399986)
		(width 0.1143)
		(layer "In9.Cu")
		(net "P5E_PEX1_STN0_TX_DP<2>")
	)
	(segment
		(start 199.549258 -122.970036)
		(end 200.006458 -122.970036)
		(width 0.1651)
		(layer "In9.Cu")
		(net "P5E_PEX1_STN0_TX_DP<2>")
	)
	(segment
		(start 206.077058 -133.421628)
		(end 214.054182 -152.6794)
		(width 0.1651)
		(layer "In9.Cu")
		(net "P5E_PEX1_STN0_TX_DP<2>")
	)
	(segment
		(start 214.570564 -272.403824)
		(end 213.216744 -275.671534)
		(width 0.1651)
		(layer "In9.Cu")
		(net "P5E_PEX1_STN0_TX_DP<2>")
	)
	(segment
		(start 205.76921 -132.943854)
		(end 205.944216 -133.36651)
		(width 0.1651)
		(layer "In9.Cu")
		(net "P5E_PEX1_STN0_TX_DP<2>")
	)
	(segment
		(start 203.538328 -128.277874)
		(end 203.713334 -128.70053)
		(width 0.1651)
		(layer "In9.Cu")
		(net "P5E_PEX1_STN0_TX_DP<2>")
	)
	(segment
		(start 204.568806 -130.765804)
		(end 204.701902 -130.820668)
		(width 0.1651)
		(layer "In9.Cu")
		(net "P5E_PEX1_STN0_TX_DP<2>")
	)
	(segment
		(start 203.165456 -127.112522)
		(end 203.110338 -127.245364)
		(width 0.1651)
		(layer "In9.Cu")
		(net "P5E_PEX1_STN0_TX_DP<2>")
	)
	(segment
		(start 204.701902 -130.820668)
		(end 205.141068 -131.88061)
		(width 0.1651)
		(layer "In9.Cu")
		(net "P5E_PEX1_STN0_TX_DP<2>")
	)
	(segment
		(start 200.700894 -122.868436)
		(end 202.118976 -124.286518)
		(width 0.1651)
		(layer "In9.Cu")
		(net "P5E_PEX1_STN0_TX_DP<2>")
	)
	(segment
		(start 204.273912 -129.788158)
		(end 204.448918 -130.210306)
		(width 0.1651)
		(layer "In9.Cu")
		(net "P5E_PEX1_STN0_TX_DP<2>")
	)
	(segment
		(start 202.430888 -125.040136)
		(end 202.54595 -125.617478)
		(width 0.1651)
		(layer "In9.Cu")
		(net "P5E_PEX1_STN0_TX_DP<2>")
	)
	(segment
		(start 200.533762 -221.67723)
		(end 200.535794 -221.701614)
		(width 0.1651)
		(layer "In9.Cu")
		(net "P5E_PEX1_STN0_TX_DP<2>")
	)
	(segment
		(start 115.860068 -355.978206)
		(end 115.540028 -355.658166)
		(width 0.13462)
		(layer "F.Cu")
		(net "P5E_PEX1_STN6_TX_DN<101>")
	)
	(segment
		(start 115.540028 -355.026722)
		(end 115.834668 -354.732082)
		(width 0.13462)
		(layer "F.Cu")
		(net "P5E_PEX1_STN6_TX_DN<101>")
	)
	(segment
		(start 115.540028 -355.658166)
		(end 115.540028 -355.026722)
		(width 0.13462)
		(layer "F.Cu")
		(net "P5E_PEX1_STN6_TX_DN<101>")
	)
	(segment
		(start 117.098318 -341.473282)
		(end 117.664484 -340.907116)
		(width 0.1651)
		(layer "In7.Cu")
		(net "P5E_PEX1_STN6_TX_DN<101>")
	)
	(segment
		(start 168.720262 -311.784492)
		(end 168.834562 -311.670192)
		(width 0.1143)
		(layer "In7.Cu")
		(net "P5E_PEX1_STN6_TX_DN<101>")
	)
	(segment
		(start 168.720262 -319.942718)
		(end 168.720262 -311.784492)
		(width 0.1143)
		(layer "In7.Cu")
		(net "P5E_PEX1_STN6_TX_DN<101>")
	)
	(segment
		(start 117.098318 -352.268282)
		(end 117.098318 -341.473282)
		(width 0.1651)
		(layer "In7.Cu")
		(net "P5E_PEX1_STN6_TX_DN<101>")
	)
	(segment
		(start 168.834562 -311.670192)
		(end 168.985692 -311.670192)
		(width 0.1143)
		(layer "In7.Cu")
		(net "P5E_PEX1_STN6_TX_DN<101>")
	)
	(segment
		(start 115.543838 -353.822762)
		(end 117.098318 -352.268282)
		(width 0.1651)
		(layer "In7.Cu")
		(net "P5E_PEX1_STN6_TX_DN<101>")
	)
	(segment
		(start 168.765982 -320.140076)
		(end 168.765982 -320.016886)
		(width 0.1651)
		(layer "In7.Cu")
		(net "P5E_PEX1_STN6_TX_DN<101>")
	)
	(segment
		(start 168.765982 -320.016886)
		(end 168.765982 -319.988438)
		(width 0.1143)
		(layer "In7.Cu")
		(net "P5E_PEX1_STN6_TX_DN<101>")
	)
	(segment
		(start 166.384478 -322.18376)
		(end 167.590978 -321.460368)
		(width 0.1651)
		(layer "In7.Cu")
		(net "P5E_PEX1_STN6_TX_DN<101>")
	)
	(segment
		(start 168.663112 -320.388234)
		(end 168.765982 -320.140076)
		(width 0.1651)
		(layer "In7.Cu")
		(net "P5E_PEX1_STN6_TX_DN<101>")
	)
	(segment
		(start 169.099992 -311.784492)
		(end 169.099992 -312.049922)
		(width 0.1143)
		(layer "In7.Cu")
		(net "P5E_PEX1_STN6_TX_DN<101>")
	)
	(segment
		(start 115.834668 -354.732082)
		(end 115.543838 -354.441252)
		(width 0.1651)
		(layer "In7.Cu")
		(net "P5E_PEX1_STN6_TX_DN<101>")
	)
	(segment
		(start 117.664484 -340.907116)
		(end 130.98399 -332.923388)
		(width 0.1651)
		(layer "In7.Cu")
		(net "P5E_PEX1_STN6_TX_DN<101>")
	)
	(segment
		(start 168.985692 -311.670192)
		(end 169.099992 -311.784492)
		(width 0.1143)
		(layer "In7.Cu")
		(net "P5E_PEX1_STN6_TX_DN<101>")
	)
	(segment
		(start 115.543838 -354.441252)
		(end 115.543838 -353.822762)
		(width 0.1651)
		(layer "In7.Cu")
		(net "P5E_PEX1_STN6_TX_DN<101>")
	)
	(segment
		(start 168.765982 -319.988438)
		(end 168.720262 -319.942718)
		(width 0.1143)
		(layer "In7.Cu")
		(net "P5E_PEX1_STN6_TX_DN<101>")
	)
	(segment
		(start 167.590978 -321.460368)
		(end 168.663112 -320.388234)
		(width 0.1651)
		(layer "In7.Cu")
		(net "P5E_PEX1_STN6_TX_DN<101>")
	)
	(segment
		(start 130.98399 -332.923388)
		(end 166.384478 -322.18376)
		(width 0.1651)
		(layer "In7.Cu")
		(net "P5E_PEX1_STN6_TX_DN<101>")
	)
	(segment
		(start 316.374272 -136.17575)
		(end 316.083442 -135.88492)
		(width 0.13462)
		(layer "F.Cu")
		(net "P5E_PEX2_STN0_TX_DP<7>")
	)
	(segment
		(start 316.083442 -135.88492)
		(end 315.444378 -135.88492)
		(width 0.13462)
		(layer "F.Cu")
		(net "P5E_PEX2_STN0_TX_DP<7>")
	)
	(segment
		(start 315.444378 -135.88492)
		(end 315.128148 -136.20115)
		(width 0.13462)
		(layer "F.Cu")
		(net "P5E_PEX2_STN0_TX_DP<7>")
	)
	(segment
		(start 320.129662 -142.599156)
		(end 320.129408 -142.599156)
		(width 0.1651)
		(layer "In9.Cu")
		(net "P5E_PEX2_STN0_TX_DP<7>")
	)
	(segment
		(start 319.126616 -140.457428)
		(end 319.266316 -140.515086)
		(width 0.1651)
		(layer "In9.Cu")
		(net "P5E_PEX2_STN0_TX_DP<7>")
	)
	(segment
		(start 316.13475 -271.68348)
		(end 316.012322 -277.275798)
		(width 0.1651)
		(layer "In9.Cu")
		(net "P5E_PEX2_STN0_TX_DP<7>")
	)
	(segment
		(start 315.727334 -177.393854)
		(end 315.727588 -177.393854)
		(width 0.1651)
		(layer "In9.Cu")
		(net "P5E_PEX2_STN0_TX_DP<7>")
	)
	(segment
		(start 318.83477 -139.473178)
		(end 318.834516 -139.473178)
		(width 0.1651)
		(layer "In9.Cu")
		(net "P5E_PEX2_STN0_TX_DP<7>")
	)
	(segment
		(start 316.374272 -136.17575)
		(end 316.665102 -135.88492)
		(width 0.1651)
		(layer "In9.Cu")
		(net "P5E_PEX2_STN0_TX_DP<7>")
	)
	(segment
		(start 325.315326 -158.684722)
		(end 316.77864 -173.475142)
		(width 0.1651)
		(layer "In9.Cu")
		(net "P5E_PEX2_STN0_TX_DP<7>")
	)
	(segment
		(start 319.266316 -140.515086)
		(end 319.266062 -140.515086)
		(width 0.1651)
		(layer "In9.Cu")
		(net "P5E_PEX2_STN0_TX_DP<7>")
	)
	(segment
		(start 317.244222 -135.88492)
		(end 317.422022 -136.06272)
		(width 0.1651)
		(layer "In9.Cu")
		(net "P5E_PEX2_STN0_TX_DP<7>")
	)
	(segment
		(start 317.643002 -136.874758)
		(end 317.817754 -137.297414)
		(width 0.1651)
		(layer "In9.Cu")
		(net "P5E_PEX2_STN0_TX_DP<7>")
	)
	(segment
		(start 318.95161 -140.034772)
		(end 319.126616 -140.457428)
		(width 0.1651)
		(layer "In9.Cu")
		(net "P5E_PEX2_STN0_TX_DP<7>")
	)
	(segment
		(start 319.989962 -142.541244)
		(end 320.129662 -142.599156)
		(width 0.1651)
		(layer "In9.Cu")
		(net "P5E_PEX2_STN0_TX_DP<7>")
	)
	(segment
		(start 321.991228 -146.146774)
		(end 321.990974 -146.146774)
		(width 0.1651)
		(layer "In9.Cu")
		(net "P5E_PEX2_STN0_TX_DP<7>")
	)
	(segment
		(start 314.301632 -279.17775)
		(end 314.079636 -279.400254)
		(width 0.1143)
		(layer "In9.Cu")
		(net "P5E_PEX2_STN0_TX_DP<7>")
	)
	(segment
		(start 317.422022 -136.06272)
		(end 317.70066 -136.735566)
		(width 0.1651)
		(layer "In9.Cu")
		(net "P5E_PEX2_STN0_TX_DP<7>")
	)
	(segment
		(start 317.70066 -136.735566)
		(end 317.643002 -136.874758)
		(width 0.1651)
		(layer "In9.Cu")
		(net "P5E_PEX2_STN0_TX_DP<7>")
	)
	(segment
		(start 319.266062 -140.515086)
		(end 319.440814 -140.937234)
		(width 0.1651)
		(layer "In9.Cu")
		(net "P5E_PEX2_STN0_TX_DP<7>")
	)
	(segment
		(start 316.173866 -175.729646)
		(end 316.17412 -175.729646)
		(width 0.1651)
		(layer "In9.Cu")
		(net "P5E_PEX2_STN0_TX_DP<7>")
	)
	(segment
		(start 319.009268 -139.895326)
		(end 318.95161 -140.034772)
		(width 0.1651)
		(layer "In9.Cu")
		(net "P5E_PEX2_STN0_TX_DP<7>")
	)
	(segment
		(start 319.440814 -140.937234)
		(end 319.383156 -141.07668)
		(width 0.1651)
		(layer "In9.Cu")
		(net "P5E_PEX2_STN0_TX_DP<7>")
	)
	(segment
		(start 318.834516 -139.473178)
		(end 319.009268 -139.895326)
		(width 0.1651)
		(layer "In9.Cu")
		(net "P5E_PEX2_STN0_TX_DP<7>")
	)
	(segment
		(start 315.572648 -177.972212)
		(end 311.757822 -221.581218)
		(width 0.1651)
		(layer "In9.Cu")
		(net "P5E_PEX2_STN0_TX_DP<7>")
	)
	(segment
		(start 319.872614 -141.979142)
		(end 319.814956 -142.118588)
		(width 0.1651)
		(layer "In9.Cu")
		(net "P5E_PEX2_STN0_TX_DP<7>")
	)
	(segment
		(start 316.17412 -175.729646)
		(end 315.876432 -176.839118)
		(width 0.1651)
		(layer "In9.Cu")
		(net "P5E_PEX2_STN0_TX_DP<7>")
	)
	(segment
		(start 316.77864 -173.475142)
		(end 316.173866 -175.729646)
		(width 0.1651)
		(layer "In9.Cu")
		(net "P5E_PEX2_STN0_TX_DP<7>")
	)
	(segment
		(start 314.079636 -279.400254)
		(end 314.079636 -279.635458)
		(width 0.1143)
		(layer "In9.Cu")
		(net "P5E_PEX2_STN0_TX_DP<7>")
	)
	(segment
		(start 321.321684 -145.47723)
		(end 321.991228 -146.146774)
		(width 0.1651)
		(layer "In9.Cu")
		(net "P5E_PEX2_STN0_TX_DP<7>")
	)
	(segment
		(start 318.146176 -137.81151)
		(end 318.088518 -137.950702)
		(width 0.1651)
		(layer "In9.Cu")
		(net "P5E_PEX2_STN0_TX_DP<7>")
	)
	(segment
		(start 317.817754 -137.297414)
		(end 317.957454 -137.355326)
		(width 0.1651)
		(layer "In9.Cu")
		(net "P5E_PEX2_STN0_TX_DP<7>")
	)
	(segment
		(start 313.94781 -246.652034)
		(end 313.948064 -246.652034)
		(width 0.1651)
		(layer "In9.Cu")
		(net "P5E_PEX2_STN0_TX_DP<7>")
	)
	(segment
		(start 315.070998 -278.944324)
		(end 315.050932 -278.96439)
		(width 0.1143)
		(layer "In9.Cu")
		(net "P5E_PEX2_STN0_TX_DP<7>")
	)
	(segment
		(start 315.304678 -278.71039)
		(end 315.070998 -278.944324)
		(width 0.1651)
		(layer "In9.Cu")
		(net "P5E_PEX2_STN0_TX_DP<7>")
	)
	(segment
		(start 311.757822 -221.581218)
		(end 313.94781 -246.652034)
		(width 0.1651)
		(layer "In9.Cu")
		(net "P5E_PEX2_STN0_TX_DP<7>")
	)
	(segment
		(start 317.957454 -137.355326)
		(end 318.146176 -137.81151)
		(width 0.1651)
		(layer "In9.Cu")
		(net "P5E_PEX2_STN0_TX_DP<7>")
	)
	(segment
		(start 315.876432 -176.839118)
		(end 315.876178 -176.839118)
		(width 0.1651)
		(layer "In9.Cu")
		(net "P5E_PEX2_STN0_TX_DP<7>")
	)
	(segment
		(start 316.665102 -135.88492)
		(end 317.244222 -135.88492)
		(width 0.1651)
		(layer "In9.Cu")
		(net "P5E_PEX2_STN0_TX_DP<7>")
	)
	(segment
		(start 318.520064 -138.992864)
		(end 318.69507 -139.41552)
		(width 0.1651)
		(layer "In9.Cu")
		(net "P5E_PEX2_STN0_TX_DP<7>")
	)
	(segment
		(start 319.558162 -141.499336)
		(end 319.697862 -141.556994)
		(width 0.1651)
		(layer "In9.Cu")
		(net "P5E_PEX2_STN0_TX_DP<7>")
	)
	(segment
		(start 315.727588 -177.393854)
		(end 315.572648 -177.972212)
		(width 0.1651)
		(layer "In9.Cu")
		(net "P5E_PEX2_STN0_TX_DP<7>")
	)
	(segment
		(start 316.012322 -277.275798)
		(end 315.304678 -278.71039)
		(width 0.1651)
		(layer "In9.Cu")
		(net "P5E_PEX2_STN0_TX_DP<7>")
	)
	(segment
		(start 315.876178 -176.839118)
		(end 315.727334 -177.393854)
		(width 0.1651)
		(layer "In9.Cu")
		(net "P5E_PEX2_STN0_TX_DP<7>")
	)
	(segment
		(start 313.948064 -246.652034)
		(end 316.13475 -271.68348)
		(width 0.1651)
		(layer "In9.Cu")
		(net "P5E_PEX2_STN0_TX_DP<7>")
	)
	(segment
		(start 314.901834 -279.17775)
		(end 314.301632 -279.17775)
		(width 0.1143)
		(layer "In9.Cu")
		(net "P5E_PEX2_STN0_TX_DP<7>")
	)
	(segment
		(start 318.263524 -138.373358)
		(end 318.403224 -138.43127)
		(width 0.1651)
		(layer "In9.Cu")
		(net "P5E_PEX2_STN0_TX_DP<7>")
	)
	(segment
		(start 325.315326 -154.171904)
		(end 325.315326 -158.684722)
		(width 0.1651)
		(layer "In9.Cu")
		(net "P5E_PEX2_STN0_TX_DP<7>")
	)
	(segment
		(start 320.129408 -142.599156)
		(end 321.321684 -145.47723)
		(width 0.1651)
		(layer "In9.Cu")
		(net "P5E_PEX2_STN0_TX_DP<7>")
	)
	(segment
		(start 319.383156 -141.07668)
		(end 319.558162 -141.499336)
		(width 0.1651)
		(layer "In9.Cu")
		(net "P5E_PEX2_STN0_TX_DP<7>")
	)
	(segment
		(start 319.814956 -142.118588)
		(end 319.989962 -142.541244)
		(width 0.1651)
		(layer "In9.Cu")
		(net "P5E_PEX2_STN0_TX_DP<7>")
	)
	(segment
		(start 315.050932 -278.96439)
		(end 315.050932 -279.028652)
		(width 0.1143)
		(layer "In9.Cu")
		(net "P5E_PEX2_STN0_TX_DP<7>")
	)
	(segment
		(start 314.079636 -279.635458)
		(end 313.965336 -279.749758)
		(width 0.1143)
		(layer "In9.Cu")
		(net "P5E_PEX2_STN0_TX_DP<7>")
	)
	(segment
		(start 318.577722 -138.853418)
		(end 318.520064 -138.992864)
		(width 0.1651)
		(layer "In9.Cu")
		(net "P5E_PEX2_STN0_TX_DP<7>")
	)
	(segment
		(start 318.088518 -137.950702)
		(end 318.263524 -138.373358)
		(width 0.1651)
		(layer "In9.Cu")
		(net "P5E_PEX2_STN0_TX_DP<7>")
	)
	(segment
		(start 319.697862 -141.556994)
		(end 319.872614 -141.979142)
		(width 0.1651)
		(layer "In9.Cu")
		(net "P5E_PEX2_STN0_TX_DP<7>")
	)
	(segment
		(start 318.40297 -138.43127)
		(end 318.577722 -138.853418)
		(width 0.1651)
		(layer "In9.Cu")
		(net "P5E_PEX2_STN0_TX_DP<7>")
	)
	(segment
		(start 318.69507 -139.41552)
		(end 318.83477 -139.473178)
		(width 0.1651)
		(layer "In9.Cu")
		(net "P5E_PEX2_STN0_TX_DP<7>")
	)
	(segment
		(start 313.965336 -279.749758)
		(end 313.699906 -279.749758)
		(width 0.1143)
		(layer "In9.Cu")
		(net "P5E_PEX2_STN0_TX_DP<7>")
	)
	(segment
		(start 318.403224 -138.43127)
		(end 318.40297 -138.43127)
		(width 0.1651)
		(layer "In9.Cu")
		(net "P5E_PEX2_STN0_TX_DP<7>")
	)
	(segment
		(start 321.990974 -146.146774)
		(end 325.315326 -154.171904)
		(width 0.1651)
		(layer "In9.Cu")
		(net "P5E_PEX2_STN0_TX_DP<7>")
	)
	(segment
		(start 315.050932 -279.028652)
		(end 314.901834 -279.17775)
		(width 0.1143)
		(layer "In9.Cu")
		(net "P5E_PEX2_STN0_TX_DP<7>")
	)
	(segment
		(start 331.451204 -355.026722)
		(end 331.156564 -354.732082)
		(width 0.13462)
		(layer "F.Cu")
		(net "P5E_PEX2_STN6_TX_DP<102>")
	)
	(segment
		(start 331.451204 -355.658166)
		(end 331.451204 -355.026722)
		(width 0.13462)
		(layer "F.Cu")
		(net "P5E_PEX2_STN6_TX_DP<102>")
	)
	(segment
		(start 331.131164 -355.978206)
		(end 331.451204 -355.658166)
		(width 0.13462)
		(layer "F.Cu")
		(net "P5E_PEX2_STN6_TX_DP<102>")
	)
	(segment
		(start 283.679646 -319.921128)
		(end 283.679646 -313.59475)
		(width 0.1143)
		(layer "In13.Cu")
		(net "P5E_PEX2_STN6_TX_DP<102>")
	)
	(segment
		(start 333.001874 -352.259646)
		(end 333.001874 -342.32723)
		(width 0.1651)
		(layer "In13.Cu")
		(net "P5E_PEX2_STN6_TX_DP<102>")
	)
	(segment
		(start 283.894784 -313.379612)
		(end 284.135576 -313.379612)
		(width 0.1143)
		(layer "In13.Cu")
		(net "P5E_PEX2_STN6_TX_DP<102>")
	)
	(segment
		(start 333.001874 -342.32723)
		(end 332.492858 -340.986364)
		(width 0.1651)
		(layer "In13.Cu")
		(net "P5E_PEX2_STN6_TX_DP<102>")
	)
	(segment
		(start 283.633926 -323.107558)
		(end 283.633926 -319.995296)
		(width 0.1651)
		(layer "In13.Cu")
		(net "P5E_PEX2_STN6_TX_DP<102>")
	)
	(segment
		(start 330.253594 -338.279486)
		(end 314.72124 -331.403706)
		(width 0.1651)
		(layer "In13.Cu")
		(net "P5E_PEX2_STN6_TX_DP<102>")
	)
	(segment
		(start 284.249876 -313.265312)
		(end 284.249876 -312.999882)
		(width 0.1143)
		(layer "In13.Cu")
		(net "P5E_PEX2_STN6_TX_DP<102>")
	)
	(segment
		(start 283.679646 -313.59475)
		(end 283.894784 -313.379612)
		(width 0.1143)
		(layer "In13.Cu")
		(net "P5E_PEX2_STN6_TX_DP<102>")
	)
	(segment
		(start 331.447394 -354.441252)
		(end 331.447394 -353.814126)
		(width 0.1651)
		(layer "In13.Cu")
		(net "P5E_PEX2_STN6_TX_DP<102>")
	)
	(segment
		(start 285.85414 -325.750174)
		(end 283.932376 -323.828156)
		(width 0.1651)
		(layer "In13.Cu")
		(net "P5E_PEX2_STN6_TX_DP<102>")
	)
	(segment
		(start 283.633926 -319.995296)
		(end 283.633926 -319.966848)
		(width 0.1143)
		(layer "In13.Cu")
		(net "P5E_PEX2_STN6_TX_DP<102>")
	)
	(segment
		(start 331.156564 -354.732082)
		(end 331.447394 -354.441252)
		(width 0.1651)
		(layer "In13.Cu")
		(net "P5E_PEX2_STN6_TX_DP<102>")
	)
	(segment
		(start 283.633926 -319.966848)
		(end 283.679646 -319.921128)
		(width 0.1143)
		(layer "In13.Cu")
		(net "P5E_PEX2_STN6_TX_DP<102>")
	)
	(segment
		(start 331.447394 -353.814126)
		(end 333.001874 -352.259646)
		(width 0.1651)
		(layer "In13.Cu")
		(net "P5E_PEX2_STN6_TX_DP<102>")
	)
	(segment
		(start 332.492858 -340.986364)
		(end 330.253594 -338.279486)
		(width 0.1651)
		(layer "In13.Cu")
		(net "P5E_PEX2_STN6_TX_DP<102>")
	)
	(segment
		(start 314.72124 -331.403706)
		(end 285.85414 -325.750174)
		(width 0.1651)
		(layer "In13.Cu")
		(net "P5E_PEX2_STN6_TX_DP<102>")
	)
	(segment
		(start 283.932376 -323.828156)
		(end 283.633926 -323.107558)
		(width 0.1651)
		(layer "In13.Cu")
		(net "P5E_PEX2_STN6_TX_DP<102>")
	)
	(segment
		(start 284.135576 -313.379612)
		(end 284.249876 -313.265312)
		(width 0.1143)
		(layer "In13.Cu")
		(net "P5E_PEX2_STN6_TX_DP<102>")
	)
	(segment
		(start 338.980526 -367.076736)
		(end 338.994242 -366.58169)
		(width 0.1651)
		(layer "In5.Cu")
		(net "P5E_PEX2_STN5_RX_DP<91>")
	)
	(segment
		(start 339.046058 -364.740444)
		(end 339.04555 -364.74019)
		(width 0.1651)
		(layer "In5.Cu")
		(net "P5E_PEX2_STN5_RX_DP<91>")
	)
	(segment
		(start 339.119718 -362.083096)
		(end 339.119972 -362.083096)
		(width 0.1651)
		(layer "In5.Cu")
		(net "P5E_PEX2_STN5_RX_DP<91>")
	)
	(segment
		(start 338.98078 -367.076736)
		(end 338.980526 -367.076736)
		(width 0.1651)
		(layer "In5.Cu")
		(net "P5E_PEX2_STN5_RX_DP<91>")
	)
	(segment
		(start 339.138768 -361.409996)
		(end 339.138514 -361.409996)
		(width 0.1651)
		(layer "In5.Cu")
		(net "P5E_PEX2_STN5_RX_DP<91>")
	)
	(segment
		(start 339.119972 -362.083096)
		(end 339.033358 -361.991656)
		(width 0.1651)
		(layer "In5.Cu")
		(net "P5E_PEX2_STN5_RX_DP<91>")
	)
	(segment
		(start 301.349918 -318.015366)
		(end 301.349918 -317.749936)
		(width 0.1143)
		(layer "In5.Cu")
		(net "P5E_PEX2_STN5_RX_DP<91>")
	)
	(segment
		(start 338.88934 -367.163096)
		(end 338.98078 -367.076736)
		(width 0.1651)
		(layer "In5.Cu")
		(net "P5E_PEX2_STN5_RX_DP<91>")
	)
	(segment
		(start 339.138514 -361.409996)
		(end 339.219794 -358.4956)
		(width 0.1651)
		(layer "In5.Cu")
		(net "P5E_PEX2_STN5_RX_DP<91>")
	)
	(segment
		(start 301.235618 -318.129666)
		(end 301.349918 -318.015366)
		(width 0.1143)
		(layer "In5.Cu")
		(net "P5E_PEX2_STN5_RX_DP<91>")
	)
	(segment
		(start 338.090002 -371.590062)
		(end 338.090002 -371.972078)
		(width 0.1651)
		(layer "In5.Cu")
		(net "P5E_PEX2_STN5_RX_DP<91>")
	)
	(segment
		(start 339.013292 -365.90859)
		(end 339.027008 -365.413544)
		(width 0.1651)
		(layer "In5.Cu")
		(net "P5E_PEX2_STN5_RX_DP<91>")
	)
	(segment
		(start 338.961984 -367.749836)
		(end 338.875624 -367.65865)
		(width 0.1651)
		(layer "In5.Cu")
		(net "P5E_PEX2_STN5_RX_DP<91>")
	)
	(segment
		(start 338.875624 -367.65865)
		(end 338.88934 -367.163096)
		(width 0.1651)
		(layer "In5.Cu")
		(net "P5E_PEX2_STN5_RX_DP<91>")
	)
	(segment
		(start 339.219794 -341.96274)
		(end 338.751672 -341.494618)
		(width 0.1651)
		(layer "In5.Cu")
		(net "P5E_PEX2_STN5_RX_DP<91>")
	)
	(segment
		(start 300.733968 -321.162172)
		(end 300.733968 -319.969896)
		(width 0.1651)
		(layer "In5.Cu")
		(net "P5E_PEX2_STN5_RX_DP<91>")
	)
	(segment
		(start 338.934044 -371.812312)
		(end 338.934044 -368.754406)
		(width 0.1651)
		(layer "In5.Cu")
		(net "P5E_PEX2_STN5_RX_DP<91>")
	)
	(segment
		(start 300.733968 -319.969896)
		(end 300.733968 -319.941448)
		(width 0.1143)
		(layer "In5.Cu")
		(net "P5E_PEX2_STN5_RX_DP<91>")
	)
	(segment
		(start 339.219794 -358.4956)
		(end 339.219794 -341.96274)
		(width 0.1651)
		(layer "In5.Cu")
		(net "P5E_PEX2_STN5_RX_DP<91>")
	)
	(segment
		(start 338.907882 -366.490504)
		(end 338.921598 -365.99495)
		(width 0.1651)
		(layer "In5.Cu")
		(net "P5E_PEX2_STN5_RX_DP<91>")
	)
	(segment
		(start 300.779688 -318.355472)
		(end 301.005494 -318.129666)
		(width 0.1143)
		(layer "In5.Cu")
		(net "P5E_PEX2_STN5_RX_DP<91>")
	)
	(segment
		(start 300.779688 -319.895728)
		(end 300.779688 -318.355472)
		(width 0.1143)
		(layer "In5.Cu")
		(net "P5E_PEX2_STN5_RX_DP<91>")
	)
	(segment
		(start 339.027008 -365.413544)
		(end 338.940648 -365.322358)
		(width 0.1651)
		(layer "In5.Cu")
		(net "P5E_PEX2_STN5_RX_DP<91>")
	)
	(segment
		(start 338.934044 -368.754406)
		(end 338.961984 -367.749836)
		(width 0.1651)
		(layer "In5.Cu")
		(net "P5E_PEX2_STN5_RX_DP<91>")
	)
	(segment
		(start 338.090002 -371.972078)
		(end 338.217002 -372.099078)
		(width 0.1651)
		(layer "In5.Cu")
		(net "P5E_PEX2_STN5_RX_DP<91>")
	)
	(segment
		(start 301.005494 -318.129666)
		(end 301.235618 -318.129666)
		(width 0.1143)
		(layer "In5.Cu")
		(net "P5E_PEX2_STN5_RX_DP<91>")
	)
	(segment
		(start 300.733968 -319.941448)
		(end 300.779688 -319.895728)
		(width 0.1143)
		(layer "In5.Cu")
		(net "P5E_PEX2_STN5_RX_DP<91>")
	)
	(segment
		(start 301.178214 -322.23456)
		(end 300.733968 -321.162172)
		(width 0.1651)
		(layer "In5.Cu")
		(net "P5E_PEX2_STN5_RX_DP<91>")
	)
	(segment
		(start 338.994242 -366.58169)
		(end 338.907882 -366.490504)
		(width 0.1651)
		(layer "In5.Cu")
		(net "P5E_PEX2_STN5_RX_DP<91>")
	)
	(segment
		(start 338.921598 -365.99495)
		(end 339.013292 -365.90859)
		(width 0.1651)
		(layer "In5.Cu")
		(net "P5E_PEX2_STN5_RX_DP<91>")
	)
	(segment
		(start 339.04555 -364.74019)
		(end 339.119718 -362.083096)
		(width 0.1651)
		(layer "In5.Cu")
		(net "P5E_PEX2_STN5_RX_DP<91>")
	)
	(segment
		(start 338.751672 -341.494618)
		(end 304.743612 -325.148194)
		(width 0.1651)
		(layer "In5.Cu")
		(net "P5E_PEX2_STN5_RX_DP<91>")
	)
	(segment
		(start 338.940648 -365.322358)
		(end 338.954364 -364.826804)
		(width 0.1651)
		(layer "In5.Cu")
		(net "P5E_PEX2_STN5_RX_DP<91>")
	)
	(segment
		(start 339.047328 -361.496356)
		(end 339.138768 -361.409996)
		(width 0.1651)
		(layer "In5.Cu")
		(net "P5E_PEX2_STN5_RX_DP<91>")
	)
	(segment
		(start 304.743612 -325.148194)
		(end 304.743612 -325.14794)
		(width 0.1651)
		(layer "In5.Cu")
		(net "P5E_PEX2_STN5_RX_DP<91>")
	)
	(segment
		(start 338.217002 -372.099078)
		(end 338.647278 -372.099078)
		(width 0.1651)
		(layer "In5.Cu")
		(net "P5E_PEX2_STN5_RX_DP<91>")
	)
	(segment
		(start 304.743612 -325.14794)
		(end 303.488344 -324.54469)
		(width 0.1651)
		(layer "In5.Cu")
		(net "P5E_PEX2_STN5_RX_DP<91>")
	)
	(segment
		(start 338.954364 -364.826804)
		(end 339.046058 -364.740444)
		(width 0.1651)
		(layer "In5.Cu")
		(net "P5E_PEX2_STN5_RX_DP<91>")
	)
	(segment
		(start 339.033358 -361.991656)
		(end 339.047328 -361.496356)
		(width 0.1651)
		(layer "In5.Cu")
		(net "P5E_PEX2_STN5_RX_DP<91>")
	)
	(segment
		(start 338.647278 -372.099078)
		(end 338.934044 -371.812312)
		(width 0.1651)
		(layer "In5.Cu")
		(net "P5E_PEX2_STN5_RX_DP<91>")
	)
	(segment
		(start 303.488344 -324.54469)
		(end 301.178214 -322.23456)
		(width 0.1651)
		(layer "In5.Cu")
		(net "P5E_PEX2_STN5_RX_DP<91>")
	)
	(segment
		(start 139.842748 -351.611438)
		(end 140.137388 -351.316798)
		(width 0.13462)
		(layer "F.Cu")
		(net "P5E_PEX1_STN5_TX_C_DP<93>")
	)
	(segment
		(start 140.137388 -350.685354)
		(end 139.817348 -350.365314)
		(width 0.13462)
		(layer "F.Cu")
		(net "P5E_PEX1_STN5_TX_C_DP<93>")
	)
	(segment
		(start 140.137388 -351.316798)
		(end 140.137388 -350.685354)
		(width 0.13462)
		(layer "F.Cu")
		(net "P5E_PEX1_STN5_TX_C_DP<93>")
	)
	(segment
		(start 131.441952 -365.08563)
		(end 131.833366 -364.781592)
		(width 0.1651)
		(layer "In13.Cu")
		(net "P5E_PEX1_STN5_TX_C_DP<93>")
	)
	(segment
		(start 140.133578 -351.902268)
		(end 139.842748 -351.611438)
		(width 0.1651)
		(layer "In13.Cu")
		(net "P5E_PEX1_STN5_TX_C_DP<93>")
	)
	(segment
		(start 127.037084 -379.899164)
		(end 127.258572 -379.899164)
		(width 0.1651)
		(layer "In13.Cu")
		(net "P5E_PEX1_STN5_TX_C_DP<93>")
	)
	(segment
		(start 131.933188 -364.794038)
		(end 137.82548 -360.218482)
		(width 0.1651)
		(layer "In13.Cu")
		(net "P5E_PEX1_STN5_TX_C_DP<93>")
	)
	(segment
		(start 126.910084 -379.772164)
		(end 127.037084 -379.899164)
		(width 0.1651)
		(layer "In13.Cu")
		(net "P5E_PEX1_STN5_TX_C_DP<93>")
	)
	(segment
		(start 127.78486 -379.372876)
		(end 127.78486 -368.957098)
		(width 0.1651)
		(layer "In13.Cu")
		(net "P5E_PEX1_STN5_TX_C_DP<93>")
	)
	(segment
		(start 128.458976 -367.491772)
		(end 131.429252 -365.185198)
		(width 0.1651)
		(layer "In13.Cu")
		(net "P5E_PEX1_STN5_TX_C_DP<93>")
	)
	(segment
		(start 140.133578 -352.436176)
		(end 140.133578 -351.902268)
		(width 0.1651)
		(layer "In13.Cu")
		(net "P5E_PEX1_STN5_TX_C_DP<93>")
	)
	(segment
		(start 138.579098 -358.678734)
		(end 138.579098 -353.990656)
		(width 0.1651)
		(layer "In13.Cu")
		(net "P5E_PEX1_STN5_TX_C_DP<93>")
	)
	(segment
		(start 127.258572 -379.899164)
		(end 127.78486 -379.372876)
		(width 0.1651)
		(layer "In13.Cu")
		(net "P5E_PEX1_STN5_TX_C_DP<93>")
	)
	(segment
		(start 127.78486 -368.957098)
		(end 128.458976 -367.491772)
		(width 0.1651)
		(layer "In13.Cu")
		(net "P5E_PEX1_STN5_TX_C_DP<93>")
	)
	(segment
		(start 126.910084 -379.390148)
		(end 126.910084 -379.772164)
		(width 0.1651)
		(layer "In13.Cu")
		(net "P5E_PEX1_STN5_TX_C_DP<93>")
	)
	(segment
		(start 131.429252 -365.185198)
		(end 131.441952 -365.08563)
		(width 0.1651)
		(layer "In13.Cu")
		(net "P5E_PEX1_STN5_TX_C_DP<93>")
	)
	(segment
		(start 131.833366 -364.781592)
		(end 131.933188 -364.794038)
		(width 0.1651)
		(layer "In13.Cu")
		(net "P5E_PEX1_STN5_TX_C_DP<93>")
	)
	(segment
		(start 138.579098 -353.990656)
		(end 140.133578 -352.436176)
		(width 0.1651)
		(layer "In13.Cu")
		(net "P5E_PEX1_STN5_TX_C_DP<93>")
	)
	(segment
		(start 137.82548 -360.218482)
		(end 138.579098 -358.678734)
		(width 0.1651)
		(layer "In13.Cu")
		(net "P5E_PEX1_STN5_TX_C_DP<93>")
	)
	(segment
		(start 196.705982 -146.784568)
		(end 197.337426 -146.784568)
		(width 0.13462)
		(layer "F.Cu")
		(net "P5E_PEX1_STN0_TX_DP<10>")
	)
	(segment
		(start 197.337426 -146.784568)
		(end 197.632066 -147.079208)
		(width 0.13462)
		(layer "F.Cu")
		(net "P5E_PEX1_STN0_TX_DP<10>")
	)
	(segment
		(start 196.385942 -147.104608)
		(end 196.705982 -146.784568)
		(width 0.13462)
		(layer "F.Cu")
		(net "P5E_PEX1_STN0_TX_DP<10>")
	)
	(segment
		(start 195.083938 -271.554448)
		(end 195.129658 -271.600168)
		(width 0.1143)
		(layer "In9.Cu")
		(net "P5E_PEX1_STN0_TX_DP<10>")
	)
	(segment
		(start 197.922896 -146.788378)
		(end 200.042526 -146.788378)
		(width 0.1651)
		(layer "In9.Cu")
		(net "P5E_PEX1_STN0_TX_DP<10>")
	)
	(segment
		(start 203.213462 -148.881846)
		(end 203.488544 -149.29358)
		(width 0.1651)
		(layer "In9.Cu")
		(net "P5E_PEX1_STN0_TX_DP<10>")
	)
	(segment
		(start 203.463906 -149.41677)
		(end 203.739496 -149.829012)
		(width 0.1651)
		(layer "In9.Cu")
		(net "P5E_PEX1_STN0_TX_DP<10>")
	)
	(segment
		(start 197.911974 -172.492162)
		(end 196.574664 -177.47996)
		(width 0.1651)
		(layer "In9.Cu")
		(net "P5E_PEX1_STN0_TX_DP<10>")
	)
	(segment
		(start 195.585588 -280.319988)
		(end 195.699888 -280.434288)
		(width 0.1143)
		(layer "In9.Cu")
		(net "P5E_PEX1_STN0_TX_DP<10>")
	)
	(segment
		(start 196.574664 -177.47996)
		(end 196.572378 -177.504852)
		(width 0.1651)
		(layer "In9.Cu")
		(net "P5E_PEX1_STN0_TX_DP<10>")
	)
	(segment
		(start 204.388466 -150.800562)
		(end 204.51191 -150.824946)
		(width 0.1651)
		(layer "In9.Cu")
		(net "P5E_PEX1_STN0_TX_DP<10>")
	)
	(segment
		(start 196.572378 -177.504852)
		(end 196.572632 -177.504852)
		(width 0.1651)
		(layer "In9.Cu")
		(net "P5E_PEX1_STN0_TX_DP<10>")
	)
	(segment
		(start 195.129658 -280.10485)
		(end 195.344796 -280.319988)
		(width 0.1143)
		(layer "In9.Cu")
		(net "P5E_PEX1_STN0_TX_DP<10>")
	)
	(segment
		(start 203.862686 -149.853396)
		(end 204.137768 -150.26513)
		(width 0.1651)
		(layer "In9.Cu")
		(net "P5E_PEX1_STN0_TX_DP<10>")
	)
	(segment
		(start 201.88174 -147.550124)
		(end 203.213462 -148.881846)
		(width 0.1651)
		(layer "In9.Cu")
		(net "P5E_PEX1_STN0_TX_DP<10>")
	)
	(segment
		(start 195.129658 -271.600168)
		(end 195.129658 -280.10485)
		(width 0.1143)
		(layer "In9.Cu")
		(net "P5E_PEX1_STN0_TX_DP<10>")
	)
	(segment
		(start 196.572632 -177.504852)
		(end 192.666874 -222.099124)
		(width 0.1651)
		(layer "In9.Cu")
		(net "P5E_PEX1_STN0_TX_DP<10>")
	)
	(segment
		(start 204.877162 -151.371808)
		(end 206.312262 -154.836622)
		(width 0.1651)
		(layer "In9.Cu")
		(net "P5E_PEX1_STN0_TX_DP<10>")
	)
	(segment
		(start 204.51191 -150.824946)
		(end 204.877162 -151.371808)
		(width 0.1651)
		(layer "In9.Cu")
		(net "P5E_PEX1_STN0_TX_DP<10>")
	)
	(segment
		(start 197.632066 -147.079208)
		(end 197.922896 -146.788378)
		(width 0.1651)
		(layer "In9.Cu")
		(net "P5E_PEX1_STN0_TX_DP<10>")
	)
	(segment
		(start 200.042526 -146.788378)
		(end 201.88174 -147.550124)
		(width 0.1651)
		(layer "In9.Cu")
		(net "P5E_PEX1_STN0_TX_DP<10>")
	)
	(segment
		(start 192.666874 -222.099124)
		(end 196.047106 -260.76529)
		(width 0.1651)
		(layer "In9.Cu")
		(net "P5E_PEX1_STN0_TX_DP<10>")
	)
	(segment
		(start 203.739496 -149.829012)
		(end 203.862686 -149.853396)
		(width 0.1651)
		(layer "In9.Cu")
		(net "P5E_PEX1_STN0_TX_DP<10>")
	)
	(segment
		(start 196.047106 -268.773402)
		(end 195.083938 -271.09928)
		(width 0.1651)
		(layer "In9.Cu")
		(net "P5E_PEX1_STN0_TX_DP<10>")
	)
	(segment
		(start 206.312262 -157.940248)
		(end 197.911974 -172.492162)
		(width 0.1651)
		(layer "In9.Cu")
		(net "P5E_PEX1_STN0_TX_DP<10>")
	)
	(segment
		(start 195.083938 -271.09928)
		(end 195.083938 -271.526)
		(width 0.1651)
		(layer "In9.Cu")
		(net "P5E_PEX1_STN0_TX_DP<10>")
	)
	(segment
		(start 196.047106 -260.76529)
		(end 196.047106 -268.773402)
		(width 0.1651)
		(layer "In9.Cu")
		(net "P5E_PEX1_STN0_TX_DP<10>")
	)
	(segment
		(start 204.137768 -150.26513)
		(end 204.11313 -150.38832)
		(width 0.1651)
		(layer "In9.Cu")
		(net "P5E_PEX1_STN0_TX_DP<10>")
	)
	(segment
		(start 204.11313 -150.38832)
		(end 204.388466 -150.800562)
		(width 0.1651)
		(layer "In9.Cu")
		(net "P5E_PEX1_STN0_TX_DP<10>")
	)
	(segment
		(start 206.312262 -154.836622)
		(end 206.312262 -157.940248)
		(width 0.1651)
		(layer "In9.Cu")
		(net "P5E_PEX1_STN0_TX_DP<10>")
	)
	(segment
		(start 195.344796 -280.319988)
		(end 195.585588 -280.319988)
		(width 0.1143)
		(layer "In9.Cu")
		(net "P5E_PEX1_STN0_TX_DP<10>")
	)
	(segment
		(start 203.488544 -149.29358)
		(end 203.463906 -149.41677)
		(width 0.1651)
		(layer "In9.Cu")
		(net "P5E_PEX1_STN0_TX_DP<10>")
	)
	(segment
		(start 195.699888 -280.434288)
		(end 195.699888 -280.699718)
		(width 0.1143)
		(layer "In9.Cu")
		(net "P5E_PEX1_STN0_TX_DP<10>")
	)
	(segment
		(start 195.083938 -271.526)
		(end 195.083938 -271.554448)
		(width 0.1143)
		(layer "In9.Cu")
		(net "P5E_PEX1_STN0_TX_DP<10>")
	)
	(segment
		(start 125.186948 -355.978206)
		(end 124.866908 -355.658166)
		(width 0.13462)
		(layer "F.Cu")
		(net "P5E_PEX1_STN6_TX_DN<105>")
	)
	(segment
		(start 124.866908 -355.026722)
		(end 125.161548 -354.732082)
		(width 0.13462)
		(layer "F.Cu")
		(net "P5E_PEX1_STN6_TX_DN<105>")
	)
	(segment
		(start 124.866908 -355.658166)
		(end 124.866908 -355.026722)
		(width 0.13462)
		(layer "F.Cu")
		(net "P5E_PEX1_STN6_TX_DN<105>")
	)
	(segment
		(start 161.90214 -325.860918)
		(end 158.075376 -328.1553)
		(width 0.1651)
		(layer "In13.Cu")
		(net "P5E_PEX1_STN6_TX_DN<105>")
	)
	(segment
		(start 165.06317 -311.670192)
		(end 164.920168 -311.813194)
		(width 0.1143)
		(layer "In13.Cu")
		(net "P5E_PEX1_STN6_TX_DN<105>")
	)
	(segment
		(start 124.870718 -354.441252)
		(end 125.161548 -354.732082)
		(width 0.1651)
		(layer "In13.Cu")
		(net "P5E_PEX1_STN6_TX_DN<105>")
	)
	(segment
		(start 164.920168 -319.995296)
		(end 164.965888 -320.041016)
		(width 0.1143)
		(layer "In13.Cu")
		(net "P5E_PEX1_STN6_TX_DN<105>")
	)
	(segment
		(start 164.965888 -320.041016)
		(end 164.965888 -320.063114)
		(width 0.1143)
		(layer "In13.Cu")
		(net "P5E_PEX1_STN6_TX_DN<105>")
	)
	(segment
		(start 164.965888 -322.79717)
		(end 161.90214 -325.860918)
		(width 0.1651)
		(layer "In13.Cu")
		(net "P5E_PEX1_STN6_TX_DN<105>")
	)
	(segment
		(start 148.686266 -332.044294)
		(end 145.913094 -332.594712)
		(width 0.1651)
		(layer "In13.Cu")
		(net "P5E_PEX1_STN6_TX_DN<105>")
	)
	(segment
		(start 126.425198 -341.457534)
		(end 126.425198 -352.293428)
		(width 0.1651)
		(layer "In13.Cu")
		(net "P5E_PEX1_STN6_TX_DN<105>")
	)
	(segment
		(start 165.299898 -312.049922)
		(end 165.299898 -311.784492)
		(width 0.1143)
		(layer "In13.Cu")
		(net "P5E_PEX1_STN6_TX_DN<105>")
	)
	(segment
		(start 165.185598 -311.670192)
		(end 165.06317 -311.670192)
		(width 0.1143)
		(layer "In13.Cu")
		(net "P5E_PEX1_STN6_TX_DN<105>")
	)
	(segment
		(start 141.879066 -332.594712)
		(end 132.1943 -336.606134)
		(width 0.1651)
		(layer "In13.Cu")
		(net "P5E_PEX1_STN6_TX_DN<105>")
	)
	(segment
		(start 132.1943 -336.606134)
		(end 129.428748 -338.453984)
		(width 0.1651)
		(layer "In13.Cu")
		(net "P5E_PEX1_STN6_TX_DN<105>")
	)
	(segment
		(start 153.383996 -330.098654)
		(end 148.686266 -332.044294)
		(width 0.1651)
		(layer "In13.Cu")
		(net "P5E_PEX1_STN6_TX_DN<105>")
	)
	(segment
		(start 158.075376 -328.1553)
		(end 153.383742 -330.0984)
		(width 0.1651)
		(layer "In13.Cu")
		(net "P5E_PEX1_STN6_TX_DN<105>")
	)
	(segment
		(start 145.913094 -332.594712)
		(end 141.879066 -332.594712)
		(width 0.1651)
		(layer "In13.Cu")
		(net "P5E_PEX1_STN6_TX_DN<105>")
	)
	(segment
		(start 164.920168 -311.813194)
		(end 164.920168 -319.995296)
		(width 0.1143)
		(layer "In13.Cu")
		(net "P5E_PEX1_STN6_TX_DN<105>")
	)
	(segment
		(start 124.870718 -353.847908)
		(end 124.870718 -354.441252)
		(width 0.1651)
		(layer "In13.Cu")
		(net "P5E_PEX1_STN6_TX_DN<105>")
	)
	(segment
		(start 126.425198 -352.293428)
		(end 124.870718 -353.847908)
		(width 0.1651)
		(layer "In13.Cu")
		(net "P5E_PEX1_STN6_TX_DN<105>")
	)
	(segment
		(start 164.965888 -320.063114)
		(end 164.965888 -322.79717)
		(width 0.1651)
		(layer "In13.Cu")
		(net "P5E_PEX1_STN6_TX_DN<105>")
	)
	(segment
		(start 153.383742 -330.0984)
		(end 153.383996 -330.098654)
		(width 0.1651)
		(layer "In13.Cu")
		(net "P5E_PEX1_STN6_TX_DN<105>")
	)
	(segment
		(start 165.299898 -311.784492)
		(end 165.185598 -311.670192)
		(width 0.1143)
		(layer "In13.Cu")
		(net "P5E_PEX1_STN6_TX_DN<105>")
	)
	(segment
		(start 129.428748 -338.453984)
		(end 126.425198 -341.457534)
		(width 0.1651)
		(layer "In13.Cu")
		(net "P5E_PEX1_STN6_TX_DN<105>")
	)
	(segment
		(start 312.796174 -153.70048)
		(end 312.48604 -153.390346)
		(width 0.13462)
		(layer "F.Cu")
		(net "P5E_PEX2_STN0_TX_DP<14>")
	)
	(segment
		(start 313.732164 -153.415746)
		(end 313.44743 -153.70048)
		(width 0.13462)
		(layer "F.Cu")
		(net "P5E_PEX2_STN0_TX_DP<14>")
	)
	(segment
		(start 313.44743 -153.70048)
		(end 312.796174 -153.70048)
		(width 0.13462)
		(layer "F.Cu")
		(net "P5E_PEX2_STN0_TX_DP<14>")
	)
	(segment
		(start 308.55793 -267.660374)
		(end 308.141878 -268.665198)
		(width 0.1651)
		(layer "In9.Cu")
		(net "P5E_PEX2_STN0_TX_DP<14>")
	)
	(segment
		(start 318.823086 -156.835856)
		(end 310.487822 -171.27347)
		(width 0.1651)
		(layer "In9.Cu")
		(net "P5E_PEX2_STN0_TX_DP<14>")
	)
	(segment
		(start 314.022994 -153.706576)
		(end 317.137542 -153.706576)
		(width 0.1651)
		(layer "In9.Cu")
		(net "P5E_PEX2_STN0_TX_DP<14>")
	)
	(segment
		(start 310.487822 -171.273724)
		(end 308.995572 -176.843436)
		(width 0.1651)
		(layer "In9.Cu")
		(net "P5E_PEX2_STN0_TX_DP<14>")
	)
	(segment
		(start 308.55793 -260.666992)
		(end 308.55793 -267.660374)
		(width 0.1651)
		(layer "In9.Cu")
		(net "P5E_PEX2_STN0_TX_DP<14>")
	)
	(segment
		(start 308.776878 -179.342288)
		(end 305.110896 -221.249748)
		(width 0.1651)
		(layer "In9.Cu")
		(net "P5E_PEX2_STN0_TX_DP<14>")
	)
	(segment
		(start 318.525906 -155.09494)
		(end 318.823086 -155.81249)
		(width 0.1651)
		(layer "In9.Cu")
		(net "P5E_PEX2_STN0_TX_DP<14>")
	)
	(segment
		(start 317.137542 -153.706576)
		(end 318.525906 -155.09494)
		(width 0.1651)
		(layer "In9.Cu")
		(net "P5E_PEX2_STN0_TX_DP<14>")
	)
	(segment
		(start 307.665882 -271.526)
		(end 307.665882 -271.554448)
		(width 0.1143)
		(layer "In9.Cu")
		(net "P5E_PEX2_STN0_TX_DP<14>")
	)
	(segment
		(start 307.665882 -271.554448)
		(end 307.620162 -271.600168)
		(width 0.1143)
		(layer "In9.Cu")
		(net "P5E_PEX2_STN0_TX_DP<14>")
	)
	(segment
		(start 308.141878 -268.665198)
		(end 308.18328 -268.764766)
		(width 0.1651)
		(layer "In9.Cu")
		(net "P5E_PEX2_STN0_TX_DP<14>")
	)
	(segment
		(start 307.893974 -269.263876)
		(end 307.665882 -269.814548)
		(width 0.1651)
		(layer "In9.Cu")
		(net "P5E_PEX2_STN0_TX_DP<14>")
	)
	(segment
		(start 310.487822 -171.27347)
		(end 310.487822 -171.273724)
		(width 0.1651)
		(layer "In9.Cu")
		(net "P5E_PEX2_STN0_TX_DP<14>")
	)
	(segment
		(start 308.995572 -176.843436)
		(end 308.807866 -178.988974)
		(width 0.1651)
		(layer "In9.Cu")
		(net "P5E_PEX2_STN0_TX_DP<14>")
	)
	(segment
		(start 308.807866 -178.988974)
		(end 308.777132 -179.342288)
		(width 0.1651)
		(layer "In9.Cu")
		(net "P5E_PEX2_STN0_TX_DP<14>")
	)
	(segment
		(start 305.110896 -221.249748)
		(end 308.55793 -260.666992)
		(width 0.1651)
		(layer "In9.Cu")
		(net "P5E_PEX2_STN0_TX_DP<14>")
	)
	(segment
		(start 318.823086 -155.81249)
		(end 318.823086 -156.835856)
		(width 0.1651)
		(layer "In9.Cu")
		(net "P5E_PEX2_STN0_TX_DP<14>")
	)
	(segment
		(start 307.620162 -280.025856)
		(end 307.723794 -280.129488)
		(width 0.1143)
		(layer "In9.Cu")
		(net "P5E_PEX2_STN0_TX_DP<14>")
	)
	(segment
		(start 308.777132 -179.342288)
		(end 308.776878 -179.342288)
		(width 0.1651)
		(layer "In9.Cu")
		(net "P5E_PEX2_STN0_TX_DP<14>")
	)
	(segment
		(start 313.732164 -153.415746)
		(end 314.022994 -153.706576)
		(width 0.1651)
		(layer "In9.Cu")
		(net "P5E_PEX2_STN0_TX_DP<14>")
	)
	(segment
		(start 307.665882 -269.814548)
		(end 307.665882 -271.526)
		(width 0.1651)
		(layer "In9.Cu")
		(net "P5E_PEX2_STN0_TX_DP<14>")
	)
	(segment
		(start 308.18328 -268.764766)
		(end 307.993288 -269.222728)
		(width 0.1651)
		(layer "In9.Cu")
		(net "P5E_PEX2_STN0_TX_DP<14>")
	)
	(segment
		(start 307.723794 -280.129488)
		(end 307.885592 -280.129488)
		(width 0.1143)
		(layer "In9.Cu")
		(net "P5E_PEX2_STN0_TX_DP<14>")
	)
	(segment
		(start 307.993288 -269.222728)
		(end 307.893974 -269.263876)
		(width 0.1651)
		(layer "In9.Cu")
		(net "P5E_PEX2_STN0_TX_DP<14>")
	)
	(segment
		(start 307.885592 -280.129488)
		(end 307.999892 -280.015188)
		(width 0.1143)
		(layer "In9.Cu")
		(net "P5E_PEX2_STN0_TX_DP<14>")
	)
	(segment
		(start 307.620162 -271.600168)
		(end 307.620162 -280.025856)
		(width 0.1143)
		(layer "In9.Cu")
		(net "P5E_PEX2_STN0_TX_DP<14>")
	)
	(segment
		(start 307.999892 -280.015188)
		(end 307.999892 -279.749504)
		(width 0.1143)
		(layer "In9.Cu")
		(net "P5E_PEX2_STN0_TX_DP<14>")
	)
	(segment
		(start 293.337742 -348.88043)
		(end 293.632382 -348.58579)
		(width 0.13462)
		(layer "F.Cu")
		(net "P5E_PEX2_STN7_TX_DN<124>")
	)
	(segment
		(start 293.337742 -349.511874)
		(end 293.337742 -348.88043)
		(width 0.13462)
		(layer "F.Cu")
		(net "P5E_PEX2_STN7_TX_DN<124>")
	)
	(segment
		(start 293.657782 -349.831914)
		(end 293.337742 -349.511874)
		(width 0.13462)
		(layer "F.Cu")
		(net "P5E_PEX2_STN7_TX_DN<124>")
	)
	(segment
		(start 271.899888 -311.784492)
		(end 271.899888 -312.049922)
		(width 0.1143)
		(layer "In7.Cu")
		(net "P5E_PEX2_STN7_TX_DN<124>")
	)
	(segment
		(start 272.240756 -322.812156)
		(end 271.565878 -321.182746)
		(width 0.1651)
		(layer "In7.Cu")
		(net "P5E_PEX2_STN7_TX_DN<124>")
	)
	(segment
		(start 271.785588 -311.670192)
		(end 271.899888 -311.784492)
		(width 0.1143)
		(layer "In7.Cu")
		(net "P5E_PEX2_STN7_TX_DN<124>")
	)
	(segment
		(start 293.632382 -348.58579)
		(end 293.341552 -348.29496)
		(width 0.1651)
		(layer "In7.Cu")
		(net "P5E_PEX2_STN7_TX_DN<124>")
	)
	(segment
		(start 293.341552 -348.29496)
		(end 293.341552 -347.784674)
		(width 0.1651)
		(layer "In7.Cu")
		(net "P5E_PEX2_STN7_TX_DN<124>")
	)
	(segment
		(start 293.341552 -347.784674)
		(end 294.896032 -346.230194)
		(width 0.1651)
		(layer "In7.Cu")
		(net "P5E_PEX2_STN7_TX_DN<124>")
	)
	(segment
		(start 271.520158 -319.86728)
		(end 271.520158 -311.784492)
		(width 0.1143)
		(layer "In7.Cu")
		(net "P5E_PEX2_STN7_TX_DN<124>")
	)
	(segment
		(start 271.634458 -311.670192)
		(end 271.785588 -311.670192)
		(width 0.1143)
		(layer "In7.Cu")
		(net "P5E_PEX2_STN7_TX_DN<124>")
	)
	(segment
		(start 294.896032 -342.10625)
		(end 294.422576 -341.365078)
		(width 0.1651)
		(layer "In7.Cu")
		(net "P5E_PEX2_STN7_TX_DN<124>")
	)
	(segment
		(start 271.565878 -321.182746)
		(end 271.565878 -319.941448)
		(width 0.1651)
		(layer "In7.Cu")
		(net "P5E_PEX2_STN7_TX_DN<124>")
	)
	(segment
		(start 272.495518 -323.066918)
		(end 272.240756 -322.812156)
		(width 0.1651)
		(layer "In7.Cu")
		(net "P5E_PEX2_STN7_TX_DN<124>")
	)
	(segment
		(start 271.565878 -319.941448)
		(end 271.565878 -319.913)
		(width 0.1143)
		(layer "In7.Cu")
		(net "P5E_PEX2_STN7_TX_DN<124>")
	)
	(segment
		(start 294.422576 -341.365078)
		(end 272.495518 -323.066918)
		(width 0.1651)
		(layer "In7.Cu")
		(net "P5E_PEX2_STN7_TX_DN<124>")
	)
	(segment
		(start 294.896032 -346.230194)
		(end 294.896032 -342.10625)
		(width 0.1651)
		(layer "In7.Cu")
		(net "P5E_PEX2_STN7_TX_DN<124>")
	)
	(segment
		(start 271.565878 -319.913)
		(end 271.520158 -319.86728)
		(width 0.1143)
		(layer "In7.Cu")
		(net "P5E_PEX2_STN7_TX_DN<124>")
	)
	(segment
		(start 271.520158 -311.784492)
		(end 271.634458 -311.670192)
		(width 0.1143)
		(layer "In7.Cu")
		(net "P5E_PEX2_STN7_TX_DN<124>")
	)
	(segment
		(start 298.833794 -319.941448)
		(end 298.879514 -319.895728)
		(width 0.1143)
		(layer "In5.Cu")
		(net "P5E_PEX2_STN5_RX_DP<89>")
	)
	(segment
		(start 333.958438 -365.511588)
		(end 333.886302 -365.021368)
		(width 0.1651)
		(layer "In5.Cu")
		(net "P5E_PEX2_STN5_RX_DP<89>")
	)
	(segment
		(start 334.131666 -366.076484)
		(end 334.059784 -365.586518)
		(width 0.1651)
		(layer "In5.Cu")
		(net "P5E_PEX2_STN5_RX_DP<89>")
	)
	(segment
		(start 333.68996 -371.590062)
		(end 333.68996 -371.972078)
		(width 0.1651)
		(layer "In5.Cu")
		(net "P5E_PEX2_STN5_RX_DP<89>")
	)
	(segment
		(start 333.001874 -358.400858)
		(end 333.001874 -341.851234)
		(width 0.1651)
		(layer "In5.Cu")
		(net "P5E_PEX2_STN5_RX_DP<89>")
	)
	(segment
		(start 299.449744 -318.015366)
		(end 299.449744 -317.749936)
		(width 0.1143)
		(layer "In5.Cu")
		(net "P5E_PEX2_STN5_RX_DP<89>")
	)
	(segment
		(start 333.886302 -365.021368)
		(end 333.961486 -364.92053)
		(width 0.1651)
		(layer "In5.Cu")
		(net "P5E_PEX2_STN5_RX_DP<89>")
	)
	(segment
		(start 302.489362 -326.522588)
		(end 299.649388 -323.682614)
		(width 0.1651)
		(layer "In5.Cu")
		(net "P5E_PEX2_STN5_RX_DP<89>")
	)
	(segment
		(start 334.299052 -367.82375)
		(end 334.226916 -367.333276)
		(width 0.1651)
		(layer "In5.Cu")
		(net "P5E_PEX2_STN5_RX_DP<89>")
	)
	(segment
		(start 333.585058 -362.361734)
		(end 333.483712 -362.286804)
		(width 0.1651)
		(layer "In5.Cu")
		(net "P5E_PEX2_STN5_RX_DP<89>")
	)
	(segment
		(start 333.48676 -361.695492)
		(end 333.001874 -358.400858)
		(width 0.1651)
		(layer "In5.Cu")
		(net "P5E_PEX2_STN5_RX_DP<89>")
	)
	(segment
		(start 333.001874 -341.851234)
		(end 331.74813 -340.597744)
		(width 0.1651)
		(layer "In5.Cu")
		(net "P5E_PEX2_STN5_RX_DP<89>")
	)
	(segment
		(start 334.247236 -372.099078)
		(end 334.534002 -371.812312)
		(width 0.1651)
		(layer "In5.Cu")
		(net "P5E_PEX2_STN5_RX_DP<89>")
	)
	(segment
		(start 334.301846 -367.232438)
		(end 334.229964 -366.742472)
		(width 0.1651)
		(layer "In5.Cu")
		(net "P5E_PEX2_STN5_RX_DP<89>")
	)
	(segment
		(start 299.649388 -323.682614)
		(end 298.833794 -321.713606)
		(width 0.1651)
		(layer "In5.Cu")
		(net "P5E_PEX2_STN5_RX_DP<89>")
	)
	(segment
		(start 334.059784 -365.586518)
		(end 333.958438 -365.511588)
		(width 0.1651)
		(layer "In5.Cu")
		(net "P5E_PEX2_STN5_RX_DP<89>")
	)
	(segment
		(start 333.961486 -364.92053)
		(end 333.584804 -362.361734)
		(width 0.1651)
		(layer "In5.Cu")
		(net "P5E_PEX2_STN5_RX_DP<89>")
	)
	(segment
		(start 303.700688 -327.105264)
		(end 303.700688 -327.10501)
		(width 0.1651)
		(layer "In5.Cu")
		(net "P5E_PEX2_STN5_RX_DP<89>")
	)
	(segment
		(start 299.335444 -318.129666)
		(end 299.449744 -318.015366)
		(width 0.1143)
		(layer "In5.Cu")
		(net "P5E_PEX2_STN5_RX_DP<89>")
	)
	(segment
		(start 303.700688 -327.10501)
		(end 302.489362 -326.522588)
		(width 0.1651)
		(layer "In5.Cu")
		(net "P5E_PEX2_STN5_RX_DP<89>")
	)
	(segment
		(start 334.056482 -366.177322)
		(end 334.131666 -366.076484)
		(width 0.1651)
		(layer "In5.Cu")
		(net "P5E_PEX2_STN5_RX_DP<89>")
	)
	(segment
		(start 334.226916 -367.333276)
		(end 334.301846 -367.232438)
		(width 0.1651)
		(layer "In5.Cu")
		(net "P5E_PEX2_STN5_RX_DP<89>")
	)
	(segment
		(start 334.534002 -371.812312)
		(end 334.534002 -368.808508)
		(width 0.1651)
		(layer "In5.Cu")
		(net "P5E_PEX2_STN5_RX_DP<89>")
	)
	(segment
		(start 333.81696 -372.099078)
		(end 334.247236 -372.099078)
		(width 0.1651)
		(layer "In5.Cu")
		(net "P5E_PEX2_STN5_RX_DP<89>")
	)
	(segment
		(start 298.833794 -319.969896)
		(end 298.833794 -319.941448)
		(width 0.1143)
		(layer "In5.Cu")
		(net "P5E_PEX2_STN5_RX_DP<89>")
	)
	(segment
		(start 334.534002 -368.808508)
		(end 334.39989 -367.89868)
		(width 0.1651)
		(layer "In5.Cu")
		(net "P5E_PEX2_STN5_RX_DP<89>")
	)
	(segment
		(start 298.833794 -321.713606)
		(end 298.833794 -319.969896)
		(width 0.1651)
		(layer "In5.Cu")
		(net "P5E_PEX2_STN5_RX_DP<89>")
	)
	(segment
		(start 333.483712 -362.286804)
		(end 333.41183 -361.796584)
		(width 0.1651)
		(layer "In5.Cu")
		(net "P5E_PEX2_STN5_RX_DP<89>")
	)
	(segment
		(start 334.229964 -366.742472)
		(end 334.128618 -366.667542)
		(width 0.1651)
		(layer "In5.Cu")
		(net "P5E_PEX2_STN5_RX_DP<89>")
	)
	(segment
		(start 299.10532 -318.129666)
		(end 299.335444 -318.129666)
		(width 0.1143)
		(layer "In5.Cu")
		(net "P5E_PEX2_STN5_RX_DP<89>")
	)
	(segment
		(start 298.879514 -319.895728)
		(end 298.879514 -318.355472)
		(width 0.1143)
		(layer "In5.Cu")
		(net "P5E_PEX2_STN5_RX_DP<89>")
	)
	(segment
		(start 331.74813 -340.597744)
		(end 303.700688 -327.105264)
		(width 0.1651)
		(layer "In5.Cu")
		(net "P5E_PEX2_STN5_RX_DP<89>")
	)
	(segment
		(start 298.879514 -318.355472)
		(end 299.10532 -318.129666)
		(width 0.1143)
		(layer "In5.Cu")
		(net "P5E_PEX2_STN5_RX_DP<89>")
	)
	(segment
		(start 333.68996 -371.972078)
		(end 333.81696 -372.099078)
		(width 0.1651)
		(layer "In5.Cu")
		(net "P5E_PEX2_STN5_RX_DP<89>")
	)
	(segment
		(start 334.39989 -367.89868)
		(end 334.400144 -367.89868)
		(width 0.1651)
		(layer "In5.Cu")
		(net "P5E_PEX2_STN5_RX_DP<89>")
	)
	(segment
		(start 334.128618 -366.667542)
		(end 334.056482 -366.177322)
		(width 0.1651)
		(layer "In5.Cu")
		(net "P5E_PEX2_STN5_RX_DP<89>")
	)
	(segment
		(start 333.41183 -361.796584)
		(end 333.48676 -361.695492)
		(width 0.1651)
		(layer "In5.Cu")
		(net "P5E_PEX2_STN5_RX_DP<89>")
	)
	(segment
		(start 333.584804 -362.361734)
		(end 333.585058 -362.361734)
		(width 0.1651)
		(layer "In5.Cu")
		(net "P5E_PEX2_STN5_RX_DP<89>")
	)
	(segment
		(start 334.400144 -367.89868)
		(end 334.299052 -367.82375)
		(width 0.1651)
		(layer "In5.Cu")
		(net "P5E_PEX2_STN5_RX_DP<89>")
	)
	(segment
		(start 197.337426 -119.264684)
		(end 197.632066 -119.559324)
		(width 0.13462)
		(layer "F.Cu")
		(net "P5E_PEX1_STN0_TX_DP<0>")
	)
	(segment
		(start 196.705982 -119.264684)
		(end 197.337426 -119.264684)
		(width 0.13462)
		(layer "F.Cu")
		(net "P5E_PEX1_STN0_TX_DP<0>")
	)
	(segment
		(start 196.385942 -119.584724)
		(end 196.705982 -119.264684)
		(width 0.13462)
		(layer "F.Cu")
		(net "P5E_PEX1_STN0_TX_DP<0>")
	)
	(segment
		(start 204.51699 -124.976636)
		(end 204.691996 -125.399292)
		(width 0.1651)
		(layer "In9.Cu")
		(net "P5E_PEX1_STN0_TX_DP<0>")
	)
	(segment
		(start 193.444876 -287.729676)
		(end 193.229738 -287.944814)
		(width 0.1143)
		(layer "In9.Cu")
		(net "P5E_PEX1_STN0_TX_DP<0>")
	)
	(segment
		(start 205.346554 -126.713996)
		(end 207.09255 -130.928872)
		(width 0.1651)
		(layer "In9.Cu")
		(net "P5E_PEX1_STN0_TX_DP<0>")
	)
	(segment
		(start 203.233782 -121.878598)
		(end 203.408788 -122.301254)
		(width 0.1651)
		(layer "In9.Cu")
		(net "P5E_PEX1_STN0_TX_DP<0>")
	)
	(segment
		(start 199.220074 -119.370094)
		(end 199.677274 -119.370094)
		(width 0.1651)
		(layer "In9.Cu")
		(net "P5E_PEX1_STN0_TX_DP<0>")
	)
	(segment
		(start 203.288646 -121.745756)
		(end 203.233782 -121.878598)
		(width 0.1651)
		(layer "In9.Cu")
		(net "P5E_PEX1_STN0_TX_DP<0>")
	)
	(segment
		(start 215.989662 -159.92983)
		(end 215.658446 -161.16935)
		(width 0.1651)
		(layer "In9.Cu")
		(net "P5E_PEX1_STN0_TX_DP<0>")
	)
	(segment
		(start 204.691996 -125.399292)
		(end 204.824838 -125.45441)
		(width 0.1651)
		(layer "In9.Cu")
		(net "P5E_PEX1_STN0_TX_DP<0>")
	)
	(segment
		(start 204.903832 -249.385836)
		(end 214.699596 -264.044684)
		(width 0.1651)
		(layer "In9.Cu")
		(net "P5E_PEX1_STN0_TX_DP<0>")
	)
	(segment
		(start 204.144118 -123.811284)
		(end 204.089254 -123.943872)
		(width 0.1651)
		(layer "In9.Cu")
		(net "P5E_PEX1_STN0_TX_DP<0>")
	)
	(segment
		(start 205.09357 -126.10338)
		(end 205.038706 -126.236222)
		(width 0.1651)
		(layer "In9.Cu")
		(net "P5E_PEX1_STN0_TX_DP<0>")
	)
	(segment
		(start 197.632066 -119.559324)
		(end 197.922896 -119.268494)
		(width 0.1651)
		(layer "In9.Cu")
		(net "P5E_PEX1_STN0_TX_DP<0>")
	)
	(segment
		(start 216.04478 -267.29182)
		(end 216.515442 -272.702782)
		(width 0.1651)
		(layer "In9.Cu")
		(net "P5E_PEX1_STN0_TX_DP<0>")
	)
	(segment
		(start 201.980292 -120.433592)
		(end 202.008486 -120.574562)
		(width 0.1651)
		(layer "In9.Cu")
		(net "P5E_PEX1_STN0_TX_DP<0>")
	)
	(segment
		(start 199.677274 -119.370094)
		(end 199.778874 -119.268494)
		(width 0.1651)
		(layer "In9.Cu")
		(net "P5E_PEX1_STN0_TX_DP<0>")
	)
	(segment
		(start 203.408788 -122.301254)
		(end 203.54163 -122.356118)
		(width 0.1651)
		(layer "In9.Cu")
		(net "P5E_PEX1_STN0_TX_DP<0>")
	)
	(segment
		(start 207.09255 -130.928872)
		(end 207.408018 -131.24434)
		(width 0.1651)
		(layer "In9.Cu")
		(net "P5E_PEX1_STN0_TX_DP<0>")
	)
	(segment
		(start 197.922896 -119.268494)
		(end 199.118474 -119.268494)
		(width 0.1651)
		(layer "In9.Cu")
		(net "P5E_PEX1_STN0_TX_DP<0>")
	)
	(segment
		(start 215.989662 -151.961596)
		(end 215.989662 -159.92983)
		(width 0.1651)
		(layer "In9.Cu")
		(net "P5E_PEX1_STN0_TX_DP<0>")
	)
	(segment
		(start 204.26426 -124.366528)
		(end 204.397102 -124.421646)
		(width 0.1651)
		(layer "In9.Cu")
		(net "P5E_PEX1_STN0_TX_DP<0>")
	)
	(segment
		(start 214.699596 -264.044684)
		(end 216.04478 -267.29182)
		(width 0.1651)
		(layer "In9.Cu")
		(net "P5E_PEX1_STN0_TX_DP<0>")
	)
	(segment
		(start 204.824838 -125.45441)
		(end 205.09357 -126.10338)
		(width 0.1651)
		(layer "In9.Cu")
		(net "P5E_PEX1_STN0_TX_DP<0>")
	)
	(segment
		(start 205.337156 -286.253174)
		(end 201.882756 -287.683956)
		(width 0.1651)
		(layer "In9.Cu")
		(net "P5E_PEX1_STN0_TX_DP<0>")
	)
	(segment
		(start 200.236074 -119.268494)
		(end 201.980292 -120.433592)
		(width 0.1651)
		(layer "In9.Cu")
		(net "P5E_PEX1_STN0_TX_DP<0>")
	)
	(segment
		(start 199.989186 -287.683956)
		(end 199.943466 -287.729676)
		(width 0.1143)
		(layer "In9.Cu")
		(net "P5E_PEX1_STN0_TX_DP<0>")
	)
	(segment
		(start 207.086962 -176.023778)
		(end 206.222092 -179.192428)
		(width 0.1651)
		(layer "In9.Cu")
		(net "P5E_PEX1_STN0_TX_DP<0>")
	)
	(segment
		(start 193.115438 -288.299906)
		(end 192.850008 -288.299906)
		(width 0.1143)
		(layer "In9.Cu")
		(net "P5E_PEX1_STN0_TX_DP<0>")
	)
	(segment
		(start 202.388724 -120.828816)
		(end 202.529694 -120.800876)
		(width 0.1651)
		(layer "In9.Cu")
		(net "P5E_PEX1_STN0_TX_DP<0>")
	)
	(segment
		(start 200.017634 -287.683956)
		(end 199.989186 -287.683956)
		(width 0.1143)
		(layer "In9.Cu")
		(net "P5E_PEX1_STN0_TX_DP<0>")
	)
	(segment
		(start 193.229738 -287.944814)
		(end 193.229738 -288.185606)
		(width 0.1143)
		(layer "In9.Cu")
		(net "P5E_PEX1_STN0_TX_DP<0>")
	)
	(segment
		(start 193.229738 -288.185606)
		(end 193.115438 -288.299906)
		(width 0.1143)
		(layer "In9.Cu")
		(net "P5E_PEX1_STN0_TX_DP<0>")
	)
	(segment
		(start 215.658446 -161.16935)
		(end 207.086962 -176.023778)
		(width 0.1651)
		(layer "In9.Cu")
		(net "P5E_PEX1_STN0_TX_DP<0>")
	)
	(segment
		(start 202.529694 -120.800876)
		(end 203.037948 -121.14022)
		(width 0.1651)
		(layer "In9.Cu")
		(net "P5E_PEX1_STN0_TX_DP<0>")
	)
	(segment
		(start 199.943466 -287.729676)
		(end 193.444876 -287.729676)
		(width 0.1143)
		(layer "In9.Cu")
		(net "P5E_PEX1_STN0_TX_DP<0>")
	)
	(segment
		(start 199.118474 -119.268494)
		(end 199.220074 -119.370094)
		(width 0.1651)
		(layer "In9.Cu")
		(net "P5E_PEX1_STN0_TX_DP<0>")
	)
	(segment
		(start 206.222092 -179.192428)
		(end 202.495404 -221.785942)
		(width 0.1651)
		(layer "In9.Cu")
		(net "P5E_PEX1_STN0_TX_DP<0>")
	)
	(segment
		(start 203.716382 -122.77852)
		(end 203.661518 -122.911108)
		(width 0.1651)
		(layer "In9.Cu")
		(net "P5E_PEX1_STN0_TX_DP<0>")
	)
	(segment
		(start 201.882756 -287.683956)
		(end 200.017634 -287.683956)
		(width 0.1651)
		(layer "In9.Cu")
		(net "P5E_PEX1_STN0_TX_DP<0>")
	)
	(segment
		(start 216.515442 -272.702782)
		(end 214.837518 -276.752812)
		(width 0.1651)
		(layer "In9.Cu")
		(net "P5E_PEX1_STN0_TX_DP<0>")
	)
	(segment
		(start 205.213712 -126.658878)
		(end 205.346554 -126.713996)
		(width 0.1651)
		(layer "In9.Cu")
		(net "P5E_PEX1_STN0_TX_DP<0>")
	)
	(segment
		(start 199.778874 -119.268494)
		(end 200.236074 -119.268494)
		(width 0.1651)
		(layer "In9.Cu")
		(net "P5E_PEX1_STN0_TX_DP<0>")
	)
	(segment
		(start 202.495404 -221.785942)
		(end 204.903832 -249.385836)
		(width 0.1651)
		(layer "In9.Cu")
		(net "P5E_PEX1_STN0_TX_DP<0>")
	)
	(segment
		(start 207.408018 -131.24434)
		(end 215.989662 -151.961596)
		(width 0.1651)
		(layer "In9.Cu")
		(net "P5E_PEX1_STN0_TX_DP<0>")
	)
	(segment
		(start 204.397102 -124.421646)
		(end 204.571854 -124.843794)
		(width 0.1651)
		(layer "In9.Cu")
		(net "P5E_PEX1_STN0_TX_DP<0>")
	)
	(segment
		(start 214.837518 -276.752812)
		(end 205.337156 -286.253174)
		(width 0.1651)
		(layer "In9.Cu")
		(net "P5E_PEX1_STN0_TX_DP<0>")
	)
	(segment
		(start 202.008486 -120.574562)
		(end 202.388724 -120.828816)
		(width 0.1651)
		(layer "In9.Cu")
		(net "P5E_PEX1_STN0_TX_DP<0>")
	)
	(segment
		(start 204.089254 -123.943872)
		(end 204.26426 -124.366528)
		(width 0.1651)
		(layer "In9.Cu")
		(net "P5E_PEX1_STN0_TX_DP<0>")
	)
	(segment
		(start 203.54163 -122.356118)
		(end 203.716382 -122.77852)
		(width 0.1651)
		(layer "In9.Cu")
		(net "P5E_PEX1_STN0_TX_DP<0>")
	)
	(segment
		(start 203.661518 -122.911108)
		(end 203.836524 -123.333764)
		(width 0.1651)
		(layer "In9.Cu")
		(net "P5E_PEX1_STN0_TX_DP<0>")
	)
	(segment
		(start 203.969366 -123.388882)
		(end 204.144118 -123.811284)
		(width 0.1651)
		(layer "In9.Cu")
		(net "P5E_PEX1_STN0_TX_DP<0>")
	)
	(segment
		(start 203.836524 -123.333764)
		(end 203.969366 -123.388882)
		(width 0.1651)
		(layer "In9.Cu")
		(net "P5E_PEX1_STN0_TX_DP<0>")
	)
	(segment
		(start 205.038706 -126.236222)
		(end 205.213712 -126.658878)
		(width 0.1651)
		(layer "In9.Cu")
		(net "P5E_PEX1_STN0_TX_DP<0>")
	)
	(segment
		(start 203.037948 -121.14022)
		(end 203.288646 -121.745756)
		(width 0.1651)
		(layer "In9.Cu")
		(net "P5E_PEX1_STN0_TX_DP<0>")
	)
	(segment
		(start 204.571854 -124.843794)
		(end 204.51699 -124.976636)
		(width 0.1651)
		(layer "In9.Cu")
		(net "P5E_PEX1_STN0_TX_DP<0>")
	)
	(segment
		(start 124.592588 -349.511874)
		(end 124.592588 -348.88043)
		(width 0.13462)
		(layer "F.Cu")
		(net "P5E_PEX1_STN6_TX_DP<97>")
	)
	(segment
		(start 124.272548 -349.831914)
		(end 124.592588 -349.511874)
		(width 0.13462)
		(layer "F.Cu")
		(net "P5E_PEX1_STN6_TX_DP<97>")
	)
	(segment
		(start 124.592588 -348.88043)
		(end 124.297948 -348.58579)
		(width 0.13462)
		(layer "F.Cu")
		(net "P5E_PEX1_STN6_TX_DP<97>")
	)
	(segment
		(start 170.389296 -323.910198)
		(end 171.470574 -322.82892)
		(width 0.1651)
		(layer "In7.Cu")
		(net "P5E_PEX1_STN6_TX_DP<97>")
	)
	(segment
		(start 126.143258 -341.191342)
		(end 128.516126 -338.818474)
		(width 0.1651)
		(layer "In7.Cu")
		(net "P5E_PEX1_STN6_TX_DP<97>")
	)
	(segment
		(start 171.470574 -322.82892)
		(end 172.284136 -320.864738)
		(width 0.1651)
		(layer "In7.Cu")
		(net "P5E_PEX1_STN6_TX_DP<97>")
	)
	(segment
		(start 172.555662 -311.479692)
		(end 172.785786 -311.479692)
		(width 0.1143)
		(layer "In7.Cu")
		(net "P5E_PEX1_STN6_TX_DP<97>")
	)
	(segment
		(start 124.588778 -347.620082)
		(end 126.143258 -346.065602)
		(width 0.1651)
		(layer "In7.Cu")
		(net "P5E_PEX1_STN6_TX_DP<97>")
	)
	(segment
		(start 172.284136 -320.864738)
		(end 172.284136 -320.016886)
		(width 0.1651)
		(layer "In7.Cu")
		(net "P5E_PEX1_STN6_TX_DP<97>")
	)
	(segment
		(start 167.821356 -325.449184)
		(end 170.389296 -323.910198)
		(width 0.1651)
		(layer "In7.Cu")
		(net "P5E_PEX1_STN6_TX_DP<97>")
	)
	(segment
		(start 133.4008 -335.890362)
		(end 150.644606 -330.659486)
		(width 0.1651)
		(layer "In7.Cu")
		(net "P5E_PEX1_STN6_TX_DP<97>")
	)
	(segment
		(start 172.900086 -311.365392)
		(end 172.900086 -311.099962)
		(width 0.1143)
		(layer "In7.Cu")
		(net "P5E_PEX1_STN6_TX_DP<97>")
	)
	(segment
		(start 172.329856 -311.705498)
		(end 172.555662 -311.479692)
		(width 0.1143)
		(layer "In7.Cu")
		(net "P5E_PEX1_STN6_TX_DP<97>")
	)
	(segment
		(start 124.588778 -348.29496)
		(end 124.588778 -347.620082)
		(width 0.1651)
		(layer "In7.Cu")
		(net "P5E_PEX1_STN6_TX_DP<97>")
	)
	(segment
		(start 150.644352 -330.659486)
		(end 167.821356 -325.449184)
		(width 0.1651)
		(layer "In7.Cu")
		(net "P5E_PEX1_STN6_TX_DP<97>")
	)
	(segment
		(start 126.143258 -346.065602)
		(end 126.143258 -341.191342)
		(width 0.1651)
		(layer "In7.Cu")
		(net "P5E_PEX1_STN6_TX_DP<97>")
	)
	(segment
		(start 172.329856 -319.942718)
		(end 172.329856 -311.705498)
		(width 0.1143)
		(layer "In7.Cu")
		(net "P5E_PEX1_STN6_TX_DP<97>")
	)
	(segment
		(start 172.284136 -319.988438)
		(end 172.329856 -319.942718)
		(width 0.1143)
		(layer "In7.Cu")
		(net "P5E_PEX1_STN6_TX_DP<97>")
	)
	(segment
		(start 128.516126 -338.818474)
		(end 133.4008 -335.890362)
		(width 0.1651)
		(layer "In7.Cu")
		(net "P5E_PEX1_STN6_TX_DP<97>")
	)
	(segment
		(start 172.785786 -311.479692)
		(end 172.900086 -311.365392)
		(width 0.1143)
		(layer "In7.Cu")
		(net "P5E_PEX1_STN6_TX_DP<97>")
	)
	(segment
		(start 150.644606 -330.659486)
		(end 150.644352 -330.659486)
		(width 0.1651)
		(layer "In7.Cu")
		(net "P5E_PEX1_STN6_TX_DP<97>")
	)
	(segment
		(start 124.297948 -348.58579)
		(end 124.588778 -348.29496)
		(width 0.1651)
		(layer "In7.Cu")
		(net "P5E_PEX1_STN6_TX_DP<97>")
	)
	(segment
		(start 172.284136 -320.016886)
		(end 172.284136 -319.988438)
		(width 0.1143)
		(layer "In7.Cu")
		(net "P5E_PEX1_STN6_TX_DP<97>")
	)
	(segment
		(start 270.910558 -136.1186)
		(end 271.213834 -135.815324)
		(width 0.13462)
		(layer "F.Cu")
		(net "P5E_PEX2_STN1_TX_DN<31>")
	)
	(segment
		(start 269.96771 -135.840724)
		(end 270.245586 -136.1186)
		(width 0.13462)
		(layer "F.Cu")
		(net "P5E_PEX2_STN1_TX_DN<31>")
	)
	(segment
		(start 270.245586 -136.1186)
		(end 270.910558 -136.1186)
		(width 0.13462)
		(layer "F.Cu")
		(net "P5E_PEX2_STN1_TX_DN<31>")
	)
	(segment
		(start 305.529488 -271.600168)
		(end 305.483768 -271.554448)
		(width 0.1143)
		(layer "In9.Cu")
		(net "P5E_PEX2_STN1_TX_DN<31>")
	)
	(segment
		(start 305.483768 -271.526)
		(end 305.483768 -262.6106)
		(width 0.1651)
		(layer "In9.Cu")
		(net "P5E_PEX2_STN1_TX_DN<31>")
	)
	(segment
		(start 305.483768 -262.6106)
		(end 279.324308 -185.333386)
		(width 0.1651)
		(layer "In9.Cu")
		(net "P5E_PEX2_STN1_TX_DN<31>")
	)
	(segment
		(start 306.099718 -280.434288)
		(end 305.985418 -280.319988)
		(width 0.1143)
		(layer "In9.Cu")
		(net "P5E_PEX2_STN1_TX_DN<31>")
	)
	(segment
		(start 269.795752 -138.46683)
		(end 268.557502 -137.22858)
		(width 0.1651)
		(layer "In9.Cu")
		(net "P5E_PEX2_STN1_TX_DN<31>")
	)
	(segment
		(start 305.985418 -280.319988)
		(end 305.744626 -280.319988)
		(width 0.1143)
		(layer "In9.Cu")
		(net "P5E_PEX2_STN1_TX_DN<31>")
	)
	(segment
		(start 269.67688 -136.131554)
		(end 269.96771 -135.840724)
		(width 0.1651)
		(layer "In9.Cu")
		(net "P5E_PEX2_STN1_TX_DN<31>")
	)
	(segment
		(start 305.744626 -280.319988)
		(end 305.529488 -280.10485)
		(width 0.1143)
		(layer "In9.Cu")
		(net "P5E_PEX2_STN1_TX_DN<31>")
	)
	(segment
		(start 268.950694 -136.131554)
		(end 269.67688 -136.131554)
		(width 0.1651)
		(layer "In9.Cu")
		(net "P5E_PEX2_STN1_TX_DN<31>")
	)
	(segment
		(start 268.557502 -137.22858)
		(end 268.557502 -136.524746)
		(width 0.1651)
		(layer "In9.Cu")
		(net "P5E_PEX2_STN1_TX_DN<31>")
	)
	(segment
		(start 268.557502 -136.524746)
		(end 268.950694 -136.131554)
		(width 0.1651)
		(layer "In9.Cu")
		(net "P5E_PEX2_STN1_TX_DN<31>")
	)
	(segment
		(start 279.324308 -185.333386)
		(end 270.219424 -139.489688)
		(width 0.1651)
		(layer "In9.Cu")
		(net "P5E_PEX2_STN1_TX_DN<31>")
	)
	(segment
		(start 305.483768 -271.554448)
		(end 305.483768 -271.526)
		(width 0.1143)
		(layer "In9.Cu")
		(net "P5E_PEX2_STN1_TX_DN<31>")
	)
	(segment
		(start 270.219424 -139.489688)
		(end 269.795752 -138.46683)
		(width 0.1651)
		(layer "In9.Cu")
		(net "P5E_PEX2_STN1_TX_DN<31>")
	)
	(segment
		(start 305.529488 -280.10485)
		(end 305.529488 -271.600168)
		(width 0.1143)
		(layer "In9.Cu")
		(net "P5E_PEX2_STN1_TX_DN<31>")
	)
	(segment
		(start 306.099718 -280.699718)
		(end 306.099718 -280.434288)
		(width 0.1143)
		(layer "In9.Cu")
		(net "P5E_PEX2_STN1_TX_DN<31>")
	)
	(segment
		(start 152.471628 -123.71324)
		(end 152.151588 -123.3932)
		(width 0.13462)
		(layer "F.Cu")
		(net "P5E_PEX1_STN1_TX_DN<26>")
	)
	(segment
		(start 151.520144 -123.3932)
		(end 151.225504 -123.68784)
		(width 0.13462)
		(layer "F.Cu")
		(net "P5E_PEX1_STN1_TX_DN<26>")
	)
	(segment
		(start 152.151588 -123.3932)
		(end 151.520144 -123.3932)
		(width 0.13462)
		(layer "F.Cu")
		(net "P5E_PEX1_STN1_TX_DN<26>")
	)
	(segment
		(start 148.327872 -128.115314)
		(end 148.178266 -128.17729)
		(width 0.1651)
		(layer "In9.Cu")
		(net "P5E_PEX1_STN1_TX_DN<26>")
	)
	(segment
		(start 146.26463 -132.797296)
		(end 146.26463 -136.960356)
		(width 0.1651)
		(layer "In9.Cu")
		(net "P5E_PEX1_STN1_TX_DN<26>")
	)
	(segment
		(start 149.565868 -158.050738)
		(end 149.835616 -159.407098)
		(width 0.1651)
		(layer "In9.Cu")
		(net "P5E_PEX1_STN1_TX_DN<26>")
	)
	(segment
		(start 147.41398 -130.321558)
		(end 147.264374 -130.383534)
		(width 0.1651)
		(layer "In9.Cu")
		(net "P5E_PEX1_STN1_TX_DN<26>")
	)
	(segment
		(start 148.784818 -127.011938)
		(end 148.635212 -127.073914)
		(width 0.1651)
		(layer "In9.Cu")
		(net "P5E_PEX1_STN1_TX_DN<26>")
	)
	(segment
		(start 150.049484 -159.960564)
		(end 149.969474 -160.079944)
		(width 0.1651)
		(layer "In9.Cu")
		(net "P5E_PEX1_STN1_TX_DN<26>")
	)
	(segment
		(start 147.264374 -130.383534)
		(end 147.264374 -130.383788)
		(width 0.1651)
		(layer "In9.Cu")
		(net "P5E_PEX1_STN1_TX_DN<26>")
	)
	(segment
		(start 149.821392 -124.210318)
		(end 149.883368 -124.35967)
		(width 0.1651)
		(layer "In9.Cu")
		(net "P5E_PEX1_STN1_TX_DN<26>")
	)
	(segment
		(start 150.20671 -161.272474)
		(end 184.916064 -263.80948)
		(width 0.1651)
		(layer "In9.Cu")
		(net "P5E_PEX1_STN1_TX_DN<26>")
	)
	(segment
		(start 149.69871 -124.805694)
		(end 149.549104 -124.86767)
		(width 0.1651)
		(layer "In9.Cu")
		(net "P5E_PEX1_STN1_TX_DN<26>")
	)
	(segment
		(start 149.883368 -124.35967)
		(end 149.69871 -124.805694)
		(width 0.1651)
		(layer "In9.Cu")
		(net "P5E_PEX1_STN1_TX_DN<26>")
	)
	(segment
		(start 147.00504 -131.010152)
		(end 147.067016 -131.159504)
		(width 0.1651)
		(layer "In9.Cu")
		(net "P5E_PEX1_STN1_TX_DN<26>")
	)
	(segment
		(start 148.9075 -126.416562)
		(end 148.969476 -126.565914)
		(width 0.1651)
		(layer "In9.Cu")
		(net "P5E_PEX1_STN1_TX_DN<26>")
	)
	(segment
		(start 149.969474 -160.079944)
		(end 150.20671 -161.272474)
		(width 0.1651)
		(layer "In9.Cu")
		(net "P5E_PEX1_STN1_TX_DN<26>")
	)
	(segment
		(start 185.24982 -278.115268)
		(end 185.24982 -277.849838)
		(width 0.1143)
		(layer "In9.Cu")
		(net "P5E_PEX1_STN1_TX_DN<26>")
	)
	(segment
		(start 148.635212 -127.073914)
		(end 148.635212 -127.074168)
		(width 0.1651)
		(layer "In9.Cu")
		(net "P5E_PEX1_STN1_TX_DN<26>")
	)
	(segment
		(start 147.264374 -130.383788)
		(end 147.00504 -131.010152)
		(width 0.1651)
		(layer "In9.Cu")
		(net "P5E_PEX1_STN1_TX_DN<26>")
	)
	(segment
		(start 149.092158 -125.970792)
		(end 148.9075 -126.416562)
		(width 0.1651)
		(layer "In9.Cu")
		(net "P5E_PEX1_STN1_TX_DN<26>")
	)
	(segment
		(start 150.298658 -123.39701)
		(end 150.058882 -123.636786)
		(width 0.1651)
		(layer "In9.Cu")
		(net "P5E_PEX1_STN1_TX_DN<26>")
	)
	(segment
		(start 184.916064 -263.80948)
		(end 184.916064 -271.471898)
		(width 0.1651)
		(layer "In9.Cu")
		(net "P5E_PEX1_STN1_TX_DN<26>")
	)
	(segment
		(start 147.598638 -129.875534)
		(end 147.41398 -130.321558)
		(width 0.1651)
		(layer "In9.Cu")
		(net "P5E_PEX1_STN1_TX_DN<26>")
	)
	(segment
		(start 184.973722 -278.229568)
		(end 185.13552 -278.229568)
		(width 0.1143)
		(layer "In9.Cu")
		(net "P5E_PEX1_STN1_TX_DN<26>")
	)
	(segment
		(start 147.72132 -129.280412)
		(end 147.536662 -129.726182)
		(width 0.1651)
		(layer "In9.Cu")
		(net "P5E_PEX1_STN1_TX_DN<26>")
	)
	(segment
		(start 148.51253 -127.66929)
		(end 148.327872 -128.115314)
		(width 0.1651)
		(layer "In9.Cu")
		(net "P5E_PEX1_STN1_TX_DN<26>")
	)
	(segment
		(start 150.934674 -123.39701)
		(end 150.298658 -123.39701)
		(width 0.1651)
		(layer "In9.Cu")
		(net "P5E_PEX1_STN1_TX_DN<26>")
	)
	(segment
		(start 149.426422 -125.462792)
		(end 149.241764 -125.908816)
		(width 0.1651)
		(layer "In9.Cu")
		(net "P5E_PEX1_STN1_TX_DN<26>")
	)
	(segment
		(start 149.241764 -125.908816)
		(end 149.092158 -125.970792)
		(width 0.1651)
		(layer "In9.Cu")
		(net "P5E_PEX1_STN1_TX_DN<26>")
	)
	(segment
		(start 148.178266 -128.17729)
		(end 147.993608 -128.62306)
		(width 0.1651)
		(layer "In9.Cu")
		(net "P5E_PEX1_STN1_TX_DN<26>")
	)
	(segment
		(start 184.916064 -271.500346)
		(end 184.870344 -271.546066)
		(width 0.1143)
		(layer "In9.Cu")
		(net "P5E_PEX1_STN1_TX_DN<26>")
	)
	(segment
		(start 147.536662 -129.726182)
		(end 147.598638 -129.875534)
		(width 0.1651)
		(layer "In9.Cu")
		(net "P5E_PEX1_STN1_TX_DN<26>")
	)
	(segment
		(start 184.870344 -278.12619)
		(end 184.973722 -278.229568)
		(width 0.1143)
		(layer "In9.Cu")
		(net "P5E_PEX1_STN1_TX_DN<26>")
	)
	(segment
		(start 147.067016 -131.159504)
		(end 146.882104 -131.605528)
		(width 0.1651)
		(layer "In9.Cu")
		(net "P5E_PEX1_STN1_TX_DN<26>")
	)
	(segment
		(start 150.058882 -123.636786)
		(end 149.821392 -124.210318)
		(width 0.1651)
		(layer "In9.Cu")
		(net "P5E_PEX1_STN1_TX_DN<26>")
	)
	(segment
		(start 184.870344 -271.546066)
		(end 184.870344 -278.12619)
		(width 0.1143)
		(layer "In9.Cu")
		(net "P5E_PEX1_STN1_TX_DN<26>")
	)
	(segment
		(start 148.635212 -127.074168)
		(end 148.450554 -127.519938)
		(width 0.1651)
		(layer "In9.Cu")
		(net "P5E_PEX1_STN1_TX_DN<26>")
	)
	(segment
		(start 148.833332 -143.161004)
		(end 149.565868 -158.050738)
		(width 0.1651)
		(layer "In9.Cu")
		(net "P5E_PEX1_STN1_TX_DN<26>")
	)
	(segment
		(start 146.26463 -136.960356)
		(end 148.833332 -143.161004)
		(width 0.1651)
		(layer "In9.Cu")
		(net "P5E_PEX1_STN1_TX_DN<26>")
	)
	(segment
		(start 146.732498 -131.66725)
		(end 146.732752 -131.66725)
		(width 0.1651)
		(layer "In9.Cu")
		(net "P5E_PEX1_STN1_TX_DN<26>")
	)
	(segment
		(start 149.549104 -124.86767)
		(end 149.364446 -125.31344)
		(width 0.1651)
		(layer "In9.Cu")
		(net "P5E_PEX1_STN1_TX_DN<26>")
	)
	(segment
		(start 148.450554 -127.519938)
		(end 148.51253 -127.66929)
		(width 0.1651)
		(layer "In9.Cu")
		(net "P5E_PEX1_STN1_TX_DN<26>")
	)
	(segment
		(start 147.870926 -129.218436)
		(end 147.72132 -129.280412)
		(width 0.1651)
		(layer "In9.Cu")
		(net "P5E_PEX1_STN1_TX_DN<26>")
	)
	(segment
		(start 148.055584 -128.772412)
		(end 147.870926 -129.218436)
		(width 0.1651)
		(layer "In9.Cu")
		(net "P5E_PEX1_STN1_TX_DN<26>")
	)
	(segment
		(start 146.732752 -131.66725)
		(end 146.26463 -132.797296)
		(width 0.1651)
		(layer "In9.Cu")
		(net "P5E_PEX1_STN1_TX_DN<26>")
	)
	(segment
		(start 149.835616 -159.407098)
		(end 149.95525 -159.487108)
		(width 0.1651)
		(layer "In9.Cu")
		(net "P5E_PEX1_STN1_TX_DN<26>")
	)
	(segment
		(start 147.993608 -128.62306)
		(end 148.055584 -128.772412)
		(width 0.1651)
		(layer "In9.Cu")
		(net "P5E_PEX1_STN1_TX_DN<26>")
	)
	(segment
		(start 149.364446 -125.31344)
		(end 149.426422 -125.462792)
		(width 0.1651)
		(layer "In9.Cu")
		(net "P5E_PEX1_STN1_TX_DN<26>")
	)
	(segment
		(start 148.969476 -126.565914)
		(end 148.784818 -127.011938)
		(width 0.1651)
		(layer "In9.Cu")
		(net "P5E_PEX1_STN1_TX_DN<26>")
	)
	(segment
		(start 146.882104 -131.605528)
		(end 146.732498 -131.66725)
		(width 0.1651)
		(layer "In9.Cu")
		(net "P5E_PEX1_STN1_TX_DN<26>")
	)
	(segment
		(start 184.916064 -271.471898)
		(end 184.916064 -271.500346)
		(width 0.1143)
		(layer "In9.Cu")
		(net "P5E_PEX1_STN1_TX_DN<26>")
	)
	(segment
		(start 149.95525 -159.487108)
		(end 150.049484 -159.960564)
		(width 0.1651)
		(layer "In9.Cu")
		(net "P5E_PEX1_STN1_TX_DN<26>")
	)
	(segment
		(start 151.225504 -123.68784)
		(end 150.934674 -123.39701)
		(width 0.1651)
		(layer "In9.Cu")
		(net "P5E_PEX1_STN1_TX_DN<26>")
	)
	(segment
		(start 185.13552 -278.229568)
		(end 185.24982 -278.115268)
		(width 0.1143)
		(layer "In9.Cu")
		(net "P5E_PEX1_STN1_TX_DN<26>")
	)
	(segment
		(start 181.408832 -355.658166)
		(end 181.408832 -355.026722)
		(width 0.13462)
		(layer "F.Cu")
		(net "P5E_PEX1_STN7_TX_DP<122>")
	)
	(segment
		(start 181.728872 -355.978206)
		(end 181.408832 -355.658166)
		(width 0.13462)
		(layer "F.Cu")
		(net "P5E_PEX1_STN7_TX_DP<122>")
	)
	(segment
		(start 181.408832 -355.026722)
		(end 181.703472 -354.732082)
		(width 0.13462)
		(layer "F.Cu")
		(net "P5E_PEX1_STN7_TX_DP<122>")
	)
	(segment
		(start 180.7337 -338.776564)
		(end 174.539402 -335.205578)
		(width 0.1651)
		(layer "In11.Cu")
		(net "P5E_PEX1_STN7_TX_DP<122>")
	)
	(segment
		(start 174.539402 -335.205578)
		(end 156.604462 -325.944484)
		(width 0.1651)
		(layer "In11.Cu")
		(net "P5E_PEX1_STN7_TX_DP<122>")
	)
	(segment
		(start 156.604462 -325.944484)
		(end 152.55748 -321.719702)
		(width 0.1651)
		(layer "In11.Cu")
		(net "P5E_PEX1_STN7_TX_DP<122>")
	)
	(segment
		(start 152.448514 -315.68898)
		(end 152.667462 -315.470032)
		(width 0.1143)
		(layer "In11.Cu")
		(net "P5E_PEX1_STN7_TX_DP<122>")
	)
	(segment
		(start 181.412642 -354.441252)
		(end 181.412642 -353.799902)
		(width 0.1651)
		(layer "In11.Cu")
		(net "P5E_PEX1_STN7_TX_DP<122>")
	)
	(segment
		(start 151.30907 -316.892686)
		(end 152.43302 -315.768736)
		(width 0.1651)
		(layer "In11.Cu")
		(net "P5E_PEX1_STN7_TX_DP<122>")
	)
	(segment
		(start 153.243534 -315.470032)
		(end 153.52014 -315.193426)
		(width 0.1143)
		(layer "In11.Cu")
		(net "P5E_PEX1_STN7_TX_DP<122>")
	)
	(segment
		(start 153.60904 -314.899802)
		(end 153.89987 -314.899802)
		(width 0.1143)
		(layer "In11.Cu")
		(net "P5E_PEX1_STN7_TX_DP<122>")
	)
	(segment
		(start 153.52014 -315.193426)
		(end 153.52014 -314.988702)
		(width 0.1143)
		(layer "In11.Cu")
		(net "P5E_PEX1_STN7_TX_DP<122>")
	)
	(segment
		(start 151.30907 -317.60668)
		(end 151.30907 -316.892686)
		(width 0.1651)
		(layer "In11.Cu")
		(net "P5E_PEX1_STN7_TX_DP<122>")
	)
	(segment
		(start 152.667462 -315.470032)
		(end 153.243534 -315.470032)
		(width 0.1143)
		(layer "In11.Cu")
		(net "P5E_PEX1_STN7_TX_DP<122>")
	)
	(segment
		(start 152.448514 -315.753242)
		(end 152.448514 -315.68898)
		(width 0.1143)
		(layer "In11.Cu")
		(net "P5E_PEX1_STN7_TX_DP<122>")
	)
	(segment
		(start 152.43302 -315.768736)
		(end 152.448514 -315.753242)
		(width 0.1143)
		(layer "In11.Cu")
		(net "P5E_PEX1_STN7_TX_DP<122>")
	)
	(segment
		(start 182.967122 -352.245422)
		(end 182.967122 -341.197946)
		(width 0.1651)
		(layer "In11.Cu")
		(net "P5E_PEX1_STN7_TX_DP<122>")
	)
	(segment
		(start 181.412642 -353.799902)
		(end 182.967122 -352.245422)
		(width 0.1651)
		(layer "In11.Cu")
		(net "P5E_PEX1_STN7_TX_DP<122>")
	)
	(segment
		(start 181.703472 -354.732082)
		(end 181.412642 -354.441252)
		(width 0.1651)
		(layer "In11.Cu")
		(net "P5E_PEX1_STN7_TX_DP<122>")
	)
	(segment
		(start 182.967122 -341.197946)
		(end 180.7337 -338.776564)
		(width 0.1651)
		(layer "In11.Cu")
		(net "P5E_PEX1_STN7_TX_DP<122>")
	)
	(segment
		(start 152.55748 -321.719702)
		(end 151.30907 -317.60668)
		(width 0.1651)
		(layer "In11.Cu")
		(net "P5E_PEX1_STN7_TX_DP<122>")
	)
	(segment
		(start 153.52014 -314.988702)
		(end 153.60904 -314.899802)
		(width 0.1143)
		(layer "In11.Cu")
		(net "P5E_PEX1_STN7_TX_DP<122>")
	)
	(segment
		(start 316.086998 -144.709388)
		(end 315.440822 -144.709388)
		(width 0.13462)
		(layer "F.Cu")
		(net "P5E_PEX2_STN0_TX_DN<9>")
	)
	(segment
		(start 316.374272 -144.422114)
		(end 316.086998 -144.709388)
		(width 0.13462)
		(layer "F.Cu")
		(net "P5E_PEX2_STN0_TX_DN<9>")
	)
	(segment
		(start 315.440822 -144.709388)
		(end 315.128148 -144.396714)
		(width 0.13462)
		(layer "F.Cu")
		(net "P5E_PEX2_STN0_TX_DN<9>")
	)
	(segment
		(start 312.635392 -278.229568)
		(end 312.749692 -278.115268)
		(width 0.1143)
		(layer "In9.Cu")
		(net "P5E_PEX2_STN0_TX_DN<9>")
	)
	(segment
		(start 312.415936 -271.357344)
		(end 312.415936 -271.471898)
		(width 0.1651)
		(layer "In9.Cu")
		(net "P5E_PEX2_STN0_TX_DN<9>")
	)
	(segment
		(start 317.372746 -144.712944)
		(end 319.527428 -146.867626)
		(width 0.1651)
		(layer "In9.Cu")
		(net "P5E_PEX2_STN0_TX_DN<9>")
	)
	(segment
		(start 312.370216 -278.12619)
		(end 312.473594 -278.229568)
		(width 0.1143)
		(layer "In9.Cu")
		(net "P5E_PEX2_STN0_TX_DN<9>")
	)
	(segment
		(start 323.661786 -154.593036)
		(end 323.661786 -158.27502)
		(width 0.1651)
		(layer "In9.Cu")
		(net "P5E_PEX2_STN0_TX_DN<9>")
	)
	(segment
		(start 310.035448 -221.85376)
		(end 313.39663 -260.314694)
		(width 0.1651)
		(layer "In9.Cu")
		(net "P5E_PEX2_STN0_TX_DN<9>")
	)
	(segment
		(start 316.374272 -144.422114)
		(end 316.665102 -144.712944)
		(width 0.1651)
		(layer "In9.Cu")
		(net "P5E_PEX2_STN0_TX_DN<9>")
	)
	(segment
		(start 312.415936 -271.471898)
		(end 312.415936 -271.500346)
		(width 0.1143)
		(layer "In9.Cu")
		(net "P5E_PEX2_STN0_TX_DN<9>")
	)
	(segment
		(start 321.985386 -150.546054)
		(end 323.661786 -154.593036)
		(width 0.1651)
		(layer "In9.Cu")
		(net "P5E_PEX2_STN0_TX_DN<9>")
	)
	(segment
		(start 313.39663 -260.314694)
		(end 313.39663 -268.989302)
		(width 0.1651)
		(layer "In9.Cu")
		(net "P5E_PEX2_STN0_TX_DN<9>")
	)
	(segment
		(start 323.661786 -158.27502)
		(end 315.17844 -172.971714)
		(width 0.1651)
		(layer "In9.Cu")
		(net "P5E_PEX2_STN0_TX_DN<9>")
	)
	(segment
		(start 316.665102 -144.712944)
		(end 317.372746 -144.712944)
		(width 0.1651)
		(layer "In9.Cu")
		(net "P5E_PEX2_STN0_TX_DN<9>")
	)
	(segment
		(start 319.527428 -146.867626)
		(end 321.985386 -150.546054)
		(width 0.1651)
		(layer "In9.Cu")
		(net "P5E_PEX2_STN0_TX_DN<9>")
	)
	(segment
		(start 313.898534 -177.74412)
		(end 310.035448 -221.85376)
		(width 0.1651)
		(layer "In9.Cu")
		(net "P5E_PEX2_STN0_TX_DN<9>")
	)
	(segment
		(start 312.473594 -278.229568)
		(end 312.635392 -278.229568)
		(width 0.1143)
		(layer "In9.Cu")
		(net "P5E_PEX2_STN0_TX_DN<9>")
	)
	(segment
		(start 315.17844 -172.971714)
		(end 313.898534 -177.74412)
		(width 0.1651)
		(layer "In9.Cu")
		(net "P5E_PEX2_STN0_TX_DN<9>")
	)
	(segment
		(start 312.370216 -271.546066)
		(end 312.370216 -278.12619)
		(width 0.1143)
		(layer "In9.Cu")
		(net "P5E_PEX2_STN0_TX_DN<9>")
	)
	(segment
		(start 312.749692 -278.115268)
		(end 312.749692 -277.849838)
		(width 0.1143)
		(layer "In9.Cu")
		(net "P5E_PEX2_STN0_TX_DN<9>")
	)
	(segment
		(start 312.415936 -271.500346)
		(end 312.370216 -271.546066)
		(width 0.1143)
		(layer "In9.Cu")
		(net "P5E_PEX2_STN0_TX_DN<9>")
	)
	(segment
		(start 313.39663 -268.989302)
		(end 312.415936 -271.357344)
		(width 0.1651)
		(layer "In9.Cu")
		(net "P5E_PEX2_STN0_TX_DN<9>")
	)
	(segment
		(start 187.921392 -357.733854)
		(end 187.626752 -357.439214)
		(width 0.13462)
		(layer "F.Cu")
		(net "P5E_PEX1_STN7_TX_C_DN<125>")
	)
	(segment
		(start 187.626752 -357.439214)
		(end 187.626752 -356.80777)
		(width 0.13462)
		(layer "F.Cu")
		(net "P5E_PEX1_STN7_TX_C_DN<125>")
	)
	(segment
		(start 187.626752 -356.80777)
		(end 187.946792 -356.48773)
		(width 0.13462)
		(layer "F.Cu")
		(net "P5E_PEX1_STN7_TX_C_DN<125>")
	)
	(segment
		(start 171.036996 -376.281188)
		(end 170.909996 -376.408188)
		(width 0.1651)
		(layer "In11.Cu")
		(net "P5E_PEX1_STN7_TX_C_DN<125>")
	)
	(segment
		(start 172.067474 -375.589038)
		(end 171.375324 -376.281188)
		(width 0.1651)
		(layer "In11.Cu")
		(net "P5E_PEX1_STN7_TX_C_DN<125>")
	)
	(segment
		(start 187.630562 -358.024684)
		(end 187.630562 -359.20934)
		(width 0.1651)
		(layer "In11.Cu")
		(net "P5E_PEX1_STN7_TX_C_DN<125>")
	)
	(segment
		(start 172.067474 -368.916458)
		(end 172.067474 -375.589038)
		(width 0.1651)
		(layer "In11.Cu")
		(net "P5E_PEX1_STN7_TX_C_DN<125>")
	)
	(segment
		(start 170.909996 -376.408188)
		(end 170.909996 -376.790204)
		(width 0.1651)
		(layer "In11.Cu")
		(net "P5E_PEX1_STN7_TX_C_DN<125>")
	)
	(segment
		(start 183.015128 -363.824774)
		(end 172.922438 -368.061494)
		(width 0.1651)
		(layer "In11.Cu")
		(net "P5E_PEX1_STN7_TX_C_DN<125>")
	)
	(segment
		(start 187.630562 -359.20934)
		(end 183.015128 -363.824774)
		(width 0.1651)
		(layer "In11.Cu")
		(net "P5E_PEX1_STN7_TX_C_DN<125>")
	)
	(segment
		(start 172.922438 -368.061494)
		(end 172.067474 -368.916458)
		(width 0.1651)
		(layer "In11.Cu")
		(net "P5E_PEX1_STN7_TX_C_DN<125>")
	)
	(segment
		(start 187.921392 -357.733854)
		(end 187.630562 -358.024684)
		(width 0.1651)
		(layer "In11.Cu")
		(net "P5E_PEX1_STN7_TX_C_DN<125>")
	)
	(segment
		(start 171.375324 -376.281188)
		(end 171.036996 -376.281188)
		(width 0.1651)
		(layer "In11.Cu")
		(net "P5E_PEX1_STN7_TX_C_DN<125>")
	)
	(segment
		(start 196.385942 -129.880106)
		(end 196.705982 -130.200146)
		(width 0.13462)
		(layer "F.Cu")
		(net "P5E_PEX1_STN0_TX_DN<4>")
	)
	(segment
		(start 196.705982 -130.200146)
		(end 197.337426 -130.200146)
		(width 0.13462)
		(layer "F.Cu")
		(net "P5E_PEX1_STN0_TX_DN<4>")
	)
	(segment
		(start 197.337426 -130.200146)
		(end 197.632066 -129.905506)
		(width 0.13462)
		(layer "F.Cu")
		(net "P5E_PEX1_STN0_TX_DN<4>")
	)
	(segment
		(start 203.653136 -174.772828)
		(end 202.60818 -178.670712)
		(width 0.1651)
		(layer "In9.Cu")
		(net "P5E_PEX1_STN0_TX_DN<4>")
	)
	(segment
		(start 212.400642 -159.455866)
		(end 212.321394 -159.752792)
		(width 0.1651)
		(layer "In9.Cu")
		(net "P5E_PEX1_STN0_TX_DN<4>")
	)
	(segment
		(start 208.52638 -144.276572)
		(end 208.698592 -144.448784)
		(width 0.1651)
		(layer "In9.Cu")
		(net "P5E_PEX1_STN0_TX_DN<4>")
	)
	(segment
		(start 193.52387 -284.120082)
		(end 193.420238 -284.223714)
		(width 0.1143)
		(layer "In9.Cu")
		(net "P5E_PEX1_STN0_TX_DN<4>")
	)
	(segment
		(start 212.564726 -268.181582)
		(end 212.91169 -272.151602)
		(width 0.1651)
		(layer "In9.Cu")
		(net "P5E_PEX1_STN0_TX_DN<4>")
	)
	(segment
		(start 212.321394 -159.752792)
		(end 203.653136 -174.772828)
		(width 0.1651)
		(layer "In9.Cu")
		(net "P5E_PEX1_STN0_TX_DN<4>")
	)
	(segment
		(start 212.400642 -153.386282)
		(end 212.400642 -159.455866)
		(width 0.1651)
		(layer "In9.Cu")
		(net "P5E_PEX1_STN0_TX_DN<4>")
	)
	(segment
		(start 200.36028 -130.196336)
		(end 201.427588 -130.63855)
		(width 0.1651)
		(layer "In9.Cu")
		(net "P5E_PEX1_STN0_TX_DN<4>")
	)
	(segment
		(start 197.632066 -129.905506)
		(end 197.922896 -130.196336)
		(width 0.1651)
		(layer "In9.Cu")
		(net "P5E_PEX1_STN0_TX_DN<4>")
	)
	(segment
		(start 198.85279 -221.593156)
		(end 201.396854 -250.731782)
		(width 0.1651)
		(layer "In9.Cu")
		(net "P5E_PEX1_STN0_TX_DN<4>")
	)
	(segment
		(start 193.534538 -284.499812)
		(end 193.799968 -284.499812)
		(width 0.1143)
		(layer "In9.Cu")
		(net "P5E_PEX1_STN0_TX_DN<4>")
	)
	(segment
		(start 201.1299 -284.165802)
		(end 200.017634 -284.165802)
		(width 0.1651)
		(layer "In9.Cu")
		(net "P5E_PEX1_STN0_TX_DN<4>")
	)
	(segment
		(start 203.90231 -133.113272)
		(end 208.52638 -144.276572)
		(width 0.1651)
		(layer "In9.Cu")
		(net "P5E_PEX1_STN0_TX_DN<4>")
	)
	(segment
		(start 203.331064 -283.253942)
		(end 201.1299 -284.165802)
		(width 0.1651)
		(layer "In9.Cu")
		(net "P5E_PEX1_STN0_TX_DN<4>")
	)
	(segment
		(start 211.763864 -266.247626)
		(end 212.564726 -268.181582)
		(width 0.1651)
		(layer "In9.Cu")
		(net "P5E_PEX1_STN0_TX_DN<4>")
	)
	(segment
		(start 193.420238 -284.385512)
		(end 193.534538 -284.499812)
		(width 0.1143)
		(layer "In9.Cu")
		(net "P5E_PEX1_STN0_TX_DN<4>")
	)
	(segment
		(start 199.989186 -284.165802)
		(end 199.943466 -284.120082)
		(width 0.1143)
		(layer "In9.Cu")
		(net "P5E_PEX1_STN0_TX_DN<4>")
	)
	(segment
		(start 197.922896 -130.196336)
		(end 200.36028 -130.196336)
		(width 0.1651)
		(layer "In9.Cu")
		(net "P5E_PEX1_STN0_TX_DN<4>")
	)
	(segment
		(start 201.396854 -250.731782)
		(end 211.763864 -266.247626)
		(width 0.1651)
		(layer "In9.Cu")
		(net "P5E_PEX1_STN0_TX_DN<4>")
	)
	(segment
		(start 193.420238 -284.223714)
		(end 193.420238 -284.385512)
		(width 0.1143)
		(layer "In9.Cu")
		(net "P5E_PEX1_STN0_TX_DN<4>")
	)
	(segment
		(start 211.835238 -274.749768)
		(end 203.331064 -283.253942)
		(width 0.1651)
		(layer "In9.Cu")
		(net "P5E_PEX1_STN0_TX_DN<4>")
	)
	(segment
		(start 200.017634 -284.165802)
		(end 199.989186 -284.165802)
		(width 0.1143)
		(layer "In9.Cu")
		(net "P5E_PEX1_STN0_TX_DN<4>")
	)
	(segment
		(start 199.943466 -284.120082)
		(end 193.52387 -284.120082)
		(width 0.1143)
		(layer "In9.Cu")
		(net "P5E_PEX1_STN0_TX_DN<4>")
	)
	(segment
		(start 208.698592 -144.448784)
		(end 212.400642 -153.386282)
		(width 0.1651)
		(layer "In9.Cu")
		(net "P5E_PEX1_STN0_TX_DN<4>")
	)
	(segment
		(start 201.427588 -130.63855)
		(end 203.90231 -133.113272)
		(width 0.1651)
		(layer "In9.Cu")
		(net "P5E_PEX1_STN0_TX_DN<4>")
	)
	(segment
		(start 202.60818 -178.670712)
		(end 198.85279 -221.593156)
		(width 0.1651)
		(layer "In9.Cu")
		(net "P5E_PEX1_STN0_TX_DN<4>")
	)
	(segment
		(start 212.91169 -272.151602)
		(end 211.835238 -274.749768)
		(width 0.1651)
		(layer "In9.Cu")
		(net "P5E_PEX1_STN0_TX_DN<4>")
	)
	(segment
		(start 121.757948 -348.88043)
		(end 122.052588 -348.58579)
		(width 0.13462)
		(layer "F.Cu")
		(net "P5E_PEX1_STN6_TX_DN<107>")
	)
	(segment
		(start 121.757948 -349.511874)
		(end 121.757948 -348.88043)
		(width 0.13462)
		(layer "F.Cu")
		(net "P5E_PEX1_STN6_TX_DN<107>")
	)
	(segment
		(start 122.077988 -349.831914)
		(end 121.757948 -349.511874)
		(width 0.13462)
		(layer "F.Cu")
		(net "P5E_PEX1_STN6_TX_DN<107>")
	)
	(segment
		(start 126.261114 -338.173568)
		(end 123.316238 -341.118444)
		(width 0.1651)
		(layer "In13.Cu")
		(net "P5E_PEX1_STN6_TX_DN<107>")
	)
	(segment
		(start 163.12388 -311.670192)
		(end 163.020248 -311.773824)
		(width 0.1143)
		(layer "In13.Cu")
		(net "P5E_PEX1_STN6_TX_DN<107>")
	)
	(segment
		(start 157.229048 -326.414892)
		(end 148.237702 -330.13904)
		(width 0.1651)
		(layer "In13.Cu")
		(net "P5E_PEX1_STN6_TX_DN<107>")
	)
	(segment
		(start 160.694116 -324.337426)
		(end 157.229048 -326.414892)
		(width 0.1651)
		(layer "In13.Cu")
		(net "P5E_PEX1_STN6_TX_DN<107>")
	)
	(segment
		(start 123.316238 -346.069412)
		(end 121.761758 -347.623892)
		(width 0.1651)
		(layer "In13.Cu")
		(net "P5E_PEX1_STN6_TX_DN<107>")
	)
	(segment
		(start 163.020248 -311.773824)
		(end 163.020248 -319.995296)
		(width 0.1143)
		(layer "In13.Cu")
		(net "P5E_PEX1_STN6_TX_DN<107>")
	)
	(segment
		(start 163.399978 -312.049922)
		(end 163.399978 -311.784492)
		(width 0.1143)
		(layer "In13.Cu")
		(net "P5E_PEX1_STN6_TX_DN<107>")
	)
	(segment
		(start 163.285678 -311.670192)
		(end 163.12388 -311.670192)
		(width 0.1143)
		(layer "In13.Cu")
		(net "P5E_PEX1_STN6_TX_DN<107>")
	)
	(segment
		(start 163.065968 -321.965574)
		(end 160.694116 -324.337426)
		(width 0.1651)
		(layer "In13.Cu")
		(net "P5E_PEX1_STN6_TX_DN<107>")
	)
	(segment
		(start 163.020248 -319.995296)
		(end 163.065968 -320.041016)
		(width 0.1143)
		(layer "In13.Cu")
		(net "P5E_PEX1_STN6_TX_DN<107>")
	)
	(segment
		(start 148.237702 -330.13904)
		(end 145.838418 -330.61529)
		(width 0.1651)
		(layer "In13.Cu")
		(net "P5E_PEX1_STN6_TX_DN<107>")
	)
	(segment
		(start 121.761758 -347.623892)
		(end 121.761758 -348.29496)
		(width 0.1651)
		(layer "In13.Cu")
		(net "P5E_PEX1_STN6_TX_DN<107>")
	)
	(segment
		(start 141.647418 -330.61529)
		(end 130.927094 -335.055972)
		(width 0.1651)
		(layer "In13.Cu")
		(net "P5E_PEX1_STN6_TX_DN<107>")
	)
	(segment
		(start 121.761758 -348.29496)
		(end 122.052588 -348.58579)
		(width 0.1651)
		(layer "In13.Cu")
		(net "P5E_PEX1_STN6_TX_DN<107>")
	)
	(segment
		(start 163.065968 -320.041016)
		(end 163.065968 -320.063114)
		(width 0.1143)
		(layer "In13.Cu")
		(net "P5E_PEX1_STN6_TX_DN<107>")
	)
	(segment
		(start 145.838418 -330.61529)
		(end 141.647418 -330.61529)
		(width 0.1651)
		(layer "In13.Cu")
		(net "P5E_PEX1_STN6_TX_DN<107>")
	)
	(segment
		(start 163.065968 -320.063114)
		(end 163.065968 -321.965574)
		(width 0.1651)
		(layer "In13.Cu")
		(net "P5E_PEX1_STN6_TX_DN<107>")
	)
	(segment
		(start 163.399978 -311.784492)
		(end 163.285678 -311.670192)
		(width 0.1143)
		(layer "In13.Cu")
		(net "P5E_PEX1_STN6_TX_DN<107>")
	)
	(segment
		(start 123.316238 -341.118444)
		(end 123.316238 -346.069412)
		(width 0.1651)
		(layer "In13.Cu")
		(net "P5E_PEX1_STN6_TX_DN<107>")
	)
	(segment
		(start 130.927094 -335.055972)
		(end 126.261114 -338.173568)
		(width 0.1651)
		(layer "In13.Cu")
		(net "P5E_PEX1_STN6_TX_DN<107>")
	)
	(segment
		(start 312.810906 -122.8598)
		(end 312.48604 -123.184666)
		(width 0.13462)
		(layer "F.Cu")
		(net "P5E_PEX2_STN0_TX_DP<2>")
	)
	(segment
		(start 313.432698 -122.8598)
		(end 312.810906 -122.8598)
		(width 0.13462)
		(layer "F.Cu")
		(net "P5E_PEX2_STN0_TX_DP<2>")
	)
	(segment
		(start 313.732164 -123.159266)
		(end 313.432698 -122.8598)
		(width 0.13462)
		(layer "F.Cu")
		(net "P5E_PEX2_STN0_TX_DP<2>")
	)
	(segment
		(start 319.518284 -127.722884)
		(end 319.693036 -128.145032)
		(width 0.1651)
		(layer "In9.Cu")
		(net "P5E_PEX2_STN0_TX_DP<2>")
	)
	(segment
		(start 319.210182 -127.245364)
		(end 319.385188 -127.66802)
		(width 0.1651)
		(layer "In9.Cu")
		(net "P5E_PEX2_STN0_TX_DP<2>")
	)
	(segment
		(start 316.08903 -285.784036)
		(end 316.04331 -285.829756)
		(width 0.1143)
		(layer "In9.Cu")
		(net "P5E_PEX2_STN0_TX_DP<2>")
	)
	(segment
		(start 318.83731 -126.080012)
		(end 318.782446 -126.2126)
		(width 0.1651)
		(layer "In9.Cu")
		(net "P5E_PEX2_STN0_TX_DP<2>")
	)
	(segment
		(start 318.21882 -124.286518)
		(end 318.530732 -125.040136)
		(width 0.1651)
		(layer "In9.Cu")
		(net "P5E_PEX2_STN0_TX_DP<2>")
	)
	(segment
		(start 321.304158 -175.418242)
		(end 320.379344 -178.865784)
		(width 0.1651)
		(layer "In9.Cu")
		(net "P5E_PEX2_STN0_TX_DP<2>")
	)
	(segment
		(start 330.263754 -267.760958)
		(end 330.670408 -272.403824)
		(width 0.1651)
		(layer "In9.Cu")
		(net "P5E_PEX2_STN0_TX_DP<2>")
	)
	(segment
		(start 313.732164 -123.159266)
		(end 314.022994 -122.868436)
		(width 0.1651)
		(layer "In9.Cu")
		(net "P5E_PEX2_STN0_TX_DP<2>")
	)
	(segment
		(start 322.176902 -133.421628)
		(end 330.154026 -152.6794)
		(width 0.1651)
		(layer "In9.Cu")
		(net "P5E_PEX2_STN0_TX_DP<2>")
	)
	(segment
		(start 329.225148 -265.25347)
		(end 330.263754 -267.760958)
		(width 0.1651)
		(layer "In9.Cu")
		(net "P5E_PEX2_STN0_TX_DP<2>")
	)
	(segment
		(start 322.04406 -133.36651)
		(end 322.176902 -133.421628)
		(width 0.1651)
		(layer "In9.Cu")
		(net "P5E_PEX2_STN0_TX_DP<2>")
	)
	(segment
		(start 309.54472 -285.829756)
		(end 309.329582 -286.044894)
		(width 0.1143)
		(layer "In9.Cu")
		(net "P5E_PEX2_STN0_TX_DP<2>")
	)
	(segment
		(start 320.240914 -129.733294)
		(end 320.37401 -129.788158)
		(width 0.1651)
		(layer "In9.Cu")
		(net "P5E_PEX2_STN0_TX_DP<2>")
	)
	(segment
		(start 318.782446 -126.2126)
		(end 318.957452 -126.635256)
		(width 0.1651)
		(layer "In9.Cu")
		(net "P5E_PEX2_STN0_TX_DP<2>")
	)
	(segment
		(start 309.329582 -286.044894)
		(end 309.329582 -286.285686)
		(width 0.1143)
		(layer "In9.Cu")
		(net "P5E_PEX2_STN0_TX_DP<2>")
	)
	(segment
		(start 316.635892 -221.701614)
		(end 319.11671 -250.126246)
		(width 0.1651)
		(layer "In9.Cu")
		(net "P5E_PEX2_STN0_TX_DP<2>")
	)
	(segment
		(start 320.493644 -130.343148)
		(end 320.66865 -130.765804)
		(width 0.1651)
		(layer "In9.Cu")
		(net "P5E_PEX2_STN0_TX_DP<2>")
	)
	(segment
		(start 315.649102 -122.970036)
		(end 316.106302 -122.970036)
		(width 0.1651)
		(layer "In9.Cu")
		(net "P5E_PEX2_STN0_TX_DP<2>")
	)
	(segment
		(start 318.530732 -125.040136)
		(end 318.645794 -125.617478)
		(width 0.1651)
		(layer "In9.Cu")
		(net "P5E_PEX2_STN0_TX_DP<2>")
	)
	(segment
		(start 316.207902 -122.868436)
		(end 316.800738 -122.868436)
		(width 0.1651)
		(layer "In9.Cu")
		(net "P5E_PEX2_STN0_TX_DP<2>")
	)
	(segment
		(start 321.923918 -132.811012)
		(end 321.869054 -132.943854)
		(width 0.1651)
		(layer "In9.Cu")
		(net "P5E_PEX2_STN0_TX_DP<2>")
	)
	(segment
		(start 316.800738 -122.868436)
		(end 318.21882 -124.286518)
		(width 0.1651)
		(layer "In9.Cu")
		(net "P5E_PEX2_STN0_TX_DP<2>")
	)
	(segment
		(start 319.385188 -127.66802)
		(end 319.518284 -127.722884)
		(width 0.1651)
		(layer "In9.Cu")
		(net "P5E_PEX2_STN0_TX_DP<2>")
	)
	(segment
		(start 321.749166 -132.388864)
		(end 321.923918 -132.811012)
		(width 0.1651)
		(layer "In9.Cu")
		(net "P5E_PEX2_STN0_TX_DP<2>")
	)
	(segment
		(start 329.316588 -275.671534)
		(end 320.354198 -284.633924)
		(width 0.1651)
		(layer "In9.Cu")
		(net "P5E_PEX2_STN0_TX_DP<2>")
	)
	(segment
		(start 316.117478 -285.784036)
		(end 316.08903 -285.784036)
		(width 0.1143)
		(layer "In9.Cu")
		(net "P5E_PEX2_STN0_TX_DP<2>")
	)
	(segment
		(start 319.813178 -128.70053)
		(end 319.946274 -128.755394)
		(width 0.1651)
		(layer "In9.Cu")
		(net "P5E_PEX2_STN0_TX_DP<2>")
	)
	(segment
		(start 321.869054 -132.943854)
		(end 322.04406 -133.36651)
		(width 0.1651)
		(layer "In9.Cu")
		(net "P5E_PEX2_STN0_TX_DP<2>")
	)
	(segment
		(start 320.373756 -129.788158)
		(end 320.548762 -130.210306)
		(width 0.1651)
		(layer "In9.Cu")
		(net "P5E_PEX2_STN0_TX_DP<2>")
	)
	(segment
		(start 314.022994 -122.868436)
		(end 315.547502 -122.868436)
		(width 0.1651)
		(layer "In9.Cu")
		(net "P5E_PEX2_STN0_TX_DP<2>")
	)
	(segment
		(start 318.957452 -126.635256)
		(end 319.090294 -126.690374)
		(width 0.1651)
		(layer "In9.Cu")
		(net "P5E_PEX2_STN0_TX_DP<2>")
	)
	(segment
		(start 309.329582 -286.285686)
		(end 309.215282 -286.399986)
		(width 0.1143)
		(layer "In9.Cu")
		(net "P5E_PEX2_STN0_TX_DP<2>")
	)
	(segment
		(start 316.04331 -285.829756)
		(end 309.54472 -285.829756)
		(width 0.1143)
		(layer "In9.Cu")
		(net "P5E_PEX2_STN0_TX_DP<2>")
	)
	(segment
		(start 319.090294 -126.690374)
		(end 319.2653 -127.112522)
		(width 0.1651)
		(layer "In9.Cu")
		(net "P5E_PEX2_STN0_TX_DP<2>")
	)
	(segment
		(start 315.547502 -122.868436)
		(end 315.649102 -122.970036)
		(width 0.1651)
		(layer "In9.Cu")
		(net "P5E_PEX2_STN0_TX_DP<2>")
	)
	(segment
		(start 317.577978 -285.784036)
		(end 316.117478 -285.784036)
		(width 0.1651)
		(layer "In9.Cu")
		(net "P5E_PEX2_STN0_TX_DP<2>")
	)
	(segment
		(start 319.11671 -250.126246)
		(end 329.225148 -265.25347)
		(width 0.1651)
		(layer "In9.Cu")
		(net "P5E_PEX2_STN0_TX_DP<2>")
	)
	(segment
		(start 319.946274 -128.755394)
		(end 319.94602 -128.755648)
		(width 0.1651)
		(layer "In9.Cu")
		(net "P5E_PEX2_STN0_TX_DP<2>")
	)
	(segment
		(start 318.645794 -125.617478)
		(end 318.83731 -126.080012)
		(width 0.1651)
		(layer "In9.Cu")
		(net "P5E_PEX2_STN0_TX_DP<2>")
	)
	(segment
		(start 320.66865 -130.765804)
		(end 320.801746 -130.820668)
		(width 0.1651)
		(layer "In9.Cu")
		(net "P5E_PEX2_STN0_TX_DP<2>")
	)
	(segment
		(start 320.379344 -178.865784)
		(end 316.633606 -221.67723)
		(width 0.1651)
		(layer "In9.Cu")
		(net "P5E_PEX2_STN0_TX_DP<2>")
	)
	(segment
		(start 319.94602 -128.755648)
		(end 320.121026 -129.177796)
		(width 0.1651)
		(layer "In9.Cu")
		(net "P5E_PEX2_STN0_TX_DP<2>")
	)
	(segment
		(start 320.065908 -129.310638)
		(end 320.240914 -129.733294)
		(width 0.1651)
		(layer "In9.Cu")
		(net "P5E_PEX2_STN0_TX_DP<2>")
	)
	(segment
		(start 316.106302 -122.970036)
		(end 316.207902 -122.868436)
		(width 0.1651)
		(layer "In9.Cu")
		(net "P5E_PEX2_STN0_TX_DP<2>")
	)
	(segment
		(start 316.635638 -221.701614)
		(end 316.635892 -221.701614)
		(width 0.1651)
		(layer "In9.Cu")
		(net "P5E_PEX2_STN0_TX_DP<2>")
	)
	(segment
		(start 321.240912 -131.88061)
		(end 321.749166 -132.388864)
		(width 0.1651)
		(layer "In9.Cu")
		(net "P5E_PEX2_STN0_TX_DP<2>")
	)
	(segment
		(start 320.548762 -130.210306)
		(end 320.493644 -130.343148)
		(width 0.1651)
		(layer "In9.Cu")
		(net "P5E_PEX2_STN0_TX_DP<2>")
	)
	(segment
		(start 320.801746 -130.820668)
		(end 321.240912 -131.88061)
		(width 0.1651)
		(layer "In9.Cu")
		(net "P5E_PEX2_STN0_TX_DP<2>")
	)
	(segment
		(start 319.693036 -128.145032)
		(end 319.638172 -128.277874)
		(width 0.1651)
		(layer "In9.Cu")
		(net "P5E_PEX2_STN0_TX_DP<2>")
	)
	(segment
		(start 320.37401 -129.788158)
		(end 320.373756 -129.788158)
		(width 0.1651)
		(layer "In9.Cu")
		(net "P5E_PEX2_STN0_TX_DP<2>")
	)
	(segment
		(start 319.638172 -128.277874)
		(end 319.813178 -128.70053)
		(width 0.1651)
		(layer "In9.Cu")
		(net "P5E_PEX2_STN0_TX_DP<2>")
	)
	(segment
		(start 330.154026 -159.674306)
		(end 329.950572 -160.435544)
		(width 0.1651)
		(layer "In9.Cu")
		(net "P5E_PEX2_STN0_TX_DP<2>")
	)
	(segment
		(start 330.670408 -272.403824)
		(end 329.316588 -275.671534)
		(width 0.1651)
		(layer "In9.Cu")
		(net "P5E_PEX2_STN0_TX_DP<2>")
	)
	(segment
		(start 319.2653 -127.112522)
		(end 319.210182 -127.245364)
		(width 0.1651)
		(layer "In9.Cu")
		(net "P5E_PEX2_STN0_TX_DP<2>")
	)
	(segment
		(start 320.354198 -284.633924)
		(end 317.577978 -285.784036)
		(width 0.1651)
		(layer "In9.Cu")
		(net "P5E_PEX2_STN0_TX_DP<2>")
	)
	(segment
		(start 309.215282 -286.399986)
		(end 308.949852 -286.399986)
		(width 0.1143)
		(layer "In9.Cu")
		(net "P5E_PEX2_STN0_TX_DP<2>")
	)
	(segment
		(start 316.633606 -221.67723)
		(end 316.635638 -221.701614)
		(width 0.1651)
		(layer "In9.Cu")
		(net "P5E_PEX2_STN0_TX_DP<2>")
	)
	(segment
		(start 320.121026 -129.177796)
		(end 320.065908 -129.310638)
		(width 0.1651)
		(layer "In9.Cu")
		(net "P5E_PEX2_STN0_TX_DP<2>")
	)
	(segment
		(start 329.950572 -160.435544)
		(end 321.304158 -175.418242)
		(width 0.1651)
		(layer "In9.Cu")
		(net "P5E_PEX2_STN0_TX_DP<2>")
	)
	(segment
		(start 330.154026 -152.6794)
		(end 330.154026 -159.674306)
		(width 0.1651)
		(layer "In9.Cu")
		(net "P5E_PEX2_STN0_TX_DP<2>")
	)
	(segment
		(start 191.817498 -402.272246)
		(end 191.817498 -401.528534)
		(width 0.4572)
		(layer "F.Cu")
		(net "P12V_AUX")
	)
	(segment
		(start 239.754664 -206.11211)
		(end 240.008664 -205.85811)
		(width 0.4572)
		(layer "F.Cu")
		(net "P12V_AUX")
	)
	(segment
		(start 195.656962 -412.10484)
		(end 196.435472 -411.32633)
		(width 0.4572)
		(layer "F.Cu")
		(net "P12V_AUX")
	)
	(segment
		(start 240.008664 -205.85811)
		(end 240.008664 -205.47711)
		(width 0.4572)
		(layer "F.Cu")
		(net "P12V_AUX")
	)
	(segment
		(start 189.210696 -410.195522)
		(end 189.210696 -410.898086)
		(width 0.4572)
		(layer "F.Cu")
		(net "P12V_AUX")
	)
	(segment
		(start 195.975478 -368.26698)
		(end 195.975478 -367.491772)
		(width 0.381)
		(layer "F.Cu")
		(net "P12V_AUX")
	)
	(segment
		(start 188.806074 -414.183576)
		(end 188.806074 -413.479234)
		(width 0.4572)
		(layer "F.Cu")
		(net "P12V_AUX")
	)
	(segment
		(start 196.810376 -411.32633)
		(end 197.62343 -411.32633)
		(width 0.4572)
		(layer "F.Cu")
		(net "P12V_AUX")
	)
	(segment
		(start 264.90295 -336.065368)
		(end 266.151868 -336.065368)
		(width 0.4572)
		(layer "F.Cu")
		(net "P12V_AUX")
	)
	(segment
		(start 241.003328 -348.400116)
		(end 241.765328 -348.400116)
		(width 0.4572)
		(layer "F.Cu")
		(net "P12V_AUX")
	)
	(segment
		(start 266.283694 -339.479636)
		(end 266.497816 -339.693758)
		(width 0.4572)
		(layer "F.Cu")
		(net "P12V_AUX")
	)
	(segment
		(start 194.695064 -412.10484)
		(end 195.656962 -412.10484)
		(width 0.4572)
		(layer "F.Cu")
		(net "P12V_AUX")
	)
	(segment
		(start 266.151868 -336.065368)
		(end 266.283694 -336.197194)
		(width 0.4572)
		(layer "F.Cu")
		(net "P12V_AUX")
	)
	(segment
		(start 196.435472 -411.32633)
		(end 196.810376 -411.32633)
		(width 0.4572)
		(layer "F.Cu")
		(net "P12V_AUX")
	)
	(segment
		(start 189.77356 -402.26869)
		(end 189.77356 -401.65909)
		(width 0.4572)
		(layer "F.Cu")
		(net "P12V_AUX")
	)
	(segment
		(start 266.283694 -336.197194)
		(end 266.283694 -339.479636)
		(width 0.4572)
		(layer "F.Cu")
		(net "P12V_AUX")
	)
	(segment
		(start 222.576644 -175.50638)
		(end 223.186244 -175.50638)
		(width 0.4572)
		(layer "F.Cu")
		(net "P12V_AUX")
	)
	(segment
		(start 243.577872 -348.400116)
		(end 241.765328 -348.400116)
		(width 0.4572)
		(layer "F.Cu")
		(net "P12V_AUX")
	)
	(via
		(at 217.463624 -56.313832)
		(size 0.508)
		(drill 0.254)
		(layers "F.Cu" "B.Cu")
		(net "P12V_AUX")
	)
	(via
		(at 231.633776 -365.343186)
		(size 0.508)
		(drill 0.254)
		(layers "F.Cu" "B.Cu")
		(net "P12V_AUX")
	)
	(via
		(at 450.218302 -98.476308)
		(size 0.508)
		(drill 0.254)
		(layers "F.Cu" "B.Cu")
		(net "P12V_AUX")
	)
	(via
		(at 422.360598 -52.518818)
		(size 0.508)
		(drill 0.254)
		(layers "F.Cu" "B.Cu")
		(net "P12V_AUX")
	)
	(via
		(at 217.917776 -363.819186)
		(size 0.508)
		(drill 0.254)
		(layers "F.Cu" "B.Cu")
		(net "P12V_AUX")
	)
	(via
		(at 358.102154 -268.756638)
		(size 0.508)
		(drill 0.254)
		(layers "F.Cu" "B.Cu")
		(net "P12V_AUX")
	)
	(via
		(at 74.501756 -63.18631)
		(size 0.508)
		(drill 0.254)
		(layers "F.Cu" "B.Cu")
		(net "P12V_AUX")
	)
	(via
		(at 448.541902 -98.908108)
		(size 0.508)
		(drill 0.254)
		(layers "F.Cu" "B.Cu")
		(net "P12V_AUX")
	)
	(via
		(at 76.468478 -56.297068)
		(size 0.508)
		(drill 0.254)
		(layers "F.Cu" "B.Cu")
		(net "P12V_AUX")
	)
	(via
		(at 307.386736 -68.12153)
		(size 0.508)
		(drill 0.254)
		(layers "F.Cu" "B.Cu")
		(net "P12V_AUX")
	)
	(via
		(at 280.895552 -52.518818)
		(size 0.508)
		(drill 0.254)
		(layers "F.Cu" "B.Cu")
		(net "P12V_AUX")
	)
	(via
		(at 221.727776 -363.057186)
		(size 0.508)
		(drill 0.254)
		(layers "F.Cu" "B.Cu")
		(net "P12V_AUX")
	)
	(via
		(at 256.09804 -68.75653)
		(size 0.508)
		(drill 0.254)
		(layers "F.Cu" "B.Cu")
		(net "P12V_AUX")
	)
	(via
		(at 15.710916 -157.645862)
		(size 0.508)
		(drill 0.254)
		(layers "F.Cu" "B.Cu")
		(net "P12V_AUX")
	)
	(via
		(at 243.544598 -157.647894)
		(size 0.4064)
		(drill 0.2032)
		(layers "F.Cu" "B.Cu")
		(net "P12V_AUX")
	)
	(via
		(at 15.710916 -156.934662)
		(size 0.508)
		(drill 0.254)
		(layers "F.Cu" "B.Cu")
		(net "P12V_AUX")
	)
	(via
		(at 139.998196 -68.12153)
		(size 0.508)
		(drill 0.254)
		(layers "F.Cu" "B.Cu")
		(net "P12V_AUX")
	)
	(via
		(at 340.155784 -112.035844)
		(size 0.4064)
		(drill 0.2032)
		(layers "F.Cu" "B.Cu")
		(net "P12V_AUX")
	)
	(via
		(at 448.676776 -57.968134)
		(size 0.508)
		(drill 0.254)
		(layers "F.Cu" "B.Cu")
		(net "P12V_AUX")
	)
	(via
		(at 254.701802 -63.18631)
		(size 0.508)
		(drill 0.254)
		(layers "F.Cu" "B.Cu")
		(net "P12V_AUX")
	)
	(via
		(at 207.238854 -363.932216)
		(size 0.508)
		(drill 0.254)
		(layers "F.Cu" "B.Cu")
		(net "P12V_AUX")
	)
	(via
		(at 242.92941 -131.419854)
		(size 0.508)
		(drill 0.254)
		(layers "F.Cu" "B.Cu")
		(net "P12V_AUX")
	)
	(via
		(at 216.476834 -58.679334)
		(size 0.508)
		(drill 0.254)
		(layers "F.Cu" "B.Cu")
		(net "P12V_AUX")
	)
	(via
		(at 244.064282 -363.473238)
		(size 0.508)
		(drill 0.254)
		(layers "F.Cu" "B.Cu")
		(net "P12V_AUX")
	)
	(via
		(at 360.007154 -268.756638)
		(size 0.508)
		(drill 0.254)
		(layers "F.Cu" "B.Cu")
		(net "P12V_AUX")
	)
	(via
		(at 127.806958 -268.756638)
		(size 0.508)
		(drill 0.254)
		(layers "F.Cu" "B.Cu")
		(net "P12V_AUX")
	)
	(via
		(at 423.630598 -52.518818)
		(size 0.508)
		(drill 0.254)
		(layers "F.Cu" "B.Cu")
		(net "P12V_AUX")
	)
	(via
		(at 240.008664 -205.47711)
		(size 0.508)
		(drill 0.254)
		(layers "F.Cu" "B.Cu")
		(net "P12V_AUX")
	)
	(via
		(at 22.093682 -56.313832)
		(size 0.508)
		(drill 0.254)
		(layers "F.Cu" "B.Cu")
		(net "P12V_AUX")
	)
	(via
		(at 11.379454 -128.22555)
		(size 0.508)
		(drill 0.254)
		(layers "F.Cu" "B.Cu")
		(net "P12V_AUX")
	)
	(via
		(at 48.551846 -68.75653)
		(size 0.508)
		(drill 0.254)
		(layers "F.Cu" "B.Cu")
		(net "P12V_AUX")
	)
	(via
		(at 221.727776 -363.819186)
		(size 0.508)
		(drill 0.254)
		(layers "F.Cu" "B.Cu")
		(net "P12V_AUX")
	)
	(via
		(at 425.127674 -67.537838)
		(size 0.508)
		(drill 0.254)
		(layers "F.Cu" "B.Cu")
		(net "P12V_AUX")
	)
	(via
		(at 164.193728 -56.313832)
		(size 0.508)
		(drill 0.254)
		(layers "F.Cu" "B.Cu")
		(net "P12V_AUX")
	)
	(via
		(at 100.51669 -59.992006)
		(size 0.508)
		(drill 0.254)
		(layers "F.Cu" "B.Cu")
		(net "P12V_AUX")
	)
	(via
		(at 220.203776 -365.343186)
		(size 0.508)
		(drill 0.254)
		(layers "F.Cu" "B.Cu")
		(net "P12V_AUX")
	)
	(via
		(at 422.801796 -63.18631)
		(size 0.508)
		(drill 0.254)
		(layers "F.Cu" "B.Cu")
		(net "P12V_AUX")
	)
	(via
		(at 51.462686 -67.537838)
		(size 0.508)
		(drill 0.254)
		(layers "F.Cu" "B.Cu")
		(net "P12V_AUX")
	)
	(via
		(at 210.286854 -362.560616)
		(size 0.508)
		(drill 0.254)
		(layers "F.Cu" "B.Cu")
		(net "P12V_AUX")
	)
	(via
		(at 230.871776 -362.295186)
		(size 0.508)
		(drill 0.254)
		(layers "F.Cu" "B.Cu")
		(net "P12V_AUX")
	)
	(via
		(at 138.651996 -68.75653)
		(size 0.508)
		(drill 0.254)
		(layers "F.Cu" "B.Cu")
		(net "P12V_AUX")
	)
	(via
		(at 306.8955 -52.518818)
		(size 0.508)
		(drill 0.254)
		(layers "F.Cu" "B.Cu")
		(net "P12V_AUX")
	)
	(via
		(at 138.601958 -63.18631)
		(size 0.508)
		(drill 0.254)
		(layers "F.Cu" "B.Cu")
		(net "P12V_AUX")
	)
	(via
		(at 254.576834 -58.679334)
		(size 0.508)
		(drill 0.254)
		(layers "F.Cu" "B.Cu")
		(net "P12V_AUX")
	)
	(via
		(at 280.293572 -56.313832)
		(size 0.508)
		(drill 0.254)
		(layers "F.Cu" "B.Cu")
		(net "P12V_AUX")
	)
	(via
		(at 229.043738 -101.851968)
		(size 0.508)
		(drill 0.254)
		(layers "F.Cu" "B.Cu")
		(net "P12V_AUX")
	)
	(via
		(at 230.109776 -363.057186)
		(size 0.508)
		(drill 0.254)
		(layers "F.Cu" "B.Cu")
		(net "P12V_AUX")
	)
	(via
		(at 107.955842 -112.935766)
		(size 0.4064)
		(drill 0.2032)
		(layers "F.Cu" "B.Cu")
		(net "P12V_AUX")
	)
	(via
		(at 205.736444 -365.45139)
		(size 0.508)
		(drill 0.254)
		(layers "F.Cu" "B.Cu")
		(net "P12V_AUX")
	)
	(via
		(at 216.193624 -56.313832)
		(size 0.508)
		(drill 0.254)
		(layers "F.Cu" "B.Cu")
		(net "P12V_AUX")
	)
	(via
		(at 397.63065 -52.518818)
		(size 0.508)
		(drill 0.254)
		(layers "F.Cu" "B.Cu")
		(net "P12V_AUX")
	)
	(via
		(at 254.75184 -68.75653)
		(size 0.508)
		(drill 0.254)
		(layers "F.Cu" "B.Cu")
		(net "P12V_AUX")
	)
	(via
		(at 25.462738 -67.537838)
		(size 0.508)
		(drill 0.254)
		(layers "F.Cu" "B.Cu")
		(net "P12V_AUX")
	)
	(via
		(at 331.752702 -97.489518)
		(size 0.508)
		(drill 0.254)
		(layers "F.Cu" "B.Cu")
		(net "P12V_AUX")
	)
	(via
		(at 263.110218 -365.814102)
		(size 0.508)
		(drill 0.254)
		(layers "F.Cu" "B.Cu")
		(net "P12V_AUX")
	)
	(via
		(at 217.917776 -366.105186)
		(size 0.508)
		(drill 0.254)
		(layers "F.Cu" "B.Cu")
		(net "P12V_AUX")
	)
	(via
		(at 335.082134 -268.756638)
		(size 0.508)
		(drill 0.254)
		(layers "F.Cu" "B.Cu")
		(net "P12V_AUX")
	)
	(via
		(at 208.000854 -363.246416)
		(size 0.508)
		(drill 0.254)
		(layers "F.Cu" "B.Cu")
		(net "P12V_AUX")
	)
	(via
		(at 422.995598 -52.518818)
		(size 0.508)
		(drill 0.254)
		(layers "F.Cu" "B.Cu")
		(net "P12V_AUX")
	)
	(via
		(at 109.513116 -106.77525)
		(size 0.508)
		(drill 0.254)
		(layers "F.Cu" "B.Cu")
		(net "P12V_AUX")
	)
	(via
		(at 127.252476 -135.098028)
		(size 0.508)
		(drill 0.254)
		(layers "F.Cu" "B.Cu")
		(net "P12V_AUX")
	)
	(via
		(at 11.504422 -132.732526)
		(size 0.508)
		(drill 0.254)
		(layers "F.Cu" "B.Cu")
		(net "P12V_AUX")
	)
	(via
		(at 220.203776 -363.819186)
		(size 0.508)
		(drill 0.254)
		(layers "F.Cu" "B.Cu")
		(net "P12V_AUX")
	)
	(via
		(at 109.584998 -103.658416)
		(size 0.508)
		(drill 0.254)
		(layers "F.Cu" "B.Cu")
		(net "P12V_AUX")
	)
	(via
		(at 239.70615 -364.170976)
		(size 0.508)
		(drill 0.254)
		(layers "F.Cu" "B.Cu")
		(net "P12V_AUX")
	)
	(via
		(at 258.059174 -365.022638)
		(size 0.508)
		(drill 0.254)
		(layers "F.Cu" "B.Cu")
		(net "P12V_AUX")
	)
	(via
		(at 195.975478 -367.491772)
		(size 0.508)
		(drill 0.254)
		(layers "F.Cu" "B.Cu")
		(net "P12V_AUX")
	)
	(via
		(at 74.093578 -56.313832)
		(size 0.508)
		(drill 0.254)
		(layers "F.Cu" "B.Cu")
		(net "P12V_AUX")
	)
	(via
		(at 221.727776 -365.343186)
		(size 0.508)
		(drill 0.254)
		(layers "F.Cu" "B.Cu")
		(net "P12V_AUX")
	)
	(via
		(at 220.203776 -364.581186)
		(size 0.508)
		(drill 0.254)
		(layers "F.Cu" "B.Cu")
		(net "P12V_AUX")
	)
	(via
		(at 258.821174 -365.022638)
		(size 0.508)
		(drill 0.254)
		(layers "F.Cu" "B.Cu")
		(net "P12V_AUX")
	)
	(via
		(at 225.904552 -320.816732)
		(size 0.508)
		(drill 0.254)
		(layers "F.Cu" "B.Cu")
		(net "P12V_AUX")
	)
	(via
		(at 246.350282 -362.711238)
		(size 0.508)
		(drill 0.254)
		(layers "F.Cu" "B.Cu")
		(net "P12V_AUX")
	)
	(via
		(at 360.236262 -134.408926)
		(size 0.508)
		(drill 0.254)
		(layers "F.Cu" "B.Cu")
		(net "P12V_AUX")
	)
	(via
		(at 225.365564 -101.640132)
		(size 0.508)
		(drill 0.254)
		(layers "F.Cu" "B.Cu")
		(net "P12V_AUX")
	)
	(via
		(at 102.468426 -56.297068)
		(size 0.508)
		(drill 0.254)
		(layers "F.Cu" "B.Cu")
		(net "P12V_AUX")
	)
	(via
		(at 220.965776 -364.581186)
		(size 0.508)
		(drill 0.254)
		(layers "F.Cu" "B.Cu")
		(net "P12V_AUX")
	)
	(via
		(at 280.260552 -52.518818)
		(size 0.508)
		(drill 0.254)
		(layers "F.Cu" "B.Cu")
		(net "P12V_AUX")
	)
	(via
		(at 240.46815 -365.694976)
		(size 0.508)
		(drill 0.254)
		(layers "F.Cu" "B.Cu")
		(net "P12V_AUX")
	)
	(via
		(at 48.69561 -52.518818)
		(size 0.508)
		(drill 0.254)
		(layers "F.Cu" "B.Cu")
		(net "P12V_AUX")
	)
	(via
		(at 230.871776 -363.057186)
		(size 0.508)
		(drill 0.254)
		(layers "F.Cu" "B.Cu")
		(net "P12V_AUX")
	)
	(via
		(at 107.244642 -110.235746)
		(size 0.4064)
		(drill 0.2032)
		(layers "F.Cu" "B.Cu")
		(net "P12V_AUX")
	)
	(via
		(at 253.733046 -365.759238)
		(size 0.508)
		(drill 0.254)
		(layers "F.Cu" "B.Cu")
		(net "P12V_AUX")
	)
	(via
		(at 359.644696 -156.936694)
		(size 0.4064)
		(drill 0.2032)
		(layers "F.Cu" "B.Cu")
		(net "P12V_AUX")
	)
	(via
		(at 107.244642 -112.935766)
		(size 0.4064)
		(drill 0.2032)
		(layers "F.Cu" "B.Cu")
		(net "P12V_AUX")
	)
	(via
		(at 256.535174 -364.260638)
		(size 0.508)
		(drill 0.254)
		(layers "F.Cu" "B.Cu")
		(net "P12V_AUX")
	)
	(via
		(at 125.266958 -268.756638)
		(size 0.508)
		(drill 0.254)
		(layers "F.Cu" "B.Cu")
		(net "P12V_AUX")
	)
	(via
		(at 101.186742 -68.12153)
		(size 0.508)
		(drill 0.254)
		(layers "F.Cu" "B.Cu")
		(net "P12V_AUX")
	)
	(via
		(at 164.616892 -59.992006)
		(size 0.508)
		(drill 0.254)
		(layers "F.Cu" "B.Cu")
		(net "P12V_AUX")
	)
	(via
		(at 23.898098 -68.12153)
		(size 0.508)
		(drill 0.254)
		(layers "F.Cu" "B.Cu")
		(net "P12V_AUX")
	)
	(via
		(at 228.585776 -363.057186)
		(size 0.508)
		(drill 0.254)
		(layers "F.Cu" "B.Cu")
		(net "P12V_AUX")
	)
	(via
		(at 127.604266 -133.443726)
		(size 0.508)
		(drill 0.254)
		(layers "F.Cu" "B.Cu")
		(net "P12V_AUX")
	)
	(via
		(at 110.224316 -106.77525)
		(size 0.508)
		(drill 0.254)
		(layers "F.Cu" "B.Cu")
		(net "P12V_AUX")
	)
	(via
		(at 240.46815 -362.646976)
		(size 0.508)
		(drill 0.254)
		(layers "F.Cu" "B.Cu")
		(net "P12V_AUX")
	)
	(via
		(at 281.386788 -68.12153)
		(size 0.508)
		(drill 0.254)
		(layers "F.Cu" "B.Cu")
		(net "P12V_AUX")
	)
	(via
		(at 238.18215 -364.170976)
		(size 0.508)
		(drill 0.254)
		(layers "F.Cu" "B.Cu")
		(net "P12V_AUX")
	)
	(via
		(at 244.064282 -365.759238)
		(size 0.508)
		(drill 0.254)
		(layers "F.Cu" "B.Cu")
		(net "P12V_AUX")
	)
	(via
		(at 256.067052 -358.136444)
		(size 0.508)
		(drill 0.254)
		(layers "F.Cu" "B.Cu")
		(net "P12V_AUX")
	)
	(via
		(at 250.685046 -364.997238)
		(size 0.508)
		(drill 0.254)
		(layers "F.Cu" "B.Cu")
		(net "P12V_AUX")
	)
	(via
		(at 335.717134 -269.417038)
		(size 0.508)
		(drill 0.254)
		(layers "F.Cu" "B.Cu")
		(net "P12V_AUX")
	)
	(via
		(at 247.112282 -363.473238)
		(size 0.508)
		(drill 0.254)
		(layers "F.Cu" "B.Cu")
		(net "P12V_AUX")
	)
	(via
		(at 339.442552 -107.934506)
		(size 0.508)
		(drill 0.254)
		(layers "F.Cu" "B.Cu")
		(net "P12V_AUX")
	)
	(via
		(at 110.30966 -180.949346)
		(size 0.508)
		(drill 0.254)
		(layers "F.Cu" "B.Cu")
		(net "P12V_AUX")
	)
	(via
		(at 138.651996 -68.12153)
		(size 0.508)
		(drill 0.254)
		(layers "F.Cu" "B.Cu")
		(net "P12V_AUX")
	)
	(via
		(at 103.516938 -269.417038)
		(size 0.508)
		(drill 0.254)
		(layers "F.Cu" "B.Cu")
		(net "P12V_AUX")
	)
	(via
		(at 372.198138 -68.12153)
		(size 0.508)
		(drill 0.254)
		(layers "F.Cu" "B.Cu")
		(net "P12V_AUX")
	)
	(via
		(at 244.826282 -363.473238)
		(size 0.508)
		(drill 0.254)
		(layers "F.Cu" "B.Cu")
		(net "P12V_AUX")
	)
	(via
		(at 138.16076 -52.518818)
		(size 0.508)
		(drill 0.254)
		(layers "F.Cu" "B.Cu")
		(net "P12V_AUX")
	)
	(via
		(at 11.504422 -133.443726)
		(size 0.508)
		(drill 0.254)
		(layers "F.Cu" "B.Cu")
		(net "P12V_AUX")
	)
	(via
		(at 108.801916 -106.77525)
		(size 0.508)
		(drill 0.254)
		(layers "F.Cu" "B.Cu")
		(net "P12V_AUX")
	)
	(via
		(at 361.44454 -157.647894)
		(size 0.4064)
		(drill 0.2032)
		(layers "F.Cu" "B.Cu")
		(net "P12V_AUX")
	)
	(via
		(at 457.16063 -320.940176)
		(size 0.508)
		(drill 0.254)
		(layers "F.Cu" "B.Cu")
		(net "P12V_AUX")
	)
	(via
		(at 110.296198 -103.658416)
		(size 0.508)
		(drill 0.254)
		(layers "F.Cu" "B.Cu")
		(net "P12V_AUX")
	)
	(via
		(at 216.601802 -63.18631)
		(size 0.508)
		(drill 0.254)
		(layers "F.Cu" "B.Cu")
		(net "P12V_AUX")
	)
	(via
		(at 448.676776 -58.679334)
		(size 0.508)
		(drill 0.254)
		(layers "F.Cu" "B.Cu")
		(net "P12V_AUX")
	)
	(via
		(at 191.817498 -401.528534)
		(size 0.508)
		(drill 0.254)
		(layers "F.Cu" "B.Cu")
		(net "P12V_AUX")
	)
	(via
		(at 359.029508 -131.419854)
		(size 0.508)
		(drill 0.254)
		(layers "F.Cu" "B.Cu")
		(net "P12V_AUX")
	)
	(via
		(at 252.209046 -364.235238)
		(size 0.508)
		(drill 0.254)
		(layers "F.Cu" "B.Cu")
		(net "P12V_AUX")
	)
	(via
		(at 335.717134 -268.756638)
		(size 0.508)
		(drill 0.254)
		(layers "F.Cu" "B.Cu")
		(net "P12V_AUX")
	)
	(via
		(at 10.972292 -317.89497)
		(size 0.508)
		(drill 0.254)
		(layers "F.Cu" "B.Cu")
		(net "P12V_AUX")
	)
	(via
		(at 244.826282 -362.711238)
		(size 0.508)
		(drill 0.254)
		(layers "F.Cu" "B.Cu")
		(net "P12V_AUX")
	)
	(via
		(at 100.093526 -56.313832)
		(size 0.508)
		(drill 0.254)
		(layers "F.Cu" "B.Cu")
		(net "P12V_AUX")
	)
	(via
		(at 141.562836 -67.537838)
		(size 0.508)
		(drill 0.254)
		(layers "F.Cu" "B.Cu")
		(net "P12V_AUX")
	)
	(via
		(at 342.424258 -106.77525)
		(size 0.508)
		(drill 0.254)
		(layers "F.Cu" "B.Cu")
		(net "P12V_AUX")
	)
	(via
		(at 126.844298 -128.22555)
		(size 0.508)
		(drill 0.254)
		(layers "F.Cu" "B.Cu")
		(net "P12V_AUX")
	)
	(via
		(at 244.064282 -362.711238)
		(size 0.508)
		(drill 0.254)
		(layers "F.Cu" "B.Cu")
		(net "P12V_AUX")
	)
	(via
		(at 362.344716 -156.936694)
		(size 0.4064)
		(drill 0.2032)
		(layers "F.Cu" "B.Cu")
		(net "P12V_AUX")
	)
	(via
		(at 239.851184 -155.212034)
		(size 0.508)
		(drill 0.254)
		(layers "F.Cu" "B.Cu")
		(net "P12V_AUX")
	)
	(via
		(at 455.544682 -112.035844)
		(size 0.4064)
		(drill 0.2032)
		(layers "F.Cu" "B.Cu")
		(net "P12V_AUX")
	)
	(via
		(at 254.293624 -56.313832)
		(size 0.508)
		(drill 0.254)
		(layers "F.Cu" "B.Cu")
		(net "P12V_AUX")
	)
	(via
		(at 280.751788 -68.75653)
		(size 0.508)
		(drill 0.254)
		(layers "F.Cu" "B.Cu")
		(net "P12V_AUX")
	)
	(via
		(at 12.244578 -156.936694)
		(size 0.4064)
		(drill 0.2032)
		(layers "F.Cu" "B.Cu")
		(net "P12V_AUX")
	)
	(via
		(at 238.94415 -364.170976)
		(size 0.508)
		(drill 0.254)
		(layers "F.Cu" "B.Cu")
		(net "P12V_AUX")
	)
	(via
		(at 216.795604 -52.518818)
		(size 0.508)
		(drill 0.254)
		(layers "F.Cu" "B.Cu")
		(net "P12V_AUX")
	)
	(via
		(at 165.236906 -63.18631)
		(size 0.508)
		(drill 0.254)
		(layers "F.Cu" "B.Cu")
		(net "P12V_AUX")
	)
	(via
		(at 100.501704 -63.18631)
		(size 0.508)
		(drill 0.254)
		(layers "F.Cu" "B.Cu")
		(net "P12V_AUX")
	)
	(via
		(at 49.151794 -59.992006)
		(size 0.508)
		(drill 0.254)
		(layers "F.Cu" "B.Cu")
		(net "P12V_AUX")
	)
	(via
		(at 225.365564 -102.910132)
		(size 0.508)
		(drill 0.254)
		(layers "F.Cu" "B.Cu")
		(net "P12V_AUX")
	)
	(via
		(at 230.871776 -365.343186)
		(size 0.508)
		(drill 0.254)
		(layers "F.Cu" "B.Cu")
		(net "P12V_AUX")
	)
	(via
		(at 232.395776 -365.343186)
		(size 0.508)
		(drill 0.254)
		(layers "F.Cu" "B.Cu")
		(net "P12V_AUX")
	)
	(via
		(at 339.444584 -112.935766)
		(size 0.4064)
		(drill 0.2032)
		(layers "F.Cu" "B.Cu")
		(net "P12V_AUX")
	)
	(via
		(at 23.898098 -68.75653)
		(size 0.508)
		(drill 0.254)
		(layers "F.Cu" "B.Cu")
		(net "P12V_AUX")
	)
	(via
		(at 252.209046 -363.473238)
		(size 0.508)
		(drill 0.254)
		(layers "F.Cu" "B.Cu")
		(net "P12V_AUX")
	)
	(via
		(at 458.524356 -106.77525)
		(size 0.508)
		(drill 0.254)
		(layers "F.Cu" "B.Cu")
		(net "P12V_AUX")
	)
	(via
		(at 306.751736 -68.12153)
		(size 0.508)
		(drill 0.254)
		(layers "F.Cu" "B.Cu")
		(net "P12V_AUX")
	)
	(via
		(at 164.828728 -56.313832)
		(size 0.508)
		(drill 0.254)
		(layers "F.Cu" "B.Cu")
		(net "P12V_AUX")
	)
	(via
		(at 208.762854 -363.246416)
		(size 0.508)
		(drill 0.254)
		(layers "F.Cu" "B.Cu")
		(net "P12V_AUX")
	)
	(via
		(at 263.872218 -365.814102)
		(size 0.508)
		(drill 0.254)
		(layers "F.Cu" "B.Cu")
		(net "P12V_AUX")
	)
	(via
		(at 261.586218 -362.766102)
		(size 0.508)
		(drill 0.254)
		(layers "F.Cu" "B.Cu")
		(net "P12V_AUX")
	)
	(via
		(at 233.768646 -115.286536)
		(size 0.4064)
		(drill 0.2032)
		(layers "F.Cu" "B.Cu")
		(net "P12V_AUX")
	)
	(via
		(at 398.198086 -68.75653)
		(size 0.508)
		(drill 0.254)
		(layers "F.Cu" "B.Cu")
		(net "P12V_AUX")
	)
	(via
		(at 228.585776 -366.105186)
		(size 0.508)
		(drill 0.254)
		(layers "F.Cu" "B.Cu")
		(net "P12V_AUX")
	)
	(via
		(at 331.752702 -98.759518)
		(size 0.508)
		(drill 0.254)
		(layers "F.Cu" "B.Cu")
		(net "P12V_AUX")
	)
	(via
		(at 448.81673 -59.992006)
		(size 0.508)
		(drill 0.254)
		(layers "F.Cu" "B.Cu")
		(net "P12V_AUX")
	)
	(via
		(at 244.44452 -157.647894)
		(size 0.4064)
		(drill 0.2032)
		(layers "F.Cu" "B.Cu")
		(net "P12V_AUX")
	)
	(via
		(at 220.965776 -363.819186)
		(size 0.508)
		(drill 0.254)
		(layers "F.Cu" "B.Cu")
		(net "P12V_AUX")
	)
	(via
		(at 165.430708 -52.518818)
		(size 0.508)
		(drill 0.254)
		(layers "F.Cu" "B.Cu")
		(net "P12V_AUX")
	)
	(via
		(at 255.355852 -360.270044)
		(size 0.508)
		(drill 0.254)
		(layers "F.Cu" "B.Cu")
		(net "P12V_AUX")
	)
	(via
		(at 21.945092 -57.002934)
		(size 0.508)
		(drill 0.254)
		(layers "F.Cu" "B.Cu")
		(net "P12V_AUX")
	)
	(via
		(at 209.524854 -363.932216)
		(size 0.508)
		(drill 0.254)
		(layers "F.Cu" "B.Cu")
		(net "P12V_AUX")
	)
	(via
		(at 258.821174 -364.260638)
		(size 0.508)
		(drill 0.254)
		(layers "F.Cu" "B.Cu")
		(net "P12V_AUX")
	)
	(via
		(at 264.634218 -363.528102)
		(size 0.508)
		(drill 0.254)
		(layers "F.Cu" "B.Cu")
		(net "P12V_AUX")
	)
	(via
		(at 190.651892 -68.75653)
		(size 0.508)
		(drill 0.254)
		(layers "F.Cu" "B.Cu")
		(net "P12V_AUX")
	)
	(via
		(at 140.927836 -67.537838)
		(size 0.508)
		(drill 0.254)
		(layers "F.Cu" "B.Cu")
		(net "P12V_AUX")
	)
	(via
		(at 164.651944 -68.12153)
		(size 0.508)
		(drill 0.254)
		(layers "F.Cu" "B.Cu")
		(net "P12V_AUX")
	)
	(via
		(at 362.344716 -157.647894)
		(size 0.4064)
		(drill 0.2032)
		(layers "F.Cu" "B.Cu")
		(net "P12V_AUX")
	)
	(via
		(at 107.955842 -112.035844)
		(size 0.4064)
		(drill 0.2032)
		(layers "F.Cu" "B.Cu")
		(net "P12V_AUX")
	)
	(via
		(at 255.355852 -358.136444)
		(size 0.508)
		(drill 0.254)
		(layers "F.Cu" "B.Cu")
		(net "P12V_AUX")
	)
	(via
		(at 138.82878 -56.313832)
		(size 0.508)
		(drill 0.254)
		(layers "F.Cu" "B.Cu")
		(net "P12V_AUX")
	)
	(via
		(at 307.971698 -63.18631)
		(size 0.508)
		(drill 0.254)
		(layers "F.Cu" "B.Cu")
		(net "P12V_AUX")
	)
	(via
		(at 458.596238 -103.658416)
		(size 0.508)
		(drill 0.254)
		(layers "F.Cu" "B.Cu")
		(net "P12V_AUX")
	)
	(via
		(at 207.260444 -365.45139)
		(size 0.508)
		(drill 0.254)
		(layers "F.Cu" "B.Cu")
		(net "P12V_AUX")
	)
	(via
		(at 341.001858 -106.77525)
		(size 0.508)
		(drill 0.254)
		(layers "F.Cu" "B.Cu")
		(net "P12V_AUX")
	)
	(via
		(at 450.197982 -68.75653)
		(size 0.508)
		(drill 0.254)
		(layers "F.Cu" "B.Cu")
		(net "P12V_AUX")
	)
	(via
		(at 233.057446 -116.186458)
		(size 0.4064)
		(drill 0.2032)
		(layers "F.Cu" "B.Cu")
		(net "P12V_AUX")
	)
	(via
		(at 47.94504 -57.002934)
		(size 0.508)
		(drill 0.254)
		(layers "F.Cu" "B.Cu")
		(net "P12V_AUX")
	)
	(via
		(at 139.251944 -59.992006)
		(size 0.508)
		(drill 0.254)
		(layers "F.Cu" "B.Cu")
		(net "P12V_AUX")
	)
	(via
		(at 232.395776 -366.105186)
		(size 0.508)
		(drill 0.254)
		(layers "F.Cu" "B.Cu")
		(net "P12V_AUX")
	)
	(via
		(at 423.486834 -68.12153)
		(size 0.508)
		(drill 0.254)
		(layers "F.Cu" "B.Cu")
		(net "P12V_AUX")
	)
	(via
		(at 448.851782 -68.12153)
		(size 0.508)
		(drill 0.254)
		(layers "F.Cu" "B.Cu")
		(net "P12V_AUX")
	)
	(via
		(at 207.238854 -364.618016)
		(size 0.508)
		(drill 0.254)
		(layers "F.Cu" "B.Cu")
		(net "P12V_AUX")
	)
	(via
		(at 265.396218 -364.290102)
		(size 0.508)
		(drill 0.254)
		(layers "F.Cu" "B.Cu")
		(net "P12V_AUX")
	)
	(via
		(at 456.255882 -111.135922)
		(size 0.4064)
		(drill 0.2032)
		(layers "F.Cu" "B.Cu")
		(net "P12V_AUX")
	)
	(via
		(at 189.77356 -401.65909)
		(size 0.508)
		(drill 0.254)
		(layers "F.Cu" "B.Cu")
		(net "P12V_AUX")
	)
	(via
		(at 455.89063 -320.305176)
		(size 0.508)
		(drill 0.254)
		(layers "F.Cu" "B.Cu")
		(net "P12V_AUX")
	)
	(via
		(at 136.861804 -156.707332)
		(size 0.508)
		(drill 0.254)
		(layers "F.Cu" "B.Cu")
		(net "P12V_AUX")
	)
	(via
		(at 219.441776 -365.343186)
		(size 0.508)
		(drill 0.254)
		(layers "F.Cu" "B.Cu")
		(net "P12V_AUX")
	)
	(via
		(at 130.14452 -157.647894)
		(size 0.4064)
		(drill 0.2032)
		(layers "F.Cu" "B.Cu")
		(net "P12V_AUX")
	)
	(via
		(at 238.94415 -363.408976)
		(size 0.508)
		(drill 0.254)
		(layers "F.Cu" "B.Cu")
		(net "P12V_AUX")
	)
	(via
		(at 229.043738 -102.486968)
		(size 0.508)
		(drill 0.254)
		(layers "F.Cu" "B.Cu")
		(net "P12V_AUX")
	)
	(via
		(at 133.796024 -155.933902)
		(size 0.508)
		(drill 0.254)
		(layers "F.Cu" "B.Cu")
		(net "P12V_AUX")
	)
	(via
		(at 234.81792 -110.925864)
		(size 0.508)
		(drill 0.254)
		(layers "F.Cu" "B.Cu")
		(net "P12V_AUX")
	)
	(via
		(at 208.784444 -366.13719)
		(size 0.508)
		(drill 0.254)
		(layers "F.Cu" "B.Cu")
		(net "P12V_AUX")
	)
	(via
		(at 360.007154 -269.417038)
		(size 0.508)
		(drill 0.254)
		(layers "F.Cu" "B.Cu")
		(net "P12V_AUX")
	)
	(via
		(at 263.872218 -362.766102)
		(size 0.508)
		(drill 0.254)
		(layers "F.Cu" "B.Cu")
		(net "P12V_AUX")
	)
	(via
		(at 307.986684 -59.992006)
		(size 0.508)
		(drill 0.254)
		(layers "F.Cu" "B.Cu")
		(net "P12V_AUX")
	)
	(via
		(at 107.24261 -107.934506)
		(size 0.508)
		(drill 0.254)
		(layers "F.Cu" "B.Cu")
		(net "P12V_AUX")
	)
	(via
		(at 396.801848 -63.18631)
		(size 0.508)
		(drill 0.254)
		(layers "F.Cu" "B.Cu")
		(net "P12V_AUX")
	)
	(via
		(at 263.110218 -363.528102)
		(size 0.508)
		(drill 0.254)
		(layers "F.Cu" "B.Cu")
		(net "P12V_AUX")
	)
	(via
		(at 109.03966 -180.288946)
		(size 0.508)
		(drill 0.254)
		(layers "F.Cu" "B.Cu")
		(net "P12V_AUX")
	)
	(via
		(at 230.871776 -364.581186)
		(size 0.508)
		(drill 0.254)
		(layers "F.Cu" "B.Cu")
		(net "P12V_AUX")
	)
	(via
		(at 239.70615 -363.408976)
		(size 0.508)
		(drill 0.254)
		(layers "F.Cu" "B.Cu")
		(net "P12V_AUX")
	)
	(via
		(at 259.583174 -362.736638)
		(size 0.508)
		(drill 0.254)
		(layers "F.Cu" "B.Cu")
		(net "P12V_AUX")
	)
	(via
		(at 228.585776 -364.581186)
		(size 0.508)
		(drill 0.254)
		(layers "F.Cu" "B.Cu")
		(net "P12V_AUX")
	)
	(via
		(at 74.551794 -68.12153)
		(size 0.508)
		(drill 0.254)
		(layers "F.Cu" "B.Cu")
		(net "P12V_AUX")
	)
	(via
		(at 75.897994 -68.75653)
		(size 0.508)
		(drill 0.254)
		(layers "F.Cu" "B.Cu")
		(net "P12V_AUX")
	)
	(via
		(at 243.56441 -131.419854)
		(size 0.508)
		(drill 0.254)
		(layers "F.Cu" "B.Cu")
		(net "P12V_AUX")
	)
	(via
		(at 139.286996 -68.75653)
		(size 0.508)
		(drill 0.254)
		(layers "F.Cu" "B.Cu")
		(net "P12V_AUX")
	)
	(via
		(at 131.81076 -156.934662)
		(size 0.508)
		(drill 0.254)
		(layers "F.Cu" "B.Cu")
		(net "P12V_AUX")
	)
	(via
		(at 210.286854 -363.932216)
		(size 0.508)
		(drill 0.254)
		(layers "F.Cu" "B.Cu")
		(net "P12V_AUX")
	)
	(via
		(at 164.045138 -57.002934)
		(size 0.508)
		(drill 0.254)
		(layers "F.Cu" "B.Cu")
		(net "P12V_AUX")
	)
	(via
		(at 455.544682 -110.235746)
		(size 0.4064)
		(drill 0.2032)
		(layers "F.Cu" "B.Cu")
		(net "P12V_AUX")
	)
	(via
		(at 75.151742 -59.992006)
		(size 0.508)
		(drill 0.254)
		(layers "F.Cu" "B.Cu")
		(net "P12V_AUX")
	)
	(via
		(at 396.24508 -57.002934)
		(size 0.508)
		(drill 0.254)
		(layers "F.Cu" "B.Cu")
		(net "P12V_AUX")
	)
	(via
		(at 360.544618 -157.647894)
		(size 0.4064)
		(drill 0.2032)
		(layers "F.Cu" "B.Cu")
		(net "P12V_AUX")
	)
	(via
		(at 49.786794 -59.992006)
		(size 0.508)
		(drill 0.254)
		(layers "F.Cu" "B.Cu")
		(net "P12V_AUX")
	)
	(via
		(at 14.044676 -156.936694)
		(size 0.4064)
		(drill 0.2032)
		(layers "F.Cu" "B.Cu")
		(net "P12V_AUX")
	)
	(via
		(at 110.94466 -180.949346)
		(size 0.508)
		(drill 0.254)
		(layers "F.Cu" "B.Cu")
		(net "P12V_AUX")
	)
	(via
		(at 100.376736 -57.968134)
		(size 0.508)
		(drill 0.254)
		(layers "F.Cu" "B.Cu")
		(net "P12V_AUX")
	)
	(via
		(at 218.92768 -67.537838)
		(size 0.508)
		(drill 0.254)
		(layers "F.Cu" "B.Cu")
		(net "P12V_AUX")
	)
	(via
		(at 10.972292 -318.52997)
		(size 0.508)
		(drill 0.254)
		(layers "F.Cu" "B.Cu")
		(net "P12V_AUX")
	)
	(via
		(at 257.66268 -67.537838)
		(size 0.508)
		(drill 0.254)
		(layers "F.Cu" "B.Cu")
		(net "P12V_AUX")
	)
	(via
		(at 23.77186 -63.18631)
		(size 0.508)
		(drill 0.254)
		(layers "F.Cu" "B.Cu")
		(net "P12V_AUX")
	)
	(via
		(at 10.109454 -128.22555)
		(size 0.508)
		(drill 0.254)
		(layers "F.Cu" "B.Cu")
		(net "P12V_AUX")
	)
	(via
		(at 358.737154 -269.417038)
		(size 0.508)
		(drill 0.254)
		(layers "F.Cu" "B.Cu")
		(net "P12V_AUX")
	)
	(via
		(at 449.507102 -98.476308)
		(size 0.508)
		(drill 0.254)
		(layers "F.Cu" "B.Cu")
		(net "P12V_AUX")
	)
	(via
		(at 308.097936 -68.75653)
		(size 0.508)
		(drill 0.254)
		(layers "F.Cu" "B.Cu")
		(net "P12V_AUX")
	)
	(via
		(at 371.486938 -68.75653)
		(size 0.508)
		(drill 0.254)
		(layers "F.Cu" "B.Cu")
		(net "P12V_AUX")
	)
	(via
		(at 138.616944 -59.992006)
		(size 0.508)
		(drill 0.254)
		(layers "F.Cu" "B.Cu")
		(net "P12V_AUX")
	)
	(via
		(at 216.160604 -52.518818)
		(size 0.508)
		(drill 0.254)
		(layers "F.Cu" "B.Cu")
		(net "P12V_AUX")
	)
	(via
		(at 48.551846 -68.12153)
		(size 0.508)
		(drill 0.254)
		(layers "F.Cu" "B.Cu")
		(net "P12V_AUX")
	)
	(via
		(at 243.987574 -135.098028)
		(size 0.508)
		(drill 0.254)
		(layers "F.Cu" "B.Cu")
		(net "P12V_AUX")
	)
	(via
		(at 450.071744 -63.18631)
		(size 0.508)
		(drill 0.254)
		(layers "F.Cu" "B.Cu")
		(net "P12V_AUX")
	)
	(via
		(at 131.81076 -157.645862)
		(size 0.508)
		(drill 0.254)
		(layers "F.Cu" "B.Cu")
		(net "P12V_AUX")
	)
	(via
		(at 370.851938 -68.12153)
		(size 0.508)
		(drill 0.254)
		(layers "F.Cu" "B.Cu")
		(net "P12V_AUX")
	)
	(via
		(at 231.633776 -362.295186)
		(size 0.508)
		(drill 0.254)
		(layers "F.Cu" "B.Cu")
		(net "P12V_AUX")
	)
	(via
		(at 24.362918 -167.226996)
		(size 0.508)
		(drill 0.254)
		(layers "F.Cu" "B.Cu")
		(net "P12V_AUX")
	)
	(via
		(at 456.255882 -110.235746)
		(size 0.4064)
		(drill 0.2032)
		(layers "F.Cu" "B.Cu")
		(net "P12V_AUX")
	)
	(via
		(at 359.372154 -268.756638)
		(size 0.508)
		(drill 0.254)
		(layers "F.Cu" "B.Cu")
		(net "P12V_AUX")
	)
	(via
		(at 100.695506 -52.518818)
		(size 0.508)
		(drill 0.254)
		(layers "F.Cu" "B.Cu")
		(net "P12V_AUX")
	)
	(via
		(at 216.828624 -56.313832)
		(size 0.508)
		(drill 0.254)
		(layers "F.Cu" "B.Cu")
		(net "P12V_AUX")
	)
	(via
		(at 307.386736 -68.75653)
		(size 0.508)
		(drill 0.254)
		(layers "F.Cu" "B.Cu")
		(net "P12V_AUX")
	)
	(via
		(at 263.872218 -363.528102)
		(size 0.508)
		(drill 0.254)
		(layers "F.Cu" "B.Cu")
		(net "P12V_AUX")
	)
	(via
		(at 252.971046 -364.997238)
		(size 0.508)
		(drill 0.254)
		(layers "F.Cu" "B.Cu")
		(net "P12V_AUX")
	)
	(via
		(at 243.704364 -132.732526)
		(size 0.508)
		(drill 0.254)
		(layers "F.Cu" "B.Cu")
		(net "P12V_AUX")
	)
	(via
		(at 9.742932 -135.114792)
		(size 0.508)
		(drill 0.254)
		(layers "F.Cu" "B.Cu")
		(net "P12V_AUX")
	)
	(via
		(at 191.998092 -68.75653)
		(size 0.508)
		(drill 0.254)
		(layers "F.Cu" "B.Cu")
		(net "P12V_AUX")
	)
	(via
		(at 333.351632 -59.992006)
		(size 0.508)
		(drill 0.254)
		(layers "F.Cu" "B.Cu")
		(net "P12V_AUX")
	)
	(via
		(at 447.8528 -97.489518)
		(size 0.508)
		(drill 0.254)
		(layers "F.Cu" "B.Cu")
		(net "P12V_AUX")
	)
	(via
		(at 127.171958 -269.417038)
		(size 0.508)
		(drill 0.254)
		(layers "F.Cu" "B.Cu")
		(net "P12V_AUX")
	)
	(via
		(at 255.773174 -365.022638)
		(size 0.508)
		(drill 0.254)
		(layers "F.Cu" "B.Cu")
		(net "P12V_AUX")
	)
	(via
		(at 263.110218 -365.052102)
		(size 0.508)
		(drill 0.254)
		(layers "F.Cu" "B.Cu")
		(net "P12V_AUX")
	)
	(via
		(at 126.209298 -128.22555)
		(size 0.508)
		(drill 0.254)
		(layers "F.Cu" "B.Cu")
		(net "P12V_AUX")
	)
	(via
		(at 232.238042 -101.231954)
		(size 0.508)
		(drill 0.254)
		(layers "F.Cu" "B.Cu")
		(net "P12V_AUX")
	)
	(via
		(at 283.027628 -67.537838)
		(size 0.508)
		(drill 0.254)
		(layers "F.Cu" "B.Cu")
		(net "P12V_AUX")
	)
	(via
		(at 306.751736 -68.75653)
		(size 0.508)
		(drill 0.254)
		(layers "F.Cu" "B.Cu")
		(net "P12V_AUX")
	)
	(via
		(at 219.56268 -67.537838)
		(size 0.508)
		(drill 0.254)
		(layers "F.Cu" "B.Cu")
		(net "P12V_AUX")
	)
	(via
		(at 455.544682 -112.935766)
		(size 0.4064)
		(drill 0.2032)
		(layers "F.Cu" "B.Cu")
		(net "P12V_AUX")
	)
	(via
		(at 283.662628 -67.537838)
		(size 0.508)
		(drill 0.254)
		(layers "F.Cu" "B.Cu")
		(net "P12V_AUX")
	)
	(via
		(at 397.486886 -68.12153)
		(size 0.508)
		(drill 0.254)
		(layers "F.Cu" "B.Cu")
		(net "P12V_AUX")
	)
	(via
		(at 48.37684 -58.679334)
		(size 0.508)
		(drill 0.254)
		(layers "F.Cu" "B.Cu")
		(net "P12V_AUX")
	)
	(via
		(at 139.286996 -68.12153)
		(size 0.508)
		(drill 0.254)
		(layers "F.Cu" "B.Cu")
		(net "P12V_AUX")
	)
	(via
		(at 256.09804 -68.12153)
		(size 0.508)
		(drill 0.254)
		(layers "F.Cu" "B.Cu")
		(net "P12V_AUX")
	)
	(via
		(at 256.067052 -360.270044)
		(size 0.508)
		(drill 0.254)
		(layers "F.Cu" "B.Cu")
		(net "P12V_AUX")
	)
	(via
		(at 254.145034 -57.002934)
		(size 0.508)
		(drill 0.254)
		(layers "F.Cu" "B.Cu")
		(net "P12V_AUX")
	)
	(via
		(at 258.059174 -364.260638)
		(size 0.508)
		(drill 0.254)
		(layers "F.Cu" "B.Cu")
		(net "P12V_AUX")
	)
	(via
		(at 281.33675 -63.18631)
		(size 0.508)
		(drill 0.254)
		(layers "F.Cu" "B.Cu")
		(net "P12V_AUX")
	)
	(via
		(at 249.923046 -362.711238)
		(size 0.508)
		(drill 0.254)
		(layers "F.Cu" "B.Cu")
		(net "P12V_AUX")
	)
	(via
		(at 218.679776 -363.057186)
		(size 0.508)
		(drill 0.254)
		(layers "F.Cu" "B.Cu")
		(net "P12V_AUX")
	)
	(via
		(at 16.89862 -158.753302)
		(size 0.508)
		(drill 0.254)
		(layers "F.Cu" "B.Cu")
		(net "P12V_AUX")
	)
	(via
		(at 422.393618 -56.313832)
		(size 0.508)
		(drill 0.254)
		(layers "F.Cu" "B.Cu")
		(net "P12V_AUX")
	)
	(via
		(at 423.436796 -63.18631)
		(size 0.508)
		(drill 0.254)
		(layers "F.Cu" "B.Cu")
		(net "P12V_AUX")
	)
	(via
		(at 49.186846 -68.75653)
		(size 0.508)
		(drill 0.254)
		(layers "F.Cu" "B.Cu")
		(net "P12V_AUX")
	)
	(via
		(at 77.462634 -67.537838)
		(size 0.508)
		(drill 0.254)
		(layers "F.Cu" "B.Cu")
		(net "P12V_AUX")
	)
	(via
		(at 101.78669 -59.992006)
		(size 0.508)
		(drill 0.254)
		(layers "F.Cu" "B.Cu")
		(net "P12V_AUX")
	)
	(via
		(at 359.664508 -131.419854)
		(size 0.508)
		(drill 0.254)
		(layers "F.Cu" "B.Cu")
		(net "P12V_AUX")
	)
	(via
		(at 239.70615 -365.694976)
		(size 0.508)
		(drill 0.254)
		(layers "F.Cu" "B.Cu")
		(net "P12V_AUX")
	)
	(via
		(at 336.987134 -268.756638)
		(size 0.508)
		(drill 0.254)
		(layers "F.Cu" "B.Cu")
		(net "P12V_AUX")
	)
	(via
		(at 373.762778 -67.537838)
		(size 0.508)
		(drill 0.254)
		(layers "F.Cu" "B.Cu")
		(net "P12V_AUX")
	)
	(via
		(at 336.352134 -269.417038)
		(size 0.508)
		(drill 0.254)
		(layers "F.Cu" "B.Cu")
		(net "P12V_AUX")
	)
	(via
		(at 106.425238 -98.35134)
		(size 0.508)
		(drill 0.254)
		(layers "F.Cu" "B.Cu")
		(net "P12V_AUX")
	)
	(via
		(at 256.535174 -365.022638)
		(size 0.508)
		(drill 0.254)
		(layers "F.Cu" "B.Cu")
		(net "P12V_AUX")
	)
	(via
		(at 334.118204 -98.476308)
		(size 0.508)
		(drill 0.254)
		(layers "F.Cu" "B.Cu")
		(net "P12V_AUX")
	)
	(via
		(at 259.583174 -365.022638)
		(size 0.508)
		(drill 0.254)
		(layers "F.Cu" "B.Cu")
		(net "P12V_AUX")
	)
	(via
		(at 334.097884 -68.75653)
		(size 0.508)
		(drill 0.254)
		(layers "F.Cu" "B.Cu")
		(net "P12V_AUX")
	)
	(via
		(at 139.998196 -68.75653)
		(size 0.508)
		(drill 0.254)
		(layers "F.Cu" "B.Cu")
		(net "P12V_AUX")
	)
	(via
		(at 373.127778 -67.537838)
		(size 0.508)
		(drill 0.254)
		(layers "F.Cu" "B.Cu")
		(net "P12V_AUX")
	)
	(via
		(at 448.995546 -52.518818)
		(size 0.508)
		(drill 0.254)
		(layers "F.Cu" "B.Cu")
		(net "P12V_AUX")
	)
	(via
		(at 280.716736 -59.992006)
		(size 0.508)
		(drill 0.254)
		(layers "F.Cu" "B.Cu")
		(net "P12V_AUX")
	)
	(via
		(at 369.062 -155.996132)
		(size 0.508)
		(drill 0.254)
		(layers "F.Cu" "B.Cu")
		(net "P12V_AUX")
	)
	(via
		(at 333.407004 -98.476308)
		(size 0.508)
		(drill 0.254)
		(layers "F.Cu" "B.Cu")
		(net "P12V_AUX")
	)
	(via
		(at 232.395776 -363.819186)
		(size 0.508)
		(drill 0.254)
		(layers "F.Cu" "B.Cu")
		(net "P12V_AUX")
	)
	(via
		(at 220.965776 -365.343186)
		(size 0.508)
		(drill 0.254)
		(layers "F.Cu" "B.Cu")
		(net "P12V_AUX")
	)
	(via
		(at 105.731818 -211.250022)
		(size 0.508)
		(drill 0.254)
		(layers "F.Cu" "B.Cu")
		(net "P12V_AUX")
	)
	(via
		(at 103.230934 -98.336354)
		(size 0.508)
		(drill 0.254)
		(layers "F.Cu" "B.Cu")
		(net "P12V_AUX")
	)
	(via
		(at 424.086782 -59.992006)
		(size 0.508)
		(drill 0.254)
		(layers "F.Cu" "B.Cu")
		(net "P12V_AUX")
	)
	(via
		(at 241.942874 -135.114792)
		(size 0.508)
		(drill 0.254)
		(layers "F.Cu" "B.Cu")
		(net "P12V_AUX")
	)
	(via
		(at 110.30966 -180.288946)
		(size 0.508)
		(drill 0.254)
		(layers "F.Cu" "B.Cu")
		(net "P12V_AUX")
	)
	(via
		(at 372.0719 -63.18631)
		(size 0.508)
		(drill 0.254)
		(layers "F.Cu" "B.Cu")
		(net "P12V_AUX")
	)
	(via
		(at 396.816834 -59.992006)
		(size 0.508)
		(drill 0.254)
		(layers "F.Cu" "B.Cu")
		(net "P12V_AUX")
	)
	(via
		(at 190.651892 -68.12153)
		(size 0.508)
		(drill 0.254)
		(layers "F.Cu" "B.Cu")
		(net "P12V_AUX")
	)
	(via
		(at 247.112282 -364.235238)
		(size 0.508)
		(drill 0.254)
		(layers "F.Cu" "B.Cu")
		(net "P12V_AUX")
	)
	(via
		(at 398.086834 -59.992006)
		(size 0.508)
		(drill 0.254)
		(layers "F.Cu" "B.Cu")
		(net "P12V_AUX")
	)
	(via
		(at 231.633776 -363.819186)
		(size 0.508)
		(drill 0.254)
		(layers "F.Cu" "B.Cu")
		(net "P12V_AUX")
	)
	(via
		(at 247.874282 -365.759238)
		(size 0.508)
		(drill 0.254)
		(layers "F.Cu" "B.Cu")
		(net "P12V_AUX")
	)
	(via
		(at 206.476854 -364.618016)
		(size 0.508)
		(drill 0.254)
		(layers "F.Cu" "B.Cu")
		(net "P12V_AUX")
	)
	(via
		(at 337.622134 -269.417038)
		(size 0.508)
		(drill 0.254)
		(layers "F.Cu" "B.Cu")
		(net "P12V_AUX")
	)
	(via
		(at 398.071848 -63.18631)
		(size 0.508)
		(drill 0.254)
		(layers "F.Cu" "B.Cu")
		(net "P12V_AUX")
	)
	(via
		(at 218.568524 -56.297068)
		(size 0.508)
		(drill 0.254)
		(layers "F.Cu" "B.Cu")
		(net "P12V_AUX")
	)
	(via
		(at 112.672114 -259.020564)
		(size 0.508)
		(drill 0.254)
		(layers "F.Cu" "B.Cu")
		(net "P12V_AUX")
	)
	(via
		(at 450.08673 -59.992006)
		(size 0.508)
		(drill 0.254)
		(layers "F.Cu" "B.Cu")
		(net "P12V_AUX")
	)
	(via
		(at 165.286944 -68.12153)
		(size 0.508)
		(drill 0.254)
		(layers "F.Cu" "B.Cu")
		(net "P12V_AUX")
	)
	(via
		(at 250.685046 -364.235238)
		(size 0.508)
		(drill 0.254)
		(layers "F.Cu" "B.Cu")
		(net "P12V_AUX")
	)
	(via
		(at 48.72863 -56.313832)
		(size 0.508)
		(drill 0.254)
		(layers "F.Cu" "B.Cu")
		(net "P12V_AUX")
	)
	(via
		(at 206.498444 -366.13719)
		(size 0.508)
		(drill 0.254)
		(layers "F.Cu" "B.Cu")
		(net "P12V_AUX")
	)
	(via
		(at 23.186898 -68.12153)
		(size 0.508)
		(drill 0.254)
		(layers "F.Cu" "B.Cu")
		(net "P12V_AUX")
	)
	(via
		(at 262.348218 -363.528102)
		(size 0.508)
		(drill 0.254)
		(layers "F.Cu" "B.Cu")
		(net "P12V_AUX")
	)
	(via
		(at 188.806074 -413.479234)
		(size 0.508)
		(drill 0.254)
		(layers "F.Cu" "B.Cu")
		(net "P12V_AUX")
	)
	(via
		(at 254.576834 -57.968134)
		(size 0.508)
		(drill 0.254)
		(layers "F.Cu" "B.Cu")
		(net "P12V_AUX")
	)
	(via
		(at 451.530974 -97.701354)
		(size 0.508)
		(drill 0.254)
		(layers "F.Cu" "B.Cu")
		(net "P12V_AUX")
	)
	(via
		(at 256.067052 -359.558844)
		(size 0.508)
		(drill 0.254)
		(layers "F.Cu" "B.Cu")
		(net "P12V_AUX")
	)
	(via
		(at 240.46815 -363.408976)
		(size 0.508)
		(drill 0.254)
		(layers "F.Cu" "B.Cu")
		(net "P12V_AUX")
	)
	(via
		(at 243.544598 -156.936694)
		(size 0.4064)
		(drill 0.2032)
		(layers "F.Cu" "B.Cu")
		(net "P12V_AUX")
	)
	(via
		(at 370.676932 -58.679334)
		(size 0.508)
		(drill 0.254)
		(layers "F.Cu" "B.Cu")
		(net "P12V_AUX")
	)
	(via
		(at 217.251788 -59.992006)
		(size 0.508)
		(drill 0.254)
		(layers "F.Cu" "B.Cu")
		(net "P12V_AUX")
	)
	(via
		(at 190.61684 -59.992006)
		(size 0.508)
		(drill 0.254)
		(layers "F.Cu" "B.Cu")
		(net "P12V_AUX")
	)
	(via
		(at 282.668472 -56.297068)
		(size 0.508)
		(drill 0.254)
		(layers "F.Cu" "B.Cu")
		(net "P12V_AUX")
	)
	(via
		(at 255.773174 -363.498638)
		(size 0.508)
		(drill 0.254)
		(layers "F.Cu" "B.Cu")
		(net "P12V_AUX")
	)
	(via
		(at 332.716632 -59.992006)
		(size 0.508)
		(drill 0.254)
		(layers "F.Cu" "B.Cu")
		(net "P12V_AUX")
	)
	(via
		(at 249.923046 -365.759238)
		(size 0.508)
		(drill 0.254)
		(layers "F.Cu" "B.Cu")
		(net "P12V_AUX")
	)
	(via
		(at 280.576782 -58.679334)
		(size 0.508)
		(drill 0.254)
		(layers "F.Cu" "B.Cu")
		(net "P12V_AUX")
	)
	(via
		(at 448.360546 -52.518818)
		(size 0.508)
		(drill 0.254)
		(layers "F.Cu" "B.Cu")
		(net "P12V_AUX")
	)
	(via
		(at 233.768646 -114.38636)
		(size 0.4064)
		(drill 0.2032)
		(layers "F.Cu" "B.Cu")
		(net "P12V_AUX")
	)
	(via
		(at 136.861804 -155.996132)
		(size 0.508)
		(drill 0.254)
		(layers "F.Cu" "B.Cu")
		(net "P12V_AUX")
	)
	(via
		(at 104.786938 -268.756638)
		(size 0.508)
		(drill 0.254)
		(layers "F.Cu" "B.Cu")
		(net "P12V_AUX")
	)
	(via
		(at 209.524854 -364.618016)
		(size 0.508)
		(drill 0.254)
		(layers "F.Cu" "B.Cu")
		(net "P12V_AUX")
	)
	(via
		(at 191.25184 -59.992006)
		(size 0.508)
		(drill 0.254)
		(layers "F.Cu" "B.Cu")
		(net "P12V_AUX")
	)
	(via
		(at 280.751788 -68.12153)
		(size 0.508)
		(drill 0.254)
		(layers "F.Cu" "B.Cu")
		(net "P12V_AUX")
	)
	(via
		(at 230.109776 -364.581186)
		(size 0.508)
		(drill 0.254)
		(layers "F.Cu" "B.Cu")
		(net "P12V_AUX")
	)
	(via
		(at 107.955842 -110.235746)
		(size 0.4064)
		(drill 0.2032)
		(layers "F.Cu" "B.Cu")
		(net "P12V_AUX")
	)
	(via
		(at 164.601906 -63.18631)
		(size 0.508)
		(drill 0.254)
		(layers "F.Cu" "B.Cu")
		(net "P12V_AUX")
	)
	(via
		(at 205.736444 -366.13719)
		(size 0.508)
		(drill 0.254)
		(layers "F.Cu" "B.Cu")
		(net "P12V_AUX")
	)
	(via
		(at 253.733046 -362.711238)
		(size 0.508)
		(drill 0.254)
		(layers "F.Cu" "B.Cu")
		(net "P12V_AUX")
	)
	(via
		(at 335.430876 -97.701354)
		(size 0.508)
		(drill 0.254)
		(layers "F.Cu" "B.Cu")
		(net "P12V_AUX")
	)
	(via
		(at 75.786742 -59.992006)
		(size 0.508)
		(drill 0.254)
		(layers "F.Cu" "B.Cu")
		(net "P12V_AUX")
	)
	(via
		(at 237.42015 -362.646976)
		(size 0.508)
		(drill 0.254)
		(layers "F.Cu" "B.Cu")
		(net "P12V_AUX")
	)
	(via
		(at 358.102154 -269.417038)
		(size 0.508)
		(drill 0.254)
		(layers "F.Cu" "B.Cu")
		(net "P12V_AUX")
	)
	(via
		(at 256.067052 -358.847644)
		(size 0.508)
		(drill 0.254)
		(layers "F.Cu" "B.Cu")
		(net "P12V_AUX")
	)
	(via
		(at 451.530974 -98.336354)
		(size 0.508)
		(drill 0.254)
		(layers "F.Cu" "B.Cu")
		(net "P12V_AUX")
	)
	(via
		(at 139.46378 -56.313832)
		(size 0.508)
		(drill 0.254)
		(layers "F.Cu" "B.Cu")
		(net "P12V_AUX")
	)
	(via
		(at 250.685046 -363.473238)
		(size 0.508)
		(drill 0.254)
		(layers "F.Cu" "B.Cu")
		(net "P12V_AUX")
	)
	(via
		(at 263.110218 -364.290102)
		(size 0.508)
		(drill 0.254)
		(layers "F.Cu" "B.Cu")
		(net "P12V_AUX")
	)
	(via
		(at 233.055414 -112.08512)
		(size 0.508)
		(drill 0.254)
		(layers "F.Cu" "B.Cu")
		(net "P12V_AUX")
	)
	(via
		(at 340.155784 -112.935766)
		(size 0.4064)
		(drill 0.2032)
		(layers "F.Cu" "B.Cu")
		(net "P12V_AUX")
	)
	(via
		(at 370.245132 -57.002934)
		(size 0.508)
		(drill 0.254)
		(layers "F.Cu" "B.Cu")
		(net "P12V_AUX")
	)
	(via
		(at 358.042972 -135.114792)
		(size 0.508)
		(drill 0.254)
		(layers "F.Cu" "B.Cu")
		(net "P12V_AUX")
	)
	(via
		(at 243.704364 -133.443726)
		(size 0.508)
		(drill 0.254)
		(layers "F.Cu" "B.Cu")
		(net "P12V_AUX")
	)
	(via
		(at 333.563468 -56.313832)
		(size 0.508)
		(drill 0.254)
		(layers "F.Cu" "B.Cu")
		(net "P12V_AUX")
	)
	(via
		(at 253.733046 -364.997238)
		(size 0.508)
		(drill 0.254)
		(layers "F.Cu" "B.Cu")
		(net "P12V_AUX")
	)
	(via
		(at 341.07374 -103.658416)
		(size 0.508)
		(drill 0.254)
		(layers "F.Cu" "B.Cu")
		(net "P12V_AUX")
	)
	(via
		(at 74.551794 -68.75653)
		(size 0.508)
		(drill 0.254)
		(layers "F.Cu" "B.Cu")
		(net "P12V_AUX")
	)
	(via
		(at 216.616788 -59.992006)
		(size 0.508)
		(drill 0.254)
		(layers "F.Cu" "B.Cu")
		(net "P12V_AUX")
	)
	(via
		(at 262.348218 -365.814102)
		(size 0.508)
		(drill 0.254)
		(layers "F.Cu" "B.Cu")
		(net "P12V_AUX")
	)
	(via
		(at 396.36065 -52.518818)
		(size 0.508)
		(drill 0.254)
		(layers "F.Cu" "B.Cu")
		(net "P12V_AUX")
	)
	(via
		(at 217.871802 -63.18631)
		(size 0.508)
		(drill 0.254)
		(layers "F.Cu" "B.Cu")
		(net "P12V_AUX")
	)
	(via
		(at 255.773174 -365.784638)
		(size 0.508)
		(drill 0.254)
		(layers "F.Cu" "B.Cu")
		(net "P12V_AUX")
	)
	(via
		(at 20.76196 -156.707332)
		(size 0.508)
		(drill 0.254)
		(layers "F.Cu" "B.Cu")
		(net "P12V_AUX")
	)
	(via
		(at 455.54265 -108.569506)
		(size 0.508)
		(drill 0.254)
		(layers "F.Cu" "B.Cu")
		(net "P12V_AUX")
	)
	(via
		(at 136.861804 -157.418532)
		(size 0.508)
		(drill 0.254)
		(layers "F.Cu" "B.Cu")
		(net "P12V_AUX")
	)
	(via
		(at 335.430876 -97.066354)
		(size 0.508)
		(drill 0.254)
		(layers "F.Cu" "B.Cu")
		(net "P12V_AUX")
	)
	(via
		(at 11.152632 -135.098028)
		(size 0.508)
		(drill 0.254)
		(layers "F.Cu" "B.Cu")
		(net "P12V_AUX")
	)
	(via
		(at 139.871958 -63.18631)
		(size 0.508)
		(drill 0.254)
		(layers "F.Cu" "B.Cu")
		(net "P12V_AUX")
	)
	(via
		(at 140.56868 -56.297068)
		(size 0.508)
		(drill 0.254)
		(layers "F.Cu" "B.Cu")
		(net "P12V_AUX")
	)
	(via
		(at 11.364468 -131.419854)
		(size 0.508)
		(drill 0.254)
		(layers "F.Cu" "B.Cu")
		(net "P12V_AUX")
	)
	(via
		(at 238.94415 -365.694976)
		(size 0.508)
		(drill 0.254)
		(layers "F.Cu" "B.Cu")
		(net "P12V_AUX")
	)
	(via
		(at 209.524854 -363.246416)
		(size 0.508)
		(drill 0.254)
		(layers "F.Cu" "B.Cu")
		(net "P12V_AUX")
	)
	(via
		(at 371.663722 -56.313832)
		(size 0.508)
		(drill 0.254)
		(layers "F.Cu" "B.Cu")
		(net "P12V_AUX")
	)
	(via
		(at 11.787632 -135.098028)
		(size 0.508)
		(drill 0.254)
		(layers "F.Cu" "B.Cu")
		(net "P12V_AUX")
	)
	(via
		(at 231.633776 -366.105186)
		(size 0.508)
		(drill 0.254)
		(layers "F.Cu" "B.Cu")
		(net "P12V_AUX")
	)
	(via
		(at 206.498444 -365.45139)
		(size 0.508)
		(drill 0.254)
		(layers "F.Cu" "B.Cu")
		(net "P12V_AUX")
	)
	(via
		(at 23.13686 -63.18631)
		(size 0.508)
		(drill 0.254)
		(layers "F.Cu" "B.Cu")
		(net "P12V_AUX")
	)
	(via
		(at 101.897942 -68.12153)
		(size 0.508)
		(drill 0.254)
		(layers "F.Cu" "B.Cu")
		(net "P12V_AUX")
	)
	(via
		(at 306.716684 -59.992006)
		(size 0.508)
		(drill 0.254)
		(layers "F.Cu" "B.Cu")
		(net "P12V_AUX")
	)
	(via
		(at 14.044676 -157.647894)
		(size 0.4064)
		(drill 0.2032)
		(layers "F.Cu" "B.Cu")
		(net "P12V_AUX")
	)
	(via
		(at 457.101956 -106.77525)
		(size 0.508)
		(drill 0.254)
		(layers "F.Cu" "B.Cu")
		(net "P12V_AUX")
	)
	(via
		(at 258.059174 -365.784638)
		(size 0.508)
		(drill 0.254)
		(layers "F.Cu" "B.Cu")
		(net "P12V_AUX")
	)
	(via
		(at 225.365564 -102.275132)
		(size 0.508)
		(drill 0.254)
		(layers "F.Cu" "B.Cu")
		(net "P12V_AUX")
	)
	(via
		(at 241.51971 -320.816732)
		(size 0.508)
		(drill 0.254)
		(layers "F.Cu" "B.Cu")
		(net "P12V_AUX")
	)
	(via
		(at 107.244642 -112.035844)
		(size 0.4064)
		(drill 0.2032)
		(layers "F.Cu" "B.Cu")
		(net "P12V_AUX")
	)
	(via
		(at 346.65031 -255.210564)
		(size 0.508)
		(drill 0.254)
		(layers "F.Cu" "B.Cu")
		(net "P12V_AUX")
	)
	(via
		(at 127.887476 -135.098028)
		(size 0.508)
		(drill 0.254)
		(layers "F.Cu" "B.Cu")
		(net "P12V_AUX")
	)
	(via
		(at 242.78971 -320.181732)
		(size 0.508)
		(drill 0.254)
		(layers "F.Cu" "B.Cu")
		(net "P12V_AUX")
	)
	(via
		(at 246.350282 -364.235238)
		(size 0.508)
		(drill 0.254)
		(layers "F.Cu" "B.Cu")
		(net "P12V_AUX")
	)
	(via
		(at 230.109776 -365.343186)
		(size 0.508)
		(drill 0.254)
		(layers "F.Cu" "B.Cu")
		(net "P12V_AUX")
	)
	(via
		(at 229.347776 -362.295186)
		(size 0.508)
		(drill 0.254)
		(layers "F.Cu" "B.Cu")
		(net "P12V_AUX")
	)
	(via
		(at 249.923046 -364.235238)
		(size 0.508)
		(drill 0.254)
		(layers "F.Cu" "B.Cu")
		(net "P12V_AUX")
	)
	(via
		(at 101.363526 -56.313832)
		(size 0.508)
		(drill 0.254)
		(layers "F.Cu" "B.Cu")
		(net "P12V_AUX")
	)
	(via
		(at 449.486782 -68.75653)
		(size 0.508)
		(drill 0.254)
		(layers "F.Cu" "B.Cu")
		(net "P12V_AUX")
	)
	(via
		(at 233.057446 -115.286536)
		(size 0.4064)
		(drill 0.2032)
		(layers "F.Cu" "B.Cu")
		(net "P12V_AUX")
	)
	(via
		(at 233.768646 -117.08638)
		(size 0.4064)
		(drill 0.2032)
		(layers "F.Cu" "B.Cu")
		(net "P12V_AUX")
	)
	(via
		(at 451.762622 -67.537838)
		(size 0.508)
		(drill 0.254)
		(layers "F.Cu" "B.Cu")
		(net "P12V_AUX")
	)
	(via
		(at 217.99804 -68.12153)
		(size 0.508)
		(drill 0.254)
		(layers "F.Cu" "B.Cu")
		(net "P12V_AUX")
	)
	(via
		(at 396.67688 -58.679334)
		(size 0.508)
		(drill 0.254)
		(layers "F.Cu" "B.Cu")
		(net "P12V_AUX")
	)
	(via
		(at 218.679776 -364.581186)
		(size 0.508)
		(drill 0.254)
		(layers "F.Cu" "B.Cu")
		(net "P12V_AUX")
	)
	(via
		(at 209.524854 -362.560616)
		(size 0.508)
		(drill 0.254)
		(layers "F.Cu" "B.Cu")
		(net "P12V_AUX")
	)
	(via
		(at 244.44452 -156.936694)
		(size 0.4064)
		(drill 0.2032)
		(layers "F.Cu" "B.Cu")
		(net "P12V_AUX")
	)
	(via
		(at 211.048854 -363.246416)
		(size 0.508)
		(drill 0.254)
		(layers "F.Cu" "B.Cu")
		(net "P12V_AUX")
	)
	(via
		(at 425.762674 -67.537838)
		(size 0.508)
		(drill 0.254)
		(layers "F.Cu" "B.Cu")
		(net "P12V_AUX")
	)
	(via
		(at 238.18215 -363.408976)
		(size 0.508)
		(drill 0.254)
		(layers "F.Cu" "B.Cu")
		(net "P12V_AUX")
	)
	(via
		(at 259.583174 -364.260638)
		(size 0.508)
		(drill 0.254)
		(layers "F.Cu" "B.Cu")
		(net "P12V_AUX")
	)
	(via
		(at 281.97175 -63.18631)
		(size 0.508)
		(drill 0.254)
		(layers "F.Cu" "B.Cu")
		(net "P12V_AUX")
	)
	(via
		(at 336.987134 -269.417038)
		(size 0.508)
		(drill 0.254)
		(layers "F.Cu" "B.Cu")
		(net "P12V_AUX")
	)
	(via
		(at 221.727776 -364.581186)
		(size 0.508)
		(drill 0.254)
		(layers "F.Cu" "B.Cu")
		(net "P12V_AUX")
	)
	(via
		(at 422.851834 -68.75653)
		(size 0.508)
		(drill 0.254)
		(layers "F.Cu" "B.Cu")
		(net "P12V_AUX")
	)
	(via
		(at 263.872218 -364.290102)
		(size 0.508)
		(drill 0.254)
		(layers "F.Cu" "B.Cu")
		(net "P12V_AUX")
	)
	(via
		(at 228.585776 -362.295186)
		(size 0.508)
		(drill 0.254)
		(layers "F.Cu" "B.Cu")
		(net "P12V_AUX")
	)
	(via
		(at 13.1445 -157.647894)
		(size 0.4064)
		(drill 0.2032)
		(layers "F.Cu" "B.Cu")
		(net "P12V_AUX")
	)
	(via
		(at 100.241862 -98.908108)
		(size 0.508)
		(drill 0.254)
		(layers "F.Cu" "B.Cu")
		(net "P12V_AUX")
	)
	(via
		(at 23.363682 -56.313832)
		(size 0.508)
		(drill 0.254)
		(layers "F.Cu" "B.Cu")
		(net "P12V_AUX")
	)
	(via
		(at 360.087672 -135.098028)
		(size 0.508)
		(drill 0.254)
		(layers "F.Cu" "B.Cu")
		(net "P12V_AUX")
	)
	(via
		(at 48.501808 -63.18631)
		(size 0.508)
		(drill 0.254)
		(layers "F.Cu" "B.Cu")
		(net "P12V_AUX")
	)
	(via
		(at 108.358178 -180.93944)
		(size 0.508)
		(drill 0.254)
		(layers "F.Cu" "B.Cu")
		(net "P12V_AUX")
	)
	(via
		(at 190.601854 -63.18631)
		(size 0.508)
		(drill 0.254)
		(layers "F.Cu" "B.Cu")
		(net "P12V_AUX")
	)
	(via
		(at 280.70175 -63.18631)
		(size 0.508)
		(drill 0.254)
		(layers "F.Cu" "B.Cu")
		(net "P12V_AUX")
	)
	(via
		(at 249.098562 -158.753302)
		(size 0.508)
		(drill 0.254)
		(layers "F.Cu" "B.Cu")
		(net "P12V_AUX")
	)
	(via
		(at 337.622134 -268.756638)
		(size 0.508)
		(drill 0.254)
		(layers "F.Cu" "B.Cu")
		(net "P12V_AUX")
	)
	(via
		(at 126.829312 -131.419854)
		(size 0.508)
		(drill 0.254)
		(layers "F.Cu" "B.Cu")
		(net "P12V_AUX")
	)
	(via
		(at 244.826282 -365.759238)
		(size 0.508)
		(drill 0.254)
		(layers "F.Cu" "B.Cu")
		(net "P12V_AUX")
	)
	(via
		(at 217.99804 -68.75653)
		(size 0.508)
		(drill 0.254)
		(layers "F.Cu" "B.Cu")
		(net "P12V_AUX")
	)
	(via
		(at 423.028618 -56.313832)
		(size 0.508)
		(drill 0.254)
		(layers "F.Cu" "B.Cu")
		(net "P12V_AUX")
	)
	(via
		(at 255.38684 -68.12153)
		(size 0.508)
		(drill 0.254)
		(layers "F.Cu" "B.Cu")
		(net "P12V_AUX")
	)
	(via
		(at 217.917776 -364.581186)
		(size 0.508)
		(drill 0.254)
		(layers "F.Cu" "B.Cu")
		(net "P12V_AUX")
	)
	(via
		(at 75.186794 -68.75653)
		(size 0.508)
		(drill 0.254)
		(layers "F.Cu" "B.Cu")
		(net "P12V_AUX")
	)
	(via
		(at 237.42015 -363.408976)
		(size 0.508)
		(drill 0.254)
		(layers "F.Cu" "B.Cu")
		(net "P12V_AUX")
	)
	(via
		(at 338.227924 -98.188018)
		(size 0.508)
		(drill 0.254)
		(layers "F.Cu" "B.Cu")
		(net "P12V_AUX")
	)
	(via
		(at 238.94415 -364.932976)
		(size 0.508)
		(drill 0.254)
		(layers "F.Cu" "B.Cu")
		(net "P12V_AUX")
	)
	(via
		(at 280.576782 -57.968134)
		(size 0.508)
		(drill 0.254)
		(layers "F.Cu" "B.Cu")
		(net "P12V_AUX")
	)
	(via
		(at 254.928624 -56.313832)
		(size 0.508)
		(drill 0.254)
		(layers "F.Cu" "B.Cu")
		(net "P12V_AUX")
	)
	(via
		(at 49.898046 -68.12153)
		(size 0.508)
		(drill 0.254)
		(layers "F.Cu" "B.Cu")
		(net "P12V_AUX")
	)
	(via
		(at 247.112282 -364.997238)
		(size 0.508)
		(drill 0.254)
		(layers "F.Cu" "B.Cu")
		(net "P12V_AUX")
	)
	(via
		(at 281.386788 -68.75653)
		(size 0.508)
		(drill 0.254)
		(layers "F.Cu" "B.Cu")
		(net "P12V_AUX")
	)
	(via
		(at 246.244618 -156.936694)
		(size 0.4064)
		(drill 0.2032)
		(layers "F.Cu" "B.Cu")
		(net "P12V_AUX")
	)
	(via
		(at 241.23015 -362.646976)
		(size 0.508)
		(drill 0.254)
		(layers "F.Cu" "B.Cu")
		(net "P12V_AUX")
	)
	(via
		(at 75.136756 -63.18631)
		(size 0.508)
		(drill 0.254)
		(layers "F.Cu" "B.Cu")
		(net "P12V_AUX")
	)
	(via
		(at 251.447046 -365.759238)
		(size 0.508)
		(drill 0.254)
		(layers "F.Cu" "B.Cu")
		(net "P12V_AUX")
	)
	(via
		(at 217.236802 -63.18631)
		(size 0.508)
		(drill 0.254)
		(layers "F.Cu" "B.Cu")
		(net "P12V_AUX")
	)
	(via
		(at 358.817672 -135.098028)
		(size 0.508)
		(drill 0.254)
		(layers "F.Cu" "B.Cu")
		(net "P12V_AUX")
	)
	(via
		(at 235.52912 -110.925864)
		(size 0.508)
		(drill 0.254)
		(layers "F.Cu" "B.Cu")
		(net "P12V_AUX")
	)
	(via
		(at 307.5305 -52.518818)
		(size 0.508)
		(drill 0.254)
		(layers "F.Cu" "B.Cu")
		(net "P12V_AUX")
	)
	(via
		(at 397.451834 -59.992006)
		(size 0.508)
		(drill 0.254)
		(layers "F.Cu" "B.Cu")
		(net "P12V_AUX")
	)
	(via
		(at 449.630546 -52.518818)
		(size 0.508)
		(drill 0.254)
		(layers "F.Cu" "B.Cu")
		(net "P12V_AUX")
	)
	(via
		(at 22.695662 -52.518818)
		(size 0.508)
		(drill 0.254)
		(layers "F.Cu" "B.Cu")
		(net "P12V_AUX")
	)
	(via
		(at 332.293468 -56.313832)
		(size 0.508)
		(drill 0.254)
		(layers "F.Cu" "B.Cu")
		(net "P12V_AUX")
	)
	(via
		(at 125.901958 -269.417038)
		(size 0.508)
		(drill 0.254)
		(layers "F.Cu" "B.Cu")
		(net "P12V_AUX")
	)
	(via
		(at 397.66367 -56.313832)
		(size 0.508)
		(drill 0.254)
		(layers "F.Cu" "B.Cu")
		(net "P12V_AUX")
	)
	(via
		(at 216.65184 -68.75653)
		(size 0.508)
		(drill 0.254)
		(layers "F.Cu" "B.Cu")
		(net "P12V_AUX")
	)
	(via
		(at 165.463728 -56.313832)
		(size 0.508)
		(drill 0.254)
		(layers "F.Cu" "B.Cu")
		(net "P12V_AUX")
	)
	(via
		(at 109.67466 -180.949346)
		(size 0.508)
		(drill 0.254)
		(layers "F.Cu" "B.Cu")
		(net "P12V_AUX")
	)
	(via
		(at 253.733046 -363.473238)
		(size 0.508)
		(drill 0.254)
		(layers "F.Cu" "B.Cu")
		(net "P12V_AUX")
	)
	(via
		(at 396.99565 -52.518818)
		(size 0.508)
		(drill 0.254)
		(layers "F.Cu" "B.Cu")
		(net "P12V_AUX")
	)
	(via
		(at 23.186898 -68.75653)
		(size 0.508)
		(drill 0.254)
		(layers "F.Cu" "B.Cu")
		(net "P12V_AUX")
	)
	(via
		(at 399.762726 -67.537838)
		(size 0.508)
		(drill 0.254)
		(layers "F.Cu" "B.Cu")
		(net "P12V_AUX")
	)
	(via
		(at 244.826282 -364.235238)
		(size 0.508)
		(drill 0.254)
		(layers "F.Cu" "B.Cu")
		(net "P12V_AUX")
	)
	(via
		(at 423.486834 -68.75653)
		(size 0.508)
		(drill 0.254)
		(layers "F.Cu" "B.Cu")
		(net "P12V_AUX")
	)
	(via
		(at 332.701646 -63.18631)
		(size 0.508)
		(drill 0.254)
		(layers "F.Cu" "B.Cu")
		(net "P12V_AUX")
	)
	(via
		(at 208.022444 -366.13719)
		(size 0.508)
		(drill 0.254)
		(layers "F.Cu" "B.Cu")
		(net "P12V_AUX")
	)
	(via
		(at 238.18215 -365.694976)
		(size 0.508)
		(drill 0.254)
		(layers "F.Cu" "B.Cu")
		(net "P12V_AUX")
	)
	(via
		(at 456.255882 -112.035844)
		(size 0.4064)
		(drill 0.2032)
		(layers "F.Cu" "B.Cu")
		(net "P12V_AUX")
	)
	(via
		(at 10.729468 -131.419854)
		(size 0.508)
		(drill 0.254)
		(layers "F.Cu" "B.Cu")
		(net "P12V_AUX")
	)
	(via
		(at 49.33061 -52.518818)
		(size 0.508)
		(drill 0.254)
		(layers "F.Cu" "B.Cu")
		(net "P12V_AUX")
	)
	(via
		(at 233.057446 -114.38636)
		(size 0.4064)
		(drill 0.2032)
		(layers "F.Cu" "B.Cu")
		(net "P12V_AUX")
	)
	(via
		(at 249.923046 -364.997238)
		(size 0.508)
		(drill 0.254)
		(layers "F.Cu" "B.Cu")
		(net "P12V_AUX")
	)
	(via
		(at 127.4445 -157.647894)
		(size 0.4064)
		(drill 0.2032)
		(layers "F.Cu" "B.Cu")
		(net "P12V_AUX")
	)
	(via
		(at 48.06061 -52.518818)
		(size 0.508)
		(drill 0.254)
		(layers "F.Cu" "B.Cu")
		(net "P12V_AUX")
	)
	(via
		(at 423.663618 -56.313832)
		(size 0.508)
		(drill 0.254)
		(layers "F.Cu" "B.Cu")
		(net "P12V_AUX")
	)
	(via
		(at 372.086886 -59.992006)
		(size 0.508)
		(drill 0.254)
		(layers "F.Cu" "B.Cu")
		(net "P12V_AUX")
	)
	(via
		(at 247.874282 -364.235238)
		(size 0.508)
		(drill 0.254)
		(layers "F.Cu" "B.Cu")
		(net "P12V_AUX")
	)
	(via
		(at 257.297174 -365.022638)
		(size 0.508)
		(drill 0.254)
		(layers "F.Cu" "B.Cu")
		(net "P12V_AUX")
	)
	(via
		(at 125.842776 -135.114792)
		(size 0.508)
		(drill 0.254)
		(layers "F.Cu" "B.Cu")
		(net "P12V_AUX")
	)
	(via
		(at 252.961902 -157.418532)
		(size 0.508)
		(drill 0.254)
		(layers "F.Cu" "B.Cu")
		(net "P12V_AUX")
	)
	(via
		(at 208.022444 -365.45139)
		(size 0.508)
		(drill 0.254)
		(layers "F.Cu" "B.Cu")
		(net "P12V_AUX")
	)
	(via
		(at 258.059174 -362.736638)
		(size 0.508)
		(drill 0.254)
		(layers "F.Cu" "B.Cu")
		(net "P12V_AUX")
	)
	(via
		(at 257.297174 -364.260638)
		(size 0.508)
		(drill 0.254)
		(layers "F.Cu" "B.Cu")
		(net "P12V_AUX")
	)
	(via
		(at 13.1445 -156.936694)
		(size 0.4064)
		(drill 0.2032)
		(layers "F.Cu" "B.Cu")
		(net "P12V_AUX")
	)
	(via
		(at 457.173838 -103.658416)
		(size 0.508)
		(drill 0.254)
		(layers "F.Cu" "B.Cu")
		(net "P12V_AUX")
	)
	(via
		(at 451.530974 -97.066354)
		(size 0.508)
		(drill 0.254)
		(layers "F.Cu" "B.Cu")
		(net "P12V_AUX")
	)
	(via
		(at 341.713058 -106.77525)
		(size 0.508)
		(drill 0.254)
		(layers "F.Cu" "B.Cu")
		(net "P12V_AUX")
	)
	(via
		(at 396.851886 -68.12153)
		(size 0.508)
		(drill 0.254)
		(layers "F.Cu" "B.Cu")
		(net "P12V_AUX")
	)
	(via
		(at 218.679776 -366.105186)
		(size 0.508)
		(drill 0.254)
		(layers "F.Cu" "B.Cu")
		(net "P12V_AUX")
	)
	(via
		(at 100.376736 -58.679334)
		(size 0.508)
		(drill 0.254)
		(layers "F.Cu" "B.Cu")
		(net "P12V_AUX")
	)
	(via
		(at 138.19378 -56.313832)
		(size 0.508)
		(drill 0.254)
		(layers "F.Cu" "B.Cu")
		(net "P12V_AUX")
	)
	(via
		(at 128.344422 -157.647894)
		(size 0.4064)
		(drill 0.2032)
		(layers "F.Cu" "B.Cu")
		(net "P12V_AUX")
	)
	(via
		(at 127.464312 -131.419854)
		(size 0.508)
		(drill 0.254)
		(layers "F.Cu" "B.Cu")
		(net "P12V_AUX")
	)
	(via
		(at 49.186846 -68.12153)
		(size 0.508)
		(drill 0.254)
		(layers "F.Cu" "B.Cu")
		(net "P12V_AUX")
	)
	(via
		(at 108.873798 -103.658416)
		(size 0.508)
		(drill 0.254)
		(layers "F.Cu" "B.Cu")
		(net "P12V_AUX")
	)
	(via
		(at 105.731818 -210.615022)
		(size 0.508)
		(drill 0.254)
		(layers "F.Cu" "B.Cu")
		(net "P12V_AUX")
	)
	(via
		(at 107.955842 -111.135922)
		(size 0.4064)
		(drill 0.2032)
		(layers "F.Cu" "B.Cu")
		(net "P12V_AUX")
	)
	(via
		(at 369.062 -156.707332)
		(size 0.508)
		(drill 0.254)
		(layers "F.Cu" "B.Cu")
		(net "P12V_AUX")
	)
	(via
		(at 105.096818 -210.615022)
		(size 0.508)
		(drill 0.254)
		(layers "F.Cu" "B.Cu")
		(net "P12V_AUX")
	)
	(via
		(at 247.874282 -363.473238)
		(size 0.508)
		(drill 0.254)
		(layers "F.Cu" "B.Cu")
		(net "P12V_AUX")
	)
	(via
		(at 334.668368 -56.297068)
		(size 0.508)
		(drill 0.254)
		(layers "F.Cu" "B.Cu")
		(net "P12V_AUX")
	)
	(via
		(at 232.238042 -101.866954)
		(size 0.508)
		(drill 0.254)
		(layers "F.Cu" "B.Cu")
		(net "P12V_AUX")
	)
	(via
		(at 219.441776 -363.819186)
		(size 0.508)
		(drill 0.254)
		(layers "F.Cu" "B.Cu")
		(net "P12V_AUX")
	)
	(via
		(at 123.751086 -155.212034)
		(size 0.508)
		(drill 0.254)
		(layers "F.Cu" "B.Cu")
		(net "P12V_AUX")
	)
	(via
		(at 220.203776 -362.295186)
		(size 0.508)
		(drill 0.254)
		(layers "F.Cu" "B.Cu")
		(net "P12V_AUX")
	)
	(via
		(at 99.55276 -98.759518)
		(size 0.508)
		(drill 0.254)
		(layers "F.Cu" "B.Cu")
		(net "P12V_AUX")
	)
	(via
		(at 207.260444 -366.13719)
		(size 0.508)
		(drill 0.254)
		(layers "F.Cu" "B.Cu")
		(net "P12V_AUX")
	)
	(via
		(at 306.29352 -56.313832)
		(size 0.508)
		(drill 0.254)
		(layers "F.Cu" "B.Cu")
		(net "P12V_AUX")
	)
	(via
		(at 255.38684 -68.75653)
		(size 0.508)
		(drill 0.254)
		(layers "F.Cu" "B.Cu")
		(net "P12V_AUX")
	)
	(via
		(at 250.685046 -362.711238)
		(size 0.508)
		(drill 0.254)
		(layers "F.Cu" "B.Cu")
		(net "P12V_AUX")
	)
	(via
		(at 262.348218 -362.766102)
		(size 0.508)
		(drill 0.254)
		(layers "F.Cu" "B.Cu")
		(net "P12V_AUX")
	)
	(via
		(at 263.110218 -362.766102)
		(size 0.508)
		(drill 0.254)
		(layers "F.Cu" "B.Cu")
		(net "P12V_AUX")
	)
	(via
		(at 241.51971 -320.181732)
		(size 0.508)
		(drill 0.254)
		(layers "F.Cu" "B.Cu")
		(net "P12V_AUX")
	)
	(via
		(at 165.251892 -59.992006)
		(size 0.508)
		(drill 0.254)
		(layers "F.Cu" "B.Cu")
		(net "P12V_AUX")
	)
	(via
		(at 10.517632 -135.098028)
		(size 0.508)
		(drill 0.254)
		(layers "F.Cu" "B.Cu")
		(net "P12V_AUX")
	)
	(via
		(at 245.588282 -364.997238)
		(size 0.508)
		(drill 0.254)
		(layers "F.Cu" "B.Cu")
		(net "P12V_AUX")
	)
	(via
		(at 127.604266 -132.732526)
		(size 0.508)
		(drill 0.254)
		(layers "F.Cu" "B.Cu")
		(net "P12V_AUX")
	)
	(via
		(at 216.476834 -57.968134)
		(size 0.508)
		(drill 0.254)
		(layers "F.Cu" "B.Cu")
		(net "P12V_AUX")
	)
	(via
		(at 333.386684 -68.75653)
		(size 0.508)
		(drill 0.254)
		(layers "F.Cu" "B.Cu")
		(net "P12V_AUX")
	)
	(via
		(at 227.731066 -102.626922)
		(size 0.508)
		(drill 0.254)
		(layers "F.Cu" "B.Cu")
		(net "P12V_AUX")
	)
	(via
		(at 247.112282 -362.711238)
		(size 0.508)
		(drill 0.254)
		(layers "F.Cu" "B.Cu")
		(net "P12V_AUX")
	)
	(via
		(at 255.355852 -358.847644)
		(size 0.508)
		(drill 0.254)
		(layers "F.Cu" "B.Cu")
		(net "P12V_AUX")
	)
	(via
		(at 252.971046 -363.473238)
		(size 0.508)
		(drill 0.254)
		(layers "F.Cu" "B.Cu")
		(net "P12V_AUX")
	)
	(via
		(at 22.551898 -68.12153)
		(size 0.508)
		(drill 0.254)
		(layers "F.Cu" "B.Cu")
		(net "P12V_AUX")
	)
	(via
		(at 23.786846 -59.992006)
		(size 0.508)
		(drill 0.254)
		(layers "F.Cu" "B.Cu")
		(net "P12V_AUX")
	)
	(via
		(at 331.752702 -98.124518)
		(size 0.508)
		(drill 0.254)
		(layers "F.Cu" "B.Cu")
		(net "P12V_AUX")
	)
	(via
		(at 265.396218 -363.528102)
		(size 0.508)
		(drill 0.254)
		(layers "F.Cu" "B.Cu")
		(net "P12V_AUX")
	)
	(via
		(at 218.679776 -365.343186)
		(size 0.508)
		(drill 0.254)
		(layers "F.Cu" "B.Cu")
		(net "P12V_AUX")
	)
	(via
		(at 22.376892 -58.679334)
		(size 0.508)
		(drill 0.254)
		(layers "F.Cu" "B.Cu")
		(net "P12V_AUX")
	)
	(via
		(at 358.737154 -268.756638)
		(size 0.508)
		(drill 0.254)
		(layers "F.Cu" "B.Cu")
		(net "P12V_AUX")
	)
	(via
		(at 218.679776 -363.819186)
		(size 0.508)
		(drill 0.254)
		(layers "F.Cu" "B.Cu")
		(net "P12V_AUX")
	)
	(via
		(at 17.69618 -155.933902)
		(size 0.508)
		(drill 0.254)
		(layers "F.Cu" "B.Cu")
		(net "P12V_AUX")
	)
	(via
		(at 73.944988 -57.002934)
		(size 0.508)
		(drill 0.254)
		(layers "F.Cu" "B.Cu")
		(net "P12V_AUX")
	)
	(via
		(at 74.376788 -58.679334)
		(size 0.508)
		(drill 0.254)
		(layers "F.Cu" "B.Cu")
		(net "P12V_AUX")
	)
	(via
		(at 75.771756 -63.18631)
		(size 0.508)
		(drill 0.254)
		(layers "F.Cu" "B.Cu")
		(net "P12V_AUX")
	)
	(via
		(at 225.269552 -320.816732)
		(size 0.508)
		(drill 0.254)
		(layers "F.Cu" "B.Cu")
		(net "P12V_AUX")
	)
	(via
		(at 49.36363 -56.313832)
		(size 0.508)
		(drill 0.254)
		(layers "F.Cu" "B.Cu")
		(net "P12V_AUX")
	)
	(via
		(at 105.096818 -211.250022)
		(size 0.508)
		(drill 0.254)
		(layers "F.Cu" "B.Cu")
		(net "P12V_AUX")
	)
	(via
		(at 127.806958 -269.417038)
		(size 0.508)
		(drill 0.254)
		(layers "F.Cu" "B.Cu")
		(net "P12V_AUX")
	)
	(via
		(at 23.151846 -59.992006)
		(size 0.508)
		(drill 0.254)
		(layers "F.Cu" "B.Cu")
		(net "P12V_AUX")
	)
	(via
		(at 255.563624 -56.313832)
		(size 0.508)
		(drill 0.254)
		(layers "F.Cu" "B.Cu")
		(net "P12V_AUX")
	)
	(via
		(at 106.425238 -97.71634)
		(size 0.508)
		(drill 0.254)
		(layers "F.Cu" "B.Cu")
		(net "P12V_AUX")
	)
	(via
		(at 111.57966 -180.288946)
		(size 0.508)
		(drill 0.254)
		(layers "F.Cu" "B.Cu")
		(net "P12V_AUX")
	)
	(via
		(at 370.995702 -52.518818)
		(size 0.508)
		(drill 0.254)
		(layers "F.Cu" "B.Cu")
		(net "P12V_AUX")
	)
	(via
		(at 107.244642 -111.135922)
		(size 0.4064)
		(drill 0.2032)
		(layers "F.Cu" "B.Cu")
		(net "P12V_AUX")
	)
	(via
		(at 101.918262 -98.476308)
		(size 0.508)
		(drill 0.254)
		(layers "F.Cu" "B.Cu")
		(net "P12V_AUX")
	)
	(via
		(at 191.236854 -63.18631)
		(size 0.508)
		(drill 0.254)
		(layers "F.Cu" "B.Cu")
		(net "P12V_AUX")
	)
	(via
		(at 103.462582 -67.537838)
		(size 0.508)
		(drill 0.254)
		(layers "F.Cu" "B.Cu")
		(net "P12V_AUX")
	)
	(via
		(at 449.45173 -59.992006)
		(size 0.508)
		(drill 0.254)
		(layers "F.Cu" "B.Cu")
		(net "P12V_AUX")
	)
	(via
		(at 229.347776 -363.819186)
		(size 0.508)
		(drill 0.254)
		(layers "F.Cu" "B.Cu")
		(net "P12V_AUX")
	)
	(via
		(at 252.209046 -364.997238)
		(size 0.508)
		(drill 0.254)
		(layers "F.Cu" "B.Cu")
		(net "P12V_AUX")
	)
	(via
		(at 306.92852 -56.313832)
		(size 0.508)
		(drill 0.254)
		(layers "F.Cu" "B.Cu")
		(net "P12V_AUX")
	)
	(via
		(at 206.476854 -363.932216)
		(size 0.508)
		(drill 0.254)
		(layers "F.Cu" "B.Cu")
		(net "P12V_AUX")
	)
	(via
		(at 333.986632 -59.992006)
		(size 0.508)
		(drill 0.254)
		(layers "F.Cu" "B.Cu")
		(net "P12V_AUX")
	)
	(via
		(at 241.003328 -348.400116)
		(size 0.508)
		(drill 0.254)
		(layers "F.Cu" "B.Cu")
		(net "P12V_AUX")
	)
	(via
		(at 239.70615 -364.932976)
		(size 0.508)
		(drill 0.254)
		(layers "F.Cu" "B.Cu")
		(net "P12V_AUX")
	)
	(via
		(at 242.15471 -320.816732)
		(size 0.508)
		(drill 0.254)
		(layers "F.Cu" "B.Cu")
		(net "P12V_AUX")
	)
	(via
		(at 12.244578 -157.647894)
		(size 0.4064)
		(drill 0.2032)
		(layers "F.Cu" "B.Cu")
		(net "P12V_AUX")
	)
	(via
		(at 247.910858 -157.645862)
		(size 0.508)
		(drill 0.254)
		(layers "F.Cu" "B.Cu")
		(net "P12V_AUX")
	)
	(via
		(at 11.344656 -156.936694)
		(size 0.4064)
		(drill 0.2032)
		(layers "F.Cu" "B.Cu")
		(net "P12V_AUX")
	)
	(via
		(at 139.236958 -63.18631)
		(size 0.508)
		(drill 0.254)
		(layers "F.Cu" "B.Cu")
		(net "P12V_AUX")
	)
	(via
		(at 228.585776 -365.343186)
		(size 0.508)
		(drill 0.254)
		(layers "F.Cu" "B.Cu")
		(net "P12V_AUX")
	)
	(via
		(at 256.535174 -363.498638)
		(size 0.508)
		(drill 0.254)
		(layers "F.Cu" "B.Cu")
		(net "P12V_AUX")
	)
	(via
		(at 232.395776 -364.581186)
		(size 0.508)
		(drill 0.254)
		(layers "F.Cu" "B.Cu")
		(net "P12V_AUX")
	)
	(via
		(at 138.04519 -57.002934)
		(size 0.508)
		(drill 0.254)
		(layers "F.Cu" "B.Cu")
		(net "P12V_AUX")
	)
	(via
		(at 255.773174 -362.736638)
		(size 0.508)
		(drill 0.254)
		(layers "F.Cu" "B.Cu")
		(net "P12V_AUX")
	)
	(via
		(at 448.801744 -63.18631)
		(size 0.508)
		(drill 0.254)
		(layers "F.Cu" "B.Cu")
		(net "P12V_AUX")
	)
	(via
		(at 254.895604 -52.518818)
		(size 0.508)
		(drill 0.254)
		(layers "F.Cu" "B.Cu")
		(net "P12V_AUX")
	)
	(via
		(at 249.896122 -157.356302)
		(size 0.508)
		(drill 0.254)
		(layers "F.Cu" "B.Cu")
		(net "P12V_AUX")
	)
	(via
		(at 222.576644 -175.50638)
		(size 0.508)
		(drill 0.254)
		(layers "F.Cu" "B.Cu")
		(net "P12V_AUX")
	)
	(via
		(at 306.57673 -58.679334)
		(size 0.508)
		(drill 0.254)
		(layers "F.Cu" "B.Cu")
		(net "P12V_AUX")
	)
	(via
		(at 264.634218 -362.766102)
		(size 0.508)
		(drill 0.254)
		(layers "F.Cu" "B.Cu")
		(net "P12V_AUX")
	)
	(via
		(at 339.442552 -108.569506)
		(size 0.508)
		(drill 0.254)
		(layers "F.Cu" "B.Cu")
		(net "P12V_AUX")
	)
	(via
		(at 258.059174 -363.498638)
		(size 0.508)
		(drill 0.254)
		(layers "F.Cu" "B.Cu")
		(net "P12V_AUX")
	)
	(via
		(at 398.76857 -56.297068)
		(size 0.508)
		(drill 0.254)
		(layers "F.Cu" "B.Cu")
		(net "P12V_AUX")
	)
	(via
		(at 397.02867 -56.313832)
		(size 0.508)
		(drill 0.254)
		(layers "F.Cu" "B.Cu")
		(net "P12V_AUX")
	)
	(via
		(at 225.904552 -320.181732)
		(size 0.508)
		(drill 0.254)
		(layers "F.Cu" "B.Cu")
		(net "P12V_AUX")
	)
	(via
		(at 399.127726 -67.537838)
		(size 0.508)
		(drill 0.254)
		(layers "F.Cu" "B.Cu")
		(net "P12V_AUX")
	)
	(via
		(at 449.663566 -56.313832)
		(size 0.508)
		(drill 0.254)
		(layers "F.Cu" "B.Cu")
		(net "P12V_AUX")
	)
	(via
		(at 221.727776 -362.295186)
		(size 0.508)
		(drill 0.254)
		(layers "F.Cu" "B.Cu")
		(net "P12V_AUX")
	)
	(via
		(at 74.728578 -56.313832)
		(size 0.508)
		(drill 0.254)
		(layers "F.Cu" "B.Cu")
		(net "P12V_AUX")
	)
	(via
		(at 105.421938 -268.756638)
		(size 0.508)
		(drill 0.254)
		(layers "F.Cu" "B.Cu")
		(net "P12V_AUX")
	)
	(via
		(at 456.52563 -320.305176)
		(size 0.508)
		(drill 0.254)
		(layers "F.Cu" "B.Cu")
		(net "P12V_AUX")
	)
	(via
		(at 422.245028 -57.002934)
		(size 0.508)
		(drill 0.254)
		(layers "F.Cu" "B.Cu")
		(net "P12V_AUX")
	)
	(via
		(at 217.886788 -59.992006)
		(size 0.508)
		(drill 0.254)
		(layers "F.Cu" "B.Cu")
		(net "P12V_AUX")
	)
	(via
		(at 211.048854 -363.932216)
		(size 0.508)
		(drill 0.254)
		(layers "F.Cu" "B.Cu")
		(net "P12V_AUX")
	)
	(via
		(at 357.467154 -269.417038)
		(size 0.508)
		(drill 0.254)
		(layers "F.Cu" "B.Cu")
		(net "P12V_AUX")
	)
	(via
		(at 11.936222 -134.408926)
		(size 0.508)
		(drill 0.254)
		(layers "F.Cu" "B.Cu")
		(net "P12V_AUX")
	)
	(via
		(at 229.043738 -101.216968)
		(size 0.508)
		(drill 0.254)
		(layers "F.Cu" "B.Cu")
		(net "P12V_AUX")
	)
	(via
		(at 103.230934 -97.066354)
		(size 0.508)
		(drill 0.254)
		(layers "F.Cu" "B.Cu")
		(net "P12V_AUX")
	)
	(via
		(at 422.676828 -57.968134)
		(size 0.508)
		(drill 0.254)
		(layers "F.Cu" "B.Cu")
		(net "P12V_AUX")
	)
	(via
		(at 424.071796 -63.18631)
		(size 0.508)
		(drill 0.254)
		(layers "F.Cu" "B.Cu")
		(net "P12V_AUX")
	)
	(via
		(at 127.479298 -128.22555)
		(size 0.508)
		(drill 0.254)
		(layers "F.Cu" "B.Cu")
		(net "P12V_AUX")
	)
	(via
		(at 165.886892 -59.992006)
		(size 0.508)
		(drill 0.254)
		(layers "F.Cu" "B.Cu")
		(net "P12V_AUX")
	)
	(via
		(at 192.927732 -67.537838)
		(size 0.508)
		(drill 0.254)
		(layers "F.Cu" "B.Cu")
		(net "P12V_AUX")
	)
	(via
		(at 164.651944 -68.75653)
		(size 0.508)
		(drill 0.254)
		(layers "F.Cu" "B.Cu")
		(net "P12V_AUX")
	)
	(via
		(at 10.744454 -128.22555)
		(size 0.508)
		(drill 0.254)
		(layers "F.Cu" "B.Cu")
		(net "P12V_AUX")
	)
	(via
		(at 11.607292 -317.89497)
		(size 0.508)
		(drill 0.254)
		(layers "F.Cu" "B.Cu")
		(net "P12V_AUX")
	)
	(via
		(at 457.813156 -106.77525)
		(size 0.508)
		(drill 0.254)
		(layers "F.Cu" "B.Cu")
		(net "P12V_AUX")
	)
	(via
		(at 12.242292 -317.89497)
		(size 0.508)
		(drill 0.254)
		(layers "F.Cu" "B.Cu")
		(net "P12V_AUX")
	)
	(via
		(at 101.771704 -63.18631)
		(size 0.508)
		(drill 0.254)
		(layers "F.Cu" "B.Cu")
		(net "P12V_AUX")
	)
	(via
		(at 251.447046 -364.235238)
		(size 0.508)
		(drill 0.254)
		(layers "F.Cu" "B.Cu")
		(net "P12V_AUX")
	)
	(via
		(at 332.441804 -98.908108)
		(size 0.508)
		(drill 0.254)
		(layers "F.Cu" "B.Cu")
		(net "P12V_AUX")
	)
	(via
		(at 220.203776 -366.105186)
		(size 0.508)
		(drill 0.254)
		(layers "F.Cu" "B.Cu")
		(net "P12V_AUX")
	)
	(via
		(at 208.000854 -363.932216)
		(size 0.508)
		(drill 0.254)
		(layers "F.Cu" "B.Cu")
		(net "P12V_AUX")
	)
	(via
		(at 335.027524 -67.537838)
		(size 0.508)
		(drill 0.254)
		(layers "F.Cu" "B.Cu")
		(net "P12V_AUX")
	)
	(via
		(at 334.097884 -68.12153)
		(size 0.508)
		(drill 0.254)
		(layers "F.Cu" "B.Cu")
		(net "P12V_AUX")
	)
	(via
		(at 332.928468 -56.313832)
		(size 0.508)
		(drill 0.254)
		(layers "F.Cu" "B.Cu")
		(net "P12V_AUX")
	)
	(via
		(at 422.851834 -68.12153)
		(size 0.508)
		(drill 0.254)
		(layers "F.Cu" "B.Cu")
		(net "P12V_AUX")
	)
	(via
		(at 102.881938 -269.417038)
		(size 0.508)
		(drill 0.254)
		(layers "F.Cu" "B.Cu")
		(net "P12V_AUX")
	)
	(via
		(at 257.297174 -363.498638)
		(size 0.508)
		(drill 0.254)
		(layers "F.Cu" "B.Cu")
		(net "P12V_AUX")
	)
	(via
		(at 219.441776 -362.295186)
		(size 0.508)
		(drill 0.254)
		(layers "F.Cu" "B.Cu")
		(net "P12V_AUX")
	)
	(via
		(at 139.43076 -52.518818)
		(size 0.508)
		(drill 0.254)
		(layers "F.Cu" "B.Cu")
		(net "P12V_AUX")
	)
	(via
		(at 259.583174 -365.784638)
		(size 0.508)
		(drill 0.254)
		(layers "F.Cu" "B.Cu")
		(net "P12V_AUX")
	)
	(via
		(at 252.209046 -362.711238)
		(size 0.508)
		(drill 0.254)
		(layers "F.Cu" "B.Cu")
		(net "P12V_AUX")
	)
	(via
		(at 165.286944 -68.75653)
		(size 0.508)
		(drill 0.254)
		(layers "F.Cu" "B.Cu")
		(net "P12V_AUX")
	)
	(via
		(at 229.347776 -364.581186)
		(size 0.508)
		(drill 0.254)
		(layers "F.Cu" "B.Cu")
		(net "P12V_AUX")
	)
	(via
		(at 332.895448 -52.518818)
		(size 0.508)
		(drill 0.254)
		(layers "F.Cu" "B.Cu")
		(net "P12V_AUX")
	)
	(via
		(at 192.568576 -56.297068)
		(size 0.508)
		(drill 0.254)
		(layers "F.Cu" "B.Cu")
		(net "P12V_AUX")
	)
	(via
		(at 371.451886 -59.992006)
		(size 0.508)
		(drill 0.254)
		(layers "F.Cu" "B.Cu")
		(net "P12V_AUX")
	)
	(via
		(at 307.351684 -59.992006)
		(size 0.508)
		(drill 0.254)
		(layers "F.Cu" "B.Cu")
		(net "P12V_AUX")
	)
	(via
		(at 247.874282 -362.711238)
		(size 0.508)
		(drill 0.254)
		(layers "F.Cu" "B.Cu")
		(net "P12V_AUX")
	)
	(via
		(at 263.872218 -365.052102)
		(size 0.508)
		(drill 0.254)
		(layers "F.Cu" "B.Cu")
		(net "P12V_AUX")
	)
	(via
		(at 242.29441 -131.419854)
		(size 0.508)
		(drill 0.254)
		(layers "F.Cu" "B.Cu")
		(net "P12V_AUX")
	)
	(via
		(at 306.701698 -63.18631)
		(size 0.508)
		(drill 0.254)
		(layers "F.Cu" "B.Cu")
		(net "P12V_AUX")
	)
	(via
		(at 266.497816 -339.693758)
		(size 0.508)
		(drill 0.254)
		(layers "F.Cu" "B.Cu")
		(net "P12V_AUX")
	)
	(via
		(at 332.260448 -52.518818)
		(size 0.508)
		(drill 0.254)
		(layers "F.Cu" "B.Cu")
		(net "P12V_AUX")
	)
	(via
		(at 190.476886 -57.968134)
		(size 0.508)
		(drill 0.254)
		(layers "F.Cu" "B.Cu")
		(net "P12V_AUX")
	)
	(via
		(at 234.889802 -107.80903)
		(size 0.508)
		(drill 0.254)
		(layers "F.Cu" "B.Cu")
		(net "P12V_AUX")
	)
	(via
		(at 369.062 -157.418532)
		(size 0.508)
		(drill 0.254)
		(layers "F.Cu" "B.Cu")
		(net "P12V_AUX")
	)
	(via
		(at 306.2605 -52.518818)
		(size 0.508)
		(drill 0.254)
		(layers "F.Cu" "B.Cu")
		(net "P12V_AUX")
	)
	(via
		(at 217.917776 -362.295186)
		(size 0.508)
		(drill 0.254)
		(layers "F.Cu" "B.Cu")
		(net "P12V_AUX")
	)
	(via
		(at 230.871776 -363.819186)
		(size 0.508)
		(drill 0.254)
		(layers "F.Cu" "B.Cu")
		(net "P12V_AUX")
	)
	(via
		(at 99.944936 -57.002934)
		(size 0.508)
		(drill 0.254)
		(layers "F.Cu" "B.Cu")
		(net "P12V_AUX")
	)
	(via
		(at 265.396218 -365.814102)
		(size 0.508)
		(drill 0.254)
		(layers "F.Cu" "B.Cu")
		(net "P12V_AUX")
	)
	(via
		(at 396.67688 -57.968134)
		(size 0.508)
		(drill 0.254)
		(layers "F.Cu" "B.Cu")
		(net "P12V_AUX")
	)
	(via
		(at 226.054666 -103.058722)
		(size 0.508)
		(drill 0.254)
		(layers "F.Cu" "B.Cu")
		(net "P12V_AUX")
	)
	(via
		(at 232.395776 -362.295186)
		(size 0.508)
		(drill 0.254)
		(layers "F.Cu" "B.Cu")
		(net "P12V_AUX")
	)
	(via
		(at 370.676932 -57.968134)
		(size 0.508)
		(drill 0.254)
		(layers "F.Cu" "B.Cu")
		(net "P12V_AUX")
	)
	(via
		(at 360.544618 -156.936694)
		(size 0.4064)
		(drill 0.2032)
		(layers "F.Cu" "B.Cu")
		(net "P12V_AUX")
	)
	(via
		(at 133.796024 -157.356302)
		(size 0.508)
		(drill 0.254)
		(layers "F.Cu" "B.Cu")
		(net "P12V_AUX")
	)
	(via
		(at 451.127622 -67.537838)
		(size 0.508)
		(drill 0.254)
		(layers "F.Cu" "B.Cu")
		(net "P12V_AUX")
	)
	(via
		(at 191.88684 -59.992006)
		(size 0.508)
		(drill 0.254)
		(layers "F.Cu" "B.Cu")
		(net "P12V_AUX")
	)
	(via
		(at 281.530552 -52.518818)
		(size 0.508)
		(drill 0.254)
		(layers "F.Cu" "B.Cu")
		(net "P12V_AUX")
	)
	(via
		(at 191.998092 -68.12153)
		(size 0.508)
		(drill 0.254)
		(layers "F.Cu" "B.Cu")
		(net "P12V_AUX")
	)
	(via
		(at 453.820022 -116.62918)
		(size 0.508)
		(drill 0.254)
		(layers "F.Cu" "B.Cu")
		(net "P12V_AUX")
	)
	(via
		(at 139.886944 -59.992006)
		(size 0.508)
		(drill 0.254)
		(layers "F.Cu" "B.Cu")
		(net "P12V_AUX")
	)
	(via
		(at 190.476886 -58.679334)
		(size 0.508)
		(drill 0.254)
		(layers "F.Cu" "B.Cu")
		(net "P12V_AUX")
	)
	(via
		(at 338.90839 -98.188018)
		(size 0.508)
		(drill 0.254)
		(layers "F.Cu" "B.Cu")
		(net "P12V_AUX")
	)
	(via
		(at 237.42015 -365.694976)
		(size 0.508)
		(drill 0.254)
		(layers "F.Cu" "B.Cu")
		(net "P12V_AUX")
	)
	(via
		(at 129.244344 -157.647894)
		(size 0.4064)
		(drill 0.2032)
		(layers "F.Cu" "B.Cu")
		(net "P12V_AUX")
	)
	(via
		(at 130.14452 -156.936694)
		(size 0.4064)
		(drill 0.2032)
		(layers "F.Cu" "B.Cu")
		(net "P12V_AUX")
	)
	(via
		(at 103.230934 -97.701354)
		(size 0.508)
		(drill 0.254)
		(layers "F.Cu" "B.Cu")
		(net "P12V_AUX")
	)
	(via
		(at 99.55276 -97.489518)
		(size 0.508)
		(drill 0.254)
		(layers "F.Cu" "B.Cu")
		(net "P12V_AUX")
	)
	(via
		(at 233.057446 -117.08638)
		(size 0.4064)
		(drill 0.2032)
		(layers "F.Cu" "B.Cu")
		(net "P12V_AUX")
	)
	(via
		(at 455.544682 -111.135922)
		(size 0.4064)
		(drill 0.2032)
		(layers "F.Cu" "B.Cu")
		(net "P12V_AUX")
	)
	(via
		(at 217.28684 -68.75653)
		(size 0.508)
		(drill 0.254)
		(layers "F.Cu" "B.Cu")
		(net "P12V_AUX")
	)
	(via
		(at 24.827738 -67.537838)
		(size 0.508)
		(drill 0.254)
		(layers "F.Cu" "B.Cu")
		(net "P12V_AUX")
	)
	(via
		(at 127.4445 -156.936694)
		(size 0.4064)
		(drill 0.2032)
		(layers "F.Cu" "B.Cu")
		(net "P12V_AUX")
	)
	(via
		(at 22.376892 -57.968134)
		(size 0.508)
		(drill 0.254)
		(layers "F.Cu" "B.Cu")
		(net "P12V_AUX")
	)
	(via
		(at 165.998144 -68.75653)
		(size 0.508)
		(drill 0.254)
		(layers "F.Cu" "B.Cu")
		(net "P12V_AUX")
	)
	(via
		(at 332.751684 -68.12153)
		(size 0.508)
		(drill 0.254)
		(layers "F.Cu" "B.Cu")
		(net "P12V_AUX")
	)
	(via
		(at 227.019866 -102.626922)
		(size 0.508)
		(drill 0.254)
		(layers "F.Cu" "B.Cu")
		(net "P12V_AUX")
	)
	(via
		(at 251.447046 -364.997238)
		(size 0.508)
		(drill 0.254)
		(layers "F.Cu" "B.Cu")
		(net "P12V_AUX")
	)
	(via
		(at 424.768518 -56.297068)
		(size 0.508)
		(drill 0.254)
		(layers "F.Cu" "B.Cu")
		(net "P12V_AUX")
	)
	(via
		(at 364.010956 -157.645862)
		(size 0.508)
		(drill 0.254)
		(layers "F.Cu" "B.Cu")
		(net "P12V_AUX")
	)
	(via
		(at 208.762854 -362.560616)
		(size 0.508)
		(drill 0.254)
		(layers "F.Cu" "B.Cu")
		(net "P12V_AUX")
	)
	(via
		(at 258.821174 -363.498638)
		(size 0.508)
		(drill 0.254)
		(layers "F.Cu" "B.Cu")
		(net "P12V_AUX")
	)
	(via
		(at 217.28684 -68.12153)
		(size 0.508)
		(drill 0.254)
		(layers "F.Cu" "B.Cu")
		(net "P12V_AUX")
	)
	(via
		(at 261.586218 -363.528102)
		(size 0.508)
		(drill 0.254)
		(layers "F.Cu" "B.Cu")
		(net "P12V_AUX")
	)
	(via
		(at 241.765328 -348.400116)
		(size 0.508)
		(drill 0.254)
		(layers "F.Cu" "B.Cu")
		(net "P12V_AUX")
	)
	(via
		(at 233.768646 -116.186458)
		(size 0.4064)
		(drill 0.2032)
		(layers "F.Cu" "B.Cu")
		(net "P12V_AUX")
	)
	(via
		(at 281.563572 -56.313832)
		(size 0.508)
		(drill 0.254)
		(layers "F.Cu" "B.Cu")
		(net "P12V_AUX")
	)
	(via
		(at 210.286854 -364.618016)
		(size 0.508)
		(drill 0.254)
		(layers "F.Cu" "B.Cu")
		(net "P12V_AUX")
	)
	(via
		(at 241.23015 -365.694976)
		(size 0.508)
		(drill 0.254)
		(layers "F.Cu" "B.Cu")
		(net "P12V_AUX")
	)
	(via
		(at 333.386684 -68.12153)
		(size 0.508)
		(drill 0.254)
		(layers "F.Cu" "B.Cu")
		(net "P12V_AUX")
	)
	(via
		(at 244.064282 -364.997238)
		(size 0.508)
		(drill 0.254)
		(layers "F.Cu" "B.Cu")
		(net "P12V_AUX")
	)
	(via
		(at 133.796024 -156.645102)
		(size 0.508)
		(drill 0.254)
		(layers "F.Cu" "B.Cu")
		(net "P12V_AUX")
	)
	(via
		(at 306.14493 -57.002934)
		(size 0.508)
		(drill 0.254)
		(layers "F.Cu" "B.Cu")
		(net "P12V_AUX")
	)
	(via
		(at 242.15471 -320.181732)
		(size 0.508)
		(drill 0.254)
		(layers "F.Cu" "B.Cu")
		(net "P12V_AUX")
	)
	(via
		(at 261.586218 -364.290102)
		(size 0.508)
		(drill 0.254)
		(layers "F.Cu" "B.Cu")
		(net "P12V_AUX")
	)
	(via
		(at 252.971046 -365.759238)
		(size 0.508)
		(drill 0.254)
		(layers "F.Cu" "B.Cu")
		(net "P12V_AUX")
	)
	(via
		(at 246.350282 -365.759238)
		(size 0.508)
		(drill 0.254)
		(layers "F.Cu" "B.Cu")
		(net "P12V_AUX")
	)
	(via
		(at 457.885038 -103.658416)
		(size 0.508)
		(drill 0.254)
		(layers "F.Cu" "B.Cu")
		(net "P12V_AUX")
	)
	(via
		(at 217.917776 -363.057186)
		(size 0.508)
		(drill 0.254)
		(layers "F.Cu" "B.Cu")
		(net "P12V_AUX")
	)
	(via
		(at 309.027576 -67.537838)
		(size 0.508)
		(drill 0.254)
		(layers "F.Cu" "B.Cu")
		(net "P12V_AUX")
	)
	(via
		(at 205.740254 -364.618016)
		(size 0.508)
		(drill 0.254)
		(layers "F.Cu" "B.Cu")
		(net "P12V_AUX")
	)
	(via
		(at 449.436744 -63.18631)
		(size 0.508)
		(drill 0.254)
		(layers "F.Cu" "B.Cu")
		(net "P12V_AUX")
	)
	(via
		(at 126.536958 -268.756638)
		(size 0.508)
		(drill 0.254)
		(layers "F.Cu" "B.Cu")
		(net "P12V_AUX")
	)
	(via
		(at 370.851938 -68.75653)
		(size 0.508)
		(drill 0.254)
		(layers "F.Cu" "B.Cu")
		(net "P12V_AUX")
	)
	(via
		(at 126.536958 -269.417038)
		(size 0.508)
		(drill 0.254)
		(layers "F.Cu" "B.Cu")
		(net "P12V_AUX")
	)
	(via
		(at 102.881938 -268.756638)
		(size 0.508)
		(drill 0.254)
		(layers "F.Cu" "B.Cu")
		(net "P12V_AUX")
	)
	(via
		(at 359.804462 -133.443726)
		(size 0.508)
		(drill 0.254)
		(layers "F.Cu" "B.Cu")
		(net "P12V_AUX")
	)
	(via
		(at 365.19866 -158.753302)
		(size 0.508)
		(drill 0.254)
		(layers "F.Cu" "B.Cu")
		(net "P12V_AUX")
	)
	(via
		(at 164.160708 -52.518818)
		(size 0.508)
		(drill 0.254)
		(layers "F.Cu" "B.Cu")
		(net "P12V_AUX")
	)
	(via
		(at 424.198034 -68.12153)
		(size 0.508)
		(drill 0.254)
		(layers "F.Cu" "B.Cu")
		(net "P12V_AUX")
	)
	(via
		(at 448.244976 -57.002934)
		(size 0.508)
		(drill 0.254)
		(layers "F.Cu" "B.Cu")
		(net "P12V_AUX")
	)
	(via
		(at 100.728526 -56.313832)
		(size 0.508)
		(drill 0.254)
		(layers "F.Cu" "B.Cu")
		(net "P12V_AUX")
	)
	(via
		(at 219.441776 -364.581186)
		(size 0.508)
		(drill 0.254)
		(layers "F.Cu" "B.Cu")
		(net "P12V_AUX")
	)
	(via
		(at 164.476938 -58.679334)
		(size 0.508)
		(drill 0.254)
		(layers "F.Cu" "B.Cu")
		(net "P12V_AUX")
	)
	(via
		(at 190.795656 -52.518818)
		(size 0.508)
		(drill 0.254)
		(layers "F.Cu" "B.Cu")
		(net "P12V_AUX")
	)
	(via
		(at 225.269552 -320.181732)
		(size 0.508)
		(drill 0.254)
		(layers "F.Cu" "B.Cu")
		(net "P12V_AUX")
	)
	(via
		(at 252.971046 -362.711238)
		(size 0.508)
		(drill 0.254)
		(layers "F.Cu" "B.Cu")
		(net "P12V_AUX")
	)
	(via
		(at 365.99622 -157.356302)
		(size 0.508)
		(drill 0.254)
		(layers "F.Cu" "B.Cu")
		(net "P12V_AUX")
	)
	(via
		(at 259.583174 -363.498638)
		(size 0.508)
		(drill 0.254)
		(layers "F.Cu" "B.Cu")
		(net "P12V_AUX")
	)
	(via
		(at 7.651242 -155.212034)
		(size 0.508)
		(drill 0.254)
		(layers "F.Cu" "B.Cu")
		(net "P12V_AUX")
	)
	(via
		(at 282.097988 -68.12153)
		(size 0.508)
		(drill 0.254)
		(layers "F.Cu" "B.Cu")
		(net "P12V_AUX")
	)
	(via
		(at 138.47699 -58.679334)
		(size 0.508)
		(drill 0.254)
		(layers "F.Cu" "B.Cu")
		(net "P12V_AUX")
	)
	(via
		(at 240.46815 -364.932976)
		(size 0.508)
		(drill 0.254)
		(layers "F.Cu" "B.Cu")
		(net "P12V_AUX")
	)
	(via
		(at 109.03966 -180.949346)
		(size 0.508)
		(drill 0.254)
		(layers "F.Cu" "B.Cu")
		(net "P12V_AUX")
	)
	(via
		(at 264.634218 -365.814102)
		(size 0.508)
		(drill 0.254)
		(layers "F.Cu" "B.Cu")
		(net "P12V_AUX")
	)
	(via
		(at 251.447046 -363.473238)
		(size 0.508)
		(drill 0.254)
		(layers "F.Cu" "B.Cu")
		(net "P12V_AUX")
	)
	(via
		(at 12.242292 -318.52997)
		(size 0.508)
		(drill 0.254)
		(layers "F.Cu" "B.Cu")
		(net "P12V_AUX")
	)
	(via
		(at 340.155784 -111.135922)
		(size 0.4064)
		(drill 0.2032)
		(layers "F.Cu" "B.Cu")
		(net "P12V_AUX")
	)
	(via
		(at 229.347776 -365.343186)
		(size 0.508)
		(drill 0.254)
		(layers "F.Cu" "B.Cu")
		(net "P12V_AUX")
	)
	(via
		(at 167.562784 -67.537838)
		(size 0.508)
		(drill 0.254)
		(layers "F.Cu" "B.Cu")
		(net "P12V_AUX")
	)
	(via
		(at 344.87231 -259.020564)
		(size 0.508)
		(drill 0.254)
		(layers "F.Cu" "B.Cu")
		(net "P12V_AUX")
	)
	(via
		(at 230.109776 -362.295186)
		(size 0.508)
		(drill 0.254)
		(layers "F.Cu" "B.Cu")
		(net "P12V_AUX")
	)
	(via
		(at 49.898046 -68.75653)
		(size 0.508)
		(drill 0.254)
		(layers "F.Cu" "B.Cu")
		(net "P12V_AUX")
	)
	(via
		(at 245.588282 -365.759238)
		(size 0.508)
		(drill 0.254)
		(layers "F.Cu" "B.Cu")
		(net "P12V_AUX")
	)
	(via
		(at 22.551898 -68.75653)
		(size 0.508)
		(drill 0.254)
		(layers "F.Cu" "B.Cu")
		(net "P12V_AUX")
	)
	(via
		(at 230.871776 -366.105186)
		(size 0.508)
		(drill 0.254)
		(layers "F.Cu" "B.Cu")
		(net "P12V_AUX")
	)
	(via
		(at 255.336802 -63.18631)
		(size 0.508)
		(drill 0.254)
		(layers "F.Cu" "B.Cu")
		(net "P12V_AUX")
	)
	(via
		(at 234.178602 -107.80903)
		(size 0.508)
		(drill 0.254)
		(layers "F.Cu" "B.Cu")
		(net "P12V_AUX")
	)
	(via
		(at 246.244618 -157.647894)
		(size 0.4064)
		(drill 0.2032)
		(layers "F.Cu" "B.Cu")
		(net "P12V_AUX")
	)
	(via
		(at 396.851886 -68.75653)
		(size 0.508)
		(drill 0.254)
		(layers "F.Cu" "B.Cu")
		(net "P12V_AUX")
	)
	(via
		(at 232.395776 -363.057186)
		(size 0.508)
		(drill 0.254)
		(layers "F.Cu" "B.Cu")
		(net "P12V_AUX")
	)
	(via
		(at 49.771808 -63.18631)
		(size 0.508)
		(drill 0.254)
		(layers "F.Cu" "B.Cu")
		(net "P12V_AUX")
	)
	(via
		(at 229.347776 -363.057186)
		(size 0.508)
		(drill 0.254)
		(layers "F.Cu" "B.Cu")
		(net "P12V_AUX")
	)
	(via
		(at 450.197982 -68.12153)
		(size 0.508)
		(drill 0.254)
		(layers "F.Cu" "B.Cu")
		(net "P12V_AUX")
	)
	(via
		(at 74.376788 -57.968134)
		(size 0.508)
		(drill 0.254)
		(layers "F.Cu" "B.Cu")
		(net "P12V_AUX")
	)
	(via
		(at 234.10672 -110.925864)
		(size 0.508)
		(drill 0.254)
		(layers "F.Cu" "B.Cu")
		(net "P12V_AUX")
	)
	(via
		(at 132.998464 -158.753302)
		(size 0.508)
		(drill 0.254)
		(layers "F.Cu" "B.Cu")
		(net "P12V_AUX")
	)
	(via
		(at 456.52563 -320.940176)
		(size 0.508)
		(drill 0.254)
		(layers "F.Cu" "B.Cu")
		(net "P12V_AUX")
	)
	(via
		(at 257.02768 -67.537838)
		(size 0.508)
		(drill 0.254)
		(layers "F.Cu" "B.Cu")
		(net "P12V_AUX")
	)
	(via
		(at 361.44454 -156.936694)
		(size 0.4064)
		(drill 0.2032)
		(layers "F.Cu" "B.Cu")
		(net "P12V_AUX")
	)
	(via
		(at 22.50186 -63.18631)
		(size 0.508)
		(drill 0.254)
		(layers "F.Cu" "B.Cu")
		(net "P12V_AUX")
	)
	(via
		(at 255.773174 -364.260638)
		(size 0.508)
		(drill 0.254)
		(layers "F.Cu" "B.Cu")
		(net "P12V_AUX")
	)
	(via
		(at 76.827634 -67.537838)
		(size 0.508)
		(drill 0.254)
		(layers "F.Cu" "B.Cu")
		(net "P12V_AUX")
	)
	(via
		(at 104.151938 -269.417038)
		(size 0.508)
		(drill 0.254)
		(layers "F.Cu" "B.Cu")
		(net "P12V_AUX")
	)
	(via
		(at 307.56352 -56.313832)
		(size 0.508)
		(drill 0.254)
		(layers "F.Cu" "B.Cu")
		(net "P12V_AUX")
	)
	(via
		(at 342.49614 -103.658416)
		(size 0.508)
		(drill 0.254)
		(layers "F.Cu" "B.Cu")
		(net "P12V_AUX")
	)
	(via
		(at 370.393722 -56.313832)
		(size 0.508)
		(drill 0.254)
		(layers "F.Cu" "B.Cu")
		(net "P12V_AUX")
	)
	(via
		(at 254.75184 -68.12153)
		(size 0.508)
		(drill 0.254)
		(layers "F.Cu" "B.Cu")
		(net "P12V_AUX")
	)
	(via
		(at 365.99622 -155.933902)
		(size 0.508)
		(drill 0.254)
		(layers "F.Cu" "B.Cu")
		(net "P12V_AUX")
	)
	(via
		(at 256.535174 -362.736638)
		(size 0.508)
		(drill 0.254)
		(layers "F.Cu" "B.Cu")
		(net "P12V_AUX")
	)
	(via
		(at 358.409494 -128.22555)
		(size 0.508)
		(drill 0.254)
		(layers "F.Cu" "B.Cu")
		(net "P12V_AUX")
	)
	(via
		(at 340.155784 -110.235746)
		(size 0.4064)
		(drill 0.2032)
		(layers "F.Cu" "B.Cu")
		(net "P12V_AUX")
	)
	(via
		(at 105.519982 -116.62918)
		(size 0.508)
		(drill 0.254)
		(layers "F.Cu" "B.Cu")
		(net "P12V_AUX")
	)
	(via
		(at 261.586218 -365.814102)
		(size 0.508)
		(drill 0.254)
		(layers "F.Cu" "B.Cu")
		(net "P12V_AUX")
	)
	(via
		(at 48.09363 -56.313832)
		(size 0.508)
		(drill 0.254)
		(layers "F.Cu" "B.Cu")
		(net "P12V_AUX")
	)
	(via
		(at 17.69618 -157.356302)
		(size 0.508)
		(drill 0.254)
		(layers "F.Cu" "B.Cu")
		(net "P12V_AUX")
	)
	(via
		(at 424.198034 -68.75653)
		(size 0.508)
		(drill 0.254)
		(layers "F.Cu" "B.Cu")
		(net "P12V_AUX")
	)
	(via
		(at 254.260604 -52.518818)
		(size 0.508)
		(drill 0.254)
		(layers "F.Cu" "B.Cu")
		(net "P12V_AUX")
	)
	(via
		(at 191.463676 -56.313832)
		(size 0.508)
		(drill 0.254)
		(layers "F.Cu" "B.Cu")
		(net "P12V_AUX")
	)
	(via
		(at 447.8528 -98.124518)
		(size 0.508)
		(drill 0.254)
		(layers "F.Cu" "B.Cu")
		(net "P12V_AUX")
	)
	(via
		(at 249.923046 -363.473238)
		(size 0.508)
		(drill 0.254)
		(layers "F.Cu" "B.Cu")
		(net "P12V_AUX")
	)
	(via
		(at 261.586218 -365.052102)
		(size 0.508)
		(drill 0.254)
		(layers "F.Cu" "B.Cu")
		(net "P12V_AUX")
	)
	(via
		(at 23.595838 -167.223186)
		(size 0.508)
		(drill 0.254)
		(layers "F.Cu" "B.Cu")
		(net "P12V_AUX")
	)
	(via
		(at 335.430876 -98.336354)
		(size 0.508)
		(drill 0.254)
		(layers "F.Cu" "B.Cu")
		(net "P12V_AUX")
	)
	(via
		(at 339.444584 -110.235746)
		(size 0.4064)
		(drill 0.2032)
		(layers "F.Cu" "B.Cu")
		(net "P12V_AUX")
	)
	(via
		(at 281.351736 -59.992006)
		(size 0.508)
		(drill 0.254)
		(layers "F.Cu" "B.Cu")
		(net "P12V_AUX")
	)
	(via
		(at 335.082134 -269.417038)
		(size 0.508)
		(drill 0.254)
		(layers "F.Cu" "B.Cu")
		(net "P12V_AUX")
	)
	(via
		(at 208.762854 -363.932216)
		(size 0.508)
		(drill 0.254)
		(layers "F.Cu" "B.Cu")
		(net "P12V_AUX")
	)
	(via
		(at 190.193676 -56.313832)
		(size 0.508)
		(drill 0.254)
		(layers "F.Cu" "B.Cu")
		(net "P12V_AUX")
	)
	(via
		(at 371.4369 -63.18631)
		(size 0.508)
		(drill 0.254)
		(layers "F.Cu" "B.Cu")
		(net "P12V_AUX")
	)
	(via
		(at 238.18215 -362.646976)
		(size 0.508)
		(drill 0.254)
		(layers "F.Cu" "B.Cu")
		(net "P12V_AUX")
	)
	(via
		(at 106.425238 -97.08134)
		(size 0.508)
		(drill 0.254)
		(layers "F.Cu" "B.Cu")
		(net "P12V_AUX")
	)
	(via
		(at 20.76196 -157.418532)
		(size 0.508)
		(drill 0.254)
		(layers "F.Cu" "B.Cu")
		(net "P12V_AUX")
	)
	(via
		(at 255.530604 -52.518818)
		(size 0.508)
		(drill 0.254)
		(layers "F.Cu" "B.Cu")
		(net "P12V_AUX")
	)
	(via
		(at 332.751684 -68.75653)
		(size 0.508)
		(drill 0.254)
		(layers "F.Cu" "B.Cu")
		(net "P12V_AUX")
	)
	(via
		(at 107.24261 -108.569506)
		(size 0.508)
		(drill 0.254)
		(layers "F.Cu" "B.Cu")
		(net "P12V_AUX")
	)
	(via
		(at 371.028722 -56.313832)
		(size 0.508)
		(drill 0.254)
		(layers "F.Cu" "B.Cu")
		(net "P12V_AUX")
	)
	(via
		(at 166.568628 -56.297068)
		(size 0.508)
		(drill 0.254)
		(layers "F.Cu" "B.Cu")
		(net "P12V_AUX")
	)
	(via
		(at 242.944396 -128.22555)
		(size 0.508)
		(drill 0.254)
		(layers "F.Cu" "B.Cu")
		(net "P12V_AUX")
	)
	(via
		(at 337.719924 -116.62918)
		(size 0.508)
		(drill 0.254)
		(layers "F.Cu" "B.Cu")
		(net "P12V_AUX")
	)
	(via
		(at 370.816886 -59.992006)
		(size 0.508)
		(drill 0.254)
		(layers "F.Cu" "B.Cu")
		(net "P12V_AUX")
	)
	(via
		(at 129.244344 -156.936694)
		(size 0.4064)
		(drill 0.2032)
		(layers "F.Cu" "B.Cu")
		(net "P12V_AUX")
	)
	(via
		(at 359.044494 -128.22555)
		(size 0.508)
		(drill 0.254)
		(layers "F.Cu" "B.Cu")
		(net "P12V_AUX")
	)
	(via
		(at 333.971646 -63.18631)
		(size 0.508)
		(drill 0.254)
		(layers "F.Cu" "B.Cu")
		(net "P12V_AUX")
	)
	(via
		(at 256.535174 -365.784638)
		(size 0.508)
		(drill 0.254)
		(layers "F.Cu" "B.Cu")
		(net "P12V_AUX")
	)
	(via
		(at 164.795708 -52.518818)
		(size 0.508)
		(drill 0.254)
		(layers "F.Cu" "B.Cu")
		(net "P12V_AUX")
	)
	(via
		(at 126.617476 -135.098028)
		(size 0.508)
		(drill 0.254)
		(layers "F.Cu" "B.Cu")
		(net "P12V_AUX")
	)
	(via
		(at 359.679494 -128.22555)
		(size 0.508)
		(drill 0.254)
		(layers "F.Cu" "B.Cu")
		(net "P12V_AUX")
	)
	(via
		(at 238.18215 -364.932976)
		(size 0.508)
		(drill 0.254)
		(layers "F.Cu" "B.Cu")
		(net "P12V_AUX")
	)
	(via
		(at 359.452672 -135.098028)
		(size 0.508)
		(drill 0.254)
		(layers "F.Cu" "B.Cu")
		(net "P12V_AUX")
	)
	(via
		(at 104.786938 -269.417038)
		(size 0.508)
		(drill 0.254)
		(layers "F.Cu" "B.Cu")
		(net "P12V_AUX")
	)
	(via
		(at 189.210696 -410.898086)
		(size 0.508)
		(drill 0.254)
		(layers "F.Cu" "B.Cu")
		(net "P12V_AUX")
	)
	(via
		(at 48.37684 -57.968134)
		(size 0.508)
		(drill 0.254)
		(layers "F.Cu" "B.Cu")
		(net "P12V_AUX")
	)
	(via
		(at 306.57673 -57.968134)
		(size 0.508)
		(drill 0.254)
		(layers "F.Cu" "B.Cu")
		(net "P12V_AUX")
	)
	(via
		(at 262.348218 -365.052102)
		(size 0.508)
		(drill 0.254)
		(layers "F.Cu" "B.Cu")
		(net "P12V_AUX")
	)
	(via
		(at 20.76196 -155.996132)
		(size 0.508)
		(drill 0.254)
		(layers "F.Cu" "B.Cu")
		(net "P12V_AUX")
	)
	(via
		(at 359.644696 -157.647894)
		(size 0.4064)
		(drill 0.2032)
		(layers "F.Cu" "B.Cu")
		(net "P12V_AUX")
	)
	(via
		(at 339.444584 -111.135922)
		(size 0.4064)
		(drill 0.2032)
		(layers "F.Cu" "B.Cu")
		(net "P12V_AUX")
	)
	(via
		(at 335.662524 -67.537838)
		(size 0.508)
		(drill 0.254)
		(layers "F.Cu" "B.Cu")
		(net "P12V_AUX")
	)
	(via
		(at 101.207062 -98.476308)
		(size 0.508)
		(drill 0.254)
		(layers "F.Cu" "B.Cu")
		(net "P12V_AUX")
	)
	(via
		(at 216.65184 -68.12153)
		(size 0.508)
		(drill 0.254)
		(layers "F.Cu" "B.Cu")
		(net "P12V_AUX")
	)
	(via
		(at 100.551742 -68.75653)
		(size 0.508)
		(drill 0.254)
		(layers "F.Cu" "B.Cu")
		(net "P12V_AUX")
	)
	(via
		(at 372.768622 -56.297068)
		(size 0.508)
		(drill 0.254)
		(layers "F.Cu" "B.Cu")
		(net "P12V_AUX")
	)
	(via
		(at 422.816782 -59.992006)
		(size 0.508)
		(drill 0.254)
		(layers "F.Cu" "B.Cu")
		(net "P12V_AUX")
	)
	(via
		(at 257.297174 -362.736638)
		(size 0.508)
		(drill 0.254)
		(layers "F.Cu" "B.Cu")
		(net "P12V_AUX")
	)
	(via
		(at 336.352134 -268.756638)
		(size 0.508)
		(drill 0.254)
		(layers "F.Cu" "B.Cu")
		(net "P12V_AUX")
	)
	(via
		(at 365.99622 -156.645102)
		(size 0.508)
		(drill 0.254)
		(layers "F.Cu" "B.Cu")
		(net "P12V_AUX")
	)
	(via
		(at 24.468582 -56.297068)
		(size 0.508)
		(drill 0.254)
		(layers "F.Cu" "B.Cu")
		(net "P12V_AUX")
	)
	(via
		(at 250.685046 -365.759238)
		(size 0.508)
		(drill 0.254)
		(layers "F.Cu" "B.Cu")
		(net "P12V_AUX")
	)
	(via
		(at 104.461818 -211.250022)
		(size 0.508)
		(drill 0.254)
		(layers "F.Cu" "B.Cu")
		(net "P12V_AUX")
	)
	(via
		(at 282.097988 -68.75653)
		(size 0.508)
		(drill 0.254)
		(layers "F.Cu" "B.Cu")
		(net "P12V_AUX")
	)
	(via
		(at 75.363578 -56.313832)
		(size 0.508)
		(drill 0.254)
		(layers "F.Cu" "B.Cu")
		(net "P12V_AUX")
	)
	(via
		(at 308.097936 -68.12153)
		(size 0.508)
		(drill 0.254)
		(layers "F.Cu" "B.Cu")
		(net "P12V_AUX")
	)
	(via
		(at 11.344656 -157.647894)
		(size 0.4064)
		(drill 0.2032)
		(layers "F.Cu" "B.Cu")
		(net "P12V_AUX")
	)
	(via
		(at 280.144982 -57.002934)
		(size 0.508)
		(drill 0.254)
		(layers "F.Cu" "B.Cu")
		(net "P12V_AUX")
	)
	(via
		(at 233.055414 -112.72012)
		(size 0.508)
		(drill 0.254)
		(layers "F.Cu" "B.Cu")
		(net "P12V_AUX")
	)
	(via
		(at 165.871906 -63.18631)
		(size 0.508)
		(drill 0.254)
		(layers "F.Cu" "B.Cu")
		(net "P12V_AUX")
	)
	(via
		(at 220.965776 -363.057186)
		(size 0.508)
		(drill 0.254)
		(layers "F.Cu" "B.Cu")
		(net "P12V_AUX")
	)
	(via
		(at 308.66842 -56.297068)
		(size 0.508)
		(drill 0.254)
		(layers "F.Cu" "B.Cu")
		(net "P12V_AUX")
	)
	(via
		(at 397.486886 -68.75653)
		(size 0.508)
		(drill 0.254)
		(layers "F.Cu" "B.Cu")
		(net "P12V_AUX")
	)
	(via
		(at 208.784444 -365.45139)
		(size 0.508)
		(drill 0.254)
		(layers "F.Cu" "B.Cu")
		(net "P12V_AUX")
	)
	(via
		(at 371.486938 -68.12153)
		(size 0.508)
		(drill 0.254)
		(layers "F.Cu" "B.Cu")
		(net "P12V_AUX")
	)
	(via
		(at 138.79576 -52.518818)
		(size 0.508)
		(drill 0.254)
		(layers "F.Cu" "B.Cu")
		(net "P12V_AUX")
	)
	(via
		(at 245.588282 -364.235238)
		(size 0.508)
		(drill 0.254)
		(layers "F.Cu" "B.Cu")
		(net "P12V_AUX")
	)
	(via
		(at 101.330506 -52.518818)
		(size 0.508)
		(drill 0.254)
		(layers "F.Cu" "B.Cu")
		(net "P12V_AUX")
	)
	(via
		(at 220.965776 -362.295186)
		(size 0.508)
		(drill 0.254)
		(layers "F.Cu" "B.Cu")
		(net "P12V_AUX")
	)
	(via
		(at 22.516846 -59.992006)
		(size 0.508)
		(drill 0.254)
		(layers "F.Cu" "B.Cu")
		(net "P12V_AUX")
	)
	(via
		(at 221.727776 -366.105186)
		(size 0.508)
		(drill 0.254)
		(layers "F.Cu" "B.Cu")
		(net "P12V_AUX")
	)
	(via
		(at 100.060506 -52.518818)
		(size 0.508)
		(drill 0.254)
		(layers "F.Cu" "B.Cu")
		(net "P12V_AUX")
	)
	(via
		(at 370.8019 -63.18631)
		(size 0.508)
		(drill 0.254)
		(layers "F.Cu" "B.Cu")
		(net "P12V_AUX")
	)
	(via
		(at 457.16063 -320.305176)
		(size 0.508)
		(drill 0.254)
		(layers "F.Cu" "B.Cu")
		(net "P12V_AUX")
	)
	(via
		(at 101.186742 -68.75653)
		(size 0.508)
		(drill 0.254)
		(layers "F.Cu" "B.Cu")
		(net "P12V_AUX")
	)
	(via
		(at 191.430656 -52.518818)
		(size 0.508)
		(drill 0.254)
		(layers "F.Cu" "B.Cu")
		(net "P12V_AUX")
	)
	(via
		(at 104.461818 -210.615022)
		(size 0.508)
		(drill 0.254)
		(layers "F.Cu" "B.Cu")
		(net "P12V_AUX")
	)
	(via
		(at 333.336646 -63.18631)
		(size 0.508)
		(drill 0.254)
		(layers "F.Cu" "B.Cu")
		(net "P12V_AUX")
	)
	(via
		(at 190.160656 -52.518818)
		(size 0.508)
		(drill 0.254)
		(layers "F.Cu" "B.Cu")
		(net "P12V_AUX")
	)
	(via
		(at 22.060662 -52.518818)
		(size 0.508)
		(drill 0.254)
		(layers "F.Cu" "B.Cu")
		(net "P12V_AUX")
	)
	(via
		(at 220.965776 -366.105186)
		(size 0.508)
		(drill 0.254)
		(layers "F.Cu" "B.Cu")
		(net "P12V_AUX")
	)
	(via
		(at 247.874282 -364.997238)
		(size 0.508)
		(drill 0.254)
		(layers "F.Cu" "B.Cu")
		(net "P12V_AUX")
	)
	(via
		(at 104.151938 -268.756638)
		(size 0.508)
		(drill 0.254)
		(layers "F.Cu" "B.Cu")
		(net "P12V_AUX")
	)
	(via
		(at 49.136808 -63.18631)
		(size 0.508)
		(drill 0.254)
		(layers "F.Cu" "B.Cu")
		(net "P12V_AUX")
	)
	(via
		(at 258.821174 -365.784638)
		(size 0.508)
		(drill 0.254)
		(layers "F.Cu" "B.Cu")
		(net "P12V_AUX")
	)
	(via
		(at 48.516794 -59.992006)
		(size 0.508)
		(drill 0.254)
		(layers "F.Cu" "B.Cu")
		(net "P12V_AUX")
	)
	(via
		(at 110.94466 -180.288946)
		(size 0.508)
		(drill 0.254)
		(layers "F.Cu" "B.Cu")
		(net "P12V_AUX")
	)
	(via
		(at 125.901958 -268.756638)
		(size 0.508)
		(drill 0.254)
		(layers "F.Cu" "B.Cu")
		(net "P12V_AUX")
	)
	(via
		(at 208.762854 -364.618016)
		(size 0.508)
		(drill 0.254)
		(layers "F.Cu" "B.Cu")
		(net "P12V_AUX")
	)
	(via
		(at 228.585776 -363.819186)
		(size 0.508)
		(drill 0.254)
		(layers "F.Cu" "B.Cu")
		(net "P12V_AUX")
	)
	(via
		(at 24.377142 -166.53764)
		(size 0.508)
		(drill 0.254)
		(layers "F.Cu" "B.Cu")
		(net "P12V_AUX")
	)
	(via
		(at 218.679776 -362.295186)
		(size 0.508)
		(drill 0.254)
		(layers "F.Cu" "B.Cu")
		(net "P12V_AUX")
	)
	(via
		(at 74.695558 -52.518818)
		(size 0.508)
		(drill 0.254)
		(layers "F.Cu" "B.Cu")
		(net "P12V_AUX")
	)
	(via
		(at 22.728682 -56.313832)
		(size 0.508)
		(drill 0.254)
		(layers "F.Cu" "B.Cu")
		(net "P12V_AUX")
	)
	(via
		(at 219.441776 -363.057186)
		(size 0.508)
		(drill 0.254)
		(layers "F.Cu" "B.Cu")
		(net "P12V_AUX")
	)
	(via
		(at 307.336698 -63.18631)
		(size 0.508)
		(drill 0.254)
		(layers "F.Cu" "B.Cu")
		(net "P12V_AUX")
	)
	(via
		(at 128.036066 -134.408926)
		(size 0.508)
		(drill 0.254)
		(layers "F.Cu" "B.Cu")
		(net "P12V_AUX")
	)
	(via
		(at 422.676828 -58.679334)
		(size 0.508)
		(drill 0.254)
		(layers "F.Cu" "B.Cu")
		(net "P12V_AUX")
	)
	(via
		(at 252.209046 -365.759238)
		(size 0.508)
		(drill 0.254)
		(layers "F.Cu" "B.Cu")
		(net "P12V_AUX")
	)
	(via
		(at 109.67466 -180.288946)
		(size 0.508)
		(drill 0.254)
		(layers "F.Cu" "B.Cu")
		(net "P12V_AUX")
	)
	(via
		(at 101.15169 -59.992006)
		(size 0.508)
		(drill 0.254)
		(layers "F.Cu" "B.Cu")
		(net "P12V_AUX")
	)
	(via
		(at 108.358178 -180.27904)
		(size 0.508)
		(drill 0.254)
		(layers "F.Cu" "B.Cu")
		(net "P12V_AUX")
	)
	(via
		(at 74.060558 -52.518818)
		(size 0.508)
		(drill 0.254)
		(layers "F.Cu" "B.Cu")
		(net "P12V_AUX")
	)
	(via
		(at 246.350282 -363.473238)
		(size 0.508)
		(drill 0.254)
		(layers "F.Cu" "B.Cu")
		(net "P12V_AUX")
	)
	(via
		(at 232.238042 -102.501954)
		(size 0.508)
		(drill 0.254)
		(layers "F.Cu" "B.Cu")
		(net "P12V_AUX")
	)
	(via
		(at 242.717574 -135.098028)
		(size 0.508)
		(drill 0.254)
		(layers "F.Cu" "B.Cu")
		(net "P12V_AUX")
	)
	(via
		(at 265.396218 -365.052102)
		(size 0.508)
		(drill 0.254)
		(layers "F.Cu" "B.Cu")
		(net "P12V_AUX")
	)
	(via
		(at 245.588282 -363.473238)
		(size 0.508)
		(drill 0.254)
		(layers "F.Cu" "B.Cu")
		(net "P12V_AUX")
	)
	(via
		(at 191.871854 -63.18631)
		(size 0.508)
		(drill 0.254)
		(layers "F.Cu" "B.Cu")
		(net "P12V_AUX")
	)
	(via
		(at 337.539584 -98.188018)
		(size 0.508)
		(drill 0.254)
		(layers "F.Cu" "B.Cu")
		(net "P12V_AUX")
	)
	(via
		(at 128.344422 -156.936694)
		(size 0.4064)
		(drill 0.2032)
		(layers "F.Cu" "B.Cu")
		(net "P12V_AUX")
	)
	(via
		(at 455.54265 -107.934506)
		(size 0.508)
		(drill 0.254)
		(layers "F.Cu" "B.Cu")
		(net "P12V_AUX")
	)
	(via
		(at 231.633776 -364.581186)
		(size 0.508)
		(drill 0.254)
		(layers "F.Cu" "B.Cu")
		(net "P12V_AUX")
	)
	(via
		(at 341.78494 -103.658416)
		(size 0.508)
		(drill 0.254)
		(layers "F.Cu" "B.Cu")
		(net "P12V_AUX")
	)
	(via
		(at 114.450114 -255.210564)
		(size 0.508)
		(drill 0.254)
		(layers "F.Cu" "B.Cu")
		(net "P12V_AUX")
	)
	(via
		(at 370.360702 -52.518818)
		(size 0.508)
		(drill 0.254)
		(layers "F.Cu" "B.Cu")
		(net "P12V_AUX")
	)
	(via
		(at 309.662576 -67.537838)
		(size 0.508)
		(drill 0.254)
		(layers "F.Cu" "B.Cu")
		(net "P12V_AUX")
	)
	(via
		(at 355.951282 -155.212034)
		(size 0.508)
		(drill 0.254)
		(layers "F.Cu" "B.Cu")
		(net "P12V_AUX")
	)
	(via
		(at 264.634218 -364.290102)
		(size 0.508)
		(drill 0.254)
		(layers "F.Cu" "B.Cu")
		(net "P12V_AUX")
	)
	(via
		(at 230.109776 -366.105186)
		(size 0.508)
		(drill 0.254)
		(layers "F.Cu" "B.Cu")
		(net "P12V_AUX")
	)
	(via
		(at 217.917776 -365.343186)
		(size 0.508)
		(drill 0.254)
		(layers "F.Cu" "B.Cu")
		(net "P12V_AUX")
	)
	(via
		(at 262.348218 -364.290102)
		(size 0.508)
		(drill 0.254)
		(layers "F.Cu" "B.Cu")
		(net "P12V_AUX")
	)
	(via
		(at 265.396218 -362.766102)
		(size 0.508)
		(drill 0.254)
		(layers "F.Cu" "B.Cu")
		(net "P12V_AUX")
	)
	(via
		(at 75.330558 -52.518818)
		(size 0.508)
		(drill 0.254)
		(layers "F.Cu" "B.Cu")
		(net "P12V_AUX")
	)
	(via
		(at 235.601002 -107.80903)
		(size 0.508)
		(drill 0.254)
		(layers "F.Cu" "B.Cu")
		(net "P12V_AUX")
	)
	(via
		(at 75.186794 -68.12153)
		(size 0.508)
		(drill 0.254)
		(layers "F.Cu" "B.Cu")
		(net "P12V_AUX")
	)
	(via
		(at 255.351788 -59.992006)
		(size 0.508)
		(drill 0.254)
		(layers "F.Cu" "B.Cu")
		(net "P12V_AUX")
	)
	(via
		(at 359.804462 -132.732526)
		(size 0.508)
		(drill 0.254)
		(layers "F.Cu" "B.Cu")
		(net "P12V_AUX")
	)
	(via
		(at 358.394508 -131.419854)
		(size 0.508)
		(drill 0.254)
		(layers "F.Cu" "B.Cu")
		(net "P12V_AUX")
	)
	(via
		(at 258.821174 -362.736638)
		(size 0.508)
		(drill 0.254)
		(layers "F.Cu" "B.Cu")
		(net "P12V_AUX")
	)
	(via
		(at 190.045086 -57.002934)
		(size 0.508)
		(drill 0.254)
		(layers "F.Cu" "B.Cu")
		(net "P12V_AUX")
	)
	(via
		(at 237.42015 -364.170976)
		(size 0.508)
		(drill 0.254)
		(layers "F.Cu" "B.Cu")
		(net "P12V_AUX")
	)
	(via
		(at 231.633776 -363.057186)
		(size 0.508)
		(drill 0.254)
		(layers "F.Cu" "B.Cu")
		(net "P12V_AUX")
	)
	(via
		(at 127.171958 -268.756638)
		(size 0.508)
		(drill 0.254)
		(layers "F.Cu" "B.Cu")
		(net "P12V_AUX")
	)
	(via
		(at 244.136164 -134.408926)
		(size 0.508)
		(drill 0.254)
		(layers "F.Cu" "B.Cu")
		(net "P12V_AUX")
	)
	(via
		(at 241.23015 -364.932976)
		(size 0.508)
		(drill 0.254)
		(layers "F.Cu" "B.Cu")
		(net "P12V_AUX")
	)
	(via
		(at 165.998144 -68.12153)
		(size 0.508)
		(drill 0.254)
		(layers "F.Cu" "B.Cu")
		(net "P12V_AUX")
	)
	(via
		(at 244.826282 -364.997238)
		(size 0.508)
		(drill 0.254)
		(layers "F.Cu" "B.Cu")
		(net "P12V_AUX")
	)
	(via
		(at 241.23015 -363.408976)
		(size 0.508)
		(drill 0.254)
		(layers "F.Cu" "B.Cu")
		(net "P12V_AUX")
	)
	(via
		(at 244.064282 -364.235238)
		(size 0.508)
		(drill 0.254)
		(layers "F.Cu" "B.Cu")
		(net "P12V_AUX")
	)
	(via
		(at 23.330662 -52.518818)
		(size 0.508)
		(drill 0.254)
		(layers "F.Cu" "B.Cu")
		(net "P12V_AUX")
	)
	(via
		(at 216.045034 -57.002934)
		(size 0.508)
		(drill 0.254)
		(layers "F.Cu" "B.Cu")
		(net "P12V_AUX")
	)
	(via
		(at 164.476938 -57.968134)
		(size 0.508)
		(drill 0.254)
		(layers "F.Cu" "B.Cu")
		(net "P12V_AUX")
	)
	(via
		(at 243.352574 -135.098028)
		(size 0.508)
		(drill 0.254)
		(layers "F.Cu" "B.Cu")
		(net "P12V_AUX")
	)
	(via
		(at 50.46853 -56.297068)
		(size 0.508)
		(drill 0.254)
		(layers "F.Cu" "B.Cu")
		(net "P12V_AUX")
	)
	(via
		(at 449.028566 -56.313832)
		(size 0.508)
		(drill 0.254)
		(layers "F.Cu" "B.Cu")
		(net "P12V_AUX")
	)
	(via
		(at 226.539552 -320.181732)
		(size 0.508)
		(drill 0.254)
		(layers "F.Cu" "B.Cu")
		(net "P12V_AUX")
	)
	(via
		(at 190.828676 -56.313832)
		(size 0.508)
		(drill 0.254)
		(layers "F.Cu" "B.Cu")
		(net "P12V_AUX")
	)
	(via
		(at 423.451782 -59.992006)
		(size 0.508)
		(drill 0.254)
		(layers "F.Cu" "B.Cu")
		(net "P12V_AUX")
	)
	(via
		(at 255.355852 -357.425244)
		(size 0.508)
		(drill 0.254)
		(layers "F.Cu" "B.Cu")
		(net "P12V_AUX")
	)
	(via
		(at 237.42015 -364.932976)
		(size 0.508)
		(drill 0.254)
		(layers "F.Cu" "B.Cu")
		(net "P12V_AUX")
	)
	(via
		(at 357.467154 -268.756638)
		(size 0.508)
		(drill 0.254)
		(layers "F.Cu" "B.Cu")
		(net "P12V_AUX")
	)
	(via
		(at 456.255882 -112.935766)
		(size 0.4064)
		(drill 0.2032)
		(layers "F.Cu" "B.Cu")
		(net "P12V_AUX")
	)
	(via
		(at 101.897942 -68.75653)
		(size 0.508)
		(drill 0.254)
		(layers "F.Cu" "B.Cu")
		(net "P12V_AUX")
	)
	(via
		(at 10.094468 -131.419854)
		(size 0.508)
		(drill 0.254)
		(layers "F.Cu" "B.Cu")
		(net "P12V_AUX")
	)
	(via
		(at 256.668524 -56.297068)
		(size 0.508)
		(drill 0.254)
		(layers "F.Cu" "B.Cu")
		(net "P12V_AUX")
	)
	(via
		(at 125.266958 -269.417038)
		(size 0.508)
		(drill 0.254)
		(layers "F.Cu" "B.Cu")
		(net "P12V_AUX")
	)
	(via
		(at 241.23015 -364.170976)
		(size 0.508)
		(drill 0.254)
		(layers "F.Cu" "B.Cu")
		(net "P12V_AUX")
	)
	(via
		(at 75.897994 -68.12153)
		(size 0.508)
		(drill 0.254)
		(layers "F.Cu" "B.Cu")
		(net "P12V_AUX")
	)
	(via
		(at 252.971046 -364.235238)
		(size 0.508)
		(drill 0.254)
		(layers "F.Cu" "B.Cu")
		(net "P12V_AUX")
	)
	(via
		(at 332.576678 -58.679334)
		(size 0.508)
		(drill 0.254)
		(layers "F.Cu" "B.Cu")
		(net "P12V_AUX")
	)
	(via
		(at 246.350282 -364.997238)
		(size 0.508)
		(drill 0.254)
		(layers "F.Cu" "B.Cu")
		(net "P12V_AUX")
	)
	(via
		(at 359.372154 -269.417038)
		(size 0.508)
		(drill 0.254)
		(layers "F.Cu" "B.Cu")
		(net "P12V_AUX")
	)
	(via
		(at 102.827582 -67.537838)
		(size 0.508)
		(drill 0.254)
		(layers "F.Cu" "B.Cu")
		(net "P12V_AUX")
	)
	(via
		(at 103.516938 -268.756638)
		(size 0.508)
		(drill 0.254)
		(layers "F.Cu" "B.Cu")
		(net "P12V_AUX")
	)
	(via
		(at 205.754986 -363.925612)
		(size 0.508)
		(drill 0.254)
		(layers "F.Cu" "B.Cu")
		(net "P12V_AUX")
	)
	(via
		(at 252.961902 -156.707332)
		(size 0.508)
		(drill 0.254)
		(layers "F.Cu" "B.Cu")
		(net "P12V_AUX")
	)
	(via
		(at 166.927784 -67.537838)
		(size 0.508)
		(drill 0.254)
		(layers "F.Cu" "B.Cu")
		(net "P12V_AUX")
	)
	(via
		(at 256.067052 -357.425244)
		(size 0.508)
		(drill 0.254)
		(layers "F.Cu" "B.Cu")
		(net "P12V_AUX")
	)
	(via
		(at 397.436848 -63.18631)
		(size 0.508)
		(drill 0.254)
		(layers "F.Cu" "B.Cu")
		(net "P12V_AUX")
	)
	(via
		(at 138.47699 -57.968134)
		(size 0.508)
		(drill 0.254)
		(layers "F.Cu" "B.Cu")
		(net "P12V_AUX")
	)
	(via
		(at 371.630702 -52.518818)
		(size 0.508)
		(drill 0.254)
		(layers "F.Cu" "B.Cu")
		(net "P12V_AUX")
	)
	(via
		(at 247.112282 -365.759238)
		(size 0.508)
		(drill 0.254)
		(layers "F.Cu" "B.Cu")
		(net "P12V_AUX")
	)
	(via
		(at 245.344442 -156.936694)
		(size 0.4064)
		(drill 0.2032)
		(layers "F.Cu" "B.Cu")
		(net "P12V_AUX")
	)
	(via
		(at 245.588282 -362.711238)
		(size 0.508)
		(drill 0.254)
		(layers "F.Cu" "B.Cu")
		(net "P12V_AUX")
	)
	(via
		(at 50.827686 -67.537838)
		(size 0.508)
		(drill 0.254)
		(layers "F.Cu" "B.Cu")
		(net "P12V_AUX")
	)
	(via
		(at 247.910858 -156.934662)
		(size 0.508)
		(drill 0.254)
		(layers "F.Cu" "B.Cu")
		(net "P12V_AUX")
	)
	(via
		(at 243.579396 -128.22555)
		(size 0.508)
		(drill 0.254)
		(layers "F.Cu" "B.Cu")
		(net "P12V_AUX")
	)
	(via
		(at 197.62343 -411.32633)
		(size 0.508)
		(drill 0.254)
		(layers "F.Cu" "B.Cu")
		(net "P12V_AUX")
	)
	(via
		(at 281.986736 -59.992006)
		(size 0.508)
		(drill 0.254)
		(layers "F.Cu" "B.Cu")
		(net "P12V_AUX")
	)
	(via
		(at 240.46815 -364.170976)
		(size 0.508)
		(drill 0.254)
		(layers "F.Cu" "B.Cu")
		(net "P12V_AUX")
	)
	(via
		(at 251.447046 -362.711238)
		(size 0.508)
		(drill 0.254)
		(layers "F.Cu" "B.Cu")
		(net "P12V_AUX")
	)
	(via
		(at 253.733046 -364.235238)
		(size 0.508)
		(drill 0.254)
		(layers "F.Cu" "B.Cu")
		(net "P12V_AUX")
	)
	(via
		(at 332.144878 -57.002934)
		(size 0.508)
		(drill 0.254)
		(layers "F.Cu" "B.Cu")
		(net "P12V_AUX")
	)
	(via
		(at 242.78971 -320.816732)
		(size 0.508)
		(drill 0.254)
		(layers "F.Cu" "B.Cu")
		(net "P12V_AUX")
	)
	(via
		(at 220.203776 -363.057186)
		(size 0.508)
		(drill 0.254)
		(layers "F.Cu" "B.Cu")
		(net "P12V_AUX")
	)
	(via
		(at 191.286892 -68.75653)
		(size 0.508)
		(drill 0.254)
		(layers "F.Cu" "B.Cu")
		(net "P12V_AUX")
	)
	(via
		(at 255.355852 -359.558844)
		(size 0.508)
		(drill 0.254)
		(layers "F.Cu" "B.Cu")
		(net "P12V_AUX")
	)
	(via
		(at 364.010956 -156.934662)
		(size 0.508)
		(drill 0.254)
		(layers "F.Cu" "B.Cu")
		(net "P12V_AUX")
	)
	(via
		(at 11.607292 -318.52997)
		(size 0.508)
		(drill 0.254)
		(layers "F.Cu" "B.Cu")
		(net "P12V_AUX")
	)
	(via
		(at 372.198138 -68.75653)
		(size 0.508)
		(drill 0.254)
		(layers "F.Cu" "B.Cu")
		(net "P12V_AUX")
	)
	(via
		(at 254.716788 -59.992006)
		(size 0.508)
		(drill 0.254)
		(layers "F.Cu" "B.Cu")
		(net "P12V_AUX")
	)
	(via
		(at 448.851782 -68.75653)
		(size 0.508)
		(drill 0.254)
		(layers "F.Cu" "B.Cu")
		(net "P12V_AUX")
	)
	(via
		(at 450.768466 -56.297068)
		(size 0.508)
		(drill 0.254)
		(layers "F.Cu" "B.Cu")
		(net "P12V_AUX")
	)
	(via
		(at 255.971802 -63.18631)
		(size 0.508)
		(drill 0.254)
		(layers "F.Cu" "B.Cu")
		(net "P12V_AUX")
	)
	(via
		(at 191.286892 -68.12153)
		(size 0.508)
		(drill 0.254)
		(layers "F.Cu" "B.Cu")
		(net "P12V_AUX")
	)
	(via
		(at 242.309396 -128.22555)
		(size 0.508)
		(drill 0.254)
		(layers "F.Cu" "B.Cu")
		(net "P12V_AUX")
	)
	(via
		(at 210.286854 -363.246416)
		(size 0.508)
		(drill 0.254)
		(layers "F.Cu" "B.Cu")
		(net "P12V_AUX")
	)
	(via
		(at 339.444584 -112.035844)
		(size 0.4064)
		(drill 0.2032)
		(layers "F.Cu" "B.Cu")
		(net "P12V_AUX")
	)
	(via
		(at 238.94415 -362.646976)
		(size 0.508)
		(drill 0.254)
		(layers "F.Cu" "B.Cu")
		(net "P12V_AUX")
	)
	(via
		(at 100.551742 -68.12153)
		(size 0.508)
		(drill 0.254)
		(layers "F.Cu" "B.Cu")
		(net "P12V_AUX")
	)
	(via
		(at 396.39367 -56.313832)
		(size 0.508)
		(drill 0.254)
		(layers "F.Cu" "B.Cu")
		(net "P12V_AUX")
	)
	(via
		(at 219.441776 -366.105186)
		(size 0.508)
		(drill 0.254)
		(layers "F.Cu" "B.Cu")
		(net "P12V_AUX")
	)
	(via
		(at 264.634218 -365.052102)
		(size 0.508)
		(drill 0.254)
		(layers "F.Cu" "B.Cu")
		(net "P12V_AUX")
	)
	(via
		(at 99.55276 -98.124518)
		(size 0.508)
		(drill 0.254)
		(layers "F.Cu" "B.Cu")
		(net "P12V_AUX")
	)
	(via
		(at 230.109776 -363.819186)
		(size 0.508)
		(drill 0.254)
		(layers "F.Cu" "B.Cu")
		(net "P12V_AUX")
	)
	(via
		(at 217.430604 -52.518818)
		(size 0.508)
		(drill 0.254)
		(layers "F.Cu" "B.Cu")
		(net "P12V_AUX")
	)
	(via
		(at 239.70615 -362.646976)
		(size 0.508)
		(drill 0.254)
		(layers "F.Cu" "B.Cu")
		(net "P12V_AUX")
	)
	(via
		(at 447.8528 -98.759518)
		(size 0.508)
		(drill 0.254)
		(layers "F.Cu" "B.Cu")
		(net "P12V_AUX")
	)
	(via
		(at 332.576678 -57.968134)
		(size 0.508)
		(drill 0.254)
		(layers "F.Cu" "B.Cu")
		(net "P12V_AUX")
	)
	(via
		(at 249.896122 -156.645102)
		(size 0.508)
		(drill 0.254)
		(layers "F.Cu" "B.Cu")
		(net "P12V_AUX")
	)
	(via
		(at 231.332786 -120.779794)
		(size 0.508)
		(drill 0.254)
		(layers "F.Cu" "B.Cu")
		(net "P12V_AUX")
	)
	(via
		(at 74.516742 -59.992006)
		(size 0.508)
		(drill 0.254)
		(layers "F.Cu" "B.Cu")
		(net "P12V_AUX")
	)
	(via
		(at 193.562732 -67.537838)
		(size 0.508)
		(drill 0.254)
		(layers "F.Cu" "B.Cu")
		(net "P12V_AUX")
	)
	(via
		(at 449.486782 -68.12153)
		(size 0.508)
		(drill 0.254)
		(layers "F.Cu" "B.Cu")
		(net "P12V_AUX")
	)
	(via
		(at 333.530448 -52.518818)
		(size 0.508)
		(drill 0.254)
		(layers "F.Cu" "B.Cu")
		(net "P12V_AUX")
	)
	(via
		(at 101.136704 -63.18631)
		(size 0.508)
		(drill 0.254)
		(layers "F.Cu" "B.Cu")
		(net "P12V_AUX")
	)
	(via
		(at 226.539552 -320.816732)
		(size 0.508)
		(drill 0.254)
		(layers "F.Cu" "B.Cu")
		(net "P12V_AUX")
	)
	(via
		(at 249.896122 -155.933902)
		(size 0.508)
		(drill 0.254)
		(layers "F.Cu" "B.Cu")
		(net "P12V_AUX")
	)
	(via
		(at 252.961902 -155.996132)
		(size 0.508)
		(drill 0.254)
		(layers "F.Cu" "B.Cu")
		(net "P12V_AUX")
	)
	(via
		(at 455.89063 -320.940176)
		(size 0.508)
		(drill 0.254)
		(layers "F.Cu" "B.Cu")
		(net "P12V_AUX")
	)
	(via
		(at 208.000854 -364.618016)
		(size 0.508)
		(drill 0.254)
		(layers "F.Cu" "B.Cu")
		(net "P12V_AUX")
	)
	(via
		(at 448.393566 -56.313832)
		(size 0.508)
		(drill 0.254)
		(layers "F.Cu" "B.Cu")
		(net "P12V_AUX")
	)
	(via
		(at 17.69618 -156.645102)
		(size 0.508)
		(drill 0.254)
		(layers "F.Cu" "B.Cu")
		(net "P12V_AUX")
	)
	(via
		(at 105.421938 -269.417038)
		(size 0.508)
		(drill 0.254)
		(layers "F.Cu" "B.Cu")
		(net "P12V_AUX")
	)
	(via
		(at 280.928572 -56.313832)
		(size 0.508)
		(drill 0.254)
		(layers "F.Cu" "B.Cu")
		(net "P12V_AUX")
	)
	(via
		(at 245.344442 -157.647894)
		(size 0.4064)
		(drill 0.2032)
		(layers "F.Cu" "B.Cu")
		(net "P12V_AUX")
	)
	(via
		(at 398.198086 -68.12153)
		(size 0.508)
		(drill 0.254)
		(layers "F.Cu" "B.Cu")
		(net "P12V_AUX")
	)
	(via
		(at 255.986788 -59.992006)
		(size 0.508)
		(drill 0.254)
		(layers "F.Cu" "B.Cu")
		(net "P12V_AUX")
	)
	(via
		(at 257.297174 -365.784638)
		(size 0.508)
		(drill 0.254)
		(layers "F.Cu" "B.Cu")
		(net "P12V_AUX")
	)
	(via
		(at 111.57966 -180.949346)
		(size 0.508)
		(drill 0.254)
		(layers "F.Cu" "B.Cu")
		(net "P12V_AUX")
	)
	(via
		(at 229.347776 -366.105186)
		(size 0.508)
		(drill 0.254)
		(layers "F.Cu" "B.Cu")
		(net "P12V_AUX")
	)
	(via
		(at 126.194312 -131.419854)
		(size 0.508)
		(drill 0.254)
		(layers "F.Cu" "B.Cu")
		(net "P12V_AUX")
	)
	(segment
		(start 249.493786 -346.70111)
		(end 250.272296 -345.9226)
		(width 0.4572)
		(layer "B.Cu")
		(net "P12V_AUX")
	)
	(segment
		(start 241.770154 -348.39529)
		(end 247.283732 -348.39529)
		(width 0.4572)
		(layer "B.Cu")
		(net "P12V_AUX")
	)
	(segment
		(start 344.87231 -258.404614)
		(end 344.87231 -259.020564)
		(width 0.381)
		(layer "B.Cu")
		(net "P12V_AUX")
	)
	(segment
		(start 250.272296 -345.9226)
		(end 250.272296 -345.917774)
		(width 0.4572)
		(layer "B.Cu")
		(net "P12V_AUX")
	)
	(segment
		(start 346.65031 -255.826514)
		(end 346.65031 -255.210564)
		(width 0.381)
		(layer "B.Cu")
		(net "P12V_AUX")
	)
	(segment
		(start 247.283732 -348.39529)
		(end 248.977912 -346.70111)
		(width 0.4572)
		(layer "B.Cu")
		(net "P12V_AUX")
	)
	(segment
		(start 114.450114 -255.826514)
		(end 114.450114 -255.210564)
		(width 0.381)
		(layer "B.Cu")
		(net "P12V_AUX")
	)
	(segment
		(start 241.765328 -348.400116)
		(end 241.770154 -348.39529)
		(width 0.4572)
		(layer "B.Cu")
		(net "P12V_AUX")
	)
	(segment
		(start 248.977912 -346.70111)
		(end 249.493786 -346.70111)
		(width 0.4572)
		(layer "B.Cu")
		(net "P12V_AUX")
	)
	(segment
		(start 112.672114 -258.404614)
		(end 112.672114 -259.020564)
		(width 0.381)
		(layer "B.Cu")
		(net "P12V_AUX")
	)
	(segment
		(start 181.408832 -356.831646)
		(end 181.728872 -356.511606)
		(width 0.13462)
		(layer "F.Cu")
		(net "P5E_PEX1_STN7_TX_C_DP<122>")
	)
	(segment
		(start 181.703472 -357.75773)
		(end 181.408832 -357.46309)
		(width 0.13462)
		(layer "F.Cu")
		(net "P5E_PEX1_STN7_TX_C_DP<122>")
	)
	(segment
		(start 181.408832 -357.46309)
		(end 181.408832 -356.831646)
		(width 0.13462)
		(layer "F.Cu")
		(net "P5E_PEX1_STN7_TX_C_DP<122>")
	)
	(segment
		(start 181.412642 -358.04856)
		(end 181.703472 -357.75773)
		(width 0.1651)
		(layer "In11.Cu")
		(net "P5E_PEX1_STN7_TX_C_DP<122>")
	)
	(segment
		(start 164.31006 -375.308114)
		(end 164.43706 -375.181114)
		(width 0.1651)
		(layer "In11.Cu")
		(net "P5E_PEX1_STN7_TX_C_DP<122>")
	)
	(segment
		(start 165.467538 -374.488964)
		(end 165.467538 -368.740182)
		(width 0.1651)
		(layer "In11.Cu")
		(net "P5E_PEX1_STN7_TX_C_DP<122>")
	)
	(segment
		(start 165.467538 -368.740182)
		(end 166.65575 -367.55197)
		(width 0.1651)
		(layer "In11.Cu")
		(net "P5E_PEX1_STN7_TX_C_DP<122>")
	)
	(segment
		(start 166.65575 -367.55197)
		(end 177.588672 -362.962444)
		(width 0.1651)
		(layer "In11.Cu")
		(net "P5E_PEX1_STN7_TX_C_DP<122>")
	)
	(segment
		(start 164.43706 -375.181114)
		(end 164.775388 -375.181114)
		(width 0.1651)
		(layer "In11.Cu")
		(net "P5E_PEX1_STN7_TX_C_DP<122>")
	)
	(segment
		(start 164.31006 -375.69013)
		(end 164.31006 -375.308114)
		(width 0.1651)
		(layer "In11.Cu")
		(net "P5E_PEX1_STN7_TX_C_DP<122>")
	)
	(segment
		(start 164.775388 -375.181114)
		(end 165.467538 -374.488964)
		(width 0.1651)
		(layer "In11.Cu")
		(net "P5E_PEX1_STN7_TX_C_DP<122>")
	)
	(segment
		(start 177.61839 -362.962444)
		(end 181.412642 -359.168192)
		(width 0.1651)
		(layer "In11.Cu")
		(net "P5E_PEX1_STN7_TX_C_DP<122>")
	)
	(segment
		(start 181.412642 -359.168192)
		(end 181.412642 -358.04856)
		(width 0.1651)
		(layer "In11.Cu")
		(net "P5E_PEX1_STN7_TX_C_DP<122>")
	)
	(segment
		(start 177.588672 -362.962444)
		(end 177.61839 -362.962444)
		(width 0.1651)
		(layer "In11.Cu")
		(net "P5E_PEX1_STN7_TX_C_DP<122>")
	)
	(segment
		(start 154.162252 -125.199902)
		(end 153.867612 -125.494542)
		(width 0.13462)
		(layer "F.Cu")
		(net "P5E_PEX1_STN1_TX_DP<27>")
	)
	(segment
		(start 155.113736 -125.519942)
		(end 154.793696 -125.199902)
		(width 0.13462)
		(layer "F.Cu")
		(net "P5E_PEX1_STN1_TX_DP<27>")
	)
	(segment
		(start 154.793696 -125.199902)
		(end 154.162252 -125.199902)
		(width 0.13462)
		(layer "F.Cu")
		(net "P5E_PEX1_STN1_TX_DP<27>")
	)
	(segment
		(start 150.557738 -128.575562)
		(end 150.434548 -128.599946)
		(width 0.1651)
		(layer "In9.Cu")
		(net "P5E_PEX1_STN1_TX_DP<27>")
	)
	(segment
		(start 185.923936 -280.129488)
		(end 186.085734 -280.129488)
		(width 0.1143)
		(layer "In9.Cu")
		(net "P5E_PEX1_STN1_TX_DP<27>")
	)
	(segment
		(start 185.866024 -263.596628)
		(end 185.866024 -266.61745)
		(width 0.1651)
		(layer "In9.Cu")
		(net "P5E_PEX1_STN1_TX_DP<27>")
	)
	(segment
		(start 186.200034 -280.015188)
		(end 186.200034 -279.749504)
		(width 0.1143)
		(layer "In9.Cu")
		(net "P5E_PEX1_STN1_TX_DP<27>")
	)
	(segment
		(start 185.820304 -280.025856)
		(end 185.923936 -280.129488)
		(width 0.1143)
		(layer "In9.Cu")
		(net "P5E_PEX1_STN1_TX_DP<27>")
	)
	(segment
		(start 149.079712 -130.627628)
		(end 148.80463 -131.039362)
		(width 0.1651)
		(layer "In9.Cu")
		(net "P5E_PEX1_STN1_TX_DP<27>")
	)
	(segment
		(start 185.866024 -267.83665)
		(end 186.005724 -267.97635)
		(width 0.1651)
		(layer "In9.Cu")
		(net "P5E_PEX1_STN1_TX_DP<27>")
	)
	(segment
		(start 151.38019 -127.184912)
		(end 151.404574 -127.308356)
		(width 0.1651)
		(layer "In9.Cu")
		(net "P5E_PEX1_STN1_TX_DP<27>")
	)
	(segment
		(start 150.190962 -129.170176)
		(end 149.915626 -129.582164)
		(width 0.1651)
		(layer "In9.Cu")
		(net "P5E_PEX1_STN1_TX_DP<27>")
	)
	(segment
		(start 149.513544 -130.184144)
		(end 149.238208 -130.596132)
		(width 0.1651)
		(layer "In9.Cu")
		(net "P5E_PEX1_STN1_TX_DP<27>")
	)
	(segment
		(start 151.164544 -127.667512)
		(end 151.0411 -127.69215)
		(width 0.1651)
		(layer "In9.Cu")
		(net "P5E_PEX1_STN1_TX_DP<27>")
	)
	(segment
		(start 148.836126 -131.197858)
		(end 148.56079 -131.609846)
		(width 0.1651)
		(layer "In9.Cu")
		(net "P5E_PEX1_STN1_TX_DP<27>")
	)
	(segment
		(start 185.820304 -271.600168)
		(end 185.820304 -280.025856)
		(width 0.1143)
		(layer "In9.Cu")
		(net "P5E_PEX1_STN1_TX_DP<27>")
	)
	(segment
		(start 148.80463 -131.039362)
		(end 148.836126 -131.197858)
		(width 0.1651)
		(layer "In9.Cu")
		(net "P5E_PEX1_STN1_TX_DP<27>")
	)
	(segment
		(start 149.915626 -129.582164)
		(end 149.75713 -129.613914)
		(width 0.1651)
		(layer "In9.Cu")
		(net "P5E_PEX1_STN1_TX_DP<27>")
	)
	(segment
		(start 186.005724 -266.75715)
		(end 186.005724 -267.20165)
		(width 0.1651)
		(layer "In9.Cu")
		(net "P5E_PEX1_STN1_TX_DP<27>")
	)
	(segment
		(start 149.238208 -130.596132)
		(end 149.079712 -130.627628)
		(width 0.1651)
		(layer "In9.Cu")
		(net "P5E_PEX1_STN1_TX_DP<27>")
	)
	(segment
		(start 149.807676 -142.991078)
		(end 150.16226 -150.200614)
		(width 0.1651)
		(layer "In9.Cu")
		(net "P5E_PEX1_STN1_TX_DP<27>")
	)
	(segment
		(start 150.159466 -129.01168)
		(end 150.190962 -129.170176)
		(width 0.1651)
		(layer "In9.Cu")
		(net "P5E_PEX1_STN1_TX_DP<27>")
	)
	(segment
		(start 151.0411 -127.69215)
		(end 150.773384 -128.092962)
		(width 0.1651)
		(layer "In9.Cu")
		(net "P5E_PEX1_STN1_TX_DP<27>")
	)
	(segment
		(start 147.23237 -134.125716)
		(end 147.23237 -136.774428)
		(width 0.1651)
		(layer "In9.Cu")
		(net "P5E_PEX1_STN1_TX_DP<27>")
	)
	(segment
		(start 151.390858 -161.75228)
		(end 185.866024 -263.596628)
		(width 0.1651)
		(layer "In9.Cu")
		(net "P5E_PEX1_STN1_TX_DP<27>")
	)
	(segment
		(start 150.513542 -157.341062)
		(end 151.390858 -161.75228)
		(width 0.1651)
		(layer "In9.Cu")
		(net "P5E_PEX1_STN1_TX_DP<27>")
	)
	(segment
		(start 185.866024 -267.34135)
		(end 185.866024 -267.83665)
		(width 0.1651)
		(layer "In9.Cu")
		(net "P5E_PEX1_STN1_TX_DP<27>")
	)
	(segment
		(start 185.866024 -271.554448)
		(end 185.820304 -271.600168)
		(width 0.1143)
		(layer "In9.Cu")
		(net "P5E_PEX1_STN1_TX_DP<27>")
	)
	(segment
		(start 150.773384 -128.092962)
		(end 150.798022 -128.216152)
		(width 0.1651)
		(layer "In9.Cu")
		(net "P5E_PEX1_STN1_TX_DP<27>")
	)
	(segment
		(start 153.867612 -125.494542)
		(end 153.576782 -125.203712)
		(width 0.1651)
		(layer "In9.Cu")
		(net "P5E_PEX1_STN1_TX_DP<27>")
	)
	(segment
		(start 151.404574 -127.308356)
		(end 151.164544 -127.667512)
		(width 0.1651)
		(layer "In9.Cu")
		(net "P5E_PEX1_STN1_TX_DP<27>")
	)
	(segment
		(start 148.402294 -131.641342)
		(end 148.031454 -132.196332)
		(width 0.1651)
		(layer "In9.Cu")
		(net "P5E_PEX1_STN1_TX_DP<27>")
	)
	(segment
		(start 153.009346 -125.203712)
		(end 152.08885 -126.124208)
		(width 0.1651)
		(layer "In9.Cu")
		(net "P5E_PEX1_STN1_TX_DP<27>")
	)
	(segment
		(start 150.16226 -150.200614)
		(end 150.513542 -157.341062)
		(width 0.1651)
		(layer "In9.Cu")
		(net "P5E_PEX1_STN1_TX_DP<27>")
	)
	(segment
		(start 150.434548 -128.599946)
		(end 150.159466 -129.01168)
		(width 0.1651)
		(layer "In9.Cu")
		(net "P5E_PEX1_STN1_TX_DP<27>")
	)
	(segment
		(start 148.031454 -132.196332)
		(end 147.23237 -134.125716)
		(width 0.1651)
		(layer "In9.Cu")
		(net "P5E_PEX1_STN1_TX_DP<27>")
	)
	(segment
		(start 148.56079 -131.609846)
		(end 148.402294 -131.641342)
		(width 0.1651)
		(layer "In9.Cu")
		(net "P5E_PEX1_STN1_TX_DP<27>")
	)
	(segment
		(start 186.005724 -269.64005)
		(end 185.866024 -269.77975)
		(width 0.1651)
		(layer "In9.Cu")
		(net "P5E_PEX1_STN1_TX_DP<27>")
	)
	(segment
		(start 149.75713 -129.613914)
		(end 149.482048 -130.025648)
		(width 0.1651)
		(layer "In9.Cu")
		(net "P5E_PEX1_STN1_TX_DP<27>")
	)
	(segment
		(start 150.798022 -128.216152)
		(end 150.557738 -128.575562)
		(width 0.1651)
		(layer "In9.Cu")
		(net "P5E_PEX1_STN1_TX_DP<27>")
	)
	(segment
		(start 186.005724 -269.19555)
		(end 186.005724 -269.64005)
		(width 0.1651)
		(layer "In9.Cu")
		(net "P5E_PEX1_STN1_TX_DP<27>")
	)
	(segment
		(start 152.08885 -126.124208)
		(end 151.38019 -127.184912)
		(width 0.1651)
		(layer "In9.Cu")
		(net "P5E_PEX1_STN1_TX_DP<27>")
	)
	(segment
		(start 186.085734 -280.129488)
		(end 186.200034 -280.015188)
		(width 0.1143)
		(layer "In9.Cu")
		(net "P5E_PEX1_STN1_TX_DP<27>")
	)
	(segment
		(start 185.866024 -266.61745)
		(end 186.005724 -266.75715)
		(width 0.1651)
		(layer "In9.Cu")
		(net "P5E_PEX1_STN1_TX_DP<27>")
	)
	(segment
		(start 186.005724 -267.97635)
		(end 186.005724 -268.42085)
		(width 0.1651)
		(layer "In9.Cu")
		(net "P5E_PEX1_STN1_TX_DP<27>")
	)
	(segment
		(start 186.005724 -268.42085)
		(end 185.866024 -268.56055)
		(width 0.1651)
		(layer "In9.Cu")
		(net "P5E_PEX1_STN1_TX_DP<27>")
	)
	(segment
		(start 185.866024 -269.77975)
		(end 185.866024 -271.526)
		(width 0.1651)
		(layer "In9.Cu")
		(net "P5E_PEX1_STN1_TX_DP<27>")
	)
	(segment
		(start 186.005724 -267.20165)
		(end 185.866024 -267.34135)
		(width 0.1651)
		(layer "In9.Cu")
		(net "P5E_PEX1_STN1_TX_DP<27>")
	)
	(segment
		(start 153.576782 -125.203712)
		(end 153.009346 -125.203712)
		(width 0.1651)
		(layer "In9.Cu")
		(net "P5E_PEX1_STN1_TX_DP<27>")
	)
	(segment
		(start 149.482048 -130.025648)
		(end 149.513544 -130.184144)
		(width 0.1651)
		(layer "In9.Cu")
		(net "P5E_PEX1_STN1_TX_DP<27>")
	)
	(segment
		(start 185.866024 -271.526)
		(end 185.866024 -271.554448)
		(width 0.1143)
		(layer "In9.Cu")
		(net "P5E_PEX1_STN1_TX_DP<27>")
	)
	(segment
		(start 185.866024 -268.56055)
		(end 185.866024 -269.05585)
		(width 0.1651)
		(layer "In9.Cu")
		(net "P5E_PEX1_STN1_TX_DP<27>")
	)
	(segment
		(start 147.23237 -136.774428)
		(end 149.807676 -142.991078)
		(width 0.1651)
		(layer "In9.Cu")
		(net "P5E_PEX1_STN1_TX_DP<27>")
	)
	(segment
		(start 185.866024 -269.05585)
		(end 186.005724 -269.19555)
		(width 0.1651)
		(layer "In9.Cu")
		(net "P5E_PEX1_STN1_TX_DP<27>")
	)
	(segment
		(start 121.757948 -343.365582)
		(end 121.757948 -342.734138)
		(width 0.13462)
		(layer "F.Cu")
		(net "P5E_PEX1_STN6_TX_DN<99>")
	)
	(segment
		(start 121.757948 -342.734138)
		(end 122.052588 -342.439498)
		(width 0.13462)
		(layer "F.Cu")
		(net "P5E_PEX1_STN6_TX_DN<99>")
	)
	(segment
		(start 122.077988 -343.685622)
		(end 121.757948 -343.365582)
		(width 0.13462)
		(layer "F.Cu")
		(net "P5E_PEX1_STN6_TX_DN<99>")
	)
	(segment
		(start 169.112946 -322.776088)
		(end 170.10126 -321.787774)
		(width 0.1651)
		(layer "In7.Cu")
		(net "P5E_PEX1_STN6_TX_DN<99>")
	)
	(segment
		(start 170.665902 -319.988438)
		(end 170.620182 -319.942718)
		(width 0.1143)
		(layer "In7.Cu")
		(net "P5E_PEX1_STN6_TX_DN<99>")
	)
	(segment
		(start 122.052588 -342.439498)
		(end 121.761758 -342.148668)
		(width 0.1651)
		(layer "In7.Cu")
		(net "P5E_PEX1_STN6_TX_DN<99>")
	)
	(segment
		(start 170.665902 -320.016886)
		(end 170.665902 -319.988438)
		(width 0.1143)
		(layer "In7.Cu")
		(net "P5E_PEX1_STN6_TX_DN<99>")
	)
	(segment
		(start 170.665902 -320.424556)
		(end 170.665902 -320.016886)
		(width 0.1651)
		(layer "In7.Cu")
		(net "P5E_PEX1_STN6_TX_DN<99>")
	)
	(segment
		(start 167.159178 -323.947282)
		(end 169.112946 -322.776088)
		(width 0.1651)
		(layer "In7.Cu")
		(net "P5E_PEX1_STN6_TX_DN<99>")
	)
	(segment
		(start 170.620182 -311.784492)
		(end 170.734482 -311.670192)
		(width 0.1143)
		(layer "In7.Cu")
		(net "P5E_PEX1_STN6_TX_DN<99>")
	)
	(segment
		(start 170.999912 -311.784492)
		(end 170.999912 -312.049922)
		(width 0.1143)
		(layer "In7.Cu")
		(net "P5E_PEX1_STN6_TX_DN<99>")
	)
	(segment
		(start 121.761758 -342.148668)
		(end 121.761758 -341.044022)
		(width 0.1651)
		(layer "In7.Cu")
		(net "P5E_PEX1_STN6_TX_DN<99>")
	)
	(segment
		(start 170.885612 -311.670192)
		(end 170.999912 -311.784492)
		(width 0.1143)
		(layer "In7.Cu")
		(net "P5E_PEX1_STN6_TX_DN<99>")
	)
	(segment
		(start 170.734482 -311.670192)
		(end 170.885612 -311.670192)
		(width 0.1143)
		(layer "In7.Cu")
		(net "P5E_PEX1_STN6_TX_DN<99>")
	)
	(segment
		(start 121.761758 -341.044022)
		(end 121.953528 -340.852252)
		(width 0.1651)
		(layer "In7.Cu")
		(net "P5E_PEX1_STN6_TX_DN<99>")
	)
	(segment
		(start 170.620182 -319.942718)
		(end 170.620182 -311.784492)
		(width 0.1143)
		(layer "In7.Cu")
		(net "P5E_PEX1_STN6_TX_DN<99>")
	)
	(segment
		(start 121.953528 -340.852252)
		(end 132.738622 -334.388206)
		(width 0.1651)
		(layer "In7.Cu")
		(net "P5E_PEX1_STN6_TX_DN<99>")
	)
	(segment
		(start 170.10126 -321.787774)
		(end 170.665902 -320.424556)
		(width 0.1651)
		(layer "In7.Cu")
		(net "P5E_PEX1_STN6_TX_DN<99>")
	)
	(segment
		(start 132.738622 -334.388206)
		(end 167.159178 -323.947282)
		(width 0.1651)
		(layer "In7.Cu")
		(net "P5E_PEX1_STN6_TX_DN<99>")
	)
	(segment
		(start 315.453776 -151.92248)
		(end 315.128148 -151.596852)
		(width 0.13462)
		(layer "F.Cu")
		(net "P5E_PEX2_STN0_TX_DN<13>")
	)
	(segment
		(start 316.374272 -151.622252)
		(end 316.074044 -151.92248)
		(width 0.13462)
		(layer "F.Cu")
		(net "P5E_PEX2_STN0_TX_DN<13>")
	)
	(segment
		(start 316.074044 -151.92248)
		(end 315.453776 -151.92248)
		(width 0.13462)
		(layer "F.Cu")
		(net "P5E_PEX2_STN0_TX_DN<13>")
	)
	(segment
		(start 308.6735 -278.229568)
		(end 308.570122 -278.12619)
		(width 0.1143)
		(layer "In9.Cu")
		(net "P5E_PEX2_STN0_TX_DN<13>")
	)
	(segment
		(start 308.615842 -271.500346)
		(end 308.615842 -271.471898)
		(width 0.1143)
		(layer "In9.Cu")
		(net "P5E_PEX2_STN0_TX_DN<13>")
	)
	(segment
		(start 308.949598 -278.115268)
		(end 308.835298 -278.229568)
		(width 0.1143)
		(layer "In9.Cu")
		(net "P5E_PEX2_STN0_TX_DN<13>")
	)
	(segment
		(start 316.665102 -151.913082)
		(end 316.374272 -151.622252)
		(width 0.1651)
		(layer "In9.Cu")
		(net "P5E_PEX2_STN0_TX_DN<13>")
	)
	(segment
		(start 309.52567 -260.750558)
		(end 306.080668 -221.36227)
		(width 0.1651)
		(layer "In9.Cu")
		(net "P5E_PEX2_STN0_TX_DN<13>")
	)
	(segment
		(start 317.905384 -152.370028)
		(end 317.448438 -151.913082)
		(width 0.1651)
		(layer "In9.Cu")
		(net "P5E_PEX2_STN0_TX_DN<13>")
	)
	(segment
		(start 317.448438 -151.913082)
		(end 316.665102 -151.913082)
		(width 0.1651)
		(layer "In9.Cu")
		(net "P5E_PEX2_STN0_TX_DN<13>")
	)
	(segment
		(start 306.080668 -221.36227)
		(end 309.962296 -177.001678)
		(width 0.1651)
		(layer "In9.Cu")
		(net "P5E_PEX2_STN0_TX_DN<13>")
	)
	(segment
		(start 308.570122 -271.546066)
		(end 308.615842 -271.500346)
		(width 0.1143)
		(layer "In9.Cu")
		(net "P5E_PEX2_STN0_TX_DN<13>")
	)
	(segment
		(start 308.835298 -278.229568)
		(end 308.6735 -278.229568)
		(width 0.1143)
		(layer "In9.Cu")
		(net "P5E_PEX2_STN0_TX_DN<13>")
	)
	(segment
		(start 308.615842 -270.044164)
		(end 309.52567 -267.847064)
		(width 0.1651)
		(layer "In9.Cu")
		(net "P5E_PEX2_STN0_TX_DN<13>")
	)
	(segment
		(start 319.790826 -155.576524)
		(end 319.371726 -154.564334)
		(width 0.1651)
		(layer "In9.Cu")
		(net "P5E_PEX2_STN0_TX_DN<13>")
	)
	(segment
		(start 308.570122 -278.12619)
		(end 308.570122 -271.546066)
		(width 0.1143)
		(layer "In9.Cu")
		(net "P5E_PEX2_STN0_TX_DN<13>")
	)
	(segment
		(start 309.962296 -177.001678)
		(end 311.401206 -171.632118)
		(width 0.1651)
		(layer "In9.Cu")
		(net "P5E_PEX2_STN0_TX_DN<13>")
	)
	(segment
		(start 319.371726 -154.564334)
		(end 317.905384 -152.370028)
		(width 0.1651)
		(layer "In9.Cu")
		(net "P5E_PEX2_STN0_TX_DN<13>")
	)
	(segment
		(start 309.52567 -267.847064)
		(end 309.52567 -260.750558)
		(width 0.1651)
		(layer "In9.Cu")
		(net "P5E_PEX2_STN0_TX_DN<13>")
	)
	(segment
		(start 308.949598 -277.849838)
		(end 308.949598 -278.115268)
		(width 0.1143)
		(layer "In9.Cu")
		(net "P5E_PEX2_STN0_TX_DN<13>")
	)
	(segment
		(start 308.615842 -271.471898)
		(end 308.615842 -270.044164)
		(width 0.1651)
		(layer "In9.Cu")
		(net "P5E_PEX2_STN0_TX_DN<13>")
	)
	(segment
		(start 319.790826 -157.099254)
		(end 319.790826 -155.576524)
		(width 0.1651)
		(layer "In9.Cu")
		(net "P5E_PEX2_STN0_TX_DN<13>")
	)
	(segment
		(start 311.401206 -171.632118)
		(end 319.790826 -157.099254)
		(width 0.1651)
		(layer "In9.Cu")
		(net "P5E_PEX2_STN0_TX_DN<13>")
	)
	(segment
		(start 304.199798 -316.534292)
		(end 304.199798 -316.799722)
		(width 0.1143)
		(layer "In5.Cu")
		(net "P5E_PEX2_STN5_RX_DN<94>")
	)
	(segment
		(start 345.23426 -339.88502)
		(end 308.01691 -322.747386)
		(width 0.1651)
		(layer "In5.Cu")
		(net "P5E_PEX2_STN5_RX_DN<94>")
	)
	(segment
		(start 303.865788 -320.373502)
		(end 303.865788 -319.969896)
		(width 0.1651)
		(layer "In5.Cu")
		(net "P5E_PEX2_STN5_RX_DN<94>")
	)
	(segment
		(start 345.364054 -371.281198)
		(end 345.81592 -370.829332)
		(width 0.1651)
		(layer "In5.Cu")
		(net "P5E_PEX2_STN5_RX_DN<94>")
	)
	(segment
		(start 344.689938 -371.408198)
		(end 344.816938 -371.281198)
		(width 0.1651)
		(layer "In5.Cu")
		(net "P5E_PEX2_STN5_RX_DN<94>")
	)
	(segment
		(start 304.723546 -321.231006)
		(end 304.458116 -320.96583)
		(width 0.1651)
		(layer "In5.Cu")
		(net "P5E_PEX2_STN5_RX_DN<94>")
	)
	(segment
		(start 307.382164 -322.455032)
		(end 304.723546 -321.231006)
		(width 0.1651)
		(layer "In5.Cu")
		(net "P5E_PEX2_STN5_RX_DN<94>")
	)
	(segment
		(start 346.946474 -341.938864)
		(end 346.62872 -341.279988)
		(width 0.1651)
		(layer "In5.Cu")
		(net "P5E_PEX2_STN5_RX_DN<94>")
	)
	(segment
		(start 303.865788 -319.941448)
		(end 303.820068 -319.895728)
		(width 0.1143)
		(layer "In5.Cu")
		(net "P5E_PEX2_STN5_RX_DN<94>")
	)
	(segment
		(start 346.77477 -357.694992)
		(end 346.946474 -341.938864)
		(width 0.1651)
		(layer "In5.Cu")
		(net "P5E_PEX2_STN5_RX_DN<94>")
	)
	(segment
		(start 303.865788 -319.969896)
		(end 303.865788 -319.941448)
		(width 0.1143)
		(layer "In5.Cu")
		(net "P5E_PEX2_STN5_RX_DN<94>")
	)
	(segment
		(start 303.820068 -316.534292)
		(end 303.934368 -316.419992)
		(width 0.1143)
		(layer "In5.Cu")
		(net "P5E_PEX2_STN5_RX_DN<94>")
	)
	(segment
		(start 344.816938 -371.281198)
		(end 345.364054 -371.281198)
		(width 0.1651)
		(layer "In5.Cu")
		(net "P5E_PEX2_STN5_RX_DN<94>")
	)
	(segment
		(start 345.81592 -370.829332)
		(end 346.77477 -357.694992)
		(width 0.1651)
		(layer "In5.Cu")
		(net "P5E_PEX2_STN5_RX_DN<94>")
	)
	(segment
		(start 308.01691 -322.747386)
		(end 307.967126 -322.612766)
		(width 0.1651)
		(layer "In5.Cu")
		(net "P5E_PEX2_STN5_RX_DN<94>")
	)
	(segment
		(start 303.934368 -316.419992)
		(end 304.085498 -316.419992)
		(width 0.1143)
		(layer "In5.Cu")
		(net "P5E_PEX2_STN5_RX_DN<94>")
	)
	(segment
		(start 307.967126 -322.612766)
		(end 307.517038 -322.405248)
		(width 0.1651)
		(layer "In5.Cu")
		(net "P5E_PEX2_STN5_RX_DN<94>")
	)
	(segment
		(start 346.62872 -341.279988)
		(end 345.23426 -339.88502)
		(width 0.1651)
		(layer "In5.Cu")
		(net "P5E_PEX2_STN5_RX_DN<94>")
	)
	(segment
		(start 304.458116 -320.96583)
		(end 303.865788 -320.373502)
		(width 0.1651)
		(layer "In5.Cu")
		(net "P5E_PEX2_STN5_RX_DN<94>")
	)
	(segment
		(start 303.820068 -319.895728)
		(end 303.820068 -316.534292)
		(width 0.1143)
		(layer "In5.Cu")
		(net "P5E_PEX2_STN5_RX_DN<94>")
	)
	(segment
		(start 307.517038 -322.405248)
		(end 307.382164 -322.455032)
		(width 0.1651)
		(layer "In5.Cu")
		(net "P5E_PEX2_STN5_RX_DN<94>")
	)
	(segment
		(start 344.689938 -371.790214)
		(end 344.689938 -371.408198)
		(width 0.1651)
		(layer "In5.Cu")
		(net "P5E_PEX2_STN5_RX_DN<94>")
	)
	(segment
		(start 304.085498 -316.419992)
		(end 304.199798 -316.534292)
		(width 0.1143)
		(layer "In5.Cu")
		(net "P5E_PEX2_STN5_RX_DN<94>")
	)
	(segment
		(start 140.706348 -351.611438)
		(end 140.411708 -351.316798)
		(width 0.13462)
		(layer "F.Cu")
		(net "P5E_PEX1_STN5_TX_C_DN<93>")
	)
	(segment
		(start 140.411708 -351.316798)
		(end 140.411708 -350.685354)
		(width 0.13462)
		(layer "F.Cu")
		(net "P5E_PEX1_STN5_TX_C_DN<93>")
	)
	(segment
		(start 140.411708 -350.685354)
		(end 140.731748 -350.365314)
		(width 0.13462)
		(layer "F.Cu")
		(net "P5E_PEX1_STN5_TX_C_DN<93>")
	)
	(segment
		(start 138.861038 -358.744266)
		(end 138.078718 -360.342434)
		(width 0.1651)
		(layer "In13.Cu")
		(net "P5E_PEX1_STN5_TX_C_DN<93>")
	)
	(segment
		(start 138.078718 -360.342688)
		(end 138.050016 -360.401108)
		(width 0.1651)
		(layer "In13.Cu")
		(net "P5E_PEX1_STN5_TX_C_DN<93>")
	)
	(segment
		(start 140.706348 -351.611438)
		(end 140.415518 -351.902268)
		(width 0.1651)
		(layer "In13.Cu")
		(net "P5E_PEX1_STN5_TX_C_DN<93>")
	)
	(segment
		(start 128.0668 -369.019074)
		(end 128.0668 -379.489716)
		(width 0.1651)
		(layer "In13.Cu")
		(net "P5E_PEX1_STN5_TX_C_DN<93>")
	)
	(segment
		(start 127.375412 -380.181104)
		(end 127.037084 -380.181104)
		(width 0.1651)
		(layer "In13.Cu")
		(net "P5E_PEX1_STN5_TX_C_DN<93>")
	)
	(segment
		(start 138.861038 -354.107496)
		(end 138.861038 -358.744266)
		(width 0.1651)
		(layer "In13.Cu")
		(net "P5E_PEX1_STN5_TX_C_DN<93>")
	)
	(segment
		(start 128.0668 -379.489716)
		(end 127.375412 -380.181104)
		(width 0.1651)
		(layer "In13.Cu")
		(net "P5E_PEX1_STN5_TX_C_DN<93>")
	)
	(segment
		(start 140.415518 -352.553016)
		(end 138.861038 -354.107496)
		(width 0.1651)
		(layer "In13.Cu")
		(net "P5E_PEX1_STN5_TX_C_DN<93>")
	)
	(segment
		(start 138.050016 -360.401108)
		(end 128.68656 -367.672366)
		(width 0.1651)
		(layer "In13.Cu")
		(net "P5E_PEX1_STN5_TX_C_DN<93>")
	)
	(segment
		(start 126.910084 -380.308104)
		(end 126.910084 -380.69012)
		(width 0.1651)
		(layer "In13.Cu")
		(net "P5E_PEX1_STN5_TX_C_DN<93>")
	)
	(segment
		(start 128.68656 -367.672366)
		(end 128.0668 -369.019074)
		(width 0.1651)
		(layer "In13.Cu")
		(net "P5E_PEX1_STN5_TX_C_DN<93>")
	)
	(segment
		(start 138.078718 -360.342434)
		(end 138.078718 -360.342688)
		(width 0.1651)
		(layer "In13.Cu")
		(net "P5E_PEX1_STN5_TX_C_DN<93>")
	)
	(segment
		(start 140.415518 -351.902268)
		(end 140.415518 -352.553016)
		(width 0.1651)
		(layer "In13.Cu")
		(net "P5E_PEX1_STN5_TX_C_DN<93>")
	)
	(segment
		(start 127.037084 -380.181104)
		(end 126.910084 -380.308104)
		(width 0.1651)
		(layer "In13.Cu")
		(net "P5E_PEX1_STN5_TX_C_DN<93>")
	)
	(segment
		(start 196.705982 -130.474466)
		(end 197.337426 -130.474466)
		(width 0.13462)
		(layer "F.Cu")
		(net "P5E_PEX1_STN0_TX_DP<4>")
	)
	(segment
		(start 197.337426 -130.474466)
		(end 197.632066 -130.769106)
		(width 0.13462)
		(layer "F.Cu")
		(net "P5E_PEX1_STN0_TX_DP<4>")
	)
	(segment
		(start 196.385942 -130.794506)
		(end 196.705982 -130.474466)
		(width 0.13462)
		(layer "F.Cu")
		(net "P5E_PEX1_STN0_TX_DP<4>")
	)
	(segment
		(start 212.118702 -153.442416)
		(end 212.118702 -159.418782)
		(width 0.1651)
		(layer "In9.Cu")
		(net "P5E_PEX1_STN0_TX_DP<4>")
	)
	(segment
		(start 203.663296 -133.273038)
		(end 203.838048 -133.695186)
		(width 0.1651)
		(layer "In9.Cu")
		(net "P5E_PEX1_STN0_TX_DP<4>")
	)
	(segment
		(start 201.073766 -283.883862)
		(end 200.017634 -283.883862)
		(width 0.1651)
		(layer "In9.Cu")
		(net "P5E_PEX1_STN0_TX_DP<4>")
	)
	(segment
		(start 203.783184 -133.828028)
		(end 203.95819 -134.250684)
		(width 0.1651)
		(layer "In9.Cu")
		(net "P5E_PEX1_STN0_TX_DP<4>")
	)
	(segment
		(start 201.122026 -250.828302)
		(end 211.513928 -266.38123)
		(width 0.1651)
		(layer "In9.Cu")
		(net "P5E_PEX1_STN0_TX_DP<4>")
	)
	(segment
		(start 204.091032 -134.305802)
		(end 204.265784 -134.72795)
		(width 0.1651)
		(layer "In9.Cu")
		(net "P5E_PEX1_STN0_TX_DP<4>")
	)
	(segment
		(start 202.935586 -132.545328)
		(end 203.663296 -133.273038)
		(width 0.1651)
		(layer "In9.Cu")
		(net "P5E_PEX1_STN0_TX_DP<4>")
	)
	(segment
		(start 208.459578 -144.60855)
		(end 212.118702 -153.442416)
		(width 0.1651)
		(layer "In9.Cu")
		(net "P5E_PEX1_STN0_TX_DP<4>")
	)
	(segment
		(start 199.498458 -130.478276)
		(end 200.304146 -130.478276)
		(width 0.1651)
		(layer "In9.Cu")
		(net "P5E_PEX1_STN0_TX_DP<4>")
	)
	(segment
		(start 204.518768 -135.338566)
		(end 204.69352 -135.760714)
		(width 0.1651)
		(layer "In9.Cu")
		(net "P5E_PEX1_STN0_TX_DP<4>")
	)
	(segment
		(start 202.468226 -132.077968)
		(end 202.468226 -132.221732)
		(width 0.1651)
		(layer "In9.Cu")
		(net "P5E_PEX1_STN0_TX_DP<4>")
	)
	(segment
		(start 212.287612 -268.2494)
		(end 212.62467 -272.107406)
		(width 0.1651)
		(layer "In9.Cu")
		(net "P5E_PEX1_STN0_TX_DP<4>")
	)
	(segment
		(start 199.843898 -236.187234)
		(end 201.122026 -250.828302)
		(width 0.1651)
		(layer "In9.Cu")
		(net "P5E_PEX1_STN0_TX_DP<4>")
	)
	(segment
		(start 205.121256 -136.793478)
		(end 205.066392 -136.92632)
		(width 0.1651)
		(layer "In9.Cu")
		(net "P5E_PEX1_STN0_TX_DP<4>")
	)
	(segment
		(start 205.066392 -136.92632)
		(end 205.241398 -137.348976)
		(width 0.1651)
		(layer "In9.Cu")
		(net "P5E_PEX1_STN0_TX_DP<4>")
	)
	(segment
		(start 198.838058 -130.478276)
		(end 198.939658 -130.579876)
		(width 0.1651)
		(layer "In9.Cu")
		(net "P5E_PEX1_STN0_TX_DP<4>")
	)
	(segment
		(start 201.677778 -131.431284)
		(end 202.001374 -131.75488)
		(width 0.1651)
		(layer "In9.Cu")
		(net "P5E_PEX1_STN0_TX_DP<4>")
	)
	(segment
		(start 201.267822 -130.877564)
		(end 201.677778 -131.28752)
		(width 0.1651)
		(layer "In9.Cu")
		(net "P5E_PEX1_STN0_TX_DP<4>")
	)
	(segment
		(start 204.21092 -134.860792)
		(end 204.385926 -135.283448)
		(width 0.1651)
		(layer "In9.Cu")
		(net "P5E_PEX1_STN0_TX_DP<4>")
	)
	(segment
		(start 200.304146 -130.478276)
		(end 201.267822 -130.877564)
		(width 0.1651)
		(layer "In9.Cu")
		(net "P5E_PEX1_STN0_TX_DP<4>")
	)
	(segment
		(start 203.390246 -174.663862)
		(end 202.329288 -178.621436)
		(width 0.1651)
		(layer "In9.Cu")
		(net "P5E_PEX1_STN0_TX_DP<4>")
	)
	(segment
		(start 212.058504 -159.64408)
		(end 203.390246 -174.663862)
		(width 0.1651)
		(layer "In9.Cu")
		(net "P5E_PEX1_STN0_TX_DP<4>")
	)
	(segment
		(start 198.939658 -130.579876)
		(end 199.396858 -130.579876)
		(width 0.1651)
		(layer "In9.Cu")
		(net "P5E_PEX1_STN0_TX_DP<4>")
	)
	(segment
		(start 203.95819 -134.250684)
		(end 204.091032 -134.305802)
		(width 0.1651)
		(layer "In9.Cu")
		(net "P5E_PEX1_STN0_TX_DP<4>")
	)
	(segment
		(start 204.385926 -135.283448)
		(end 204.518768 -135.338566)
		(width 0.1651)
		(layer "In9.Cu")
		(net "P5E_PEX1_STN0_TX_DP<4>")
	)
	(segment
		(start 204.946504 -136.37133)
		(end 205.121256 -136.793478)
		(width 0.1651)
		(layer "In9.Cu")
		(net "P5E_PEX1_STN0_TX_DP<4>")
	)
	(segment
		(start 202.468226 -132.221732)
		(end 202.791822 -132.545328)
		(width 0.1651)
		(layer "In9.Cu")
		(net "P5E_PEX1_STN0_TX_DP<4>")
	)
	(segment
		(start 205.241398 -137.348976)
		(end 205.37424 -137.404094)
		(width 0.1651)
		(layer "In9.Cu")
		(net "P5E_PEX1_STN0_TX_DP<4>")
	)
	(segment
		(start 203.838048 -133.695186)
		(end 203.783184 -133.828028)
		(width 0.1651)
		(layer "In9.Cu")
		(net "P5E_PEX1_STN0_TX_DP<4>")
	)
	(segment
		(start 199.989186 -283.883862)
		(end 199.943466 -283.929582)
		(width 0.1143)
		(layer "In9.Cu")
		(net "P5E_PEX1_STN0_TX_DP<4>")
	)
	(segment
		(start 199.396858 -130.579876)
		(end 199.498458 -130.478276)
		(width 0.1651)
		(layer "In9.Cu")
		(net "P5E_PEX1_STN0_TX_DP<4>")
	)
	(segment
		(start 202.791822 -132.545328)
		(end 202.935586 -132.545328)
		(width 0.1651)
		(layer "In9.Cu")
		(net "P5E_PEX1_STN0_TX_DP<4>")
	)
	(segment
		(start 208.287366 -144.436338)
		(end 208.459578 -144.60855)
		(width 0.1651)
		(layer "In9.Cu")
		(net "P5E_PEX1_STN0_TX_DP<4>")
	)
	(segment
		(start 202.329288 -178.621436)
		(end 198.56958 -221.593156)
		(width 0.1651)
		(layer "In9.Cu")
		(net "P5E_PEX1_STN0_TX_DP<4>")
	)
	(segment
		(start 193.115438 -284.499812)
		(end 192.850008 -284.499812)
		(width 0.1143)
		(layer "In9.Cu")
		(net "P5E_PEX1_STN0_TX_DP<4>")
	)
	(segment
		(start 199.943466 -283.929582)
		(end 193.444876 -283.929582)
		(width 0.1143)
		(layer "In9.Cu")
		(net "P5E_PEX1_STN0_TX_DP<4>")
	)
	(segment
		(start 204.69352 -135.760714)
		(end 204.638656 -135.893556)
		(width 0.1651)
		(layer "In9.Cu")
		(net "P5E_PEX1_STN0_TX_DP<4>")
	)
	(segment
		(start 198.56958 -221.593156)
		(end 199.843898 -236.187234)
		(width 0.1651)
		(layer "In9.Cu")
		(net "P5E_PEX1_STN0_TX_DP<4>")
	)
	(segment
		(start 202.001374 -131.75488)
		(end 202.145138 -131.75488)
		(width 0.1651)
		(layer "In9.Cu")
		(net "P5E_PEX1_STN0_TX_DP<4>")
	)
	(segment
		(start 202.145138 -131.75488)
		(end 202.468226 -132.077968)
		(width 0.1651)
		(layer "In9.Cu")
		(net "P5E_PEX1_STN0_TX_DP<4>")
	)
	(segment
		(start 197.922896 -130.478276)
		(end 198.838058 -130.478276)
		(width 0.1651)
		(layer "In9.Cu")
		(net "P5E_PEX1_STN0_TX_DP<4>")
	)
	(segment
		(start 212.62467 -272.107406)
		(end 211.596224 -274.590002)
		(width 0.1651)
		(layer "In9.Cu")
		(net "P5E_PEX1_STN0_TX_DP<4>")
	)
	(segment
		(start 200.017634 -283.883862)
		(end 199.989186 -283.883862)
		(width 0.1143)
		(layer "In9.Cu")
		(net "P5E_PEX1_STN0_TX_DP<4>")
	)
	(segment
		(start 201.677778 -131.28752)
		(end 201.677778 -131.431284)
		(width 0.1651)
		(layer "In9.Cu")
		(net "P5E_PEX1_STN0_TX_DP<4>")
	)
	(segment
		(start 211.596224 -274.590002)
		(end 203.171298 -283.014928)
		(width 0.1651)
		(layer "In9.Cu")
		(net "P5E_PEX1_STN0_TX_DP<4>")
	)
	(segment
		(start 193.229738 -284.14472)
		(end 193.229738 -284.385512)
		(width 0.1143)
		(layer "In9.Cu")
		(net "P5E_PEX1_STN0_TX_DP<4>")
	)
	(segment
		(start 205.37424 -137.404094)
		(end 208.287366 -144.436338)
		(width 0.1651)
		(layer "In9.Cu")
		(net "P5E_PEX1_STN0_TX_DP<4>")
	)
	(segment
		(start 204.265784 -134.72795)
		(end 204.21092 -134.860792)
		(width 0.1651)
		(layer "In9.Cu")
		(net "P5E_PEX1_STN0_TX_DP<4>")
	)
	(segment
		(start 193.229738 -284.385512)
		(end 193.115438 -284.499812)
		(width 0.1143)
		(layer "In9.Cu")
		(net "P5E_PEX1_STN0_TX_DP<4>")
	)
	(segment
		(start 203.171298 -283.014928)
		(end 201.073766 -283.883862)
		(width 0.1651)
		(layer "In9.Cu")
		(net "P5E_PEX1_STN0_TX_DP<4>")
	)
	(segment
		(start 197.632066 -130.769106)
		(end 197.922896 -130.478276)
		(width 0.1651)
		(layer "In9.Cu")
		(net "P5E_PEX1_STN0_TX_DP<4>")
	)
	(segment
		(start 211.513928 -266.38123)
		(end 212.287612 -268.2494)
		(width 0.1651)
		(layer "In9.Cu")
		(net "P5E_PEX1_STN0_TX_DP<4>")
	)
	(segment
		(start 204.638656 -135.893556)
		(end 204.813662 -136.316212)
		(width 0.1651)
		(layer "In9.Cu")
		(net "P5E_PEX1_STN0_TX_DP<4>")
	)
	(segment
		(start 193.444876 -283.929582)
		(end 193.229738 -284.14472)
		(width 0.1143)
		(layer "In9.Cu")
		(net "P5E_PEX1_STN0_TX_DP<4>")
	)
	(segment
		(start 204.813662 -136.316212)
		(end 204.946504 -136.37133)
		(width 0.1651)
		(layer "In9.Cu")
		(net "P5E_PEX1_STN0_TX_DP<4>")
	)
	(segment
		(start 212.118702 -159.418782)
		(end 212.058504 -159.64408)
		(width 0.1651)
		(layer "In9.Cu")
		(net "P5E_PEX1_STN0_TX_DP<4>")
	)
	(segment
		(start 159.371792 -355.026722)
		(end 159.077152 -354.732082)
		(width 0.13462)
		(layer "F.Cu")
		(net "P5E_PEX1_STN7_TX_DP<112>")
	)
	(segment
		(start 159.371792 -355.658166)
		(end 159.371792 -355.026722)
		(width 0.13462)
		(layer "F.Cu")
		(net "P5E_PEX1_STN7_TX_DP<112>")
	)
	(segment
		(start 159.051752 -355.978206)
		(end 159.371792 -355.658166)
		(width 0.13462)
		(layer "F.Cu")
		(net "P5E_PEX1_STN7_TX_DP<112>")
	)
	(segment
		(start 133.076442 -317.186056)
		(end 135.697468 -310.865266)
		(width 0.1651)
		(layer "In11.Cu")
		(net "P5E_PEX1_STN7_TX_DP<112>")
	)
	(segment
		(start 158.359094 -301.599854)
		(end 158.649924 -301.599854)
		(width 0.1143)
		(layer "In11.Cu")
		(net "P5E_PEX1_STN7_TX_DP<112>")
	)
	(segment
		(start 132.62737 -323.06895)
		(end 132.62737 -319.450466)
		(width 0.1651)
		(layer "In11.Cu")
		(net "P5E_PEX1_STN7_TX_DP<112>")
	)
	(segment
		(start 158.270194 -301.30623)
		(end 158.270194 -301.510954)
		(width 0.1143)
		(layer "In11.Cu")
		(net "P5E_PEX1_STN7_TX_DP<112>")
	)
	(segment
		(start 140.262102 -304.722784)
		(end 142.879572 -302.105568)
		(width 0.1651)
		(layer "In11.Cu")
		(net "P5E_PEX1_STN7_TX_DP<112>")
	)
	(segment
		(start 136.1821 -330.266548)
		(end 133.670548 -326.510396)
		(width 0.1651)
		(layer "In11.Cu")
		(net "P5E_PEX1_STN7_TX_DP<112>")
	)
	(segment
		(start 157.993588 -301.029624)
		(end 158.270194 -301.30623)
		(width 0.1143)
		(layer "In11.Cu")
		(net "P5E_PEX1_STN7_TX_DP<112>")
	)
	(segment
		(start 132.62737 -319.450466)
		(end 133.076442 -317.186056)
		(width 0.1651)
		(layer "In11.Cu")
		(net "P5E_PEX1_STN7_TX_DP<112>")
	)
	(segment
		(start 151.69642 -301.029624)
		(end 157.993588 -301.029624)
		(width 0.1143)
		(layer "In11.Cu")
		(net "P5E_PEX1_STN7_TX_DP<112>")
	)
	(segment
		(start 145.587466 -300.983904)
		(end 151.628602 -300.983904)
		(width 0.1651)
		(layer "In11.Cu")
		(net "P5E_PEX1_STN7_TX_DP<112>")
	)
	(segment
		(start 151.6507 -300.983904)
		(end 151.69642 -301.029624)
		(width 0.1143)
		(layer "In11.Cu")
		(net "P5E_PEX1_STN7_TX_DP<112>")
	)
	(segment
		(start 142.879572 -302.105568)
		(end 145.587466 -300.983904)
		(width 0.1651)
		(layer "In11.Cu")
		(net "P5E_PEX1_STN7_TX_DP<112>")
	)
	(segment
		(start 159.367982 -353.94138)
		(end 158.72714 -352.414332)
		(width 0.1651)
		(layer "In11.Cu")
		(net "P5E_PEX1_STN7_TX_DP<112>")
	)
	(segment
		(start 158.270194 -301.510954)
		(end 158.359094 -301.599854)
		(width 0.1143)
		(layer "In11.Cu")
		(net "P5E_PEX1_STN7_TX_DP<112>")
	)
	(segment
		(start 133.670548 -326.510396)
		(end 132.62737 -323.06895)
		(width 0.1651)
		(layer "In11.Cu")
		(net "P5E_PEX1_STN7_TX_DP<112>")
	)
	(segment
		(start 159.367982 -354.441252)
		(end 159.367982 -353.94138)
		(width 0.1651)
		(layer "In11.Cu")
		(net "P5E_PEX1_STN7_TX_DP<112>")
	)
	(segment
		(start 151.628602 -300.983904)
		(end 151.6507 -300.983904)
		(width 0.1143)
		(layer "In11.Cu")
		(net "P5E_PEX1_STN7_TX_DP<112>")
	)
	(segment
		(start 159.077152 -354.732082)
		(end 159.367982 -354.441252)
		(width 0.1651)
		(layer "In11.Cu")
		(net "P5E_PEX1_STN7_TX_DP<112>")
	)
	(segment
		(start 158.72714 -352.414332)
		(end 136.1821 -330.266548)
		(width 0.1651)
		(layer "In11.Cu")
		(net "P5E_PEX1_STN7_TX_DP<112>")
	)
	(segment
		(start 135.697468 -310.865266)
		(end 140.262102 -304.722784)
		(width 0.1651)
		(layer "In11.Cu")
		(net "P5E_PEX1_STN7_TX_DP<112>")
	)
	(segment
		(start 268.258544 -119.51208)
		(end 268.571726 -119.198898)
		(width 0.13462)
		(layer "F.Cu")
		(net "P5E_PEX2_STN1_TX_DP<24>")
	)
	(segment
		(start 267.325602 -119.224298)
		(end 267.613384 -119.51208)
		(width 0.13462)
		(layer "F.Cu")
		(net "P5E_PEX2_STN1_TX_DP<24>")
	)
	(segment
		(start 267.613384 -119.51208)
		(end 268.258544 -119.51208)
		(width 0.13462)
		(layer "F.Cu")
		(net "P5E_PEX2_STN1_TX_DP<24>")
	)
	(segment
		(start 267.034772 -119.515128)
		(end 267.325602 -119.224298)
		(width 0.1651)
		(layer "In9.Cu")
		(net "P5E_PEX2_STN1_TX_DP<24>")
	)
	(segment
		(start 299.44949 -278.799798)
		(end 299.44949 -278.534368)
		(width 0.1143)
		(layer "In9.Cu")
		(net "P5E_PEX2_STN1_TX_DP<24>")
	)
	(segment
		(start 299.094398 -278.420068)
		(end 298.879514 -278.205184)
		(width 0.1143)
		(layer "In9.Cu")
		(net "P5E_PEX2_STN1_TX_DP<24>")
	)
	(segment
		(start 262.70458 -143.627094)
		(end 260.147054 -137.452608)
		(width 0.1651)
		(layer "In9.Cu")
		(net "P5E_PEX2_STN1_TX_DP<24>")
	)
	(segment
		(start 260.147054 -131.866386)
		(end 264.543032 -121.253758)
		(width 0.1651)
		(layer "In9.Cu")
		(net "P5E_PEX2_STN1_TX_DP<24>")
	)
	(segment
		(start 260.147054 -137.452608)
		(end 260.147054 -131.866386)
		(width 0.1651)
		(layer "In9.Cu")
		(net "P5E_PEX2_STN1_TX_DP<24>")
	)
	(segment
		(start 299.33519 -278.420068)
		(end 299.094398 -278.420068)
		(width 0.1143)
		(layer "In9.Cu")
		(net "P5E_PEX2_STN1_TX_DP<24>")
	)
	(segment
		(start 264.543032 -121.253758)
		(end 266.281662 -119.515128)
		(width 0.1651)
		(layer "In9.Cu")
		(net "P5E_PEX2_STN1_TX_DP<24>")
	)
	(segment
		(start 298.879514 -271.546066)
		(end 298.833794 -271.500346)
		(width 0.1143)
		(layer "In9.Cu")
		(net "P5E_PEX2_STN1_TX_DP<24>")
	)
	(segment
		(start 299.44949 -278.534368)
		(end 299.33519 -278.420068)
		(width 0.1143)
		(layer "In9.Cu")
		(net "P5E_PEX2_STN1_TX_DP<24>")
	)
	(segment
		(start 298.879514 -278.205184)
		(end 298.879514 -271.546066)
		(width 0.1143)
		(layer "In9.Cu")
		(net "P5E_PEX2_STN1_TX_DP<24>")
	)
	(segment
		(start 298.833794 -271.500346)
		(end 298.833794 -271.471898)
		(width 0.1143)
		(layer "In9.Cu")
		(net "P5E_PEX2_STN1_TX_DP<24>")
	)
	(segment
		(start 264.021824 -161.439098)
		(end 263.435592 -158.49219)
		(width 0.1651)
		(layer "In9.Cu")
		(net "P5E_PEX2_STN1_TX_DP<24>")
	)
	(segment
		(start 298.833794 -264.281666)
		(end 264.021824 -161.439098)
		(width 0.1651)
		(layer "In9.Cu")
		(net "P5E_PEX2_STN1_TX_DP<24>")
	)
	(segment
		(start 266.281662 -119.515128)
		(end 267.034772 -119.515128)
		(width 0.1651)
		(layer "In9.Cu")
		(net "P5E_PEX2_STN1_TX_DP<24>")
	)
	(segment
		(start 298.833794 -271.471898)
		(end 298.833794 -264.281666)
		(width 0.1651)
		(layer "In9.Cu")
		(net "P5E_PEX2_STN1_TX_DP<24>")
	)
	(segment
		(start 263.435592 -158.49219)
		(end 262.70458 -143.627094)
		(width 0.1651)
		(layer "In9.Cu")
		(net "P5E_PEX2_STN1_TX_DP<24>")
	)
	(segment
		(start 298.489878 -384.20802)
		(end 298.489878 -384.590036)
		(width 0.1651)
		(layer "In5.Cu")
		(net "P5E_PEX2_STN7_RX_DN<125>")
	)
	(segment
		(start 297.08729 -340.782148)
		(end 297.674284 -341.4649)
		(width 0.1651)
		(layer "In5.Cu")
		(net "P5E_PEX2_STN7_RX_DN<125>")
	)
	(segment
		(start 298.616878 -384.08102)
		(end 298.489878 -384.20802)
		(width 0.1651)
		(layer "In5.Cu")
		(net "P5E_PEX2_STN7_RX_DN<125>")
	)
	(segment
		(start 272.849848 -318.434466)
		(end 272.735548 -318.320166)
		(width 0.1143)
		(layer "In5.Cu")
		(net "P5E_PEX2_STN7_RX_DN<125>")
	)
	(segment
		(start 295.876472 -340.12505)
		(end 295.997122 -340.089236)
		(width 0.1651)
		(layer "In5.Cu")
		(net "P5E_PEX2_STN7_RX_DN<125>")
	)
	(segment
		(start 297.674284 -341.4649)
		(end 298.004992 -342.378538)
		(width 0.1651)
		(layer "In5.Cu")
		(net "P5E_PEX2_STN7_RX_DN<125>")
	)
	(segment
		(start 272.735548 -318.320166)
		(end 272.584418 -318.320166)
		(width 0.1143)
		(layer "In5.Cu")
		(net "P5E_PEX2_STN7_RX_DN<125>")
	)
	(segment
		(start 272.584418 -318.320166)
		(end 272.470118 -318.434466)
		(width 0.1143)
		(layer "In5.Cu")
		(net "P5E_PEX2_STN7_RX_DN<125>")
	)
	(segment
		(start 299.163994 -384.08102)
		(end 298.616878 -384.08102)
		(width 0.1651)
		(layer "In5.Cu")
		(net "P5E_PEX2_STN7_RX_DN<125>")
	)
	(segment
		(start 296.468292 -340.44636)
		(end 297.08729 -340.782148)
		(width 0.1651)
		(layer "In5.Cu")
		(net "P5E_PEX2_STN7_RX_DN<125>")
	)
	(segment
		(start 272.470118 -319.96888)
		(end 272.515838 -320.0146)
		(width 0.1143)
		(layer "In5.Cu")
		(net "P5E_PEX2_STN7_RX_DN<125>")
	)
	(segment
		(start 277.268686 -330.02728)
		(end 295.876472 -340.12505)
		(width 0.1651)
		(layer "In5.Cu")
		(net "P5E_PEX2_STN7_RX_DN<125>")
	)
	(segment
		(start 298.004992 -342.378538)
		(end 298.004992 -359.664762)
		(width 0.1651)
		(layer "In5.Cu")
		(net "P5E_PEX2_STN7_RX_DN<125>")
	)
	(segment
		(start 272.849848 -318.699896)
		(end 272.849848 -318.434466)
		(width 0.1143)
		(layer "In5.Cu")
		(net "P5E_PEX2_STN7_RX_DN<125>")
	)
	(segment
		(start 299.61586 -368.718846)
		(end 299.61586 -383.629154)
		(width 0.1651)
		(layer "In5.Cu")
		(net "P5E_PEX2_STN7_RX_DN<125>")
	)
	(segment
		(start 299.61586 -383.629154)
		(end 299.163994 -384.08102)
		(width 0.1651)
		(layer "In5.Cu")
		(net "P5E_PEX2_STN7_RX_DN<125>")
	)
	(segment
		(start 296.432732 -340.32571)
		(end 296.468292 -340.44636)
		(width 0.1651)
		(layer "In5.Cu")
		(net "P5E_PEX2_STN7_RX_DN<125>")
	)
	(segment
		(start 272.470118 -318.434466)
		(end 272.470118 -319.96888)
		(width 0.1143)
		(layer "In5.Cu")
		(net "P5E_PEX2_STN7_RX_DN<125>")
	)
	(segment
		(start 274.57527 -328.20229)
		(end 277.268686 -330.02728)
		(width 0.1651)
		(layer "In5.Cu")
		(net "P5E_PEX2_STN7_RX_DN<125>")
	)
	(segment
		(start 272.75282 -326.0217)
		(end 274.57527 -328.20229)
		(width 0.1651)
		(layer "In5.Cu")
		(net "P5E_PEX2_STN7_RX_DN<125>")
	)
	(segment
		(start 272.515838 -320.0146)
		(end 272.515838 -320.043048)
		(width 0.1143)
		(layer "In5.Cu")
		(net "P5E_PEX2_STN7_RX_DN<125>")
	)
	(segment
		(start 272.515838 -320.043048)
		(end 272.515838 -325.403464)
		(width 0.1651)
		(layer "In5.Cu")
		(net "P5E_PEX2_STN7_RX_DN<125>")
	)
	(segment
		(start 295.997122 -340.089236)
		(end 296.432732 -340.32571)
		(width 0.1651)
		(layer "In5.Cu")
		(net "P5E_PEX2_STN7_RX_DN<125>")
	)
	(segment
		(start 272.515838 -325.403464)
		(end 272.75282 -326.0217)
		(width 0.1651)
		(layer "In5.Cu")
		(net "P5E_PEX2_STN7_RX_DN<125>")
	)
	(segment
		(start 298.004992 -359.664762)
		(end 299.61586 -368.718846)
		(width 0.1651)
		(layer "In5.Cu")
		(net "P5E_PEX2_STN7_RX_DN<125>")
	)
	(segment
		(start 184.243472 -350.685354)
		(end 183.923432 -350.365314)
		(width 0.13462)
		(layer "F.Cu")
		(net "P5E_PEX1_STN7_TX_C_DP<123>")
	)
	(segment
		(start 184.243472 -351.316798)
		(end 184.243472 -350.685354)
		(width 0.13462)
		(layer "F.Cu")
		(net "P5E_PEX1_STN7_TX_C_DP<123>")
	)
	(segment
		(start 183.948832 -351.611438)
		(end 184.243472 -351.316798)
		(width 0.13462)
		(layer "F.Cu")
		(net "P5E_PEX1_STN7_TX_C_DP<123>")
	)
	(segment
		(start 181.675024 -360.512106)
		(end 181.513226 -360.512106)
		(width 0.1651)
		(layer "In11.Cu")
		(net "P5E_PEX1_STN7_TX_C_DP<123>")
	)
	(segment
		(start 181.513226 -360.512106)
		(end 181.162706 -360.862626)
		(width 0.1651)
		(layer "In11.Cu")
		(net "P5E_PEX1_STN7_TX_C_DP<123>")
	)
	(segment
		(start 184.239662 -351.902268)
		(end 184.239662 -352.4631)
		(width 0.1651)
		(layer "In11.Cu")
		(net "P5E_PEX1_STN7_TX_C_DP<123>")
	)
	(segment
		(start 179.122578 -363.064552)
		(end 168.677844 -367.4491)
		(width 0.1651)
		(layer "In11.Cu")
		(net "P5E_PEX1_STN7_TX_C_DP<123>")
	)
	(segment
		(start 184.239662 -352.4631)
		(end 182.685182 -354.01758)
		(width 0.1651)
		(layer "In11.Cu")
		(net "P5E_PEX1_STN7_TX_C_DP<123>")
	)
	(segment
		(start 166.509954 -375.872248)
		(end 166.509954 -375.490232)
		(width 0.1651)
		(layer "In11.Cu")
		(net "P5E_PEX1_STN7_TX_C_DP<123>")
	)
	(segment
		(start 182.685182 -359.501948)
		(end 181.675024 -360.512106)
		(width 0.1651)
		(layer "In11.Cu")
		(net "P5E_PEX1_STN7_TX_C_DP<123>")
	)
	(segment
		(start 167.385492 -368.741452)
		(end 167.385492 -375.472198)
		(width 0.1651)
		(layer "In11.Cu")
		(net "P5E_PEX1_STN7_TX_C_DP<123>")
	)
	(segment
		(start 183.948832 -351.611438)
		(end 184.239662 -351.902268)
		(width 0.1651)
		(layer "In11.Cu")
		(net "P5E_PEX1_STN7_TX_C_DP<123>")
	)
	(segment
		(start 181.162706 -360.862626)
		(end 181.162706 -361.024424)
		(width 0.1651)
		(layer "In11.Cu")
		(net "P5E_PEX1_STN7_TX_C_DP<123>")
	)
	(segment
		(start 166.858442 -375.999248)
		(end 166.636954 -375.999248)
		(width 0.1651)
		(layer "In11.Cu")
		(net "P5E_PEX1_STN7_TX_C_DP<123>")
	)
	(segment
		(start 166.636954 -375.999248)
		(end 166.509954 -375.872248)
		(width 0.1651)
		(layer "In11.Cu")
		(net "P5E_PEX1_STN7_TX_C_DP<123>")
	)
	(segment
		(start 181.162706 -361.024424)
		(end 179.122578 -363.064552)
		(width 0.1651)
		(layer "In11.Cu")
		(net "P5E_PEX1_STN7_TX_C_DP<123>")
	)
	(segment
		(start 167.385492 -375.472198)
		(end 166.858442 -375.999248)
		(width 0.1651)
		(layer "In11.Cu")
		(net "P5E_PEX1_STN7_TX_C_DP<123>")
	)
	(segment
		(start 168.677844 -367.4491)
		(end 167.385492 -368.741452)
		(width 0.1651)
		(layer "In11.Cu")
		(net "P5E_PEX1_STN7_TX_C_DP<123>")
	)
	(segment
		(start 182.685182 -354.01758)
		(end 182.685182 -359.501948)
		(width 0.1651)
		(layer "In11.Cu")
		(net "P5E_PEX1_STN7_TX_C_DP<123>")
	)
	(segment
		(start 152.471628 -134.008876)
		(end 152.151588 -134.328916)
		(width 0.13462)
		(layer "F.Cu")
		(net "P5E_PEX1_STN1_TX_DP<30>")
	)
	(segment
		(start 151.520144 -134.328916)
		(end 151.225504 -134.034276)
		(width 0.13462)
		(layer "F.Cu")
		(net "P5E_PEX1_STN1_TX_DP<30>")
	)
	(segment
		(start 152.151588 -134.328916)
		(end 151.520144 -134.328916)
		(width 0.13462)
		(layer "F.Cu")
		(net "P5E_PEX1_STN1_TX_DP<30>")
	)
	(segment
		(start 188.47943 -278.205184)
		(end 188.694314 -278.420068)
		(width 0.1143)
		(layer "In9.Cu")
		(net "P5E_PEX1_STN1_TX_DP<30>")
	)
	(segment
		(start 188.935106 -278.420068)
		(end 189.04966 -278.534622)
		(width 0.1143)
		(layer "In9.Cu")
		(net "P5E_PEX1_STN1_TX_DP<30>")
	)
	(segment
		(start 150.298404 -134.325106)
		(end 149.964394 -134.659116)
		(width 0.1651)
		(layer "In9.Cu")
		(net "P5E_PEX1_STN1_TX_DP<30>")
	)
	(segment
		(start 149.841204 -135.323072)
		(end 150.673816 -137.332212)
		(width 0.1651)
		(layer "In9.Cu")
		(net "P5E_PEX1_STN1_TX_DP<30>")
	)
	(segment
		(start 151.225504 -134.034276)
		(end 150.934674 -134.325106)
		(width 0.1651)
		(layer "In9.Cu")
		(net "P5E_PEX1_STN1_TX_DP<30>")
	)
	(segment
		(start 189.04966 -278.534622)
		(end 189.04966 -278.799798)
		(width 0.1143)
		(layer "In9.Cu")
		(net "P5E_PEX1_STN1_TX_DP<30>")
	)
	(segment
		(start 188.43371 -271.500346)
		(end 188.47943 -271.546066)
		(width 0.1143)
		(layer "In9.Cu")
		(net "P5E_PEX1_STN1_TX_DP<30>")
	)
	(segment
		(start 150.934674 -134.325106)
		(end 150.298404 -134.325106)
		(width 0.1651)
		(layer "In9.Cu")
		(net "P5E_PEX1_STN1_TX_DP<30>")
	)
	(segment
		(start 149.964394 -134.659116)
		(end 149.841204 -134.956296)
		(width 0.1651)
		(layer "In9.Cu")
		(net "P5E_PEX1_STN1_TX_DP<30>")
	)
	(segment
		(start 188.43371 -271.471898)
		(end 188.43371 -271.500346)
		(width 0.1143)
		(layer "In9.Cu")
		(net "P5E_PEX1_STN1_TX_DP<30>")
	)
	(segment
		(start 188.43371 -262.993378)
		(end 188.43371 -271.471898)
		(width 0.1651)
		(layer "In9.Cu")
		(net "P5E_PEX1_STN1_TX_DP<30>")
	)
	(segment
		(start 149.841204 -134.956296)
		(end 149.841204 -135.323072)
		(width 0.1651)
		(layer "In9.Cu")
		(net "P5E_PEX1_STN1_TX_DP<30>")
	)
	(segment
		(start 161.448496 -183.275986)
		(end 188.43371 -262.993378)
		(width 0.1651)
		(layer "In9.Cu")
		(net "P5E_PEX1_STN1_TX_DP<30>")
	)
	(segment
		(start 150.673816 -137.332212)
		(end 152.499822 -139.158218)
		(width 0.1651)
		(layer "In9.Cu")
		(net "P5E_PEX1_STN1_TX_DP<30>")
	)
	(segment
		(start 152.499822 -139.158218)
		(end 152.852882 -140.010642)
		(width 0.1651)
		(layer "In9.Cu")
		(net "P5E_PEX1_STN1_TX_DP<30>")
	)
	(segment
		(start 188.47943 -271.546066)
		(end 188.47943 -278.205184)
		(width 0.1143)
		(layer "In9.Cu")
		(net "P5E_PEX1_STN1_TX_DP<30>")
	)
	(segment
		(start 152.852882 -140.010642)
		(end 161.448496 -183.275986)
		(width 0.1651)
		(layer "In9.Cu")
		(net "P5E_PEX1_STN1_TX_DP<30>")
	)
	(segment
		(start 188.694314 -278.420068)
		(end 188.935106 -278.420068)
		(width 0.1143)
		(layer "In9.Cu")
		(net "P5E_PEX1_STN1_TX_DP<30>")
	)
	(segment
		(start 165.269672 -349.831914)
		(end 165.589712 -349.511874)
		(width 0.13462)
		(layer "F.Cu")
		(net "P5E_PEX1_STN7_TX_DP<114>")
	)
	(segment
		(start 165.589712 -348.88043)
		(end 165.295072 -348.58579)
		(width 0.13462)
		(layer "F.Cu")
		(net "P5E_PEX1_STN7_TX_DP<114>")
	)
	(segment
		(start 165.589712 -349.511874)
		(end 165.589712 -348.88043)
		(width 0.13462)
		(layer "F.Cu")
		(net "P5E_PEX1_STN7_TX_DP<114>")
	)
	(segment
		(start 134.543546 -322.738242)
		(end 134.543546 -319.677542)
		(width 0.1651)
		(layer "In11.Cu")
		(net "P5E_PEX1_STN7_TX_DP<114>")
	)
	(segment
		(start 165.105842 -347.1164)
		(end 140.559028 -331.42428)
		(width 0.1651)
		(layer "In11.Cu")
		(net "P5E_PEX1_STN7_TX_DP<114>")
	)
	(segment
		(start 157.993588 -302.929544)
		(end 158.270194 -303.20615)
		(width 0.1143)
		(layer "In11.Cu")
		(net "P5E_PEX1_STN7_TX_DP<114>")
	)
	(segment
		(start 136.910826 -312.94959)
		(end 142.64259 -305.23688)
		(width 0.1651)
		(layer "In11.Cu")
		(net "P5E_PEX1_STN7_TX_DP<114>")
	)
	(segment
		(start 158.359094 -303.499774)
		(end 158.649924 -303.499774)
		(width 0.1143)
		(layer "In11.Cu")
		(net "P5E_PEX1_STN7_TX_DP<114>")
	)
	(segment
		(start 165.585902 -348.29496)
		(end 165.585902 -347.805248)
		(width 0.1651)
		(layer "In11.Cu")
		(net "P5E_PEX1_STN7_TX_DP<114>")
	)
	(segment
		(start 165.295072 -348.58579)
		(end 165.585902 -348.29496)
		(width 0.1651)
		(layer "In11.Cu")
		(net "P5E_PEX1_STN7_TX_DP<114>")
	)
	(segment
		(start 151.587708 -302.929544)
		(end 157.993588 -302.929544)
		(width 0.1143)
		(layer "In11.Cu")
		(net "P5E_PEX1_STN7_TX_DP<114>")
	)
	(segment
		(start 135.443976 -325.708772)
		(end 134.543546 -322.738242)
		(width 0.1651)
		(layer "In11.Cu")
		(net "P5E_PEX1_STN7_TX_DP<114>")
	)
	(segment
		(start 151.541988 -302.883824)
		(end 151.587708 -302.929544)
		(width 0.1143)
		(layer "In11.Cu")
		(net "P5E_PEX1_STN7_TX_DP<114>")
	)
	(segment
		(start 151.51989 -302.883824)
		(end 151.541988 -302.883824)
		(width 0.1143)
		(layer "In11.Cu")
		(net "P5E_PEX1_STN7_TX_DP<114>")
	)
	(segment
		(start 158.270194 -303.410874)
		(end 158.359094 -303.499774)
		(width 0.1143)
		(layer "In11.Cu")
		(net "P5E_PEX1_STN7_TX_DP<114>")
	)
	(segment
		(start 134.93115 -317.724028)
		(end 136.910826 -312.94959)
		(width 0.1651)
		(layer "In11.Cu")
		(net "P5E_PEX1_STN7_TX_DP<114>")
	)
	(segment
		(start 165.585902 -347.805248)
		(end 165.105842 -347.1164)
		(width 0.1651)
		(layer "In11.Cu")
		(net "P5E_PEX1_STN7_TX_DP<114>")
	)
	(segment
		(start 142.64259 -305.23688)
		(end 143.903954 -303.97577)
		(width 0.1651)
		(layer "In11.Cu")
		(net "P5E_PEX1_STN7_TX_DP<114>")
	)
	(segment
		(start 137.531602 -328.830686)
		(end 135.443976 -325.708772)
		(width 0.1651)
		(layer "In11.Cu")
		(net "P5E_PEX1_STN7_TX_DP<114>")
	)
	(segment
		(start 158.270194 -303.20615)
		(end 158.270194 -303.410874)
		(width 0.1143)
		(layer "In11.Cu")
		(net "P5E_PEX1_STN7_TX_DP<114>")
	)
	(segment
		(start 140.559028 -331.42428)
		(end 137.531602 -328.830686)
		(width 0.1651)
		(layer "In11.Cu")
		(net "P5E_PEX1_STN7_TX_DP<114>")
	)
	(segment
		(start 146.539966 -302.883824)
		(end 151.51989 -302.883824)
		(width 0.1651)
		(layer "In11.Cu")
		(net "P5E_PEX1_STN7_TX_DP<114>")
	)
	(segment
		(start 143.903954 -303.97577)
		(end 146.539966 -302.883824)
		(width 0.1651)
		(layer "In11.Cu")
		(net "P5E_PEX1_STN7_TX_DP<114>")
	)
	(segment
		(start 134.543546 -319.677542)
		(end 134.93115 -317.724028)
		(width 0.1651)
		(layer "In11.Cu")
		(net "P5E_PEX1_STN7_TX_DP<114>")
	)
	(segment
		(start 313.732164 -150.67915)
		(end 313.446414 -150.3934)
		(width 0.13462)
		(layer "F.Cu")
		(net "P5E_PEX2_STN0_TX_DN<12>")
	)
	(segment
		(start 312.79719 -150.3934)
		(end 312.48604 -150.70455)
		(width 0.13462)
		(layer "F.Cu")
		(net "P5E_PEX2_STN0_TX_DN<12>")
	)
	(segment
		(start 313.446414 -150.3934)
		(end 312.79719 -150.3934)
		(width 0.13462)
		(layer "F.Cu")
		(net "P5E_PEX2_STN0_TX_DN<12>")
	)
	(segment
		(start 317.656718 -150.902416)
		(end 316.415928 -150.38832)
		(width 0.1651)
		(layer "In9.Cu")
		(net "P5E_PEX2_STN0_TX_DN<12>")
	)
	(segment
		(start 310.725058 -177.518314)
		(end 310.76265 -177.088292)
		(width 0.1651)
		(layer "In9.Cu")
		(net "P5E_PEX2_STN0_TX_DN<12>")
	)
	(segment
		(start 310.21147 -268.076934)
		(end 310.21147 -260.829806)
		(width 0.1651)
		(layer "In9.Cu")
		(net "P5E_PEX2_STN0_TX_DN<12>")
	)
	(segment
		(start 312.22315 -171.638976)
		(end 320.476626 -157.341824)
		(width 0.1651)
		(layer "In9.Cu")
		(net "P5E_PEX2_STN0_TX_DN<12>")
	)
	(segment
		(start 309.899812 -280.699718)
		(end 309.899812 -280.434288)
		(width 0.1143)
		(layer "In9.Cu")
		(net "P5E_PEX2_STN0_TX_DN<12>")
	)
	(segment
		(start 309.283862 -271.554448)
		(end 309.283862 -271.526)
		(width 0.1143)
		(layer "In9.Cu")
		(net "P5E_PEX2_STN0_TX_DN<12>")
	)
	(segment
		(start 309.54472 -280.319988)
		(end 309.329582 -280.10485)
		(width 0.1143)
		(layer "In9.Cu")
		(net "P5E_PEX2_STN0_TX_DN<12>")
	)
	(segment
		(start 310.6674 -178.176428)
		(end 310.563514 -178.05273)
		(width 0.1651)
		(layer "In9.Cu")
		(net "P5E_PEX2_STN0_TX_DN<12>")
	)
	(segment
		(start 309.621682 -269.301722)
		(end 309.72125 -269.260574)
		(width 0.1651)
		(layer "In9.Cu")
		(net "P5E_PEX2_STN0_TX_DN<12>")
	)
	(segment
		(start 306.824888 -222.097346)
		(end 308.747414 -200.12406)
		(width 0.1651)
		(layer "In9.Cu")
		(net "P5E_PEX2_STN0_TX_DN<12>")
	)
	(segment
		(start 314.022994 -150.38832)
		(end 313.732164 -150.67915)
		(width 0.1651)
		(layer "In9.Cu")
		(net "P5E_PEX2_STN0_TX_DN<12>")
	)
	(segment
		(start 310.76265 -177.088292)
		(end 312.22315 -171.638976)
		(width 0.1651)
		(layer "In9.Cu")
		(net "P5E_PEX2_STN0_TX_DN<12>")
	)
	(segment
		(start 318.338962 -151.58466)
		(end 317.656718 -150.902416)
		(width 0.1651)
		(layer "In9.Cu")
		(net "P5E_PEX2_STN0_TX_DN<12>")
	)
	(segment
		(start 309.431944 -269.759684)
		(end 309.621682 -269.301722)
		(width 0.1651)
		(layer "In9.Cu")
		(net "P5E_PEX2_STN0_TX_DN<12>")
	)
	(segment
		(start 310.601106 -177.6222)
		(end 310.725058 -177.518314)
		(width 0.1651)
		(layer "In9.Cu")
		(net "P5E_PEX2_STN0_TX_DN<12>")
	)
	(segment
		(start 309.899812 -280.434288)
		(end 309.785512 -280.319988)
		(width 0.1143)
		(layer "In9.Cu")
		(net "P5E_PEX2_STN0_TX_DN<12>")
	)
	(segment
		(start 309.785512 -280.319988)
		(end 309.54472 -280.319988)
		(width 0.1143)
		(layer "In9.Cu")
		(net "P5E_PEX2_STN0_TX_DN<12>")
	)
	(segment
		(start 320.476626 -155.236926)
		(end 319.983104 -154.044904)
		(width 0.1651)
		(layer "In9.Cu")
		(net "P5E_PEX2_STN0_TX_DN<12>")
	)
	(segment
		(start 309.72125 -269.260574)
		(end 310.21147 -268.076934)
		(width 0.1651)
		(layer "In9.Cu")
		(net "P5E_PEX2_STN0_TX_DN<12>")
	)
	(segment
		(start 319.983104 -154.044904)
		(end 318.338962 -151.58466)
		(width 0.1651)
		(layer "In9.Cu")
		(net "P5E_PEX2_STN0_TX_DN<12>")
	)
	(segment
		(start 310.563514 -178.05273)
		(end 310.601106 -177.6222)
		(width 0.1651)
		(layer "In9.Cu")
		(net "P5E_PEX2_STN0_TX_DN<12>")
	)
	(segment
		(start 309.473346 -269.859252)
		(end 309.431944 -269.759684)
		(width 0.1651)
		(layer "In9.Cu")
		(net "P5E_PEX2_STN0_TX_DN<12>")
	)
	(segment
		(start 309.283862 -271.526)
		(end 309.283862 -270.316706)
		(width 0.1651)
		(layer "In9.Cu")
		(net "P5E_PEX2_STN0_TX_DN<12>")
	)
	(segment
		(start 308.747414 -200.12406)
		(end 310.6674 -178.176428)
		(width 0.1651)
		(layer "In9.Cu")
		(net "P5E_PEX2_STN0_TX_DN<12>")
	)
	(segment
		(start 320.476626 -157.341824)
		(end 320.476626 -155.236926)
		(width 0.1651)
		(layer "In9.Cu")
		(net "P5E_PEX2_STN0_TX_DN<12>")
	)
	(segment
		(start 309.329582 -280.10485)
		(end 309.329582 -271.600168)
		(width 0.1143)
		(layer "In9.Cu")
		(net "P5E_PEX2_STN0_TX_DN<12>")
	)
	(segment
		(start 316.415928 -150.38832)
		(end 314.022994 -150.38832)
		(width 0.1651)
		(layer "In9.Cu")
		(net "P5E_PEX2_STN0_TX_DN<12>")
	)
	(segment
		(start 310.21147 -260.829806)
		(end 306.824888 -222.097346)
		(width 0.1651)
		(layer "In9.Cu")
		(net "P5E_PEX2_STN0_TX_DN<12>")
	)
	(segment
		(start 309.283862 -270.316706)
		(end 309.473346 -269.859252)
		(width 0.1651)
		(layer "In9.Cu")
		(net "P5E_PEX2_STN0_TX_DN<12>")
	)
	(segment
		(start 309.329582 -271.600168)
		(end 309.283862 -271.554448)
		(width 0.1143)
		(layer "In9.Cu")
		(net "P5E_PEX2_STN0_TX_DN<12>")
	)
	(segment
		(start 271.565878 -325.630032)
		(end 271.565878 -320.043048)
		(width 0.1651)
		(layer "In5.Cu")
		(net "P5E_PEX2_STN7_RX_DN<124>")
	)
	(segment
		(start 294.896032 -341.98814)
		(end 294.49014 -341.19058)
		(width 0.1651)
		(layer "In5.Cu")
		(net "P5E_PEX2_STN7_RX_DN<124>")
	)
	(segment
		(start 296.416984 -382.9812)
		(end 296.9641 -382.9812)
		(width 0.1651)
		(layer "In5.Cu")
		(net "P5E_PEX2_STN7_RX_DN<124>")
	)
	(segment
		(start 296.9641 -382.9812)
		(end 297.415966 -382.529334)
		(width 0.1651)
		(layer "In5.Cu")
		(net "P5E_PEX2_STN7_RX_DN<124>")
	)
	(segment
		(start 271.899888 -316.534292)
		(end 271.899888 -316.799722)
		(width 0.1143)
		(layer "In5.Cu")
		(net "P5E_PEX2_STN7_RX_DN<124>")
	)
	(segment
		(start 297.415966 -382.529334)
		(end 297.415966 -368.723926)
		(width 0.1651)
		(layer "In5.Cu")
		(net "P5E_PEX2_STN7_RX_DN<124>")
	)
	(segment
		(start 273.92122 -328.94524)
		(end 271.91716 -326.57288)
		(width 0.1651)
		(layer "In5.Cu")
		(net "P5E_PEX2_STN7_RX_DN<124>")
	)
	(segment
		(start 276.583902 -330.762864)
		(end 273.92122 -328.94524)
		(width 0.1651)
		(layer "In5.Cu")
		(net "P5E_PEX2_STN7_RX_DN<124>")
	)
	(segment
		(start 294.49014 -341.19058)
		(end 293.625524 -340.16315)
		(width 0.1651)
		(layer "In5.Cu")
		(net "P5E_PEX2_STN7_RX_DN<124>")
	)
	(segment
		(start 271.520158 -316.534292)
		(end 271.634458 -316.419992)
		(width 0.1143)
		(layer "In5.Cu")
		(net "P5E_PEX2_STN7_RX_DN<124>")
	)
	(segment
		(start 271.565878 -320.043048)
		(end 271.565878 -320.0146)
		(width 0.1143)
		(layer "In5.Cu")
		(net "P5E_PEX2_STN7_RX_DN<124>")
	)
	(segment
		(start 296.289984 -383.1082)
		(end 296.416984 -382.9812)
		(width 0.1651)
		(layer "In5.Cu")
		(net "P5E_PEX2_STN7_RX_DN<124>")
	)
	(segment
		(start 271.91716 -326.57288)
		(end 271.565878 -325.630032)
		(width 0.1651)
		(layer "In5.Cu")
		(net "P5E_PEX2_STN7_RX_DN<124>")
	)
	(segment
		(start 293.625524 -340.16315)
		(end 276.583902 -330.762864)
		(width 0.1651)
		(layer "In5.Cu")
		(net "P5E_PEX2_STN7_RX_DN<124>")
	)
	(segment
		(start 271.634458 -316.419992)
		(end 271.785588 -316.419992)
		(width 0.1143)
		(layer "In5.Cu")
		(net "P5E_PEX2_STN7_RX_DN<124>")
	)
	(segment
		(start 294.896032 -358.005126)
		(end 294.896032 -341.98814)
		(width 0.1651)
		(layer "In5.Cu")
		(net "P5E_PEX2_STN7_RX_DN<124>")
	)
	(segment
		(start 271.785588 -316.419992)
		(end 271.899888 -316.534292)
		(width 0.1143)
		(layer "In5.Cu")
		(net "P5E_PEX2_STN7_RX_DN<124>")
	)
	(segment
		(start 296.289984 -383.490216)
		(end 296.289984 -383.1082)
		(width 0.1651)
		(layer "In5.Cu")
		(net "P5E_PEX2_STN7_RX_DN<124>")
	)
	(segment
		(start 271.565878 -320.0146)
		(end 271.520158 -319.96888)
		(width 0.1143)
		(layer "In5.Cu")
		(net "P5E_PEX2_STN7_RX_DN<124>")
	)
	(segment
		(start 271.520158 -319.96888)
		(end 271.520158 -316.534292)
		(width 0.1143)
		(layer "In5.Cu")
		(net "P5E_PEX2_STN7_RX_DN<124>")
	)
	(segment
		(start 297.415966 -368.723926)
		(end 294.896032 -358.005126)
		(width 0.1651)
		(layer "In5.Cu")
		(net "P5E_PEX2_STN7_RX_DN<124>")
	)
	(segment
		(start 151.520144 -123.11888)
		(end 151.225504 -122.82424)
		(width 0.13462)
		(layer "F.Cu")
		(net "P5E_PEX1_STN1_TX_DP<26>")
	)
	(segment
		(start 152.471628 -122.79884)
		(end 152.151588 -123.11888)
		(width 0.13462)
		(layer "F.Cu")
		(net "P5E_PEX1_STN1_TX_DP<26>")
	)
	(segment
		(start 152.151588 -123.11888)
		(end 151.520144 -123.11888)
		(width 0.13462)
		(layer "F.Cu")
		(net "P5E_PEX1_STN1_TX_DP<26>")
	)
	(segment
		(start 185.24982 -278.534368)
		(end 185.24982 -278.799798)
		(width 0.1143)
		(layer "In9.Cu")
		(net "P5E_PEX1_STN1_TX_DP<26>")
	)
	(segment
		(start 184.634124 -271.471898)
		(end 184.634124 -271.500346)
		(width 0.1143)
		(layer "In9.Cu")
		(net "P5E_PEX1_STN1_TX_DP<26>")
	)
	(segment
		(start 149.93366 -161.345626)
		(end 184.634124 -263.855962)
		(width 0.1651)
		(layer "In9.Cu")
		(net "P5E_PEX1_STN1_TX_DP<26>")
	)
	(segment
		(start 149.819868 -123.47702)
		(end 145.98269 -132.741162)
		(width 0.1651)
		(layer "In9.Cu")
		(net "P5E_PEX1_STN1_TX_DP<26>")
	)
	(segment
		(start 150.181818 -123.11507)
		(end 149.819868 -123.47702)
		(width 0.1651)
		(layer "In9.Cu")
		(net "P5E_PEX1_STN1_TX_DP<26>")
	)
	(segment
		(start 148.553932 -143.223742)
		(end 149.285198 -158.085282)
		(width 0.1651)
		(layer "In9.Cu")
		(net "P5E_PEX1_STN1_TX_DP<26>")
	)
	(segment
		(start 184.894728 -278.420068)
		(end 185.13552 -278.420068)
		(width 0.1143)
		(layer "In9.Cu")
		(net "P5E_PEX1_STN1_TX_DP<26>")
	)
	(segment
		(start 149.285198 -158.085282)
		(end 149.93366 -161.345626)
		(width 0.1651)
		(layer "In9.Cu")
		(net "P5E_PEX1_STN1_TX_DP<26>")
	)
	(segment
		(start 145.98269 -137.01649)
		(end 148.553932 -143.223742)
		(width 0.1651)
		(layer "In9.Cu")
		(net "P5E_PEX1_STN1_TX_DP<26>")
	)
	(segment
		(start 150.934674 -123.11507)
		(end 150.181818 -123.11507)
		(width 0.1651)
		(layer "In9.Cu")
		(net "P5E_PEX1_STN1_TX_DP<26>")
	)
	(segment
		(start 184.679844 -278.205184)
		(end 184.894728 -278.420068)
		(width 0.1143)
		(layer "In9.Cu")
		(net "P5E_PEX1_STN1_TX_DP<26>")
	)
	(segment
		(start 185.13552 -278.420068)
		(end 185.24982 -278.534368)
		(width 0.1143)
		(layer "In9.Cu")
		(net "P5E_PEX1_STN1_TX_DP<26>")
	)
	(segment
		(start 184.679844 -271.546066)
		(end 184.679844 -278.205184)
		(width 0.1143)
		(layer "In9.Cu")
		(net "P5E_PEX1_STN1_TX_DP<26>")
	)
	(segment
		(start 151.225504 -122.82424)
		(end 150.934674 -123.11507)
		(width 0.1651)
		(layer "In9.Cu")
		(net "P5E_PEX1_STN1_TX_DP<26>")
	)
	(segment
		(start 145.98269 -132.741162)
		(end 145.98269 -137.01649)
		(width 0.1651)
		(layer "In9.Cu")
		(net "P5E_PEX1_STN1_TX_DP<26>")
	)
	(segment
		(start 184.634124 -263.855962)
		(end 184.634124 -271.471898)
		(width 0.1651)
		(layer "In9.Cu")
		(net "P5E_PEX1_STN1_TX_DP<26>")
	)
	(segment
		(start 184.634124 -271.500346)
		(end 184.679844 -271.546066)
		(width 0.1143)
		(layer "In9.Cu")
		(net "P5E_PEX1_STN1_TX_DP<26>")
	)
	(segment
		(start 124.592588 -343.365582)
		(end 124.592588 -342.734138)
		(width 0.13462)
		(layer "F.Cu")
		(net "P5E_PEX1_STN6_TX_DP<106>")
	)
	(segment
		(start 124.592588 -342.734138)
		(end 124.297948 -342.439498)
		(width 0.13462)
		(layer "F.Cu")
		(net "P5E_PEX1_STN6_TX_DP<106>")
	)
	(segment
		(start 124.272548 -343.685622)
		(end 124.592588 -343.365582)
		(width 0.13462)
		(layer "F.Cu")
		(net "P5E_PEX1_STN6_TX_DP<106>")
	)
	(segment
		(start 164.349938 -312.999882)
		(end 164.349938 -313.265312)
		(width 0.1143)
		(layer "In13.Cu")
		(net "P5E_PEX1_STN6_TX_DP<106>")
	)
	(segment
		(start 164.349938 -313.265312)
		(end 164.235638 -313.379612)
		(width 0.1143)
		(layer "In13.Cu")
		(net "P5E_PEX1_STN6_TX_DP<106>")
	)
	(segment
		(start 131.27482 -335.644236)
		(end 127.360934 -338.259674)
		(width 0.1651)
		(layer "In13.Cu")
		(net "P5E_PEX1_STN6_TX_DP<106>")
	)
	(segment
		(start 145.916396 -331.309472)
		(end 141.740128 -331.309472)
		(width 0.1651)
		(layer "In13.Cu")
		(net "P5E_PEX1_STN6_TX_DP<106>")
	)
	(segment
		(start 163.733988 -320.063114)
		(end 163.733988 -322.272152)
		(width 0.1651)
		(layer "In13.Cu")
		(net "P5E_PEX1_STN6_TX_DP<106>")
	)
	(segment
		(start 157.524958 -327.032366)
		(end 148.379434 -330.820522)
		(width 0.1651)
		(layer "In13.Cu")
		(net "P5E_PEX1_STN6_TX_DP<106>")
	)
	(segment
		(start 163.733988 -322.272152)
		(end 161.142172 -324.863968)
		(width 0.1651)
		(layer "In13.Cu")
		(net "P5E_PEX1_STN6_TX_DP<106>")
	)
	(segment
		(start 163.779708 -313.59475)
		(end 163.779708 -319.995296)
		(width 0.1143)
		(layer "In13.Cu")
		(net "P5E_PEX1_STN6_TX_DP<106>")
	)
	(segment
		(start 147.148296 -331.064616)
		(end 147.148296 -331.06487)
		(width 0.1651)
		(layer "In13.Cu")
		(net "P5E_PEX1_STN6_TX_DP<106>")
	)
	(segment
		(start 147.148296 -331.06487)
		(end 145.916396 -331.309472)
		(width 0.1651)
		(layer "In13.Cu")
		(net "P5E_PEX1_STN6_TX_DP<106>")
	)
	(segment
		(start 124.588778 -341.03183)
		(end 124.588778 -342.148668)
		(width 0.1651)
		(layer "In13.Cu")
		(net "P5E_PEX1_STN6_TX_DP<106>")
	)
	(segment
		(start 164.235638 -313.379612)
		(end 163.994846 -313.379612)
		(width 0.1143)
		(layer "In13.Cu")
		(net "P5E_PEX1_STN6_TX_DP<106>")
	)
	(segment
		(start 124.588778 -342.148668)
		(end 124.297948 -342.439498)
		(width 0.1651)
		(layer "In13.Cu")
		(net "P5E_PEX1_STN6_TX_DP<106>")
	)
	(segment
		(start 163.779708 -319.995296)
		(end 163.733988 -320.041016)
		(width 0.1143)
		(layer "In13.Cu")
		(net "P5E_PEX1_STN6_TX_DP<106>")
	)
	(segment
		(start 163.994846 -313.379612)
		(end 163.779708 -313.59475)
		(width 0.1143)
		(layer "In13.Cu")
		(net "P5E_PEX1_STN6_TX_DP<106>")
	)
	(segment
		(start 141.740128 -331.309472)
		(end 131.27482 -335.644236)
		(width 0.1651)
		(layer "In13.Cu")
		(net "P5E_PEX1_STN6_TX_DP<106>")
	)
	(segment
		(start 163.733988 -320.041016)
		(end 163.733988 -320.063114)
		(width 0.1143)
		(layer "In13.Cu")
		(net "P5E_PEX1_STN6_TX_DP<106>")
	)
	(segment
		(start 148.379434 -330.820522)
		(end 147.148296 -331.064616)
		(width 0.1651)
		(layer "In13.Cu")
		(net "P5E_PEX1_STN6_TX_DP<106>")
	)
	(segment
		(start 127.360934 -338.259674)
		(end 124.588778 -341.03183)
		(width 0.1651)
		(layer "In13.Cu")
		(net "P5E_PEX1_STN6_TX_DP<106>")
	)
	(segment
		(start 161.142172 -324.863968)
		(end 157.524958 -327.032366)
		(width 0.1651)
		(layer "In13.Cu")
		(net "P5E_PEX1_STN6_TX_DP<106>")
	)
	(segment
		(start 270.892016 -132.5372)
		(end 271.213834 -132.215382)
		(width 0.13462)
		(layer "F.Cu")
		(net "P5E_PEX2_STN1_TX_DN<29>")
	)
	(segment
		(start 270.264128 -132.5372)
		(end 270.892016 -132.5372)
		(width 0.13462)
		(layer "F.Cu")
		(net "P5E_PEX2_STN1_TX_DN<29>")
	)
	(segment
		(start 269.96771 -132.240782)
		(end 270.264128 -132.5372)
		(width 0.13462)
		(layer "F.Cu")
		(net "P5E_PEX2_STN1_TX_DN<29>")
	)
	(segment
		(start 303.583848 -271.554448)
		(end 303.583848 -271.526)
		(width 0.1143)
		(layer "In9.Cu")
		(net "P5E_PEX2_STN1_TX_DN<29>")
	)
	(segment
		(start 304.199798 -280.699718)
		(end 304.199798 -280.434288)
		(width 0.1143)
		(layer "In9.Cu")
		(net "P5E_PEX2_STN1_TX_DN<29>")
	)
	(segment
		(start 267.571728 -141.801342)
		(end 264.973562 -135.529828)
		(width 0.1651)
		(layer "In9.Cu")
		(net "P5E_PEX2_STN1_TX_DN<29>")
	)
	(segment
		(start 269.415514 -162.281108)
		(end 268.304518 -156.69641)
		(width 0.1651)
		(layer "In9.Cu")
		(net "P5E_PEX2_STN1_TX_DN<29>")
	)
	(segment
		(start 303.583848 -271.526)
		(end 303.583848 -263.217406)
		(width 0.1651)
		(layer "In9.Cu")
		(net "P5E_PEX2_STN1_TX_DN<29>")
	)
	(segment
		(start 303.629568 -280.10485)
		(end 303.629568 -271.600168)
		(width 0.1143)
		(layer "In9.Cu")
		(net "P5E_PEX2_STN1_TX_DN<29>")
	)
	(segment
		(start 264.973562 -134.743444)
		(end 265.238738 -134.103364)
		(width 0.1651)
		(layer "In9.Cu")
		(net "P5E_PEX2_STN1_TX_DN<29>")
	)
	(segment
		(start 264.973562 -135.529828)
		(end 264.973562 -134.743444)
		(width 0.1651)
		(layer "In9.Cu")
		(net "P5E_PEX2_STN1_TX_DN<29>")
	)
	(segment
		(start 303.583848 -263.217406)
		(end 269.415514 -162.281108)
		(width 0.1651)
		(layer "In9.Cu")
		(net "P5E_PEX2_STN1_TX_DN<29>")
	)
	(segment
		(start 304.199798 -280.434288)
		(end 304.085498 -280.319988)
		(width 0.1143)
		(layer "In9.Cu")
		(net "P5E_PEX2_STN1_TX_DN<29>")
	)
	(segment
		(start 304.085498 -280.319988)
		(end 303.844706 -280.319988)
		(width 0.1143)
		(layer "In9.Cu")
		(net "P5E_PEX2_STN1_TX_DN<29>")
	)
	(segment
		(start 268.304518 -156.69641)
		(end 267.571728 -141.801342)
		(width 0.1651)
		(layer "In9.Cu")
		(net "P5E_PEX2_STN1_TX_DN<29>")
	)
	(segment
		(start 303.844706 -280.319988)
		(end 303.629568 -280.10485)
		(width 0.1143)
		(layer "In9.Cu")
		(net "P5E_PEX2_STN1_TX_DN<29>")
	)
	(segment
		(start 303.629568 -271.600168)
		(end 303.583848 -271.554448)
		(width 0.1143)
		(layer "In9.Cu")
		(net "P5E_PEX2_STN1_TX_DN<29>")
	)
	(segment
		(start 266.370054 -132.972048)
		(end 267.433298 -132.531612)
		(width 0.1651)
		(layer "In9.Cu")
		(net "P5E_PEX2_STN1_TX_DN<29>")
	)
	(segment
		(start 265.238738 -134.103364)
		(end 266.370054 -132.972048)
		(width 0.1651)
		(layer "In9.Cu")
		(net "P5E_PEX2_STN1_TX_DN<29>")
	)
	(segment
		(start 267.433298 -132.531612)
		(end 269.67688 -132.531612)
		(width 0.1651)
		(layer "In9.Cu")
		(net "P5E_PEX2_STN1_TX_DN<29>")
	)
	(segment
		(start 269.67688 -132.531612)
		(end 269.96771 -132.240782)
		(width 0.1651)
		(layer "In9.Cu")
		(net "P5E_PEX2_STN1_TX_DN<29>")
	)
	(segment
		(start 130.810508 -345.170506)
		(end 130.810508 -344.539062)
		(width 0.13462)
		(layer "F.Cu")
		(net "P5E_PEX1_STN5_TX_C_DP<88>")
	)
	(segment
		(start 130.515868 -345.465146)
		(end 130.810508 -345.170506)
		(width 0.13462)
		(layer "F.Cu")
		(net "P5E_PEX1_STN5_TX_C_DP<88>")
	)
	(segment
		(start 130.810508 -344.539062)
		(end 130.490468 -344.219022)
		(width 0.13462)
		(layer "F.Cu")
		(net "P5E_PEX1_STN5_TX_C_DP<88>")
	)
	(segment
		(start 128.94945 -358.741726)
		(end 129.252218 -358.092502)
		(width 0.1651)
		(layer "In13.Cu")
		(net "P5E_PEX1_STN5_TX_C_DP<88>")
	)
	(segment
		(start 115.910106 -378.67209)
		(end 116.037106 -378.79909)
		(width 0.1651)
		(layer "In13.Cu")
		(net "P5E_PEX1_STN5_TX_C_DP<88>")
	)
	(segment
		(start 130.806698 -345.755976)
		(end 130.515868 -345.465146)
		(width 0.1651)
		(layer "In13.Cu")
		(net "P5E_PEX1_STN5_TX_C_DP<88>")
	)
	(segment
		(start 129.252218 -355.79685)
		(end 129.252218 -347.974666)
		(width 0.1651)
		(layer "In13.Cu")
		(net "P5E_PEX1_STN5_TX_C_DP<88>")
	)
	(segment
		(start 126.681992 -360.645202)
		(end 126.694438 -360.501946)
		(width 0.1651)
		(layer "In13.Cu")
		(net "P5E_PEX1_STN5_TX_C_DP<88>")
	)
	(segment
		(start 116.037106 -378.79909)
		(end 116.258594 -378.79909)
		(width 0.1651)
		(layer "In13.Cu")
		(net "P5E_PEX1_STN5_TX_C_DP<88>")
	)
	(segment
		(start 128.13157 -359.428288)
		(end 128.94945 -358.741726)
		(width 0.1651)
		(layer "In13.Cu")
		(net "P5E_PEX1_STN5_TX_C_DP<88>")
	)
	(segment
		(start 129.1844 -356.452932)
		(end 129.1844 -355.864668)
		(width 0.1651)
		(layer "In13.Cu")
		(net "P5E_PEX1_STN5_TX_C_DP<88>")
	)
	(segment
		(start 127.988568 -359.415588)
		(end 128.13157 -359.428288)
		(width 0.1651)
		(layer "In13.Cu")
		(net "P5E_PEX1_STN5_TX_C_DP<88>")
	)
	(segment
		(start 129.1844 -355.864668)
		(end 129.252218 -355.79685)
		(width 0.1651)
		(layer "In13.Cu")
		(net "P5E_PEX1_STN5_TX_C_DP<88>")
	)
	(segment
		(start 126.694438 -360.501946)
		(end 127.074168 -360.18343)
		(width 0.1651)
		(layer "In13.Cu")
		(net "P5E_PEX1_STN5_TX_C_DP<88>")
	)
	(segment
		(start 116.258594 -378.79909)
		(end 116.784882 -378.272802)
		(width 0.1651)
		(layer "In13.Cu")
		(net "P5E_PEX1_STN5_TX_C_DP<88>")
	)
	(segment
		(start 129.252218 -347.974666)
		(end 130.806698 -346.420186)
		(width 0.1651)
		(layer "In13.Cu")
		(net "P5E_PEX1_STN5_TX_C_DP<88>")
	)
	(segment
		(start 129.252218 -356.52075)
		(end 129.1844 -356.452932)
		(width 0.1651)
		(layer "In13.Cu")
		(net "P5E_PEX1_STN5_TX_C_DP<88>")
	)
	(segment
		(start 116.784882 -369.626642)
		(end 117.299994 -368.520726)
		(width 0.1651)
		(layer "In13.Cu")
		(net "P5E_PEX1_STN5_TX_C_DP<88>")
	)
	(segment
		(start 129.252218 -358.092502)
		(end 129.252218 -356.52075)
		(width 0.1651)
		(layer "In13.Cu")
		(net "P5E_PEX1_STN5_TX_C_DP<88>")
	)
	(segment
		(start 130.806698 -346.420186)
		(end 130.806698 -345.755976)
		(width 0.1651)
		(layer "In13.Cu")
		(net "P5E_PEX1_STN5_TX_C_DP<88>")
	)
	(segment
		(start 117.299994 -368.520726)
		(end 126.681992 -360.645202)
		(width 0.1651)
		(layer "In13.Cu")
		(net "P5E_PEX1_STN5_TX_C_DP<88>")
	)
	(segment
		(start 115.910106 -378.290074)
		(end 115.910106 -378.67209)
		(width 0.1651)
		(layer "In13.Cu")
		(net "P5E_PEX1_STN5_TX_C_DP<88>")
	)
	(segment
		(start 116.784882 -378.272802)
		(end 116.784882 -369.626642)
		(width 0.1651)
		(layer "In13.Cu")
		(net "P5E_PEX1_STN5_TX_C_DP<88>")
	)
	(segment
		(start 127.608838 -359.734358)
		(end 127.988568 -359.415588)
		(width 0.1651)
		(layer "In13.Cu")
		(net "P5E_PEX1_STN5_TX_C_DP<88>")
	)
	(segment
		(start 127.074168 -360.18343)
		(end 127.21717 -360.195876)
		(width 0.1651)
		(layer "In13.Cu")
		(net "P5E_PEX1_STN5_TX_C_DP<88>")
	)
	(segment
		(start 127.21717 -360.195876)
		(end 127.596392 -359.877614)
		(width 0.1651)
		(layer "In13.Cu")
		(net "P5E_PEX1_STN5_TX_C_DP<88>")
	)
	(segment
		(start 127.596392 -359.877614)
		(end 127.608838 -359.734358)
		(width 0.1651)
		(layer "In13.Cu")
		(net "P5E_PEX1_STN5_TX_C_DP<88>")
	)
	(segment
		(start 152.151588 -119.793258)
		(end 151.520144 -119.793258)
		(width 0.13462)
		(layer "F.Cu")
		(net "P5E_PEX1_STN1_TX_DN<24>")
	)
	(segment
		(start 152.471628 -120.113298)
		(end 152.151588 -119.793258)
		(width 0.13462)
		(layer "F.Cu")
		(net "P5E_PEX1_STN1_TX_DN<24>")
	)
	(segment
		(start 151.520144 -119.793258)
		(end 151.225504 -120.087898)
		(width 0.13462)
		(layer "F.Cu")
		(net "P5E_PEX1_STN1_TX_DN<24>")
	)
	(segment
		(start 147.522946 -124.151136)
		(end 147.578064 -124.283724)
		(width 0.1651)
		(layer "In9.Cu")
		(net "P5E_PEX1_STN1_TX_DN<24>")
	)
	(segment
		(start 147.707604 -123.705366)
		(end 147.522946 -124.151136)
		(width 0.1651)
		(layer "In9.Cu")
		(net "P5E_PEX1_STN1_TX_DN<24>")
	)
	(segment
		(start 144.32915 -137.396474)
		(end 146.884136 -143.564356)
		(width 0.1651)
		(layer "In9.Cu")
		(net "P5E_PEX1_STN1_TX_DN<24>")
	)
	(segment
		(start 146.181318 -127.38989)
		(end 146.236436 -127.522478)
		(width 0.1651)
		(layer "In9.Cu")
		(net "P5E_PEX1_STN1_TX_DN<24>")
	)
	(segment
		(start 150.934674 -119.797068)
		(end 150.298658 -119.797068)
		(width 0.1651)
		(layer "In9.Cu")
		(net "P5E_PEX1_STN1_TX_DN<24>")
	)
	(segment
		(start 146.365976 -126.943866)
		(end 146.365976 -126.94412)
		(width 0.1651)
		(layer "In9.Cu")
		(net "P5E_PEX1_STN1_TX_DN<24>")
	)
	(segment
		(start 147.26031 -124.784866)
		(end 147.075652 -125.230636)
		(width 0.1651)
		(layer "In9.Cu")
		(net "P5E_PEX1_STN1_TX_DN<24>")
	)
	(segment
		(start 148.472144 -122.124724)
		(end 148.287486 -122.571002)
		(width 0.1651)
		(layer "In9.Cu")
		(net "P5E_PEX1_STN1_TX_DN<24>")
	)
	(segment
		(start 145.264124 -129.604516)
		(end 145.319242 -129.737104)
		(width 0.1651)
		(layer "In9.Cu")
		(net "P5E_PEX1_STN1_TX_DN<24>")
	)
	(segment
		(start 149.388576 -120.868694)
		(end 149.227032 -120.868694)
		(width 0.1651)
		(layer "In9.Cu")
		(net "P5E_PEX1_STN1_TX_DN<24>")
	)
	(segment
		(start 145.734024 -128.469644)
		(end 145.789142 -128.602232)
		(width 0.1651)
		(layer "In9.Cu")
		(net "P5E_PEX1_STN1_TX_DN<24>")
	)
	(segment
		(start 147.969986 -123.071636)
		(end 148.025104 -123.204224)
		(width 0.1651)
		(layer "In9.Cu")
		(net "P5E_PEX1_STN1_TX_DN<24>")
	)
	(segment
		(start 183.01589 -271.500346)
		(end 182.97017 -271.546066)
		(width 0.1143)
		(layer "In9.Cu")
		(net "P5E_PEX1_STN1_TX_DN<24>")
	)
	(segment
		(start 146.68373 -126.442724)
		(end 146.499072 -126.889002)
		(width 0.1651)
		(layer "In9.Cu")
		(net "P5E_PEX1_STN1_TX_DN<24>")
	)
	(segment
		(start 146.628612 -126.310136)
		(end 146.68373 -126.442724)
		(width 0.1651)
		(layer "In9.Cu")
		(net "P5E_PEX1_STN1_TX_DN<24>")
	)
	(segment
		(start 150.298658 -119.797068)
		(end 149.729952 -120.365774)
		(width 0.1651)
		(layer "In9.Cu")
		(net "P5E_PEX1_STN1_TX_DN<24>")
	)
	(segment
		(start 146.946112 -125.809502)
		(end 146.813016 -125.864366)
		(width 0.1651)
		(layer "In9.Cu")
		(net "P5E_PEX1_STN1_TX_DN<24>")
	)
	(segment
		(start 147.13077 -125.363224)
		(end 146.946112 -125.809502)
		(width 0.1651)
		(layer "In9.Cu")
		(net "P5E_PEX1_STN1_TX_DN<24>")
	)
	(segment
		(start 146.884136 -143.564356)
		(end 147.616418 -158.457646)
		(width 0.1651)
		(layer "In9.Cu")
		(net "P5E_PEX1_STN1_TX_DN<24>")
	)
	(segment
		(start 145.001488 -130.238246)
		(end 144.32915 -131.861306)
		(width 0.1651)
		(layer "In9.Cu")
		(net "P5E_PEX1_STN1_TX_DN<24>")
	)
	(segment
		(start 146.365976 -126.94412)
		(end 146.181318 -127.38989)
		(width 0.1651)
		(layer "In9.Cu")
		(net "P5E_PEX1_STN1_TX_DN<24>")
	)
	(segment
		(start 145.471388 -129.103374)
		(end 145.471642 -129.103374)
		(width 0.1651)
		(layer "In9.Cu")
		(net "P5E_PEX1_STN1_TX_DN<24>")
	)
	(segment
		(start 148.287486 -122.571002)
		(end 148.154644 -122.625866)
		(width 0.1651)
		(layer "In9.Cu")
		(net "P5E_PEX1_STN1_TX_DN<24>")
	)
	(segment
		(start 148.639022 -121.456958)
		(end 148.41728 -121.992136)
		(width 0.1651)
		(layer "In9.Cu")
		(net "P5E_PEX1_STN1_TX_DN<24>")
	)
	(segment
		(start 147.393406 -124.730002)
		(end 147.26031 -124.784866)
		(width 0.1651)
		(layer "In9.Cu")
		(net "P5E_PEX1_STN1_TX_DN<24>")
	)
	(segment
		(start 183.01589 -271.471898)
		(end 183.01589 -271.500346)
		(width 0.1143)
		(layer "In9.Cu")
		(net "P5E_PEX1_STN1_TX_DN<24>")
	)
	(segment
		(start 182.97017 -278.12619)
		(end 183.073548 -278.229568)
		(width 0.1143)
		(layer "In9.Cu")
		(net "P5E_PEX1_STN1_TX_DN<24>")
	)
	(segment
		(start 148.025104 -123.204224)
		(end 147.840446 -123.650502)
		(width 0.1651)
		(layer "In9.Cu")
		(net "P5E_PEX1_STN1_TX_DN<24>")
	)
	(segment
		(start 147.840446 -123.650502)
		(end 147.70735 -123.705366)
		(width 0.1651)
		(layer "In9.Cu")
		(net "P5E_PEX1_STN1_TX_DN<24>")
	)
	(segment
		(start 147.70735 -123.705366)
		(end 147.707604 -123.705366)
		(width 0.1651)
		(layer "In9.Cu")
		(net "P5E_PEX1_STN1_TX_DN<24>")
	)
	(segment
		(start 182.97017 -271.546066)
		(end 182.97017 -278.12619)
		(width 0.1143)
		(layer "In9.Cu")
		(net "P5E_PEX1_STN1_TX_DN<24>")
	)
	(segment
		(start 183.01589 -264.235184)
		(end 183.01589 -271.471898)
		(width 0.1651)
		(layer "In9.Cu")
		(net "P5E_PEX1_STN1_TX_DN<24>")
	)
	(segment
		(start 146.81327 -125.864366)
		(end 146.628612 -126.310136)
		(width 0.1651)
		(layer "In9.Cu")
		(net "P5E_PEX1_STN1_TX_DN<24>")
	)
	(segment
		(start 146.051778 -127.968756)
		(end 145.918682 -128.02362)
		(width 0.1651)
		(layer "In9.Cu")
		(net "P5E_PEX1_STN1_TX_DN<24>")
	)
	(segment
		(start 183.073548 -278.229568)
		(end 183.235346 -278.229568)
		(width 0.1143)
		(layer "In9.Cu")
		(net "P5E_PEX1_STN1_TX_DN<24>")
	)
	(segment
		(start 148.41728 -121.992136)
		(end 148.472144 -122.124724)
		(width 0.1651)
		(layer "In9.Cu")
		(net "P5E_PEX1_STN1_TX_DN<24>")
	)
	(segment
		(start 146.499072 -126.889002)
		(end 146.365976 -126.943866)
		(width 0.1651)
		(layer "In9.Cu")
		(net "P5E_PEX1_STN1_TX_DN<24>")
	)
	(segment
		(start 147.578064 -124.283724)
		(end 147.393406 -124.730002)
		(width 0.1651)
		(layer "In9.Cu")
		(net "P5E_PEX1_STN1_TX_DN<24>")
	)
	(segment
		(start 147.075652 -125.230636)
		(end 147.13077 -125.363224)
		(width 0.1651)
		(layer "In9.Cu")
		(net "P5E_PEX1_STN1_TX_DN<24>")
	)
	(segment
		(start 144.32915 -131.861306)
		(end 144.32915 -137.396474)
		(width 0.1651)
		(layer "In9.Cu")
		(net "P5E_PEX1_STN1_TX_DN<24>")
	)
	(segment
		(start 148.19503 -161.3662)
		(end 183.01589 -264.235184)
		(width 0.1651)
		(layer "In9.Cu")
		(net "P5E_PEX1_STN1_TX_DN<24>")
	)
	(segment
		(start 149.729952 -120.365774)
		(end 149.729952 -120.527318)
		(width 0.1651)
		(layer "In9.Cu")
		(net "P5E_PEX1_STN1_TX_DN<24>")
	)
	(segment
		(start 145.319242 -129.737104)
		(end 145.13433 -130.183382)
		(width 0.1651)
		(layer "In9.Cu")
		(net "P5E_PEX1_STN1_TX_DN<24>")
	)
	(segment
		(start 145.918682 -128.023874)
		(end 145.734024 -128.469644)
		(width 0.1651)
		(layer "In9.Cu")
		(net "P5E_PEX1_STN1_TX_DN<24>")
	)
	(segment
		(start 145.789142 -128.602232)
		(end 145.604484 -129.04851)
		(width 0.1651)
		(layer "In9.Cu")
		(net "P5E_PEX1_STN1_TX_DN<24>")
	)
	(segment
		(start 145.471642 -129.103374)
		(end 145.264124 -129.604516)
		(width 0.1651)
		(layer "In9.Cu")
		(net "P5E_PEX1_STN1_TX_DN<24>")
	)
	(segment
		(start 183.235346 -278.229568)
		(end 183.349646 -278.115268)
		(width 0.1143)
		(layer "In9.Cu")
		(net "P5E_PEX1_STN1_TX_DN<24>")
	)
	(segment
		(start 149.227032 -120.868694)
		(end 148.639022 -121.456958)
		(width 0.1651)
		(layer "In9.Cu")
		(net "P5E_PEX1_STN1_TX_DN<24>")
	)
	(segment
		(start 145.918682 -128.02362)
		(end 145.918682 -128.023874)
		(width 0.1651)
		(layer "In9.Cu")
		(net "P5E_PEX1_STN1_TX_DN<24>")
	)
	(segment
		(start 145.604484 -129.04851)
		(end 145.471388 -129.103374)
		(width 0.1651)
		(layer "In9.Cu")
		(net "P5E_PEX1_STN1_TX_DN<24>")
	)
	(segment
		(start 146.236436 -127.522478)
		(end 146.051778 -127.968756)
		(width 0.1651)
		(layer "In9.Cu")
		(net "P5E_PEX1_STN1_TX_DN<24>")
	)
	(segment
		(start 183.349646 -278.115268)
		(end 183.349646 -277.849838)
		(width 0.1143)
		(layer "In9.Cu")
		(net "P5E_PEX1_STN1_TX_DN<24>")
	)
	(segment
		(start 145.13433 -130.183382)
		(end 145.001488 -130.238246)
		(width 0.1651)
		(layer "In9.Cu")
		(net "P5E_PEX1_STN1_TX_DN<24>")
	)
	(segment
		(start 146.813016 -125.864366)
		(end 146.81327 -125.864366)
		(width 0.1651)
		(layer "In9.Cu")
		(net "P5E_PEX1_STN1_TX_DN<24>")
	)
	(segment
		(start 147.616418 -158.457646)
		(end 148.19503 -161.3662)
		(width 0.1651)
		(layer "In9.Cu")
		(net "P5E_PEX1_STN1_TX_DN<24>")
	)
	(segment
		(start 149.729952 -120.527318)
		(end 149.388576 -120.868694)
		(width 0.1651)
		(layer "In9.Cu")
		(net "P5E_PEX1_STN1_TX_DN<24>")
	)
	(segment
		(start 151.225504 -120.087898)
		(end 150.934674 -119.797068)
		(width 0.1651)
		(layer "In9.Cu")
		(net "P5E_PEX1_STN1_TX_DN<24>")
	)
	(segment
		(start 148.154644 -122.625866)
		(end 147.969986 -123.071636)
		(width 0.1651)
		(layer "In9.Cu")
		(net "P5E_PEX1_STN1_TX_DN<24>")
	)
	(segment
		(start 171.487592 -349.831914)
		(end 171.807632 -349.511874)
		(width 0.13462)
		(layer "F.Cu")
		(net "P5E_PEX1_STN7_TX_DP<117>")
	)
	(segment
		(start 171.807632 -349.511874)
		(end 171.807632 -348.88043)
		(width 0.13462)
		(layer "F.Cu")
		(net "P5E_PEX1_STN7_TX_DP<117>")
	)
	(segment
		(start 171.807632 -348.88043)
		(end 171.512992 -348.58579)
		(width 0.13462)
		(layer "F.Cu")
		(net "P5E_PEX1_STN7_TX_DP<117>")
	)
	(segment
		(start 138.995912 -315.438028)
		(end 137.710926 -318.53759)
		(width 0.1651)
		(layer "In11.Cu")
		(net "P5E_PEX1_STN7_TX_DP<117>")
	)
	(segment
		(start 171.803822 -347.586554)
		(end 171.803822 -348.29496)
		(width 0.1651)
		(layer "In11.Cu")
		(net "P5E_PEX1_STN7_TX_DP<117>")
	)
	(segment
		(start 173.358302 -346.032074)
		(end 171.803822 -347.586554)
		(width 0.1651)
		(layer "In11.Cu")
		(net "P5E_PEX1_STN7_TX_DP<117>")
	)
	(segment
		(start 173.358048 -341.841582)
		(end 173.358302 -341.841836)
		(width 0.1651)
		(layer "In11.Cu")
		(net "P5E_PEX1_STN7_TX_DP<117>")
	)
	(segment
		(start 160.170114 -306.261008)
		(end 160.170114 -306.003198)
		(width 0.1143)
		(layer "In11.Cu")
		(net "P5E_PEX1_STN7_TX_DP<117>")
	)
	(segment
		(start 173.358302 -341.841836)
		(end 173.358302 -346.032074)
		(width 0.1651)
		(layer "In11.Cu")
		(net "P5E_PEX1_STN7_TX_DP<117>")
	)
	(segment
		(start 171.803822 -348.29496)
		(end 171.512992 -348.58579)
		(width 0.1651)
		(layer "In11.Cu")
		(net "P5E_PEX1_STN7_TX_DP<117>")
	)
	(segment
		(start 140.079222 -327.116694)
		(end 140.603224 -327.565766)
		(width 0.1651)
		(layer "In11.Cu")
		(net "P5E_PEX1_STN7_TX_DP<117>")
	)
	(segment
		(start 151.52243 -305.733958)
		(end 151.500332 -305.733958)
		(width 0.1143)
		(layer "In11.Cu")
		(net "P5E_PEX1_STN7_TX_DP<117>")
	)
	(segment
		(start 172.945044 -341.291926)
		(end 172.945298 -341.291926)
		(width 0.1651)
		(layer "In11.Cu")
		(net "P5E_PEX1_STN7_TX_DP<117>")
	)
	(segment
		(start 139.883896 -314.219336)
		(end 139.443206 -314.82411)
		(width 0.1651)
		(layer "In11.Cu")
		(net "P5E_PEX1_STN7_TX_DP<117>")
	)
	(segment
		(start 148.202904 -331.571346)
		(end 167.748458 -338.818474)
		(width 0.1651)
		(layer "In11.Cu")
		(net "P5E_PEX1_STN7_TX_DP<117>")
	)
	(segment
		(start 148.973286 -305.733958)
		(end 147.970494 -306.132738)
		(width 0.1651)
		(layer "In11.Cu")
		(net "P5E_PEX1_STN7_TX_DP<117>")
	)
	(segment
		(start 151.500332 -305.733958)
		(end 148.973286 -305.733958)
		(width 0.1651)
		(layer "In11.Cu")
		(net "P5E_PEX1_STN7_TX_DP<117>")
	)
	(segment
		(start 137.41781 -322.243196)
		(end 138.104372 -324.507606)
		(width 0.1651)
		(layer "In11.Cu")
		(net "P5E_PEX1_STN7_TX_DP<117>")
	)
	(segment
		(start 172.873416 -341.242396)
		(end 172.945044 -341.291926)
		(width 0.1651)
		(layer "In11.Cu")
		(net "P5E_PEX1_STN7_TX_DP<117>")
	)
	(segment
		(start 139.539726 -326.654414)
		(end 140.079222 -327.116694)
		(width 0.1651)
		(layer "In11.Cu")
		(net "P5E_PEX1_STN7_TX_DP<117>")
	)
	(segment
		(start 160.259014 -306.349908)
		(end 160.170114 -306.261008)
		(width 0.1143)
		(layer "In11.Cu")
		(net "P5E_PEX1_STN7_TX_DP<117>")
	)
	(segment
		(start 140.603224 -327.565766)
		(end 143.398494 -329.37831)
		(width 0.1651)
		(layer "In11.Cu")
		(net "P5E_PEX1_STN7_TX_DP<117>")
	)
	(segment
		(start 147.970494 -306.132738)
		(end 139.883896 -314.219336)
		(width 0.1651)
		(layer "In11.Cu")
		(net "P5E_PEX1_STN7_TX_DP<117>")
	)
	(segment
		(start 160.170114 -306.003198)
		(end 159.946594 -305.779678)
		(width 0.1143)
		(layer "In11.Cu")
		(net "P5E_PEX1_STN7_TX_DP<117>")
	)
	(segment
		(start 137.710926 -318.53759)
		(end 137.41781 -320.016632)
		(width 0.1651)
		(layer "In11.Cu")
		(net "P5E_PEX1_STN7_TX_DP<117>")
	)
	(segment
		(start 151.56815 -305.779678)
		(end 151.52243 -305.733958)
		(width 0.1143)
		(layer "In11.Cu")
		(net "P5E_PEX1_STN7_TX_DP<117>")
	)
	(segment
		(start 148.193506 -331.567028)
		(end 148.193252 -331.567028)
		(width 0.1651)
		(layer "In11.Cu")
		(net "P5E_PEX1_STN7_TX_DP<117>")
	)
	(segment
		(start 139.443206 -314.82411)
		(end 139.442952 -314.824364)
		(width 0.1651)
		(layer "In11.Cu")
		(net "P5E_PEX1_STN7_TX_DP<117>")
	)
	(segment
		(start 139.442952 -314.824364)
		(end 138.995912 -315.438028)
		(width 0.1651)
		(layer "In11.Cu")
		(net "P5E_PEX1_STN7_TX_DP<117>")
	)
	(segment
		(start 148.193252 -331.567028)
		(end 148.202904 -331.571346)
		(width 0.1651)
		(layer "In11.Cu")
		(net "P5E_PEX1_STN7_TX_DP<117>")
	)
	(segment
		(start 172.873162 -341.242396)
		(end 172.873416 -341.242396)
		(width 0.1651)
		(layer "In11.Cu")
		(net "P5E_PEX1_STN7_TX_DP<117>")
	)
	(segment
		(start 172.945298 -341.291926)
		(end 173.358048 -341.841582)
		(width 0.1651)
		(layer "In11.Cu")
		(net "P5E_PEX1_STN7_TX_DP<117>")
	)
	(segment
		(start 160.549844 -306.349908)
		(end 160.259014 -306.349908)
		(width 0.1143)
		(layer "In11.Cu")
		(net "P5E_PEX1_STN7_TX_DP<117>")
	)
	(segment
		(start 167.748458 -338.818474)
		(end 172.873162 -341.242396)
		(width 0.1651)
		(layer "In11.Cu")
		(net "P5E_PEX1_STN7_TX_DP<117>")
	)
	(segment
		(start 143.398494 -329.37831)
		(end 148.193506 -331.567028)
		(width 0.1651)
		(layer "In11.Cu")
		(net "P5E_PEX1_STN7_TX_DP<117>")
	)
	(segment
		(start 138.104372 -324.507606)
		(end 139.539726 -326.654414)
		(width 0.1651)
		(layer "In11.Cu")
		(net "P5E_PEX1_STN7_TX_DP<117>")
	)
	(segment
		(start 159.946594 -305.779678)
		(end 151.56815 -305.779678)
		(width 0.1143)
		(layer "In11.Cu")
		(net "P5E_PEX1_STN7_TX_DP<117>")
	)
	(segment
		(start 137.41781 -320.016632)
		(end 137.41781 -322.243196)
		(width 0.1651)
		(layer "In11.Cu")
		(net "P5E_PEX1_STN7_TX_DP<117>")
	)
	(segment
		(start 312.810906 -143.1798)
		(end 312.48604 -143.504666)
		(width 0.13462)
		(layer "F.Cu")
		(net "P5E_PEX2_STN0_TX_DP<8>")
	)
	(segment
		(start 313.432698 -143.1798)
		(end 312.810906 -143.1798)
		(width 0.13462)
		(layer "F.Cu")
		(net "P5E_PEX2_STN0_TX_DP<8>")
	)
	(segment
		(start 313.732164 -143.479266)
		(end 313.432698 -143.1798)
		(width 0.13462)
		(layer "F.Cu")
		(net "P5E_PEX2_STN0_TX_DP<8>")
	)
	(segment
		(start 317.459614 -143.669512)
		(end 318.566292 -144.77619)
		(width 0.1651)
		(layer "In9.Cu")
		(net "P5E_PEX2_STN0_TX_DP<8>")
	)
	(segment
		(start 314.08243 -260.280912)
		(end 314.08243 -261.21614)
		(width 0.1651)
		(layer "In9.Cu")
		(net "P5E_PEX2_STN0_TX_DP<8>")
	)
	(segment
		(start 321.622928 -148.154898)
		(end 321.622674 -148.154898)
		(width 0.1651)
		(layer "In9.Cu")
		(net "P5E_PEX2_STN0_TX_DP<8>")
	)
	(segment
		(start 314.079636 -276.785578)
		(end 313.965336 -276.899878)
		(width 0.1143)
		(layer "In9.Cu")
		(net "P5E_PEX2_STN0_TX_DP<8>")
	)
	(segment
		(start 320.97345 -147.183348)
		(end 321.248532 -147.595082)
		(width 0.1651)
		(layer "In9.Cu")
		(net "P5E_PEX2_STN0_TX_DP<8>")
	)
	(segment
		(start 324.347586 -154.332686)
		(end 324.347586 -158.440882)
		(width 0.1651)
		(layer "In9.Cu")
		(net "P5E_PEX2_STN0_TX_DP<8>")
	)
	(segment
		(start 310.741822 -222.047308)
		(end 314.08243 -260.280912)
		(width 0.1651)
		(layer "In9.Cu")
		(net "P5E_PEX2_STN0_TX_DP<8>")
	)
	(segment
		(start 314.022994 -143.188436)
		(end 314.498228 -143.188436)
		(width 0.1651)
		(layer "In9.Cu")
		(net "P5E_PEX2_STN0_TX_DP<8>")
	)
	(segment
		(start 314.498228 -143.188436)
		(end 315.010038 -142.9766)
		(width 0.1651)
		(layer "In9.Cu")
		(net "P5E_PEX2_STN0_TX_DP<8>")
	)
	(segment
		(start 322.20027 -149.38121)
		(end 322.390262 -149.839172)
		(width 0.1651)
		(layer "In9.Cu")
		(net "P5E_PEX2_STN0_TX_DP<8>")
	)
	(segment
		(start 319.868804 -146.078702)
		(end 320.270124 -146.480022)
		(width 0.1651)
		(layer "In9.Cu")
		(net "P5E_PEX2_STN0_TX_DP<8>")
	)
	(segment
		(start 320.74612 -146.956018)
		(end 320.97345 -147.183348)
		(width 0.1651)
		(layer "In9.Cu")
		(net "P5E_PEX2_STN0_TX_DP<8>")
	)
	(segment
		(start 315.02985 -276.183598)
		(end 314.8965 -276.316948)
		(width 0.1143)
		(layer "In9.Cu")
		(net "P5E_PEX2_STN0_TX_DP<8>")
	)
	(segment
		(start 314.8965 -276.316948)
		(end 314.327794 -276.316948)
		(width 0.1143)
		(layer "In9.Cu")
		(net "P5E_PEX2_STN0_TX_DP<8>")
	)
	(segment
		(start 320.62039 -146.956018)
		(end 320.74612 -146.956018)
		(width 0.1651)
		(layer "In9.Cu")
		(net "P5E_PEX2_STN0_TX_DP<8>")
	)
	(segment
		(start 316.29223 -143.282162)
		(end 316.750192 -143.4719)
		(width 0.1651)
		(layer "In9.Cu")
		(net "P5E_PEX2_STN0_TX_DP<8>")
	)
	(segment
		(start 315.010038 -142.9766)
		(end 315.78677 -142.9766)
		(width 0.1651)
		(layer "In9.Cu")
		(net "P5E_PEX2_STN0_TX_DP<8>")
	)
	(segment
		(start 314.327794 -276.316948)
		(end 314.079636 -276.565106)
		(width 0.1143)
		(layer "In9.Cu")
		(net "P5E_PEX2_STN0_TX_DP<8>")
	)
	(segment
		(start 322.24853 -149.265132)
		(end 322.20027 -149.38121)
		(width 0.1651)
		(layer "In9.Cu")
		(net "P5E_PEX2_STN0_TX_DP<8>")
	)
	(segment
		(start 319.392554 -145.602452)
		(end 319.392554 -145.728182)
		(width 0.1651)
		(layer "In9.Cu")
		(net "P5E_PEX2_STN0_TX_DP<8>")
	)
	(segment
		(start 314.079636 -276.565106)
		(end 314.079636 -276.785578)
		(width 0.1143)
		(layer "In9.Cu")
		(net "P5E_PEX2_STN0_TX_DP<8>")
	)
	(segment
		(start 314.08243 -261.21614)
		(end 314.98413 -270.372078)
		(width 0.1651)
		(layer "In9.Cu")
		(net "P5E_PEX2_STN0_TX_DP<8>")
	)
	(segment
		(start 314.98413 -270.372078)
		(end 314.98413 -271.776952)
		(width 0.1651)
		(layer "In9.Cu")
		(net "P5E_PEX2_STN0_TX_DP<8>")
	)
	(segment
		(start 322.390262 -149.839172)
		(end 322.50634 -149.887178)
		(width 0.1651)
		(layer "In9.Cu")
		(net "P5E_PEX2_STN0_TX_DP<8>")
	)
	(segment
		(start 314.98413 -271.8054)
		(end 315.02985 -271.85112)
		(width 0.1143)
		(layer "In9.Cu")
		(net "P5E_PEX2_STN0_TX_DP<8>")
	)
	(segment
		(start 315.78677 -142.9766)
		(end 316.244224 -143.166084)
		(width 0.1651)
		(layer "In9.Cu")
		(net "P5E_PEX2_STN0_TX_DP<8>")
	)
	(segment
		(start 316.750192 -143.4719)
		(end 316.86627 -143.423894)
		(width 0.1651)
		(layer "In9.Cu")
		(net "P5E_PEX2_STN0_TX_DP<8>")
	)
	(segment
		(start 316.86627 -143.423894)
		(end 317.459614 -143.669512)
		(width 0.1651)
		(layer "In9.Cu")
		(net "P5E_PEX2_STN0_TX_DP<8>")
	)
	(segment
		(start 320.270124 -146.480022)
		(end 320.270124 -146.605752)
		(width 0.1651)
		(layer "In9.Cu")
		(net "P5E_PEX2_STN0_TX_DP<8>")
	)
	(segment
		(start 319.042542 -145.25244)
		(end 319.392554 -145.602452)
		(width 0.1651)
		(layer "In9.Cu")
		(net "P5E_PEX2_STN0_TX_DP<8>")
	)
	(segment
		(start 313.732164 -143.479266)
		(end 314.022994 -143.188436)
		(width 0.1651)
		(layer "In9.Cu")
		(net "P5E_PEX2_STN0_TX_DP<8>")
	)
	(segment
		(start 321.224148 -147.718272)
		(end 321.499484 -148.13026)
		(width 0.1651)
		(layer "In9.Cu")
		(net "P5E_PEX2_STN0_TX_DP<8>")
	)
	(segment
		(start 318.916812 -145.25244)
		(end 319.042542 -145.25244)
		(width 0.1651)
		(layer "In9.Cu")
		(net "P5E_PEX2_STN0_TX_DP<8>")
	)
	(segment
		(start 319.392554 -145.728182)
		(end 319.743074 -146.078702)
		(width 0.1651)
		(layer "In9.Cu")
		(net "P5E_PEX2_STN0_TX_DP<8>")
	)
	(segment
		(start 321.248532 -147.595082)
		(end 321.224148 -147.718272)
		(width 0.1651)
		(layer "In9.Cu")
		(net "P5E_PEX2_STN0_TX_DP<8>")
	)
	(segment
		(start 322.059046 -148.807678)
		(end 322.24853 -149.265132)
		(width 0.1651)
		(layer "In9.Cu")
		(net "P5E_PEX2_STN0_TX_DP<8>")
	)
	(segment
		(start 314.98413 -271.776952)
		(end 314.98413 -271.8054)
		(width 0.1143)
		(layer "In9.Cu")
		(net "P5E_PEX2_STN0_TX_DP<8>")
	)
	(segment
		(start 316.244224 -143.166084)
		(end 316.29223 -143.282162)
		(width 0.1651)
		(layer "In9.Cu")
		(net "P5E_PEX2_STN0_TX_DP<8>")
	)
	(segment
		(start 322.50634 -149.887178)
		(end 322.506086 -149.887178)
		(width 0.1651)
		(layer "In9.Cu")
		(net "P5E_PEX2_STN0_TX_DP<8>")
	)
	(segment
		(start 318.566292 -144.77619)
		(end 318.566292 -144.90192)
		(width 0.1651)
		(layer "In9.Cu")
		(net "P5E_PEX2_STN0_TX_DP<8>")
	)
	(segment
		(start 321.499484 -148.13026)
		(end 321.622928 -148.154898)
		(width 0.1651)
		(layer "In9.Cu")
		(net "P5E_PEX2_STN0_TX_DP<8>")
	)
	(segment
		(start 315.84138 -173.177454)
		(end 314.61837 -177.738786)
		(width 0.1651)
		(layer "In9.Cu")
		(net "P5E_PEX2_STN0_TX_DP<8>")
	)
	(segment
		(start 312.680096 -199.893174)
		(end 310.741822 -222.047308)
		(width 0.1651)
		(layer "In9.Cu")
		(net "P5E_PEX2_STN0_TX_DP<8>")
	)
	(segment
		(start 324.347586 -158.440882)
		(end 315.84138 -173.177454)
		(width 0.1651)
		(layer "In9.Cu")
		(net "P5E_PEX2_STN0_TX_DP<8>")
	)
	(segment
		(start 322.506086 -149.887178)
		(end 324.347586 -154.332686)
		(width 0.1651)
		(layer "In9.Cu")
		(net "P5E_PEX2_STN0_TX_DP<8>")
	)
	(segment
		(start 314.61837 -177.738786)
		(end 312.679842 -199.893174)
		(width 0.1651)
		(layer "In9.Cu")
		(net "P5E_PEX2_STN0_TX_DP<8>")
	)
	(segment
		(start 320.270124 -146.605752)
		(end 320.62039 -146.956018)
		(width 0.1651)
		(layer "In9.Cu")
		(net "P5E_PEX2_STN0_TX_DP<8>")
	)
	(segment
		(start 313.965336 -276.899878)
		(end 313.699906 -276.899878)
		(width 0.1143)
		(layer "In9.Cu")
		(net "P5E_PEX2_STN0_TX_DP<8>")
	)
	(segment
		(start 312.679842 -199.893174)
		(end 312.680096 -199.893174)
		(width 0.1651)
		(layer "In9.Cu")
		(net "P5E_PEX2_STN0_TX_DP<8>")
	)
	(segment
		(start 321.622674 -148.154898)
		(end 322.059046 -148.807678)
		(width 0.1651)
		(layer "In9.Cu")
		(net "P5E_PEX2_STN0_TX_DP<8>")
	)
	(segment
		(start 318.566292 -144.90192)
		(end 318.916812 -145.25244)
		(width 0.1651)
		(layer "In9.Cu")
		(net "P5E_PEX2_STN0_TX_DP<8>")
	)
	(segment
		(start 319.743074 -146.078702)
		(end 319.868804 -146.078702)
		(width 0.1651)
		(layer "In9.Cu")
		(net "P5E_PEX2_STN0_TX_DP<8>")
	)
	(segment
		(start 315.02985 -271.85112)
		(end 315.02985 -276.183598)
		(width 0.1143)
		(layer "In9.Cu")
		(net "P5E_PEX2_STN0_TX_DP<8>")
	)
	(segment
		(start 291.234876 -365.321342)
		(end 291.04717 -364.862618)
		(width 0.1651)
		(layer "In5.Cu")
		(net "P5E_PEX2_STN7_RX_DN<122>")
	)
	(segment
		(start 289.088068 -360.078528)
		(end 288.900362 -359.619804)
		(width 0.1651)
		(layer "In5.Cu")
		(net "P5E_PEX2_STN7_RX_DN<122>")
	)
	(segment
		(start 288.396172 -342.24976)
		(end 288.077402 -341.239602)
		(width 0.1651)
		(layer "In5.Cu")
		(net "P5E_PEX2_STN7_RX_DN<122>")
	)
	(segment
		(start 289.362388 -360.748326)
		(end 289.424872 -360.599228)
		(width 0.1651)
		(layer "In5.Cu")
		(net "P5E_PEX2_STN7_RX_DN<122>")
	)
	(segment
		(start 292.016942 -382.69926)
		(end 292.447218 -382.69926)
		(width 0.1651)
		(layer "In5.Cu")
		(net "P5E_PEX2_STN7_RX_DN<122>")
	)
	(segment
		(start 292.30828 -367.64087)
		(end 292.158928 -367.578386)
		(width 0.1651)
		(layer "In5.Cu")
		(net "P5E_PEX2_STN7_RX_DN<122>")
	)
	(segment
		(start 291.04717 -364.862618)
		(end 291.109654 -364.71352)
		(width 0.1651)
		(layer "In5.Cu")
		(net "P5E_PEX2_STN7_RX_DN<122>")
	)
	(segment
		(start 289.838384 -361.843828)
		(end 289.886898 -361.72775)
		(width 0.1651)
		(layer "In5.Cu")
		(net "P5E_PEX2_STN7_RX_DN<122>")
	)
	(segment
		(start 291.38372 -365.384588)
		(end 291.384228 -365.383826)
		(width 0.1651)
		(layer "In5.Cu")
		(net "P5E_PEX2_STN7_RX_DN<122>")
	)
	(segment
		(start 269.429484 -319.07988)
		(end 269.429484 -316.914022)
		(width 0.1143)
		(layer "In5.Cu")
		(net "P5E_PEX2_STN7_RX_DN<122>")
	)
	(segment
		(start 272.663158 -330.98867)
		(end 272.637758 -330.95946)
		(width 0.1651)
		(layer "In5.Cu")
		(net "P5E_PEX2_STN7_RX_DN<122>")
	)
	(segment
		(start 291.889942 -382.18999)
		(end 291.889942 -382.57226)
		(width 0.1651)
		(layer "In5.Cu")
		(net "P5E_PEX2_STN7_RX_DN<122>")
	)
	(segment
		(start 292.308026 -367.64087)
		(end 292.30828 -367.64087)
		(width 0.1651)
		(layer "In5.Cu")
		(net "P5E_PEX2_STN7_RX_DN<122>")
	)
	(segment
		(start 291.971222 -367.119662)
		(end 292.033706 -366.970564)
		(width 0.1651)
		(layer "In5.Cu")
		(net "P5E_PEX2_STN7_RX_DN<122>")
	)
	(segment
		(start 289.23742 -360.141012)
		(end 289.088068 -360.078528)
		(width 0.1651)
		(layer "In5.Cu")
		(net "P5E_PEX2_STN7_RX_DN<122>")
	)
	(segment
		(start 272.635218 -330.956158)
		(end 272.632678 -330.953364)
		(width 0.1651)
		(layer "In5.Cu")
		(net "P5E_PEX2_STN7_RX_DN<122>")
	)
	(segment
		(start 291.846254 -366.512348)
		(end 291.696902 -366.449864)
		(width 0.1651)
		(layer "In5.Cu")
		(net "P5E_PEX2_STN7_RX_DN<122>")
	)
	(segment
		(start 269.383764 -319.154048)
		(end 269.383764 -319.1256)
		(width 0.1143)
		(layer "In5.Cu")
		(net "P5E_PEX2_STN7_RX_DN<122>")
	)
	(segment
		(start 291.509196 -365.99114)
		(end 291.57168 -365.842042)
		(width 0.1651)
		(layer "In5.Cu")
		(net "P5E_PEX2_STN7_RX_DN<122>")
	)
	(segment
		(start 292.158928 -367.578386)
		(end 291.971222 -367.119662)
		(width 0.1651)
		(layer "In5.Cu")
		(net "P5E_PEX2_STN7_RX_DN<122>")
	)
	(segment
		(start 270.068294 -327.996804)
		(end 269.383764 -326.318118)
		(width 0.1651)
		(layer "In5.Cu")
		(net "P5E_PEX2_STN7_RX_DN<122>")
	)
	(segment
		(start 291.109654 -364.71352)
		(end 291.1094 -364.713774)
		(width 0.1651)
		(layer "In5.Cu")
		(net "P5E_PEX2_STN7_RX_DN<122>")
	)
	(segment
		(start 290.142422 -362.350812)
		(end 290.026344 -362.302298)
		(width 0.1651)
		(layer "In5.Cu")
		(net "P5E_PEX2_STN7_RX_DN<122>")
	)
	(segment
		(start 291.696902 -366.449864)
		(end 291.509196 -365.99114)
		(width 0.1651)
		(layer "In5.Cu")
		(net "P5E_PEX2_STN7_RX_DN<122>")
	)
	(segment
		(start 289.550094 -361.20705)
		(end 289.362388 -360.748326)
		(width 0.1651)
		(layer "In5.Cu")
		(net "P5E_PEX2_STN7_RX_DN<122>")
	)
	(segment
		(start 289.699446 -361.269534)
		(end 289.550094 -361.20705)
		(width 0.1651)
		(layer "In5.Cu")
		(net "P5E_PEX2_STN7_RX_DN<122>")
	)
	(segment
		(start 289.424872 -360.599228)
		(end 289.23742 -360.141012)
		(width 0.1651)
		(layer "In5.Cu")
		(net "P5E_PEX2_STN7_RX_DN<122>")
	)
	(segment
		(start 288.900362 -359.619804)
		(end 288.962846 -359.470706)
		(width 0.1651)
		(layer "In5.Cu")
		(net "P5E_PEX2_STN7_RX_DN<122>")
	)
	(segment
		(start 291.889942 -382.57226)
		(end 292.016942 -382.69926)
		(width 0.1651)
		(layer "In5.Cu")
		(net "P5E_PEX2_STN7_RX_DN<122>")
	)
	(segment
		(start 288.077402 -341.239602)
		(end 275.45665 -332.901798)
		(width 0.1651)
		(layer "In5.Cu")
		(net "P5E_PEX2_STN7_RX_DN<122>")
	)
	(segment
		(start 290.141914 -362.350812)
		(end 290.142422 -362.350812)
		(width 0.1651)
		(layer "In5.Cu")
		(net "P5E_PEX2_STN7_RX_DN<122>")
	)
	(segment
		(start 272.637758 -330.95946)
		(end 272.637758 -330.959206)
		(width 0.1651)
		(layer "In5.Cu")
		(net "P5E_PEX2_STN7_RX_DN<122>")
	)
	(segment
		(start 272.631408 -330.951586)
		(end 270.068294 -327.996804)
		(width 0.1651)
		(layer "In5.Cu")
		(net "P5E_PEX2_STN7_RX_DN<122>")
	)
	(segment
		(start 269.383764 -326.318118)
		(end 269.383764 -319.154048)
		(width 0.1651)
		(layer "In5.Cu")
		(net "P5E_PEX2_STN7_RX_DN<122>")
	)
	(segment
		(start 272.632678 -330.953364)
		(end 272.631408 -330.951586)
		(width 0.1651)
		(layer "In5.Cu")
		(net "P5E_PEX2_STN7_RX_DN<122>")
	)
	(segment
		(start 289.886898 -361.72775)
		(end 289.699446 -361.269534)
		(width 0.1651)
		(layer "In5.Cu")
		(net "P5E_PEX2_STN7_RX_DN<122>")
	)
	(segment
		(start 275.45665 -332.901798)
		(end 272.663158 -330.98867)
		(width 0.1651)
		(layer "In5.Cu")
		(net "P5E_PEX2_STN7_RX_DN<122>")
	)
	(segment
		(start 269.383764 -319.1256)
		(end 269.429484 -319.07988)
		(width 0.1143)
		(layer "In5.Cu")
		(net "P5E_PEX2_STN7_RX_DN<122>")
	)
	(segment
		(start 291.571426 -365.842042)
		(end 291.38372 -365.384588)
		(width 0.1651)
		(layer "In5.Cu")
		(net "P5E_PEX2_STN7_RX_DN<122>")
	)
	(segment
		(start 272.637758 -330.959206)
		(end 272.635218 -330.956158)
		(width 0.1651)
		(layer "In5.Cu")
		(net "P5E_PEX2_STN7_RX_DN<122>")
	)
	(segment
		(start 288.396172 -358.08666)
		(end 288.396172 -342.24976)
		(width 0.1651)
		(layer "In5.Cu")
		(net "P5E_PEX2_STN7_RX_DN<122>")
	)
	(segment
		(start 292.733984 -368.681)
		(end 292.308026 -367.64087)
		(width 0.1651)
		(layer "In5.Cu")
		(net "P5E_PEX2_STN7_RX_DN<122>")
	)
	(segment
		(start 269.315184 -316.799722)
		(end 269.049754 -316.799722)
		(width 0.1143)
		(layer "In5.Cu")
		(net "P5E_PEX2_STN7_RX_DN<122>")
	)
	(segment
		(start 269.429484 -316.914022)
		(end 269.315184 -316.799722)
		(width 0.1143)
		(layer "In5.Cu")
		(net "P5E_PEX2_STN7_RX_DN<122>")
	)
	(segment
		(start 291.57168 -365.842042)
		(end 291.571426 -365.842042)
		(width 0.1651)
		(layer "In5.Cu")
		(net "P5E_PEX2_STN7_RX_DN<122>")
	)
	(segment
		(start 290.026344 -362.302298)
		(end 289.838384 -361.843828)
		(width 0.1651)
		(layer "In5.Cu")
		(net "P5E_PEX2_STN7_RX_DN<122>")
	)
	(segment
		(start 291.384228 -365.383826)
		(end 291.234876 -365.321342)
		(width 0.1651)
		(layer "In5.Cu")
		(net "P5E_PEX2_STN7_RX_DN<122>")
	)
	(segment
		(start 292.733984 -382.412494)
		(end 292.733984 -368.681)
		(width 0.1651)
		(layer "In5.Cu")
		(net "P5E_PEX2_STN7_RX_DN<122>")
	)
	(segment
		(start 291.1094 -364.713774)
		(end 290.141914 -362.350812)
		(width 0.1651)
		(layer "In5.Cu")
		(net "P5E_PEX2_STN7_RX_DN<122>")
	)
	(segment
		(start 288.962846 -359.470706)
		(end 288.396172 -358.08666)
		(width 0.1651)
		(layer "In5.Cu")
		(net "P5E_PEX2_STN7_RX_DN<122>")
	)
	(segment
		(start 292.447218 -382.69926)
		(end 292.733984 -382.412494)
		(width 0.1651)
		(layer "In5.Cu")
		(net "P5E_PEX2_STN7_RX_DN<122>")
	)
	(segment
		(start 292.033706 -366.970564)
		(end 291.846254 -366.512348)
		(width 0.1651)
		(layer "In5.Cu")
		(net "P5E_PEX2_STN7_RX_DN<122>")
	)
	(segment
		(start 199.34809 -132.281168)
		(end 199.979534 -132.281168)
		(width 0.13462)
		(layer "F.Cu")
		(net "P5E_PEX1_STN0_TX_DP<5>")
	)
	(segment
		(start 199.979534 -132.281168)
		(end 200.274174 -132.575808)
		(width 0.13462)
		(layer "F.Cu")
		(net "P5E_PEX1_STN0_TX_DP<5>")
	)
	(segment
		(start 199.02805 -132.601208)
		(end 199.34809 -132.281168)
		(width 0.13462)
		(layer "F.Cu")
		(net "P5E_PEX1_STN0_TX_DP<5>")
	)
	(segment
		(start 205.222602 -139.84732)
		(end 205.167738 -139.980162)
		(width 0.1651)
		(layer "In9.Cu")
		(net "P5E_PEX1_STN0_TX_DP<5>")
	)
	(segment
		(start 203.764642 -136.32688)
		(end 203.939394 -136.749028)
		(width 0.1651)
		(layer "In9.Cu")
		(net "P5E_PEX1_STN0_TX_DP<5>")
	)
	(segment
		(start 201.3839 -178.432968)
		(end 197.602856 -221.652592)
		(width 0.1651)
		(layer "In9.Cu")
		(net "P5E_PEX1_STN0_TX_DP<5>")
	)
	(segment
		(start 199.96531 -282.933648)
		(end 199.91959 -282.979368)
		(width 0.1143)
		(layer "In9.Cu")
		(net "P5E_PEX1_STN0_TX_DP<5>")
	)
	(segment
		(start 202.754484 -133.887972)
		(end 203.083922 -134.683754)
		(width 0.1651)
		(layer "In9.Cu")
		(net "P5E_PEX1_STN0_TX_DP<5>")
	)
	(segment
		(start 210.786472 -274.048728)
		(end 202.630024 -282.205176)
		(width 0.1651)
		(layer "In9.Cu")
		(net "P5E_PEX1_STN0_TX_DP<5>")
	)
	(segment
		(start 204.794866 -138.814556)
		(end 204.740002 -138.947398)
		(width 0.1651)
		(layer "In9.Cu")
		(net "P5E_PEX1_STN0_TX_DP<5>")
	)
	(segment
		(start 205.342744 -140.402818)
		(end 205.47584 -140.457682)
		(width 0.1651)
		(layer "In9.Cu")
		(net "P5E_PEX1_STN0_TX_DP<5>")
	)
	(segment
		(start 200.565004 -132.284978)
		(end 201.15149 -132.284978)
		(width 0.1651)
		(layer "In9.Cu")
		(net "P5E_PEX1_STN0_TX_DP<5>")
	)
	(segment
		(start 211.150962 -153.608024)
		(end 211.150962 -159.252412)
		(width 0.1651)
		(layer "In9.Cu")
		(net "P5E_PEX1_STN0_TX_DP<5>")
	)
	(segment
		(start 207.658208 -145.17624)
		(end 211.150962 -153.608024)
		(width 0.1651)
		(layer "In9.Cu")
		(net "P5E_PEX1_STN0_TX_DP<5>")
	)
	(segment
		(start 199.993758 -282.933648)
		(end 199.96531 -282.933648)
		(width 0.1143)
		(layer "In9.Cu")
		(net "P5E_PEX1_STN0_TX_DP<5>")
	)
	(segment
		(start 205.167738 -139.980162)
		(end 205.342744 -140.402818)
		(width 0.1651)
		(layer "In9.Cu")
		(net "P5E_PEX1_STN0_TX_DP<5>")
	)
	(segment
		(start 204.059536 -137.304526)
		(end 204.192378 -137.359644)
		(width 0.1651)
		(layer "In9.Cu")
		(net "P5E_PEX1_STN0_TX_DP<5>")
	)
	(segment
		(start 191.215264 -283.549852)
		(end 190.949834 -283.549852)
		(width 0.1143)
		(layer "In9.Cu")
		(net "P5E_PEX1_STN0_TX_DP<5>")
	)
	(segment
		(start 201.15149 -132.284978)
		(end 201.639932 -132.77342)
		(width 0.1651)
		(layer "In9.Cu")
		(net "P5E_PEX1_STN0_TX_DP<5>")
	)
	(segment
		(start 197.602856 -221.652592)
		(end 200.178416 -251.144532)
		(width 0.1651)
		(layer "In9.Cu")
		(net "P5E_PEX1_STN0_TX_DP<5>")
	)
	(segment
		(start 200.178416 -251.144532)
		(end 210.673696 -266.851384)
		(width 0.1651)
		(layer "In9.Cu")
		(net "P5E_PEX1_STN0_TX_DP<5>")
	)
	(segment
		(start 207.26908 -144.786858)
		(end 207.658462 -145.17624)
		(width 0.1651)
		(layer "In9.Cu")
		(net "P5E_PEX1_STN0_TX_DP<5>")
	)
	(segment
		(start 191.329564 -283.19476)
		(end 191.329564 -283.435552)
		(width 0.1143)
		(layer "In9.Cu")
		(net "P5E_PEX1_STN0_TX_DP<5>")
	)
	(segment
		(start 205.47584 -140.457682)
		(end 207.26908 -144.786858)
		(width 0.1651)
		(layer "In9.Cu")
		(net "P5E_PEX1_STN0_TX_DP<5>")
	)
	(segment
		(start 203.456794 -135.849106)
		(end 203.6318 -136.271762)
		(width 0.1651)
		(layer "In9.Cu")
		(net "P5E_PEX1_STN0_TX_DP<5>")
	)
	(segment
		(start 199.91959 -282.979368)
		(end 191.544956 -282.979368)
		(width 0.1143)
		(layer "In9.Cu")
		(net "P5E_PEX1_STN0_TX_DP<5>")
	)
	(segment
		(start 204.487272 -138.33729)
		(end 204.620114 -138.392408)
		(width 0.1651)
		(layer "In9.Cu")
		(net "P5E_PEX1_STN0_TX_DP<5>")
	)
	(segment
		(start 203.6318 -136.271762)
		(end 203.764642 -136.32688)
		(width 0.1651)
		(layer "In9.Cu")
		(net "P5E_PEX1_STN0_TX_DP<5>")
	)
	(segment
		(start 203.083922 -134.683754)
		(end 203.029058 -134.816596)
		(width 0.1651)
		(layer "In9.Cu")
		(net "P5E_PEX1_STN0_TX_DP<5>")
	)
	(segment
		(start 203.336906 -135.294116)
		(end 203.511658 -135.716264)
		(width 0.1651)
		(layer "In9.Cu")
		(net "P5E_PEX1_STN0_TX_DP<5>")
	)
	(segment
		(start 202.107038 -133.240526)
		(end 202.754484 -133.887972)
		(width 0.1651)
		(layer "In9.Cu")
		(net "P5E_PEX1_STN0_TX_DP<5>")
	)
	(segment
		(start 200.871582 -282.933648)
		(end 199.993758 -282.933648)
		(width 0.1651)
		(layer "In9.Cu")
		(net "P5E_PEX1_STN0_TX_DP<5>")
	)
	(segment
		(start 204.192378 -137.359644)
		(end 204.36713 -137.781792)
		(width 0.1651)
		(layer "In9.Cu")
		(net "P5E_PEX1_STN0_TX_DP<5>")
	)
	(segment
		(start 211.652612 -271.958054)
		(end 210.786472 -274.048728)
		(width 0.1651)
		(layer "In9.Cu")
		(net "P5E_PEX1_STN0_TX_DP<5>")
	)
	(segment
		(start 201.639932 -132.91693)
		(end 201.963528 -133.240526)
		(width 0.1651)
		(layer "In9.Cu")
		(net "P5E_PEX1_STN0_TX_DP<5>")
	)
	(segment
		(start 211.150962 -159.252412)
		(end 202.514454 -174.217076)
		(width 0.1651)
		(layer "In9.Cu")
		(net "P5E_PEX1_STN0_TX_DP<5>")
	)
	(segment
		(start 204.312266 -137.914634)
		(end 204.487272 -138.33729)
		(width 0.1651)
		(layer "In9.Cu")
		(net "P5E_PEX1_STN0_TX_DP<5>")
	)
	(segment
		(start 210.673696 -266.851384)
		(end 211.34832 -268.480286)
		(width 0.1651)
		(layer "In9.Cu")
		(net "P5E_PEX1_STN0_TX_DP<5>")
	)
	(segment
		(start 203.939394 -136.749028)
		(end 203.88453 -136.88187)
		(width 0.1651)
		(layer "In9.Cu")
		(net "P5E_PEX1_STN0_TX_DP<5>")
	)
	(segment
		(start 207.658462 -145.17624)
		(end 207.658208 -145.17624)
		(width 0.1651)
		(layer "In9.Cu")
		(net "P5E_PEX1_STN0_TX_DP<5>")
	)
	(segment
		(start 203.204064 -135.239252)
		(end 203.336906 -135.294116)
		(width 0.1651)
		(layer "In9.Cu")
		(net "P5E_PEX1_STN0_TX_DP<5>")
	)
	(segment
		(start 201.963528 -133.240526)
		(end 202.107038 -133.240526)
		(width 0.1651)
		(layer "In9.Cu")
		(net "P5E_PEX1_STN0_TX_DP<5>")
	)
	(segment
		(start 203.029058 -134.816596)
		(end 203.204064 -135.239252)
		(width 0.1651)
		(layer "In9.Cu")
		(net "P5E_PEX1_STN0_TX_DP<5>")
	)
	(segment
		(start 202.514454 -174.217076)
		(end 201.3839 -178.432968)
		(width 0.1651)
		(layer "In9.Cu")
		(net "P5E_PEX1_STN0_TX_DP<5>")
	)
	(segment
		(start 203.88453 -136.88187)
		(end 204.059536 -137.304526)
		(width 0.1651)
		(layer "In9.Cu")
		(net "P5E_PEX1_STN0_TX_DP<5>")
	)
	(segment
		(start 211.34832 -268.480286)
		(end 211.652612 -271.958054)
		(width 0.1651)
		(layer "In9.Cu")
		(net "P5E_PEX1_STN0_TX_DP<5>")
	)
	(segment
		(start 204.620114 -138.392408)
		(end 204.794866 -138.814556)
		(width 0.1651)
		(layer "In9.Cu")
		(net "P5E_PEX1_STN0_TX_DP<5>")
	)
	(segment
		(start 191.544956 -282.979368)
		(end 191.329564 -283.19476)
		(width 0.1143)
		(layer "In9.Cu")
		(net "P5E_PEX1_STN0_TX_DP<5>")
	)
	(segment
		(start 201.639932 -132.77342)
		(end 201.639932 -132.91693)
		(width 0.1651)
		(layer "In9.Cu")
		(net "P5E_PEX1_STN0_TX_DP<5>")
	)
	(segment
		(start 204.36713 -137.781792)
		(end 204.312266 -137.914634)
		(width 0.1651)
		(layer "In9.Cu")
		(net "P5E_PEX1_STN0_TX_DP<5>")
	)
	(segment
		(start 200.274174 -132.575808)
		(end 200.565004 -132.284978)
		(width 0.1651)
		(layer "In9.Cu")
		(net "P5E_PEX1_STN0_TX_DP<5>")
	)
	(segment
		(start 203.511658 -135.716264)
		(end 203.456794 -135.849106)
		(width 0.1651)
		(layer "In9.Cu")
		(net "P5E_PEX1_STN0_TX_DP<5>")
	)
	(segment
		(start 202.630024 -282.205176)
		(end 200.871582 -282.933648)
		(width 0.1651)
		(layer "In9.Cu")
		(net "P5E_PEX1_STN0_TX_DP<5>")
	)
	(segment
		(start 191.329564 -283.435552)
		(end 191.215264 -283.549852)
		(width 0.1143)
		(layer "In9.Cu")
		(net "P5E_PEX1_STN0_TX_DP<5>")
	)
	(segment
		(start 204.740002 -138.947398)
		(end 204.915008 -139.370054)
		(width 0.1651)
		(layer "In9.Cu")
		(net "P5E_PEX1_STN0_TX_DP<5>")
	)
	(segment
		(start 204.915008 -139.370054)
		(end 205.04785 -139.425172)
		(width 0.1651)
		(layer "In9.Cu")
		(net "P5E_PEX1_STN0_TX_DP<5>")
	)
	(segment
		(start 205.04785 -139.425172)
		(end 205.222602 -139.84732)
		(width 0.1651)
		(layer "In9.Cu")
		(net "P5E_PEX1_STN0_TX_DP<5>")
	)
	(segment
		(start 112.156748 -349.511874)
		(end 112.156748 -348.88043)
		(width 0.13462)
		(layer "F.Cu")
		(net "P5E_PEX1_STN6_TX_DP<103>")
	)
	(segment
		(start 111.836708 -349.831914)
		(end 112.156748 -349.511874)
		(width 0.13462)
		(layer "F.Cu")
		(net "P5E_PEX1_STN6_TX_DP<103>")
	)
	(segment
		(start 112.156748 -348.88043)
		(end 111.862108 -348.58579)
		(width 0.13462)
		(layer "F.Cu")
		(net "P5E_PEX1_STN6_TX_DP<103>")
	)
	(segment
		(start 165.989 -319.0748)
		(end 166.452042 -319.0748)
		(width 0.1143)
		(layer "In7.Cu")
		(net "P5E_PEX1_STN6_TX_DP<103>")
	)
	(segment
		(start 111.862108 -348.58579)
		(end 112.152938 -348.29496)
		(width 0.1651)
		(layer "In7.Cu")
		(net "P5E_PEX1_STN6_TX_DP<103>")
	)
	(segment
		(start 113.707418 -341.28456)
		(end 115.282472 -339.709506)
		(width 0.1651)
		(layer "In7.Cu")
		(net "P5E_PEX1_STN6_TX_DP<103>")
	)
	(segment
		(start 165.214808 -319.848992)
		(end 165.989 -319.0748)
		(width 0.1143)
		(layer "In7.Cu")
		(net "P5E_PEX1_STN6_TX_DP<103>")
	)
	(segment
		(start 166.629842 -311.705498)
		(end 166.855648 -311.479692)
		(width 0.1143)
		(layer "In7.Cu")
		(net "P5E_PEX1_STN6_TX_DP<103>")
	)
	(segment
		(start 130.10261 -330.826364)
		(end 164.652452 -320.34607)
		(width 0.1651)
		(layer "In7.Cu")
		(net "P5E_PEX1_STN6_TX_DP<103>")
	)
	(segment
		(start 166.855648 -311.479692)
		(end 167.085772 -311.479692)
		(width 0.1143)
		(layer "In7.Cu")
		(net "P5E_PEX1_STN6_TX_DP<103>")
	)
	(segment
		(start 112.152938 -347.620082)
		(end 113.707418 -346.065602)
		(width 0.1651)
		(layer "In7.Cu")
		(net "P5E_PEX1_STN6_TX_DP<103>")
	)
	(segment
		(start 166.452042 -319.0748)
		(end 166.629842 -318.897)
		(width 0.1143)
		(layer "In7.Cu")
		(net "P5E_PEX1_STN6_TX_DP<103>")
	)
	(segment
		(start 165.149784 -319.848992)
		(end 165.214808 -319.848992)
		(width 0.1143)
		(layer "In7.Cu")
		(net "P5E_PEX1_STN6_TX_DP<103>")
	)
	(segment
		(start 115.282472 -339.709506)
		(end 130.10261 -330.826364)
		(width 0.1651)
		(layer "In7.Cu")
		(net "P5E_PEX1_STN6_TX_DP<103>")
	)
	(segment
		(start 167.085772 -311.479692)
		(end 167.200072 -311.365392)
		(width 0.1143)
		(layer "In7.Cu")
		(net "P5E_PEX1_STN6_TX_DP<103>")
	)
	(segment
		(start 167.200072 -311.365392)
		(end 167.200072 -311.099962)
		(width 0.1143)
		(layer "In7.Cu")
		(net "P5E_PEX1_STN6_TX_DP<103>")
	)
	(segment
		(start 112.152938 -348.29496)
		(end 112.152938 -347.620082)
		(width 0.1651)
		(layer "In7.Cu")
		(net "P5E_PEX1_STN6_TX_DP<103>")
	)
	(segment
		(start 166.629842 -318.897)
		(end 166.629842 -311.705498)
		(width 0.1143)
		(layer "In7.Cu")
		(net "P5E_PEX1_STN6_TX_DP<103>")
	)
	(segment
		(start 164.652452 -320.34607)
		(end 165.139624 -319.859152)
		(width 0.1651)
		(layer "In7.Cu")
		(net "P5E_PEX1_STN6_TX_DP<103>")
	)
	(segment
		(start 165.139624 -319.859152)
		(end 165.149784 -319.848992)
		(width 0.1143)
		(layer "In7.Cu")
		(net "P5E_PEX1_STN6_TX_DP<103>")
	)
	(segment
		(start 113.707418 -346.065602)
		(end 113.707418 -341.28456)
		(width 0.1651)
		(layer "In7.Cu")
		(net "P5E_PEX1_STN6_TX_DP<103>")
	)
	(segment
		(start 268.260322 -130.720338)
		(end 268.571726 -130.408934)
		(width 0.13462)
		(layer "F.Cu")
		(net "P5E_PEX2_STN1_TX_DP<28>")
	)
	(segment
		(start 267.611606 -130.720338)
		(end 268.260322 -130.720338)
		(width 0.13462)
		(layer "F.Cu")
		(net "P5E_PEX2_STN1_TX_DP<28>")
	)
	(segment
		(start 267.325602 -130.434334)
		(end 267.611606 -130.720338)
		(width 0.13462)
		(layer "F.Cu")
		(net "P5E_PEX2_STN1_TX_DP<28>")
	)
	(segment
		(start 264.018014 -134.239508)
		(end 264.293858 -133.57352)
		(width 0.1651)
		(layer "In9.Cu")
		(net "P5E_PEX2_STN1_TX_DP<28>")
	)
	(segment
		(start 267.034772 -130.725164)
		(end 267.325602 -130.434334)
		(width 0.1651)
		(layer "In9.Cu")
		(net "P5E_PEX2_STN1_TX_DP<28>")
	)
	(segment
		(start 302.633888 -271.500346)
		(end 302.633888 -271.471898)
		(width 0.1143)
		(layer "In9.Cu")
		(net "P5E_PEX2_STN1_TX_DP<28>")
	)
	(segment
		(start 302.679608 -278.205184)
		(end 302.679608 -271.546066)
		(width 0.1143)
		(layer "In9.Cu")
		(net "P5E_PEX2_STN1_TX_DP<28>")
	)
	(segment
		(start 265.032236 -132.467858)
		(end 265.03249 -132.467858)
		(width 0.1651)
		(layer "In9.Cu")
		(net "P5E_PEX2_STN1_TX_DP<28>")
	)
	(segment
		(start 302.679608 -271.546066)
		(end 302.633888 -271.500346)
		(width 0.1143)
		(layer "In9.Cu")
		(net "P5E_PEX2_STN1_TX_DP<28>")
	)
	(segment
		(start 264.018014 -136.050782)
		(end 264.018014 -134.239508)
		(width 0.1651)
		(layer "In9.Cu")
		(net "P5E_PEX2_STN1_TX_DP<28>")
	)
	(segment
		(start 302.894492 -278.420068)
		(end 302.679608 -278.205184)
		(width 0.1143)
		(layer "In9.Cu")
		(net "P5E_PEX2_STN1_TX_DP<28>")
	)
	(segment
		(start 264.293858 -133.57352)
		(end 265.032236 -132.467858)
		(width 0.1651)
		(layer "In9.Cu")
		(net "P5E_PEX2_STN1_TX_DP<28>")
	)
	(segment
		(start 265.03249 -132.467858)
		(end 265.842242 -131.25577)
		(width 0.1651)
		(layer "In9.Cu")
		(net "P5E_PEX2_STN1_TX_DP<28>")
	)
	(segment
		(start 302.633888 -263.430258)
		(end 268.176248 -161.63925)
		(width 0.1651)
		(layer "In9.Cu")
		(net "P5E_PEX2_STN1_TX_DP<28>")
	)
	(segment
		(start 266.620244 -142.333472)
		(end 264.018014 -136.050782)
		(width 0.1651)
		(layer "In9.Cu")
		(net "P5E_PEX2_STN1_TX_DP<28>")
	)
	(segment
		(start 268.176248 -161.63925)
		(end 267.37056 -157.586934)
		(width 0.1651)
		(layer "In9.Cu")
		(net "P5E_PEX2_STN1_TX_DP<28>")
	)
	(segment
		(start 265.842242 -131.25577)
		(end 265.842496 -131.25577)
		(width 0.1651)
		(layer "In9.Cu")
		(net "P5E_PEX2_STN1_TX_DP<28>")
	)
	(segment
		(start 303.135284 -278.420068)
		(end 302.894492 -278.420068)
		(width 0.1143)
		(layer "In9.Cu")
		(net "P5E_PEX2_STN1_TX_DP<28>")
	)
	(segment
		(start 267.37056 -157.586934)
		(end 266.620244 -142.333472)
		(width 0.1651)
		(layer "In9.Cu")
		(net "P5E_PEX2_STN1_TX_DP<28>")
	)
	(segment
		(start 265.842496 -131.25577)
		(end 266.089638 -130.885692)
		(width 0.1651)
		(layer "In9.Cu")
		(net "P5E_PEX2_STN1_TX_DP<28>")
	)
	(segment
		(start 303.249584 -278.534368)
		(end 303.135284 -278.420068)
		(width 0.1143)
		(layer "In9.Cu")
		(net "P5E_PEX2_STN1_TX_DP<28>")
	)
	(segment
		(start 266.389866 -130.725164)
		(end 267.034772 -130.725164)
		(width 0.1651)
		(layer "In9.Cu")
		(net "P5E_PEX2_STN1_TX_DP<28>")
	)
	(segment
		(start 302.633888 -271.471898)
		(end 302.633888 -263.430258)
		(width 0.1651)
		(layer "In9.Cu")
		(net "P5E_PEX2_STN1_TX_DP<28>")
	)
	(segment
		(start 303.249584 -278.799798)
		(end 303.249584 -278.534368)
		(width 0.1143)
		(layer "In9.Cu")
		(net "P5E_PEX2_STN1_TX_DP<28>")
	)
	(segment
		(start 266.089638 -130.885692)
		(end 266.389866 -130.725164)
		(width 0.1651)
		(layer "In9.Cu")
		(net "P5E_PEX2_STN1_TX_DP<28>")
	)
	(segment
		(start 120.437402 -396.999206)
		(end 120.869964 -396.999206)
		(width 0.1651)
		(layer "In5.Cu")
		(net "P5E_PEX1_STN5_RX_DP<82>")
	)
	(segment
		(start 176.083976 -319.883282)
		(end 176.129696 -319.837562)
		(width 0.1143)
		(layer "In5.Cu")
		(net "P5E_PEX1_STN5_RX_DP<82>")
	)
	(segment
		(start 122.496834 -394.293344)
		(end 122.510804 -394.168376)
		(width 0.1651)
		(layer "In5.Cu")
		(net "P5E_PEX1_STN5_RX_DP<82>")
	)
	(segment
		(start 175.870616 -323.695568)
		(end 176.083976 -323.006212)
		(width 0.1651)
		(layer "In5.Cu")
		(net "P5E_PEX1_STN5_RX_DP<82>")
	)
	(segment
		(start 120.310148 -396.871952)
		(end 120.437402 -396.999206)
		(width 0.1651)
		(layer "In5.Cu")
		(net "P5E_PEX1_STN5_RX_DP<82>")
	)
	(segment
		(start 132.406644 -389.443976)
		(end 136.442196 -388.639812)
		(width 0.1651)
		(layer "In5.Cu")
		(net "P5E_PEX1_STN5_RX_DP<82>")
	)
	(segment
		(start 121.703338 -394.946378)
		(end 121.839228 -394.932662)
		(width 0.1651)
		(layer "In5.Cu")
		(net "P5E_PEX1_STN5_RX_DP<82>")
	)
	(segment
		(start 176.129696 -316.455298)
		(end 176.355502 -316.229492)
		(width 0.1143)
		(layer "In5.Cu")
		(net "P5E_PEX1_STN5_RX_DP<82>")
	)
	(segment
		(start 158.199836 -337.574128)
		(end 160.457642 -335.051146)
		(width 0.1651)
		(layer "In5.Cu")
		(net "P5E_PEX1_STN5_RX_DP<82>")
	)
	(segment
		(start 174.931578 -325.958708)
		(end 175.870616 -323.695568)
		(width 0.1651)
		(layer "In5.Cu")
		(net "P5E_PEX1_STN5_RX_DP<82>")
	)
	(segment
		(start 173.984666 -326.90562)
		(end 174.931578 -325.958708)
		(width 0.1651)
		(layer "In5.Cu")
		(net "P5E_PEX1_STN5_RX_DP<82>")
	)
	(segment
		(start 136.442196 -388.639812)
		(end 137.585958 -387.833362)
		(width 0.1651)
		(layer "In5.Cu")
		(net "P5E_PEX1_STN5_RX_DP<82>")
	)
	(segment
		(start 120.310148 -396.49019)
		(end 120.310148 -396.871952)
		(width 0.1651)
		(layer "In5.Cu")
		(net "P5E_PEX1_STN5_RX_DP<82>")
	)
	(segment
		(start 138.227054 -386.756148)
		(end 141.345666 -378.42444)
		(width 0.1651)
		(layer "In5.Cu")
		(net "P5E_PEX1_STN5_RX_DP<82>")
	)
	(segment
		(start 160.457642 -335.051146)
		(end 173.384972 -327.443846)
		(width 0.1651)
		(layer "In5.Cu")
		(net "P5E_PEX1_STN5_RX_DP<82>")
	)
	(segment
		(start 176.699926 -316.115192)
		(end 176.699926 -315.849762)
		(width 0.1143)
		(layer "In5.Cu")
		(net "P5E_PEX1_STN5_RX_DP<82>")
	)
	(segment
		(start 123.023122 -393.872974)
		(end 123.54687 -393.45489)
		(width 0.1651)
		(layer "In5.Cu")
		(net "P5E_PEX1_STN5_RX_DP<82>")
	)
	(segment
		(start 176.083976 -319.91173)
		(end 176.083976 -319.883282)
		(width 0.1143)
		(layer "In5.Cu")
		(net "P5E_PEX1_STN5_RX_DP<82>")
	)
	(segment
		(start 121.392696 -395.480032)
		(end 121.37898 -395.344142)
		(width 0.1651)
		(layer "In5.Cu")
		(net "P5E_PEX1_STN5_RX_DP<82>")
	)
	(segment
		(start 176.083976 -323.006212)
		(end 176.083976 -319.91173)
		(width 0.1651)
		(layer "In5.Cu")
		(net "P5E_PEX1_STN5_RX_DP<82>")
	)
	(segment
		(start 141.345666 -378.42444)
		(end 141.34592 -378.42444)
		(width 0.1651)
		(layer "In5.Cu")
		(net "P5E_PEX1_STN5_RX_DP<82>")
	)
	(segment
		(start 144.464278 -370.092986)
		(end 145.587466 -366.048798)
		(width 0.1651)
		(layer "In5.Cu")
		(net "P5E_PEX1_STN5_RX_DP<82>")
	)
	(segment
		(start 122.510804 -394.168376)
		(end 122.898154 -393.859004)
		(width 0.1651)
		(layer "In5.Cu")
		(net "P5E_PEX1_STN5_RX_DP<82>")
	)
	(segment
		(start 176.585626 -316.229492)
		(end 176.699926 -316.115192)
		(width 0.1143)
		(layer "In5.Cu")
		(net "P5E_PEX1_STN5_RX_DP<82>")
	)
	(segment
		(start 120.869964 -396.999206)
		(end 121.087642 -396.781528)
		(width 0.1651)
		(layer "In5.Cu")
		(net "P5E_PEX1_STN5_RX_DP<82>")
	)
	(segment
		(start 173.384972 -327.443846)
		(end 173.984666 -326.90562)
		(width 0.1651)
		(layer "In5.Cu")
		(net "P5E_PEX1_STN5_RX_DP<82>")
	)
	(segment
		(start 176.129696 -319.837562)
		(end 176.129696 -316.455298)
		(width 0.1143)
		(layer "In5.Cu")
		(net "P5E_PEX1_STN5_RX_DP<82>")
	)
	(segment
		(start 123.54687 -393.45489)
		(end 128.723136 -390.881362)
		(width 0.1651)
		(layer "In5.Cu")
		(net "P5E_PEX1_STN5_RX_DP<82>")
	)
	(segment
		(start 141.34592 -378.42444)
		(end 144.464278 -370.092986)
		(width 0.1651)
		(layer "In5.Cu")
		(net "P5E_PEX1_STN5_RX_DP<82>")
	)
	(segment
		(start 137.585958 -387.833362)
		(end 138.227054 -386.756148)
		(width 0.1651)
		(layer "In5.Cu")
		(net "P5E_PEX1_STN5_RX_DP<82>")
	)
	(segment
		(start 121.37898 -395.344142)
		(end 121.703338 -394.946378)
		(width 0.1651)
		(layer "In5.Cu")
		(net "P5E_PEX1_STN5_RX_DP<82>")
	)
	(segment
		(start 121.839228 -394.932662)
		(end 122.106182 -394.605256)
		(width 0.1651)
		(layer "In5.Cu")
		(net "P5E_PEX1_STN5_RX_DP<82>")
	)
	(segment
		(start 145.587466 -366.048798)
		(end 150.712424 -352.5266)
		(width 0.1651)
		(layer "In5.Cu")
		(net "P5E_PEX1_STN5_RX_DP<82>")
	)
	(segment
		(start 150.712424 -352.5266)
		(end 158.199836 -337.574128)
		(width 0.1651)
		(layer "In5.Cu")
		(net "P5E_PEX1_STN5_RX_DP<82>")
	)
	(segment
		(start 128.723136 -390.881362)
		(end 132.406644 -389.443976)
		(width 0.1651)
		(layer "In5.Cu")
		(net "P5E_PEX1_STN5_RX_DP<82>")
	)
	(segment
		(start 121.087642 -396.781528)
		(end 121.087642 -395.85392)
		(width 0.1651)
		(layer "In5.Cu")
		(net "P5E_PEX1_STN5_RX_DP<82>")
	)
	(segment
		(start 121.087642 -395.85392)
		(end 121.392696 -395.480032)
		(width 0.1651)
		(layer "In5.Cu")
		(net "P5E_PEX1_STN5_RX_DP<82>")
	)
	(segment
		(start 176.355502 -316.229492)
		(end 176.585626 -316.229492)
		(width 0.1143)
		(layer "In5.Cu")
		(net "P5E_PEX1_STN5_RX_DP<82>")
	)
	(segment
		(start 122.898154 -393.859004)
		(end 123.023122 -393.872974)
		(width 0.1651)
		(layer "In5.Cu")
		(net "P5E_PEX1_STN5_RX_DP<82>")
	)
	(segment
		(start 122.106182 -394.605256)
		(end 122.496834 -394.293344)
		(width 0.1651)
		(layer "In5.Cu")
		(net "P5E_PEX1_STN5_RX_DP<82>")
	)
	(segment
		(start 199.34809 -132.006848)
		(end 199.979534 -132.006848)
		(width 0.13462)
		(layer "F.Cu")
		(net "P5E_PEX1_STN0_TX_DN<5>")
	)
	(segment
		(start 199.979534 -132.006848)
		(end 200.274174 -131.712208)
		(width 0.13462)
		(layer "F.Cu")
		(net "P5E_PEX1_STN0_TX_DN<5>")
	)
	(segment
		(start 199.02805 -131.686808)
		(end 199.34809 -132.006848)
		(width 0.13462)
		(layer "F.Cu")
		(net "P5E_PEX1_STN0_TX_DN<5>")
	)
	(segment
		(start 210.923632 -266.71778)
		(end 211.625434 -268.412468)
		(width 0.1651)
		(layer "In9.Cu")
		(net "P5E_PEX1_STN0_TX_DN<5>")
	)
	(segment
		(start 211.939632 -272.00225)
		(end 211.025486 -274.208494)
		(width 0.1651)
		(layer "In9.Cu")
		(net "P5E_PEX1_STN0_TX_DN<5>")
	)
	(segment
		(start 207.897476 -145.016474)
		(end 211.432902 -153.55189)
		(width 0.1651)
		(layer "In9.Cu")
		(net "P5E_PEX1_STN0_TX_DN<5>")
	)
	(segment
		(start 211.432902 -159.328104)
		(end 202.777344 -174.326042)
		(width 0.1651)
		(layer "In9.Cu")
		(net "P5E_PEX1_STN0_TX_DN<5>")
	)
	(segment
		(start 191.634364 -283.549852)
		(end 191.900048 -283.549852)
		(width 0.1143)
		(layer "In9.Cu")
		(net "P5E_PEX1_STN0_TX_DN<5>")
	)
	(segment
		(start 199.91959 -283.169868)
		(end 191.62395 -283.169868)
		(width 0.1143)
		(layer "In9.Cu")
		(net "P5E_PEX1_STN0_TX_DN<5>")
	)
	(segment
		(start 201.26833 -132.003038)
		(end 202.993498 -133.728206)
		(width 0.1651)
		(layer "In9.Cu")
		(net "P5E_PEX1_STN0_TX_DN<5>")
	)
	(segment
		(start 191.520064 -283.435552)
		(end 191.634364 -283.549852)
		(width 0.1143)
		(layer "In9.Cu")
		(net "P5E_PEX1_STN0_TX_DN<5>")
	)
	(segment
		(start 200.927716 -283.215588)
		(end 199.993758 -283.215588)
		(width 0.1651)
		(layer "In9.Cu")
		(net "P5E_PEX1_STN0_TX_DN<5>")
	)
	(segment
		(start 202.78979 -282.44419)
		(end 200.927716 -283.215588)
		(width 0.1651)
		(layer "In9.Cu")
		(net "P5E_PEX1_STN0_TX_DN<5>")
	)
	(segment
		(start 200.453244 -251.048012)
		(end 210.923632 -266.71778)
		(width 0.1651)
		(layer "In9.Cu")
		(net "P5E_PEX1_STN0_TX_DN<5>")
	)
	(segment
		(start 200.274174 -131.712208)
		(end 200.565004 -132.003038)
		(width 0.1651)
		(layer "In9.Cu")
		(net "P5E_PEX1_STN0_TX_DN<5>")
	)
	(segment
		(start 191.520064 -283.273754)
		(end 191.520064 -283.435552)
		(width 0.1143)
		(layer "In9.Cu")
		(net "P5E_PEX1_STN0_TX_DN<5>")
	)
	(segment
		(start 191.62395 -283.169868)
		(end 191.520064 -283.273754)
		(width 0.1143)
		(layer "In9.Cu")
		(net "P5E_PEX1_STN0_TX_DN<5>")
	)
	(segment
		(start 202.777344 -174.326042)
		(end 201.662792 -178.482244)
		(width 0.1651)
		(layer "In9.Cu")
		(net "P5E_PEX1_STN0_TX_DN<5>")
	)
	(segment
		(start 202.993498 -133.728206)
		(end 207.508094 -144.627092)
		(width 0.1651)
		(layer "In9.Cu")
		(net "P5E_PEX1_STN0_TX_DN<5>")
	)
	(segment
		(start 211.025486 -274.208494)
		(end 202.78979 -282.44419)
		(width 0.1651)
		(layer "In9.Cu")
		(net "P5E_PEX1_STN0_TX_DN<5>")
	)
	(segment
		(start 211.432902 -153.55189)
		(end 211.432902 -159.328104)
		(width 0.1651)
		(layer "In9.Cu")
		(net "P5E_PEX1_STN0_TX_DN<5>")
	)
	(segment
		(start 207.508094 -144.627092)
		(end 207.897476 -145.016474)
		(width 0.1651)
		(layer "In9.Cu")
		(net "P5E_PEX1_STN0_TX_DN<5>")
	)
	(segment
		(start 200.565004 -132.003038)
		(end 201.26833 -132.003038)
		(width 0.1651)
		(layer "In9.Cu")
		(net "P5E_PEX1_STN0_TX_DN<5>")
	)
	(segment
		(start 199.96531 -283.215588)
		(end 199.91959 -283.169868)
		(width 0.1143)
		(layer "In9.Cu")
		(net "P5E_PEX1_STN0_TX_DN<5>")
	)
	(segment
		(start 201.662792 -178.482244)
		(end 197.886066 -221.652592)
		(width 0.1651)
		(layer "In9.Cu")
		(net "P5E_PEX1_STN0_TX_DN<5>")
	)
	(segment
		(start 211.625434 -268.412468)
		(end 211.939632 -272.00225)
		(width 0.1651)
		(layer "In9.Cu")
		(net "P5E_PEX1_STN0_TX_DN<5>")
	)
	(segment
		(start 199.993758 -283.215588)
		(end 199.96531 -283.215588)
		(width 0.1143)
		(layer "In9.Cu")
		(net "P5E_PEX1_STN0_TX_DN<5>")
	)
	(segment
		(start 197.886066 -221.652592)
		(end 200.453244 -251.048012)
		(width 0.1651)
		(layer "In9.Cu")
		(net "P5E_PEX1_STN0_TX_DN<5>")
	)
	(segment
		(start 121.163588 -349.831914)
		(end 121.483628 -349.511874)
		(width 0.13462)
		(layer "F.Cu")
		(net "P5E_PEX1_STN6_TX_DP<107>")
	)
	(segment
		(start 121.483628 -349.511874)
		(end 121.483628 -348.88043)
		(width 0.13462)
		(layer "F.Cu")
		(net "P5E_PEX1_STN6_TX_DP<107>")
	)
	(segment
		(start 121.483628 -348.88043)
		(end 121.188988 -348.58579)
		(width 0.13462)
		(layer "F.Cu")
		(net "P5E_PEX1_STN6_TX_DP<107>")
	)
	(segment
		(start 121.479818 -348.29496)
		(end 121.188988 -348.58579)
		(width 0.1651)
		(layer "In13.Cu")
		(net "P5E_PEX1_STN6_TX_DP<107>")
	)
	(segment
		(start 163.044886 -311.479692)
		(end 162.829748 -311.69483)
		(width 0.1143)
		(layer "In13.Cu")
		(net "P5E_PEX1_STN6_TX_DP<107>")
	)
	(segment
		(start 162.829748 -319.995296)
		(end 162.784028 -320.041016)
		(width 0.1143)
		(layer "In13.Cu")
		(net "P5E_PEX1_STN6_TX_DP<107>")
	)
	(segment
		(start 162.784028 -320.063114)
		(end 162.784028 -321.848734)
		(width 0.1651)
		(layer "In13.Cu")
		(net "P5E_PEX1_STN6_TX_DP<107>")
	)
	(segment
		(start 163.285678 -311.479692)
		(end 163.044886 -311.479692)
		(width 0.1143)
		(layer "In13.Cu")
		(net "P5E_PEX1_STN6_TX_DP<107>")
	)
	(segment
		(start 162.829748 -311.69483)
		(end 162.829748 -319.995296)
		(width 0.1143)
		(layer "In13.Cu")
		(net "P5E_PEX1_STN6_TX_DP<107>")
	)
	(segment
		(start 162.784028 -321.848734)
		(end 160.519364 -324.113398)
		(width 0.1651)
		(layer "In13.Cu")
		(net "P5E_PEX1_STN6_TX_DP<107>")
	)
	(segment
		(start 163.399978 -311.365392)
		(end 163.285678 -311.479692)
		(width 0.1143)
		(layer "In13.Cu")
		(net "P5E_PEX1_STN6_TX_DP<107>")
	)
	(segment
		(start 126.081282 -337.95462)
		(end 123.034298 -341.001604)
		(width 0.1651)
		(layer "In13.Cu")
		(net "P5E_PEX1_STN6_TX_DP<107>")
	)
	(segment
		(start 130.79349 -334.806036)
		(end 126.081282 -337.95462)
		(width 0.1651)
		(layer "In13.Cu")
		(net "P5E_PEX1_STN6_TX_DP<107>")
	)
	(segment
		(start 145.810478 -330.33335)
		(end 141.591284 -330.33335)
		(width 0.1651)
		(layer "In13.Cu")
		(net "P5E_PEX1_STN6_TX_DP<107>")
	)
	(segment
		(start 162.784028 -320.041016)
		(end 162.784028 -320.063114)
		(width 0.1143)
		(layer "In13.Cu")
		(net "P5E_PEX1_STN6_TX_DP<107>")
	)
	(segment
		(start 141.591284 -330.33335)
		(end 130.79349 -334.806036)
		(width 0.1651)
		(layer "In13.Cu")
		(net "P5E_PEX1_STN6_TX_DP<107>")
	)
	(segment
		(start 123.034298 -341.001604)
		(end 123.034298 -345.952572)
		(width 0.1651)
		(layer "In13.Cu")
		(net "P5E_PEX1_STN6_TX_DP<107>")
	)
	(segment
		(start 123.034298 -345.952572)
		(end 121.479818 -347.507052)
		(width 0.1651)
		(layer "In13.Cu")
		(net "P5E_PEX1_STN6_TX_DP<107>")
	)
	(segment
		(start 121.479818 -347.507052)
		(end 121.479818 -348.29496)
		(width 0.1651)
		(layer "In13.Cu")
		(net "P5E_PEX1_STN6_TX_DP<107>")
	)
	(segment
		(start 148.155406 -329.867768)
		(end 145.810478 -330.33335)
		(width 0.1651)
		(layer "In13.Cu")
		(net "P5E_PEX1_STN6_TX_DP<107>")
	)
	(segment
		(start 157.101794 -326.162162)
		(end 148.155406 -329.867768)
		(width 0.1651)
		(layer "In13.Cu")
		(net "P5E_PEX1_STN6_TX_DP<107>")
	)
	(segment
		(start 163.399978 -311.099962)
		(end 163.399978 -311.365392)
		(width 0.1143)
		(layer "In13.Cu")
		(net "P5E_PEX1_STN6_TX_DP<107>")
	)
	(segment
		(start 160.519364 -324.113398)
		(end 157.101794 -326.162162)
		(width 0.1651)
		(layer "In13.Cu")
		(net "P5E_PEX1_STN6_TX_DP<107>")
	)
	(segment
		(start 269.96771 -99.314254)
		(end 270.251936 -99.59848)
		(width 0.13462)
		(layer "F.Cu")
		(net "P5E_PEX2_STN1_TX_DP<16>")
	)
	(segment
		(start 270.251936 -99.59848)
		(end 270.904208 -99.59848)
		(width 0.13462)
		(layer "F.Cu")
		(net "P5E_PEX2_STN1_TX_DP<16>")
	)
	(segment
		(start 270.904208 -99.59848)
		(end 271.213834 -99.288854)
		(width 0.13462)
		(layer "F.Cu")
		(net "P5E_PEX2_STN1_TX_DP<16>")
	)
	(segment
		(start 255.715008 -159.875728)
		(end 256.27965 -162.714432)
		(width 0.1651)
		(layer "In9.Cu")
		(net "P5E_PEX2_STN1_TX_DP<16>")
	)
	(segment
		(start 291.23386 -271.500346)
		(end 291.27958 -271.546066)
		(width 0.1143)
		(layer "In9.Cu")
		(net "P5E_PEX2_STN1_TX_DP<16>")
	)
	(segment
		(start 269.67688 -99.605084)
		(end 268.456664 -99.605084)
		(width 0.1651)
		(layer "In9.Cu")
		(net "P5E_PEX2_STN1_TX_DP<16>")
	)
	(segment
		(start 291.27958 -271.546066)
		(end 291.27958 -278.205184)
		(width 0.1143)
		(layer "In9.Cu")
		(net "P5E_PEX2_STN1_TX_DP<16>")
	)
	(segment
		(start 260.367526 -106.272076)
		(end 258.322318 -111.209582)
		(width 0.1651)
		(layer "In9.Cu")
		(net "P5E_PEX2_STN1_TX_DP<16>")
	)
	(segment
		(start 255.005332 -145.421858)
		(end 255.715008 -159.875728)
		(width 0.1651)
		(layer "In9.Cu")
		(net "P5E_PEX2_STN1_TX_DP<16>")
	)
	(segment
		(start 291.23386 -265.983974)
		(end 291.23386 -271.471898)
		(width 0.1651)
		(layer "In9.Cu")
		(net "P5E_PEX2_STN1_TX_DP<16>")
	)
	(segment
		(start 291.23386 -271.471898)
		(end 291.23386 -271.500346)
		(width 0.1143)
		(layer "In9.Cu")
		(net "P5E_PEX2_STN1_TX_DP<16>")
	)
	(segment
		(start 260.367526 -106.241596)
		(end 260.367526 -106.272076)
		(width 0.1651)
		(layer "In9.Cu")
		(net "P5E_PEX2_STN1_TX_DP<16>")
	)
	(segment
		(start 252.405134 -139.143994)
		(end 255.005332 -145.421858)
		(width 0.1651)
		(layer "In9.Cu")
		(net "P5E_PEX2_STN1_TX_DP<16>")
	)
	(segment
		(start 265.976608 -100.632514)
		(end 260.367526 -106.241596)
		(width 0.1651)
		(layer "In9.Cu")
		(net "P5E_PEX2_STN1_TX_DP<16>")
	)
	(segment
		(start 291.27958 -278.205184)
		(end 291.494464 -278.420068)
		(width 0.1143)
		(layer "In9.Cu")
		(net "P5E_PEX2_STN1_TX_DP<16>")
	)
	(segment
		(start 268.456664 -99.605084)
		(end 265.976608 -100.632514)
		(width 0.1651)
		(layer "In9.Cu")
		(net "P5E_PEX2_STN1_TX_DP<16>")
	)
	(segment
		(start 256.27965 -162.714432)
		(end 291.23386 -265.983974)
		(width 0.1651)
		(layer "In9.Cu")
		(net "P5E_PEX2_STN1_TX_DP<16>")
	)
	(segment
		(start 252.405134 -130.71475)
		(end 252.405134 -139.143994)
		(width 0.1651)
		(layer "In9.Cu")
		(net "P5E_PEX2_STN1_TX_DP<16>")
	)
	(segment
		(start 291.735256 -278.420068)
		(end 291.849556 -278.534368)
		(width 0.1143)
		(layer "In9.Cu")
		(net "P5E_PEX2_STN1_TX_DP<16>")
	)
	(segment
		(start 269.96771 -99.314254)
		(end 269.67688 -99.605084)
		(width 0.1651)
		(layer "In9.Cu")
		(net "P5E_PEX2_STN1_TX_DP<16>")
	)
	(segment
		(start 258.322318 -111.209582)
		(end 252.405134 -130.71475)
		(width 0.1651)
		(layer "In9.Cu")
		(net "P5E_PEX2_STN1_TX_DP<16>")
	)
	(segment
		(start 291.849556 -278.534368)
		(end 291.849556 -278.799798)
		(width 0.1143)
		(layer "In9.Cu")
		(net "P5E_PEX2_STN1_TX_DP<16>")
	)
	(segment
		(start 291.494464 -278.420068)
		(end 291.735256 -278.420068)
		(width 0.1143)
		(layer "In9.Cu")
		(net "P5E_PEX2_STN1_TX_DP<16>")
	)
	(segment
		(start 144.828768 -313.884056)
		(end 145.145252 -313.502548)
		(width 0.1651)
		(layer "In9.Cu")
		(net "P5E_PEX1_STN7_RX_DN<119>")
	)
	(segment
		(start 166.03472 -388.95274)
		(end 161.76625 -387.183376)
		(width 0.1651)
		(layer "In9.Cu")
		(net "P5E_PEX1_STN7_RX_DN<119>")
	)
	(segment
		(start 176.159668 -395.190472)
		(end 174.488602 -393.519406)
		(width 0.1651)
		(layer "In9.Cu")
		(net "P5E_PEX1_STN7_RX_DN<119>")
	)
	(segment
		(start 148.527516 -309.864252)
		(end 150.030688 -308.36108)
		(width 0.1651)
		(layer "In9.Cu")
		(net "P5E_PEX1_STN7_RX_DN<119>")
	)
	(segment
		(start 147.66544 -310.888126)
		(end 147.66544 -310.726328)
		(width 0.1651)
		(layer "In9.Cu")
		(net "P5E_PEX1_STN7_RX_DN<119>")
	)
	(segment
		(start 148.176996 -310.376316)
		(end 148.527516 -310.025796)
		(width 0.1651)
		(layer "In9.Cu")
		(net "P5E_PEX1_STN7_RX_DN<119>")
	)
	(segment
		(start 175.437038 -410.080968)
		(end 175.775366 -410.080968)
		(width 0.1651)
		(layer "In9.Cu")
		(net "P5E_PEX1_STN7_RX_DN<119>")
	)
	(segment
		(start 151.765 -307.915818)
		(end 151.793448 -307.915818)
		(width 0.1143)
		(layer "In9.Cu")
		(net "P5E_PEX1_STN7_RX_DN<119>")
	)
	(segment
		(start 148.015452 -310.376316)
		(end 148.176996 -310.376316)
		(width 0.1651)
		(layer "In9.Cu")
		(net "P5E_PEX1_STN7_RX_DN<119>")
	)
	(segment
		(start 161.76625 -387.183376)
		(end 159.366458 -385.22656)
		(width 0.1651)
		(layer "In9.Cu")
		(net "P5E_PEX1_STN7_RX_DN<119>")
	)
	(segment
		(start 151.839168 -307.870098)
		(end 153.201878 -307.870098)
		(width 0.1143)
		(layer "In9.Cu")
		(net "P5E_PEX1_STN7_RX_DN<119>")
	)
	(segment
		(start 147.66544 -310.726328)
		(end 148.015452 -310.376316)
		(width 0.1651)
		(layer "In9.Cu")
		(net "P5E_PEX1_STN7_RX_DN<119>")
	)
	(segment
		(start 151.793448 -307.915818)
		(end 151.839168 -307.870098)
		(width 0.1143)
		(layer "In9.Cu")
		(net "P5E_PEX1_STN7_RX_DN<119>")
	)
	(segment
		(start 152.98674 -343.82837)
		(end 151.537416 -339.782658)
		(width 0.1651)
		(layer "In9.Cu")
		(net "P5E_PEX1_STN7_RX_DN<119>")
	)
	(segment
		(start 176.474374 -409.38196)
		(end 176.474374 -395.950186)
		(width 0.1651)
		(layer "In9.Cu")
		(net "P5E_PEX1_STN7_RX_DN<119>")
	)
	(segment
		(start 153.334212 -308.153816)
		(end 153.2382 -308.249828)
		(width 0.1143)
		(layer "In9.Cu")
		(net "P5E_PEX1_STN7_RX_DN<119>")
	)
	(segment
		(start 175.310038 -410.207968)
		(end 175.437038 -410.080968)
		(width 0.1651)
		(layer "In9.Cu")
		(net "P5E_PEX1_STN7_RX_DN<119>")
	)
	(segment
		(start 140.788644 -322.391278)
		(end 140.745972 -322.232274)
		(width 0.1651)
		(layer "In9.Cu")
		(net "P5E_PEX1_STN7_RX_DN<119>")
	)
	(segment
		(start 176.474374 -395.950186)
		(end 176.159668 -395.190472)
		(width 0.1651)
		(layer "In9.Cu")
		(net "P5E_PEX1_STN7_RX_DN<119>")
	)
	(segment
		(start 146.290792 -312.100976)
		(end 146.45259 -312.100976)
		(width 0.1651)
		(layer "In9.Cu")
		(net "P5E_PEX1_STN7_RX_DN<119>")
	)
	(segment
		(start 146.80311 -311.750456)
		(end 146.80311 -311.588658)
		(width 0.1651)
		(layer "In9.Cu")
		(net "P5E_PEX1_STN7_RX_DN<119>")
	)
	(segment
		(start 151.537416 -339.782658)
		(end 140.788644 -322.391278)
		(width 0.1651)
		(layer "In9.Cu")
		(net "P5E_PEX1_STN7_RX_DN<119>")
	)
	(segment
		(start 144.351756 -314.280042)
		(end 144.667986 -313.899042)
		(width 0.1651)
		(layer "In9.Cu")
		(net "P5E_PEX1_STN7_RX_DN<119>")
	)
	(segment
		(start 143.889476 -314.837572)
		(end 144.050258 -314.822586)
		(width 0.1651)
		(layer "In9.Cu")
		(net "P5E_PEX1_STN7_RX_DN<119>")
	)
	(segment
		(start 147.153122 -311.238646)
		(end 147.31492 -311.238646)
		(width 0.1651)
		(layer "In9.Cu")
		(net "P5E_PEX1_STN7_RX_DN<119>")
	)
	(segment
		(start 148.527516 -310.025796)
		(end 148.527516 -309.864252)
		(width 0.1651)
		(layer "In9.Cu")
		(net "P5E_PEX1_STN7_RX_DN<119>")
	)
	(segment
		(start 150.819866 -307.915818)
		(end 151.765 -307.915818)
		(width 0.1651)
		(layer "In9.Cu")
		(net "P5E_PEX1_STN7_RX_DN<119>")
	)
	(segment
		(start 140.745972 -320.164714)
		(end 141.69771 -318.01943)
		(width 0.1651)
		(layer "In9.Cu")
		(net "P5E_PEX1_STN7_RX_DN<119>")
	)
	(segment
		(start 153.201878 -307.870098)
		(end 153.334212 -308.002432)
		(width 0.1143)
		(layer "In9.Cu")
		(net "P5E_PEX1_STN7_RX_DN<119>")
	)
	(segment
		(start 170.303698 -390.722358)
		(end 166.034974 -388.95274)
		(width 0.1651)
		(layer "In9.Cu")
		(net "P5E_PEX1_STN7_RX_DN<119>")
	)
	(segment
		(start 146.45259 -312.100976)
		(end 146.80311 -311.750456)
		(width 0.1651)
		(layer "In9.Cu")
		(net "P5E_PEX1_STN7_RX_DN<119>")
	)
	(segment
		(start 147.31492 -311.238646)
		(end 147.66544 -310.888126)
		(width 0.1651)
		(layer "In9.Cu")
		(net "P5E_PEX1_STN7_RX_DN<119>")
	)
	(segment
		(start 153.2382 -308.249828)
		(end 152.94991 -308.249828)
		(width 0.1143)
		(layer "In9.Cu")
		(net "P5E_PEX1_STN7_RX_DN<119>")
	)
	(segment
		(start 166.034974 -388.95274)
		(end 166.03472 -388.95274)
		(width 0.1651)
		(layer "In9.Cu")
		(net "P5E_PEX1_STN7_RX_DN<119>")
	)
	(segment
		(start 145.145252 -313.502548)
		(end 145.130266 -313.341512)
		(width 0.1651)
		(layer "In9.Cu")
		(net "P5E_PEX1_STN7_RX_DN<119>")
	)
	(segment
		(start 143.550386 -315.246258)
		(end 143.889476 -314.837572)
		(width 0.1651)
		(layer "In9.Cu")
		(net "P5E_PEX1_STN7_RX_DN<119>")
	)
	(segment
		(start 144.667986 -313.899042)
		(end 144.828768 -313.884056)
		(width 0.1651)
		(layer "In9.Cu")
		(net "P5E_PEX1_STN7_RX_DN<119>")
	)
	(segment
		(start 153.334212 -308.002432)
		(end 153.334212 -308.153816)
		(width 0.1143)
		(layer "In9.Cu")
		(net "P5E_PEX1_STN7_RX_DN<119>")
	)
	(segment
		(start 150.497032 -308.049422)
		(end 150.819866 -307.915818)
		(width 0.1651)
		(layer "In9.Cu")
		(net "P5E_PEX1_STN7_RX_DN<119>")
	)
	(segment
		(start 146.80311 -311.588658)
		(end 147.153122 -311.238646)
		(width 0.1651)
		(layer "In9.Cu")
		(net "P5E_PEX1_STN7_RX_DN<119>")
	)
	(segment
		(start 175.775366 -410.080968)
		(end 176.474374 -409.38196)
		(width 0.1651)
		(layer "In9.Cu")
		(net "P5E_PEX1_STN7_RX_DN<119>")
	)
	(segment
		(start 140.745972 -322.232274)
		(end 140.745972 -320.164714)
		(width 0.1651)
		(layer "In9.Cu")
		(net "P5E_PEX1_STN7_RX_DN<119>")
	)
	(segment
		(start 174.488602 -393.519406)
		(end 170.303698 -390.722358)
		(width 0.1651)
		(layer "In9.Cu")
		(net "P5E_PEX1_STN7_RX_DN<119>")
	)
	(segment
		(start 144.050258 -314.822586)
		(end 144.366996 -314.441078)
		(width 0.1651)
		(layer "In9.Cu")
		(net "P5E_PEX1_STN7_RX_DN<119>")
	)
	(segment
		(start 141.69771 -318.01943)
		(end 143.550386 -315.246258)
		(width 0.1651)
		(layer "In9.Cu")
		(net "P5E_PEX1_STN7_RX_DN<119>")
	)
	(segment
		(start 175.310038 -410.589984)
		(end 175.310038 -410.207968)
		(width 0.1651)
		(layer "In9.Cu")
		(net "P5E_PEX1_STN7_RX_DN<119>")
	)
	(segment
		(start 159.366458 -385.22656)
		(end 158.320232 -383.326894)
		(width 0.1651)
		(layer "In9.Cu")
		(net "P5E_PEX1_STN7_RX_DN<119>")
	)
	(segment
		(start 150.030688 -308.36108)
		(end 150.497032 -308.049422)
		(width 0.1651)
		(layer "In9.Cu")
		(net "P5E_PEX1_STN7_RX_DN<119>")
	)
	(segment
		(start 145.51914 -312.872628)
		(end 146.290792 -312.100976)
		(width 0.1651)
		(layer "In9.Cu")
		(net "P5E_PEX1_STN7_RX_DN<119>")
	)
	(segment
		(start 145.130266 -313.341512)
		(end 145.51914 -312.872628)
		(width 0.1651)
		(layer "In9.Cu")
		(net "P5E_PEX1_STN7_RX_DN<119>")
	)
	(segment
		(start 144.366996 -314.441078)
		(end 144.351756 -314.280042)
		(width 0.1651)
		(layer "In9.Cu")
		(net "P5E_PEX1_STN7_RX_DN<119>")
	)
	(segment
		(start 158.320232 -383.326894)
		(end 152.98674 -343.82837)
		(width 0.1651)
		(layer "In9.Cu")
		(net "P5E_PEX1_STN7_RX_DN<119>")
	)
	(segment
		(start 288.948876 -338.742528)
		(end 288.98342 -338.863432)
		(width 0.1651)
		(layer "In5.Cu")
		(net "P5E_PEX2_STN7_RX_DN<123>")
	)
	(segment
		(start 270.615918 -325.873872)
		(end 271.043654 -327.053194)
		(width 0.1651)
		(layer "In5.Cu")
		(net "P5E_PEX2_STN7_RX_DN<123>")
	)
	(segment
		(start 289.969448 -339.311996)
		(end 290.003992 -339.4329)
		(width 0.1651)
		(layer "In5.Cu")
		(net "P5E_PEX2_STN7_RX_DN<123>")
	)
	(segment
		(start 288.395156 -338.535264)
		(end 288.51606 -338.500974)
		(width 0.1651)
		(layer "In5.Cu")
		(net "P5E_PEX2_STN7_RX_DN<123>")
	)
	(segment
		(start 270.684498 -318.320166)
		(end 270.570198 -318.434466)
		(width 0.1143)
		(layer "In5.Cu")
		(net "P5E_PEX2_STN7_RX_DN<123>")
	)
	(segment
		(start 276.0853 -331.667866)
		(end 288.395156 -338.535264)
		(width 0.1651)
		(layer "In5.Cu")
		(net "P5E_PEX2_STN7_RX_DN<123>")
	)
	(segment
		(start 270.949928 -318.699896)
		(end 270.949928 -318.434466)
		(width 0.1143)
		(layer "In5.Cu")
		(net "P5E_PEX2_STN7_RX_DN<123>")
	)
	(segment
		(start 270.835628 -318.320166)
		(end 270.684498 -318.320166)
		(width 0.1143)
		(layer "In5.Cu")
		(net "P5E_PEX2_STN7_RX_DN<123>")
	)
	(segment
		(start 270.570198 -318.434466)
		(end 270.570198 -319.96888)
		(width 0.1143)
		(layer "In5.Cu")
		(net "P5E_PEX2_STN7_RX_DN<123>")
	)
	(segment
		(start 290.003992 -339.4329)
		(end 290.4363 -339.6742)
		(width 0.1651)
		(layer "In5.Cu")
		(net "P5E_PEX2_STN7_RX_DN<123>")
	)
	(segment
		(start 274.752816 -330.774294)
		(end 274.752816 -330.77404)
		(width 0.1651)
		(layer "In5.Cu")
		(net "P5E_PEX2_STN7_RX_DN<123>")
	)
	(segment
		(start 290.4363 -339.6742)
		(end 291.41674 -341.03818)
		(width 0.1651)
		(layer "In5.Cu")
		(net "P5E_PEX2_STN7_RX_DN<123>")
	)
	(segment
		(start 291.787072 -358.0638)
		(end 295.215818 -368.750342)
		(width 0.1651)
		(layer "In5.Cu")
		(net "P5E_PEX2_STN7_RX_DN<123>")
	)
	(segment
		(start 295.215818 -368.750342)
		(end 295.215818 -383.629154)
		(width 0.1651)
		(layer "In5.Cu")
		(net "P5E_PEX2_STN7_RX_DN<123>")
	)
	(segment
		(start 294.216836 -384.08102)
		(end 294.089836 -384.20802)
		(width 0.1651)
		(layer "In5.Cu")
		(net "P5E_PEX2_STN7_RX_DN<123>")
	)
	(segment
		(start 291.787072 -342.00592)
		(end 291.787072 -358.0638)
		(width 0.1651)
		(layer "In5.Cu")
		(net "P5E_PEX2_STN7_RX_DN<123>")
	)
	(segment
		(start 294.089836 -384.20802)
		(end 294.089836 -384.590036)
		(width 0.1651)
		(layer "In5.Cu")
		(net "P5E_PEX2_STN7_RX_DN<123>")
	)
	(segment
		(start 289.536886 -339.070442)
		(end 289.969448 -339.311996)
		(width 0.1651)
		(layer "In5.Cu")
		(net "P5E_PEX2_STN7_RX_DN<123>")
	)
	(segment
		(start 270.615918 -320.043048)
		(end 270.615918 -325.873872)
		(width 0.1651)
		(layer "In5.Cu")
		(net "P5E_PEX2_STN7_RX_DN<123>")
	)
	(segment
		(start 271.043654 -327.053194)
		(end 273.41957 -329.880214)
		(width 0.1651)
		(layer "In5.Cu")
		(net "P5E_PEX2_STN7_RX_DN<123>")
	)
	(segment
		(start 295.215818 -383.629154)
		(end 294.763952 -384.08102)
		(width 0.1651)
		(layer "In5.Cu")
		(net "P5E_PEX2_STN7_RX_DN<123>")
	)
	(segment
		(start 274.752816 -330.77404)
		(end 276.0853 -331.667866)
		(width 0.1651)
		(layer "In5.Cu")
		(net "P5E_PEX2_STN7_RX_DN<123>")
	)
	(segment
		(start 289.415728 -339.104732)
		(end 289.536886 -339.070442)
		(width 0.1651)
		(layer "In5.Cu")
		(net "P5E_PEX2_STN7_RX_DN<123>")
	)
	(segment
		(start 270.615918 -320.0146)
		(end 270.615918 -320.043048)
		(width 0.1143)
		(layer "In5.Cu")
		(net "P5E_PEX2_STN7_RX_DN<123>")
	)
	(segment
		(start 291.41674 -341.03818)
		(end 291.787072 -342.00592)
		(width 0.1651)
		(layer "In5.Cu")
		(net "P5E_PEX2_STN7_RX_DN<123>")
	)
	(segment
		(start 270.949928 -318.434466)
		(end 270.835628 -318.320166)
		(width 0.1143)
		(layer "In5.Cu")
		(net "P5E_PEX2_STN7_RX_DN<123>")
	)
	(segment
		(start 288.51606 -338.500974)
		(end 288.948876 -338.742528)
		(width 0.1651)
		(layer "In5.Cu")
		(net "P5E_PEX2_STN7_RX_DN<123>")
	)
	(segment
		(start 270.570198 -319.96888)
		(end 270.615918 -320.0146)
		(width 0.1143)
		(layer "In5.Cu")
		(net "P5E_PEX2_STN7_RX_DN<123>")
	)
	(segment
		(start 273.41957 -329.880214)
		(end 274.752816 -330.774294)
		(width 0.1651)
		(layer "In5.Cu")
		(net "P5E_PEX2_STN7_RX_DN<123>")
	)
	(segment
		(start 288.98342 -338.863432)
		(end 289.415728 -339.104732)
		(width 0.1651)
		(layer "In5.Cu")
		(net "P5E_PEX2_STN7_RX_DN<123>")
	)
	(segment
		(start 294.763952 -384.08102)
		(end 294.216836 -384.08102)
		(width 0.1651)
		(layer "In5.Cu")
		(net "P5E_PEX2_STN7_RX_DN<123>")
	)
	(segment
		(start 154.162252 -99.608894)
		(end 153.867612 -99.314254)
		(width 0.13462)
		(layer "F.Cu")
		(net "P5E_PEX1_STN1_TX_DP<16>")
	)
	(segment
		(start 154.793696 -99.608894)
		(end 154.162252 -99.608894)
		(width 0.13462)
		(layer "F.Cu")
		(net "P5E_PEX1_STN1_TX_DP<16>")
	)
	(segment
		(start 155.113736 -99.288854)
		(end 154.793696 -99.608894)
		(width 0.13462)
		(layer "F.Cu")
		(net "P5E_PEX1_STN1_TX_DP<16>")
	)
	(segment
		(start 138.905488 -145.421858)
		(end 139.615164 -159.875728)
		(width 0.1651)
		(layer "In9.Cu")
		(net "P5E_PEX1_STN1_TX_DP<16>")
	)
	(segment
		(start 136.30529 -130.71475)
		(end 136.30529 -139.143994)
		(width 0.1651)
		(layer "In9.Cu")
		(net "P5E_PEX1_STN1_TX_DP<16>")
	)
	(segment
		(start 136.30529 -139.143994)
		(end 138.905488 -145.421858)
		(width 0.1651)
		(layer "In9.Cu")
		(net "P5E_PEX1_STN1_TX_DP<16>")
	)
	(segment
		(start 175.749712 -278.534368)
		(end 175.749712 -278.799798)
		(width 0.1143)
		(layer "In9.Cu")
		(net "P5E_PEX1_STN1_TX_DP<16>")
	)
	(segment
		(start 144.309846 -106.199178)
		(end 142.188946 -111.319818)
		(width 0.1651)
		(layer "In9.Cu")
		(net "P5E_PEX1_STN1_TX_DP<16>")
	)
	(segment
		(start 140.179806 -162.714432)
		(end 175.134016 -265.983974)
		(width 0.1651)
		(layer "In9.Cu")
		(net "P5E_PEX1_STN1_TX_DP<16>")
	)
	(segment
		(start 175.635412 -278.420068)
		(end 175.749712 -278.534368)
		(width 0.1143)
		(layer "In9.Cu")
		(net "P5E_PEX1_STN1_TX_DP<16>")
	)
	(segment
		(start 149.876764 -100.632514)
		(end 144.309846 -106.199178)
		(width 0.1651)
		(layer "In9.Cu")
		(net "P5E_PEX1_STN1_TX_DP<16>")
	)
	(segment
		(start 175.179736 -271.546066)
		(end 175.179736 -278.205184)
		(width 0.1143)
		(layer "In9.Cu")
		(net "P5E_PEX1_STN1_TX_DP<16>")
	)
	(segment
		(start 142.188946 -111.319818)
		(end 136.30529 -130.71475)
		(width 0.1651)
		(layer "In9.Cu")
		(net "P5E_PEX1_STN1_TX_DP<16>")
	)
	(segment
		(start 152.35682 -99.605084)
		(end 149.876764 -100.632514)
		(width 0.1651)
		(layer "In9.Cu")
		(net "P5E_PEX1_STN1_TX_DP<16>")
	)
	(segment
		(start 153.867612 -99.314254)
		(end 153.576782 -99.605084)
		(width 0.1651)
		(layer "In9.Cu")
		(net "P5E_PEX1_STN1_TX_DP<16>")
	)
	(segment
		(start 175.134016 -271.471898)
		(end 175.134016 -271.500346)
		(width 0.1143)
		(layer "In9.Cu")
		(net "P5E_PEX1_STN1_TX_DP<16>")
	)
	(segment
		(start 175.39462 -278.420068)
		(end 175.635412 -278.420068)
		(width 0.1143)
		(layer "In9.Cu")
		(net "P5E_PEX1_STN1_TX_DP<16>")
	)
	(segment
		(start 175.179736 -278.205184)
		(end 175.39462 -278.420068)
		(width 0.1143)
		(layer "In9.Cu")
		(net "P5E_PEX1_STN1_TX_DP<16>")
	)
	(segment
		(start 175.134016 -271.500346)
		(end 175.179736 -271.546066)
		(width 0.1143)
		(layer "In9.Cu")
		(net "P5E_PEX1_STN1_TX_DP<16>")
	)
	(segment
		(start 139.615164 -159.875728)
		(end 140.179806 -162.714432)
		(width 0.1651)
		(layer "In9.Cu")
		(net "P5E_PEX1_STN1_TX_DP<16>")
	)
	(segment
		(start 175.134016 -265.983974)
		(end 175.134016 -271.471898)
		(width 0.1651)
		(layer "In9.Cu")
		(net "P5E_PEX1_STN1_TX_DP<16>")
	)
	(segment
		(start 153.576782 -99.605084)
		(end 152.35682 -99.605084)
		(width 0.1651)
		(layer "In9.Cu")
		(net "P5E_PEX1_STN1_TX_DP<16>")
	)
	(segment
		(start 178.299872 -349.511874)
		(end 178.299872 -348.88043)
		(width 0.13462)
		(layer "F.Cu")
		(net "P5E_PEX1_STN7_TX_DN<120>")
	)
	(segment
		(start 178.299872 -348.88043)
		(end 178.594512 -348.58579)
		(width 0.13462)
		(layer "F.Cu")
		(net "P5E_PEX1_STN7_TX_DN<120>")
	)
	(segment
		(start 178.619912 -349.831914)
		(end 178.299872 -349.511874)
		(width 0.13462)
		(layer "F.Cu")
		(net "P5E_PEX1_STN7_TX_DN<120>")
	)
	(segment
		(start 149.148546 -310.725058)
		(end 149.499066 -310.374538)
		(width 0.1651)
		(layer "In11.Cu")
		(net "P5E_PEX1_STN7_TX_DN<120>")
	)
	(segment
		(start 179.858162 -341.909908)
		(end 178.789584 -340.48827)
		(width 0.1651)
		(layer "In11.Cu")
		(net "P5E_PEX1_STN7_TX_DN<120>")
	)
	(segment
		(start 141.736064 -317.6016)
		(end 142.366746 -316.970918)
		(width 0.1651)
		(layer "In11.Cu")
		(net "P5E_PEX1_STN7_TX_DN<120>")
	)
	(segment
		(start 148.273262 -311.456578)
		(end 149.004782 -310.725058)
		(width 0.1651)
		(layer "In11.Cu")
		(net "P5E_PEX1_STN7_TX_DN<120>")
	)
	(segment
		(start 157.990794 -309.199788)
		(end 157.699964 -309.199788)
		(width 0.1143)
		(layer "In11.Cu")
		(net "P5E_PEX1_STN7_TX_DN<120>")
	)
	(segment
		(start 146.08175 -313.64809)
		(end 146.889978 -312.839862)
		(width 0.1651)
		(layer "In11.Cu")
		(net "P5E_PEX1_STN7_TX_DN<120>")
	)
	(segment
		(start 143.705326 -315.632338)
		(end 144.055338 -315.282326)
		(width 0.1651)
		(layer "In11.Cu")
		(net "P5E_PEX1_STN7_TX_DN<120>")
	)
	(segment
		(start 144.899634 -314.43803)
		(end 146.08175 -313.64809)
		(width 0.1651)
		(layer "In11.Cu")
		(net "P5E_PEX1_STN7_TX_DN<120>")
	)
	(segment
		(start 158.079694 -309.110888)
		(end 157.990794 -309.199788)
		(width 0.1143)
		(layer "In11.Cu")
		(net "P5E_PEX1_STN7_TX_DN<120>")
	)
	(segment
		(start 150.343362 -309.530242)
		(end 150.343362 -309.386478)
		(width 0.1651)
		(layer "In11.Cu")
		(net "P5E_PEX1_STN7_TX_DN<120>")
	)
	(segment
		(start 144.549622 -314.931806)
		(end 144.549622 -314.788042)
		(width 0.1651)
		(layer "In11.Cu")
		(net "P5E_PEX1_STN7_TX_DN<120>")
	)
	(segment
		(start 141.022578 -323.185536)
		(end 140.574014 -321.706748)
		(width 0.1651)
		(layer "In11.Cu")
		(net "P5E_PEX1_STN7_TX_DN<120>")
	)
	(segment
		(start 144.199102 -315.282326)
		(end 144.549622 -314.931806)
		(width 0.1651)
		(layer "In11.Cu")
		(net "P5E_PEX1_STN7_TX_DN<120>")
	)
	(segment
		(start 150.864062 -308.865778)
		(end 151.664924 -308.865778)
		(width 0.1651)
		(layer "In11.Cu")
		(net "P5E_PEX1_STN7_TX_DN<120>")
	)
	(segment
		(start 147.384262 -312.489342)
		(end 147.384262 -312.345578)
		(width 0.1651)
		(layer "In11.Cu")
		(net "P5E_PEX1_STN7_TX_DN<120>")
	)
	(segment
		(start 148.273262 -311.600342)
		(end 148.273262 -311.456578)
		(width 0.1651)
		(layer "In11.Cu")
		(net "P5E_PEX1_STN7_TX_DN<120>")
	)
	(segment
		(start 178.594512 -348.58579)
		(end 178.303682 -348.29496)
		(width 0.1651)
		(layer "In11.Cu")
		(net "P5E_PEX1_STN7_TX_DN<120>")
	)
	(segment
		(start 147.778978 -311.950862)
		(end 147.922742 -311.950862)
		(width 0.1651)
		(layer "In11.Cu")
		(net "P5E_PEX1_STN7_TX_DN<120>")
	)
	(segment
		(start 141.759686 -324.288404)
		(end 141.022578 -323.185536)
		(width 0.1651)
		(layer "In11.Cu")
		(net "P5E_PEX1_STN7_TX_DN<120>")
	)
	(segment
		(start 149.004782 -310.725058)
		(end 149.148546 -310.725058)
		(width 0.1651)
		(layer "In11.Cu")
		(net "P5E_PEX1_STN7_TX_DN<120>")
	)
	(segment
		(start 179.858162 -346.142056)
		(end 179.858162 -341.909908)
		(width 0.1651)
		(layer "In11.Cu")
		(net "P5E_PEX1_STN7_TX_DN<120>")
	)
	(segment
		(start 151.687022 -308.865778)
		(end 151.732742 -308.820058)
		(width 0.1143)
		(layer "In11.Cu")
		(net "P5E_PEX1_STN7_TX_DN<120>")
	)
	(segment
		(start 157.933898 -308.820058)
		(end 158.079694 -308.965854)
		(width 0.1143)
		(layer "In11.Cu")
		(net "P5E_PEX1_STN7_TX_DN<120>")
	)
	(segment
		(start 142.86103 -316.476634)
		(end 143.211042 -316.126622)
		(width 0.1651)
		(layer "In11.Cu")
		(net "P5E_PEX1_STN7_TX_DN<120>")
	)
	(segment
		(start 168.21785 -335.473802)
		(end 149.891242 -328.679048)
		(width 0.1651)
		(layer "In11.Cu")
		(net "P5E_PEX1_STN7_TX_DN<120>")
	)
	(segment
		(start 151.664924 -308.865778)
		(end 151.687022 -308.865778)
		(width 0.1143)
		(layer "In11.Cu")
		(net "P5E_PEX1_STN7_TX_DN<120>")
	)
	(segment
		(start 178.303682 -347.696536)
		(end 179.858162 -346.142056)
		(width 0.1651)
		(layer "In11.Cu")
		(net "P5E_PEX1_STN7_TX_DN<120>")
	)
	(segment
		(start 149.849078 -309.880762)
		(end 149.992842 -309.880762)
		(width 0.1651)
		(layer "In11.Cu")
		(net "P5E_PEX1_STN7_TX_DN<120>")
	)
	(segment
		(start 142.94104 -325.300848)
		(end 141.759686 -324.288404)
		(width 0.1651)
		(layer "In11.Cu")
		(net "P5E_PEX1_STN7_TX_DN<120>")
	)
	(segment
		(start 140.574014 -320.405506)
		(end 141.736064 -317.6016)
		(width 0.1651)
		(layer "In11.Cu")
		(net "P5E_PEX1_STN7_TX_DN<120>")
	)
	(segment
		(start 142.51051 -316.970918)
		(end 142.86103 -316.620398)
		(width 0.1651)
		(layer "In11.Cu")
		(net "P5E_PEX1_STN7_TX_DN<120>")
	)
	(segment
		(start 149.499066 -310.374538)
		(end 149.499066 -310.230774)
		(width 0.1651)
		(layer "In11.Cu")
		(net "P5E_PEX1_STN7_TX_DN<120>")
	)
	(segment
		(start 143.211042 -316.126622)
		(end 143.354806 -316.126622)
		(width 0.1651)
		(layer "In11.Cu")
		(net "P5E_PEX1_STN7_TX_DN<120>")
	)
	(segment
		(start 144.009872 -325.99376)
		(end 142.94104 -325.300848)
		(width 0.1651)
		(layer "In11.Cu")
		(net "P5E_PEX1_STN7_TX_DN<120>")
	)
	(segment
		(start 142.366746 -316.970918)
		(end 142.51051 -316.970918)
		(width 0.1651)
		(layer "In11.Cu")
		(net "P5E_PEX1_STN7_TX_DN<120>")
	)
	(segment
		(start 178.303682 -348.29496)
		(end 178.303682 -347.696536)
		(width 0.1651)
		(layer "In11.Cu")
		(net "P5E_PEX1_STN7_TX_DN<120>")
	)
	(segment
		(start 144.055338 -315.282326)
		(end 144.199102 -315.282326)
		(width 0.1651)
		(layer "In11.Cu")
		(net "P5E_PEX1_STN7_TX_DN<120>")
	)
	(segment
		(start 147.384262 -312.345578)
		(end 147.778978 -311.950862)
		(width 0.1651)
		(layer "In11.Cu")
		(net "P5E_PEX1_STN7_TX_DN<120>")
	)
	(segment
		(start 149.499066 -310.230774)
		(end 149.849078 -309.880762)
		(width 0.1651)
		(layer "In11.Cu")
		(net "P5E_PEX1_STN7_TX_DN<120>")
	)
	(segment
		(start 178.789584 -340.48827)
		(end 168.21785 -335.473802)
		(width 0.1651)
		(layer "In11.Cu")
		(net "P5E_PEX1_STN7_TX_DN<120>")
	)
	(segment
		(start 151.732742 -308.820058)
		(end 157.933898 -308.820058)
		(width 0.1143)
		(layer "In11.Cu")
		(net "P5E_PEX1_STN7_TX_DN<120>")
	)
	(segment
		(start 144.549622 -314.788042)
		(end 144.899634 -314.43803)
		(width 0.1651)
		(layer "In11.Cu")
		(net "P5E_PEX1_STN7_TX_DN<120>")
	)
	(segment
		(start 158.079694 -308.965854)
		(end 158.079694 -309.110888)
		(width 0.1143)
		(layer "In11.Cu")
		(net "P5E_PEX1_STN7_TX_DN<120>")
	)
	(segment
		(start 147.922742 -311.950862)
		(end 148.273262 -311.600342)
		(width 0.1651)
		(layer "In11.Cu")
		(net "P5E_PEX1_STN7_TX_DN<120>")
	)
	(segment
		(start 143.354806 -316.126622)
		(end 143.705326 -315.776102)
		(width 0.1651)
		(layer "In11.Cu")
		(net "P5E_PEX1_STN7_TX_DN<120>")
	)
	(segment
		(start 149.992842 -309.880762)
		(end 150.343362 -309.530242)
		(width 0.1651)
		(layer "In11.Cu")
		(net "P5E_PEX1_STN7_TX_DN<120>")
	)
	(segment
		(start 143.705326 -315.776102)
		(end 143.705326 -315.632338)
		(width 0.1651)
		(layer "In11.Cu")
		(net "P5E_PEX1_STN7_TX_DN<120>")
	)
	(segment
		(start 146.889978 -312.839862)
		(end 147.033742 -312.839862)
		(width 0.1651)
		(layer "In11.Cu")
		(net "P5E_PEX1_STN7_TX_DN<120>")
	)
	(segment
		(start 140.574014 -321.706748)
		(end 140.574014 -320.405506)
		(width 0.1651)
		(layer "In11.Cu")
		(net "P5E_PEX1_STN7_TX_DN<120>")
	)
	(segment
		(start 142.86103 -316.620398)
		(end 142.86103 -316.476634)
		(width 0.1651)
		(layer "In11.Cu")
		(net "P5E_PEX1_STN7_TX_DN<120>")
	)
	(segment
		(start 147.033742 -312.839862)
		(end 147.384262 -312.489342)
		(width 0.1651)
		(layer "In11.Cu")
		(net "P5E_PEX1_STN7_TX_DN<120>")
	)
	(segment
		(start 150.343362 -309.386478)
		(end 150.864062 -308.865778)
		(width 0.1651)
		(layer "In11.Cu")
		(net "P5E_PEX1_STN7_TX_DN<120>")
	)
	(segment
		(start 149.891242 -328.679048)
		(end 144.009872 -325.99376)
		(width 0.1651)
		(layer "In11.Cu")
		(net "P5E_PEX1_STN7_TX_DN<120>")
	)
	(segment
		(start 267.6271 -105.283)
		(end 268.244828 -105.283)
		(width 0.13462)
		(layer "F.Cu")
		(net "P5E_PEX2_STN1_TX_DP<19>")
	)
	(segment
		(start 268.244828 -105.283)
		(end 268.571726 -105.609898)
		(width 0.13462)
		(layer "F.Cu")
		(net "P5E_PEX2_STN1_TX_DP<19>")
	)
	(segment
		(start 267.325602 -105.584498)
		(end 267.6271 -105.283)
		(width 0.13462)
		(layer "F.Cu")
		(net "P5E_PEX2_STN1_TX_DP<19>")
	)
	(segment
		(start 264.414762 -107.512104)
		(end 264.064242 -107.862624)
		(width 0.1651)
		(layer "In9.Cu")
		(net "P5E_PEX2_STN1_TX_DP<19>")
	)
	(segment
		(start 262.450834 -110.969552)
		(end 262.301228 -111.031274)
		(width 0.1651)
		(layer "In9.Cu")
		(net "P5E_PEX2_STN1_TX_DP<19>")
	)
	(segment
		(start 264.926572 -107.018328)
		(end 264.764774 -107.018328)
		(width 0.1651)
		(layer "In9.Cu")
		(net "P5E_PEX2_STN1_TX_DP<19>")
	)
	(segment
		(start 261.984236 -112.096042)
		(end 261.83463 -112.157764)
		(width 0.1651)
		(layer "In9.Cu")
		(net "P5E_PEX2_STN1_TX_DP<19>")
	)
	(segment
		(start 262.917432 -109.843062)
		(end 262.767826 -109.904784)
		(width 0.1651)
		(layer "In9.Cu")
		(net "P5E_PEX2_STN1_TX_DP<19>")
	)
	(segment
		(start 265.277092 -106.50601)
		(end 265.277092 -106.667808)
		(width 0.1651)
		(layer "In9.Cu")
		(net "P5E_PEX2_STN1_TX_DP<19>")
	)
	(segment
		(start 263.106916 -109.3851)
		(end 262.917432 -109.843062)
		(width 0.1651)
		(layer "In9.Cu")
		(net "P5E_PEX2_STN1_TX_DP<19>")
	)
	(segment
		(start 261.368286 -113.284254)
		(end 261.178802 -113.741708)
		(width 0.1651)
		(layer "In9.Cu")
		(net "P5E_PEX2_STN1_TX_DP<19>")
	)
	(segment
		(start 262.578342 -110.362238)
		(end 262.640318 -110.51159)
		(width 0.1651)
		(layer "In9.Cu")
		(net "P5E_PEX2_STN1_TX_DP<19>")
	)
	(segment
		(start 294.31996 -280.025856)
		(end 294.423592 -280.129488)
		(width 0.1143)
		(layer "In9.Cu")
		(net "P5E_PEX2_STN1_TX_DP<19>")
	)
	(segment
		(start 267.325602 -105.584498)
		(end 267.034772 -105.293668)
		(width 0.1651)
		(layer "In9.Cu")
		(net "P5E_PEX2_STN1_TX_DP<19>")
	)
	(segment
		(start 261.707376 -112.76457)
		(end 261.517892 -113.222532)
		(width 0.1651)
		(layer "In9.Cu")
		(net "P5E_PEX2_STN1_TX_DP<19>")
	)
	(segment
		(start 255.590294 -138.417046)
		(end 258.150106 -144.596358)
		(width 0.1651)
		(layer "In9.Cu")
		(net "P5E_PEX2_STN1_TX_DP<19>")
	)
	(segment
		(start 262.111998 -111.488728)
		(end 262.111744 -111.488728)
		(width 0.1651)
		(layer "In9.Cu")
		(net "P5E_PEX2_STN1_TX_DP<19>")
	)
	(segment
		(start 263.396984 -108.385864)
		(end 263.04494 -109.235748)
		(width 0.1651)
		(layer "In9.Cu")
		(net "P5E_PEX2_STN1_TX_DP<19>")
	)
	(segment
		(start 260.901688 -114.410744)
		(end 260.901942 -114.410744)
		(width 0.1651)
		(layer "In9.Cu")
		(net "P5E_PEX2_STN1_TX_DP<19>")
	)
	(segment
		(start 262.640318 -110.51159)
		(end 262.450834 -110.969552)
		(width 0.1651)
		(layer "In9.Cu")
		(net "P5E_PEX2_STN1_TX_DP<19>")
	)
	(segment
		(start 261.83463 -112.157764)
		(end 261.834884 -112.157764)
		(width 0.1651)
		(layer "In9.Cu")
		(net "P5E_PEX2_STN1_TX_DP<19>")
	)
	(segment
		(start 258.150106 -144.596358)
		(end 258.865878 -159.178498)
		(width 0.1651)
		(layer "In9.Cu")
		(net "P5E_PEX2_STN1_TX_DP<19>")
	)
	(segment
		(start 265.277092 -106.667808)
		(end 264.926572 -107.018328)
		(width 0.1651)
		(layer "In9.Cu")
		(net "P5E_PEX2_STN1_TX_DP<19>")
	)
	(segment
		(start 294.69969 -280.015188)
		(end 294.69969 -279.749504)
		(width 0.1143)
		(layer "In9.Cu")
		(net "P5E_PEX2_STN1_TX_DP<19>")
	)
	(segment
		(start 294.36568 -271.554448)
		(end 294.31996 -271.600168)
		(width 0.1143)
		(layer "In9.Cu")
		(net "P5E_PEX2_STN1_TX_DP<19>")
	)
	(segment
		(start 265.627104 -106.155998)
		(end 265.277092 -106.50601)
		(width 0.1651)
		(layer "In9.Cu")
		(net "P5E_PEX2_STN1_TX_DP<19>")
	)
	(segment
		(start 263.04494 -109.235748)
		(end 263.106916 -109.3851)
		(width 0.1651)
		(layer "In9.Cu")
		(net "P5E_PEX2_STN1_TX_DP<19>")
	)
	(segment
		(start 294.58539 -280.129488)
		(end 294.69969 -280.015188)
		(width 0.1143)
		(layer "In9.Cu")
		(net "P5E_PEX2_STN1_TX_DP<19>")
	)
	(segment
		(start 262.767826 -109.904784)
		(end 262.578342 -110.362238)
		(width 0.1651)
		(layer "In9.Cu")
		(net "P5E_PEX2_STN1_TX_DP<19>")
	)
	(segment
		(start 255.590294 -131.101338)
		(end 255.590294 -138.417046)
		(width 0.1651)
		(layer "In9.Cu")
		(net "P5E_PEX2_STN1_TX_DP<19>")
	)
	(segment
		(start 261.834884 -112.157764)
		(end 261.6454 -112.615218)
		(width 0.1651)
		(layer "In9.Cu")
		(net "P5E_PEX2_STN1_TX_DP<19>")
	)
	(segment
		(start 262.301228 -111.031274)
		(end 262.301482 -111.031274)
		(width 0.1651)
		(layer "In9.Cu")
		(net "P5E_PEX2_STN1_TX_DP<19>")
	)
	(segment
		(start 266.489434 -105.293668)
		(end 266.139422 -105.64368)
		(width 0.1651)
		(layer "In9.Cu")
		(net "P5E_PEX2_STN1_TX_DP<19>")
	)
	(segment
		(start 266.139422 -105.805478)
		(end 265.788902 -106.155998)
		(width 0.1651)
		(layer "In9.Cu")
		(net "P5E_PEX2_STN1_TX_DP<19>")
	)
	(segment
		(start 266.139422 -105.64368)
		(end 266.139422 -105.805478)
		(width 0.1651)
		(layer "In9.Cu")
		(net "P5E_PEX2_STN1_TX_DP<19>")
	)
	(segment
		(start 264.764774 -107.018328)
		(end 264.414762 -107.36834)
		(width 0.1651)
		(layer "In9.Cu")
		(net "P5E_PEX2_STN1_TX_DP<19>")
	)
	(segment
		(start 294.423592 -280.129488)
		(end 294.58539 -280.129488)
		(width 0.1143)
		(layer "In9.Cu")
		(net "P5E_PEX2_STN1_TX_DP<19>")
	)
	(segment
		(start 264.064242 -107.862624)
		(end 263.920478 -107.862624)
		(width 0.1651)
		(layer "In9.Cu")
		(net "P5E_PEX2_STN1_TX_DP<19>")
	)
	(segment
		(start 263.920478 -107.862624)
		(end 263.397238 -108.385864)
		(width 0.1651)
		(layer "In9.Cu")
		(net "P5E_PEX2_STN1_TX_DP<19>")
	)
	(segment
		(start 263.397238 -108.385864)
		(end 263.396984 -108.385864)
		(width 0.1651)
		(layer "In9.Cu")
		(net "P5E_PEX2_STN1_TX_DP<19>")
	)
	(segment
		(start 265.788902 -106.155998)
		(end 265.627104 -106.155998)
		(width 0.1651)
		(layer "In9.Cu")
		(net "P5E_PEX2_STN1_TX_DP<19>")
	)
	(segment
		(start 261.240778 -113.89106)
		(end 261.051294 -114.349022)
		(width 0.1651)
		(layer "In9.Cu")
		(net "P5E_PEX2_STN1_TX_DP<19>")
	)
	(segment
		(start 294.36568 -271.526)
		(end 294.36568 -271.554448)
		(width 0.1143)
		(layer "In9.Cu")
		(net "P5E_PEX2_STN1_TX_DP<19>")
	)
	(segment
		(start 259.97408 -116.651278)
		(end 255.590294 -131.101338)
		(width 0.1651)
		(layer "In9.Cu")
		(net "P5E_PEX2_STN1_TX_DP<19>")
	)
	(segment
		(start 264.414762 -107.36834)
		(end 264.414762 -107.512104)
		(width 0.1651)
		(layer "In9.Cu")
		(net "P5E_PEX2_STN1_TX_DP<19>")
	)
	(segment
		(start 294.31996 -271.600168)
		(end 294.31996 -280.025856)
		(width 0.1143)
		(layer "In9.Cu")
		(net "P5E_PEX2_STN1_TX_DP<19>")
	)
	(segment
		(start 262.17372 -111.63808)
		(end 261.984236 -112.096042)
		(width 0.1651)
		(layer "In9.Cu")
		(net "P5E_PEX2_STN1_TX_DP<19>")
	)
	(segment
		(start 294.36568 -265.298682)
		(end 294.36568 -271.526)
		(width 0.1651)
		(layer "In9.Cu")
		(net "P5E_PEX2_STN1_TX_DP<19>")
	)
	(segment
		(start 267.034772 -105.293668)
		(end 266.489434 -105.293668)
		(width 0.1651)
		(layer "In9.Cu")
		(net "P5E_PEX2_STN1_TX_DP<19>")
	)
	(segment
		(start 258.865878 -159.178498)
		(end 259.46481 -162.189414)
		(width 0.1651)
		(layer "In9.Cu")
		(net "P5E_PEX2_STN1_TX_DP<19>")
	)
	(segment
		(start 260.901942 -114.410744)
		(end 259.97408 -116.651278)
		(width 0.1651)
		(layer "In9.Cu")
		(net "P5E_PEX2_STN1_TX_DP<19>")
	)
	(segment
		(start 261.051294 -114.349022)
		(end 260.901688 -114.410744)
		(width 0.1651)
		(layer "In9.Cu")
		(net "P5E_PEX2_STN1_TX_DP<19>")
	)
	(segment
		(start 262.111744 -111.488728)
		(end 262.17372 -111.63808)
		(width 0.1651)
		(layer "In9.Cu")
		(net "P5E_PEX2_STN1_TX_DP<19>")
	)
	(segment
		(start 262.301482 -111.031274)
		(end 262.111998 -111.488728)
		(width 0.1651)
		(layer "In9.Cu")
		(net "P5E_PEX2_STN1_TX_DP<19>")
	)
	(segment
		(start 261.178802 -113.741708)
		(end 261.240778 -113.89106)
		(width 0.1651)
		(layer "In9.Cu")
		(net "P5E_PEX2_STN1_TX_DP<19>")
	)
	(segment
		(start 259.46481 -162.189414)
		(end 294.36568 -265.298682)
		(width 0.1651)
		(layer "In9.Cu")
		(net "P5E_PEX2_STN1_TX_DP<19>")
	)
	(segment
		(start 261.6454 -112.615218)
		(end 261.707376 -112.76457)
		(width 0.1651)
		(layer "In9.Cu")
		(net "P5E_PEX2_STN1_TX_DP<19>")
	)
	(segment
		(start 261.517892 -113.222532)
		(end 261.368286 -113.284254)
		(width 0.1651)
		(layer "In9.Cu")
		(net "P5E_PEX2_STN1_TX_DP<19>")
	)
	(segment
		(start 156.494734 -384.092704)
		(end 151.133302 -344.388948)
		(width 0.1651)
		(layer "In9.Cu")
		(net "P5E_PEX1_STN7_RX_DN<117>")
	)
	(segment
		(start 142.636748 -312.91149)
		(end 142.608554 -312.77052)
		(width 0.1651)
		(layer "In9.Cu")
		(net "P5E_PEX1_STN7_RX_DN<117>")
	)
	(segment
		(start 147.268438 -307.163216)
		(end 148.409406 -306.568094)
		(width 0.1651)
		(layer "In9.Cu")
		(net "P5E_PEX1_STN7_RX_DN<117>")
	)
	(segment
		(start 170.909996 -410.589984)
		(end 170.909996 -410.208222)
		(width 0.1651)
		(layer "In9.Cu")
		(net "P5E_PEX1_STN7_RX_DN<117>")
	)
	(segment
		(start 172.074332 -395.360652)
		(end 170.118278 -393.404598)
		(width 0.1651)
		(layer "In9.Cu")
		(net "P5E_PEX1_STN7_RX_DN<117>")
	)
	(segment
		(start 151.793448 -306.015898)
		(end 151.839168 -305.970178)
		(width 0.1143)
		(layer "In9.Cu")
		(net "P5E_PEX1_STN7_RX_DN<117>")
	)
	(segment
		(start 148.409406 -306.568094)
		(end 148.546566 -306.611274)
		(width 0.1651)
		(layer "In9.Cu")
		(net "P5E_PEX1_STN7_RX_DN<117>")
	)
	(segment
		(start 138.830812 -319.654936)
		(end 140.454888 -315.99378)
		(width 0.1651)
		(layer "In9.Cu")
		(net "P5E_PEX1_STN7_RX_DN<117>")
	)
	(segment
		(start 143.271748 -311.777634)
		(end 143.54683 -311.3659)
		(width 0.1651)
		(layer "In9.Cu")
		(net "P5E_PEX1_STN7_RX_DN<117>")
	)
	(segment
		(start 160.740852 -388.855458)
		(end 157.782514 -386.442712)
		(width 0.1651)
		(layer "In9.Cu")
		(net "P5E_PEX1_STN7_RX_DN<117>")
	)
	(segment
		(start 153.2382 -306.349908)
		(end 152.94991 -306.349908)
		(width 0.1143)
		(layer "In9.Cu")
		(net "P5E_PEX1_STN7_RX_DN<117>")
	)
	(segment
		(start 140.454888 -315.99378)
		(end 142.220188 -313.351418)
		(width 0.1651)
		(layer "In9.Cu")
		(net "P5E_PEX1_STN7_RX_DN<117>")
	)
	(segment
		(start 142.608554 -312.77052)
		(end 142.883636 -312.358786)
		(width 0.1651)
		(layer "In9.Cu")
		(net "P5E_PEX1_STN7_RX_DN<117>")
	)
	(segment
		(start 170.909996 -410.208222)
		(end 171.036996 -410.081222)
		(width 0.1651)
		(layer "In9.Cu")
		(net "P5E_PEX1_STN7_RX_DN<117>")
	)
	(segment
		(start 153.201878 -305.970178)
		(end 153.334212 -306.102512)
		(width 0.1143)
		(layer "In9.Cu")
		(net "P5E_PEX1_STN7_RX_DN<117>")
	)
	(segment
		(start 153.334212 -306.253896)
		(end 153.2382 -306.349908)
		(width 0.1143)
		(layer "In9.Cu")
		(net "P5E_PEX1_STN7_RX_DN<117>")
	)
	(segment
		(start 146.07413 -308.501288)
		(end 146.07413 -308.357524)
		(width 0.1651)
		(layer "In9.Cu")
		(net "P5E_PEX1_STN7_RX_DN<117>")
	)
	(segment
		(start 143.6878 -311.337706)
		(end 143.963136 -310.925718)
		(width 0.1651)
		(layer "In9.Cu")
		(net "P5E_PEX1_STN7_RX_DN<117>")
	)
	(segment
		(start 146.07413 -308.357524)
		(end 146.424142 -308.007512)
		(width 0.1651)
		(layer "In9.Cu")
		(net "P5E_PEX1_STN7_RX_DN<117>")
	)
	(segment
		(start 171.375324 -410.081222)
		(end 172.074332 -409.382214)
		(width 0.1651)
		(layer "In9.Cu")
		(net "P5E_PEX1_STN7_RX_DN<117>")
	)
	(segment
		(start 138.830812 -322.522342)
		(end 138.830812 -319.654936)
		(width 0.1651)
		(layer "In9.Cu")
		(net "P5E_PEX1_STN7_RX_DN<117>")
	)
	(segment
		(start 143.963136 -310.925718)
		(end 143.935196 -310.784748)
		(width 0.1651)
		(layer "In9.Cu")
		(net "P5E_PEX1_STN7_RX_DN<117>")
	)
	(segment
		(start 142.361158 -313.323478)
		(end 142.636748 -312.91149)
		(width 0.1651)
		(layer "In9.Cu")
		(net "P5E_PEX1_STN7_RX_DN<117>")
	)
	(segment
		(start 143.299942 -311.918604)
		(end 143.271748 -311.777634)
		(width 0.1651)
		(layer "In9.Cu")
		(net "P5E_PEX1_STN7_RX_DN<117>")
	)
	(segment
		(start 157.782514 -386.442712)
		(end 156.494734 -384.092704)
		(width 0.1651)
		(layer "In9.Cu")
		(net "P5E_PEX1_STN7_RX_DN<117>")
	)
	(segment
		(start 146.918426 -307.513228)
		(end 147.268438 -307.163216)
		(width 0.1651)
		(layer "In9.Cu")
		(net "P5E_PEX1_STN7_RX_DN<117>")
	)
	(segment
		(start 170.118278 -393.404598)
		(end 167.510714 -391.66165)
		(width 0.1651)
		(layer "In9.Cu")
		(net "P5E_PEX1_STN7_RX_DN<117>")
	)
	(segment
		(start 149.758146 -340.54923)
		(end 138.995404 -323.135244)
		(width 0.1651)
		(layer "In9.Cu")
		(net "P5E_PEX1_STN7_RX_DN<117>")
	)
	(segment
		(start 146.567906 -308.007512)
		(end 146.918426 -307.656992)
		(width 0.1651)
		(layer "In9.Cu")
		(net "P5E_PEX1_STN7_RX_DN<117>")
	)
	(segment
		(start 164.125148 -390.2583)
		(end 160.740852 -388.855458)
		(width 0.1651)
		(layer "In9.Cu")
		(net "P5E_PEX1_STN7_RX_DN<117>")
	)
	(segment
		(start 148.546566 -306.611274)
		(end 148.985986 -306.381912)
		(width 0.1651)
		(layer "In9.Cu")
		(net "P5E_PEX1_STN7_RX_DN<117>")
	)
	(segment
		(start 151.133302 -344.388948)
		(end 149.758146 -340.54923)
		(width 0.1651)
		(layer "In9.Cu")
		(net "P5E_PEX1_STN7_RX_DN<117>")
	)
	(segment
		(start 145.579846 -308.851808)
		(end 145.72361 -308.851808)
		(width 0.1651)
		(layer "In9.Cu")
		(net "P5E_PEX1_STN7_RX_DN<117>")
	)
	(segment
		(start 142.883636 -312.358786)
		(end 143.024352 -312.330592)
		(width 0.1651)
		(layer "In9.Cu")
		(net "P5E_PEX1_STN7_RX_DN<117>")
	)
	(segment
		(start 167.510714 -391.66165)
		(end 164.125656 -390.258554)
		(width 0.1651)
		(layer "In9.Cu")
		(net "P5E_PEX1_STN7_RX_DN<117>")
	)
	(segment
		(start 151.839168 -305.970178)
		(end 153.201878 -305.970178)
		(width 0.1143)
		(layer "In9.Cu")
		(net "P5E_PEX1_STN7_RX_DN<117>")
	)
	(segment
		(start 143.024352 -312.330592)
		(end 143.299942 -311.918604)
		(width 0.1651)
		(layer "In9.Cu")
		(net "P5E_PEX1_STN7_RX_DN<117>")
	)
	(segment
		(start 148.985986 -306.381912)
		(end 149.029166 -306.244752)
		(width 0.1651)
		(layer "In9.Cu")
		(net "P5E_PEX1_STN7_RX_DN<117>")
	)
	(segment
		(start 138.995404 -323.135244)
		(end 138.830812 -322.522342)
		(width 0.1651)
		(layer "In9.Cu")
		(net "P5E_PEX1_STN7_RX_DN<117>")
	)
	(segment
		(start 143.935196 -310.784748)
		(end 144.515332 -309.916322)
		(width 0.1651)
		(layer "In9.Cu")
		(net "P5E_PEX1_STN7_RX_DN<117>")
	)
	(segment
		(start 144.515332 -309.916322)
		(end 145.579846 -308.851808)
		(width 0.1651)
		(layer "In9.Cu")
		(net "P5E_PEX1_STN7_RX_DN<117>")
	)
	(segment
		(start 172.074332 -409.382214)
		(end 172.074332 -395.360652)
		(width 0.1651)
		(layer "In9.Cu")
		(net "P5E_PEX1_STN7_RX_DN<117>")
	)
	(segment
		(start 149.029166 -306.244752)
		(end 149.467824 -306.015898)
		(width 0.1651)
		(layer "In9.Cu")
		(net "P5E_PEX1_STN7_RX_DN<117>")
	)
	(segment
		(start 145.72361 -308.851808)
		(end 146.07413 -308.501288)
		(width 0.1651)
		(layer "In9.Cu")
		(net "P5E_PEX1_STN7_RX_DN<117>")
	)
	(segment
		(start 142.220188 -313.351418)
		(end 142.361158 -313.323478)
		(width 0.1651)
		(layer "In9.Cu")
		(net "P5E_PEX1_STN7_RX_DN<117>")
	)
	(segment
		(start 143.54683 -311.3659)
		(end 143.6878 -311.337706)
		(width 0.1651)
		(layer "In9.Cu")
		(net "P5E_PEX1_STN7_RX_DN<117>")
	)
	(segment
		(start 146.918426 -307.656992)
		(end 146.918426 -307.513228)
		(width 0.1651)
		(layer "In9.Cu")
		(net "P5E_PEX1_STN7_RX_DN<117>")
	)
	(segment
		(start 149.467824 -306.015898)
		(end 151.765 -306.015898)
		(width 0.1651)
		(layer "In9.Cu")
		(net "P5E_PEX1_STN7_RX_DN<117>")
	)
	(segment
		(start 164.125656 -390.258554)
		(end 164.125148 -390.2583)
		(width 0.1651)
		(layer "In9.Cu")
		(net "P5E_PEX1_STN7_RX_DN<117>")
	)
	(segment
		(start 151.765 -306.015898)
		(end 151.793448 -306.015898)
		(width 0.1143)
		(layer "In9.Cu")
		(net "P5E_PEX1_STN7_RX_DN<117>")
	)
	(segment
		(start 153.334212 -306.102512)
		(end 153.334212 -306.253896)
		(width 0.1143)
		(layer "In9.Cu")
		(net "P5E_PEX1_STN7_RX_DN<117>")
	)
	(segment
		(start 171.036996 -410.081222)
		(end 171.375324 -410.081222)
		(width 0.1651)
		(layer "In9.Cu")
		(net "P5E_PEX1_STN7_RX_DN<117>")
	)
	(segment
		(start 146.424142 -308.007512)
		(end 146.567906 -308.007512)
		(width 0.1651)
		(layer "In9.Cu")
		(net "P5E_PEX1_STN7_RX_DN<117>")
	)
	(segment
		(start 19.901408 -351.316798)
		(end 19.901408 -350.685354)
		(width 0.13462)
		(layer "F.Cu")
		(net "P5E_PEX0_STN7_TX_C_DN<112>")
	)
	(segment
		(start 20.196048 -351.611438)
		(end 19.901408 -351.316798)
		(width 0.13462)
		(layer "F.Cu")
		(net "P5E_PEX0_STN7_TX_C_DN<112>")
	)
	(segment
		(start 19.901408 -350.685354)
		(end 20.221448 -350.365314)
		(width 0.13462)
		(layer "F.Cu")
		(net "P5E_PEX0_STN7_TX_C_DN<112>")
	)
	(segment
		(start 24.53513 -391.808462)
		(end 21.74494 -389.018272)
		(width 0.1651)
		(layer "In7.Cu")
		(net "P5E_PEX0_STN7_TX_C_DN<112>")
	)
	(segment
		(start 21.74494 -389.018272)
		(end 20.064984 -385.28498)
		(width 0.1651)
		(layer "In7.Cu")
		(net "P5E_PEX0_STN7_TX_C_DN<112>")
	)
	(segment
		(start 19.139408 -369.929664)
		(end 19.905218 -354.344478)
		(width 0.1651)
		(layer "In7.Cu")
		(net "P5E_PEX0_STN7_TX_C_DN<112>")
	)
	(segment
		(start 29.08427 -400.607276)
		(end 29.08427 -394.00607)
		(width 0.1651)
		(layer "In7.Cu")
		(net "P5E_PEX0_STN7_TX_C_DN<112>")
	)
	(segment
		(start 20.064984 -385.28498)
		(end 19.139408 -369.929664)
		(width 0.1651)
		(layer "In7.Cu")
		(net "P5E_PEX0_STN7_TX_C_DN<112>")
	)
	(segment
		(start 28.5496 -393.4714)
		(end 24.53513 -391.808462)
		(width 0.1651)
		(layer "In7.Cu")
		(net "P5E_PEX0_STN7_TX_C_DN<112>")
	)
	(segment
		(start 19.905218 -351.902268)
		(end 20.196048 -351.611438)
		(width 0.1651)
		(layer "In7.Cu")
		(net "P5E_PEX0_STN7_TX_C_DN<112>")
	)
	(segment
		(start 19.905218 -354.344478)
		(end 19.905218 -351.902268)
		(width 0.1651)
		(layer "In7.Cu")
		(net "P5E_PEX0_STN7_TX_C_DN<112>")
	)
	(segment
		(start 27.910028 -401.308062)
		(end 28.037028 -401.181062)
		(width 0.1651)
		(layer "In7.Cu")
		(net "P5E_PEX0_STN7_TX_C_DN<112>")
	)
	(segment
		(start 28.037028 -401.181062)
		(end 28.510484 -401.181062)
		(width 0.1651)
		(layer "In7.Cu")
		(net "P5E_PEX0_STN7_TX_C_DN<112>")
	)
	(segment
		(start 28.510484 -401.181062)
		(end 29.08427 -400.607276)
		(width 0.1651)
		(layer "In7.Cu")
		(net "P5E_PEX0_STN7_TX_C_DN<112>")
	)
	(segment
		(start 27.910028 -401.690078)
		(end 27.910028 -401.308062)
		(width 0.1651)
		(layer "In7.Cu")
		(net "P5E_PEX0_STN7_TX_C_DN<112>")
	)
	(segment
		(start 29.08427 -394.00607)
		(end 28.5496 -393.4714)
		(width 0.1651)
		(layer "In7.Cu")
		(net "P5E_PEX0_STN7_TX_C_DN<112>")
	)
	(segment
		(start 187.352432 -345.170506)
		(end 187.352432 -344.539062)
		(width 0.13462)
		(layer "F.Cu")
		(net "P5E_PEX1_STN7_TX_C_DP<124>")
	)
	(segment
		(start 187.057792 -345.465146)
		(end 187.352432 -345.170506)
		(width 0.13462)
		(layer "F.Cu")
		(net "P5E_PEX1_STN7_TX_C_DP<124>")
	)
	(segment
		(start 187.352432 -344.539062)
		(end 187.032392 -344.219022)
		(width 0.13462)
		(layer "F.Cu")
		(net "P5E_PEX1_STN7_TX_C_DP<124>")
	)
	(segment
		(start 183.978804 -360.219752)
		(end 184.329324 -359.869232)
		(width 0.1651)
		(layer "In11.Cu")
		(net "P5E_PEX1_STN7_TX_C_DP<124>")
	)
	(segment
		(start 170.936158 -367.545366)
		(end 181.006496 -363.31779)
		(width 0.1651)
		(layer "In11.Cu")
		(net "P5E_PEX1_STN7_TX_C_DP<124>")
	)
	(segment
		(start 184.329324 -359.869232)
		(end 184.455054 -359.869232)
		(width 0.1651)
		(layer "In11.Cu")
		(net "P5E_PEX1_STN7_TX_C_DP<124>")
	)
	(segment
		(start 181.976268 -362.348018)
		(end 182.32628 -361.998006)
		(width 0.1651)
		(layer "In11.Cu")
		(net "P5E_PEX1_STN7_TX_C_DP<124>")
	)
	(segment
		(start 168.710102 -374.390158)
		(end 168.710102 -374.772174)
		(width 0.1651)
		(layer "In11.Cu")
		(net "P5E_PEX1_STN7_TX_C_DP<124>")
	)
	(segment
		(start 185.794142 -347.937328)
		(end 187.348622 -346.382848)
		(width 0.1651)
		(layer "In11.Cu")
		(net "P5E_PEX1_STN7_TX_C_DP<124>")
	)
	(segment
		(start 183.503062 -360.695494)
		(end 183.628792 -360.695494)
		(width 0.1651)
		(layer "In11.Cu")
		(net "P5E_PEX1_STN7_TX_C_DP<124>")
	)
	(segment
		(start 185.794142 -358.530144)
		(end 185.794142 -347.937328)
		(width 0.1651)
		(layer "In11.Cu")
		(net "P5E_PEX1_STN7_TX_C_DP<124>")
	)
	(segment
		(start 169.58564 -368.895884)
		(end 170.936158 -367.545366)
		(width 0.1651)
		(layer "In11.Cu")
		(net "P5E_PEX1_STN7_TX_C_DP<124>")
	)
	(segment
		(start 183.978804 -360.345482)
		(end 183.978804 -360.219752)
		(width 0.1651)
		(layer "In11.Cu")
		(net "P5E_PEX1_STN7_TX_C_DP<124>")
	)
	(segment
		(start 181.850538 -362.348018)
		(end 181.976268 -362.348018)
		(width 0.1651)
		(layer "In11.Cu")
		(net "P5E_PEX1_STN7_TX_C_DP<124>")
	)
	(segment
		(start 184.455054 -359.869232)
		(end 185.794142 -358.530144)
		(width 0.1651)
		(layer "In11.Cu")
		(net "P5E_PEX1_STN7_TX_C_DP<124>")
	)
	(segment
		(start 182.32628 -361.998006)
		(end 182.32628 -361.872276)
		(width 0.1651)
		(layer "In11.Cu")
		(net "P5E_PEX1_STN7_TX_C_DP<124>")
	)
	(segment
		(start 187.348622 -346.382848)
		(end 187.348622 -345.755976)
		(width 0.1651)
		(layer "In11.Cu")
		(net "P5E_PEX1_STN7_TX_C_DP<124>")
	)
	(segment
		(start 169.58564 -374.372124)
		(end 169.58564 -368.895884)
		(width 0.1651)
		(layer "In11.Cu")
		(net "P5E_PEX1_STN7_TX_C_DP<124>")
	)
	(segment
		(start 181.006496 -363.31779)
		(end 181.500018 -362.824268)
		(width 0.1651)
		(layer "In11.Cu")
		(net "P5E_PEX1_STN7_TX_C_DP<124>")
	)
	(segment
		(start 183.152542 -361.171744)
		(end 183.152542 -361.046014)
		(width 0.1651)
		(layer "In11.Cu")
		(net "P5E_PEX1_STN7_TX_C_DP<124>")
	)
	(segment
		(start 183.152542 -361.046014)
		(end 183.503062 -360.695494)
		(width 0.1651)
		(layer "In11.Cu")
		(net "P5E_PEX1_STN7_TX_C_DP<124>")
	)
	(segment
		(start 183.628792 -360.695494)
		(end 183.978804 -360.345482)
		(width 0.1651)
		(layer "In11.Cu")
		(net "P5E_PEX1_STN7_TX_C_DP<124>")
	)
	(segment
		(start 181.500018 -362.698538)
		(end 181.850538 -362.348018)
		(width 0.1651)
		(layer "In11.Cu")
		(net "P5E_PEX1_STN7_TX_C_DP<124>")
	)
	(segment
		(start 182.80253 -361.521756)
		(end 183.152542 -361.171744)
		(width 0.1651)
		(layer "In11.Cu")
		(net "P5E_PEX1_STN7_TX_C_DP<124>")
	)
	(segment
		(start 182.32628 -361.872276)
		(end 182.6768 -361.521756)
		(width 0.1651)
		(layer "In11.Cu")
		(net "P5E_PEX1_STN7_TX_C_DP<124>")
	)
	(segment
		(start 181.500018 -362.824268)
		(end 181.500018 -362.698538)
		(width 0.1651)
		(layer "In11.Cu")
		(net "P5E_PEX1_STN7_TX_C_DP<124>")
	)
	(segment
		(start 187.348622 -345.755976)
		(end 187.057792 -345.465146)
		(width 0.1651)
		(layer "In11.Cu")
		(net "P5E_PEX1_STN7_TX_C_DP<124>")
	)
	(segment
		(start 168.837102 -374.899174)
		(end 169.05859 -374.899174)
		(width 0.1651)
		(layer "In11.Cu")
		(net "P5E_PEX1_STN7_TX_C_DP<124>")
	)
	(segment
		(start 182.6768 -361.521756)
		(end 182.80253 -361.521756)
		(width 0.1651)
		(layer "In11.Cu")
		(net "P5E_PEX1_STN7_TX_C_DP<124>")
	)
	(segment
		(start 168.710102 -374.772174)
		(end 168.837102 -374.899174)
		(width 0.1651)
		(layer "In11.Cu")
		(net "P5E_PEX1_STN7_TX_C_DP<124>")
	)
	(segment
		(start 169.05859 -374.899174)
		(end 169.58564 -374.372124)
		(width 0.1651)
		(layer "In11.Cu")
		(net "P5E_PEX1_STN7_TX_C_DP<124>")
	)
	(segment
		(start 152.471628 -119.198898)
		(end 152.151588 -119.518938)
		(width 0.13462)
		(layer "F.Cu")
		(net "P5E_PEX1_STN1_TX_DP<24>")
	)
	(segment
		(start 151.520144 -119.518938)
		(end 151.225504 -119.224298)
		(width 0.13462)
		(layer "F.Cu")
		(net "P5E_PEX1_STN1_TX_DP<24>")
	)
	(segment
		(start 152.151588 -119.518938)
		(end 151.520144 -119.518938)
		(width 0.13462)
		(layer "F.Cu")
		(net "P5E_PEX1_STN1_TX_DP<24>")
	)
	(segment
		(start 182.994554 -278.420068)
		(end 183.235346 -278.420068)
		(width 0.1143)
		(layer "In9.Cu")
		(net "P5E_PEX1_STN1_TX_DP<24>")
	)
	(segment
		(start 147.92198 -161.439098)
		(end 182.73395 -264.281666)
		(width 0.1651)
		(layer "In9.Cu")
		(net "P5E_PEX1_STN1_TX_DP<24>")
	)
	(segment
		(start 150.934674 -119.515128)
		(end 150.181818 -119.515128)
		(width 0.1651)
		(layer "In9.Cu")
		(net "P5E_PEX1_STN1_TX_DP<24>")
	)
	(segment
		(start 182.73395 -264.281666)
		(end 182.73395 -271.471898)
		(width 0.1651)
		(layer "In9.Cu")
		(net "P5E_PEX1_STN1_TX_DP<24>")
	)
	(segment
		(start 182.73395 -271.500346)
		(end 182.77967 -271.546066)
		(width 0.1143)
		(layer "In9.Cu")
		(net "P5E_PEX1_STN1_TX_DP<24>")
	)
	(segment
		(start 147.335748 -158.49219)
		(end 147.92198 -161.439098)
		(width 0.1651)
		(layer "In9.Cu")
		(net "P5E_PEX1_STN1_TX_DP<24>")
	)
	(segment
		(start 144.04721 -137.452608)
		(end 146.604736 -143.627094)
		(width 0.1651)
		(layer "In9.Cu")
		(net "P5E_PEX1_STN1_TX_DP<24>")
	)
	(segment
		(start 146.604736 -143.627094)
		(end 147.335748 -158.49219)
		(width 0.1651)
		(layer "In9.Cu")
		(net "P5E_PEX1_STN1_TX_DP<24>")
	)
	(segment
		(start 151.225504 -119.224298)
		(end 150.934674 -119.515128)
		(width 0.1651)
		(layer "In9.Cu")
		(net "P5E_PEX1_STN1_TX_DP<24>")
	)
	(segment
		(start 148.399754 -121.297192)
		(end 144.04721 -131.805172)
		(width 0.1651)
		(layer "In9.Cu")
		(net "P5E_PEX1_STN1_TX_DP<24>")
	)
	(segment
		(start 182.77967 -278.205184)
		(end 182.994554 -278.420068)
		(width 0.1143)
		(layer "In9.Cu")
		(net "P5E_PEX1_STN1_TX_DP<24>")
	)
	(segment
		(start 144.04721 -131.805172)
		(end 144.04721 -137.452608)
		(width 0.1651)
		(layer "In9.Cu")
		(net "P5E_PEX1_STN1_TX_DP<24>")
	)
	(segment
		(start 150.181818 -119.515128)
		(end 148.399754 -121.297192)
		(width 0.1651)
		(layer "In9.Cu")
		(net "P5E_PEX1_STN1_TX_DP<24>")
	)
	(segment
		(start 182.73395 -271.471898)
		(end 182.73395 -271.500346)
		(width 0.1143)
		(layer "In9.Cu")
		(net "P5E_PEX1_STN1_TX_DP<24>")
	)
	(segment
		(start 182.77967 -271.546066)
		(end 182.77967 -278.205184)
		(width 0.1143)
		(layer "In9.Cu")
		(net "P5E_PEX1_STN1_TX_DP<24>")
	)
	(segment
		(start 183.235346 -278.420068)
		(end 183.349646 -278.534368)
		(width 0.1143)
		(layer "In9.Cu")
		(net "P5E_PEX1_STN1_TX_DP<24>")
	)
	(segment
		(start 183.349646 -278.534368)
		(end 183.349646 -278.799798)
		(width 0.1143)
		(layer "In9.Cu")
		(net "P5E_PEX1_STN1_TX_DP<24>")
	)
	(segment
		(start 187.032392 -355.95433)
		(end 187.352432 -355.63429)
		(width 0.13462)
		(layer "F.Cu")
		(net "P5E_PEX1_STN7_TX_DP<125>")
	)
	(segment
		(start 187.352432 -355.63429)
		(end 187.352432 -355.002846)
		(width 0.13462)
		(layer "F.Cu")
		(net "P5E_PEX1_STN7_TX_DP<125>")
	)
	(segment
		(start 187.352432 -355.002846)
		(end 187.057792 -354.708206)
		(width 0.13462)
		(layer "F.Cu")
		(net "P5E_PEX1_STN7_TX_DP<125>")
	)
	(segment
		(start 156.750004 -313.290712)
		(end 156.661104 -313.379612)
		(width 0.1143)
		(layer "In11.Cu")
		(net "P5E_PEX1_STN7_TX_DP<125>")
	)
	(segment
		(start 187.348622 -354.417376)
		(end 187.057792 -354.708206)
		(width 0.1651)
		(layer "In11.Cu")
		(net "P5E_PEX1_STN7_TX_DP<125>")
	)
	(segment
		(start 157.811216 -323.372988)
		(end 174.747682 -332.120748)
		(width 0.1651)
		(layer "In11.Cu")
		(net "P5E_PEX1_STN7_TX_DP<125>")
	)
	(segment
		(start 188.903102 -340.969854)
		(end 188.903102 -352.101404)
		(width 0.1651)
		(layer "In11.Cu")
		(net "P5E_PEX1_STN7_TX_DP<125>")
	)
	(segment
		(start 156.134054 -320.02095)
		(end 156.134054 -320.043048)
		(width 0.1143)
		(layer "In11.Cu")
		(net "P5E_PEX1_STN7_TX_DP<125>")
	)
	(segment
		(start 156.134054 -321.159632)
		(end 156.453332 -321.954652)
		(width 0.1651)
		(layer "In11.Cu")
		(net "P5E_PEX1_STN7_TX_DP<125>")
	)
	(segment
		(start 180.12664 -335.220056)
		(end 180.12664 -335.22031)
		(width 0.1651)
		(layer "In11.Cu")
		(net "P5E_PEX1_STN7_TX_DP<125>")
	)
	(segment
		(start 180.12664 -335.22031)
		(end 185.504836 -338.31911)
		(width 0.1651)
		(layer "In11.Cu")
		(net "P5E_PEX1_STN7_TX_DP<125>")
	)
	(segment
		(start 156.134054 -320.043048)
		(end 156.134054 -321.159632)
		(width 0.1651)
		(layer "In11.Cu")
		(net "P5E_PEX1_STN7_TX_DP<125>")
	)
	(segment
		(start 188.903102 -352.101404)
		(end 187.348622 -353.655884)
		(width 0.1651)
		(layer "In11.Cu")
		(net "P5E_PEX1_STN7_TX_DP<125>")
	)
	(segment
		(start 156.661104 -313.379612)
		(end 156.45638 -313.379612)
		(width 0.1143)
		(layer "In11.Cu")
		(net "P5E_PEX1_STN7_TX_DP<125>")
	)
	(segment
		(start 174.747682 -332.120748)
		(end 180.126386 -335.220056)
		(width 0.1651)
		(layer "In11.Cu")
		(net "P5E_PEX1_STN7_TX_DP<125>")
	)
	(segment
		(start 156.179774 -313.656218)
		(end 156.179774 -319.97523)
		(width 0.1143)
		(layer "In11.Cu")
		(net "P5E_PEX1_STN7_TX_DP<125>")
	)
	(segment
		(start 156.179774 -319.97523)
		(end 156.134054 -320.02095)
		(width 0.1143)
		(layer "In11.Cu")
		(net "P5E_PEX1_STN7_TX_DP<125>")
	)
	(segment
		(start 156.750004 -312.999882)
		(end 156.750004 -313.290712)
		(width 0.1143)
		(layer "In11.Cu")
		(net "P5E_PEX1_STN7_TX_DP<125>")
	)
	(segment
		(start 156.45638 -313.379612)
		(end 156.179774 -313.656218)
		(width 0.1143)
		(layer "In11.Cu")
		(net "P5E_PEX1_STN7_TX_DP<125>")
	)
	(segment
		(start 156.453332 -321.954652)
		(end 157.811216 -323.372988)
		(width 0.1651)
		(layer "In11.Cu")
		(net "P5E_PEX1_STN7_TX_DP<125>")
	)
	(segment
		(start 188.568584 -340.524084)
		(end 188.903102 -340.969854)
		(width 0.1651)
		(layer "In11.Cu")
		(net "P5E_PEX1_STN7_TX_DP<125>")
	)
	(segment
		(start 185.504836 -338.31911)
		(end 188.568584 -340.524084)
		(width 0.1651)
		(layer "In11.Cu")
		(net "P5E_PEX1_STN7_TX_DP<125>")
	)
	(segment
		(start 180.126386 -335.220056)
		(end 180.12664 -335.220056)
		(width 0.1651)
		(layer "In11.Cu")
		(net "P5E_PEX1_STN7_TX_DP<125>")
	)
	(segment
		(start 187.348622 -353.655884)
		(end 187.348622 -354.417376)
		(width 0.1651)
		(layer "In11.Cu")
		(net "P5E_PEX1_STN7_TX_DP<125>")
	)
	(segment
		(start 268.24305 -134.5946)
		(end 268.571726 -134.923276)
		(width 0.13462)
		(layer "F.Cu")
		(net "P5E_PEX2_STN1_TX_DN<30>")
	)
	(segment
		(start 267.628878 -134.5946)
		(end 268.24305 -134.5946)
		(width 0.13462)
		(layer "F.Cu")
		(net "P5E_PEX2_STN1_TX_DN<30>")
	)
	(segment
		(start 267.325602 -134.897876)
		(end 267.628878 -134.5946)
		(width 0.13462)
		(layer "F.Cu")
		(net "P5E_PEX2_STN1_TX_DN<30>")
	)
	(segment
		(start 270.26489 -144.577308)
		(end 270.175228 -144.711674)
		(width 0.1651)
		(layer "In9.Cu")
		(net "P5E_PEX2_STN1_TX_DN<30>")
	)
	(segment
		(start 304.873406 -278.229568)
		(end 305.035204 -278.229568)
		(width 0.1143)
		(layer "In9.Cu")
		(net "P5E_PEX2_STN1_TX_DN<30>")
	)
	(segment
		(start 266.515342 -134.607046)
		(end 266.303506 -134.818882)
		(width 0.1651)
		(layer "In9.Cu")
		(net "P5E_PEX2_STN1_TX_DN<30>")
	)
	(segment
		(start 267.35405 -137.513568)
		(end 267.515594 -137.513568)
		(width 0.1651)
		(layer "In9.Cu")
		(net "P5E_PEX2_STN1_TX_DN<30>")
	)
	(segment
		(start 304.770028 -278.12619)
		(end 304.873406 -278.229568)
		(width 0.1143)
		(layer "In9.Cu")
		(net "P5E_PEX2_STN1_TX_DN<30>")
	)
	(segment
		(start 304.815748 -271.500346)
		(end 304.770028 -271.546066)
		(width 0.1143)
		(layer "In9.Cu")
		(net "P5E_PEX2_STN1_TX_DN<30>")
	)
	(segment
		(start 269.789656 -142.185644)
		(end 269.69974 -142.32001)
		(width 0.1651)
		(layer "In9.Cu")
		(net "P5E_PEX2_STN1_TX_DN<30>")
	)
	(segment
		(start 266.4079 -135.711946)
		(end 266.4079 -135.7122)
		(width 0.1651)
		(layer "In9.Cu")
		(net "P5E_PEX2_STN1_TX_DN<30>")
	)
	(segment
		(start 270.502634 -145.77314)
		(end 270.412972 -145.90776)
		(width 0.1651)
		(layer "In9.Cu")
		(net "P5E_PEX2_STN1_TX_DN<30>")
	)
	(segment
		(start 269.551912 -140.989812)
		(end 269.461996 -141.124178)
		(width 0.1651)
		(layer "In9.Cu")
		(net "P5E_PEX2_STN1_TX_DN<30>")
	)
	(segment
		(start 270.406368 -145.287238)
		(end 270.502634 -145.77314)
		(width 0.1651)
		(layer "In9.Cu")
		(net "P5E_PEX2_STN1_TX_DN<30>")
	)
	(segment
		(start 266.680188 -136.369552)
		(end 267.012928 -137.172446)
		(width 0.1651)
		(layer "In9.Cu")
		(net "P5E_PEX2_STN1_TX_DN<30>")
	)
	(segment
		(start 277.821644 -183.203088)
		(end 304.815748 -262.946896)
		(width 0.1651)
		(layer "In9.Cu")
		(net "P5E_PEX2_STN1_TX_DN<30>")
	)
	(segment
		(start 266.742164 -136.2202)
		(end 266.680188 -136.369552)
		(width 0.1651)
		(layer "In9.Cu")
		(net "P5E_PEX2_STN1_TX_DN<30>")
	)
	(segment
		(start 270.027146 -143.381476)
		(end 269.937484 -143.515842)
		(width 0.1651)
		(layer "In9.Cu")
		(net "P5E_PEX2_STN1_TX_DN<30>")
	)
	(segment
		(start 270.650716 -147.103846)
		(end 277.821644 -183.203088)
		(width 0.1651)
		(layer "In9.Cu")
		(net "P5E_PEX2_STN1_TX_DN<30>")
	)
	(segment
		(start 270.740378 -146.969226)
		(end 270.650716 -147.103846)
		(width 0.1651)
		(layer "In9.Cu")
		(net "P5E_PEX2_STN1_TX_DN<30>")
	)
	(segment
		(start 269.461996 -141.124178)
		(end 269.558262 -141.609826)
		(width 0.1651)
		(layer "In9.Cu")
		(net "P5E_PEX2_STN1_TX_DN<30>")
	)
	(segment
		(start 270.03375 -144.00149)
		(end 270.168624 -144.091406)
		(width 0.1651)
		(layer "In9.Cu")
		(net "P5E_PEX2_STN1_TX_DN<30>")
	)
	(segment
		(start 270.412972 -145.90776)
		(end 270.509238 -146.393408)
		(width 0.1651)
		(layer "In9.Cu")
		(net "P5E_PEX2_STN1_TX_DN<30>")
	)
	(segment
		(start 267.857224 -138.016742)
		(end 268.838934 -138.998452)
		(width 0.1651)
		(layer "In9.Cu")
		(net "P5E_PEX2_STN1_TX_DN<30>")
	)
	(segment
		(start 269.796006 -142.805658)
		(end 269.93088 -142.895574)
		(width 0.1651)
		(layer "In9.Cu")
		(net "P5E_PEX2_STN1_TX_DN<30>")
	)
	(segment
		(start 266.223242 -135.01243)
		(end 266.223242 -135.266938)
		(width 0.1651)
		(layer "In9.Cu")
		(net "P5E_PEX2_STN1_TX_DN<30>")
	)
	(segment
		(start 267.012928 -137.172446)
		(end 267.35405 -137.513568)
		(width 0.1651)
		(layer "In9.Cu")
		(net "P5E_PEX2_STN1_TX_DN<30>")
	)
	(segment
		(start 267.515594 -137.513568)
		(end 267.857224 -137.855198)
		(width 0.1651)
		(layer "In9.Cu")
		(net "P5E_PEX2_STN1_TX_DN<30>")
	)
	(segment
		(start 267.325602 -134.897876)
		(end 267.034772 -134.607046)
		(width 0.1651)
		(layer "In9.Cu")
		(net "P5E_PEX2_STN1_TX_DN<30>")
	)
	(segment
		(start 270.509238 -146.393408)
		(end 270.643858 -146.483324)
		(width 0.1651)
		(layer "In9.Cu")
		(net "P5E_PEX2_STN1_TX_DN<30>")
	)
	(segment
		(start 267.857224 -137.855198)
		(end 267.857224 -138.016742)
		(width 0.1651)
		(layer "In9.Cu")
		(net "P5E_PEX2_STN1_TX_DN<30>")
	)
	(segment
		(start 270.168624 -144.091406)
		(end 270.26489 -144.577308)
		(width 0.1651)
		(layer "In9.Cu")
		(net "P5E_PEX2_STN1_TX_DN<30>")
	)
	(segment
		(start 266.557506 -135.773922)
		(end 266.742164 -136.2202)
		(width 0.1651)
		(layer "In9.Cu")
		(net "P5E_PEX2_STN1_TX_DN<30>")
	)
	(segment
		(start 305.035204 -278.229568)
		(end 305.149504 -278.115268)
		(width 0.1143)
		(layer "In9.Cu")
		(net "P5E_PEX2_STN1_TX_DN<30>")
	)
	(segment
		(start 270.643858 -146.483324)
		(end 270.740378 -146.969226)
		(width 0.1651)
		(layer "In9.Cu")
		(net "P5E_PEX2_STN1_TX_DN<30>")
	)
	(segment
		(start 269.93088 -142.895574)
		(end 270.027146 -143.381476)
		(width 0.1651)
		(layer "In9.Cu")
		(net "P5E_PEX2_STN1_TX_DN<30>")
	)
	(segment
		(start 269.69974 -142.32001)
		(end 269.796006 -142.805658)
		(width 0.1651)
		(layer "In9.Cu")
		(net "P5E_PEX2_STN1_TX_DN<30>")
	)
	(segment
		(start 266.303506 -134.818882)
		(end 266.223242 -135.01243)
		(width 0.1651)
		(layer "In9.Cu")
		(net "P5E_PEX2_STN1_TX_DN<30>")
	)
	(segment
		(start 270.271494 -145.197322)
		(end 270.406368 -145.287238)
		(width 0.1651)
		(layer "In9.Cu")
		(net "P5E_PEX2_STN1_TX_DN<30>")
	)
	(segment
		(start 304.815748 -262.946896)
		(end 304.815748 -271.471898)
		(width 0.1651)
		(layer "In9.Cu")
		(net "P5E_PEX2_STN1_TX_DN<30>")
	)
	(segment
		(start 269.455392 -140.50391)
		(end 269.551912 -140.989812)
		(width 0.1651)
		(layer "In9.Cu")
		(net "P5E_PEX2_STN1_TX_DN<30>")
	)
	(segment
		(start 305.149504 -278.115268)
		(end 305.149504 -277.849838)
		(width 0.1143)
		(layer "In9.Cu")
		(net "P5E_PEX2_STN1_TX_DN<30>")
	)
	(segment
		(start 269.558262 -141.609826)
		(end 269.693136 -141.699742)
		(width 0.1651)
		(layer "In9.Cu")
		(net "P5E_PEX2_STN1_TX_DN<30>")
	)
	(segment
		(start 304.770028 -271.546066)
		(end 304.770028 -278.12619)
		(width 0.1143)
		(layer "In9.Cu")
		(net "P5E_PEX2_STN1_TX_DN<30>")
	)
	(segment
		(start 267.034772 -134.607046)
		(end 266.515342 -134.607046)
		(width 0.1651)
		(layer "In9.Cu")
		(net "P5E_PEX2_STN1_TX_DN<30>")
	)
	(segment
		(start 269.937484 -143.515842)
		(end 270.03375 -144.00149)
		(width 0.1651)
		(layer "In9.Cu")
		(net "P5E_PEX2_STN1_TX_DN<30>")
	)
	(segment
		(start 266.4079 -135.7122)
		(end 266.557506 -135.773922)
		(width 0.1651)
		(layer "In9.Cu")
		(net "P5E_PEX2_STN1_TX_DN<30>")
	)
	(segment
		(start 268.838934 -138.998452)
		(end 269.224252 -139.928346)
		(width 0.1651)
		(layer "In9.Cu")
		(net "P5E_PEX2_STN1_TX_DN<30>")
	)
	(segment
		(start 270.175228 -144.711674)
		(end 270.271494 -145.197322)
		(width 0.1651)
		(layer "In9.Cu")
		(net "P5E_PEX2_STN1_TX_DN<30>")
	)
	(segment
		(start 269.693136 -141.699742)
		(end 269.789656 -142.185644)
		(width 0.1651)
		(layer "In9.Cu")
		(net "P5E_PEX2_STN1_TX_DN<30>")
	)
	(segment
		(start 269.320518 -140.413994)
		(end 269.455392 -140.50391)
		(width 0.1651)
		(layer "In9.Cu")
		(net "P5E_PEX2_STN1_TX_DN<30>")
	)
	(segment
		(start 304.815748 -271.471898)
		(end 304.815748 -271.500346)
		(width 0.1143)
		(layer "In9.Cu")
		(net "P5E_PEX2_STN1_TX_DN<30>")
	)
	(segment
		(start 269.224252 -139.928346)
		(end 269.320518 -140.413994)
		(width 0.1651)
		(layer "In9.Cu")
		(net "P5E_PEX2_STN1_TX_DN<30>")
	)
	(segment
		(start 266.223242 -135.266938)
		(end 266.4079 -135.711946)
		(width 0.1651)
		(layer "In9.Cu")
		(net "P5E_PEX2_STN1_TX_DN<30>")
	)
	(segment
		(start 177.033936 -323.340984)
		(end 176.812956 -324.092316)
		(width 0.1651)
		(layer "In5.Cu")
		(net "P5E_PEX1_STN5_RX_DP<83>")
	)
	(segment
		(start 151.586184 -352.979736)
		(end 146.46148 -366.502188)
		(width 0.1651)
		(layer "In5.Cu")
		(net "P5E_PEX1_STN5_RX_DP<83>")
	)
	(segment
		(start 136.826752 -389.537448)
		(end 132.676646 -390.364218)
		(width 0.1651)
		(layer "In5.Cu")
		(net "P5E_PEX1_STN5_RX_DP<83>")
	)
	(segment
		(start 122.637296 -398.09928)
		(end 122.510042 -397.972026)
		(width 0.1651)
		(layer "In5.Cu")
		(net "P5E_PEX1_STN5_RX_DP<83>")
	)
	(segment
		(start 123.668282 -395.136116)
		(end 123.530868 -395.192758)
		(width 0.1651)
		(layer "In5.Cu")
		(net "P5E_PEX1_STN5_RX_DP<83>")
	)
	(segment
		(start 177.033936 -319.91173)
		(end 177.033936 -323.340984)
		(width 0.1651)
		(layer "In5.Cu")
		(net "P5E_PEX1_STN5_RX_DP<83>")
	)
	(segment
		(start 177.079656 -318.355472)
		(end 177.079656 -319.837562)
		(width 0.1143)
		(layer "In5.Cu")
		(net "P5E_PEX1_STN5_RX_DP<83>")
	)
	(segment
		(start 177.649886 -318.015366)
		(end 177.535586 -318.129666)
		(width 0.1143)
		(layer "In5.Cu")
		(net "P5E_PEX1_STN5_RX_DP<83>")
	)
	(segment
		(start 123.287536 -397.32966)
		(end 123.287536 -397.881602)
		(width 0.1651)
		(layer "In5.Cu")
		(net "P5E_PEX1_STN5_RX_DP<83>")
	)
	(segment
		(start 177.305462 -318.129666)
		(end 177.079656 -318.355472)
		(width 0.1143)
		(layer "In5.Cu")
		(net "P5E_PEX1_STN5_RX_DP<83>")
	)
	(segment
		(start 177.079656 -319.837562)
		(end 177.033936 -319.883282)
		(width 0.1143)
		(layer "In5.Cu")
		(net "P5E_PEX1_STN5_RX_DP<83>")
	)
	(segment
		(start 123.396756 -395.788134)
		(end 123.287536 -396.050516)
		(width 0.1651)
		(layer "In5.Cu")
		(net "P5E_PEX1_STN5_RX_DP<83>")
	)
	(segment
		(start 158.95828 -338.258404)
		(end 151.586184 -352.979736)
		(width 0.1651)
		(layer "In5.Cu")
		(net "P5E_PEX1_STN5_RX_DP<83>")
	)
	(segment
		(start 139.101068 -387.209538)
		(end 138.357356 -388.45871)
		(width 0.1651)
		(layer "In5.Cu")
		(net "P5E_PEX1_STN5_RX_DP<83>")
	)
	(segment
		(start 123.287536 -396.050516)
		(end 123.287536 -396.62354)
		(width 0.1651)
		(layer "In5.Cu")
		(net "P5E_PEX1_STN5_RX_DP<83>")
	)
	(segment
		(start 123.287536 -397.881602)
		(end 123.069858 -398.09928)
		(width 0.1651)
		(layer "In5.Cu")
		(net "P5E_PEX1_STN5_RX_DP<83>")
	)
	(segment
		(start 123.847606 -394.705586)
		(end 123.668282 -395.136116)
		(width 0.1651)
		(layer "In5.Cu")
		(net "P5E_PEX1_STN5_RX_DP<83>")
	)
	(segment
		(start 174.046388 -328.195178)
		(end 161.257488 -335.688686)
		(width 0.1651)
		(layer "In5.Cu")
		(net "P5E_PEX1_STN5_RX_DP<83>")
	)
	(segment
		(start 123.530868 -395.192758)
		(end 123.340368 -395.650974)
		(width 0.1651)
		(layer "In5.Cu")
		(net "P5E_PEX1_STN5_RX_DP<83>")
	)
	(segment
		(start 146.46148 -366.502188)
		(end 145.338292 -370.546376)
		(width 0.1651)
		(layer "In5.Cu")
		(net "P5E_PEX1_STN5_RX_DP<83>")
	)
	(segment
		(start 123.287536 -396.62354)
		(end 123.2154 -396.695676)
		(width 0.1651)
		(layer "In5.Cu")
		(net "P5E_PEX1_STN5_RX_DP<83>")
	)
	(segment
		(start 175.866044 -326.375522)
		(end 174.046388 -328.195178)
		(width 0.1651)
		(layer "In5.Cu")
		(net "P5E_PEX1_STN5_RX_DP<83>")
	)
	(segment
		(start 129.12471 -391.750042)
		(end 124.428758 -394.084302)
		(width 0.1651)
		(layer "In5.Cu")
		(net "P5E_PEX1_STN5_RX_DP<83>")
	)
	(segment
		(start 124.428758 -394.084302)
		(end 123.847606 -394.705586)
		(width 0.1651)
		(layer "In5.Cu")
		(net "P5E_PEX1_STN5_RX_DP<83>")
	)
	(segment
		(start 122.510042 -397.972026)
		(end 122.510042 -397.59001)
		(width 0.1651)
		(layer "In5.Cu")
		(net "P5E_PEX1_STN5_RX_DP<83>")
	)
	(segment
		(start 123.069858 -398.09928)
		(end 122.637296 -398.09928)
		(width 0.1651)
		(layer "In5.Cu")
		(net "P5E_PEX1_STN5_RX_DP<83>")
	)
	(segment
		(start 176.812956 -324.092316)
		(end 175.866044 -326.375522)
		(width 0.1651)
		(layer "In5.Cu")
		(net "P5E_PEX1_STN5_RX_DP<83>")
	)
	(segment
		(start 177.535586 -318.129666)
		(end 177.305462 -318.129666)
		(width 0.1143)
		(layer "In5.Cu")
		(net "P5E_PEX1_STN5_RX_DP<83>")
	)
	(segment
		(start 145.338292 -370.546376)
		(end 139.101068 -387.209538)
		(width 0.1651)
		(layer "In5.Cu")
		(net "P5E_PEX1_STN5_RX_DP<83>")
	)
	(segment
		(start 177.033936 -319.883282)
		(end 177.033936 -319.91173)
		(width 0.1143)
		(layer "In5.Cu")
		(net "P5E_PEX1_STN5_RX_DP<83>")
	)
	(segment
		(start 177.649886 -317.749936)
		(end 177.649886 -318.015366)
		(width 0.1143)
		(layer "In5.Cu")
		(net "P5E_PEX1_STN5_RX_DP<83>")
	)
	(segment
		(start 132.676646 -390.364218)
		(end 129.12471 -391.750042)
		(width 0.1651)
		(layer "In5.Cu")
		(net "P5E_PEX1_STN5_RX_DP<83>")
	)
	(segment
		(start 161.257488 -335.688686)
		(end 158.95828 -338.258404)
		(width 0.1651)
		(layer "In5.Cu")
		(net "P5E_PEX1_STN5_RX_DP<83>")
	)
	(segment
		(start 123.2154 -397.257524)
		(end 123.287536 -397.32966)
		(width 0.1651)
		(layer "In5.Cu")
		(net "P5E_PEX1_STN5_RX_DP<83>")
	)
	(segment
		(start 123.340368 -395.650974)
		(end 123.396756 -395.788134)
		(width 0.1651)
		(layer "In5.Cu")
		(net "P5E_PEX1_STN5_RX_DP<83>")
	)
	(segment
		(start 123.2154 -396.695676)
		(end 123.2154 -397.257524)
		(width 0.1651)
		(layer "In5.Cu")
		(net "P5E_PEX1_STN5_RX_DP<83>")
	)
	(segment
		(start 138.357356 -388.45871)
		(end 136.826752 -389.537448)
		(width 0.1651)
		(layer "In5.Cu")
		(net "P5E_PEX1_STN5_RX_DP<83>")
	)
	(segment
		(start 336.392774 -341.665814)
		(end 335.481676 -340.753954)
		(width 0.1651)
		(layer "In5.Cu")
		(net "P5E_PEX2_STN5_RX_DN<90>")
	)
	(segment
		(start 300.399704 -316.534292)
		(end 300.399704 -316.799722)
		(width 0.1143)
		(layer "In5.Cu")
		(net "P5E_PEX2_STN5_RX_DN<90>")
	)
	(segment
		(start 305.068478 -326.202294)
		(end 305.020726 -326.066658)
		(width 0.1651)
		(layer "In5.Cu")
		(net "P5E_PEX2_STN5_RX_DN<90>")
	)
	(segment
		(start 300.065694 -319.941448)
		(end 300.019974 -319.895728)
		(width 0.1143)
		(layer "In5.Cu")
		(net "P5E_PEX2_STN5_RX_DN<90>")
	)
	(segment
		(start 300.70425 -322.90893)
		(end 300.065694 -321.367404)
		(width 0.1651)
		(layer "In5.Cu")
		(net "P5E_PEX2_STN5_RX_DN<90>")
	)
	(segment
		(start 300.019974 -316.534292)
		(end 300.134274 -316.419992)
		(width 0.1143)
		(layer "In5.Cu")
		(net "P5E_PEX2_STN5_RX_DN<90>")
	)
	(segment
		(start 300.285404 -316.419992)
		(end 300.399704 -316.534292)
		(width 0.1143)
		(layer "In5.Cu")
		(net "P5E_PEX2_STN5_RX_DN<90>")
	)
	(segment
		(start 300.065694 -319.969896)
		(end 300.065694 -319.941448)
		(width 0.1143)
		(layer "In5.Cu")
		(net "P5E_PEX2_STN5_RX_DN<90>")
	)
	(segment
		(start 303.014888 -325.219568)
		(end 300.70425 -322.90893)
		(width 0.1651)
		(layer "In5.Cu")
		(net "P5E_PEX2_STN5_RX_DN<90>")
	)
	(segment
		(start 304.573686 -325.852536)
		(end 304.43805 -325.900542)
		(width 0.1651)
		(layer "In5.Cu")
		(net "P5E_PEX2_STN5_RX_DN<90>")
	)
	(segment
		(start 335.890108 -371.790214)
		(end 335.890108 -371.408198)
		(width 0.1651)
		(layer "In5.Cu")
		(net "P5E_PEX2_STN5_RX_DN<90>")
	)
	(segment
		(start 300.134274 -316.419992)
		(end 300.285404 -316.419992)
		(width 0.1143)
		(layer "In5.Cu")
		(net "P5E_PEX2_STN5_RX_DN<90>")
	)
	(segment
		(start 335.890108 -371.408198)
		(end 336.017108 -371.281198)
		(width 0.1651)
		(layer "In5.Cu")
		(net "P5E_PEX2_STN5_RX_DN<90>")
	)
	(segment
		(start 335.481676 -340.753954)
		(end 305.068478 -326.202294)
		(width 0.1651)
		(layer "In5.Cu")
		(net "P5E_PEX2_STN5_RX_DN<90>")
	)
	(segment
		(start 337.01609 -369.026948)
		(end 336.392774 -358.528874)
		(width 0.1651)
		(layer "In5.Cu")
		(net "P5E_PEX2_STN5_RX_DN<90>")
	)
	(segment
		(start 337.01609 -370.829332)
		(end 337.01609 -369.026948)
		(width 0.1651)
		(layer "In5.Cu")
		(net "P5E_PEX2_STN5_RX_DN<90>")
	)
	(segment
		(start 305.020726 -326.066658)
		(end 304.573686 -325.852536)
		(width 0.1651)
		(layer "In5.Cu")
		(net "P5E_PEX2_STN5_RX_DN<90>")
	)
	(segment
		(start 300.019974 -319.895728)
		(end 300.019974 -316.534292)
		(width 0.1143)
		(layer "In5.Cu")
		(net "P5E_PEX2_STN5_RX_DN<90>")
	)
	(segment
		(start 336.392774 -358.528874)
		(end 336.392774 -341.665814)
		(width 0.1651)
		(layer "In5.Cu")
		(net "P5E_PEX2_STN5_RX_DN<90>")
	)
	(segment
		(start 300.065694 -321.367404)
		(end 300.065694 -319.969896)
		(width 0.1651)
		(layer "In5.Cu")
		(net "P5E_PEX2_STN5_RX_DN<90>")
	)
	(segment
		(start 336.564224 -371.281198)
		(end 337.01609 -370.829332)
		(width 0.1651)
		(layer "In5.Cu")
		(net "P5E_PEX2_STN5_RX_DN<90>")
	)
	(segment
		(start 336.017108 -371.281198)
		(end 336.564224 -371.281198)
		(width 0.1651)
		(layer "In5.Cu")
		(net "P5E_PEX2_STN5_RX_DN<90>")
	)
	(segment
		(start 304.43805 -325.900542)
		(end 303.014888 -325.219568)
		(width 0.1651)
		(layer "In5.Cu")
		(net "P5E_PEX2_STN5_RX_DN<90>")
	)
	(segment
		(start 41.389808 -355.658166)
		(end 41.389808 -355.026722)
		(width 0.13462)
		(layer "F.Cu")
		(net "P5E_PEX0_STN7_TX_DP<123>")
	)
	(segment
		(start 41.069768 -355.978206)
		(end 41.389808 -355.658166)
		(width 0.13462)
		(layer "F.Cu")
		(net "P5E_PEX0_STN7_TX_DP<123>")
	)
	(segment
		(start 41.389808 -355.026722)
		(end 41.095168 -354.732082)
		(width 0.13462)
		(layer "F.Cu")
		(net "P5E_PEX0_STN7_TX_DP<123>")
	)
	(segment
		(start 38.134036 -319.8368)
		(end 38.179756 -319.79108)
		(width 0.1143)
		(layer "In7.Cu")
		(net "P5E_PEX0_STN7_TX_DP<123>")
	)
	(segment
		(start 38.134036 -319.865248)
		(end 38.134036 -319.8368)
		(width 0.1143)
		(layer "In7.Cu")
		(net "P5E_PEX0_STN7_TX_DP<123>")
	)
	(segment
		(start 38.405562 -313.379612)
		(end 38.635686 -313.379612)
		(width 0.1143)
		(layer "In7.Cu")
		(net "P5E_PEX0_STN7_TX_DP<123>")
	)
	(segment
		(start 41.385998 -354.441252)
		(end 41.385998 -353.825302)
		(width 0.1651)
		(layer "In7.Cu")
		(net "P5E_PEX0_STN7_TX_DP<123>")
	)
	(segment
		(start 38.179756 -319.79108)
		(end 38.179756 -313.605418)
		(width 0.1143)
		(layer "In7.Cu")
		(net "P5E_PEX0_STN7_TX_DP<123>")
	)
	(segment
		(start 41.095168 -354.732082)
		(end 41.385998 -354.441252)
		(width 0.1651)
		(layer "In7.Cu")
		(net "P5E_PEX0_STN7_TX_DP<123>")
	)
	(segment
		(start 38.134036 -324.994524)
		(end 38.134036 -319.865248)
		(width 0.1651)
		(layer "In7.Cu")
		(net "P5E_PEX0_STN7_TX_DP<123>")
	)
	(segment
		(start 38.179756 -313.605418)
		(end 38.405562 -313.379612)
		(width 0.1143)
		(layer "In7.Cu")
		(net "P5E_PEX0_STN7_TX_DP<123>")
	)
	(segment
		(start 41.385998 -353.825302)
		(end 42.940478 -352.270822)
		(width 0.1651)
		(layer "In7.Cu")
		(net "P5E_PEX0_STN7_TX_DP<123>")
	)
	(segment
		(start 38.749986 -313.265312)
		(end 38.749986 -312.999882)
		(width 0.1143)
		(layer "In7.Cu")
		(net "P5E_PEX0_STN7_TX_DP<123>")
	)
	(segment
		(start 42.940478 -352.270822)
		(end 42.940478 -340.839044)
		(width 0.1651)
		(layer "In7.Cu")
		(net "P5E_PEX0_STN7_TX_DP<123>")
	)
	(segment
		(start 38.635686 -313.379612)
		(end 38.749986 -313.265312)
		(width 0.1143)
		(layer "In7.Cu")
		(net "P5E_PEX0_STN7_TX_DP<123>")
	)
	(segment
		(start 42.940478 -340.839044)
		(end 38.134036 -324.994524)
		(width 0.1651)
		(layer "In7.Cu")
		(net "P5E_PEX0_STN7_TX_DP<123>")
	)
	(segment
		(start 196.705982 -122.590306)
		(end 197.337426 -122.590306)
		(width 0.13462)
		(layer "F.Cu")
		(net "P5E_PEX1_STN0_TX_DN<2>")
	)
	(segment
		(start 196.385942 -122.270266)
		(end 196.705982 -122.590306)
		(width 0.13462)
		(layer "F.Cu")
		(net "P5E_PEX1_STN0_TX_DN<2>")
	)
	(segment
		(start 197.337426 -122.590306)
		(end 197.632066 -122.295666)
		(width 0.13462)
		(layer "F.Cu")
		(net "P5E_PEX1_STN0_TX_DN<2>")
	)
	(segment
		(start 199.989186 -286.065976)
		(end 199.943466 -286.020256)
		(width 0.1143)
		(layer "In9.Cu")
		(net "P5E_PEX1_STN0_TX_DN<2>")
	)
	(segment
		(start 193.420238 -286.285686)
		(end 193.534538 -286.399986)
		(width 0.1143)
		(layer "In9.Cu")
		(net "P5E_PEX1_STN0_TX_DN<2>")
	)
	(segment
		(start 214.857584 -272.44802)
		(end 213.455758 -275.8313)
		(width 0.1651)
		(layer "In9.Cu")
		(net "P5E_PEX1_STN0_TX_DN<2>")
	)
	(segment
		(start 197.922896 -122.586496)
		(end 200.817734 -122.586496)
		(width 0.1651)
		(layer "In9.Cu")
		(net "P5E_PEX1_STN0_TX_DN<2>")
	)
	(segment
		(start 204.558392 -178.91506)
		(end 200.816972 -221.67723)
		(width 0.1651)
		(layer "In9.Cu")
		(net "P5E_PEX1_STN0_TX_DN<2>")
	)
	(segment
		(start 214.441024 -267.69314)
		(end 214.857584 -272.44802)
		(width 0.1651)
		(layer "In9.Cu")
		(net "P5E_PEX1_STN0_TX_DN<2>")
	)
	(segment
		(start 203.291694 -250.029726)
		(end 213.37524 -265.119866)
		(width 0.1651)
		(layer "In9.Cu")
		(net "P5E_PEX1_STN0_TX_DN<2>")
	)
	(segment
		(start 214.336122 -152.623266)
		(end 214.336122 -159.71139)
		(width 0.1651)
		(layer "In9.Cu")
		(net "P5E_PEX1_STN0_TX_DN<2>")
	)
	(segment
		(start 213.455758 -275.8313)
		(end 204.41412 -284.872938)
		(width 0.1651)
		(layer "In9.Cu")
		(net "P5E_PEX1_STN0_TX_DN<2>")
	)
	(segment
		(start 201.534268 -286.065976)
		(end 200.017634 -286.065976)
		(width 0.1651)
		(layer "In9.Cu")
		(net "P5E_PEX1_STN0_TX_DN<2>")
	)
	(segment
		(start 199.943466 -286.020256)
		(end 193.52387 -286.020256)
		(width 0.1143)
		(layer "In9.Cu")
		(net "P5E_PEX1_STN0_TX_DN<2>")
	)
	(segment
		(start 202.817222 -125.535182)
		(end 205.380082 -131.720844)
		(width 0.1651)
		(layer "In9.Cu")
		(net "P5E_PEX1_STN0_TX_DN<2>")
	)
	(segment
		(start 200.817734 -122.586496)
		(end 202.35799 -124.126752)
		(width 0.1651)
		(layer "In9.Cu")
		(net "P5E_PEX1_STN0_TX_DN<2>")
	)
	(segment
		(start 193.420238 -286.123888)
		(end 193.420238 -286.285686)
		(width 0.1143)
		(layer "In9.Cu")
		(net "P5E_PEX1_STN0_TX_DN<2>")
	)
	(segment
		(start 205.380082 -131.720844)
		(end 205.888336 -132.229098)
		(width 0.1651)
		(layer "In9.Cu")
		(net "P5E_PEX1_STN0_TX_DN<2>")
	)
	(segment
		(start 214.336122 -159.71139)
		(end 214.113618 -160.544256)
		(width 0.1651)
		(layer "In9.Cu")
		(net "P5E_PEX1_STN0_TX_DN<2>")
	)
	(segment
		(start 204.41412 -284.872938)
		(end 201.534268 -286.065976)
		(width 0.1651)
		(layer "In9.Cu")
		(net "P5E_PEX1_STN0_TX_DN<2>")
	)
	(segment
		(start 205.888336 -132.229098)
		(end 214.336122 -152.623266)
		(width 0.1651)
		(layer "In9.Cu")
		(net "P5E_PEX1_STN0_TX_DN<2>")
	)
	(segment
		(start 197.632066 -122.295666)
		(end 197.922896 -122.586496)
		(width 0.1651)
		(layer "In9.Cu")
		(net "P5E_PEX1_STN0_TX_DN<2>")
	)
	(segment
		(start 193.534538 -286.399986)
		(end 193.799968 -286.399986)
		(width 0.1143)
		(layer "In9.Cu")
		(net "P5E_PEX1_STN0_TX_DN<2>")
	)
	(segment
		(start 193.52387 -286.020256)
		(end 193.420238 -286.123888)
		(width 0.1143)
		(layer "In9.Cu")
		(net "P5E_PEX1_STN0_TX_DN<2>")
	)
	(segment
		(start 214.113618 -160.544256)
		(end 205.467204 -175.527208)
		(width 0.1651)
		(layer "In9.Cu")
		(net "P5E_PEX1_STN0_TX_DN<2>")
	)
	(segment
		(start 202.70216 -124.95784)
		(end 202.817222 -125.535182)
		(width 0.1651)
		(layer "In9.Cu")
		(net "P5E_PEX1_STN0_TX_DN<2>")
	)
	(segment
		(start 202.35799 -124.126752)
		(end 202.70216 -124.95784)
		(width 0.1651)
		(layer "In9.Cu")
		(net "P5E_PEX1_STN0_TX_DN<2>")
	)
	(segment
		(start 200.017634 -286.065976)
		(end 199.989186 -286.065976)
		(width 0.1143)
		(layer "In9.Cu")
		(net "P5E_PEX1_STN0_TX_DN<2>")
	)
	(segment
		(start 213.37524 -265.119866)
		(end 214.441024 -267.69314)
		(width 0.1651)
		(layer "In9.Cu")
		(net "P5E_PEX1_STN0_TX_DN<2>")
	)
	(segment
		(start 205.467204 -175.527208)
		(end 204.558392 -178.91506)
		(width 0.1651)
		(layer "In9.Cu")
		(net "P5E_PEX1_STN0_TX_DN<2>")
	)
	(segment
		(start 200.816972 -221.67723)
		(end 203.291694 -250.029726)
		(width 0.1651)
		(layer "In9.Cu")
		(net "P5E_PEX1_STN0_TX_DN<2>")
	)
	(segment
		(start 159.966152 -355.978206)
		(end 159.646112 -355.658166)
		(width 0.13462)
		(layer "F.Cu")
		(net "P5E_PEX1_STN7_TX_DN<112>")
	)
	(segment
		(start 159.646112 -355.658166)
		(end 159.646112 -355.026722)
		(width 0.13462)
		(layer "F.Cu")
		(net "P5E_PEX1_STN7_TX_DN<112>")
	)
	(segment
		(start 159.646112 -355.026722)
		(end 159.940752 -354.732082)
		(width 0.13462)
		(layer "F.Cu")
		(net "P5E_PEX1_STN7_TX_DN<112>")
	)
	(segment
		(start 136.402064 -310.560466)
		(end 136.259824 -310.581294)
		(width 0.1651)
		(layer "In11.Cu")
		(net "P5E_PEX1_STN7_TX_DN<112>")
	)
	(segment
		(start 139.56411 -306.32654)
		(end 139.268454 -306.724558)
		(width 0.1651)
		(layer "In11.Cu")
		(net "P5E_PEX1_STN7_TX_DN<112>")
	)
	(segment
		(start 133.347714 -317.268352)
		(end 132.90931 -319.478406)
		(width 0.1651)
		(layer "In11.Cu")
		(net "P5E_PEX1_STN7_TX_DN<112>")
	)
	(segment
		(start 136.259824 -310.581294)
		(end 135.94461 -311.005474)
		(width 0.1651)
		(layer "In11.Cu")
		(net "P5E_PEX1_STN7_TX_DN<112>")
	)
	(segment
		(start 142.535148 -335.96961)
		(end 142.536418 -336.113374)
		(width 0.1651)
		(layer "In11.Cu")
		(net "P5E_PEX1_STN7_TX_DN<112>")
	)
	(segment
		(start 145.6436 -301.265844)
		(end 143.039338 -302.344582)
		(width 0.1651)
		(layer "In11.Cu")
		(net "P5E_PEX1_STN7_TX_DN<112>")
	)
	(segment
		(start 139.268454 -306.724558)
		(end 139.108688 -306.747926)
		(width 0.1651)
		(layer "In11.Cu")
		(net "P5E_PEX1_STN7_TX_DN<112>")
	)
	(segment
		(start 132.90931 -323.02704)
		(end 133.928358 -326.388476)
		(width 0.1651)
		(layer "In11.Cu")
		(net "P5E_PEX1_STN7_TX_DN<112>")
	)
	(segment
		(start 136.676638 -310.020462)
		(end 136.69772 -310.162448)
		(width 0.1651)
		(layer "In11.Cu")
		(net "P5E_PEX1_STN7_TX_DN<112>")
	)
	(segment
		(start 143.38808 -336.95005)
		(end 143.741394 -337.297014)
		(width 0.1651)
		(layer "In11.Cu")
		(net "P5E_PEX1_STN7_TX_DN<112>")
	)
	(segment
		(start 139.108688 -306.747926)
		(end 138.813286 -307.145436)
		(width 0.1651)
		(layer "In11.Cu")
		(net "P5E_PEX1_STN7_TX_DN<112>")
	)
	(segment
		(start 143.033242 -336.459068)
		(end 143.38681 -336.80654)
		(width 0.1651)
		(layer "In11.Cu")
		(net "P5E_PEX1_STN7_TX_DN<112>")
	)
	(segment
		(start 151.628602 -301.265844)
		(end 145.6436 -301.265844)
		(width 0.1651)
		(layer "In11.Cu")
		(net "P5E_PEX1_STN7_TX_DN<112>")
	)
	(segment
		(start 137.684256 -308.66461)
		(end 137.388854 -309.06212)
		(width 0.1651)
		(layer "In11.Cu")
		(net "P5E_PEX1_STN7_TX_DN<112>")
	)
	(segment
		(start 158.079694 -301.385224)
		(end 157.914594 -301.220124)
		(width 0.1143)
		(layer "In11.Cu")
		(net "P5E_PEX1_STN7_TX_DN<112>")
	)
	(segment
		(start 158.965392 -352.252788)
		(end 159.649922 -353.884484)
		(width 0.1651)
		(layer "In11.Cu")
		(net "P5E_PEX1_STN7_TX_DN<112>")
	)
	(segment
		(start 151.6507 -301.265844)
		(end 151.628602 -301.265844)
		(width 0.1143)
		(layer "In11.Cu")
		(net "P5E_PEX1_STN7_TX_DN<112>")
	)
	(segment
		(start 157.699964 -301.599854)
		(end 157.990794 -301.599854)
		(width 0.1143)
		(layer "In11.Cu")
		(net "P5E_PEX1_STN7_TX_DN<112>")
	)
	(segment
		(start 133.928358 -326.388476)
		(end 136.40054 -330.0857)
		(width 0.1651)
		(layer "In11.Cu")
		(net "P5E_PEX1_STN7_TX_DN<112>")
	)
	(segment
		(start 157.990794 -301.599854)
		(end 158.079694 -301.510954)
		(width 0.1143)
		(layer "In11.Cu")
		(net "P5E_PEX1_STN7_TX_DN<112>")
	)
	(segment
		(start 157.914594 -301.220124)
		(end 151.69642 -301.220124)
		(width 0.1143)
		(layer "In11.Cu")
		(net "P5E_PEX1_STN7_TX_DN<112>")
	)
	(segment
		(start 137.826242 -308.643782)
		(end 137.684256 -308.66461)
		(width 0.1651)
		(layer "In11.Cu")
		(net "P5E_PEX1_STN7_TX_DN<112>")
	)
	(segment
		(start 140.476224 -304.907696)
		(end 139.540742 -306.166774)
		(width 0.1651)
		(layer "In11.Cu")
		(net "P5E_PEX1_STN7_TX_DN<112>")
	)
	(segment
		(start 142.18158 -335.622392)
		(end 142.535148 -335.96961)
		(width 0.1651)
		(layer "In11.Cu")
		(net "P5E_PEX1_STN7_TX_DN<112>")
	)
	(segment
		(start 144.239742 -337.786726)
		(end 158.965392 -352.252788)
		(width 0.1651)
		(layer "In11.Cu")
		(net "P5E_PEX1_STN7_TX_DN<112>")
	)
	(segment
		(start 158.079694 -301.510954)
		(end 158.079694 -301.385224)
		(width 0.1143)
		(layer "In11.Cu")
		(net "P5E_PEX1_STN7_TX_DN<112>")
	)
	(segment
		(start 138.834114 -307.287676)
		(end 138.538458 -307.68544)
		(width 0.1651)
		(layer "In11.Cu")
		(net "P5E_PEX1_STN7_TX_DN<112>")
	)
	(segment
		(start 143.38681 -336.80654)
		(end 143.38808 -336.95005)
		(width 0.1651)
		(layer "In11.Cu")
		(net "P5E_PEX1_STN7_TX_DN<112>")
	)
	(segment
		(start 142.889732 -336.460338)
		(end 143.033242 -336.459068)
		(width 0.1651)
		(layer "In11.Cu")
		(net "P5E_PEX1_STN7_TX_DN<112>")
	)
	(segment
		(start 137.114026 -309.602124)
		(end 136.97204 -309.622952)
		(width 0.1651)
		(layer "In11.Cu")
		(net "P5E_PEX1_STN7_TX_DN<112>")
	)
	(segment
		(start 136.40054 -330.0857)
		(end 142.037816 -335.623662)
		(width 0.1651)
		(layer "In11.Cu")
		(net "P5E_PEX1_STN7_TX_DN<112>")
	)
	(segment
		(start 136.97204 -309.622952)
		(end 136.676638 -310.020462)
		(width 0.1651)
		(layer "In11.Cu")
		(net "P5E_PEX1_STN7_TX_DN<112>")
	)
	(segment
		(start 138.121898 -308.246018)
		(end 137.826242 -308.643782)
		(width 0.1651)
		(layer "In11.Cu")
		(net "P5E_PEX1_STN7_TX_DN<112>")
	)
	(segment
		(start 139.540742 -306.166774)
		(end 139.56411 -306.32654)
		(width 0.1651)
		(layer "In11.Cu")
		(net "P5E_PEX1_STN7_TX_DN<112>")
	)
	(segment
		(start 138.10107 -308.103778)
		(end 138.121898 -308.246018)
		(width 0.1651)
		(layer "In11.Cu")
		(net "P5E_PEX1_STN7_TX_DN<112>")
	)
	(segment
		(start 143.741394 -337.297014)
		(end 143.884904 -337.295744)
		(width 0.1651)
		(layer "In11.Cu")
		(net "P5E_PEX1_STN7_TX_DN<112>")
	)
	(segment
		(start 138.396472 -307.706268)
		(end 138.10107 -308.103778)
		(width 0.1651)
		(layer "In11.Cu")
		(net "P5E_PEX1_STN7_TX_DN<112>")
	)
	(segment
		(start 136.69772 -310.162448)
		(end 136.402064 -310.560466)
		(width 0.1651)
		(layer "In11.Cu")
		(net "P5E_PEX1_STN7_TX_DN<112>")
	)
	(segment
		(start 159.649922 -354.441252)
		(end 159.940752 -354.732082)
		(width 0.1651)
		(layer "In11.Cu")
		(net "P5E_PEX1_STN7_TX_DN<112>")
	)
	(segment
		(start 138.813286 -307.145436)
		(end 138.834114 -307.287676)
		(width 0.1651)
		(layer "In11.Cu")
		(net "P5E_PEX1_STN7_TX_DN<112>")
	)
	(segment
		(start 159.649922 -353.884484)
		(end 159.649922 -354.441252)
		(width 0.1651)
		(layer "In11.Cu")
		(net "P5E_PEX1_STN7_TX_DN<112>")
	)
	(segment
		(start 144.238472 -337.643216)
		(end 144.239742 -337.786726)
		(width 0.1651)
		(layer "In11.Cu")
		(net "P5E_PEX1_STN7_TX_DN<112>")
	)
	(segment
		(start 142.037816 -335.623662)
		(end 142.18158 -335.622392)
		(width 0.1651)
		(layer "In11.Cu")
		(net "P5E_PEX1_STN7_TX_DN<112>")
	)
	(segment
		(start 137.409682 -309.20436)
		(end 137.114026 -309.602124)
		(width 0.1651)
		(layer "In11.Cu")
		(net "P5E_PEX1_STN7_TX_DN<112>")
	)
	(segment
		(start 137.388854 -309.06212)
		(end 137.409682 -309.20436)
		(width 0.1651)
		(layer "In11.Cu")
		(net "P5E_PEX1_STN7_TX_DN<112>")
	)
	(segment
		(start 151.69642 -301.220124)
		(end 151.6507 -301.265844)
		(width 0.1143)
		(layer "In11.Cu")
		(net "P5E_PEX1_STN7_TX_DN<112>")
	)
	(segment
		(start 135.94461 -311.005474)
		(end 133.347714 -317.268352)
		(width 0.1651)
		(layer "In11.Cu")
		(net "P5E_PEX1_STN7_TX_DN<112>")
	)
	(segment
		(start 138.538458 -307.68544)
		(end 138.396472 -307.706268)
		(width 0.1651)
		(layer "In11.Cu")
		(net "P5E_PEX1_STN7_TX_DN<112>")
	)
	(segment
		(start 143.039338 -302.344582)
		(end 140.476224 -304.907696)
		(width 0.1651)
		(layer "In11.Cu")
		(net "P5E_PEX1_STN7_TX_DN<112>")
	)
	(segment
		(start 143.884904 -337.295744)
		(end 144.238472 -337.643216)
		(width 0.1651)
		(layer "In11.Cu")
		(net "P5E_PEX1_STN7_TX_DN<112>")
	)
	(segment
		(start 132.90931 -319.478406)
		(end 132.90931 -323.02704)
		(width 0.1651)
		(layer "In11.Cu")
		(net "P5E_PEX1_STN7_TX_DN<112>")
	)
	(segment
		(start 142.536418 -336.113374)
		(end 142.889732 -336.460338)
		(width 0.1651)
		(layer "In11.Cu")
		(net "P5E_PEX1_STN7_TX_DN<112>")
	)
	(segment
		(start 267.613384 -105.00868)
		(end 268.258544 -105.00868)
		(width 0.13462)
		(layer "F.Cu")
		(net "P5E_PEX2_STN1_TX_DN<19>")
	)
	(segment
		(start 267.325602 -104.720898)
		(end 267.613384 -105.00868)
		(width 0.13462)
		(layer "F.Cu")
		(net "P5E_PEX2_STN1_TX_DN<19>")
	)
	(segment
		(start 268.258544 -105.00868)
		(end 268.571726 -104.695498)
		(width 0.13462)
		(layer "F.Cu")
		(net "P5E_PEX2_STN1_TX_DN<19>")
	)
	(segment
		(start 263.158224 -108.226098)
		(end 263.157716 -108.226098)
		(width 0.1651)
		(layer "In9.Cu")
		(net "P5E_PEX2_STN1_TX_DN<19>")
	)
	(segment
		(start 266.372594 -105.011728)
		(end 263.158224 -108.226098)
		(width 0.1651)
		(layer "In9.Cu")
		(net "P5E_PEX2_STN1_TX_DN<19>")
	)
	(segment
		(start 294.12946 -271.600168)
		(end 294.12946 -280.10485)
		(width 0.1143)
		(layer "In9.Cu")
		(net "P5E_PEX2_STN1_TX_DN<19>")
	)
	(segment
		(start 294.58539 -280.319988)
		(end 294.69969 -280.434288)
		(width 0.1143)
		(layer "In9.Cu")
		(net "P5E_PEX2_STN1_TX_DN<19>")
	)
	(segment
		(start 294.08374 -271.554448)
		(end 294.12946 -271.600168)
		(width 0.1143)
		(layer "In9.Cu")
		(net "P5E_PEX2_STN1_TX_DN<19>")
	)
	(segment
		(start 258.22783 -151.935942)
		(end 258.22783 -151.935688)
		(width 0.1651)
		(layer "In9.Cu")
		(net "P5E_PEX2_STN1_TX_DN<19>")
	)
	(segment
		(start 267.034772 -105.011728)
		(end 266.372594 -105.011728)
		(width 0.1651)
		(layer "In9.Cu")
		(net "P5E_PEX2_STN1_TX_DN<19>")
	)
	(segment
		(start 267.325602 -104.720898)
		(end 267.034772 -105.011728)
		(width 0.1651)
		(layer "In9.Cu")
		(net "P5E_PEX2_STN1_TX_DN<19>")
	)
	(segment
		(start 255.308354 -131.059428)
		(end 255.308354 -138.47318)
		(width 0.1651)
		(layer "In9.Cu")
		(net "P5E_PEX2_STN1_TX_DN<19>")
	)
	(segment
		(start 257.870706 -144.659096)
		(end 258.22783 -151.935942)
		(width 0.1651)
		(layer "In9.Cu")
		(net "P5E_PEX2_STN1_TX_DN<19>")
	)
	(segment
		(start 259.19176 -162.262312)
		(end 294.08374 -265.345164)
		(width 0.1651)
		(layer "In9.Cu")
		(net "P5E_PEX2_STN1_TX_DN<19>")
	)
	(segment
		(start 258.406138 -155.565094)
		(end 258.585208 -159.213042)
		(width 0.1651)
		(layer "In9.Cu")
		(net "P5E_PEX2_STN1_TX_DN<19>")
	)
	(segment
		(start 258.22783 -151.935688)
		(end 258.406138 -155.565094)
		(width 0.1651)
		(layer "In9.Cu")
		(net "P5E_PEX2_STN1_TX_DN<19>")
	)
	(segment
		(start 294.08374 -265.345164)
		(end 294.08374 -271.526)
		(width 0.1651)
		(layer "In9.Cu")
		(net "P5E_PEX2_STN1_TX_DN<19>")
	)
	(segment
		(start 294.344598 -280.319988)
		(end 294.58539 -280.319988)
		(width 0.1143)
		(layer "In9.Cu")
		(net "P5E_PEX2_STN1_TX_DN<19>")
	)
	(segment
		(start 263.157716 -108.226098)
		(end 259.708142 -116.556028)
		(width 0.1651)
		(layer "In9.Cu")
		(net "P5E_PEX2_STN1_TX_DN<19>")
	)
	(segment
		(start 294.69969 -280.434288)
		(end 294.69969 -280.699718)
		(width 0.1143)
		(layer "In9.Cu")
		(net "P5E_PEX2_STN1_TX_DN<19>")
	)
	(segment
		(start 294.12946 -280.10485)
		(end 294.344598 -280.319988)
		(width 0.1143)
		(layer "In9.Cu")
		(net "P5E_PEX2_STN1_TX_DN<19>")
	)
	(segment
		(start 255.308354 -138.47318)
		(end 257.870706 -144.659096)
		(width 0.1651)
		(layer "In9.Cu")
		(net "P5E_PEX2_STN1_TX_DN<19>")
	)
	(segment
		(start 258.585208 -159.213042)
		(end 259.19176 -162.262312)
		(width 0.1651)
		(layer "In9.Cu")
		(net "P5E_PEX2_STN1_TX_DN<19>")
	)
	(segment
		(start 259.708142 -116.556028)
		(end 255.308354 -131.059428)
		(width 0.1651)
		(layer "In9.Cu")
		(net "P5E_PEX2_STN1_TX_DN<19>")
	)
	(segment
		(start 294.08374 -271.526)
		(end 294.08374 -271.554448)
		(width 0.1143)
		(layer "In9.Cu")
		(net "P5E_PEX2_STN1_TX_DN<19>")
	)
	(segment
		(start 132.486146 -389.715756)
		(end 136.555734 -388.904734)
		(width 0.1651)
		(layer "In5.Cu")
		(net "P5E_PEX1_STN5_RX_DN<82>")
	)
	(segment
		(start 176.320196 -316.534292)
		(end 176.434496 -316.419992)
		(width 0.1143)
		(layer "In5.Cu")
		(net "P5E_PEX1_STN5_RX_DN<82>")
	)
	(segment
		(start 120.437148 -397.281146)
		(end 120.986804 -397.281146)
		(width 0.1651)
		(layer "In5.Cu")
		(net "P5E_PEX1_STN5_RX_DN<82>")
	)
	(segment
		(start 176.434496 -316.419992)
		(end 176.585626 -316.419992)
		(width 0.1143)
		(layer "In5.Cu")
		(net "P5E_PEX1_STN5_RX_DN<82>")
	)
	(segment
		(start 174.178722 -327.110344)
		(end 175.170592 -326.118474)
		(width 0.1651)
		(layer "In5.Cu")
		(net "P5E_PEX1_STN5_RX_DN<82>")
	)
	(segment
		(start 120.310148 -397.408146)
		(end 120.437148 -397.281146)
		(width 0.1651)
		(layer "In5.Cu")
		(net "P5E_PEX1_STN5_RX_DN<82>")
	)
	(segment
		(start 158.43504 -337.734148)
		(end 160.63849 -335.271872)
		(width 0.1651)
		(layer "In5.Cu")
		(net "P5E_PEX1_STN5_RX_DN<82>")
	)
	(segment
		(start 128.837436 -391.139426)
		(end 132.486146 -389.715756)
		(width 0.1651)
		(layer "In5.Cu")
		(net "P5E_PEX1_STN5_RX_DN<82>")
	)
	(segment
		(start 138.483086 -386.877814)
		(end 144.732756 -370.180362)
		(width 0.1651)
		(layer "In5.Cu")
		(net "P5E_PEX1_STN5_RX_DN<82>")
	)
	(segment
		(start 137.79754 -388.029196)
		(end 138.483086 -386.877814)
		(width 0.1651)
		(layer "In5.Cu")
		(net "P5E_PEX1_STN5_RX_DN<82>")
	)
	(segment
		(start 120.986804 -397.281146)
		(end 121.369582 -396.898368)
		(width 0.1651)
		(layer "In5.Cu")
		(net "P5E_PEX1_STN5_RX_DN<82>")
	)
	(segment
		(start 145.85569 -366.136682)
		(end 150.97125 -352.640138)
		(width 0.1651)
		(layer "In5.Cu")
		(net "P5E_PEX1_STN5_RX_DN<82>")
	)
	(segment
		(start 120.310148 -397.790162)
		(end 120.310148 -397.408146)
		(width 0.1651)
		(layer "In5.Cu")
		(net "P5E_PEX1_STN5_RX_DN<82>")
	)
	(segment
		(start 176.365916 -319.91173)
		(end 176.365916 -319.883282)
		(width 0.1143)
		(layer "In5.Cu")
		(net "P5E_PEX1_STN5_RX_DN<82>")
	)
	(segment
		(start 176.1363 -323.79158)
		(end 176.365916 -323.048884)
		(width 0.1651)
		(layer "In5.Cu")
		(net "P5E_PEX1_STN5_RX_DN<82>")
	)
	(segment
		(start 176.365916 -319.883282)
		(end 176.320196 -319.837562)
		(width 0.1143)
		(layer "In5.Cu")
		(net "P5E_PEX1_STN5_RX_DN<82>")
	)
	(segment
		(start 122.057668 -395.11097)
		(end 122.305826 -394.806932)
		(width 0.1651)
		(layer "In5.Cu")
		(net "P5E_PEX1_STN5_RX_DN<82>")
	)
	(segment
		(start 121.369582 -395.954504)
		(end 122.057668 -395.111224)
		(width 0.1651)
		(layer "In5.Cu")
		(net "P5E_PEX1_STN5_RX_DN<82>")
	)
	(segment
		(start 176.320196 -319.837562)
		(end 176.320196 -316.534292)
		(width 0.1143)
		(layer "In5.Cu")
		(net "P5E_PEX1_STN5_RX_DN<82>")
	)
	(segment
		(start 176.699926 -316.534292)
		(end 176.699926 -316.799722)
		(width 0.1143)
		(layer "In5.Cu")
		(net "P5E_PEX1_STN5_RX_DN<82>")
	)
	(segment
		(start 176.585626 -316.419992)
		(end 176.699926 -316.534292)
		(width 0.1143)
		(layer "In5.Cu")
		(net "P5E_PEX1_STN5_RX_DN<82>")
	)
	(segment
		(start 121.369582 -396.898368)
		(end 121.369582 -395.954504)
		(width 0.1651)
		(layer "In5.Cu")
		(net "P5E_PEX1_STN5_RX_DN<82>")
	)
	(segment
		(start 144.732756 -370.180362)
		(end 145.85569 -366.136682)
		(width 0.1651)
		(layer "In5.Cu")
		(net "P5E_PEX1_STN5_RX_DN<82>")
	)
	(segment
		(start 136.555734 -388.904734)
		(end 137.79754 -388.029196)
		(width 0.1651)
		(layer "In5.Cu")
		(net "P5E_PEX1_STN5_RX_DN<82>")
	)
	(segment
		(start 150.97125 -352.640138)
		(end 158.43504 -337.734148)
		(width 0.1651)
		(layer "In5.Cu")
		(net "P5E_PEX1_STN5_RX_DN<82>")
	)
	(segment
		(start 122.305826 -394.806932)
		(end 123.69927 -393.694412)
		(width 0.1651)
		(layer "In5.Cu")
		(net "P5E_PEX1_STN5_RX_DN<82>")
	)
	(segment
		(start 175.170592 -326.118474)
		(end 176.1363 -323.79158)
		(width 0.1651)
		(layer "In5.Cu")
		(net "P5E_PEX1_STN5_RX_DN<82>")
	)
	(segment
		(start 122.057668 -395.111224)
		(end 122.057668 -395.11097)
		(width 0.1651)
		(layer "In5.Cu")
		(net "P5E_PEX1_STN5_RX_DN<82>")
	)
	(segment
		(start 173.552358 -327.6727)
		(end 174.178722 -327.110344)
		(width 0.1651)
		(layer "In5.Cu")
		(net "P5E_PEX1_STN5_RX_DN<82>")
	)
	(segment
		(start 123.69927 -393.694158)
		(end 128.837436 -391.139426)
		(width 0.1651)
		(layer "In5.Cu")
		(net "P5E_PEX1_STN5_RX_DN<82>")
	)
	(segment
		(start 176.365916 -323.048884)
		(end 176.365916 -319.91173)
		(width 0.1651)
		(layer "In5.Cu")
		(net "P5E_PEX1_STN5_RX_DN<82>")
	)
	(segment
		(start 160.63849 -335.271872)
		(end 173.552358 -327.6727)
		(width 0.1651)
		(layer "In5.Cu")
		(net "P5E_PEX1_STN5_RX_DN<82>")
	)
	(segment
		(start 123.69927 -393.694412)
		(end 123.69927 -393.694158)
		(width 0.1651)
		(layer "In5.Cu")
		(net "P5E_PEX1_STN5_RX_DN<82>")
	)
	(segment
		(start 330.430886 -361.628944)
		(end 330.51623 -361.491784)
		(width 0.1651)
		(layer "In5.Cu")
		(net "P5E_PEX2_STN5_RX_DP<88>")
	)
	(segment
		(start 331.997304 -367.832386)
		(end 331.85989 -367.747042)
		(width 0.1651)
		(layer "In5.Cu")
		(net "P5E_PEX2_STN5_RX_DP<88>")
	)
	(segment
		(start 330.543662 -362.111544)
		(end 330.430886 -361.628944)
		(width 0.1651)
		(layer "In5.Cu")
		(net "P5E_PEX2_STN5_RX_DP<88>")
	)
	(segment
		(start 331.490066 -370.489988)
		(end 331.490066 -370.872258)
		(width 0.1651)
		(layer "In5.Cu")
		(net "P5E_PEX2_STN5_RX_DP<88>")
	)
	(segment
		(start 331.832458 -367.127282)
		(end 331.719936 -366.64519)
		(width 0.1651)
		(layer "In5.Cu")
		(net "P5E_PEX2_STN5_RX_DP<88>")
	)
	(segment
		(start 332.047342 -370.999258)
		(end 332.334108 -370.712492)
		(width 0.1651)
		(layer "In5.Cu")
		(net "P5E_PEX2_STN5_RX_DP<88>")
	)
	(segment
		(start 331.55509 -365.939832)
		(end 330.681076 -362.196888)
		(width 0.1651)
		(layer "In5.Cu")
		(net "P5E_PEX2_STN5_RX_DP<88>")
	)
	(segment
		(start 297.883834 -319.9638)
		(end 297.929554 -319.91808)
		(width 0.1143)
		(layer "In5.Cu")
		(net "P5E_PEX2_STN5_RX_DP<88>")
	)
	(segment
		(start 329.892914 -358.82199)
		(end 329.892914 -341.867998)
		(width 0.1651)
		(layer "In5.Cu")
		(net "P5E_PEX2_STN5_RX_DP<88>")
	)
	(segment
		(start 297.929554 -319.91808)
		(end 297.929554 -316.455298)
		(width 0.1143)
		(layer "In5.Cu")
		(net "P5E_PEX2_STN5_RX_DP<88>")
	)
	(segment
		(start 297.929554 -316.455298)
		(end 298.15536 -316.229492)
		(width 0.1143)
		(layer "In5.Cu")
		(net "P5E_PEX2_STN5_RX_DP<88>")
	)
	(segment
		(start 328.699368 -340.674452)
		(end 302.044354 -327.475088)
		(width 0.1651)
		(layer "In5.Cu")
		(net "P5E_PEX2_STN5_RX_DP<88>")
	)
	(segment
		(start 298.835826 -324.26656)
		(end 297.883834 -321.968114)
		(width 0.1651)
		(layer "In5.Cu")
		(net "P5E_PEX2_STN5_RX_DP<88>")
	)
	(segment
		(start 302.044354 -327.475088)
		(end 298.835826 -324.26656)
		(width 0.1651)
		(layer "In5.Cu")
		(net "P5E_PEX2_STN5_RX_DP<88>")
	)
	(segment
		(start 331.617066 -370.999258)
		(end 332.047342 -370.999258)
		(width 0.1651)
		(layer "In5.Cu")
		(net "P5E_PEX2_STN5_RX_DP<88>")
	)
	(segment
		(start 297.883834 -321.968114)
		(end 297.883834 -319.992248)
		(width 0.1651)
		(layer "In5.Cu")
		(net "P5E_PEX2_STN5_RX_DP<88>")
	)
	(segment
		(start 331.719936 -366.64519)
		(end 331.582522 -366.559846)
		(width 0.1651)
		(layer "In5.Cu")
		(net "P5E_PEX2_STN5_RX_DP<88>")
	)
	(segment
		(start 330.681076 -362.196888)
		(end 330.543662 -362.111544)
		(width 0.1651)
		(layer "In5.Cu")
		(net "P5E_PEX2_STN5_RX_DP<88>")
	)
	(segment
		(start 297.883834 -319.992248)
		(end 297.883834 -319.9638)
		(width 0.1143)
		(layer "In5.Cu")
		(net "P5E_PEX2_STN5_RX_DP<88>")
	)
	(segment
		(start 331.469746 -366.077246)
		(end 331.55509 -365.939832)
		(width 0.1651)
		(layer "In5.Cu")
		(net "P5E_PEX2_STN5_RX_DP<88>")
	)
	(segment
		(start 331.747114 -367.264696)
		(end 331.832458 -367.127282)
		(width 0.1651)
		(layer "In5.Cu")
		(net "P5E_PEX2_STN5_RX_DP<88>")
	)
	(segment
		(start 331.582522 -366.559846)
		(end 331.469746 -366.077246)
		(width 0.1651)
		(layer "In5.Cu")
		(net "P5E_PEX2_STN5_RX_DP<88>")
	)
	(segment
		(start 329.892914 -341.867998)
		(end 328.699368 -340.674452)
		(width 0.1651)
		(layer "In5.Cu")
		(net "P5E_PEX2_STN5_RX_DP<88>")
	)
	(segment
		(start 332.334108 -370.712492)
		(end 332.334108 -369.274598)
		(width 0.1651)
		(layer "In5.Cu")
		(net "P5E_PEX2_STN5_RX_DP<88>")
	)
	(segment
		(start 330.51623 -361.491784)
		(end 329.892914 -358.82199)
		(width 0.1651)
		(layer "In5.Cu")
		(net "P5E_PEX2_STN5_RX_DP<88>")
	)
	(segment
		(start 298.385484 -316.229492)
		(end 298.499784 -316.115192)
		(width 0.1143)
		(layer "In5.Cu")
		(net "P5E_PEX2_STN5_RX_DP<88>")
	)
	(segment
		(start 331.490066 -370.872258)
		(end 331.617066 -370.999258)
		(width 0.1651)
		(layer "In5.Cu")
		(net "P5E_PEX2_STN5_RX_DP<88>")
	)
	(segment
		(start 298.499784 -316.115192)
		(end 298.499784 -315.849762)
		(width 0.1143)
		(layer "In5.Cu")
		(net "P5E_PEX2_STN5_RX_DP<88>")
	)
	(segment
		(start 332.334108 -369.274598)
		(end 331.997304 -367.832386)
		(width 0.1651)
		(layer "In5.Cu")
		(net "P5E_PEX2_STN5_RX_DP<88>")
	)
	(segment
		(start 331.85989 -367.747042)
		(end 331.747114 -367.264696)
		(width 0.1651)
		(layer "In5.Cu")
		(net "P5E_PEX2_STN5_RX_DP<88>")
	)
	(segment
		(start 298.15536 -316.229492)
		(end 298.385484 -316.229492)
		(width 0.1143)
		(layer "In5.Cu")
		(net "P5E_PEX2_STN5_RX_DP<88>")
	)
	(segment
		(start 19.627088 -351.316798)
		(end 19.627088 -350.685354)
		(width 0.13462)
		(layer "F.Cu")
		(net "P5E_PEX0_STN7_TX_C_DP<112>")
	)
	(segment
		(start 19.627088 -350.685354)
		(end 19.307048 -350.365314)
		(width 0.13462)
		(layer "F.Cu")
		(net "P5E_PEX0_STN7_TX_C_DP<112>")
	)
	(segment
		(start 19.332448 -351.611438)
		(end 19.627088 -351.316798)
		(width 0.13462)
		(layer "F.Cu")
		(net "P5E_PEX0_STN7_TX_C_DP<112>")
	)
	(segment
		(start 21.508974 -389.181086)
		(end 19.7866 -385.35356)
		(width 0.1651)
		(layer "In7.Cu")
		(net "P5E_PEX0_STN7_TX_C_DP<112>")
	)
	(segment
		(start 19.7866 -385.35356)
		(end 18.85696 -369.931188)
		(width 0.1651)
		(layer "In7.Cu")
		(net "P5E_PEX0_STN7_TX_C_DP<112>")
	)
	(segment
		(start 18.85696 -369.931188)
		(end 19.623278 -354.337366)
		(width 0.1651)
		(layer "In7.Cu")
		(net "P5E_PEX0_STN7_TX_C_DP<112>")
	)
	(segment
		(start 28.80233 -394.12291)
		(end 28.389834 -393.710414)
		(width 0.1651)
		(layer "In7.Cu")
		(net "P5E_PEX0_STN7_TX_C_DP<112>")
	)
	(segment
		(start 28.80233 -400.490436)
		(end 28.80233 -394.12291)
		(width 0.1651)
		(layer "In7.Cu")
		(net "P5E_PEX0_STN7_TX_C_DP<112>")
	)
	(segment
		(start 19.623278 -354.337366)
		(end 19.623278 -351.902268)
		(width 0.1651)
		(layer "In7.Cu")
		(net "P5E_PEX0_STN7_TX_C_DP<112>")
	)
	(segment
		(start 24.375364 -392.047476)
		(end 21.508974 -389.181086)
		(width 0.1651)
		(layer "In7.Cu")
		(net "P5E_PEX0_STN7_TX_C_DP<112>")
	)
	(segment
		(start 19.623278 -351.902268)
		(end 19.332448 -351.611438)
		(width 0.1651)
		(layer "In7.Cu")
		(net "P5E_PEX0_STN7_TX_C_DP<112>")
	)
	(segment
		(start 28.037028 -400.899122)
		(end 28.393644 -400.899122)
		(width 0.1651)
		(layer "In7.Cu")
		(net "P5E_PEX0_STN7_TX_C_DP<112>")
	)
	(segment
		(start 28.389834 -393.710414)
		(end 24.375364 -392.047476)
		(width 0.1651)
		(layer "In7.Cu")
		(net "P5E_PEX0_STN7_TX_C_DP<112>")
	)
	(segment
		(start 27.910028 -400.772122)
		(end 28.037028 -400.899122)
		(width 0.1651)
		(layer "In7.Cu")
		(net "P5E_PEX0_STN7_TX_C_DP<112>")
	)
	(segment
		(start 27.910028 -400.390106)
		(end 27.910028 -400.772122)
		(width 0.1651)
		(layer "In7.Cu")
		(net "P5E_PEX0_STN7_TX_C_DP<112>")
	)
	(segment
		(start 28.393644 -400.899122)
		(end 28.80233 -400.490436)
		(width 0.1651)
		(layer "In7.Cu")
		(net "P5E_PEX0_STN7_TX_C_DP<112>")
	)
	(segment
		(start 197.337426 -133.800342)
		(end 197.632066 -133.505702)
		(width 0.13462)
		(layer "F.Cu")
		(net "P5E_PEX1_STN0_TX_DN<6>")
	)
	(segment
		(start 196.385942 -133.480302)
		(end 196.705982 -133.800342)
		(width 0.13462)
		(layer "F.Cu")
		(net "P5E_PEX1_STN0_TX_DN<6>")
	)
	(segment
		(start 196.705982 -133.800342)
		(end 197.337426 -133.800342)
		(width 0.13462)
		(layer "F.Cu")
		(net "P5E_PEX1_STN0_TX_DN<6>")
	)
	(segment
		(start 210.465162 -153.928572)
		(end 210.465162 -158.997904)
		(width 0.1651)
		(layer "In9.Cu")
		(net "P5E_PEX1_STN0_TX_DN<6>")
	)
	(segment
		(start 206.947008 -145.434812)
		(end 210.465162 -153.928572)
		(width 0.1651)
		(layer "In9.Cu")
		(net "P5E_PEX1_STN0_TX_DN<6>")
	)
	(segment
		(start 210.943952 -271.584166)
		(end 210.168236 -273.714718)
		(width 0.1651)
		(layer "In9.Cu")
		(net "P5E_PEX1_STN0_TX_DN<6>")
	)
	(segment
		(start 210.691476 -268.704568)
		(end 210.943952 -271.584166)
		(width 0.1651)
		(layer "In9.Cu")
		(net "P5E_PEX1_STN0_TX_DN<6>")
	)
	(segment
		(start 210.095084 -267.264388)
		(end 210.691476 -268.704568)
		(width 0.1651)
		(layer "In9.Cu")
		(net "P5E_PEX1_STN0_TX_DN<6>")
	)
	(segment
		(start 201.714862 -134.558024)
		(end 202.496166 -135.339328)
		(width 0.1651)
		(layer "In9.Cu")
		(net "P5E_PEX1_STN0_TX_DN<6>")
	)
	(segment
		(start 202.496166 -135.339328)
		(end 206.487776 -144.97558)
		(width 0.1651)
		(layer "In9.Cu")
		(net "P5E_PEX1_STN0_TX_DN<6>")
	)
	(segment
		(start 200.017634 -282.265882)
		(end 199.989186 -282.265882)
		(width 0.1143)
		(layer "In9.Cu")
		(net "P5E_PEX1_STN0_TX_DN<6>")
	)
	(segment
		(start 201.869294 -173.890686)
		(end 200.713594 -178.200304)
		(width 0.1651)
		(layer "In9.Cu")
		(net "P5E_PEX1_STN0_TX_DN<6>")
	)
	(segment
		(start 202.248516 -281.634438)
		(end 200.723754 -282.265882)
		(width 0.1651)
		(layer "In9.Cu")
		(net "P5E_PEX1_STN0_TX_DN<6>")
	)
	(segment
		(start 199.943466 -282.220162)
		(end 193.52387 -282.220162)
		(width 0.1143)
		(layer "In9.Cu")
		(net "P5E_PEX1_STN0_TX_DN<6>")
	)
	(segment
		(start 200.713594 -178.200304)
		(end 196.912992 -221.640654)
		(width 0.1651)
		(layer "In9.Cu")
		(net "P5E_PEX1_STN0_TX_DN<6>")
	)
	(segment
		(start 210.168236 -273.714718)
		(end 202.248516 -281.634438)
		(width 0.1651)
		(layer "In9.Cu")
		(net "P5E_PEX1_STN0_TX_DN<6>")
	)
	(segment
		(start 199.989186 -282.265882)
		(end 199.943466 -282.220162)
		(width 0.1143)
		(layer "In9.Cu")
		(net "P5E_PEX1_STN0_TX_DN<6>")
	)
	(segment
		(start 197.632066 -133.505702)
		(end 197.922896 -133.796532)
		(width 0.1651)
		(layer "In9.Cu")
		(net "P5E_PEX1_STN0_TX_DN<6>")
	)
	(segment
		(start 196.912992 -221.640654)
		(end 199.515222 -251.430536)
		(width 0.1651)
		(layer "In9.Cu")
		(net "P5E_PEX1_STN0_TX_DN<6>")
	)
	(segment
		(start 193.420238 -282.323794)
		(end 193.420238 -282.485592)
		(width 0.1143)
		(layer "In9.Cu")
		(net "P5E_PEX1_STN0_TX_DN<6>")
	)
	(segment
		(start 206.487776 -144.97558)
		(end 206.947008 -145.434812)
		(width 0.1651)
		(layer "In9.Cu")
		(net "P5E_PEX1_STN0_TX_DN<6>")
	)
	(segment
		(start 193.420238 -282.485592)
		(end 193.534538 -282.599892)
		(width 0.1143)
		(layer "In9.Cu")
		(net "P5E_PEX1_STN0_TX_DN<6>")
	)
	(segment
		(start 200.723754 -282.265882)
		(end 200.017634 -282.265882)
		(width 0.1651)
		(layer "In9.Cu")
		(net "P5E_PEX1_STN0_TX_DN<6>")
	)
	(segment
		(start 199.515222 -251.430536)
		(end 210.095084 -267.264388)
		(width 0.1651)
		(layer "In9.Cu")
		(net "P5E_PEX1_STN0_TX_DN<6>")
	)
	(segment
		(start 210.465162 -158.997904)
		(end 201.869294 -173.890686)
		(width 0.1651)
		(layer "In9.Cu")
		(net "P5E_PEX1_STN0_TX_DN<6>")
	)
	(segment
		(start 197.922896 -133.796532)
		(end 199.87641 -133.796532)
		(width 0.1651)
		(layer "In9.Cu")
		(net "P5E_PEX1_STN0_TX_DN<6>")
	)
	(segment
		(start 193.534538 -282.599892)
		(end 193.799968 -282.599892)
		(width 0.1143)
		(layer "In9.Cu")
		(net "P5E_PEX1_STN0_TX_DN<6>")
	)
	(segment
		(start 199.87641 -133.796532)
		(end 201.714862 -134.558024)
		(width 0.1651)
		(layer "In9.Cu")
		(net "P5E_PEX1_STN0_TX_DN<6>")
	)
	(segment
		(start 193.52387 -282.220162)
		(end 193.420238 -282.323794)
		(width 0.1143)
		(layer "In9.Cu")
		(net "P5E_PEX1_STN0_TX_DN<6>")
	)
	(segment
		(start 187.626752 -343.365582)
		(end 187.626752 -342.734138)
		(width 0.13462)
		(layer "F.Cu")
		(net "P5E_PEX1_STN7_TX_DN<124>")
	)
	(segment
		(start 187.946792 -343.685622)
		(end 187.626752 -343.365582)
		(width 0.13462)
		(layer "F.Cu")
		(net "P5E_PEX1_STN7_TX_DN<124>")
	)
	(segment
		(start 187.626752 -342.734138)
		(end 187.921392 -342.439498)
		(width 0.13462)
		(layer "F.Cu")
		(net "P5E_PEX1_STN7_TX_DN<124>")
	)
	(segment
		(start 187.052712 -340.68639)
		(end 182.620666 -337.49742)
		(width 0.1651)
		(layer "In11.Cu")
		(net "P5E_PEX1_STN7_TX_DN<124>")
	)
	(segment
		(start 157.645608 -324.180708)
		(end 155.86583 -322.323714)
		(width 0.1651)
		(layer "In11.Cu")
		(net "P5E_PEX1_STN7_TX_DN<124>")
	)
	(segment
		(start 187.630562 -341.45601)
		(end 187.052712 -340.68639)
		(width 0.1651)
		(layer "In11.Cu")
		(net "P5E_PEX1_STN7_TX_DN<124>")
	)
	(segment
		(start 155.420314 -311.82818)
		(end 155.578302 -311.670192)
		(width 0.1143)
		(layer "In11.Cu")
		(net "P5E_PEX1_STN7_TX_DN<124>")
	)
	(segment
		(start 155.711144 -311.670192)
		(end 155.800044 -311.759092)
		(width 0.1143)
		(layer "In11.Cu")
		(net "P5E_PEX1_STN7_TX_DN<124>")
	)
	(segment
		(start 155.466034 -321.459606)
		(end 155.466034 -320.043048)
		(width 0.1651)
		(layer "In11.Cu")
		(net "P5E_PEX1_STN7_TX_DN<124>")
	)
	(segment
		(start 187.921392 -342.439498)
		(end 187.630562 -342.148668)
		(width 0.1651)
		(layer "In11.Cu")
		(net "P5E_PEX1_STN7_TX_DN<124>")
	)
	(segment
		(start 155.800044 -311.759092)
		(end 155.800044 -312.049922)
		(width 0.1143)
		(layer "In11.Cu")
		(net "P5E_PEX1_STN7_TX_DN<124>")
	)
	(segment
		(start 155.86583 -322.323714)
		(end 155.466034 -321.459606)
		(width 0.1651)
		(layer "In11.Cu")
		(net "P5E_PEX1_STN7_TX_DN<124>")
	)
	(segment
		(start 155.466034 -320.043048)
		(end 155.466034 -320.02095)
		(width 0.1143)
		(layer "In11.Cu")
		(net "P5E_PEX1_STN7_TX_DN<124>")
	)
	(segment
		(start 155.466034 -320.02095)
		(end 155.420314 -319.97523)
		(width 0.1143)
		(layer "In11.Cu")
		(net "P5E_PEX1_STN7_TX_DN<124>")
	)
	(segment
		(start 175.576992 -333.438246)
		(end 157.645608 -324.180708)
		(width 0.1651)
		(layer "In11.Cu")
		(net "P5E_PEX1_STN7_TX_DN<124>")
	)
	(segment
		(start 182.60822 -337.490308)
		(end 175.576992 -333.438246)
		(width 0.1651)
		(layer "In11.Cu")
		(net "P5E_PEX1_STN7_TX_DN<124>")
	)
	(segment
		(start 182.60822 -337.490054)
		(end 182.60822 -337.490308)
		(width 0.1651)
		(layer "In11.Cu")
		(net "P5E_PEX1_STN7_TX_DN<124>")
	)
	(segment
		(start 155.578302 -311.670192)
		(end 155.711144 -311.670192)
		(width 0.1143)
		(layer "In11.Cu")
		(net "P5E_PEX1_STN7_TX_DN<124>")
	)
	(segment
		(start 182.620666 -337.49742)
		(end 182.60822 -337.490054)
		(width 0.1651)
		(layer "In11.Cu")
		(net "P5E_PEX1_STN7_TX_DN<124>")
	)
	(segment
		(start 155.420314 -319.97523)
		(end 155.420314 -311.82818)
		(width 0.1143)
		(layer "In11.Cu")
		(net "P5E_PEX1_STN7_TX_DN<124>")
	)
	(segment
		(start 187.630562 -342.148668)
		(end 187.630562 -341.45601)
		(width 0.1651)
		(layer "In11.Cu")
		(net "P5E_PEX1_STN7_TX_DN<124>")
	)
	(segment
		(start 313.435492 -146.51228)
		(end 312.808112 -146.51228)
		(width 0.13462)
		(layer "F.Cu")
		(net "P5E_PEX2_STN0_TX_DN<10>")
	)
	(segment
		(start 312.808112 -146.51228)
		(end 312.48604 -146.190208)
		(width 0.13462)
		(layer "F.Cu")
		(net "P5E_PEX2_STN0_TX_DN<10>")
	)
	(segment
		(start 313.732164 -146.215608)
		(end 313.435492 -146.51228)
		(width 0.13462)
		(layer "F.Cu")
		(net "P5E_PEX2_STN0_TX_DN<10>")
	)
	(segment
		(start 318.14135 -147.31111)
		(end 319.547748 -148.717508)
		(width 0.1651)
		(layer "In9.Cu")
		(net "P5E_PEX2_STN0_TX_DN<10>")
	)
	(segment
		(start 313.732164 -146.215608)
		(end 314.022994 -146.506438)
		(width 0.1651)
		(layer "In9.Cu")
		(net "P5E_PEX2_STN0_TX_DN<10>")
	)
	(segment
		(start 311.465722 -271.155414)
		(end 311.465722 -271.526)
		(width 0.1651)
		(layer "In9.Cu")
		(net "P5E_PEX2_STN0_TX_DN<10>")
	)
	(segment
		(start 314.274708 -172.601128)
		(end 312.9534 -177.529236)
		(width 0.1651)
		(layer "In9.Cu")
		(net "P5E_PEX2_STN0_TX_DN<10>")
	)
	(segment
		(start 311.420002 -271.600168)
		(end 311.420002 -280.025856)
		(width 0.1143)
		(layer "In9.Cu")
		(net "P5E_PEX2_STN0_TX_DN<10>")
	)
	(segment
		(start 321.226942 -151.238204)
		(end 322.694046 -154.780488)
		(width 0.1651)
		(layer "In9.Cu")
		(net "P5E_PEX2_STN0_TX_DN<10>")
	)
	(segment
		(start 322.694046 -154.780488)
		(end 322.694046 -158.01594)
		(width 0.1651)
		(layer "In9.Cu")
		(net "P5E_PEX2_STN0_TX_DN<10>")
	)
	(segment
		(start 311.465722 -271.526)
		(end 311.465722 -271.554448)
		(width 0.1143)
		(layer "In9.Cu")
		(net "P5E_PEX2_STN0_TX_DN<10>")
	)
	(segment
		(start 316.250066 -146.527774)
		(end 318.14135 -147.31111)
		(width 0.1651)
		(layer "In9.Cu")
		(net "P5E_PEX2_STN0_TX_DN<10>")
	)
	(segment
		(start 312.9534 -177.529236)
		(end 309.049928 -222.099124)
		(width 0.1651)
		(layer "In9.Cu")
		(net "P5E_PEX2_STN0_TX_DN<10>")
	)
	(segment
		(start 311.799732 -280.015188)
		(end 311.799732 -279.749758)
		(width 0.1143)
		(layer "In9.Cu")
		(net "P5E_PEX2_STN0_TX_DN<10>")
	)
	(segment
		(start 311.685432 -280.129488)
		(end 311.799732 -280.015188)
		(width 0.1143)
		(layer "In9.Cu")
		(net "P5E_PEX2_STN0_TX_DN<10>")
	)
	(segment
		(start 311.465722 -271.554448)
		(end 311.420002 -271.600168)
		(width 0.1143)
		(layer "In9.Cu")
		(net "P5E_PEX2_STN0_TX_DN<10>")
	)
	(segment
		(start 309.049928 -222.099124)
		(end 312.42889 -260.752844)
		(width 0.1651)
		(layer "In9.Cu")
		(net "P5E_PEX2_STN0_TX_DN<10>")
	)
	(segment
		(start 312.42889 -268.829536)
		(end 311.465722 -271.155414)
		(width 0.1651)
		(layer "In9.Cu")
		(net "P5E_PEX2_STN0_TX_DN<10>")
	)
	(segment
		(start 322.694046 -158.01594)
		(end 314.274708 -172.601128)
		(width 0.1651)
		(layer "In9.Cu")
		(net "P5E_PEX2_STN0_TX_DN<10>")
	)
	(segment
		(start 316.22873 -146.506438)
		(end 316.250066 -146.527774)
		(width 0.1651)
		(layer "In9.Cu")
		(net "P5E_PEX2_STN0_TX_DN<10>")
	)
	(segment
		(start 311.523634 -280.129488)
		(end 311.685432 -280.129488)
		(width 0.1143)
		(layer "In9.Cu")
		(net "P5E_PEX2_STN0_TX_DN<10>")
	)
	(segment
		(start 311.420002 -280.025856)
		(end 311.523634 -280.129488)
		(width 0.1143)
		(layer "In9.Cu")
		(net "P5E_PEX2_STN0_TX_DN<10>")
	)
	(segment
		(start 312.42889 -260.752844)
		(end 312.42889 -268.829536)
		(width 0.1651)
		(layer "In9.Cu")
		(net "P5E_PEX2_STN0_TX_DN<10>")
	)
	(segment
		(start 319.547748 -148.717508)
		(end 319.547748 -148.725128)
		(width 0.1651)
		(layer "In9.Cu")
		(net "P5E_PEX2_STN0_TX_DN<10>")
	)
	(segment
		(start 319.547748 -148.725128)
		(end 321.226942 -151.238204)
		(width 0.1651)
		(layer "In9.Cu")
		(net "P5E_PEX2_STN0_TX_DN<10>")
	)
	(segment
		(start 314.022994 -146.506438)
		(end 316.22873 -146.506438)
		(width 0.1651)
		(layer "In9.Cu")
		(net "P5E_PEX2_STN0_TX_DN<10>")
	)
	(segment
		(start 172.834808 -394.19022)
		(end 172.42282 -393.914884)
		(width 0.1651)
		(layer "In9.Cu")
		(net "P5E_PEX1_STN7_RX_DP<118>")
	)
	(segment
		(start 139.506452 -322.414646)
		(end 139.506452 -319.877694)
		(width 0.1651)
		(layer "In9.Cu")
		(net "P5E_PEX1_STN7_RX_DP<118>")
	)
	(segment
		(start 155.509214 -307.299868)
		(end 155.800044 -307.299868)
		(width 0.1143)
		(layer "In9.Cu")
		(net "P5E_PEX1_STN7_RX_DP<118>")
	)
	(segment
		(start 142.342362 -327.264522)
		(end 139.630658 -322.876672)
		(width 0.1651)
		(layer "In9.Cu")
		(net "P5E_PEX1_STN7_RX_DP<118>")
	)
	(segment
		(start 155.196286 -306.729638)
		(end 155.420314 -306.953666)
		(width 0.1143)
		(layer "In9.Cu")
		(net "P5E_PEX1_STN7_RX_DP<118>")
	)
	(segment
		(start 173.458378 -408.699208)
		(end 173.992286 -408.1653)
		(width 0.1651)
		(layer "In9.Cu")
		(net "P5E_PEX1_STN7_RX_DP<118>")
	)
	(segment
		(start 151.783542 -344.168984)
		(end 150.396448 -340.296246)
		(width 0.1651)
		(layer "In9.Cu")
		(net "P5E_PEX1_STN7_RX_DP<118>")
	)
	(segment
		(start 173.992286 -394.987272)
		(end 173.552866 -394.547852)
		(width 0.1651)
		(layer "In9.Cu")
		(net "P5E_PEX1_STN7_RX_DP<118>")
	)
	(segment
		(start 172.975778 -394.16228)
		(end 172.834808 -394.19022)
		(width 0.1651)
		(layer "In9.Cu")
		(net "P5E_PEX1_STN7_RX_DP<118>")
	)
	(segment
		(start 172.39488 -393.773914)
		(end 171.983146 -393.498832)
		(width 0.1651)
		(layer "In9.Cu")
		(net "P5E_PEX1_STN7_RX_DP<118>")
	)
	(segment
		(start 157.144466 -383.870962)
		(end 151.783542 -344.168984)
		(width 0.1651)
		(layer "In9.Cu")
		(net "P5E_PEX1_STN7_RX_DP<118>")
	)
	(segment
		(start 173.23689 -408.699208)
		(end 173.458378 -408.699208)
		(width 0.1651)
		(layer "In9.Cu")
		(net "P5E_PEX1_STN7_RX_DP<118>")
	)
	(segment
		(start 155.420314 -307.210968)
		(end 155.509214 -307.299868)
		(width 0.1143)
		(layer "In9.Cu")
		(net "P5E_PEX1_STN7_RX_DP<118>")
	)
	(segment
		(start 150.457916 -306.683918)
		(end 151.765 -306.683918)
		(width 0.1651)
		(layer "In9.Cu")
		(net "P5E_PEX1_STN7_RX_DP<118>")
	)
	(segment
		(start 169.121328 -391.585958)
		(end 161.06902 -388.248398)
		(width 0.1651)
		(layer "In9.Cu")
		(net "P5E_PEX1_STN7_RX_DP<118>")
	)
	(segment
		(start 149.129242 -307.234336)
		(end 150.457916 -306.683918)
		(width 0.1651)
		(layer "In9.Cu")
		(net "P5E_PEX1_STN7_RX_DP<118>")
	)
	(segment
		(start 151.765 -306.683918)
		(end 151.793448 -306.683918)
		(width 0.1143)
		(layer "In9.Cu")
		(net "P5E_PEX1_STN7_RX_DP<118>")
	)
	(segment
		(start 171.402248 -393.110466)
		(end 169.121328 -391.585958)
		(width 0.1651)
		(layer "In9.Cu")
		(net "P5E_PEX1_STN7_RX_DP<118>")
	)
	(segment
		(start 173.992286 -408.1653)
		(end 173.992286 -394.987272)
		(width 0.1651)
		(layer "In9.Cu")
		(net "P5E_PEX1_STN7_RX_DP<118>")
	)
	(segment
		(start 171.983146 -393.498832)
		(end 171.842176 -393.526772)
		(width 0.1651)
		(layer "In9.Cu")
		(net "P5E_PEX1_STN7_RX_DP<118>")
	)
	(segment
		(start 158.323026 -386.009388)
		(end 157.144466 -383.870962)
		(width 0.1651)
		(layer "In9.Cu")
		(net "P5E_PEX1_STN7_RX_DP<118>")
	)
	(segment
		(start 145.031968 -331.616558)
		(end 142.342108 -327.264522)
		(width 0.1651)
		(layer "In9.Cu")
		(net "P5E_PEX1_STN7_RX_DP<118>")
	)
	(segment
		(start 150.396448 -340.296246)
		(end 145.032222 -331.616812)
		(width 0.1651)
		(layer "In9.Cu")
		(net "P5E_PEX1_STN7_RX_DP<118>")
	)
	(segment
		(start 139.506452 -319.877694)
		(end 140.814552 -316.930786)
		(width 0.1651)
		(layer "In9.Cu")
		(net "P5E_PEX1_STN7_RX_DP<118>")
	)
	(segment
		(start 172.42282 -393.914884)
		(end 172.39488 -393.773914)
		(width 0.1651)
		(layer "In9.Cu")
		(net "P5E_PEX1_STN7_RX_DP<118>")
	)
	(segment
		(start 145.032222 -331.616812)
		(end 145.031968 -331.616558)
		(width 0.1651)
		(layer "In9.Cu")
		(net "P5E_PEX1_STN7_RX_DP<118>")
	)
	(segment
		(start 151.839168 -306.729638)
		(end 155.196286 -306.729638)
		(width 0.1143)
		(layer "In9.Cu")
		(net "P5E_PEX1_STN7_RX_DP<118>")
	)
	(segment
		(start 151.793448 -306.683918)
		(end 151.839168 -306.729638)
		(width 0.1143)
		(layer "In9.Cu")
		(net "P5E_PEX1_STN7_RX_DP<118>")
	)
	(segment
		(start 173.10989 -408.190192)
		(end 173.10989 -408.572208)
		(width 0.1651)
		(layer "In9.Cu")
		(net "P5E_PEX1_STN7_RX_DP<118>")
	)
	(segment
		(start 155.420314 -306.953666)
		(end 155.420314 -307.210968)
		(width 0.1143)
		(layer "In9.Cu")
		(net "P5E_PEX1_STN7_RX_DP<118>")
	)
	(segment
		(start 161.06902 -388.248398)
		(end 158.323026 -386.009388)
		(width 0.1651)
		(layer "In9.Cu")
		(net "P5E_PEX1_STN7_RX_DP<118>")
	)
	(segment
		(start 140.814552 -316.930786)
		(end 142.892018 -313.821318)
		(width 0.1651)
		(layer "In9.Cu")
		(net "P5E_PEX1_STN7_RX_DP<118>")
	)
	(segment
		(start 171.430188 -393.251436)
		(end 171.402248 -393.110466)
		(width 0.1651)
		(layer "In9.Cu")
		(net "P5E_PEX1_STN7_RX_DP<118>")
	)
	(segment
		(start 139.630658 -322.876672)
		(end 139.506452 -322.414646)
		(width 0.1651)
		(layer "In9.Cu")
		(net "P5E_PEX1_STN7_RX_DP<118>")
	)
	(segment
		(start 144.770094 -311.593484)
		(end 149.129242 -307.234336)
		(width 0.1651)
		(layer "In9.Cu")
		(net "P5E_PEX1_STN7_RX_DP<118>")
	)
	(segment
		(start 173.552866 -394.547852)
		(end 172.975778 -394.16228)
		(width 0.1651)
		(layer "In9.Cu")
		(net "P5E_PEX1_STN7_RX_DP<118>")
	)
	(segment
		(start 142.342108 -327.264522)
		(end 142.342362 -327.264522)
		(width 0.1651)
		(layer "In9.Cu")
		(net "P5E_PEX1_STN7_RX_DP<118>")
	)
	(segment
		(start 142.892018 -313.821318)
		(end 144.770094 -311.593484)
		(width 0.1651)
		(layer "In9.Cu")
		(net "P5E_PEX1_STN7_RX_DP<118>")
	)
	(segment
		(start 171.842176 -393.526772)
		(end 171.430188 -393.251436)
		(width 0.1651)
		(layer "In9.Cu")
		(net "P5E_PEX1_STN7_RX_DP<118>")
	)
	(segment
		(start 173.10989 -408.572208)
		(end 173.23689 -408.699208)
		(width 0.1651)
		(layer "In9.Cu")
		(net "P5E_PEX1_STN7_RX_DP<118>")
	)
	(segment
		(start 190.461392 -351.316798)
		(end 190.461392 -350.685354)
		(width 0.13462)
		(layer "F.Cu")
		(net "P5E_PEX1_STN7_TX_C_DP<126>")
	)
	(segment
		(start 190.461392 -350.685354)
		(end 190.141352 -350.365314)
		(width 0.13462)
		(layer "F.Cu")
		(net "P5E_PEX1_STN7_TX_C_DP<126>")
	)
	(segment
		(start 190.166752 -351.611438)
		(end 190.461392 -351.316798)
		(width 0.13462)
		(layer "F.Cu")
		(net "P5E_PEX1_STN7_TX_C_DP<126>")
	)
	(segment
		(start 173.458378 -374.899174)
		(end 173.985428 -374.372124)
		(width 0.1651)
		(layer "In11.Cu")
		(net "P5E_PEX1_STN7_TX_C_DP<126>")
	)
	(segment
		(start 186.12866 -361.971082)
		(end 186.478672 -361.62107)
		(width 0.1651)
		(layer "In11.Cu")
		(net "P5E_PEX1_STN7_TX_C_DP<126>")
	)
	(segment
		(start 188.203332 -359.89641)
		(end 188.203332 -359.734612)
		(width 0.1651)
		(layer "In11.Cu")
		(net "P5E_PEX1_STN7_TX_C_DP<126>")
	)
	(segment
		(start 189.57798 -358.521762)
		(end 190.457582 -357.64216)
		(width 0.1651)
		(layer "In11.Cu")
		(net "P5E_PEX1_STN7_TX_C_DP<126>")
	)
	(segment
		(start 188.553852 -359.384092)
		(end 188.71565 -359.384092)
		(width 0.1651)
		(layer "In11.Cu")
		(net "P5E_PEX1_STN7_TX_C_DP<126>")
	)
	(segment
		(start 190.457582 -351.902268)
		(end 190.166752 -351.611438)
		(width 0.1651)
		(layer "In11.Cu")
		(net "P5E_PEX1_STN7_TX_C_DP<126>")
	)
	(segment
		(start 189.416182 -358.521762)
		(end 189.57798 -358.521762)
		(width 0.1651)
		(layer "In11.Cu")
		(net "P5E_PEX1_STN7_TX_C_DP<126>")
	)
	(segment
		(start 186.99099 -361.108752)
		(end 187.341002 -360.75874)
		(width 0.1651)
		(layer "In11.Cu")
		(net "P5E_PEX1_STN7_TX_C_DP<126>")
	)
	(segment
		(start 173.10989 -374.390158)
		(end 173.10989 -374.772174)
		(width 0.1651)
		(layer "In11.Cu")
		(net "P5E_PEX1_STN7_TX_C_DP<126>")
	)
	(segment
		(start 187.85332 -360.246422)
		(end 188.203332 -359.89641)
		(width 0.1651)
		(layer "In11.Cu")
		(net "P5E_PEX1_STN7_TX_C_DP<126>")
	)
	(segment
		(start 190.457582 -357.64216)
		(end 190.457582 -351.902268)
		(width 0.1651)
		(layer "In11.Cu")
		(net "P5E_PEX1_STN7_TX_C_DP<126>")
	)
	(segment
		(start 186.829192 -361.108752)
		(end 186.99099 -361.108752)
		(width 0.1651)
		(layer "In11.Cu")
		(net "P5E_PEX1_STN7_TX_C_DP<126>")
	)
	(segment
		(start 186.478672 -361.459272)
		(end 186.829192 -361.108752)
		(width 0.1651)
		(layer "In11.Cu")
		(net "P5E_PEX1_STN7_TX_C_DP<126>")
	)
	(segment
		(start 185.616342 -362.4834)
		(end 185.616342 -362.321602)
		(width 0.1651)
		(layer "In11.Cu")
		(net "P5E_PEX1_STN7_TX_C_DP<126>")
	)
	(segment
		(start 187.341002 -360.75874)
		(end 187.341002 -360.596942)
		(width 0.1651)
		(layer "In11.Cu")
		(net "P5E_PEX1_STN7_TX_C_DP<126>")
	)
	(segment
		(start 173.23689 -374.899174)
		(end 173.458378 -374.899174)
		(width 0.1651)
		(layer "In11.Cu")
		(net "P5E_PEX1_STN7_TX_C_DP<126>")
	)
	(segment
		(start 184.754012 -363.183932)
		(end 185.104532 -362.833412)
		(width 0.1651)
		(layer "In11.Cu")
		(net "P5E_PEX1_STN7_TX_C_DP<126>")
	)
	(segment
		(start 185.616342 -362.321602)
		(end 185.966862 -361.971082)
		(width 0.1651)
		(layer "In11.Cu")
		(net "P5E_PEX1_STN7_TX_C_DP<126>")
	)
	(segment
		(start 187.341002 -360.596942)
		(end 187.691522 -360.246422)
		(width 0.1651)
		(layer "In11.Cu")
		(net "P5E_PEX1_STN7_TX_C_DP<126>")
	)
	(segment
		(start 173.10989 -374.772174)
		(end 173.23689 -374.899174)
		(width 0.1651)
		(layer "In11.Cu")
		(net "P5E_PEX1_STN7_TX_C_DP<126>")
	)
	(segment
		(start 185.966862 -361.971082)
		(end 186.12866 -361.971082)
		(width 0.1651)
		(layer "In11.Cu")
		(net "P5E_PEX1_STN7_TX_C_DP<126>")
	)
	(segment
		(start 173.985428 -368.822224)
		(end 174.793148 -368.014504)
		(width 0.1651)
		(layer "In11.Cu")
		(net "P5E_PEX1_STN7_TX_C_DP<126>")
	)
	(segment
		(start 184.754012 -363.34573)
		(end 184.754012 -363.183932)
		(width 0.1651)
		(layer "In11.Cu")
		(net "P5E_PEX1_STN7_TX_C_DP<126>")
	)
	(segment
		(start 185.104532 -362.833412)
		(end 185.26633 -362.833412)
		(width 0.1651)
		(layer "In11.Cu")
		(net "P5E_PEX1_STN7_TX_C_DP<126>")
	)
	(segment
		(start 188.203332 -359.734612)
		(end 188.553852 -359.384092)
		(width 0.1651)
		(layer "In11.Cu")
		(net "P5E_PEX1_STN7_TX_C_DP<126>")
	)
	(segment
		(start 186.478672 -361.62107)
		(end 186.478672 -361.459272)
		(width 0.1651)
		(layer "In11.Cu")
		(net "P5E_PEX1_STN7_TX_C_DP<126>")
	)
	(segment
		(start 185.26633 -362.833412)
		(end 185.616342 -362.4834)
		(width 0.1651)
		(layer "In11.Cu")
		(net "P5E_PEX1_STN7_TX_C_DP<126>")
	)
	(segment
		(start 188.71565 -359.384092)
		(end 189.065662 -359.03408)
		(width 0.1651)
		(layer "In11.Cu")
		(net "P5E_PEX1_STN7_TX_C_DP<126>")
	)
	(segment
		(start 189.065662 -358.872282)
		(end 189.416182 -358.521762)
		(width 0.1651)
		(layer "In11.Cu")
		(net "P5E_PEX1_STN7_TX_C_DP<126>")
	)
	(segment
		(start 173.985428 -374.372124)
		(end 173.985428 -368.822224)
		(width 0.1651)
		(layer "In11.Cu")
		(net "P5E_PEX1_STN7_TX_C_DP<126>")
	)
	(segment
		(start 174.793148 -368.014504)
		(end 183.914288 -364.185454)
		(width 0.1651)
		(layer "In11.Cu")
		(net "P5E_PEX1_STN7_TX_C_DP<126>")
	)
	(segment
		(start 189.065662 -359.03408)
		(end 189.065662 -358.872282)
		(width 0.1651)
		(layer "In11.Cu")
		(net "P5E_PEX1_STN7_TX_C_DP<126>")
	)
	(segment
		(start 183.914288 -364.185454)
		(end 184.754012 -363.34573)
		(width 0.1651)
		(layer "In11.Cu")
		(net "P5E_PEX1_STN7_TX_C_DP<126>")
	)
	(segment
		(start 187.691522 -360.246422)
		(end 187.85332 -360.246422)
		(width 0.1651)
		(layer "In11.Cu")
		(net "P5E_PEX1_STN7_TX_C_DP<126>")
	)
	(segment
		(start 154.793696 -106.808778)
		(end 154.162252 -106.808778)
		(width 0.13462)
		(layer "F.Cu")
		(net "P5E_PEX1_STN1_TX_DP<20>")
	)
	(segment
		(start 154.162252 -106.808778)
		(end 153.867612 -106.514138)
		(width 0.13462)
		(layer "F.Cu")
		(net "P5E_PEX1_STN1_TX_DP<20>")
	)
	(segment
		(start 155.113736 -106.488738)
		(end 154.793696 -106.808778)
		(width 0.13462)
		(layer "F.Cu")
		(net "P5E_PEX1_STN1_TX_DP<20>")
	)
	(segment
		(start 140.17625 -138.253978)
		(end 142.758668 -144.488662)
		(width 0.1651)
		(layer "In9.Cu")
		(net "P5E_PEX1_STN1_TX_DP<20>")
	)
	(segment
		(start 144.344898 -117.428518)
		(end 140.17625 -131.172458)
		(width 0.1651)
		(layer "In9.Cu")
		(net "P5E_PEX1_STN1_TX_DP<20>")
	)
	(segment
		(start 140.17625 -131.172458)
		(end 140.17625 -138.253978)
		(width 0.1651)
		(layer "In9.Cu")
		(net "P5E_PEX1_STN1_TX_DP<20>")
	)
	(segment
		(start 178.97983 -271.546066)
		(end 178.97983 -278.205184)
		(width 0.1143)
		(layer "In9.Cu")
		(net "P5E_PEX1_STN1_TX_DP<20>")
	)
	(segment
		(start 144.05102 -162.077146)
		(end 178.93411 -265.13282)
		(width 0.1651)
		(layer "In9.Cu")
		(net "P5E_PEX1_STN1_TX_DP<20>")
	)
	(segment
		(start 151.66467 -106.804968)
		(end 149.522688 -107.69219)
		(width 0.1651)
		(layer "In9.Cu")
		(net "P5E_PEX1_STN1_TX_DP<20>")
	)
	(segment
		(start 179.194714 -278.420068)
		(end 179.435506 -278.420068)
		(width 0.1143)
		(layer "In9.Cu")
		(net "P5E_PEX1_STN1_TX_DP<20>")
	)
	(segment
		(start 142.758668 -144.488662)
		(end 143.483076 -159.221678)
		(width 0.1651)
		(layer "In9.Cu")
		(net "P5E_PEX1_STN1_TX_DP<20>")
	)
	(segment
		(start 178.93411 -271.500346)
		(end 178.97983 -271.546066)
		(width 0.1143)
		(layer "In9.Cu")
		(net "P5E_PEX1_STN1_TX_DP<20>")
	)
	(segment
		(start 153.867612 -106.514138)
		(end 153.576782 -106.804968)
		(width 0.1651)
		(layer "In9.Cu")
		(net "P5E_PEX1_STN1_TX_DP<20>")
	)
	(segment
		(start 178.93411 -271.471898)
		(end 178.93411 -271.500346)
		(width 0.1143)
		(layer "In9.Cu")
		(net "P5E_PEX1_STN1_TX_DP<20>")
	)
	(segment
		(start 179.435506 -278.420068)
		(end 179.549806 -278.534368)
		(width 0.1143)
		(layer "In9.Cu")
		(net "P5E_PEX1_STN1_TX_DP<20>")
	)
	(segment
		(start 143.483076 -159.221678)
		(end 144.05102 -162.077146)
		(width 0.1651)
		(layer "In9.Cu")
		(net "P5E_PEX1_STN1_TX_DP<20>")
	)
	(segment
		(start 178.93411 -265.13282)
		(end 178.93411 -271.471898)
		(width 0.1651)
		(layer "In9.Cu")
		(net "P5E_PEX1_STN1_TX_DP<20>")
	)
	(segment
		(start 153.576782 -106.804968)
		(end 151.66467 -106.804968)
		(width 0.1651)
		(layer "In9.Cu")
		(net "P5E_PEX1_STN1_TX_DP<20>")
	)
	(segment
		(start 147.568158 -109.64672)
		(end 144.344898 -117.428518)
		(width 0.1651)
		(layer "In9.Cu")
		(net "P5E_PEX1_STN1_TX_DP<20>")
	)
	(segment
		(start 178.97983 -278.205184)
		(end 179.194714 -278.420068)
		(width 0.1143)
		(layer "In9.Cu")
		(net "P5E_PEX1_STN1_TX_DP<20>")
	)
	(segment
		(start 149.522688 -107.69219)
		(end 147.568158 -109.64672)
		(width 0.1651)
		(layer "In9.Cu")
		(net "P5E_PEX1_STN1_TX_DP<20>")
	)
	(segment
		(start 179.549806 -278.534368)
		(end 179.549806 -278.799798)
		(width 0.1143)
		(layer "In9.Cu")
		(net "P5E_PEX1_STN1_TX_DP<20>")
	)
	(segment
		(start 112.431068 -343.365582)
		(end 112.431068 -342.734138)
		(width 0.13462)
		(layer "F.Cu")
		(net "P5E_PEX1_STN6_TX_DN<111>")
	)
	(segment
		(start 112.431068 -342.734138)
		(end 112.725708 -342.439498)
		(width 0.13462)
		(layer "F.Cu")
		(net "P5E_PEX1_STN6_TX_DN<111>")
	)
	(segment
		(start 112.751108 -343.685622)
		(end 112.431068 -343.365582)
		(width 0.13462)
		(layer "F.Cu")
		(net "P5E_PEX1_STN6_TX_DN<111>")
	)
	(segment
		(start 159.323786 -311.670192)
		(end 159.220154 -311.773824)
		(width 0.1143)
		(layer "In13.Cu")
		(net "P5E_PEX1_STN6_TX_DN<111>")
	)
	(segment
		(start 159.220154 -311.773824)
		(end 159.220154 -319.995296)
		(width 0.1143)
		(layer "In13.Cu")
		(net "P5E_PEX1_STN6_TX_DN<111>")
	)
	(segment
		(start 127.268732 -332.420214)
		(end 113.60912 -339.722206)
		(width 0.1651)
		(layer "In13.Cu")
		(net "P5E_PEX1_STN6_TX_DN<111>")
	)
	(segment
		(start 112.434878 -341.132668)
		(end 112.434878 -342.148668)
		(width 0.1651)
		(layer "In13.Cu")
		(net "P5E_PEX1_STN6_TX_DN<111>")
	)
	(segment
		(start 159.265874 -320.041016)
		(end 159.265874 -320.063114)
		(width 0.1143)
		(layer "In13.Cu")
		(net "P5E_PEX1_STN6_TX_DN<111>")
	)
	(segment
		(start 159.220154 -319.995296)
		(end 159.265874 -320.041016)
		(width 0.1143)
		(layer "In13.Cu")
		(net "P5E_PEX1_STN6_TX_DN<111>")
	)
	(segment
		(start 159.265874 -320.231008)
		(end 158.099252 -321.39763)
		(width 0.1651)
		(layer "In13.Cu")
		(net "P5E_PEX1_STN6_TX_DN<111>")
	)
	(segment
		(start 113.60912 -339.722206)
		(end 113.226342 -340.086188)
		(width 0.1651)
		(layer "In13.Cu")
		(net "P5E_PEX1_STN6_TX_DN<111>")
	)
	(segment
		(start 145.842736 -326.625966)
		(end 141.25702 -326.625966)
		(width 0.1651)
		(layer "In13.Cu")
		(net "P5E_PEX1_STN6_TX_DN<111>")
	)
	(segment
		(start 159.599884 -312.049922)
		(end 159.599884 -311.784492)
		(width 0.1143)
		(layer "In13.Cu")
		(net "P5E_PEX1_STN6_TX_DN<111>")
	)
	(segment
		(start 141.25702 -326.625966)
		(end 127.268732 -332.420214)
		(width 0.1651)
		(layer "In13.Cu")
		(net "P5E_PEX1_STN6_TX_DN<111>")
	)
	(segment
		(start 112.844072 -340.450424)
		(end 112.434878 -341.132668)
		(width 0.1651)
		(layer "In13.Cu")
		(net "P5E_PEX1_STN6_TX_DN<111>")
	)
	(segment
		(start 112.434878 -342.148668)
		(end 112.725708 -342.439498)
		(width 0.1651)
		(layer "In13.Cu")
		(net "P5E_PEX1_STN6_TX_DN<111>")
	)
	(segment
		(start 147.34159 -326.328532)
		(end 145.842736 -326.625966)
		(width 0.1651)
		(layer "In13.Cu")
		(net "P5E_PEX1_STN6_TX_DN<111>")
	)
	(segment
		(start 158.099252 -321.39763)
		(end 155.536392 -322.934076)
		(width 0.1651)
		(layer "In13.Cu")
		(net "P5E_PEX1_STN6_TX_DN<111>")
	)
	(segment
		(start 113.226342 -340.086188)
		(end 113.226342 -340.086442)
		(width 0.1651)
		(layer "In13.Cu")
		(net "P5E_PEX1_STN6_TX_DN<111>")
	)
	(segment
		(start 159.265874 -320.063114)
		(end 159.265874 -320.231008)
		(width 0.1651)
		(layer "In13.Cu")
		(net "P5E_PEX1_STN6_TX_DN<111>")
	)
	(segment
		(start 159.599884 -311.784492)
		(end 159.485584 -311.670192)
		(width 0.1143)
		(layer "In13.Cu")
		(net "P5E_PEX1_STN6_TX_DN<111>")
	)
	(segment
		(start 159.485584 -311.670192)
		(end 159.323786 -311.670192)
		(width 0.1143)
		(layer "In13.Cu")
		(net "P5E_PEX1_STN6_TX_DN<111>")
	)
	(segment
		(start 113.226342 -340.086442)
		(end 112.844072 -340.450424)
		(width 0.1651)
		(layer "In13.Cu")
		(net "P5E_PEX1_STN6_TX_DN<111>")
	)
	(segment
		(start 155.536392 -322.934076)
		(end 147.34159 -326.328532)
		(width 0.1651)
		(layer "In13.Cu")
		(net "P5E_PEX1_STN6_TX_DN<111>")
	)
	(segment
		(start 160.076388 -389.934196)
		(end 156.75864 -387.228588)
		(width 0.1651)
		(layer "In9.Cu")
		(net "P5E_PEX1_STN7_RX_DP<116>")
	)
	(segment
		(start 168.837102 -408.699208)
		(end 169.05859 -408.699208)
		(width 0.1651)
		(layer "In9.Cu")
		(net "P5E_PEX1_STN7_RX_DP<116>")
	)
	(segment
		(start 156.75864 -387.228588)
		(end 155.315158 -384.608324)
		(width 0.1651)
		(layer "In9.Cu")
		(net "P5E_PEX1_STN7_RX_DP<116>")
	)
	(segment
		(start 137.591292 -322.703952)
		(end 137.591292 -319.295526)
		(width 0.1651)
		(layer "In9.Cu")
		(net "P5E_PEX1_STN7_RX_DP<116>")
	)
	(segment
		(start 169.085006 -394.360908)
		(end 168.639236 -394.062966)
		(width 0.1651)
		(layer "In9.Cu")
		(net "P5E_PEX1_STN7_RX_DP<116>")
	)
	(segment
		(start 168.058338 -393.6746)
		(end 168.058338 -393.674854)
		(width 0.1651)
		(layer "In9.Cu")
		(net "P5E_PEX1_STN7_RX_DP<116>")
	)
	(segment
		(start 148.608796 -341.048848)
		(end 137.837418 -323.620638)
		(width 0.1651)
		(layer "In9.Cu")
		(net "P5E_PEX1_STN7_RX_DP<116>")
	)
	(segment
		(start 155.315158 -384.608324)
		(end 149.931882 -344.74404)
		(width 0.1651)
		(layer "In9.Cu")
		(net "P5E_PEX1_STN7_RX_DP<116>")
	)
	(segment
		(start 155.509214 -305.399948)
		(end 155.800044 -305.399948)
		(width 0.1143)
		(layer "In9.Cu")
		(net "P5E_PEX1_STN7_RX_DP<116>")
	)
	(segment
		(start 145.730214 -305.85664)
		(end 149.165818 -304.783998)
		(width 0.1651)
		(layer "In9.Cu")
		(net "P5E_PEX1_STN7_RX_DP<116>")
	)
	(segment
		(start 155.420314 -305.053746)
		(end 155.420314 -305.311048)
		(width 0.1143)
		(layer "In9.Cu")
		(net "P5E_PEX1_STN7_RX_DP<116>")
	)
	(segment
		(start 137.837418 -323.620638)
		(end 137.591292 -322.703952)
		(width 0.1651)
		(layer "In9.Cu")
		(net "P5E_PEX1_STN7_RX_DP<116>")
	)
	(segment
		(start 166.35603 -392.537188)
		(end 160.076388 -389.934196)
		(width 0.1651)
		(layer "In9.Cu")
		(net "P5E_PEX1_STN7_RX_DP<116>")
	)
	(segment
		(start 169.592498 -408.1653)
		(end 169.592498 -394.8684)
		(width 0.1651)
		(layer "In9.Cu")
		(net "P5E_PEX1_STN7_RX_DP<116>")
	)
	(segment
		(start 137.591292 -319.295526)
		(end 141.816582 -309.770526)
		(width 0.1651)
		(layer "In9.Cu")
		(net "P5E_PEX1_STN7_RX_DP<116>")
	)
	(segment
		(start 155.420314 -305.311048)
		(end 155.509214 -305.399948)
		(width 0.1143)
		(layer "In9.Cu")
		(net "P5E_PEX1_STN7_RX_DP<116>")
	)
	(segment
		(start 168.058338 -393.674854)
		(end 166.35603 -392.537188)
		(width 0.1651)
		(layer "In9.Cu")
		(net "P5E_PEX1_STN7_RX_DP<116>")
	)
	(segment
		(start 149.931882 -344.74404)
		(end 148.608796 -341.048848)
		(width 0.1651)
		(layer "In9.Cu")
		(net "P5E_PEX1_STN7_RX_DP<116>")
	)
	(segment
		(start 169.05859 -408.699208)
		(end 169.592498 -408.1653)
		(width 0.1651)
		(layer "In9.Cu")
		(net "P5E_PEX1_STN7_RX_DP<116>")
	)
	(segment
		(start 151.793448 -304.783998)
		(end 151.839168 -304.829718)
		(width 0.1143)
		(layer "In9.Cu")
		(net "P5E_PEX1_STN7_RX_DP<116>")
	)
	(segment
		(start 155.196286 -304.829718)
		(end 155.420314 -305.053746)
		(width 0.1143)
		(layer "In9.Cu")
		(net "P5E_PEX1_STN7_RX_DP<116>")
	)
	(segment
		(start 168.710102 -408.190192)
		(end 168.710102 -408.572208)
		(width 0.1651)
		(layer "In9.Cu")
		(net "P5E_PEX1_STN7_RX_DP<116>")
	)
	(segment
		(start 151.765 -304.783998)
		(end 151.793448 -304.783998)
		(width 0.1143)
		(layer "In9.Cu")
		(net "P5E_PEX1_STN7_RX_DP<116>")
	)
	(segment
		(start 168.639236 -394.062966)
		(end 168.498266 -394.09116)
		(width 0.1651)
		(layer "In9.Cu")
		(net "P5E_PEX1_STN7_RX_DP<116>")
	)
	(segment
		(start 169.592498 -394.8684)
		(end 169.085006 -394.360908)
		(width 0.1651)
		(layer "In9.Cu")
		(net "P5E_PEX1_STN7_RX_DP<116>")
	)
	(segment
		(start 149.165818 -304.783998)
		(end 151.765 -304.783998)
		(width 0.1651)
		(layer "In9.Cu")
		(net "P5E_PEX1_STN7_RX_DP<116>")
	)
	(segment
		(start 168.086278 -393.81557)
		(end 168.058338 -393.6746)
		(width 0.1651)
		(layer "In9.Cu")
		(net "P5E_PEX1_STN7_RX_DP<116>")
	)
	(segment
		(start 168.710102 -408.572208)
		(end 168.837102 -408.699208)
		(width 0.1651)
		(layer "In9.Cu")
		(net "P5E_PEX1_STN7_RX_DP<116>")
	)
	(segment
		(start 168.498266 -394.09116)
		(end 168.086278 -393.81557)
		(width 0.1651)
		(layer "In9.Cu")
		(net "P5E_PEX1_STN7_RX_DP<116>")
	)
	(segment
		(start 141.816582 -309.770526)
		(end 145.730214 -305.85664)
		(width 0.1651)
		(layer "In9.Cu")
		(net "P5E_PEX1_STN7_RX_DP<116>")
	)
	(segment
		(start 151.839168 -304.829718)
		(end 155.196286 -304.829718)
		(width 0.1143)
		(layer "In9.Cu")
		(net "P5E_PEX1_STN7_RX_DP<116>")
	)
	(segment
		(start 347.62567 -367.093754)
		(end 347.60916 -366.598708)
		(width 0.1651)
		(layer "In5.Cu")
		(net "P5E_PEX2_STN5_RX_DP<95>")
	)
	(segment
		(start 347.695012 -366.50676)
		(end 347.678756 -366.011968)
		(width 0.1651)
		(layer "In5.Cu")
		(net "P5E_PEX2_STN5_RX_DP<95>")
	)
	(segment
		(start 347.734128 -371.812312)
		(end 347.734128 -367.674652)
		(width 0.1651)
		(layer "In5.Cu")
		(net "P5E_PEX2_STN5_RX_DP<95>")
	)
	(segment
		(start 347.678756 -366.011968)
		(end 347.586554 -365.925862)
		(width 0.1651)
		(layer "In5.Cu")
		(net "P5E_PEX2_STN5_RX_DP<95>")
	)
	(segment
		(start 305.149758 -318.015366)
		(end 305.149758 -317.749936)
		(width 0.1143)
		(layer "In5.Cu")
		(net "P5E_PEX2_STN5_RX_DP<95>")
	)
	(segment
		(start 347.655896 -365.338868)
		(end 347.63964 -364.844076)
		(width 0.1651)
		(layer "In5.Cu")
		(net "P5E_PEX2_STN5_RX_DP<95>")
	)
	(segment
		(start 347.54185 -361.906566)
		(end 347.756226 -341.457534)
		(width 0.1651)
		(layer "In5.Cu")
		(net "P5E_PEX2_STN5_RX_DP<95>")
	)
	(segment
		(start 347.756226 -341.457534)
		(end 347.43009 -340.669626)
		(width 0.1651)
		(layer "In5.Cu")
		(net "P5E_PEX2_STN5_RX_DP<95>")
	)
	(segment
		(start 304.805334 -318.129666)
		(end 305.035458 -318.129666)
		(width 0.1143)
		(layer "In5.Cu")
		(net "P5E_PEX2_STN5_RX_DP<95>")
	)
	(segment
		(start 344.650822 -338.690966)
		(end 304.79619 -320.34099)
		(width 0.1651)
		(layer "In5.Cu")
		(net "P5E_PEX2_STN5_RX_DP<95>")
	)
	(segment
		(start 347.547438 -364.75797)
		(end 347.531182 -364.26267)
		(width 0.1651)
		(layer "In5.Cu")
		(net "P5E_PEX2_STN5_RX_DP<95>")
	)
	(segment
		(start 346.890086 -371.972078)
		(end 347.017086 -372.099078)
		(width 0.1651)
		(layer "In5.Cu")
		(net "P5E_PEX2_STN5_RX_DP<95>")
	)
	(segment
		(start 345.853004 -339.244432)
		(end 345.308682 -338.993988)
		(width 0.1651)
		(layer "In5.Cu")
		(net "P5E_PEX2_STN5_RX_DP<95>")
	)
	(segment
		(start 304.533808 -319.916048)
		(end 304.533808 -319.8876)
		(width 0.1143)
		(layer "In5.Cu")
		(net "P5E_PEX2_STN5_RX_DP<95>")
	)
	(segment
		(start 347.617034 -364.170976)
		(end 347.54185 -361.906566)
		(width 0.1651)
		(layer "In5.Cu")
		(net "P5E_PEX2_STN5_RX_DP<95>")
	)
	(segment
		(start 304.579528 -319.84188)
		(end 304.579528 -318.355472)
		(width 0.1143)
		(layer "In5.Cu")
		(net "P5E_PEX2_STN5_RX_DP<95>")
	)
	(segment
		(start 304.79619 -320.34099)
		(end 304.533808 -320.078608)
		(width 0.1651)
		(layer "In5.Cu")
		(net "P5E_PEX2_STN5_RX_DP<95>")
	)
	(segment
		(start 304.533808 -320.078608)
		(end 304.533808 -319.916048)
		(width 0.1651)
		(layer "In5.Cu")
		(net "P5E_PEX2_STN5_RX_DP<95>")
	)
	(segment
		(start 347.447362 -372.099078)
		(end 347.734128 -371.812312)
		(width 0.1651)
		(layer "In5.Cu")
		(net "P5E_PEX2_STN5_RX_DP<95>")
	)
	(segment
		(start 347.734128 -367.674652)
		(end 347.717872 -367.17986)
		(width 0.1651)
		(layer "In5.Cu")
		(net "P5E_PEX2_STN5_RX_DP<95>")
	)
	(segment
		(start 347.43009 -340.669626)
		(end 345.853004 -339.244432)
		(width 0.1651)
		(layer "In5.Cu")
		(net "P5E_PEX2_STN5_RX_DP<95>")
	)
	(segment
		(start 347.63964 -364.844076)
		(end 347.547438 -364.75797)
		(width 0.1651)
		(layer "In5.Cu")
		(net "P5E_PEX2_STN5_RX_DP<95>")
	)
	(segment
		(start 345.157044 -339.049868)
		(end 344.706956 -338.842858)
		(width 0.1651)
		(layer "In5.Cu")
		(net "P5E_PEX2_STN5_RX_DP<95>")
	)
	(segment
		(start 304.533808 -319.8876)
		(end 304.579528 -319.84188)
		(width 0.1143)
		(layer "In5.Cu")
		(net "P5E_PEX2_STN5_RX_DP<95>")
	)
	(segment
		(start 347.570044 -365.430816)
		(end 347.655896 -365.338868)
		(width 0.1651)
		(layer "In5.Cu")
		(net "P5E_PEX2_STN5_RX_DP<95>")
	)
	(segment
		(start 347.531182 -364.26267)
		(end 347.617034 -364.170976)
		(width 0.1651)
		(layer "In5.Cu")
		(net "P5E_PEX2_STN5_RX_DP<95>")
	)
	(segment
		(start 346.890086 -371.590062)
		(end 346.890086 -371.972078)
		(width 0.1651)
		(layer "In5.Cu")
		(net "P5E_PEX2_STN5_RX_DP<95>")
	)
	(segment
		(start 345.308682 -338.993988)
		(end 345.157044 -339.049868)
		(width 0.1651)
		(layer "In5.Cu")
		(net "P5E_PEX2_STN5_RX_DP<95>")
	)
	(segment
		(start 347.586554 -365.925862)
		(end 347.570044 -365.430816)
		(width 0.1651)
		(layer "In5.Cu")
		(net "P5E_PEX2_STN5_RX_DP<95>")
	)
	(segment
		(start 304.579528 -318.355472)
		(end 304.805334 -318.129666)
		(width 0.1143)
		(layer "In5.Cu")
		(net "P5E_PEX2_STN5_RX_DP<95>")
	)
	(segment
		(start 347.60916 -366.598708)
		(end 347.695012 -366.50676)
		(width 0.1651)
		(layer "In5.Cu")
		(net "P5E_PEX2_STN5_RX_DP<95>")
	)
	(segment
		(start 347.717872 -367.17986)
		(end 347.62567 -367.093754)
		(width 0.1651)
		(layer "In5.Cu")
		(net "P5E_PEX2_STN5_RX_DP<95>")
	)
	(segment
		(start 305.035458 -318.129666)
		(end 305.149758 -318.015366)
		(width 0.1143)
		(layer "In5.Cu")
		(net "P5E_PEX2_STN5_RX_DP<95>")
	)
	(segment
		(start 344.706956 -338.842858)
		(end 344.650822 -338.690966)
		(width 0.1651)
		(layer "In5.Cu")
		(net "P5E_PEX2_STN5_RX_DP<95>")
	)
	(segment
		(start 347.017086 -372.099078)
		(end 347.447362 -372.099078)
		(width 0.1651)
		(layer "In5.Cu")
		(net "P5E_PEX2_STN5_RX_DP<95>")
	)
	(segment
		(start 143.520668 -356.831646)
		(end 143.840708 -356.511606)
		(width 0.13462)
		(layer "F.Cu")
		(net "P5E_PEX1_STN5_TX_C_DN<95>")
	)
	(segment
		(start 143.520668 -357.46309)
		(end 143.520668 -356.831646)
		(width 0.13462)
		(layer "F.Cu")
		(net "P5E_PEX1_STN5_TX_C_DN<95>")
	)
	(segment
		(start 143.815308 -357.75773)
		(end 143.520668 -357.46309)
		(width 0.13462)
		(layer "F.Cu")
		(net "P5E_PEX1_STN5_TX_C_DN<95>")
	)
	(segment
		(start 143.04518 -359.619296)
		(end 143.524478 -358.624886)
		(width 0.1651)
		(layer "In13.Cu")
		(net "P5E_PEX1_STN5_TX_C_DN<95>")
	)
	(segment
		(start 131.437126 -380.181104)
		(end 131.775454 -380.181104)
		(width 0.1651)
		(layer "In13.Cu")
		(net "P5E_PEX1_STN5_TX_C_DN<95>")
	)
	(segment
		(start 131.310126 -380.69012)
		(end 131.310126 -380.308104)
		(width 0.1651)
		(layer "In13.Cu")
		(net "P5E_PEX1_STN5_TX_C_DN<95>")
	)
	(segment
		(start 132.466842 -369.024154)
		(end 133.23189 -367.437162)
		(width 0.1651)
		(layer "In13.Cu")
		(net "P5E_PEX1_STN5_TX_C_DN<95>")
	)
	(segment
		(start 143.524478 -358.04856)
		(end 143.815308 -357.75773)
		(width 0.1651)
		(layer "In13.Cu")
		(net "P5E_PEX1_STN5_TX_C_DN<95>")
	)
	(segment
		(start 131.775454 -380.181104)
		(end 132.466842 -379.489716)
		(width 0.1651)
		(layer "In13.Cu")
		(net "P5E_PEX1_STN5_TX_C_DN<95>")
	)
	(segment
		(start 131.310126 -380.308104)
		(end 131.437126 -380.181104)
		(width 0.1651)
		(layer "In13.Cu")
		(net "P5E_PEX1_STN5_TX_C_DN<95>")
	)
	(segment
		(start 143.524478 -358.624886)
		(end 143.524478 -358.04856)
		(width 0.1651)
		(layer "In13.Cu")
		(net "P5E_PEX1_STN5_TX_C_DN<95>")
	)
	(segment
		(start 132.466842 -379.489716)
		(end 132.466842 -369.024154)
		(width 0.1651)
		(layer "In13.Cu")
		(net "P5E_PEX1_STN5_TX_C_DN<95>")
	)
	(segment
		(start 133.23189 -367.437162)
		(end 143.04518 -359.619296)
		(width 0.1651)
		(layer "In13.Cu")
		(net "P5E_PEX1_STN5_TX_C_DN<95>")
	)
	(segment
		(start 41.664128 -355.026722)
		(end 41.958768 -354.732082)
		(width 0.13462)
		(layer "F.Cu")
		(net "P5E_PEX0_STN7_TX_DN<123>")
	)
	(segment
		(start 41.664128 -355.658166)
		(end 41.664128 -355.026722)
		(width 0.13462)
		(layer "F.Cu")
		(net "P5E_PEX0_STN7_TX_DN<123>")
	)
	(segment
		(start 41.984168 -355.978206)
		(end 41.664128 -355.658166)
		(width 0.13462)
		(layer "F.Cu")
		(net "P5E_PEX0_STN7_TX_DN<123>")
	)
	(segment
		(start 38.415976 -319.865248)
		(end 38.415976 -319.8368)
		(width 0.1143)
		(layer "In7.Cu")
		(net "P5E_PEX0_STN7_TX_DN<123>")
	)
	(segment
		(start 38.370256 -313.684412)
		(end 38.484556 -313.570112)
		(width 0.1143)
		(layer "In7.Cu")
		(net "P5E_PEX0_STN7_TX_DN<123>")
	)
	(segment
		(start 41.667938 -353.942142)
		(end 43.222418 -352.387662)
		(width 0.1651)
		(layer "In7.Cu")
		(net "P5E_PEX0_STN7_TX_DN<123>")
	)
	(segment
		(start 43.222418 -352.387662)
		(end 43.222418 -340.797134)
		(width 0.1651)
		(layer "In7.Cu")
		(net "P5E_PEX0_STN7_TX_DN<123>")
	)
	(segment
		(start 38.415976 -319.8368)
		(end 38.370256 -319.79108)
		(width 0.1143)
		(layer "In7.Cu")
		(net "P5E_PEX0_STN7_TX_DN<123>")
	)
	(segment
		(start 38.484556 -313.570112)
		(end 38.635686 -313.570112)
		(width 0.1143)
		(layer "In7.Cu")
		(net "P5E_PEX0_STN7_TX_DN<123>")
	)
	(segment
		(start 43.222418 -340.797134)
		(end 38.415976 -324.952614)
		(width 0.1651)
		(layer "In7.Cu")
		(net "P5E_PEX0_STN7_TX_DN<123>")
	)
	(segment
		(start 38.635686 -313.570112)
		(end 38.749986 -313.684412)
		(width 0.1143)
		(layer "In7.Cu")
		(net "P5E_PEX0_STN7_TX_DN<123>")
	)
	(segment
		(start 41.958768 -354.732082)
		(end 41.667938 -354.441252)
		(width 0.1651)
		(layer "In7.Cu")
		(net "P5E_PEX0_STN7_TX_DN<123>")
	)
	(segment
		(start 38.749986 -313.684412)
		(end 38.749986 -313.949842)
		(width 0.1143)
		(layer "In7.Cu")
		(net "P5E_PEX0_STN7_TX_DN<123>")
	)
	(segment
		(start 38.415976 -324.952614)
		(end 38.415976 -319.865248)
		(width 0.1651)
		(layer "In7.Cu")
		(net "P5E_PEX0_STN7_TX_DN<123>")
	)
	(segment
		(start 41.667938 -354.441252)
		(end 41.667938 -353.942142)
		(width 0.1651)
		(layer "In7.Cu")
		(net "P5E_PEX0_STN7_TX_DN<123>")
	)
	(segment
		(start 38.370256 -319.79108)
		(end 38.370256 -313.684412)
		(width 0.1143)
		(layer "In7.Cu")
		(net "P5E_PEX0_STN7_TX_DN<123>")
	)
	(segment
		(start 154.793696 -132.535422)
		(end 154.162252 -132.535422)
		(width 0.13462)
		(layer "F.Cu")
		(net "P5E_PEX1_STN1_TX_DN<29>")
	)
	(segment
		(start 154.162252 -132.535422)
		(end 153.867612 -132.240782)
		(width 0.13462)
		(layer "F.Cu")
		(net "P5E_PEX1_STN1_TX_DN<29>")
	)
	(segment
		(start 155.113736 -132.215382)
		(end 154.793696 -132.535422)
		(width 0.13462)
		(layer "F.Cu")
		(net "P5E_PEX1_STN1_TX_DN<29>")
	)
	(segment
		(start 153.867612 -132.240782)
		(end 153.576782 -132.531612)
		(width 0.1651)
		(layer "In9.Cu")
		(net "P5E_PEX1_STN1_TX_DN<29>")
	)
	(segment
		(start 187.529724 -271.600168)
		(end 187.529724 -280.10485)
		(width 0.1143)
		(layer "In9.Cu")
		(net "P5E_PEX1_STN1_TX_DN<29>")
	)
	(segment
		(start 187.985654 -280.319988)
		(end 188.099954 -280.434288)
		(width 0.1143)
		(layer "In9.Cu")
		(net "P5E_PEX1_STN1_TX_DN<29>")
	)
	(segment
		(start 148.873718 -134.743444)
		(end 148.873718 -135.529828)
		(width 0.1651)
		(layer "In9.Cu")
		(net "P5E_PEX1_STN1_TX_DN<29>")
	)
	(segment
		(start 151.333454 -132.531612)
		(end 150.27021 -132.972048)
		(width 0.1651)
		(layer "In9.Cu")
		(net "P5E_PEX1_STN1_TX_DN<29>")
	)
	(segment
		(start 153.31567 -162.281108)
		(end 187.484004 -263.217406)
		(width 0.1651)
		(layer "In9.Cu")
		(net "P5E_PEX1_STN1_TX_DN<29>")
	)
	(segment
		(start 187.484004 -263.217406)
		(end 187.484004 -271.526)
		(width 0.1651)
		(layer "In9.Cu")
		(net "P5E_PEX1_STN1_TX_DN<29>")
	)
	(segment
		(start 153.576782 -132.531612)
		(end 151.333454 -132.531612)
		(width 0.1651)
		(layer "In9.Cu")
		(net "P5E_PEX1_STN1_TX_DN<29>")
	)
	(segment
		(start 149.138894 -134.103364)
		(end 148.873718 -134.743444)
		(width 0.1651)
		(layer "In9.Cu")
		(net "P5E_PEX1_STN1_TX_DN<29>")
	)
	(segment
		(start 148.873718 -135.529828)
		(end 151.471884 -141.801342)
		(width 0.1651)
		(layer "In9.Cu")
		(net "P5E_PEX1_STN1_TX_DN<29>")
	)
	(segment
		(start 150.27021 -132.972048)
		(end 149.138894 -134.103364)
		(width 0.1651)
		(layer "In9.Cu")
		(net "P5E_PEX1_STN1_TX_DN<29>")
	)
	(segment
		(start 188.099954 -280.434288)
		(end 188.099954 -280.699718)
		(width 0.1143)
		(layer "In9.Cu")
		(net "P5E_PEX1_STN1_TX_DN<29>")
	)
	(segment
		(start 187.484004 -271.554448)
		(end 187.529724 -271.600168)
		(width 0.1143)
		(layer "In9.Cu")
		(net "P5E_PEX1_STN1_TX_DN<29>")
	)
	(segment
		(start 187.744862 -280.319988)
		(end 187.985654 -280.319988)
		(width 0.1143)
		(layer "In9.Cu")
		(net "P5E_PEX1_STN1_TX_DN<29>")
	)
	(segment
		(start 151.471884 -141.801342)
		(end 152.204674 -156.69641)
		(width 0.1651)
		(layer "In9.Cu")
		(net "P5E_PEX1_STN1_TX_DN<29>")
	)
	(segment
		(start 187.529724 -280.10485)
		(end 187.744862 -280.319988)
		(width 0.1143)
		(layer "In9.Cu")
		(net "P5E_PEX1_STN1_TX_DN<29>")
	)
	(segment
		(start 152.204674 -156.69641)
		(end 153.31567 -162.281108)
		(width 0.1651)
		(layer "In9.Cu")
		(net "P5E_PEX1_STN1_TX_DN<29>")
	)
	(segment
		(start 187.484004 -271.526)
		(end 187.484004 -271.554448)
		(width 0.1143)
		(layer "In9.Cu")
		(net "P5E_PEX1_STN1_TX_DN<29>")
	)
	(segment
		(start 175.510952 -343.685622)
		(end 175.190912 -343.365582)
		(width 0.13462)
		(layer "F.Cu")
		(net "P5E_PEX1_STN7_TX_DN<118>")
	)
	(segment
		(start 175.190912 -343.365582)
		(end 175.190912 -342.734138)
		(width 0.13462)
		(layer "F.Cu")
		(net "P5E_PEX1_STN7_TX_DN<118>")
	)
	(segment
		(start 175.190912 -342.734138)
		(end 175.485552 -342.439498)
		(width 0.13462)
		(layer "F.Cu")
		(net "P5E_PEX1_STN7_TX_DN<118>")
	)
	(segment
		(start 138.657838 -320.156078)
		(end 138.908536 -318.891666)
		(width 0.1651)
		(layer "In11.Cu")
		(net "P5E_PEX1_STN7_TX_DN<118>")
	)
	(segment
		(start 158.079694 -307.085238)
		(end 158.079694 -307.210968)
		(width 0.1143)
		(layer "In11.Cu")
		(net "P5E_PEX1_STN7_TX_DN<118>")
	)
	(segment
		(start 147.698968 -329.950064)
		(end 147.661376 -329.848972)
		(width 0.1651)
		(layer "In11.Cu")
		(net "P5E_PEX1_STN7_TX_DN<118>")
	)
	(segment
		(start 139.888976 -316.824868)
		(end 139.827254 -316.675516)
		(width 0.1651)
		(layer "In11.Cu")
		(net "P5E_PEX1_STN7_TX_DN<118>")
	)
	(segment
		(start 147.210526 -329.643232)
		(end 147.109434 -329.680824)
		(width 0.1651)
		(layer "In11.Cu")
		(net "P5E_PEX1_STN7_TX_DN<118>")
	)
	(segment
		(start 142.549626 -313.828938)
		(end 142.549626 -313.685174)
		(width 0.1651)
		(layer "In11.Cu")
		(net "P5E_PEX1_STN7_TX_DN<118>")
	)
	(segment
		(start 139.248642 -323.985382)
		(end 138.657838 -322.03644)
		(width 0.1651)
		(layer "In11.Cu")
		(net "P5E_PEX1_STN7_TX_DN<118>")
	)
	(segment
		(start 151.688546 -306.920138)
		(end 157.914594 -306.920138)
		(width 0.1143)
		(layer "In11.Cu")
		(net "P5E_PEX1_STN7_TX_DN<118>")
	)
	(segment
		(start 147.109434 -329.680824)
		(end 146.659092 -329.475338)
		(width 0.1651)
		(layer "In11.Cu")
		(net "P5E_PEX1_STN7_TX_DN<118>")
	)
	(segment
		(start 142.899638 -313.335162)
		(end 143.043402 -313.335162)
		(width 0.1651)
		(layer "In11.Cu")
		(net "P5E_PEX1_STN7_TX_DN<118>")
	)
	(segment
		(start 146.659092 -329.475338)
		(end 146.6215 -329.374246)
		(width 0.1651)
		(layer "In11.Cu")
		(net "P5E_PEX1_STN7_TX_DN<118>")
	)
	(segment
		(start 146.17065 -329.168506)
		(end 146.069812 -329.206098)
		(width 0.1651)
		(layer "In11.Cu")
		(net "P5E_PEX1_STN7_TX_DN<118>")
	)
	(segment
		(start 138.657838 -322.03644)
		(end 138.657838 -320.156078)
		(width 0.1651)
		(layer "In11.Cu")
		(net "P5E_PEX1_STN7_TX_DN<118>")
	)
	(segment
		(start 144.568926 -311.892696)
		(end 144.727422 -311.924192)
		(width 0.1651)
		(layer "In11.Cu")
		(net "P5E_PEX1_STN7_TX_DN<118>")
	)
	(segment
		(start 149.892258 -306.965858)
		(end 151.620728 -306.965858)
		(width 0.1651)
		(layer "In11.Cu")
		(net "P5E_PEX1_STN7_TX_DN<118>")
	)
	(segment
		(start 158.079694 -307.210968)
		(end 157.990794 -307.299868)
		(width 0.1143)
		(layer "In11.Cu")
		(net "P5E_PEX1_STN7_TX_DN<118>")
	)
	(segment
		(start 157.914594 -306.920138)
		(end 158.079694 -307.085238)
		(width 0.1143)
		(layer "In11.Cu")
		(net "P5E_PEX1_STN7_TX_DN<118>")
	)
	(segment
		(start 140.861034 -315.51753)
		(end 140.861034 -315.373766)
		(width 0.1651)
		(layer "In11.Cu")
		(net "P5E_PEX1_STN7_TX_DN<118>")
	)
	(segment
		(start 143.88338 -328.208132)
		(end 141.493748 -326.658732)
		(width 0.1651)
		(layer "In11.Cu")
		(net "P5E_PEX1_STN7_TX_DN<118>")
	)
	(segment
		(start 148.413216 -330.275946)
		(end 147.698968 -329.94981)
		(width 0.1651)
		(layer "In11.Cu")
		(net "P5E_PEX1_STN7_TX_DN<118>")
	)
	(segment
		(start 141.493748 -326.658732)
		(end 140.421614 -325.73976)
		(width 0.1651)
		(layer "In11.Cu")
		(net "P5E_PEX1_STN7_TX_DN<118>")
	)
	(segment
		(start 141.70533 -314.673234)
		(end 141.70533 -314.52947)
		(width 0.1651)
		(layer "In11.Cu")
		(net "P5E_PEX1_STN7_TX_DN<118>")
	)
	(segment
		(start 139.549886 -317.344552)
		(end 139.699492 -317.282576)
		(width 0.1651)
		(layer "In11.Cu")
		(net "P5E_PEX1_STN7_TX_DN<118>")
	)
	(segment
		(start 143.393922 -312.984642)
		(end 143.393922 -312.840878)
		(width 0.1651)
		(layer "In11.Cu")
		(net "P5E_PEX1_STN7_TX_DN<118>")
	)
	(segment
		(start 167.799004 -337.463892)
		(end 148.413216 -330.275946)
		(width 0.1651)
		(layer "In11.Cu")
		(net "P5E_PEX1_STN7_TX_DN<118>")
	)
	(segment
		(start 140.421614 -325.73976)
		(end 139.248642 -323.985382)
		(width 0.1651)
		(layer "In11.Cu")
		(net "P5E_PEX1_STN7_TX_DN<118>")
	)
	(segment
		(start 141.70533 -314.52947)
		(end 142.055342 -314.179458)
		(width 0.1651)
		(layer "In11.Cu")
		(net "P5E_PEX1_STN7_TX_DN<118>")
	)
	(segment
		(start 147.661376 -329.848972)
		(end 147.210526 -329.643232)
		(width 0.1651)
		(layer "In11.Cu")
		(net "P5E_PEX1_STN7_TX_DN<118>")
	)
	(segment
		(start 145.13941 -311.648856)
		(end 145.17116 -311.490106)
		(width 0.1651)
		(layer "In11.Cu")
		(net "P5E_PEX1_STN7_TX_DN<118>")
	)
	(segment
		(start 147.698968 -329.94981)
		(end 147.698968 -329.950064)
		(width 0.1651)
		(layer "In11.Cu")
		(net "P5E_PEX1_STN7_TX_DN<118>")
	)
	(segment
		(start 139.827254 -316.675516)
		(end 140.016738 -316.218062)
		(width 0.1651)
		(layer "In11.Cu")
		(net "P5E_PEX1_STN7_TX_DN<118>")
	)
	(segment
		(start 146.069812 -329.206098)
		(end 143.88338 -328.208132)
		(width 0.1651)
		(layer "In11.Cu")
		(net "P5E_PEX1_STN7_TX_DN<118>")
	)
	(segment
		(start 151.620728 -306.965858)
		(end 151.642826 -306.965858)
		(width 0.1143)
		(layer "In11.Cu")
		(net "P5E_PEX1_STN7_TX_DN<118>")
	)
	(segment
		(start 139.699492 -317.282576)
		(end 139.888976 -316.824868)
		(width 0.1651)
		(layer "In11.Cu")
		(net "P5E_PEX1_STN7_TX_DN<118>")
	)
	(segment
		(start 143.885666 -312.349134)
		(end 144.568926 -311.892696)
		(width 0.1651)
		(layer "In11.Cu")
		(net "P5E_PEX1_STN7_TX_DN<118>")
	)
	(segment
		(start 146.6215 -329.374246)
		(end 146.17065 -329.168506)
		(width 0.1651)
		(layer "In11.Cu")
		(net "P5E_PEX1_STN7_TX_DN<118>")
	)
	(segment
		(start 175.194722 -341.508588)
		(end 174.559468 -340.66226)
		(width 0.1651)
		(layer "In11.Cu")
		(net "P5E_PEX1_STN7_TX_DN<118>")
	)
	(segment
		(start 140.36675 -315.86805)
		(end 140.510514 -315.86805)
		(width 0.1651)
		(layer "In11.Cu")
		(net "P5E_PEX1_STN7_TX_DN<118>")
	)
	(segment
		(start 138.908536 -318.891666)
		(end 139.549886 -317.344552)
		(width 0.1651)
		(layer "In11.Cu")
		(net "P5E_PEX1_STN7_TX_DN<118>")
	)
	(segment
		(start 175.485552 -342.439498)
		(end 175.194722 -342.148668)
		(width 0.1651)
		(layer "In11.Cu")
		(net "P5E_PEX1_STN7_TX_DN<118>")
	)
	(segment
		(start 140.510514 -315.86805)
		(end 140.861034 -315.51753)
		(width 0.1651)
		(layer "In11.Cu")
		(net "P5E_PEX1_STN7_TX_DN<118>")
	)
	(segment
		(start 140.861034 -315.373766)
		(end 141.211046 -315.023754)
		(width 0.1651)
		(layer "In11.Cu")
		(net "P5E_PEX1_STN7_TX_DN<118>")
	)
	(segment
		(start 142.055342 -314.179458)
		(end 142.199106 -314.179458)
		(width 0.1651)
		(layer "In11.Cu")
		(net "P5E_PEX1_STN7_TX_DN<118>")
	)
	(segment
		(start 143.043402 -313.335162)
		(end 143.393922 -312.984642)
		(width 0.1651)
		(layer "In11.Cu")
		(net "P5E_PEX1_STN7_TX_DN<118>")
	)
	(segment
		(start 141.35481 -315.023754)
		(end 141.70533 -314.673234)
		(width 0.1651)
		(layer "In11.Cu")
		(net "P5E_PEX1_STN7_TX_DN<118>")
	)
	(segment
		(start 174.559468 -340.66226)
		(end 167.799004 -337.463892)
		(width 0.1651)
		(layer "In11.Cu")
		(net "P5E_PEX1_STN7_TX_DN<118>")
	)
	(segment
		(start 175.194722 -342.148668)
		(end 175.194722 -341.508588)
		(width 0.1651)
		(layer "In11.Cu")
		(net "P5E_PEX1_STN7_TX_DN<118>")
	)
	(segment
		(start 145.17116 -311.490106)
		(end 145.76425 -311.093866)
		(width 0.1651)
		(layer "In11.Cu")
		(net "P5E_PEX1_STN7_TX_DN<118>")
	)
	(segment
		(start 142.199106 -314.179458)
		(end 142.549626 -313.828938)
		(width 0.1651)
		(layer "In11.Cu")
		(net "P5E_PEX1_STN7_TX_DN<118>")
	)
	(segment
		(start 141.211046 -315.023754)
		(end 141.35481 -315.023754)
		(width 0.1651)
		(layer "In11.Cu")
		(net "P5E_PEX1_STN7_TX_DN<118>")
	)
	(segment
		(start 140.016738 -316.218062)
		(end 140.36675 -315.86805)
		(width 0.1651)
		(layer "In11.Cu")
		(net "P5E_PEX1_STN7_TX_DN<118>")
	)
	(segment
		(start 142.549626 -313.685174)
		(end 142.899638 -313.335162)
		(width 0.1651)
		(layer "In11.Cu")
		(net "P5E_PEX1_STN7_TX_DN<118>")
	)
	(segment
		(start 145.76425 -311.093866)
		(end 149.892258 -306.965858)
		(width 0.1651)
		(layer "In11.Cu")
		(net "P5E_PEX1_STN7_TX_DN<118>")
	)
	(segment
		(start 151.642826 -306.965858)
		(end 151.688546 -306.920138)
		(width 0.1143)
		(layer "In11.Cu")
		(net "P5E_PEX1_STN7_TX_DN<118>")
	)
	(segment
		(start 144.727422 -311.924192)
		(end 145.13941 -311.648856)
		(width 0.1651)
		(layer "In11.Cu")
		(net "P5E_PEX1_STN7_TX_DN<118>")
	)
	(segment
		(start 143.393922 -312.840878)
		(end 143.885666 -312.349134)
		(width 0.1651)
		(layer "In11.Cu")
		(net "P5E_PEX1_STN7_TX_DN<118>")
	)
	(segment
		(start 157.990794 -307.299868)
		(end 157.699964 -307.299868)
		(width 0.1143)
		(layer "In11.Cu")
		(net "P5E_PEX1_STN7_TX_DN<118>")
	)
	(segment
		(start 146.929602 -305.777646)
		(end 147.056856 -305.844448)
		(width 0.1651)
		(layer "In9.Cu")
		(net "P5E_PEX1_STN7_RX_DN<116>")
	)
	(segment
		(start 145.468086 -306.661566)
		(end 145.468086 -306.517802)
		(width 0.1651)
		(layer "In9.Cu")
		(net "P5E_PEX1_STN7_RX_DN<116>")
	)
	(segment
		(start 144.62379 -307.362098)
		(end 144.973802 -307.012086)
		(width 0.1651)
		(layer "In9.Cu")
		(net "P5E_PEX1_STN7_RX_DN<116>")
	)
	(segment
		(start 155.229814 -305.311048)
		(end 155.140914 -305.399948)
		(width 0.1143)
		(layer "In9.Cu")
		(net "P5E_PEX1_STN7_RX_DN<116>")
	)
	(segment
		(start 142.053056 -309.932832)
		(end 144.129506 -307.856382)
		(width 0.1651)
		(layer "In9.Cu")
		(net "P5E_PEX1_STN7_RX_DN<116>")
	)
	(segment
		(start 147.056856 -305.844448)
		(end 147.530058 -305.696874)
		(width 0.1651)
		(layer "In9.Cu")
		(net "P5E_PEX1_STN7_RX_DN<116>")
	)
	(segment
		(start 169.17543 -408.981148)
		(end 169.874438 -408.28214)
		(width 0.1651)
		(layer "In9.Cu")
		(net "P5E_PEX1_STN7_RX_DN<116>")
	)
	(segment
		(start 169.264838 -394.14196)
		(end 166.489634 -392.287252)
		(width 0.1651)
		(layer "In9.Cu")
		(net "P5E_PEX1_STN7_RX_DN<116>")
	)
	(segment
		(start 168.837102 -408.981148)
		(end 169.17543 -408.981148)
		(width 0.1651)
		(layer "In9.Cu")
		(net "P5E_PEX1_STN7_RX_DN<116>")
	)
	(segment
		(start 145.117566 -307.012086)
		(end 145.468086 -306.661566)
		(width 0.1651)
		(layer "In9.Cu")
		(net "P5E_PEX1_STN7_RX_DN<116>")
	)
	(segment
		(start 150.207472 -344.67673)
		(end 148.86432 -340.925912)
		(width 0.1651)
		(layer "In9.Cu")
		(net "P5E_PEX1_STN7_RX_DN<116>")
	)
	(segment
		(start 147.530058 -305.696874)
		(end 147.596606 -305.569366)
		(width 0.1651)
		(layer "In9.Cu")
		(net "P5E_PEX1_STN7_RX_DN<116>")
	)
	(segment
		(start 169.874438 -408.28214)
		(end 169.874438 -394.75156)
		(width 0.1651)
		(layer "In9.Cu")
		(net "P5E_PEX1_STN7_RX_DN<116>")
	)
	(segment
		(start 145.880582 -306.105306)
		(end 146.929602 -305.777646)
		(width 0.1651)
		(layer "In9.Cu")
		(net "P5E_PEX1_STN7_RX_DN<116>")
	)
	(segment
		(start 145.468086 -306.517802)
		(end 145.880582 -306.105306)
		(width 0.1651)
		(layer "In9.Cu")
		(net "P5E_PEX1_STN7_RX_DN<116>")
	)
	(segment
		(start 144.62379 -307.505862)
		(end 144.62379 -307.362098)
		(width 0.1651)
		(layer "In9.Cu")
		(net "P5E_PEX1_STN7_RX_DN<116>")
	)
	(segment
		(start 155.140914 -305.399948)
		(end 154.850084 -305.399948)
		(width 0.1143)
		(layer "In9.Cu")
		(net "P5E_PEX1_STN7_RX_DN<116>")
	)
	(segment
		(start 156.979366 -387.044438)
		(end 155.5877 -384.518408)
		(width 0.1651)
		(layer "In9.Cu")
		(net "P5E_PEX1_STN7_RX_DN<116>")
	)
	(segment
		(start 144.129506 -307.856382)
		(end 144.27327 -307.856382)
		(width 0.1651)
		(layer "In9.Cu")
		(net "P5E_PEX1_STN7_RX_DN<116>")
	)
	(segment
		(start 137.873232 -319.35547)
		(end 142.053056 -309.932832)
		(width 0.1651)
		(layer "In9.Cu")
		(net "P5E_PEX1_STN7_RX_DN<116>")
	)
	(segment
		(start 137.873232 -322.666614)
		(end 137.873232 -319.35547)
		(width 0.1651)
		(layer "In9.Cu")
		(net "P5E_PEX1_STN7_RX_DN<116>")
	)
	(segment
		(start 149.208998 -305.065938)
		(end 151.765 -305.065938)
		(width 0.1651)
		(layer "In9.Cu")
		(net "P5E_PEX1_STN7_RX_DN<116>")
	)
	(segment
		(start 151.765 -305.065938)
		(end 151.793448 -305.065938)
		(width 0.1143)
		(layer "In9.Cu")
		(net "P5E_PEX1_STN7_RX_DN<116>")
	)
	(segment
		(start 148.736304 -305.213512)
		(end 149.208998 -305.065938)
		(width 0.1651)
		(layer "In9.Cu")
		(net "P5E_PEX1_STN7_RX_DN<116>")
	)
	(segment
		(start 151.793448 -305.065938)
		(end 151.839168 -305.020218)
		(width 0.1143)
		(layer "In9.Cu")
		(net "P5E_PEX1_STN7_RX_DN<116>")
	)
	(segment
		(start 148.86432 -340.925912)
		(end 138.099038 -323.507608)
		(width 0.1651)
		(layer "In9.Cu")
		(net "P5E_PEX1_STN7_RX_DN<116>")
	)
	(segment
		(start 155.117292 -305.020218)
		(end 155.229814 -305.13274)
		(width 0.1143)
		(layer "In9.Cu")
		(net "P5E_PEX1_STN7_RX_DN<116>")
	)
	(segment
		(start 155.5877 -384.518408)
		(end 150.207472 -344.67673)
		(width 0.1651)
		(layer "In9.Cu")
		(net "P5E_PEX1_STN7_RX_DN<116>")
	)
	(segment
		(start 144.27327 -307.856382)
		(end 144.62379 -307.505862)
		(width 0.1651)
		(layer "In9.Cu")
		(net "P5E_PEX1_STN7_RX_DN<116>")
	)
	(segment
		(start 166.489634 -392.287252)
		(end 160.222692 -389.68934)
		(width 0.1651)
		(layer "In9.Cu")
		(net "P5E_PEX1_STN7_RX_DN<116>")
	)
	(segment
		(start 148.196554 -305.488594)
		(end 148.669756 -305.34102)
		(width 0.1651)
		(layer "In9.Cu")
		(net "P5E_PEX1_STN7_RX_DN<116>")
	)
	(segment
		(start 169.874438 -394.75156)
		(end 169.264838 -394.14196)
		(width 0.1651)
		(layer "In9.Cu")
		(net "P5E_PEX1_STN7_RX_DN<116>")
	)
	(segment
		(start 168.710102 -409.108148)
		(end 168.837102 -408.981148)
		(width 0.1651)
		(layer "In9.Cu")
		(net "P5E_PEX1_STN7_RX_DN<116>")
	)
	(segment
		(start 144.973802 -307.012086)
		(end 145.117566 -307.012086)
		(width 0.1651)
		(layer "In9.Cu")
		(net "P5E_PEX1_STN7_RX_DN<116>")
	)
	(segment
		(start 148.0693 -305.421792)
		(end 148.196554 -305.488594)
		(width 0.1651)
		(layer "In9.Cu")
		(net "P5E_PEX1_STN7_RX_DN<116>")
	)
	(segment
		(start 138.099038 -323.507608)
		(end 137.873232 -322.666614)
		(width 0.1651)
		(layer "In9.Cu")
		(net "P5E_PEX1_STN7_RX_DN<116>")
	)
	(segment
		(start 155.229814 -305.13274)
		(end 155.229814 -305.311048)
		(width 0.1143)
		(layer "In9.Cu")
		(net "P5E_PEX1_STN7_RX_DN<116>")
	)
	(segment
		(start 151.839168 -305.020218)
		(end 155.117292 -305.020218)
		(width 0.1143)
		(layer "In9.Cu")
		(net "P5E_PEX1_STN7_RX_DN<116>")
	)
	(segment
		(start 148.669756 -305.34102)
		(end 148.736304 -305.213512)
		(width 0.1651)
		(layer "In9.Cu")
		(net "P5E_PEX1_STN7_RX_DN<116>")
	)
	(segment
		(start 160.222692 -389.68934)
		(end 156.979366 -387.044438)
		(width 0.1651)
		(layer "In9.Cu")
		(net "P5E_PEX1_STN7_RX_DN<116>")
	)
	(segment
		(start 147.596606 -305.569366)
		(end 148.0693 -305.421792)
		(width 0.1651)
		(layer "In9.Cu")
		(net "P5E_PEX1_STN7_RX_DN<116>")
	)
	(segment
		(start 168.710102 -409.490164)
		(end 168.710102 -409.108148)
		(width 0.1651)
		(layer "In9.Cu")
		(net "P5E_PEX1_STN7_RX_DN<116>")
	)
	(segment
		(start 287.6169 -382.9812)
		(end 287.4899 -383.1082)
		(width 0.1651)
		(layer "In5.Cu")
		(net "P5E_PEX2_STN7_RX_DN<120>")
	)
	(segment
		(start 266.10183 -313.22645)
		(end 265.98753 -313.34075)
		(width 0.1651)
		(layer "In5.Cu")
		(net "P5E_PEX2_STN7_RX_DN<120>")
	)
	(segment
		(start 287.4899 -383.1082)
		(end 287.4899 -383.490216)
		(width 0.1651)
		(layer "In5.Cu")
		(net "P5E_PEX2_STN7_RX_DN<120>")
	)
	(segment
		(start 267.900658 -308.865778)
		(end 267.87221 -308.865778)
		(width 0.1143)
		(layer "In5.Cu")
		(net "P5E_PEX2_STN7_RX_DN<120>")
	)
	(segment
		(start 266.15009 -309.84571)
		(end 266.04087 -310.109362)
		(width 0.1651)
		(layer "In5.Cu")
		(net "P5E_PEX2_STN7_RX_DN<120>")
	)
	(segment
		(start 266.327382 -317.29934)
		(end 266.58697 -318.366394)
		(width 0.1651)
		(layer "In5.Cu")
		(net "P5E_PEX2_STN7_RX_DN<120>")
	)
	(segment
		(start 266.58697 -318.366394)
		(end 266.709906 -318.441324)
		(width 0.1651)
		(layer "In5.Cu")
		(net "P5E_PEX2_STN7_RX_DN<120>")
	)
	(segment
		(start 282.460192 -341.99576)
		(end 282.460192 -358.033574)
		(width 0.1651)
		(layer "In5.Cu")
		(net "P5E_PEX2_STN7_RX_DN<120>")
	)
	(segment
		(start 271.215358 -309.199788)
		(end 271.329658 -309.085488)
		(width 0.1143)
		(layer "In5.Cu")
		(net "P5E_PEX2_STN7_RX_DN<120>")
	)
	(segment
		(start 266.1158 -314.61964)
		(end 265.98753 -314.74791)
		(width 0.1651)
		(layer "In5.Cu")
		(net "P5E_PEX2_STN7_RX_DN<120>")
	)
	(segment
		(start 288.164016 -382.9812)
		(end 287.6169 -382.9812)
		(width 0.1651)
		(layer "In5.Cu")
		(net "P5E_PEX2_STN7_RX_DN<120>")
	)
	(segment
		(start 266.709906 -318.441324)
		(end 266.827 -318.922654)
		(width 0.1651)
		(layer "In5.Cu")
		(net "P5E_PEX2_STN7_RX_DN<120>")
	)
	(segment
		(start 270.949928 -309.199788)
		(end 271.215358 -309.199788)
		(width 0.1143)
		(layer "In5.Cu")
		(net "P5E_PEX2_STN7_RX_DN<120>")
	)
	(segment
		(start 265.98753 -314.74791)
		(end 265.98753 -315.90361)
		(width 0.1651)
		(layer "In5.Cu")
		(net "P5E_PEX2_STN7_RX_DN<120>")
	)
	(segment
		(start 266.411456 -317.161418)
		(end 266.327382 -317.29934)
		(width 0.1651)
		(layer "In5.Cu")
		(net "P5E_PEX2_STN7_RX_DN<120>")
	)
	(segment
		(start 266.1158 -314.17768)
		(end 266.1158 -314.61964)
		(width 0.1651)
		(layer "In5.Cu")
		(net "P5E_PEX2_STN7_RX_DN<120>")
	)
	(segment
		(start 267.130022 -308.865778)
		(end 266.15009 -309.84571)
		(width 0.1651)
		(layer "In5.Cu")
		(net "P5E_PEX2_STN7_RX_DN<120>")
	)
	(segment
		(start 265.98753 -312.61685)
		(end 266.10183 -312.73115)
		(width 0.1651)
		(layer "In5.Cu")
		(net "P5E_PEX2_STN7_RX_DN<120>")
	)
	(segment
		(start 266.04087 -310.796178)
		(end 265.98753 -312.039)
		(width 0.1651)
		(layer "In5.Cu")
		(net "P5E_PEX2_STN7_RX_DN<120>")
	)
	(segment
		(start 266.752324 -319.045336)
		(end 267.1318 -320.604896)
		(width 0.1651)
		(layer "In5.Cu")
		(net "P5E_PEX2_STN7_RX_DN<120>")
	)
	(segment
		(start 282.460192 -358.033574)
		(end 288.615882 -368.610388)
		(width 0.1651)
		(layer "In5.Cu")
		(net "P5E_PEX2_STN7_RX_DN<120>")
	)
	(segment
		(start 271.793208 -332.747112)
		(end 282.0416 -340.86546)
		(width 0.1651)
		(layer "In5.Cu")
		(net "P5E_PEX2_STN7_RX_DN<120>")
	)
	(segment
		(start 267.87221 -308.865778)
		(end 267.130022 -308.865778)
		(width 0.1651)
		(layer "In5.Cu")
		(net "P5E_PEX2_STN7_RX_DN<120>")
	)
	(segment
		(start 265.98753 -313.34075)
		(end 265.98753 -314.04941)
		(width 0.1651)
		(layer "In5.Cu")
		(net "P5E_PEX2_STN7_RX_DN<120>")
	)
	(segment
		(start 266.10183 -312.73115)
		(end 266.10183 -313.22645)
		(width 0.1651)
		(layer "In5.Cu")
		(net "P5E_PEX2_STN7_RX_DN<120>")
	)
	(segment
		(start 288.615882 -382.529334)
		(end 288.164016 -382.9812)
		(width 0.1651)
		(layer "In5.Cu")
		(net "P5E_PEX2_STN7_RX_DN<120>")
	)
	(segment
		(start 267.1318 -320.604896)
		(end 267.1318 -325.443342)
		(width 0.1651)
		(layer "In5.Cu")
		(net "P5E_PEX2_STN7_RX_DN<120>")
	)
	(segment
		(start 265.98753 -312.039)
		(end 265.98753 -312.61685)
		(width 0.1651)
		(layer "In5.Cu")
		(net "P5E_PEX2_STN7_RX_DN<120>")
	)
	(segment
		(start 266.04087 -310.109362)
		(end 266.04087 -310.796178)
		(width 0.1651)
		(layer "In5.Cu")
		(net "P5E_PEX2_STN7_RX_DN<120>")
	)
	(segment
		(start 268.75486 -329.296014)
		(end 271.793208 -332.747112)
		(width 0.1651)
		(layer "In5.Cu")
		(net "P5E_PEX2_STN7_RX_DN<120>")
	)
	(segment
		(start 266.827 -318.922654)
		(end 266.752324 -319.045336)
		(width 0.1651)
		(layer "In5.Cu")
		(net "P5E_PEX2_STN7_RX_DN<120>")
	)
	(segment
		(start 267.1318 -325.443342)
		(end 268.75486 -329.296014)
		(width 0.1651)
		(layer "In5.Cu")
		(net "P5E_PEX2_STN7_RX_DN<120>")
	)
	(segment
		(start 271.329658 -308.934358)
		(end 271.215358 -308.820058)
		(width 0.1143)
		(layer "In5.Cu")
		(net "P5E_PEX2_STN7_RX_DN<120>")
	)
	(segment
		(start 288.615882 -368.610388)
		(end 288.615882 -382.529334)
		(width 0.1651)
		(layer "In5.Cu")
		(net "P5E_PEX2_STN7_RX_DN<120>")
	)
	(segment
		(start 266.294362 -316.679834)
		(end 266.411456 -317.161418)
		(width 0.1651)
		(layer "In5.Cu")
		(net "P5E_PEX2_STN7_RX_DN<120>")
	)
	(segment
		(start 265.98753 -314.04941)
		(end 266.1158 -314.17768)
		(width 0.1651)
		(layer "In5.Cu")
		(net "P5E_PEX2_STN7_RX_DN<120>")
	)
	(segment
		(start 271.215358 -308.820058)
		(end 267.946378 -308.820058)
		(width 0.1143)
		(layer "In5.Cu")
		(net "P5E_PEX2_STN7_RX_DN<120>")
	)
	(segment
		(start 282.0416 -340.86546)
		(end 282.460192 -341.99576)
		(width 0.1651)
		(layer "In5.Cu")
		(net "P5E_PEX2_STN7_RX_DN<120>")
	)
	(segment
		(start 265.98753 -315.90361)
		(end 266.156186 -316.59576)
		(width 0.1651)
		(layer "In5.Cu")
		(net "P5E_PEX2_STN7_RX_DN<120>")
	)
	(segment
		(start 267.946378 -308.820058)
		(end 267.900658 -308.865778)
		(width 0.1143)
		(layer "In5.Cu")
		(net "P5E_PEX2_STN7_RX_DN<120>")
	)
	(segment
		(start 266.156186 -316.59576)
		(end 266.294362 -316.679834)
		(width 0.1651)
		(layer "In5.Cu")
		(net "P5E_PEX2_STN7_RX_DN<120>")
	)
	(segment
		(start 271.329658 -309.085488)
		(end 271.329658 -308.934358)
		(width 0.1143)
		(layer "In5.Cu")
		(net "P5E_PEX2_STN7_RX_DN<120>")
	)
	(segment
		(start 41.069768 -343.685622)
		(end 41.389808 -343.365582)
		(width 0.13462)
		(layer "F.Cu")
		(net "P5E_PEX0_STN7_TX_DN<122>")
	)
	(segment
		(start 41.389808 -342.734138)
		(end 41.095168 -342.439498)
		(width 0.13462)
		(layer "F.Cu")
		(net "P5E_PEX0_STN7_TX_DN<122>")
	)
	(segment
		(start 41.389808 -343.365582)
		(end 41.389808 -342.734138)
		(width 0.13462)
		(layer "F.Cu")
		(net "P5E_PEX0_STN7_TX_DN<122>")
	)
	(segment
		(start 36.324032 -323.079872)
		(end 36.398454 -322.94068)
		(width 0.1651)
		(layer "In7.Cu")
		(net "P5E_PEX0_STN7_TX_DN<122>")
	)
	(segment
		(start 37.115242 -315.279532)
		(end 37.229542 -315.165232)
		(width 0.1143)
		(layer "In7.Cu")
		(net "P5E_PEX0_STN7_TX_DN<122>")
	)
	(segment
		(start 35.362896 -319.527682)
		(end 35.222942 -319.06591)
		(width 0.1651)
		(layer "In7.Cu")
		(net "P5E_PEX0_STN7_TX_DN<122>")
	)
	(segment
		(start 36.398454 -322.94068)
		(end 36.2585 -322.478908)
		(width 0.1651)
		(layer "In7.Cu")
		(net "P5E_PEX0_STN7_TX_DN<122>")
	)
	(segment
		(start 36.1188 -322.404486)
		(end 35.978846 -321.942206)
		(width 0.1651)
		(layer "In7.Cu")
		(net "P5E_PEX0_STN7_TX_DN<122>")
	)
	(segment
		(start 36.40455 -315.279532)
		(end 37.115242 -315.279532)
		(width 0.1143)
		(layer "In7.Cu")
		(net "P5E_PEX0_STN7_TX_DN<122>")
	)
	(segment
		(start 35.38601 -316.23381)
		(end 36.068 -315.55182)
		(width 0.1651)
		(layer "In7.Cu")
		(net "P5E_PEX0_STN7_TX_DN<122>")
	)
	(segment
		(start 36.743386 -324.078346)
		(end 36.603432 -323.616574)
		(width 0.1651)
		(layer "In7.Cu")
		(net "P5E_PEX0_STN7_TX_DN<122>")
	)
	(segment
		(start 35.63366 -320.80454)
		(end 35.708082 -320.665348)
		(width 0.1651)
		(layer "In7.Cu")
		(net "P5E_PEX0_STN7_TX_DN<122>")
	)
	(segment
		(start 36.74364 -324.078346)
		(end 36.743386 -324.078346)
		(width 0.1651)
		(layer "In7.Cu")
		(net "P5E_PEX0_STN7_TX_DN<122>")
	)
	(segment
		(start 36.669218 -324.217538)
		(end 36.74364 -324.078346)
		(width 0.1651)
		(layer "In7.Cu")
		(net "P5E_PEX0_STN7_TX_DN<122>")
	)
	(segment
		(start 41.385998 -342.148668)
		(end 41.385998 -340.809072)
		(width 0.1651)
		(layer "In7.Cu")
		(net "P5E_PEX0_STN7_TX_DN<122>")
	)
	(segment
		(start 41.095168 -342.439498)
		(end 41.385998 -342.148668)
		(width 0.1651)
		(layer "In7.Cu")
		(net "P5E_PEX0_STN7_TX_DN<122>")
	)
	(segment
		(start 36.948872 -324.75424)
		(end 36.809172 -324.679818)
		(width 0.1651)
		(layer "In7.Cu")
		(net "P5E_PEX0_STN7_TX_DN<122>")
	)
	(segment
		(start 35.978846 -321.942206)
		(end 36.053268 -321.803014)
		(width 0.1651)
		(layer "In7.Cu")
		(net "P5E_PEX0_STN7_TX_DN<122>")
	)
	(segment
		(start 36.463986 -323.542152)
		(end 36.324032 -323.079872)
		(width 0.1651)
		(layer "In7.Cu")
		(net "P5E_PEX0_STN7_TX_DN<122>")
	)
	(segment
		(start 35.913314 -321.341242)
		(end 35.773614 -321.26682)
		(width 0.1651)
		(layer "In7.Cu")
		(net "P5E_PEX0_STN7_TX_DN<122>")
	)
	(segment
		(start 36.603432 -323.616574)
		(end 36.603686 -323.616574)
		(width 0.1651)
		(layer "In7.Cu")
		(net "P5E_PEX0_STN7_TX_DN<122>")
	)
	(segment
		(start 36.053268 -321.803014)
		(end 35.913314 -321.341242)
		(width 0.1651)
		(layer "In7.Cu")
		(net "P5E_PEX0_STN7_TX_DN<122>")
	)
	(segment
		(start 35.428428 -320.129154)
		(end 35.288474 -319.666874)
		(width 0.1651)
		(layer "In7.Cu")
		(net "P5E_PEX0_STN7_TX_DN<122>")
	)
	(segment
		(start 36.603686 -323.616574)
		(end 36.463986 -323.542152)
		(width 0.1651)
		(layer "In7.Cu")
		(net "P5E_PEX0_STN7_TX_DN<122>")
	)
	(segment
		(start 36.2585 -322.478908)
		(end 36.1188 -322.404486)
		(width 0.1651)
		(layer "In7.Cu")
		(net "P5E_PEX0_STN7_TX_DN<122>")
	)
	(segment
		(start 41.385998 -340.809072)
		(end 41.315386 -340.331806)
		(width 0.1651)
		(layer "In7.Cu")
		(net "P5E_PEX0_STN7_TX_DN<122>")
	)
	(segment
		(start 41.117266 -339.760052)
		(end 41.2115 -339.633052)
		(width 0.1651)
		(layer "In7.Cu")
		(net "P5E_PEX0_STN7_TX_DN<122>")
	)
	(segment
		(start 40.97147 -338.015072)
		(end 36.948364 -324.75424)
		(width 0.1651)
		(layer "In7.Cu")
		(net "P5E_PEX0_STN7_TX_DN<122>")
	)
	(segment
		(start 35.04946 -317.89624)
		(end 35.04946 -317.046356)
		(width 0.1651)
		(layer "In7.Cu")
		(net "P5E_PEX0_STN7_TX_DN<122>")
	)
	(segment
		(start 35.773614 -321.26682)
		(end 35.63366 -320.80454)
		(width 0.1651)
		(layer "In7.Cu")
		(net "P5E_PEX0_STN7_TX_DN<122>")
	)
	(segment
		(start 35.222942 -319.06591)
		(end 35.04946 -317.89624)
		(width 0.1651)
		(layer "In7.Cu")
		(net "P5E_PEX0_STN7_TX_DN<122>")
	)
	(segment
		(start 41.315386 -340.331806)
		(end 41.188132 -340.237572)
		(width 0.1651)
		(layer "In7.Cu")
		(net "P5E_PEX0_STN7_TX_DN<122>")
	)
	(segment
		(start 41.2115 -339.633052)
		(end 40.97147 -338.015072)
		(width 0.1651)
		(layer "In7.Cu")
		(net "P5E_PEX0_STN7_TX_DN<122>")
	)
	(segment
		(start 41.188132 -340.237572)
		(end 41.117266 -339.760052)
		(width 0.1651)
		(layer "In7.Cu")
		(net "P5E_PEX0_STN7_TX_DN<122>")
	)
	(segment
		(start 37.229542 -315.014102)
		(end 37.115242 -314.899802)
		(width 0.1143)
		(layer "In7.Cu")
		(net "P5E_PEX0_STN7_TX_DN<122>")
	)
	(segment
		(start 37.229542 -315.165232)
		(end 37.229542 -315.014102)
		(width 0.1143)
		(layer "In7.Cu")
		(net "P5E_PEX0_STN7_TX_DN<122>")
	)
	(segment
		(start 36.809172 -324.679818)
		(end 36.669218 -324.217538)
		(width 0.1651)
		(layer "In7.Cu")
		(net "P5E_PEX0_STN7_TX_DN<122>")
	)
	(segment
		(start 36.068 -315.55182)
		(end 36.088066 -315.531754)
		(width 0.1143)
		(layer "In7.Cu")
		(net "P5E_PEX0_STN7_TX_DN<122>")
	)
	(segment
		(start 36.152074 -315.532008)
		(end 36.40455 -315.279532)
		(width 0.1143)
		(layer "In7.Cu")
		(net "P5E_PEX0_STN7_TX_DN<122>")
	)
	(segment
		(start 35.288474 -319.666874)
		(end 35.362896 -319.527682)
		(width 0.1651)
		(layer "In7.Cu")
		(net "P5E_PEX0_STN7_TX_DN<122>")
	)
	(segment
		(start 35.568128 -320.203576)
		(end 35.428428 -320.129154)
		(width 0.1651)
		(layer "In7.Cu")
		(net "P5E_PEX0_STN7_TX_DN<122>")
	)
	(segment
		(start 35.04946 -317.046356)
		(end 35.38601 -316.23381)
		(width 0.1651)
		(layer "In7.Cu")
		(net "P5E_PEX0_STN7_TX_DN<122>")
	)
	(segment
		(start 36.088066 -315.531754)
		(end 36.152074 -315.532008)
		(width 0.1143)
		(layer "In7.Cu")
		(net "P5E_PEX0_STN7_TX_DN<122>")
	)
	(segment
		(start 37.115242 -314.899802)
		(end 36.849812 -314.899802)
		(width 0.1143)
		(layer "In7.Cu")
		(net "P5E_PEX0_STN7_TX_DN<122>")
	)
	(segment
		(start 35.708082 -320.665348)
		(end 35.568128 -320.203576)
		(width 0.1651)
		(layer "In7.Cu")
		(net "P5E_PEX0_STN7_TX_DN<122>")
	)
	(segment
		(start 36.948364 -324.75424)
		(end 36.948872 -324.75424)
		(width 0.1651)
		(layer "In7.Cu")
		(net "P5E_PEX0_STN7_TX_DN<122>")
	)
	(segment
		(start 199.02805 -151.596852)
		(end 199.34809 -151.916892)
		(width 0.13462)
		(layer "F.Cu")
		(net "P5E_PEX1_STN0_TX_DN<13>")
	)
	(segment
		(start 199.979534 -151.916892)
		(end 200.274174 -151.622252)
		(width 0.13462)
		(layer "F.Cu")
		(net "P5E_PEX1_STN0_TX_DN<13>")
	)
	(segment
		(start 199.34809 -151.916892)
		(end 199.979534 -151.916892)
		(width 0.13462)
		(layer "F.Cu")
		(net "P5E_PEX1_STN0_TX_DN<13>")
	)
	(segment
		(start 192.470278 -278.12619)
		(end 192.573656 -278.229568)
		(width 0.1143)
		(layer "In9.Cu")
		(net "P5E_PEX1_STN0_TX_DN<13>")
	)
	(segment
		(start 192.849754 -278.115268)
		(end 192.849754 -277.849838)
		(width 0.1143)
		(layer "In9.Cu")
		(net "P5E_PEX1_STN0_TX_DN<13>")
	)
	(segment
		(start 189.980824 -221.36227)
		(end 193.425826 -260.750558)
		(width 0.1651)
		(layer "In9.Cu")
		(net "P5E_PEX1_STN0_TX_DN<13>")
	)
	(segment
		(start 201.348594 -151.913082)
		(end 201.80554 -152.370028)
		(width 0.1651)
		(layer "In9.Cu")
		(net "P5E_PEX1_STN0_TX_DN<13>")
	)
	(segment
		(start 203.690982 -157.099254)
		(end 195.301362 -171.632118)
		(width 0.1651)
		(layer "In9.Cu")
		(net "P5E_PEX1_STN0_TX_DN<13>")
	)
	(segment
		(start 201.80554 -152.370028)
		(end 203.271882 -154.564334)
		(width 0.1651)
		(layer "In9.Cu")
		(net "P5E_PEX1_STN0_TX_DN<13>")
	)
	(segment
		(start 192.515998 -271.471898)
		(end 192.515998 -271.500346)
		(width 0.1143)
		(layer "In9.Cu")
		(net "P5E_PEX1_STN0_TX_DN<13>")
	)
	(segment
		(start 203.690982 -155.576524)
		(end 203.690982 -157.099254)
		(width 0.1651)
		(layer "In9.Cu")
		(net "P5E_PEX1_STN0_TX_DN<13>")
	)
	(segment
		(start 200.274174 -151.622252)
		(end 200.565004 -151.913082)
		(width 0.1651)
		(layer "In9.Cu")
		(net "P5E_PEX1_STN0_TX_DN<13>")
	)
	(segment
		(start 200.565004 -151.913082)
		(end 201.348594 -151.913082)
		(width 0.1651)
		(layer "In9.Cu")
		(net "P5E_PEX1_STN0_TX_DN<13>")
	)
	(segment
		(start 192.515998 -271.500346)
		(end 192.470278 -271.546066)
		(width 0.1143)
		(layer "In9.Cu")
		(net "P5E_PEX1_STN0_TX_DN<13>")
	)
	(segment
		(start 193.425826 -267.847064)
		(end 192.515998 -270.044164)
		(width 0.1651)
		(layer "In9.Cu")
		(net "P5E_PEX1_STN0_TX_DN<13>")
	)
	(segment
		(start 193.425826 -260.750558)
		(end 193.425826 -267.847064)
		(width 0.1651)
		(layer "In9.Cu")
		(net "P5E_PEX1_STN0_TX_DN<13>")
	)
	(segment
		(start 195.301362 -171.632118)
		(end 193.862452 -177.001678)
		(width 0.1651)
		(layer "In9.Cu")
		(net "P5E_PEX1_STN0_TX_DN<13>")
	)
	(segment
		(start 192.515998 -270.044164)
		(end 192.515998 -271.471898)
		(width 0.1651)
		(layer "In9.Cu")
		(net "P5E_PEX1_STN0_TX_DN<13>")
	)
	(segment
		(start 193.862452 -177.001678)
		(end 189.980824 -221.36227)
		(width 0.1651)
		(layer "In9.Cu")
		(net "P5E_PEX1_STN0_TX_DN<13>")
	)
	(segment
		(start 192.470278 -271.546066)
		(end 192.470278 -278.12619)
		(width 0.1143)
		(layer "In9.Cu")
		(net "P5E_PEX1_STN0_TX_DN<13>")
	)
	(segment
		(start 192.573656 -278.229568)
		(end 192.735454 -278.229568)
		(width 0.1143)
		(layer "In9.Cu")
		(net "P5E_PEX1_STN0_TX_DN<13>")
	)
	(segment
		(start 203.271882 -154.564334)
		(end 203.690982 -155.576524)
		(width 0.1651)
		(layer "In9.Cu")
		(net "P5E_PEX1_STN0_TX_DN<13>")
	)
	(segment
		(start 192.735454 -278.229568)
		(end 192.849754 -278.115268)
		(width 0.1143)
		(layer "In9.Cu")
		(net "P5E_PEX1_STN0_TX_DN<13>")
	)
	(segment
		(start 111.836708 -343.685622)
		(end 112.156748 -343.365582)
		(width 0.13462)
		(layer "F.Cu")
		(net "P5E_PEX1_STN6_TX_DP<111>")
	)
	(segment
		(start 112.156748 -342.734138)
		(end 111.862108 -342.439498)
		(width 0.13462)
		(layer "F.Cu")
		(net "P5E_PEX1_STN6_TX_DP<111>")
	)
	(segment
		(start 112.156748 -343.365582)
		(end 112.156748 -342.734138)
		(width 0.13462)
		(layer "F.Cu")
		(net "P5E_PEX1_STN6_TX_DP<111>")
	)
	(segment
		(start 155.409138 -322.681346)
		(end 147.259294 -326.05726)
		(width 0.1651)
		(layer "In13.Cu")
		(net "P5E_PEX1_STN6_TX_DP<111>")
	)
	(segment
		(start 113.442242 -339.49132)
		(end 112.621822 -340.27237)
		(width 0.1651)
		(layer "In13.Cu")
		(net "P5E_PEX1_STN6_TX_DP<111>")
	)
	(segment
		(start 159.029654 -311.69483)
		(end 159.029654 -319.995296)
		(width 0.1143)
		(layer "In13.Cu")
		(net "P5E_PEX1_STN6_TX_DP<111>")
	)
	(segment
		(start 159.485584 -311.479692)
		(end 159.244792 -311.479692)
		(width 0.1143)
		(layer "In13.Cu")
		(net "P5E_PEX1_STN6_TX_DP<111>")
	)
	(segment
		(start 112.152938 -341.054436)
		(end 112.152938 -342.148668)
		(width 0.1651)
		(layer "In13.Cu")
		(net "P5E_PEX1_STN6_TX_DP<111>")
	)
	(segment
		(start 127.148082 -332.164944)
		(end 113.442242 -339.49132)
		(width 0.1651)
		(layer "In13.Cu")
		(net "P5E_PEX1_STN6_TX_DP<111>")
	)
	(segment
		(start 158.983934 -320.063114)
		(end 158.983934 -320.114168)
		(width 0.1651)
		(layer "In13.Cu")
		(net "P5E_PEX1_STN6_TX_DP<111>")
	)
	(segment
		(start 159.599884 -311.365392)
		(end 159.485584 -311.479692)
		(width 0.1143)
		(layer "In13.Cu")
		(net "P5E_PEX1_STN6_TX_DP<111>")
	)
	(segment
		(start 158.983934 -320.041016)
		(end 158.983934 -320.063114)
		(width 0.1143)
		(layer "In13.Cu")
		(net "P5E_PEX1_STN6_TX_DP<111>")
	)
	(segment
		(start 158.983934 -320.114168)
		(end 157.9245 -321.173602)
		(width 0.1651)
		(layer "In13.Cu")
		(net "P5E_PEX1_STN6_TX_DP<111>")
	)
	(segment
		(start 159.244792 -311.479692)
		(end 159.029654 -311.69483)
		(width 0.1143)
		(layer "In13.Cu")
		(net "P5E_PEX1_STN6_TX_DP<111>")
	)
	(segment
		(start 157.9245 -321.173602)
		(end 155.409138 -322.681346)
		(width 0.1651)
		(layer "In13.Cu")
		(net "P5E_PEX1_STN6_TX_DP<111>")
	)
	(segment
		(start 159.599884 -311.099962)
		(end 159.599884 -311.365392)
		(width 0.1143)
		(layer "In13.Cu")
		(net "P5E_PEX1_STN6_TX_DP<111>")
	)
	(segment
		(start 141.200886 -326.344026)
		(end 127.148082 -332.164944)
		(width 0.1651)
		(layer "In13.Cu")
		(net "P5E_PEX1_STN6_TX_DP<111>")
	)
	(segment
		(start 112.152938 -342.148668)
		(end 111.862108 -342.439498)
		(width 0.1651)
		(layer "In13.Cu")
		(net "P5E_PEX1_STN6_TX_DP<111>")
	)
	(segment
		(start 159.029654 -319.995296)
		(end 158.983934 -320.041016)
		(width 0.1143)
		(layer "In13.Cu")
		(net "P5E_PEX1_STN6_TX_DP<111>")
	)
	(segment
		(start 147.259294 -326.05726)
		(end 145.814796 -326.344026)
		(width 0.1651)
		(layer "In13.Cu")
		(net "P5E_PEX1_STN6_TX_DP<111>")
	)
	(segment
		(start 112.621822 -340.27237)
		(end 112.152938 -341.054436)
		(width 0.1651)
		(layer "In13.Cu")
		(net "P5E_PEX1_STN6_TX_DP<111>")
	)
	(segment
		(start 145.814796 -326.344026)
		(end 141.200886 -326.344026)
		(width 0.1651)
		(layer "In13.Cu")
		(net "P5E_PEX1_STN6_TX_DP<111>")
	)
	(segment
		(start 138.81862 -314.493148)
		(end 139.01928 -314.040774)
		(width 0.1651)
		(layer "In9.Cu")
		(net "P5E_PEX1_STN7_RX_DN<115>")
	)
	(segment
		(start 138.869928 -314.62726)
		(end 138.818366 -314.493148)
		(width 0.1651)
		(layer "In9.Cu")
		(net "P5E_PEX1_STN7_RX_DN<115>")
	)
	(segment
		(start 138.669014 -315.080142)
		(end 138.869928 -314.62726)
		(width 0.1651)
		(layer "In9.Cu")
		(net "P5E_PEX1_STN7_RX_DN<115>")
	)
	(segment
		(start 139.786868 -312.310272)
		(end 139.987528 -311.857898)
		(width 0.1651)
		(layer "In9.Cu")
		(net "P5E_PEX1_STN7_RX_DN<115>")
	)
	(segment
		(start 167.67429 -409.382214)
		(end 167.67429 -395.391132)
		(width 0.1651)
		(layer "In9.Cu")
		(net "P5E_PEX1_STN7_RX_DN<115>")
	)
	(segment
		(start 139.786614 -312.310272)
		(end 139.786868 -312.310272)
		(width 0.1651)
		(layer "In9.Cu")
		(net "P5E_PEX1_STN7_RX_DN<115>")
	)
	(segment
		(start 138.534902 -315.131958)
		(end 138.669014 -315.080142)
		(width 0.1651)
		(layer "In9.Cu")
		(net "P5E_PEX1_STN7_RX_DN<115>")
	)
	(segment
		(start 151.793448 -304.115724)
		(end 151.839168 -304.070004)
		(width 0.1143)
		(layer "In9.Cu")
		(net "P5E_PEX1_STN7_RX_DN<115>")
	)
	(segment
		(start 139.838176 -312.444384)
		(end 139.786614 -312.310272)
		(width 0.1651)
		(layer "In9.Cu")
		(net "P5E_PEX1_STN7_RX_DN<115>")
	)
	(segment
		(start 138.818366 -314.493148)
		(end 138.81862 -314.493148)
		(width 0.1651)
		(layer "In9.Cu")
		(net "P5E_PEX1_STN7_RX_DN<115>")
	)
	(segment
		(start 165.00221 -392.719052)
		(end 159.7279 -390.53262)
		(width 0.1651)
		(layer "In9.Cu")
		(net "P5E_PEX1_STN7_RX_DN<115>")
	)
	(segment
		(start 140.471652 -310.76646)
		(end 140.471398 -310.766206)
		(width 0.1651)
		(layer "In9.Cu")
		(net "P5E_PEX1_STN7_RX_DN<115>")
	)
	(segment
		(start 153.334212 -304.202338)
		(end 153.334212 -304.353722)
		(width 0.1143)
		(layer "In9.Cu")
		(net "P5E_PEX1_STN7_RX_DN<115>")
	)
	(segment
		(start 139.987274 -311.857644)
		(end 140.121386 -311.805828)
		(width 0.1651)
		(layer "In9.Cu")
		(net "P5E_PEX1_STN7_RX_DN<115>")
	)
	(segment
		(start 140.806678 -310.261508)
		(end 140.754862 -310.12765)
		(width 0.1651)
		(layer "In9.Cu")
		(net "P5E_PEX1_STN7_RX_DN<115>")
	)
	(segment
		(start 153.2382 -304.449734)
		(end 152.94991 -304.449734)
		(width 0.1143)
		(layer "In9.Cu")
		(net "P5E_PEX1_STN7_RX_DN<115>")
	)
	(segment
		(start 141.044168 -309.475378)
		(end 145.222468 -305.297332)
		(width 0.1651)
		(layer "In9.Cu")
		(net "P5E_PEX1_STN7_RX_DN<115>")
	)
	(segment
		(start 166.509954 -410.208222)
		(end 166.636954 -410.081222)
		(width 0.1651)
		(layer "In9.Cu")
		(net "P5E_PEX1_STN7_RX_DN<115>")
	)
	(segment
		(start 166.975282 -410.081222)
		(end 167.67429 -409.382214)
		(width 0.1651)
		(layer "In9.Cu")
		(net "P5E_PEX1_STN7_RX_DN<115>")
	)
	(segment
		(start 140.471398 -310.766206)
		(end 140.60551 -310.714644)
		(width 0.1651)
		(layer "In9.Cu")
		(net "P5E_PEX1_STN7_RX_DN<115>")
	)
	(segment
		(start 147.976844 -341.313262)
		(end 137.202418 -323.879718)
		(width 0.1651)
		(layer "In9.Cu")
		(net "P5E_PEX1_STN7_RX_DN<115>")
	)
	(segment
		(start 138.385804 -315.718698)
		(end 138.334242 -315.584586)
		(width 0.1651)
		(layer "In9.Cu")
		(net "P5E_PEX1_STN7_RX_DN<115>")
	)
	(segment
		(start 137.202418 -323.879718)
		(end 136.915652 -322.811648)
		(width 0.1651)
		(layer "In9.Cu")
		(net "P5E_PEX1_STN7_RX_DN<115>")
	)
	(segment
		(start 138.334496 -315.584586)
		(end 138.535156 -315.132212)
		(width 0.1651)
		(layer "In9.Cu")
		(net "P5E_PEX1_STN7_RX_DN<115>")
	)
	(segment
		(start 140.60551 -310.714644)
		(end 140.806678 -310.261508)
		(width 0.1651)
		(layer "In9.Cu")
		(net "P5E_PEX1_STN7_RX_DN<115>")
	)
	(segment
		(start 140.270738 -311.218834)
		(end 140.270992 -311.218834)
		(width 0.1651)
		(layer "In9.Cu")
		(net "P5E_PEX1_STN7_RX_DN<115>")
	)
	(segment
		(start 140.270992 -311.218834)
		(end 140.471652 -310.76646)
		(width 0.1651)
		(layer "In9.Cu")
		(net "P5E_PEX1_STN7_RX_DN<115>")
	)
	(segment
		(start 138.051032 -316.22365)
		(end 138.050778 -316.223396)
		(width 0.1651)
		(layer "In9.Cu")
		(net "P5E_PEX1_STN7_RX_DN<115>")
	)
	(segment
		(start 139.354052 -313.535822)
		(end 139.30249 -313.40171)
		(width 0.1651)
		(layer "In9.Cu")
		(net "P5E_PEX1_STN7_RX_DN<115>")
	)
	(segment
		(start 149.008846 -304.115724)
		(end 151.765 -304.115724)
		(width 0.1651)
		(layer "In9.Cu")
		(net "P5E_PEX1_STN7_RX_DN<115>")
	)
	(segment
		(start 151.765 -304.115724)
		(end 151.793448 -304.115724)
		(width 0.1143)
		(layer "In9.Cu")
		(net "P5E_PEX1_STN7_RX_DN<115>")
	)
	(segment
		(start 159.7279 -390.53262)
		(end 156.221938 -387.673342)
		(width 0.1651)
		(layer "In9.Cu")
		(net "P5E_PEX1_STN7_RX_DN<115>")
	)
	(segment
		(start 145.222468 -305.297332)
		(end 149.008846 -304.115724)
		(width 0.1651)
		(layer "In9.Cu")
		(net "P5E_PEX1_STN7_RX_DN<115>")
	)
	(segment
		(start 140.754862 -310.12765)
		(end 141.044168 -309.475378)
		(width 0.1651)
		(layer "In9.Cu")
		(net "P5E_PEX1_STN7_RX_DN<115>")
	)
	(segment
		(start 139.503404 -312.949336)
		(end 139.50315 -312.949082)
		(width 0.1651)
		(layer "In9.Cu")
		(net "P5E_PEX1_STN7_RX_DN<115>")
	)
	(segment
		(start 140.121386 -311.805828)
		(end 140.3223 -311.352946)
		(width 0.1651)
		(layer "In9.Cu")
		(net "P5E_PEX1_STN7_RX_DN<115>")
	)
	(segment
		(start 139.637262 -312.897266)
		(end 139.838176 -312.444384)
		(width 0.1651)
		(layer "In9.Cu")
		(net "P5E_PEX1_STN7_RX_DN<115>")
	)
	(segment
		(start 139.019026 -314.04052)
		(end 139.153138 -313.988704)
		(width 0.1651)
		(layer "In9.Cu")
		(net "P5E_PEX1_STN7_RX_DN<115>")
	)
	(segment
		(start 151.839168 -304.070004)
		(end 153.201878 -304.070004)
		(width 0.1143)
		(layer "In9.Cu")
		(net "P5E_PEX1_STN7_RX_DN<115>")
	)
	(segment
		(start 138.050778 -316.223396)
		(end 138.18489 -316.17158)
		(width 0.1651)
		(layer "In9.Cu")
		(net "P5E_PEX1_STN7_RX_DN<115>")
	)
	(segment
		(start 139.01928 -314.040774)
		(end 139.019026 -314.04052)
		(width 0.1651)
		(layer "In9.Cu")
		(net "P5E_PEX1_STN7_RX_DN<115>")
	)
	(segment
		(start 138.334242 -315.584586)
		(end 138.334496 -315.584586)
		(width 0.1651)
		(layer "In9.Cu")
		(net "P5E_PEX1_STN7_RX_DN<115>")
	)
	(segment
		(start 139.153138 -313.988704)
		(end 139.354052 -313.535822)
		(width 0.1651)
		(layer "In9.Cu")
		(net "P5E_PEX1_STN7_RX_DN<115>")
	)
	(segment
		(start 139.50315 -312.949082)
		(end 139.637262 -312.897266)
		(width 0.1651)
		(layer "In9.Cu")
		(net "P5E_PEX1_STN7_RX_DN<115>")
	)
	(segment
		(start 167.67429 -395.391132)
		(end 165.00221 -392.719052)
		(width 0.1651)
		(layer "In9.Cu")
		(net "P5E_PEX1_STN7_RX_DN<115>")
	)
	(segment
		(start 154.668474 -384.852926)
		(end 149.280372 -344.95232)
		(width 0.1651)
		(layer "In9.Cu")
		(net "P5E_PEX1_STN7_RX_DN<115>")
	)
	(segment
		(start 166.636954 -410.081222)
		(end 166.975282 -410.081222)
		(width 0.1651)
		(layer "In9.Cu")
		(net "P5E_PEX1_STN7_RX_DN<115>")
	)
	(segment
		(start 153.334212 -304.353722)
		(end 153.2382 -304.449734)
		(width 0.1143)
		(layer "In9.Cu")
		(net "P5E_PEX1_STN7_RX_DN<115>")
	)
	(segment
		(start 166.509954 -410.589984)
		(end 166.509954 -410.208222)
		(width 0.1651)
		(layer "In9.Cu")
		(net "P5E_PEX1_STN7_RX_DN<115>")
	)
	(segment
		(start 140.3223 -311.352946)
		(end 140.270738 -311.218834)
		(width 0.1651)
		(layer "In9.Cu")
		(net "P5E_PEX1_STN7_RX_DN<115>")
	)
	(segment
		(start 156.221938 -387.673342)
		(end 154.668474 -384.852926)
		(width 0.1651)
		(layer "In9.Cu")
		(net "P5E_PEX1_STN7_RX_DN<115>")
	)
	(segment
		(start 139.987528 -311.857898)
		(end 139.987274 -311.857644)
		(width 0.1651)
		(layer "In9.Cu")
		(net "P5E_PEX1_STN7_RX_DN<115>")
	)
	(segment
		(start 136.915652 -318.783208)
		(end 138.051032 -316.22365)
		(width 0.1651)
		(layer "In9.Cu")
		(net "P5E_PEX1_STN7_RX_DN<115>")
	)
	(segment
		(start 153.201878 -304.070004)
		(end 153.334212 -304.202338)
		(width 0.1143)
		(layer "In9.Cu")
		(net "P5E_PEX1_STN7_RX_DN<115>")
	)
	(segment
		(start 149.280372 -344.95232)
		(end 147.976844 -341.313262)
		(width 0.1651)
		(layer "In9.Cu")
		(net "P5E_PEX1_STN7_RX_DN<115>")
	)
	(segment
		(start 138.535156 -315.132212)
		(end 138.534902 -315.131958)
		(width 0.1651)
		(layer "In9.Cu")
		(net "P5E_PEX1_STN7_RX_DN<115>")
	)
	(segment
		(start 136.915652 -322.811648)
		(end 136.915652 -318.783208)
		(width 0.1651)
		(layer "In9.Cu")
		(net "P5E_PEX1_STN7_RX_DN<115>")
	)
	(segment
		(start 138.18489 -316.17158)
		(end 138.385804 -315.718698)
		(width 0.1651)
		(layer "In9.Cu")
		(net "P5E_PEX1_STN7_RX_DN<115>")
	)
	(segment
		(start 139.302744 -313.40171)
		(end 139.503404 -312.949336)
		(width 0.1651)
		(layer "In9.Cu")
		(net "P5E_PEX1_STN7_RX_DN<115>")
	)
	(segment
		(start 139.30249 -313.40171)
		(end 139.302744 -313.40171)
		(width 0.1651)
		(layer "In9.Cu")
		(net "P5E_PEX1_STN7_RX_DN<115>")
	)
	(segment
		(start 299.115734 -319.941448)
		(end 299.115734 -319.969896)
		(width 0.1143)
		(layer "In5.Cu")
		(net "P5E_PEX2_STN5_RX_DN<89>")
	)
	(segment
		(start 334.815942 -371.929152)
		(end 334.364076 -372.381018)
		(width 0.1651)
		(layer "In5.Cu")
		(net "P5E_PEX2_STN5_RX_DN<89>")
	)
	(segment
		(start 304.405538 -327.018396)
		(end 304.453036 -327.154032)
		(width 0.1651)
		(layer "In5.Cu")
		(net "P5E_PEX2_STN5_RX_DN<89>")
	)
	(segment
		(start 299.888402 -323.522848)
		(end 302.654716 -326.289162)
		(width 0.1651)
		(layer "In5.Cu")
		(net "P5E_PEX2_STN5_RX_DN<89>")
	)
	(segment
		(start 333.283814 -341.734394)
		(end 333.283814 -358.38003)
		(width 0.1651)
		(layer "In5.Cu")
		(net "P5E_PEX2_STN5_RX_DN<89>")
	)
	(segment
		(start 333.68996 -372.508018)
		(end 333.68996 -372.890034)
		(width 0.1651)
		(layer "In5.Cu")
		(net "P5E_PEX2_STN5_RX_DN<89>")
	)
	(segment
		(start 334.815942 -368.78768)
		(end 334.815942 -371.929152)
		(width 0.1651)
		(layer "In5.Cu")
		(net "P5E_PEX2_STN5_RX_DN<89>")
	)
	(segment
		(start 299.184314 -318.320166)
		(end 299.070014 -318.434466)
		(width 0.1143)
		(layer "In5.Cu")
		(net "P5E_PEX2_STN5_RX_DN<89>")
	)
	(segment
		(start 299.115734 -321.657472)
		(end 299.888402 -323.522848)
		(width 0.1651)
		(layer "In5.Cu")
		(net "P5E_PEX2_STN5_RX_DN<89>")
	)
	(segment
		(start 299.070014 -318.434466)
		(end 299.070014 -319.895728)
		(width 0.1143)
		(layer "In5.Cu")
		(net "P5E_PEX2_STN5_RX_DN<89>")
	)
	(segment
		(start 303.959006 -326.803512)
		(end 304.405538 -327.018396)
		(width 0.1651)
		(layer "In5.Cu")
		(net "P5E_PEX2_STN5_RX_DN<89>")
	)
	(segment
		(start 334.364076 -372.381018)
		(end 333.81696 -372.381018)
		(width 0.1651)
		(layer "In5.Cu")
		(net "P5E_PEX2_STN5_RX_DN<89>")
	)
	(segment
		(start 299.070014 -319.895728)
		(end 299.115734 -319.941448)
		(width 0.1143)
		(layer "In5.Cu")
		(net "P5E_PEX2_STN5_RX_DN<89>")
	)
	(segment
		(start 299.335444 -318.320166)
		(end 299.184314 -318.320166)
		(width 0.1143)
		(layer "In5.Cu")
		(net "P5E_PEX2_STN5_RX_DN<89>")
	)
	(segment
		(start 303.82337 -326.85101)
		(end 303.959006 -326.803512)
		(width 0.1651)
		(layer "In5.Cu")
		(net "P5E_PEX2_STN5_RX_DN<89>")
	)
	(segment
		(start 331.913738 -340.364318)
		(end 333.283814 -341.734394)
		(width 0.1651)
		(layer "In5.Cu")
		(net "P5E_PEX2_STN5_RX_DN<89>")
	)
	(segment
		(start 304.453036 -327.154032)
		(end 331.913738 -340.364318)
		(width 0.1651)
		(layer "In5.Cu")
		(net "P5E_PEX2_STN5_RX_DN<89>")
	)
	(segment
		(start 333.81696 -372.381018)
		(end 333.68996 -372.508018)
		(width 0.1651)
		(layer "In5.Cu")
		(net "P5E_PEX2_STN5_RX_DN<89>")
	)
	(segment
		(start 333.283814 -358.38003)
		(end 334.815942 -368.78768)
		(width 0.1651)
		(layer "In5.Cu")
		(net "P5E_PEX2_STN5_RX_DN<89>")
	)
	(segment
		(start 302.654716 -326.289162)
		(end 303.82337 -326.85101)
		(width 0.1651)
		(layer "In5.Cu")
		(net "P5E_PEX2_STN5_RX_DN<89>")
	)
	(segment
		(start 299.449744 -318.699896)
		(end 299.449744 -318.434466)
		(width 0.1143)
		(layer "In5.Cu")
		(net "P5E_PEX2_STN5_RX_DN<89>")
	)
	(segment
		(start 299.449744 -318.434466)
		(end 299.335444 -318.320166)
		(width 0.1143)
		(layer "In5.Cu")
		(net "P5E_PEX2_STN5_RX_DN<89>")
	)
	(segment
		(start 299.115734 -319.969896)
		(end 299.115734 -321.657472)
		(width 0.1651)
		(layer "In5.Cu")
		(net "P5E_PEX2_STN5_RX_DN<89>")
	)
	(segment
		(start 199.34809 -120.796812)
		(end 199.979534 -120.796812)
		(width 0.13462)
		(layer "F.Cu")
		(net "P5E_PEX1_STN0_TX_DN<1>")
	)
	(segment
		(start 199.02805 -120.476772)
		(end 199.34809 -120.796812)
		(width 0.13462)
		(layer "F.Cu")
		(net "P5E_PEX1_STN0_TX_DN<1>")
	)
	(segment
		(start 199.979534 -120.796812)
		(end 200.274174 -120.502172)
		(width 0.13462)
		(layer "F.Cu")
		(net "P5E_PEX1_STN0_TX_DN<1>")
	)
	(segment
		(start 191.520064 -287.073848)
		(end 191.520064 -287.235646)
		(width 0.1143)
		(layer "In9.Cu")
		(net "P5E_PEX1_STN0_TX_DN<1>")
	)
	(segment
		(start 191.634364 -287.349946)
		(end 191.900048 -287.349946)
		(width 0.1143)
		(layer "In9.Cu")
		(net "P5E_PEX1_STN0_TX_DN<1>")
	)
	(segment
		(start 215.379808 -267.461492)
		(end 215.829642 -272.597372)
		(width 0.1651)
		(layer "In9.Cu")
		(net "P5E_PEX1_STN0_TX_DN<1>")
	)
	(segment
		(start 199.993758 -287.015682)
		(end 199.96531 -287.015682)
		(width 0.1143)
		(layer "In9.Cu")
		(net "P5E_PEX1_STN0_TX_DN<1>")
	)
	(segment
		(start 214.266272 -276.371812)
		(end 204.955648 -285.682436)
		(width 0.1651)
		(layer "In9.Cu")
		(net "P5E_PEX1_STN0_TX_DN<1>")
	)
	(segment
		(start 206.656432 -131.57454)
		(end 215.303862 -152.451308)
		(width 0.1651)
		(layer "In9.Cu")
		(net "P5E_PEX1_STN0_TX_DN<1>")
	)
	(segment
		(start 199.91959 -286.969962)
		(end 191.62395 -286.969962)
		(width 0.1143)
		(layer "In9.Cu")
		(net "P5E_PEX1_STN0_TX_DN<1>")
	)
	(segment
		(start 204.955648 -285.682436)
		(end 201.737214 -287.015682)
		(width 0.1651)
		(layer "In9.Cu")
		(net "P5E_PEX1_STN0_TX_DN<1>")
	)
	(segment
		(start 214.119206 -264.418572)
		(end 215.379808 -267.461492)
		(width 0.1651)
		(layer "In9.Cu")
		(net "P5E_PEX1_STN0_TX_DN<1>")
	)
	(segment
		(start 215.023446 -160.888934)
		(end 206.4004 -175.832008)
		(width 0.1651)
		(layer "In9.Cu")
		(net "P5E_PEX1_STN0_TX_DN<1>")
	)
	(segment
		(start 191.520064 -287.235646)
		(end 191.634364 -287.349946)
		(width 0.1143)
		(layer "In9.Cu")
		(net "P5E_PEX1_STN0_TX_DN<1>")
	)
	(segment
		(start 199.96531 -287.015682)
		(end 199.91959 -286.969962)
		(width 0.1143)
		(layer "In9.Cu")
		(net "P5E_PEX1_STN0_TX_DN<1>")
	)
	(segment
		(start 200.565004 -120.793002)
		(end 201.233786 -120.793002)
		(width 0.1651)
		(layer "In9.Cu")
		(net "P5E_PEX1_STN0_TX_DN<1>")
	)
	(segment
		(start 201.737214 -287.015682)
		(end 199.993758 -287.015682)
		(width 0.1651)
		(layer "In9.Cu")
		(net "P5E_PEX1_STN0_TX_DN<1>")
	)
	(segment
		(start 202.595988 -122.155204)
		(end 206.385922 -131.30403)
		(width 0.1651)
		(layer "In9.Cu")
		(net "P5E_PEX1_STN0_TX_DN<1>")
	)
	(segment
		(start 201.233786 -120.793002)
		(end 202.595988 -122.155204)
		(width 0.1651)
		(layer "In9.Cu")
		(net "P5E_PEX1_STN0_TX_DN<1>")
	)
	(segment
		(start 204.23759 -249.630438)
		(end 214.119206 -264.418572)
		(width 0.1651)
		(layer "In9.Cu")
		(net "P5E_PEX1_STN0_TX_DN<1>")
	)
	(segment
		(start 215.829642 -272.597372)
		(end 214.266272 -276.371812)
		(width 0.1651)
		(layer "In9.Cu")
		(net "P5E_PEX1_STN0_TX_DN<1>")
	)
	(segment
		(start 215.303862 -159.839152)
		(end 215.023446 -160.888934)
		(width 0.1651)
		(layer "In9.Cu")
		(net "P5E_PEX1_STN0_TX_DN<1>")
	)
	(segment
		(start 215.303862 -152.451308)
		(end 215.303862 -159.839152)
		(width 0.1651)
		(layer "In9.Cu")
		(net "P5E_PEX1_STN0_TX_DN<1>")
	)
	(segment
		(start 205.505558 -179.166774)
		(end 201.792332 -221.611444)
		(width 0.1651)
		(layer "In9.Cu")
		(net "P5E_PEX1_STN0_TX_DN<1>")
	)
	(segment
		(start 201.792332 -221.611444)
		(end 204.23759 -249.630438)
		(width 0.1651)
		(layer "In9.Cu")
		(net "P5E_PEX1_STN0_TX_DN<1>")
	)
	(segment
		(start 191.62395 -286.969962)
		(end 191.520064 -287.073848)
		(width 0.1143)
		(layer "In9.Cu")
		(net "P5E_PEX1_STN0_TX_DN<1>")
	)
	(segment
		(start 206.385922 -131.30403)
		(end 206.656432 -131.57454)
		(width 0.1651)
		(layer "In9.Cu")
		(net "P5E_PEX1_STN0_TX_DN<1>")
	)
	(segment
		(start 200.274174 -120.502172)
		(end 200.565004 -120.793002)
		(width 0.1651)
		(layer "In9.Cu")
		(net "P5E_PEX1_STN0_TX_DN<1>")
	)
	(segment
		(start 206.4004 -175.832008)
		(end 205.505558 -179.166774)
		(width 0.1651)
		(layer "In9.Cu")
		(net "P5E_PEX1_STN0_TX_DN<1>")
	)
	(segment
		(start 187.626752 -355.002846)
		(end 187.921392 -354.708206)
		(width 0.13462)
		(layer "F.Cu")
		(net "P5E_PEX1_STN7_TX_DN<125>")
	)
	(segment
		(start 187.626752 -355.63429)
		(end 187.626752 -355.002846)
		(width 0.13462)
		(layer "F.Cu")
		(net "P5E_PEX1_STN7_TX_DN<125>")
	)
	(segment
		(start 187.946792 -355.95433)
		(end 187.626752 -355.63429)
		(width 0.13462)
		(layer "F.Cu")
		(net "P5E_PEX1_STN7_TX_DN<125>")
	)
	(segment
		(start 156.661104 -313.570112)
		(end 156.535374 -313.570112)
		(width 0.1143)
		(layer "In11.Cu")
		(net "P5E_PEX1_STN7_TX_DN<125>")
	)
	(segment
		(start 189.185042 -352.218244)
		(end 187.630562 -353.772724)
		(width 0.1651)
		(layer "In11.Cu")
		(net "P5E_PEX1_STN7_TX_DN<125>")
	)
	(segment
		(start 189.185042 -340.87562)
		(end 189.185042 -352.218244)
		(width 0.1651)
		(layer "In11.Cu")
		(net "P5E_PEX1_STN7_TX_DN<125>")
	)
	(segment
		(start 156.750004 -313.659012)
		(end 156.661104 -313.570112)
		(width 0.1143)
		(layer "In11.Cu")
		(net "P5E_PEX1_STN7_TX_DN<125>")
	)
	(segment
		(start 187.630562 -353.772724)
		(end 187.630562 -354.417376)
		(width 0.1651)
		(layer "In11.Cu")
		(net "P5E_PEX1_STN7_TX_DN<125>")
	)
	(segment
		(start 156.370274 -319.97523)
		(end 156.415994 -320.02095)
		(width 0.1143)
		(layer "In11.Cu")
		(net "P5E_PEX1_STN7_TX_DN<125>")
	)
	(segment
		(start 188.768228 -340.320376)
		(end 189.185042 -340.87562)
		(width 0.1651)
		(layer "In11.Cu")
		(net "P5E_PEX1_STN7_TX_DN<125>")
	)
	(segment
		(start 180.267356 -334.975708)
		(end 185.657998 -338.081874)
		(width 0.1651)
		(layer "In11.Cu")
		(net "P5E_PEX1_STN7_TX_DN<125>")
	)
	(segment
		(start 156.750004 -313.949842)
		(end 156.750004 -313.659012)
		(width 0.1143)
		(layer "In11.Cu")
		(net "P5E_PEX1_STN7_TX_DN<125>")
	)
	(segment
		(start 156.415994 -321.105022)
		(end 156.694632 -321.79895)
		(width 0.1651)
		(layer "In11.Cu")
		(net "P5E_PEX1_STN7_TX_DN<125>")
	)
	(segment
		(start 156.415994 -320.043048)
		(end 156.415994 -321.105022)
		(width 0.1651)
		(layer "In11.Cu")
		(net "P5E_PEX1_STN7_TX_DN<125>")
	)
	(segment
		(start 174.88281 -331.873098)
		(end 180.267102 -334.975708)
		(width 0.1651)
		(layer "In11.Cu")
		(net "P5E_PEX1_STN7_TX_DN<125>")
	)
	(segment
		(start 156.535374 -313.570112)
		(end 156.370274 -313.735212)
		(width 0.1143)
		(layer "In11.Cu")
		(net "P5E_PEX1_STN7_TX_DN<125>")
	)
	(segment
		(start 180.267102 -334.975708)
		(end 180.267356 -334.975708)
		(width 0.1651)
		(layer "In11.Cu")
		(net "P5E_PEX1_STN7_TX_DN<125>")
	)
	(segment
		(start 156.370274 -313.735212)
		(end 156.370274 -319.97523)
		(width 0.1143)
		(layer "In11.Cu")
		(net "P5E_PEX1_STN7_TX_DN<125>")
	)
	(segment
		(start 156.694632 -321.79895)
		(end 157.982412 -323.14388)
		(width 0.1651)
		(layer "In11.Cu")
		(net "P5E_PEX1_STN7_TX_DN<125>")
	)
	(segment
		(start 156.415994 -320.02095)
		(end 156.415994 -320.043048)
		(width 0.1143)
		(layer "In11.Cu")
		(net "P5E_PEX1_STN7_TX_DN<125>")
	)
	(segment
		(start 187.630562 -354.417376)
		(end 187.921392 -354.708206)
		(width 0.1651)
		(layer "In11.Cu")
		(net "P5E_PEX1_STN7_TX_DN<125>")
	)
	(segment
		(start 157.982412 -323.14388)
		(end 174.88281 -331.873098)
		(width 0.1651)
		(layer "In11.Cu")
		(net "P5E_PEX1_STN7_TX_DN<125>")
	)
	(segment
		(start 185.657998 -338.081874)
		(end 188.768228 -340.320376)
		(width 0.1651)
		(layer "In11.Cu")
		(net "P5E_PEX1_STN7_TX_DN<125>")
	)
	(segment
		(start 147.72386 -366.662716)
		(end 152.720802 -353.478592)
		(width 0.1651)
		(layer "In5.Cu")
		(net "P5E_PEX1_STN5_RX_DN<84>")
	)
	(segment
		(start 178.599846 -316.534292)
		(end 178.599846 -316.799722)
		(width 0.1143)
		(layer "In5.Cu")
		(net "P5E_PEX1_STN5_RX_DN<84>")
	)
	(segment
		(start 139.30249 -389.306054)
		(end 140.224256 -387.757924)
		(width 0.1651)
		(layer "In5.Cu")
		(net "P5E_PEX1_STN5_RX_DN<84>")
	)
	(segment
		(start 131.414012 -392.190224)
		(end 131.414266 -392.190224)
		(width 0.1651)
		(layer "In5.Cu")
		(net "P5E_PEX1_STN5_RX_DN<84>")
	)
	(segment
		(start 174.965868 -329.089766)
		(end 177.10531 -326.949816)
		(width 0.1651)
		(layer "In5.Cu")
		(net "P5E_PEX1_STN5_RX_DN<84>")
	)
	(segment
		(start 178.265836 -323.718174)
		(end 178.265836 -319.91173)
		(width 0.1651)
		(layer "In5.Cu")
		(net "P5E_PEX1_STN5_RX_DN<84>")
	)
	(segment
		(start 124.71019 -397.408146)
		(end 124.83719 -397.281146)
		(width 0.1651)
		(layer "In5.Cu")
		(net "P5E_PEX1_STN5_RX_DN<84>")
	)
	(segment
		(start 140.224256 -387.757924)
		(end 146.515328 -370.93144)
		(width 0.1651)
		(layer "In5.Cu")
		(net "P5E_PEX1_STN5_RX_DN<84>")
	)
	(segment
		(start 177.10531 -326.949816)
		(end 177.828448 -325.205852)
		(width 0.1651)
		(layer "In5.Cu")
		(net "P5E_PEX1_STN5_RX_DN<84>")
	)
	(segment
		(start 125.769624 -396.898368)
		(end 125.769624 -396.240508)
		(width 0.1651)
		(layer "In5.Cu")
		(net "P5E_PEX1_STN5_RX_DN<84>")
	)
	(segment
		(start 178.265836 -319.883282)
		(end 178.220116 -319.837562)
		(width 0.1143)
		(layer "In5.Cu")
		(net "P5E_PEX1_STN5_RX_DN<84>")
	)
	(segment
		(start 161.989516 -336.726784)
		(end 174.965868 -329.089766)
		(width 0.1651)
		(layer "In5.Cu")
		(net "P5E_PEX1_STN5_RX_DN<84>")
	)
	(segment
		(start 178.334416 -316.419992)
		(end 178.485546 -316.419992)
		(width 0.1143)
		(layer "In5.Cu")
		(net "P5E_PEX1_STN5_RX_DN<84>")
	)
	(segment
		(start 131.414266 -392.190224)
		(end 133.05282 -391.550906)
		(width 0.1651)
		(layer "In5.Cu")
		(net "P5E_PEX1_STN5_RX_DN<84>")
	)
	(segment
		(start 178.220116 -319.837562)
		(end 178.220116 -316.534292)
		(width 0.1143)
		(layer "In5.Cu")
		(net "P5E_PEX1_STN5_RX_DN<84>")
	)
	(segment
		(start 178.485546 -316.419992)
		(end 178.599846 -316.534292)
		(width 0.1143)
		(layer "In5.Cu")
		(net "P5E_PEX1_STN5_RX_DN<84>")
	)
	(segment
		(start 177.828448 -325.205852)
		(end 178.265836 -323.718174)
		(width 0.1651)
		(layer "In5.Cu")
		(net "P5E_PEX1_STN5_RX_DN<84>")
	)
	(segment
		(start 133.05282 -391.550906)
		(end 137.324846 -390.700006)
		(width 0.1651)
		(layer "In5.Cu")
		(net "P5E_PEX1_STN5_RX_DN<84>")
	)
	(segment
		(start 129.775204 -392.829796)
		(end 131.414012 -392.190224)
		(width 0.1651)
		(layer "In5.Cu")
		(net "P5E_PEX1_STN5_RX_DN<84>")
	)
	(segment
		(start 128.000506 -393.918694)
		(end 129.775204 -392.829796)
		(width 0.1651)
		(layer "In5.Cu")
		(net "P5E_PEX1_STN5_RX_DN<84>")
	)
	(segment
		(start 124.71019 -397.790162)
		(end 124.71019 -397.408146)
		(width 0.1651)
		(layer "In5.Cu")
		(net "P5E_PEX1_STN5_RX_DN<84>")
	)
	(segment
		(start 125.386846 -397.281146)
		(end 125.769624 -396.898368)
		(width 0.1651)
		(layer "In5.Cu")
		(net "P5E_PEX1_STN5_RX_DN<84>")
	)
	(segment
		(start 146.515328 -370.93144)
		(end 147.72386 -366.662716)
		(width 0.1651)
		(layer "In5.Cu")
		(net "P5E_PEX1_STN5_RX_DN<84>")
	)
	(segment
		(start 124.83719 -397.281146)
		(end 125.386846 -397.281146)
		(width 0.1651)
		(layer "In5.Cu")
		(net "P5E_PEX1_STN5_RX_DN<84>")
	)
	(segment
		(start 152.720802 -353.478592)
		(end 159.990536 -338.96046)
		(width 0.1651)
		(layer "In5.Cu")
		(net "P5E_PEX1_STN5_RX_DN<84>")
	)
	(segment
		(start 125.769624 -396.240508)
		(end 128.000506 -393.918694)
		(width 0.1651)
		(layer "In5.Cu")
		(net "P5E_PEX1_STN5_RX_DN<84>")
	)
	(segment
		(start 159.990536 -338.96046)
		(end 161.989516 -336.726784)
		(width 0.1651)
		(layer "In5.Cu")
		(net "P5E_PEX1_STN5_RX_DN<84>")
	)
	(segment
		(start 178.265836 -319.91173)
		(end 178.265836 -319.883282)
		(width 0.1143)
		(layer "In5.Cu")
		(net "P5E_PEX1_STN5_RX_DN<84>")
	)
	(segment
		(start 178.220116 -316.534292)
		(end 178.334416 -316.419992)
		(width 0.1143)
		(layer "In5.Cu")
		(net "P5E_PEX1_STN5_RX_DN<84>")
	)
	(segment
		(start 137.324846 -390.700006)
		(end 139.30249 -389.306054)
		(width 0.1651)
		(layer "In5.Cu")
		(net "P5E_PEX1_STN5_RX_DN<84>")
	)
	(segment
		(start 296.907204 -341.005414)
		(end 297.426634 -341.60968)
		(width 0.1651)
		(layer "In5.Cu")
		(net "P5E_PEX2_STN7_RX_DP<125>")
	)
	(segment
		(start 298.739814 -366.057942)
		(end 298.826682 -366.545876)
		(width 0.1651)
		(layer "In5.Cu")
		(net "P5E_PEX2_STN7_RX_DP<125>")
	)
	(segment
		(start 298.745656 -365.437928)
		(end 298.83227 -365.925354)
		(width 0.1651)
		(layer "In5.Cu")
		(net "P5E_PEX2_STN7_RX_DP<125>")
	)
	(segment
		(start 298.616878 -383.79908)
		(end 298.489878 -383.67208)
		(width 0.1651)
		(layer "In5.Cu")
		(net "P5E_PEX2_STN7_RX_DP<125>")
	)
	(segment
		(start 298.83227 -365.925354)
		(end 298.739814 -366.057942)
		(width 0.1651)
		(layer "In5.Cu")
		(net "P5E_PEX2_STN7_RX_DP<125>")
	)
	(segment
		(start 272.233898 -325.455788)
		(end 272.506186 -326.16648)
		(width 0.1651)
		(layer "In5.Cu")
		(net "P5E_PEX2_STN7_RX_DP<125>")
	)
	(segment
		(start 298.612814 -365.345218)
		(end 298.745656 -365.437928)
		(width 0.1651)
		(layer "In5.Cu")
		(net "P5E_PEX2_STN7_RX_DP<125>")
	)
	(segment
		(start 297.723052 -342.428068)
		(end 297.723052 -359.689654)
		(width 0.1651)
		(layer "In5.Cu")
		(net "P5E_PEX2_STN7_RX_DP<125>")
	)
	(segment
		(start 297.723052 -359.689654)
		(end 298.618656 -364.72495)
		(width 0.1651)
		(layer "In5.Cu")
		(net "P5E_PEX2_STN7_RX_DP<125>")
	)
	(segment
		(start 277.122128 -330.26858)
		(end 296.907204 -341.005414)
		(width 0.1651)
		(layer "In5.Cu")
		(net "P5E_PEX2_STN7_RX_DP<125>")
	)
	(segment
		(start 272.279618 -318.355472)
		(end 272.279618 -319.96888)
		(width 0.1143)
		(layer "In5.Cu")
		(net "P5E_PEX2_STN7_RX_DP<125>")
	)
	(segment
		(start 297.426634 -341.60968)
		(end 297.723052 -342.428068)
		(width 0.1651)
		(layer "In5.Cu")
		(net "P5E_PEX2_STN7_RX_DP<125>")
	)
	(segment
		(start 298.489878 -383.67208)
		(end 298.489878 -383.290064)
		(width 0.1651)
		(layer "In5.Cu")
		(net "P5E_PEX2_STN7_RX_DP<125>")
	)
	(segment
		(start 298.826682 -366.545876)
		(end 298.959524 -366.638332)
		(width 0.1651)
		(layer "In5.Cu")
		(net "P5E_PEX2_STN7_RX_DP<125>")
	)
	(segment
		(start 272.849848 -318.015366)
		(end 272.735548 -318.129666)
		(width 0.1143)
		(layer "In5.Cu")
		(net "P5E_PEX2_STN7_RX_DP<125>")
	)
	(segment
		(start 298.959524 -366.638332)
		(end 298.95927 -366.638332)
		(width 0.1651)
		(layer "In5.Cu")
		(net "P5E_PEX2_STN7_RX_DP<125>")
	)
	(segment
		(start 272.505424 -318.129666)
		(end 272.279618 -318.355472)
		(width 0.1143)
		(layer "In5.Cu")
		(net "P5E_PEX2_STN7_RX_DP<125>")
	)
	(segment
		(start 272.849848 -317.749936)
		(end 272.849848 -318.015366)
		(width 0.1143)
		(layer "In5.Cu")
		(net "P5E_PEX2_STN7_RX_DP<125>")
	)
	(segment
		(start 272.279618 -319.96888)
		(end 272.233898 -320.0146)
		(width 0.1143)
		(layer "In5.Cu")
		(net "P5E_PEX2_STN7_RX_DP<125>")
	)
	(segment
		(start 272.506186 -326.16648)
		(end 274.384262 -328.413618)
		(width 0.1651)
		(layer "In5.Cu")
		(net "P5E_PEX2_STN7_RX_DP<125>")
	)
	(segment
		(start 274.384262 -328.413618)
		(end 277.122128 -330.26858)
		(width 0.1651)
		(layer "In5.Cu")
		(net "P5E_PEX2_STN7_RX_DP<125>")
	)
	(segment
		(start 299.33392 -368.743738)
		(end 299.33392 -383.512314)
		(width 0.1651)
		(layer "In5.Cu")
		(net "P5E_PEX2_STN7_RX_DP<125>")
	)
	(segment
		(start 272.233898 -320.043048)
		(end 272.233898 -325.455788)
		(width 0.1651)
		(layer "In5.Cu")
		(net "P5E_PEX2_STN7_RX_DP<125>")
	)
	(segment
		(start 298.618656 -364.72495)
		(end 298.5262 -364.857538)
		(width 0.1651)
		(layer "In5.Cu")
		(net "P5E_PEX2_STN7_RX_DP<125>")
	)
	(segment
		(start 272.735548 -318.129666)
		(end 272.505424 -318.129666)
		(width 0.1143)
		(layer "In5.Cu")
		(net "P5E_PEX2_STN7_RX_DP<125>")
	)
	(segment
		(start 272.233898 -320.0146)
		(end 272.233898 -320.043048)
		(width 0.1143)
		(layer "In5.Cu")
		(net "P5E_PEX2_STN7_RX_DP<125>")
	)
	(segment
		(start 298.95927 -366.638332)
		(end 299.33392 -368.743738)
		(width 0.1651)
		(layer "In5.Cu")
		(net "P5E_PEX2_STN7_RX_DP<125>")
	)
	(segment
		(start 299.047154 -383.79908)
		(end 298.616878 -383.79908)
		(width 0.1651)
		(layer "In5.Cu")
		(net "P5E_PEX2_STN7_RX_DP<125>")
	)
	(segment
		(start 298.5262 -364.857538)
		(end 298.612814 -365.345218)
		(width 0.1651)
		(layer "In5.Cu")
		(net "P5E_PEX2_STN7_RX_DP<125>")
	)
	(segment
		(start 299.33392 -383.512314)
		(end 299.047154 -383.79908)
		(width 0.1651)
		(layer "In5.Cu")
		(net "P5E_PEX2_STN7_RX_DP<125>")
	)
	(segment
		(start 154.162252 -99.883214)
		(end 153.867612 -100.177854)
		(width 0.13462)
		(layer "F.Cu")
		(net "P5E_PEX1_STN1_TX_DN<16>")
	)
	(segment
		(start 155.113736 -100.203254)
		(end 154.793696 -99.883214)
		(width 0.13462)
		(layer "F.Cu")
		(net "P5E_PEX1_STN1_TX_DN<16>")
	)
	(segment
		(start 154.793696 -99.883214)
		(end 154.162252 -99.883214)
		(width 0.13462)
		(layer "F.Cu")
		(net "P5E_PEX1_STN1_TX_DN<16>")
	)
	(segment
		(start 151.459184 -100.4062)
		(end 151.309832 -100.344224)
		(width 0.1651)
		(layer "In9.Cu")
		(net "P5E_PEX1_STN1_TX_DN<16>")
	)
	(segment
		(start 144.54886 -106.358944)
		(end 144.340072 -106.863896)
		(width 0.1651)
		(layer "In9.Cu")
		(net "P5E_PEX1_STN1_TX_DN<16>")
	)
	(segment
		(start 148.284946 -102.784656)
		(end 148.123402 -102.784656)
		(width 0.1651)
		(layer "In9.Cu")
		(net "P5E_PEX1_STN1_TX_DN<16>")
	)
	(segment
		(start 145.590514 -105.317544)
		(end 144.54886 -106.358944)
		(width 0.1651)
		(layer "In9.Cu")
		(net "P5E_PEX1_STN1_TX_DN<16>")
	)
	(segment
		(start 153.576782 -99.887024)
		(end 152.414224 -99.887024)
		(width 0.1651)
		(layer "In9.Cu")
		(net "P5E_PEX1_STN1_TX_DN<16>")
	)
	(segment
		(start 146.43481 -104.473248)
		(end 146.093688 -104.81437)
		(width 0.1651)
		(layer "In9.Cu")
		(net "P5E_PEX1_STN1_TX_DN<16>")
	)
	(segment
		(start 142.454884 -111.415068)
		(end 136.58723 -130.75666)
		(width 0.1651)
		(layer "In9.Cu")
		(net "P5E_PEX1_STN1_TX_DN<16>")
	)
	(segment
		(start 149.470618 -101.598984)
		(end 149.129242 -101.94036)
		(width 0.1651)
		(layer "In9.Cu")
		(net "P5E_PEX1_STN1_TX_DN<16>")
	)
	(segment
		(start 146.596354 -104.473248)
		(end 146.43481 -104.473248)
		(width 0.1651)
		(layer "In9.Cu")
		(net "P5E_PEX1_STN1_TX_DN<16>")
	)
	(segment
		(start 139.895834 -159.841184)
		(end 140.452856 -162.641534)
		(width 0.1651)
		(layer "In9.Cu")
		(net "P5E_PEX1_STN1_TX_DN<16>")
	)
	(segment
		(start 175.473614 -278.229568)
		(end 175.635412 -278.229568)
		(width 0.1143)
		(layer "In9.Cu")
		(net "P5E_PEX1_STN1_TX_DN<16>")
	)
	(segment
		(start 152.414224 -99.887024)
		(end 151.967184 -100.071936)
		(width 0.1651)
		(layer "In9.Cu")
		(net "P5E_PEX1_STN1_TX_DN<16>")
	)
	(segment
		(start 147.78228 -103.287322)
		(end 147.44065 -103.628952)
		(width 0.1651)
		(layer "In9.Cu")
		(net "P5E_PEX1_STN1_TX_DN<16>")
	)
	(segment
		(start 136.58723 -130.75666)
		(end 136.58723 -139.08786)
		(width 0.1651)
		(layer "In9.Cu")
		(net "P5E_PEX1_STN1_TX_DN<16>")
	)
	(segment
		(start 146.937984 -104.131618)
		(end 146.596354 -104.473248)
		(width 0.1651)
		(layer "In9.Cu")
		(net "P5E_PEX1_STN1_TX_DN<16>")
	)
	(segment
		(start 149.129242 -101.94036)
		(end 148.967698 -101.94036)
		(width 0.1651)
		(layer "In9.Cu")
		(net "P5E_PEX1_STN1_TX_DN<16>")
	)
	(segment
		(start 175.415956 -265.937492)
		(end 175.415956 -271.471898)
		(width 0.1651)
		(layer "In9.Cu")
		(net "P5E_PEX1_STN1_TX_DN<16>")
	)
	(segment
		(start 147.279106 -103.628952)
		(end 146.937984 -103.970074)
		(width 0.1651)
		(layer "In9.Cu")
		(net "P5E_PEX1_STN1_TX_DN<16>")
	)
	(segment
		(start 175.370236 -271.546066)
		(end 175.370236 -278.12619)
		(width 0.1143)
		(layer "In9.Cu")
		(net "P5E_PEX1_STN1_TX_DN<16>")
	)
	(segment
		(start 175.749712 -278.115268)
		(end 175.749712 -277.849838)
		(width 0.1143)
		(layer "In9.Cu")
		(net "P5E_PEX1_STN1_TX_DN<16>")
	)
	(segment
		(start 148.626576 -102.281482)
		(end 148.626576 -102.443026)
		(width 0.1651)
		(layer "In9.Cu")
		(net "P5E_PEX1_STN1_TX_DN<16>")
	)
	(segment
		(start 136.58723 -139.08786)
		(end 139.184888 -145.35912)
		(width 0.1651)
		(layer "In9.Cu")
		(net "P5E_PEX1_STN1_TX_DN<16>")
	)
	(segment
		(start 143.751554 -108.583984)
		(end 143.601948 -108.645706)
		(width 0.1651)
		(layer "In9.Cu")
		(net "P5E_PEX1_STN1_TX_DN<16>")
	)
	(segment
		(start 175.370236 -278.12619)
		(end 175.473614 -278.229568)
		(width 0.1143)
		(layer "In9.Cu")
		(net "P5E_PEX1_STN1_TX_DN<16>")
	)
	(segment
		(start 148.626576 -102.443026)
		(end 148.284946 -102.784656)
		(width 0.1651)
		(layer "In9.Cu")
		(net "P5E_PEX1_STN1_TX_DN<16>")
	)
	(segment
		(start 148.967698 -101.94036)
		(end 148.626576 -102.281482)
		(width 0.1651)
		(layer "In9.Cu")
		(net "P5E_PEX1_STN1_TX_DN<16>")
	)
	(segment
		(start 139.184888 -145.35912)
		(end 139.895834 -159.841184)
		(width 0.1651)
		(layer "In9.Cu")
		(net "P5E_PEX1_STN1_TX_DN<16>")
	)
	(segment
		(start 149.470618 -101.43744)
		(end 149.470618 -101.598984)
		(width 0.1651)
		(layer "In9.Cu")
		(net "P5E_PEX1_STN1_TX_DN<16>")
	)
	(segment
		(start 175.635412 -278.229568)
		(end 175.749712 -278.115268)
		(width 0.1143)
		(layer "In9.Cu")
		(net "P5E_PEX1_STN1_TX_DN<16>")
	)
	(segment
		(start 175.415956 -271.471898)
		(end 175.415956 -271.500346)
		(width 0.1143)
		(layer "In9.Cu")
		(net "P5E_PEX1_STN1_TX_DN<16>")
	)
	(segment
		(start 151.309832 -100.344224)
		(end 150.03653 -100.871528)
		(width 0.1651)
		(layer "In9.Cu")
		(net "P5E_PEX1_STN1_TX_DN<16>")
	)
	(segment
		(start 146.937984 -103.970074)
		(end 146.937984 -104.131618)
		(width 0.1651)
		(layer "In9.Cu")
		(net "P5E_PEX1_STN1_TX_DN<16>")
	)
	(segment
		(start 140.452856 -162.641534)
		(end 175.415956 -265.937492)
		(width 0.1651)
		(layer "In9.Cu")
		(net "P5E_PEX1_STN1_TX_DN<16>")
	)
	(segment
		(start 175.415956 -271.500346)
		(end 175.370236 -271.546066)
		(width 0.1143)
		(layer "In9.Cu")
		(net "P5E_PEX1_STN1_TX_DN<16>")
	)
	(segment
		(start 143.601948 -108.645706)
		(end 142.454884 -111.415068)
		(width 0.1651)
		(layer "In9.Cu")
		(net "P5E_PEX1_STN1_TX_DN<16>")
	)
	(segment
		(start 147.44065 -103.628952)
		(end 147.279106 -103.628952)
		(width 0.1651)
		(layer "In9.Cu")
		(net "P5E_PEX1_STN1_TX_DN<16>")
	)
	(segment
		(start 143.874236 -107.988354)
		(end 143.936212 -108.137706)
		(width 0.1651)
		(layer "In9.Cu")
		(net "P5E_PEX1_STN1_TX_DN<16>")
	)
	(segment
		(start 144.402048 -107.013248)
		(end 144.21739 -107.459272)
		(width 0.1651)
		(layer "In9.Cu")
		(net "P5E_PEX1_STN1_TX_DN<16>")
	)
	(segment
		(start 144.340072 -106.863896)
		(end 144.402048 -107.013248)
		(width 0.1651)
		(layer "In9.Cu")
		(net "P5E_PEX1_STN1_TX_DN<16>")
	)
	(segment
		(start 146.093688 -104.81437)
		(end 146.093688 -104.975914)
		(width 0.1651)
		(layer "In9.Cu")
		(net "P5E_PEX1_STN1_TX_DN<16>")
	)
	(segment
		(start 148.123402 -102.784656)
		(end 147.78228 -103.125778)
		(width 0.1651)
		(layer "In9.Cu")
		(net "P5E_PEX1_STN1_TX_DN<16>")
	)
	(segment
		(start 151.967184 -100.071936)
		(end 151.905462 -100.221542)
		(width 0.1651)
		(layer "In9.Cu")
		(net "P5E_PEX1_STN1_TX_DN<16>")
	)
	(segment
		(start 144.21739 -107.459272)
		(end 144.067784 -107.521248)
		(width 0.1651)
		(layer "In9.Cu")
		(net "P5E_PEX1_STN1_TX_DN<16>")
	)
	(segment
		(start 144.067784 -107.521248)
		(end 143.874236 -107.988354)
		(width 0.1651)
		(layer "In9.Cu")
		(net "P5E_PEX1_STN1_TX_DN<16>")
	)
	(segment
		(start 146.093688 -104.975914)
		(end 145.752058 -105.317544)
		(width 0.1651)
		(layer "In9.Cu")
		(net "P5E_PEX1_STN1_TX_DN<16>")
	)
	(segment
		(start 151.905462 -100.221542)
		(end 151.459184 -100.4062)
		(width 0.1651)
		(layer "In9.Cu")
		(net "P5E_PEX1_STN1_TX_DN<16>")
	)
	(segment
		(start 153.867612 -100.177854)
		(end 153.576782 -99.887024)
		(width 0.1651)
		(layer "In9.Cu")
		(net "P5E_PEX1_STN1_TX_DN<16>")
	)
	(segment
		(start 143.936212 -108.137706)
		(end 143.751554 -108.583984)
		(width 0.1651)
		(layer "In9.Cu")
		(net "P5E_PEX1_STN1_TX_DN<16>")
	)
	(segment
		(start 145.752058 -105.317544)
		(end 145.590514 -105.317544)
		(width 0.1651)
		(layer "In9.Cu")
		(net "P5E_PEX1_STN1_TX_DN<16>")
	)
	(segment
		(start 147.78228 -103.125778)
		(end 147.78228 -103.287322)
		(width 0.1651)
		(layer "In9.Cu")
		(net "P5E_PEX1_STN1_TX_DN<16>")
	)
	(segment
		(start 150.03653 -100.871528)
		(end 149.470618 -101.43744)
		(width 0.1651)
		(layer "In9.Cu")
		(net "P5E_PEX1_STN1_TX_DN<16>")
	)
	(segment
		(start 115.540028 -342.734138)
		(end 115.834668 -342.439498)
		(width 0.13462)
		(layer "F.Cu")
		(net "P5E_PEX1_STN6_TX_DN<102>")
	)
	(segment
		(start 115.860068 -343.685622)
		(end 115.540028 -343.365582)
		(width 0.13462)
		(layer "F.Cu")
		(net "P5E_PEX1_STN6_TX_DN<102>")
	)
	(segment
		(start 115.540028 -343.365582)
		(end 115.540028 -342.734138)
		(width 0.13462)
		(layer "F.Cu")
		(net "P5E_PEX1_STN6_TX_DN<102>")
	)
	(segment
		(start 167.770302 -319.442592)
		(end 167.770302 -313.684412)
		(width 0.1143)
		(layer "In7.Cu")
		(net "P5E_PEX1_STN6_TX_DN<102>")
	)
	(segment
		(start 167.884602 -313.570112)
		(end 168.035732 -313.570112)
		(width 0.1143)
		(layer "In7.Cu")
		(net "P5E_PEX1_STN6_TX_DN<102>")
	)
	(segment
		(start 116.047774 -340.693756)
		(end 130.364484 -332.11262)
		(width 0.1651)
		(layer "In7.Cu")
		(net "P5E_PEX1_STN6_TX_DN<102>")
	)
	(segment
		(start 168.150032 -313.684412)
		(end 168.150032 -313.949842)
		(width 0.1143)
		(layer "In7.Cu")
		(net "P5E_PEX1_STN6_TX_DN<102>")
	)
	(segment
		(start 167.770302 -313.684412)
		(end 167.884602 -313.570112)
		(width 0.1143)
		(layer "In7.Cu")
		(net "P5E_PEX1_STN6_TX_DN<102>")
	)
	(segment
		(start 165.964616 -321.31254)
		(end 167.345614 -319.931542)
		(width 0.1651)
		(layer "In7.Cu")
		(net "P5E_PEX1_STN6_TX_DN<102>")
	)
	(segment
		(start 167.365426 -319.847468)
		(end 167.770302 -319.442592)
		(width 0.1143)
		(layer "In7.Cu")
		(net "P5E_PEX1_STN6_TX_DN<102>")
	)
	(segment
		(start 168.035732 -313.570112)
		(end 168.150032 -313.684412)
		(width 0.1143)
		(layer "In7.Cu")
		(net "P5E_PEX1_STN6_TX_DN<102>")
	)
	(segment
		(start 115.543838 -342.148668)
		(end 115.543838 -341.197692)
		(width 0.1651)
		(layer "In7.Cu")
		(net "P5E_PEX1_STN6_TX_DN<102>")
	)
	(segment
		(start 115.543838 -341.197692)
		(end 116.047774 -340.693756)
		(width 0.1651)
		(layer "In7.Cu")
		(net "P5E_PEX1_STN6_TX_DN<102>")
	)
	(segment
		(start 130.364484 -332.11262)
		(end 165.964616 -321.31254)
		(width 0.1651)
		(layer "In7.Cu")
		(net "P5E_PEX1_STN6_TX_DN<102>")
	)
	(segment
		(start 167.36568 -319.911476)
		(end 167.365426 -319.847468)
		(width 0.1143)
		(layer "In7.Cu")
		(net "P5E_PEX1_STN6_TX_DN<102>")
	)
	(segment
		(start 167.345614 -319.931542)
		(end 167.36568 -319.911476)
		(width 0.1143)
		(layer "In7.Cu")
		(net "P5E_PEX1_STN6_TX_DN<102>")
	)
	(segment
		(start 115.834668 -342.439498)
		(end 115.543838 -342.148668)
		(width 0.1651)
		(layer "In7.Cu")
		(net "P5E_PEX1_STN6_TX_DN<102>")
	)
	(segment
		(start 129.887472 -396.781528)
		(end 129.887472 -395.892782)
		(width 0.1651)
		(layer "In5.Cu")
		(net "P5E_PEX1_STN5_RX_DP<86>")
	)
	(segment
		(start 129.237232 -396.999206)
		(end 129.669794 -396.999206)
		(width 0.1651)
		(layer "In5.Cu")
		(net "P5E_PEX1_STN5_RX_DP<86>")
	)
	(segment
		(start 161.376868 -339.880702)
		(end 162.617912 -338.492592)
		(width 0.1651)
		(layer "In5.Cu")
		(net "P5E_PEX1_STN5_RX_DP<86>")
	)
	(segment
		(start 180.38572 -316.229492)
		(end 180.50002 -316.115192)
		(width 0.1143)
		(layer "In5.Cu")
		(net "P5E_PEX1_STN5_RX_DP<86>")
	)
	(segment
		(start 178.590702 -327.787254)
		(end 179.307236 -326.05853)
		(width 0.1651)
		(layer "In5.Cu")
		(net "P5E_PEX1_STN5_RX_DP<86>")
	)
	(segment
		(start 129.109978 -396.871952)
		(end 129.237232 -396.999206)
		(width 0.1651)
		(layer "In5.Cu")
		(net "P5E_PEX1_STN5_RX_DP<86>")
	)
	(segment
		(start 130.228594 -395.55166)
		(end 130.228594 -395.42466)
		(width 0.1651)
		(layer "In5.Cu")
		(net "P5E_PEX1_STN5_RX_DP<86>")
	)
	(segment
		(start 129.109978 -396.49019)
		(end 129.109978 -396.871952)
		(width 0.1651)
		(layer "In5.Cu")
		(net "P5E_PEX1_STN5_RX_DP<86>")
	)
	(segment
		(start 131.41071 -394.211302)
		(end 131.568698 -394.211302)
		(width 0.1651)
		(layer "In5.Cu")
		(net "P5E_PEX1_STN5_RX_DP<86>")
	)
	(segment
		(start 154.30119 -354.010468)
		(end 161.376868 -339.880702)
		(width 0.1651)
		(layer "In5.Cu")
		(net "P5E_PEX1_STN5_RX_DP<86>")
	)
	(segment
		(start 131.568698 -394.211302)
		(end 132.113782 -393.666218)
		(width 0.1651)
		(layer "In5.Cu")
		(net "P5E_PEX1_STN5_RX_DP<86>")
	)
	(segment
		(start 132.113782 -393.666218)
		(end 133.382258 -393.170918)
		(width 0.1651)
		(layer "In5.Cu")
		(net "P5E_PEX1_STN5_RX_DP<86>")
	)
	(segment
		(start 133.382258 -393.170918)
		(end 137.931652 -392.2649)
		(width 0.1651)
		(layer "In5.Cu")
		(net "P5E_PEX1_STN5_RX_DP<86>")
	)
	(segment
		(start 131.069334 -394.71092)
		(end 131.069334 -394.552932)
		(width 0.1651)
		(layer "In5.Cu")
		(net "P5E_PEX1_STN5_RX_DP<86>")
	)
	(segment
		(start 129.669794 -396.999206)
		(end 129.887472 -396.781528)
		(width 0.1651)
		(layer "In5.Cu")
		(net "P5E_PEX1_STN5_RX_DP<86>")
	)
	(segment
		(start 149.422104 -366.883696)
		(end 154.30119 -354.010468)
		(width 0.1651)
		(layer "In5.Cu")
		(net "P5E_PEX1_STN5_RX_DP<86>")
	)
	(segment
		(start 141.746224 -388.472934)
		(end 148.27631 -370.876322)
		(width 0.1651)
		(layer "In5.Cu")
		(net "P5E_PEX1_STN5_RX_DP<86>")
	)
	(segment
		(start 162.617912 -338.492592)
		(end 176.73828 -329.948286)
		(width 0.1651)
		(layer "In5.Cu")
		(net "P5E_PEX1_STN5_RX_DP<86>")
	)
	(segment
		(start 130.601212 -395.052042)
		(end 130.728212 -395.052042)
		(width 0.1651)
		(layer "In5.Cu")
		(net "P5E_PEX1_STN5_RX_DP<86>")
	)
	(segment
		(start 180.155596 -316.229492)
		(end 180.38572 -316.229492)
		(width 0.1143)
		(layer "In5.Cu")
		(net "P5E_PEX1_STN5_RX_DP<86>")
	)
	(segment
		(start 137.931652 -392.2649)
		(end 140.579856 -390.399524)
		(width 0.1651)
		(layer "In5.Cu")
		(net "P5E_PEX1_STN5_RX_DP<86>")
	)
	(segment
		(start 179.307236 -326.05853)
		(end 179.88407 -324.159626)
		(width 0.1651)
		(layer "In5.Cu")
		(net "P5E_PEX1_STN5_RX_DP<86>")
	)
	(segment
		(start 180.50002 -316.115192)
		(end 180.50002 -315.849762)
		(width 0.1143)
		(layer "In5.Cu")
		(net "P5E_PEX1_STN5_RX_DP<86>")
	)
	(segment
		(start 130.228594 -395.42466)
		(end 130.601212 -395.052042)
		(width 0.1651)
		(layer "In5.Cu")
		(net "P5E_PEX1_STN5_RX_DP<86>")
	)
	(segment
		(start 179.88407 -319.91173)
		(end 179.88407 -319.883282)
		(width 0.1143)
		(layer "In5.Cu")
		(net "P5E_PEX1_STN5_RX_DP<86>")
	)
	(segment
		(start 129.887472 -395.892782)
		(end 130.228594 -395.55166)
		(width 0.1651)
		(layer "In5.Cu")
		(net "P5E_PEX1_STN5_RX_DP<86>")
	)
	(segment
		(start 130.728212 -395.052042)
		(end 131.069334 -394.71092)
		(width 0.1651)
		(layer "In5.Cu")
		(net "P5E_PEX1_STN5_RX_DP<86>")
	)
	(segment
		(start 179.92979 -319.837562)
		(end 179.92979 -316.455298)
		(width 0.1143)
		(layer "In5.Cu")
		(net "P5E_PEX1_STN5_RX_DP<86>")
	)
	(segment
		(start 176.73828 -329.948286)
		(end 178.590702 -327.787254)
		(width 0.1651)
		(layer "In5.Cu")
		(net "P5E_PEX1_STN5_RX_DP<86>")
	)
	(segment
		(start 131.069334 -394.552932)
		(end 131.41071 -394.211302)
		(width 0.1651)
		(layer "In5.Cu")
		(net "P5E_PEX1_STN5_RX_DP<86>")
	)
	(segment
		(start 179.92979 -316.455298)
		(end 180.155596 -316.229492)
		(width 0.1143)
		(layer "In5.Cu")
		(net "P5E_PEX1_STN5_RX_DP<86>")
	)
	(segment
		(start 179.88407 -319.883282)
		(end 179.92979 -319.837562)
		(width 0.1143)
		(layer "In5.Cu")
		(net "P5E_PEX1_STN5_RX_DP<86>")
	)
	(segment
		(start 140.579856 -390.399524)
		(end 141.746224 -388.472934)
		(width 0.1651)
		(layer "In5.Cu")
		(net "P5E_PEX1_STN5_RX_DP<86>")
	)
	(segment
		(start 179.88407 -324.159626)
		(end 179.88407 -319.91173)
		(width 0.1651)
		(layer "In5.Cu")
		(net "P5E_PEX1_STN5_RX_DP<86>")
	)
	(segment
		(start 148.27631 -370.876322)
		(end 149.422104 -366.883696)
		(width 0.1651)
		(layer "In5.Cu")
		(net "P5E_PEX1_STN5_RX_DP<86>")
	)
	(segment
		(start 286.573214 -360.731562)
		(end 286.573468 -360.731562)
		(width 0.1651)
		(layer "In5.Cu")
		(net "P5E_PEX2_STN7_RX_DN<121>")
	)
	(segment
		(start 268.38275 -310.73725)
		(end 267.30706 -311.81294)
		(width 0.1651)
		(layer "In5.Cu")
		(net "P5E_PEX2_STN7_RX_DN<121>")
	)
	(segment
		(start 286.893508 -361.381294)
		(end 286.893254 -361.381548)
		(width 0.1651)
		(layer "In5.Cu")
		(net "P5E_PEX2_STN7_RX_DN<121>")
	)
	(segment
		(start 267.30706 -317.82131)
		(end 267.86078 -320.52514)
		(width 0.1651)
		(layer "In5.Cu")
		(net "P5E_PEX2_STN7_RX_DN<121>")
	)
	(segment
		(start 286.35452 -360.28757)
		(end 286.573214 -360.731562)
		(width 0.1651)
		(layer "In5.Cu")
		(net "P5E_PEX2_STN7_RX_DN<121>")
	)
	(segment
		(start 268.402816 -310.717184)
		(end 268.38275 -310.73725)
		(width 0.1143)
		(layer "In5.Cu")
		(net "P5E_PEX2_STN7_RX_DN<121>")
	)
	(segment
		(start 289.887152 -367.462054)
		(end 290.533836 -368.775234)
		(width 0.1651)
		(layer "In5.Cu")
		(net "P5E_PEX2_STN7_RX_DN<121>")
	)
	(segment
		(start 268.654784 -310.529478)
		(end 268.466824 -310.717438)
		(width 0.1143)
		(layer "In5.Cu")
		(net "P5E_PEX2_STN7_RX_DN<121>")
	)
	(segment
		(start 286.740346 -361.329224)
		(end 286.893508 -361.381294)
		(width 0.1651)
		(layer "In5.Cu")
		(net "P5E_PEX2_STN7_RX_DN<121>")
	)
	(segment
		(start 285.287212 -341.84717)
		(end 285.287212 -358.119426)
		(width 0.1651)
		(layer "In5.Cu")
		(net "P5E_PEX2_STN7_RX_DN<121>")
	)
	(segment
		(start 269.315184 -310.529478)
		(end 268.654784 -310.529478)
		(width 0.1143)
		(layer "In5.Cu")
		(net "P5E_PEX2_STN7_RX_DN<121>")
	)
	(segment
		(start 289.816794 -383.79908)
		(end 289.689794 -383.67208)
		(width 0.1651)
		(layer "In5.Cu")
		(net "P5E_PEX2_STN7_RX_DN<121>")
	)
	(segment
		(start 289.689794 -383.67208)
		(end 289.689794 -383.290064)
		(width 0.1651)
		(layer "In5.Cu")
		(net "P5E_PEX2_STN7_RX_DN<121>")
	)
	(segment
		(start 286.573468 -360.731562)
		(end 286.521398 -360.88447)
		(width 0.1651)
		(layer "In5.Cu")
		(net "P5E_PEX2_STN7_RX_DN<121>")
	)
	(segment
		(start 289.567366 -366.812322)
		(end 289.515296 -366.96523)
		(width 0.1651)
		(layer "In5.Cu")
		(net "P5E_PEX2_STN7_RX_DN<121>")
	)
	(segment
		(start 290.24707 -383.79908)
		(end 289.816794 -383.79908)
		(width 0.1651)
		(layer "In5.Cu")
		(net "P5E_PEX2_STN7_RX_DN<121>")
	)
	(segment
		(start 285.287212 -358.119426)
		(end 286.034734 -359.637584)
		(width 0.1651)
		(layer "In5.Cu")
		(net "P5E_PEX2_STN7_RX_DN<121>")
	)
	(segment
		(start 269.315184 -310.149748)
		(end 269.429484 -310.264048)
		(width 0.1143)
		(layer "In5.Cu")
		(net "P5E_PEX2_STN7_RX_DN<121>")
	)
	(segment
		(start 289.734244 -367.409984)
		(end 289.887406 -367.462054)
		(width 0.1651)
		(layer "In5.Cu")
		(net "P5E_PEX2_STN7_RX_DN<121>")
	)
	(segment
		(start 289.515296 -366.96523)
		(end 289.734244 -367.409984)
		(width 0.1651)
		(layer "In5.Cu")
		(net "P5E_PEX2_STN7_RX_DN<121>")
	)
	(segment
		(start 269.429484 -310.264048)
		(end 269.429484 -310.415178)
		(width 0.1143)
		(layer "In5.Cu")
		(net "P5E_PEX2_STN7_RX_DN<121>")
	)
	(segment
		(start 285.982664 -359.790746)
		(end 286.201612 -360.235246)
		(width 0.1651)
		(layer "In5.Cu")
		(net "P5E_PEX2_STN7_RX_DN<121>")
	)
	(segment
		(start 269.429484 -310.415178)
		(end 269.315184 -310.529478)
		(width 0.1143)
		(layer "In5.Cu")
		(net "P5E_PEX2_STN7_RX_DN<121>")
	)
	(segment
		(start 289.567112 -366.812322)
		(end 289.567366 -366.812322)
		(width 0.1651)
		(layer "In5.Cu")
		(net "P5E_PEX2_STN7_RX_DN<121>")
	)
	(segment
		(start 284.763464 -340.54288)
		(end 285.287212 -341.84717)
		(width 0.1651)
		(layer "In5.Cu")
		(net "P5E_PEX2_STN7_RX_DN<121>")
	)
	(segment
		(start 286.354774 -360.287316)
		(end 286.35452 -360.28757)
		(width 0.1651)
		(layer "In5.Cu")
		(net "P5E_PEX2_STN7_RX_DN<121>")
	)
	(segment
		(start 267.86078 -320.52514)
		(end 267.86078 -325.322946)
		(width 0.1651)
		(layer "In5.Cu")
		(net "P5E_PEX2_STN7_RX_DN<121>")
	)
	(segment
		(start 286.201612 -360.235246)
		(end 286.354774 -360.287316)
		(width 0.1651)
		(layer "In5.Cu")
		(net "P5E_PEX2_STN7_RX_DN<121>")
	)
	(segment
		(start 269.311374 -328.765154)
		(end 272.060162 -331.972412)
		(width 0.1651)
		(layer "In5.Cu")
		(net "P5E_PEX2_STN7_RX_DN<121>")
	)
	(segment
		(start 268.466824 -310.717438)
		(end 268.402816 -310.717184)
		(width 0.1143)
		(layer "In5.Cu")
		(net "P5E_PEX2_STN7_RX_DN<121>")
	)
	(segment
		(start 289.887406 -367.462054)
		(end 289.887152 -367.462054)
		(width 0.1651)
		(layer "In5.Cu")
		(net "P5E_PEX2_STN7_RX_DN<121>")
	)
	(segment
		(start 269.049754 -310.149748)
		(end 269.315184 -310.149748)
		(width 0.1143)
		(layer "In5.Cu")
		(net "P5E_PEX2_STN7_RX_DN<121>")
	)
	(segment
		(start 272.060162 -331.972412)
		(end 280.387552 -337.590638)
		(width 0.1651)
		(layer "In5.Cu")
		(net "P5E_PEX2_STN7_RX_DN<121>")
	)
	(segment
		(start 267.86078 -325.322946)
		(end 269.311374 -328.765154)
		(width 0.1651)
		(layer "In5.Cu")
		(net "P5E_PEX2_STN7_RX_DN<121>")
	)
	(segment
		(start 286.893254 -361.381548)
		(end 289.567112 -366.812322)
		(width 0.1651)
		(layer "In5.Cu")
		(net "P5E_PEX2_STN7_RX_DN<121>")
	)
	(segment
		(start 290.533836 -383.512314)
		(end 290.24707 -383.79908)
		(width 0.1651)
		(layer "In5.Cu")
		(net "P5E_PEX2_STN7_RX_DN<121>")
	)
	(segment
		(start 290.533836 -368.775234)
		(end 290.533836 -383.512314)
		(width 0.1651)
		(layer "In5.Cu")
		(net "P5E_PEX2_STN7_RX_DN<121>")
	)
	(segment
		(start 280.966926 -337.981544)
		(end 284.763464 -340.54288)
		(width 0.1651)
		(layer "In5.Cu")
		(net "P5E_PEX2_STN7_RX_DN<121>")
	)
	(segment
		(start 280.387552 -337.590638)
		(end 280.414984 -337.731608)
		(width 0.1651)
		(layer "In5.Cu")
		(net "P5E_PEX2_STN7_RX_DN<121>")
	)
	(segment
		(start 286.521398 -360.88447)
		(end 286.740346 -361.329224)
		(width 0.1651)
		(layer "In5.Cu")
		(net "P5E_PEX2_STN7_RX_DN<121>")
	)
	(segment
		(start 280.825702 -338.008976)
		(end 280.966926 -337.981544)
		(width 0.1651)
		(layer "In5.Cu")
		(net "P5E_PEX2_STN7_RX_DN<121>")
	)
	(segment
		(start 280.414984 -337.731608)
		(end 280.825702 -338.008976)
		(width 0.1651)
		(layer "In5.Cu")
		(net "P5E_PEX2_STN7_RX_DN<121>")
	)
	(segment
		(start 286.034734 -359.637584)
		(end 285.982664 -359.790746)
		(width 0.1651)
		(layer "In5.Cu")
		(net "P5E_PEX2_STN7_RX_DN<121>")
	)
	(segment
		(start 267.30706 -311.81294)
		(end 267.30706 -317.82131)
		(width 0.1651)
		(layer "In5.Cu")
		(net "P5E_PEX2_STN7_RX_DN<121>")
	)
	(segment
		(start 28.953968 -343.365582)
		(end 28.953968 -342.734138)
		(width 0.13462)
		(layer "F.Cu")
		(net "P5E_PEX0_STN7_TX_DP<116>")
	)
	(segment
		(start 28.633928 -343.685622)
		(end 28.953968 -343.365582)
		(width 0.13462)
		(layer "F.Cu")
		(net "P5E_PEX0_STN7_TX_DP<116>")
	)
	(segment
		(start 28.953968 -342.734138)
		(end 28.659328 -342.439498)
		(width 0.13462)
		(layer "F.Cu")
		(net "P5E_PEX0_STN7_TX_DP<116>")
	)
	(segment
		(start 27.954478 -337.598766)
		(end 22.639782 -327.65619)
		(width 0.1651)
		(layer "In7.Cu")
		(net "P5E_PEX0_STN7_TX_DP<116>")
	)
	(segment
		(start 28.949904 -341.572596)
		(end 27.954478 -337.598766)
		(width 0.1651)
		(layer "In7.Cu")
		(net "P5E_PEX0_STN7_TX_DP<116>")
	)
	(segment
		(start 42.284396 -305.399948)
		(end 42.549826 -305.399948)
		(width 0.1143)
		(layer "In7.Cu")
		(net "P5E_PEX0_STN7_TX_DP<116>")
	)
	(segment
		(start 28.950158 -341.57285)
		(end 28.949904 -341.572596)
		(width 0.1651)
		(layer "In7.Cu")
		(net "P5E_PEX0_STN7_TX_DP<116>")
	)
	(segment
		(start 20.715224 -323.00926)
		(end 20.715224 -320.013838)
		(width 0.1651)
		(layer "In7.Cu")
		(net "P5E_PEX0_STN7_TX_DP<116>")
	)
	(segment
		(start 42.170096 -305.285648)
		(end 42.284396 -305.399948)
		(width 0.1143)
		(layer "In7.Cu")
		(net "P5E_PEX0_STN7_TX_DP<116>")
	)
	(segment
		(start 22.639782 -327.65619)
		(end 20.715224 -323.00926)
		(width 0.1651)
		(layer "In7.Cu")
		(net "P5E_PEX0_STN7_TX_DP<116>")
	)
	(segment
		(start 26.49601 -308.994556)
		(end 29.519626 -305.971194)
		(width 0.1651)
		(layer "In7.Cu")
		(net "P5E_PEX0_STN7_TX_DP<116>")
	)
	(segment
		(start 35.73272 -304.829718)
		(end 41.94429 -304.829718)
		(width 0.1143)
		(layer "In7.Cu")
		(net "P5E_PEX0_STN7_TX_DP<116>")
	)
	(segment
		(start 21.143214 -317.86068)
		(end 22.075648 -315.609986)
		(width 0.1651)
		(layer "In7.Cu")
		(net "P5E_PEX0_STN7_TX_DP<116>")
	)
	(segment
		(start 28.950158 -342.148668)
		(end 28.950158 -341.57285)
		(width 0.1651)
		(layer "In7.Cu")
		(net "P5E_PEX0_STN7_TX_DP<116>")
	)
	(segment
		(start 35.687 -304.783998)
		(end 35.73272 -304.829718)
		(width 0.1143)
		(layer "In7.Cu")
		(net "P5E_PEX0_STN7_TX_DP<116>")
	)
	(segment
		(start 42.170096 -305.055524)
		(end 42.170096 -305.285648)
		(width 0.1143)
		(layer "In7.Cu")
		(net "P5E_PEX0_STN7_TX_DP<116>")
	)
	(segment
		(start 28.659328 -342.439498)
		(end 28.950158 -342.148668)
		(width 0.1651)
		(layer "In7.Cu")
		(net "P5E_PEX0_STN7_TX_DP<116>")
	)
	(segment
		(start 32.386016 -304.783998)
		(end 35.658552 -304.783998)
		(width 0.1651)
		(layer "In7.Cu")
		(net "P5E_PEX0_STN7_TX_DP<116>")
	)
	(segment
		(start 41.94429 -304.829718)
		(end 42.170096 -305.055524)
		(width 0.1143)
		(layer "In7.Cu")
		(net "P5E_PEX0_STN7_TX_DP<116>")
	)
	(segment
		(start 22.075648 -315.609986)
		(end 26.49601 -308.994556)
		(width 0.1651)
		(layer "In7.Cu")
		(net "P5E_PEX0_STN7_TX_DP<116>")
	)
	(segment
		(start 35.658552 -304.783998)
		(end 35.687 -304.783998)
		(width 0.1143)
		(layer "In7.Cu")
		(net "P5E_PEX0_STN7_TX_DP<116>")
	)
	(segment
		(start 29.519626 -305.971194)
		(end 32.386016 -304.783998)
		(width 0.1651)
		(layer "In7.Cu")
		(net "P5E_PEX0_STN7_TX_DP<116>")
	)
	(segment
		(start 20.715224 -320.013838)
		(end 21.143214 -317.86068)
		(width 0.1651)
		(layer "In7.Cu")
		(net "P5E_PEX0_STN7_TX_DP<116>")
	)
	(segment
		(start 154.793696 -121.325386)
		(end 154.162252 -121.325386)
		(width 0.13462)
		(layer "F.Cu")
		(net "P5E_PEX1_STN1_TX_DN<25>")
	)
	(segment
		(start 155.113736 -121.005346)
		(end 154.793696 -121.325386)
		(width 0.13462)
		(layer "F.Cu")
		(net "P5E_PEX1_STN1_TX_DN<25>")
	)
	(segment
		(start 154.162252 -121.325386)
		(end 153.867612 -121.030746)
		(width 0.13462)
		(layer "F.Cu")
		(net "P5E_PEX1_STN1_TX_DN<25>")
	)
	(segment
		(start 148.832824 -123.037854)
		(end 145.01495 -132.255006)
		(width 0.1651)
		(layer "In9.Cu")
		(net "P5E_PEX1_STN1_TX_DN<25>")
	)
	(segment
		(start 150.549102 -121.321576)
		(end 148.832824 -123.037854)
		(width 0.1651)
		(layer "In9.Cu")
		(net "P5E_PEX1_STN1_TX_DN<25>")
	)
	(segment
		(start 183.72963 -271.600168)
		(end 183.72963 -280.10485)
		(width 0.1143)
		(layer "In9.Cu")
		(net "P5E_PEX1_STN1_TX_DN<25>")
	)
	(segment
		(start 183.72963 -280.10485)
		(end 183.944768 -280.319988)
		(width 0.1143)
		(layer "In9.Cu")
		(net "P5E_PEX1_STN1_TX_DN<25>")
	)
	(segment
		(start 184.29986 -280.434288)
		(end 184.29986 -280.699718)
		(width 0.1143)
		(layer "In9.Cu")
		(net "P5E_PEX1_STN1_TX_DN<25>")
	)
	(segment
		(start 147.559014 -143.39316)
		(end 148.288756 -158.240222)
		(width 0.1651)
		(layer "In9.Cu")
		(net "P5E_PEX1_STN1_TX_DN<25>")
	)
	(segment
		(start 145.01495 -137.251186)
		(end 147.559014 -143.39316)
		(width 0.1651)
		(layer "In9.Cu")
		(net "P5E_PEX1_STN1_TX_DN<25>")
	)
	(segment
		(start 145.01495 -132.255006)
		(end 145.01495 -137.251186)
		(width 0.1651)
		(layer "In9.Cu")
		(net "P5E_PEX1_STN1_TX_DN<25>")
	)
	(segment
		(start 183.68391 -271.554448)
		(end 183.72963 -271.600168)
		(width 0.1143)
		(layer "In9.Cu")
		(net "P5E_PEX1_STN1_TX_DN<25>")
	)
	(segment
		(start 183.68391 -264.068306)
		(end 183.68391 -271.526)
		(width 0.1651)
		(layer "In9.Cu")
		(net "P5E_PEX1_STN1_TX_DN<25>")
	)
	(segment
		(start 153.576782 -121.321576)
		(end 150.549102 -121.321576)
		(width 0.1651)
		(layer "In9.Cu")
		(net "P5E_PEX1_STN1_TX_DN<25>")
	)
	(segment
		(start 153.867612 -121.030746)
		(end 153.576782 -121.321576)
		(width 0.1651)
		(layer "In9.Cu")
		(net "P5E_PEX1_STN1_TX_DN<25>")
	)
	(segment
		(start 148.288756 -158.240222)
		(end 148.89861 -161.306002)
		(width 0.1651)
		(layer "In9.Cu")
		(net "P5E_PEX1_STN1_TX_DN<25>")
	)
	(segment
		(start 148.89861 -161.306002)
		(end 183.68391 -264.068306)
		(width 0.1651)
		(layer "In9.Cu")
		(net "P5E_PEX1_STN1_TX_DN<25>")
	)
	(segment
		(start 183.68391 -271.526)
		(end 183.68391 -271.554448)
		(width 0.1143)
		(layer "In9.Cu")
		(net "P5E_PEX1_STN1_TX_DN<25>")
	)
	(segment
		(start 183.944768 -280.319988)
		(end 184.18556 -280.319988)
		(width 0.1143)
		(layer "In9.Cu")
		(net "P5E_PEX1_STN1_TX_DN<25>")
	)
	(segment
		(start 184.18556 -280.319988)
		(end 184.29986 -280.434288)
		(width 0.1143)
		(layer "In9.Cu")
		(net "P5E_PEX1_STN1_TX_DN<25>")
	)
	(segment
		(start 127.701548 -342.734138)
		(end 127.406908 -342.439498)
		(width 0.13462)
		(layer "F.Cu")
		(net "P5E_PEX1_STN6_TX_DP<96>")
	)
	(segment
		(start 127.381508 -343.685622)
		(end 127.701548 -343.365582)
		(width 0.13462)
		(layer "F.Cu")
		(net "P5E_PEX1_STN6_TX_DP<96>")
	)
	(segment
		(start 127.701548 -343.365582)
		(end 127.701548 -342.734138)
		(width 0.13462)
		(layer "F.Cu")
		(net "P5E_PEX1_STN6_TX_DP<96>")
	)
	(segment
		(start 173.279816 -313.605418)
		(end 173.505622 -313.379612)
		(width 0.1143)
		(layer "In7.Cu")
		(net "P5E_PEX1_STN6_TX_DP<96>")
	)
	(segment
		(start 173.505622 -313.379612)
		(end 173.735746 -313.379612)
		(width 0.1143)
		(layer "In7.Cu")
		(net "P5E_PEX1_STN6_TX_DP<96>")
	)
	(segment
		(start 173.735746 -313.379612)
		(end 173.850046 -313.265312)
		(width 0.1143)
		(layer "In7.Cu")
		(net "P5E_PEX1_STN6_TX_DP<96>")
	)
	(segment
		(start 129.223008 -339.508592)
		(end 133.79069 -336.770726)
		(width 0.1651)
		(layer "In7.Cu")
		(net "P5E_PEX1_STN6_TX_DP<96>")
	)
	(segment
		(start 173.850046 -313.265312)
		(end 173.850046 -312.999882)
		(width 0.1143)
		(layer "In7.Cu")
		(net "P5E_PEX1_STN6_TX_DP<96>")
	)
	(segment
		(start 151.034496 -331.53985)
		(end 168.211246 -326.329294)
		(width 0.1651)
		(layer "In7.Cu")
		(net "P5E_PEX1_STN6_TX_DP<96>")
	)
	(segment
		(start 133.79069 -336.770726)
		(end 151.034496 -331.53985)
		(width 0.1651)
		(layer "In7.Cu")
		(net "P5E_PEX1_STN6_TX_DP<96>")
	)
	(segment
		(start 168.211246 -326.329294)
		(end 171.13631 -324.576186)
		(width 0.1651)
		(layer "In7.Cu")
		(net "P5E_PEX1_STN6_TX_DP<96>")
	)
	(segment
		(start 173.279816 -319.92824)
		(end 173.279816 -313.605418)
		(width 0.1143)
		(layer "In7.Cu")
		(net "P5E_PEX1_STN6_TX_DP<96>")
	)
	(segment
		(start 173.234096 -319.97396)
		(end 173.279816 -319.92824)
		(width 0.1143)
		(layer "In7.Cu")
		(net "P5E_PEX1_STN6_TX_DP<96>")
	)
	(segment
		(start 171.13631 -324.576186)
		(end 172.287184 -323.425312)
		(width 0.1651)
		(layer "In7.Cu")
		(net "P5E_PEX1_STN6_TX_DP<96>")
	)
	(segment
		(start 173.234096 -321.139312)
		(end 173.234096 -320.002408)
		(width 0.1651)
		(layer "In7.Cu")
		(net "P5E_PEX1_STN6_TX_DP<96>")
	)
	(segment
		(start 173.234096 -320.002408)
		(end 173.234096 -319.97396)
		(width 0.1143)
		(layer "In7.Cu")
		(net "P5E_PEX1_STN6_TX_DP<96>")
	)
	(segment
		(start 127.697738 -342.148668)
		(end 127.697738 -341.033862)
		(width 0.1651)
		(layer "In7.Cu")
		(net "P5E_PEX1_STN6_TX_DP<96>")
	)
	(segment
		(start 127.406908 -342.439498)
		(end 127.697738 -342.148668)
		(width 0.1651)
		(layer "In7.Cu")
		(net "P5E_PEX1_STN6_TX_DP<96>")
	)
	(segment
		(start 127.697738 -341.033862)
		(end 129.223008 -339.508592)
		(width 0.1651)
		(layer "In7.Cu")
		(net "P5E_PEX1_STN6_TX_DP<96>")
	)
	(segment
		(start 172.287184 -323.425312)
		(end 173.234096 -321.139312)
		(width 0.1651)
		(layer "In7.Cu")
		(net "P5E_PEX1_STN6_TX_DP<96>")
	)
	(segment
		(start 177.951892 -327.457054)
		(end 178.651408 -325.880476)
		(width 0.1651)
		(layer "In5.Cu")
		(net "P5E_PEX1_STN5_RX_DN<85>")
	)
	(segment
		(start 130.358642 -393.62761)
		(end 133.32206 -392.471656)
		(width 0.1651)
		(layer "In5.Cu")
		(net "P5E_PEX1_STN5_RX_DN<85>")
	)
	(segment
		(start 162.60191 -337.475068)
		(end 175.49876 -329.910186)
		(width 0.1651)
		(layer "In5.Cu")
		(net "P5E_PEX1_STN5_RX_DN<85>")
	)
	(segment
		(start 179.21605 -324.021196)
		(end 179.21605 -319.91173)
		(width 0.1651)
		(layer "In5.Cu")
		(net "P5E_PEX1_STN5_RX_DN<85>")
	)
	(segment
		(start 127.969518 -396.085822)
		(end 128.276096 -395.048486)
		(width 0.1651)
		(layer "In5.Cu")
		(net "P5E_PEX1_STN5_RX_DN<85>")
	)
	(segment
		(start 178.651408 -325.880476)
		(end 179.21605 -324.021196)
		(width 0.1651)
		(layer "In5.Cu")
		(net "P5E_PEX1_STN5_RX_DN<85>")
	)
	(segment
		(start 175.49876 -329.910186)
		(end 176.680114 -328.72934)
		(width 0.1651)
		(layer "In5.Cu")
		(net "P5E_PEX1_STN5_RX_DN<85>")
	)
	(segment
		(start 179.17033 -319.837562)
		(end 179.17033 -318.434466)
		(width 0.1143)
		(layer "In5.Cu")
		(net "P5E_PEX1_STN5_RX_DN<85>")
	)
	(segment
		(start 128.76784 -394.604494)
		(end 130.358642 -393.62761)
		(width 0.1651)
		(layer "In5.Cu")
		(net "P5E_PEX1_STN5_RX_DN<85>")
	)
	(segment
		(start 179.28463 -318.320166)
		(end 179.43576 -318.320166)
		(width 0.1143)
		(layer "In5.Cu")
		(net "P5E_PEX1_STN5_RX_DN<85>")
	)
	(segment
		(start 127.969518 -397.998442)
		(end 127.969518 -396.085822)
		(width 0.1651)
		(layer "In5.Cu")
		(net "P5E_PEX1_STN5_RX_DN<85>")
	)
	(segment
		(start 140.045186 -389.951468)
		(end 141.197584 -388.016496)
		(width 0.1651)
		(layer "In5.Cu")
		(net "P5E_PEX1_STN5_RX_DN<85>")
	)
	(segment
		(start 126.910084 -398.50822)
		(end 127.037084 -398.38122)
		(width 0.1651)
		(layer "In5.Cu")
		(net "P5E_PEX1_STN5_RX_DN<85>")
	)
	(segment
		(start 153.658062 -353.740974)
		(end 160.786572 -339.505798)
		(width 0.1651)
		(layer "In5.Cu")
		(net "P5E_PEX1_STN5_RX_DN<85>")
	)
	(segment
		(start 179.21605 -319.91173)
		(end 179.21605 -319.883282)
		(width 0.1143)
		(layer "In5.Cu")
		(net "P5E_PEX1_STN5_RX_DN<85>")
	)
	(segment
		(start 160.786572 -339.505798)
		(end 162.60191 -337.475068)
		(width 0.1651)
		(layer "In5.Cu")
		(net "P5E_PEX1_STN5_RX_DN<85>")
	)
	(segment
		(start 179.55006 -318.434466)
		(end 179.55006 -318.699896)
		(width 0.1143)
		(layer "In5.Cu")
		(net "P5E_PEX1_STN5_RX_DN<85>")
	)
	(segment
		(start 126.910084 -398.890236)
		(end 126.910084 -398.50822)
		(width 0.1651)
		(layer "In5.Cu")
		(net "P5E_PEX1_STN5_RX_DN<85>")
	)
	(segment
		(start 133.32206 -392.471656)
		(end 137.709656 -391.597388)
		(width 0.1651)
		(layer "In5.Cu")
		(net "P5E_PEX1_STN5_RX_DN<85>")
	)
	(segment
		(start 179.43576 -318.320166)
		(end 179.55006 -318.434466)
		(width 0.1143)
		(layer "In5.Cu")
		(net "P5E_PEX1_STN5_RX_DN<85>")
	)
	(segment
		(start 179.21605 -319.883282)
		(end 179.17033 -319.837562)
		(width 0.1143)
		(layer "In5.Cu")
		(net "P5E_PEX1_STN5_RX_DN<85>")
	)
	(segment
		(start 127.037084 -398.38122)
		(end 127.58674 -398.38122)
		(width 0.1651)
		(layer "In5.Cu")
		(net "P5E_PEX1_STN5_RX_DN<85>")
	)
	(segment
		(start 127.58674 -398.38122)
		(end 127.969518 -397.998442)
		(width 0.1651)
		(layer "In5.Cu")
		(net "P5E_PEX1_STN5_RX_DN<85>")
	)
	(segment
		(start 176.680114 -328.72934)
		(end 176.680114 -328.728832)
		(width 0.1651)
		(layer "In5.Cu")
		(net "P5E_PEX1_STN5_RX_DN<85>")
	)
	(segment
		(start 176.680114 -328.728832)
		(end 177.951892 -327.457054)
		(width 0.1651)
		(layer "In5.Cu")
		(net "P5E_PEX1_STN5_RX_DN<85>")
	)
	(segment
		(start 179.17033 -318.434466)
		(end 179.28463 -318.320166)
		(width 0.1143)
		(layer "In5.Cu")
		(net "P5E_PEX1_STN5_RX_DN<85>")
	)
	(segment
		(start 148.644356 -366.972088)
		(end 153.658062 -353.740974)
		(width 0.1651)
		(layer "In5.Cu")
		(net "P5E_PEX1_STN5_RX_DN<85>")
	)
	(segment
		(start 147.53209 -370.945664)
		(end 148.644356 -366.972088)
		(width 0.1651)
		(layer "In5.Cu")
		(net "P5E_PEX1_STN5_RX_DN<85>")
	)
	(segment
		(start 141.197584 -388.016496)
		(end 147.53209 -370.945664)
		(width 0.1651)
		(layer "In5.Cu")
		(net "P5E_PEX1_STN5_RX_DN<85>")
	)
	(segment
		(start 137.709656 -391.597388)
		(end 140.045186 -389.951468)
		(width 0.1651)
		(layer "In5.Cu")
		(net "P5E_PEX1_STN5_RX_DN<85>")
	)
	(segment
		(start 128.276096 -395.048486)
		(end 128.76784 -394.604494)
		(width 0.1651)
		(layer "In5.Cu")
		(net "P5E_PEX1_STN5_RX_DN<85>")
	)
	(segment
		(start 47.607728 -343.365582)
		(end 47.607728 -342.734138)
		(width 0.13462)
		(layer "F.Cu")
		(net "P5E_PEX0_STN7_TX_DP<125>")
	)
	(segment
		(start 47.287688 -343.685622)
		(end 47.607728 -343.365582)
		(width 0.13462)
		(layer "F.Cu")
		(net "P5E_PEX0_STN7_TX_DP<125>")
	)
	(segment
		(start 47.607728 -342.734138)
		(end 47.313088 -342.439498)
		(width 0.13462)
		(layer "F.Cu")
		(net "P5E_PEX0_STN7_TX_DP<125>")
	)
	(segment
		(start 40.079676 -319.81648)
		(end 40.079676 -313.605418)
		(width 0.1143)
		(layer "In7.Cu")
		(net "P5E_PEX0_STN7_TX_DP<125>")
	)
	(segment
		(start 47.313088 -342.439498)
		(end 47.603918 -342.148668)
		(width 0.1651)
		(layer "In7.Cu")
		(net "P5E_PEX0_STN7_TX_DP<125>")
	)
	(segment
		(start 40.251888 -323.549264)
		(end 40.045132 -323.112892)
		(width 0.1651)
		(layer "In7.Cu")
		(net "P5E_PEX0_STN7_TX_DP<125>")
	)
	(segment
		(start 40.400732 -323.602604)
		(end 40.251888 -323.549264)
		(width 0.1651)
		(layer "In7.Cu")
		(net "P5E_PEX0_STN7_TX_DP<125>")
	)
	(segment
		(start 40.305482 -313.379612)
		(end 40.535606 -313.379612)
		(width 0.1143)
		(layer "In7.Cu")
		(net "P5E_PEX0_STN7_TX_DP<125>")
	)
	(segment
		(start 40.098472 -322.964048)
		(end 40.033956 -322.82765)
		(width 0.1651)
		(layer "In7.Cu")
		(net "P5E_PEX0_STN7_TX_DP<125>")
	)
	(segment
		(start 45.263562 -333.883508)
		(end 40.400732 -323.602604)
		(width 0.1651)
		(layer "In7.Cu")
		(net "P5E_PEX0_STN7_TX_DP<125>")
	)
	(segment
		(start 40.649906 -313.265312)
		(end 40.649906 -312.999882)
		(width 0.1143)
		(layer "In7.Cu")
		(net "P5E_PEX0_STN7_TX_DP<125>")
	)
	(segment
		(start 47.603918 -342.148668)
		(end 47.603918 -340.686644)
		(width 0.1651)
		(layer "In7.Cu")
		(net "P5E_PEX0_STN7_TX_DP<125>")
	)
	(segment
		(start 40.033956 -322.82765)
		(end 40.033956 -319.890648)
		(width 0.1651)
		(layer "In7.Cu")
		(net "P5E_PEX0_STN7_TX_DP<125>")
	)
	(segment
		(start 40.045132 -323.112892)
		(end 40.098472 -322.964048)
		(width 0.1651)
		(layer "In7.Cu")
		(net "P5E_PEX0_STN7_TX_DP<125>")
	)
	(segment
		(start 40.535606 -313.379612)
		(end 40.649906 -313.265312)
		(width 0.1143)
		(layer "In7.Cu")
		(net "P5E_PEX0_STN7_TX_DP<125>")
	)
	(segment
		(start 40.033956 -319.890648)
		(end 40.033956 -319.8622)
		(width 0.1143)
		(layer "In7.Cu")
		(net "P5E_PEX0_STN7_TX_DP<125>")
	)
	(segment
		(start 47.603918 -340.686644)
		(end 45.263562 -333.883508)
		(width 0.1651)
		(layer "In7.Cu")
		(net "P5E_PEX0_STN7_TX_DP<125>")
	)
	(segment
		(start 40.079676 -313.605418)
		(end 40.305482 -313.379612)
		(width 0.1143)
		(layer "In7.Cu")
		(net "P5E_PEX0_STN7_TX_DP<125>")
	)
	(segment
		(start 40.033956 -319.8622)
		(end 40.079676 -319.81648)
		(width 0.1143)
		(layer "In7.Cu")
		(net "P5E_PEX0_STN7_TX_DP<125>")
	)
	(segment
		(start 154.162252 -110.683294)
		(end 153.867612 -110.977934)
		(width 0.13462)
		(layer "F.Cu")
		(net "P5E_PEX1_STN1_TX_DN<22>")
	)
	(segment
		(start 155.113736 -111.003334)
		(end 154.793696 -110.683294)
		(width 0.13462)
		(layer "F.Cu")
		(net "P5E_PEX1_STN1_TX_DN<22>")
	)
	(segment
		(start 154.793696 -110.683294)
		(end 154.162252 -110.683294)
		(width 0.13462)
		(layer "F.Cu")
		(net "P5E_PEX1_STN1_TX_DN<22>")
	)
	(segment
		(start 181.173628 -278.229568)
		(end 181.335426 -278.229568)
		(width 0.1143)
		(layer "In9.Cu")
		(net "P5E_PEX1_STN1_TX_DN<22>")
	)
	(segment
		(start 145.330164 -151.43353)
		(end 145.694146 -158.844488)
		(width 0.1651)
		(layer "In9.Cu")
		(net "P5E_PEX1_STN1_TX_DN<22>")
	)
	(segment
		(start 148.337524 -114.31016)
		(end 148.399246 -114.459512)
		(width 0.1651)
		(layer "In9.Cu")
		(net "P5E_PEX1_STN1_TX_DN<22>")
	)
	(segment
		(start 181.11597 -271.471898)
		(end 181.11597 -271.500346)
		(width 0.1143)
		(layer "In9.Cu")
		(net "P5E_PEX1_STN1_TX_DN<22>")
	)
	(segment
		(start 181.449726 -278.115268)
		(end 181.449726 -277.849838)
		(width 0.1143)
		(layer "In9.Cu")
		(net "P5E_PEX1_STN1_TX_DN<22>")
	)
	(segment
		(start 147.60829 -116.070634)
		(end 147.423632 -116.516404)
		(width 0.1651)
		(layer "In9.Cu")
		(net "P5E_PEX1_STN1_TX_DN<22>")
	)
	(segment
		(start 144.963134 -143.952976)
		(end 145.330164 -151.433276)
		(width 0.1651)
		(layer "In9.Cu")
		(net "P5E_PEX1_STN1_TX_DN<22>")
	)
	(segment
		(start 181.11597 -264.660634)
		(end 181.11597 -271.471898)
		(width 0.1651)
		(layer "In9.Cu")
		(net "P5E_PEX1_STN1_TX_DN<22>")
	)
	(segment
		(start 147.028662 -117.768878)
		(end 146.844004 -118.214902)
		(width 0.1651)
		(layer "In9.Cu")
		(net "P5E_PEX1_STN1_TX_DN<22>")
	)
	(segment
		(start 148.214588 -114.905536)
		(end 148.064982 -114.967512)
		(width 0.1651)
		(layer "In9.Cu")
		(net "P5E_PEX1_STN1_TX_DN<22>")
	)
	(segment
		(start 150.510494 -111.206026)
		(end 150.361142 -111.14405)
		(width 0.1651)
		(layer "In9.Cu")
		(net "P5E_PEX1_STN1_TX_DN<22>")
	)
	(segment
		(start 142.39367 -137.75055)
		(end 144.963134 -143.952976)
		(width 0.1651)
		(layer "In9.Cu")
		(net "P5E_PEX1_STN1_TX_DN<22>")
	)
	(segment
		(start 147.880578 -115.413282)
		(end 147.9423 -115.562634)
		(width 0.1651)
		(layer "In9.Cu")
		(net "P5E_PEX1_STN1_TX_DN<22>")
	)
	(segment
		(start 181.07025 -278.12619)
		(end 181.173628 -278.229568)
		(width 0.1143)
		(layer "In9.Cu")
		(net "P5E_PEX1_STN1_TX_DN<22>")
	)
	(segment
		(start 147.757642 -116.008658)
		(end 147.608036 -116.070634)
		(width 0.1651)
		(layer "In9.Cu")
		(net "P5E_PEX1_STN1_TX_DN<22>")
	)
	(segment
		(start 150.956772 -111.021368)
		(end 150.510494 -111.206026)
		(width 0.1651)
		(layer "In9.Cu")
		(net "P5E_PEX1_STN1_TX_DN<22>")
	)
	(segment
		(start 152.279858 -110.687104)
		(end 151.464264 -110.687104)
		(width 0.1651)
		(layer "In9.Cu")
		(net "P5E_PEX1_STN1_TX_DN<22>")
	)
	(segment
		(start 148.521928 -113.864136)
		(end 148.521928 -113.86439)
		(width 0.1651)
		(layer "In9.Cu")
		(net "P5E_PEX1_STN1_TX_DN<22>")
	)
	(segment
		(start 149.12848 -112.698784)
		(end 148.978874 -112.76076)
		(width 0.1651)
		(layer "In9.Cu")
		(net "P5E_PEX1_STN1_TX_DN<22>")
	)
	(segment
		(start 181.335426 -278.229568)
		(end 181.449726 -278.115268)
		(width 0.1143)
		(layer "In9.Cu")
		(net "P5E_PEX1_STN1_TX_DN<22>")
	)
	(segment
		(start 147.423632 -116.516404)
		(end 147.485608 -116.665756)
		(width 0.1651)
		(layer "In9.Cu")
		(net "P5E_PEX1_STN1_TX_DN<22>")
	)
	(segment
		(start 148.978874 -112.761014)
		(end 148.79447 -113.206784)
		(width 0.1651)
		(layer "In9.Cu")
		(net "P5E_PEX1_STN1_TX_DN<22>")
	)
	(segment
		(start 151.464264 -110.687104)
		(end 151.018494 -110.871762)
		(width 0.1651)
		(layer "In9.Cu")
		(net "P5E_PEX1_STN1_TX_DN<22>")
	)
	(segment
		(start 181.07025 -271.546066)
		(end 181.07025 -278.12619)
		(width 0.1143)
		(layer "In9.Cu")
		(net "P5E_PEX1_STN1_TX_DN<22>")
	)
	(segment
		(start 148.521928 -113.86439)
		(end 148.337524 -114.31016)
		(width 0.1651)
		(layer "In9.Cu")
		(net "P5E_PEX1_STN1_TX_DN<22>")
	)
	(segment
		(start 146.844004 -118.214902)
		(end 146.694398 -118.276878)
		(width 0.1651)
		(layer "In9.Cu")
		(net "P5E_PEX1_STN1_TX_DN<22>")
	)
	(segment
		(start 148.79447 -113.206784)
		(end 148.856192 -113.356136)
		(width 0.1651)
		(layer "In9.Cu")
		(net "P5E_PEX1_STN1_TX_DN<22>")
	)
	(segment
		(start 149.313138 -112.25276)
		(end 149.12848 -112.698784)
		(width 0.1651)
		(layer "In9.Cu")
		(net "P5E_PEX1_STN1_TX_DN<22>")
	)
	(segment
		(start 147.9423 -115.562634)
		(end 147.757642 -116.008658)
		(width 0.1651)
		(layer "In9.Cu")
		(net "P5E_PEX1_STN1_TX_DN<22>")
	)
	(segment
		(start 152.991058 -110.687104)
		(end 152.876758 -110.801404)
		(width 0.1651)
		(layer "In9.Cu")
		(net "P5E_PEX1_STN1_TX_DN<22>")
	)
	(segment
		(start 146.259042 -161.684716)
		(end 181.11597 -264.660634)
		(width 0.1651)
		(layer "In9.Cu")
		(net "P5E_PEX1_STN1_TX_DN<22>")
	)
	(segment
		(start 149.43582 -111.657638)
		(end 149.251416 -112.103408)
		(width 0.1651)
		(layer "In9.Cu")
		(net "P5E_PEX1_STN1_TX_DN<22>")
	)
	(segment
		(start 148.399246 -114.459512)
		(end 148.214588 -114.905536)
		(width 0.1651)
		(layer "In9.Cu")
		(net "P5E_PEX1_STN1_TX_DN<22>")
	)
	(segment
		(start 181.11597 -271.500346)
		(end 181.07025 -271.546066)
		(width 0.1143)
		(layer "In9.Cu")
		(net "P5E_PEX1_STN1_TX_DN<22>")
	)
	(segment
		(start 148.671534 -113.80216)
		(end 148.521928 -113.864136)
		(width 0.1651)
		(layer "In9.Cu")
		(net "P5E_PEX1_STN1_TX_DN<22>")
	)
	(segment
		(start 149.251416 -112.103408)
		(end 149.313138 -112.25276)
		(width 0.1651)
		(layer "In9.Cu")
		(net "P5E_PEX1_STN1_TX_DN<22>")
	)
	(segment
		(start 148.978874 -112.76076)
		(end 148.978874 -112.761014)
		(width 0.1651)
		(layer "In9.Cu")
		(net "P5E_PEX1_STN1_TX_DN<22>")
	)
	(segment
		(start 145.605754 -120.906032)
		(end 142.39367 -131.49326)
		(width 0.1651)
		(layer "In9.Cu")
		(net "P5E_PEX1_STN1_TX_DN<22>")
	)
	(segment
		(start 145.694146 -158.844488)
		(end 146.259042 -161.684716)
		(width 0.1651)
		(layer "In9.Cu")
		(net "P5E_PEX1_STN1_TX_DN<22>")
	)
	(segment
		(start 146.694398 -118.276878)
		(end 146.694398 -118.277386)
		(width 0.1651)
		(layer "In9.Cu")
		(net "P5E_PEX1_STN1_TX_DN<22>")
	)
	(segment
		(start 145.330164 -151.433276)
		(end 145.330164 -151.43353)
		(width 0.1651)
		(layer "In9.Cu")
		(net "P5E_PEX1_STN1_TX_DN<22>")
	)
	(segment
		(start 153.867612 -110.977934)
		(end 153.576782 -110.687104)
		(width 0.1651)
		(layer "In9.Cu")
		(net "P5E_PEX1_STN1_TX_DN<22>")
	)
	(segment
		(start 146.96694 -117.619526)
		(end 147.028662 -117.768878)
		(width 0.1651)
		(layer "In9.Cu")
		(net "P5E_PEX1_STN1_TX_DN<22>")
	)
	(segment
		(start 147.485608 -116.665756)
		(end 147.30095 -117.11178)
		(width 0.1651)
		(layer "In9.Cu")
		(net "P5E_PEX1_STN1_TX_DN<22>")
	)
	(segment
		(start 149.65807 -111.435388)
		(end 149.43582 -111.657638)
		(width 0.1651)
		(layer "In9.Cu")
		(net "P5E_PEX1_STN1_TX_DN<22>")
	)
	(segment
		(start 152.876758 -110.801404)
		(end 152.394158 -110.801404)
		(width 0.1651)
		(layer "In9.Cu")
		(net "P5E_PEX1_STN1_TX_DN<22>")
	)
	(segment
		(start 150.361142 -111.14405)
		(end 149.65807 -111.435388)
		(width 0.1651)
		(layer "In9.Cu")
		(net "P5E_PEX1_STN1_TX_DN<22>")
	)
	(segment
		(start 151.018494 -110.871762)
		(end 150.956772 -111.021368)
		(width 0.1651)
		(layer "In9.Cu")
		(net "P5E_PEX1_STN1_TX_DN<22>")
	)
	(segment
		(start 152.394158 -110.801404)
		(end 152.279858 -110.687104)
		(width 0.1651)
		(layer "In9.Cu")
		(net "P5E_PEX1_STN1_TX_DN<22>")
	)
	(segment
		(start 148.064982 -114.967512)
		(end 147.880578 -115.413282)
		(width 0.1651)
		(layer "In9.Cu")
		(net "P5E_PEX1_STN1_TX_DN<22>")
	)
	(segment
		(start 147.608036 -116.070634)
		(end 147.60829 -116.070634)
		(width 0.1651)
		(layer "In9.Cu")
		(net "P5E_PEX1_STN1_TX_DN<22>")
	)
	(segment
		(start 147.30095 -117.11178)
		(end 147.151344 -117.173756)
		(width 0.1651)
		(layer "In9.Cu")
		(net "P5E_PEX1_STN1_TX_DN<22>")
	)
	(segment
		(start 153.576782 -110.687104)
		(end 152.991058 -110.687104)
		(width 0.1651)
		(layer "In9.Cu")
		(net "P5E_PEX1_STN1_TX_DN<22>")
	)
	(segment
		(start 142.39367 -131.49326)
		(end 142.39367 -137.75055)
		(width 0.1651)
		(layer "In9.Cu")
		(net "P5E_PEX1_STN1_TX_DN<22>")
	)
	(segment
		(start 146.694398 -118.277386)
		(end 145.605754 -120.906032)
		(width 0.1651)
		(layer "In9.Cu")
		(net "P5E_PEX1_STN1_TX_DN<22>")
	)
	(segment
		(start 148.856192 -113.356136)
		(end 148.671534 -113.80216)
		(width 0.1651)
		(layer "In9.Cu")
		(net "P5E_PEX1_STN1_TX_DN<22>")
	)
	(segment
		(start 147.151344 -117.173756)
		(end 146.96694 -117.619526)
		(width 0.1651)
		(layer "In9.Cu")
		(net "P5E_PEX1_STN1_TX_DN<22>")
	)
	(segment
		(start 118.374668 -355.026722)
		(end 118.080028 -354.732082)
		(width 0.13462)
		(layer "F.Cu")
		(net "P5E_PEX1_STN6_TX_DP<108>")
	)
	(segment
		(start 118.054628 -355.978206)
		(end 118.374668 -355.658166)
		(width 0.13462)
		(layer "F.Cu")
		(net "P5E_PEX1_STN6_TX_DP<108>")
	)
	(segment
		(start 118.374668 -355.658166)
		(end 118.374668 -355.026722)
		(width 0.13462)
		(layer "F.Cu")
		(net "P5E_PEX1_STN6_TX_DP<108>")
	)
	(segment
		(start 161.834068 -321.392804)
		(end 159.815022 -323.41185)
		(width 0.1651)
		(layer "In13.Cu")
		(net "P5E_PEX1_STN6_TX_DP<108>")
	)
	(segment
		(start 162.094926 -313.379612)
		(end 161.879788 -313.59475)
		(width 0.1143)
		(layer "In13.Cu")
		(net "P5E_PEX1_STN6_TX_DP<108>")
	)
	(segment
		(start 162.450018 -313.265312)
		(end 162.335718 -313.379612)
		(width 0.1143)
		(layer "In13.Cu")
		(net "P5E_PEX1_STN6_TX_DP<108>")
	)
	(segment
		(start 122.004836 -339.391244)
		(end 119.925338 -341.470742)
		(width 0.1651)
		(layer "In13.Cu")
		(net "P5E_PEX1_STN6_TX_DP<108>")
	)
	(segment
		(start 119.925338 -341.470742)
		(end 119.925338 -352.273108)
		(width 0.1651)
		(layer "In13.Cu")
		(net "P5E_PEX1_STN6_TX_DP<108>")
	)
	(segment
		(start 147.930362 -328.915522)
		(end 146.88185 -329.123294)
		(width 0.1651)
		(layer "In13.Cu")
		(net "P5E_PEX1_STN6_TX_DP<108>")
	)
	(segment
		(start 118.370858 -353.827588)
		(end 118.370858 -354.441252)
		(width 0.1651)
		(layer "In13.Cu")
		(net "P5E_PEX1_STN6_TX_DP<108>")
	)
	(segment
		(start 119.925338 -352.273108)
		(end 118.370858 -353.827588)
		(width 0.1651)
		(layer "In13.Cu")
		(net "P5E_PEX1_STN6_TX_DP<108>")
	)
	(segment
		(start 161.834068 -320.063114)
		(end 161.834068 -321.392804)
		(width 0.1651)
		(layer "In13.Cu")
		(net "P5E_PEX1_STN6_TX_DP<108>")
	)
	(segment
		(start 156.67863 -325.291958)
		(end 147.930362 -328.915522)
		(width 0.1651)
		(layer "In13.Cu")
		(net "P5E_PEX1_STN6_TX_DP<108>")
	)
	(segment
		(start 159.815022 -323.41185)
		(end 156.67863 -325.291958)
		(width 0.1651)
		(layer "In13.Cu")
		(net "P5E_PEX1_STN6_TX_DP<108>")
	)
	(segment
		(start 146.88185 -329.123548)
		(end 145.83283 -329.331828)
		(width 0.1651)
		(layer "In13.Cu")
		(net "P5E_PEX1_STN6_TX_DP<108>")
	)
	(segment
		(start 145.83283 -329.331828)
		(end 141.503908 -329.331828)
		(width 0.1651)
		(layer "In13.Cu")
		(net "P5E_PEX1_STN6_TX_DP<108>")
	)
	(segment
		(start 162.335718 -313.379612)
		(end 162.094926 -313.379612)
		(width 0.1143)
		(layer "In13.Cu")
		(net "P5E_PEX1_STN6_TX_DP<108>")
	)
	(segment
		(start 141.503908 -329.331828)
		(end 129.810764 -334.175354)
		(width 0.1651)
		(layer "In13.Cu")
		(net "P5E_PEX1_STN6_TX_DP<108>")
	)
	(segment
		(start 161.879788 -313.59475)
		(end 161.879788 -319.995296)
		(width 0.1143)
		(layer "In13.Cu")
		(net "P5E_PEX1_STN6_TX_DP<108>")
	)
	(segment
		(start 161.834068 -320.041016)
		(end 161.834068 -320.063114)
		(width 0.1143)
		(layer "In13.Cu")
		(net "P5E_PEX1_STN6_TX_DP<108>")
	)
	(segment
		(start 146.88185 -329.123294)
		(end 146.88185 -329.123548)
		(width 0.1651)
		(layer "In13.Cu")
		(net "P5E_PEX1_STN6_TX_DP<108>")
	)
	(segment
		(start 161.879788 -319.995296)
		(end 161.834068 -320.041016)
		(width 0.1143)
		(layer "In13.Cu")
		(net "P5E_PEX1_STN6_TX_DP<108>")
	)
	(segment
		(start 162.450018 -312.999882)
		(end 162.450018 -313.265312)
		(width 0.1143)
		(layer "In13.Cu")
		(net "P5E_PEX1_STN6_TX_DP<108>")
	)
	(segment
		(start 118.370858 -354.441252)
		(end 118.080028 -354.732082)
		(width 0.1651)
		(layer "In13.Cu")
		(net "P5E_PEX1_STN6_TX_DP<108>")
	)
	(segment
		(start 129.810764 -334.175354)
		(end 122.004836 -339.391244)
		(width 0.1651)
		(layer "In13.Cu")
		(net "P5E_PEX1_STN6_TX_DP<108>")
	)
	(segment
		(start 118.11 -398.890236)
		(end 118.11 -398.50822)
		(width 0.1651)
		(layer "In5.Cu")
		(net "P5E_PEX1_STN5_RX_DN<81>")
	)
	(segment
		(start 175.415956 -319.91173)
		(end 175.415956 -319.883282)
		(width 0.1143)
		(layer "In5.Cu")
		(net "P5E_PEX1_STN5_RX_DN<81>")
	)
	(segment
		(start 175.370236 -319.837562)
		(end 175.370236 -318.434466)
		(width 0.1143)
		(layer "In5.Cu")
		(net "P5E_PEX1_STN5_RX_DN<81>")
	)
	(segment
		(start 140.661898 -378.230892)
		(end 143.78559 -369.885976)
		(width 0.1651)
		(layer "In5.Cu")
		(net "P5E_PEX1_STN5_RX_DN<81>")
	)
	(segment
		(start 118.786656 -398.38122)
		(end 119.169434 -397.998442)
		(width 0.1651)
		(layer "In5.Cu")
		(net "P5E_PEX1_STN5_RX_DN<81>")
	)
	(segment
		(start 118.11 -398.50822)
		(end 118.237 -398.38122)
		(width 0.1651)
		(layer "In5.Cu")
		(net "P5E_PEX1_STN5_RX_DN<81>")
	)
	(segment
		(start 119.169434 -396.065248)
		(end 119.563896 -395.144498)
		(width 0.1651)
		(layer "In5.Cu")
		(net "P5E_PEX1_STN5_RX_DN<81>")
	)
	(segment
		(start 119.563896 -395.14399)
		(end 119.82069 -394.54455)
		(width 0.1651)
		(layer "In5.Cu")
		(net "P5E_PEX1_STN5_RX_DN<81>")
	)
	(segment
		(start 150.022814 -352.348038)
		(end 157.607254 -337.201764)
		(width 0.1651)
		(layer "In5.Cu")
		(net "P5E_PEX1_STN5_RX_DN<81>")
	)
	(segment
		(start 175.484536 -318.320166)
		(end 175.635666 -318.320166)
		(width 0.1143)
		(layer "In5.Cu")
		(net "P5E_PEX1_STN5_RX_DN<81>")
	)
	(segment
		(start 136.169908 -388.007606)
		(end 137.062464 -387.378702)
		(width 0.1651)
		(layer "In5.Cu")
		(net "P5E_PEX1_STN5_RX_DN<81>")
	)
	(segment
		(start 174.392082 -325.421498)
		(end 175.415956 -322.95465)
		(width 0.1651)
		(layer "In5.Cu")
		(net "P5E_PEX1_STN5_RX_DN<81>")
	)
	(segment
		(start 140.661644 -378.231654)
		(end 140.661898 -378.230892)
		(width 0.1651)
		(layer "In5.Cu")
		(net "P5E_PEX1_STN5_RX_DN<81>")
	)
	(segment
		(start 132.08381 -388.82193)
		(end 136.169908 -388.007606)
		(width 0.1651)
		(layer "In5.Cu")
		(net "P5E_PEX1_STN5_RX_DN<81>")
	)
	(segment
		(start 119.563896 -395.144498)
		(end 119.563896 -395.14399)
		(width 0.1651)
		(layer "In5.Cu")
		(net "P5E_PEX1_STN5_RX_DN<81>")
	)
	(segment
		(start 175.415956 -319.883282)
		(end 175.370236 -319.837562)
		(width 0.1143)
		(layer "In5.Cu")
		(net "P5E_PEX1_STN5_RX_DN<81>")
	)
	(segment
		(start 143.78559 -369.885976)
		(end 144.908524 -365.842296)
		(width 0.1651)
		(layer "In5.Cu")
		(net "P5E_PEX1_STN5_RX_DN<81>")
	)
	(segment
		(start 175.749966 -318.434466)
		(end 175.749966 -318.699896)
		(width 0.1143)
		(layer "In5.Cu")
		(net "P5E_PEX1_STN5_RX_DN<81>")
	)
	(segment
		(start 118.237 -398.38122)
		(end 118.786656 -398.38122)
		(width 0.1651)
		(layer "In5.Cu")
		(net "P5E_PEX1_STN5_RX_DN<81>")
	)
	(segment
		(start 175.635666 -318.320166)
		(end 175.749966 -318.434466)
		(width 0.1143)
		(layer "In5.Cu")
		(net "P5E_PEX1_STN5_RX_DN<81>")
	)
	(segment
		(start 119.169434 -397.998442)
		(end 119.169434 -396.065248)
		(width 0.1651)
		(layer "In5.Cu")
		(net "P5E_PEX1_STN5_RX_DN<81>")
	)
	(segment
		(start 157.607254 -337.201764)
		(end 159.976312 -334.55356)
		(width 0.1651)
		(layer "In5.Cu")
		(net "P5E_PEX1_STN5_RX_DN<81>")
	)
	(segment
		(start 119.82069 -394.54455)
		(end 128.594358 -390.183624)
		(width 0.1651)
		(layer "In5.Cu")
		(net "P5E_PEX1_STN5_RX_DN<81>")
	)
	(segment
		(start 137.535158 -386.58419)
		(end 140.661644 -378.231654)
		(width 0.1651)
		(layer "In5.Cu")
		(net "P5E_PEX1_STN5_RX_DN<81>")
	)
	(segment
		(start 128.594358 -390.183624)
		(end 132.08381 -388.82193)
		(width 0.1651)
		(layer "In5.Cu")
		(net "P5E_PEX1_STN5_RX_DN<81>")
	)
	(segment
		(start 137.062464 -387.378702)
		(end 137.535158 -386.58419)
		(width 0.1651)
		(layer "In5.Cu")
		(net "P5E_PEX1_STN5_RX_DN<81>")
	)
	(segment
		(start 175.370236 -318.434466)
		(end 175.484536 -318.320166)
		(width 0.1143)
		(layer "In5.Cu")
		(net "P5E_PEX1_STN5_RX_DN<81>")
	)
	(segment
		(start 172.86732 -326.946514)
		(end 174.392082 -325.421498)
		(width 0.1651)
		(layer "In5.Cu")
		(net "P5E_PEX1_STN5_RX_DN<81>")
	)
	(segment
		(start 159.976312 -334.55356)
		(end 172.86732 -326.946514)
		(width 0.1651)
		(layer "In5.Cu")
		(net "P5E_PEX1_STN5_RX_DN<81>")
	)
	(segment
		(start 144.908524 -365.842296)
		(end 150.022814 -352.348038)
		(width 0.1651)
		(layer "In5.Cu")
		(net "P5E_PEX1_STN5_RX_DN<81>")
	)
	(segment
		(start 175.415956 -322.95465)
		(end 175.415956 -319.91173)
		(width 0.1651)
		(layer "In5.Cu")
		(net "P5E_PEX1_STN5_RX_DN<81>")
	)
	(segment
		(start 199.979534 -152.191212)
		(end 200.274174 -152.485852)
		(width 0.13462)
		(layer "F.Cu")
		(net "P5E_PEX1_STN0_TX_DP<13>")
	)
	(segment
		(start 199.02805 -152.511252)
		(end 199.34809 -152.191212)
		(width 0.13462)
		(layer "F.Cu")
		(net "P5E_PEX1_STN0_TX_DP<13>")
	)
	(segment
		(start 199.34809 -152.191212)
		(end 199.979534 -152.191212)
		(width 0.13462)
		(layer "F.Cu")
		(net "P5E_PEX1_STN0_TX_DP<13>")
	)
	(segment
		(start 192.849754 -278.534368)
		(end 192.849754 -278.799798)
		(width 0.1143)
		(layer "In9.Cu")
		(net "P5E_PEX1_STN0_TX_DP<13>")
	)
	(segment
		(start 202.010264 -153.366724)
		(end 202.151234 -153.394664)
		(width 0.1651)
		(layer "In9.Cu")
		(net "P5E_PEX1_STN0_TX_DP<13>")
	)
	(segment
		(start 192.735454 -278.420068)
		(end 192.849754 -278.534368)
		(width 0.1143)
		(layer "In9.Cu")
		(net "P5E_PEX1_STN0_TX_DP<13>")
	)
	(segment
		(start 202.715622 -154.239468)
		(end 203.021946 -154.697938)
		(width 0.1651)
		(layer "In9.Cu")
		(net "P5E_PEX1_STN0_TX_DP<13>")
	)
	(segment
		(start 202.574652 -154.211528)
		(end 202.715622 -154.239468)
		(width 0.1651)
		(layer "In9.Cu")
		(net "P5E_PEX1_STN0_TX_DP<13>")
	)
	(segment
		(start 192.279778 -271.546066)
		(end 192.279778 -278.205184)
		(width 0.1143)
		(layer "In9.Cu")
		(net "P5E_PEX1_STN0_TX_DP<13>")
	)
	(segment
		(start 192.234058 -271.471898)
		(end 192.234058 -271.500346)
		(width 0.1143)
		(layer "In9.Cu")
		(net "P5E_PEX1_STN0_TX_DP<13>")
	)
	(segment
		(start 203.409042 -157.023562)
		(end 195.038472 -171.523152)
		(width 0.1651)
		(layer "In9.Cu")
		(net "P5E_PEX1_STN0_TX_DP<13>")
	)
	(segment
		(start 200.274174 -152.485852)
		(end 200.565004 -152.195022)
		(width 0.1651)
		(layer "In9.Cu")
		(net "P5E_PEX1_STN0_TX_DP<13>")
	)
	(segment
		(start 202.348592 -153.873454)
		(end 202.574652 -154.211528)
		(width 0.1651)
		(layer "In9.Cu")
		(net "P5E_PEX1_STN0_TX_DP<13>")
	)
	(segment
		(start 193.143886 -267.79093)
		(end 192.234058 -269.98803)
		(width 0.1651)
		(layer "In9.Cu")
		(net "P5E_PEX1_STN0_TX_DP<13>")
	)
	(segment
		(start 189.697614 -221.36227)
		(end 193.143886 -260.763004)
		(width 0.1651)
		(layer "In9.Cu")
		(net "P5E_PEX1_STN0_TX_DP<13>")
	)
	(segment
		(start 203.409042 -155.632658)
		(end 203.409042 -157.023562)
		(width 0.1651)
		(layer "In9.Cu")
		(net "P5E_PEX1_STN0_TX_DP<13>")
	)
	(segment
		(start 202.151234 -153.394664)
		(end 202.15098 -153.394664)
		(width 0.1651)
		(layer "In9.Cu")
		(net "P5E_PEX1_STN0_TX_DP<13>")
	)
	(segment
		(start 202.15098 -153.394664)
		(end 202.376786 -153.732484)
		(width 0.1651)
		(layer "In9.Cu")
		(net "P5E_PEX1_STN0_TX_DP<13>")
	)
	(segment
		(start 192.234058 -271.500346)
		(end 192.279778 -271.546066)
		(width 0.1143)
		(layer "In9.Cu")
		(net "P5E_PEX1_STN0_TX_DP<13>")
	)
	(segment
		(start 201.231754 -152.195022)
		(end 201.586592 -152.54986)
		(width 0.1651)
		(layer "In9.Cu")
		(net "P5E_PEX1_STN0_TX_DP<13>")
	)
	(segment
		(start 193.58356 -176.952402)
		(end 189.697614 -221.36227)
		(width 0.1651)
		(layer "In9.Cu")
		(net "P5E_PEX1_STN0_TX_DP<13>")
	)
	(segment
		(start 200.565004 -152.195022)
		(end 201.231754 -152.195022)
		(width 0.1651)
		(layer "In9.Cu")
		(net "P5E_PEX1_STN0_TX_DP<13>")
	)
	(segment
		(start 201.784204 -153.02865)
		(end 202.010264 -153.366724)
		(width 0.1651)
		(layer "In9.Cu")
		(net "P5E_PEX1_STN0_TX_DP<13>")
	)
	(segment
		(start 192.279778 -278.205184)
		(end 192.494662 -278.420068)
		(width 0.1143)
		(layer "In9.Cu")
		(net "P5E_PEX1_STN0_TX_DP<13>")
	)
	(segment
		(start 195.038472 -171.523152)
		(end 193.58356 -176.952402)
		(width 0.1651)
		(layer "In9.Cu")
		(net "P5E_PEX1_STN0_TX_DP<13>")
	)
	(segment
		(start 201.586592 -152.54986)
		(end 201.812144 -152.88768)
		(width 0.1651)
		(layer "In9.Cu")
		(net "P5E_PEX1_STN0_TX_DP<13>")
	)
	(segment
		(start 192.494662 -278.420068)
		(end 192.735454 -278.420068)
		(width 0.1143)
		(layer "In9.Cu")
		(net "P5E_PEX1_STN0_TX_DP<13>")
	)
	(segment
		(start 203.021946 -154.697938)
		(end 203.409042 -155.632658)
		(width 0.1651)
		(layer "In9.Cu")
		(net "P5E_PEX1_STN0_TX_DP<13>")
	)
	(segment
		(start 201.812144 -152.88768)
		(end 201.784204 -153.02865)
		(width 0.1651)
		(layer "In9.Cu")
		(net "P5E_PEX1_STN0_TX_DP<13>")
	)
	(segment
		(start 202.376786 -153.732484)
		(end 202.348592 -153.873454)
		(width 0.1651)
		(layer "In9.Cu")
		(net "P5E_PEX1_STN0_TX_DP<13>")
	)
	(segment
		(start 192.234058 -269.98803)
		(end 192.234058 -271.471898)
		(width 0.1651)
		(layer "In9.Cu")
		(net "P5E_PEX1_STN0_TX_DP<13>")
	)
	(segment
		(start 193.143886 -260.763004)
		(end 193.143886 -267.79093)
		(width 0.1651)
		(layer "In9.Cu")
		(net "P5E_PEX1_STN0_TX_DP<13>")
	)
	(segment
		(start 180.814472 -343.685622)
		(end 181.134512 -343.365582)
		(width 0.13462)
		(layer "F.Cu")
		(net "P5E_PEX1_STN7_TX_DN<121>")
	)
	(segment
		(start 181.134512 -342.734138)
		(end 180.839872 -342.439498)
		(width 0.13462)
		(layer "F.Cu")
		(net "P5E_PEX1_STN7_TX_DN<121>")
	)
	(segment
		(start 181.134512 -343.365582)
		(end 181.134512 -342.734138)
		(width 0.13462)
		(layer "F.Cu")
		(net "P5E_PEX1_STN7_TX_DN<121>")
	)
	(segment
		(start 153.32964 -312.138822)
		(end 153.24074 -312.049922)
		(width 0.1143)
		(layer "In11.Cu")
		(net "P5E_PEX1_STN7_TX_DN<121>")
	)
	(segment
		(start 155.87599 -327.04786)
		(end 151.456136 -322.43395)
		(width 0.1651)
		(layer "In11.Cu")
		(net "P5E_PEX1_STN7_TX_DN<121>")
	)
	(segment
		(start 152.133808 -312.849768)
		(end 152.149302 -312.834274)
		(width 0.1143)
		(layer "In11.Cu")
		(net "P5E_PEX1_STN7_TX_DN<121>")
	)
	(segment
		(start 172.085762 -335.41843)
		(end 155.87599 -327.04786)
		(width 0.1651)
		(layer "In11.Cu")
		(net "P5E_PEX1_STN7_TX_DN<121>")
	)
	(segment
		(start 152.618948 -312.429652)
		(end 153.16454 -312.429652)
		(width 0.1143)
		(layer "In11.Cu")
		(net "P5E_PEX1_STN7_TX_DN<121>")
	)
	(segment
		(start 150.068534 -316.549786)
		(end 151.282654 -313.700922)
		(width 0.1651)
		(layer "In11.Cu")
		(net "P5E_PEX1_STN7_TX_DN<121>")
	)
	(segment
		(start 151.282654 -313.700922)
		(end 152.133808 -312.849768)
		(width 0.1651)
		(layer "In11.Cu")
		(net "P5E_PEX1_STN7_TX_DN<121>")
	)
	(segment
		(start 151.456136 -322.43395)
		(end 150.068534 -317.861442)
		(width 0.1651)
		(layer "In11.Cu")
		(net "P5E_PEX1_STN7_TX_DN<121>")
	)
	(segment
		(start 181.130702 -342.148668)
		(end 181.130702 -341.462106)
		(width 0.1651)
		(layer "In11.Cu")
		(net "P5E_PEX1_STN7_TX_DN<121>")
	)
	(segment
		(start 181.130702 -341.462106)
		(end 179.49418 -339.68817)
		(width 0.1651)
		(layer "In11.Cu")
		(net "P5E_PEX1_STN7_TX_DN<121>")
	)
	(segment
		(start 153.32964 -312.264552)
		(end 153.32964 -312.138822)
		(width 0.1143)
		(layer "In11.Cu")
		(net "P5E_PEX1_STN7_TX_DN<121>")
	)
	(segment
		(start 179.49418 -339.68817)
		(end 172.085762 -335.41843)
		(width 0.1651)
		(layer "In11.Cu")
		(net "P5E_PEX1_STN7_TX_DN<121>")
	)
	(segment
		(start 153.24074 -312.049922)
		(end 152.94991 -312.049922)
		(width 0.1143)
		(layer "In11.Cu")
		(net "P5E_PEX1_STN7_TX_DN<121>")
	)
	(segment
		(start 152.149302 -312.834274)
		(end 152.214326 -312.834274)
		(width 0.1143)
		(layer "In11.Cu")
		(net "P5E_PEX1_STN7_TX_DN<121>")
	)
	(segment
		(start 180.839872 -342.439498)
		(end 181.130702 -342.148668)
		(width 0.1651)
		(layer "In11.Cu")
		(net "P5E_PEX1_STN7_TX_DN<121>")
	)
	(segment
		(start 150.068534 -317.861442)
		(end 150.068534 -316.549786)
		(width 0.1651)
		(layer "In11.Cu")
		(net "P5E_PEX1_STN7_TX_DN<121>")
	)
	(segment
		(start 152.214326 -312.834274)
		(end 152.618948 -312.429652)
		(width 0.1143)
		(layer "In11.Cu")
		(net "P5E_PEX1_STN7_TX_DN<121>")
	)
	(segment
		(start 153.16454 -312.429652)
		(end 153.32964 -312.264552)
		(width 0.1143)
		(layer "In11.Cu")
		(net "P5E_PEX1_STN7_TX_DN<121>")
	)
	(segment
		(start 129.109978 -397.790162)
		(end 129.109978 -397.408146)
		(width 0.1651)
		(layer "In5.Cu")
		(net "P5E_PEX1_STN5_RX_DN<86>")
	)
	(segment
		(start 162.80003 -338.712048)
		(end 176.922938 -330.166218)
		(width 0.1651)
		(layer "In5.Cu")
		(net "P5E_PEX1_STN5_RX_DN<86>")
	)
	(segment
		(start 154.560016 -354.124006)
		(end 161.612326 -340.040722)
		(width 0.1651)
		(layer "In5.Cu")
		(net "P5E_PEX1_STN5_RX_DN<86>")
	)
	(segment
		(start 161.612326 -340.040722)
		(end 162.80003 -338.712048)
		(width 0.1651)
		(layer "In5.Cu")
		(net "P5E_PEX1_STN5_RX_DN<86>")
	)
	(segment
		(start 180.16601 -324.201536)
		(end 180.16601 -319.91173)
		(width 0.1651)
		(layer "In5.Cu")
		(net "P5E_PEX1_STN5_RX_DN<86>")
	)
	(segment
		(start 140.742416 -390.630156)
		(end 140.790422 -390.59612)
		(width 0.1651)
		(layer "In5.Cu")
		(net "P5E_PEX1_STN5_RX_DN<86>")
	)
	(segment
		(start 130.169412 -396.009622)
		(end 132.271516 -393.907518)
		(width 0.1651)
		(layer "In5.Cu")
		(net "P5E_PEX1_STN5_RX_DN<86>")
	)
	(segment
		(start 129.109978 -397.408146)
		(end 129.236978 -397.281146)
		(width 0.1651)
		(layer "In5.Cu")
		(net "P5E_PEX1_STN5_RX_DN<86>")
	)
	(segment
		(start 180.16601 -319.91173)
		(end 180.16601 -319.883282)
		(width 0.1143)
		(layer "In5.Cu")
		(net "P5E_PEX1_STN5_RX_DN<86>")
	)
	(segment
		(start 180.50002 -316.534292)
		(end 180.50002 -316.799722)
		(width 0.1143)
		(layer "In5.Cu")
		(net "P5E_PEX1_STN5_RX_DN<86>")
	)
	(segment
		(start 133.46176 -393.442698)
		(end 138.04519 -392.529822)
		(width 0.1651)
		(layer "In5.Cu")
		(net "P5E_PEX1_STN5_RX_DN<86>")
	)
	(segment
		(start 148.544534 -370.96446)
		(end 149.690074 -366.97285)
		(width 0.1651)
		(layer "In5.Cu")
		(net "P5E_PEX1_STN5_RX_DN<86>")
	)
	(segment
		(start 180.12029 -316.534292)
		(end 180.23459 -316.419992)
		(width 0.1143)
		(layer "In5.Cu")
		(net "P5E_PEX1_STN5_RX_DN<86>")
	)
	(segment
		(start 140.742416 -390.629902)
		(end 140.742416 -390.630156)
		(width 0.1651)
		(layer "In5.Cu")
		(net "P5E_PEX1_STN5_RX_DN<86>")
	)
	(segment
		(start 132.271516 -393.907518)
		(end 133.46176 -393.442698)
		(width 0.1651)
		(layer "In5.Cu")
		(net "P5E_PEX1_STN5_RX_DN<86>")
	)
	(segment
		(start 176.922938 -330.166218)
		(end 178.834034 -327.936606)
		(width 0.1651)
		(layer "In5.Cu")
		(net "P5E_PEX1_STN5_RX_DN<86>")
	)
	(segment
		(start 179.573174 -326.15378)
		(end 180.16601 -324.201536)
		(width 0.1651)
		(layer "In5.Cu")
		(net "P5E_PEX1_STN5_RX_DN<86>")
	)
	(segment
		(start 138.04519 -392.529822)
		(end 140.742416 -390.629902)
		(width 0.1651)
		(layer "In5.Cu")
		(net "P5E_PEX1_STN5_RX_DN<86>")
	)
	(segment
		(start 180.23459 -316.419992)
		(end 180.38572 -316.419992)
		(width 0.1143)
		(layer "In5.Cu")
		(net "P5E_PEX1_STN5_RX_DN<86>")
	)
	(segment
		(start 130.169412 -396.898368)
		(end 130.169412 -396.009622)
		(width 0.1651)
		(layer "In5.Cu")
		(net "P5E_PEX1_STN5_RX_DN<86>")
	)
	(segment
		(start 129.236978 -397.281146)
		(end 129.786634 -397.281146)
		(width 0.1651)
		(layer "In5.Cu")
		(net "P5E_PEX1_STN5_RX_DN<86>")
	)
	(segment
		(start 178.834034 -327.936606)
		(end 179.573174 -326.15378)
		(width 0.1651)
		(layer "In5.Cu")
		(net "P5E_PEX1_STN5_RX_DN<86>")
	)
	(segment
		(start 180.16601 -319.883282)
		(end 180.12029 -319.837562)
		(width 0.1143)
		(layer "In5.Cu")
		(net "P5E_PEX1_STN5_RX_DN<86>")
	)
	(segment
		(start 180.38572 -316.419992)
		(end 180.50002 -316.534292)
		(width 0.1143)
		(layer "In5.Cu")
		(net "P5E_PEX1_STN5_RX_DN<86>")
	)
	(segment
		(start 129.786634 -397.281146)
		(end 130.169412 -396.898368)
		(width 0.1651)
		(layer "In5.Cu")
		(net "P5E_PEX1_STN5_RX_DN<86>")
	)
	(segment
		(start 142.00124 -388.596124)
		(end 148.544534 -370.96446)
		(width 0.1651)
		(layer "In5.Cu")
		(net "P5E_PEX1_STN5_RX_DN<86>")
	)
	(segment
		(start 149.690074 -366.97285)
		(end 154.560016 -354.124006)
		(width 0.1651)
		(layer "In5.Cu")
		(net "P5E_PEX1_STN5_RX_DN<86>")
	)
	(segment
		(start 140.790422 -390.59612)
		(end 142.00124 -388.596124)
		(width 0.1651)
		(layer "In5.Cu")
		(net "P5E_PEX1_STN5_RX_DN<86>")
	)
	(segment
		(start 180.12029 -319.837562)
		(end 180.12029 -316.534292)
		(width 0.1143)
		(layer "In5.Cu")
		(net "P5E_PEX1_STN5_RX_DN<86>")
	)
	(segment
		(start 196.385942 -154.304746)
		(end 196.705982 -153.984706)
		(width 0.13462)
		(layer "F.Cu")
		(net "P5E_PEX1_STN0_TX_DN<14>")
	)
	(segment
		(start 197.337426 -153.984706)
		(end 197.632066 -154.279346)
		(width 0.13462)
		(layer "F.Cu")
		(net "P5E_PEX1_STN0_TX_DN<14>")
	)
	(segment
		(start 196.705982 -153.984706)
		(end 197.337426 -153.984706)
		(width 0.13462)
		(layer "F.Cu")
		(net "P5E_PEX1_STN0_TX_DN<14>")
	)
	(segment
		(start 200.920858 -153.988516)
		(end 202.187048 -155.254706)
		(width 0.1651)
		(layer "In9.Cu")
		(net "P5E_PEX1_STN0_TX_DN<14>")
	)
	(segment
		(start 192.458086 -178.608736)
		(end 192.334134 -178.712622)
		(width 0.1651)
		(layer "In9.Cu")
		(net "P5E_PEX1_STN0_TX_DN<14>")
	)
	(segment
		(start 192.334134 -178.712622)
		(end 192.29197 -179.193698)
		(width 0.1651)
		(layer "In9.Cu")
		(net "P5E_PEX1_STN0_TX_DN<14>")
	)
	(segment
		(start 188.727842 -221.249748)
		(end 192.176146 -260.679438)
		(width 0.1651)
		(layer "In9.Cu")
		(net "P5E_PEX1_STN0_TX_DN<14>")
	)
	(segment
		(start 191.900048 -280.434288)
		(end 191.900048 -280.699718)
		(width 0.1143)
		(layer "In9.Cu")
		(net "P5E_PEX1_STN0_TX_DN<14>")
	)
	(segment
		(start 192.616836 -176.794414)
		(end 192.566544 -177.371248)
		(width 0.1651)
		(layer "In9.Cu")
		(net "P5E_PEX1_STN0_TX_DN<14>")
	)
	(segment
		(start 191.284098 -271.554448)
		(end 191.329818 -271.600168)
		(width 0.1143)
		(layer "In9.Cu")
		(net "P5E_PEX1_STN0_TX_DN<14>")
	)
	(segment
		(start 192.176146 -267.60424)
		(end 191.284098 -269.758414)
		(width 0.1651)
		(layer "In9.Cu")
		(net "P5E_PEX1_STN0_TX_DN<14>")
	)
	(segment
		(start 197.922896 -153.988516)
		(end 200.920858 -153.988516)
		(width 0.1651)
		(layer "In9.Cu")
		(net "P5E_PEX1_STN0_TX_DN<14>")
	)
	(segment
		(start 194.125088 -171.164758)
		(end 192.616836 -176.794414)
		(width 0.1651)
		(layer "In9.Cu")
		(net "P5E_PEX1_STN0_TX_DN<14>")
	)
	(segment
		(start 191.284098 -269.758414)
		(end 191.284098 -271.526)
		(width 0.1651)
		(layer "In9.Cu")
		(net "P5E_PEX1_STN0_TX_DN<14>")
	)
	(segment
		(start 192.400428 -177.95621)
		(end 192.504314 -178.080162)
		(width 0.1651)
		(layer "In9.Cu")
		(net "P5E_PEX1_STN0_TX_DN<14>")
	)
	(segment
		(start 202.441302 -155.868624)
		(end 202.441302 -156.760164)
		(width 0.1651)
		(layer "In9.Cu")
		(net "P5E_PEX1_STN0_TX_DN<14>")
	)
	(segment
		(start 192.566544 -177.371248)
		(end 192.442338 -177.475134)
		(width 0.1651)
		(layer "In9.Cu")
		(net "P5E_PEX1_STN0_TX_DN<14>")
	)
	(segment
		(start 202.187048 -155.254706)
		(end 202.441302 -155.868624)
		(width 0.1651)
		(layer "In9.Cu")
		(net "P5E_PEX1_STN0_TX_DN<14>")
	)
	(segment
		(start 192.442338 -177.475134)
		(end 192.400428 -177.95621)
		(width 0.1651)
		(layer "In9.Cu")
		(net "P5E_PEX1_STN0_TX_DN<14>")
	)
	(segment
		(start 191.329818 -280.10485)
		(end 191.544956 -280.319988)
		(width 0.1143)
		(layer "In9.Cu")
		(net "P5E_PEX1_STN0_TX_DN<14>")
	)
	(segment
		(start 191.785748 -280.319988)
		(end 191.900048 -280.434288)
		(width 0.1143)
		(layer "In9.Cu")
		(net "P5E_PEX1_STN0_TX_DN<14>")
	)
	(segment
		(start 191.544956 -280.319988)
		(end 191.785748 -280.319988)
		(width 0.1143)
		(layer "In9.Cu")
		(net "P5E_PEX1_STN0_TX_DN<14>")
	)
	(segment
		(start 192.395856 -179.317396)
		(end 192.39611 -179.31765)
		(width 0.1651)
		(layer "In9.Cu")
		(net "P5E_PEX1_STN0_TX_DN<14>")
	)
	(segment
		(start 191.284098 -271.526)
		(end 191.284098 -271.554448)
		(width 0.1143)
		(layer "In9.Cu")
		(net "P5E_PEX1_STN0_TX_DN<14>")
	)
	(segment
		(start 191.329818 -271.600168)
		(end 191.329818 -280.10485)
		(width 0.1143)
		(layer "In9.Cu")
		(net "P5E_PEX1_STN0_TX_DN<14>")
	)
	(segment
		(start 202.441302 -156.760164)
		(end 194.125088 -171.164758)
		(width 0.1651)
		(layer "In9.Cu")
		(net "P5E_PEX1_STN0_TX_DN<14>")
	)
	(segment
		(start 192.29197 -179.193698)
		(end 192.395856 -179.317396)
		(width 0.1651)
		(layer "In9.Cu")
		(net "P5E_PEX1_STN0_TX_DN<14>")
	)
	(segment
		(start 197.632066 -154.279346)
		(end 197.922896 -153.988516)
		(width 0.1651)
		(layer "In9.Cu")
		(net "P5E_PEX1_STN0_TX_DN<14>")
	)
	(segment
		(start 192.39611 -179.31765)
		(end 188.727842 -221.249748)
		(width 0.1651)
		(layer "In9.Cu")
		(net "P5E_PEX1_STN0_TX_DN<14>")
	)
	(segment
		(start 192.176146 -260.679438)
		(end 192.176146 -267.60424)
		(width 0.1651)
		(layer "In9.Cu")
		(net "P5E_PEX1_STN0_TX_DN<14>")
	)
	(segment
		(start 192.504314 -178.080162)
		(end 192.458086 -178.608736)
		(width 0.1651)
		(layer "In9.Cu")
		(net "P5E_PEX1_STN0_TX_DN<14>")
	)
	(segment
		(start 183.923432 -349.831914)
		(end 184.243472 -349.511874)
		(width 0.13462)
		(layer "F.Cu")
		(net "P5E_PEX1_STN7_TX_DP<123>")
	)
	(segment
		(start 184.243472 -348.88043)
		(end 183.948832 -348.58579)
		(width 0.13462)
		(layer "F.Cu")
		(net "P5E_PEX1_STN7_TX_DP<123>")
	)
	(segment
		(start 184.243472 -349.511874)
		(end 184.243472 -348.88043)
		(width 0.13462)
		(layer "F.Cu")
		(net "P5E_PEX1_STN7_TX_DP<123>")
	)
	(segment
		(start 154.728418 -322.95973)
		(end 154.234134 -321.895216)
		(width 0.1651)
		(layer "In11.Cu")
		(net "P5E_PEX1_STN7_TX_DP<123>")
	)
	(segment
		(start 154.234134 -321.895216)
		(end 154.234134 -320.043048)
		(width 0.1651)
		(layer "In11.Cu")
		(net "P5E_PEX1_STN7_TX_DP<123>")
	)
	(segment
		(start 154.234134 -320.02095)
		(end 154.279854 -319.97523)
		(width 0.1143)
		(layer "In11.Cu")
		(net "P5E_PEX1_STN7_TX_DP<123>")
	)
	(segment
		(start 185.794142 -341.961724)
		(end 184.804812 -340.643972)
		(width 0.1651)
		(layer "In11.Cu")
		(net "P5E_PEX1_STN7_TX_DP<123>")
	)
	(segment
		(start 154.761184 -313.379612)
		(end 154.850084 -313.290712)
		(width 0.1143)
		(layer "In11.Cu")
		(net "P5E_PEX1_STN7_TX_DP<123>")
	)
	(segment
		(start 154.850084 -313.290712)
		(end 154.850084 -312.999882)
		(width 0.1143)
		(layer "In11.Cu")
		(net "P5E_PEX1_STN7_TX_DP<123>")
	)
	(segment
		(start 154.279854 -319.97523)
		(end 154.279854 -313.6392)
		(width 0.1143)
		(layer "In11.Cu")
		(net "P5E_PEX1_STN7_TX_DP<123>")
	)
	(segment
		(start 183.948832 -348.58579)
		(end 184.239662 -348.29496)
		(width 0.1651)
		(layer "In11.Cu")
		(net "P5E_PEX1_STN7_TX_DP<123>")
	)
	(segment
		(start 184.239662 -348.29496)
		(end 184.239662 -347.578426)
		(width 0.1651)
		(layer "In11.Cu")
		(net "P5E_PEX1_STN7_TX_DP<123>")
	)
	(segment
		(start 176.803812 -335.601818)
		(end 157.084268 -325.418958)
		(width 0.1651)
		(layer "In11.Cu")
		(net "P5E_PEX1_STN7_TX_DP<123>")
	)
	(segment
		(start 184.239662 -347.578426)
		(end 185.794142 -346.023946)
		(width 0.1651)
		(layer "In11.Cu")
		(net "P5E_PEX1_STN7_TX_DP<123>")
	)
	(segment
		(start 184.804812 -340.643972)
		(end 181.795674 -338.478368)
		(width 0.1651)
		(layer "In11.Cu")
		(net "P5E_PEX1_STN7_TX_DP<123>")
	)
	(segment
		(start 181.795674 -338.478368)
		(end 176.803812 -335.601818)
		(width 0.1651)
		(layer "In11.Cu")
		(net "P5E_PEX1_STN7_TX_DP<123>")
	)
	(segment
		(start 157.084268 -325.418958)
		(end 154.728418 -322.95973)
		(width 0.1651)
		(layer "In11.Cu")
		(net "P5E_PEX1_STN7_TX_DP<123>")
	)
	(segment
		(start 185.794142 -346.023946)
		(end 185.794142 -341.961724)
		(width 0.1651)
		(layer "In11.Cu")
		(net "P5E_PEX1_STN7_TX_DP<123>")
	)
	(segment
		(start 154.279854 -313.6392)
		(end 154.539442 -313.379612)
		(width 0.1143)
		(layer "In11.Cu")
		(net "P5E_PEX1_STN7_TX_DP<123>")
	)
	(segment
		(start 154.234134 -320.043048)
		(end 154.234134 -320.02095)
		(width 0.1143)
		(layer "In11.Cu")
		(net "P5E_PEX1_STN7_TX_DP<123>")
	)
	(segment
		(start 154.539442 -313.379612)
		(end 154.761184 -313.379612)
		(width 0.1143)
		(layer "In11.Cu")
		(net "P5E_PEX1_STN7_TX_DP<123>")
	)
	(segment
		(start 148.245322 -309.747412)
		(end 148.245576 -309.747412)
		(width 0.1651)
		(layer "In9.Cu")
		(net "P5E_PEX1_STN7_RX_DP<119>")
	)
	(segment
		(start 176.192434 -409.26512)
		(end 176.192434 -396.00632)
		(width 0.1651)
		(layer "In9.Cu")
		(net "P5E_PEX1_STN7_RX_DP<119>")
	)
	(segment
		(start 176.192434 -396.00632)
		(end 175.920654 -395.350238)
		(width 0.1651)
		(layer "In9.Cu")
		(net "P5E_PEX1_STN7_RX_DP<119>")
	)
	(segment
		(start 151.281892 -339.905594)
		(end 145.923 -331.235304)
		(width 0.1651)
		(layer "In9.Cu")
		(net "P5E_PEX1_STN7_RX_DP<119>")
	)
	(segment
		(start 175.310038 -409.672028)
		(end 175.437038 -409.799028)
		(width 0.1651)
		(layer "In9.Cu")
		(net "P5E_PEX1_STN7_RX_DP<119>")
	)
	(segment
		(start 153.280872 -307.679598)
		(end 153.524712 -307.923438)
		(width 0.1143)
		(layer "In9.Cu")
		(net "P5E_PEX1_STN7_RX_DP<119>")
	)
	(segment
		(start 175.658526 -409.799028)
		(end 176.192434 -409.26512)
		(width 0.1651)
		(layer "In9.Cu")
		(net "P5E_PEX1_STN7_RX_DP<119>")
	)
	(segment
		(start 149.850856 -308.142132)
		(end 150.363428 -307.799486)
		(width 0.1651)
		(layer "In9.Cu")
		(net "P5E_PEX1_STN7_RX_DP<119>")
	)
	(segment
		(start 175.920654 -395.350238)
		(end 174.30877 -393.738354)
		(width 0.1651)
		(layer "In9.Cu")
		(net "P5E_PEX1_STN7_RX_DP<119>")
	)
	(segment
		(start 161.619946 -387.428232)
		(end 159.145732 -385.41071)
		(width 0.1651)
		(layer "In9.Cu")
		(net "P5E_PEX1_STN7_RX_DP<119>")
	)
	(segment
		(start 175.437038 -409.799028)
		(end 175.658526 -409.799028)
		(width 0.1651)
		(layer "In9.Cu")
		(net "P5E_PEX1_STN7_RX_DP<119>")
	)
	(segment
		(start 145.923 -331.235304)
		(end 145.923254 -331.235304)
		(width 0.1651)
		(layer "In9.Cu")
		(net "P5E_PEX1_STN7_RX_DP<119>")
	)
	(segment
		(start 140.464032 -320.10477)
		(end 141.449552 -317.882778)
		(width 0.1651)
		(layer "In9.Cu")
		(net "P5E_PEX1_STN7_RX_DP<119>")
	)
	(segment
		(start 153.6192 -308.249828)
		(end 153.89987 -308.249828)
		(width 0.1143)
		(layer "In9.Cu")
		(net "P5E_PEX1_STN7_RX_DP<119>")
	)
	(segment
		(start 151.793448 -307.633878)
		(end 151.839168 -307.679598)
		(width 0.1143)
		(layer "In9.Cu")
		(net "P5E_PEX1_STN7_RX_DP<119>")
	)
	(segment
		(start 145.310352 -312.682382)
		(end 148.245322 -309.747412)
		(width 0.1651)
		(layer "In9.Cu")
		(net "P5E_PEX1_STN7_RX_DP<119>")
	)
	(segment
		(start 153.524712 -307.923438)
		(end 153.524712 -308.15534)
		(width 0.1143)
		(layer "In9.Cu")
		(net "P5E_PEX1_STN7_RX_DP<119>")
	)
	(segment
		(start 148.245576 -309.747412)
		(end 149.850856 -308.142132)
		(width 0.1651)
		(layer "In9.Cu")
		(net "P5E_PEX1_STN7_RX_DP<119>")
	)
	(segment
		(start 153.524712 -308.15534)
		(end 153.6192 -308.249828)
		(width 0.1143)
		(layer "In9.Cu")
		(net "P5E_PEX1_STN7_RX_DP<119>")
	)
	(segment
		(start 150.363428 -307.799486)
		(end 150.763732 -307.633878)
		(width 0.1651)
		(layer "In9.Cu")
		(net "P5E_PEX1_STN7_RX_DP<119>")
	)
	(segment
		(start 141.449552 -317.882778)
		(end 143.324072 -315.077348)
		(width 0.1651)
		(layer "In9.Cu")
		(net "P5E_PEX1_STN7_RX_DP<119>")
	)
	(segment
		(start 151.765 -307.633878)
		(end 151.793448 -307.633878)
		(width 0.1143)
		(layer "In9.Cu")
		(net "P5E_PEX1_STN7_RX_DP<119>")
	)
	(segment
		(start 143.324072 -315.077348)
		(end 145.310352 -312.682382)
		(width 0.1651)
		(layer "In9.Cu")
		(net "P5E_PEX1_STN7_RX_DP<119>")
	)
	(segment
		(start 159.145732 -385.41071)
		(end 158.04769 -383.41681)
		(width 0.1651)
		(layer "In9.Cu")
		(net "P5E_PEX1_STN7_RX_DP<119>")
	)
	(segment
		(start 152.71115 -343.89568)
		(end 151.281892 -339.905594)
		(width 0.1651)
		(layer "In9.Cu")
		(net "P5E_PEX1_STN7_RX_DP<119>")
	)
	(segment
		(start 140.464032 -322.269612)
		(end 140.464032 -320.10477)
		(width 0.1651)
		(layer "In9.Cu")
		(net "P5E_PEX1_STN7_RX_DP<119>")
	)
	(segment
		(start 151.839168 -307.679598)
		(end 153.280872 -307.679598)
		(width 0.1143)
		(layer "In9.Cu")
		(net "P5E_PEX1_STN7_RX_DP<119>")
	)
	(segment
		(start 175.310038 -409.290012)
		(end 175.310038 -409.672028)
		(width 0.1651)
		(layer "In9.Cu")
		(net "P5E_PEX1_STN7_RX_DP<119>")
	)
	(segment
		(start 145.923254 -331.235304)
		(end 140.527024 -322.504308)
		(width 0.1651)
		(layer "In9.Cu")
		(net "P5E_PEX1_STN7_RX_DP<119>")
	)
	(segment
		(start 170.170094 -390.972294)
		(end 161.619946 -387.428232)
		(width 0.1651)
		(layer "In9.Cu")
		(net "P5E_PEX1_STN7_RX_DP<119>")
	)
	(segment
		(start 174.30877 -393.738354)
		(end 170.170094 -390.972294)
		(width 0.1651)
		(layer "In9.Cu")
		(net "P5E_PEX1_STN7_RX_DP<119>")
	)
	(segment
		(start 158.04769 -383.41681)
		(end 152.71115 -343.89568)
		(width 0.1651)
		(layer "In9.Cu")
		(net "P5E_PEX1_STN7_RX_DP<119>")
	)
	(segment
		(start 140.527024 -322.504308)
		(end 140.464032 -322.269612)
		(width 0.1651)
		(layer "In9.Cu")
		(net "P5E_PEX1_STN7_RX_DP<119>")
	)
	(segment
		(start 150.763732 -307.633878)
		(end 151.765 -307.633878)
		(width 0.1651)
		(layer "In9.Cu")
		(net "P5E_PEX1_STN7_RX_DP<119>")
	)
	(segment
		(start 341.636096 -365.547402)
		(end 341.67953 -365.053626)
		(width 0.1651)
		(layer "In5.Cu")
		(net "P5E_PEX2_STN5_RX_DP<92>")
	)
	(segment
		(start 341.673688 -366.136936)
		(end 341.716868 -365.643668)
		(width 0.1651)
		(layer "In5.Cu")
		(net "P5E_PEX2_STN5_RX_DP<92>")
	)
	(segment
		(start 341.885778 -362.702348)
		(end 341.929212 -362.208826)
		(width 0.1651)
		(layer "In5.Cu")
		(net "P5E_PEX2_STN5_RX_DP<92>")
	)
	(segment
		(start 301.729648 -319.895728)
		(end 301.729648 -316.455298)
		(width 0.1143)
		(layer "In5.Cu")
		(net "P5E_PEX2_STN5_RX_DP<92>")
	)
	(segment
		(start 342.025732 -362.128054)
		(end 342.025478 -362.128054)
		(width 0.1651)
		(layer "In5.Cu")
		(net "P5E_PEX2_STN5_RX_DP<92>")
	)
	(segment
		(start 341.77605 -364.972854)
		(end 341.775796 -364.972854)
		(width 0.1651)
		(layer "In5.Cu")
		(net "P5E_PEX2_STN5_RX_DP<92>")
	)
	(segment
		(start 342.328754 -358.67594)
		(end 342.328754 -341.945214)
		(width 0.1651)
		(layer "In5.Cu")
		(net "P5E_PEX2_STN5_RX_DP<92>")
	)
	(segment
		(start 342.025478 -362.128054)
		(end 342.068658 -361.634786)
		(width 0.1651)
		(layer "In5.Cu")
		(net "P5E_PEX2_STN5_RX_DP<92>")
	)
	(segment
		(start 342.068658 -361.634786)
		(end 341.987886 -361.53852)
		(width 0.1651)
		(layer "In5.Cu")
		(net "P5E_PEX2_STN5_RX_DP<92>")
	)
	(segment
		(start 342.328754 -341.945214)
		(end 341.729568 -341.346028)
		(width 0.1651)
		(layer "In5.Cu")
		(net "P5E_PEX2_STN5_RX_DP<92>")
	)
	(segment
		(start 341.96655 -362.798868)
		(end 341.885778 -362.702348)
		(width 0.1651)
		(layer "In5.Cu")
		(net "P5E_PEX2_STN5_RX_DP<92>")
	)
	(segment
		(start 341.533734 -366.711484)
		(end 341.577168 -366.217708)
		(width 0.1651)
		(layer "In5.Cu")
		(net "P5E_PEX2_STN5_RX_DP<92>")
	)
	(segment
		(start 341.474806 -367.38179)
		(end 341.57158 -367.301018)
		(width 0.1651)
		(layer "In5.Cu")
		(net "P5E_PEX2_STN5_RX_DP<92>")
	)
	(segment
		(start 302.089566 -321.789298)
		(end 301.683928 -320.810128)
		(width 0.1651)
		(layer "In5.Cu")
		(net "P5E_PEX2_STN5_RX_DP<92>")
	)
	(segment
		(start 341.577168 -366.217708)
		(end 341.673688 -366.136936)
		(width 0.1651)
		(layer "In5.Cu")
		(net "P5E_PEX2_STN5_RX_DP<92>")
	)
	(segment
		(start 341.571326 -367.301018)
		(end 341.614506 -366.80775)
		(width 0.1651)
		(layer "In5.Cu")
		(net "P5E_PEX2_STN5_RX_DP<92>")
	)
	(segment
		(start 340.41715 -370.999258)
		(end 340.847426 -370.999258)
		(width 0.1651)
		(layer "In5.Cu")
		(net "P5E_PEX2_STN5_RX_DP<92>")
	)
	(segment
		(start 301.683928 -319.969896)
		(end 301.683928 -319.941448)
		(width 0.1143)
		(layer "In5.Cu")
		(net "P5E_PEX2_STN5_RX_DP<92>")
	)
	(segment
		(start 342.03132 -361.044744)
		(end 342.12784 -360.963972)
		(width 0.1651)
		(layer "In5.Cu")
		(net "P5E_PEX2_STN5_RX_DP<92>")
	)
	(segment
		(start 342.12784 -360.963972)
		(end 342.328754 -358.67594)
		(width 0.1651)
		(layer "In5.Cu")
		(net "P5E_PEX2_STN5_RX_DP<92>")
	)
	(segment
		(start 341.729568 -341.346028)
		(end 305.388518 -324.24624)
		(width 0.1651)
		(layer "In5.Cu")
		(net "P5E_PEX2_STN5_RX_DP<92>")
	)
	(segment
		(start 305.388518 -324.24624)
		(end 303.798478 -323.49821)
		(width 0.1651)
		(layer "In5.Cu")
		(net "P5E_PEX2_STN5_RX_DP<92>")
	)
	(segment
		(start 301.729648 -316.455298)
		(end 301.955454 -316.229492)
		(width 0.1143)
		(layer "In5.Cu")
		(net "P5E_PEX2_STN5_RX_DP<92>")
	)
	(segment
		(start 302.185578 -316.229492)
		(end 302.299878 -316.115192)
		(width 0.1143)
		(layer "In5.Cu")
		(net "P5E_PEX2_STN5_RX_DP<92>")
	)
	(segment
		(start 341.67953 -365.053626)
		(end 341.77605 -364.972854)
		(width 0.1651)
		(layer "In5.Cu")
		(net "P5E_PEX2_STN5_RX_DP<92>")
	)
	(segment
		(start 341.716868 -365.643668)
		(end 341.636096 -365.547402)
		(width 0.1651)
		(layer "In5.Cu")
		(net "P5E_PEX2_STN5_RX_DP<92>")
	)
	(segment
		(start 341.929212 -362.208826)
		(end 342.025732 -362.128054)
		(width 0.1651)
		(layer "In5.Cu")
		(net "P5E_PEX2_STN5_RX_DP<92>")
	)
	(segment
		(start 341.57158 -367.301018)
		(end 341.571326 -367.301018)
		(width 0.1651)
		(layer "In5.Cu")
		(net "P5E_PEX2_STN5_RX_DP<92>")
	)
	(segment
		(start 341.431626 -367.875312)
		(end 341.474806 -367.38179)
		(width 0.1651)
		(layer "In5.Cu")
		(net "P5E_PEX2_STN5_RX_DP<92>")
	)
	(segment
		(start 341.512398 -367.971832)
		(end 341.431626 -367.875312)
		(width 0.1651)
		(layer "In5.Cu")
		(net "P5E_PEX2_STN5_RX_DP<92>")
	)
	(segment
		(start 340.847426 -370.999258)
		(end 341.285068 -370.561362)
		(width 0.1651)
		(layer "In5.Cu")
		(net "P5E_PEX2_STN5_RX_DP<92>")
	)
	(segment
		(start 340.29015 -370.872258)
		(end 340.41715 -370.999258)
		(width 0.1651)
		(layer "In5.Cu")
		(net "P5E_PEX2_STN5_RX_DP<92>")
	)
	(segment
		(start 341.775796 -364.972854)
		(end 341.96655 -362.798868)
		(width 0.1651)
		(layer "In5.Cu")
		(net "P5E_PEX2_STN5_RX_DP<92>")
	)
	(segment
		(start 301.683928 -319.941448)
		(end 301.729648 -319.895728)
		(width 0.1143)
		(layer "In5.Cu")
		(net "P5E_PEX2_STN5_RX_DP<92>")
	)
	(segment
		(start 303.798478 -323.49821)
		(end 302.089566 -321.789298)
		(width 0.1651)
		(layer "In5.Cu")
		(net "P5E_PEX2_STN5_RX_DP<92>")
	)
	(segment
		(start 341.614506 -366.80775)
		(end 341.533734 -366.711484)
		(width 0.1651)
		(layer "In5.Cu")
		(net "P5E_PEX2_STN5_RX_DP<92>")
	)
	(segment
		(start 341.285068 -370.561362)
		(end 341.512398 -367.971832)
		(width 0.1651)
		(layer "In5.Cu")
		(net "P5E_PEX2_STN5_RX_DP<92>")
	)
	(segment
		(start 340.29015 -370.489988)
		(end 340.29015 -370.872258)
		(width 0.1651)
		(layer "In5.Cu")
		(net "P5E_PEX2_STN5_RX_DP<92>")
	)
	(segment
		(start 301.683928 -320.810128)
		(end 301.683928 -319.969896)
		(width 0.1651)
		(layer "In5.Cu")
		(net "P5E_PEX2_STN5_RX_DP<92>")
	)
	(segment
		(start 341.987886 -361.53852)
		(end 342.03132 -361.044744)
		(width 0.1651)
		(layer "In5.Cu")
		(net "P5E_PEX2_STN5_RX_DP<92>")
	)
	(segment
		(start 302.299878 -316.115192)
		(end 302.299878 -315.849762)
		(width 0.1143)
		(layer "In5.Cu")
		(net "P5E_PEX2_STN5_RX_DP<92>")
	)
	(segment
		(start 301.955454 -316.229492)
		(end 302.185578 -316.229492)
		(width 0.1143)
		(layer "In5.Cu")
		(net "P5E_PEX2_STN5_RX_DP<92>")
	)
	(segment
		(start 152.761188 -101.415342)
		(end 152.129744 -101.415342)
		(width 0.13462)
		(layer "F.Cu")
		(net "P5E_PEX1_STN1_TX_DN<17>")
	)
	(segment
		(start 153.081228 -101.095302)
		(end 152.761188 -101.415342)
		(width 0.13462)
		(layer "F.Cu")
		(net "P5E_PEX1_STN1_TX_DN<17>")
	)
	(segment
		(start 152.129744 -101.415342)
		(end 151.835104 -101.120702)
		(width 0.13462)
		(layer "F.Cu")
		(net "P5E_PEX1_STN1_TX_DN<17>")
	)
	(segment
		(start 142.750794 -112.762538)
		(end 137.27303 -130.82016)
		(width 0.1651)
		(layer "In9.Cu")
		(net "P5E_PEX1_STN1_TX_DN<17>")
	)
	(segment
		(start 141.147546 -162.555174)
		(end 176.083976 -265.771122)
		(width 0.1651)
		(layer "In9.Cu")
		(net "P5E_PEX1_STN1_TX_DN<17>")
	)
	(segment
		(start 145.2118 -106.821478)
		(end 142.750794 -112.762538)
		(width 0.1651)
		(layer "In9.Cu")
		(net "P5E_PEX1_STN1_TX_DN<17>")
	)
	(segment
		(start 176.129696 -280.10485)
		(end 176.344834 -280.319988)
		(width 0.1143)
		(layer "In9.Cu")
		(net "P5E_PEX1_STN1_TX_DN<17>")
	)
	(segment
		(start 137.27303 -138.880088)
		(end 139.86002 -145.126456)
		(width 0.1651)
		(layer "In9.Cu")
		(net "P5E_PEX1_STN1_TX_DN<17>")
	)
	(segment
		(start 176.129696 -271.600168)
		(end 176.129696 -280.10485)
		(width 0.1143)
		(layer "In9.Cu")
		(net "P5E_PEX1_STN1_TX_DN<17>")
	)
	(segment
		(start 151.835104 -101.120702)
		(end 151.544274 -101.411532)
		(width 0.1651)
		(layer "In9.Cu")
		(net "P5E_PEX1_STN1_TX_DN<17>")
	)
	(segment
		(start 176.083976 -271.526)
		(end 176.083976 -271.554448)
		(width 0.1143)
		(layer "In9.Cu")
		(net "P5E_PEX1_STN1_TX_DN<17>")
	)
	(segment
		(start 176.083976 -265.771122)
		(end 176.083976 -271.526)
		(width 0.1651)
		(layer "In9.Cu")
		(net "P5E_PEX1_STN1_TX_DN<17>")
	)
	(segment
		(start 150.325328 -101.70795)
		(end 145.2118 -106.821478)
		(width 0.1651)
		(layer "In9.Cu")
		(net "P5E_PEX1_STN1_TX_DN<17>")
	)
	(segment
		(start 176.585626 -280.319988)
		(end 176.699926 -280.434288)
		(width 0.1143)
		(layer "In9.Cu")
		(net "P5E_PEX1_STN1_TX_DN<17>")
	)
	(segment
		(start 140.575284 -159.677608)
		(end 141.147546 -162.555174)
		(width 0.1651)
		(layer "In9.Cu")
		(net "P5E_PEX1_STN1_TX_DN<17>")
	)
	(segment
		(start 176.083976 -271.554448)
		(end 176.129696 -271.600168)
		(width 0.1143)
		(layer "In9.Cu")
		(net "P5E_PEX1_STN1_TX_DN<17>")
	)
	(segment
		(start 151.544274 -101.411532)
		(end 151.040846 -101.411532)
		(width 0.1651)
		(layer "In9.Cu")
		(net "P5E_PEX1_STN1_TX_DN<17>")
	)
	(segment
		(start 139.86002 -145.126456)
		(end 140.575284 -159.677608)
		(width 0.1651)
		(layer "In9.Cu")
		(net "P5E_PEX1_STN1_TX_DN<17>")
	)
	(segment
		(start 176.699926 -280.434288)
		(end 176.699926 -280.699718)
		(width 0.1143)
		(layer "In9.Cu")
		(net "P5E_PEX1_STN1_TX_DN<17>")
	)
	(segment
		(start 176.344834 -280.319988)
		(end 176.585626 -280.319988)
		(width 0.1143)
		(layer "In9.Cu")
		(net "P5E_PEX1_STN1_TX_DN<17>")
	)
	(segment
		(start 137.27303 -130.82016)
		(end 137.27303 -138.880088)
		(width 0.1651)
		(layer "In9.Cu")
		(net "P5E_PEX1_STN1_TX_DN<17>")
	)
	(segment
		(start 151.040846 -101.411532)
		(end 150.325328 -101.70795)
		(width 0.1651)
		(layer "In9.Cu")
		(net "P5E_PEX1_STN1_TX_DN<17>")
	)
	(segment
		(start 190.461392 -349.511874)
		(end 190.461392 -348.88043)
		(width 0.13462)
		(layer "F.Cu")
		(net "P5E_PEX1_STN7_TX_DP<126>")
	)
	(segment
		(start 190.461392 -348.88043)
		(end 190.166752 -348.58579)
		(width 0.13462)
		(layer "F.Cu")
		(net "P5E_PEX1_STN7_TX_DP<126>")
	)
	(segment
		(start 190.141352 -349.831914)
		(end 190.461392 -349.511874)
		(width 0.13462)
		(layer "F.Cu")
		(net "P5E_PEX1_STN7_TX_DP<126>")
	)
	(segment
		(start 157.129734 -311.779666)
		(end 157.429708 -311.479692)
		(width 0.1143)
		(layer "In11.Cu")
		(net "P5E_PEX1_STN7_TX_DP<126>")
	)
	(segment
		(start 157.084014 -321.216528)
		(end 157.084014 -320.043048)
		(width 0.1651)
		(layer "In11.Cu")
		(net "P5E_PEX1_STN7_TX_DP<126>")
	)
	(segment
		(start 192.012062 -345.991434)
		(end 192.012062 -341.87765)
		(width 0.1651)
		(layer "In11.Cu")
		(net "P5E_PEX1_STN7_TX_DP<126>")
	)
	(segment
		(start 192.012062 -341.87765)
		(end 191.264794 -340.88197)
		(width 0.1651)
		(layer "In11.Cu")
		(net "P5E_PEX1_STN7_TX_DP<126>")
	)
	(segment
		(start 190.12281 -339.870796)
		(end 173.239176 -330.141834)
		(width 0.1651)
		(layer "In11.Cu")
		(net "P5E_PEX1_STN7_TX_DP<126>")
	)
	(segment
		(start 157.699964 -311.390792)
		(end 157.699964 -311.099962)
		(width 0.1143)
		(layer "In11.Cu")
		(net "P5E_PEX1_STN7_TX_DP<126>")
	)
	(segment
		(start 158.163514 -322.344288)
		(end 157.084014 -321.216528)
		(width 0.1651)
		(layer "In11.Cu")
		(net "P5E_PEX1_STN7_TX_DP<126>")
	)
	(segment
		(start 157.084014 -320.043048)
		(end 157.084014 -320.02095)
		(width 0.1143)
		(layer "In11.Cu")
		(net "P5E_PEX1_STN7_TX_DP<126>")
	)
	(segment
		(start 157.429708 -311.479692)
		(end 157.611064 -311.479692)
		(width 0.1143)
		(layer "In11.Cu")
		(net "P5E_PEX1_STN7_TX_DP<126>")
	)
	(segment
		(start 173.239176 -330.141834)
		(end 158.163514 -322.344288)
		(width 0.1651)
		(layer "In11.Cu")
		(net "P5E_PEX1_STN7_TX_DP<126>")
	)
	(segment
		(start 157.611064 -311.479692)
		(end 157.699964 -311.390792)
		(width 0.1143)
		(layer "In11.Cu")
		(net "P5E_PEX1_STN7_TX_DP<126>")
	)
	(segment
		(start 190.457582 -347.545914)
		(end 192.012062 -345.991434)
		(width 0.1651)
		(layer "In11.Cu")
		(net "P5E_PEX1_STN7_TX_DP<126>")
	)
	(segment
		(start 157.084014 -320.02095)
		(end 157.129734 -319.97523)
		(width 0.1143)
		(layer "In11.Cu")
		(net "P5E_PEX1_STN7_TX_DP<126>")
	)
	(segment
		(start 157.129734 -319.97523)
		(end 157.129734 -311.779666)
		(width 0.1143)
		(layer "In11.Cu")
		(net "P5E_PEX1_STN7_TX_DP<126>")
	)
	(segment
		(start 191.264794 -340.88197)
		(end 190.12281 -339.870796)
		(width 0.1651)
		(layer "In11.Cu")
		(net "P5E_PEX1_STN7_TX_DP<126>")
	)
	(segment
		(start 190.457582 -348.29496)
		(end 190.457582 -347.545914)
		(width 0.1651)
		(layer "In11.Cu")
		(net "P5E_PEX1_STN7_TX_DP<126>")
	)
	(segment
		(start 190.166752 -348.58579)
		(end 190.457582 -348.29496)
		(width 0.1651)
		(layer "In11.Cu")
		(net "P5E_PEX1_STN7_TX_DP<126>")
	)
	(segment
		(start 135.721852 -393.837668)
		(end 135.77443 -393.75842)
		(width 0.1651)
		(layer "In5.Cu")
		(net "P5E_PEX1_STN5_RX_DP<87>")
	)
	(segment
		(start 179.389278 -328.369422)
		(end 180.222144 -326.35952)
		(width 0.1651)
		(layer "In5.Cu")
		(net "P5E_PEX1_STN5_RX_DP<87>")
	)
	(segment
		(start 150.353522 -367.122456)
		(end 155.021026 -354.807012)
		(width 0.1651)
		(layer "In5.Cu")
		(net "P5E_PEX1_STN5_RX_DP<87>")
	)
	(segment
		(start 132.08762 -397.881602)
		(end 132.08762 -395.140434)
		(width 0.1651)
		(layer "In5.Cu")
		(net "P5E_PEX1_STN5_RX_DP<87>")
	)
	(segment
		(start 180.87975 -319.86728)
		(end 180.87975 -318.355472)
		(width 0.1143)
		(layer "In5.Cu")
		(net "P5E_PEX1_STN5_RX_DP<87>")
	)
	(segment
		(start 180.83403 -319.913)
		(end 180.87975 -319.86728)
		(width 0.1143)
		(layer "In5.Cu")
		(net "P5E_PEX1_STN5_RX_DP<87>")
	)
	(segment
		(start 133.171692 -394.279374)
		(end 134.38886 -394.036804)
		(width 0.1651)
		(layer "In5.Cu")
		(net "P5E_PEX1_STN5_RX_DP<87>")
	)
	(segment
		(start 138.011916 -393.381738)
		(end 141.321536 -391.050526)
		(width 0.1651)
		(layer "In5.Cu")
		(net "P5E_PEX1_STN5_RX_DP<87>")
	)
	(segment
		(start 181.33568 -318.129666)
		(end 181.44998 -318.015366)
		(width 0.1143)
		(layer "In5.Cu")
		(net "P5E_PEX1_STN5_RX_DP<87>")
	)
	(segment
		(start 155.021026 -354.807012)
		(end 162.197796 -340.47557)
		(width 0.1651)
		(layer "In5.Cu")
		(net "P5E_PEX1_STN5_RX_DP<87>")
	)
	(segment
		(start 141.321536 -391.050526)
		(end 142.600426 -388.919212)
		(width 0.1651)
		(layer "In5.Cu")
		(net "P5E_PEX1_STN5_RX_DP<87>")
	)
	(segment
		(start 181.44998 -318.015366)
		(end 181.44998 -317.749936)
		(width 0.1143)
		(layer "In5.Cu")
		(net "P5E_PEX1_STN5_RX_DP<87>")
	)
	(segment
		(start 131.310126 -397.972026)
		(end 131.43738 -398.09928)
		(width 0.1651)
		(layer "In5.Cu")
		(net "P5E_PEX1_STN5_RX_DP<87>")
	)
	(segment
		(start 180.222144 -326.35952)
		(end 180.83403 -324.344284)
		(width 0.1651)
		(layer "In5.Cu")
		(net "P5E_PEX1_STN5_RX_DP<87>")
	)
	(segment
		(start 135.77443 -393.75842)
		(end 136.335262 -393.64666)
		(width 0.1651)
		(layer "In5.Cu")
		(net "P5E_PEX1_STN5_RX_DP<87>")
	)
	(segment
		(start 136.887712 -393.605512)
		(end 136.967976 -393.484862)
		(width 0.1651)
		(layer "In5.Cu")
		(net "P5E_PEX1_STN5_RX_DP<87>")
	)
	(segment
		(start 136.335262 -393.64666)
		(end 136.41451 -393.699746)
		(width 0.1651)
		(layer "In5.Cu")
		(net "P5E_PEX1_STN5_RX_DP<87>")
	)
	(segment
		(start 136.967976 -393.484862)
		(end 137.459974 -393.387072)
		(width 0.1651)
		(layer "In5.Cu")
		(net "P5E_PEX1_STN5_RX_DP<87>")
	)
	(segment
		(start 149.212808 -371.099334)
		(end 150.353522 -367.122456)
		(width 0.1651)
		(layer "In5.Cu")
		(net "P5E_PEX1_STN5_RX_DP<87>")
	)
	(segment
		(start 142.600426 -388.919212)
		(end 149.212808 -371.099334)
		(width 0.1651)
		(layer "In5.Cu")
		(net "P5E_PEX1_STN5_RX_DP<87>")
	)
	(segment
		(start 131.43738 -398.09928)
		(end 131.869942 -398.09928)
		(width 0.1651)
		(layer "In5.Cu")
		(net "P5E_PEX1_STN5_RX_DP<87>")
	)
	(segment
		(start 181.105556 -318.129666)
		(end 181.33568 -318.129666)
		(width 0.1143)
		(layer "In5.Cu")
		(net "P5E_PEX1_STN5_RX_DP<87>")
	)
	(segment
		(start 137.58037 -393.46759)
		(end 138.011916 -393.381738)
		(width 0.1651)
		(layer "In5.Cu")
		(net "P5E_PEX1_STN5_RX_DP<87>")
	)
	(segment
		(start 136.41451 -393.699746)
		(end 136.887712 -393.605512)
		(width 0.1651)
		(layer "In5.Cu")
		(net "P5E_PEX1_STN5_RX_DP<87>")
	)
	(segment
		(start 134.72287 -394.036804)
		(end 135.721852 -393.837668)
		(width 0.1651)
		(layer "In5.Cu")
		(net "P5E_PEX1_STN5_RX_DP<87>")
	)
	(segment
		(start 180.83403 -319.941448)
		(end 180.83403 -319.913)
		(width 0.1143)
		(layer "In5.Cu")
		(net "P5E_PEX1_STN5_RX_DP<87>")
	)
	(segment
		(start 134.38886 -394.036804)
		(end 134.72287 -394.036804)
		(width 0.1651)
		(layer "In5.Cu")
		(net "P5E_PEX1_STN5_RX_DP<87>")
	)
	(segment
		(start 132.691886 -394.536168)
		(end 133.171692 -394.279374)
		(width 0.1651)
		(layer "In5.Cu")
		(net "P5E_PEX1_STN5_RX_DP<87>")
	)
	(segment
		(start 163.387278 -339.144356)
		(end 177.443638 -330.637896)
		(width 0.1651)
		(layer "In5.Cu")
		(net "P5E_PEX1_STN5_RX_DP<87>")
	)
	(segment
		(start 180.83403 -324.344284)
		(end 180.83403 -319.941448)
		(width 0.1651)
		(layer "In5.Cu")
		(net "P5E_PEX1_STN5_RX_DP<87>")
	)
	(segment
		(start 177.443638 -330.637896)
		(end 179.389278 -328.369422)
		(width 0.1651)
		(layer "In5.Cu")
		(net "P5E_PEX1_STN5_RX_DP<87>")
	)
	(segment
		(start 137.459974 -393.387072)
		(end 137.58037 -393.46759)
		(width 0.1651)
		(layer "In5.Cu")
		(net "P5E_PEX1_STN5_RX_DP<87>")
	)
	(segment
		(start 131.310126 -397.59001)
		(end 131.310126 -397.972026)
		(width 0.1651)
		(layer "In5.Cu")
		(net "P5E_PEX1_STN5_RX_DP<87>")
	)
	(segment
		(start 180.87975 -318.355472)
		(end 181.105556 -318.129666)
		(width 0.1143)
		(layer "In5.Cu")
		(net "P5E_PEX1_STN5_RX_DP<87>")
	)
	(segment
		(start 162.197796 -340.47557)
		(end 163.387278 -339.144356)
		(width 0.1651)
		(layer "In5.Cu")
		(net "P5E_PEX1_STN5_RX_DP<87>")
	)
	(segment
		(start 131.869942 -398.09928)
		(end 132.08762 -397.881602)
		(width 0.1651)
		(layer "In5.Cu")
		(net "P5E_PEX1_STN5_RX_DP<87>")
	)
	(segment
		(start 132.08762 -395.140434)
		(end 132.691886 -394.536168)
		(width 0.1651)
		(layer "In5.Cu")
		(net "P5E_PEX1_STN5_RX_DP<87>")
	)
	(segment
		(start 199.02805 -145.311114)
		(end 199.34809 -144.991074)
		(width 0.13462)
		(layer "F.Cu")
		(net "P5E_PEX1_STN0_TX_DP<9>")
	)
	(segment
		(start 199.34809 -144.991074)
		(end 199.979534 -144.991074)
		(width 0.13462)
		(layer "F.Cu")
		(net "P5E_PEX1_STN0_TX_DP<9>")
	)
	(segment
		(start 199.979534 -144.991074)
		(end 200.274174 -145.285714)
		(width 0.13462)
		(layer "F.Cu")
		(net "P5E_PEX1_STN0_TX_DP<9>")
	)
	(segment
		(start 200.274174 -145.285714)
		(end 200.565004 -144.994884)
		(width 0.1651)
		(layer "In9.Cu")
		(net "P5E_PEX1_STN0_TX_DP<9>")
	)
	(segment
		(start 197.014846 -268.933168)
		(end 196.034152 -271.30121)
		(width 0.1651)
		(layer "In9.Cu")
		(net "P5E_PEX1_STN0_TX_DP<9>")
	)
	(segment
		(start 202.42403 -146.262852)
		(end 202.42403 -146.399504)
		(width 0.1651)
		(layer "In9.Cu")
		(net "P5E_PEX1_STN0_TX_DP<9>")
	)
	(segment
		(start 196.034152 -271.500346)
		(end 196.079872 -271.546066)
		(width 0.1143)
		(layer "In9.Cu")
		(net "P5E_PEX1_STN0_TX_DP<9>")
	)
	(segment
		(start 196.649848 -278.534368)
		(end 196.649848 -278.799798)
		(width 0.1143)
		(layer "In9.Cu")
		(net "P5E_PEX1_STN0_TX_DP<9>")
	)
	(segment
		(start 196.535548 -278.420068)
		(end 196.649848 -278.534368)
		(width 0.1143)
		(layer "In9.Cu")
		(net "P5E_PEX1_STN0_TX_DP<9>")
	)
	(segment
		(start 196.034152 -271.471898)
		(end 196.034152 -271.500346)
		(width 0.1143)
		(layer "In9.Cu")
		(net "P5E_PEX1_STN0_TX_DP<9>")
	)
	(segment
		(start 202.884024 -146.722846)
		(end 203.208636 -147.047458)
		(width 0.1651)
		(layer "In9.Cu")
		(net "P5E_PEX1_STN0_TX_DP<9>")
	)
	(segment
		(start 193.652394 -221.85376)
		(end 197.014846 -260.32714)
		(width 0.1651)
		(layer "In9.Cu")
		(net "P5E_PEX1_STN0_TX_DP<9>")
	)
	(segment
		(start 201.156062 -144.994884)
		(end 201.640694 -145.479516)
		(width 0.1651)
		(layer "In9.Cu")
		(net "P5E_PEX1_STN0_TX_DP<9>")
	)
	(segment
		(start 201.96429 -145.939764)
		(end 202.100942 -145.939764)
		(width 0.1651)
		(layer "In9.Cu")
		(net "P5E_PEX1_STN0_TX_DP<9>")
	)
	(segment
		(start 198.815706 -172.862748)
		(end 197.519798 -177.694844)
		(width 0.1651)
		(layer "In9.Cu")
		(net "P5E_PEX1_STN0_TX_DP<9>")
	)
	(segment
		(start 207.280002 -158.199328)
		(end 198.815706 -172.862748)
		(width 0.1651)
		(layer "In9.Cu")
		(net "P5E_PEX1_STN0_TX_DP<9>")
	)
	(segment
		(start 205.635606 -150.679658)
		(end 207.280002 -154.64917)
		(width 0.1651)
		(layer "In9.Cu")
		(net "P5E_PEX1_STN0_TX_DP<9>")
	)
	(segment
		(start 202.42403 -146.399504)
		(end 202.747626 -146.722846)
		(width 0.1651)
		(layer "In9.Cu")
		(net "P5E_PEX1_STN0_TX_DP<9>")
	)
	(segment
		(start 196.079872 -278.205184)
		(end 196.294756 -278.420068)
		(width 0.1143)
		(layer "In9.Cu")
		(net "P5E_PEX1_STN0_TX_DP<9>")
	)
	(segment
		(start 196.294756 -278.420068)
		(end 196.535548 -278.420068)
		(width 0.1143)
		(layer "In9.Cu")
		(net "P5E_PEX1_STN0_TX_DP<9>")
	)
	(segment
		(start 201.640694 -145.479516)
		(end 201.640694 -145.616168)
		(width 0.1651)
		(layer "In9.Cu")
		(net "P5E_PEX1_STN0_TX_DP<9>")
	)
	(segment
		(start 201.640694 -145.616168)
		(end 201.96429 -145.939764)
		(width 0.1651)
		(layer "In9.Cu")
		(net "P5E_PEX1_STN0_TX_DP<9>")
	)
	(segment
		(start 203.208636 -147.047458)
		(end 205.635606 -150.679658)
		(width 0.1651)
		(layer "In9.Cu")
		(net "P5E_PEX1_STN0_TX_DP<9>")
	)
	(segment
		(start 196.034152 -271.30121)
		(end 196.034152 -271.471898)
		(width 0.1651)
		(layer "In9.Cu")
		(net "P5E_PEX1_STN0_TX_DP<9>")
	)
	(segment
		(start 197.014846 -260.32714)
		(end 197.014846 -268.933168)
		(width 0.1651)
		(layer "In9.Cu")
		(net "P5E_PEX1_STN0_TX_DP<9>")
	)
	(segment
		(start 196.079872 -271.546066)
		(end 196.079872 -278.205184)
		(width 0.1143)
		(layer "In9.Cu")
		(net "P5E_PEX1_STN0_TX_DP<9>")
	)
	(segment
		(start 202.747626 -146.722846)
		(end 202.884024 -146.722846)
		(width 0.1651)
		(layer "In9.Cu")
		(net "P5E_PEX1_STN0_TX_DP<9>")
	)
	(segment
		(start 197.519798 -177.694844)
		(end 193.652394 -221.85376)
		(width 0.1651)
		(layer "In9.Cu")
		(net "P5E_PEX1_STN0_TX_DP<9>")
	)
	(segment
		(start 202.100942 -145.939764)
		(end 202.42403 -146.262852)
		(width 0.1651)
		(layer "In9.Cu")
		(net "P5E_PEX1_STN0_TX_DP<9>")
	)
	(segment
		(start 207.280002 -154.64917)
		(end 207.280002 -158.199328)
		(width 0.1651)
		(layer "In9.Cu")
		(net "P5E_PEX1_STN0_TX_DP<9>")
	)
	(segment
		(start 200.565004 -144.994884)
		(end 201.156062 -144.994884)
		(width 0.1651)
		(layer "In9.Cu")
		(net "P5E_PEX1_STN0_TX_DP<9>")
	)
	(segment
		(start 172.401992 -349.831914)
		(end 172.081952 -349.511874)
		(width 0.13462)
		(layer "F.Cu")
		(net "P5E_PEX1_STN7_TX_DN<117>")
	)
	(segment
		(start 172.081952 -348.88043)
		(end 172.376592 -348.58579)
		(width 0.13462)
		(layer "F.Cu")
		(net "P5E_PEX1_STN7_TX_DN<117>")
	)
	(segment
		(start 172.081952 -349.511874)
		(end 172.081952 -348.88043)
		(width 0.13462)
		(layer "F.Cu")
		(net "P5E_PEX1_STN7_TX_DN<117>")
	)
	(segment
		(start 146.352768 -308.149244)
		(end 146.002756 -308.499256)
		(width 0.1651)
		(layer "In11.Cu")
		(net "P5E_PEX1_STN7_TX_DN<117>")
	)
	(segment
		(start 142.131288 -312.370724)
		(end 141.781276 -312.720736)
		(width 0.1651)
		(layer "In11.Cu")
		(net "P5E_PEX1_STN7_TX_DN<117>")
	)
	(segment
		(start 143.963644 -310.682132)
		(end 143.81988 -310.682132)
		(width 0.1651)
		(layer "In11.Cu")
		(net "P5E_PEX1_STN7_TX_DN<117>")
	)
	(segment
		(start 144.314164 -310.187848)
		(end 144.314164 -310.331612)
		(width 0.1651)
		(layer "In11.Cu")
		(net "P5E_PEX1_STN7_TX_DN<117>")
	)
	(segment
		(start 145.508472 -308.99354)
		(end 145.15846 -309.343552)
		(width 0.1651)
		(layer "In11.Cu")
		(net "P5E_PEX1_STN7_TX_DN<117>")
	)
	(segment
		(start 173.143164 -341.085678)
		(end 173.640242 -341.747348)
		(width 0.1651)
		(layer "In11.Cu")
		(net "P5E_PEX1_STN7_TX_DN<117>")
	)
	(segment
		(start 159.979614 -306.261008)
		(end 159.979614 -306.082192)
		(width 0.1143)
		(layer "In11.Cu")
		(net "P5E_PEX1_STN7_TX_DN<117>")
	)
	(segment
		(start 145.15846 -309.343552)
		(end 145.15846 -309.487316)
		(width 0.1651)
		(layer "In11.Cu")
		(net "P5E_PEX1_STN7_TX_DN<117>")
	)
	(segment
		(start 139.243562 -315.576966)
		(end 137.982198 -318.619886)
		(width 0.1651)
		(layer "In11.Cu")
		(net "P5E_PEX1_STN7_TX_DN<117>")
	)
	(segment
		(start 167.857932 -338.558124)
		(end 172.993558 -340.98738)
		(width 0.1651)
		(layer "In11.Cu")
		(net "P5E_PEX1_STN7_TX_DN<117>")
	)
	(segment
		(start 140.09878 -314.403232)
		(end 139.243562 -315.576966)
		(width 0.1651)
		(layer "In11.Cu")
		(net "P5E_PEX1_STN7_TX_DN<117>")
	)
	(segment
		(start 146.847052 -307.65496)
		(end 146.847052 -307.798724)
		(width 0.1651)
		(layer "In11.Cu")
		(net "P5E_PEX1_STN7_TX_DN<117>")
	)
	(segment
		(start 148.3106 -331.310488)
		(end 167.857932 -338.558124)
		(width 0.1651)
		(layer "In11.Cu")
		(net "P5E_PEX1_STN7_TX_DN<117>")
	)
	(segment
		(start 145.15846 -309.487316)
		(end 144.80794 -309.837836)
		(width 0.1651)
		(layer "In11.Cu")
		(net "P5E_PEX1_STN7_TX_DN<117>")
	)
	(segment
		(start 144.80794 -309.837836)
		(end 144.664176 -309.837836)
		(width 0.1651)
		(layer "In11.Cu")
		(net "P5E_PEX1_STN7_TX_DN<117>")
	)
	(segment
		(start 142.275052 -312.370724)
		(end 142.131288 -312.370724)
		(width 0.1651)
		(layer "In11.Cu")
		(net "P5E_PEX1_STN7_TX_DN<117>")
	)
	(segment
		(start 147.197064 -307.304948)
		(end 146.847052 -307.65496)
		(width 0.1651)
		(layer "In11.Cu")
		(net "P5E_PEX1_STN7_TX_DN<117>")
	)
	(segment
		(start 149.027388 -306.015898)
		(end 148.128736 -306.373276)
		(width 0.1651)
		(layer "In11.Cu")
		(net "P5E_PEX1_STN7_TX_DN<117>")
	)
	(segment
		(start 172.993812 -340.98738)
		(end 173.01464 -340.997286)
		(width 0.1651)
		(layer "In11.Cu")
		(net "P5E_PEX1_STN7_TX_DN<117>")
	)
	(segment
		(start 138.362182 -324.385686)
		(end 139.752578 -326.465438)
		(width 0.1651)
		(layer "In11.Cu")
		(net "P5E_PEX1_STN7_TX_DN<117>")
	)
	(segment
		(start 143.534638 -329.130152)
		(end 148.3106 -331.310488)
		(width 0.1651)
		(layer "In11.Cu")
		(net "P5E_PEX1_STN7_TX_DN<117>")
	)
	(segment
		(start 151.500332 -306.015898)
		(end 149.027388 -306.015898)
		(width 0.1651)
		(layer "In11.Cu")
		(net "P5E_PEX1_STN7_TX_DN<117>")
	)
	(segment
		(start 151.52243 -306.015898)
		(end 151.500332 -306.015898)
		(width 0.1143)
		(layer "In11.Cu")
		(net "P5E_PEX1_STN7_TX_DN<117>")
	)
	(segment
		(start 159.890714 -306.349908)
		(end 159.979614 -306.261008)
		(width 0.1143)
		(layer "In11.Cu")
		(net "P5E_PEX1_STN7_TX_DN<117>")
	)
	(segment
		(start 145.652236 -308.99354)
		(end 145.508472 -308.99354)
		(width 0.1651)
		(layer "In11.Cu")
		(net "P5E_PEX1_STN7_TX_DN<117>")
	)
	(segment
		(start 151.56815 -305.970178)
		(end 151.52243 -306.015898)
		(width 0.1143)
		(layer "In11.Cu")
		(net "P5E_PEX1_STN7_TX_DN<117>")
	)
	(segment
		(start 144.314164 -310.331612)
		(end 143.963644 -310.682132)
		(width 0.1651)
		(layer "In11.Cu")
		(net "P5E_PEX1_STN7_TX_DN<117>")
	)
	(segment
		(start 143.119348 -311.526428)
		(end 142.975584 -311.526428)
		(width 0.1651)
		(layer "In11.Cu")
		(net "P5E_PEX1_STN7_TX_DN<117>")
	)
	(segment
		(start 147.340828 -307.304948)
		(end 147.197064 -307.304948)
		(width 0.1651)
		(layer "In11.Cu")
		(net "P5E_PEX1_STN7_TX_DN<117>")
	)
	(segment
		(start 144.664176 -309.837836)
		(end 144.314164 -310.187848)
		(width 0.1651)
		(layer "In11.Cu")
		(net "P5E_PEX1_STN7_TX_DN<117>")
	)
	(segment
		(start 143.469868 -311.032144)
		(end 143.469868 -311.175908)
		(width 0.1651)
		(layer "In11.Cu")
		(net "P5E_PEX1_STN7_TX_DN<117>")
	)
	(segment
		(start 172.993558 -340.98738)
		(end 172.993812 -340.98738)
		(width 0.1651)
		(layer "In11.Cu")
		(net "P5E_PEX1_STN7_TX_DN<117>")
	)
	(segment
		(start 146.002756 -308.499256)
		(end 146.002756 -308.64302)
		(width 0.1651)
		(layer "In11.Cu")
		(net "P5E_PEX1_STN7_TX_DN<117>")
	)
	(segment
		(start 137.69975 -320.044318)
		(end 137.69975 -322.201286)
		(width 0.1651)
		(layer "In11.Cu")
		(net "P5E_PEX1_STN7_TX_DN<117>")
	)
	(segment
		(start 141.32306 -313.178952)
		(end 140.09878 -314.403232)
		(width 0.1651)
		(layer "In11.Cu")
		(net "P5E_PEX1_STN7_TX_DN<117>")
	)
	(segment
		(start 146.847052 -307.798724)
		(end 146.496532 -308.149244)
		(width 0.1651)
		(layer "In11.Cu")
		(net "P5E_PEX1_STN7_TX_DN<117>")
	)
	(segment
		(start 141.781276 -312.828686)
		(end 141.430756 -313.178952)
		(width 0.1651)
		(layer "In11.Cu")
		(net "P5E_PEX1_STN7_TX_DN<117>")
	)
	(segment
		(start 143.469868 -311.175908)
		(end 143.119348 -311.526428)
		(width 0.1651)
		(layer "In11.Cu")
		(net "P5E_PEX1_STN7_TX_DN<117>")
	)
	(segment
		(start 137.982198 -318.619886)
		(end 137.69975 -320.044318)
		(width 0.1651)
		(layer "In11.Cu")
		(net "P5E_PEX1_STN7_TX_DN<117>")
	)
	(segment
		(start 147.691348 -306.810664)
		(end 147.691348 -306.954428)
		(width 0.1651)
		(layer "In11.Cu")
		(net "P5E_PEX1_STN7_TX_DN<117>")
	)
	(segment
		(start 143.81988 -310.682132)
		(end 143.469868 -311.032144)
		(width 0.1651)
		(layer "In11.Cu")
		(net "P5E_PEX1_STN7_TX_DN<117>")
	)
	(segment
		(start 137.69975 -322.201286)
		(end 138.362182 -324.385686)
		(width 0.1651)
		(layer "In11.Cu")
		(net "P5E_PEX1_STN7_TX_DN<117>")
	)
	(segment
		(start 139.752578 -326.465438)
		(end 140.772642 -327.339198)
		(width 0.1651)
		(layer "In11.Cu")
		(net "P5E_PEX1_STN7_TX_DN<117>")
	)
	(segment
		(start 141.781276 -312.720736)
		(end 141.781276 -312.828686)
		(width 0.1651)
		(layer "In11.Cu")
		(net "P5E_PEX1_STN7_TX_DN<117>")
	)
	(segment
		(start 159.979614 -306.082192)
		(end 159.8676 -305.970178)
		(width 0.1143)
		(layer "In11.Cu")
		(net "P5E_PEX1_STN7_TX_DN<117>")
	)
	(segment
		(start 142.625572 -312.020204)
		(end 142.275052 -312.370724)
		(width 0.1651)
		(layer "In11.Cu")
		(net "P5E_PEX1_STN7_TX_DN<117>")
	)
	(segment
		(start 173.640242 -346.148914)
		(end 172.085762 -347.703394)
		(width 0.1651)
		(layer "In11.Cu")
		(net "P5E_PEX1_STN7_TX_DN<117>")
	)
	(segment
		(start 146.002756 -308.64302)
		(end 145.652236 -308.99354)
		(width 0.1651)
		(layer "In11.Cu")
		(net "P5E_PEX1_STN7_TX_DN<117>")
	)
	(segment
		(start 141.430756 -313.178952)
		(end 141.32306 -313.178952)
		(width 0.1651)
		(layer "In11.Cu")
		(net "P5E_PEX1_STN7_TX_DN<117>")
	)
	(segment
		(start 159.8676 -305.970178)
		(end 151.56815 -305.970178)
		(width 0.1143)
		(layer "In11.Cu")
		(net "P5E_PEX1_STN7_TX_DN<117>")
	)
	(segment
		(start 172.085762 -348.29496)
		(end 172.376592 -348.58579)
		(width 0.1651)
		(layer "In11.Cu")
		(net "P5E_PEX1_STN7_TX_DN<117>")
	)
	(segment
		(start 159.599884 -306.349908)
		(end 159.890714 -306.349908)
		(width 0.1143)
		(layer "In11.Cu")
		(net "P5E_PEX1_STN7_TX_DN<117>")
	)
	(segment
		(start 173.640242 -341.747348)
		(end 173.640242 -346.148914)
		(width 0.1651)
		(layer "In11.Cu")
		(net "P5E_PEX1_STN7_TX_DN<117>")
	)
	(segment
		(start 148.128736 -306.373276)
		(end 147.691348 -306.810664)
		(width 0.1651)
		(layer "In11.Cu")
		(net "P5E_PEX1_STN7_TX_DN<117>")
	)
	(segment
		(start 140.772642 -327.339198)
		(end 143.534638 -329.130152)
		(width 0.1651)
		(layer "In11.Cu")
		(net "P5E_PEX1_STN7_TX_DN<117>")
	)
	(segment
		(start 146.496532 -308.149244)
		(end 146.352768 -308.149244)
		(width 0.1651)
		(layer "In11.Cu")
		(net "P5E_PEX1_STN7_TX_DN<117>")
	)
	(segment
		(start 142.625572 -311.87644)
		(end 142.625572 -312.020204)
		(width 0.1651)
		(layer "In11.Cu")
		(net "P5E_PEX1_STN7_TX_DN<117>")
	)
	(segment
		(start 142.975584 -311.526428)
		(end 142.625572 -311.87644)
		(width 0.1651)
		(layer "In11.Cu")
		(net "P5E_PEX1_STN7_TX_DN<117>")
	)
	(segment
		(start 172.085762 -347.703394)
		(end 172.085762 -348.29496)
		(width 0.1651)
		(layer "In11.Cu")
		(net "P5E_PEX1_STN7_TX_DN<117>")
	)
	(segment
		(start 147.691348 -306.954428)
		(end 147.340828 -307.304948)
		(width 0.1651)
		(layer "In11.Cu")
		(net "P5E_PEX1_STN7_TX_DN<117>")
	)
	(segment
		(start 173.01464 -340.997286)
		(end 173.143164 -341.085678)
		(width 0.1651)
		(layer "In11.Cu")
		(net "P5E_PEX1_STN7_TX_DN<117>")
	)
	(segment
		(start 141.938756 -306.351178)
		(end 142.08252 -306.351178)
		(width 0.1651)
		(layer "In9.Cu")
		(net "P5E_PEX1_STN7_RX_DN<114>")
	)
	(segment
		(start 153.754074 -385.22402)
		(end 148.357844 -345.263216)
		(width 0.1651)
		(layer "In9.Cu")
		(net "P5E_PEX1_STN7_RX_DN<114>")
	)
	(segment
		(start 147.070826 -341.66937)
		(end 136.305798 -324.251828)
		(width 0.1651)
		(layer "In9.Cu")
		(net "P5E_PEX1_STN7_RX_DN<114>")
	)
	(segment
		(start 151.839168 -303.120044)
		(end 155.117292 -303.120044)
		(width 0.1143)
		(layer "In9.Cu")
		(net "P5E_PEX1_STN7_RX_DN<114>")
	)
	(segment
		(start 142.08252 -306.351178)
		(end 142.43304 -306.000658)
		(width 0.1651)
		(layer "In9.Cu")
		(net "P5E_PEX1_STN7_RX_DN<114>")
	)
	(segment
		(start 146.87169 -303.670716)
		(end 147.680172 -303.520602)
		(width 0.1651)
		(layer "In9.Cu")
		(net "P5E_PEX1_STN7_RX_DN<114>")
	)
	(segment
		(start 164.775388 -408.981148)
		(end 165.474396 -408.28214)
		(width 0.1651)
		(layer "In9.Cu")
		(net "P5E_PEX1_STN7_RX_DN<114>")
	)
	(segment
		(start 145.697702 -303.888902)
		(end 146.18462 -303.798478)
		(width 0.1651)
		(layer "In9.Cu")
		(net "P5E_PEX1_STN7_RX_DN<114>")
	)
	(segment
		(start 164.43706 -408.981148)
		(end 164.775388 -408.981148)
		(width 0.1651)
		(layer "In9.Cu")
		(net "P5E_PEX1_STN7_RX_DN<114>")
	)
	(segment
		(start 164.31006 -409.108148)
		(end 164.43706 -408.981148)
		(width 0.1651)
		(layer "In9.Cu")
		(net "P5E_PEX1_STN7_RX_DN<114>")
	)
	(segment
		(start 142.43304 -305.856894)
		(end 142.783052 -305.506882)
		(width 0.1651)
		(layer "In9.Cu")
		(net "P5E_PEX1_STN7_RX_DN<114>")
	)
	(segment
		(start 145.616422 -304.00752)
		(end 145.697702 -303.888902)
		(width 0.1651)
		(layer "In9.Cu")
		(net "P5E_PEX1_STN7_RX_DN<114>")
	)
	(segment
		(start 148.357844 -345.263216)
		(end 147.070826 -341.66937)
		(width 0.1651)
		(layer "In9.Cu")
		(net "P5E_PEX1_STN7_RX_DN<114>")
	)
	(segment
		(start 142.926816 -305.506882)
		(end 143.277082 -305.156616)
		(width 0.1651)
		(layer "In9.Cu")
		(net "P5E_PEX1_STN7_RX_DN<114>")
	)
	(segment
		(start 165.474396 -408.28214)
		(end 165.474396 -394.868908)
		(width 0.1651)
		(layer "In9.Cu")
		(net "P5E_PEX1_STN7_RX_DN<114>")
	)
	(segment
		(start 143.277082 -305.012852)
		(end 144.02943 -304.260504)
		(width 0.1651)
		(layer "In9.Cu")
		(net "P5E_PEX1_STN7_RX_DN<114>")
	)
	(segment
		(start 146.79041 -303.789334)
		(end 146.87169 -303.670716)
		(width 0.1651)
		(layer "In9.Cu")
		(net "P5E_PEX1_STN7_RX_DN<114>")
	)
	(segment
		(start 148.816822 -303.165764)
		(end 151.765 -303.165764)
		(width 0.1651)
		(layer "In9.Cu")
		(net "P5E_PEX1_STN7_RX_DN<114>")
	)
	(segment
		(start 144.299686 -304.14849)
		(end 145.010632 -304.016664)
		(width 0.1651)
		(layer "In9.Cu")
		(net "P5E_PEX1_STN7_RX_DN<114>")
	)
	(segment
		(start 146.18462 -303.798478)
		(end 146.302984 -303.879758)
		(width 0.1651)
		(layer "In9.Cu")
		(net "P5E_PEX1_STN7_RX_DN<114>")
	)
	(segment
		(start 143.277082 -305.156616)
		(end 143.277082 -305.012852)
		(width 0.1651)
		(layer "In9.Cu")
		(net "P5E_PEX1_STN7_RX_DN<114>")
	)
	(segment
		(start 142.43304 -306.000658)
		(end 142.43304 -305.856894)
		(width 0.1651)
		(layer "In9.Cu")
		(net "P5E_PEX1_STN7_RX_DN<114>")
	)
	(segment
		(start 151.765 -303.165764)
		(end 151.793448 -303.165764)
		(width 0.1143)
		(layer "In9.Cu")
		(net "P5E_PEX1_STN7_RX_DN<114>")
	)
	(segment
		(start 151.793448 -303.165764)
		(end 151.839168 -303.120044)
		(width 0.1143)
		(layer "In9.Cu")
		(net "P5E_PEX1_STN7_RX_DN<114>")
	)
	(segment
		(start 146.302984 -303.879758)
		(end 146.79041 -303.789334)
		(width 0.1651)
		(layer "In9.Cu")
		(net "P5E_PEX1_STN7_RX_DN<114>")
	)
	(segment
		(start 145.12925 -304.097944)
		(end 145.616422 -304.00752)
		(width 0.1651)
		(layer "In9.Cu")
		(net "P5E_PEX1_STN7_RX_DN<114>")
	)
	(segment
		(start 163.974272 -393.368784)
		(end 159.271208 -391.419334)
		(width 0.1651)
		(layer "In9.Cu")
		(net "P5E_PEX1_STN7_RX_DN<114>")
	)
	(segment
		(start 159.271208 -391.419334)
		(end 155.451556 -388.30504)
		(width 0.1651)
		(layer "In9.Cu")
		(net "P5E_PEX1_STN7_RX_DN<114>")
	)
	(segment
		(start 135.958072 -322.956682)
		(end 135.958072 -318.557656)
		(width 0.1651)
		(layer "In9.Cu")
		(net "P5E_PEX1_STN7_RX_DN<114>")
	)
	(segment
		(start 164.31006 -409.490164)
		(end 164.31006 -409.108148)
		(width 0.1651)
		(layer "In9.Cu")
		(net "P5E_PEX1_STN7_RX_DN<114>")
	)
	(segment
		(start 155.229814 -303.232566)
		(end 155.229814 -303.410874)
		(width 0.1143)
		(layer "In9.Cu")
		(net "P5E_PEX1_STN7_RX_DN<114>")
	)
	(segment
		(start 142.783052 -305.506882)
		(end 142.926816 -305.506882)
		(width 0.1651)
		(layer "In9.Cu")
		(net "P5E_PEX1_STN7_RX_DN<114>")
	)
	(segment
		(start 147.680172 -303.520602)
		(end 148.816822 -303.165764)
		(width 0.1651)
		(layer "In9.Cu")
		(net "P5E_PEX1_STN7_RX_DN<114>")
	)
	(segment
		(start 136.305798 -324.251828)
		(end 135.958072 -322.956682)
		(width 0.1651)
		(layer "In9.Cu")
		(net "P5E_PEX1_STN7_RX_DN<114>")
	)
	(segment
		(start 155.229814 -303.410874)
		(end 155.140914 -303.499774)
		(width 0.1143)
		(layer "In9.Cu")
		(net "P5E_PEX1_STN7_RX_DN<114>")
	)
	(segment
		(start 165.474396 -394.868908)
		(end 163.974272 -393.368784)
		(width 0.1651)
		(layer "In9.Cu")
		(net "P5E_PEX1_STN7_RX_DN<114>")
	)
	(segment
		(start 155.451556 -388.30504)
		(end 153.754074 -385.22402)
		(width 0.1651)
		(layer "In9.Cu")
		(net "P5E_PEX1_STN7_RX_DN<114>")
	)
	(segment
		(start 155.117292 -303.120044)
		(end 155.229814 -303.232566)
		(width 0.1143)
		(layer "In9.Cu")
		(net "P5E_PEX1_STN7_RX_DN<114>")
	)
	(segment
		(start 140.920724 -307.369464)
		(end 141.938756 -306.351178)
		(width 0.1651)
		(layer "In9.Cu")
		(net "P5E_PEX1_STN7_RX_DN<114>")
	)
	(segment
		(start 144.02943 -304.260504)
		(end 144.299686 -304.14849)
		(width 0.1651)
		(layer "In9.Cu")
		(net "P5E_PEX1_STN7_RX_DN<114>")
	)
	(segment
		(start 135.958072 -318.557656)
		(end 140.920724 -307.369464)
		(width 0.1651)
		(layer "In9.Cu")
		(net "P5E_PEX1_STN7_RX_DN<114>")
	)
	(segment
		(start 145.010632 -304.016664)
		(end 145.12925 -304.097944)
		(width 0.1651)
		(layer "In9.Cu")
		(net "P5E_PEX1_STN7_RX_DN<114>")
	)
	(segment
		(start 155.140914 -303.499774)
		(end 154.850084 -303.499774)
		(width 0.1143)
		(layer "In9.Cu")
		(net "P5E_PEX1_STN7_RX_DN<114>")
	)
	(segment
		(start 41.664128 -343.365582)
		(end 41.664128 -342.734138)
		(width 0.13462)
		(layer "F.Cu")
		(net "P5E_PEX0_STN7_TX_DP<122>")
	)
	(segment
		(start 41.984168 -343.685622)
		(end 41.664128 -343.365582)
		(width 0.13462)
		(layer "F.Cu")
		(net "P5E_PEX0_STN7_TX_DP<122>")
	)
	(segment
		(start 41.664128 -342.734138)
		(end 41.958768 -342.439498)
		(width 0.13462)
		(layer "F.Cu")
		(net "P5E_PEX0_STN7_TX_DP<122>")
	)
	(segment
		(start 35.3314 -317.10249)
		(end 35.625024 -316.393576)
		(width 0.1651)
		(layer "In7.Cu")
		(net "P5E_PEX0_STN7_TX_DP<122>")
	)
	(segment
		(start 41.667938 -342.148668)
		(end 41.667938 -340.788244)
		(width 0.1651)
		(layer "In7.Cu")
		(net "P5E_PEX0_STN7_TX_DP<122>")
	)
	(segment
		(start 36.287456 -315.731144)
		(end 36.287456 -315.66612)
		(width 0.1143)
		(layer "In7.Cu")
		(net "P5E_PEX0_STN7_TX_DP<122>")
	)
	(segment
		(start 35.498786 -319.003934)
		(end 35.3314 -317.875412)
		(width 0.1651)
		(layer "In7.Cu")
		(net "P5E_PEX0_STN7_TX_DP<122>")
	)
	(segment
		(start 41.958768 -342.439498)
		(end 41.667938 -342.148668)
		(width 0.1651)
		(layer "In7.Cu")
		(net "P5E_PEX0_STN7_TX_DP<122>")
	)
	(segment
		(start 36.483544 -315.470032)
		(end 37.194236 -315.470032)
		(width 0.1143)
		(layer "In7.Cu")
		(net "P5E_PEX0_STN7_TX_DP<122>")
	)
	(segment
		(start 36.87318 -323.534278)
		(end 35.565842 -319.224914)
		(width 0.1651)
		(layer "In7.Cu")
		(net "P5E_PEX0_STN7_TX_DP<122>")
	)
	(segment
		(start 36.287456 -315.66612)
		(end 36.483544 -315.470032)
		(width 0.1143)
		(layer "In7.Cu")
		(net "P5E_PEX0_STN7_TX_DP<122>")
	)
	(segment
		(start 35.625024 -316.393576)
		(end 36.26739 -315.75121)
		(width 0.1651)
		(layer "In7.Cu")
		(net "P5E_PEX0_STN7_TX_DP<122>")
	)
	(segment
		(start 37.194236 -315.470032)
		(end 37.420042 -315.244226)
		(width 0.1143)
		(layer "In7.Cu")
		(net "P5E_PEX0_STN7_TX_DP<122>")
	)
	(segment
		(start 35.565842 -319.224914)
		(end 35.498786 -319.003934)
		(width 0.1651)
		(layer "In7.Cu")
		(net "P5E_PEX0_STN7_TX_DP<122>")
	)
	(segment
		(start 35.3314 -317.875412)
		(end 35.3314 -317.10249)
		(width 0.1651)
		(layer "In7.Cu")
		(net "P5E_PEX0_STN7_TX_DP<122>")
	)
	(segment
		(start 36.873434 -323.53504)
		(end 36.87318 -323.534278)
		(width 0.1651)
		(layer "In7.Cu")
		(net "P5E_PEX0_STN7_TX_DP<122>")
	)
	(segment
		(start 36.26739 -315.75121)
		(end 36.287456 -315.731144)
		(width 0.1143)
		(layer "In7.Cu")
		(net "P5E_PEX0_STN7_TX_DP<122>")
	)
	(segment
		(start 41.247314 -337.953096)
		(end 36.873434 -323.53504)
		(width 0.1651)
		(layer "In7.Cu")
		(net "P5E_PEX0_STN7_TX_DP<122>")
	)
	(segment
		(start 41.667938 -340.788244)
		(end 41.247314 -337.953096)
		(width 0.1651)
		(layer "In7.Cu")
		(net "P5E_PEX0_STN7_TX_DP<122>")
	)
	(segment
		(start 37.420042 -315.244226)
		(end 37.420042 -315.014102)
		(width 0.1143)
		(layer "In7.Cu")
		(net "P5E_PEX0_STN7_TX_DP<122>")
	)
	(segment
		(start 37.420042 -315.014102)
		(end 37.534342 -314.899802)
		(width 0.1143)
		(layer "In7.Cu")
		(net "P5E_PEX0_STN7_TX_DP<122>")
	)
	(segment
		(start 37.534342 -314.899802)
		(end 37.799772 -314.899802)
		(width 0.1143)
		(layer "In7.Cu")
		(net "P5E_PEX0_STN7_TX_DP<122>")
	)
	(segment
		(start 196.705982 -150.38451)
		(end 197.337426 -150.38451)
		(width 0.13462)
		(layer "F.Cu")
		(net "P5E_PEX1_STN0_TX_DN<12>")
	)
	(segment
		(start 196.385942 -150.70455)
		(end 196.705982 -150.38451)
		(width 0.13462)
		(layer "F.Cu")
		(net "P5E_PEX1_STN0_TX_DN<12>")
	)
	(segment
		(start 197.337426 -150.38451)
		(end 197.632066 -150.67915)
		(width 0.13462)
		(layer "F.Cu")
		(net "P5E_PEX1_STN0_TX_DN<12>")
	)
	(segment
		(start 193.685668 -280.319988)
		(end 193.799968 -280.434288)
		(width 0.1143)
		(layer "In9.Cu")
		(net "P5E_PEX1_STN0_TX_DN<12>")
	)
	(segment
		(start 193.184018 -270.316706)
		(end 193.184018 -271.526)
		(width 0.1651)
		(layer "In9.Cu")
		(net "P5E_PEX1_STN0_TX_DN<12>")
	)
	(segment
		(start 194.625214 -177.518314)
		(end 194.501262 -177.6222)
		(width 0.1651)
		(layer "In9.Cu")
		(net "P5E_PEX1_STN0_TX_DN<12>")
	)
	(segment
		(start 193.184018 -271.526)
		(end 193.184018 -271.554448)
		(width 0.1143)
		(layer "In9.Cu")
		(net "P5E_PEX1_STN0_TX_DN<12>")
	)
	(segment
		(start 201.556874 -150.902416)
		(end 202.239118 -151.58466)
		(width 0.1651)
		(layer "In9.Cu")
		(net "P5E_PEX1_STN0_TX_DN<12>")
	)
	(segment
		(start 194.567556 -178.176428)
		(end 192.64757 -200.12406)
		(width 0.1651)
		(layer "In9.Cu")
		(net "P5E_PEX1_STN0_TX_DN<12>")
	)
	(segment
		(start 190.725044 -222.097346)
		(end 194.111626 -260.829806)
		(width 0.1651)
		(layer "In9.Cu")
		(net "P5E_PEX1_STN0_TX_DN<12>")
	)
	(segment
		(start 200.316084 -150.38832)
		(end 201.556874 -150.902416)
		(width 0.1651)
		(layer "In9.Cu")
		(net "P5E_PEX1_STN0_TX_DN<12>")
	)
	(segment
		(start 194.111626 -260.829806)
		(end 194.111626 -268.076934)
		(width 0.1651)
		(layer "In9.Cu")
		(net "P5E_PEX1_STN0_TX_DN<12>")
	)
	(segment
		(start 194.111626 -268.076934)
		(end 193.621406 -269.260574)
		(width 0.1651)
		(layer "In9.Cu")
		(net "P5E_PEX1_STN0_TX_DN<12>")
	)
	(segment
		(start 196.123306 -171.638976)
		(end 194.662806 -177.088292)
		(width 0.1651)
		(layer "In9.Cu")
		(net "P5E_PEX1_STN0_TX_DN<12>")
	)
	(segment
		(start 193.3321 -269.759684)
		(end 193.373502 -269.859252)
		(width 0.1651)
		(layer "In9.Cu")
		(net "P5E_PEX1_STN0_TX_DN<12>")
	)
	(segment
		(start 204.376782 -157.341824)
		(end 196.123306 -171.638976)
		(width 0.1651)
		(layer "In9.Cu")
		(net "P5E_PEX1_STN0_TX_DN<12>")
	)
	(segment
		(start 204.376782 -155.236926)
		(end 204.376782 -157.341824)
		(width 0.1651)
		(layer "In9.Cu")
		(net "P5E_PEX1_STN0_TX_DN<12>")
	)
	(segment
		(start 193.621406 -269.260574)
		(end 193.521838 -269.301722)
		(width 0.1651)
		(layer "In9.Cu")
		(net "P5E_PEX1_STN0_TX_DN<12>")
	)
	(segment
		(start 194.46367 -178.05273)
		(end 194.567556 -178.176428)
		(width 0.1651)
		(layer "In9.Cu")
		(net "P5E_PEX1_STN0_TX_DN<12>")
	)
	(segment
		(start 193.444876 -280.319988)
		(end 193.685668 -280.319988)
		(width 0.1143)
		(layer "In9.Cu")
		(net "P5E_PEX1_STN0_TX_DN<12>")
	)
	(segment
		(start 193.184018 -271.554448)
		(end 193.229738 -271.600168)
		(width 0.1143)
		(layer "In9.Cu")
		(net "P5E_PEX1_STN0_TX_DN<12>")
	)
	(segment
		(start 194.501262 -177.6222)
		(end 194.46367 -178.05273)
		(width 0.1651)
		(layer "In9.Cu")
		(net "P5E_PEX1_STN0_TX_DN<12>")
	)
	(segment
		(start 193.799968 -280.434288)
		(end 193.799968 -280.699718)
		(width 0.1143)
		(layer "In9.Cu")
		(net "P5E_PEX1_STN0_TX_DN<12>")
	)
	(segment
		(start 192.64757 -200.12406)
		(end 190.725044 -222.097346)
		(width 0.1651)
		(layer "In9.Cu")
		(net "P5E_PEX1_STN0_TX_DN<12>")
	)
	(segment
		(start 203.88326 -154.044904)
		(end 204.376782 -155.236926)
		(width 0.1651)
		(layer "In9.Cu")
		(net "P5E_PEX1_STN0_TX_DN<12>")
	)
	(segment
		(start 197.922896 -150.38832)
		(end 200.316084 -150.38832)
		(width 0.1651)
		(layer "In9.Cu")
		(net "P5E_PEX1_STN0_TX_DN<12>")
	)
	(segment
		(start 193.229738 -271.600168)
		(end 193.229738 -280.10485)
		(width 0.1143)
		(layer "In9.Cu")
		(net "P5E_PEX1_STN0_TX_DN<12>")
	)
	(segment
		(start 193.521838 -269.301722)
		(end 193.3321 -269.759684)
		(width 0.1651)
		(layer "In9.Cu")
		(net "P5E_PEX1_STN0_TX_DN<12>")
	)
	(segment
		(start 202.239118 -151.58466)
		(end 203.88326 -154.044904)
		(width 0.1651)
		(layer "In9.Cu")
		(net "P5E_PEX1_STN0_TX_DN<12>")
	)
	(segment
		(start 193.229738 -280.10485)
		(end 193.444876 -280.319988)
		(width 0.1143)
		(layer "In9.Cu")
		(net "P5E_PEX1_STN0_TX_DN<12>")
	)
	(segment
		(start 194.662806 -177.088292)
		(end 194.625214 -177.518314)
		(width 0.1651)
		(layer "In9.Cu")
		(net "P5E_PEX1_STN0_TX_DN<12>")
	)
	(segment
		(start 197.632066 -150.67915)
		(end 197.922896 -150.38832)
		(width 0.1651)
		(layer "In9.Cu")
		(net "P5E_PEX1_STN0_TX_DN<12>")
	)
	(segment
		(start 193.373502 -269.859252)
		(end 193.184018 -270.316706)
		(width 0.1651)
		(layer "In9.Cu")
		(net "P5E_PEX1_STN0_TX_DN<12>")
	)
	(segment
		(start 190.735712 -348.88043)
		(end 191.030352 -348.58579)
		(width 0.13462)
		(layer "F.Cu")
		(net "P5E_PEX1_STN7_TX_DN<126>")
	)
	(segment
		(start 191.055752 -349.831914)
		(end 190.735712 -349.511874)
		(width 0.13462)
		(layer "F.Cu")
		(net "P5E_PEX1_STN7_TX_DN<126>")
	)
	(segment
		(start 190.735712 -349.511874)
		(end 190.735712 -348.88043)
		(width 0.13462)
		(layer "F.Cu")
		(net "P5E_PEX1_STN7_TX_DN<126>")
	)
	(segment
		(start 190.739522 -347.662754)
		(end 190.739522 -348.29496)
		(width 0.1651)
		(layer "In11.Cu")
		(net "P5E_PEX1_STN7_TX_DN<126>")
	)
	(segment
		(start 158.932118 -322.424044)
		(end 159.069024 -322.380356)
		(width 0.1651)
		(layer "In11.Cu")
		(net "P5E_PEX1_STN7_TX_DN<126>")
	)
	(segment
		(start 161.190178 -323.477636)
		(end 161.63036 -323.705474)
		(width 0.1651)
		(layer "In11.Cu")
		(net "P5E_PEX1_STN7_TX_DN<126>")
	)
	(segment
		(start 159.069024 -322.380356)
		(end 159.509206 -322.608194)
		(width 0.1651)
		(layer "In11.Cu")
		(net "P5E_PEX1_STN7_TX_DN<126>")
	)
	(segment
		(start 190.288418 -339.640672)
		(end 191.473328 -340.689692)
		(width 0.1651)
		(layer "In11.Cu")
		(net "P5E_PEX1_STN7_TX_DN<126>")
	)
	(segment
		(start 192.294002 -346.108274)
		(end 190.739522 -347.662754)
		(width 0.1651)
		(layer "In11.Cu")
		(net "P5E_PEX1_STN7_TX_DN<126>")
	)
	(segment
		(start 157.508702 -311.670192)
		(end 157.320234 -311.85866)
		(width 0.1143)
		(layer "In11.Cu")
		(net "P5E_PEX1_STN7_TX_DN<126>")
	)
	(segment
		(start 161.63036 -323.705474)
		(end 161.673794 -323.84238)
		(width 0.1651)
		(layer "In11.Cu")
		(net "P5E_PEX1_STN7_TX_DN<126>")
	)
	(segment
		(start 157.611064 -311.670192)
		(end 157.508702 -311.670192)
		(width 0.1143)
		(layer "In11.Cu")
		(net "P5E_PEX1_STN7_TX_DN<126>")
	)
	(segment
		(start 159.992822 -322.97243)
		(end 160.129728 -322.928996)
		(width 0.1651)
		(layer "In11.Cu")
		(net "P5E_PEX1_STN7_TX_DN<126>")
	)
	(segment
		(start 191.473328 -340.689692)
		(end 192.294002 -341.783416)
		(width 0.1651)
		(layer "In11.Cu")
		(net "P5E_PEX1_STN7_TX_DN<126>")
	)
	(segment
		(start 161.673794 -323.84238)
		(end 173.374558 -329.894184)
		(width 0.1651)
		(layer "In11.Cu")
		(net "P5E_PEX1_STN7_TX_DN<126>")
	)
	(segment
		(start 190.739522 -348.29496)
		(end 191.030352 -348.58579)
		(width 0.1651)
		(layer "In11.Cu")
		(net "P5E_PEX1_STN7_TX_DN<126>")
	)
	(segment
		(start 192.294002 -341.783416)
		(end 192.294002 -346.108274)
		(width 0.1651)
		(layer "In11.Cu")
		(net "P5E_PEX1_STN7_TX_DN<126>")
	)
	(segment
		(start 159.552894 -322.7451)
		(end 159.992822 -322.97243)
		(width 0.1651)
		(layer "In11.Cu")
		(net "P5E_PEX1_STN7_TX_DN<126>")
	)
	(segment
		(start 157.365954 -320.02095)
		(end 157.365954 -320.043048)
		(width 0.1143)
		(layer "In11.Cu")
		(net "P5E_PEX1_STN7_TX_DN<126>")
	)
	(segment
		(start 173.374558 -329.894184)
		(end 190.288418 -339.640672)
		(width 0.1651)
		(layer "In11.Cu")
		(net "P5E_PEX1_STN7_TX_DN<126>")
	)
	(segment
		(start 157.365954 -321.103244)
		(end 158.334964 -322.11518)
		(width 0.1651)
		(layer "In11.Cu")
		(net "P5E_PEX1_STN7_TX_DN<126>")
	)
	(segment
		(start 160.613344 -323.29374)
		(end 161.053272 -323.52107)
		(width 0.1651)
		(layer "In11.Cu")
		(net "P5E_PEX1_STN7_TX_DN<126>")
	)
	(segment
		(start 158.334964 -322.11518)
		(end 158.932118 -322.424044)
		(width 0.1651)
		(layer "In11.Cu")
		(net "P5E_PEX1_STN7_TX_DN<126>")
	)
	(segment
		(start 159.509206 -322.608194)
		(end 159.552894 -322.7451)
		(width 0.1651)
		(layer "In11.Cu")
		(net "P5E_PEX1_STN7_TX_DN<126>")
	)
	(segment
		(start 161.053272 -323.52107)
		(end 161.190178 -323.477636)
		(width 0.1651)
		(layer "In11.Cu")
		(net "P5E_PEX1_STN7_TX_DN<126>")
	)
	(segment
		(start 160.56991 -323.156834)
		(end 160.613344 -323.29374)
		(width 0.1651)
		(layer "In11.Cu")
		(net "P5E_PEX1_STN7_TX_DN<126>")
	)
	(segment
		(start 160.129728 -322.928996)
		(end 160.56991 -323.156834)
		(width 0.1651)
		(layer "In11.Cu")
		(net "P5E_PEX1_STN7_TX_DN<126>")
	)
	(segment
		(start 157.320234 -311.85866)
		(end 157.320234 -319.97523)
		(width 0.1143)
		(layer "In11.Cu")
		(net "P5E_PEX1_STN7_TX_DN<126>")
	)
	(segment
		(start 157.699964 -312.049922)
		(end 157.699964 -311.759092)
		(width 0.1143)
		(layer "In11.Cu")
		(net "P5E_PEX1_STN7_TX_DN<126>")
	)
	(segment
		(start 157.699964 -311.759092)
		(end 157.611064 -311.670192)
		(width 0.1143)
		(layer "In11.Cu")
		(net "P5E_PEX1_STN7_TX_DN<126>")
	)
	(segment
		(start 157.320234 -319.97523)
		(end 157.365954 -320.02095)
		(width 0.1143)
		(layer "In11.Cu")
		(net "P5E_PEX1_STN7_TX_DN<126>")
	)
	(segment
		(start 157.365954 -320.043048)
		(end 157.365954 -321.103244)
		(width 0.1651)
		(layer "In11.Cu")
		(net "P5E_PEX1_STN7_TX_DN<126>")
	)
	(segment
		(start 140.528548 -306.198778)
		(end 140.672058 -306.198778)
		(width 0.1651)
		(layer "In9.Cu")
		(net "P5E_PEX1_STN7_RX_DN<113>")
	)
	(segment
		(start 147.617688 -302.536352)
		(end 148.645118 -302.215804)
		(width 0.1651)
		(layer "In9.Cu")
		(net "P5E_PEX1_STN7_RX_DN<113>")
	)
	(segment
		(start 142.737078 -303.990248)
		(end 143.132302 -303.595024)
		(width 0.1651)
		(layer "In9.Cu")
		(net "P5E_PEX1_STN7_RX_DN<113>")
	)
	(segment
		(start 139.652248 -307.51272)
		(end 139.600686 -307.378608)
		(width 0.1651)
		(layer "In9.Cu")
		(net "P5E_PEX1_STN7_RX_DN<113>")
	)
	(segment
		(start 137.86485 -311.291732)
		(end 137.998962 -311.239916)
		(width 0.1651)
		(layer "In9.Cu")
		(net "P5E_PEX1_STN7_RX_DN<113>")
	)
	(segment
		(start 151.793448 -302.215804)
		(end 151.839168 -302.170084)
		(width 0.1143)
		(layer "In9.Cu")
		(net "P5E_PEX1_STN7_RX_DN<113>")
	)
	(segment
		(start 153.2382 -302.549814)
		(end 152.94991 -302.549814)
		(width 0.1143)
		(layer "In9.Cu")
		(net "P5E_PEX1_STN7_RX_DN<113>")
	)
	(segment
		(start 139.168124 -308.604158)
		(end 139.116562 -308.470046)
		(width 0.1651)
		(layer "In9.Cu")
		(net "P5E_PEX1_STN7_RX_DN<113>")
	)
	(segment
		(start 141.893036 -304.978054)
		(end 141.893036 -304.83429)
		(width 0.1651)
		(layer "In9.Cu")
		(net "P5E_PEX1_STN7_RX_DN<113>")
	)
	(segment
		(start 161.859976 -393.540996)
		(end 158.750254 -392.251692)
		(width 0.1651)
		(layer "In9.Cu")
		(net "P5E_PEX1_STN7_RX_DN<113>")
	)
	(segment
		(start 139.801346 -306.92598)
		(end 140.528548 -306.198778)
		(width 0.1651)
		(layer "In9.Cu")
		(net "P5E_PEX1_STN7_RX_DN<113>")
	)
	(segment
		(start 142.737078 -304.133758)
		(end 142.737078 -303.990248)
		(width 0.1651)
		(layer "In9.Cu")
		(net "P5E_PEX1_STN7_RX_DN<113>")
	)
	(segment
		(start 141.542516 -305.328574)
		(end 141.893036 -304.978054)
		(width 0.1651)
		(layer "In9.Cu")
		(net "P5E_PEX1_STN7_RX_DN<113>")
	)
	(segment
		(start 138.483086 -310.148478)
		(end 138.684 -309.695596)
		(width 0.1651)
		(layer "In9.Cu")
		(net "P5E_PEX1_STN7_RX_DN<113>")
	)
	(segment
		(start 138.684 -309.695596)
		(end 138.632438 -309.561484)
		(width 0.1651)
		(layer "In9.Cu")
		(net "P5E_PEX1_STN7_RX_DN<113>")
	)
	(segment
		(start 144.1196 -303.186338)
		(end 147.617688 -302.536352)
		(width 0.1651)
		(layer "In9.Cu")
		(net "P5E_PEX1_STN7_RX_DN<113>")
	)
	(segment
		(start 135.000492 -323.101716)
		(end 135.000492 -317.749428)
		(width 0.1651)
		(layer "In9.Cu")
		(net "P5E_PEX1_STN7_RX_DN<113>")
	)
	(segment
		(start 142.243048 -304.484278)
		(end 142.386558 -304.484278)
		(width 0.1651)
		(layer "In9.Cu")
		(net "P5E_PEX1_STN7_RX_DN<113>")
	)
	(segment
		(start 138.199876 -310.787034)
		(end 138.148314 -310.652922)
		(width 0.1651)
		(layer "In9.Cu")
		(net "P5E_PEX1_STN7_RX_DN<113>")
	)
	(segment
		(start 162.109912 -410.208222)
		(end 162.236912 -410.081222)
		(width 0.1651)
		(layer "In9.Cu")
		(net "P5E_PEX1_STN7_RX_DN<113>")
	)
	(segment
		(start 152.835102 -385.562094)
		(end 147.451572 -345.694508)
		(width 0.1651)
		(layer "In9.Cu")
		(net "P5E_PEX1_STN7_RX_DN<113>")
	)
	(segment
		(start 139.451334 -307.965602)
		(end 139.652248 -307.51272)
		(width 0.1651)
		(layer "In9.Cu")
		(net "P5E_PEX1_STN7_RX_DN<113>")
	)
	(segment
		(start 138.348974 -310.200294)
		(end 138.483086 -310.148478)
		(width 0.1651)
		(layer "In9.Cu")
		(net "P5E_PEX1_STN7_RX_DN<113>")
	)
	(segment
		(start 141.398752 -305.328574)
		(end 141.542516 -305.328574)
		(width 0.1651)
		(layer "In9.Cu")
		(net "P5E_PEX1_STN7_RX_DN<113>")
	)
	(segment
		(start 139.317222 -308.017418)
		(end 139.451334 -307.965602)
		(width 0.1651)
		(layer "In9.Cu")
		(net "P5E_PEX1_STN7_RX_DN<113>")
	)
	(segment
		(start 162.109912 -410.589984)
		(end 162.109912 -410.208222)
		(width 0.1651)
		(layer "In9.Cu")
		(net "P5E_PEX1_STN7_RX_DN<113>")
	)
	(segment
		(start 153.201878 -302.170084)
		(end 153.334212 -302.302418)
		(width 0.1143)
		(layer "In9.Cu")
		(net "P5E_PEX1_STN7_RX_DN<113>")
	)
	(segment
		(start 153.334212 -302.302418)
		(end 153.334212 -302.453802)
		(width 0.1143)
		(layer "In9.Cu")
		(net "P5E_PEX1_STN7_RX_DN<113>")
	)
	(segment
		(start 139.116562 -308.470046)
		(end 139.317222 -308.017418)
		(width 0.1651)
		(layer "In9.Cu")
		(net "P5E_PEX1_STN7_RX_DN<113>")
	)
	(segment
		(start 162.57524 -410.081222)
		(end 163.274248 -409.382214)
		(width 0.1651)
		(layer "In9.Cu")
		(net "P5E_PEX1_STN7_RX_DN<113>")
	)
	(segment
		(start 153.334212 -302.453802)
		(end 153.2382 -302.549814)
		(width 0.1143)
		(layer "In9.Cu")
		(net "P5E_PEX1_STN7_RX_DN<113>")
	)
	(segment
		(start 137.998962 -311.239916)
		(end 138.199876 -310.787034)
		(width 0.1651)
		(layer "In9.Cu")
		(net "P5E_PEX1_STN7_RX_DN<113>")
	)
	(segment
		(start 141.022578 -305.704748)
		(end 141.398752 -305.328574)
		(width 0.1651)
		(layer "In9.Cu")
		(net "P5E_PEX1_STN7_RX_DN<113>")
	)
	(segment
		(start 158.750254 -392.251692)
		(end 154.700478 -388.949184)
		(width 0.1651)
		(layer "In9.Cu")
		(net "P5E_PEX1_STN7_RX_DN<113>")
	)
	(segment
		(start 146.1008 -341.922608)
		(end 135.409178 -324.623684)
		(width 0.1651)
		(layer "In9.Cu")
		(net "P5E_PEX1_STN7_RX_DN<113>")
	)
	(segment
		(start 138.632438 -309.561484)
		(end 138.833098 -309.108856)
		(width 0.1651)
		(layer "In9.Cu")
		(net "P5E_PEX1_STN7_RX_DN<113>")
	)
	(segment
		(start 138.96721 -309.05704)
		(end 139.168124 -308.604158)
		(width 0.1651)
		(layer "In9.Cu")
		(net "P5E_PEX1_STN7_RX_DN<113>")
	)
	(segment
		(start 139.600686 -307.378608)
		(end 139.801346 -306.92598)
		(width 0.1651)
		(layer "In9.Cu")
		(net "P5E_PEX1_STN7_RX_DN<113>")
	)
	(segment
		(start 138.148314 -310.652922)
		(end 138.348974 -310.200294)
		(width 0.1651)
		(layer "In9.Cu")
		(net "P5E_PEX1_STN7_RX_DN<113>")
	)
	(segment
		(start 140.672058 -306.198778)
		(end 141.022578 -305.848258)
		(width 0.1651)
		(layer "In9.Cu")
		(net "P5E_PEX1_STN7_RX_DN<113>")
	)
	(segment
		(start 135.409178 -324.623684)
		(end 135.000492 -323.101716)
		(width 0.1651)
		(layer "In9.Cu")
		(net "P5E_PEX1_STN7_RX_DN<113>")
	)
	(segment
		(start 163.274248 -409.382214)
		(end 163.274248 -394.955268)
		(width 0.1651)
		(layer "In9.Cu")
		(net "P5E_PEX1_STN7_RX_DN<113>")
	)
	(segment
		(start 142.386558 -304.484278)
		(end 142.737078 -304.133758)
		(width 0.1651)
		(layer "In9.Cu")
		(net "P5E_PEX1_STN7_RX_DN<113>")
	)
	(segment
		(start 143.132302 -303.595024)
		(end 144.1196 -303.186338)
		(width 0.1651)
		(layer "In9.Cu")
		(net "P5E_PEX1_STN7_RX_DN<113>")
	)
	(segment
		(start 154.700478 -388.949184)
		(end 152.835102 -385.562094)
		(width 0.1651)
		(layer "In9.Cu")
		(net "P5E_PEX1_STN7_RX_DN<113>")
	)
	(segment
		(start 162.236912 -410.081222)
		(end 162.57524 -410.081222)
		(width 0.1651)
		(layer "In9.Cu")
		(net "P5E_PEX1_STN7_RX_DN<113>")
	)
	(segment
		(start 151.765 -302.215804)
		(end 151.793448 -302.215804)
		(width 0.1143)
		(layer "In9.Cu")
		(net "P5E_PEX1_STN7_RX_DN<113>")
	)
	(segment
		(start 141.022578 -305.848258)
		(end 141.022578 -305.704748)
		(width 0.1651)
		(layer "In9.Cu")
		(net "P5E_PEX1_STN7_RX_DN<113>")
	)
	(segment
		(start 147.451572 -345.694508)
		(end 146.1008 -341.922608)
		(width 0.1651)
		(layer "In9.Cu")
		(net "P5E_PEX1_STN7_RX_DN<113>")
	)
	(segment
		(start 135.000492 -317.749428)
		(end 137.86485 -311.291732)
		(width 0.1651)
		(layer "In9.Cu")
		(net "P5E_PEX1_STN7_RX_DN<113>")
	)
	(segment
		(start 148.645118 -302.215804)
		(end 151.765 -302.215804)
		(width 0.1651)
		(layer "In9.Cu")
		(net "P5E_PEX1_STN7_RX_DN<113>")
	)
	(segment
		(start 151.839168 -302.170084)
		(end 153.201878 -302.170084)
		(width 0.1143)
		(layer "In9.Cu")
		(net "P5E_PEX1_STN7_RX_DN<113>")
	)
	(segment
		(start 141.893036 -304.83429)
		(end 142.243048 -304.484278)
		(width 0.1651)
		(layer "In9.Cu")
		(net "P5E_PEX1_STN7_RX_DN<113>")
	)
	(segment
		(start 163.274248 -394.955268)
		(end 161.859976 -393.540996)
		(width 0.1651)
		(layer "In9.Cu")
		(net "P5E_PEX1_STN7_RX_DN<113>")
	)
	(segment
		(start 138.833098 -309.108856)
		(end 138.96721 -309.05704)
		(width 0.1651)
		(layer "In9.Cu")
		(net "P5E_PEX1_STN7_RX_DN<113>")
	)
	(segment
		(start 267.946378 -308.629558)
		(end 267.900658 -308.583838)
		(width 0.1143)
		(layer "In5.Cu")
		(net "P5E_PEX2_STN7_RX_DP<120>")
	)
	(segment
		(start 265.75893 -310.790082)
		(end 265.70559 -312.032904)
		(width 0.1651)
		(layer "In5.Cu")
		(net "P5E_PEX2_STN7_RX_DP<120>")
	)
	(segment
		(start 268.512798 -329.447906)
		(end 271.611852 -332.967838)
		(width 0.1651)
		(layer "In5.Cu")
		(net "P5E_PEX2_STN7_RX_DP<120>")
	)
	(segment
		(start 265.88212 -316.662308)
		(end 265.88212 -316.662816)
		(width 0.1651)
		(layer "In5.Cu")
		(net "P5E_PEX2_STN7_RX_DP<120>")
	)
	(segment
		(start 279.52827 -339.234272)
		(end 279.542748 -339.35924)
		(width 0.1651)
		(layer "In5.Cu")
		(net "P5E_PEX2_STN7_RX_DP<120>")
	)
	(segment
		(start 287.113726 -366.590072)
		(end 287.07715 -366.72901)
		(width 0.1651)
		(layer "In5.Cu")
		(net "P5E_PEX2_STN7_RX_DP<120>")
	)
	(segment
		(start 271.899888 -309.199788)
		(end 271.634458 -309.199788)
		(width 0.1143)
		(layer "In5.Cu")
		(net "P5E_PEX2_STN7_RX_DP<120>")
	)
	(segment
		(start 280.056336 -339.65261)
		(end 281.804618 -341.037418)
		(width 0.1651)
		(layer "In5.Cu")
		(net "P5E_PEX2_STN7_RX_DP<120>")
	)
	(segment
		(start 287.07715 -366.72901)
		(end 287.326324 -367.157254)
		(width 0.1651)
		(layer "In5.Cu")
		(net "P5E_PEX2_STN7_RX_DP<120>")
	)
	(segment
		(start 279.542748 -339.35924)
		(end 279.931368 -339.667088)
		(width 0.1651)
		(layer "In5.Cu")
		(net "P5E_PEX2_STN7_RX_DP<120>")
	)
	(segment
		(start 288.333942 -368.686588)
		(end 288.333942 -382.412494)
		(width 0.1651)
		(layer "In5.Cu")
		(net "P5E_PEX2_STN7_RX_DP<120>")
	)
	(segment
		(start 287.4899 -382.57226)
		(end 287.4899 -382.18999)
		(width 0.1651)
		(layer "In5.Cu")
		(net "P5E_PEX2_STN7_RX_DP<120>")
	)
	(segment
		(start 271.616424 -332.967076)
		(end 271.617948 -332.968346)
		(width 0.1651)
		(layer "In5.Cu")
		(net "P5E_PEX2_STN7_RX_DP<120>")
	)
	(segment
		(start 267.900658 -308.583838)
		(end 267.87221 -308.583838)
		(width 0.1143)
		(layer "In5.Cu")
		(net "P5E_PEX2_STN7_RX_DP<120>")
	)
	(segment
		(start 288.047176 -382.69926)
		(end 287.6169 -382.69926)
		(width 0.1651)
		(layer "In5.Cu")
		(net "P5E_PEX2_STN7_RX_DP<120>")
	)
	(segment
		(start 287.6169 -382.69926)
		(end 287.4899 -382.57226)
		(width 0.1651)
		(layer "In5.Cu")
		(net "P5E_PEX2_STN7_RX_DP<120>")
	)
	(segment
		(start 265.911076 -309.685944)
		(end 265.75893 -310.053228)
		(width 0.1651)
		(layer "In5.Cu")
		(net "P5E_PEX2_STN7_RX_DP<120>")
	)
	(segment
		(start 288.333942 -382.412494)
		(end 288.047176 -382.69926)
		(width 0.1651)
		(layer "In5.Cu")
		(net "P5E_PEX2_STN7_RX_DP<120>")
	)
	(segment
		(start 265.70559 -312.032904)
		(end 265.70559 -315.937646)
		(width 0.1651)
		(layer "In5.Cu")
		(net "P5E_PEX2_STN7_RX_DP<120>")
	)
	(segment
		(start 266.84986 -325.500492)
		(end 268.512798 -329.447906)
		(width 0.1651)
		(layer "In5.Cu")
		(net "P5E_PEX2_STN7_RX_DP<120>")
	)
	(segment
		(start 271.617948 -332.968346)
		(end 279.52827 -339.234272)
		(width 0.1651)
		(layer "In5.Cu")
		(net "P5E_PEX2_STN7_RX_DP<120>")
	)
	(segment
		(start 265.75893 -310.053228)
		(end 265.75893 -310.790082)
		(width 0.1651)
		(layer "In5.Cu")
		(net "P5E_PEX2_STN7_RX_DP<120>")
	)
	(segment
		(start 271.520158 -309.085488)
		(end 271.520158 -308.855364)
		(width 0.1143)
		(layer "In5.Cu")
		(net "P5E_PEX2_STN7_RX_DP<120>")
	)
	(segment
		(start 287.465262 -367.194084)
		(end 288.333942 -368.686588)
		(width 0.1651)
		(layer "In5.Cu")
		(net "P5E_PEX2_STN7_RX_DP<120>")
	)
	(segment
		(start 267.013182 -308.583838)
		(end 265.911076 -309.685944)
		(width 0.1651)
		(layer "In5.Cu")
		(net "P5E_PEX2_STN7_RX_DP<120>")
	)
	(segment
		(start 279.931368 -339.667088)
		(end 280.056336 -339.65261)
		(width 0.1651)
		(layer "In5.Cu")
		(net "P5E_PEX2_STN7_RX_DP<120>")
	)
	(segment
		(start 265.70559 -315.937646)
		(end 265.88212 -316.662308)
		(width 0.1651)
		(layer "In5.Cu")
		(net "P5E_PEX2_STN7_RX_DP<120>")
	)
	(segment
		(start 287.326324 -367.157254)
		(end 287.465262 -367.194084)
		(width 0.1651)
		(layer "In5.Cu")
		(net "P5E_PEX2_STN7_RX_DP<120>")
	)
	(segment
		(start 271.634458 -309.199788)
		(end 271.520158 -309.085488)
		(width 0.1143)
		(layer "In5.Cu")
		(net "P5E_PEX2_STN7_RX_DP<120>")
	)
	(segment
		(start 271.520158 -308.855364)
		(end 271.294352 -308.629558)
		(width 0.1143)
		(layer "In5.Cu")
		(net "P5E_PEX2_STN7_RX_DP<120>")
	)
	(segment
		(start 266.84986 -320.638932)
		(end 266.84986 -325.500492)
		(width 0.1651)
		(layer "In5.Cu")
		(net "P5E_PEX2_STN7_RX_DP<120>")
	)
	(segment
		(start 271.294352 -308.629558)
		(end 267.946378 -308.629558)
		(width 0.1143)
		(layer "In5.Cu")
		(net "P5E_PEX2_STN7_RX_DP<120>")
	)
	(segment
		(start 282.178252 -342.046306)
		(end 282.178252 -358.109774)
		(width 0.1651)
		(layer "In5.Cu")
		(net "P5E_PEX2_STN7_RX_DP<120>")
	)
	(segment
		(start 265.88212 -316.662816)
		(end 266.84986 -320.638932)
		(width 0.1651)
		(layer "In5.Cu")
		(net "P5E_PEX2_STN7_RX_DP<120>")
	)
	(segment
		(start 281.804618 -341.037418)
		(end 282.178252 -342.046306)
		(width 0.1651)
		(layer "In5.Cu")
		(net "P5E_PEX2_STN7_RX_DP<120>")
	)
	(segment
		(start 282.178252 -358.109774)
		(end 287.113726 -366.590072)
		(width 0.1651)
		(layer "In5.Cu")
		(net "P5E_PEX2_STN7_RX_DP<120>")
	)
	(segment
		(start 267.87221 -308.583838)
		(end 267.013182 -308.583838)
		(width 0.1651)
		(layer "In5.Cu")
		(net "P5E_PEX2_STN7_RX_DP<120>")
	)
	(segment
		(start 271.611852 -332.967838)
		(end 271.616424 -332.967076)
		(width 0.1651)
		(layer "In5.Cu")
		(net "P5E_PEX2_STN7_RX_DP<120>")
	)
	(segment
		(start 50.991008 -348.88043)
		(end 51.285648 -348.58579)
		(width 0.13462)
		(layer "F.Cu")
		(net "P5E_PEX0_STN7_TX_DN<127>")
	)
	(segment
		(start 50.991008 -349.511874)
		(end 50.991008 -348.88043)
		(width 0.13462)
		(layer "F.Cu")
		(net "P5E_PEX0_STN7_TX_DN<127>")
	)
	(segment
		(start 51.311048 -349.831914)
		(end 50.991008 -349.511874)
		(width 0.13462)
		(layer "F.Cu")
		(net "P5E_PEX0_STN7_TX_DN<127>")
	)
	(segment
		(start 50.994818 -347.658182)
		(end 52.549298 -346.103702)
		(width 0.1651)
		(layer "In7.Cu")
		(net "P5E_PEX0_STN7_TX_DN<127>")
	)
	(segment
		(start 42.284396 -313.570112)
		(end 42.435526 -313.570112)
		(width 0.1143)
		(layer "In7.Cu")
		(net "P5E_PEX0_STN7_TX_DN<127>")
	)
	(segment
		(start 42.215816 -321.633596)
		(end 42.215816 -319.916048)
		(width 0.1651)
		(layer "In7.Cu")
		(net "P5E_PEX0_STN7_TX_DN<127>")
	)
	(segment
		(start 42.170096 -313.684412)
		(end 42.284396 -313.570112)
		(width 0.1143)
		(layer "In7.Cu")
		(net "P5E_PEX0_STN7_TX_DN<127>")
	)
	(segment
		(start 52.549298 -346.103702)
		(end 52.549298 -342.252554)
		(width 0.1651)
		(layer "In7.Cu")
		(net "P5E_PEX0_STN7_TX_DN<127>")
	)
	(segment
		(start 42.215816 -319.8876)
		(end 42.170096 -319.84188)
		(width 0.1143)
		(layer "In7.Cu")
		(net "P5E_PEX0_STN7_TX_DN<127>")
	)
	(segment
		(start 47.040546 -329.913996)
		(end 42.215816 -321.633596)
		(width 0.1651)
		(layer "In7.Cu")
		(net "P5E_PEX0_STN7_TX_DN<127>")
	)
	(segment
		(start 42.215816 -319.916048)
		(end 42.215816 -319.8876)
		(width 0.1143)
		(layer "In7.Cu")
		(net "P5E_PEX0_STN7_TX_DN<127>")
	)
	(segment
		(start 51.285648 -348.58579)
		(end 50.994818 -348.29496)
		(width 0.1651)
		(layer "In7.Cu")
		(net "P5E_PEX0_STN7_TX_DN<127>")
	)
	(segment
		(start 42.435526 -313.570112)
		(end 42.549826 -313.684412)
		(width 0.1143)
		(layer "In7.Cu")
		(net "P5E_PEX0_STN7_TX_DN<127>")
	)
	(segment
		(start 42.549826 -313.684412)
		(end 42.549826 -313.949842)
		(width 0.1143)
		(layer "In7.Cu")
		(net "P5E_PEX0_STN7_TX_DN<127>")
	)
	(segment
		(start 52.549298 -342.252554)
		(end 51.96459 -340.324948)
		(width 0.1651)
		(layer "In7.Cu")
		(net "P5E_PEX0_STN7_TX_DN<127>")
	)
	(segment
		(start 50.994818 -348.29496)
		(end 50.994818 -347.658182)
		(width 0.1651)
		(layer "In7.Cu")
		(net "P5E_PEX0_STN7_TX_DN<127>")
	)
	(segment
		(start 42.170096 -319.84188)
		(end 42.170096 -313.684412)
		(width 0.1143)
		(layer "In7.Cu")
		(net "P5E_PEX0_STN7_TX_DN<127>")
	)
	(segment
		(start 51.96459 -340.324948)
		(end 47.040546 -329.913996)
		(width 0.1651)
		(layer "In7.Cu")
		(net "P5E_PEX0_STN7_TX_DN<127>")
	)
	(segment
		(start 197.337426 -150.11019)
		(end 197.632066 -149.81555)
		(width 0.13462)
		(layer "F.Cu")
		(net "P5E_PEX1_STN0_TX_DP<12>")
	)
	(segment
		(start 196.705982 -150.11019)
		(end 197.337426 -150.11019)
		(width 0.13462)
		(layer "F.Cu")
		(net "P5E_PEX1_STN0_TX_DP<12>")
	)
	(segment
		(start 196.385942 -149.79015)
		(end 196.705982 -150.11019)
		(width 0.13462)
		(layer "F.Cu")
		(net "P5E_PEX1_STN0_TX_DP<12>")
	)
	(segment
		(start 193.420238 -271.600168)
		(end 193.420238 -280.025856)
		(width 0.1143)
		(layer "In9.Cu")
		(net "P5E_PEX1_STN0_TX_DP<12>")
	)
	(segment
		(start 193.420238 -280.025856)
		(end 193.52387 -280.129488)
		(width 0.1143)
		(layer "In9.Cu")
		(net "P5E_PEX1_STN0_TX_DP<12>")
	)
	(segment
		(start 204.133196 -153.9113)
		(end 204.658722 -155.180792)
		(width 0.1651)
		(layer "In9.Cu")
		(net "P5E_PEX1_STN0_TX_DP<12>")
	)
	(segment
		(start 204.658722 -155.180792)
		(end 204.658722 -157.417516)
		(width 0.1651)
		(layer "In9.Cu")
		(net "P5E_PEX1_STN0_TX_DP<12>")
	)
	(segment
		(start 193.799968 -280.015188)
		(end 193.799968 -279.749504)
		(width 0.1143)
		(layer "In9.Cu")
		(net "P5E_PEX1_STN0_TX_DP<12>")
	)
	(segment
		(start 193.465958 -271.526)
		(end 193.465958 -271.554448)
		(width 0.1143)
		(layer "In9.Cu")
		(net "P5E_PEX1_STN0_TX_DP<12>")
	)
	(segment
		(start 193.685668 -280.129488)
		(end 193.799968 -280.015188)
		(width 0.1143)
		(layer "In9.Cu")
		(net "P5E_PEX1_STN0_TX_DP<12>")
	)
	(segment
		(start 194.393566 -260.81736)
		(end 194.393566 -268.133068)
		(width 0.1651)
		(layer "In9.Cu")
		(net "P5E_PEX1_STN0_TX_DP<12>")
	)
	(segment
		(start 201.71664 -150.663402)
		(end 202.458066 -151.404828)
		(width 0.1651)
		(layer "In9.Cu")
		(net "P5E_PEX1_STN0_TX_DP<12>")
	)
	(segment
		(start 196.386196 -171.747942)
		(end 194.941698 -177.137568)
		(width 0.1651)
		(layer "In9.Cu")
		(net "P5E_PEX1_STN0_TX_DP<12>")
	)
	(segment
		(start 193.52387 -280.129488)
		(end 193.685668 -280.129488)
		(width 0.1143)
		(layer "In9.Cu")
		(net "P5E_PEX1_STN0_TX_DP<12>")
	)
	(segment
		(start 194.393566 -268.133068)
		(end 193.465958 -270.37284)
		(width 0.1651)
		(layer "In9.Cu")
		(net "P5E_PEX1_STN0_TX_DP<12>")
	)
	(segment
		(start 197.922896 -150.10638)
		(end 200.372218 -150.10638)
		(width 0.1651)
		(layer "In9.Cu")
		(net "P5E_PEX1_STN0_TX_DP<12>")
	)
	(segment
		(start 204.658722 -157.417516)
		(end 196.386196 -171.747942)
		(width 0.1651)
		(layer "In9.Cu")
		(net "P5E_PEX1_STN0_TX_DP<12>")
	)
	(segment
		(start 194.941698 -177.137568)
		(end 191.008254 -222.097346)
		(width 0.1651)
		(layer "In9.Cu")
		(net "P5E_PEX1_STN0_TX_DP<12>")
	)
	(segment
		(start 193.465958 -270.37284)
		(end 193.465958 -271.526)
		(width 0.1651)
		(layer "In9.Cu")
		(net "P5E_PEX1_STN0_TX_DP<12>")
	)
	(segment
		(start 200.372218 -150.10638)
		(end 201.71664 -150.663402)
		(width 0.1651)
		(layer "In9.Cu")
		(net "P5E_PEX1_STN0_TX_DP<12>")
	)
	(segment
		(start 197.632066 -149.81555)
		(end 197.922896 -150.10638)
		(width 0.1651)
		(layer "In9.Cu")
		(net "P5E_PEX1_STN0_TX_DP<12>")
	)
	(segment
		(start 202.458066 -151.404828)
		(end 204.133196 -153.9113)
		(width 0.1651)
		(layer "In9.Cu")
		(net "P5E_PEX1_STN0_TX_DP<12>")
	)
	(segment
		(start 193.465958 -271.554448)
		(end 193.420238 -271.600168)
		(width 0.1143)
		(layer "In9.Cu")
		(net "P5E_PEX1_STN0_TX_DP<12>")
	)
	(segment
		(start 191.008254 -222.097346)
		(end 194.393566 -260.81736)
		(width 0.1651)
		(layer "In9.Cu")
		(net "P5E_PEX1_STN0_TX_DP<12>")
	)
	(segment
		(start 115.265708 -355.658166)
		(end 115.265708 -355.026722)
		(width 0.13462)
		(layer "F.Cu")
		(net "P5E_PEX1_STN6_TX_DP<101>")
	)
	(segment
		(start 114.945668 -355.978206)
		(end 115.265708 -355.658166)
		(width 0.13462)
		(layer "F.Cu")
		(net "P5E_PEX1_STN6_TX_DP<101>")
	)
	(segment
		(start 115.265708 -355.026722)
		(end 114.971068 -354.732082)
		(width 0.13462)
		(layer "F.Cu")
		(net "P5E_PEX1_STN6_TX_DP<101>")
	)
	(segment
		(start 168.484042 -320.083942)
		(end 168.484042 -320.016886)
		(width 0.1651)
		(layer "In7.Cu")
		(net "P5E_PEX1_STN6_TX_DP<101>")
	)
	(segment
		(start 116.816378 -352.151442)
		(end 116.816378 -341.356442)
		(width 0.1651)
		(layer "In7.Cu")
		(net "P5E_PEX1_STN6_TX_DP<101>")
	)
	(segment
		(start 168.529762 -311.705498)
		(end 168.755568 -311.479692)
		(width 0.1143)
		(layer "In7.Cu")
		(net "P5E_PEX1_STN6_TX_DP<101>")
	)
	(segment
		(start 117.489732 -340.683088)
		(end 130.868674 -332.663546)
		(width 0.1651)
		(layer "In7.Cu")
		(net "P5E_PEX1_STN6_TX_DP<101>")
	)
	(segment
		(start 168.484042 -320.016886)
		(end 168.484042 -319.988438)
		(width 0.1143)
		(layer "In7.Cu")
		(net "P5E_PEX1_STN6_TX_DP<101>")
	)
	(segment
		(start 168.424098 -320.228468)
		(end 168.484042 -320.083942)
		(width 0.1651)
		(layer "In7.Cu")
		(net "P5E_PEX1_STN6_TX_DP<101>")
	)
	(segment
		(start 115.261898 -354.441252)
		(end 115.261898 -353.705922)
		(width 0.1651)
		(layer "In7.Cu")
		(net "P5E_PEX1_STN6_TX_DP<101>")
	)
	(segment
		(start 168.484042 -319.988438)
		(end 168.529762 -319.942718)
		(width 0.1143)
		(layer "In7.Cu")
		(net "P5E_PEX1_STN6_TX_DP<101>")
	)
	(segment
		(start 130.868674 -332.663546)
		(end 148.602446 -327.283572)
		(width 0.1651)
		(layer "In7.Cu")
		(net "P5E_PEX1_STN6_TX_DP<101>")
	)
	(segment
		(start 168.755568 -311.479692)
		(end 168.985692 -311.479692)
		(width 0.1143)
		(layer "In7.Cu")
		(net "P5E_PEX1_STN6_TX_DP<101>")
	)
	(segment
		(start 166.269162 -321.923918)
		(end 167.416226 -321.23634)
		(width 0.1651)
		(layer "In7.Cu")
		(net "P5E_PEX1_STN6_TX_DP<101>")
	)
	(segment
		(start 115.261898 -353.705922)
		(end 116.816378 -352.151442)
		(width 0.1651)
		(layer "In7.Cu")
		(net "P5E_PEX1_STN6_TX_DP<101>")
	)
	(segment
		(start 168.985692 -311.479692)
		(end 169.099992 -311.365392)
		(width 0.1143)
		(layer "In7.Cu")
		(net "P5E_PEX1_STN6_TX_DP<101>")
	)
	(segment
		(start 168.529762 -319.942718)
		(end 168.529762 -311.705498)
		(width 0.1143)
		(layer "In7.Cu")
		(net "P5E_PEX1_STN6_TX_DP<101>")
	)
	(segment
		(start 148.602446 -327.283572)
		(end 166.269162 -321.923918)
		(width 0.1651)
		(layer "In7.Cu")
		(net "P5E_PEX1_STN6_TX_DP<101>")
	)
	(segment
		(start 116.816378 -341.356442)
		(end 117.489732 -340.683088)
		(width 0.1651)
		(layer "In7.Cu")
		(net "P5E_PEX1_STN6_TX_DP<101>")
	)
	(segment
		(start 114.971068 -354.732082)
		(end 115.261898 -354.441252)
		(width 0.1651)
		(layer "In7.Cu")
		(net "P5E_PEX1_STN6_TX_DP<101>")
	)
	(segment
		(start 167.416226 -321.23634)
		(end 168.424098 -320.228468)
		(width 0.1651)
		(layer "In7.Cu")
		(net "P5E_PEX1_STN6_TX_DP<101>")
	)
	(segment
		(start 169.099992 -311.365392)
		(end 169.099992 -311.099962)
		(width 0.1143)
		(layer "In7.Cu")
		(net "P5E_PEX1_STN6_TX_DP<101>")
	)
	(segment
		(start 150.621492 -367.21161)
		(end 155.279852 -354.92055)
		(width 0.1651)
		(layer "In5.Cu")
		(net "P5E_PEX1_STN5_RX_DN<87>")
	)
	(segment
		(start 132.36956 -395.257274)
		(end 132.861812 -394.765022)
		(width 0.1651)
		(layer "In5.Cu")
		(net "P5E_PEX1_STN5_RX_DN<87>")
	)
	(segment
		(start 181.18455 -318.320166)
		(end 181.33568 -318.320166)
		(width 0.1143)
		(layer "In5.Cu")
		(net "P5E_PEX1_STN5_RX_DN<87>")
	)
	(segment
		(start 131.986782 -398.38122)
		(end 132.36956 -397.998442)
		(width 0.1651)
		(layer "In5.Cu")
		(net "P5E_PEX1_STN5_RX_DN<87>")
	)
	(segment
		(start 135.776716 -394.114274)
		(end 135.77697 -394.114528)
		(width 0.1651)
		(layer "In5.Cu")
		(net "P5E_PEX1_STN5_RX_DN<87>")
	)
	(segment
		(start 135.77697 -394.114528)
		(end 138.125454 -393.64666)
		(width 0.1651)
		(layer "In5.Cu")
		(net "P5E_PEX1_STN5_RX_DN<87>")
	)
	(segment
		(start 181.11597 -319.913)
		(end 181.07025 -319.86728)
		(width 0.1143)
		(layer "In5.Cu")
		(net "P5E_PEX1_STN5_RX_DN<87>")
	)
	(segment
		(start 177.628296 -330.855828)
		(end 179.632864 -328.519028)
		(width 0.1651)
		(layer "In5.Cu")
		(net "P5E_PEX1_STN5_RX_DN<87>")
	)
	(segment
		(start 155.279852 -354.92055)
		(end 162.433254 -340.63559)
		(width 0.1651)
		(layer "In5.Cu")
		(net "P5E_PEX1_STN5_RX_DN<87>")
	)
	(segment
		(start 181.44998 -318.434466)
		(end 181.44998 -318.699896)
		(width 0.1143)
		(layer "In5.Cu")
		(net "P5E_PEX1_STN5_RX_DN<87>")
	)
	(segment
		(start 180.488082 -326.45477)
		(end 181.11597 -324.386194)
		(width 0.1651)
		(layer "In5.Cu")
		(net "P5E_PEX1_STN5_RX_DN<87>")
	)
	(segment
		(start 181.11597 -319.941448)
		(end 181.11597 -319.913)
		(width 0.1143)
		(layer "In5.Cu")
		(net "P5E_PEX1_STN5_RX_DN<87>")
	)
	(segment
		(start 181.11597 -324.386194)
		(end 181.11597 -319.941448)
		(width 0.1651)
		(layer "In5.Cu")
		(net "P5E_PEX1_STN5_RX_DN<87>")
	)
	(segment
		(start 132.36956 -397.998442)
		(end 132.36956 -395.257274)
		(width 0.1651)
		(layer "In5.Cu")
		(net "P5E_PEX1_STN5_RX_DN<87>")
	)
	(segment
		(start 142.855696 -389.041894)
		(end 149.481032 -371.187472)
		(width 0.1651)
		(layer "In5.Cu")
		(net "P5E_PEX1_STN5_RX_DN<87>")
	)
	(segment
		(start 138.125454 -393.64666)
		(end 141.532864 -391.246868)
		(width 0.1651)
		(layer "In5.Cu")
		(net "P5E_PEX1_STN5_RX_DN<87>")
	)
	(segment
		(start 163.569396 -339.363812)
		(end 177.628296 -330.855828)
		(width 0.1651)
		(layer "In5.Cu")
		(net "P5E_PEX1_STN5_RX_DN<87>")
	)
	(segment
		(start 133.267958 -394.547852)
		(end 134.4168 -394.318744)
		(width 0.1651)
		(layer "In5.Cu")
		(net "P5E_PEX1_STN5_RX_DN<87>")
	)
	(segment
		(start 141.532864 -391.246868)
		(end 142.855696 -389.041894)
		(width 0.1651)
		(layer "In5.Cu")
		(net "P5E_PEX1_STN5_RX_DN<87>")
	)
	(segment
		(start 181.33568 -318.320166)
		(end 181.44998 -318.434466)
		(width 0.1143)
		(layer "In5.Cu")
		(net "P5E_PEX1_STN5_RX_DN<87>")
	)
	(segment
		(start 162.433254 -340.63559)
		(end 163.569396 -339.363812)
		(width 0.1651)
		(layer "In5.Cu")
		(net "P5E_PEX1_STN5_RX_DN<87>")
	)
	(segment
		(start 131.310126 -398.890236)
		(end 131.310126 -398.50822)
		(width 0.1651)
		(layer "In5.Cu")
		(net "P5E_PEX1_STN5_RX_DN<87>")
	)
	(segment
		(start 131.310126 -398.50822)
		(end 131.437126 -398.38122)
		(width 0.1651)
		(layer "In5.Cu")
		(net "P5E_PEX1_STN5_RX_DN<87>")
	)
	(segment
		(start 134.75081 -394.318744)
		(end 135.776716 -394.114274)
		(width 0.1651)
		(layer "In5.Cu")
		(net "P5E_PEX1_STN5_RX_DN<87>")
	)
	(segment
		(start 181.07025 -318.434466)
		(end 181.18455 -318.320166)
		(width 0.1143)
		(layer "In5.Cu")
		(net "P5E_PEX1_STN5_RX_DN<87>")
	)
	(segment
		(start 134.4168 -394.318744)
		(end 134.75081 -394.318744)
		(width 0.1651)
		(layer "In5.Cu")
		(net "P5E_PEX1_STN5_RX_DN<87>")
	)
	(segment
		(start 181.07025 -319.86728)
		(end 181.07025 -318.434466)
		(width 0.1143)
		(layer "In5.Cu")
		(net "P5E_PEX1_STN5_RX_DN<87>")
	)
	(segment
		(start 179.632864 -328.519028)
		(end 180.488082 -326.45477)
		(width 0.1651)
		(layer "In5.Cu")
		(net "P5E_PEX1_STN5_RX_DN<87>")
	)
	(segment
		(start 131.437126 -398.38122)
		(end 131.986782 -398.38122)
		(width 0.1651)
		(layer "In5.Cu")
		(net "P5E_PEX1_STN5_RX_DN<87>")
	)
	(segment
		(start 132.861812 -394.765022)
		(end 133.267958 -394.547852)
		(width 0.1651)
		(layer "In5.Cu")
		(net "P5E_PEX1_STN5_RX_DN<87>")
	)
	(segment
		(start 149.481032 -371.187472)
		(end 150.621492 -367.21161)
		(width 0.1651)
		(layer "In5.Cu")
		(net "P5E_PEX1_STN5_RX_DN<87>")
	)
	(segment
		(start 152.471628 -134.923276)
		(end 152.151588 -134.603236)
		(width 0.13462)
		(layer "F.Cu")
		(net "P5E_PEX1_STN1_TX_DN<30>")
	)
	(segment
		(start 152.151588 -134.603236)
		(end 151.520144 -134.603236)
		(width 0.13462)
		(layer "F.Cu")
		(net "P5E_PEX1_STN1_TX_DN<30>")
	)
	(segment
		(start 151.520144 -134.603236)
		(end 151.225504 -134.897876)
		(width 0.13462)
		(layer "F.Cu")
		(net "P5E_PEX1_STN1_TX_DN<30>")
	)
	(segment
		(start 154.164792 -144.577308)
		(end 154.068526 -144.091406)
		(width 0.1651)
		(layer "In9.Cu")
		(net "P5E_PEX1_STN1_TX_DN<30>")
	)
	(segment
		(start 151.757126 -138.016742)
		(end 151.757126 -137.855198)
		(width 0.1651)
		(layer "In9.Cu")
		(net "P5E_PEX1_STN1_TX_DN<30>")
	)
	(segment
		(start 161.721546 -183.203088)
		(end 154.550618 -147.103846)
		(width 0.1651)
		(layer "In9.Cu")
		(net "P5E_PEX1_STN1_TX_DN<30>")
	)
	(segment
		(start 151.757126 -137.855198)
		(end 151.415496 -137.513568)
		(width 0.1651)
		(layer "In9.Cu")
		(net "P5E_PEX1_STN1_TX_DN<30>")
	)
	(segment
		(start 151.415496 -137.513568)
		(end 151.253952 -137.513568)
		(width 0.1651)
		(layer "In9.Cu")
		(net "P5E_PEX1_STN1_TX_DN<30>")
	)
	(segment
		(start 153.933652 -144.00149)
		(end 153.837386 -143.515842)
		(width 0.1651)
		(layer "In9.Cu")
		(net "P5E_PEX1_STN1_TX_DN<30>")
	)
	(segment
		(start 188.66993 -278.12619)
		(end 188.66993 -271.546066)
		(width 0.1143)
		(layer "In9.Cu")
		(net "P5E_PEX1_STN1_TX_DN<30>")
	)
	(segment
		(start 153.361898 -141.124178)
		(end 153.451814 -140.989812)
		(width 0.1651)
		(layer "In9.Cu")
		(net "P5E_PEX1_STN1_TX_DN<30>")
	)
	(segment
		(start 154.171396 -145.197322)
		(end 154.07513 -144.711674)
		(width 0.1651)
		(layer "In9.Cu")
		(net "P5E_PEX1_STN1_TX_DN<30>")
	)
	(segment
		(start 150.457408 -135.773922)
		(end 150.307802 -135.7122)
		(width 0.1651)
		(layer "In9.Cu")
		(net "P5E_PEX1_STN1_TX_DN<30>")
	)
	(segment
		(start 154.402536 -145.77314)
		(end 154.30627 -145.287238)
		(width 0.1651)
		(layer "In9.Cu")
		(net "P5E_PEX1_STN1_TX_DN<30>")
	)
	(segment
		(start 153.837386 -143.515842)
		(end 153.927048 -143.381476)
		(width 0.1651)
		(layer "In9.Cu")
		(net "P5E_PEX1_STN1_TX_DN<30>")
	)
	(segment
		(start 188.935106 -278.229568)
		(end 188.773308 -278.229568)
		(width 0.1143)
		(layer "In9.Cu")
		(net "P5E_PEX1_STN1_TX_DN<30>")
	)
	(segment
		(start 153.599642 -142.32001)
		(end 153.689558 -142.185644)
		(width 0.1651)
		(layer "In9.Cu")
		(net "P5E_PEX1_STN1_TX_DN<30>")
	)
	(segment
		(start 150.307802 -135.711946)
		(end 150.123144 -135.266938)
		(width 0.1651)
		(layer "In9.Cu")
		(net "P5E_PEX1_STN1_TX_DN<30>")
	)
	(segment
		(start 188.71565 -262.946896)
		(end 161.721546 -183.203088)
		(width 0.1651)
		(layer "In9.Cu")
		(net "P5E_PEX1_STN1_TX_DN<30>")
	)
	(segment
		(start 154.068526 -144.091406)
		(end 153.933652 -144.00149)
		(width 0.1651)
		(layer "In9.Cu")
		(net "P5E_PEX1_STN1_TX_DN<30>")
	)
	(segment
		(start 188.71565 -271.471898)
		(end 188.71565 -262.946896)
		(width 0.1651)
		(layer "In9.Cu")
		(net "P5E_PEX1_STN1_TX_DN<30>")
	)
	(segment
		(start 154.550618 -147.103846)
		(end 154.64028 -146.969226)
		(width 0.1651)
		(layer "In9.Cu")
		(net "P5E_PEX1_STN1_TX_DN<30>")
	)
	(segment
		(start 151.253952 -137.513568)
		(end 150.91283 -137.172446)
		(width 0.1651)
		(layer "In9.Cu")
		(net "P5E_PEX1_STN1_TX_DN<30>")
	)
	(segment
		(start 150.91283 -137.172446)
		(end 150.58009 -136.369552)
		(width 0.1651)
		(layer "In9.Cu")
		(net "P5E_PEX1_STN1_TX_DN<30>")
	)
	(segment
		(start 154.30627 -145.287238)
		(end 154.171396 -145.197322)
		(width 0.1651)
		(layer "In9.Cu")
		(net "P5E_PEX1_STN1_TX_DN<30>")
	)
	(segment
		(start 154.40914 -146.393408)
		(end 154.312874 -145.90776)
		(width 0.1651)
		(layer "In9.Cu")
		(net "P5E_PEX1_STN1_TX_DN<30>")
	)
	(segment
		(start 154.312874 -145.90776)
		(end 154.402536 -145.77314)
		(width 0.1651)
		(layer "In9.Cu")
		(net "P5E_PEX1_STN1_TX_DN<30>")
	)
	(segment
		(start 154.64028 -146.969226)
		(end 154.54376 -146.483324)
		(width 0.1651)
		(layer "In9.Cu")
		(net "P5E_PEX1_STN1_TX_DN<30>")
	)
	(segment
		(start 150.415244 -134.607046)
		(end 150.934674 -134.607046)
		(width 0.1651)
		(layer "In9.Cu")
		(net "P5E_PEX1_STN1_TX_DN<30>")
	)
	(segment
		(start 150.203408 -134.818882)
		(end 150.415244 -134.607046)
		(width 0.1651)
		(layer "In9.Cu")
		(net "P5E_PEX1_STN1_TX_DN<30>")
	)
	(segment
		(start 150.123144 -135.01243)
		(end 150.203408 -134.818882)
		(width 0.1651)
		(layer "In9.Cu")
		(net "P5E_PEX1_STN1_TX_DN<30>")
	)
	(segment
		(start 154.07513 -144.711674)
		(end 154.164792 -144.577308)
		(width 0.1651)
		(layer "In9.Cu")
		(net "P5E_PEX1_STN1_TX_DN<30>")
	)
	(segment
		(start 153.124154 -139.928346)
		(end 152.738836 -138.998452)
		(width 0.1651)
		(layer "In9.Cu")
		(net "P5E_PEX1_STN1_TX_DN<30>")
	)
	(segment
		(start 150.307802 -135.7122)
		(end 150.307802 -135.711946)
		(width 0.1651)
		(layer "In9.Cu")
		(net "P5E_PEX1_STN1_TX_DN<30>")
	)
	(segment
		(start 153.593038 -141.699742)
		(end 153.458164 -141.609826)
		(width 0.1651)
		(layer "In9.Cu")
		(net "P5E_PEX1_STN1_TX_DN<30>")
	)
	(segment
		(start 153.927048 -143.381476)
		(end 153.830782 -142.895574)
		(width 0.1651)
		(layer "In9.Cu")
		(net "P5E_PEX1_STN1_TX_DN<30>")
	)
	(segment
		(start 154.54376 -146.483324)
		(end 154.40914 -146.393408)
		(width 0.1651)
		(layer "In9.Cu")
		(net "P5E_PEX1_STN1_TX_DN<30>")
	)
	(segment
		(start 153.22042 -140.413994)
		(end 153.124154 -139.928346)
		(width 0.1651)
		(layer "In9.Cu")
		(net "P5E_PEX1_STN1_TX_DN<30>")
	)
	(segment
		(start 150.934674 -134.607046)
		(end 151.225504 -134.897876)
		(width 0.1651)
		(layer "In9.Cu")
		(net "P5E_PEX1_STN1_TX_DN<30>")
	)
	(segment
		(start 153.458164 -141.609826)
		(end 153.361898 -141.124178)
		(width 0.1651)
		(layer "In9.Cu")
		(net "P5E_PEX1_STN1_TX_DN<30>")
	)
	(segment
		(start 153.695908 -142.805658)
		(end 153.599642 -142.32001)
		(width 0.1651)
		(layer "In9.Cu")
		(net "P5E_PEX1_STN1_TX_DN<30>")
	)
	(segment
		(start 188.773308 -278.229568)
		(end 188.66993 -278.12619)
		(width 0.1143)
		(layer "In9.Cu")
		(net "P5E_PEX1_STN1_TX_DN<30>")
	)
	(segment
		(start 189.04966 -278.115014)
		(end 188.935106 -278.229568)
		(width 0.1143)
		(layer "In9.Cu")
		(net "P5E_PEX1_STN1_TX_DN<30>")
	)
	(segment
		(start 150.58009 -136.369552)
		(end 150.642066 -136.2202)
		(width 0.1651)
		(layer "In9.Cu")
		(net "P5E_PEX1_STN1_TX_DN<30>")
	)
	(segment
		(start 150.123144 -135.266938)
		(end 150.123144 -135.01243)
		(width 0.1651)
		(layer "In9.Cu")
		(net "P5E_PEX1_STN1_TX_DN<30>")
	)
	(segment
		(start 153.689558 -142.185644)
		(end 153.593038 -141.699742)
		(width 0.1651)
		(layer "In9.Cu")
		(net "P5E_PEX1_STN1_TX_DN<30>")
	)
	(segment
		(start 152.738836 -138.998452)
		(end 151.757126 -138.016742)
		(width 0.1651)
		(layer "In9.Cu")
		(net "P5E_PEX1_STN1_TX_DN<30>")
	)
	(segment
		(start 153.830782 -142.895574)
		(end 153.695908 -142.805658)
		(width 0.1651)
		(layer "In9.Cu")
		(net "P5E_PEX1_STN1_TX_DN<30>")
	)
	(segment
		(start 188.71565 -271.500346)
		(end 188.71565 -271.471898)
		(width 0.1143)
		(layer "In9.Cu")
		(net "P5E_PEX1_STN1_TX_DN<30>")
	)
	(segment
		(start 189.04966 -277.849838)
		(end 189.04966 -278.115014)
		(width 0.1143)
		(layer "In9.Cu")
		(net "P5E_PEX1_STN1_TX_DN<30>")
	)
	(segment
		(start 188.66993 -271.546066)
		(end 188.71565 -271.500346)
		(width 0.1143)
		(layer "In9.Cu")
		(net "P5E_PEX1_STN1_TX_DN<30>")
	)
	(segment
		(start 150.642066 -136.2202)
		(end 150.457408 -135.773922)
		(width 0.1651)
		(layer "In9.Cu")
		(net "P5E_PEX1_STN1_TX_DN<30>")
	)
	(segment
		(start 153.355294 -140.50391)
		(end 153.22042 -140.413994)
		(width 0.1651)
		(layer "In9.Cu")
		(net "P5E_PEX1_STN1_TX_DN<30>")
	)
	(segment
		(start 153.451814 -140.989812)
		(end 153.355294 -140.50391)
		(width 0.1651)
		(layer "In9.Cu")
		(net "P5E_PEX1_STN1_TX_DN<30>")
	)
	(segment
		(start 115.265708 -343.365582)
		(end 115.265708 -342.734138)
		(width 0.13462)
		(layer "F.Cu")
		(net "P5E_PEX1_STN6_TX_DP<102>")
	)
	(segment
		(start 114.945668 -343.685622)
		(end 115.265708 -343.365582)
		(width 0.13462)
		(layer "F.Cu")
		(net "P5E_PEX1_STN6_TX_DP<102>")
	)
	(segment
		(start 115.265708 -342.734138)
		(end 114.971068 -342.439498)
		(width 0.13462)
		(layer "F.Cu")
		(net "P5E_PEX1_STN6_TX_DP<102>")
	)
	(segment
		(start 119.482108 -338.30641)
		(end 119.482108 -338.306664)
		(width 0.1651)
		(layer "In7.Cu")
		(net "P5E_PEX1_STN6_TX_DP<102>")
	)
	(segment
		(start 168.150032 -313.265312)
		(end 168.150032 -312.999882)
		(width 0.1143)
		(layer "In7.Cu")
		(net "P5E_PEX1_STN6_TX_DP<102>")
	)
	(segment
		(start 119.482108 -338.306664)
		(end 130.249168 -331.852778)
		(width 0.1651)
		(layer "In7.Cu")
		(net "P5E_PEX1_STN6_TX_DP<102>")
	)
	(segment
		(start 167.146224 -319.732152)
		(end 167.16629 -319.712086)
		(width 0.1143)
		(layer "In7.Cu")
		(net "P5E_PEX1_STN6_TX_DP<102>")
	)
	(segment
		(start 114.971068 -342.439498)
		(end 115.261898 -342.148668)
		(width 0.1651)
		(layer "In7.Cu")
		(net "P5E_PEX1_STN6_TX_DP<102>")
	)
	(segment
		(start 165.81501 -321.063112)
		(end 167.146224 -319.732152)
		(width 0.1651)
		(layer "In7.Cu")
		(net "P5E_PEX1_STN6_TX_DP<102>")
	)
	(segment
		(start 167.579802 -313.605418)
		(end 167.805608 -313.379612)
		(width 0.1143)
		(layer "In7.Cu")
		(net "P5E_PEX1_STN6_TX_DP<102>")
	)
	(segment
		(start 115.873022 -340.469728)
		(end 119.482108 -338.30641)
		(width 0.1651)
		(layer "In7.Cu")
		(net "P5E_PEX1_STN6_TX_DP<102>")
	)
	(segment
		(start 115.261898 -342.148668)
		(end 115.261898 -341.080852)
		(width 0.1651)
		(layer "In7.Cu")
		(net "P5E_PEX1_STN6_TX_DP<102>")
	)
	(segment
		(start 130.249168 -331.852778)
		(end 165.81501 -321.063112)
		(width 0.1651)
		(layer "In7.Cu")
		(net "P5E_PEX1_STN6_TX_DP<102>")
	)
	(segment
		(start 167.805608 -313.379612)
		(end 168.035732 -313.379612)
		(width 0.1143)
		(layer "In7.Cu")
		(net "P5E_PEX1_STN6_TX_DP<102>")
	)
	(segment
		(start 167.579802 -319.363598)
		(end 167.579802 -313.605418)
		(width 0.1143)
		(layer "In7.Cu")
		(net "P5E_PEX1_STN6_TX_DP<102>")
	)
	(segment
		(start 168.035732 -313.379612)
		(end 168.150032 -313.265312)
		(width 0.1143)
		(layer "In7.Cu")
		(net "P5E_PEX1_STN6_TX_DP<102>")
	)
	(segment
		(start 167.231314 -319.712086)
		(end 167.579802 -319.363598)
		(width 0.1143)
		(layer "In7.Cu")
		(net "P5E_PEX1_STN6_TX_DP<102>")
	)
	(segment
		(start 115.261898 -341.080852)
		(end 115.873022 -340.469728)
		(width 0.1651)
		(layer "In7.Cu")
		(net "P5E_PEX1_STN6_TX_DP<102>")
	)
	(segment
		(start 167.16629 -319.712086)
		(end 167.231314 -319.712086)
		(width 0.1143)
		(layer "In7.Cu")
		(net "P5E_PEX1_STN6_TX_DP<102>")
	)
	(segment
		(start 141.534388 -303.752758)
		(end 141.884908 -303.402238)
		(width 0.1651)
		(layer "In9.Cu")
		(net "P5E_PEX1_STN7_RX_DN<112>")
	)
	(segment
		(start 152.49652 -301.220124)
		(end 155.117292 -301.220124)
		(width 0.1143)
		(layer "In9.Cu")
		(net "P5E_PEX1_STN7_RX_DN<112>")
	)
	(segment
		(start 140.196316 -304.947066)
		(end 140.546328 -304.597054)
		(width 0.1651)
		(layer "In9.Cu")
		(net "P5E_PEX1_STN7_RX_DN<112>")
	)
	(segment
		(start 141.040612 -304.246534)
		(end 141.040612 -304.10277)
		(width 0.1651)
		(layer "In9.Cu")
		(net "P5E_PEX1_STN7_RX_DN<112>")
	)
	(segment
		(start 158.217362 -393.070842)
		(end 153.888186 -389.54075)
		(width 0.1651)
		(layer "In9.Cu")
		(net "P5E_PEX1_STN7_RX_DN<112>")
	)
	(segment
		(start 155.229814 -301.510954)
		(end 155.140914 -301.599854)
		(width 0.1143)
		(layer "In9.Cu")
		(net "P5E_PEX1_STN7_RX_DN<112>")
	)
	(segment
		(start 141.884908 -303.258474)
		(end 142.23492 -302.908462)
		(width 0.1651)
		(layer "In9.Cu")
		(net "P5E_PEX1_STN7_RX_DN<112>")
	)
	(segment
		(start 160.375346 -408.981148)
		(end 161.074354 -408.28214)
		(width 0.1651)
		(layer "In9.Cu")
		(net "P5E_PEX1_STN7_RX_DN<112>")
	)
	(segment
		(start 138.887454 -306.255928)
		(end 139.702032 -305.44135)
		(width 0.1651)
		(layer "In9.Cu")
		(net "P5E_PEX1_STN7_RX_DN<112>")
	)
	(segment
		(start 139.702032 -305.44135)
		(end 139.845796 -305.44135)
		(width 0.1651)
		(layer "In9.Cu")
		(net "P5E_PEX1_STN7_RX_DN<112>")
	)
	(segment
		(start 137.978134 -308.305962)
		(end 137.97788 -308.305962)
		(width 0.1651)
		(layer "In9.Cu")
		(net "P5E_PEX1_STN7_RX_DN<112>")
	)
	(segment
		(start 146.54022 -346.085414)
		(end 145.152364 -342.210898)
		(width 0.1651)
		(layer "In9.Cu")
		(net "P5E_PEX1_STN7_RX_DN<112>")
	)
	(segment
		(start 134.512558 -324.995286)
		(end 134.042912 -323.24675)
		(width 0.1651)
		(layer "In9.Cu")
		(net "P5E_PEX1_STN7_RX_DN<112>")
	)
	(segment
		(start 139.845796 -305.44135)
		(end 140.196316 -305.09083)
		(width 0.1651)
		(layer "In9.Cu")
		(net "P5E_PEX1_STN7_RX_DN<112>")
	)
	(segment
		(start 161.074354 -408.28214)
		(end 161.074354 -394.75156)
		(width 0.1651)
		(layer "In9.Cu")
		(net "P5E_PEX1_STN7_RX_DN<112>")
	)
	(segment
		(start 155.117292 -301.220124)
		(end 155.229814 -301.332646)
		(width 0.1143)
		(layer "In9.Cu")
		(net "P5E_PEX1_STN7_RX_DN<112>")
	)
	(segment
		(start 141.040612 -304.10277)
		(end 141.390624 -303.752758)
		(width 0.1651)
		(layer "In9.Cu")
		(net "P5E_PEX1_STN7_RX_DN<112>")
	)
	(segment
		(start 137.97788 -308.305962)
		(end 138.111992 -308.2544)
		(width 0.1651)
		(layer "In9.Cu")
		(net "P5E_PEX1_STN7_RX_DN<112>")
	)
	(segment
		(start 140.196316 -305.09083)
		(end 140.196316 -304.947066)
		(width 0.1651)
		(layer "In9.Cu")
		(net "P5E_PEX1_STN7_RX_DN<112>")
	)
	(segment
		(start 152.422352 -301.265844)
		(end 152.4508 -301.265844)
		(width 0.1143)
		(layer "In9.Cu")
		(net "P5E_PEX1_STN7_RX_DN<112>")
	)
	(segment
		(start 155.140914 -301.599854)
		(end 154.850084 -301.599854)
		(width 0.1143)
		(layer "In9.Cu")
		(net "P5E_PEX1_STN7_RX_DN<112>")
	)
	(segment
		(start 153.888186 -389.54075)
		(end 151.927306 -385.980432)
		(width 0.1651)
		(layer "In9.Cu")
		(net "P5E_PEX1_STN7_RX_DN<112>")
	)
	(segment
		(start 140.546328 -304.597054)
		(end 140.690092 -304.597054)
		(width 0.1651)
		(layer "In9.Cu")
		(net "P5E_PEX1_STN7_RX_DN<112>")
	)
	(segment
		(start 160.22701 -393.904216)
		(end 158.217362 -393.070842)
		(width 0.1651)
		(layer "In9.Cu")
		(net "P5E_PEX1_STN7_RX_DN<112>")
	)
	(segment
		(start 143.989298 -302.182022)
		(end 147.86356 -301.265844)
		(width 0.1651)
		(layer "In9.Cu")
		(net "P5E_PEX1_STN7_RX_DN<112>")
	)
	(segment
		(start 134.042912 -323.24675)
		(end 134.042912 -317.17742)
		(width 0.1651)
		(layer "In9.Cu")
		(net "P5E_PEX1_STN7_RX_DN<112>")
	)
	(segment
		(start 145.152364 -342.210898)
		(end 134.512558 -324.995286)
		(width 0.1651)
		(layer "In9.Cu")
		(net "P5E_PEX1_STN7_RX_DN<112>")
	)
	(segment
		(start 160.037018 -408.981148)
		(end 160.375346 -408.981148)
		(width 0.1651)
		(layer "In9.Cu")
		(net "P5E_PEX1_STN7_RX_DN<112>")
	)
	(segment
		(start 141.390624 -303.752758)
		(end 141.534388 -303.752758)
		(width 0.1651)
		(layer "In9.Cu")
		(net "P5E_PEX1_STN7_RX_DN<112>")
	)
	(segment
		(start 140.690092 -304.597054)
		(end 141.040612 -304.246534)
		(width 0.1651)
		(layer "In9.Cu")
		(net "P5E_PEX1_STN7_RX_DN<112>")
	)
	(segment
		(start 138.31316 -307.801518)
		(end 138.261344 -307.667406)
		(width 0.1651)
		(layer "In9.Cu")
		(net "P5E_PEX1_STN7_RX_DN<112>")
	)
	(segment
		(start 134.042912 -317.17742)
		(end 137.978134 -308.305962)
		(width 0.1651)
		(layer "In9.Cu")
		(net "P5E_PEX1_STN7_RX_DN<112>")
	)
	(segment
		(start 141.884908 -303.402238)
		(end 141.884908 -303.258474)
		(width 0.1651)
		(layer "In9.Cu")
		(net "P5E_PEX1_STN7_RX_DN<112>")
	)
	(segment
		(start 159.910018 -409.490164)
		(end 159.910018 -409.108148)
		(width 0.1651)
		(layer "In9.Cu")
		(net "P5E_PEX1_STN7_RX_DN<112>")
	)
	(segment
		(start 155.229814 -301.332646)
		(end 155.229814 -301.510954)
		(width 0.1143)
		(layer "In9.Cu")
		(net "P5E_PEX1_STN7_RX_DN<112>")
	)
	(segment
		(start 142.23492 -302.908462)
		(end 143.989298 -302.182022)
		(width 0.1651)
		(layer "In9.Cu")
		(net "P5E_PEX1_STN7_RX_DN<112>")
	)
	(segment
		(start 138.261344 -307.667406)
		(end 138.887454 -306.255928)
		(width 0.1651)
		(layer "In9.Cu")
		(net "P5E_PEX1_STN7_RX_DN<112>")
	)
	(segment
		(start 159.910018 -409.108148)
		(end 160.037018 -408.981148)
		(width 0.1651)
		(layer "In9.Cu")
		(net "P5E_PEX1_STN7_RX_DN<112>")
	)
	(segment
		(start 138.111992 -308.2544)
		(end 138.31316 -307.801518)
		(width 0.1651)
		(layer "In9.Cu")
		(net "P5E_PEX1_STN7_RX_DN<112>")
	)
	(segment
		(start 147.86356 -301.265844)
		(end 152.422352 -301.265844)
		(width 0.1651)
		(layer "In9.Cu")
		(net "P5E_PEX1_STN7_RX_DN<112>")
	)
	(segment
		(start 151.927306 -385.980432)
		(end 146.54022 -346.085414)
		(width 0.1651)
		(layer "In9.Cu")
		(net "P5E_PEX1_STN7_RX_DN<112>")
	)
	(segment
		(start 161.074354 -394.75156)
		(end 160.22701 -393.904216)
		(width 0.1651)
		(layer "In9.Cu")
		(net "P5E_PEX1_STN7_RX_DN<112>")
	)
	(segment
		(start 152.4508 -301.265844)
		(end 152.49652 -301.220124)
		(width 0.1143)
		(layer "In9.Cu")
		(net "P5E_PEX1_STN7_RX_DN<112>")
	)
	(segment
		(start 155.113736 -135.815324)
		(end 154.793696 -136.135364)
		(width 0.13462)
		(layer "F.Cu")
		(net "P5E_PEX1_STN1_TX_DN<31>")
	)
	(segment
		(start 154.162252 -136.135364)
		(end 153.867612 -135.840724)
		(width 0.13462)
		(layer "F.Cu")
		(net "P5E_PEX1_STN1_TX_DN<31>")
	)
	(segment
		(start 154.793696 -136.135364)
		(end 154.162252 -136.135364)
		(width 0.13462)
		(layer "F.Cu")
		(net "P5E_PEX1_STN1_TX_DN<31>")
	)
	(segment
		(start 189.383924 -271.554448)
		(end 189.429644 -271.600168)
		(width 0.1143)
		(layer "In9.Cu")
		(net "P5E_PEX1_STN1_TX_DN<31>")
	)
	(segment
		(start 153.695908 -138.46683)
		(end 154.11958 -139.489688)
		(width 0.1651)
		(layer "In9.Cu")
		(net "P5E_PEX1_STN1_TX_DN<31>")
	)
	(segment
		(start 189.999874 -280.434288)
		(end 189.999874 -280.699718)
		(width 0.1143)
		(layer "In9.Cu")
		(net "P5E_PEX1_STN1_TX_DN<31>")
	)
	(segment
		(start 152.457658 -137.22858)
		(end 153.695908 -138.46683)
		(width 0.1651)
		(layer "In9.Cu")
		(net "P5E_PEX1_STN1_TX_DN<31>")
	)
	(segment
		(start 152.85085 -136.131554)
		(end 152.457658 -136.524746)
		(width 0.1651)
		(layer "In9.Cu")
		(net "P5E_PEX1_STN1_TX_DN<31>")
	)
	(segment
		(start 153.867612 -135.840724)
		(end 153.577036 -136.1313)
		(width 0.1651)
		(layer "In9.Cu")
		(net "P5E_PEX1_STN1_TX_DN<31>")
	)
	(segment
		(start 152.457658 -136.524746)
		(end 152.457658 -137.22858)
		(width 0.1651)
		(layer "In9.Cu")
		(net "P5E_PEX1_STN1_TX_DN<31>")
	)
	(segment
		(start 163.224464 -185.333386)
		(end 189.383924 -262.6106)
		(width 0.1651)
		(layer "In9.Cu")
		(net "P5E_PEX1_STN1_TX_DN<31>")
	)
	(segment
		(start 153.577036 -136.1313)
		(end 153.577036 -136.131554)
		(width 0.1651)
		(layer "In9.Cu")
		(net "P5E_PEX1_STN1_TX_DN<31>")
	)
	(segment
		(start 189.383924 -262.6106)
		(end 189.383924 -271.526)
		(width 0.1651)
		(layer "In9.Cu")
		(net "P5E_PEX1_STN1_TX_DN<31>")
	)
	(segment
		(start 154.11958 -139.489688)
		(end 163.224464 -185.333386)
		(width 0.1651)
		(layer "In9.Cu")
		(net "P5E_PEX1_STN1_TX_DN<31>")
	)
	(segment
		(start 189.429644 -271.600168)
		(end 189.429644 -280.10485)
		(width 0.1143)
		(layer "In9.Cu")
		(net "P5E_PEX1_STN1_TX_DN<31>")
	)
	(segment
		(start 189.429644 -280.10485)
		(end 189.644782 -280.319988)
		(width 0.1143)
		(layer "In9.Cu")
		(net "P5E_PEX1_STN1_TX_DN<31>")
	)
	(segment
		(start 153.577036 -136.131554)
		(end 152.85085 -136.131554)
		(width 0.1651)
		(layer "In9.Cu")
		(net "P5E_PEX1_STN1_TX_DN<31>")
	)
	(segment
		(start 189.885574 -280.319988)
		(end 189.999874 -280.434288)
		(width 0.1143)
		(layer "In9.Cu")
		(net "P5E_PEX1_STN1_TX_DN<31>")
	)
	(segment
		(start 189.383924 -271.526)
		(end 189.383924 -271.554448)
		(width 0.1143)
		(layer "In9.Cu")
		(net "P5E_PEX1_STN1_TX_DN<31>")
	)
	(segment
		(start 189.644782 -280.319988)
		(end 189.885574 -280.319988)
		(width 0.1143)
		(layer "In9.Cu")
		(net "P5E_PEX1_STN1_TX_DN<31>")
	)
	(segment
		(start 121.757948 -355.658166)
		(end 121.757948 -355.026722)
		(width 0.13462)
		(layer "F.Cu")
		(net "P5E_PEX1_STN6_TX_DN<98>")
	)
	(segment
		(start 121.757948 -355.026722)
		(end 122.052588 -354.732082)
		(width 0.13462)
		(layer "F.Cu")
		(net "P5E_PEX1_STN6_TX_DN<98>")
	)
	(segment
		(start 122.077988 -355.978206)
		(end 121.757948 -355.658166)
		(width 0.13462)
		(layer "F.Cu")
		(net "P5E_PEX1_STN6_TX_DN<98>")
	)
	(segment
		(start 171.570142 -313.684412)
		(end 171.684442 -313.570112)
		(width 0.1143)
		(layer "In7.Cu")
		(net "P5E_PEX1_STN6_TX_DN<98>")
	)
	(segment
		(start 171.684442 -313.570112)
		(end 171.835572 -313.570112)
		(width 0.1143)
		(layer "In7.Cu")
		(net "P5E_PEX1_STN6_TX_DN<98>")
	)
	(segment
		(start 123.316238 -352.268282)
		(end 123.316238 -341.851996)
		(width 0.1651)
		(layer "In7.Cu")
		(net "P5E_PEX1_STN6_TX_DN<98>")
	)
	(segment
		(start 171.835572 -313.570112)
		(end 171.949872 -313.684412)
		(width 0.1143)
		(layer "In7.Cu")
		(net "P5E_PEX1_STN6_TX_DN<98>")
	)
	(segment
		(start 171.949872 -313.684412)
		(end 171.949872 -313.949842)
		(width 0.1143)
		(layer "In7.Cu")
		(net "P5E_PEX1_STN6_TX_DN<98>")
	)
	(segment
		(start 171.615862 -320.675762)
		(end 171.615862 -320.002408)
		(width 0.1651)
		(layer "In7.Cu")
		(net "P5E_PEX1_STN6_TX_DN<98>")
	)
	(segment
		(start 167.550338 -324.826884)
		(end 169.94505 -323.391276)
		(width 0.1651)
		(layer "In7.Cu")
		(net "P5E_PEX1_STN6_TX_DN<98>")
	)
	(segment
		(start 123.316238 -341.851996)
		(end 125.068584 -340.09965)
		(width 0.1651)
		(layer "In7.Cu")
		(net "P5E_PEX1_STN6_TX_DN<98>")
	)
	(segment
		(start 171.570142 -319.92824)
		(end 171.570142 -313.684412)
		(width 0.1143)
		(layer "In7.Cu")
		(net "P5E_PEX1_STN6_TX_DN<98>")
	)
	(segment
		(start 171.615862 -319.97396)
		(end 171.570142 -319.92824)
		(width 0.1143)
		(layer "In7.Cu")
		(net "P5E_PEX1_STN6_TX_DN<98>")
	)
	(segment
		(start 170.87723 -322.459096)
		(end 171.615862 -320.675762)
		(width 0.1651)
		(layer "In7.Cu")
		(net "P5E_PEX1_STN6_TX_DN<98>")
	)
	(segment
		(start 133.12521 -335.270348)
		(end 167.550338 -324.826884)
		(width 0.1651)
		(layer "In7.Cu")
		(net "P5E_PEX1_STN6_TX_DN<98>")
	)
	(segment
		(start 121.761758 -353.822762)
		(end 123.316238 -352.268282)
		(width 0.1651)
		(layer "In7.Cu")
		(net "P5E_PEX1_STN6_TX_DN<98>")
	)
	(segment
		(start 122.052588 -354.732082)
		(end 121.761758 -354.441252)
		(width 0.1651)
		(layer "In7.Cu")
		(net "P5E_PEX1_STN6_TX_DN<98>")
	)
	(segment
		(start 125.068584 -340.09965)
		(end 133.12521 -335.270348)
		(width 0.1651)
		(layer "In7.Cu")
		(net "P5E_PEX1_STN6_TX_DN<98>")
	)
	(segment
		(start 171.615862 -320.002408)
		(end 171.615862 -319.97396)
		(width 0.1143)
		(layer "In7.Cu")
		(net "P5E_PEX1_STN6_TX_DN<98>")
	)
	(segment
		(start 121.761758 -354.441252)
		(end 121.761758 -353.822762)
		(width 0.1651)
		(layer "In7.Cu")
		(net "P5E_PEX1_STN6_TX_DN<98>")
	)
	(segment
		(start 169.94505 -323.391276)
		(end 170.87723 -322.459096)
		(width 0.1651)
		(layer "In7.Cu")
		(net "P5E_PEX1_STN6_TX_DN<98>")
	)
	(segment
		(start 176.866296 -326.79005)
		(end 177.562002 -325.111872)
		(width 0.1651)
		(layer "In5.Cu")
		(net "P5E_PEX1_STN5_RX_DP<84>")
	)
	(segment
		(start 127.134874 -394.41247)
		(end 127.822198 -393.697206)
		(width 0.1651)
		(layer "In5.Cu")
		(net "P5E_PEX1_STN5_RX_DP<84>")
	)
	(segment
		(start 125.818646 -395.623542)
		(end 126.155958 -395.272768)
		(width 0.1651)
		(layer "In5.Cu")
		(net "P5E_PEX1_STN5_RX_DP<84>")
	)
	(segment
		(start 137.211308 -390.435084)
		(end 139.090908 -389.11022)
		(width 0.1651)
		(layer "In5.Cu")
		(net "P5E_PEX1_STN5_RX_DP<84>")
	)
	(segment
		(start 126.155958 -395.272768)
		(end 126.311406 -395.26972)
		(width 0.1651)
		(layer "In5.Cu")
		(net "P5E_PEX1_STN5_RX_DP<84>")
	)
	(segment
		(start 126.64313 -394.801598)
		(end 127.014986 -394.414756)
		(width 0.1651)
		(layer "In5.Cu")
		(net "P5E_PEX1_STN5_RX_DP<84>")
	)
	(segment
		(start 125.487684 -396.781528)
		(end 125.487684 -396.12697)
		(width 0.1651)
		(layer "In5.Cu")
		(net "P5E_PEX1_STN5_RX_DP<84>")
	)
	(segment
		(start 131.31165 -391.927588)
		(end 132.973318 -391.279126)
		(width 0.1651)
		(layer "In5.Cu")
		(net "P5E_PEX1_STN5_RX_DP<84>")
	)
	(segment
		(start 125.270006 -396.999206)
		(end 125.487684 -396.781528)
		(width 0.1651)
		(layer "In5.Cu")
		(net "P5E_PEX1_STN5_RX_DP<84>")
	)
	(segment
		(start 178.029616 -316.455298)
		(end 178.255422 -316.229492)
		(width 0.1143)
		(layer "In5.Cu")
		(net "P5E_PEX1_STN5_RX_DP<84>")
	)
	(segment
		(start 152.461976 -353.365054)
		(end 159.755332 -338.80044)
		(width 0.1651)
		(layer "In5.Cu")
		(net "P5E_PEX1_STN5_RX_DP<84>")
	)
	(segment
		(start 126.64567 -394.92174)
		(end 126.64313 -394.801598)
		(width 0.1651)
		(layer "In5.Cu")
		(net "P5E_PEX1_STN5_RX_DP<84>")
	)
	(segment
		(start 177.983896 -323.677534)
		(end 177.983896 -319.91173)
		(width 0.1651)
		(layer "In5.Cu")
		(net "P5E_PEX1_STN5_RX_DP<84>")
	)
	(segment
		(start 125.487684 -396.12697)
		(end 125.821948 -395.77899)
		(width 0.1651)
		(layer "In5.Cu")
		(net "P5E_PEX1_STN5_RX_DP<84>")
	)
	(segment
		(start 178.485546 -316.229492)
		(end 178.599846 -316.115192)
		(width 0.1143)
		(layer "In5.Cu")
		(net "P5E_PEX1_STN5_RX_DP<84>")
	)
	(segment
		(start 139.968986 -387.635496)
		(end 146.247104 -370.843556)
		(width 0.1651)
		(layer "In5.Cu")
		(net "P5E_PEX1_STN5_RX_DP<84>")
	)
	(segment
		(start 125.821948 -395.77899)
		(end 125.818646 -395.623542)
		(width 0.1651)
		(layer "In5.Cu")
		(net "P5E_PEX1_STN5_RX_DP<84>")
	)
	(segment
		(start 129.64922 -392.576304)
		(end 131.311396 -391.927588)
		(width 0.1651)
		(layer "In5.Cu")
		(net "P5E_PEX1_STN5_RX_DP<84>")
	)
	(segment
		(start 124.71019 -396.49019)
		(end 124.71019 -396.871952)
		(width 0.1651)
		(layer "In5.Cu")
		(net "P5E_PEX1_STN5_RX_DP<84>")
	)
	(segment
		(start 139.090908 -389.11022)
		(end 139.968986 -387.635496)
		(width 0.1651)
		(layer "In5.Cu")
		(net "P5E_PEX1_STN5_RX_DP<84>")
	)
	(segment
		(start 146.247104 -370.843556)
		(end 147.45589 -366.57407)
		(width 0.1651)
		(layer "In5.Cu")
		(net "P5E_PEX1_STN5_RX_DP<84>")
	)
	(segment
		(start 161.808668 -336.506058)
		(end 174.791878 -328.864976)
		(width 0.1651)
		(layer "In5.Cu")
		(net "P5E_PEX1_STN5_RX_DP<84>")
	)
	(segment
		(start 159.755332 -338.80044)
		(end 161.808668 -336.506058)
		(width 0.1651)
		(layer "In5.Cu")
		(net "P5E_PEX1_STN5_RX_DP<84>")
	)
	(segment
		(start 178.599846 -316.115192)
		(end 178.599846 -315.849762)
		(width 0.1143)
		(layer "In5.Cu")
		(net "P5E_PEX1_STN5_RX_DP<84>")
	)
	(segment
		(start 127.822198 -393.697206)
		(end 129.64922 -392.576304)
		(width 0.1651)
		(layer "In5.Cu")
		(net "P5E_PEX1_STN5_RX_DP<84>")
	)
	(segment
		(start 132.973318 -391.279126)
		(end 137.211308 -390.435084)
		(width 0.1651)
		(layer "In5.Cu")
		(net "P5E_PEX1_STN5_RX_DP<84>")
	)
	(segment
		(start 177.562002 -325.111872)
		(end 177.983896 -323.677534)
		(width 0.1651)
		(layer "In5.Cu")
		(net "P5E_PEX1_STN5_RX_DP<84>")
	)
	(segment
		(start 147.45589 -366.57407)
		(end 152.461976 -353.365054)
		(width 0.1651)
		(layer "In5.Cu")
		(net "P5E_PEX1_STN5_RX_DP<84>")
	)
	(segment
		(start 124.71019 -396.871952)
		(end 124.837444 -396.999206)
		(width 0.1651)
		(layer "In5.Cu")
		(net "P5E_PEX1_STN5_RX_DP<84>")
	)
	(segment
		(start 126.311406 -395.26972)
		(end 126.64567 -394.92174)
		(width 0.1651)
		(layer "In5.Cu")
		(net "P5E_PEX1_STN5_RX_DP<84>")
	)
	(segment
		(start 177.983896 -319.883282)
		(end 178.029616 -319.837562)
		(width 0.1143)
		(layer "In5.Cu")
		(net "P5E_PEX1_STN5_RX_DP<84>")
	)
	(segment
		(start 177.983896 -319.91173)
		(end 177.983896 -319.883282)
		(width 0.1143)
		(layer "In5.Cu")
		(net "P5E_PEX1_STN5_RX_DP<84>")
	)
	(segment
		(start 127.135128 -394.41247)
		(end 127.134874 -394.41247)
		(width 0.1651)
		(layer "In5.Cu")
		(net "P5E_PEX1_STN5_RX_DP<84>")
	)
	(segment
		(start 131.311396 -391.927588)
		(end 131.31165 -391.927588)
		(width 0.1651)
		(layer "In5.Cu")
		(net "P5E_PEX1_STN5_RX_DP<84>")
	)
	(segment
		(start 178.029616 -319.837562)
		(end 178.029616 -316.455298)
		(width 0.1143)
		(layer "In5.Cu")
		(net "P5E_PEX1_STN5_RX_DP<84>")
	)
	(segment
		(start 174.791878 -328.864976)
		(end 176.866296 -326.79005)
		(width 0.1651)
		(layer "In5.Cu")
		(net "P5E_PEX1_STN5_RX_DP<84>")
	)
	(segment
		(start 178.255422 -316.229492)
		(end 178.485546 -316.229492)
		(width 0.1143)
		(layer "In5.Cu")
		(net "P5E_PEX1_STN5_RX_DP<84>")
	)
	(segment
		(start 127.014986 -394.414756)
		(end 127.135128 -394.41247)
		(width 0.1651)
		(layer "In5.Cu")
		(net "P5E_PEX1_STN5_RX_DP<84>")
	)
	(segment
		(start 124.837444 -396.999206)
		(end 125.270006 -396.999206)
		(width 0.1651)
		(layer "In5.Cu")
		(net "P5E_PEX1_STN5_RX_DP<84>")
	)
	(segment
		(start 151.520144 -108.61548)
		(end 151.225504 -108.32084)
		(width 0.13462)
		(layer "F.Cu")
		(net "P5E_PEX1_STN1_TX_DN<21>")
	)
	(segment
		(start 152.151588 -108.61548)
		(end 151.520144 -108.61548)
		(width 0.13462)
		(layer "F.Cu")
		(net "P5E_PEX1_STN1_TX_DN<21>")
	)
	(segment
		(start 152.471628 -108.29544)
		(end 152.151588 -108.61548)
		(width 0.13462)
		(layer "F.Cu")
		(net "P5E_PEX1_STN1_TX_DN<21>")
	)
	(segment
		(start 144.438624 -159.000952)
		(end 145.01876 -161.917634)
		(width 0.1651)
		(layer "In9.Cu")
		(net "P5E_PEX1_STN1_TX_DN<21>")
	)
	(segment
		(start 180.38572 -280.319988)
		(end 180.50002 -280.434288)
		(width 0.1143)
		(layer "In9.Cu")
		(net "P5E_PEX1_STN1_TX_DN<21>")
	)
	(segment
		(start 148.485352 -110.278418)
		(end 144.891506 -118.953534)
		(width 0.1651)
		(layer "In9.Cu")
		(net "P5E_PEX1_STN1_TX_DN<21>")
	)
	(segment
		(start 151.225504 -108.32084)
		(end 150.934674 -108.61167)
		(width 0.1651)
		(layer "In9.Cu")
		(net "P5E_PEX1_STN1_TX_DN<21>")
	)
	(segment
		(start 179.92979 -280.10485)
		(end 180.144928 -280.319988)
		(width 0.1143)
		(layer "In9.Cu")
		(net "P5E_PEX1_STN1_TX_DN<21>")
	)
	(segment
		(start 145.01876 -161.917634)
		(end 179.88407 -264.919968)
		(width 0.1651)
		(layer "In9.Cu")
		(net "P5E_PEX1_STN1_TX_DN<21>")
	)
	(segment
		(start 179.92979 -271.600168)
		(end 179.92979 -280.10485)
		(width 0.1143)
		(layer "In9.Cu")
		(net "P5E_PEX1_STN1_TX_DN<21>")
	)
	(segment
		(start 179.88407 -271.526)
		(end 179.88407 -271.554448)
		(width 0.1143)
		(layer "In9.Cu")
		(net "P5E_PEX1_STN1_TX_DN<21>")
	)
	(segment
		(start 180.144928 -280.319988)
		(end 180.38572 -280.319988)
		(width 0.1143)
		(layer "In9.Cu")
		(net "P5E_PEX1_STN1_TX_DN<21>")
	)
	(segment
		(start 144.891506 -118.953534)
		(end 141.14399 -131.308856)
		(width 0.1651)
		(layer "In9.Cu")
		(net "P5E_PEX1_STN1_TX_DN<21>")
	)
	(segment
		(start 179.88407 -264.919968)
		(end 179.88407 -271.526)
		(width 0.1651)
		(layer "In9.Cu")
		(net "P5E_PEX1_STN1_TX_DN<21>")
	)
	(segment
		(start 150.934674 -108.61167)
		(end 150.152354 -108.61167)
		(width 0.1651)
		(layer "In9.Cu")
		(net "P5E_PEX1_STN1_TX_DN<21>")
	)
	(segment
		(start 180.50002 -280.434288)
		(end 180.50002 -280.699718)
		(width 0.1143)
		(layer "In9.Cu")
		(net "P5E_PEX1_STN1_TX_DN<21>")
	)
	(segment
		(start 141.14399 -138.027156)
		(end 143.712692 -144.22882)
		(width 0.1651)
		(layer "In9.Cu")
		(net "P5E_PEX1_STN1_TX_DN<21>")
	)
	(segment
		(start 143.712692 -144.22882)
		(end 144.256506 -155.297378)
		(width 0.1651)
		(layer "In9.Cu")
		(net "P5E_PEX1_STN1_TX_DN<21>")
	)
	(segment
		(start 144.256506 -155.297378)
		(end 144.438624 -159.000952)
		(width 0.1651)
		(layer "In9.Cu")
		(net "P5E_PEX1_STN1_TX_DN<21>")
	)
	(segment
		(start 179.88407 -271.554448)
		(end 179.92979 -271.600168)
		(width 0.1143)
		(layer "In9.Cu")
		(net "P5E_PEX1_STN1_TX_DN<21>")
	)
	(segment
		(start 141.14399 -131.308856)
		(end 141.14399 -138.027156)
		(width 0.1651)
		(layer "In9.Cu")
		(net "P5E_PEX1_STN1_TX_DN<21>")
	)
	(segment
		(start 150.152354 -108.61167)
		(end 148.485352 -110.278418)
		(width 0.1651)
		(layer "In9.Cu")
		(net "P5E_PEX1_STN1_TX_DN<21>")
	)
	(segment
		(start 162.755072 -355.658166)
		(end 162.755072 -355.026722)
		(width 0.13462)
		(layer "F.Cu")
		(net "P5E_PEX1_STN7_TX_DN<113>")
	)
	(segment
		(start 163.075112 -355.978206)
		(end 162.755072 -355.658166)
		(width 0.13462)
		(layer "F.Cu")
		(net "P5E_PEX1_STN7_TX_DN<113>")
	)
	(segment
		(start 162.755072 -355.026722)
		(end 163.049712 -354.732082)
		(width 0.13462)
		(layer "F.Cu")
		(net "P5E_PEX1_STN7_TX_DN<113>")
	)
	(segment
		(start 137.36447 -311.175146)
		(end 137.660126 -310.777382)
		(width 0.1651)
		(layer "In11.Cu")
		(net "P5E_PEX1_STN7_TX_DN<113>")
	)
	(segment
		(start 159.890714 -302.549814)
		(end 159.599884 -302.549814)
		(width 0.1143)
		(layer "In11.Cu")
		(net "P5E_PEX1_STN7_TX_DN<113>")
	)
	(segment
		(start 137.93216 -310.220106)
		(end 137.931906 -310.220106)
		(width 0.1651)
		(layer "In11.Cu")
		(net "P5E_PEX1_STN7_TX_DN<113>")
	)
	(segment
		(start 139.11453 -308.820058)
		(end 139.090908 -308.660292)
		(width 0.1651)
		(layer "In11.Cu")
		(net "P5E_PEX1_STN7_TX_DN<113>")
	)
	(segment
		(start 139.54633 -308.23916)
		(end 139.841986 -307.841396)
		(width 0.1651)
		(layer "In11.Cu")
		(net "P5E_PEX1_STN7_TX_DN<113>")
	)
	(segment
		(start 138.363706 -309.638954)
		(end 138.36396 -309.638954)
		(width 0.1651)
		(layer "In11.Cu")
		(net "P5E_PEX1_STN7_TX_DN<113>")
	)
	(segment
		(start 134.815072 -325.987664)
		(end 133.867398 -322.861686)
		(width 0.1651)
		(layer "In11.Cu")
		(net "P5E_PEX1_STN7_TX_DN<113>")
	)
	(segment
		(start 140.273786 -307.260498)
		(end 140.569442 -306.862734)
		(width 0.1651)
		(layer "In11.Cu")
		(net "P5E_PEX1_STN7_TX_DN<113>")
	)
	(segment
		(start 141.296898 -305.884072)
		(end 141.273276 -305.724306)
		(width 0.1651)
		(layer "In11.Cu")
		(net "P5E_PEX1_STN7_TX_DN<113>")
	)
	(segment
		(start 162.758882 -354.441252)
		(end 162.758882 -354.000308)
		(width 0.1651)
		(layer "In11.Cu")
		(net "P5E_PEX1_STN7_TX_DN<113>")
	)
	(segment
		(start 162.758882 -354.000308)
		(end 162.545014 -353.488752)
		(width 0.1651)
		(layer "In11.Cu")
		(net "P5E_PEX1_STN7_TX_DN<113>")
	)
	(segment
		(start 141.568678 -305.326796)
		(end 143.68145 -303.214024)
		(width 0.1651)
		(layer "In11.Cu")
		(net "P5E_PEX1_STN7_TX_DN<113>")
	)
	(segment
		(start 139.386818 -308.263036)
		(end 139.38631 -308.262782)
		(width 0.1651)
		(layer "In11.Cu")
		(net "P5E_PEX1_STN7_TX_DN<113>")
	)
	(segment
		(start 138.091672 -310.196484)
		(end 138.387328 -309.79872)
		(width 0.1651)
		(layer "In11.Cu")
		(net "P5E_PEX1_STN7_TX_DN<113>")
	)
	(segment
		(start 141.273276 -305.724306)
		(end 141.568678 -305.326796)
		(width 0.1651)
		(layer "In11.Cu")
		(net "P5E_PEX1_STN7_TX_DN<113>")
	)
	(segment
		(start 163.049712 -354.732082)
		(end 162.758882 -354.441252)
		(width 0.1651)
		(layer "In11.Cu")
		(net "P5E_PEX1_STN7_TX_DN<113>")
	)
	(segment
		(start 142.675356 -334.665066)
		(end 137.066528 -329.354688)
		(width 0.1651)
		(layer "In11.Cu")
		(net "P5E_PEX1_STN7_TX_DN<113>")
	)
	(segment
		(start 137.636504 -310.61787)
		(end 137.93216 -310.220106)
		(width 0.1651)
		(layer "In11.Cu")
		(net "P5E_PEX1_STN7_TX_DN<113>")
	)
	(segment
		(start 138.659108 -309.241444)
		(end 138.818874 -309.217822)
		(width 0.1651)
		(layer "In11.Cu")
		(net "P5E_PEX1_STN7_TX_DN<113>")
	)
	(segment
		(start 139.818618 -307.68163)
		(end 140.11402 -307.284374)
		(width 0.1651)
		(layer "In11.Cu")
		(net "P5E_PEX1_STN7_TX_DN<113>")
	)
	(segment
		(start 143.201136 -335.16316)
		(end 143.196818 -335.001362)
		(width 0.1651)
		(layer "In11.Cu")
		(net "P5E_PEX1_STN7_TX_DN<113>")
	)
	(segment
		(start 139.091162 -308.660546)
		(end 139.386818 -308.263036)
		(width 0.1651)
		(layer "In11.Cu")
		(net "P5E_PEX1_STN7_TX_DN<113>")
	)
	(segment
		(start 139.818364 -307.68163)
		(end 139.818618 -307.68163)
		(width 0.1651)
		(layer "In11.Cu")
		(net "P5E_PEX1_STN7_TX_DN<113>")
	)
	(segment
		(start 140.54582 -306.702968)
		(end 140.841222 -306.305458)
		(width 0.1651)
		(layer "In11.Cu")
		(net "P5E_PEX1_STN7_TX_DN<113>")
	)
	(segment
		(start 133.867398 -322.861686)
		(end 133.867398 -319.591944)
		(width 0.1651)
		(layer "In11.Cu")
		(net "P5E_PEX1_STN7_TX_DN<113>")
	)
	(segment
		(start 138.818874 -309.217822)
		(end 139.11453 -308.820058)
		(width 0.1651)
		(layer "In11.Cu")
		(net "P5E_PEX1_STN7_TX_DN<113>")
	)
	(segment
		(start 136.522714 -312.11647)
		(end 137.204704 -311.198768)
		(width 0.1651)
		(layer "In11.Cu")
		(net "P5E_PEX1_STN7_TX_DN<113>")
	)
	(segment
		(start 140.113766 -307.28412)
		(end 140.273786 -307.260498)
		(width 0.1651)
		(layer "In11.Cu")
		(net "P5E_PEX1_STN7_TX_DN<113>")
	)
	(segment
		(start 133.867398 -319.591944)
		(end 134.275322 -317.537084)
		(width 0.1651)
		(layer "In11.Cu")
		(net "P5E_PEX1_STN7_TX_DN<113>")
	)
	(segment
		(start 138.36396 -309.638954)
		(end 138.659362 -309.241698)
		(width 0.1651)
		(layer "In11.Cu")
		(net "P5E_PEX1_STN7_TX_DN<113>")
	)
	(segment
		(start 162.545014 -353.488752)
		(end 162.274758 -353.221798)
		(width 0.1651)
		(layer "In11.Cu")
		(net "P5E_PEX1_STN7_TX_DN<113>")
	)
	(segment
		(start 162.274758 -353.221798)
		(end 143.201136 -335.162906)
		(width 0.1651)
		(layer "In11.Cu")
		(net "P5E_PEX1_STN7_TX_DN<113>")
	)
	(segment
		(start 137.660126 -310.777382)
		(end 137.636504 -310.61787)
		(width 0.1651)
		(layer "In11.Cu")
		(net "P5E_PEX1_STN7_TX_DN<113>")
	)
	(segment
		(start 142.8369 -334.660748)
		(end 142.675356 -334.665066)
		(width 0.1651)
		(layer "In11.Cu")
		(net "P5E_PEX1_STN7_TX_DN<113>")
	)
	(segment
		(start 141.001242 -306.281836)
		(end 141.296898 -305.884072)
		(width 0.1651)
		(layer "In11.Cu")
		(net "P5E_PEX1_STN7_TX_DN<113>")
	)
	(segment
		(start 137.931906 -310.220106)
		(end 138.091672 -310.196484)
		(width 0.1651)
		(layer "In11.Cu")
		(net "P5E_PEX1_STN7_TX_DN<113>")
	)
	(segment
		(start 138.659362 -309.241698)
		(end 138.659108 -309.241444)
		(width 0.1651)
		(layer "In11.Cu")
		(net "P5E_PEX1_STN7_TX_DN<113>")
	)
	(segment
		(start 151.583136 -302.215804)
		(end 151.605234 -302.215804)
		(width 0.1143)
		(layer "In11.Cu")
		(net "P5E_PEX1_STN7_TX_DN<113>")
	)
	(segment
		(start 143.196818 -335.001362)
		(end 142.8369 -334.660748)
		(width 0.1651)
		(layer "In11.Cu")
		(net "P5E_PEX1_STN7_TX_DN<113>")
	)
	(segment
		(start 140.841222 -306.305458)
		(end 141.001242 -306.281836)
		(width 0.1651)
		(layer "In11.Cu")
		(net "P5E_PEX1_STN7_TX_DN<113>")
	)
	(segment
		(start 159.979614 -302.311308)
		(end 159.979614 -302.460914)
		(width 0.1143)
		(layer "In11.Cu")
		(net "P5E_PEX1_STN7_TX_DN<113>")
	)
	(segment
		(start 146.091402 -302.215804)
		(end 151.583136 -302.215804)
		(width 0.1651)
		(layer "In11.Cu")
		(net "P5E_PEX1_STN7_TX_DN<113>")
	)
	(segment
		(start 137.066528 -329.354688)
		(end 134.815072 -325.987664)
		(width 0.1651)
		(layer "In11.Cu")
		(net "P5E_PEX1_STN7_TX_DN<113>")
	)
	(segment
		(start 137.204704 -311.198768)
		(end 137.36447 -311.175146)
		(width 0.1651)
		(layer "In11.Cu")
		(net "P5E_PEX1_STN7_TX_DN<113>")
	)
	(segment
		(start 139.090908 -308.660292)
		(end 139.091162 -308.660546)
		(width 0.1651)
		(layer "In11.Cu")
		(net "P5E_PEX1_STN7_TX_DN<113>")
	)
	(segment
		(start 139.38631 -308.262782)
		(end 139.54633 -308.23916)
		(width 0.1651)
		(layer "In11.Cu")
		(net "P5E_PEX1_STN7_TX_DN<113>")
	)
	(segment
		(start 140.11402 -307.284374)
		(end 140.113766 -307.28412)
		(width 0.1651)
		(layer "In11.Cu")
		(net "P5E_PEX1_STN7_TX_DN<113>")
	)
	(segment
		(start 140.569442 -306.862734)
		(end 140.54582 -306.702968)
		(width 0.1651)
		(layer "In11.Cu")
		(net "P5E_PEX1_STN7_TX_DN<113>")
	)
	(segment
		(start 159.979614 -302.460914)
		(end 159.890714 -302.549814)
		(width 0.1143)
		(layer "In11.Cu")
		(net "P5E_PEX1_STN7_TX_DN<113>")
	)
	(segment
		(start 159.83839 -302.170084)
		(end 159.979614 -302.311308)
		(width 0.1143)
		(layer "In11.Cu")
		(net "P5E_PEX1_STN7_TX_DN<113>")
	)
	(segment
		(start 143.201136 -335.162906)
		(end 143.201136 -335.16316)
		(width 0.1651)
		(layer "In11.Cu")
		(net "P5E_PEX1_STN7_TX_DN<113>")
	)
	(segment
		(start 151.650954 -302.170084)
		(end 159.83839 -302.170084)
		(width 0.1143)
		(layer "In11.Cu")
		(net "P5E_PEX1_STN7_TX_DN<113>")
	)
	(segment
		(start 139.841986 -307.841396)
		(end 139.818364 -307.68163)
		(width 0.1651)
		(layer "In11.Cu")
		(net "P5E_PEX1_STN7_TX_DN<113>")
	)
	(segment
		(start 143.68145 -303.214024)
		(end 146.091402 -302.215804)
		(width 0.1651)
		(layer "In11.Cu")
		(net "P5E_PEX1_STN7_TX_DN<113>")
	)
	(segment
		(start 134.275322 -317.537084)
		(end 136.522714 -312.11647)
		(width 0.1651)
		(layer "In11.Cu")
		(net "P5E_PEX1_STN7_TX_DN<113>")
	)
	(segment
		(start 138.387328 -309.79872)
		(end 138.363706 -309.638954)
		(width 0.1651)
		(layer "In11.Cu")
		(net "P5E_PEX1_STN7_TX_DN<113>")
	)
	(segment
		(start 151.605234 -302.215804)
		(end 151.650954 -302.170084)
		(width 0.1143)
		(layer "In11.Cu")
		(net "P5E_PEX1_STN7_TX_DN<113>")
	)
	(segment
		(start 172.132752 -325.931276)
		(end 173.269148 -324.79488)
		(width 0.1651)
		(layer "In5.Cu")
		(net "P5E_PEX1_STN5_RX_DP<80>")
	)
	(segment
		(start 118.28399 -393.913106)
		(end 118.334282 -393.763246)
		(width 0.1651)
		(layer "In5.Cu")
		(net "P5E_PEX1_STN5_RX_DP<80>")
	)
	(segment
		(start 116.91366 -395.896592)
		(end 116.875306 -395.771624)
		(width 0.1651)
		(layer "In5.Cu")
		(net "P5E_PEX1_STN5_RX_DP<80>")
	)
	(segment
		(start 116.469922 -396.999206)
		(end 116.6876 -396.781528)
		(width 0.1651)
		(layer "In5.Cu")
		(net "P5E_PEX1_STN5_RX_DP<80>")
	)
	(segment
		(start 174.184056 -322.588636)
		(end 174.184056 -319.91173)
		(width 0.1651)
		(layer "In5.Cu")
		(net "P5E_PEX1_STN5_RX_DP<80>")
	)
	(segment
		(start 136.088374 -386.550662)
		(end 136.310624 -386.195824)
		(width 0.1651)
		(layer "In5.Cu")
		(net "P5E_PEX1_STN5_RX_DP<80>")
	)
	(segment
		(start 159.12719 -333.618078)
		(end 172.132752 -325.931276)
		(width 0.1651)
		(layer "In5.Cu")
		(net "P5E_PEX1_STN5_RX_DP<80>")
	)
	(segment
		(start 118.334282 -393.763246)
		(end 118.76659 -393.548108)
		(width 0.1651)
		(layer "In5.Cu")
		(net "P5E_PEX1_STN5_RX_DP<80>")
	)
	(segment
		(start 131.735068 -387.629654)
		(end 135.67029 -386.845302)
		(width 0.1651)
		(layer "In5.Cu")
		(net "P5E_PEX1_STN5_RX_DP<80>")
	)
	(segment
		(start 174.800006 -316.115192)
		(end 174.800006 -315.849762)
		(width 0.1143)
		(layer "In5.Cu")
		(net "P5E_PEX1_STN5_RX_DP<80>")
	)
	(segment
		(start 115.910106 -396.871952)
		(end 116.03736 -396.999206)
		(width 0.1651)
		(layer "In5.Cu")
		(net "P5E_PEX1_STN5_RX_DP<80>")
	)
	(segment
		(start 136.310624 -386.195824)
		(end 142.371826 -369.996212)
		(width 0.1651)
		(layer "In5.Cu")
		(net "P5E_PEX1_STN5_RX_DP<80>")
	)
	(segment
		(start 117.119908 -395.310868)
		(end 117.244876 -395.272514)
		(width 0.1651)
		(layer "In5.Cu")
		(net "P5E_PEX1_STN5_RX_DP<80>")
	)
	(segment
		(start 173.269148 -324.79488)
		(end 174.184056 -322.588636)
		(width 0.1651)
		(layer "In5.Cu")
		(net "P5E_PEX1_STN5_RX_DP<80>")
	)
	(segment
		(start 118.91645 -393.5984)
		(end 127.964946 -389.101076)
		(width 0.1651)
		(layer "In5.Cu")
		(net "P5E_PEX1_STN5_RX_DP<80>")
	)
	(segment
		(start 143.495014 -365.952278)
		(end 148.75891 -352.067876)
		(width 0.1651)
		(layer "In5.Cu")
		(net "P5E_PEX1_STN5_RX_DP<80>")
	)
	(segment
		(start 116.875306 -395.771624)
		(end 117.119908 -395.310868)
		(width 0.1651)
		(layer "In5.Cu")
		(net "P5E_PEX1_STN5_RX_DP<80>")
	)
	(segment
		(start 116.03736 -396.999206)
		(end 116.469922 -396.999206)
		(width 0.1651)
		(layer "In5.Cu")
		(net "P5E_PEX1_STN5_RX_DP<80>")
	)
	(segment
		(start 174.229776 -319.837562)
		(end 174.229776 -316.455298)
		(width 0.1143)
		(layer "In5.Cu")
		(net "P5E_PEX1_STN5_RX_DP<80>")
	)
	(segment
		(start 127.964946 -389.101076)
		(end 131.735068 -387.629654)
		(width 0.1651)
		(layer "In5.Cu")
		(net "P5E_PEX1_STN5_RX_DP<80>")
	)
	(segment
		(start 116.6876 -396.781528)
		(end 116.6876 -396.322804)
		(width 0.1651)
		(layer "In5.Cu")
		(net "P5E_PEX1_STN5_RX_DP<80>")
	)
	(segment
		(start 174.455582 -316.229492)
		(end 174.685706 -316.229492)
		(width 0.1143)
		(layer "In5.Cu")
		(net "P5E_PEX1_STN5_RX_DP<80>")
	)
	(segment
		(start 142.371826 -369.996212)
		(end 143.495014 -365.952278)
		(width 0.1651)
		(layer "In5.Cu")
		(net "P5E_PEX1_STN5_RX_DP<80>")
	)
	(segment
		(start 115.910106 -396.49019)
		(end 115.910106 -396.871952)
		(width 0.1651)
		(layer "In5.Cu")
		(net "P5E_PEX1_STN5_RX_DP<80>")
	)
	(segment
		(start 117.851936 -394.127736)
		(end 118.28399 -393.913106)
		(width 0.1651)
		(layer "In5.Cu")
		(net "P5E_PEX1_STN5_RX_DP<80>")
	)
	(segment
		(start 174.184056 -319.883282)
		(end 174.229776 -319.837562)
		(width 0.1143)
		(layer "In5.Cu")
		(net "P5E_PEX1_STN5_RX_DP<80>")
	)
	(segment
		(start 135.67029 -386.845302)
		(end 136.088374 -386.550662)
		(width 0.1651)
		(layer "In5.Cu")
		(net "P5E_PEX1_STN5_RX_DP<80>")
	)
	(segment
		(start 174.229776 -316.455298)
		(end 174.455582 -316.229492)
		(width 0.1143)
		(layer "In5.Cu")
		(net "P5E_PEX1_STN5_RX_DP<80>")
	)
	(segment
		(start 117.244876 -395.272514)
		(end 117.851936 -394.127736)
		(width 0.1651)
		(layer "In5.Cu")
		(net "P5E_PEX1_STN5_RX_DP<80>")
	)
	(segment
		(start 156.562552 -336.484214)
		(end 159.12719 -333.618078)
		(width 0.1651)
		(layer "In5.Cu")
		(net "P5E_PEX1_STN5_RX_DP<80>")
	)
	(segment
		(start 148.75891 -352.067876)
		(end 156.562552 -336.484214)
		(width 0.1651)
		(layer "In5.Cu")
		(net "P5E_PEX1_STN5_RX_DP<80>")
	)
	(segment
		(start 174.184056 -319.91173)
		(end 174.184056 -319.883282)
		(width 0.1143)
		(layer "In5.Cu")
		(net "P5E_PEX1_STN5_RX_DP<80>")
	)
	(segment
		(start 118.76659 -393.548108)
		(end 118.91645 -393.5984)
		(width 0.1651)
		(layer "In5.Cu")
		(net "P5E_PEX1_STN5_RX_DP<80>")
	)
	(segment
		(start 116.6876 -396.322804)
		(end 116.91366 -395.896592)
		(width 0.1651)
		(layer "In5.Cu")
		(net "P5E_PEX1_STN5_RX_DP<80>")
	)
	(segment
		(start 174.685706 -316.229492)
		(end 174.800006 -316.115192)
		(width 0.1143)
		(layer "In5.Cu")
		(net "P5E_PEX1_STN5_RX_DP<80>")
	)
	(segment
		(start 168.698672 -357.46309)
		(end 168.698672 -356.831646)
		(width 0.13462)
		(layer "F.Cu")
		(net "P5E_PEX1_STN7_TX_C_DP<116>")
	)
	(segment
		(start 168.698672 -356.831646)
		(end 168.378632 -356.511606)
		(width 0.13462)
		(layer "F.Cu")
		(net "P5E_PEX1_STN7_TX_C_DP<116>")
	)
	(segment
		(start 168.404032 -357.75773)
		(end 168.698672 -357.46309)
		(width 0.13462)
		(layer "F.Cu")
		(net "P5E_PEX1_STN7_TX_C_DP<116>")
	)
	(segment
		(start 165.530022 -392.401806)
		(end 165.669722 -392.368786)
		(width 0.1651)
		(layer "In11.Cu")
		(net "P5E_PEX1_STN7_TX_C_DP<116>")
	)
	(segment
		(start 155.759912 -385.074668)
		(end 156.739082 -387.496558)
		(width 0.1651)
		(layer "In11.Cu")
		(net "P5E_PEX1_STN7_TX_C_DP<116>")
	)
	(segment
		(start 159.673036 -389.673338)
		(end 163.169346 -390.828022)
		(width 0.1651)
		(layer "In11.Cu")
		(net "P5E_PEX1_STN7_TX_C_DP<116>")
	)
	(segment
		(start 163.169346 -390.828022)
		(end 164.058346 -391.375646)
		(width 0.1651)
		(layer "In11.Cu")
		(net "P5E_PEX1_STN7_TX_C_DP<116>")
	)
	(segment
		(start 168.837102 -400.899122)
		(end 168.710102 -400.772122)
		(width 0.1651)
		(layer "In11.Cu")
		(net "P5E_PEX1_STN7_TX_C_DP<116>")
	)
	(segment
		(start 156.739082 -387.496558)
		(end 159.673036 -389.673338)
		(width 0.1651)
		(layer "In11.Cu")
		(net "P5E_PEX1_STN7_TX_C_DP<116>")
	)
	(segment
		(start 167.10787 -393.254738)
		(end 167.141144 -393.394438)
		(width 0.1651)
		(layer "In11.Cu")
		(net "P5E_PEX1_STN7_TX_C_DP<116>")
	)
	(segment
		(start 169.158666 -394.518388)
		(end 169.15892 -394.518388)
		(width 0.1651)
		(layer "In11.Cu")
		(net "P5E_PEX1_STN7_TX_C_DP<116>")
	)
	(segment
		(start 166.124636 -392.768074)
		(end 166.54653 -393.02817)
		(width 0.1651)
		(layer "In11.Cu")
		(net "P5E_PEX1_STN7_TX_C_DP<116>")
	)
	(segment
		(start 166.89832 -360.45775)
		(end 158.775908 -363.867192)
		(width 0.1651)
		(layer "In11.Cu")
		(net "P5E_PEX1_STN7_TX_C_DP<116>")
	)
	(segment
		(start 156.544772 -366.157002)
		(end 155.709112 -368.367564)
		(width 0.1651)
		(layer "In11.Cu")
		(net "P5E_PEX1_STN7_TX_C_DP<116>")
	)
	(segment
		(start 165.074854 -392.00201)
		(end 165.108128 -392.14171)
		(width 0.1651)
		(layer "In11.Cu")
		(net "P5E_PEX1_STN7_TX_C_DP<116>")
	)
	(segment
		(start 164.058346 -391.375646)
		(end 164.09162 -391.5156)
		(width 0.1651)
		(layer "In11.Cu")
		(net "P5E_PEX1_STN7_TX_C_DP<116>")
	)
	(segment
		(start 166.091362 -392.628374)
		(end 166.124636 -392.768074)
		(width 0.1651)
		(layer "In11.Cu")
		(net "P5E_PEX1_STN7_TX_C_DP<116>")
	)
	(segment
		(start 167.563038 -393.654534)
		(end 167.702738 -393.621514)
		(width 0.1651)
		(layer "In11.Cu")
		(net "P5E_PEX1_STN7_TX_C_DP<116>")
	)
	(segment
		(start 155.709112 -368.367564)
		(end 155.536392 -382.496314)
		(width 0.1651)
		(layer "In11.Cu")
		(net "P5E_PEX1_STN7_TX_C_DP<116>")
	)
	(segment
		(start 165.108128 -392.14171)
		(end 165.530022 -392.401806)
		(width 0.1651)
		(layer "In11.Cu")
		(net "P5E_PEX1_STN7_TX_C_DP<116>")
	)
	(segment
		(start 166.68623 -392.99515)
		(end 167.10787 -393.254738)
		(width 0.1651)
		(layer "In11.Cu")
		(net "P5E_PEX1_STN7_TX_C_DP<116>")
	)
	(segment
		(start 168.579546 -394.280898)
		(end 168.7195 -394.247878)
		(width 0.1651)
		(layer "In11.Cu")
		(net "P5E_PEX1_STN7_TX_C_DP<116>")
	)
	(segment
		(start 169.15892 -394.518388)
		(end 169.59326 -394.952728)
		(width 0.1651)
		(layer "In11.Cu")
		(net "P5E_PEX1_STN7_TX_C_DP<116>")
	)
	(segment
		(start 158.775908 -363.867192)
		(end 156.544772 -366.157002)
		(width 0.1651)
		(layer "In11.Cu")
		(net "P5E_PEX1_STN7_TX_C_DP<116>")
	)
	(segment
		(start 164.09162 -391.5156)
		(end 164.513514 -391.775442)
		(width 0.1651)
		(layer "In11.Cu")
		(net "P5E_PEX1_STN7_TX_C_DP<116>")
	)
	(segment
		(start 164.513514 -391.775442)
		(end 164.653214 -391.742422)
		(width 0.1651)
		(layer "In11.Cu")
		(net "P5E_PEX1_STN7_TX_C_DP<116>")
	)
	(segment
		(start 169.452798 -400.899122)
		(end 168.837102 -400.899122)
		(width 0.1651)
		(layer "In11.Cu")
		(net "P5E_PEX1_STN7_TX_C_DP<116>")
	)
	(segment
		(start 164.653214 -391.742422)
		(end 165.074854 -392.00201)
		(width 0.1651)
		(layer "In11.Cu")
		(net "P5E_PEX1_STN7_TX_C_DP<116>")
	)
	(segment
		(start 168.124378 -393.881102)
		(end 168.157652 -394.020802)
		(width 0.1651)
		(layer "In11.Cu")
		(net "P5E_PEX1_STN7_TX_C_DP<116>")
	)
	(segment
		(start 169.59326 -400.75866)
		(end 169.452798 -400.899122)
		(width 0.1651)
		(layer "In11.Cu")
		(net "P5E_PEX1_STN7_TX_C_DP<116>")
	)
	(segment
		(start 168.7195 -394.247878)
		(end 169.158666 -394.518388)
		(width 0.1651)
		(layer "In11.Cu")
		(net "P5E_PEX1_STN7_TX_C_DP<116>")
	)
	(segment
		(start 167.702738 -393.621514)
		(end 168.124378 -393.881102)
		(width 0.1651)
		(layer "In11.Cu")
		(net "P5E_PEX1_STN7_TX_C_DP<116>")
	)
	(segment
		(start 168.157652 -394.020802)
		(end 168.579546 -394.280898)
		(width 0.1651)
		(layer "In11.Cu")
		(net "P5E_PEX1_STN7_TX_C_DP<116>")
	)
	(segment
		(start 168.710102 -400.772122)
		(end 168.710102 -400.390106)
		(width 0.1651)
		(layer "In11.Cu")
		(net "P5E_PEX1_STN7_TX_C_DP<116>")
	)
	(segment
		(start 168.694862 -358.04856)
		(end 168.694862 -358.661208)
		(width 0.1651)
		(layer "In11.Cu")
		(net "P5E_PEX1_STN7_TX_C_DP<116>")
	)
	(segment
		(start 168.694862 -358.661208)
		(end 166.89832 -360.45775)
		(width 0.1651)
		(layer "In11.Cu")
		(net "P5E_PEX1_STN7_TX_C_DP<116>")
	)
	(segment
		(start 168.404032 -357.75773)
		(end 168.694862 -358.04856)
		(width 0.1651)
		(layer "In11.Cu")
		(net "P5E_PEX1_STN7_TX_C_DP<116>")
	)
	(segment
		(start 169.59326 -394.952728)
		(end 169.59326 -400.75866)
		(width 0.1651)
		(layer "In11.Cu")
		(net "P5E_PEX1_STN7_TX_C_DP<116>")
	)
	(segment
		(start 155.536392 -382.496314)
		(end 155.759912 -385.074668)
		(width 0.1651)
		(layer "In11.Cu")
		(net "P5E_PEX1_STN7_TX_C_DP<116>")
	)
	(segment
		(start 167.141144 -393.394438)
		(end 167.563038 -393.654534)
		(width 0.1651)
		(layer "In11.Cu")
		(net "P5E_PEX1_STN7_TX_C_DP<116>")
	)
	(segment
		(start 166.54653 -393.02817)
		(end 166.68623 -392.99515)
		(width 0.1651)
		(layer "In11.Cu")
		(net "P5E_PEX1_STN7_TX_C_DP<116>")
	)
	(segment
		(start 165.669722 -392.368786)
		(end 166.091362 -392.628374)
		(width 0.1651)
		(layer "In11.Cu")
		(net "P5E_PEX1_STN7_TX_C_DP<116>")
	)
	(segment
		(start 35.171888 -343.365582)
		(end 35.171888 -342.734138)
		(width 0.13462)
		(layer "F.Cu")
		(net "P5E_PEX0_STN7_TX_DP<119>")
	)
	(segment
		(start 35.171888 -342.734138)
		(end 34.877248 -342.439498)
		(width 0.13462)
		(layer "F.Cu")
		(net "P5E_PEX0_STN7_TX_DP<119>")
	)
	(segment
		(start 34.851848 -343.685622)
		(end 35.171888 -343.365582)
		(width 0.13462)
		(layer "F.Cu")
		(net "P5E_PEX0_STN7_TX_DP<119>")
	)
	(segment
		(start 33.316164 -338.143596)
		(end 24.960072 -325.637906)
		(width 0.1651)
		(layer "In7.Cu")
		(net "P5E_PEX0_STN7_TX_DP<119>")
	)
	(segment
		(start 34.74466 -340.665308)
		(end 33.316164 -338.143596)
		(width 0.1651)
		(layer "In7.Cu")
		(net "P5E_PEX0_STN7_TX_DP<119>")
	)
	(segment
		(start 33.78835 -307.994304)
		(end 34.6583 -307.633878)
		(width 0.1651)
		(layer "In7.Cu")
		(net "P5E_PEX0_STN7_TX_DP<119>")
	)
	(segment
		(start 24.994362 -316.788292)
		(end 33.78835 -307.994304)
		(width 0.1651)
		(layer "In7.Cu")
		(net "P5E_PEX0_STN7_TX_DP<119>")
	)
	(segment
		(start 35.168078 -342.148668)
		(end 35.168078 -341.831676)
		(width 0.1651)
		(layer "In7.Cu")
		(net "P5E_PEX0_STN7_TX_DP<119>")
	)
	(segment
		(start 35.658552 -307.633878)
		(end 35.687 -307.633878)
		(width 0.1143)
		(layer "In7.Cu")
		(net "P5E_PEX0_STN7_TX_DP<119>")
	)
	(segment
		(start 34.877248 -342.439498)
		(end 35.168078 -342.148668)
		(width 0.1651)
		(layer "In7.Cu")
		(net "P5E_PEX0_STN7_TX_DP<119>")
	)
	(segment
		(start 23.580344 -320.299588)
		(end 23.832058 -319.033906)
		(width 0.1651)
		(layer "In7.Cu")
		(net "P5E_PEX0_STN7_TX_DP<119>")
	)
	(segment
		(start 24.107648 -318.36868)
		(end 24.107648 -318.368934)
		(width 0.1651)
		(layer "In7.Cu")
		(net "P5E_PEX0_STN7_TX_DP<119>")
	)
	(segment
		(start 24.107648 -318.368934)
		(end 24.382984 -317.704216)
		(width 0.1651)
		(layer "In7.Cu")
		(net "P5E_PEX0_STN7_TX_DP<119>")
	)
	(segment
		(start 35.073336 -341.472012)
		(end 34.74466 -340.665308)
		(width 0.1651)
		(layer "In7.Cu")
		(net "P5E_PEX0_STN7_TX_DP<119>")
	)
	(segment
		(start 44.070016 -308.135528)
		(end 44.184316 -308.249828)
		(width 0.1143)
		(layer "In7.Cu")
		(net "P5E_PEX0_STN7_TX_DP<119>")
	)
	(segment
		(start 35.168078 -341.831676)
		(end 35.073336 -341.472012)
		(width 0.1651)
		(layer "In7.Cu")
		(net "P5E_PEX0_STN7_TX_DP<119>")
	)
	(segment
		(start 34.6583 -307.633878)
		(end 35.658552 -307.633878)
		(width 0.1651)
		(layer "In7.Cu")
		(net "P5E_PEX0_STN7_TX_DP<119>")
	)
	(segment
		(start 44.184316 -308.249828)
		(end 44.449746 -308.249828)
		(width 0.1143)
		(layer "In7.Cu")
		(net "P5E_PEX0_STN7_TX_DP<119>")
	)
	(segment
		(start 24.382984 -317.704216)
		(end 24.994362 -316.788292)
		(width 0.1651)
		(layer "In7.Cu")
		(net "P5E_PEX0_STN7_TX_DP<119>")
	)
	(segment
		(start 44.070016 -307.905404)
		(end 44.070016 -308.135528)
		(width 0.1143)
		(layer "In7.Cu")
		(net "P5E_PEX0_STN7_TX_DP<119>")
	)
	(segment
		(start 23.832058 -319.033906)
		(end 24.107648 -318.36868)
		(width 0.1651)
		(layer "In7.Cu")
		(net "P5E_PEX0_STN7_TX_DP<119>")
	)
	(segment
		(start 23.580344 -322.306696)
		(end 23.580344 -320.299588)
		(width 0.1651)
		(layer "In7.Cu")
		(net "P5E_PEX0_STN7_TX_DP<119>")
	)
	(segment
		(start 35.73272 -307.679598)
		(end 43.84421 -307.679598)
		(width 0.1143)
		(layer "In7.Cu")
		(net "P5E_PEX0_STN7_TX_DP<119>")
	)
	(segment
		(start 35.687 -307.633878)
		(end 35.73272 -307.679598)
		(width 0.1143)
		(layer "In7.Cu")
		(net "P5E_PEX0_STN7_TX_DP<119>")
	)
	(segment
		(start 43.84421 -307.679598)
		(end 44.070016 -307.905404)
		(width 0.1143)
		(layer "In7.Cu")
		(net "P5E_PEX0_STN7_TX_DP<119>")
	)
	(segment
		(start 24.960072 -325.637906)
		(end 23.580344 -322.306696)
		(width 0.1651)
		(layer "In7.Cu")
		(net "P5E_PEX0_STN7_TX_DP<119>")
	)
	(segment
		(start 199.979534 -124.671074)
		(end 200.274174 -124.965714)
		(width 0.13462)
		(layer "F.Cu")
		(net "P5E_PEX1_STN0_TX_DP<3>")
	)
	(segment
		(start 199.34809 -124.671074)
		(end 199.979534 -124.671074)
		(width 0.13462)
		(layer "F.Cu")
		(net "P5E_PEX1_STN0_TX_DP<3>")
	)
	(segment
		(start 199.02805 -124.991114)
		(end 199.34809 -124.671074)
		(width 0.13462)
		(layer "F.Cu")
		(net "P5E_PEX1_STN0_TX_DP<3>")
	)
	(segment
		(start 191.329564 -285.09468)
		(end 191.329564 -285.335472)
		(width 0.1143)
		(layer "In9.Cu")
		(net "P5E_PEX1_STN0_TX_DP<3>")
	)
	(segment
		(start 202.805538 -129.102358)
		(end 202.805792 -129.102358)
		(width 0.1651)
		(layer "In9.Cu")
		(net "P5E_PEX1_STN0_TX_DP<3>")
	)
	(segment
		(start 205.55331 -135.001762)
		(end 213.086442 -153.18867)
		(width 0.1651)
		(layer "In9.Cu")
		(net "P5E_PEX1_STN0_TX_DP<3>")
	)
	(segment
		(start 202.371198 -128.072388)
		(end 202.371452 -128.072388)
		(width 0.1651)
		(layer "In9.Cu")
		(net "P5E_PEX1_STN0_TX_DP<3>")
	)
	(segment
		(start 202.627992 -128.681226)
		(end 202.805538 -129.102358)
		(width 0.1651)
		(layer "In9.Cu")
		(net "P5E_PEX1_STN0_TX_DP<3>")
	)
	(segment
		(start 203.363322 -130.687318)
		(end 203.496672 -130.74142)
		(width 0.1651)
		(layer "In9.Cu")
		(net "P5E_PEX1_STN0_TX_DP<3>")
	)
	(segment
		(start 201.276712 -284.833568)
		(end 199.993758 -284.833568)
		(width 0.1651)
		(layer "In9.Cu")
		(net "P5E_PEX1_STN0_TX_DP<3>")
	)
	(segment
		(start 203.496672 -130.74142)
		(end 203.674218 -131.162552)
		(width 0.1651)
		(layer "In9.Cu")
		(net "P5E_PEX1_STN0_TX_DP<3>")
	)
	(segment
		(start 203.931012 -131.77139)
		(end 204.215238 -132.44576)
		(width 0.1651)
		(layer "In9.Cu")
		(net "P5E_PEX1_STN0_TX_DP<3>")
	)
	(segment
		(start 204.817726 -133.491224)
		(end 204.992732 -133.91388)
		(width 0.1651)
		(layer "In9.Cu")
		(net "P5E_PEX1_STN0_TX_DP<3>")
	)
	(segment
		(start 204.692504 -132.92328)
		(end 204.87259 -133.358636)
		(width 0.1651)
		(layer "In9.Cu")
		(net "P5E_PEX1_STN0_TX_DP<3>")
	)
	(segment
		(start 201.937112 -127.042418)
		(end 201.88301 -127.175514)
		(width 0.1651)
		(layer "In9.Cu")
		(net "P5E_PEX1_STN0_TX_DP<3>")
	)
	(segment
		(start 201.49947 -125.312932)
		(end 201.759566 -126.621286)
		(width 0.1651)
		(layer "In9.Cu")
		(net "P5E_PEX1_STN0_TX_DP<3>")
	)
	(segment
		(start 201.323448 -124.887736)
		(end 201.49947 -125.312932)
		(width 0.1651)
		(layer "In9.Cu")
		(net "P5E_PEX1_STN0_TX_DP<3>")
	)
	(segment
		(start 201.110596 -124.674884)
		(end 201.323448 -124.887736)
		(width 0.1651)
		(layer "In9.Cu")
		(net "P5E_PEX1_STN0_TX_DP<3>")
	)
	(segment
		(start 202.805792 -129.102358)
		(end 202.75169 -129.235454)
		(width 0.1651)
		(layer "In9.Cu")
		(net "P5E_PEX1_STN0_TX_DP<3>")
	)
	(segment
		(start 203.239878 -130.132582)
		(end 203.185776 -130.265678)
		(width 0.1651)
		(layer "In9.Cu")
		(net "P5E_PEX1_STN0_TX_DP<3>")
	)
	(segment
		(start 212.348826 -265.879326)
		(end 213.225634 -267.996162)
		(width 0.1651)
		(layer "In9.Cu")
		(net "P5E_PEX1_STN0_TX_DP<3>")
	)
	(segment
		(start 200.274174 -124.965714)
		(end 200.565004 -124.674884)
		(width 0.1651)
		(layer "In9.Cu")
		(net "P5E_PEX1_STN0_TX_DP<3>")
	)
	(segment
		(start 202.193652 -127.651256)
		(end 202.371198 -128.072388)
		(width 0.1651)
		(layer "In9.Cu")
		(net "P5E_PEX1_STN0_TX_DP<3>")
	)
	(segment
		(start 213.225634 -267.996162)
		(end 213.596728 -272.258028)
		(width 0.1651)
		(layer "In9.Cu")
		(net "P5E_PEX1_STN0_TX_DP<3>")
	)
	(segment
		(start 191.544956 -284.879288)
		(end 191.329564 -285.09468)
		(width 0.1143)
		(layer "In9.Cu")
		(net "P5E_PEX1_STN0_TX_DP<3>")
	)
	(segment
		(start 203.293472 -178.781202)
		(end 199.544178 -221.628208)
		(width 0.1651)
		(layer "In9.Cu")
		(net "P5E_PEX1_STN0_TX_DP<3>")
	)
	(segment
		(start 205.125574 -133.968998)
		(end 205.300326 -134.391146)
		(width 0.1651)
		(layer "In9.Cu")
		(net "P5E_PEX1_STN0_TX_DP<3>")
	)
	(segment
		(start 202.75169 -129.235454)
		(end 202.929236 -129.657094)
		(width 0.1651)
		(layer "In9.Cu")
		(net "P5E_PEX1_STN0_TX_DP<3>")
	)
	(segment
		(start 202.060556 -127.597154)
		(end 202.193906 -127.651256)
		(width 0.1651)
		(layer "In9.Cu")
		(net "P5E_PEX1_STN0_TX_DP<3>")
	)
	(segment
		(start 199.544178 -221.628208)
		(end 202.063604 -250.487688)
		(width 0.1651)
		(layer "In9.Cu")
		(net "P5E_PEX1_STN0_TX_DP<3>")
	)
	(segment
		(start 204.215238 -132.44576)
		(end 204.692504 -132.92328)
		(width 0.1651)
		(layer "In9.Cu")
		(net "P5E_PEX1_STN0_TX_DP<3>")
	)
	(segment
		(start 191.215264 -285.449772)
		(end 190.949834 -285.449772)
		(width 0.1143)
		(layer "In9.Cu")
		(net "P5E_PEX1_STN0_TX_DP<3>")
	)
	(segment
		(start 203.712826 -283.824426)
		(end 201.276712 -284.833568)
		(width 0.1651)
		(layer "In9.Cu")
		(net "P5E_PEX1_STN0_TX_DP<3>")
	)
	(segment
		(start 203.062586 -129.711196)
		(end 203.062332 -129.71145)
		(width 0.1651)
		(layer "In9.Cu")
		(net "P5E_PEX1_STN0_TX_DP<3>")
	)
	(segment
		(start 202.371452 -128.072388)
		(end 202.31735 -128.205484)
		(width 0.1651)
		(layer "In9.Cu")
		(net "P5E_PEX1_STN0_TX_DP<3>")
	)
	(segment
		(start 203.674218 -131.162552)
		(end 203.620116 -131.295648)
		(width 0.1651)
		(layer "In9.Cu")
		(net "P5E_PEX1_STN0_TX_DP<3>")
	)
	(segment
		(start 202.193906 -127.651256)
		(end 202.193652 -127.651256)
		(width 0.1651)
		(layer "In9.Cu")
		(net "P5E_PEX1_STN0_TX_DP<3>")
	)
	(segment
		(start 213.596728 -272.258028)
		(end 212.407246 -275.130006)
		(width 0.1651)
		(layer "In9.Cu")
		(net "P5E_PEX1_STN0_TX_DP<3>")
	)
	(segment
		(start 203.620116 -131.295648)
		(end 203.797662 -131.717288)
		(width 0.1651)
		(layer "In9.Cu")
		(net "P5E_PEX1_STN0_TX_DP<3>")
	)
	(segment
		(start 205.245462 -134.523988)
		(end 205.420468 -134.946644)
		(width 0.1651)
		(layer "In9.Cu")
		(net "P5E_PEX1_STN0_TX_DP<3>")
	)
	(segment
		(start 199.993758 -284.833568)
		(end 199.96531 -284.833568)
		(width 0.1143)
		(layer "In9.Cu")
		(net "P5E_PEX1_STN0_TX_DP<3>")
	)
	(segment
		(start 202.31735 -128.205484)
		(end 202.494896 -128.627124)
		(width 0.1651)
		(layer "In9.Cu")
		(net "P5E_PEX1_STN0_TX_DP<3>")
	)
	(segment
		(start 205.300326 -134.391146)
		(end 205.245462 -134.523988)
		(width 0.1651)
		(layer "In9.Cu")
		(net "P5E_PEX1_STN0_TX_DP<3>")
	)
	(segment
		(start 213.086442 -159.546544)
		(end 212.952584 -160.047178)
		(width 0.1651)
		(layer "In9.Cu")
		(net "P5E_PEX1_STN0_TX_DP<3>")
	)
	(segment
		(start 204.294486 -175.049942)
		(end 203.293472 -178.781202)
		(width 0.1651)
		(layer "In9.Cu")
		(net "P5E_PEX1_STN0_TX_DP<3>")
	)
	(segment
		(start 203.185776 -130.265678)
		(end 203.363322 -130.687318)
		(width 0.1651)
		(layer "In9.Cu")
		(net "P5E_PEX1_STN0_TX_DP<3>")
	)
	(segment
		(start 204.87259 -133.358636)
		(end 204.817726 -133.491224)
		(width 0.1651)
		(layer "In9.Cu")
		(net "P5E_PEX1_STN0_TX_DP<3>")
	)
	(segment
		(start 205.420468 -134.946644)
		(end 205.55331 -135.001762)
		(width 0.1651)
		(layer "In9.Cu")
		(net "P5E_PEX1_STN0_TX_DP<3>")
	)
	(segment
		(start 204.992732 -133.91388)
		(end 205.125574 -133.968998)
		(width 0.1651)
		(layer "In9.Cu")
		(net "P5E_PEX1_STN0_TX_DP<3>")
	)
	(segment
		(start 203.062332 -129.71145)
		(end 203.239878 -130.132582)
		(width 0.1651)
		(layer "In9.Cu")
		(net "P5E_PEX1_STN0_TX_DP<3>")
	)
	(segment
		(start 213.086442 -153.18867)
		(end 213.086442 -159.546544)
		(width 0.1651)
		(layer "In9.Cu")
		(net "P5E_PEX1_STN0_TX_DP<3>")
	)
	(segment
		(start 199.91959 -284.879288)
		(end 191.544956 -284.879288)
		(width 0.1143)
		(layer "In9.Cu")
		(net "P5E_PEX1_STN0_TX_DP<3>")
	)
	(segment
		(start 202.494896 -128.627124)
		(end 202.628246 -128.681226)
		(width 0.1651)
		(layer "In9.Cu")
		(net "P5E_PEX1_STN0_TX_DP<3>")
	)
	(segment
		(start 202.063604 -250.487688)
		(end 212.348826 -265.879326)
		(width 0.1651)
		(layer "In9.Cu")
		(net "P5E_PEX1_STN0_TX_DP<3>")
	)
	(segment
		(start 203.797662 -131.717288)
		(end 203.931012 -131.77139)
		(width 0.1651)
		(layer "In9.Cu")
		(net "P5E_PEX1_STN0_TX_DP<3>")
	)
	(segment
		(start 212.952584 -160.047178)
		(end 204.294486 -175.049942)
		(width 0.1651)
		(layer "In9.Cu")
		(net "P5E_PEX1_STN0_TX_DP<3>")
	)
	(segment
		(start 212.407246 -275.130006)
		(end 203.712826 -283.824426)
		(width 0.1651)
		(layer "In9.Cu")
		(net "P5E_PEX1_STN0_TX_DP<3>")
	)
	(segment
		(start 202.628246 -128.681226)
		(end 202.627992 -128.681226)
		(width 0.1651)
		(layer "In9.Cu")
		(net "P5E_PEX1_STN0_TX_DP<3>")
	)
	(segment
		(start 200.565004 -124.674884)
		(end 201.110596 -124.674884)
		(width 0.1651)
		(layer "In9.Cu")
		(net "P5E_PEX1_STN0_TX_DP<3>")
	)
	(segment
		(start 202.929236 -129.657094)
		(end 203.062586 -129.711196)
		(width 0.1651)
		(layer "In9.Cu")
		(net "P5E_PEX1_STN0_TX_DP<3>")
	)
	(segment
		(start 201.759566 -126.621286)
		(end 201.937112 -127.042418)
		(width 0.1651)
		(layer "In9.Cu")
		(net "P5E_PEX1_STN0_TX_DP<3>")
	)
	(segment
		(start 201.88301 -127.175514)
		(end 202.060556 -127.597154)
		(width 0.1651)
		(layer "In9.Cu")
		(net "P5E_PEX1_STN0_TX_DP<3>")
	)
	(segment
		(start 191.329564 -285.335472)
		(end 191.215264 -285.449772)
		(width 0.1143)
		(layer "In9.Cu")
		(net "P5E_PEX1_STN0_TX_DP<3>")
	)
	(segment
		(start 199.96531 -284.833568)
		(end 199.91959 -284.879288)
		(width 0.1143)
		(layer "In9.Cu")
		(net "P5E_PEX1_STN0_TX_DP<3>")
	)
	(segment
		(start 127.975868 -349.511874)
		(end 127.975868 -348.88043)
		(width 0.13462)
		(layer "F.Cu")
		(net "P5E_PEX1_STN6_TX_DN<104>")
	)
	(segment
		(start 127.975868 -348.88043)
		(end 128.270508 -348.58579)
		(width 0.13462)
		(layer "F.Cu")
		(net "P5E_PEX1_STN6_TX_DN<104>")
	)
	(segment
		(start 128.295908 -349.831914)
		(end 127.975868 -349.511874)
		(width 0.13462)
		(layer "F.Cu")
		(net "P5E_PEX1_STN6_TX_DN<104>")
	)
	(segment
		(start 166.249858 -313.684412)
		(end 166.135558 -313.570112)
		(width 0.1143)
		(layer "In13.Cu")
		(net "P5E_PEX1_STN6_TX_DN<104>")
	)
	(segment
		(start 165.915848 -323.224144)
		(end 162.553396 -326.586596)
		(width 0.1651)
		(layer "In13.Cu")
		(net "P5E_PEX1_STN6_TX_DN<104>")
	)
	(segment
		(start 166.249858 -313.949842)
		(end 166.249858 -313.684412)
		(width 0.1143)
		(layer "In13.Cu")
		(net "P5E_PEX1_STN6_TX_DN<104>")
	)
	(segment
		(start 129.534158 -340.61273)
		(end 129.534158 -346.103702)
		(width 0.1651)
		(layer "In13.Cu")
		(net "P5E_PEX1_STN6_TX_DN<104>")
	)
	(segment
		(start 165.915848 -320.041016)
		(end 165.915848 -320.063114)
		(width 0.1143)
		(layer "In13.Cu")
		(net "P5E_PEX1_STN6_TX_DN<104>")
	)
	(segment
		(start 127.979678 -348.29496)
		(end 128.270508 -348.58579)
		(width 0.1651)
		(layer "In13.Cu")
		(net "P5E_PEX1_STN6_TX_DN<104>")
	)
	(segment
		(start 165.870128 -319.995296)
		(end 165.915848 -320.041016)
		(width 0.1143)
		(layer "In13.Cu")
		(net "P5E_PEX1_STN6_TX_DN<104>")
	)
	(segment
		(start 165.870128 -313.673744)
		(end 165.870128 -319.995296)
		(width 0.1143)
		(layer "In13.Cu")
		(net "P5E_PEX1_STN6_TX_DN<104>")
	)
	(segment
		(start 145.966688 -333.567278)
		(end 142.036292 -333.567278)
		(width 0.1651)
		(layer "In13.Cu")
		(net "P5E_PEX1_STN6_TX_DN<104>")
	)
	(segment
		(start 142.036292 -333.567278)
		(end 132.72135 -337.425538)
		(width 0.1651)
		(layer "In13.Cu")
		(net "P5E_PEX1_STN6_TX_DN<104>")
	)
	(segment
		(start 158.455614 -329.043284)
		(end 148.975064 -332.970124)
		(width 0.1651)
		(layer "In13.Cu")
		(net "P5E_PEX1_STN6_TX_DN<104>")
	)
	(segment
		(start 129.534158 -346.103702)
		(end 127.979678 -347.658182)
		(width 0.1651)
		(layer "In13.Cu")
		(net "P5E_PEX1_STN6_TX_DN<104>")
	)
	(segment
		(start 165.915848 -320.063114)
		(end 165.915848 -323.224144)
		(width 0.1651)
		(layer "In13.Cu")
		(net "P5E_PEX1_STN6_TX_DN<104>")
	)
	(segment
		(start 166.135558 -313.570112)
		(end 165.97376 -313.570112)
		(width 0.1143)
		(layer "In13.Cu")
		(net "P5E_PEX1_STN6_TX_DN<104>")
	)
	(segment
		(start 132.72135 -337.425538)
		(end 129.534158 -340.61273)
		(width 0.1651)
		(layer "In13.Cu")
		(net "P5E_PEX1_STN6_TX_DN<104>")
	)
	(segment
		(start 162.553396 -326.586596)
		(end 158.455614 -329.043284)
		(width 0.1651)
		(layer "In13.Cu")
		(net "P5E_PEX1_STN6_TX_DN<104>")
	)
	(segment
		(start 127.979678 -347.658182)
		(end 127.979678 -348.29496)
		(width 0.1651)
		(layer "In13.Cu")
		(net "P5E_PEX1_STN6_TX_DN<104>")
	)
	(segment
		(start 165.97376 -313.570112)
		(end 165.870128 -313.673744)
		(width 0.1143)
		(layer "In13.Cu")
		(net "P5E_PEX1_STN6_TX_DN<104>")
	)
	(segment
		(start 148.975064 -332.970124)
		(end 145.966688 -333.567278)
		(width 0.1651)
		(layer "In13.Cu")
		(net "P5E_PEX1_STN6_TX_DN<104>")
	)
	(segment
		(start 173.508162 -324.954646)
		(end 174.465996 -322.645024)
		(width 0.1651)
		(layer "In5.Cu")
		(net "P5E_PEX1_STN5_RX_DN<80>")
	)
	(segment
		(start 116.586762 -397.281146)
		(end 116.96954 -396.898368)
		(width 0.1651)
		(layer "In5.Cu")
		(net "P5E_PEX1_STN5_RX_DN<80>")
	)
	(segment
		(start 116.96954 -396.393162)
		(end 118.058692 -394.34008)
		(width 0.1651)
		(layer "In5.Cu")
		(net "P5E_PEX1_STN5_RX_DN<80>")
	)
	(segment
		(start 128.079246 -389.35914)
		(end 131.81457 -387.901434)
		(width 0.1651)
		(layer "In5.Cu")
		(net "P5E_PEX1_STN5_RX_DN<80>")
	)
	(segment
		(start 174.685706 -316.419992)
		(end 174.800006 -316.534292)
		(width 0.1143)
		(layer "In5.Cu")
		(net "P5E_PEX1_STN5_RX_DN<80>")
	)
	(segment
		(start 115.910106 -397.790162)
		(end 115.910106 -397.408146)
		(width 0.1651)
		(layer "In5.Cu")
		(net "P5E_PEX1_STN5_RX_DN<80>")
	)
	(segment
		(start 174.420276 -319.837562)
		(end 174.420276 -316.534292)
		(width 0.1143)
		(layer "In5.Cu")
		(net "P5E_PEX1_STN5_RX_DN<80>")
	)
	(segment
		(start 116.96954 -396.898368)
		(end 116.96954 -396.393162)
		(width 0.1651)
		(layer "In5.Cu")
		(net "P5E_PEX1_STN5_RX_DN<80>")
	)
	(segment
		(start 131.81457 -387.901434)
		(end 135.784082 -387.110478)
		(width 0.1651)
		(layer "In5.Cu")
		(net "P5E_PEX1_STN5_RX_DN<80>")
	)
	(segment
		(start 116.037106 -397.281146)
		(end 116.586762 -397.281146)
		(width 0.1651)
		(layer "In5.Cu")
		(net "P5E_PEX1_STN5_RX_DN<80>")
	)
	(segment
		(start 136.564878 -386.321554)
		(end 142.635986 -370.094764)
		(width 0.1651)
		(layer "In5.Cu")
		(net "P5E_PEX1_STN5_RX_DN<80>")
	)
	(segment
		(start 143.763238 -366.040162)
		(end 149.017736 -352.181414)
		(width 0.1651)
		(layer "In5.Cu")
		(net "P5E_PEX1_STN5_RX_DN<80>")
	)
	(segment
		(start 174.465996 -322.645024)
		(end 174.465996 -319.91173)
		(width 0.1651)
		(layer "In5.Cu")
		(net "P5E_PEX1_STN5_RX_DN<80>")
	)
	(segment
		(start 118.058692 -394.34008)
		(end 128.079246 -389.35914)
		(width 0.1651)
		(layer "In5.Cu")
		(net "P5E_PEX1_STN5_RX_DN<80>")
	)
	(segment
		(start 135.784082 -387.110478)
		(end 136.297416 -386.748528)
		(width 0.1651)
		(layer "In5.Cu")
		(net "P5E_PEX1_STN5_RX_DN<80>")
	)
	(segment
		(start 174.465996 -319.91173)
		(end 174.465996 -319.883282)
		(width 0.1143)
		(layer "In5.Cu")
		(net "P5E_PEX1_STN5_RX_DN<80>")
	)
	(segment
		(start 142.643606 -370.07165)
		(end 143.202914 -368.057938)
		(width 0.1651)
		(layer "In5.Cu")
		(net "P5E_PEX1_STN5_RX_DN<80>")
	)
	(segment
		(start 174.465996 -319.883282)
		(end 174.420276 -319.837562)
		(width 0.1143)
		(layer "In5.Cu")
		(net "P5E_PEX1_STN5_RX_DN<80>")
	)
	(segment
		(start 115.910106 -397.408146)
		(end 116.037106 -397.281146)
		(width 0.1651)
		(layer "In5.Cu")
		(net "P5E_PEX1_STN5_RX_DN<80>")
	)
	(segment
		(start 174.420276 -316.534292)
		(end 174.534576 -316.419992)
		(width 0.1143)
		(layer "In5.Cu")
		(net "P5E_PEX1_STN5_RX_DN<80>")
	)
	(segment
		(start 142.635986 -370.094764)
		(end 142.63878 -370.087906)
		(width 0.1651)
		(layer "In5.Cu")
		(net "P5E_PEX1_STN5_RX_DN<80>")
	)
	(segment
		(start 136.297416 -386.748528)
		(end 136.564878 -386.321554)
		(width 0.1651)
		(layer "In5.Cu")
		(net "P5E_PEX1_STN5_RX_DN<80>")
	)
	(segment
		(start 143.202914 -368.057684)
		(end 143.763238 -366.040162)
		(width 0.1651)
		(layer "In5.Cu")
		(net "P5E_PEX1_STN5_RX_DN<80>")
	)
	(segment
		(start 143.202914 -368.057938)
		(end 143.202914 -368.057684)
		(width 0.1651)
		(layer "In5.Cu")
		(net "P5E_PEX1_STN5_RX_DN<80>")
	)
	(segment
		(start 174.800006 -316.534292)
		(end 174.800006 -316.799722)
		(width 0.1143)
		(layer "In5.Cu")
		(net "P5E_PEX1_STN5_RX_DN<80>")
	)
	(segment
		(start 174.534576 -316.419992)
		(end 174.685706 -316.419992)
		(width 0.1143)
		(layer "In5.Cu")
		(net "P5E_PEX1_STN5_RX_DN<80>")
	)
	(segment
		(start 142.63878 -370.087906)
		(end 142.643606 -370.07165)
		(width 0.1651)
		(layer "In5.Cu")
		(net "P5E_PEX1_STN5_RX_DN<80>")
	)
	(segment
		(start 149.017736 -352.181414)
		(end 156.797756 -336.644234)
		(width 0.1651)
		(layer "In5.Cu")
		(net "P5E_PEX1_STN5_RX_DN<80>")
	)
	(segment
		(start 156.797756 -336.644234)
		(end 159.308292 -333.83855)
		(width 0.1651)
		(layer "In5.Cu")
		(net "P5E_PEX1_STN5_RX_DN<80>")
	)
	(segment
		(start 159.308292 -333.83855)
		(end 172.306996 -326.155812)
		(width 0.1651)
		(layer "In5.Cu")
		(net "P5E_PEX1_STN5_RX_DN<80>")
	)
	(segment
		(start 172.306996 -326.155812)
		(end 173.508162 -324.954646)
		(width 0.1651)
		(layer "In5.Cu")
		(net "P5E_PEX1_STN5_RX_DN<80>")
	)
	(segment
		(start 47.882048 -355.026722)
		(end 48.176688 -354.732082)
		(width 0.13462)
		(layer "F.Cu")
		(net "P5E_PEX0_STN7_TX_DN<126>")
	)
	(segment
		(start 47.882048 -355.658166)
		(end 47.882048 -355.026722)
		(width 0.13462)
		(layer "F.Cu")
		(net "P5E_PEX0_STN7_TX_DN<126>")
	)
	(segment
		(start 48.202088 -355.978206)
		(end 47.882048 -355.658166)
		(width 0.13462)
		(layer "F.Cu")
		(net "P5E_PEX0_STN7_TX_DN<126>")
	)
	(segment
		(start 41.65219 -322.829936)
		(end 41.65219 -322.829682)
		(width 0.1651)
		(layer "In7.Cu")
		(net "P5E_PEX0_STN7_TX_DN<126>")
	)
	(segment
		(start 41.260776 -319.916048)
		(end 41.265856 -319.910968)
		(width 0.1143)
		(layer "In7.Cu")
		(net "P5E_PEX0_STN7_TX_DN<126>")
	)
	(segment
		(start 41.485566 -311.670192)
		(end 41.599866 -311.784492)
		(width 0.1143)
		(layer "In7.Cu")
		(net "P5E_PEX0_STN7_TX_DN<126>")
	)
	(segment
		(start 41.599866 -311.784492)
		(end 41.599866 -312.049922)
		(width 0.1143)
		(layer "In7.Cu")
		(net "P5E_PEX0_STN7_TX_DN<126>")
	)
	(segment
		(start 49.440338 -341.97798)
		(end 48.845978 -339.331046)
		(width 0.1651)
		(layer "In7.Cu")
		(net "P5E_PEX0_STN7_TX_DN<126>")
	)
	(segment
		(start 41.265856 -319.8876)
		(end 41.220136 -319.84188)
		(width 0.1143)
		(layer "In7.Cu")
		(net "P5E_PEX0_STN7_TX_DN<126>")
	)
	(segment
		(start 41.334436 -311.670192)
		(end 41.485566 -311.670192)
		(width 0.1143)
		(layer "In7.Cu")
		(net "P5E_PEX0_STN7_TX_DN<126>")
	)
	(segment
		(start 48.176688 -354.732082)
		(end 47.885858 -354.441252)
		(width 0.1651)
		(layer "In7.Cu")
		(net "P5E_PEX0_STN7_TX_DN<126>")
	)
	(segment
		(start 47.885858 -354.441252)
		(end 47.885858 -353.942142)
		(width 0.1651)
		(layer "In7.Cu")
		(net "P5E_PEX0_STN7_TX_DN<126>")
	)
	(segment
		(start 41.65219 -322.829682)
		(end 41.260776 -322.002404)
		(width 0.1651)
		(layer "In7.Cu")
		(net "P5E_PEX0_STN7_TX_DN<126>")
	)
	(segment
		(start 41.220136 -319.84188)
		(end 41.220136 -311.784492)
		(width 0.1143)
		(layer "In7.Cu")
		(net "P5E_PEX0_STN7_TX_DN<126>")
	)
	(segment
		(start 41.220136 -311.784492)
		(end 41.334436 -311.670192)
		(width 0.1143)
		(layer "In7.Cu")
		(net "P5E_PEX0_STN7_TX_DN<126>")
	)
	(segment
		(start 47.216314 -334.594708)
		(end 41.753028 -323.043296)
		(width 0.1651)
		(layer "In7.Cu")
		(net "P5E_PEX0_STN7_TX_DN<126>")
	)
	(segment
		(start 41.260776 -322.002404)
		(end 41.260776 -319.916048)
		(width 0.1651)
		(layer "In7.Cu")
		(net "P5E_PEX0_STN7_TX_DN<126>")
	)
	(segment
		(start 48.845978 -339.331046)
		(end 47.216314 -334.594708)
		(width 0.1651)
		(layer "In7.Cu")
		(net "P5E_PEX0_STN7_TX_DN<126>")
	)
	(segment
		(start 41.265856 -319.910968)
		(end 41.265856 -319.8876)
		(width 0.1143)
		(layer "In7.Cu")
		(net "P5E_PEX0_STN7_TX_DN<126>")
	)
	(segment
		(start 41.753028 -323.043296)
		(end 41.65219 -322.829936)
		(width 0.1651)
		(layer "In7.Cu")
		(net "P5E_PEX0_STN7_TX_DN<126>")
	)
	(segment
		(start 47.885858 -353.942142)
		(end 49.440338 -352.387662)
		(width 0.1651)
		(layer "In7.Cu")
		(net "P5E_PEX0_STN7_TX_DN<126>")
	)
	(segment
		(start 49.440338 -352.387662)
		(end 49.440338 -341.97798)
		(width 0.1651)
		(layer "In7.Cu")
		(net "P5E_PEX0_STN7_TX_DN<126>")
	)
	(segment
		(start 199.34809 -155.791154)
		(end 199.979534 -155.791154)
		(width 0.13462)
		(layer "F.Cu")
		(net "P5E_PEX1_STN0_TX_DP<15>")
	)
	(segment
		(start 199.02805 -156.111194)
		(end 199.34809 -155.791154)
		(width 0.13462)
		(layer "F.Cu")
		(net "P5E_PEX1_STN0_TX_DP<15>")
	)
	(segment
		(start 199.979534 -155.791154)
		(end 200.274174 -156.085794)
		(width 0.13462)
		(layer "F.Cu")
		(net "P5E_PEX1_STN0_TX_DP<15>")
	)
	(segment
		(start 190.379858 -271.546066)
		(end 190.379858 -278.205184)
		(width 0.1143)
		(layer "In9.Cu")
		(net "P5E_PEX1_STN0_TX_DP<15>")
	)
	(segment
		(start 191.490854 -176.846738)
		(end 191.491108 -176.846738)
		(width 0.1651)
		(layer "In9.Cu")
		(net "P5E_PEX1_STN0_TX_DP<15>")
	)
	(segment
		(start 200.631298 -157.77972)
		(end 200.66381 -157.901132)
		(width 0.1651)
		(layer "In9.Cu")
		(net "P5E_PEX1_STN0_TX_DP<15>")
	)
	(segment
		(start 193.011552 -171.156122)
		(end 191.49314 -176.821846)
		(width 0.1651)
		(layer "In9.Cu")
		(net "P5E_PEX1_STN0_TX_DP<15>")
	)
	(segment
		(start 200.294748 -158.362396)
		(end 200.046844 -158.791656)
		(width 0.1651)
		(layer "In9.Cu")
		(net "P5E_PEX1_STN0_TX_DP<15>")
	)
	(segment
		(start 201.174096 -155.794964)
		(end 201.47534 -156.096208)
		(width 0.1651)
		(layer "In9.Cu")
		(net "P5E_PEX1_STN0_TX_DP<15>")
	)
	(segment
		(start 190.594742 -278.420068)
		(end 190.835534 -278.420068)
		(width 0.1143)
		(layer "In9.Cu")
		(net "P5E_PEX1_STN0_TX_DP<15>")
	)
	(segment
		(start 200.66381 -157.901132)
		(end 200.416414 -158.329884)
		(width 0.1651)
		(layer "In9.Cu")
		(net "P5E_PEX1_STN0_TX_DP<15>")
	)
	(segment
		(start 201.47534 -156.096208)
		(end 201.47534 -156.49575)
		(width 0.1651)
		(layer "In9.Cu")
		(net "P5E_PEX1_STN0_TX_DP<15>")
	)
	(segment
		(start 190.334138 -271.471898)
		(end 190.334138 -271.500346)
		(width 0.1143)
		(layer "In9.Cu")
		(net "P5E_PEX1_STN0_TX_DP<15>")
	)
	(segment
		(start 200.274174 -156.085794)
		(end 200.565004 -155.794964)
		(width 0.1651)
		(layer "In9.Cu")
		(net "P5E_PEX1_STN0_TX_DP<15>")
	)
	(segment
		(start 200.046844 -158.791656)
		(end 200.07961 -158.913068)
		(width 0.1651)
		(layer "In9.Cu")
		(net "P5E_PEX1_STN0_TX_DP<15>")
	)
	(segment
		(start 191.491108 -176.846738)
		(end 187.679838 -220.410278)
		(width 0.1651)
		(layer "In9.Cu")
		(net "P5E_PEX1_STN0_TX_DP<15>")
	)
	(segment
		(start 191.208406 -260.7437)
		(end 191.208406 -267.41755)
		(width 0.1651)
		(layer "In9.Cu")
		(net "P5E_PEX1_STN0_TX_DP<15>")
	)
	(segment
		(start 200.565004 -155.794964)
		(end 201.174096 -155.794964)
		(width 0.1651)
		(layer "In9.Cu")
		(net "P5E_PEX1_STN0_TX_DP<15>")
	)
	(segment
		(start 190.379858 -278.205184)
		(end 190.594742 -278.420068)
		(width 0.1143)
		(layer "In9.Cu")
		(net "P5E_PEX1_STN0_TX_DP<15>")
	)
	(segment
		(start 201.000614 -157.317948)
		(end 200.879202 -157.350714)
		(width 0.1651)
		(layer "In9.Cu")
		(net "P5E_PEX1_STN0_TX_DP<15>")
	)
	(segment
		(start 200.879202 -157.350714)
		(end 200.631298 -157.77972)
		(width 0.1651)
		(layer "In9.Cu")
		(net "P5E_PEX1_STN0_TX_DP<15>")
	)
	(segment
		(start 190.334138 -271.500346)
		(end 190.379858 -271.546066)
		(width 0.1143)
		(layer "In9.Cu")
		(net "P5E_PEX1_STN0_TX_DP<15>")
	)
	(segment
		(start 201.47534 -156.49575)
		(end 201.000614 -157.317948)
		(width 0.1651)
		(layer "In9.Cu")
		(net "P5E_PEX1_STN0_TX_DP<15>")
	)
	(segment
		(start 200.07961 -158.913068)
		(end 193.011552 -171.156122)
		(width 0.1651)
		(layer "In9.Cu")
		(net "P5E_PEX1_STN0_TX_DP<15>")
	)
	(segment
		(start 190.949834 -278.534368)
		(end 190.949834 -278.799798)
		(width 0.1143)
		(layer "In9.Cu")
		(net "P5E_PEX1_STN0_TX_DP<15>")
	)
	(segment
		(start 190.835534 -278.420068)
		(end 190.949834 -278.534368)
		(width 0.1143)
		(layer "In9.Cu")
		(net "P5E_PEX1_STN0_TX_DP<15>")
	)
	(segment
		(start 188.564012 -230.515922)
		(end 191.208406 -260.7437)
		(width 0.1651)
		(layer "In9.Cu")
		(net "P5E_PEX1_STN0_TX_DP<15>")
	)
	(segment
		(start 187.679838 -220.410278)
		(end 188.564012 -230.515922)
		(width 0.1651)
		(layer "In9.Cu")
		(net "P5E_PEX1_STN0_TX_DP<15>")
	)
	(segment
		(start 200.416414 -158.329884)
		(end 200.294748 -158.362396)
		(width 0.1651)
		(layer "In9.Cu")
		(net "P5E_PEX1_STN0_TX_DP<15>")
	)
	(segment
		(start 191.208406 -267.41755)
		(end 190.334138 -269.528798)
		(width 0.1651)
		(layer "In9.Cu")
		(net "P5E_PEX1_STN0_TX_DP<15>")
	)
	(segment
		(start 190.334138 -269.528798)
		(end 190.334138 -271.471898)
		(width 0.1651)
		(layer "In9.Cu")
		(net "P5E_PEX1_STN0_TX_DP<15>")
	)
	(segment
		(start 191.49314 -176.821846)
		(end 191.490854 -176.846738)
		(width 0.1651)
		(layer "In9.Cu")
		(net "P5E_PEX1_STN0_TX_DP<15>")
	)
	(segment
		(start 181.728872 -343.685622)
		(end 181.408832 -343.365582)
		(width 0.13462)
		(layer "F.Cu")
		(net "P5E_PEX1_STN7_TX_DP<121>")
	)
	(segment
		(start 181.408832 -342.734138)
		(end 181.703472 -342.439498)
		(width 0.13462)
		(layer "F.Cu")
		(net "P5E_PEX1_STN7_TX_DP<121>")
	)
	(segment
		(start 181.408832 -343.365582)
		(end 181.408832 -342.734138)
		(width 0.13462)
		(layer "F.Cu")
		(net "P5E_PEX1_STN7_TX_DP<121>")
	)
	(segment
		(start 151.028654 -320.053462)
		(end 151.0284 -320.053462)
		(width 0.1651)
		(layer "In11.Cu")
		(net "P5E_PEX1_STN7_TX_DP<121>")
	)
	(segment
		(start 153.243534 -312.620152)
		(end 153.52014 -312.343546)
		(width 0.1143)
		(layer "In11.Cu")
		(net "P5E_PEX1_STN7_TX_DP<121>")
	)
	(segment
		(start 152.348438 -312.969656)
		(end 152.697942 -312.620152)
		(width 0.1143)
		(layer "In11.Cu")
		(net "P5E_PEX1_STN7_TX_DP<121>")
	)
	(segment
		(start 150.350474 -316.607444)
		(end 151.520652 -313.861704)
		(width 0.1651)
		(layer "In11.Cu")
		(net "P5E_PEX1_STN7_TX_DP<121>")
	)
	(segment
		(start 151.520652 -313.861704)
		(end 152.332944 -313.049412)
		(width 0.1651)
		(layer "In11.Cu")
		(net "P5E_PEX1_STN7_TX_DP<121>")
	)
	(segment
		(start 153.52014 -312.343546)
		(end 153.52014 -312.138822)
		(width 0.1143)
		(layer "In11.Cu")
		(net "P5E_PEX1_STN7_TX_DP<121>")
	)
	(segment
		(start 181.412642 -342.148668)
		(end 181.412642 -341.35187)
		(width 0.1651)
		(layer "In11.Cu")
		(net "P5E_PEX1_STN7_TX_DP<121>")
	)
	(segment
		(start 156.047186 -326.818752)
		(end 151.70658 -322.287392)
		(width 0.1651)
		(layer "In11.Cu")
		(net "P5E_PEX1_STN7_TX_DP<121>")
	)
	(segment
		(start 179.672488 -339.465158)
		(end 172.22089 -335.17078)
		(width 0.1651)
		(layer "In11.Cu")
		(net "P5E_PEX1_STN7_TX_DP<121>")
	)
	(segment
		(start 181.703472 -342.439498)
		(end 181.412642 -342.148668)
		(width 0.1651)
		(layer "In11.Cu")
		(net "P5E_PEX1_STN7_TX_DP<121>")
	)
	(segment
		(start 151.70658 -322.287392)
		(end 151.028654 -320.053462)
		(width 0.1651)
		(layer "In11.Cu")
		(net "P5E_PEX1_STN7_TX_DP<121>")
	)
	(segment
		(start 150.350474 -317.819532)
		(end 150.350474 -316.607444)
		(width 0.1651)
		(layer "In11.Cu")
		(net "P5E_PEX1_STN7_TX_DP<121>")
	)
	(segment
		(start 151.0284 -320.053462)
		(end 150.350474 -317.819532)
		(width 0.1651)
		(layer "In11.Cu")
		(net "P5E_PEX1_STN7_TX_DP<121>")
	)
	(segment
		(start 152.697942 -312.620152)
		(end 153.243534 -312.620152)
		(width 0.1143)
		(layer "In11.Cu")
		(net "P5E_PEX1_STN7_TX_DP<121>")
	)
	(segment
		(start 181.412642 -341.35187)
		(end 179.672488 -339.465158)
		(width 0.1651)
		(layer "In11.Cu")
		(net "P5E_PEX1_STN7_TX_DP<121>")
	)
	(segment
		(start 152.332944 -313.049412)
		(end 152.348438 -313.033918)
		(width 0.1143)
		(layer "In11.Cu")
		(net "P5E_PEX1_STN7_TX_DP<121>")
	)
	(segment
		(start 153.52014 -312.138822)
		(end 153.60904 -312.049922)
		(width 0.1143)
		(layer "In11.Cu")
		(net "P5E_PEX1_STN7_TX_DP<121>")
	)
	(segment
		(start 153.60904 -312.049922)
		(end 153.89987 -312.049922)
		(width 0.1143)
		(layer "In11.Cu")
		(net "P5E_PEX1_STN7_TX_DP<121>")
	)
	(segment
		(start 152.348438 -313.033918)
		(end 152.348438 -312.969656)
		(width 0.1143)
		(layer "In11.Cu")
		(net "P5E_PEX1_STN7_TX_DP<121>")
	)
	(segment
		(start 172.22089 -335.17078)
		(end 156.047186 -326.818752)
		(width 0.1651)
		(layer "In11.Cu")
		(net "P5E_PEX1_STN7_TX_DP<121>")
	)
	(segment
		(start 174.153068 -325.261732)
		(end 175.134016 -322.898262)
		(width 0.1651)
		(layer "In5.Cu")
		(net "P5E_PEX1_STN5_RX_DP<81>")
	)
	(segment
		(start 119.304816 -395.032738)
		(end 119.60225 -394.338048)
		(width 0.1651)
		(layer "In5.Cu")
		(net "P5E_PEX1_STN5_RX_DP<81>")
	)
	(segment
		(start 119.60225 -394.338048)
		(end 128.480058 -389.92556)
		(width 0.1651)
		(layer "In5.Cu")
		(net "P5E_PEX1_STN5_RX_DP<81>")
	)
	(segment
		(start 132.004308 -388.55015)
		(end 136.05637 -387.742684)
		(width 0.1651)
		(layer "In5.Cu")
		(net "P5E_PEX1_STN5_RX_DP<81>")
	)
	(segment
		(start 118.237254 -398.09928)
		(end 118.669816 -398.09928)
		(width 0.1651)
		(layer "In5.Cu")
		(net "P5E_PEX1_STN5_RX_DP<81>")
	)
	(segment
		(start 118.887494 -396.007336)
		(end 119.026432 -395.682724)
		(width 0.1651)
		(layer "In5.Cu")
		(net "P5E_PEX1_STN5_RX_DP<81>")
	)
	(segment
		(start 175.749966 -318.015366)
		(end 175.749966 -317.749936)
		(width 0.1143)
		(layer "In5.Cu")
		(net "P5E_PEX1_STN5_RX_DP<81>")
	)
	(segment
		(start 172.693076 -326.721724)
		(end 174.153068 -325.261732)
		(width 0.1651)
		(layer "In5.Cu")
		(net "P5E_PEX1_STN5_RX_DP<81>")
	)
	(segment
		(start 157.37205 -337.041744)
		(end 159.79521 -334.332834)
		(width 0.1651)
		(layer "In5.Cu")
		(net "P5E_PEX1_STN5_RX_DP<81>")
	)
	(segment
		(start 118.7958 -397.212566)
		(end 118.7958 -396.689834)
		(width 0.1651)
		(layer "In5.Cu")
		(net "P5E_PEX1_STN5_RX_DP<81>")
	)
	(segment
		(start 136.05637 -387.742684)
		(end 136.850882 -387.182868)
		(width 0.1651)
		(layer "In5.Cu")
		(net "P5E_PEX1_STN5_RX_DP<81>")
	)
	(segment
		(start 119.304816 -395.033246)
		(end 119.304816 -395.032738)
		(width 0.1651)
		(layer "In5.Cu")
		(net "P5E_PEX1_STN5_RX_DP<81>")
	)
	(segment
		(start 137.277094 -386.46608)
		(end 140.39723 -378.13234)
		(width 0.1651)
		(layer "In5.Cu")
		(net "P5E_PEX1_STN5_RX_DP<81>")
	)
	(segment
		(start 175.405542 -318.129666)
		(end 175.635666 -318.129666)
		(width 0.1143)
		(layer "In5.Cu")
		(net "P5E_PEX1_STN5_RX_DP<81>")
	)
	(segment
		(start 118.11 -397.972026)
		(end 118.237254 -398.09928)
		(width 0.1651)
		(layer "In5.Cu")
		(net "P5E_PEX1_STN5_RX_DP<81>")
	)
	(segment
		(start 118.977918 -395.561312)
		(end 119.18315 -395.082014)
		(width 0.1651)
		(layer "In5.Cu")
		(net "P5E_PEX1_STN5_RX_DP<81>")
	)
	(segment
		(start 136.850882 -387.182868)
		(end 137.277094 -386.46608)
		(width 0.1651)
		(layer "In5.Cu")
		(net "P5E_PEX1_STN5_RX_DP<81>")
	)
	(segment
		(start 128.480058 -389.92556)
		(end 132.004308 -388.55015)
		(width 0.1651)
		(layer "In5.Cu")
		(net "P5E_PEX1_STN5_RX_DP<81>")
	)
	(segment
		(start 118.11 -397.59001)
		(end 118.11 -397.972026)
		(width 0.1651)
		(layer "In5.Cu")
		(net "P5E_PEX1_STN5_RX_DP<81>")
	)
	(segment
		(start 149.763988 -352.2345)
		(end 157.37205 -337.041744)
		(width 0.1651)
		(layer "In5.Cu")
		(net "P5E_PEX1_STN5_RX_DP<81>")
	)
	(segment
		(start 140.397738 -378.13234)
		(end 143.517112 -369.7986)
		(width 0.1651)
		(layer "In5.Cu")
		(net "P5E_PEX1_STN5_RX_DP<81>")
	)
	(segment
		(start 118.887494 -397.30426)
		(end 118.7958 -397.212566)
		(width 0.1651)
		(layer "In5.Cu")
		(net "P5E_PEX1_STN5_RX_DP<81>")
	)
	(segment
		(start 144.6403 -365.754412)
		(end 149.763988 -352.2345)
		(width 0.1651)
		(layer "In5.Cu")
		(net "P5E_PEX1_STN5_RX_DP<81>")
	)
	(segment
		(start 118.7958 -396.689834)
		(end 118.887494 -396.59814)
		(width 0.1651)
		(layer "In5.Cu")
		(net "P5E_PEX1_STN5_RX_DP<81>")
	)
	(segment
		(start 118.887494 -397.881602)
		(end 118.887494 -397.30426)
		(width 0.1651)
		(layer "In5.Cu")
		(net "P5E_PEX1_STN5_RX_DP<81>")
	)
	(segment
		(start 118.669816 -398.09928)
		(end 118.887494 -397.881602)
		(width 0.1651)
		(layer "In5.Cu")
		(net "P5E_PEX1_STN5_RX_DP<81>")
	)
	(segment
		(start 175.179736 -318.355472)
		(end 175.405542 -318.129666)
		(width 0.1143)
		(layer "In5.Cu")
		(net "P5E_PEX1_STN5_RX_DP<81>")
	)
	(segment
		(start 175.134016 -319.91173)
		(end 175.134016 -319.883282)
		(width 0.1143)
		(layer "In5.Cu")
		(net "P5E_PEX1_STN5_RX_DP<81>")
	)
	(segment
		(start 119.026432 -395.682724)
		(end 118.977918 -395.561312)
		(width 0.1651)
		(layer "In5.Cu")
		(net "P5E_PEX1_STN5_RX_DP<81>")
	)
	(segment
		(start 175.179736 -319.837562)
		(end 175.179736 -318.355472)
		(width 0.1143)
		(layer "In5.Cu")
		(net "P5E_PEX1_STN5_RX_DP<81>")
	)
	(segment
		(start 118.887494 -396.59814)
		(end 118.887494 -396.007336)
		(width 0.1651)
		(layer "In5.Cu")
		(net "P5E_PEX1_STN5_RX_DP<81>")
	)
	(segment
		(start 143.517112 -369.7986)
		(end 144.6403 -365.754412)
		(width 0.1651)
		(layer "In5.Cu")
		(net "P5E_PEX1_STN5_RX_DP<81>")
	)
	(segment
		(start 175.134016 -319.883282)
		(end 175.179736 -319.837562)
		(width 0.1143)
		(layer "In5.Cu")
		(net "P5E_PEX1_STN5_RX_DP<81>")
	)
	(segment
		(start 175.635666 -318.129666)
		(end 175.749966 -318.015366)
		(width 0.1143)
		(layer "In5.Cu")
		(net "P5E_PEX1_STN5_RX_DP<81>")
	)
	(segment
		(start 175.134016 -322.898262)
		(end 175.134016 -319.91173)
		(width 0.1651)
		(layer "In5.Cu")
		(net "P5E_PEX1_STN5_RX_DP<81>")
	)
	(segment
		(start 119.18315 -395.082014)
		(end 119.304816 -395.033246)
		(width 0.1651)
		(layer "In5.Cu")
		(net "P5E_PEX1_STN5_RX_DP<81>")
	)
	(segment
		(start 159.79521 -334.332834)
		(end 172.693076 -326.721724)
		(width 0.1651)
		(layer "In5.Cu")
		(net "P5E_PEX1_STN5_RX_DP<81>")
	)
	(segment
		(start 140.39723 -378.13234)
		(end 140.397738 -378.13234)
		(width 0.1651)
		(layer "In5.Cu")
		(net "P5E_PEX1_STN5_RX_DP<81>")
	)
	(segment
		(start 61.941202 -350.685354)
		(end 62.261242 -350.365314)
		(width 0.13462)
		(layer "F.Cu")
		(net "P5E_PEX0_STN5_TX_C_DN<80>")
	)
	(segment
		(start 62.235842 -351.611438)
		(end 61.941202 -351.316798)
		(width 0.13462)
		(layer "F.Cu")
		(net "P5E_PEX0_STN5_TX_C_DN<80>")
	)
	(segment
		(start 61.941202 -351.316798)
		(end 61.941202 -350.685354)
		(width 0.13462)
		(layer "F.Cu")
		(net "P5E_PEX0_STN5_TX_C_DN<80>")
	)
	(segment
		(start 65.436496 -389.105394)
		(end 64.040004 -385.733544)
		(width 0.1651)
		(layer "In7.Cu")
		(net "P5E_PEX0_STN5_TX_C_DN<80>")
	)
	(segment
		(start 63.0682 -376.769376)
		(end 61.945012 -355.991668)
		(width 0.1651)
		(layer "In7.Cu")
		(net "P5E_PEX0_STN5_TX_C_DN<80>")
	)
	(segment
		(start 61.945012 -351.902268)
		(end 62.235842 -351.611438)
		(width 0.1651)
		(layer "In7.Cu")
		(net "P5E_PEX0_STN5_TX_C_DN<80>")
	)
	(segment
		(start 73.084182 -404.486872)
		(end 73.084182 -394.470382)
		(width 0.1651)
		(layer "In7.Cu")
		(net "P5E_PEX0_STN5_TX_C_DN<80>")
	)
	(segment
		(start 72.03694 -405.080978)
		(end 72.490076 -405.080978)
		(width 0.1651)
		(layer "In7.Cu")
		(net "P5E_PEX0_STN5_TX_C_DN<80>")
	)
	(segment
		(start 71.90994 -405.207978)
		(end 72.03694 -405.080978)
		(width 0.1651)
		(layer "In7.Cu")
		(net "P5E_PEX0_STN5_TX_C_DN<80>")
	)
	(segment
		(start 72.091042 -393.477242)
		(end 68.280026 -391.898632)
		(width 0.1651)
		(layer "In7.Cu")
		(net "P5E_PEX0_STN5_TX_C_DN<80>")
	)
	(segment
		(start 61.945012 -355.991668)
		(end 61.945012 -351.902268)
		(width 0.1651)
		(layer "In7.Cu")
		(net "P5E_PEX0_STN5_TX_C_DN<80>")
	)
	(segment
		(start 73.084182 -394.470382)
		(end 72.091042 -393.477242)
		(width 0.1651)
		(layer "In7.Cu")
		(net "P5E_PEX0_STN5_TX_C_DN<80>")
	)
	(segment
		(start 68.280026 -391.898632)
		(end 68.194174 -391.863072)
		(width 0.1651)
		(layer "In7.Cu")
		(net "P5E_PEX0_STN5_TX_C_DN<80>")
	)
	(segment
		(start 64.040004 -385.733544)
		(end 63.0682 -376.769376)
		(width 0.1651)
		(layer "In7.Cu")
		(net "P5E_PEX0_STN5_TX_C_DN<80>")
	)
	(segment
		(start 68.194174 -391.863072)
		(end 65.436496 -389.105394)
		(width 0.1651)
		(layer "In7.Cu")
		(net "P5E_PEX0_STN5_TX_C_DN<80>")
	)
	(segment
		(start 72.490076 -405.080978)
		(end 73.084182 -404.486872)
		(width 0.1651)
		(layer "In7.Cu")
		(net "P5E_PEX0_STN5_TX_C_DN<80>")
	)
	(segment
		(start 71.90994 -405.589994)
		(end 71.90994 -405.207978)
		(width 0.1651)
		(layer "In7.Cu")
		(net "P5E_PEX0_STN5_TX_C_DN<80>")
	)
	(segment
		(start 139.842748 -345.465146)
		(end 140.137388 -345.170506)
		(width 0.13462)
		(layer "F.Cu")
		(net "P5E_PEX1_STN5_TX_C_DP<85>")
	)
	(segment
		(start 140.137388 -345.170506)
		(end 140.137388 -344.539062)
		(width 0.13462)
		(layer "F.Cu")
		(net "P5E_PEX1_STN5_TX_C_DP<85>")
	)
	(segment
		(start 140.137388 -344.539062)
		(end 139.817348 -344.219022)
		(width 0.13462)
		(layer "F.Cu")
		(net "P5E_PEX1_STN5_TX_C_DP<85>")
	)
	(segment
		(start 139.767564 -364.324138)
		(end 139.716764 -364.419134)
		(width 0.1651)
		(layer "In7.Cu")
		(net "P5E_PEX1_STN5_TX_C_DP<85>")
	)
	(segment
		(start 141.06906 -369.946174)
		(end 140.7414 -383.232152)
		(width 0.1651)
		(layer "In7.Cu")
		(net "P5E_PEX1_STN5_TX_C_DP<85>")
	)
	(segment
		(start 139.716764 -364.419134)
		(end 139.860528 -364.893352)
		(width 0.1651)
		(layer "In7.Cu")
		(net "P5E_PEX1_STN5_TX_C_DP<85>")
	)
	(segment
		(start 140.517372 -386.419852)
		(end 140.155676 -387.614922)
		(width 0.1651)
		(layer "In7.Cu")
		(net "P5E_PEX1_STN5_TX_C_DP<85>")
	)
	(segment
		(start 127.973074 -394.835888)
		(end 127.687578 -396.30985)
		(width 0.1651)
		(layer "In7.Cu")
		(net "P5E_PEX1_STN5_TX_C_DP<85>")
	)
	(segment
		(start 141.06906 -368.613944)
		(end 141.06906 -369.946174)
		(width 0.1651)
		(layer "In7.Cu")
		(net "P5E_PEX1_STN5_TX_C_DP<85>")
	)
	(segment
		(start 137.24763 -390.364218)
		(end 128.915414 -393.893802)
		(width 0.1651)
		(layer "In7.Cu")
		(net "P5E_PEX1_STN5_TX_C_DP<85>")
	)
	(segment
		(start 139.956032 -364.944152)
		(end 141.06906 -368.613944)
		(width 0.1651)
		(layer "In7.Cu")
		(net "P5E_PEX1_STN5_TX_C_DP<85>")
	)
	(segment
		(start 140.133578 -345.755976)
		(end 140.133578 -346.360242)
		(width 0.1651)
		(layer "In7.Cu")
		(net "P5E_PEX1_STN5_TX_C_DP<85>")
	)
	(segment
		(start 140.7414 -383.232152)
		(end 140.7414 -384.168904)
		(width 0.1651)
		(layer "In7.Cu")
		(net "P5E_PEX1_STN5_TX_C_DP<85>")
	)
	(segment
		(start 140.133578 -346.360242)
		(end 138.579098 -347.914722)
		(width 0.1651)
		(layer "In7.Cu")
		(net "P5E_PEX1_STN5_TX_C_DP<85>")
	)
	(segment
		(start 139.590018 -388.692136)
		(end 138.334242 -389.735568)
		(width 0.1651)
		(layer "In7.Cu")
		(net "P5E_PEX1_STN5_TX_C_DP<85>")
	)
	(segment
		(start 139.842748 -345.465146)
		(end 140.133578 -345.755976)
		(width 0.1651)
		(layer "In7.Cu")
		(net "P5E_PEX1_STN5_TX_C_DP<85>")
	)
	(segment
		(start 139.860528 -364.893352)
		(end 139.956032 -364.944152)
		(width 0.1651)
		(layer "In7.Cu")
		(net "P5E_PEX1_STN5_TX_C_DP<85>")
	)
	(segment
		(start 140.7414 -384.168904)
		(end 140.517372 -386.419852)
		(width 0.1651)
		(layer "In7.Cu")
		(net "P5E_PEX1_STN5_TX_C_DP<85>")
	)
	(segment
		(start 126.910084 -405.771858)
		(end 126.910084 -405.390096)
		(width 0.1651)
		(layer "In7.Cu")
		(net "P5E_PEX1_STN5_TX_C_DP<85>")
	)
	(segment
		(start 138.579098 -347.914722)
		(end 138.579098 -358.336088)
		(width 0.1651)
		(layer "In7.Cu")
		(net "P5E_PEX1_STN5_TX_C_DP<85>")
	)
	(segment
		(start 140.155676 -387.614922)
		(end 139.590018 -388.692136)
		(width 0.1651)
		(layer "In7.Cu")
		(net "P5E_PEX1_STN5_TX_C_DP<85>")
	)
	(segment
		(start 127.687578 -405.48052)
		(end 127.26924 -405.898858)
		(width 0.1651)
		(layer "In7.Cu")
		(net "P5E_PEX1_STN5_TX_C_DP<85>")
	)
	(segment
		(start 127.26924 -405.898858)
		(end 127.037084 -405.898858)
		(width 0.1651)
		(layer "In7.Cu")
		(net "P5E_PEX1_STN5_TX_C_DP<85>")
	)
	(segment
		(start 138.579098 -358.336088)
		(end 139.180062 -362.38688)
		(width 0.1651)
		(layer "In7.Cu")
		(net "P5E_PEX1_STN5_TX_C_DP<85>")
	)
	(segment
		(start 138.334242 -389.735568)
		(end 137.24763 -390.364218)
		(width 0.1651)
		(layer "In7.Cu")
		(net "P5E_PEX1_STN5_TX_C_DP<85>")
	)
	(segment
		(start 128.915414 -393.893802)
		(end 127.973074 -394.835888)
		(width 0.1651)
		(layer "In7.Cu")
		(net "P5E_PEX1_STN5_TX_C_DP<85>")
	)
	(segment
		(start 127.687578 -396.30985)
		(end 127.687578 -405.48052)
		(width 0.1651)
		(layer "In7.Cu")
		(net "P5E_PEX1_STN5_TX_C_DP<85>")
	)
	(segment
		(start 139.180062 -362.38688)
		(end 139.767564 -364.324138)
		(width 0.1651)
		(layer "In7.Cu")
		(net "P5E_PEX1_STN5_TX_C_DP<85>")
	)
	(segment
		(start 127.037084 -405.898858)
		(end 126.910084 -405.771858)
		(width 0.1651)
		(layer "In7.Cu")
		(net "P5E_PEX1_STN5_TX_C_DP<85>")
	)
	(segment
		(start 35.171888 -355.658166)
		(end 35.171888 -355.026722)
		(width 0.13462)
		(layer "F.Cu")
		(net "P5E_PEX0_STN7_TX_DP<120>")
	)
	(segment
		(start 34.851848 -355.978206)
		(end 35.171888 -355.658166)
		(width 0.13462)
		(layer "F.Cu")
		(net "P5E_PEX0_STN7_TX_DP<120>")
	)
	(segment
		(start 35.171888 -355.026722)
		(end 34.877248 -354.732082)
		(width 0.13462)
		(layer "F.Cu")
		(net "P5E_PEX0_STN7_TX_DP<120>")
	)
	(segment
		(start 36.722558 -342.116156)
		(end 36.722304 -342.115902)
		(width 0.1651)
		(layer "In7.Cu")
		(net "P5E_PEX0_STN7_TX_DP<120>")
	)
	(segment
		(start 36.080954 -340.859364)
		(end 35.896296 -340.41334)
		(width 0.1651)
		(layer "In7.Cu")
		(net "P5E_PEX0_STN7_TX_DP<120>")
	)
	(segment
		(start 42.170096 -308.855364)
		(end 42.170096 -309.085488)
		(width 0.1143)
		(layer "In7.Cu")
		(net "P5E_PEX0_STN7_TX_DP<120>")
	)
	(segment
		(start 35.37585 -338.864956)
		(end 35.10788 -338.46389)
		(width 0.1651)
		(layer "In7.Cu")
		(net "P5E_PEX0_STN7_TX_DP<120>")
	)
	(segment
		(start 42.284396 -309.199788)
		(end 42.549826 -309.199788)
		(width 0.1143)
		(layer "In7.Cu")
		(net "P5E_PEX0_STN7_TX_DP<120>")
	)
	(segment
		(start 36.722558 -342.115902)
		(end 36.227258 -340.919816)
		(width 0.1651)
		(layer "In7.Cu")
		(net "P5E_PEX0_STN7_TX_DP<120>")
	)
	(segment
		(start 25.105106 -318.461644)
		(end 25.643078 -317.656718)
		(width 0.1651)
		(layer "In7.Cu")
		(net "P5E_PEX0_STN7_TX_DP<120>")
	)
	(segment
		(start 24.535384 -321.969384)
		(end 24.535384 -320.395346)
		(width 0.1651)
		(layer "In7.Cu")
		(net "P5E_PEX0_STN7_TX_DP<120>")
	)
	(segment
		(start 34.95294 -338.432902)
		(end 34.684462 -338.031582)
		(width 0.1651)
		(layer "In7.Cu")
		(net "P5E_PEX0_STN7_TX_DP<120>")
	)
	(segment
		(start 42.170096 -309.085488)
		(end 42.284396 -309.199788)
		(width 0.1143)
		(layer "In7.Cu")
		(net "P5E_PEX0_STN7_TX_DP<120>")
	)
	(segment
		(start 35.683952 -308.583838)
		(end 35.7124 -308.583838)
		(width 0.1143)
		(layer "In7.Cu")
		(net "P5E_PEX0_STN7_TX_DP<120>")
	)
	(segment
		(start 41.94429 -308.629558)
		(end 42.170096 -308.855364)
		(width 0.1143)
		(layer "In7.Cu")
		(net "P5E_PEX0_STN7_TX_DP<120>")
	)
	(segment
		(start 35.7124 -308.583838)
		(end 35.75812 -308.629558)
		(width 0.1143)
		(layer "In7.Cu")
		(net "P5E_PEX0_STN7_TX_DP<120>")
	)
	(segment
		(start 35.75812 -308.629558)
		(end 41.94429 -308.629558)
		(width 0.1143)
		(layer "In7.Cu")
		(net "P5E_PEX0_STN7_TX_DP<120>")
	)
	(segment
		(start 35.168078 -353.825302)
		(end 36.722558 -352.270822)
		(width 0.1651)
		(layer "In7.Cu")
		(net "P5E_PEX0_STN7_TX_DP<120>")
	)
	(segment
		(start 34.594292 -308.705504)
		(end 34.887916 -308.583838)
		(width 0.1651)
		(layer "In7.Cu")
		(net "P5E_PEX0_STN7_TX_DP<120>")
	)
	(segment
		(start 24.535384 -320.395346)
		(end 24.748998 -319.32118)
		(width 0.1651)
		(layer "In7.Cu")
		(net "P5E_PEX0_STN7_TX_DP<120>")
	)
	(segment
		(start 25.643078 -317.656718)
		(end 34.594292 -308.705504)
		(width 0.1651)
		(layer "In7.Cu")
		(net "P5E_PEX0_STN7_TX_DP<120>")
	)
	(segment
		(start 34.877248 -354.732082)
		(end 35.168078 -354.441252)
		(width 0.1651)
		(layer "In7.Cu")
		(net "P5E_PEX0_STN7_TX_DP<120>")
	)
	(segment
		(start 35.168078 -354.441252)
		(end 35.168078 -353.825302)
		(width 0.1651)
		(layer "In7.Cu")
		(net "P5E_PEX0_STN7_TX_DP<120>")
	)
	(segment
		(start 25.267412 -323.737224)
		(end 24.535384 -321.969384)
		(width 0.1651)
		(layer "In7.Cu")
		(net "P5E_PEX0_STN7_TX_DP<120>")
	)
	(segment
		(start 34.715196 -337.876388)
		(end 25.267412 -323.737224)
		(width 0.1651)
		(layer "In7.Cu")
		(net "P5E_PEX0_STN7_TX_DP<120>")
	)
	(segment
		(start 24.748998 -319.32118)
		(end 25.105106 -318.461644)
		(width 0.1651)
		(layer "In7.Cu")
		(net "P5E_PEX0_STN7_TX_DP<120>")
	)
	(segment
		(start 35.896296 -340.41334)
		(end 35.956748 -340.26729)
		(width 0.1651)
		(layer "In7.Cu")
		(net "P5E_PEX0_STN7_TX_DP<120>")
	)
	(segment
		(start 34.684462 -338.031582)
		(end 34.715196 -337.876388)
		(width 0.1651)
		(layer "In7.Cu")
		(net "P5E_PEX0_STN7_TX_DP<120>")
	)
	(segment
		(start 35.10788 -338.46389)
		(end 34.95294 -338.432902)
		(width 0.1651)
		(layer "In7.Cu")
		(net "P5E_PEX0_STN7_TX_DP<120>")
	)
	(segment
		(start 36.227258 -340.919816)
		(end 36.080954 -340.859364)
		(width 0.1651)
		(layer "In7.Cu")
		(net "P5E_PEX0_STN7_TX_DP<120>")
	)
	(segment
		(start 36.722558 -352.270822)
		(end 36.722558 -342.116156)
		(width 0.1651)
		(layer "In7.Cu")
		(net "P5E_PEX0_STN7_TX_DP<120>")
	)
	(segment
		(start 35.956748 -340.26729)
		(end 35.37585 -338.864956)
		(width 0.1651)
		(layer "In7.Cu")
		(net "P5E_PEX0_STN7_TX_DP<120>")
	)
	(segment
		(start 34.887916 -308.583838)
		(end 35.683952 -308.583838)
		(width 0.1651)
		(layer "In7.Cu")
		(net "P5E_PEX0_STN7_TX_DP<120>")
	)
	(segment
		(start 36.722304 -342.115902)
		(end 36.722558 -342.115902)
		(width 0.1651)
		(layer "In7.Cu")
		(net "P5E_PEX0_STN7_TX_DP<120>")
	)
	(segment
		(start 196.385942 -134.394702)
		(end 196.705982 -134.074662)
		(width 0.13462)
		(layer "F.Cu")
		(net "P5E_PEX1_STN0_TX_DP<6>")
	)
	(segment
		(start 196.705982 -134.074662)
		(end 197.337426 -134.074662)
		(width 0.13462)
		(layer "F.Cu")
		(net "P5E_PEX1_STN0_TX_DP<6>")
	)
	(segment
		(start 197.337426 -134.074662)
		(end 197.632066 -134.369302)
		(width 0.13462)
		(layer "F.Cu")
		(net "P5E_PEX1_STN0_TX_DP<6>")
	)
	(segment
		(start 199.256396 -134.185152)
		(end 199.363076 -134.078472)
		(width 0.1651)
		(layer "In9.Cu")
		(net "P5E_PEX1_STN0_TX_DP<6>")
	)
	(segment
		(start 203.97216 -139.639294)
		(end 204.146912 -140.061442)
		(width 0.1651)
		(layer "In9.Cu")
		(net "P5E_PEX1_STN0_TX_DP<6>")
	)
	(segment
		(start 203.236322 -138.12901)
		(end 203.411328 -138.551666)
		(width 0.1651)
		(layer "In9.Cu")
		(net "P5E_PEX1_STN0_TX_DP<6>")
	)
	(segment
		(start 196.632068 -221.665038)
		(end 199.240394 -251.527056)
		(width 0.1651)
		(layer "In9.Cu")
		(net "P5E_PEX1_STN0_TX_DP<6>")
	)
	(segment
		(start 199.989186 -281.983942)
		(end 199.943466 -282.029662)
		(width 0.1143)
		(layer "In9.Cu")
		(net "P5E_PEX1_STN0_TX_DP<6>")
	)
	(segment
		(start 200.242424 -134.253224)
		(end 200.300336 -134.392924)
		(width 0.1651)
		(layer "In9.Cu")
		(net "P5E_PEX1_STN0_TX_DP<6>")
	)
	(segment
		(start 204.092048 -140.194284)
		(end 204.267054 -140.61694)
		(width 0.1651)
		(layer "In9.Cu")
		(net "P5E_PEX1_STN0_TX_DP<6>")
	)
	(segment
		(start 193.115438 -282.599892)
		(end 192.850008 -282.599892)
		(width 0.1143)
		(layer "In9.Cu")
		(net "P5E_PEX1_STN0_TX_DP<6>")
	)
	(segment
		(start 198.799196 -134.185152)
		(end 199.256396 -134.185152)
		(width 0.1651)
		(layer "In9.Cu")
		(net "P5E_PEX1_STN0_TX_DP<6>")
	)
	(segment
		(start 202.86345 -136.963404)
		(end 202.808586 -137.096246)
		(width 0.1651)
		(layer "In9.Cu")
		(net "P5E_PEX1_STN0_TX_DP<6>")
	)
	(segment
		(start 210.414362 -268.772386)
		(end 210.65744 -271.54632)
		(width 0.1651)
		(layer "In9.Cu")
		(net "P5E_PEX1_STN0_TX_DP<6>")
	)
	(segment
		(start 198.692516 -134.078472)
		(end 198.799196 -134.185152)
		(width 0.1651)
		(layer "In9.Cu")
		(net "P5E_PEX1_STN0_TX_DP<6>")
	)
	(segment
		(start 210.65744 -271.54632)
		(end 209.92465 -273.559524)
		(width 0.1651)
		(layer "In9.Cu")
		(net "P5E_PEX1_STN0_TX_DP<6>")
	)
	(segment
		(start 206.707994 -145.594578)
		(end 210.183222 -153.984706)
		(width 0.1651)
		(layer "In9.Cu")
		(net "P5E_PEX1_STN0_TX_DP<6>")
	)
	(segment
		(start 200.300336 -134.392924)
		(end 200.722992 -134.56793)
		(width 0.1651)
		(layer "In9.Cu")
		(net "P5E_PEX1_STN0_TX_DP<6>")
	)
	(segment
		(start 193.229738 -282.2448)
		(end 193.229738 -282.485592)
		(width 0.1143)
		(layer "In9.Cu")
		(net "P5E_PEX1_STN0_TX_DP<6>")
	)
	(segment
		(start 199.820022 -134.078472)
		(end 200.242424 -134.253478)
		(width 0.1651)
		(layer "In9.Cu")
		(net "P5E_PEX1_STN0_TX_DP<6>")
	)
	(segment
		(start 196.629782 -221.640654)
		(end 196.631814 -221.665038)
		(width 0.1651)
		(layer "In9.Cu")
		(net "P5E_PEX1_STN0_TX_DP<6>")
	)
	(segment
		(start 200.017634 -281.983942)
		(end 199.989186 -281.983942)
		(width 0.1143)
		(layer "In9.Cu")
		(net "P5E_PEX1_STN0_TX_DP<6>")
	)
	(segment
		(start 201.555096 -134.797038)
		(end 202.257152 -135.499094)
		(width 0.1651)
		(layer "In9.Cu")
		(net "P5E_PEX1_STN0_TX_DP<6>")
	)
	(segment
		(start 200.242424 -134.253478)
		(end 200.242424 -134.253224)
		(width 0.1651)
		(layer "In9.Cu")
		(net "P5E_PEX1_STN0_TX_DP<6>")
	)
	(segment
		(start 193.229738 -282.485592)
		(end 193.115438 -282.599892)
		(width 0.1143)
		(layer "In9.Cu")
		(net "P5E_PEX1_STN0_TX_DP<6>")
	)
	(segment
		(start 193.444876 -282.029662)
		(end 193.229738 -282.2448)
		(width 0.1143)
		(layer "In9.Cu")
		(net "P5E_PEX1_STN0_TX_DP<6>")
	)
	(segment
		(start 203.291186 -137.996168)
		(end 203.236322 -138.12901)
		(width 0.1651)
		(layer "In9.Cu")
		(net "P5E_PEX1_STN0_TX_DP<6>")
	)
	(segment
		(start 204.267054 -140.61694)
		(end 204.399896 -140.672058)
		(width 0.1651)
		(layer "In9.Cu")
		(net "P5E_PEX1_STN0_TX_DP<6>")
	)
	(segment
		(start 202.431904 -135.921242)
		(end 202.374246 -136.060688)
		(width 0.1651)
		(layer "In9.Cu")
		(net "P5E_PEX1_STN0_TX_DP<6>")
	)
	(segment
		(start 203.116434 -137.57402)
		(end 203.291186 -137.996168)
		(width 0.1651)
		(layer "In9.Cu")
		(net "P5E_PEX1_STN0_TX_DP<6>")
	)
	(segment
		(start 202.08875 -281.395424)
		(end 200.66762 -281.983942)
		(width 0.1651)
		(layer "In9.Cu")
		(net "P5E_PEX1_STN0_TX_DP<6>")
	)
	(segment
		(start 210.183222 -153.984706)
		(end 210.183222 -158.922212)
		(width 0.1651)
		(layer "In9.Cu")
		(net "P5E_PEX1_STN0_TX_DP<6>")
	)
	(segment
		(start 202.983592 -137.518902)
		(end 203.116434 -137.57402)
		(width 0.1651)
		(layer "In9.Cu")
		(net "P5E_PEX1_STN0_TX_DP<6>")
	)
	(segment
		(start 203.664058 -139.161774)
		(end 203.839064 -139.58443)
		(width 0.1651)
		(layer "In9.Cu")
		(net "P5E_PEX1_STN0_TX_DP<6>")
	)
	(segment
		(start 204.399896 -140.672058)
		(end 206.248762 -145.135346)
		(width 0.1651)
		(layer "In9.Cu")
		(net "P5E_PEX1_STN0_TX_DP<6>")
	)
	(segment
		(start 206.248762 -145.135346)
		(end 206.707994 -145.594578)
		(width 0.1651)
		(layer "In9.Cu")
		(net "P5E_PEX1_STN0_TX_DP<6>")
	)
	(segment
		(start 197.632066 -134.369302)
		(end 197.922896 -134.078472)
		(width 0.1651)
		(layer "In9.Cu")
		(net "P5E_PEX1_STN0_TX_DP<6>")
	)
	(segment
		(start 200.434702 -178.151028)
		(end 196.629782 -221.640654)
		(width 0.1651)
		(layer "In9.Cu")
		(net "P5E_PEX1_STN0_TX_DP<6>")
	)
	(segment
		(start 202.688952 -136.541256)
		(end 202.688698 -136.541256)
		(width 0.1651)
		(layer "In9.Cu")
		(net "P5E_PEX1_STN0_TX_DP<6>")
	)
	(segment
		(start 202.257152 -135.499094)
		(end 202.431904 -135.921242)
		(width 0.1651)
		(layer "In9.Cu")
		(net "P5E_PEX1_STN0_TX_DP<6>")
	)
	(segment
		(start 204.570838 -259.504434)
		(end 209.845148 -267.397992)
		(width 0.1651)
		(layer "In9.Cu")
		(net "P5E_PEX1_STN0_TX_DP<6>")
	)
	(segment
		(start 203.54417 -138.606784)
		(end 203.718922 -139.028932)
		(width 0.1651)
		(layer "In9.Cu")
		(net "P5E_PEX1_STN0_TX_DP<6>")
	)
	(segment
		(start 200.66762 -281.983942)
		(end 200.017634 -281.983942)
		(width 0.1651)
		(layer "In9.Cu")
		(net "P5E_PEX1_STN0_TX_DP<6>")
	)
	(segment
		(start 199.363076 -134.078472)
		(end 199.820022 -134.078472)
		(width 0.1651)
		(layer "In9.Cu")
		(net "P5E_PEX1_STN0_TX_DP<6>")
	)
	(segment
		(start 199.943466 -282.029662)
		(end 193.444876 -282.029662)
		(width 0.1143)
		(layer "In9.Cu")
		(net "P5E_PEX1_STN0_TX_DP<6>")
	)
	(segment
		(start 200.722992 -134.56793)
		(end 200.862438 -134.510272)
		(width 0.1651)
		(layer "In9.Cu")
		(net "P5E_PEX1_STN0_TX_DP<6>")
	)
	(segment
		(start 204.146912 -140.061442)
		(end 204.092048 -140.194284)
		(width 0.1651)
		(layer "In9.Cu")
		(net "P5E_PEX1_STN0_TX_DP<6>")
	)
	(segment
		(start 209.845148 -267.397992)
		(end 210.414362 -268.772386)
		(width 0.1651)
		(layer "In9.Cu")
		(net "P5E_PEX1_STN0_TX_DP<6>")
	)
	(segment
		(start 203.411328 -138.551666)
		(end 203.54417 -138.606784)
		(width 0.1651)
		(layer "In9.Cu")
		(net "P5E_PEX1_STN0_TX_DP<6>")
	)
	(segment
		(start 202.374246 -136.060688)
		(end 202.549252 -136.483344)
		(width 0.1651)
		(layer "In9.Cu")
		(net "P5E_PEX1_STN0_TX_DP<6>")
	)
	(segment
		(start 200.862438 -134.510272)
		(end 201.555096 -134.797038)
		(width 0.1651)
		(layer "In9.Cu")
		(net "P5E_PEX1_STN0_TX_DP<6>")
	)
	(segment
		(start 202.808586 -137.096246)
		(end 202.983592 -137.518902)
		(width 0.1651)
		(layer "In9.Cu")
		(net "P5E_PEX1_STN0_TX_DP<6>")
	)
	(segment
		(start 197.922896 -134.078472)
		(end 198.692516 -134.078472)
		(width 0.1651)
		(layer "In9.Cu")
		(net "P5E_PEX1_STN0_TX_DP<6>")
	)
	(segment
		(start 209.92465 -273.559524)
		(end 202.08875 -281.395424)
		(width 0.1651)
		(layer "In9.Cu")
		(net "P5E_PEX1_STN0_TX_DP<6>")
	)
	(segment
		(start 202.688698 -136.541256)
		(end 202.86345 -136.963404)
		(width 0.1651)
		(layer "In9.Cu")
		(net "P5E_PEX1_STN0_TX_DP<6>")
	)
	(segment
		(start 196.631814 -221.665038)
		(end 196.632068 -221.665038)
		(width 0.1651)
		(layer "In9.Cu")
		(net "P5E_PEX1_STN0_TX_DP<6>")
	)
	(segment
		(start 202.549252 -136.483344)
		(end 202.688952 -136.541256)
		(width 0.1651)
		(layer "In9.Cu")
		(net "P5E_PEX1_STN0_TX_DP<6>")
	)
	(segment
		(start 203.839064 -139.58443)
		(end 203.97216 -139.639294)
		(width 0.1651)
		(layer "In9.Cu")
		(net "P5E_PEX1_STN0_TX_DP<6>")
	)
	(segment
		(start 210.183222 -158.922212)
		(end 201.606404 -173.78172)
		(width 0.1651)
		(layer "In9.Cu")
		(net "P5E_PEX1_STN0_TX_DP<6>")
	)
	(segment
		(start 199.240394 -251.527056)
		(end 204.570838 -259.504434)
		(width 0.1651)
		(layer "In9.Cu")
		(net "P5E_PEX1_STN0_TX_DP<6>")
	)
	(segment
		(start 201.606404 -173.78172)
		(end 200.434702 -178.151028)
		(width 0.1651)
		(layer "In9.Cu")
		(net "P5E_PEX1_STN0_TX_DP<6>")
	)
	(segment
		(start 203.718922 -139.028932)
		(end 203.664058 -139.161774)
		(width 0.1651)
		(layer "In9.Cu")
		(net "P5E_PEX1_STN0_TX_DP<6>")
	)
	(segment
		(start 124.866908 -342.734138)
		(end 125.161548 -342.439498)
		(width 0.13462)
		(layer "F.Cu")
		(net "P5E_PEX1_STN6_TX_DN<106>")
	)
	(segment
		(start 125.186948 -343.685622)
		(end 124.866908 -343.365582)
		(width 0.13462)
		(layer "F.Cu")
		(net "P5E_PEX1_STN6_TX_DN<106>")
	)
	(segment
		(start 124.866908 -343.365582)
		(end 124.866908 -342.734138)
		(width 0.13462)
		(layer "F.Cu")
		(net "P5E_PEX1_STN6_TX_DN<106>")
	)
	(segment
		(start 164.07384 -313.570112)
		(end 163.970208 -313.673744)
		(width 0.1143)
		(layer "In13.Cu")
		(net "P5E_PEX1_STN6_TX_DN<106>")
	)
	(segment
		(start 124.870718 -342.148668)
		(end 125.161548 -342.439498)
		(width 0.1651)
		(layer "In13.Cu")
		(net "P5E_PEX1_STN6_TX_DN<106>")
	)
	(segment
		(start 124.870718 -341.14867)
		(end 124.870718 -342.148668)
		(width 0.1651)
		(layer "In13.Cu")
		(net "P5E_PEX1_STN6_TX_DN<106>")
	)
	(segment
		(start 164.015928 -322.388992)
		(end 161.316924 -325.087996)
		(width 0.1651)
		(layer "In13.Cu")
		(net "P5E_PEX1_STN6_TX_DN<106>")
	)
	(segment
		(start 164.349938 -313.684412)
		(end 164.235638 -313.570112)
		(width 0.1143)
		(layer "In13.Cu")
		(net "P5E_PEX1_STN6_TX_DN<106>")
	)
	(segment
		(start 131.408424 -335.894172)
		(end 127.540766 -338.478622)
		(width 0.1651)
		(layer "In13.Cu")
		(net "P5E_PEX1_STN6_TX_DN<106>")
	)
	(segment
		(start 161.316924 -325.087996)
		(end 157.652212 -327.285096)
		(width 0.1651)
		(layer "In13.Cu")
		(net "P5E_PEX1_STN6_TX_DN<106>")
	)
	(segment
		(start 164.235638 -313.570112)
		(end 164.07384 -313.570112)
		(width 0.1143)
		(layer "In13.Cu")
		(net "P5E_PEX1_STN6_TX_DN<106>")
	)
	(segment
		(start 153.059892 -329.187048)
		(end 153.060146 -329.187302)
		(width 0.1651)
		(layer "In13.Cu")
		(net "P5E_PEX1_STN6_TX_DN<106>")
	)
	(segment
		(start 163.970208 -313.673744)
		(end 163.970208 -319.995296)
		(width 0.1143)
		(layer "In13.Cu")
		(net "P5E_PEX1_STN6_TX_DN<106>")
	)
	(segment
		(start 163.970208 -319.995296)
		(end 164.015928 -320.041016)
		(width 0.1143)
		(layer "In13.Cu")
		(net "P5E_PEX1_STN6_TX_DN<106>")
	)
	(segment
		(start 145.944336 -331.591412)
		(end 141.796262 -331.591412)
		(width 0.1651)
		(layer "In13.Cu")
		(net "P5E_PEX1_STN6_TX_DN<106>")
	)
	(segment
		(start 164.349938 -313.949842)
		(end 164.349938 -313.684412)
		(width 0.1143)
		(layer "In13.Cu")
		(net "P5E_PEX1_STN6_TX_DN<106>")
	)
	(segment
		(start 148.46173 -331.091794)
		(end 145.944336 -331.591412)
		(width 0.1651)
		(layer "In13.Cu")
		(net "P5E_PEX1_STN6_TX_DN<106>")
	)
	(segment
		(start 127.540766 -338.478622)
		(end 124.870718 -341.14867)
		(width 0.1651)
		(layer "In13.Cu")
		(net "P5E_PEX1_STN6_TX_DN<106>")
	)
	(segment
		(start 157.652212 -327.285096)
		(end 153.059892 -329.187048)
		(width 0.1651)
		(layer "In13.Cu")
		(net "P5E_PEX1_STN6_TX_DN<106>")
	)
	(segment
		(start 164.015928 -320.063114)
		(end 164.015928 -322.388992)
		(width 0.1651)
		(layer "In13.Cu")
		(net "P5E_PEX1_STN6_TX_DN<106>")
	)
	(segment
		(start 141.796262 -331.591412)
		(end 131.408424 -335.894172)
		(width 0.1651)
		(layer "In13.Cu")
		(net "P5E_PEX1_STN6_TX_DN<106>")
	)
	(segment
		(start 153.060146 -329.187302)
		(end 148.46173 -331.091794)
		(width 0.1651)
		(layer "In13.Cu")
		(net "P5E_PEX1_STN6_TX_DN<106>")
	)
	(segment
		(start 164.015928 -320.041016)
		(end 164.015928 -320.063114)
		(width 0.1143)
		(layer "In13.Cu")
		(net "P5E_PEX1_STN6_TX_DN<106>")
	)
	(segment
		(start 142.349474 -332.744572)
		(end 136.940798 -323.992748)
		(width 0.1651)
		(layer "In9.Cu")
		(net "P5E_PEX1_STN7_RX_DP<115>")
	)
	(segment
		(start 159.581596 -390.777476)
		(end 156.001212 -387.857492)
		(width 0.1651)
		(layer "In9.Cu")
		(net "P5E_PEX1_STN7_RX_DP<115>")
	)
	(segment
		(start 153.280872 -303.879504)
		(end 153.524712 -304.123344)
		(width 0.1143)
		(layer "In9.Cu")
		(net "P5E_PEX1_STN7_RX_DP<115>")
	)
	(segment
		(start 136.642856 -322.884546)
		(end 136.642856 -322.884038)
		(width 0.1651)
		(layer "In9.Cu")
		(net "P5E_PEX1_STN7_RX_DP<115>")
	)
	(segment
		(start 145.0721 -305.048666)
		(end 148.965666 -303.833784)
		(width 0.1651)
		(layer "In9.Cu")
		(net "P5E_PEX1_STN7_RX_DP<115>")
	)
	(segment
		(start 153.524712 -304.355246)
		(end 153.6192 -304.449734)
		(width 0.1143)
		(layer "In9.Cu")
		(net "P5E_PEX1_STN7_RX_DP<115>")
	)
	(segment
		(start 166.858442 -409.799282)
		(end 167.39235 -409.265374)
		(width 0.1651)
		(layer "In9.Cu")
		(net "P5E_PEX1_STN7_RX_DP<115>")
	)
	(segment
		(start 156.001212 -387.857492)
		(end 154.395932 -384.942842)
		(width 0.1651)
		(layer "In9.Cu")
		(net "P5E_PEX1_STN7_RX_DP<115>")
	)
	(segment
		(start 149.004782 -345.01963)
		(end 147.72132 -341.436198)
		(width 0.1651)
		(layer "In9.Cu")
		(net "P5E_PEX1_STN7_RX_DP<115>")
	)
	(segment
		(start 166.636954 -409.799282)
		(end 166.858442 -409.799282)
		(width 0.1651)
		(layer "In9.Cu")
		(net "P5E_PEX1_STN7_RX_DP<115>")
	)
	(segment
		(start 142.349728 -332.744826)
		(end 142.349474 -332.744572)
		(width 0.1651)
		(layer "In9.Cu")
		(net "P5E_PEX1_STN7_RX_DP<115>")
	)
	(segment
		(start 166.509954 -409.290012)
		(end 166.509954 -409.672282)
		(width 0.1651)
		(layer "In9.Cu")
		(net "P5E_PEX1_STN7_RX_DP<115>")
	)
	(segment
		(start 136.643364 -322.885562)
		(end 136.64311 -322.885562)
		(width 0.1651)
		(layer "In9.Cu")
		(net "P5E_PEX1_STN7_RX_DP<115>")
	)
	(segment
		(start 151.765 -303.833784)
		(end 151.793448 -303.833784)
		(width 0.1143)
		(layer "In9.Cu")
		(net "P5E_PEX1_STN7_RX_DP<115>")
	)
	(segment
		(start 136.633712 -322.849748)
		(end 136.633712 -318.723264)
		(width 0.1651)
		(layer "In9.Cu")
		(net "P5E_PEX1_STN7_RX_DP<115>")
	)
	(segment
		(start 166.509954 -409.672282)
		(end 166.636954 -409.799282)
		(width 0.1651)
		(layer "In9.Cu")
		(net "P5E_PEX1_STN7_RX_DP<115>")
	)
	(segment
		(start 148.965666 -303.833784)
		(end 151.765 -303.833784)
		(width 0.1651)
		(layer "In9.Cu")
		(net "P5E_PEX1_STN7_RX_DP<115>")
	)
	(segment
		(start 136.642856 -322.884038)
		(end 136.633712 -322.849748)
		(width 0.1651)
		(layer "In9.Cu")
		(net "P5E_PEX1_STN7_RX_DP<115>")
	)
	(segment
		(start 153.6192 -304.449734)
		(end 153.89987 -304.449734)
		(width 0.1143)
		(layer "In9.Cu")
		(net "P5E_PEX1_STN7_RX_DP<115>")
	)
	(segment
		(start 164.842444 -392.958066)
		(end 159.581596 -390.777476)
		(width 0.1651)
		(layer "In9.Cu")
		(net "P5E_PEX1_STN7_RX_DP<115>")
	)
	(segment
		(start 151.839168 -303.879504)
		(end 153.280872 -303.879504)
		(width 0.1143)
		(layer "In9.Cu")
		(net "P5E_PEX1_STN7_RX_DP<115>")
	)
	(segment
		(start 153.524712 -304.123344)
		(end 153.524712 -304.355246)
		(width 0.1143)
		(layer "In9.Cu")
		(net "P5E_PEX1_STN7_RX_DP<115>")
	)
	(segment
		(start 167.39235 -395.507972)
		(end 164.842444 -392.958066)
		(width 0.1651)
		(layer "In9.Cu")
		(net "P5E_PEX1_STN7_RX_DP<115>")
	)
	(segment
		(start 136.64311 -322.885562)
		(end 136.642856 -322.884546)
		(width 0.1651)
		(layer "In9.Cu")
		(net "P5E_PEX1_STN7_RX_DP<115>")
	)
	(segment
		(start 147.72132 -341.436198)
		(end 142.349728 -332.744826)
		(width 0.1651)
		(layer "In9.Cu")
		(net "P5E_PEX1_STN7_RX_DP<115>")
	)
	(segment
		(start 136.940798 -323.992748)
		(end 136.643364 -322.885562)
		(width 0.1651)
		(layer "In9.Cu")
		(net "P5E_PEX1_STN7_RX_DP<115>")
	)
	(segment
		(start 136.633712 -318.723264)
		(end 140.807694 -309.313072)
		(width 0.1651)
		(layer "In9.Cu")
		(net "P5E_PEX1_STN7_RX_DP<115>")
	)
	(segment
		(start 167.39235 -409.265374)
		(end 167.39235 -395.507972)
		(width 0.1651)
		(layer "In9.Cu")
		(net "P5E_PEX1_STN7_RX_DP<115>")
	)
	(segment
		(start 151.793448 -303.833784)
		(end 151.839168 -303.879504)
		(width 0.1143)
		(layer "In9.Cu")
		(net "P5E_PEX1_STN7_RX_DP<115>")
	)
	(segment
		(start 140.807694 -309.313072)
		(end 145.0721 -305.048666)
		(width 0.1651)
		(layer "In9.Cu")
		(net "P5E_PEX1_STN7_RX_DP<115>")
	)
	(segment
		(start 154.395932 -384.942842)
		(end 149.004782 -345.01963)
		(width 0.1651)
		(layer "In9.Cu")
		(net "P5E_PEX1_STN7_RX_DP<115>")
	)
	(segment
		(start 140.137388 -357.46309)
		(end 140.137388 -356.831646)
		(width 0.13462)
		(layer "F.Cu")
		(net "P5E_PEX1_STN5_TX_C_DP<86>")
	)
	(segment
		(start 139.842748 -357.75773)
		(end 140.137388 -357.46309)
		(width 0.13462)
		(layer "F.Cu")
		(net "P5E_PEX1_STN5_TX_C_DP<86>")
	)
	(segment
		(start 140.137388 -356.831646)
		(end 139.817348 -356.511606)
		(width 0.13462)
		(layer "F.Cu")
		(net "P5E_PEX1_STN5_TX_C_DP<86>")
	)
	(segment
		(start 140.728192 -362.284264)
		(end 140.788136 -362.194602)
		(width 0.1651)
		(layer "In7.Cu")
		(net "P5E_PEX1_STN5_TX_C_DP<86>")
	)
	(segment
		(start 142.088108 -368.728752)
		(end 141.360906 -365.072422)
		(width 0.1651)
		(layer "In7.Cu")
		(net "P5E_PEX1_STN5_TX_C_DP<86>")
	)
	(segment
		(start 141.23416 -364.436914)
		(end 141.13764 -363.951266)
		(width 0.1651)
		(layer "In7.Cu")
		(net "P5E_PEX1_STN5_TX_C_DP<86>")
	)
	(segment
		(start 140.824712 -362.770166)
		(end 140.728192 -362.284264)
		(width 0.1651)
		(layer "In7.Cu")
		(net "P5E_PEX1_STN5_TX_C_DP<86>")
	)
	(segment
		(start 132.006848 -393.661138)
		(end 137.75436 -391.239756)
		(width 0.1651)
		(layer "In7.Cu")
		(net "P5E_PEX1_STN5_TX_C_DP<86>")
	)
	(segment
		(start 141.13764 -363.951266)
		(end 141.047724 -363.891322)
		(width 0.1651)
		(layer "In7.Cu")
		(net "P5E_PEX1_STN5_TX_C_DP<86>")
	)
	(segment
		(start 129.469134 -404.798784)
		(end 129.887472 -404.380446)
		(width 0.1651)
		(layer "In7.Cu")
		(net "P5E_PEX1_STN5_TX_C_DP<86>")
	)
	(segment
		(start 141.04366 -387.97865)
		(end 141.50975 -386.438648)
		(width 0.1651)
		(layer "In7.Cu")
		(net "P5E_PEX1_STN5_TX_C_DP<86>")
	)
	(segment
		(start 140.133578 -358.903778)
		(end 140.133578 -358.04856)
		(width 0.1651)
		(layer "In7.Cu")
		(net "P5E_PEX1_STN5_TX_C_DP<86>")
	)
	(segment
		(start 141.50975 -386.438648)
		(end 141.7574 -383.95148)
		(width 0.1651)
		(layer "In7.Cu")
		(net "P5E_PEX1_STN5_TX_C_DP<86>")
	)
	(segment
		(start 129.109978 -404.290022)
		(end 129.109978 -404.671784)
		(width 0.1651)
		(layer "In7.Cu")
		(net "P5E_PEX1_STN5_TX_C_DP<86>")
	)
	(segment
		(start 141.047724 -363.891322)
		(end 140.951204 -363.40542)
		(width 0.1651)
		(layer "In7.Cu")
		(net "P5E_PEX1_STN5_TX_C_DP<86>")
	)
	(segment
		(start 141.7574 -383.95148)
		(end 141.7574 -383.24155)
		(width 0.1651)
		(layer "In7.Cu")
		(net "P5E_PEX1_STN5_TX_C_DP<86>")
	)
	(segment
		(start 140.50518 -361.163108)
		(end 140.565124 -361.073446)
		(width 0.1651)
		(layer "In7.Cu")
		(net "P5E_PEX1_STN5_TX_C_DP<86>")
	)
	(segment
		(start 129.109978 -404.671784)
		(end 129.236978 -404.798784)
		(width 0.1651)
		(layer "In7.Cu")
		(net "P5E_PEX1_STN5_TX_C_DP<86>")
	)
	(segment
		(start 129.887472 -404.380446)
		(end 129.887472 -396.2654)
		(width 0.1651)
		(layer "In7.Cu")
		(net "P5E_PEX1_STN5_TX_C_DP<86>")
	)
	(segment
		(start 140.565124 -361.073446)
		(end 140.133578 -358.903778)
		(width 0.1651)
		(layer "In7.Cu")
		(net "P5E_PEX1_STN5_TX_C_DP<86>")
	)
	(segment
		(start 140.133578 -358.04856)
		(end 139.842748 -357.75773)
		(width 0.1651)
		(layer "In7.Cu")
		(net "P5E_PEX1_STN5_TX_C_DP<86>")
	)
	(segment
		(start 140.914628 -362.83011)
		(end 140.824712 -362.770166)
		(width 0.1651)
		(layer "In7.Cu")
		(net "P5E_PEX1_STN5_TX_C_DP<86>")
	)
	(segment
		(start 130.4036 -394.7414)
		(end 132.006848 -393.661138)
		(width 0.1651)
		(layer "In7.Cu")
		(net "P5E_PEX1_STN5_TX_C_DP<86>")
	)
	(segment
		(start 141.360906 -365.072422)
		(end 141.27099 -365.012732)
		(width 0.1651)
		(layer "In7.Cu")
		(net "P5E_PEX1_STN5_TX_C_DP<86>")
	)
	(segment
		(start 141.27099 -365.012732)
		(end 141.17447 -364.526576)
		(width 0.1651)
		(layer "In7.Cu")
		(net "P5E_PEX1_STN5_TX_C_DP<86>")
	)
	(segment
		(start 129.887472 -396.2654)
		(end 130.4036 -394.7414)
		(width 0.1651)
		(layer "In7.Cu")
		(net "P5E_PEX1_STN5_TX_C_DP<86>")
	)
	(segment
		(start 140.691616 -361.708954)
		(end 140.6017 -361.64901)
		(width 0.1651)
		(layer "In7.Cu")
		(net "P5E_PEX1_STN5_TX_C_DP<86>")
	)
	(segment
		(start 129.236978 -404.798784)
		(end 129.469134 -404.798784)
		(width 0.1651)
		(layer "In7.Cu")
		(net "P5E_PEX1_STN5_TX_C_DP<86>")
	)
	(segment
		(start 140.788136 -362.194602)
		(end 140.691616 -361.708954)
		(width 0.1651)
		(layer "In7.Cu")
		(net "P5E_PEX1_STN5_TX_C_DP<86>")
	)
	(segment
		(start 141.011148 -363.315758)
		(end 140.914628 -362.83011)
		(width 0.1651)
		(layer "In7.Cu")
		(net "P5E_PEX1_STN5_TX_C_DP<86>")
	)
	(segment
		(start 141.17447 -364.526576)
		(end 141.23416 -364.436914)
		(width 0.1651)
		(layer "In7.Cu")
		(net "P5E_PEX1_STN5_TX_C_DP<86>")
	)
	(segment
		(start 142.088108 -369.853718)
		(end 142.088108 -368.728752)
		(width 0.1651)
		(layer "In7.Cu")
		(net "P5E_PEX1_STN5_TX_C_DP<86>")
	)
	(segment
		(start 137.75436 -391.239756)
		(end 138.62685 -390.735058)
		(width 0.1651)
		(layer "In7.Cu")
		(net "P5E_PEX1_STN5_TX_C_DP<86>")
	)
	(segment
		(start 141.7574 -383.24155)
		(end 142.088108 -369.853718)
		(width 0.1651)
		(layer "In7.Cu")
		(net "P5E_PEX1_STN5_TX_C_DP<86>")
	)
	(segment
		(start 140.6017 -361.64901)
		(end 140.50518 -361.163108)
		(width 0.1651)
		(layer "In7.Cu")
		(net "P5E_PEX1_STN5_TX_C_DP<86>")
	)
	(segment
		(start 140.346938 -389.305038)
		(end 141.04366 -387.97865)
		(width 0.1651)
		(layer "In7.Cu")
		(net "P5E_PEX1_STN5_TX_C_DP<86>")
	)
	(segment
		(start 138.62685 -390.735058)
		(end 140.346938 -389.305038)
		(width 0.1651)
		(layer "In7.Cu")
		(net "P5E_PEX1_STN5_TX_C_DP<86>")
	)
	(segment
		(start 140.951204 -363.40542)
		(end 141.011148 -363.315758)
		(width 0.1651)
		(layer "In7.Cu")
		(net "P5E_PEX1_STN5_TX_C_DP<86>")
	)
	(segment
		(start 36.051744 -119.793258)
		(end 35.4203 -119.793258)
		(width 0.13462)
		(layer "F.Cu")
		(net "P5E_PEX0_STN1_TX_DN<24>")
	)
	(segment
		(start 36.371784 -120.113298)
		(end 36.051744 -119.793258)
		(width 0.13462)
		(layer "F.Cu")
		(net "P5E_PEX0_STN1_TX_DN<24>")
	)
	(segment
		(start 35.4203 -119.793258)
		(end 35.12566 -120.087898)
		(width 0.13462)
		(layer "F.Cu")
		(net "P5E_PEX0_STN1_TX_DN<24>")
	)
	(segment
		(start 33.288478 -120.868694)
		(end 33.629854 -120.527318)
		(width 0.1651)
		(layer "In9.Cu")
		(net "P5E_PEX0_STN1_TX_DN<24>")
	)
	(segment
		(start 30.738572 -125.864366)
		(end 30.738318 -125.864366)
		(width 0.1651)
		(layer "In9.Cu")
		(net "P5E_PEX0_STN1_TX_DN<24>")
	)
	(segment
		(start 66.915792 -271.500346)
		(end 66.915792 -271.471898)
		(width 0.1143)
		(layer "In9.Cu")
		(net "P5E_PEX0_STN1_TX_DN<24>")
	)
	(segment
		(start 31.000954 -125.230636)
		(end 31.185612 -124.784866)
		(width 0.1651)
		(layer "In9.Cu")
		(net "P5E_PEX0_STN1_TX_DN<24>")
	)
	(segment
		(start 29.39669 -129.103374)
		(end 29.529786 -129.04851)
		(width 0.1651)
		(layer "In9.Cu")
		(net "P5E_PEX0_STN1_TX_DN<24>")
	)
	(segment
		(start 29.529786 -129.04851)
		(end 29.714444 -128.602232)
		(width 0.1651)
		(layer "In9.Cu")
		(net "P5E_PEX0_STN1_TX_DN<24>")
	)
	(segment
		(start 31.056072 -125.363224)
		(end 31.000954 -125.230636)
		(width 0.1651)
		(layer "In9.Cu")
		(net "P5E_PEX0_STN1_TX_DN<24>")
	)
	(segment
		(start 34.19856 -119.797068)
		(end 34.83483 -119.797068)
		(width 0.1651)
		(layer "In9.Cu")
		(net "P5E_PEX0_STN1_TX_DN<24>")
	)
	(segment
		(start 29.843984 -128.02362)
		(end 29.97708 -127.968756)
		(width 0.1651)
		(layer "In9.Cu")
		(net "P5E_PEX0_STN1_TX_DN<24>")
	)
	(segment
		(start 32.212788 -122.571002)
		(end 32.397446 -122.124724)
		(width 0.1651)
		(layer "In9.Cu")
		(net "P5E_PEX0_STN1_TX_DN<24>")
	)
	(segment
		(start 31.632652 -123.705366)
		(end 31.765748 -123.650502)
		(width 0.1651)
		(layer "In9.Cu")
		(net "P5E_PEX0_STN1_TX_DN<24>")
	)
	(segment
		(start 32.397446 -122.124724)
		(end 32.342582 -121.992136)
		(width 0.1651)
		(layer "In9.Cu")
		(net "P5E_PEX0_STN1_TX_DN<24>")
	)
	(segment
		(start 33.629854 -120.365774)
		(end 34.19856 -119.797068)
		(width 0.1651)
		(layer "In9.Cu")
		(net "P5E_PEX0_STN1_TX_DN<24>")
	)
	(segment
		(start 67.249548 -278.115268)
		(end 67.135248 -278.229568)
		(width 0.1143)
		(layer "In9.Cu")
		(net "P5E_PEX0_STN1_TX_DN<24>")
	)
	(segment
		(start 29.244544 -129.737104)
		(end 29.189426 -129.604516)
		(width 0.1651)
		(layer "In9.Cu")
		(net "P5E_PEX0_STN1_TX_DN<24>")
	)
	(segment
		(start 31.185612 -124.784866)
		(end 31.318708 -124.730002)
		(width 0.1651)
		(layer "In9.Cu")
		(net "P5E_PEX0_STN1_TX_DN<24>")
	)
	(segment
		(start 31.765748 -123.650502)
		(end 31.950406 -123.204224)
		(width 0.1651)
		(layer "In9.Cu")
		(net "P5E_PEX0_STN1_TX_DN<24>")
	)
	(segment
		(start 31.503366 -124.283724)
		(end 31.448248 -124.151136)
		(width 0.1651)
		(layer "In9.Cu")
		(net "P5E_PEX0_STN1_TX_DN<24>")
	)
	(segment
		(start 30.553914 -126.310136)
		(end 30.738572 -125.864366)
		(width 0.1651)
		(layer "In9.Cu")
		(net "P5E_PEX0_STN1_TX_DN<24>")
	)
	(segment
		(start 31.632906 -123.705366)
		(end 31.632652 -123.705366)
		(width 0.1651)
		(layer "In9.Cu")
		(net "P5E_PEX0_STN1_TX_DN<24>")
	)
	(segment
		(start 66.915792 -264.235184)
		(end 32.094932 -161.3662)
		(width 0.1651)
		(layer "In9.Cu")
		(net "P5E_PEX0_STN1_TX_DN<24>")
	)
	(segment
		(start 28.229052 -131.92252)
		(end 28.92679 -130.238246)
		(width 0.1651)
		(layer "In9.Cu")
		(net "P5E_PEX0_STN1_TX_DN<24>")
	)
	(segment
		(start 30.10662 -127.38989)
		(end 30.291278 -126.94412)
		(width 0.1651)
		(layer "In9.Cu")
		(net "P5E_PEX0_STN1_TX_DN<24>")
	)
	(segment
		(start 31.448248 -124.151136)
		(end 31.632906 -123.705366)
		(width 0.1651)
		(layer "In9.Cu")
		(net "P5E_PEX0_STN1_TX_DN<24>")
	)
	(segment
		(start 31.51632 -158.457646)
		(end 31.15183 -151.045672)
		(width 0.1651)
		(layer "In9.Cu")
		(net "P5E_PEX0_STN1_TX_DN<24>")
	)
	(segment
		(start 32.342582 -121.992136)
		(end 32.582104 -121.413524)
		(width 0.1651)
		(layer "In9.Cu")
		(net "P5E_PEX0_STN1_TX_DN<24>")
	)
	(segment
		(start 30.291278 -126.94412)
		(end 30.291278 -126.943866)
		(width 0.1651)
		(layer "In9.Cu")
		(net "P5E_PEX0_STN1_TX_DN<24>")
	)
	(segment
		(start 31.318708 -124.730002)
		(end 31.503366 -124.283724)
		(width 0.1651)
		(layer "In9.Cu")
		(net "P5E_PEX0_STN1_TX_DN<24>")
	)
	(segment
		(start 32.094932 -161.3662)
		(end 31.51632 -158.457646)
		(width 0.1651)
		(layer "In9.Cu")
		(net "P5E_PEX0_STN1_TX_DN<24>")
	)
	(segment
		(start 29.059632 -130.183382)
		(end 29.244544 -129.737104)
		(width 0.1651)
		(layer "In9.Cu")
		(net "P5E_PEX0_STN1_TX_DN<24>")
	)
	(segment
		(start 30.424374 -126.889002)
		(end 30.609032 -126.442724)
		(width 0.1651)
		(layer "In9.Cu")
		(net "P5E_PEX0_STN1_TX_DN<24>")
	)
	(segment
		(start 31.15183 -151.045672)
		(end 30.784038 -143.564356)
		(width 0.1651)
		(layer "In9.Cu")
		(net "P5E_PEX0_STN1_TX_DN<24>")
	)
	(segment
		(start 29.97708 -127.968756)
		(end 30.161738 -127.522478)
		(width 0.1651)
		(layer "In9.Cu")
		(net "P5E_PEX0_STN1_TX_DN<24>")
	)
	(segment
		(start 30.291278 -126.943866)
		(end 30.424374 -126.889002)
		(width 0.1651)
		(layer "In9.Cu")
		(net "P5E_PEX0_STN1_TX_DN<24>")
	)
	(segment
		(start 33.126934 -120.868694)
		(end 33.288478 -120.868694)
		(width 0.1651)
		(layer "In9.Cu")
		(net "P5E_PEX0_STN1_TX_DN<24>")
	)
	(segment
		(start 29.843984 -128.023874)
		(end 29.843984 -128.02362)
		(width 0.1651)
		(layer "In9.Cu")
		(net "P5E_PEX0_STN1_TX_DN<24>")
	)
	(segment
		(start 66.97345 -278.229568)
		(end 66.870072 -278.12619)
		(width 0.1143)
		(layer "In9.Cu")
		(net "P5E_PEX0_STN1_TX_DN<24>")
	)
	(segment
		(start 29.189426 -129.604516)
		(end 29.396944 -129.103374)
		(width 0.1651)
		(layer "In9.Cu")
		(net "P5E_PEX0_STN1_TX_DN<24>")
	)
	(segment
		(start 33.629854 -120.527318)
		(end 33.629854 -120.365774)
		(width 0.1651)
		(layer "In9.Cu")
		(net "P5E_PEX0_STN1_TX_DN<24>")
	)
	(segment
		(start 31.950406 -123.204224)
		(end 31.895288 -123.071636)
		(width 0.1651)
		(layer "In9.Cu")
		(net "P5E_PEX0_STN1_TX_DN<24>")
	)
	(segment
		(start 30.161738 -127.522478)
		(end 30.10662 -127.38989)
		(width 0.1651)
		(layer "In9.Cu")
		(net "P5E_PEX0_STN1_TX_DN<24>")
	)
	(segment
		(start 30.609032 -126.442724)
		(end 30.553914 -126.310136)
		(width 0.1651)
		(layer "In9.Cu")
		(net "P5E_PEX0_STN1_TX_DN<24>")
	)
	(segment
		(start 34.83483 -119.797068)
		(end 35.12566 -120.087898)
		(width 0.1651)
		(layer "In9.Cu")
		(net "P5E_PEX0_STN1_TX_DN<24>")
	)
	(segment
		(start 28.229052 -137.396474)
		(end 28.229052 -131.92252)
		(width 0.1651)
		(layer "In9.Cu")
		(net "P5E_PEX0_STN1_TX_DN<24>")
	)
	(segment
		(start 66.870072 -278.12619)
		(end 66.870072 -271.546066)
		(width 0.1143)
		(layer "In9.Cu")
		(net "P5E_PEX0_STN1_TX_DN<24>")
	)
	(segment
		(start 30.738318 -125.864366)
		(end 30.871414 -125.809502)
		(width 0.1651)
		(layer "In9.Cu")
		(net "P5E_PEX0_STN1_TX_DN<24>")
	)
	(segment
		(start 30.784038 -143.564356)
		(end 28.229052 -137.396474)
		(width 0.1651)
		(layer "In9.Cu")
		(net "P5E_PEX0_STN1_TX_DN<24>")
	)
	(segment
		(start 30.871414 -125.809502)
		(end 31.056072 -125.363224)
		(width 0.1651)
		(layer "In9.Cu")
		(net "P5E_PEX0_STN1_TX_DN<24>")
	)
	(segment
		(start 67.249548 -277.849838)
		(end 67.249548 -278.115268)
		(width 0.1143)
		(layer "In9.Cu")
		(net "P5E_PEX0_STN1_TX_DN<24>")
	)
	(segment
		(start 66.870072 -271.546066)
		(end 66.915792 -271.500346)
		(width 0.1143)
		(layer "In9.Cu")
		(net "P5E_PEX0_STN1_TX_DN<24>")
	)
	(segment
		(start 32.079946 -122.625866)
		(end 32.212788 -122.571002)
		(width 0.1651)
		(layer "In9.Cu")
		(net "P5E_PEX0_STN1_TX_DN<24>")
	)
	(segment
		(start 31.895288 -123.071636)
		(end 32.079946 -122.625866)
		(width 0.1651)
		(layer "In9.Cu")
		(net "P5E_PEX0_STN1_TX_DN<24>")
	)
	(segment
		(start 29.396944 -129.103374)
		(end 29.39669 -129.103374)
		(width 0.1651)
		(layer "In9.Cu")
		(net "P5E_PEX0_STN1_TX_DN<24>")
	)
	(segment
		(start 29.659326 -128.469644)
		(end 29.843984 -128.023874)
		(width 0.1651)
		(layer "In9.Cu")
		(net "P5E_PEX0_STN1_TX_DN<24>")
	)
	(segment
		(start 32.582104 -121.413524)
		(end 33.126934 -120.868694)
		(width 0.1651)
		(layer "In9.Cu")
		(net "P5E_PEX0_STN1_TX_DN<24>")
	)
	(segment
		(start 67.135248 -278.229568)
		(end 66.97345 -278.229568)
		(width 0.1143)
		(layer "In9.Cu")
		(net "P5E_PEX0_STN1_TX_DN<24>")
	)
	(segment
		(start 29.714444 -128.602232)
		(end 29.659326 -128.469644)
		(width 0.1651)
		(layer "In9.Cu")
		(net "P5E_PEX0_STN1_TX_DN<24>")
	)
	(segment
		(start 28.92679 -130.238246)
		(end 29.059632 -130.183382)
		(width 0.1651)
		(layer "In9.Cu")
		(net "P5E_PEX0_STN1_TX_DN<24>")
	)
	(segment
		(start 66.915792 -271.471898)
		(end 66.915792 -264.235184)
		(width 0.1651)
		(layer "In9.Cu")
		(net "P5E_PEX0_STN1_TX_DN<24>")
	)
	(segment
		(start 35.766248 -355.978206)
		(end 35.446208 -355.658166)
		(width 0.13462)
		(layer "F.Cu")
		(net "P5E_PEX0_STN7_TX_DN<120>")
	)
	(segment
		(start 35.446208 -355.026722)
		(end 35.740848 -354.732082)
		(width 0.13462)
		(layer "F.Cu")
		(net "P5E_PEX0_STN7_TX_DN<120>")
	)
	(segment
		(start 35.446208 -355.658166)
		(end 35.446208 -355.026722)
		(width 0.13462)
		(layer "F.Cu")
		(net "P5E_PEX0_STN7_TX_DN<120>")
	)
	(segment
		(start 28.182316 -315.632084)
		(end 28.56611 -315.24829)
		(width 0.1651)
		(layer "In7.Cu")
		(net "P5E_PEX0_STN7_TX_DN<120>")
	)
	(segment
		(start 26.675334 -325.135494)
		(end 26.40711 -324.73392)
		(width 0.1651)
		(layer "In7.Cu")
		(net "P5E_PEX0_STN7_TX_DN<120>")
	)
	(segment
		(start 37.004498 -352.387662)
		(end 37.004498 -342.059768)
		(width 0.1651)
		(layer "In7.Cu")
		(net "P5E_PEX0_STN7_TX_DN<120>")
	)
	(segment
		(start 26.40711 -324.73392)
		(end 26.251916 -324.703186)
		(width 0.1651)
		(layer "In7.Cu")
		(net "P5E_PEX0_STN7_TX_DN<120>")
	)
	(segment
		(start 26.6446 -325.290434)
		(end 26.675334 -325.135494)
		(width 0.1651)
		(layer "In7.Cu")
		(net "P5E_PEX0_STN7_TX_DN<120>")
	)
	(segment
		(start 27.06751 -325.722488)
		(end 26.91257 -325.6915)
		(width 0.1651)
		(layer "In7.Cu")
		(net "P5E_PEX0_STN7_TX_DN<120>")
	)
	(segment
		(start 35.450018 -354.441252)
		(end 35.450018 -353.942142)
		(width 0.1651)
		(layer "In7.Cu")
		(net "P5E_PEX0_STN7_TX_DN<120>")
	)
	(segment
		(start 26.251916 -324.703186)
		(end 25.517348 -323.60362)
		(width 0.1651)
		(layer "In7.Cu")
		(net "P5E_PEX0_STN7_TX_DN<120>")
	)
	(segment
		(start 27.226006 -316.47257)
		(end 27.36723 -316.47257)
		(width 0.1651)
		(layer "In7.Cu")
		(net "P5E_PEX0_STN7_TX_DN<120>")
	)
	(segment
		(start 28.066492 -315.632084)
		(end 28.182316 -315.632084)
		(width 0.1651)
		(layer "In7.Cu")
		(net "P5E_PEX0_STN7_TX_DN<120>")
	)
	(segment
		(start 26.91257 -325.6915)
		(end 26.6446 -325.290434)
		(width 0.1651)
		(layer "In7.Cu")
		(net "P5E_PEX0_STN7_TX_DN<120>")
	)
	(segment
		(start 35.450018 -353.942142)
		(end 37.004498 -352.387662)
		(width 0.1651)
		(layer "In7.Cu")
		(net "P5E_PEX0_STN7_TX_DN<120>")
	)
	(segment
		(start 28.56611 -315.24829)
		(end 28.56611 -315.132466)
		(width 0.1651)
		(layer "In7.Cu")
		(net "P5E_PEX0_STN7_TX_DN<120>")
	)
	(segment
		(start 41.979596 -308.934358)
		(end 41.979596 -309.085488)
		(width 0.1143)
		(layer "In7.Cu")
		(net "P5E_PEX0_STN7_TX_DN<120>")
	)
	(segment
		(start 37.004498 -342.059768)
		(end 35.625786 -338.731352)
		(width 0.1651)
		(layer "In7.Cu")
		(net "P5E_PEX0_STN7_TX_DN<120>")
	)
	(segment
		(start 27.335988 -326.123808)
		(end 27.06751 -325.722488)
		(width 0.1651)
		(layer "In7.Cu")
		(net "P5E_PEX0_STN7_TX_DN<120>")
	)
	(segment
		(start 24.817324 -321.91325)
		(end 24.817324 -320.423286)
		(width 0.1651)
		(layer "In7.Cu")
		(net "P5E_PEX0_STN7_TX_DN<120>")
	)
	(segment
		(start 28.56611 -315.132466)
		(end 34.754058 -308.944518)
		(width 0.1651)
		(layer "In7.Cu")
		(net "P5E_PEX0_STN7_TX_DN<120>")
	)
	(segment
		(start 25.02027 -319.403476)
		(end 25.355042 -318.595248)
		(width 0.1651)
		(layer "In7.Cu")
		(net "P5E_PEX0_STN7_TX_DN<120>")
	)
	(segment
		(start 34.754058 -308.944518)
		(end 34.94405 -308.865778)
		(width 0.1651)
		(layer "In7.Cu")
		(net "P5E_PEX0_STN7_TX_DN<120>")
	)
	(segment
		(start 41.979596 -309.085488)
		(end 41.865296 -309.199788)
		(width 0.1143)
		(layer "In7.Cu")
		(net "P5E_PEX0_STN7_TX_DN<120>")
	)
	(segment
		(start 35.683952 -308.865778)
		(end 35.7124 -308.865778)
		(width 0.1143)
		(layer "In7.Cu")
		(net "P5E_PEX0_STN7_TX_DN<120>")
	)
	(segment
		(start 35.740848 -354.732082)
		(end 35.450018 -354.441252)
		(width 0.1651)
		(layer "In7.Cu")
		(net "P5E_PEX0_STN7_TX_DN<120>")
	)
	(segment
		(start 35.7124 -308.865778)
		(end 35.75812 -308.820058)
		(width 0.1143)
		(layer "In7.Cu")
		(net "P5E_PEX0_STN7_TX_DN<120>")
	)
	(segment
		(start 27.36723 -316.47257)
		(end 27.72537 -316.11443)
		(width 0.1651)
		(layer "In7.Cu")
		(net "P5E_PEX0_STN7_TX_DN<120>")
	)
	(segment
		(start 24.817324 -320.423286)
		(end 25.02027 -319.403476)
		(width 0.1651)
		(layer "In7.Cu")
		(net "P5E_PEX0_STN7_TX_DN<120>")
	)
	(segment
		(start 27.72537 -315.973206)
		(end 28.066492 -315.632084)
		(width 0.1651)
		(layer "In7.Cu")
		(net "P5E_PEX0_STN7_TX_DN<120>")
	)
	(segment
		(start 35.625786 -338.731352)
		(end 27.305254 -326.279002)
		(width 0.1651)
		(layer "In7.Cu")
		(net "P5E_PEX0_STN7_TX_DN<120>")
	)
	(segment
		(start 41.865296 -309.199788)
		(end 41.599866 -309.199788)
		(width 0.1143)
		(layer "In7.Cu")
		(net "P5E_PEX0_STN7_TX_DN<120>")
	)
	(segment
		(start 25.517348 -323.60362)
		(end 24.817324 -321.91325)
		(width 0.1651)
		(layer "In7.Cu")
		(net "P5E_PEX0_STN7_TX_DN<120>")
	)
	(segment
		(start 34.94405 -308.865778)
		(end 35.683952 -308.865778)
		(width 0.1651)
		(layer "In7.Cu")
		(net "P5E_PEX0_STN7_TX_DN<120>")
	)
	(segment
		(start 25.355042 -318.595248)
		(end 25.862026 -317.83655)
		(width 0.1651)
		(layer "In7.Cu")
		(net "P5E_PEX0_STN7_TX_DN<120>")
	)
	(segment
		(start 27.72537 -316.11443)
		(end 27.72537 -315.973206)
		(width 0.1651)
		(layer "In7.Cu")
		(net "P5E_PEX0_STN7_TX_DN<120>")
	)
	(segment
		(start 25.862026 -317.83655)
		(end 27.226006 -316.47257)
		(width 0.1651)
		(layer "In7.Cu")
		(net "P5E_PEX0_STN7_TX_DN<120>")
	)
	(segment
		(start 41.865296 -308.820058)
		(end 41.979596 -308.934358)
		(width 0.1143)
		(layer "In7.Cu")
		(net "P5E_PEX0_STN7_TX_DN<120>")
	)
	(segment
		(start 27.305254 -326.279002)
		(end 27.335988 -326.123808)
		(width 0.1651)
		(layer "In7.Cu")
		(net "P5E_PEX0_STN7_TX_DN<120>")
	)
	(segment
		(start 35.75812 -308.820058)
		(end 41.865296 -308.820058)
		(width 0.1143)
		(layer "In7.Cu")
		(net "P5E_PEX0_STN7_TX_DN<120>")
	)
	(segment
		(start 199.34809 -124.396754)
		(end 199.979534 -124.396754)
		(width 0.13462)
		(layer "F.Cu")
		(net "P5E_PEX1_STN0_TX_DN<3>")
	)
	(segment
		(start 199.02805 -124.076714)
		(end 199.34809 -124.396754)
		(width 0.13462)
		(layer "F.Cu")
		(net "P5E_PEX1_STN0_TX_DN<3>")
	)
	(segment
		(start 199.979534 -124.396754)
		(end 200.274174 -124.102114)
		(width 0.13462)
		(layer "F.Cu")
		(net "P5E_PEX1_STN0_TX_DN<3>")
	)
	(segment
		(start 213.692232 -270.102838)
		(end 213.883748 -272.302224)
		(width 0.1651)
		(layer "In9.Cu")
		(net "P5E_PEX1_STN0_TX_DN<3>")
	)
	(segment
		(start 200.565004 -124.392944)
		(end 201.227436 -124.392944)
		(width 0.1651)
		(layer "In9.Cu")
		(net "P5E_PEX1_STN0_TX_DN<3>")
	)
	(segment
		(start 201.227436 -124.392944)
		(end 201.562462 -124.72797)
		(width 0.1651)
		(layer "In9.Cu")
		(net "P5E_PEX1_STN0_TX_DN<3>")
	)
	(segment
		(start 213.502748 -267.928344)
		(end 213.692232 -270.102838)
		(width 0.1651)
		(layer "In9.Cu")
		(net "P5E_PEX1_STN0_TX_DN<3>")
	)
	(segment
		(start 203.572364 -178.830478)
		(end 199.827388 -221.628208)
		(width 0.1651)
		(layer "In9.Cu")
		(net "P5E_PEX1_STN0_TX_DN<3>")
	)
	(segment
		(start 213.368382 -159.583628)
		(end 213.215474 -160.15589)
		(width 0.1651)
		(layer "In9.Cu")
		(net "P5E_PEX1_STN0_TX_DN<3>")
	)
	(segment
		(start 213.368382 -153.132536)
		(end 213.368382 -159.583628)
		(width 0.1651)
		(layer "In9.Cu")
		(net "P5E_PEX1_STN0_TX_DN<3>")
	)
	(segment
		(start 202.030584 -126.538228)
		(end 204.453744 -132.285486)
		(width 0.1651)
		(layer "In9.Cu")
		(net "P5E_PEX1_STN0_TX_DN<3>")
	)
	(segment
		(start 204.453744 -132.285486)
		(end 204.931518 -132.763514)
		(width 0.1651)
		(layer "In9.Cu")
		(net "P5E_PEX1_STN0_TX_DN<3>")
	)
	(segment
		(start 191.520064 -285.335472)
		(end 191.634364 -285.449772)
		(width 0.1143)
		(layer "In9.Cu")
		(net "P5E_PEX1_STN0_TX_DN<3>")
	)
	(segment
		(start 212.598762 -265.745722)
		(end 213.502748 -267.928344)
		(width 0.1651)
		(layer "In9.Cu")
		(net "P5E_PEX1_STN0_TX_DN<3>")
	)
	(segment
		(start 200.274174 -124.102114)
		(end 200.565004 -124.392944)
		(width 0.1651)
		(layer "In9.Cu")
		(net "P5E_PEX1_STN0_TX_DN<3>")
	)
	(segment
		(start 204.931518 -132.763514)
		(end 213.368382 -153.132536)
		(width 0.1651)
		(layer "In9.Cu")
		(net "P5E_PEX1_STN0_TX_DN<3>")
	)
	(segment
		(start 191.62395 -285.069788)
		(end 191.520064 -285.173674)
		(width 0.1143)
		(layer "In9.Cu")
		(net "P5E_PEX1_STN0_TX_DN<3>")
	)
	(segment
		(start 203.872592 -284.06344)
		(end 201.332846 -285.115508)
		(width 0.1651)
		(layer "In9.Cu")
		(net "P5E_PEX1_STN0_TX_DN<3>")
	)
	(segment
		(start 201.562462 -124.72797)
		(end 201.770742 -125.230636)
		(width 0.1651)
		(layer "In9.Cu")
		(net "P5E_PEX1_STN0_TX_DN<3>")
	)
	(segment
		(start 199.91959 -285.069788)
		(end 191.62395 -285.069788)
		(width 0.1143)
		(layer "In9.Cu")
		(net "P5E_PEX1_STN0_TX_DN<3>")
	)
	(segment
		(start 191.634364 -285.449772)
		(end 191.900048 -285.449772)
		(width 0.1143)
		(layer "In9.Cu")
		(net "P5E_PEX1_STN0_TX_DN<3>")
	)
	(segment
		(start 212.64626 -275.289772)
		(end 203.872592 -284.06344)
		(width 0.1651)
		(layer "In9.Cu")
		(net "P5E_PEX1_STN0_TX_DN<3>")
	)
	(segment
		(start 199.993758 -285.115508)
		(end 199.96531 -285.115508)
		(width 0.1143)
		(layer "In9.Cu")
		(net "P5E_PEX1_STN0_TX_DN<3>")
	)
	(segment
		(start 213.883748 -272.302224)
		(end 212.64626 -275.289772)
		(width 0.1651)
		(layer "In9.Cu")
		(net "P5E_PEX1_STN0_TX_DN<3>")
	)
	(segment
		(start 204.557376 -175.158908)
		(end 203.572364 -178.830478)
		(width 0.1651)
		(layer "In9.Cu")
		(net "P5E_PEX1_STN0_TX_DN<3>")
	)
	(segment
		(start 202.338432 -250.391168)
		(end 212.598762 -265.745722)
		(width 0.1651)
		(layer "In9.Cu")
		(net "P5E_PEX1_STN0_TX_DN<3>")
	)
	(segment
		(start 199.827388 -221.628208)
		(end 202.338432 -250.391168)
		(width 0.1651)
		(layer "In9.Cu")
		(net "P5E_PEX1_STN0_TX_DN<3>")
	)
	(segment
		(start 213.215474 -160.15589)
		(end 204.557376 -175.158908)
		(width 0.1651)
		(layer "In9.Cu")
		(net "P5E_PEX1_STN0_TX_DN<3>")
	)
	(segment
		(start 201.332846 -285.115508)
		(end 199.993758 -285.115508)
		(width 0.1651)
		(layer "In9.Cu")
		(net "P5E_PEX1_STN0_TX_DN<3>")
	)
	(segment
		(start 191.520064 -285.173674)
		(end 191.520064 -285.335472)
		(width 0.1143)
		(layer "In9.Cu")
		(net "P5E_PEX1_STN0_TX_DN<3>")
	)
	(segment
		(start 199.96531 -285.115508)
		(end 199.91959 -285.069788)
		(width 0.1143)
		(layer "In9.Cu")
		(net "P5E_PEX1_STN0_TX_DN<3>")
	)
	(segment
		(start 201.770742 -125.230636)
		(end 202.030584 -126.538228)
		(width 0.1651)
		(layer "In9.Cu")
		(net "P5E_PEX1_STN0_TX_DN<3>")
	)
	(segment
		(start 118.374668 -348.88043)
		(end 118.080028 -348.58579)
		(width 0.13462)
		(layer "F.Cu")
		(net "P5E_PEX1_STN6_TX_DP<100>")
	)
	(segment
		(start 118.374668 -349.511874)
		(end 118.374668 -348.88043)
		(width 0.13462)
		(layer "F.Cu")
		(net "P5E_PEX1_STN6_TX_DP<100>")
	)
	(segment
		(start 118.054628 -349.831914)
		(end 118.374668 -349.511874)
		(width 0.13462)
		(layer "F.Cu")
		(net "P5E_PEX1_STN6_TX_DP<100>")
	)
	(segment
		(start 119.925338 -340.780116)
		(end 121.031762 -339.673692)
		(width 0.1651)
		(layer "In7.Cu")
		(net "P5E_PEX1_STN6_TX_DP<100>")
	)
	(segment
		(start 169.479722 -319.92824)
		(end 169.479722 -313.605418)
		(width 0.1143)
		(layer "In7.Cu")
		(net "P5E_PEX1_STN6_TX_DP<100>")
	)
	(segment
		(start 169.479722 -313.605418)
		(end 169.705528 -313.379612)
		(width 0.1143)
		(layer "In7.Cu")
		(net "P5E_PEX1_STN6_TX_DP<100>")
	)
	(segment
		(start 169.705528 -313.379612)
		(end 169.935652 -313.379612)
		(width 0.1143)
		(layer "In7.Cu")
		(net "P5E_PEX1_STN6_TX_DP<100>")
	)
	(segment
		(start 121.031762 -339.673692)
		(end 131.259326 -333.543656)
		(width 0.1651)
		(layer "In7.Cu")
		(net "P5E_PEX1_STN6_TX_DP<100>")
	)
	(segment
		(start 140.107924 -330.859384)
		(end 166.653464 -322.80733)
		(width 0.1651)
		(layer "In7.Cu")
		(net "P5E_PEX1_STN6_TX_DP<100>")
	)
	(segment
		(start 131.259326 -333.543656)
		(end 140.107924 -330.859384)
		(width 0.1651)
		(layer "In7.Cu")
		(net "P5E_PEX1_STN6_TX_DP<100>")
	)
	(segment
		(start 166.653464 -322.80733)
		(end 168.008808 -321.995038)
		(width 0.1651)
		(layer "In7.Cu")
		(net "P5E_PEX1_STN6_TX_DP<100>")
	)
	(segment
		(start 169.434002 -320.1162)
		(end 169.434002 -320.002408)
		(width 0.1651)
		(layer "In7.Cu")
		(net "P5E_PEX1_STN6_TX_DP<100>")
	)
	(segment
		(start 169.935652 -313.379612)
		(end 170.049952 -313.265312)
		(width 0.1143)
		(layer "In7.Cu")
		(net "P5E_PEX1_STN6_TX_DP<100>")
	)
	(segment
		(start 118.370858 -347.620082)
		(end 119.925338 -346.065602)
		(width 0.1651)
		(layer "In7.Cu")
		(net "P5E_PEX1_STN6_TX_DP<100>")
	)
	(segment
		(start 170.049952 -313.265312)
		(end 170.049952 -312.999882)
		(width 0.1143)
		(layer "In7.Cu")
		(net "P5E_PEX1_STN6_TX_DP<100>")
	)
	(segment
		(start 168.008808 -321.995038)
		(end 169.1132 -320.890646)
		(width 0.1651)
		(layer "In7.Cu")
		(net "P5E_PEX1_STN6_TX_DP<100>")
	)
	(segment
		(start 169.434002 -320.002408)
		(end 169.434002 -319.97396)
		(width 0.1143)
		(layer "In7.Cu")
		(net "P5E_PEX1_STN6_TX_DP<100>")
	)
	(segment
		(start 169.434002 -319.97396)
		(end 169.479722 -319.92824)
		(width 0.1143)
		(layer "In7.Cu")
		(net "P5E_PEX1_STN6_TX_DP<100>")
	)
	(segment
		(start 118.080028 -348.58579)
		(end 118.370858 -348.29496)
		(width 0.1651)
		(layer "In7.Cu")
		(net "P5E_PEX1_STN6_TX_DP<100>")
	)
	(segment
		(start 169.1132 -320.890646)
		(end 169.434002 -320.1162)
		(width 0.1651)
		(layer "In7.Cu")
		(net "P5E_PEX1_STN6_TX_DP<100>")
	)
	(segment
		(start 118.370858 -348.29496)
		(end 118.370858 -347.620082)
		(width 0.1651)
		(layer "In7.Cu")
		(net "P5E_PEX1_STN6_TX_DP<100>")
	)
	(segment
		(start 119.925338 -346.065602)
		(end 119.925338 -340.780116)
		(width 0.1651)
		(layer "In7.Cu")
		(net "P5E_PEX1_STN6_TX_DP<100>")
	)
	(segment
		(start 127.687578 -397.30426)
		(end 127.6096 -397.226282)
		(width 0.1651)
		(layer "In5.Cu")
		(net "P5E_PEX1_STN5_RX_DP<85>")
	)
	(segment
		(start 127.747776 -395.840458)
		(end 127.676148 -395.708632)
		(width 0.1651)
		(layer "In5.Cu")
		(net "P5E_PEX1_STN5_RX_DP<85>")
	)
	(segment
		(start 148.376132 -366.88395)
		(end 153.399236 -353.627436)
		(width 0.1651)
		(layer "In5.Cu")
		(net "P5E_PEX1_STN5_RX_DP<85>")
	)
	(segment
		(start 133.242558 -392.199876)
		(end 137.596118 -391.332466)
		(width 0.1651)
		(layer "In5.Cu")
		(net "P5E_PEX1_STN5_RX_DP<85>")
	)
	(segment
		(start 127.687578 -396.59814)
		(end 127.687578 -396.044674)
		(width 0.1651)
		(layer "In5.Cu")
		(net "P5E_PEX1_STN5_RX_DP<85>")
	)
	(segment
		(start 179.205636 -318.129666)
		(end 179.43576 -318.129666)
		(width 0.1143)
		(layer "In5.Cu")
		(net "P5E_PEX1_STN5_RX_DP<85>")
	)
	(segment
		(start 127.676148 -395.708632)
		(end 127.815594 -395.234668)
		(width 0.1651)
		(layer "In5.Cu")
		(net "P5E_PEX1_STN5_RX_DP<85>")
	)
	(segment
		(start 179.55006 -318.015366)
		(end 179.55006 -317.749936)
		(width 0.1143)
		(layer "In5.Cu")
		(net "P5E_PEX1_STN5_RX_DP<85>")
	)
	(segment
		(start 160.551114 -339.345778)
		(end 162.421062 -337.254088)
		(width 0.1651)
		(layer "In5.Cu")
		(net "P5E_PEX1_STN5_RX_DP<85>")
	)
	(segment
		(start 147.263612 -370.858542)
		(end 148.376132 -366.88395)
		(width 0.1651)
		(layer "In5.Cu")
		(net "P5E_PEX1_STN5_RX_DP<85>")
	)
	(segment
		(start 126.910084 -397.972026)
		(end 127.037338 -398.09928)
		(width 0.1651)
		(layer "In5.Cu")
		(net "P5E_PEX1_STN5_RX_DP<85>")
	)
	(segment
		(start 178.97983 -319.837562)
		(end 178.97983 -318.355472)
		(width 0.1143)
		(layer "In5.Cu")
		(net "P5E_PEX1_STN5_RX_DP<85>")
	)
	(segment
		(start 128.027938 -394.892276)
		(end 128.597914 -394.377672)
		(width 0.1651)
		(layer "In5.Cu")
		(net "P5E_PEX1_STN5_RX_DP<85>")
	)
	(segment
		(start 127.947928 -395.16304)
		(end 128.027938 -394.892276)
		(width 0.1651)
		(layer "In5.Cu")
		(net "P5E_PEX1_STN5_RX_DP<85>")
	)
	(segment
		(start 176.398174 -328.611992)
		(end 177.715418 -327.294748)
		(width 0.1651)
		(layer "In5.Cu")
		(net "P5E_PEX1_STN5_RX_DP<85>")
	)
	(segment
		(start 126.910084 -397.59001)
		(end 126.910084 -397.972026)
		(width 0.1651)
		(layer "In5.Cu")
		(net "P5E_PEX1_STN5_RX_DP<85>")
	)
	(segment
		(start 127.6096 -396.676118)
		(end 127.687578 -396.59814)
		(width 0.1651)
		(layer "In5.Cu")
		(net "P5E_PEX1_STN5_RX_DP<85>")
	)
	(segment
		(start 175.325024 -329.685142)
		(end 176.356772 -328.653902)
		(width 0.1651)
		(layer "In5.Cu")
		(net "P5E_PEX1_STN5_RX_DP<85>")
	)
	(segment
		(start 177.715418 -327.294748)
		(end 178.386486 -325.781924)
		(width 0.1651)
		(layer "In5.Cu")
		(net "P5E_PEX1_STN5_RX_DP<85>")
	)
	(segment
		(start 176.398174 -328.6125)
		(end 176.398174 -328.611992)
		(width 0.1651)
		(layer "In5.Cu")
		(net "P5E_PEX1_STN5_RX_DP<85>")
	)
	(segment
		(start 127.687578 -397.881602)
		(end 127.687578 -397.30426)
		(width 0.1651)
		(layer "In5.Cu")
		(net "P5E_PEX1_STN5_RX_DP<85>")
	)
	(segment
		(start 178.97983 -318.355472)
		(end 179.205636 -318.129666)
		(width 0.1143)
		(layer "In5.Cu")
		(net "P5E_PEX1_STN5_RX_DP<85>")
	)
	(segment
		(start 140.94206 -387.894322)
		(end 147.263612 -370.858542)
		(width 0.1651)
		(layer "In5.Cu")
		(net "P5E_PEX1_STN5_RX_DP<85>")
	)
	(segment
		(start 153.399236 -353.627436)
		(end 160.551114 -339.345778)
		(width 0.1651)
		(layer "In5.Cu")
		(net "P5E_PEX1_STN5_RX_DP<85>")
	)
	(segment
		(start 162.421062 -337.254088)
		(end 175.325024 -329.685142)
		(width 0.1651)
		(layer "In5.Cu")
		(net "P5E_PEX1_STN5_RX_DP<85>")
	)
	(segment
		(start 127.037338 -398.09928)
		(end 127.4699 -398.09928)
		(width 0.1651)
		(layer "In5.Cu")
		(net "P5E_PEX1_STN5_RX_DP<85>")
	)
	(segment
		(start 179.43576 -318.129666)
		(end 179.55006 -318.015366)
		(width 0.1143)
		(layer "In5.Cu")
		(net "P5E_PEX1_STN5_RX_DP<85>")
	)
	(segment
		(start 178.93411 -319.91173)
		(end 178.93411 -319.883282)
		(width 0.1143)
		(layer "In5.Cu")
		(net "P5E_PEX1_STN5_RX_DP<85>")
	)
	(segment
		(start 127.4699 -398.09928)
		(end 127.687578 -397.881602)
		(width 0.1651)
		(layer "In5.Cu")
		(net "P5E_PEX1_STN5_RX_DP<85>")
	)
	(segment
		(start 130.232658 -393.374118)
		(end 133.242558 -392.199876)
		(width 0.1651)
		(layer "In5.Cu")
		(net "P5E_PEX1_STN5_RX_DP<85>")
	)
	(segment
		(start 139.833604 -389.755634)
		(end 140.94206 -387.894322)
		(width 0.1651)
		(layer "In5.Cu")
		(net "P5E_PEX1_STN5_RX_DP<85>")
	)
	(segment
		(start 127.6096 -397.226282)
		(end 127.6096 -396.676118)
		(width 0.1651)
		(layer "In5.Cu")
		(net "P5E_PEX1_STN5_RX_DP<85>")
	)
	(segment
		(start 137.596118 -391.332466)
		(end 139.833604 -389.755634)
		(width 0.1651)
		(layer "In5.Cu")
		(net "P5E_PEX1_STN5_RX_DP<85>")
	)
	(segment
		(start 127.815594 -395.234668)
		(end 127.947928 -395.16304)
		(width 0.1651)
		(layer "In5.Cu")
		(net "P5E_PEX1_STN5_RX_DP<85>")
	)
	(segment
		(start 178.93411 -323.979286)
		(end 178.93411 -319.91173)
		(width 0.1651)
		(layer "In5.Cu")
		(net "P5E_PEX1_STN5_RX_DP<85>")
	)
	(segment
		(start 127.747268 -395.841982)
		(end 127.747776 -395.840458)
		(width 0.1651)
		(layer "In5.Cu")
		(net "P5E_PEX1_STN5_RX_DP<85>")
	)
	(segment
		(start 176.356772 -328.653902)
		(end 176.398174 -328.6125)
		(width 0.1651)
		(layer "In5.Cu")
		(net "P5E_PEX1_STN5_RX_DP<85>")
	)
	(segment
		(start 178.93411 -319.883282)
		(end 178.97983 -319.837562)
		(width 0.1143)
		(layer "In5.Cu")
		(net "P5E_PEX1_STN5_RX_DP<85>")
	)
	(segment
		(start 178.386486 -325.781924)
		(end 178.93411 -323.979286)
		(width 0.1651)
		(layer "In5.Cu")
		(net "P5E_PEX1_STN5_RX_DP<85>")
	)
	(segment
		(start 127.687578 -396.044674)
		(end 127.747268 -395.841982)
		(width 0.1651)
		(layer "In5.Cu")
		(net "P5E_PEX1_STN5_RX_DP<85>")
	)
	(segment
		(start 128.597914 -394.377672)
		(end 130.232658 -393.374118)
		(width 0.1651)
		(layer "In5.Cu")
		(net "P5E_PEX1_STN5_RX_DP<85>")
	)
	(segment
		(start 89.352882 -345.465146)
		(end 89.647522 -345.170506)
		(width 0.13462)
		(layer "F.Cu")
		(net "P5E_PEX0_STN5_TX_C_DP<93>")
	)
	(segment
		(start 89.647522 -345.170506)
		(end 89.647522 -344.539062)
		(width 0.13462)
		(layer "F.Cu")
		(net "P5E_PEX0_STN5_TX_C_DP<93>")
	)
	(segment
		(start 89.647522 -344.539062)
		(end 89.327482 -344.219022)
		(width 0.13462)
		(layer "F.Cu")
		(net "P5E_PEX0_STN5_TX_C_DP<93>")
	)
	(segment
		(start 84.521548 -366.65789)
		(end 84.637626 -366.609884)
		(width 0.1651)
		(layer "In7.Cu")
		(net "P5E_PEX0_STN5_TX_C_DP<93>")
	)
	(segment
		(start 83.80222 -379.548136)
		(end 83.80222 -368.626644)
		(width 0.1651)
		(layer "In7.Cu")
		(net "P5E_PEX0_STN5_TX_C_DP<93>")
	)
	(segment
		(start 84.637626 -366.609884)
		(end 84.637372 -366.609884)
		(width 0.1651)
		(layer "In7.Cu")
		(net "P5E_PEX0_STN5_TX_C_DP<93>")
	)
	(segment
		(start 82.909918 -379.772164)
		(end 83.036918 -379.899164)
		(width 0.1651)
		(layer "In7.Cu")
		(net "P5E_PEX0_STN5_TX_C_DP<93>")
	)
	(segment
		(start 88.089232 -358.276652)
		(end 88.089232 -347.912182)
		(width 0.1651)
		(layer "In7.Cu")
		(net "P5E_PEX0_STN5_TX_C_DP<93>")
	)
	(segment
		(start 83.036918 -379.899164)
		(end 83.451192 -379.899164)
		(width 0.1651)
		(layer "In7.Cu")
		(net "P5E_PEX0_STN5_TX_C_DP<93>")
	)
	(segment
		(start 84.637372 -366.609884)
		(end 88.089232 -358.276652)
		(width 0.1651)
		(layer "In7.Cu")
		(net "P5E_PEX0_STN5_TX_C_DP<93>")
	)
	(segment
		(start 83.80222 -368.626644)
		(end 84.379816 -367.23193)
		(width 0.1651)
		(layer "In7.Cu")
		(net "P5E_PEX0_STN5_TX_C_DP<93>")
	)
	(segment
		(start 84.33181 -367.115852)
		(end 84.521548 -366.65789)
		(width 0.1651)
		(layer "In7.Cu")
		(net "P5E_PEX0_STN5_TX_C_DP<93>")
	)
	(segment
		(start 82.909918 -379.390148)
		(end 82.909918 -379.772164)
		(width 0.1651)
		(layer "In7.Cu")
		(net "P5E_PEX0_STN5_TX_C_DP<93>")
	)
	(segment
		(start 89.643712 -345.755976)
		(end 89.352882 -345.465146)
		(width 0.1651)
		(layer "In7.Cu")
		(net "P5E_PEX0_STN5_TX_C_DP<93>")
	)
	(segment
		(start 84.379816 -367.23193)
		(end 84.33181 -367.115852)
		(width 0.1651)
		(layer "In7.Cu")
		(net "P5E_PEX0_STN5_TX_C_DP<93>")
	)
	(segment
		(start 88.089232 -347.912182)
		(end 89.643712 -346.357702)
		(width 0.1651)
		(layer "In7.Cu")
		(net "P5E_PEX0_STN5_TX_C_DP<93>")
	)
	(segment
		(start 89.643712 -346.357702)
		(end 89.643712 -345.755976)
		(width 0.1651)
		(layer "In7.Cu")
		(net "P5E_PEX0_STN5_TX_C_DP<93>")
	)
	(segment
		(start 83.451192 -379.899164)
		(end 83.80222 -379.548136)
		(width 0.1651)
		(layer "In7.Cu")
		(net "P5E_PEX0_STN5_TX_C_DP<93>")
	)
	(segment
		(start 142.951708 -351.611438)
		(end 143.246348 -351.316798)
		(width 0.13462)
		(layer "F.Cu")
		(net "P5E_PEX1_STN5_TX_C_DP<87>")
	)
	(segment
		(start 143.246348 -350.685354)
		(end 142.926308 -350.365314)
		(width 0.13462)
		(layer "F.Cu")
		(net "P5E_PEX1_STN5_TX_C_DP<87>")
	)
	(segment
		(start 143.246348 -351.316798)
		(end 143.246348 -350.685354)
		(width 0.13462)
		(layer "F.Cu")
		(net "P5E_PEX1_STN5_TX_C_DP<87>")
	)
	(segment
		(start 142.7226 -383.257044)
		(end 142.7226 -383.9591)
		(width 0.1651)
		(layer "In7.Cu")
		(net "P5E_PEX1_STN5_TX_C_DP<87>")
	)
	(segment
		(start 132.7912 -394.462)
		(end 132.3086 -394.9192)
		(width 0.1651)
		(layer "In7.Cu")
		(net "P5E_PEX1_STN5_TX_C_DP<87>")
	)
	(segment
		(start 143.053308 -367.645442)
		(end 143.053308 -369.87734)
		(width 0.1651)
		(layer "In7.Cu")
		(net "P5E_PEX1_STN5_TX_C_DP<87>")
	)
	(segment
		(start 141.688058 -353.975162)
		(end 141.688058 -358.44099)
		(width 0.1651)
		(layer "In7.Cu")
		(net "P5E_PEX1_STN5_TX_C_DP<87>")
	)
	(segment
		(start 140.208 -390.7536)
		(end 138.707622 -391.866882)
		(width 0.1651)
		(layer "In7.Cu")
		(net "P5E_PEX1_STN5_TX_C_DP<87>")
	)
	(segment
		(start 141.3256 -389.7376)
		(end 140.208 -390.7536)
		(width 0.1651)
		(layer "In7.Cu")
		(net "P5E_PEX1_STN5_TX_C_DP<87>")
	)
	(segment
		(start 131.310126 -405.771858)
		(end 131.310126 -405.390096)
		(width 0.1651)
		(layer "In7.Cu")
		(net "P5E_PEX1_STN5_TX_C_DP<87>")
	)
	(segment
		(start 138.707622 -391.866882)
		(end 132.7912 -394.462)
		(width 0.1651)
		(layer "In7.Cu")
		(net "P5E_PEX1_STN5_TX_C_DP<87>")
	)
	(segment
		(start 142.7226 -383.9591)
		(end 142.512542 -386.55879)
		(width 0.1651)
		(layer "In7.Cu")
		(net "P5E_PEX1_STN5_TX_C_DP<87>")
	)
	(segment
		(start 132.08762 -405.48052)
		(end 131.669282 -405.898858)
		(width 0.1651)
		(layer "In7.Cu")
		(net "P5E_PEX1_STN5_TX_C_DP<87>")
	)
	(segment
		(start 143.053308 -369.87734)
		(end 142.7226 -383.257044)
		(width 0.1651)
		(layer "In7.Cu")
		(net "P5E_PEX1_STN5_TX_C_DP<87>")
	)
	(segment
		(start 141.688058 -358.44099)
		(end 142.494508 -363.87913)
		(width 0.1651)
		(layer "In7.Cu")
		(net "P5E_PEX1_STN5_TX_C_DP<87>")
	)
	(segment
		(start 141.986 -388.2136)
		(end 141.3256 -389.7376)
		(width 0.1651)
		(layer "In7.Cu")
		(net "P5E_PEX1_STN5_TX_C_DP<87>")
	)
	(segment
		(start 131.669282 -405.898858)
		(end 131.437126 -405.898858)
		(width 0.1651)
		(layer "In7.Cu")
		(net "P5E_PEX1_STN5_TX_C_DP<87>")
	)
	(segment
		(start 142.503144 -364.455964)
		(end 142.589758 -364.520226)
		(width 0.1651)
		(layer "In7.Cu")
		(net "P5E_PEX1_STN5_TX_C_DP<87>")
	)
	(segment
		(start 131.437126 -405.898858)
		(end 131.310126 -405.771858)
		(width 0.1651)
		(layer "In7.Cu")
		(net "P5E_PEX1_STN5_TX_C_DP<87>")
	)
	(segment
		(start 142.4305 -363.965744)
		(end 142.503144 -364.455964)
		(width 0.1651)
		(layer "In7.Cu")
		(net "P5E_PEX1_STN5_TX_C_DP<87>")
	)
	(segment
		(start 132.08762 -396.2654)
		(end 132.08762 -405.48052)
		(width 0.1651)
		(layer "In7.Cu")
		(net "P5E_PEX1_STN5_TX_C_DP<87>")
	)
	(segment
		(start 143.242538 -352.420682)
		(end 141.688058 -353.975162)
		(width 0.1651)
		(layer "In7.Cu")
		(net "P5E_PEX1_STN5_TX_C_DP<87>")
	)
	(segment
		(start 142.589758 -364.520226)
		(end 143.053308 -367.645442)
		(width 0.1651)
		(layer "In7.Cu")
		(net "P5E_PEX1_STN5_TX_C_DP<87>")
	)
	(segment
		(start 142.512542 -386.55879)
		(end 141.986 -388.2136)
		(width 0.1651)
		(layer "In7.Cu")
		(net "P5E_PEX1_STN5_TX_C_DP<87>")
	)
	(segment
		(start 142.951708 -351.611438)
		(end 143.242538 -351.902268)
		(width 0.1651)
		(layer "In7.Cu")
		(net "P5E_PEX1_STN5_TX_C_DP<87>")
	)
	(segment
		(start 132.3086 -394.9192)
		(end 132.08762 -396.2654)
		(width 0.1651)
		(layer "In7.Cu")
		(net "P5E_PEX1_STN5_TX_C_DP<87>")
	)
	(segment
		(start 142.494508 -363.87913)
		(end 142.4305 -363.965744)
		(width 0.1651)
		(layer "In7.Cu")
		(net "P5E_PEX1_STN5_TX_C_DP<87>")
	)
	(segment
		(start 143.242538 -351.902268)
		(end 143.242538 -352.420682)
		(width 0.1651)
		(layer "In7.Cu")
		(net "P5E_PEX1_STN5_TX_C_DP<87>")
	)
	(segment
		(start 82.928206 -120.476772)
		(end 83.248246 -120.796812)
		(width 0.13462)
		(layer "F.Cu")
		(net "P5E_PEX0_STN0_TX_DN<1>")
	)
	(segment
		(start 83.87969 -120.796812)
		(end 84.17433 -120.502172)
		(width 0.13462)
		(layer "F.Cu")
		(net "P5E_PEX0_STN0_TX_DN<1>")
	)
	(segment
		(start 83.248246 -120.796812)
		(end 83.87969 -120.796812)
		(width 0.13462)
		(layer "F.Cu")
		(net "P5E_PEX0_STN0_TX_DN<1>")
	)
	(segment
		(start 75.534266 -287.349946)
		(end 75.79995 -287.349946)
		(width 0.1143)
		(layer "In9.Cu")
		(net "P5E_PEX0_STN0_TX_DN<1>")
	)
	(segment
		(start 75.419966 -287.073848)
		(end 75.419966 -287.235646)
		(width 0.1143)
		(layer "In9.Cu")
		(net "P5E_PEX0_STN0_TX_DN<1>")
	)
	(segment
		(start 98.166174 -276.371812)
		(end 88.85555 -285.682436)
		(width 0.1651)
		(layer "In9.Cu")
		(net "P5E_PEX0_STN0_TX_DN<1>")
	)
	(segment
		(start 99.27971 -267.461492)
		(end 99.729544 -272.597372)
		(width 0.1651)
		(layer "In9.Cu")
		(net "P5E_PEX0_STN0_TX_DN<1>")
	)
	(segment
		(start 89.40546 -179.166774)
		(end 85.692234 -221.611444)
		(width 0.1651)
		(layer "In9.Cu")
		(net "P5E_PEX0_STN0_TX_DN<1>")
	)
	(segment
		(start 85.637116 -287.015682)
		(end 83.89366 -287.015682)
		(width 0.1651)
		(layer "In9.Cu")
		(net "P5E_PEX0_STN0_TX_DN<1>")
	)
	(segment
		(start 86.49589 -122.155204)
		(end 90.285824 -131.30403)
		(width 0.1651)
		(layer "In9.Cu")
		(net "P5E_PEX0_STN0_TX_DN<1>")
	)
	(segment
		(start 84.46516 -120.793002)
		(end 85.133688 -120.793002)
		(width 0.1651)
		(layer "In9.Cu")
		(net "P5E_PEX0_STN0_TX_DN<1>")
	)
	(segment
		(start 99.203764 -159.839152)
		(end 98.923348 -160.888934)
		(width 0.1651)
		(layer "In9.Cu")
		(net "P5E_PEX0_STN0_TX_DN<1>")
	)
	(segment
		(start 75.419966 -287.235646)
		(end 75.534266 -287.349946)
		(width 0.1143)
		(layer "In9.Cu")
		(net "P5E_PEX0_STN0_TX_DN<1>")
	)
	(segment
		(start 88.137492 -249.630438)
		(end 98.019108 -264.418572)
		(width 0.1651)
		(layer "In9.Cu")
		(net "P5E_PEX0_STN0_TX_DN<1>")
	)
	(segment
		(start 98.923348 -160.888934)
		(end 90.300302 -175.832008)
		(width 0.1651)
		(layer "In9.Cu")
		(net "P5E_PEX0_STN0_TX_DN<1>")
	)
	(segment
		(start 90.556334 -131.57454)
		(end 99.203764 -152.451308)
		(width 0.1651)
		(layer "In9.Cu")
		(net "P5E_PEX0_STN0_TX_DN<1>")
	)
	(segment
		(start 88.85555 -285.682436)
		(end 85.637116 -287.015682)
		(width 0.1651)
		(layer "In9.Cu")
		(net "P5E_PEX0_STN0_TX_DN<1>")
	)
	(segment
		(start 90.285824 -131.30403)
		(end 90.556334 -131.57454)
		(width 0.1651)
		(layer "In9.Cu")
		(net "P5E_PEX0_STN0_TX_DN<1>")
	)
	(segment
		(start 85.133688 -120.793002)
		(end 86.49589 -122.155204)
		(width 0.1651)
		(layer "In9.Cu")
		(net "P5E_PEX0_STN0_TX_DN<1>")
	)
	(segment
		(start 99.203764 -152.451308)
		(end 99.203764 -159.839152)
		(width 0.1651)
		(layer "In9.Cu")
		(net "P5E_PEX0_STN0_TX_DN<1>")
	)
	(segment
		(start 83.819492 -286.969962)
		(end 75.523852 -286.969962)
		(width 0.1143)
		(layer "In9.Cu")
		(net "P5E_PEX0_STN0_TX_DN<1>")
	)
	(segment
		(start 83.89366 -287.015682)
		(end 83.865212 -287.015682)
		(width 0.1143)
		(layer "In9.Cu")
		(net "P5E_PEX0_STN0_TX_DN<1>")
	)
	(segment
		(start 98.019108 -264.418572)
		(end 99.27971 -267.461492)
		(width 0.1651)
		(layer "In9.Cu")
		(net "P5E_PEX0_STN0_TX_DN<1>")
	)
	(segment
		(start 83.865212 -287.015682)
		(end 83.819492 -286.969962)
		(width 0.1143)
		(layer "In9.Cu")
		(net "P5E_PEX0_STN0_TX_DN<1>")
	)
	(segment
		(start 85.692234 -221.611444)
		(end 88.137492 -249.630438)
		(width 0.1651)
		(layer "In9.Cu")
		(net "P5E_PEX0_STN0_TX_DN<1>")
	)
	(segment
		(start 99.729544 -272.597372)
		(end 98.166174 -276.371812)
		(width 0.1651)
		(layer "In9.Cu")
		(net "P5E_PEX0_STN0_TX_DN<1>")
	)
	(segment
		(start 75.523852 -286.969962)
		(end 75.419966 -287.073848)
		(width 0.1143)
		(layer "In9.Cu")
		(net "P5E_PEX0_STN0_TX_DN<1>")
	)
	(segment
		(start 84.17433 -120.502172)
		(end 84.46516 -120.793002)
		(width 0.1651)
		(layer "In9.Cu")
		(net "P5E_PEX0_STN0_TX_DN<1>")
	)
	(segment
		(start 90.300302 -175.832008)
		(end 89.40546 -179.166774)
		(width 0.1651)
		(layer "In9.Cu")
		(net "P5E_PEX0_STN0_TX_DN<1>")
	)
	(segment
		(start 38.555168 -348.88043)
		(end 38.849808 -348.58579)
		(width 0.13462)
		(layer "F.Cu")
		(net "P5E_PEX0_STN7_TX_DP<121>")
	)
	(segment
		(start 38.555168 -349.511874)
		(end 38.555168 -348.88043)
		(width 0.13462)
		(layer "F.Cu")
		(net "P5E_PEX0_STN7_TX_DP<121>")
	)
	(segment
		(start 38.875208 -349.831914)
		(end 38.555168 -349.511874)
		(width 0.13462)
		(layer "F.Cu")
		(net "P5E_PEX0_STN7_TX_DP<121>")
	)
	(segment
		(start 36.389056 -312.937144)
		(end 36.399216 -312.926984)
		(width 0.1143)
		(layer "In7.Cu")
		(net "P5E_PEX0_STN7_TX_DP<121>")
	)
	(segment
		(start 37.194236 -312.620152)
		(end 37.420042 -312.394346)
		(width 0.1143)
		(layer "In7.Cu")
		(net "P5E_PEX0_STN7_TX_DP<121>")
	)
	(segment
		(start 35.572954 -323.134228)
		(end 35.5727 -323.133466)
		(width 0.1651)
		(layer "In7.Cu")
		(net "P5E_PEX0_STN7_TX_DP<121>")
	)
	(segment
		(start 36.399216 -312.926984)
		(end 36.399216 -312.906664)
		(width 0.1143)
		(layer "In7.Cu")
		(net "P5E_PEX0_STN7_TX_DP<121>")
	)
	(segment
		(start 40.113458 -341.457026)
		(end 39.139368 -334.890618)
		(width 0.1651)
		(layer "In7.Cu")
		(net "P5E_PEX0_STN7_TX_DP<121>")
	)
	(segment
		(start 36.64077 -312.620152)
		(end 37.194236 -312.620152)
		(width 0.1143)
		(layer "In7.Cu")
		(net "P5E_PEX0_STN7_TX_DP<121>")
	)
	(segment
		(start 34.34334 -316.140084)
		(end 34.839402 -314.75426)
		(width 0.1651)
		(layer "In7.Cu")
		(net "P5E_PEX0_STN7_TX_DP<121>")
	)
	(segment
		(start 35.5727 -323.133466)
		(end 34.920428 -320.98361)
		(width 0.1651)
		(layer "In7.Cu")
		(net "P5E_PEX0_STN7_TX_DP<121>")
	)
	(segment
		(start 37.420042 -312.394346)
		(end 37.420042 -312.164222)
		(width 0.1143)
		(layer "In7.Cu")
		(net "P5E_PEX0_STN7_TX_DP<121>")
	)
	(segment
		(start 37.534342 -312.049922)
		(end 37.799772 -312.049922)
		(width 0.1143)
		(layer "In7.Cu")
		(net "P5E_PEX0_STN7_TX_DP<121>")
	)
	(segment
		(start 34.34334 -318.140334)
		(end 34.34334 -316.140084)
		(width 0.1651)
		(layer "In7.Cu")
		(net "P5E_PEX0_STN7_TX_DP<121>")
	)
	(segment
		(start 37.420042 -312.164222)
		(end 37.534342 -312.049922)
		(width 0.1143)
		(layer "In7.Cu")
		(net "P5E_PEX0_STN7_TX_DP<121>")
	)
	(segment
		(start 34.839402 -314.75426)
		(end 36.063936 -313.262264)
		(width 0.1651)
		(layer "In7.Cu")
		(net "P5E_PEX0_STN7_TX_DP<121>")
	)
	(segment
		(start 36.063936 -313.262264)
		(end 36.389056 -312.937144)
		(width 0.1651)
		(layer "In7.Cu")
		(net "P5E_PEX0_STN7_TX_DP<121>")
	)
	(segment
		(start 36.398962 -312.862214)
		(end 36.64077 -312.620152)
		(width 0.1143)
		(layer "In7.Cu")
		(net "P5E_PEX0_STN7_TX_DP<121>")
	)
	(segment
		(start 34.920428 -320.98361)
		(end 34.886646 -320.87185)
		(width 0.1651)
		(layer "In7.Cu")
		(net "P5E_PEX0_STN7_TX_DP<121>")
	)
	(segment
		(start 38.558978 -348.29496)
		(end 38.558978 -347.658182)
		(width 0.1651)
		(layer "In7.Cu")
		(net "P5E_PEX0_STN7_TX_DP<121>")
	)
	(segment
		(start 40.113458 -346.103702)
		(end 40.113458 -341.457026)
		(width 0.1651)
		(layer "In7.Cu")
		(net "P5E_PEX0_STN7_TX_DP<121>")
	)
	(segment
		(start 39.139368 -334.890618)
		(end 35.572954 -323.134228)
		(width 0.1651)
		(layer "In7.Cu")
		(net "P5E_PEX0_STN7_TX_DP<121>")
	)
	(segment
		(start 38.849808 -348.58579)
		(end 38.558978 -348.29496)
		(width 0.1651)
		(layer "In7.Cu")
		(net "P5E_PEX0_STN7_TX_DP<121>")
	)
	(segment
		(start 34.886646 -320.87185)
		(end 34.34334 -318.140334)
		(width 0.1651)
		(layer "In7.Cu")
		(net "P5E_PEX0_STN7_TX_DP<121>")
	)
	(segment
		(start 36.399216 -312.906664)
		(end 36.398962 -312.862214)
		(width 0.1143)
		(layer "In7.Cu")
		(net "P5E_PEX0_STN7_TX_DP<121>")
	)
	(segment
		(start 38.558978 -347.658182)
		(end 40.113458 -346.103702)
		(width 0.1651)
		(layer "In7.Cu")
		(net "P5E_PEX0_STN7_TX_DP<121>")
	)
	(segment
		(start 199.34809 -135.88111)
		(end 199.979534 -135.88111)
		(width 0.13462)
		(layer "F.Cu")
		(net "P5E_PEX1_STN0_TX_DP<7>")
	)
	(segment
		(start 199.979534 -135.88111)
		(end 200.274174 -136.17575)
		(width 0.13462)
		(layer "F.Cu")
		(net "P5E_PEX1_STN0_TX_DP<7>")
	)
	(segment
		(start 199.02805 -136.20115)
		(end 199.34809 -135.88111)
		(width 0.13462)
		(layer "F.Cu")
		(net "P5E_PEX1_STN0_TX_DP<7>")
	)
	(segment
		(start 202.046332 -137.81151)
		(end 201.988674 -137.950702)
		(width 0.1651)
		(layer "In9.Cu")
		(net "P5E_PEX1_STN0_TX_DP<7>")
	)
	(segment
		(start 201.988674 -137.950702)
		(end 202.16368 -138.373358)
		(width 0.1651)
		(layer "In9.Cu")
		(net "P5E_PEX1_STN0_TX_DP<7>")
	)
	(segment
		(start 203.458318 -141.499336)
		(end 203.598018 -141.556994)
		(width 0.1651)
		(layer "In9.Cu")
		(net "P5E_PEX1_STN0_TX_DP<7>")
	)
	(segment
		(start 199.912478 -277.275798)
		(end 199.204834 -278.71039)
		(width 0.1651)
		(layer "In9.Cu")
		(net "P5E_PEX1_STN0_TX_DP<7>")
	)
	(segment
		(start 198.201788 -279.17775)
		(end 197.979792 -279.400254)
		(width 0.1143)
		(layer "In9.Cu")
		(net "P5E_PEX1_STN0_TX_DP<7>")
	)
	(segment
		(start 205.891384 -146.146774)
		(end 205.89113 -146.146774)
		(width 0.1651)
		(layer "In9.Cu")
		(net "P5E_PEX1_STN0_TX_DP<7>")
	)
	(segment
		(start 200.074276 -175.729646)
		(end 199.776588 -176.839118)
		(width 0.1651)
		(layer "In9.Cu")
		(net "P5E_PEX1_STN0_TX_DP<7>")
	)
	(segment
		(start 202.851766 -140.034772)
		(end 203.026772 -140.457428)
		(width 0.1651)
		(layer "In9.Cu")
		(net "P5E_PEX1_STN0_TX_DP<7>")
	)
	(segment
		(start 203.77277 -141.979142)
		(end 203.715112 -142.118588)
		(width 0.1651)
		(layer "In9.Cu")
		(net "P5E_PEX1_STN0_TX_DP<7>")
	)
	(segment
		(start 197.865492 -279.749758)
		(end 197.600062 -279.749758)
		(width 0.1143)
		(layer "In9.Cu")
		(net "P5E_PEX1_STN0_TX_DP<7>")
	)
	(segment
		(start 201.144378 -135.88492)
		(end 201.322178 -136.06272)
		(width 0.1651)
		(layer "In9.Cu")
		(net "P5E_PEX1_STN0_TX_DP<7>")
	)
	(segment
		(start 202.30338 -138.43127)
		(end 202.303126 -138.43127)
		(width 0.1651)
		(layer "In9.Cu")
		(net "P5E_PEX1_STN0_TX_DP<7>")
	)
	(segment
		(start 203.890118 -142.541244)
		(end 204.029818 -142.599156)
		(width 0.1651)
		(layer "In9.Cu")
		(net "P5E_PEX1_STN0_TX_DP<7>")
	)
	(segment
		(start 200.074022 -175.729646)
		(end 200.074276 -175.729646)
		(width 0.1651)
		(layer "In9.Cu")
		(net "P5E_PEX1_STN0_TX_DP<7>")
	)
	(segment
		(start 202.16368 -138.373358)
		(end 202.30338 -138.43127)
		(width 0.1651)
		(layer "In9.Cu")
		(net "P5E_PEX1_STN0_TX_DP<7>")
	)
	(segment
		(start 203.598018 -141.556994)
		(end 203.77277 -141.979142)
		(width 0.1651)
		(layer "In9.Cu")
		(net "P5E_PEX1_STN0_TX_DP<7>")
	)
	(segment
		(start 203.34097 -140.937234)
		(end 203.283312 -141.07668)
		(width 0.1651)
		(layer "In9.Cu")
		(net "P5E_PEX1_STN0_TX_DP<7>")
	)
	(segment
		(start 199.204834 -278.71039)
		(end 198.971154 -278.944324)
		(width 0.1651)
		(layer "In9.Cu")
		(net "P5E_PEX1_STN0_TX_DP<7>")
	)
	(segment
		(start 202.734672 -139.473178)
		(end 202.909424 -139.895326)
		(width 0.1651)
		(layer "In9.Cu")
		(net "P5E_PEX1_STN0_TX_DP<7>")
	)
	(segment
		(start 199.472804 -177.972212)
		(end 195.657978 -221.581218)
		(width 0.1651)
		(layer "In9.Cu")
		(net "P5E_PEX1_STN0_TX_DP<7>")
	)
	(segment
		(start 204.029818 -142.599156)
		(end 204.029564 -142.599156)
		(width 0.1651)
		(layer "In9.Cu")
		(net "P5E_PEX1_STN0_TX_DP<7>")
	)
	(segment
		(start 200.565004 -135.88492)
		(end 201.144378 -135.88492)
		(width 0.1651)
		(layer "In9.Cu")
		(net "P5E_PEX1_STN0_TX_DP<7>")
	)
	(segment
		(start 205.89113 -146.146774)
		(end 209.215482 -154.171904)
		(width 0.1651)
		(layer "In9.Cu")
		(net "P5E_PEX1_STN0_TX_DP<7>")
	)
	(segment
		(start 203.166218 -140.515086)
		(end 203.34097 -140.937234)
		(width 0.1651)
		(layer "In9.Cu")
		(net "P5E_PEX1_STN0_TX_DP<7>")
	)
	(segment
		(start 205.22184 -145.47723)
		(end 205.891384 -146.146774)
		(width 0.1651)
		(layer "In9.Cu")
		(net "P5E_PEX1_STN0_TX_DP<7>")
	)
	(segment
		(start 200.274174 -136.17575)
		(end 200.565004 -135.88492)
		(width 0.1651)
		(layer "In9.Cu")
		(net "P5E_PEX1_STN0_TX_DP<7>")
	)
	(segment
		(start 202.42022 -138.992864)
		(end 202.595226 -139.41552)
		(width 0.1651)
		(layer "In9.Cu")
		(net "P5E_PEX1_STN0_TX_DP<7>")
	)
	(segment
		(start 203.715112 -142.118588)
		(end 203.890118 -142.541244)
		(width 0.1651)
		(layer "In9.Cu")
		(net "P5E_PEX1_STN0_TX_DP<7>")
	)
	(segment
		(start 209.215482 -154.171904)
		(end 209.215482 -158.684722)
		(width 0.1651)
		(layer "In9.Cu")
		(net "P5E_PEX1_STN0_TX_DP<7>")
	)
	(segment
		(start 204.029564 -142.599156)
		(end 205.22184 -145.47723)
		(width 0.1651)
		(layer "In9.Cu")
		(net "P5E_PEX1_STN0_TX_DP<7>")
	)
	(segment
		(start 202.477878 -138.853418)
		(end 202.42022 -138.992864)
		(width 0.1651)
		(layer "In9.Cu")
		(net "P5E_PEX1_STN0_TX_DP<7>")
	)
	(segment
		(start 195.657978 -221.581218)
		(end 197.847966 -246.652034)
		(width 0.1651)
		(layer "In9.Cu")
		(net "P5E_PEX1_STN0_TX_DP<7>")
	)
	(segment
		(start 201.322178 -136.06272)
		(end 201.600816 -136.735566)
		(width 0.1651)
		(layer "In9.Cu")
		(net "P5E_PEX1_STN0_TX_DP<7>")
	)
	(segment
		(start 199.776588 -176.839118)
		(end 199.776334 -176.839118)
		(width 0.1651)
		(layer "In9.Cu")
		(net "P5E_PEX1_STN0_TX_DP<7>")
	)
	(segment
		(start 197.979792 -279.635458)
		(end 197.865492 -279.749758)
		(width 0.1143)
		(layer "In9.Cu")
		(net "P5E_PEX1_STN0_TX_DP<7>")
	)
	(segment
		(start 198.951088 -279.028652)
		(end 198.80199 -279.17775)
		(width 0.1143)
		(layer "In9.Cu")
		(net "P5E_PEX1_STN0_TX_DP<7>")
	)
	(segment
		(start 199.627744 -177.393854)
		(end 199.472804 -177.972212)
		(width 0.1651)
		(layer "In9.Cu")
		(net "P5E_PEX1_STN0_TX_DP<7>")
	)
	(segment
		(start 200.034906 -271.68348)
		(end 199.912478 -277.275798)
		(width 0.1651)
		(layer "In9.Cu")
		(net "P5E_PEX1_STN0_TX_DP<7>")
	)
	(segment
		(start 203.026772 -140.457428)
		(end 203.166472 -140.515086)
		(width 0.1651)
		(layer "In9.Cu")
		(net "P5E_PEX1_STN0_TX_DP<7>")
	)
	(segment
		(start 197.847966 -246.652034)
		(end 197.84822 -246.652034)
		(width 0.1651)
		(layer "In9.Cu")
		(net "P5E_PEX1_STN0_TX_DP<7>")
	)
	(segment
		(start 202.909424 -139.895326)
		(end 202.851766 -140.034772)
		(width 0.1651)
		(layer "In9.Cu")
		(net "P5E_PEX1_STN0_TX_DP<7>")
	)
	(segment
		(start 201.543158 -136.874758)
		(end 201.71791 -137.297414)
		(width 0.1651)
		(layer "In9.Cu")
		(net "P5E_PEX1_STN0_TX_DP<7>")
	)
	(segment
		(start 199.776334 -176.839118)
		(end 199.62749 -177.393854)
		(width 0.1651)
		(layer "In9.Cu")
		(net "P5E_PEX1_STN0_TX_DP<7>")
	)
	(segment
		(start 203.166472 -140.515086)
		(end 203.166218 -140.515086)
		(width 0.1651)
		(layer "In9.Cu")
		(net "P5E_PEX1_STN0_TX_DP<7>")
	)
	(segment
		(start 201.71791 -137.297414)
		(end 201.85761 -137.355326)
		(width 0.1651)
		(layer "In9.Cu")
		(net "P5E_PEX1_STN0_TX_DP<7>")
	)
	(segment
		(start 200.678796 -173.475142)
		(end 200.074022 -175.729646)
		(width 0.1651)
		(layer "In9.Cu")
		(net "P5E_PEX1_STN0_TX_DP<7>")
	)
	(segment
		(start 197.84822 -246.652034)
		(end 200.034906 -271.68348)
		(width 0.1651)
		(layer "In9.Cu")
		(net "P5E_PEX1_STN0_TX_DP<7>")
	)
	(segment
		(start 202.595226 -139.41552)
		(end 202.734926 -139.473178)
		(width 0.1651)
		(layer "In9.Cu")
		(net "P5E_PEX1_STN0_TX_DP<7>")
	)
	(segment
		(start 201.600816 -136.735566)
		(end 201.543158 -136.874758)
		(width 0.1651)
		(layer "In9.Cu")
		(net "P5E_PEX1_STN0_TX_DP<7>")
	)
	(segment
		(start 199.62749 -177.393854)
		(end 199.627744 -177.393854)
		(width 0.1651)
		(layer "In9.Cu")
		(net "P5E_PEX1_STN0_TX_DP<7>")
	)
	(segment
		(start 201.85761 -137.355326)
		(end 202.046332 -137.81151)
		(width 0.1651)
		(layer "In9.Cu")
		(net "P5E_PEX1_STN0_TX_DP<7>")
	)
	(segment
		(start 202.734926 -139.473178)
		(end 202.734672 -139.473178)
		(width 0.1651)
		(layer "In9.Cu")
		(net "P5E_PEX1_STN0_TX_DP<7>")
	)
	(segment
		(start 203.283312 -141.07668)
		(end 203.458318 -141.499336)
		(width 0.1651)
		(layer "In9.Cu")
		(net "P5E_PEX1_STN0_TX_DP<7>")
	)
	(segment
		(start 209.215482 -158.684722)
		(end 200.678796 -173.475142)
		(width 0.1651)
		(layer "In9.Cu")
		(net "P5E_PEX1_STN0_TX_DP<7>")
	)
	(segment
		(start 198.80199 -279.17775)
		(end 198.201788 -279.17775)
		(width 0.1143)
		(layer "In9.Cu")
		(net "P5E_PEX1_STN0_TX_DP<7>")
	)
	(segment
		(start 198.951088 -278.96439)
		(end 198.951088 -279.028652)
		(width 0.1143)
		(layer "In9.Cu")
		(net "P5E_PEX1_STN0_TX_DP<7>")
	)
	(segment
		(start 198.971154 -278.944324)
		(end 198.951088 -278.96439)
		(width 0.1143)
		(layer "In9.Cu")
		(net "P5E_PEX1_STN0_TX_DP<7>")
	)
	(segment
		(start 202.303126 -138.43127)
		(end 202.477878 -138.853418)
		(width 0.1651)
		(layer "In9.Cu")
		(net "P5E_PEX1_STN0_TX_DP<7>")
	)
	(segment
		(start 197.979792 -279.400254)
		(end 197.979792 -279.635458)
		(width 0.1143)
		(layer "In9.Cu")
		(net "P5E_PEX1_STN0_TX_DP<7>")
	)
	(segment
		(start 118.648988 -355.658166)
		(end 118.648988 -355.026722)
		(width 0.13462)
		(layer "F.Cu")
		(net "P5E_PEX1_STN6_TX_DN<108>")
	)
	(segment
		(start 118.969028 -355.978206)
		(end 118.648988 -355.658166)
		(width 0.13462)
		(layer "F.Cu")
		(net "P5E_PEX1_STN6_TX_DN<108>")
	)
	(segment
		(start 118.648988 -355.026722)
		(end 118.943628 -354.732082)
		(width 0.13462)
		(layer "F.Cu")
		(net "P5E_PEX1_STN6_TX_DN<108>")
	)
	(segment
		(start 156.805884 -325.544688)
		(end 152.412446 -327.364344)
		(width 0.1651)
		(layer "In13.Cu")
		(net "P5E_PEX1_STN6_TX_DN<108>")
	)
	(segment
		(start 120.207278 -341.587582)
		(end 120.207278 -352.389948)
		(width 0.1651)
		(layer "In13.Cu")
		(net "P5E_PEX1_STN6_TX_DN<108>")
	)
	(segment
		(start 122.184668 -339.610192)
		(end 120.207278 -341.587582)
		(width 0.1651)
		(layer "In13.Cu")
		(net "P5E_PEX1_STN6_TX_DN<108>")
	)
	(segment
		(start 162.070288 -319.995296)
		(end 162.116008 -320.041016)
		(width 0.1143)
		(layer "In13.Cu")
		(net "P5E_PEX1_STN6_TX_DN<108>")
	)
	(segment
		(start 120.207278 -352.389948)
		(end 118.652798 -353.944428)
		(width 0.1651)
		(layer "In13.Cu")
		(net "P5E_PEX1_STN6_TX_DN<108>")
	)
	(segment
		(start 162.116008 -320.041016)
		(end 162.116008 -320.063114)
		(width 0.1143)
		(layer "In13.Cu")
		(net "P5E_PEX1_STN6_TX_DN<108>")
	)
	(segment
		(start 152.412446 -327.364344)
		(end 152.412446 -327.364598)
		(width 0.1651)
		(layer "In13.Cu")
		(net "P5E_PEX1_STN6_TX_DN<108>")
	)
	(segment
		(start 162.116008 -320.063114)
		(end 162.116008 -321.509644)
		(width 0.1651)
		(layer "In13.Cu")
		(net "P5E_PEX1_STN6_TX_DN<108>")
	)
	(segment
		(start 129.944368 -334.42529)
		(end 122.184668 -339.610192)
		(width 0.1651)
		(layer "In13.Cu")
		(net "P5E_PEX1_STN6_TX_DN<108>")
	)
	(segment
		(start 162.070288 -313.673744)
		(end 162.070288 -319.995296)
		(width 0.1143)
		(layer "In13.Cu")
		(net "P5E_PEX1_STN6_TX_DN<108>")
	)
	(segment
		(start 162.116008 -321.509644)
		(end 159.989774 -323.635878)
		(width 0.1651)
		(layer "In13.Cu")
		(net "P5E_PEX1_STN6_TX_DN<108>")
	)
	(segment
		(start 162.450018 -313.949842)
		(end 162.450018 -313.684412)
		(width 0.1143)
		(layer "In13.Cu")
		(net "P5E_PEX1_STN6_TX_DN<108>")
	)
	(segment
		(start 145.86077 -329.613768)
		(end 141.560042 -329.613768)
		(width 0.1651)
		(layer "In13.Cu")
		(net "P5E_PEX1_STN6_TX_DN<108>")
	)
	(segment
		(start 162.17392 -313.570112)
		(end 162.070288 -313.673744)
		(width 0.1143)
		(layer "In13.Cu")
		(net "P5E_PEX1_STN6_TX_DN<108>")
	)
	(segment
		(start 159.989774 -323.635878)
		(end 156.805884 -325.544688)
		(width 0.1651)
		(layer "In13.Cu")
		(net "P5E_PEX1_STN6_TX_DN<108>")
	)
	(segment
		(start 148.012658 -329.186794)
		(end 145.86077 -329.613768)
		(width 0.1651)
		(layer "In13.Cu")
		(net "P5E_PEX1_STN6_TX_DN<108>")
	)
	(segment
		(start 118.652798 -354.441252)
		(end 118.943628 -354.732082)
		(width 0.1651)
		(layer "In13.Cu")
		(net "P5E_PEX1_STN6_TX_DN<108>")
	)
	(segment
		(start 162.450018 -313.684412)
		(end 162.335718 -313.570112)
		(width 0.1143)
		(layer "In13.Cu")
		(net "P5E_PEX1_STN6_TX_DN<108>")
	)
	(segment
		(start 162.335718 -313.570112)
		(end 162.17392 -313.570112)
		(width 0.1143)
		(layer "In13.Cu")
		(net "P5E_PEX1_STN6_TX_DN<108>")
	)
	(segment
		(start 118.652798 -353.944428)
		(end 118.652798 -354.441252)
		(width 0.1651)
		(layer "In13.Cu")
		(net "P5E_PEX1_STN6_TX_DN<108>")
	)
	(segment
		(start 152.412446 -327.364598)
		(end 148.012658 -329.186794)
		(width 0.1651)
		(layer "In13.Cu")
		(net "P5E_PEX1_STN6_TX_DN<108>")
	)
	(segment
		(start 141.560042 -329.613768)
		(end 129.944368 -334.42529)
		(width 0.1651)
		(layer "In13.Cu")
		(net "P5E_PEX1_STN6_TX_DN<108>")
	)
	(segment
		(start 155.420314 -303.153572)
		(end 155.420314 -303.410874)
		(width 0.1143)
		(layer "In9.Cu")
		(net "P5E_PEX1_STN7_RX_DP<114>")
	)
	(segment
		(start 155.196286 -302.929544)
		(end 155.420314 -303.153572)
		(width 0.1143)
		(layer "In9.Cu")
		(net "P5E_PEX1_STN7_RX_DP<114>")
	)
	(segment
		(start 136.044178 -324.364858)
		(end 135.685784 -323.030596)
		(width 0.1651)
		(layer "In9.Cu")
		(net "P5E_PEX1_STN7_RX_DP<114>")
	)
	(segment
		(start 148.773642 -302.883824)
		(end 151.765 -302.883824)
		(width 0.1651)
		(layer "In9.Cu")
		(net "P5E_PEX1_STN7_RX_DP<114>")
	)
	(segment
		(start 146.815302 -341.792306)
		(end 136.044178 -324.364858)
		(width 0.1651)
		(layer "In9.Cu")
		(net "P5E_PEX1_STN7_RX_DP<114>")
	)
	(segment
		(start 153.481532 -385.313936)
		(end 148.082254 -345.330526)
		(width 0.1651)
		(layer "In9.Cu")
		(net "P5E_PEX1_STN7_RX_DP<114>")
	)
	(segment
		(start 151.765 -302.883824)
		(end 151.793448 -302.883824)
		(width 0.1143)
		(layer "In9.Cu")
		(net "P5E_PEX1_STN7_RX_DP<114>")
	)
	(segment
		(start 164.31006 -408.190192)
		(end 164.31006 -408.572208)
		(width 0.1651)
		(layer "In9.Cu")
		(net "P5E_PEX1_STN7_RX_DP<114>")
	)
	(segment
		(start 155.509214 -303.499774)
		(end 155.800044 -303.499774)
		(width 0.1143)
		(layer "In9.Cu")
		(net "P5E_PEX1_STN7_RX_DP<114>")
	)
	(segment
		(start 164.658802 -394.452094)
		(end 164.515038 -394.452094)
		(width 0.1651)
		(layer "In9.Cu")
		(net "P5E_PEX1_STN7_RX_DP<114>")
	)
	(segment
		(start 155.420314 -303.410874)
		(end 155.509214 -303.499774)
		(width 0.1143)
		(layer "In9.Cu")
		(net "P5E_PEX1_STN7_RX_DP<114>")
	)
	(segment
		(start 148.082254 -345.330526)
		(end 146.815302 -341.792306)
		(width 0.1651)
		(layer "In9.Cu")
		(net "P5E_PEX1_STN7_RX_DP<114>")
	)
	(segment
		(start 164.31006 -408.572208)
		(end 164.43706 -408.699208)
		(width 0.1651)
		(layer "In9.Cu")
		(net "P5E_PEX1_STN7_RX_DP<114>")
	)
	(segment
		(start 146.820382 -303.393348)
		(end 147.6121 -303.246282)
		(width 0.1651)
		(layer "In9.Cu")
		(net "P5E_PEX1_STN7_RX_DP<114>")
	)
	(segment
		(start 151.793448 -302.883824)
		(end 151.839168 -302.929544)
		(width 0.1143)
		(layer "In9.Cu")
		(net "P5E_PEX1_STN7_RX_DP<114>")
	)
	(segment
		(start 135.676132 -318.497712)
		(end 140.68425 -307.207158)
		(width 0.1651)
		(layer "In9.Cu")
		(net "P5E_PEX1_STN7_RX_DP<114>")
	)
	(segment
		(start 135.685784 -323.030596)
		(end 135.68553 -323.030596)
		(width 0.1651)
		(layer "In9.Cu")
		(net "P5E_PEX1_STN7_RX_DP<114>")
	)
	(segment
		(start 164.164518 -394.101574)
		(end 164.164518 -393.95781)
		(width 0.1651)
		(layer "In9.Cu")
		(net "P5E_PEX1_STN7_RX_DP<114>")
	)
	(segment
		(start 163.814506 -393.607798)
		(end 159.124904 -391.66419)
		(width 0.1651)
		(layer "In9.Cu")
		(net "P5E_PEX1_STN7_RX_DP<114>")
	)
	(segment
		(start 155.23083 -388.48919)
		(end 153.481532 -385.313936)
		(width 0.1651)
		(layer "In9.Cu")
		(net "P5E_PEX1_STN7_RX_DP<114>")
	)
	(segment
		(start 143.869664 -304.02149)
		(end 144.218914 -303.876456)
		(width 0.1651)
		(layer "In9.Cu")
		(net "P5E_PEX1_STN7_RX_DP<114>")
	)
	(segment
		(start 164.515038 -394.452094)
		(end 164.164518 -394.101574)
		(width 0.1651)
		(layer "In9.Cu")
		(net "P5E_PEX1_STN7_RX_DP<114>")
	)
	(segment
		(start 147.6121 -303.246282)
		(end 148.773642 -302.883824)
		(width 0.1651)
		(layer "In9.Cu")
		(net "P5E_PEX1_STN7_RX_DP<114>")
	)
	(segment
		(start 144.218914 -303.876456)
		(end 146.820128 -303.393348)
		(width 0.1651)
		(layer "In9.Cu")
		(net "P5E_PEX1_STN7_RX_DP<114>")
	)
	(segment
		(start 165.192456 -394.985748)
		(end 164.658802 -394.452094)
		(width 0.1651)
		(layer "In9.Cu")
		(net "P5E_PEX1_STN7_RX_DP<114>")
	)
	(segment
		(start 135.68553 -323.030596)
		(end 135.676132 -322.994782)
		(width 0.1651)
		(layer "In9.Cu")
		(net "P5E_PEX1_STN7_RX_DP<114>")
	)
	(segment
		(start 165.192456 -408.1653)
		(end 165.192456 -394.985748)
		(width 0.1651)
		(layer "In9.Cu")
		(net "P5E_PEX1_STN7_RX_DP<114>")
	)
	(segment
		(start 146.820128 -303.393348)
		(end 146.820382 -303.393348)
		(width 0.1651)
		(layer "In9.Cu")
		(net "P5E_PEX1_STN7_RX_DP<114>")
	)
	(segment
		(start 159.124904 -391.66419)
		(end 155.23083 -388.48919)
		(width 0.1651)
		(layer "In9.Cu")
		(net "P5E_PEX1_STN7_RX_DP<114>")
	)
	(segment
		(start 135.676132 -322.994782)
		(end 135.676132 -318.497712)
		(width 0.1651)
		(layer "In9.Cu")
		(net "P5E_PEX1_STN7_RX_DP<114>")
	)
	(segment
		(start 164.658548 -408.699208)
		(end 165.192456 -408.1653)
		(width 0.1651)
		(layer "In9.Cu")
		(net "P5E_PEX1_STN7_RX_DP<114>")
	)
	(segment
		(start 164.164518 -393.95781)
		(end 163.814506 -393.607798)
		(width 0.1651)
		(layer "In9.Cu")
		(net "P5E_PEX1_STN7_RX_DP<114>")
	)
	(segment
		(start 151.839168 -302.929544)
		(end 155.196286 -302.929544)
		(width 0.1143)
		(layer "In9.Cu")
		(net "P5E_PEX1_STN7_RX_DP<114>")
	)
	(segment
		(start 140.68425 -307.207158)
		(end 143.869664 -304.02149)
		(width 0.1651)
		(layer "In9.Cu")
		(net "P5E_PEX1_STN7_RX_DP<114>")
	)
	(segment
		(start 164.43706 -408.699208)
		(end 164.658548 -408.699208)
		(width 0.1651)
		(layer "In9.Cu")
		(net "P5E_PEX1_STN7_RX_DP<114>")
	)
	(segment
		(start 140.411708 -344.539062)
		(end 140.731748 -344.219022)
		(width 0.13462)
		(layer "F.Cu")
		(net "P5E_PEX1_STN5_TX_C_DN<85>")
	)
	(segment
		(start 140.411708 -345.170506)
		(end 140.411708 -344.539062)
		(width 0.13462)
		(layer "F.Cu")
		(net "P5E_PEX1_STN5_TX_C_DN<85>")
	)
	(segment
		(start 140.706348 -345.465146)
		(end 140.411708 -345.170506)
		(width 0.13462)
		(layer "F.Cu")
		(net "P5E_PEX1_STN5_TX_C_DN<85>")
	)
	(segment
		(start 141.02334 -384.183128)
		(end 141.02334 -383.235708)
		(width 0.1651)
		(layer "In7.Cu")
		(net "P5E_PEX1_STN5_TX_C_DN<85>")
	)
	(segment
		(start 129.075942 -394.132054)
		(end 137.373868 -390.617202)
		(width 0.1651)
		(layer "In7.Cu")
		(net "P5E_PEX1_STN5_TX_C_DN<85>")
	)
	(segment
		(start 127.037338 -406.180798)
		(end 127.38608 -406.180798)
		(width 0.1651)
		(layer "In7.Cu")
		(net "P5E_PEX1_STN5_TX_C_DN<85>")
	)
	(segment
		(start 127.38608 -406.180798)
		(end 127.969518 -405.59736)
		(width 0.1651)
		(layer "In7.Cu")
		(net "P5E_PEX1_STN5_TX_C_DN<85>")
	)
	(segment
		(start 140.417804 -387.722364)
		(end 140.795248 -386.475224)
		(width 0.1651)
		(layer "In7.Cu")
		(net "P5E_PEX1_STN5_TX_C_DN<85>")
	)
	(segment
		(start 139.813538 -388.872984)
		(end 140.417804 -387.722364)
		(width 0.1651)
		(layer "In7.Cu")
		(net "P5E_PEX1_STN5_TX_C_DN<85>")
	)
	(segment
		(start 141.351 -368.572034)
		(end 139.455906 -362.324904)
		(width 0.1651)
		(layer "In7.Cu")
		(net "P5E_PEX1_STN5_TX_C_DN<85>")
	)
	(segment
		(start 127.969518 -405.59736)
		(end 127.969518 -396.337028)
		(width 0.1651)
		(layer "In7.Cu")
		(net "P5E_PEX1_STN5_TX_C_DN<85>")
	)
	(segment
		(start 140.415518 -345.755976)
		(end 140.706348 -345.465146)
		(width 0.1651)
		(layer "In7.Cu")
		(net "P5E_PEX1_STN5_TX_C_DN<85>")
	)
	(segment
		(start 126.910084 -406.690068)
		(end 126.910084 -406.308052)
		(width 0.1651)
		(layer "In7.Cu")
		(net "P5E_PEX1_STN5_TX_C_DN<85>")
	)
	(segment
		(start 141.02334 -383.235708)
		(end 141.351 -369.94973)
		(width 0.1651)
		(layer "In7.Cu")
		(net "P5E_PEX1_STN5_TX_C_DN<85>")
	)
	(segment
		(start 140.795248 -386.475224)
		(end 141.02334 -384.183128)
		(width 0.1651)
		(layer "In7.Cu")
		(net "P5E_PEX1_STN5_TX_C_DN<85>")
	)
	(segment
		(start 138.861038 -358.31526)
		(end 138.861038 -348.031562)
		(width 0.1651)
		(layer "In7.Cu")
		(net "P5E_PEX1_STN5_TX_C_DN<85>")
	)
	(segment
		(start 126.910084 -406.308052)
		(end 127.037338 -406.180798)
		(width 0.1651)
		(layer "In7.Cu")
		(net "P5E_PEX1_STN5_TX_C_DN<85>")
	)
	(segment
		(start 140.415518 -346.477082)
		(end 140.415518 -345.755976)
		(width 0.1651)
		(layer "In7.Cu")
		(net "P5E_PEX1_STN5_TX_C_DN<85>")
	)
	(segment
		(start 137.373868 -390.617202)
		(end 138.49604 -389.967724)
		(width 0.1651)
		(layer "In7.Cu")
		(net "P5E_PEX1_STN5_TX_C_DN<85>")
	)
	(segment
		(start 138.861038 -348.031562)
		(end 140.415518 -346.477082)
		(width 0.1651)
		(layer "In7.Cu")
		(net "P5E_PEX1_STN5_TX_C_DN<85>")
	)
	(segment
		(start 138.49604 -389.967724)
		(end 139.813538 -388.872984)
		(width 0.1651)
		(layer "In7.Cu")
		(net "P5E_PEX1_STN5_TX_C_DN<85>")
	)
	(segment
		(start 128.233678 -394.974318)
		(end 129.075942 -394.132054)
		(width 0.1651)
		(layer "In7.Cu")
		(net "P5E_PEX1_STN5_TX_C_DN<85>")
	)
	(segment
		(start 139.455906 -362.324904)
		(end 138.861038 -358.31526)
		(width 0.1651)
		(layer "In7.Cu")
		(net "P5E_PEX1_STN5_TX_C_DN<85>")
	)
	(segment
		(start 127.969518 -396.337028)
		(end 128.233678 -394.974318)
		(width 0.1651)
		(layer "In7.Cu")
		(net "P5E_PEX1_STN5_TX_C_DN<85>")
	)
	(segment
		(start 141.351 -369.94973)
		(end 141.351 -368.572034)
		(width 0.1651)
		(layer "In7.Cu")
		(net "P5E_PEX1_STN5_TX_C_DN<85>")
	)
	(segment
		(start 39.013892 -125.519942)
		(end 38.693852 -125.199902)
		(width 0.13462)
		(layer "F.Cu")
		(net "P5E_PEX0_STN1_TX_DP<27>")
	)
	(segment
		(start 38.693852 -125.199902)
		(end 38.062408 -125.199902)
		(width 0.13462)
		(layer "F.Cu")
		(net "P5E_PEX0_STN1_TX_DP<27>")
	)
	(segment
		(start 38.062408 -125.199902)
		(end 37.767768 -125.494542)
		(width 0.13462)
		(layer "F.Cu")
		(net "P5E_PEX0_STN1_TX_DP<27>")
	)
	(segment
		(start 34.059368 -129.01168)
		(end 34.090864 -129.170176)
		(width 0.1651)
		(layer "In9.Cu")
		(net "P5E_PEX0_STN1_TX_DP<27>")
	)
	(segment
		(start 32.979614 -130.627628)
		(end 32.704532 -131.039362)
		(width 0.1651)
		(layer "In9.Cu")
		(net "P5E_PEX0_STN1_TX_DP<27>")
	)
	(segment
		(start 35.280092 -127.184912)
		(end 35.304476 -127.308356)
		(width 0.1651)
		(layer "In9.Cu")
		(net "P5E_PEX0_STN1_TX_DP<27>")
	)
	(segment
		(start 69.985636 -280.129488)
		(end 70.099936 -280.015188)
		(width 0.1143)
		(layer "In9.Cu")
		(net "P5E_PEX0_STN1_TX_DP<27>")
	)
	(segment
		(start 34.697924 -128.216152)
		(end 34.45764 -128.575562)
		(width 0.1651)
		(layer "In9.Cu")
		(net "P5E_PEX0_STN1_TX_DP<27>")
	)
	(segment
		(start 32.57296 -139.95273)
		(end 32.762444 -140.410438)
		(width 0.1651)
		(layer "In9.Cu")
		(net "P5E_PEX0_STN1_TX_DP<27>")
	)
	(segment
		(start 35.988752 -126.124208)
		(end 35.280092 -127.184912)
		(width 0.1651)
		(layer "In9.Cu")
		(net "P5E_PEX0_STN1_TX_DP<27>")
	)
	(segment
		(start 69.765926 -271.526)
		(end 69.765926 -271.554448)
		(width 0.1143)
		(layer "In9.Cu")
		(net "P5E_PEX0_STN1_TX_DP<27>")
	)
	(segment
		(start 34.413444 -157.341062)
		(end 35.29076 -161.75228)
		(width 0.1651)
		(layer "In9.Cu")
		(net "P5E_PEX0_STN1_TX_DP<27>")
	)
	(segment
		(start 69.765926 -271.554448)
		(end 69.720206 -271.600168)
		(width 0.1143)
		(layer "In9.Cu")
		(net "P5E_PEX0_STN1_TX_DP<27>")
	)
	(segment
		(start 69.765926 -263.596628)
		(end 69.765926 -271.526)
		(width 0.1651)
		(layer "In9.Cu")
		(net "P5E_PEX0_STN1_TX_DP<27>")
	)
	(segment
		(start 32.889952 -141.017244)
		(end 33.00603 -141.06525)
		(width 0.1651)
		(layer "In9.Cu")
		(net "P5E_PEX0_STN1_TX_DP<27>")
	)
	(segment
		(start 35.064446 -127.667512)
		(end 34.941002 -127.69215)
		(width 0.1651)
		(layer "In9.Cu")
		(net "P5E_PEX0_STN1_TX_DP<27>")
	)
	(segment
		(start 34.090864 -129.170176)
		(end 33.815528 -129.582164)
		(width 0.1651)
		(layer "In9.Cu")
		(net "P5E_PEX0_STN1_TX_DP<27>")
	)
	(segment
		(start 33.00603 -141.06525)
		(end 33.195768 -141.523212)
		(width 0.1651)
		(layer "In9.Cu")
		(net "P5E_PEX0_STN1_TX_DP<27>")
	)
	(segment
		(start 32.106362 -138.82624)
		(end 32.295846 -139.283948)
		(width 0.1651)
		(layer "In9.Cu")
		(net "P5E_PEX0_STN1_TX_DP<27>")
	)
	(segment
		(start 34.062162 -150.200614)
		(end 34.413444 -157.341062)
		(width 0.1651)
		(layer "In9.Cu")
		(net "P5E_PEX0_STN1_TX_DP<27>")
	)
	(segment
		(start 32.704532 -131.039362)
		(end 32.736028 -131.197858)
		(width 0.1651)
		(layer "In9.Cu")
		(net "P5E_PEX0_STN1_TX_DP<27>")
	)
	(segment
		(start 31.132272 -134.125716)
		(end 31.132272 -136.774428)
		(width 0.1651)
		(layer "In9.Cu")
		(net "P5E_PEX0_STN1_TX_DP<27>")
	)
	(segment
		(start 70.099936 -280.015188)
		(end 70.099936 -279.749504)
		(width 0.1143)
		(layer "In9.Cu")
		(net "P5E_PEX0_STN1_TX_DP<27>")
	)
	(segment
		(start 34.45764 -128.575562)
		(end 34.33445 -128.599946)
		(width 0.1651)
		(layer "In9.Cu")
		(net "P5E_PEX0_STN1_TX_DP<27>")
	)
	(segment
		(start 33.147762 -141.63929)
		(end 33.707578 -142.991078)
		(width 0.1651)
		(layer "In9.Cu")
		(net "P5E_PEX0_STN1_TX_DP<27>")
	)
	(segment
		(start 33.413446 -130.184144)
		(end 33.13811 -130.596132)
		(width 0.1651)
		(layer "In9.Cu")
		(net "P5E_PEX0_STN1_TX_DP<27>")
	)
	(segment
		(start 33.815528 -129.582164)
		(end 33.657032 -129.613914)
		(width 0.1651)
		(layer "In9.Cu")
		(net "P5E_PEX0_STN1_TX_DP<27>")
	)
	(segment
		(start 36.909248 -125.203712)
		(end 35.988752 -126.124208)
		(width 0.1651)
		(layer "In9.Cu")
		(net "P5E_PEX0_STN1_TX_DP<27>")
	)
	(segment
		(start 32.23387 -139.4333)
		(end 32.423354 -139.890754)
		(width 0.1651)
		(layer "In9.Cu")
		(net "P5E_PEX0_STN1_TX_DP<27>")
	)
	(segment
		(start 31.63951 -137.69975)
		(end 31.828994 -138.157458)
		(width 0.1651)
		(layer "In9.Cu")
		(net "P5E_PEX0_STN1_TX_DP<27>")
	)
	(segment
		(start 31.489904 -137.637774)
		(end 31.63951 -137.69975)
		(width 0.1651)
		(layer "In9.Cu")
		(net "P5E_PEX0_STN1_TX_DP<27>")
	)
	(segment
		(start 33.195768 -141.523212)
		(end 33.147762 -141.63929)
		(width 0.1651)
		(layer "In9.Cu")
		(net "P5E_PEX0_STN1_TX_DP<27>")
	)
	(segment
		(start 31.931356 -132.196332)
		(end 31.132272 -134.125716)
		(width 0.1651)
		(layer "In9.Cu")
		(net "P5E_PEX0_STN1_TX_DP<27>")
	)
	(segment
		(start 69.720206 -271.600168)
		(end 69.720206 -280.025856)
		(width 0.1143)
		(layer "In9.Cu")
		(net "P5E_PEX0_STN1_TX_DP<27>")
	)
	(segment
		(start 31.132272 -136.774428)
		(end 31.489904 -137.637774)
		(width 0.1651)
		(layer "In9.Cu")
		(net "P5E_PEX0_STN1_TX_DP<27>")
	)
	(segment
		(start 33.657032 -129.613914)
		(end 33.38195 -130.025648)
		(width 0.1651)
		(layer "In9.Cu")
		(net "P5E_PEX0_STN1_TX_DP<27>")
	)
	(segment
		(start 32.423354 -139.890754)
		(end 32.57296 -139.95273)
		(width 0.1651)
		(layer "In9.Cu")
		(net "P5E_PEX0_STN1_TX_DP<27>")
	)
	(segment
		(start 34.673286 -128.092962)
		(end 34.697924 -128.216152)
		(width 0.1651)
		(layer "In9.Cu")
		(net "P5E_PEX0_STN1_TX_DP<27>")
	)
	(segment
		(start 31.767272 -138.30681)
		(end 31.956756 -138.764264)
		(width 0.1651)
		(layer "In9.Cu")
		(net "P5E_PEX0_STN1_TX_DP<27>")
	)
	(segment
		(start 32.762444 -140.410438)
		(end 32.700468 -140.55979)
		(width 0.1651)
		(layer "In9.Cu")
		(net "P5E_PEX0_STN1_TX_DP<27>")
	)
	(segment
		(start 34.33445 -128.599946)
		(end 34.059368 -129.01168)
		(width 0.1651)
		(layer "In9.Cu")
		(net "P5E_PEX0_STN1_TX_DP<27>")
	)
	(segment
		(start 37.476938 -125.203712)
		(end 36.909248 -125.203712)
		(width 0.1651)
		(layer "In9.Cu")
		(net "P5E_PEX0_STN1_TX_DP<27>")
	)
	(segment
		(start 31.828994 -138.157458)
		(end 31.767272 -138.30681)
		(width 0.1651)
		(layer "In9.Cu")
		(net "P5E_PEX0_STN1_TX_DP<27>")
	)
	(segment
		(start 35.29076 -161.75228)
		(end 69.765926 -263.596628)
		(width 0.1651)
		(layer "In9.Cu")
		(net "P5E_PEX0_STN1_TX_DP<27>")
	)
	(segment
		(start 32.295846 -139.283948)
		(end 32.23387 -139.4333)
		(width 0.1651)
		(layer "In9.Cu")
		(net "P5E_PEX0_STN1_TX_DP<27>")
	)
	(segment
		(start 32.700468 -140.55979)
		(end 32.889952 -141.017244)
		(width 0.1651)
		(layer "In9.Cu")
		(net "P5E_PEX0_STN1_TX_DP<27>")
	)
	(segment
		(start 69.823838 -280.129488)
		(end 69.985636 -280.129488)
		(width 0.1143)
		(layer "In9.Cu")
		(net "P5E_PEX0_STN1_TX_DP<27>")
	)
	(segment
		(start 32.736028 -131.197858)
		(end 32.460692 -131.609846)
		(width 0.1651)
		(layer "In9.Cu")
		(net "P5E_PEX0_STN1_TX_DP<27>")
	)
	(segment
		(start 69.720206 -280.025856)
		(end 69.823838 -280.129488)
		(width 0.1143)
		(layer "In9.Cu")
		(net "P5E_PEX0_STN1_TX_DP<27>")
	)
	(segment
		(start 33.707578 -142.991078)
		(end 34.062162 -150.200614)
		(width 0.1651)
		(layer "In9.Cu")
		(net "P5E_PEX0_STN1_TX_DP<27>")
	)
	(segment
		(start 35.304476 -127.308356)
		(end 35.064446 -127.667512)
		(width 0.1651)
		(layer "In9.Cu")
		(net "P5E_PEX0_STN1_TX_DP<27>")
	)
	(segment
		(start 32.302196 -131.641342)
		(end 31.931356 -132.196332)
		(width 0.1651)
		(layer "In9.Cu")
		(net "P5E_PEX0_STN1_TX_DP<27>")
	)
	(segment
		(start 33.38195 -130.025648)
		(end 33.413446 -130.184144)
		(width 0.1651)
		(layer "In9.Cu")
		(net "P5E_PEX0_STN1_TX_DP<27>")
	)
	(segment
		(start 33.13811 -130.596132)
		(end 32.979614 -130.627628)
		(width 0.1651)
		(layer "In9.Cu")
		(net "P5E_PEX0_STN1_TX_DP<27>")
	)
	(segment
		(start 37.767768 -125.494542)
		(end 37.476938 -125.203712)
		(width 0.1651)
		(layer "In9.Cu")
		(net "P5E_PEX0_STN1_TX_DP<27>")
	)
	(segment
		(start 31.956756 -138.764264)
		(end 32.106362 -138.82624)
		(width 0.1651)
		(layer "In9.Cu")
		(net "P5E_PEX0_STN1_TX_DP<27>")
	)
	(segment
		(start 32.460692 -131.609846)
		(end 32.302196 -131.641342)
		(width 0.1651)
		(layer "In9.Cu")
		(net "P5E_PEX0_STN1_TX_DP<27>")
	)
	(segment
		(start 34.941002 -127.69215)
		(end 34.673286 -128.092962)
		(width 0.1651)
		(layer "In9.Cu")
		(net "P5E_PEX0_STN1_TX_DP<27>")
	)
	(segment
		(start 152.151588 -112.489742)
		(end 151.520144 -112.489742)
		(width 0.13462)
		(layer "F.Cu")
		(net "P5E_PEX1_STN1_TX_DP<23>")
	)
	(segment
		(start 152.471628 -112.809782)
		(end 152.151588 -112.489742)
		(width 0.13462)
		(layer "F.Cu")
		(net "P5E_PEX1_STN1_TX_DP<23>")
	)
	(segment
		(start 151.520144 -112.489742)
		(end 151.225504 -112.784382)
		(width 0.13462)
		(layer "F.Cu")
		(net "P5E_PEX1_STN1_TX_DP<23>")
	)
	(segment
		(start 147.22729 -161.525712)
		(end 182.06593 -264.448036)
		(width 0.1651)
		(layer "In9.Cu")
		(net "P5E_PEX1_STN1_TX_DP<23>")
	)
	(segment
		(start 149.26945 -114.91087)
		(end 149.079966 -115.368324)
		(width 0.1651)
		(layer "In9.Cu")
		(net "P5E_PEX1_STN1_TX_DP<23>")
	)
	(segment
		(start 147.680172 -118.747794)
		(end 147.742148 -118.897146)
		(width 0.1651)
		(layer "In9.Cu")
		(net "P5E_PEX1_STN1_TX_DP<23>")
	)
	(segment
		(start 146.17065 -122.392186)
		(end 143.36141 -131.652518)
		(width 0.1651)
		(layer "In9.Cu")
		(net "P5E_PEX1_STN1_TX_DP<23>")
	)
	(segment
		(start 146.65071 -158.62681)
		(end 147.22729 -161.525712)
		(width 0.1651)
		(layer "In9.Cu")
		(net "P5E_PEX1_STN1_TX_DP<23>")
	)
	(segment
		(start 147.403058 -119.41683)
		(end 147.213574 -119.874284)
		(width 0.1651)
		(layer "In9.Cu")
		(net "P5E_PEX1_STN1_TX_DP<23>")
	)
	(segment
		(start 149.141942 -115.517676)
		(end 148.952458 -115.975638)
		(width 0.1651)
		(layer "In9.Cu")
		(net "P5E_PEX1_STN1_TX_DP<23>")
	)
	(segment
		(start 150.21306 -112.632744)
		(end 149.901402 -113.385092)
		(width 0.1651)
		(layer "In9.Cu")
		(net "P5E_PEX1_STN1_TX_DP<23>")
	)
	(segment
		(start 148.952458 -115.975638)
		(end 148.802852 -116.03736)
		(width 0.1651)
		(layer "In9.Cu")
		(net "P5E_PEX1_STN1_TX_DP<23>")
	)
	(segment
		(start 148.675344 -116.644166)
		(end 148.48586 -117.102128)
		(width 0.1651)
		(layer "In9.Cu")
		(net "P5E_PEX1_STN1_TX_DP<23>")
	)
	(segment
		(start 143.36141 -131.652518)
		(end 143.36141 -137.570718)
		(width 0.1651)
		(layer "In9.Cu")
		(net "P5E_PEX1_STN1_TX_DP<23>")
	)
	(segment
		(start 149.949662 -113.501424)
		(end 149.784054 -113.900458)
		(width 0.1651)
		(layer "In9.Cu")
		(net "P5E_PEX1_STN1_TX_DP<23>")
	)
	(segment
		(start 143.36141 -137.570718)
		(end 145.919698 -143.746474)
		(width 0.1651)
		(layer "In9.Cu")
		(net "P5E_PEX1_STN1_TX_DP<23>")
	)
	(segment
		(start 148.14677 -117.621304)
		(end 148.208746 -117.770656)
		(width 0.1651)
		(layer "In9.Cu")
		(net "P5E_PEX1_STN1_TX_DP<23>")
	)
	(segment
		(start 148.613368 -116.494814)
		(end 148.675344 -116.644166)
		(width 0.1651)
		(layer "In9.Cu")
		(net "P5E_PEX1_STN1_TX_DP<23>")
	)
	(segment
		(start 182.123842 -280.129488)
		(end 182.28564 -280.129488)
		(width 0.1143)
		(layer "In9.Cu")
		(net "P5E_PEX1_STN1_TX_DP<23>")
	)
	(segment
		(start 148.802852 -116.03736)
		(end 148.613368 -116.494814)
		(width 0.1651)
		(layer "In9.Cu")
		(net "P5E_PEX1_STN1_TX_DP<23>")
	)
	(segment
		(start 182.02021 -280.025856)
		(end 182.123842 -280.129488)
		(width 0.1143)
		(layer "In9.Cu")
		(net "P5E_PEX1_STN1_TX_DP<23>")
	)
	(segment
		(start 147.116546 -120.469152)
		(end 146.93646 -120.54332)
		(width 0.1651)
		(layer "In9.Cu")
		(net "P5E_PEX1_STN1_TX_DP<23>")
	)
	(segment
		(start 146.649948 -121.595642)
		(end 146.469862 -121.66981)
		(width 0.1651)
		(layer "In9.Cu")
		(net "P5E_PEX1_STN1_TX_DP<23>")
	)
	(segment
		(start 147.869656 -118.29034)
		(end 147.680172 -118.747794)
		(width 0.1651)
		(layer "In9.Cu")
		(net "P5E_PEX1_STN1_TX_DP<23>")
	)
	(segment
		(start 149.079966 -115.368324)
		(end 149.141942 -115.517676)
		(width 0.1651)
		(layer "In9.Cu")
		(net "P5E_PEX1_STN1_TX_DP<23>")
	)
	(segment
		(start 147.742148 -118.897146)
		(end 147.552664 -119.355108)
		(width 0.1651)
		(layer "In9.Cu")
		(net "P5E_PEX1_STN1_TX_DP<23>")
	)
	(segment
		(start 150.934674 -112.493552)
		(end 150.352252 -112.493552)
		(width 0.1651)
		(layer "In9.Cu")
		(net "P5E_PEX1_STN1_TX_DP<23>")
	)
	(segment
		(start 148.208746 -117.770656)
		(end 148.019262 -118.228618)
		(width 0.1651)
		(layer "In9.Cu")
		(net "P5E_PEX1_STN1_TX_DP<23>")
	)
	(segment
		(start 146.469862 -121.66981)
		(end 146.17065 -122.392186)
		(width 0.1651)
		(layer "In9.Cu")
		(net "P5E_PEX1_STN1_TX_DP<23>")
	)
	(segment
		(start 146.746976 -121.000774)
		(end 146.821652 -121.180606)
		(width 0.1651)
		(layer "In9.Cu")
		(net "P5E_PEX1_STN1_TX_DP<23>")
	)
	(segment
		(start 182.28564 -280.129488)
		(end 182.39994 -280.015188)
		(width 0.1143)
		(layer "In9.Cu")
		(net "P5E_PEX1_STN1_TX_DP<23>")
	)
	(segment
		(start 182.02021 -271.600168)
		(end 182.02021 -280.025856)
		(width 0.1143)
		(layer "In9.Cu")
		(net "P5E_PEX1_STN1_TX_DP<23>")
	)
	(segment
		(start 149.502876 -114.347498)
		(end 149.550882 -114.463576)
		(width 0.1651)
		(layer "In9.Cu")
		(net "P5E_PEX1_STN1_TX_DP<23>")
	)
	(segment
		(start 147.213574 -119.874284)
		(end 147.28825 -120.054116)
		(width 0.1651)
		(layer "In9.Cu")
		(net "P5E_PEX1_STN1_TX_DP<23>")
	)
	(segment
		(start 146.821652 -121.180606)
		(end 146.649948 -121.595642)
		(width 0.1651)
		(layer "In9.Cu")
		(net "P5E_PEX1_STN1_TX_DP<23>")
	)
	(segment
		(start 149.385528 -114.862864)
		(end 149.26945 -114.91087)
		(width 0.1651)
		(layer "In9.Cu")
		(net "P5E_PEX1_STN1_TX_DP<23>")
	)
	(segment
		(start 182.06593 -264.448036)
		(end 182.06593 -271.526)
		(width 0.1651)
		(layer "In9.Cu")
		(net "P5E_PEX1_STN1_TX_DP<23>")
	)
	(segment
		(start 150.352252 -112.493552)
		(end 150.21306 -112.632744)
		(width 0.1651)
		(layer "In9.Cu")
		(net "P5E_PEX1_STN1_TX_DP<23>")
	)
	(segment
		(start 151.225504 -112.784382)
		(end 150.934674 -112.493552)
		(width 0.1651)
		(layer "In9.Cu")
		(net "P5E_PEX1_STN1_TX_DP<23>")
	)
	(segment
		(start 149.784054 -113.900458)
		(end 149.667976 -113.948718)
		(width 0.1651)
		(layer "In9.Cu")
		(net "P5E_PEX1_STN1_TX_DP<23>")
	)
	(segment
		(start 145.919698 -143.746474)
		(end 146.65071 -158.62681)
		(width 0.1651)
		(layer "In9.Cu")
		(net "P5E_PEX1_STN1_TX_DP<23>")
	)
	(segment
		(start 149.901402 -113.385092)
		(end 149.949662 -113.501424)
		(width 0.1651)
		(layer "In9.Cu")
		(net "P5E_PEX1_STN1_TX_DP<23>")
	)
	(segment
		(start 146.93646 -120.54332)
		(end 146.746976 -121.000774)
		(width 0.1651)
		(layer "In9.Cu")
		(net "P5E_PEX1_STN1_TX_DP<23>")
	)
	(segment
		(start 148.48586 -117.102128)
		(end 148.336254 -117.16385)
		(width 0.1651)
		(layer "In9.Cu")
		(net "P5E_PEX1_STN1_TX_DP<23>")
	)
	(segment
		(start 182.06593 -271.554448)
		(end 182.02021 -271.600168)
		(width 0.1143)
		(layer "In9.Cu")
		(net "P5E_PEX1_STN1_TX_DP<23>")
	)
	(segment
		(start 148.019262 -118.228618)
		(end 147.869656 -118.29034)
		(width 0.1651)
		(layer "In9.Cu")
		(net "P5E_PEX1_STN1_TX_DP<23>")
	)
	(segment
		(start 147.28825 -120.054116)
		(end 147.116546 -120.469152)
		(width 0.1651)
		(layer "In9.Cu")
		(net "P5E_PEX1_STN1_TX_DP<23>")
	)
	(segment
		(start 182.06593 -271.526)
		(end 182.06593 -271.554448)
		(width 0.1143)
		(layer "In9.Cu")
		(net "P5E_PEX1_STN1_TX_DP<23>")
	)
	(segment
		(start 147.552664 -119.355108)
		(end 147.403058 -119.41683)
		(width 0.1651)
		(layer "In9.Cu")
		(net "P5E_PEX1_STN1_TX_DP<23>")
	)
	(segment
		(start 149.550882 -114.463576)
		(end 149.385528 -114.862864)
		(width 0.1651)
		(layer "In9.Cu")
		(net "P5E_PEX1_STN1_TX_DP<23>")
	)
	(segment
		(start 182.39994 -280.015188)
		(end 182.39994 -279.749504)
		(width 0.1143)
		(layer "In9.Cu")
		(net "P5E_PEX1_STN1_TX_DP<23>")
	)
	(segment
		(start 149.667976 -113.948718)
		(end 149.502876 -114.347498)
		(width 0.1651)
		(layer "In9.Cu")
		(net "P5E_PEX1_STN1_TX_DP<23>")
	)
	(segment
		(start 148.336254 -117.16385)
		(end 148.14677 -117.621304)
		(width 0.1651)
		(layer "In9.Cu")
		(net "P5E_PEX1_STN1_TX_DP<23>")
	)
	(segment
		(start 153.524712 -302.223424)
		(end 153.524712 -302.455326)
		(width 0.1143)
		(layer "In9.Cu")
		(net "P5E_PEX1_STN7_RX_DP<113>")
	)
	(segment
		(start 142.972536 -303.35601)
		(end 144.039082 -302.914304)
		(width 0.1651)
		(layer "In9.Cu")
		(net "P5E_PEX1_STN7_RX_DP<113>")
	)
	(segment
		(start 158.60395 -392.496548)
		(end 154.479752 -389.133334)
		(width 0.1651)
		(layer "In9.Cu")
		(net "P5E_PEX1_STN7_RX_DP<113>")
	)
	(segment
		(start 151.765 -301.933864)
		(end 151.793448 -301.933864)
		(width 0.1143)
		(layer "In9.Cu")
		(net "P5E_PEX1_STN7_RX_DP<113>")
	)
	(segment
		(start 151.839168 -301.979584)
		(end 153.280872 -301.979584)
		(width 0.1143)
		(layer "In9.Cu")
		(net "P5E_PEX1_STN7_RX_DP<113>")
	)
	(segment
		(start 144.039082 -302.914304)
		(end 147.549616 -302.262032)
		(width 0.1651)
		(layer "In9.Cu")
		(net "P5E_PEX1_STN7_RX_DP<113>")
	)
	(segment
		(start 153.6192 -302.549814)
		(end 153.89987 -302.549814)
		(width 0.1143)
		(layer "In9.Cu")
		(net "P5E_PEX1_STN7_RX_DP<113>")
	)
	(segment
		(start 154.479752 -389.133334)
		(end 152.56256 -385.65201)
		(width 0.1651)
		(layer "In9.Cu")
		(net "P5E_PEX1_STN7_RX_DP<113>")
	)
	(segment
		(start 153.280872 -301.979584)
		(end 153.524712 -302.223424)
		(width 0.1143)
		(layer "In9.Cu")
		(net "P5E_PEX1_STN7_RX_DP<113>")
	)
	(segment
		(start 147.549616 -302.262032)
		(end 148.601938 -301.933864)
		(width 0.1651)
		(layer "In9.Cu")
		(net "P5E_PEX1_STN7_RX_DP<113>")
	)
	(segment
		(start 145.845276 -342.045544)
		(end 135.147558 -324.736714)
		(width 0.1651)
		(layer "In9.Cu")
		(net "P5E_PEX1_STN7_RX_DP<113>")
	)
	(segment
		(start 151.793448 -301.933864)
		(end 151.839168 -301.979584)
		(width 0.1143)
		(layer "In9.Cu")
		(net "P5E_PEX1_STN7_RX_DP<113>")
	)
	(segment
		(start 162.4584 -409.799282)
		(end 162.992308 -409.265374)
		(width 0.1651)
		(layer "In9.Cu")
		(net "P5E_PEX1_STN7_RX_DP<113>")
	)
	(segment
		(start 162.992308 -395.072108)
		(end 162.603942 -394.683742)
		(width 0.1651)
		(layer "In9.Cu")
		(net "P5E_PEX1_STN7_RX_DP<113>")
	)
	(segment
		(start 162.109912 -409.672282)
		(end 162.236912 -409.799282)
		(width 0.1651)
		(layer "In9.Cu")
		(net "P5E_PEX1_STN7_RX_DP<113>")
	)
	(segment
		(start 153.524712 -302.455326)
		(end 153.6192 -302.549814)
		(width 0.1143)
		(layer "In9.Cu")
		(net "P5E_PEX1_STN7_RX_DP<113>")
	)
	(segment
		(start 162.992308 -409.265374)
		(end 162.992308 -395.072108)
		(width 0.1651)
		(layer "In9.Cu")
		(net "P5E_PEX1_STN7_RX_DP<113>")
	)
	(segment
		(start 139.564872 -306.763674)
		(end 142.972536 -303.35601)
		(width 0.1651)
		(layer "In9.Cu")
		(net "P5E_PEX1_STN7_RX_DP<113>")
	)
	(segment
		(start 148.601938 -301.933864)
		(end 151.765 -301.933864)
		(width 0.1651)
		(layer "In9.Cu")
		(net "P5E_PEX1_STN7_RX_DP<113>")
	)
	(segment
		(start 162.109658 -394.189458)
		(end 161.70021 -393.78001)
		(width 0.1651)
		(layer "In9.Cu")
		(net "P5E_PEX1_STN7_RX_DP<113>")
	)
	(segment
		(start 147.175982 -345.761818)
		(end 145.845276 -342.045544)
		(width 0.1651)
		(layer "In9.Cu")
		(net "P5E_PEX1_STN7_RX_DP<113>")
	)
	(segment
		(start 162.236912 -409.799282)
		(end 162.4584 -409.799282)
		(width 0.1651)
		(layer "In9.Cu")
		(net "P5E_PEX1_STN7_RX_DP<113>")
	)
	(segment
		(start 134.718552 -323.139054)
		(end 134.718552 -317.689484)
		(width 0.1651)
		(layer "In9.Cu")
		(net "P5E_PEX1_STN7_RX_DP<113>")
	)
	(segment
		(start 162.603942 -394.683742)
		(end 162.460178 -394.683742)
		(width 0.1651)
		(layer "In9.Cu")
		(net "P5E_PEX1_STN7_RX_DP<113>")
	)
	(segment
		(start 152.56256 -385.65201)
		(end 147.175982 -345.761818)
		(width 0.1651)
		(layer "In9.Cu")
		(net "P5E_PEX1_STN7_RX_DP<113>")
	)
	(segment
		(start 161.70021 -393.78001)
		(end 158.60395 -392.496548)
		(width 0.1651)
		(layer "In9.Cu")
		(net "P5E_PEX1_STN7_RX_DP<113>")
	)
	(segment
		(start 162.460178 -394.683742)
		(end 162.109658 -394.333222)
		(width 0.1651)
		(layer "In9.Cu")
		(net "P5E_PEX1_STN7_RX_DP<113>")
	)
	(segment
		(start 162.109658 -394.333222)
		(end 162.109658 -394.189458)
		(width 0.1651)
		(layer "In9.Cu")
		(net "P5E_PEX1_STN7_RX_DP<113>")
	)
	(segment
		(start 162.109912 -409.290012)
		(end 162.109912 -409.672282)
		(width 0.1651)
		(layer "In9.Cu")
		(net "P5E_PEX1_STN7_RX_DP<113>")
	)
	(segment
		(start 135.147558 -324.736714)
		(end 134.718552 -323.139054)
		(width 0.1651)
		(layer "In9.Cu")
		(net "P5E_PEX1_STN7_RX_DP<113>")
	)
	(segment
		(start 134.718552 -317.689484)
		(end 139.564872 -306.763674)
		(width 0.1651)
		(layer "In9.Cu")
		(net "P5E_PEX1_STN7_RX_DP<113>")
	)
	(segment
		(start 175.190912 -345.170506)
		(end 175.190912 -344.539062)
		(width 0.13462)
		(layer "F.Cu")
		(net "P5E_PEX1_STN7_TX_C_DN<118>")
	)
	(segment
		(start 175.485552 -345.465146)
		(end 175.190912 -345.170506)
		(width 0.13462)
		(layer "F.Cu")
		(net "P5E_PEX1_STN7_TX_C_DN<118>")
	)
	(segment
		(start 175.190912 -344.539062)
		(end 175.510952 -344.219022)
		(width 0.13462)
		(layer "F.Cu")
		(net "P5E_PEX1_STN7_TX_C_DN<118>")
	)
	(segment
		(start 172.164502 -392.767058)
		(end 170.673014 -391.847832)
		(width 0.1651)
		(layer "In11.Cu")
		(net "P5E_PEX1_STN7_TX_C_DN<118>")
	)
	(segment
		(start 173.640242 -348.068646)
		(end 175.194722 -346.514166)
		(width 0.1651)
		(layer "In11.Cu")
		(net "P5E_PEX1_STN7_TX_C_DN<118>")
	)
	(segment
		(start 164.17671 -388.82447)
		(end 160.635696 -387.655054)
		(width 0.1651)
		(layer "In11.Cu")
		(net "P5E_PEX1_STN7_TX_C_DN<118>")
	)
	(segment
		(start 173.10989 -401.308062)
		(end 173.23689 -401.181062)
		(width 0.1651)
		(layer "In11.Cu")
		(net "P5E_PEX1_STN7_TX_C_DN<118>")
	)
	(segment
		(start 157.932882 -384.517138)
		(end 157.741112 -382.305306)
		(width 0.1651)
		(layer "In11.Cu")
		(net "P5E_PEX1_STN7_TX_C_DN<118>")
	)
	(segment
		(start 173.969426 -401.181062)
		(end 174.274988 -400.8755)
		(width 0.1651)
		(layer "In11.Cu")
		(net "P5E_PEX1_STN7_TX_C_DN<118>")
	)
	(segment
		(start 170.936412 -361.29468)
		(end 173.640242 -358.59085)
		(width 0.1651)
		(layer "In11.Cu")
		(net "P5E_PEX1_STN7_TX_C_DN<118>")
	)
	(segment
		(start 158.587186 -386.13461)
		(end 157.932882 -384.517138)
		(width 0.1651)
		(layer "In11.Cu")
		(net "P5E_PEX1_STN7_TX_C_DN<118>")
	)
	(segment
		(start 158.446216 -367.467388)
		(end 159.978852 -365.894366)
		(width 0.1651)
		(layer "In11.Cu")
		(net "P5E_PEX1_STN7_TX_C_DN<118>")
	)
	(segment
		(start 173.23689 -401.181062)
		(end 173.969426 -401.181062)
		(width 0.1651)
		(layer "In11.Cu")
		(net "P5E_PEX1_STN7_TX_C_DN<118>")
	)
	(segment
		(start 174.274988 -400.8755)
		(end 174.274988 -394.877544)
		(width 0.1651)
		(layer "In11.Cu")
		(net "P5E_PEX1_STN7_TX_C_DN<118>")
	)
	(segment
		(start 173.10989 -401.690078)
		(end 173.10989 -401.308062)
		(width 0.1651)
		(layer "In11.Cu")
		(net "P5E_PEX1_STN7_TX_C_DN<118>")
	)
	(segment
		(start 174.274988 -394.877544)
		(end 172.164502 -392.767058)
		(width 0.1651)
		(layer "In11.Cu")
		(net "P5E_PEX1_STN7_TX_C_DN<118>")
	)
	(segment
		(start 159.978852 -365.894366)
		(end 170.936412 -361.29468)
		(width 0.1651)
		(layer "In11.Cu")
		(net "P5E_PEX1_STN7_TX_C_DN<118>")
	)
	(segment
		(start 175.194722 -345.755976)
		(end 175.485552 -345.465146)
		(width 0.1651)
		(layer "In11.Cu")
		(net "P5E_PEX1_STN7_TX_C_DN<118>")
	)
	(segment
		(start 160.635696 -387.655054)
		(end 158.587186 -386.13461)
		(width 0.1651)
		(layer "In11.Cu")
		(net "P5E_PEX1_STN7_TX_C_DN<118>")
	)
	(segment
		(start 157.741112 -382.305306)
		(end 157.905196 -368.89817)
		(width 0.1651)
		(layer "In11.Cu")
		(net "P5E_PEX1_STN7_TX_C_DN<118>")
	)
	(segment
		(start 173.640242 -358.59085)
		(end 173.640242 -348.068646)
		(width 0.1651)
		(layer "In11.Cu")
		(net "P5E_PEX1_STN7_TX_C_DN<118>")
	)
	(segment
		(start 175.194722 -346.514166)
		(end 175.194722 -345.755976)
		(width 0.1651)
		(layer "In11.Cu")
		(net "P5E_PEX1_STN7_TX_C_DN<118>")
	)
	(segment
		(start 170.673014 -391.847832)
		(end 164.17671 -388.82447)
		(width 0.1651)
		(layer "In11.Cu")
		(net "P5E_PEX1_STN7_TX_C_DN<118>")
	)
	(segment
		(start 157.905196 -368.89817)
		(end 158.446216 -367.467388)
		(width 0.1651)
		(layer "In11.Cu")
		(net "P5E_PEX1_STN7_TX_C_DN<118>")
	)
	(segment
		(start 82.928206 -145.311114)
		(end 83.248246 -144.991074)
		(width 0.13462)
		(layer "F.Cu")
		(net "P5E_PEX0_STN0_TX_DP<9>")
	)
	(segment
		(start 83.248246 -144.991074)
		(end 83.87969 -144.991074)
		(width 0.13462)
		(layer "F.Cu")
		(net "P5E_PEX0_STN0_TX_DP<9>")
	)
	(segment
		(start 83.87969 -144.991074)
		(end 84.17433 -145.285714)
		(width 0.13462)
		(layer "F.Cu")
		(net "P5E_PEX0_STN0_TX_DP<9>")
	)
	(segment
		(start 87.108538 -147.047458)
		(end 89.535508 -150.679658)
		(width 0.1651)
		(layer "In9.Cu")
		(net "P5E_PEX0_STN0_TX_DP<9>")
	)
	(segment
		(start 86.000844 -145.939764)
		(end 86.323932 -146.262852)
		(width 0.1651)
		(layer "In9.Cu")
		(net "P5E_PEX0_STN0_TX_DP<9>")
	)
	(segment
		(start 91.179904 -154.64917)
		(end 91.179904 -158.199328)
		(width 0.1651)
		(layer "In9.Cu")
		(net "P5E_PEX0_STN0_TX_DP<9>")
	)
	(segment
		(start 80.54975 -278.534368)
		(end 80.54975 -278.799798)
		(width 0.1143)
		(layer "In9.Cu")
		(net "P5E_PEX0_STN0_TX_DP<9>")
	)
	(segment
		(start 86.783926 -146.722846)
		(end 87.108538 -147.047458)
		(width 0.1651)
		(layer "In9.Cu")
		(net "P5E_PEX0_STN0_TX_DP<9>")
	)
	(segment
		(start 80.914748 -268.933168)
		(end 79.934054 -271.30121)
		(width 0.1651)
		(layer "In9.Cu")
		(net "P5E_PEX0_STN0_TX_DP<9>")
	)
	(segment
		(start 85.055964 -144.994884)
		(end 85.540596 -145.479516)
		(width 0.1651)
		(layer "In9.Cu")
		(net "P5E_PEX0_STN0_TX_DP<9>")
	)
	(segment
		(start 80.43545 -278.420068)
		(end 80.54975 -278.534368)
		(width 0.1143)
		(layer "In9.Cu")
		(net "P5E_PEX0_STN0_TX_DP<9>")
	)
	(segment
		(start 86.647528 -146.722846)
		(end 86.783926 -146.722846)
		(width 0.1651)
		(layer "In9.Cu")
		(net "P5E_PEX0_STN0_TX_DP<9>")
	)
	(segment
		(start 85.540596 -145.479516)
		(end 85.540596 -145.616168)
		(width 0.1651)
		(layer "In9.Cu")
		(net "P5E_PEX0_STN0_TX_DP<9>")
	)
	(segment
		(start 85.540596 -145.616168)
		(end 85.864192 -145.939764)
		(width 0.1651)
		(layer "In9.Cu")
		(net "P5E_PEX0_STN0_TX_DP<9>")
	)
	(segment
		(start 79.979774 -271.546066)
		(end 79.979774 -278.205184)
		(width 0.1143)
		(layer "In9.Cu")
		(net "P5E_PEX0_STN0_TX_DP<9>")
	)
	(segment
		(start 77.552296 -221.85376)
		(end 80.914748 -260.32714)
		(width 0.1651)
		(layer "In9.Cu")
		(net "P5E_PEX0_STN0_TX_DP<9>")
	)
	(segment
		(start 80.914748 -260.32714)
		(end 80.914748 -268.933168)
		(width 0.1651)
		(layer "In9.Cu")
		(net "P5E_PEX0_STN0_TX_DP<9>")
	)
	(segment
		(start 86.323932 -146.399504)
		(end 86.647528 -146.722846)
		(width 0.1651)
		(layer "In9.Cu")
		(net "P5E_PEX0_STN0_TX_DP<9>")
	)
	(segment
		(start 86.323932 -146.262852)
		(end 86.323932 -146.399504)
		(width 0.1651)
		(layer "In9.Cu")
		(net "P5E_PEX0_STN0_TX_DP<9>")
	)
	(segment
		(start 91.179904 -158.199328)
		(end 82.715608 -172.862748)
		(width 0.1651)
		(layer "In9.Cu")
		(net "P5E_PEX0_STN0_TX_DP<9>")
	)
	(segment
		(start 80.194658 -278.420068)
		(end 80.43545 -278.420068)
		(width 0.1143)
		(layer "In9.Cu")
		(net "P5E_PEX0_STN0_TX_DP<9>")
	)
	(segment
		(start 84.46516 -144.994884)
		(end 85.055964 -144.994884)
		(width 0.1651)
		(layer "In9.Cu")
		(net "P5E_PEX0_STN0_TX_DP<9>")
	)
	(segment
		(start 84.17433 -145.285714)
		(end 84.46516 -144.994884)
		(width 0.1651)
		(layer "In9.Cu")
		(net "P5E_PEX0_STN0_TX_DP<9>")
	)
	(segment
		(start 89.535508 -150.679658)
		(end 91.179904 -154.64917)
		(width 0.1651)
		(layer "In9.Cu")
		(net "P5E_PEX0_STN0_TX_DP<9>")
	)
	(segment
		(start 79.934054 -271.30121)
		(end 79.934054 -271.471898)
		(width 0.1651)
		(layer "In9.Cu")
		(net "P5E_PEX0_STN0_TX_DP<9>")
	)
	(segment
		(start 82.715608 -172.862748)
		(end 81.4197 -177.694844)
		(width 0.1651)
		(layer "In9.Cu")
		(net "P5E_PEX0_STN0_TX_DP<9>")
	)
	(segment
		(start 79.979774 -278.205184)
		(end 80.194658 -278.420068)
		(width 0.1143)
		(layer "In9.Cu")
		(net "P5E_PEX0_STN0_TX_DP<9>")
	)
	(segment
		(start 79.934054 -271.500346)
		(end 79.979774 -271.546066)
		(width 0.1143)
		(layer "In9.Cu")
		(net "P5E_PEX0_STN0_TX_DP<9>")
	)
	(segment
		(start 81.4197 -177.694844)
		(end 77.552296 -221.85376)
		(width 0.1651)
		(layer "In9.Cu")
		(net "P5E_PEX0_STN0_TX_DP<9>")
	)
	(segment
		(start 79.934054 -271.471898)
		(end 79.934054 -271.500346)
		(width 0.1143)
		(layer "In9.Cu")
		(net "P5E_PEX0_STN0_TX_DP<9>")
	)
	(segment
		(start 85.864192 -145.939764)
		(end 86.000844 -145.939764)
		(width 0.1651)
		(layer "In9.Cu")
		(net "P5E_PEX0_STN0_TX_DP<9>")
	)
	(segment
		(start 199.02805 -135.28675)
		(end 199.34809 -135.60679)
		(width 0.13462)
		(layer "F.Cu")
		(net "P5E_PEX1_STN0_TX_DN<7>")
	)
	(segment
		(start 199.34809 -135.60679)
		(end 199.979534 -135.60679)
		(width 0.13462)
		(layer "F.Cu")
		(net "P5E_PEX1_STN0_TX_DN<7>")
	)
	(segment
		(start 199.979534 -135.60679)
		(end 200.274174 -135.31215)
		(width 0.13462)
		(layer "F.Cu")
		(net "P5E_PEX1_STN0_TX_DN<7>")
	)
	(segment
		(start 199.160384 -279.153874)
		(end 199.09536 -279.153874)
		(width 0.1143)
		(layer "In9.Cu")
		(net "P5E_PEX1_STN0_TX_DN<7>")
	)
	(segment
		(start 199.09536 -279.153874)
		(end 198.880984 -279.36825)
		(width 0.1143)
		(layer "In9.Cu")
		(net "P5E_PEX1_STN0_TX_DN<7>")
	)
	(segment
		(start 200.193148 -277.344632)
		(end 199.437244 -278.87676)
		(width 0.1651)
		(layer "In9.Cu")
		(net "P5E_PEX1_STN0_TX_DN<7>")
	)
	(segment
		(start 198.170292 -279.479248)
		(end 198.170292 -279.635458)
		(width 0.1143)
		(layer "In9.Cu")
		(net "P5E_PEX1_STN0_TX_DN<7>")
	)
	(segment
		(start 206.130398 -145.987008)
		(end 209.497422 -154.11577)
		(width 0.1651)
		(layer "In9.Cu")
		(net "P5E_PEX1_STN0_TX_DN<7>")
	)
	(segment
		(start 199.170544 -279.143714)
		(end 199.160384 -279.153874)
		(width 0.1143)
		(layer "In9.Cu")
		(net "P5E_PEX1_STN0_TX_DN<7>")
	)
	(segment
		(start 201.261218 -135.60298)
		(end 201.561192 -135.902954)
		(width 0.1651)
		(layer "In9.Cu")
		(net "P5E_PEX1_STN0_TX_DN<7>")
	)
	(segment
		(start 198.281036 -279.36825)
		(end 198.170292 -279.479248)
		(width 0.1143)
		(layer "In9.Cu")
		(net "P5E_PEX1_STN0_TX_DN<7>")
	)
	(segment
		(start 198.170292 -279.635458)
		(end 198.284592 -279.749758)
		(width 0.1143)
		(layer "In9.Cu")
		(net "P5E_PEX1_STN0_TX_DN<7>")
	)
	(segment
		(start 200.565004 -135.60298)
		(end 201.261218 -135.60298)
		(width 0.1651)
		(layer "In9.Cu")
		(net "P5E_PEX1_STN0_TX_DN<7>")
	)
	(segment
		(start 201.561192 -135.902954)
		(end 205.460854 -145.317464)
		(width 0.1651)
		(layer "In9.Cu")
		(net "P5E_PEX1_STN0_TX_DN<7>")
	)
	(segment
		(start 209.497422 -158.760414)
		(end 200.941686 -173.584108)
		(width 0.1651)
		(layer "In9.Cu")
		(net "P5E_PEX1_STN0_TX_DN<7>")
	)
	(segment
		(start 195.941188 -221.581218)
		(end 198.129144 -246.62638)
		(width 0.1651)
		(layer "In9.Cu")
		(net "P5E_PEX1_STN0_TX_DN<7>")
	)
	(segment
		(start 209.497422 -154.11577)
		(end 209.497422 -158.760414)
		(width 0.1651)
		(layer "In9.Cu")
		(net "P5E_PEX1_STN0_TX_DN<7>")
	)
	(segment
		(start 200.941686 -173.584108)
		(end 199.751696 -178.021488)
		(width 0.1651)
		(layer "In9.Cu")
		(net "P5E_PEX1_STN0_TX_DN<7>")
	)
	(segment
		(start 198.880984 -279.36825)
		(end 198.281036 -279.36825)
		(width 0.1143)
		(layer "In9.Cu")
		(net "P5E_PEX1_STN0_TX_DN<7>")
	)
	(segment
		(start 198.129144 -246.62638)
		(end 198.129398 -246.62638)
		(width 0.1651)
		(layer "In9.Cu")
		(net "P5E_PEX1_STN0_TX_DN<7>")
	)
	(segment
		(start 200.317354 -271.674336)
		(end 200.193148 -277.344632)
		(width 0.1651)
		(layer "In9.Cu")
		(net "P5E_PEX1_STN0_TX_DN<7>")
	)
	(segment
		(start 199.751696 -178.021488)
		(end 195.941188 -221.581218)
		(width 0.1651)
		(layer "In9.Cu")
		(net "P5E_PEX1_STN0_TX_DN<7>")
	)
	(segment
		(start 205.460854 -145.317464)
		(end 206.130398 -145.987008)
		(width 0.1651)
		(layer "In9.Cu")
		(net "P5E_PEX1_STN0_TX_DN<7>")
	)
	(segment
		(start 199.437244 -278.87676)
		(end 199.170544 -279.143714)
		(width 0.1651)
		(layer "In9.Cu")
		(net "P5E_PEX1_STN0_TX_DN<7>")
	)
	(segment
		(start 198.284592 -279.749758)
		(end 198.550022 -279.749758)
		(width 0.1143)
		(layer "In9.Cu")
		(net "P5E_PEX1_STN0_TX_DN<7>")
	)
	(segment
		(start 198.129398 -246.62638)
		(end 200.317354 -271.674336)
		(width 0.1651)
		(layer "In9.Cu")
		(net "P5E_PEX1_STN0_TX_DN<7>")
	)
	(segment
		(start 200.274174 -135.31215)
		(end 200.565004 -135.60298)
		(width 0.1651)
		(layer "In9.Cu")
		(net "P5E_PEX1_STN0_TX_DN<7>")
	)
	(segment
		(start 151.765 -305.733958)
		(end 151.793448 -305.733958)
		(width 0.1143)
		(layer "In9.Cu")
		(net "P5E_PEX1_STN7_RX_DP<117>")
	)
	(segment
		(start 138.548872 -322.55968)
		(end 138.548872 -319.594992)
		(width 0.1651)
		(layer "In9.Cu")
		(net "P5E_PEX1_STN7_RX_DP<117>")
	)
	(segment
		(start 171.792392 -395.477492)
		(end 169.938446 -393.623546)
		(width 0.1651)
		(layer "In9.Cu")
		(net "P5E_PEX1_STN7_RX_DP<117>")
	)
	(segment
		(start 150.857712 -344.456258)
		(end 149.502622 -340.672166)
		(width 0.1651)
		(layer "In9.Cu")
		(net "P5E_PEX1_STN7_RX_DP<117>")
	)
	(segment
		(start 140.20673 -315.857128)
		(end 142.050516 -313.097418)
		(width 0.1651)
		(layer "In9.Cu")
		(net "P5E_PEX1_STN7_RX_DP<117>")
	)
	(segment
		(start 153.6192 -306.349908)
		(end 153.89987 -306.349908)
		(width 0.1143)
		(layer "In9.Cu")
		(net "P5E_PEX1_STN7_RX_DP<117>")
	)
	(segment
		(start 138.548872 -319.594992)
		(end 140.20673 -315.857128)
		(width 0.1651)
		(layer "In9.Cu")
		(net "P5E_PEX1_STN7_RX_DP<117>")
	)
	(segment
		(start 149.502622 -340.672166)
		(end 138.733784 -323.248274)
		(width 0.1651)
		(layer "In9.Cu")
		(net "P5E_PEX1_STN7_RX_DP<117>")
	)
	(segment
		(start 167.37711 -391.911586)
		(end 160.594548 -389.100314)
		(width 0.1651)
		(layer "In9.Cu")
		(net "P5E_PEX1_STN7_RX_DP<117>")
	)
	(segment
		(start 138.733784 -323.248274)
		(end 138.548872 -322.55968)
		(width 0.1651)
		(layer "In9.Cu")
		(net "P5E_PEX1_STN7_RX_DP<117>")
	)
	(segment
		(start 170.909996 -409.290012)
		(end 170.909996 -409.672282)
		(width 0.1651)
		(layer "In9.Cu")
		(net "P5E_PEX1_STN7_RX_DP<117>")
	)
	(segment
		(start 142.050516 -313.097418)
		(end 142.05077 -313.097164)
		(width 0.1651)
		(layer "In9.Cu")
		(net "P5E_PEX1_STN7_RX_DP<117>")
	)
	(segment
		(start 144.296384 -309.73649)
		(end 147.099528 -306.933092)
		(width 0.1651)
		(layer "In9.Cu")
		(net "P5E_PEX1_STN7_RX_DP<117>")
	)
	(segment
		(start 151.839168 -305.779678)
		(end 153.280872 -305.779678)
		(width 0.1143)
		(layer "In9.Cu")
		(net "P5E_PEX1_STN7_RX_DP<117>")
	)
	(segment
		(start 170.909996 -409.672282)
		(end 171.036996 -409.799282)
		(width 0.1651)
		(layer "In9.Cu")
		(net "P5E_PEX1_STN7_RX_DP<117>")
	)
	(segment
		(start 151.793448 -305.733958)
		(end 151.839168 -305.779678)
		(width 0.1143)
		(layer "In9.Cu")
		(net "P5E_PEX1_STN7_RX_DP<117>")
	)
	(segment
		(start 171.036996 -409.799282)
		(end 171.258484 -409.799282)
		(width 0.1651)
		(layer "In9.Cu")
		(net "P5E_PEX1_STN7_RX_DP<117>")
	)
	(segment
		(start 157.561534 -386.626608)
		(end 156.222192 -384.182366)
		(width 0.1651)
		(layer "In9.Cu")
		(net "P5E_PEX1_STN7_RX_DP<117>")
	)
	(segment
		(start 156.222192 -384.182366)
		(end 150.857712 -344.456258)
		(width 0.1651)
		(layer "In9.Cu")
		(net "P5E_PEX1_STN7_RX_DP<117>")
	)
	(segment
		(start 153.524712 -306.25542)
		(end 153.6192 -306.349908)
		(width 0.1143)
		(layer "In9.Cu")
		(net "P5E_PEX1_STN7_RX_DP<117>")
	)
	(segment
		(start 169.938446 -393.623546)
		(end 167.37711 -391.911586)
		(width 0.1651)
		(layer "In9.Cu")
		(net "P5E_PEX1_STN7_RX_DP<117>")
	)
	(segment
		(start 149.398482 -305.733958)
		(end 151.765 -305.733958)
		(width 0.1651)
		(layer "In9.Cu")
		(net "P5E_PEX1_STN7_RX_DP<117>")
	)
	(segment
		(start 171.258484 -409.799282)
		(end 171.792392 -409.265374)
		(width 0.1651)
		(layer "In9.Cu")
		(net "P5E_PEX1_STN7_RX_DP<117>")
	)
	(segment
		(start 147.099528 -306.933092)
		(end 149.398482 -305.733958)
		(width 0.1651)
		(layer "In9.Cu")
		(net "P5E_PEX1_STN7_RX_DP<117>")
	)
	(segment
		(start 153.524712 -306.023518)
		(end 153.524712 -306.25542)
		(width 0.1143)
		(layer "In9.Cu")
		(net "P5E_PEX1_STN7_RX_DP<117>")
	)
	(segment
		(start 153.280872 -305.779678)
		(end 153.524712 -306.023518)
		(width 0.1143)
		(layer "In9.Cu")
		(net "P5E_PEX1_STN7_RX_DP<117>")
	)
	(segment
		(start 142.05077 -313.097164)
		(end 144.296384 -309.73649)
		(width 0.1651)
		(layer "In9.Cu")
		(net "P5E_PEX1_STN7_RX_DP<117>")
	)
	(segment
		(start 171.792392 -409.265374)
		(end 171.792392 -395.477492)
		(width 0.1651)
		(layer "In9.Cu")
		(net "P5E_PEX1_STN7_RX_DP<117>")
	)
	(segment
		(start 160.594548 -389.100314)
		(end 157.561534 -386.626608)
		(width 0.1651)
		(layer "In9.Cu")
		(net "P5E_PEX1_STN7_RX_DP<117>")
	)
	(segment
		(start 36.051744 -134.328916)
		(end 35.4203 -134.328916)
		(width 0.13462)
		(layer "F.Cu")
		(net "P5E_PEX0_STN1_TX_DP<30>")
	)
	(segment
		(start 36.371784 -134.008876)
		(end 36.051744 -134.328916)
		(width 0.13462)
		(layer "F.Cu")
		(net "P5E_PEX0_STN1_TX_DP<30>")
	)
	(segment
		(start 35.4203 -134.328916)
		(end 35.12566 -134.034276)
		(width 0.13462)
		(layer "F.Cu")
		(net "P5E_PEX0_STN1_TX_DP<30>")
	)
	(segment
		(start 72.379586 -271.546066)
		(end 72.333866 -271.500346)
		(width 0.1143)
		(layer "In9.Cu")
		(net "P5E_PEX0_STN1_TX_DP<30>")
	)
	(segment
		(start 72.333866 -271.471898)
		(end 72.333866 -262.993378)
		(width 0.1651)
		(layer "In9.Cu")
		(net "P5E_PEX0_STN1_TX_DP<30>")
	)
	(segment
		(start 72.949562 -278.534368)
		(end 72.835262 -278.420068)
		(width 0.1143)
		(layer "In9.Cu")
		(net "P5E_PEX0_STN1_TX_DP<30>")
	)
	(segment
		(start 34.19856 -134.325106)
		(end 34.83483 -134.325106)
		(width 0.1651)
		(layer "In9.Cu")
		(net "P5E_PEX0_STN1_TX_DP<30>")
	)
	(segment
		(start 33.74136 -134.956296)
		(end 33.86455 -134.659116)
		(width 0.1651)
		(layer "In9.Cu")
		(net "P5E_PEX0_STN1_TX_DP<30>")
	)
	(segment
		(start 34.83483 -134.325106)
		(end 35.12566 -134.034276)
		(width 0.1651)
		(layer "In9.Cu")
		(net "P5E_PEX0_STN1_TX_DP<30>")
	)
	(segment
		(start 72.379586 -278.205184)
		(end 72.379586 -271.546066)
		(width 0.1143)
		(layer "In9.Cu")
		(net "P5E_PEX0_STN1_TX_DP<30>")
	)
	(segment
		(start 72.835262 -278.420068)
		(end 72.59447 -278.420068)
		(width 0.1143)
		(layer "In9.Cu")
		(net "P5E_PEX0_STN1_TX_DP<30>")
	)
	(segment
		(start 36.399978 -139.158218)
		(end 34.573972 -137.332212)
		(width 0.1651)
		(layer "In9.Cu")
		(net "P5E_PEX0_STN1_TX_DP<30>")
	)
	(segment
		(start 45.348652 -183.275986)
		(end 36.753038 -140.010642)
		(width 0.1651)
		(layer "In9.Cu")
		(net "P5E_PEX0_STN1_TX_DP<30>")
	)
	(segment
		(start 72.949562 -278.799798)
		(end 72.949562 -278.534368)
		(width 0.1143)
		(layer "In9.Cu")
		(net "P5E_PEX0_STN1_TX_DP<30>")
	)
	(segment
		(start 72.333866 -262.993378)
		(end 45.348652 -183.275986)
		(width 0.1651)
		(layer "In9.Cu")
		(net "P5E_PEX0_STN1_TX_DP<30>")
	)
	(segment
		(start 33.74136 -135.323072)
		(end 33.74136 -134.956296)
		(width 0.1651)
		(layer "In9.Cu")
		(net "P5E_PEX0_STN1_TX_DP<30>")
	)
	(segment
		(start 72.333866 -271.500346)
		(end 72.333866 -271.471898)
		(width 0.1143)
		(layer "In9.Cu")
		(net "P5E_PEX0_STN1_TX_DP<30>")
	)
	(segment
		(start 34.573972 -137.332212)
		(end 33.74136 -135.323072)
		(width 0.1651)
		(layer "In9.Cu")
		(net "P5E_PEX0_STN1_TX_DP<30>")
	)
	(segment
		(start 36.753038 -140.010642)
		(end 36.399978 -139.158218)
		(width 0.1651)
		(layer "In9.Cu")
		(net "P5E_PEX0_STN1_TX_DP<30>")
	)
	(segment
		(start 72.59447 -278.420068)
		(end 72.379586 -278.205184)
		(width 0.1143)
		(layer "In9.Cu")
		(net "P5E_PEX0_STN1_TX_DP<30>")
	)
	(segment
		(start 33.86455 -134.659116)
		(end 34.19856 -134.325106)
		(width 0.1651)
		(layer "In9.Cu")
		(net "P5E_PEX0_STN1_TX_DP<30>")
	)
	(segment
		(start 44.773088 -348.88043)
		(end 45.067728 -348.58579)
		(width 0.13462)
		(layer "F.Cu")
		(net "P5E_PEX0_STN7_TX_DN<124>")
	)
	(segment
		(start 44.773088 -349.511874)
		(end 44.773088 -348.88043)
		(width 0.13462)
		(layer "F.Cu")
		(net "P5E_PEX0_STN7_TX_DN<124>")
	)
	(segment
		(start 45.093128 -349.831914)
		(end 44.773088 -349.511874)
		(width 0.13462)
		(layer "F.Cu")
		(net "P5E_PEX0_STN7_TX_DN<124>")
	)
	(segment
		(start 45.067728 -348.58579)
		(end 44.776898 -348.29496)
		(width 0.1651)
		(layer "In7.Cu")
		(net "P5E_PEX0_STN7_TX_DN<124>")
	)
	(segment
		(start 45.874178 -339.830664)
		(end 39.532306 -324.252082)
		(width 0.1651)
		(layer "In7.Cu")
		(net "P5E_PEX0_STN7_TX_DN<124>")
	)
	(segment
		(start 39.585646 -311.670192)
		(end 39.699946 -311.784492)
		(width 0.1143)
		(layer "In7.Cu")
		(net "P5E_PEX0_STN7_TX_DN<124>")
	)
	(segment
		(start 39.320216 -311.784492)
		(end 39.434516 -311.670192)
		(width 0.1143)
		(layer "In7.Cu")
		(net "P5E_PEX0_STN7_TX_DN<124>")
	)
	(segment
		(start 39.365936 -319.865248)
		(end 39.365936 -319.8368)
		(width 0.1143)
		(layer "In7.Cu")
		(net "P5E_PEX0_STN7_TX_DN<124>")
	)
	(segment
		(start 44.776898 -347.658182)
		(end 46.331378 -346.103702)
		(width 0.1651)
		(layer "In7.Cu")
		(net "P5E_PEX0_STN7_TX_DN<124>")
	)
	(segment
		(start 46.331378 -342.166448)
		(end 45.874178 -339.830664)
		(width 0.1651)
		(layer "In7.Cu")
		(net "P5E_PEX0_STN7_TX_DN<124>")
	)
	(segment
		(start 46.331378 -346.103702)
		(end 46.331378 -342.166448)
		(width 0.1651)
		(layer "In7.Cu")
		(net "P5E_PEX0_STN7_TX_DN<124>")
	)
	(segment
		(start 44.776898 -348.29496)
		(end 44.776898 -347.658182)
		(width 0.1651)
		(layer "In7.Cu")
		(net "P5E_PEX0_STN7_TX_DN<124>")
	)
	(segment
		(start 39.434516 -311.670192)
		(end 39.585646 -311.670192)
		(width 0.1143)
		(layer "In7.Cu")
		(net "P5E_PEX0_STN7_TX_DN<124>")
	)
	(segment
		(start 39.365936 -323.511926)
		(end 39.365936 -319.865248)
		(width 0.1651)
		(layer "In7.Cu")
		(net "P5E_PEX0_STN7_TX_DN<124>")
	)
	(segment
		(start 39.365936 -319.8368)
		(end 39.320216 -319.79108)
		(width 0.1143)
		(layer "In7.Cu")
		(net "P5E_PEX0_STN7_TX_DN<124>")
	)
	(segment
		(start 39.532306 -324.252082)
		(end 39.365936 -323.511926)
		(width 0.1651)
		(layer "In7.Cu")
		(net "P5E_PEX0_STN7_TX_DN<124>")
	)
	(segment
		(start 39.320216 -319.79108)
		(end 39.320216 -311.784492)
		(width 0.1143)
		(layer "In7.Cu")
		(net "P5E_PEX0_STN7_TX_DN<124>")
	)
	(segment
		(start 39.699946 -311.784492)
		(end 39.699946 -312.049922)
		(width 0.1143)
		(layer "In7.Cu")
		(net "P5E_PEX0_STN7_TX_DN<124>")
	)
	(segment
		(start 196.385942 -118.670324)
		(end 196.705982 -118.990364)
		(width 0.13462)
		(layer "F.Cu")
		(net "P5E_PEX1_STN0_TX_DN<0>")
	)
	(segment
		(start 196.705982 -118.990364)
		(end 197.337426 -118.990364)
		(width 0.13462)
		(layer "F.Cu")
		(net "P5E_PEX1_STN0_TX_DN<0>")
	)
	(segment
		(start 197.337426 -118.990364)
		(end 197.632066 -118.695724)
		(width 0.13462)
		(layer "F.Cu")
		(net "P5E_PEX1_STN0_TX_DN<0>")
	)
	(segment
		(start 193.420238 -288.023808)
		(end 193.420238 -288.185606)
		(width 0.1143)
		(layer "In9.Cu")
		(net "P5E_PEX1_STN0_TX_DN<0>")
	)
	(segment
		(start 216.321894 -267.224002)
		(end 216.561162 -269.973044)
		(width 0.1651)
		(layer "In9.Cu")
		(net "P5E_PEX1_STN0_TX_DN<0>")
	)
	(segment
		(start 214.949532 -263.91108)
		(end 215.632792 -265.560556)
		(width 0.1651)
		(layer "In9.Cu")
		(net "P5E_PEX1_STN0_TX_DN<0>")
	)
	(segment
		(start 216.802462 -272.746978)
		(end 215.076532 -276.912578)
		(width 0.1651)
		(layer "In9.Cu")
		(net "P5E_PEX1_STN0_TX_DN<0>")
	)
	(segment
		(start 215.076532 -276.912578)
		(end 205.496922 -286.492188)
		(width 0.1651)
		(layer "In9.Cu")
		(net "P5E_PEX1_STN0_TX_DN<0>")
	)
	(segment
		(start 197.922896 -118.986554)
		(end 200.321926 -118.986554)
		(width 0.1651)
		(layer "In9.Cu")
		(net "P5E_PEX1_STN0_TX_DN<0>")
	)
	(segment
		(start 199.989186 -287.965896)
		(end 199.943466 -287.920176)
		(width 0.1143)
		(layer "In9.Cu")
		(net "P5E_PEX1_STN0_TX_DN<0>")
	)
	(segment
		(start 202.778614 -221.785942)
		(end 205.17866 -249.289316)
		(width 0.1651)
		(layer "In9.Cu")
		(net "P5E_PEX1_STN0_TX_DN<0>")
	)
	(segment
		(start 216.271602 -159.966914)
		(end 215.921336 -161.278062)
		(width 0.1651)
		(layer "In9.Cu")
		(net "P5E_PEX1_STN0_TX_DN<0>")
	)
	(segment
		(start 201.93889 -287.965896)
		(end 200.017634 -287.965896)
		(width 0.1651)
		(layer "In9.Cu")
		(net "P5E_PEX1_STN0_TX_DN<0>")
	)
	(segment
		(start 215.921336 -161.278062)
		(end 207.349344 -176.133252)
		(width 0.1651)
		(layer "In9.Cu")
		(net "P5E_PEX1_STN0_TX_DN<0>")
	)
	(segment
		(start 203.265786 -120.953276)
		(end 207.331564 -130.769106)
		(width 0.1651)
		(layer "In9.Cu")
		(net "P5E_PEX1_STN0_TX_DN<0>")
	)
	(segment
		(start 216.561162 -269.973044)
		(end 216.802462 -272.746978)
		(width 0.1651)
		(layer "In9.Cu")
		(net "P5E_PEX1_STN0_TX_DN<0>")
	)
	(segment
		(start 199.943466 -287.920176)
		(end 193.52387 -287.920176)
		(width 0.1143)
		(layer "In9.Cu")
		(net "P5E_PEX1_STN0_TX_DN<0>")
	)
	(segment
		(start 207.647032 -131.084574)
		(end 216.271602 -151.905462)
		(width 0.1651)
		(layer "In9.Cu")
		(net "P5E_PEX1_STN0_TX_DN<0>")
	)
	(segment
		(start 205.496922 -286.492188)
		(end 201.93889 -287.965896)
		(width 0.1651)
		(layer "In9.Cu")
		(net "P5E_PEX1_STN0_TX_DN<0>")
	)
	(segment
		(start 206.500984 -179.242212)
		(end 202.778614 -221.785942)
		(width 0.1651)
		(layer "In9.Cu")
		(net "P5E_PEX1_STN0_TX_DN<0>")
	)
	(segment
		(start 215.632792 -265.560556)
		(end 216.321894 -267.224002)
		(width 0.1651)
		(layer "In9.Cu")
		(net "P5E_PEX1_STN0_TX_DN<0>")
	)
	(segment
		(start 207.349344 -176.133252)
		(end 206.500984 -179.242212)
		(width 0.1651)
		(layer "In9.Cu")
		(net "P5E_PEX1_STN0_TX_DN<0>")
	)
	(segment
		(start 197.632066 -118.695724)
		(end 197.922896 -118.986554)
		(width 0.1651)
		(layer "In9.Cu")
		(net "P5E_PEX1_STN0_TX_DN<0>")
	)
	(segment
		(start 207.331564 -130.769106)
		(end 207.647032 -131.084574)
		(width 0.1651)
		(layer "In9.Cu")
		(net "P5E_PEX1_STN0_TX_DN<0>")
	)
	(segment
		(start 193.420238 -288.185606)
		(end 193.534538 -288.299906)
		(width 0.1143)
		(layer "In9.Cu")
		(net "P5E_PEX1_STN0_TX_DN<0>")
	)
	(segment
		(start 200.017634 -287.965896)
		(end 199.989186 -287.965896)
		(width 0.1143)
		(layer "In9.Cu")
		(net "P5E_PEX1_STN0_TX_DN<0>")
	)
	(segment
		(start 193.534538 -288.299906)
		(end 193.799968 -288.299906)
		(width 0.1143)
		(layer "In9.Cu")
		(net "P5E_PEX1_STN0_TX_DN<0>")
	)
	(segment
		(start 216.271602 -151.905462)
		(end 216.271602 -159.966914)
		(width 0.1651)
		(layer "In9.Cu")
		(net "P5E_PEX1_STN0_TX_DN<0>")
	)
	(segment
		(start 193.52387 -287.920176)
		(end 193.420238 -288.023808)
		(width 0.1143)
		(layer "In9.Cu")
		(net "P5E_PEX1_STN0_TX_DN<0>")
	)
	(segment
		(start 205.17866 -249.289316)
		(end 214.949532 -263.91108)
		(width 0.1651)
		(layer "In9.Cu")
		(net "P5E_PEX1_STN0_TX_DN<0>")
	)
	(segment
		(start 200.321926 -118.986554)
		(end 203.265786 -120.953276)
		(width 0.1651)
		(layer "In9.Cu")
		(net "P5E_PEX1_STN0_TX_DN<0>")
	)
	(segment
		(start 144.351502 -312.685176)
		(end 144.671034 -312.306208)
		(width 0.1651)
		(layer "In9.Cu")
		(net "P5E_PEX1_STN7_RX_DN<118>")
	)
	(segment
		(start 141.06271 -317.067438)
		(end 143.117824 -313.99099)
		(width 0.1651)
		(layer "In9.Cu")
		(net "P5E_PEX1_STN7_RX_DN<118>")
	)
	(segment
		(start 173.10989 -409.490164)
		(end 173.10989 -409.108148)
		(width 0.1651)
		(layer "In9.Cu")
		(net "P5E_PEX1_STN7_RX_DN<118>")
	)
	(segment
		(start 155.229814 -307.210968)
		(end 155.140914 -307.299868)
		(width 0.1143)
		(layer "In9.Cu")
		(net "P5E_PEX1_STN7_RX_DN<118>")
	)
	(segment
		(start 169.254932 -391.336022)
		(end 161.215324 -388.003542)
		(width 0.1651)
		(layer "In9.Cu")
		(net "P5E_PEX1_STN7_RX_DN<118>")
	)
	(segment
		(start 147.209256 -309.553102)
		(end 147.559268 -309.20309)
		(width 0.1651)
		(layer "In9.Cu")
		(net "P5E_PEX1_STN7_RX_DN<118>")
	)
	(segment
		(start 144.208246 -312.697368)
		(end 144.351502 -312.685176)
		(width 0.1651)
		(layer "In9.Cu")
		(net "P5E_PEX1_STN7_RX_DN<118>")
	)
	(segment
		(start 155.229814 -307.03266)
		(end 155.229814 -307.210968)
		(width 0.1143)
		(layer "In9.Cu")
		(net "P5E_PEX1_STN7_RX_DN<118>")
	)
	(segment
		(start 173.575218 -408.981148)
		(end 174.274226 -408.28214)
		(width 0.1651)
		(layer "In9.Cu")
		(net "P5E_PEX1_STN7_RX_DN<118>")
	)
	(segment
		(start 173.10989 -409.108148)
		(end 173.23689 -408.981148)
		(width 0.1651)
		(layer "In9.Cu")
		(net "P5E_PEX1_STN7_RX_DN<118>")
	)
	(segment
		(start 173.732698 -394.328904)
		(end 169.254932 -391.336022)
		(width 0.1651)
		(layer "In9.Cu")
		(net "P5E_PEX1_STN7_RX_DN<118>")
	)
	(segment
		(start 146.36496 -310.397398)
		(end 146.714972 -310.047386)
		(width 0.1651)
		(layer "In9.Cu")
		(net "P5E_PEX1_STN7_RX_DN<118>")
	)
	(segment
		(start 148.897594 -308.008274)
		(end 148.897594 -307.864764)
		(width 0.1651)
		(layer "In9.Cu")
		(net "P5E_PEX1_STN7_RX_DN<118>")
	)
	(segment
		(start 174.274226 -408.28214)
		(end 174.274226 -394.870432)
		(width 0.1651)
		(layer "In9.Cu")
		(net "P5E_PEX1_STN7_RX_DN<118>")
	)
	(segment
		(start 139.788392 -322.377308)
		(end 139.788392 -319.937638)
		(width 0.1651)
		(layer "In9.Cu")
		(net "P5E_PEX1_STN7_RX_DN<118>")
	)
	(segment
		(start 144.977866 -311.784492)
		(end 145.870676 -310.891682)
		(width 0.1651)
		(layer "In9.Cu")
		(net "P5E_PEX1_STN7_RX_DN<118>")
	)
	(segment
		(start 146.36496 -310.541162)
		(end 146.36496 -310.397398)
		(width 0.1651)
		(layer "In9.Cu")
		(net "P5E_PEX1_STN7_RX_DN<118>")
	)
	(segment
		(start 155.140914 -307.299868)
		(end 154.850084 -307.299868)
		(width 0.1143)
		(layer "In9.Cu")
		(net "P5E_PEX1_STN7_RX_DN<118>")
	)
	(segment
		(start 146.858736 -310.047386)
		(end 147.209256 -309.696866)
		(width 0.1651)
		(layer "In9.Cu")
		(net "P5E_PEX1_STN7_RX_DN<118>")
	)
	(segment
		(start 144.658842 -312.162952)
		(end 144.977866 -311.784492)
		(width 0.1651)
		(layer "In9.Cu")
		(net "P5E_PEX1_STN7_RX_DN<118>")
	)
	(segment
		(start 139.788392 -319.937638)
		(end 141.06271 -317.067438)
		(width 0.1651)
		(layer "In9.Cu")
		(net "P5E_PEX1_STN7_RX_DN<118>")
	)
	(segment
		(start 158.543752 -385.825238)
		(end 157.417008 -383.781046)
		(width 0.1651)
		(layer "In9.Cu")
		(net "P5E_PEX1_STN7_RX_DN<118>")
	)
	(segment
		(start 139.892278 -322.763642)
		(end 139.788392 -322.377308)
		(width 0.1651)
		(layer "In9.Cu")
		(net "P5E_PEX1_STN7_RX_DN<118>")
	)
	(segment
		(start 151.765 -306.965858)
		(end 151.793448 -306.965858)
		(width 0.1143)
		(layer "In9.Cu")
		(net "P5E_PEX1_STN7_RX_DN<118>")
	)
	(segment
		(start 146.714972 -310.047386)
		(end 146.858736 -310.047386)
		(width 0.1651)
		(layer "In9.Cu")
		(net "P5E_PEX1_STN7_RX_DN<118>")
	)
	(segment
		(start 147.703032 -309.20309)
		(end 148.053552 -308.85257)
		(width 0.1651)
		(layer "In9.Cu")
		(net "P5E_PEX1_STN7_RX_DN<118>")
	)
	(segment
		(start 148.053552 -308.708806)
		(end 148.403564 -308.358794)
		(width 0.1651)
		(layer "In9.Cu")
		(net "P5E_PEX1_STN7_RX_DN<118>")
	)
	(segment
		(start 173.23689 -408.981148)
		(end 173.575218 -408.981148)
		(width 0.1651)
		(layer "In9.Cu")
		(net "P5E_PEX1_STN7_RX_DN<118>")
	)
	(segment
		(start 150.51405 -306.965858)
		(end 151.765 -306.965858)
		(width 0.1651)
		(layer "In9.Cu")
		(net "P5E_PEX1_STN7_RX_DN<118>")
	)
	(segment
		(start 151.839168 -306.920138)
		(end 155.117292 -306.920138)
		(width 0.1143)
		(layer "In9.Cu")
		(net "P5E_PEX1_STN7_RX_DN<118>")
	)
	(segment
		(start 161.215324 -388.003542)
		(end 158.543752 -385.825238)
		(width 0.1651)
		(layer "In9.Cu")
		(net "P5E_PEX1_STN7_RX_DN<118>")
	)
	(segment
		(start 145.870676 -310.891682)
		(end 146.01444 -310.891682)
		(width 0.1651)
		(layer "In9.Cu")
		(net "P5E_PEX1_STN7_RX_DN<118>")
	)
	(segment
		(start 149.289008 -307.47335)
		(end 150.51405 -306.965858)
		(width 0.1651)
		(layer "In9.Cu")
		(net "P5E_PEX1_STN7_RX_DN<118>")
	)
	(segment
		(start 152.059132 -344.101674)
		(end 150.651972 -340.17331)
		(width 0.1651)
		(layer "In9.Cu")
		(net "P5E_PEX1_STN7_RX_DN<118>")
	)
	(segment
		(start 143.117824 -313.99099)
		(end 144.208246 -312.697368)
		(width 0.1651)
		(layer "In9.Cu")
		(net "P5E_PEX1_STN7_RX_DN<118>")
	)
	(segment
		(start 148.547074 -308.358794)
		(end 148.897594 -308.008274)
		(width 0.1651)
		(layer "In9.Cu")
		(net "P5E_PEX1_STN7_RX_DN<118>")
	)
	(segment
		(start 148.053552 -308.85257)
		(end 148.053552 -308.708806)
		(width 0.1651)
		(layer "In9.Cu")
		(net "P5E_PEX1_STN7_RX_DN<118>")
	)
	(segment
		(start 144.671034 -312.306208)
		(end 144.658842 -312.162952)
		(width 0.1651)
		(layer "In9.Cu")
		(net "P5E_PEX1_STN7_RX_DN<118>")
	)
	(segment
		(start 174.274226 -394.870432)
		(end 173.732698 -394.328904)
		(width 0.1651)
		(layer "In9.Cu")
		(net "P5E_PEX1_STN7_RX_DN<118>")
	)
	(segment
		(start 147.209256 -309.696866)
		(end 147.209256 -309.553102)
		(width 0.1651)
		(layer "In9.Cu")
		(net "P5E_PEX1_STN7_RX_DN<118>")
	)
	(segment
		(start 146.01444 -310.891682)
		(end 146.36496 -310.541162)
		(width 0.1651)
		(layer "In9.Cu")
		(net "P5E_PEX1_STN7_RX_DN<118>")
	)
	(segment
		(start 147.559268 -309.20309)
		(end 147.703032 -309.20309)
		(width 0.1651)
		(layer "In9.Cu")
		(net "P5E_PEX1_STN7_RX_DN<118>")
	)
	(segment
		(start 148.403564 -308.358794)
		(end 148.547074 -308.358794)
		(width 0.1651)
		(layer "In9.Cu")
		(net "P5E_PEX1_STN7_RX_DN<118>")
	)
	(segment
		(start 150.651972 -340.17331)
		(end 139.892278 -322.763642)
		(width 0.1651)
		(layer "In9.Cu")
		(net "P5E_PEX1_STN7_RX_DN<118>")
	)
	(segment
		(start 151.793448 -306.965858)
		(end 151.839168 -306.920138)
		(width 0.1143)
		(layer "In9.Cu")
		(net "P5E_PEX1_STN7_RX_DN<118>")
	)
	(segment
		(start 155.117292 -306.920138)
		(end 155.229814 -307.03266)
		(width 0.1143)
		(layer "In9.Cu")
		(net "P5E_PEX1_STN7_RX_DN<118>")
	)
	(segment
		(start 148.897594 -307.864764)
		(end 149.289008 -307.47335)
		(width 0.1651)
		(layer "In9.Cu")
		(net "P5E_PEX1_STN7_RX_DN<118>")
	)
	(segment
		(start 157.417008 -383.781046)
		(end 152.059132 -344.101674)
		(width 0.1651)
		(layer "In9.Cu")
		(net "P5E_PEX1_STN7_RX_DN<118>")
	)
	(segment
		(start 86.538562 -350.685354)
		(end 86.218522 -350.365314)
		(width 0.13462)
		(layer "F.Cu")
		(net "P5E_PEX0_STN5_TX_C_DP<92>")
	)
	(segment
		(start 86.538562 -351.316798)
		(end 86.538562 -350.685354)
		(width 0.13462)
		(layer "F.Cu")
		(net "P5E_PEX0_STN5_TX_C_DP<92>")
	)
	(segment
		(start 86.243922 -351.611438)
		(end 86.538562 -351.316798)
		(width 0.13462)
		(layer "F.Cu")
		(net "P5E_PEX0_STN5_TX_C_DP<92>")
	)
	(segment
		(start 82.630518 -365.490252)
		(end 82.774282 -365.016034)
		(width 0.1651)
		(layer "In7.Cu")
		(net "P5E_PEX0_STN5_TX_C_DP<92>")
	)
	(segment
		(start 82.689954 -365.600996)
		(end 82.630518 -365.490252)
		(width 0.1651)
		(layer "In7.Cu")
		(net "P5E_PEX0_STN5_TX_C_DP<92>")
	)
	(segment
		(start 81.602326 -378.370084)
		(end 81.602326 -369.185444)
		(width 0.1651)
		(layer "In7.Cu")
		(net "P5E_PEX0_STN5_TX_C_DP<92>")
	)
	(segment
		(start 84.980272 -358.050084)
		(end 84.980272 -353.990402)
		(width 0.1651)
		(layer "In7.Cu")
		(net "P5E_PEX0_STN5_TX_C_DP<92>")
	)
	(segment
		(start 81.17332 -378.79909)
		(end 81.602326 -378.370084)
		(width 0.1651)
		(layer "In7.Cu")
		(net "P5E_PEX0_STN5_TX_C_DP<92>")
	)
	(segment
		(start 82.35061 -366.719104)
		(end 82.291174 -366.60836)
		(width 0.1651)
		(layer "In7.Cu")
		(net "P5E_PEX0_STN5_TX_C_DP<92>")
	)
	(segment
		(start 82.54619 -366.07496)
		(end 82.689954 -365.600996)
		(width 0.1651)
		(layer "In7.Cu")
		(net "P5E_PEX0_STN5_TX_C_DP<92>")
	)
	(segment
		(start 81.95183 -367.726468)
		(end 82.095594 -367.25225)
		(width 0.1651)
		(layer "In7.Cu")
		(net "P5E_PEX0_STN5_TX_C_DP<92>")
	)
	(segment
		(start 86.534752 -352.435922)
		(end 86.534752 -351.902268)
		(width 0.1651)
		(layer "In7.Cu")
		(net "P5E_PEX0_STN5_TX_C_DP<92>")
	)
	(segment
		(start 82.095594 -367.25225)
		(end 82.206846 -367.193068)
		(width 0.1651)
		(layer "In7.Cu")
		(net "P5E_PEX0_STN5_TX_C_DP<92>")
	)
	(segment
		(start 80.710024 -378.67209)
		(end 80.837024 -378.79909)
		(width 0.1651)
		(layer "In7.Cu")
		(net "P5E_PEX0_STN5_TX_C_DP<92>")
	)
	(segment
		(start 86.534752 -351.902268)
		(end 86.243922 -351.611438)
		(width 0.1651)
		(layer "In7.Cu")
		(net "P5E_PEX0_STN5_TX_C_DP<92>")
	)
	(segment
		(start 82.885534 -364.956852)
		(end 82.885026 -364.956852)
		(width 0.1651)
		(layer "In7.Cu")
		(net "P5E_PEX0_STN5_TX_C_DP<92>")
	)
	(segment
		(start 80.710024 -378.290074)
		(end 80.710024 -378.67209)
		(width 0.1651)
		(layer "In7.Cu")
		(net "P5E_PEX0_STN5_TX_C_DP<92>")
	)
	(segment
		(start 84.980272 -353.990402)
		(end 86.534752 -352.435922)
		(width 0.1651)
		(layer "In7.Cu")
		(net "P5E_PEX0_STN5_TX_C_DP<92>")
	)
	(segment
		(start 81.602326 -369.185444)
		(end 82.011266 -367.837466)
		(width 0.1651)
		(layer "In7.Cu")
		(net "P5E_PEX0_STN5_TX_C_DP<92>")
	)
	(segment
		(start 82.885026 -364.956852)
		(end 84.980272 -358.050084)
		(width 0.1651)
		(layer "In7.Cu")
		(net "P5E_PEX0_STN5_TX_C_DP<92>")
	)
	(segment
		(start 82.774282 -365.016034)
		(end 82.885534 -364.956852)
		(width 0.1651)
		(layer "In7.Cu")
		(net "P5E_PEX0_STN5_TX_C_DP<92>")
	)
	(segment
		(start 80.837024 -378.79909)
		(end 81.17332 -378.79909)
		(width 0.1651)
		(layer "In7.Cu")
		(net "P5E_PEX0_STN5_TX_C_DP<92>")
	)
	(segment
		(start 82.011266 -367.837466)
		(end 81.95183 -367.726468)
		(width 0.1651)
		(layer "In7.Cu")
		(net "P5E_PEX0_STN5_TX_C_DP<92>")
	)
	(segment
		(start 82.291174 -366.60836)
		(end 82.434938 -366.134142)
		(width 0.1651)
		(layer "In7.Cu")
		(net "P5E_PEX0_STN5_TX_C_DP<92>")
	)
	(segment
		(start 82.434938 -366.134142)
		(end 82.54619 -366.07496)
		(width 0.1651)
		(layer "In7.Cu")
		(net "P5E_PEX0_STN5_TX_C_DP<92>")
	)
	(segment
		(start 82.206846 -367.193068)
		(end 82.35061 -366.719104)
		(width 0.1651)
		(layer "In7.Cu")
		(net "P5E_PEX0_STN5_TX_C_DP<92>")
	)
	(segment
		(start 175.190912 -356.831646)
		(end 175.510952 -356.511606)
		(width 0.13462)
		(layer "F.Cu")
		(net "P5E_PEX1_STN7_TX_C_DN<119>")
	)
	(segment
		(start 175.485552 -357.75773)
		(end 175.190912 -357.46309)
		(width 0.13462)
		(layer "F.Cu")
		(net "P5E_PEX1_STN7_TX_C_DN<119>")
	)
	(segment
		(start 175.190912 -357.46309)
		(end 175.190912 -356.831646)
		(width 0.13462)
		(layer "F.Cu")
		(net "P5E_PEX1_STN7_TX_C_DN<119>")
	)
	(segment
		(start 176.467516 -401.590002)
		(end 176.467516 -395.234922)
		(width 0.1651)
		(layer "In11.Cu")
		(net "P5E_PEX1_STN7_TX_C_DN<119>")
	)
	(segment
		(start 158.924498 -371.355112)
		(end 158.836614 -371.265196)
		(width 0.1651)
		(layer "In11.Cu")
		(net "P5E_PEX1_STN7_TX_C_DN<119>")
	)
	(segment
		(start 161.05124 -386.772658)
		(end 159.422592 -385.563872)
		(width 0.1651)
		(layer "In11.Cu")
		(net "P5E_PEX1_STN7_TX_C_DN<119>")
	)
	(segment
		(start 175.310038 -402.790152)
		(end 175.310038 -402.408136)
		(width 0.1651)
		(layer "In11.Cu")
		(net "P5E_PEX1_STN7_TX_C_DN<119>")
	)
	(segment
		(start 158.820866 -372.560342)
		(end 158.828232 -371.938296)
		(width 0.1651)
		(layer "In11.Cu")
		(net "P5E_PEX1_STN7_TX_C_DN<119>")
	)
	(segment
		(start 158.869634 -384.200146)
		(end 158.702248 -382.256792)
		(width 0.1651)
		(layer "In11.Cu")
		(net "P5E_PEX1_STN7_TX_C_DN<119>")
	)
	(segment
		(start 173.920912 -392.688318)
		(end 173.910244 -392.688318)
		(width 0.1651)
		(layer "In11.Cu")
		(net "P5E_PEX1_STN7_TX_C_DN<119>")
	)
	(segment
		(start 158.812484 -373.233696)
		(end 158.81223 -373.233696)
		(width 0.1651)
		(layer "In11.Cu")
		(net "P5E_PEX1_STN7_TX_C_DN<119>")
	)
	(segment
		(start 159.422592 -385.563872)
		(end 158.869634 -384.200146)
		(width 0.1651)
		(layer "In11.Cu")
		(net "P5E_PEX1_STN7_TX_C_DN<119>")
	)
	(segment
		(start 176.467516 -395.234922)
		(end 173.920912 -392.688318)
		(width 0.1651)
		(layer "In11.Cu")
		(net "P5E_PEX1_STN7_TX_C_DN<119>")
	)
	(segment
		(start 158.836614 -371.265196)
		(end 158.862522 -369.13693)
		(width 0.1651)
		(layer "In11.Cu")
		(net "P5E_PEX1_STN7_TX_C_DN<119>")
	)
	(segment
		(start 158.81223 -373.233696)
		(end 158.9024 -373.145812)
		(width 0.1651)
		(layer "In11.Cu")
		(net "P5E_PEX1_STN7_TX_C_DN<119>")
	)
	(segment
		(start 158.828232 -371.938296)
		(end 158.918402 -371.850666)
		(width 0.1651)
		(layer "In11.Cu")
		(net "P5E_PEX1_STN7_TX_C_DN<119>")
	)
	(segment
		(start 175.776382 -402.281136)
		(end 176.467516 -401.590002)
		(width 0.1651)
		(layer "In11.Cu")
		(net "P5E_PEX1_STN7_TX_C_DN<119>")
	)
	(segment
		(start 158.862522 -369.13693)
		(end 159.27578 -368.04473)
		(width 0.1651)
		(layer "In11.Cu")
		(net "P5E_PEX1_STN7_TX_C_DN<119>")
	)
	(segment
		(start 175.194722 -358.04856)
		(end 175.485552 -357.75773)
		(width 0.1651)
		(layer "In11.Cu")
		(net "P5E_PEX1_STN7_TX_C_DN<119>")
	)
	(segment
		(start 170.579034 -390.63549)
		(end 165.277292 -388.168388)
		(width 0.1651)
		(layer "In11.Cu")
		(net "P5E_PEX1_STN7_TX_C_DN<119>")
	)
	(segment
		(start 159.27578 -368.04473)
		(end 160.499298 -366.788954)
		(width 0.1651)
		(layer "In11.Cu")
		(net "P5E_PEX1_STN7_TX_C_DN<119>")
	)
	(segment
		(start 160.499298 -366.788954)
		(end 172.203618 -361.875578)
		(width 0.1651)
		(layer "In11.Cu")
		(net "P5E_PEX1_STN7_TX_C_DN<119>")
	)
	(segment
		(start 158.918402 -371.850666)
		(end 158.924498 -371.355112)
		(width 0.1651)
		(layer "In11.Cu")
		(net "P5E_PEX1_STN7_TX_C_DN<119>")
	)
	(segment
		(start 173.910244 -392.688318)
		(end 170.579034 -390.63549)
		(width 0.1651)
		(layer "In11.Cu")
		(net "P5E_PEX1_STN7_TX_C_DN<119>")
	)
	(segment
		(start 158.702248 -382.256792)
		(end 158.812484 -373.233696)
		(width 0.1651)
		(layer "In11.Cu")
		(net "P5E_PEX1_STN7_TX_C_DN<119>")
	)
	(segment
		(start 158.908496 -372.650258)
		(end 158.820866 -372.560342)
		(width 0.1651)
		(layer "In11.Cu")
		(net "P5E_PEX1_STN7_TX_C_DN<119>")
	)
	(segment
		(start 175.310038 -402.408136)
		(end 175.437038 -402.281136)
		(width 0.1651)
		(layer "In11.Cu")
		(net "P5E_PEX1_STN7_TX_C_DN<119>")
	)
	(segment
		(start 175.437038 -402.281136)
		(end 175.776382 -402.281136)
		(width 0.1651)
		(layer "In11.Cu")
		(net "P5E_PEX1_STN7_TX_C_DN<119>")
	)
	(segment
		(start 158.9024 -373.145812)
		(end 158.908496 -372.650258)
		(width 0.1651)
		(layer "In11.Cu")
		(net "P5E_PEX1_STN7_TX_C_DN<119>")
	)
	(segment
		(start 175.194722 -358.884474)
		(end 175.194722 -358.04856)
		(width 0.1651)
		(layer "In11.Cu")
		(net "P5E_PEX1_STN7_TX_C_DN<119>")
	)
	(segment
		(start 172.203618 -361.875578)
		(end 175.194722 -358.884474)
		(width 0.1651)
		(layer "In11.Cu")
		(net "P5E_PEX1_STN7_TX_C_DN<119>")
	)
	(segment
		(start 165.277292 -388.168388)
		(end 161.05124 -386.772658)
		(width 0.1651)
		(layer "In11.Cu")
		(net "P5E_PEX1_STN7_TX_C_DN<119>")
	)
	(segment
		(start 38.693852 -121.599706)
		(end 38.062408 -121.599706)
		(width 0.13462)
		(layer "F.Cu")
		(net "P5E_PEX0_STN1_TX_DP<25>")
	)
	(segment
		(start 38.062408 -121.599706)
		(end 37.767768 -121.894346)
		(width 0.13462)
		(layer "F.Cu")
		(net "P5E_PEX0_STN1_TX_DP<25>")
	)
	(segment
		(start 39.013892 -121.919746)
		(end 38.693852 -121.599706)
		(width 0.13462)
		(layer "F.Cu")
		(net "P5E_PEX0_STN1_TX_DP<25>")
	)
	(segment
		(start 67.923664 -280.129488)
		(end 67.820032 -280.025856)
		(width 0.1143)
		(layer "In9.Cu")
		(net "P5E_PEX0_STN1_TX_DP<25>")
	)
	(segment
		(start 30.818328 -128.69926)
		(end 31.00832 -128.241298)
		(width 0.1651)
		(layer "In9.Cu")
		(net "P5E_PEX0_STN1_TX_DP<25>")
	)
	(segment
		(start 33.471358 -122.586242)
		(end 33.615122 -122.586242)
		(width 0.1651)
		(layer "In9.Cu")
		(net "P5E_PEX0_STN1_TX_DP<25>")
	)
	(segment
		(start 36.11626 -121.603516)
		(end 36.20516 -121.692416)
		(width 0.1651)
		(layer "In9.Cu")
		(net "P5E_PEX0_STN1_TX_DP<25>")
	)
	(segment
		(start 67.865752 -271.526)
		(end 67.865752 -264.021824)
		(width 0.1651)
		(layer "In9.Cu")
		(net "P5E_PEX0_STN1_TX_DP<25>")
	)
	(segment
		(start 31.738316 -143.330422)
		(end 29.196792 -137.195052)
		(width 0.1651)
		(layer "In9.Cu")
		(net "P5E_PEX0_STN1_TX_DP<25>")
	)
	(segment
		(start 30.113986 -130.400552)
		(end 30.065726 -130.284474)
		(width 0.1651)
		(layer "In9.Cu")
		(net "P5E_PEX0_STN1_TX_DP<25>")
	)
	(segment
		(start 31.455614 -127.161544)
		(end 31.407354 -127.045466)
		(width 0.1651)
		(layer "In9.Cu")
		(net "P5E_PEX0_STN1_TX_DP<25>")
	)
	(segment
		(start 32.469328 -158.205678)
		(end 31.738316 -143.330422)
		(width 0.1651)
		(layer "In9.Cu")
		(net "P5E_PEX0_STN1_TX_DP<25>")
	)
	(segment
		(start 35.70986 -121.603516)
		(end 36.11626 -121.603516)
		(width 0.1651)
		(layer "In9.Cu")
		(net "P5E_PEX0_STN1_TX_DP<25>")
	)
	(segment
		(start 68.085462 -280.129488)
		(end 67.923664 -280.129488)
		(width 0.1143)
		(layer "In9.Cu")
		(net "P5E_PEX0_STN1_TX_DP<25>")
	)
	(segment
		(start 31.712662 -126.540006)
		(end 31.902654 -126.082044)
		(width 0.1651)
		(layer "In9.Cu")
		(net "P5E_PEX0_STN1_TX_DP<25>")
	)
	(segment
		(start 29.196792 -132.382006)
		(end 29.807916 -130.906774)
		(width 0.1651)
		(layer "In9.Cu")
		(net "P5E_PEX0_STN1_TX_DP<25>")
	)
	(segment
		(start 68.199762 -280.015188)
		(end 68.085462 -280.129488)
		(width 0.1143)
		(layer "In9.Cu")
		(net "P5E_PEX0_STN1_TX_DP<25>")
	)
	(segment
		(start 32.043878 -125.508512)
		(end 32.043878 -125.508258)
		(width 0.1651)
		(layer "In9.Cu")
		(net "P5E_PEX0_STN1_TX_DP<25>")
	)
	(segment
		(start 30.561026 -129.321052)
		(end 30.512766 -129.204974)
		(width 0.1651)
		(layer "In9.Cu")
		(net "P5E_PEX0_STN1_TX_DP<25>")
	)
	(segment
		(start 33.965642 -122.235722)
		(end 33.965642 -122.091958)
		(width 0.1651)
		(layer "In9.Cu")
		(net "P5E_PEX0_STN1_TX_DP<25>")
	)
	(segment
		(start 29.807916 -130.906774)
		(end 29.807916 -130.90652)
		(width 0.1651)
		(layer "In9.Cu")
		(net "P5E_PEX0_STN1_TX_DP<25>")
	)
	(segment
		(start 29.923994 -130.858514)
		(end 30.113986 -130.400552)
		(width 0.1651)
		(layer "In9.Cu")
		(net "P5E_PEX0_STN1_TX_DP<25>")
	)
	(segment
		(start 67.865752 -264.021824)
		(end 33.071562 -161.233104)
		(width 0.1651)
		(layer "In9.Cu")
		(net "P5E_PEX0_STN1_TX_DP<25>")
	)
	(segment
		(start 30.512766 -129.204974)
		(end 30.70225 -128.74752)
		(width 0.1651)
		(layer "In9.Cu")
		(net "P5E_PEX0_STN1_TX_DP<25>")
	)
	(segment
		(start 34.454084 -121.603516)
		(end 35.12566 -121.603516)
		(width 0.1651)
		(layer "In9.Cu")
		(net "P5E_PEX0_STN1_TX_DP<25>")
	)
	(segment
		(start 35.62096 -121.692416)
		(end 35.70986 -121.603516)
		(width 0.1651)
		(layer "In9.Cu")
		(net "P5E_PEX0_STN1_TX_DP<25>")
	)
	(segment
		(start 32.796988 -123.92279)
		(end 32.748982 -123.806458)
		(width 0.1651)
		(layer "In9.Cu")
		(net "P5E_PEX0_STN1_TX_DP<25>")
	)
	(segment
		(start 29.196792 -137.195052)
		(end 29.196792 -132.382006)
		(width 0.1651)
		(layer "In9.Cu")
		(net "P5E_PEX0_STN1_TX_DP<25>")
	)
	(segment
		(start 35.12566 -121.603516)
		(end 35.21456 -121.692416)
		(width 0.1651)
		(layer "In9.Cu")
		(net "P5E_PEX0_STN1_TX_DP<25>")
	)
	(segment
		(start 32.491172 -124.428758)
		(end 32.491172 -124.428504)
		(width 0.1651)
		(layer "In9.Cu")
		(net "P5E_PEX0_STN1_TX_DP<25>")
	)
	(segment
		(start 36.70046 -121.603516)
		(end 37.476938 -121.603516)
		(width 0.1651)
		(layer "In9.Cu")
		(net "P5E_PEX0_STN1_TX_DP<25>")
	)
	(segment
		(start 32.301688 -124.886212)
		(end 32.491172 -124.428758)
		(width 0.1651)
		(layer "In9.Cu")
		(net "P5E_PEX0_STN1_TX_DP<25>")
	)
	(segment
		(start 30.371034 -129.779014)
		(end 30.561026 -129.321052)
		(width 0.1651)
		(layer "In9.Cu")
		(net "P5E_PEX0_STN1_TX_DP<25>")
	)
	(segment
		(start 31.854394 -125.965966)
		(end 32.043878 -125.508512)
		(width 0.1651)
		(layer "In9.Cu")
		(net "P5E_PEX0_STN1_TX_DP<25>")
	)
	(segment
		(start 32.491172 -124.428504)
		(end 32.60725 -124.380498)
		(width 0.1651)
		(layer "In9.Cu")
		(net "P5E_PEX0_STN1_TX_DP<25>")
	)
	(segment
		(start 31.596838 -126.588012)
		(end 31.596584 -126.588012)
		(width 0.1651)
		(layer "In9.Cu")
		(net "P5E_PEX0_STN1_TX_DP<25>")
	)
	(segment
		(start 31.149544 -127.667512)
		(end 31.265622 -127.619506)
		(width 0.1651)
		(layer "In9.Cu")
		(net "P5E_PEX0_STN1_TX_DP<25>")
	)
	(segment
		(start 67.820032 -271.600168)
		(end 67.865752 -271.554448)
		(width 0.1143)
		(layer "In9.Cu")
		(net "P5E_PEX0_STN1_TX_DP<25>")
	)
	(segment
		(start 30.254956 -129.82702)
		(end 30.371034 -129.779014)
		(width 0.1651)
		(layer "In9.Cu")
		(net "P5E_PEX0_STN1_TX_DP<25>")
	)
	(segment
		(start 67.820032 -280.025856)
		(end 67.820032 -271.600168)
		(width 0.1143)
		(layer "In9.Cu")
		(net "P5E_PEX0_STN1_TX_DP<25>")
	)
	(segment
		(start 33.071562 -161.233104)
		(end 32.469328 -158.205678)
		(width 0.1651)
		(layer "In9.Cu")
		(net "P5E_PEX0_STN1_TX_DP<25>")
	)
	(segment
		(start 35.21456 -121.692416)
		(end 35.62096 -121.692416)
		(width 0.1651)
		(layer "In9.Cu")
		(net "P5E_PEX0_STN1_TX_DP<25>")
	)
	(segment
		(start 30.96006 -128.12522)
		(end 31.149544 -127.667766)
		(width 0.1651)
		(layer "In9.Cu")
		(net "P5E_PEX0_STN1_TX_DP<25>")
	)
	(segment
		(start 37.476938 -121.603516)
		(end 37.767768 -121.894346)
		(width 0.1651)
		(layer "In9.Cu")
		(net "P5E_PEX0_STN1_TX_DP<25>")
	)
	(segment
		(start 32.043878 -125.508258)
		(end 32.159956 -125.460252)
		(width 0.1651)
		(layer "In9.Cu")
		(net "P5E_PEX0_STN1_TX_DP<25>")
	)
	(segment
		(start 33.615122 -122.586242)
		(end 33.965642 -122.235722)
		(width 0.1651)
		(layer "In9.Cu")
		(net "P5E_PEX0_STN1_TX_DP<25>")
	)
	(segment
		(start 32.159956 -125.460252)
		(end 32.349948 -125.00229)
		(width 0.1651)
		(layer "In9.Cu")
		(net "P5E_PEX0_STN1_TX_DP<25>")
	)
	(segment
		(start 29.807916 -130.90652)
		(end 29.923994 -130.858514)
		(width 0.1651)
		(layer "In9.Cu")
		(net "P5E_PEX0_STN1_TX_DP<25>")
	)
	(segment
		(start 30.70225 -128.74752)
		(end 30.70225 -128.747266)
		(width 0.1651)
		(layer "In9.Cu")
		(net "P5E_PEX0_STN1_TX_DP<25>")
	)
	(segment
		(start 32.748982 -123.806458)
		(end 33.100772 -122.956828)
		(width 0.1651)
		(layer "In9.Cu")
		(net "P5E_PEX0_STN1_TX_DP<25>")
	)
	(segment
		(start 31.00832 -128.241298)
		(end 30.96006 -128.12522)
		(width 0.1651)
		(layer "In9.Cu")
		(net "P5E_PEX0_STN1_TX_DP<25>")
	)
	(segment
		(start 31.265622 -127.619506)
		(end 31.455614 -127.161544)
		(width 0.1651)
		(layer "In9.Cu")
		(net "P5E_PEX0_STN1_TX_DP<25>")
	)
	(segment
		(start 32.349948 -125.00229)
		(end 32.301688 -124.886212)
		(width 0.1651)
		(layer "In9.Cu")
		(net "P5E_PEX0_STN1_TX_DP<25>")
	)
	(segment
		(start 31.902654 -126.082044)
		(end 31.854394 -125.965966)
		(width 0.1651)
		(layer "In9.Cu")
		(net "P5E_PEX0_STN1_TX_DP<25>")
	)
	(segment
		(start 30.065726 -130.284474)
		(end 30.25521 -129.82702)
		(width 0.1651)
		(layer "In9.Cu")
		(net "P5E_PEX0_STN1_TX_DP<25>")
	)
	(segment
		(start 31.596584 -126.588012)
		(end 31.712662 -126.540006)
		(width 0.1651)
		(layer "In9.Cu")
		(net "P5E_PEX0_STN1_TX_DP<25>")
	)
	(segment
		(start 33.965642 -122.091958)
		(end 34.454084 -121.603516)
		(width 0.1651)
		(layer "In9.Cu")
		(net "P5E_PEX0_STN1_TX_DP<25>")
	)
	(segment
		(start 33.100772 -122.956828)
		(end 33.471358 -122.586242)
		(width 0.1651)
		(layer "In9.Cu")
		(net "P5E_PEX0_STN1_TX_DP<25>")
	)
	(segment
		(start 32.60725 -124.380498)
		(end 32.796988 -123.92279)
		(width 0.1651)
		(layer "In9.Cu")
		(net "P5E_PEX0_STN1_TX_DP<25>")
	)
	(segment
		(start 31.407354 -127.045466)
		(end 31.596838 -126.588012)
		(width 0.1651)
		(layer "In9.Cu")
		(net "P5E_PEX0_STN1_TX_DP<25>")
	)
	(segment
		(start 31.149544 -127.667766)
		(end 31.149544 -127.667512)
		(width 0.1651)
		(layer "In9.Cu")
		(net "P5E_PEX0_STN1_TX_DP<25>")
	)
	(segment
		(start 36.20516 -121.692416)
		(end 36.61156 -121.692416)
		(width 0.1651)
		(layer "In9.Cu")
		(net "P5E_PEX0_STN1_TX_DP<25>")
	)
	(segment
		(start 36.61156 -121.692416)
		(end 36.70046 -121.603516)
		(width 0.1651)
		(layer "In9.Cu")
		(net "P5E_PEX0_STN1_TX_DP<25>")
	)
	(segment
		(start 30.70225 -128.747266)
		(end 30.818328 -128.69926)
		(width 0.1651)
		(layer "In9.Cu")
		(net "P5E_PEX0_STN1_TX_DP<25>")
	)
	(segment
		(start 30.25521 -129.82702)
		(end 30.254956 -129.82702)
		(width 0.1651)
		(layer "In9.Cu")
		(net "P5E_PEX0_STN1_TX_DP<25>")
	)
	(segment
		(start 68.199762 -279.749504)
		(end 68.199762 -280.015188)
		(width 0.1143)
		(layer "In9.Cu")
		(net "P5E_PEX0_STN1_TX_DP<25>")
	)
	(segment
		(start 67.865752 -271.554448)
		(end 67.865752 -271.526)
		(width 0.1143)
		(layer "In9.Cu")
		(net "P5E_PEX0_STN1_TX_DP<25>")
	)
	(segment
		(start 50.396648 -349.831914)
		(end 50.716688 -349.511874)
		(width 0.13462)
		(layer "F.Cu")
		(net "P5E_PEX0_STN7_TX_DP<127>")
	)
	(segment
		(start 50.716688 -349.511874)
		(end 50.716688 -348.88043)
		(width 0.13462)
		(layer "F.Cu")
		(net "P5E_PEX0_STN7_TX_DP<127>")
	)
	(segment
		(start 50.716688 -348.88043)
		(end 50.422048 -348.58579)
		(width 0.13462)
		(layer "F.Cu")
		(net "P5E_PEX0_STN7_TX_DP<127>")
	)
	(segment
		(start 50.712878 -348.29496)
		(end 50.712878 -347.541342)
		(width 0.1651)
		(layer "In7.Cu")
		(net "P5E_PEX0_STN7_TX_DP<127>")
	)
	(segment
		(start 42.549826 -313.265312)
		(end 42.549826 -312.999882)
		(width 0.1143)
		(layer "In7.Cu")
		(net "P5E_PEX0_STN7_TX_DP<127>")
	)
	(segment
		(start 52.267358 -345.986862)
		(end 52.267358 -342.294464)
		(width 0.1651)
		(layer "In7.Cu")
		(net "P5E_PEX0_STN7_TX_DP<127>")
	)
	(segment
		(start 42.205402 -313.379612)
		(end 42.435526 -313.379612)
		(width 0.1143)
		(layer "In7.Cu")
		(net "P5E_PEX0_STN7_TX_DP<127>")
	)
	(segment
		(start 46.790864 -330.045568)
		(end 41.933876 -321.709796)
		(width 0.1651)
		(layer "In7.Cu")
		(net "P5E_PEX0_STN7_TX_DP<127>")
	)
	(segment
		(start 50.712878 -347.541342)
		(end 52.267358 -345.986862)
		(width 0.1651)
		(layer "In7.Cu")
		(net "P5E_PEX0_STN7_TX_DP<127>")
	)
	(segment
		(start 52.267358 -342.294464)
		(end 51.700684 -340.426802)
		(width 0.1651)
		(layer "In7.Cu")
		(net "P5E_PEX0_STN7_TX_DP<127>")
	)
	(segment
		(start 41.933876 -321.709796)
		(end 41.933876 -319.916048)
		(width 0.1651)
		(layer "In7.Cu")
		(net "P5E_PEX0_STN7_TX_DP<127>")
	)
	(segment
		(start 50.422048 -348.58579)
		(end 50.712878 -348.29496)
		(width 0.1651)
		(layer "In7.Cu")
		(net "P5E_PEX0_STN7_TX_DP<127>")
	)
	(segment
		(start 41.979596 -319.84188)
		(end 41.979596 -313.605418)
		(width 0.1143)
		(layer "In7.Cu")
		(net "P5E_PEX0_STN7_TX_DP<127>")
	)
	(segment
		(start 41.933876 -319.8876)
		(end 41.979596 -319.84188)
		(width 0.1143)
		(layer "In7.Cu")
		(net "P5E_PEX0_STN7_TX_DP<127>")
	)
	(segment
		(start 41.979596 -313.605418)
		(end 42.205402 -313.379612)
		(width 0.1143)
		(layer "In7.Cu")
		(net "P5E_PEX0_STN7_TX_DP<127>")
	)
	(segment
		(start 51.700684 -340.426802)
		(end 46.790864 -330.045568)
		(width 0.1651)
		(layer "In7.Cu")
		(net "P5E_PEX0_STN7_TX_DP<127>")
	)
	(segment
		(start 41.933876 -319.916048)
		(end 41.933876 -319.8876)
		(width 0.1143)
		(layer "In7.Cu")
		(net "P5E_PEX0_STN7_TX_DP<127>")
	)
	(segment
		(start 42.435526 -313.379612)
		(end 42.549826 -313.265312)
		(width 0.1143)
		(layer "In7.Cu")
		(net "P5E_PEX0_STN7_TX_DP<127>")
	)
	(segment
		(start 154.793696 -103.208836)
		(end 154.162252 -103.208836)
		(width 0.13462)
		(layer "F.Cu")
		(net "P5E_PEX1_STN1_TX_DP<18>")
	)
	(segment
		(start 155.113736 -102.888796)
		(end 154.793696 -103.208836)
		(width 0.13462)
		(layer "F.Cu")
		(net "P5E_PEX1_STN1_TX_DP<18>")
	)
	(segment
		(start 154.162252 -103.208836)
		(end 153.867612 -102.914196)
		(width 0.13462)
		(layer "F.Cu")
		(net "P5E_PEX1_STN1_TX_DP<18>")
	)
	(segment
		(start 141.352778 -155.81503)
		(end 141.532102 -159.462978)
		(width 0.1651)
		(layer "In9.Cu")
		(net "P5E_PEX1_STN1_TX_DP<18>")
	)
	(segment
		(start 177.079656 -271.546066)
		(end 177.079656 -278.205184)
		(width 0.1143)
		(layer "In9.Cu")
		(net "P5E_PEX1_STN1_TX_DP<18>")
	)
	(segment
		(start 177.033936 -271.471898)
		(end 177.033936 -271.500346)
		(width 0.1143)
		(layer "In9.Cu")
		(net "P5E_PEX1_STN1_TX_DP<18>")
	)
	(segment
		(start 177.033936 -265.558016)
		(end 177.033936 -271.471898)
		(width 0.1651)
		(layer "In9.Cu")
		(net "P5E_PEX1_STN1_TX_DP<18>")
	)
	(segment
		(start 153.576782 -103.205026)
		(end 151.750776 -103.205026)
		(width 0.1651)
		(layer "In9.Cu")
		(net "P5E_PEX1_STN1_TX_DP<18>")
	)
	(segment
		(start 177.649632 -278.534368)
		(end 177.649632 -278.799798)
		(width 0.1143)
		(layer "In9.Cu")
		(net "P5E_PEX1_STN1_TX_DP<18>")
	)
	(segment
		(start 143.33474 -114.155474)
		(end 138.24077 -130.948938)
		(width 0.1651)
		(layer "In9.Cu")
		(net "P5E_PEX1_STN1_TX_DP<18>")
	)
	(segment
		(start 153.867612 -102.914196)
		(end 153.576782 -103.205026)
		(width 0.1651)
		(layer "In9.Cu")
		(net "P5E_PEX1_STN1_TX_DP<18>")
	)
	(segment
		(start 151.750776 -103.205026)
		(end 150.622254 -103.672386)
		(width 0.1651)
		(layer "In9.Cu")
		(net "P5E_PEX1_STN1_TX_DP<18>")
	)
	(segment
		(start 138.24077 -130.948938)
		(end 138.24077 -138.693652)
		(width 0.1651)
		(layer "In9.Cu")
		(net "P5E_PEX1_STN1_TX_DP<18>")
	)
	(segment
		(start 143.80718 -113.015522)
		(end 143.33474 -114.155474)
		(width 0.1651)
		(layer "In9.Cu")
		(net "P5E_PEX1_STN1_TX_DP<18>")
	)
	(segment
		(start 149.667214 -104.068118)
		(end 145.99031 -107.745022)
		(width 0.1651)
		(layer "In9.Cu")
		(net "P5E_PEX1_STN1_TX_DP<18>")
	)
	(segment
		(start 141.532102 -159.462978)
		(end 142.11554 -162.39617)
		(width 0.1651)
		(layer "In9.Cu")
		(net "P5E_PEX1_STN1_TX_DP<18>")
	)
	(segment
		(start 138.24077 -138.693652)
		(end 140.816584 -144.912588)
		(width 0.1651)
		(layer "In9.Cu")
		(net "P5E_PEX1_STN1_TX_DP<18>")
	)
	(segment
		(start 177.033936 -271.500346)
		(end 177.079656 -271.546066)
		(width 0.1143)
		(layer "In9.Cu")
		(net "P5E_PEX1_STN1_TX_DP<18>")
	)
	(segment
		(start 140.816584 -144.912588)
		(end 141.352778 -155.81503)
		(width 0.1651)
		(layer "In9.Cu")
		(net "P5E_PEX1_STN1_TX_DP<18>")
	)
	(segment
		(start 177.29454 -278.420068)
		(end 177.535332 -278.420068)
		(width 0.1143)
		(layer "In9.Cu")
		(net "P5E_PEX1_STN1_TX_DP<18>")
	)
	(segment
		(start 142.11554 -162.39617)
		(end 177.033936 -265.558016)
		(width 0.1651)
		(layer "In9.Cu")
		(net "P5E_PEX1_STN1_TX_DP<18>")
	)
	(segment
		(start 145.99031 -107.745022)
		(end 143.807434 -113.015014)
		(width 0.1651)
		(layer "In9.Cu")
		(net "P5E_PEX1_STN1_TX_DP<18>")
	)
	(segment
		(start 150.622254 -103.672386)
		(end 150.622508 -103.672386)
		(width 0.1651)
		(layer "In9.Cu")
		(net "P5E_PEX1_STN1_TX_DP<18>")
	)
	(segment
		(start 143.807434 -113.015014)
		(end 143.80718 -113.015522)
		(width 0.1651)
		(layer "In9.Cu")
		(net "P5E_PEX1_STN1_TX_DP<18>")
	)
	(segment
		(start 177.535332 -278.420068)
		(end 177.649632 -278.534368)
		(width 0.1143)
		(layer "In9.Cu")
		(net "P5E_PEX1_STN1_TX_DP<18>")
	)
	(segment
		(start 177.079656 -278.205184)
		(end 177.29454 -278.420068)
		(width 0.1143)
		(layer "In9.Cu")
		(net "P5E_PEX1_STN1_TX_DP<18>")
	)
	(segment
		(start 150.622508 -103.672386)
		(end 149.667214 -104.068118)
		(width 0.1651)
		(layer "In9.Cu")
		(net "P5E_PEX1_STN1_TX_DP<18>")
	)
	(segment
		(start 151.654764 -386.070348)
		(end 146.26463 -346.152724)
		(width 0.1651)
		(layer "In9.Cu")
		(net "P5E_PEX1_STN7_RX_DP<112>")
	)
	(segment
		(start 139.592558 -333.751428)
		(end 139.592304 -333.751174)
		(width 0.1651)
		(layer "In9.Cu")
		(net "P5E_PEX1_STN7_RX_DP<112>")
	)
	(segment
		(start 147.83054 -300.983904)
		(end 152.422352 -300.983904)
		(width 0.1651)
		(layer "In9.Cu")
		(net "P5E_PEX1_STN7_RX_DP<112>")
	)
	(segment
		(start 153.66746 -389.7249)
		(end 151.654764 -386.070348)
		(width 0.1651)
		(layer "In9.Cu")
		(net "P5E_PEX1_STN7_RX_DP<112>")
	)
	(segment
		(start 142.127224 -302.647858)
		(end 143.90243 -301.912782)
		(width 0.1651)
		(layer "In9.Cu")
		(net "P5E_PEX1_STN7_RX_DP<112>")
	)
	(segment
		(start 152.4508 -300.983904)
		(end 152.49652 -301.029624)
		(width 0.1143)
		(layer "In9.Cu")
		(net "P5E_PEX1_STN7_RX_DP<112>")
	)
	(segment
		(start 139.592304 -333.751174)
		(end 134.250938 -325.108316)
		(width 0.1651)
		(layer "In9.Cu")
		(net "P5E_PEX1_STN7_RX_DP<112>")
	)
	(segment
		(start 155.420314 -301.253652)
		(end 155.420314 -301.510954)
		(width 0.1143)
		(layer "In9.Cu")
		(net "P5E_PEX1_STN7_RX_DP<112>")
	)
	(segment
		(start 134.250938 -325.108316)
		(end 133.770624 -323.320664)
		(width 0.1651)
		(layer "In9.Cu")
		(net "P5E_PEX1_STN7_RX_DP<112>")
	)
	(segment
		(start 146.26463 -346.152724)
		(end 144.89684 -342.333834)
		(width 0.1651)
		(layer "In9.Cu")
		(net "P5E_PEX1_STN7_RX_DP<112>")
	)
	(segment
		(start 133.760972 -323.28485)
		(end 133.760972 -317.117476)
		(width 0.1651)
		(layer "In9.Cu")
		(net "P5E_PEX1_STN7_RX_DP<112>")
	)
	(segment
		(start 152.49652 -301.029624)
		(end 155.196286 -301.029624)
		(width 0.1143)
		(layer "In9.Cu")
		(net "P5E_PEX1_STN7_RX_DP<112>")
	)
	(segment
		(start 159.294068 -393.932664)
		(end 158.83636 -393.742926)
		(width 0.1651)
		(layer "In9.Cu")
		(net "P5E_PEX1_STN7_RX_DP<112>")
	)
	(segment
		(start 160.067244 -394.14323)
		(end 159.42691 -393.8778)
		(width 0.1651)
		(layer "In9.Cu")
		(net "P5E_PEX1_STN7_RX_DP<112>")
	)
	(segment
		(start 138.65098 -306.093622)
		(end 142.096744 -302.647858)
		(width 0.1651)
		(layer "In9.Cu")
		(net "P5E_PEX1_STN7_RX_DP<112>")
	)
	(segment
		(start 133.770116 -323.31914)
		(end 133.760972 -323.28485)
		(width 0.1651)
		(layer "In9.Cu")
		(net "P5E_PEX1_STN7_RX_DP<112>")
	)
	(segment
		(start 142.096744 -302.647858)
		(end 142.127224 -302.647858)
		(width 0.1651)
		(layer "In9.Cu")
		(net "P5E_PEX1_STN7_RX_DP<112>")
	)
	(segment
		(start 133.760972 -317.117476)
		(end 138.65098 -306.093622)
		(width 0.1651)
		(layer "In9.Cu")
		(net "P5E_PEX1_STN7_RX_DP<112>")
	)
	(segment
		(start 158.071058 -393.315698)
		(end 153.66746 -389.7249)
		(width 0.1651)
		(layer "In9.Cu")
		(net "P5E_PEX1_STN7_RX_DP<112>")
	)
	(segment
		(start 160.792414 -408.1653)
		(end 160.792414 -394.8684)
		(width 0.1651)
		(layer "In9.Cu")
		(net "P5E_PEX1_STN7_RX_DP<112>")
	)
	(segment
		(start 158.781242 -393.610084)
		(end 158.071058 -393.315698)
		(width 0.1651)
		(layer "In9.Cu")
		(net "P5E_PEX1_STN7_RX_DP<112>")
	)
	(segment
		(start 143.90243 -301.912782)
		(end 147.83054 -300.983904)
		(width 0.1651)
		(layer "In9.Cu")
		(net "P5E_PEX1_STN7_RX_DP<112>")
	)
	(segment
		(start 159.910018 -408.190192)
		(end 159.910018 -408.572208)
		(width 0.1651)
		(layer "In9.Cu")
		(net "P5E_PEX1_STN7_RX_DP<112>")
	)
	(segment
		(start 144.89684 -342.333834)
		(end 139.592558 -333.751428)
		(width 0.1651)
		(layer "In9.Cu")
		(net "P5E_PEX1_STN7_RX_DP<112>")
	)
	(segment
		(start 133.770116 -323.319648)
		(end 133.770116 -323.31914)
		(width 0.1651)
		(layer "In9.Cu")
		(net "P5E_PEX1_STN7_RX_DP<112>")
	)
	(segment
		(start 133.770624 -323.320664)
		(end 133.77037 -323.320664)
		(width 0.1651)
		(layer "In9.Cu")
		(net "P5E_PEX1_STN7_RX_DP<112>")
	)
	(segment
		(start 155.196286 -301.029624)
		(end 155.420314 -301.253652)
		(width 0.1143)
		(layer "In9.Cu")
		(net "P5E_PEX1_STN7_RX_DP<112>")
	)
	(segment
		(start 159.910018 -408.572208)
		(end 160.037018 -408.699208)
		(width 0.1651)
		(layer "In9.Cu")
		(net "P5E_PEX1_STN7_RX_DP<112>")
	)
	(segment
		(start 160.792414 -394.8684)
		(end 160.067244 -394.14323)
		(width 0.1651)
		(layer "In9.Cu")
		(net "P5E_PEX1_STN7_RX_DP<112>")
	)
	(segment
		(start 158.83636 -393.742926)
		(end 158.781242 -393.610084)
		(width 0.1651)
		(layer "In9.Cu")
		(net "P5E_PEX1_STN7_RX_DP<112>")
	)
	(segment
		(start 160.037018 -408.699208)
		(end 160.258506 -408.699208)
		(width 0.1651)
		(layer "In9.Cu")
		(net "P5E_PEX1_STN7_RX_DP<112>")
	)
	(segment
		(start 155.420314 -301.510954)
		(end 155.509214 -301.599854)
		(width 0.1143)
		(layer "In9.Cu")
		(net "P5E_PEX1_STN7_RX_DP<112>")
	)
	(segment
		(start 152.422352 -300.983904)
		(end 152.4508 -300.983904)
		(width 0.1143)
		(layer "In9.Cu")
		(net "P5E_PEX1_STN7_RX_DP<112>")
	)
	(segment
		(start 159.42691 -393.8778)
		(end 159.294068 -393.932664)
		(width 0.1651)
		(layer "In9.Cu")
		(net "P5E_PEX1_STN7_RX_DP<112>")
	)
	(segment
		(start 155.509214 -301.599854)
		(end 155.800044 -301.599854)
		(width 0.1143)
		(layer "In9.Cu")
		(net "P5E_PEX1_STN7_RX_DP<112>")
	)
	(segment
		(start 133.77037 -323.320664)
		(end 133.770116 -323.319648)
		(width 0.1651)
		(layer "In9.Cu")
		(net "P5E_PEX1_STN7_RX_DP<112>")
	)
	(segment
		(start 160.258506 -408.699208)
		(end 160.792414 -408.1653)
		(width 0.1651)
		(layer "In9.Cu")
		(net "P5E_PEX1_STN7_RX_DP<112>")
	)
	(segment
		(start 39.013892 -135.815324)
		(end 38.693852 -136.135364)
		(width 0.13462)
		(layer "F.Cu")
		(net "P5E_PEX0_STN1_TX_DN<31>")
	)
	(segment
		(start 38.062408 -136.135364)
		(end 37.767768 -135.840724)
		(width 0.13462)
		(layer "F.Cu")
		(net "P5E_PEX0_STN1_TX_DN<31>")
	)
	(segment
		(start 38.693852 -136.135364)
		(end 38.062408 -136.135364)
		(width 0.13462)
		(layer "F.Cu")
		(net "P5E_PEX0_STN1_TX_DN<31>")
	)
	(segment
		(start 73.283826 -271.526)
		(end 73.283826 -262.6106)
		(width 0.1651)
		(layer "In9.Cu")
		(net "P5E_PEX0_STN1_TX_DN<31>")
	)
	(segment
		(start 37.59581 -138.46683)
		(end 36.35756 -137.22858)
		(width 0.1651)
		(layer "In9.Cu")
		(net "P5E_PEX0_STN1_TX_DN<31>")
	)
	(segment
		(start 37.476938 -136.131554)
		(end 37.767768 -135.840724)
		(width 0.1651)
		(layer "In9.Cu")
		(net "P5E_PEX0_STN1_TX_DN<31>")
	)
	(segment
		(start 73.329546 -271.600168)
		(end 73.283826 -271.554448)
		(width 0.1143)
		(layer "In9.Cu")
		(net "P5E_PEX0_STN1_TX_DN<31>")
	)
	(segment
		(start 73.283826 -271.554448)
		(end 73.283826 -271.526)
		(width 0.1143)
		(layer "In9.Cu")
		(net "P5E_PEX0_STN1_TX_DN<31>")
	)
	(segment
		(start 73.899776 -280.434288)
		(end 73.785476 -280.319988)
		(width 0.1143)
		(layer "In9.Cu")
		(net "P5E_PEX0_STN1_TX_DN<31>")
	)
	(segment
		(start 73.283826 -262.6106)
		(end 47.124366 -185.333386)
		(width 0.1651)
		(layer "In9.Cu")
		(net "P5E_PEX0_STN1_TX_DN<31>")
	)
	(segment
		(start 73.544684 -280.319988)
		(end 73.329546 -280.10485)
		(width 0.1143)
		(layer "In9.Cu")
		(net "P5E_PEX0_STN1_TX_DN<31>")
	)
	(segment
		(start 73.899776 -280.699718)
		(end 73.899776 -280.434288)
		(width 0.1143)
		(layer "In9.Cu")
		(net "P5E_PEX0_STN1_TX_DN<31>")
	)
	(segment
		(start 36.750752 -136.131554)
		(end 37.476938 -136.131554)
		(width 0.1651)
		(layer "In9.Cu")
		(net "P5E_PEX0_STN1_TX_DN<31>")
	)
	(segment
		(start 47.124366 -185.333386)
		(end 38.019482 -139.489688)
		(width 0.1651)
		(layer "In9.Cu")
		(net "P5E_PEX0_STN1_TX_DN<31>")
	)
	(segment
		(start 73.329546 -280.10485)
		(end 73.329546 -271.600168)
		(width 0.1143)
		(layer "In9.Cu")
		(net "P5E_PEX0_STN1_TX_DN<31>")
	)
	(segment
		(start 36.35756 -136.524746)
		(end 36.750752 -136.131554)
		(width 0.1651)
		(layer "In9.Cu")
		(net "P5E_PEX0_STN1_TX_DN<31>")
	)
	(segment
		(start 73.785476 -280.319988)
		(end 73.544684 -280.319988)
		(width 0.1143)
		(layer "In9.Cu")
		(net "P5E_PEX0_STN1_TX_DN<31>")
	)
	(segment
		(start 36.35756 -137.22858)
		(end 36.35756 -136.524746)
		(width 0.1651)
		(layer "In9.Cu")
		(net "P5E_PEX0_STN1_TX_DN<31>")
	)
	(segment
		(start 38.019482 -139.489688)
		(end 37.59581 -138.46683)
		(width 0.1651)
		(layer "In9.Cu")
		(net "P5E_PEX0_STN1_TX_DN<31>")
	)
	(segment
		(start 152.151588 -112.215422)
		(end 151.520144 -112.215422)
		(width 0.13462)
		(layer "F.Cu")
		(net "P5E_PEX1_STN1_TX_DN<23>")
	)
	(segment
		(start 151.520144 -112.215422)
		(end 151.225504 -111.920782)
		(width 0.13462)
		(layer "F.Cu")
		(net "P5E_PEX1_STN1_TX_DN<23>")
	)
	(segment
		(start 152.471628 -111.895382)
		(end 152.151588 -112.215422)
		(width 0.13462)
		(layer "F.Cu")
		(net "P5E_PEX1_STN1_TX_DN<23>")
	)
	(segment
		(start 145.904712 -122.296936)
		(end 143.07947 -131.610608)
		(width 0.1651)
		(layer "In9.Cu")
		(net "P5E_PEX1_STN1_TX_DN<23>")
	)
	(segment
		(start 146.37004 -158.661354)
		(end 146.95424 -161.59861)
		(width 0.1651)
		(layer "In9.Cu")
		(net "P5E_PEX1_STN1_TX_DN<23>")
	)
	(segment
		(start 182.044848 -280.319988)
		(end 182.28564 -280.319988)
		(width 0.1143)
		(layer "In9.Cu")
		(net "P5E_PEX1_STN1_TX_DN<23>")
	)
	(segment
		(start 150.934674 -112.211612)
		(end 150.235412 -112.211612)
		(width 0.1651)
		(layer "In9.Cu")
		(net "P5E_PEX1_STN1_TX_DN<23>")
	)
	(segment
		(start 146.005042 -151.235156)
		(end 146.005042 -151.234902)
		(width 0.1651)
		(layer "In9.Cu")
		(net "P5E_PEX1_STN1_TX_DN<23>")
	)
	(segment
		(start 146.95424 -161.59861)
		(end 181.78399 -264.494518)
		(width 0.1651)
		(layer "In9.Cu")
		(net "P5E_PEX1_STN1_TX_DN<23>")
	)
	(segment
		(start 181.82971 -271.600168)
		(end 181.82971 -280.10485)
		(width 0.1143)
		(layer "In9.Cu")
		(net "P5E_PEX1_STN1_TX_DN<23>")
	)
	(segment
		(start 150.235412 -112.211612)
		(end 149.974046 -112.472978)
		(width 0.1651)
		(layer "In9.Cu")
		(net "P5E_PEX1_STN1_TX_DN<23>")
	)
	(segment
		(start 181.82971 -280.10485)
		(end 182.044848 -280.319988)
		(width 0.1143)
		(layer "In9.Cu")
		(net "P5E_PEX1_STN1_TX_DN<23>")
	)
	(segment
		(start 181.78399 -271.554448)
		(end 181.82971 -271.600168)
		(width 0.1143)
		(layer "In9.Cu")
		(net "P5E_PEX1_STN1_TX_DN<23>")
	)
	(segment
		(start 182.39994 -280.434288)
		(end 182.39994 -280.699718)
		(width 0.1143)
		(layer "In9.Cu")
		(net "P5E_PEX1_STN1_TX_DN<23>")
	)
	(segment
		(start 145.640298 -143.809212)
		(end 146.005042 -151.235156)
		(width 0.1651)
		(layer "In9.Cu")
		(net "P5E_PEX1_STN1_TX_DN<23>")
	)
	(segment
		(start 181.78399 -271.526)
		(end 181.78399 -271.554448)
		(width 0.1143)
		(layer "In9.Cu")
		(net "P5E_PEX1_STN1_TX_DN<23>")
	)
	(segment
		(start 143.07947 -137.626852)
		(end 145.640298 -143.809212)
		(width 0.1651)
		(layer "In9.Cu")
		(net "P5E_PEX1_STN1_TX_DN<23>")
	)
	(segment
		(start 143.07947 -131.610608)
		(end 143.07947 -137.626852)
		(width 0.1651)
		(layer "In9.Cu")
		(net "P5E_PEX1_STN1_TX_DN<23>")
	)
	(segment
		(start 151.225504 -111.920782)
		(end 150.934674 -112.211612)
		(width 0.1651)
		(layer "In9.Cu")
		(net "P5E_PEX1_STN1_TX_DN<23>")
	)
	(segment
		(start 146.005042 -151.234902)
		(end 146.37004 -158.661354)
		(width 0.1651)
		(layer "In9.Cu")
		(net "P5E_PEX1_STN1_TX_DN<23>")
	)
	(segment
		(start 181.78399 -264.494518)
		(end 181.78399 -271.526)
		(width 0.1651)
		(layer "In9.Cu")
		(net "P5E_PEX1_STN1_TX_DN<23>")
	)
	(segment
		(start 149.974046 -112.472978)
		(end 145.904712 -122.296936)
		(width 0.1651)
		(layer "In9.Cu")
		(net "P5E_PEX1_STN1_TX_DN<23>")
	)
	(segment
		(start 182.28564 -280.319988)
		(end 182.39994 -280.434288)
		(width 0.1143)
		(layer "In9.Cu")
		(net "P5E_PEX1_STN1_TX_DN<23>")
	)
	(segment
		(start 177.384456 -318.320166)
		(end 177.535586 -318.320166)
		(width 0.1143)
		(layer "In5.Cu")
		(net "P5E_PEX1_STN5_RX_DN<83>")
	)
	(segment
		(start 177.079402 -324.18655)
		(end 177.315876 -323.381624)
		(width 0.1651)
		(layer "In5.Cu")
		(net "P5E_PEX1_STN5_RX_DN<83>")
	)
	(segment
		(start 123.186698 -398.38122)
		(end 123.569476 -397.998442)
		(width 0.1651)
		(layer "In5.Cu")
		(net "P5E_PEX1_STN5_RX_DN<83>")
	)
	(segment
		(start 159.193484 -338.418424)
		(end 161.438336 -335.90992)
		(width 0.1651)
		(layer "In5.Cu")
		(net "P5E_PEX1_STN5_RX_DN<83>")
	)
	(segment
		(start 161.438336 -335.90992)
		(end 174.220124 -328.420222)
		(width 0.1651)
		(layer "In5.Cu")
		(net "P5E_PEX1_STN5_RX_DN<83>")
	)
	(segment
		(start 146.729704 -366.590072)
		(end 151.84501 -353.093274)
		(width 0.1651)
		(layer "In5.Cu")
		(net "P5E_PEX1_STN5_RX_DN<83>")
	)
	(segment
		(start 177.535586 -318.320166)
		(end 177.649886 -318.434466)
		(width 0.1143)
		(layer "In5.Cu")
		(net "P5E_PEX1_STN5_RX_DN<83>")
	)
	(segment
		(start 122.637042 -398.38122)
		(end 123.186698 -398.38122)
		(width 0.1651)
		(layer "In5.Cu")
		(net "P5E_PEX1_STN5_RX_DN<83>")
	)
	(segment
		(start 177.649886 -318.434466)
		(end 177.649886 -318.699896)
		(width 0.1143)
		(layer "In5.Cu")
		(net "P5E_PEX1_STN5_RX_DN<83>")
	)
	(segment
		(start 132.756148 -390.635998)
		(end 136.94029 -389.80237)
		(width 0.1651)
		(layer "In5.Cu")
		(net "P5E_PEX1_STN5_RX_DN<83>")
	)
	(segment
		(start 122.510042 -398.890236)
		(end 122.510042 -398.50822)
		(width 0.1651)
		(layer "In5.Cu")
		(net "P5E_PEX1_STN5_RX_DN<83>")
	)
	(segment
		(start 177.315876 -323.381624)
		(end 177.315876 -319.91173)
		(width 0.1651)
		(layer "In5.Cu")
		(net "P5E_PEX1_STN5_RX_DN<83>")
	)
	(segment
		(start 177.315876 -319.883282)
		(end 177.270156 -319.837562)
		(width 0.1143)
		(layer "In5.Cu")
		(net "P5E_PEX1_STN5_RX_DN<83>")
	)
	(segment
		(start 176.105058 -326.535288)
		(end 177.079402 -324.18655)
		(width 0.1651)
		(layer "In5.Cu")
		(net "P5E_PEX1_STN5_RX_DN<83>")
	)
	(segment
		(start 139.356338 -387.331966)
		(end 145.60677 -370.633752)
		(width 0.1651)
		(layer "In5.Cu")
		(net "P5E_PEX1_STN5_RX_DN<83>")
	)
	(segment
		(start 174.220124 -328.420222)
		(end 176.105058 -326.535288)
		(width 0.1651)
		(layer "In5.Cu")
		(net "P5E_PEX1_STN5_RX_DN<83>")
	)
	(segment
		(start 123.569476 -396.107158)
		(end 124.088398 -394.861034)
		(width 0.1651)
		(layer "In5.Cu")
		(net "P5E_PEX1_STN5_RX_DN<83>")
	)
	(segment
		(start 177.270156 -318.434466)
		(end 177.384456 -318.320166)
		(width 0.1143)
		(layer "In5.Cu")
		(net "P5E_PEX1_STN5_RX_DN<83>")
	)
	(segment
		(start 123.569476 -397.998442)
		(end 123.569476 -396.107158)
		(width 0.1651)
		(layer "In5.Cu")
		(net "P5E_PEX1_STN5_RX_DN<83>")
	)
	(segment
		(start 124.088398 -394.861034)
		(end 124.599954 -394.314172)
		(width 0.1651)
		(layer "In5.Cu")
		(net "P5E_PEX1_STN5_RX_DN<83>")
	)
	(segment
		(start 122.510042 -398.50822)
		(end 122.637042 -398.38122)
		(width 0.1651)
		(layer "In5.Cu")
		(net "P5E_PEX1_STN5_RX_DN<83>")
	)
	(segment
		(start 177.315876 -319.91173)
		(end 177.315876 -319.883282)
		(width 0.1143)
		(layer "In5.Cu")
		(net "P5E_PEX1_STN5_RX_DN<83>")
	)
	(segment
		(start 129.23901 -392.008106)
		(end 132.756148 -390.635998)
		(width 0.1651)
		(layer "In5.Cu")
		(net "P5E_PEX1_STN5_RX_DN<83>")
	)
	(segment
		(start 145.60677 -370.633752)
		(end 146.729704 -366.590072)
		(width 0.1651)
		(layer "In5.Cu")
		(net "P5E_PEX1_STN5_RX_DN<83>")
	)
	(segment
		(start 151.84501 -353.093274)
		(end 159.193484 -338.418424)
		(width 0.1651)
		(layer "In5.Cu")
		(net "P5E_PEX1_STN5_RX_DN<83>")
	)
	(segment
		(start 177.270156 -319.837562)
		(end 177.270156 -318.434466)
		(width 0.1143)
		(layer "In5.Cu")
		(net "P5E_PEX1_STN5_RX_DN<83>")
	)
	(segment
		(start 138.568938 -388.654544)
		(end 139.356338 -387.331966)
		(width 0.1651)
		(layer "In5.Cu")
		(net "P5E_PEX1_STN5_RX_DN<83>")
	)
	(segment
		(start 124.599954 -394.314172)
		(end 129.23901 -392.008106)
		(width 0.1651)
		(layer "In5.Cu")
		(net "P5E_PEX1_STN5_RX_DN<83>")
	)
	(segment
		(start 136.94029 -389.80237)
		(end 138.568938 -388.654544)
		(width 0.1651)
		(layer "In5.Cu")
		(net "P5E_PEX1_STN5_RX_DN<83>")
	)
	(segment
		(start 61.666882 -351.316798)
		(end 61.666882 -350.685354)
		(width 0.13462)
		(layer "F.Cu")
		(net "P5E_PEX0_STN5_TX_C_DP<80>")
	)
	(segment
		(start 61.666882 -350.685354)
		(end 61.346842 -350.365314)
		(width 0.13462)
		(layer "F.Cu")
		(net "P5E_PEX0_STN5_TX_C_DP<80>")
	)
	(segment
		(start 61.372242 -351.611438)
		(end 61.666882 -351.316798)
		(width 0.13462)
		(layer "F.Cu")
		(net "P5E_PEX0_STN5_TX_C_DP<80>")
	)
	(segment
		(start 61.372242 -351.611438)
		(end 61.663072 -351.902268)
		(width 0.1651)
		(layer "In7.Cu")
		(net "P5E_PEX0_STN5_TX_C_DP<80>")
	)
	(segment
		(start 68.034408 -392.102086)
		(end 68.0847 -392.102086)
		(width 0.1651)
		(layer "In7.Cu")
		(net "P5E_PEX0_STN5_TX_C_DP<80>")
	)
	(segment
		(start 65.197482 -389.26516)
		(end 68.034408 -392.102086)
		(width 0.1651)
		(layer "In7.Cu")
		(net "P5E_PEX0_STN5_TX_C_DP<80>")
	)
	(segment
		(start 72.802242 -394.587222)
		(end 72.802242 -404.370032)
		(width 0.1651)
		(layer "In7.Cu")
		(net "P5E_PEX0_STN5_TX_C_DP<80>")
	)
	(segment
		(start 69.314314 -392.632438)
		(end 69.771768 -392.821922)
		(width 0.1651)
		(layer "In7.Cu")
		(net "P5E_PEX0_STN5_TX_C_DP<80>")
	)
	(segment
		(start 68.692268 -392.374628)
		(end 68.740274 -392.490706)
		(width 0.1651)
		(layer "In7.Cu")
		(net "P5E_PEX0_STN5_TX_C_DP<80>")
	)
	(segment
		(start 72.802242 -404.370032)
		(end 72.373236 -404.799038)
		(width 0.1651)
		(layer "In7.Cu")
		(net "P5E_PEX0_STN5_TX_C_DP<80>")
	)
	(segment
		(start 63.763906 -385.804156)
		(end 65.197482 -389.26516)
		(width 0.1651)
		(layer "In7.Cu")
		(net "P5E_PEX0_STN5_TX_C_DP<80>")
	)
	(segment
		(start 68.740274 -392.490706)
		(end 69.198236 -392.680698)
		(width 0.1651)
		(layer "In7.Cu")
		(net "P5E_PEX0_STN5_TX_C_DP<80>")
	)
	(segment
		(start 68.0847 -392.102086)
		(end 68.120514 -392.1379)
		(width 0.1651)
		(layer "In7.Cu")
		(net "P5E_PEX0_STN5_TX_C_DP<80>")
	)
	(segment
		(start 61.663072 -351.902268)
		(end 61.663072 -355.999288)
		(width 0.1651)
		(layer "In7.Cu")
		(net "P5E_PEX0_STN5_TX_C_DP<80>")
	)
	(segment
		(start 69.772022 -392.821922)
		(end 69.820282 -392.938)
		(width 0.1651)
		(layer "In7.Cu")
		(net "P5E_PEX0_STN5_TX_C_DP<80>")
	)
	(segment
		(start 70.394322 -393.079478)
		(end 70.851776 -393.268962)
		(width 0.1651)
		(layer "In7.Cu")
		(net "P5E_PEX0_STN5_TX_C_DP<80>")
	)
	(segment
		(start 71.357744 -393.575032)
		(end 71.473822 -393.526772)
		(width 0.1651)
		(layer "In7.Cu")
		(net "P5E_PEX0_STN5_TX_C_DP<80>")
	)
	(segment
		(start 72.03694 -404.799038)
		(end 71.90994 -404.672038)
		(width 0.1651)
		(layer "In7.Cu")
		(net "P5E_PEX0_STN5_TX_C_DP<80>")
	)
	(segment
		(start 68.120514 -392.1379)
		(end 68.692268 -392.374628)
		(width 0.1651)
		(layer "In7.Cu")
		(net "P5E_PEX0_STN5_TX_C_DP<80>")
	)
	(segment
		(start 70.278244 -393.127738)
		(end 70.394322 -393.079478)
		(width 0.1651)
		(layer "In7.Cu")
		(net "P5E_PEX0_STN5_TX_C_DP<80>")
	)
	(segment
		(start 71.473822 -393.526772)
		(end 71.931276 -393.716256)
		(width 0.1651)
		(layer "In7.Cu")
		(net "P5E_PEX0_STN5_TX_C_DP<80>")
	)
	(segment
		(start 71.90994 -404.672038)
		(end 71.90994 -404.290022)
		(width 0.1651)
		(layer "In7.Cu")
		(net "P5E_PEX0_STN5_TX_C_DP<80>")
	)
	(segment
		(start 69.771768 -392.821922)
		(end 69.772022 -392.821922)
		(width 0.1651)
		(layer "In7.Cu")
		(net "P5E_PEX0_STN5_TX_C_DP<80>")
	)
	(segment
		(start 71.931276 -393.716256)
		(end 72.802242 -394.587222)
		(width 0.1651)
		(layer "In7.Cu")
		(net "P5E_PEX0_STN5_TX_C_DP<80>")
	)
	(segment
		(start 61.663072 -355.999288)
		(end 62.787022 -376.792236)
		(width 0.1651)
		(layer "In7.Cu")
		(net "P5E_PEX0_STN5_TX_C_DP<80>")
	)
	(segment
		(start 72.373236 -404.799038)
		(end 72.03694 -404.799038)
		(width 0.1651)
		(layer "In7.Cu")
		(net "P5E_PEX0_STN5_TX_C_DP<80>")
	)
	(segment
		(start 70.899782 -393.385294)
		(end 71.357744 -393.575032)
		(width 0.1651)
		(layer "In7.Cu")
		(net "P5E_PEX0_STN5_TX_C_DP<80>")
	)
	(segment
		(start 62.787022 -376.792236)
		(end 63.763906 -385.804156)
		(width 0.1651)
		(layer "In7.Cu")
		(net "P5E_PEX0_STN5_TX_C_DP<80>")
	)
	(segment
		(start 69.198236 -392.680698)
		(end 69.314314 -392.632438)
		(width 0.1651)
		(layer "In7.Cu")
		(net "P5E_PEX0_STN5_TX_C_DP<80>")
	)
	(segment
		(start 70.851776 -393.268962)
		(end 70.899782 -393.385294)
		(width 0.1651)
		(layer "In7.Cu")
		(net "P5E_PEX0_STN5_TX_C_DP<80>")
	)
	(segment
		(start 69.820282 -392.938)
		(end 70.278244 -393.127738)
		(width 0.1651)
		(layer "In7.Cu")
		(net "P5E_PEX0_STN5_TX_C_DP<80>")
	)
	(segment
		(start 83.248246 -151.916892)
		(end 83.87969 -151.916892)
		(width 0.13462)
		(layer "F.Cu")
		(net "P5E_PEX0_STN0_TX_DN<13>")
	)
	(segment
		(start 82.928206 -151.596852)
		(end 83.248246 -151.916892)
		(width 0.13462)
		(layer "F.Cu")
		(net "P5E_PEX0_STN0_TX_DN<13>")
	)
	(segment
		(start 83.87969 -151.916892)
		(end 84.17433 -151.622252)
		(width 0.13462)
		(layer "F.Cu")
		(net "P5E_PEX0_STN0_TX_DN<13>")
	)
	(segment
		(start 85.248496 -151.913082)
		(end 84.46516 -151.913082)
		(width 0.1651)
		(layer "In9.Cu")
		(net "P5E_PEX0_STN0_TX_DN<13>")
	)
	(segment
		(start 77.325728 -267.847064)
		(end 77.325728 -260.750558)
		(width 0.1651)
		(layer "In9.Cu")
		(net "P5E_PEX0_STN0_TX_DN<13>")
	)
	(segment
		(start 76.4159 -271.471898)
		(end 76.4159 -270.044164)
		(width 0.1651)
		(layer "In9.Cu")
		(net "P5E_PEX0_STN0_TX_DN<13>")
	)
	(segment
		(start 76.749656 -277.849838)
		(end 76.749656 -278.115268)
		(width 0.1143)
		(layer "In9.Cu")
		(net "P5E_PEX0_STN0_TX_DN<13>")
	)
	(segment
		(start 76.473558 -278.229568)
		(end 76.37018 -278.12619)
		(width 0.1143)
		(layer "In9.Cu")
		(net "P5E_PEX0_STN0_TX_DN<13>")
	)
	(segment
		(start 76.37018 -271.546066)
		(end 76.4159 -271.500346)
		(width 0.1143)
		(layer "In9.Cu")
		(net "P5E_PEX0_STN0_TX_DN<13>")
	)
	(segment
		(start 73.880726 -221.36227)
		(end 77.762354 -177.001678)
		(width 0.1651)
		(layer "In9.Cu")
		(net "P5E_PEX0_STN0_TX_DN<13>")
	)
	(segment
		(start 76.635356 -278.229568)
		(end 76.473558 -278.229568)
		(width 0.1143)
		(layer "In9.Cu")
		(net "P5E_PEX0_STN0_TX_DN<13>")
	)
	(segment
		(start 79.201264 -171.632118)
		(end 87.590884 -157.099254)
		(width 0.1651)
		(layer "In9.Cu")
		(net "P5E_PEX0_STN0_TX_DN<13>")
	)
	(segment
		(start 87.590884 -157.099254)
		(end 87.590884 -155.576524)
		(width 0.1651)
		(layer "In9.Cu")
		(net "P5E_PEX0_STN0_TX_DN<13>")
	)
	(segment
		(start 77.762354 -177.001678)
		(end 79.201264 -171.632118)
		(width 0.1651)
		(layer "In9.Cu")
		(net "P5E_PEX0_STN0_TX_DN<13>")
	)
	(segment
		(start 76.4159 -271.500346)
		(end 76.4159 -271.471898)
		(width 0.1143)
		(layer "In9.Cu")
		(net "P5E_PEX0_STN0_TX_DN<13>")
	)
	(segment
		(start 76.4159 -270.044164)
		(end 77.325728 -267.847064)
		(width 0.1651)
		(layer "In9.Cu")
		(net "P5E_PEX0_STN0_TX_DN<13>")
	)
	(segment
		(start 87.590884 -155.576524)
		(end 87.171784 -154.564334)
		(width 0.1651)
		(layer "In9.Cu")
		(net "P5E_PEX0_STN0_TX_DN<13>")
	)
	(segment
		(start 85.705442 -152.370028)
		(end 85.248496 -151.913082)
		(width 0.1651)
		(layer "In9.Cu")
		(net "P5E_PEX0_STN0_TX_DN<13>")
	)
	(segment
		(start 76.749656 -278.115268)
		(end 76.635356 -278.229568)
		(width 0.1143)
		(layer "In9.Cu")
		(net "P5E_PEX0_STN0_TX_DN<13>")
	)
	(segment
		(start 76.37018 -278.12619)
		(end 76.37018 -271.546066)
		(width 0.1143)
		(layer "In9.Cu")
		(net "P5E_PEX0_STN0_TX_DN<13>")
	)
	(segment
		(start 77.325728 -260.750558)
		(end 73.880726 -221.36227)
		(width 0.1651)
		(layer "In9.Cu")
		(net "P5E_PEX0_STN0_TX_DN<13>")
	)
	(segment
		(start 84.46516 -151.913082)
		(end 84.17433 -151.622252)
		(width 0.1651)
		(layer "In9.Cu")
		(net "P5E_PEX0_STN0_TX_DN<13>")
	)
	(segment
		(start 87.171784 -154.564334)
		(end 85.705442 -152.370028)
		(width 0.1651)
		(layer "In9.Cu")
		(net "P5E_PEX0_STN0_TX_DN<13>")
	)
	(segment
		(start 152.151588 -130.728974)
		(end 151.520144 -130.728974)
		(width 0.13462)
		(layer "F.Cu")
		(net "P5E_PEX1_STN1_TX_DP<28>")
	)
	(segment
		(start 152.471628 -130.408934)
		(end 152.151588 -130.728974)
		(width 0.13462)
		(layer "F.Cu")
		(net "P5E_PEX1_STN1_TX_DP<28>")
	)
	(segment
		(start 151.520144 -130.728974)
		(end 151.225504 -130.434334)
		(width 0.13462)
		(layer "F.Cu")
		(net "P5E_PEX1_STN1_TX_DP<28>")
	)
	(segment
		(start 148.194014 -133.57352)
		(end 147.91817 -134.239508)
		(width 0.1651)
		(layer "In9.Cu")
		(net "P5E_PEX1_STN1_TX_DP<28>")
	)
	(segment
		(start 149.989794 -130.885692)
		(end 149.742652 -131.25577)
		(width 0.1651)
		(layer "In9.Cu")
		(net "P5E_PEX1_STN1_TX_DP<28>")
	)
	(segment
		(start 186.534044 -263.430258)
		(end 186.534044 -271.471898)
		(width 0.1651)
		(layer "In9.Cu")
		(net "P5E_PEX1_STN1_TX_DP<28>")
	)
	(segment
		(start 150.290022 -130.725164)
		(end 149.989794 -130.885692)
		(width 0.1651)
		(layer "In9.Cu")
		(net "P5E_PEX1_STN1_TX_DP<28>")
	)
	(segment
		(start 147.91817 -136.050782)
		(end 150.5204 -142.333472)
		(width 0.1651)
		(layer "In9.Cu")
		(net "P5E_PEX1_STN1_TX_DP<28>")
	)
	(segment
		(start 150.934674 -130.725164)
		(end 150.290022 -130.725164)
		(width 0.1651)
		(layer "In9.Cu")
		(net "P5E_PEX1_STN1_TX_DP<28>")
	)
	(segment
		(start 148.932646 -132.467858)
		(end 148.932392 -132.467858)
		(width 0.1651)
		(layer "In9.Cu")
		(net "P5E_PEX1_STN1_TX_DP<28>")
	)
	(segment
		(start 152.076404 -161.63925)
		(end 186.534044 -263.430258)
		(width 0.1651)
		(layer "In9.Cu")
		(net "P5E_PEX1_STN1_TX_DP<28>")
	)
	(segment
		(start 147.91817 -134.239508)
		(end 147.91817 -136.050782)
		(width 0.1651)
		(layer "In9.Cu")
		(net "P5E_PEX1_STN1_TX_DP<28>")
	)
	(segment
		(start 150.5204 -142.333472)
		(end 151.270716 -157.586934)
		(width 0.1651)
		(layer "In9.Cu")
		(net "P5E_PEX1_STN1_TX_DP<28>")
	)
	(segment
		(start 187.03544 -278.420068)
		(end 187.14974 -278.534368)
		(width 0.1143)
		(layer "In9.Cu")
		(net "P5E_PEX1_STN1_TX_DP<28>")
	)
	(segment
		(start 186.534044 -271.500346)
		(end 186.579764 -271.546066)
		(width 0.1143)
		(layer "In9.Cu")
		(net "P5E_PEX1_STN1_TX_DP<28>")
	)
	(segment
		(start 186.579764 -271.546066)
		(end 186.579764 -278.205184)
		(width 0.1143)
		(layer "In9.Cu")
		(net "P5E_PEX1_STN1_TX_DP<28>")
	)
	(segment
		(start 186.579764 -278.205184)
		(end 186.794648 -278.420068)
		(width 0.1143)
		(layer "In9.Cu")
		(net "P5E_PEX1_STN1_TX_DP<28>")
	)
	(segment
		(start 186.534044 -271.471898)
		(end 186.534044 -271.500346)
		(width 0.1143)
		(layer "In9.Cu")
		(net "P5E_PEX1_STN1_TX_DP<28>")
	)
	(segment
		(start 149.742652 -131.25577)
		(end 149.742398 -131.25577)
		(width 0.1651)
		(layer "In9.Cu")
		(net "P5E_PEX1_STN1_TX_DP<28>")
	)
	(segment
		(start 151.225504 -130.434334)
		(end 150.934674 -130.725164)
		(width 0.1651)
		(layer "In9.Cu")
		(net "P5E_PEX1_STN1_TX_DP<28>")
	)
	(segment
		(start 187.14974 -278.534368)
		(end 187.14974 -278.799798)
		(width 0.1143)
		(layer "In9.Cu")
		(net "P5E_PEX1_STN1_TX_DP<28>")
	)
	(segment
		(start 149.742398 -131.25577)
		(end 148.932646 -132.467858)
		(width 0.1651)
		(layer "In9.Cu")
		(net "P5E_PEX1_STN1_TX_DP<28>")
	)
	(segment
		(start 151.270716 -157.586934)
		(end 152.076404 -161.63925)
		(width 0.1651)
		(layer "In9.Cu")
		(net "P5E_PEX1_STN1_TX_DP<28>")
	)
	(segment
		(start 186.794648 -278.420068)
		(end 187.03544 -278.420068)
		(width 0.1143)
		(layer "In9.Cu")
		(net "P5E_PEX1_STN1_TX_DP<28>")
	)
	(segment
		(start 148.932392 -132.467858)
		(end 148.194014 -133.57352)
		(width 0.1651)
		(layer "In9.Cu")
		(net "P5E_PEX1_STN1_TX_DP<28>")
	)
	(segment
		(start 130.094228 -367.010442)
		(end 128.445514 -368.123978)
		(width 0.1651)
		(layer "In15.Cu")
		(net "P5E_PEX1_STN5_RX_DP<93>")
	)
	(segment
		(start 186.534044 -319.916048)
		(end 186.534044 -320.81851)
		(width 0.1651)
		(layer "In15.Cu")
		(net "P5E_PEX1_STN5_RX_DP<93>")
	)
	(segment
		(start 186.579764 -319.84188)
		(end 186.534044 -319.8876)
		(width 0.1143)
		(layer "In15.Cu")
		(net "P5E_PEX1_STN5_RX_DP<93>")
	)
	(segment
		(start 186.165998 -321.771772)
		(end 185.433208 -322.96227)
		(width 0.1651)
		(layer "In15.Cu")
		(net "P5E_PEX1_STN5_RX_DP<93>")
	)
	(segment
		(start 162.028632 -340.878922)
		(end 146.652996 -357.515922)
		(width 0.1651)
		(layer "In15.Cu")
		(net "P5E_PEX1_STN5_RX_DP<93>")
	)
	(segment
		(start 135.411464 -364.325408)
		(end 134.965948 -364.542324)
		(width 0.1651)
		(layer "In15.Cu")
		(net "P5E_PEX1_STN5_RX_DP<93>")
	)
	(segment
		(start 134.360666 -364.83671)
		(end 133.914896 -365.053626)
		(width 0.1651)
		(layer "In15.Cu")
		(net "P5E_PEX1_STN5_RX_DP<93>")
	)
	(segment
		(start 185.433208 -322.96227)
		(end 181.421024 -326.974454)
		(width 0.1651)
		(layer "In15.Cu")
		(net "P5E_PEX1_STN5_RX_DP<93>")
	)
	(segment
		(start 126.910084 -371.972078)
		(end 126.910084 -371.590062)
		(width 0.1651)
		(layer "In15.Cu")
		(net "P5E_PEX1_STN5_RX_DP<93>")
	)
	(segment
		(start 187.149994 -317.749936)
		(end 187.149994 -318.040766)
		(width 0.1143)
		(layer "In15.Cu")
		(net "P5E_PEX1_STN5_RX_DP<93>")
	)
	(segment
		(start 187.149994 -318.040766)
		(end 187.061094 -318.129666)
		(width 0.1143)
		(layer "In15.Cu")
		(net "P5E_PEX1_STN5_RX_DP<93>")
	)
	(segment
		(start 135.530336 -364.366556)
		(end 135.411464 -364.325408)
		(width 0.1651)
		(layer "In15.Cu")
		(net "P5E_PEX1_STN5_RX_DP<93>")
	)
	(segment
		(start 186.534044 -320.81851)
		(end 186.165998 -321.771772)
		(width 0.1651)
		(layer "In15.Cu")
		(net "P5E_PEX1_STN5_RX_DP<93>")
	)
	(segment
		(start 145.198338 -359.255314)
		(end 143.811244 -360.339386)
		(width 0.1651)
		(layer "In15.Cu")
		(net "P5E_PEX1_STN5_RX_DP<93>")
	)
	(segment
		(start 134.479538 -364.877604)
		(end 134.360666 -364.83671)
		(width 0.1651)
		(layer "In15.Cu")
		(net "P5E_PEX1_STN5_RX_DP<93>")
	)
	(segment
		(start 128.445514 -368.123978)
		(end 127.81788 -369.305586)
		(width 0.1651)
		(layer "In15.Cu")
		(net "P5E_PEX1_STN5_RX_DP<93>")
	)
	(segment
		(start 168.203372 -335.739232)
		(end 162.028632 -340.878922)
		(width 0.1651)
		(layer "In15.Cu")
		(net "P5E_PEX1_STN5_RX_DP<93>")
	)
	(segment
		(start 186.579764 -318.406272)
		(end 186.579764 -319.84188)
		(width 0.1143)
		(layer "In15.Cu")
		(net "P5E_PEX1_STN5_RX_DP<93>")
	)
	(segment
		(start 181.421024 -326.974454)
		(end 168.203372 -335.739232)
		(width 0.1651)
		(layer "In15.Cu")
		(net "P5E_PEX1_STN5_RX_DP<93>")
	)
	(segment
		(start 186.534044 -319.8876)
		(end 186.534044 -319.916048)
		(width 0.1143)
		(layer "In15.Cu")
		(net "P5E_PEX1_STN5_RX_DP<93>")
	)
	(segment
		(start 127.81788 -369.305586)
		(end 127.81788 -371.53977)
		(width 0.1651)
		(layer "In15.Cu")
		(net "P5E_PEX1_STN5_RX_DP<93>")
	)
	(segment
		(start 135.975598 -364.150148)
		(end 135.530336 -364.366556)
		(width 0.1651)
		(layer "In15.Cu")
		(net "P5E_PEX1_STN5_RX_DP<93>")
	)
	(segment
		(start 136.016746 -364.031276)
		(end 135.975598 -364.150148)
		(width 0.1651)
		(layer "In15.Cu")
		(net "P5E_PEX1_STN5_RX_DP<93>")
	)
	(segment
		(start 187.061094 -318.129666)
		(end 186.85637 -318.129666)
		(width 0.1143)
		(layer "In15.Cu")
		(net "P5E_PEX1_STN5_RX_DP<93>")
	)
	(segment
		(start 136.581134 -363.855508)
		(end 136.462262 -363.81436)
		(width 0.1651)
		(layer "In15.Cu")
		(net "P5E_PEX1_STN5_RX_DP<93>")
	)
	(segment
		(start 136.462262 -363.81436)
		(end 136.016746 -364.031276)
		(width 0.1651)
		(layer "In15.Cu")
		(net "P5E_PEX1_STN5_RX_DP<93>")
	)
	(segment
		(start 146.652996 -357.515922)
		(end 145.198338 -359.255314)
		(width 0.1651)
		(layer "In15.Cu")
		(net "P5E_PEX1_STN5_RX_DP<93>")
	)
	(segment
		(start 143.811244 -360.339386)
		(end 136.581134 -363.855508)
		(width 0.1651)
		(layer "In15.Cu")
		(net "P5E_PEX1_STN5_RX_DP<93>")
	)
	(segment
		(start 134.9248 -364.661196)
		(end 134.479538 -364.877604)
		(width 0.1651)
		(layer "In15.Cu")
		(net "P5E_PEX1_STN5_RX_DP<93>")
	)
	(segment
		(start 127.037084 -372.099078)
		(end 126.910084 -371.972078)
		(width 0.1651)
		(layer "In15.Cu")
		(net "P5E_PEX1_STN5_RX_DP<93>")
	)
	(segment
		(start 186.85637 -318.129666)
		(end 186.579764 -318.406272)
		(width 0.1143)
		(layer "In15.Cu")
		(net "P5E_PEX1_STN5_RX_DP<93>")
	)
	(segment
		(start 127.81788 -371.53977)
		(end 127.258572 -372.099078)
		(width 0.1651)
		(layer "In15.Cu")
		(net "P5E_PEX1_STN5_RX_DP<93>")
	)
	(segment
		(start 133.914896 -365.053626)
		(end 133.873748 -365.172244)
		(width 0.1651)
		(layer "In15.Cu")
		(net "P5E_PEX1_STN5_RX_DP<93>")
	)
	(segment
		(start 127.258572 -372.099078)
		(end 127.037084 -372.099078)
		(width 0.1651)
		(layer "In15.Cu")
		(net "P5E_PEX1_STN5_RX_DP<93>")
	)
	(segment
		(start 134.965948 -364.542324)
		(end 134.9248 -364.661196)
		(width 0.1651)
		(layer "In15.Cu")
		(net "P5E_PEX1_STN5_RX_DP<93>")
	)
	(segment
		(start 133.873748 -365.172244)
		(end 130.094228 -367.010442)
		(width 0.1651)
		(layer "In15.Cu")
		(net "P5E_PEX1_STN5_RX_DP<93>")
	)
	(segment
		(start 36.051744 -130.728974)
		(end 35.4203 -130.728974)
		(width 0.13462)
		(layer "F.Cu")
		(net "P5E_PEX0_STN1_TX_DP<28>")
	)
	(segment
		(start 36.371784 -130.408934)
		(end 36.051744 -130.728974)
		(width 0.13462)
		(layer "F.Cu")
		(net "P5E_PEX0_STN1_TX_DP<28>")
	)
	(segment
		(start 35.4203 -130.728974)
		(end 35.12566 -130.434334)
		(width 0.13462)
		(layer "F.Cu")
		(net "P5E_PEX0_STN1_TX_DP<28>")
	)
	(segment
		(start 32.832294 -132.467858)
		(end 32.832548 -132.467858)
		(width 0.1651)
		(layer "In9.Cu")
		(net "P5E_PEX0_STN1_TX_DP<28>")
	)
	(segment
		(start 35.170618 -157.586934)
		(end 34.420302 -142.333472)
		(width 0.1651)
		(layer "In9.Cu")
		(net "P5E_PEX0_STN1_TX_DP<28>")
	)
	(segment
		(start 71.049642 -278.534368)
		(end 70.935342 -278.420068)
		(width 0.1143)
		(layer "In9.Cu")
		(net "P5E_PEX0_STN1_TX_DP<28>")
	)
	(segment
		(start 70.479666 -278.205184)
		(end 70.479666 -271.546066)
		(width 0.1143)
		(layer "In9.Cu")
		(net "P5E_PEX0_STN1_TX_DP<28>")
	)
	(segment
		(start 71.049642 -278.799798)
		(end 71.049642 -278.534368)
		(width 0.1143)
		(layer "In9.Cu")
		(net "P5E_PEX0_STN1_TX_DP<28>")
	)
	(segment
		(start 70.479666 -271.546066)
		(end 70.433946 -271.500346)
		(width 0.1143)
		(layer "In9.Cu")
		(net "P5E_PEX0_STN1_TX_DP<28>")
	)
	(segment
		(start 34.83483 -130.725164)
		(end 35.12566 -130.434334)
		(width 0.1651)
		(layer "In9.Cu")
		(net "P5E_PEX0_STN1_TX_DP<28>")
	)
	(segment
		(start 32.093916 -133.57352)
		(end 32.832294 -132.467858)
		(width 0.1651)
		(layer "In9.Cu")
		(net "P5E_PEX0_STN1_TX_DP<28>")
	)
	(segment
		(start 70.935342 -278.420068)
		(end 70.69455 -278.420068)
		(width 0.1143)
		(layer "In9.Cu")
		(net "P5E_PEX0_STN1_TX_DP<28>")
	)
	(segment
		(start 34.420302 -142.333472)
		(end 31.818072 -136.050782)
		(width 0.1651)
		(layer "In9.Cu")
		(net "P5E_PEX0_STN1_TX_DP<28>")
	)
	(segment
		(start 70.433946 -271.471898)
		(end 70.433946 -263.430258)
		(width 0.1651)
		(layer "In9.Cu")
		(net "P5E_PEX0_STN1_TX_DP<28>")
	)
	(segment
		(start 35.976306 -161.63925)
		(end 35.170618 -157.586934)
		(width 0.1651)
		(layer "In9.Cu")
		(net "P5E_PEX0_STN1_TX_DP<28>")
	)
	(segment
		(start 31.818072 -134.239508)
		(end 32.093916 -133.57352)
		(width 0.1651)
		(layer "In9.Cu")
		(net "P5E_PEX0_STN1_TX_DP<28>")
	)
	(segment
		(start 32.832548 -132.467858)
		(end 33.6423 -131.25577)
		(width 0.1651)
		(layer "In9.Cu")
		(net "P5E_PEX0_STN1_TX_DP<28>")
	)
	(segment
		(start 31.818072 -136.050782)
		(end 31.818072 -134.239508)
		(width 0.1651)
		(layer "In9.Cu")
		(net "P5E_PEX0_STN1_TX_DP<28>")
	)
	(segment
		(start 33.6423 -131.25577)
		(end 33.642554 -131.25577)
		(width 0.1651)
		(layer "In9.Cu")
		(net "P5E_PEX0_STN1_TX_DP<28>")
	)
	(segment
		(start 34.189924 -130.725164)
		(end 34.83483 -130.725164)
		(width 0.1651)
		(layer "In9.Cu")
		(net "P5E_PEX0_STN1_TX_DP<28>")
	)
	(segment
		(start 70.69455 -278.420068)
		(end 70.479666 -278.205184)
		(width 0.1143)
		(layer "In9.Cu")
		(net "P5E_PEX0_STN1_TX_DP<28>")
	)
	(segment
		(start 33.889696 -130.885692)
		(end 34.189924 -130.725164)
		(width 0.1651)
		(layer "In9.Cu")
		(net "P5E_PEX0_STN1_TX_DP<28>")
	)
	(segment
		(start 33.642554 -131.25577)
		(end 33.889696 -130.885692)
		(width 0.1651)
		(layer "In9.Cu")
		(net "P5E_PEX0_STN1_TX_DP<28>")
	)
	(segment
		(start 70.433946 -271.500346)
		(end 70.433946 -271.471898)
		(width 0.1143)
		(layer "In9.Cu")
		(net "P5E_PEX0_STN1_TX_DP<28>")
	)
	(segment
		(start 70.433946 -263.430258)
		(end 35.976306 -161.63925)
		(width 0.1651)
		(layer "In9.Cu")
		(net "P5E_PEX0_STN1_TX_DP<28>")
	)
	(segment
		(start 28.953968 -355.658166)
		(end 28.953968 -355.026722)
		(width 0.13462)
		(layer "F.Cu")
		(net "P5E_PEX0_STN7_TX_DP<117>")
	)
	(segment
		(start 28.633928 -355.978206)
		(end 28.953968 -355.658166)
		(width 0.13462)
		(layer "F.Cu")
		(net "P5E_PEX0_STN7_TX_DP<117>")
	)
	(segment
		(start 28.953968 -355.026722)
		(end 28.659328 -354.732082)
		(width 0.13462)
		(layer "F.Cu")
		(net "P5E_PEX0_STN7_TX_DP<117>")
	)
	(segment
		(start 44.184316 -306.349908)
		(end 44.449746 -306.349908)
		(width 0.1143)
		(layer "In7.Cu")
		(net "P5E_PEX0_STN7_TX_DP<117>")
	)
	(segment
		(start 28.950158 -353.825302)
		(end 30.504638 -352.270822)
		(width 0.1651)
		(layer "In7.Cu")
		(net "P5E_PEX0_STN7_TX_DP<117>")
	)
	(segment
		(start 29.613352 -338.594192)
		(end 23.383748 -326.940672)
		(width 0.1651)
		(layer "In7.Cu")
		(net "P5E_PEX0_STN7_TX_DP<117>")
	)
	(segment
		(start 43.84421 -305.779678)
		(end 44.070016 -306.005484)
		(width 0.1143)
		(layer "In7.Cu")
		(net "P5E_PEX0_STN7_TX_DP<117>")
	)
	(segment
		(start 28.950158 -354.441252)
		(end 28.950158 -353.825302)
		(width 0.1651)
		(layer "In7.Cu")
		(net "P5E_PEX0_STN7_TX_DP<117>")
	)
	(segment
		(start 22.98573 -315.988446)
		(end 26.373836 -311.85993)
		(width 0.1651)
		(layer "In7.Cu")
		(net "P5E_PEX0_STN7_TX_DP<117>")
	)
	(segment
		(start 31.521146 -306.712874)
		(end 33.884362 -305.733958)
		(width 0.1651)
		(layer "In7.Cu")
		(net "P5E_PEX0_STN7_TX_DP<117>")
	)
	(segment
		(start 23.383748 -326.940672)
		(end 21.670264 -322.803774)
		(width 0.1651)
		(layer "In7.Cu")
		(net "P5E_PEX0_STN7_TX_DP<117>")
	)
	(segment
		(start 35.6108 -305.733958)
		(end 35.65652 -305.779678)
		(width 0.1143)
		(layer "In7.Cu")
		(net "P5E_PEX0_STN7_TX_DP<117>")
	)
	(segment
		(start 30.504638 -342.151462)
		(end 29.613352 -338.594192)
		(width 0.1651)
		(layer "In7.Cu")
		(net "P5E_PEX0_STN7_TX_DP<117>")
	)
	(segment
		(start 21.670264 -320.109088)
		(end 22.031706 -318.29121)
		(width 0.1651)
		(layer "In7.Cu")
		(net "P5E_PEX0_STN7_TX_DP<117>")
	)
	(segment
		(start 35.582352 -305.733958)
		(end 35.6108 -305.733958)
		(width 0.1143)
		(layer "In7.Cu")
		(net "P5E_PEX0_STN7_TX_DP<117>")
	)
	(segment
		(start 22.506178 -317.145924)
		(end 22.506178 -317.146178)
		(width 0.1651)
		(layer "In7.Cu")
		(net "P5E_PEX0_STN7_TX_DP<117>")
	)
	(segment
		(start 30.504638 -352.270822)
		(end 30.504638 -342.151462)
		(width 0.1651)
		(layer "In7.Cu")
		(net "P5E_PEX0_STN7_TX_DP<117>")
	)
	(segment
		(start 44.070016 -306.235608)
		(end 44.184316 -306.349908)
		(width 0.1143)
		(layer "In7.Cu")
		(net "P5E_PEX0_STN7_TX_DP<117>")
	)
	(segment
		(start 21.670264 -322.803774)
		(end 21.670264 -320.109088)
		(width 0.1651)
		(layer "In7.Cu")
		(net "P5E_PEX0_STN7_TX_DP<117>")
	)
	(segment
		(start 33.884362 -305.733958)
		(end 35.582352 -305.733958)
		(width 0.1651)
		(layer "In7.Cu")
		(net "P5E_PEX0_STN7_TX_DP<117>")
	)
	(segment
		(start 28.659328 -354.732082)
		(end 28.950158 -354.441252)
		(width 0.1651)
		(layer "In7.Cu")
		(net "P5E_PEX0_STN7_TX_DP<117>")
	)
	(segment
		(start 26.373836 -311.85993)
		(end 31.521146 -306.712874)
		(width 0.1651)
		(layer "In7.Cu")
		(net "P5E_PEX0_STN7_TX_DP<117>")
	)
	(segment
		(start 44.070016 -306.005484)
		(end 44.070016 -306.235608)
		(width 0.1143)
		(layer "In7.Cu")
		(net "P5E_PEX0_STN7_TX_DP<117>")
	)
	(segment
		(start 22.031706 -318.29121)
		(end 22.506178 -317.145924)
		(width 0.1651)
		(layer "In7.Cu")
		(net "P5E_PEX0_STN7_TX_DP<117>")
	)
	(segment
		(start 35.65652 -305.779678)
		(end 43.84421 -305.779678)
		(width 0.1143)
		(layer "In7.Cu")
		(net "P5E_PEX0_STN7_TX_DP<117>")
	)
	(segment
		(start 22.506178 -317.146178)
		(end 22.98573 -315.988446)
		(width 0.1651)
		(layer "In7.Cu")
		(net "P5E_PEX0_STN7_TX_DP<117>")
	)
	(segment
		(start 196.385942 -146.190208)
		(end 196.705982 -146.510248)
		(width 0.13462)
		(layer "F.Cu")
		(net "P5E_PEX1_STN0_TX_DN<10>")
	)
	(segment
		(start 196.705982 -146.510248)
		(end 197.337426 -146.510248)
		(width 0.13462)
		(layer "F.Cu")
		(net "P5E_PEX1_STN0_TX_DN<10>")
	)
	(segment
		(start 197.337426 -146.510248)
		(end 197.632066 -146.215608)
		(width 0.13462)
		(layer "F.Cu")
		(net "P5E_PEX1_STN0_TX_DN<10>")
	)
	(segment
		(start 198.174864 -172.601128)
		(end 196.853556 -177.529236)
		(width 0.1651)
		(layer "In9.Cu")
		(net "P5E_PEX1_STN0_TX_DN<10>")
	)
	(segment
		(start 205.127098 -151.238204)
		(end 206.594202 -154.780488)
		(width 0.1651)
		(layer "In9.Cu")
		(net "P5E_PEX1_STN0_TX_DN<10>")
	)
	(segment
		(start 202.041506 -147.31111)
		(end 203.447904 -148.717508)
		(width 0.1651)
		(layer "In9.Cu")
		(net "P5E_PEX1_STN0_TX_DN<10>")
	)
	(segment
		(start 195.585588 -280.129488)
		(end 195.699888 -280.015188)
		(width 0.1143)
		(layer "In9.Cu")
		(net "P5E_PEX1_STN0_TX_DN<10>")
	)
	(segment
		(start 206.594202 -158.01594)
		(end 198.174864 -172.601128)
		(width 0.1651)
		(layer "In9.Cu")
		(net "P5E_PEX1_STN0_TX_DN<10>")
	)
	(segment
		(start 195.320158 -271.600168)
		(end 195.320158 -280.025856)
		(width 0.1143)
		(layer "In9.Cu")
		(net "P5E_PEX1_STN0_TX_DN<10>")
	)
	(segment
		(start 195.699888 -280.015188)
		(end 195.699888 -279.749758)
		(width 0.1143)
		(layer "In9.Cu")
		(net "P5E_PEX1_STN0_TX_DN<10>")
	)
	(segment
		(start 196.329046 -260.752844)
		(end 196.329046 -268.829536)
		(width 0.1651)
		(layer "In9.Cu")
		(net "P5E_PEX1_STN0_TX_DN<10>")
	)
	(segment
		(start 197.632066 -146.215608)
		(end 197.922896 -146.506438)
		(width 0.1651)
		(layer "In9.Cu")
		(net "P5E_PEX1_STN0_TX_DN<10>")
	)
	(segment
		(start 197.922896 -146.506438)
		(end 200.128886 -146.506438)
		(width 0.1651)
		(layer "In9.Cu")
		(net "P5E_PEX1_STN0_TX_DN<10>")
	)
	(segment
		(start 203.447904 -148.717508)
		(end 203.447904 -148.725128)
		(width 0.1651)
		(layer "In9.Cu")
		(net "P5E_PEX1_STN0_TX_DN<10>")
	)
	(segment
		(start 196.329046 -268.829536)
		(end 195.365878 -271.155414)
		(width 0.1651)
		(layer "In9.Cu")
		(net "P5E_PEX1_STN0_TX_DN<10>")
	)
	(segment
		(start 203.447904 -148.725128)
		(end 205.127098 -151.238204)
		(width 0.1651)
		(layer "In9.Cu")
		(net "P5E_PEX1_STN0_TX_DN<10>")
	)
	(segment
		(start 195.365878 -271.554448)
		(end 195.320158 -271.600168)
		(width 0.1143)
		(layer "In9.Cu")
		(net "P5E_PEX1_STN0_TX_DN<10>")
	)
	(segment
		(start 206.594202 -154.780488)
		(end 206.594202 -158.01594)
		(width 0.1651)
		(layer "In9.Cu")
		(net "P5E_PEX1_STN0_TX_DN<10>")
	)
	(segment
		(start 195.365878 -271.526)
		(end 195.365878 -271.554448)
		(width 0.1143)
		(layer "In9.Cu")
		(net "P5E_PEX1_STN0_TX_DN<10>")
	)
	(segment
		(start 195.42379 -280.129488)
		(end 195.585588 -280.129488)
		(width 0.1143)
		(layer "In9.Cu")
		(net "P5E_PEX1_STN0_TX_DN<10>")
	)
	(segment
		(start 200.128886 -146.506438)
		(end 200.150222 -146.527774)
		(width 0.1651)
		(layer "In9.Cu")
		(net "P5E_PEX1_STN0_TX_DN<10>")
	)
	(segment
		(start 195.365878 -271.155414)
		(end 195.365878 -271.526)
		(width 0.1651)
		(layer "In9.Cu")
		(net "P5E_PEX1_STN0_TX_DN<10>")
	)
	(segment
		(start 196.853556 -177.529236)
		(end 192.950084 -222.099124)
		(width 0.1651)
		(layer "In9.Cu")
		(net "P5E_PEX1_STN0_TX_DN<10>")
	)
	(segment
		(start 195.320158 -280.025856)
		(end 195.42379 -280.129488)
		(width 0.1143)
		(layer "In9.Cu")
		(net "P5E_PEX1_STN0_TX_DN<10>")
	)
	(segment
		(start 192.950084 -222.099124)
		(end 196.329046 -260.752844)
		(width 0.1651)
		(layer "In9.Cu")
		(net "P5E_PEX1_STN0_TX_DN<10>")
	)
	(segment
		(start 200.150222 -146.527774)
		(end 202.041506 -147.31111)
		(width 0.1651)
		(layer "In9.Cu")
		(net "P5E_PEX1_STN0_TX_DN<10>")
	)
	(segment
		(start 146.865086 -357.702358)
		(end 145.395696 -359.459276)
		(width 0.1651)
		(layer "In15.Cu")
		(net "P5E_PEX1_STN5_RX_DN<93>")
	)
	(segment
		(start 186.419744 -321.897502)
		(end 185.655966 -323.138292)
		(width 0.1651)
		(layer "In15.Cu")
		(net "P5E_PEX1_STN5_RX_DN<93>")
	)
	(segment
		(start 143.961358 -360.579924)
		(end 130.235452 -367.255298)
		(width 0.1651)
		(layer "In15.Cu")
		(net "P5E_PEX1_STN5_RX_DN<93>")
	)
	(segment
		(start 186.815984 -320.871088)
		(end 186.419744 -321.897502)
		(width 0.1651)
		(layer "In15.Cu")
		(net "P5E_PEX1_STN5_RX_DN<93>")
	)
	(segment
		(start 186.770264 -319.84188)
		(end 186.815984 -319.8876)
		(width 0.1143)
		(layer "In15.Cu")
		(net "P5E_PEX1_STN5_RX_DN<93>")
	)
	(segment
		(start 186.815984 -319.916048)
		(end 186.815984 -320.871088)
		(width 0.1651)
		(layer "In15.Cu")
		(net "P5E_PEX1_STN5_RX_DN<93>")
	)
	(segment
		(start 126.910084 -372.508018)
		(end 126.910084 -372.890034)
		(width 0.1651)
		(layer "In15.Cu")
		(net "P5E_PEX1_STN5_RX_DN<93>")
	)
	(segment
		(start 127.037084 -372.381018)
		(end 126.910084 -372.508018)
		(width 0.1651)
		(layer "In15.Cu")
		(net "P5E_PEX1_STN5_RX_DN<93>")
	)
	(segment
		(start 181.600348 -327.19391)
		(end 168.372028 -335.9658)
		(width 0.1651)
		(layer "In15.Cu")
		(net "P5E_PEX1_STN5_RX_DN<93>")
	)
	(segment
		(start 187.149994 -318.699896)
		(end 187.149994 -318.409066)
		(width 0.1143)
		(layer "In15.Cu")
		(net "P5E_PEX1_STN5_RX_DN<93>")
	)
	(segment
		(start 185.655966 -323.138292)
		(end 181.600348 -327.19391)
		(width 0.1651)
		(layer "In15.Cu")
		(net "P5E_PEX1_STN5_RX_DN<93>")
	)
	(segment
		(start 162.223196 -341.0839)
		(end 146.865086 -357.702358)
		(width 0.1651)
		(layer "In15.Cu")
		(net "P5E_PEX1_STN5_RX_DN<93>")
	)
	(segment
		(start 186.770264 -318.485266)
		(end 186.770264 -319.84188)
		(width 0.1143)
		(layer "In15.Cu")
		(net "P5E_PEX1_STN5_RX_DN<93>")
	)
	(segment
		(start 168.372028 -335.9658)
		(end 162.223196 -341.0839)
		(width 0.1651)
		(layer "In15.Cu")
		(net "P5E_PEX1_STN5_RX_DN<93>")
	)
	(segment
		(start 187.149994 -318.409066)
		(end 187.061094 -318.320166)
		(width 0.1143)
		(layer "In15.Cu")
		(net "P5E_PEX1_STN5_RX_DN<93>")
	)
	(segment
		(start 145.395696 -359.459276)
		(end 143.961358 -360.579924)
		(width 0.1651)
		(layer "In15.Cu")
		(net "P5E_PEX1_STN5_RX_DN<93>")
	)
	(segment
		(start 187.061094 -318.320166)
		(end 186.935364 -318.320166)
		(width 0.1143)
		(layer "In15.Cu")
		(net "P5E_PEX1_STN5_RX_DN<93>")
	)
	(segment
		(start 186.935364 -318.320166)
		(end 186.770264 -318.485266)
		(width 0.1143)
		(layer "In15.Cu")
		(net "P5E_PEX1_STN5_RX_DN<93>")
	)
	(segment
		(start 130.235452 -367.255298)
		(end 128.661668 -368.318288)
		(width 0.1651)
		(layer "In15.Cu")
		(net "P5E_PEX1_STN5_RX_DN<93>")
	)
	(segment
		(start 186.815984 -319.8876)
		(end 186.815984 -319.916048)
		(width 0.1143)
		(layer "In15.Cu")
		(net "P5E_PEX1_STN5_RX_DN<93>")
	)
	(segment
		(start 128.09982 -369.375944)
		(end 128.09982 -371.65661)
		(width 0.1651)
		(layer "In15.Cu")
		(net "P5E_PEX1_STN5_RX_DN<93>")
	)
	(segment
		(start 127.375412 -372.381018)
		(end 127.037084 -372.381018)
		(width 0.1651)
		(layer "In15.Cu")
		(net "P5E_PEX1_STN5_RX_DN<93>")
	)
	(segment
		(start 128.661668 -368.318288)
		(end 128.09982 -369.375944)
		(width 0.1651)
		(layer "In15.Cu")
		(net "P5E_PEX1_STN5_RX_DN<93>")
	)
	(segment
		(start 128.09982 -371.65661)
		(end 127.375412 -372.381018)
		(width 0.1651)
		(layer "In15.Cu")
		(net "P5E_PEX1_STN5_RX_DN<93>")
	)
	(segment
		(start 35.4203 -112.489742)
		(end 35.12566 -112.784382)
		(width 0.13462)
		(layer "F.Cu")
		(net "P5E_PEX0_STN1_TX_DP<23>")
	)
	(segment
		(start 36.051744 -112.489742)
		(end 35.4203 -112.489742)
		(width 0.13462)
		(layer "F.Cu")
		(net "P5E_PEX0_STN1_TX_DP<23>")
	)
	(segment
		(start 36.371784 -112.809782)
		(end 36.051744 -112.489742)
		(width 0.13462)
		(layer "F.Cu")
		(net "P5E_PEX0_STN1_TX_DP<23>")
	)
	(segment
		(start 30.46984 -121.727722)
		(end 30.320234 -121.789444)
		(width 0.1651)
		(layer "In9.Cu")
		(net "P5E_PEX0_STN1_TX_DP<23>")
	)
	(segment
		(start 65.965832 -264.448036)
		(end 65.965832 -271.526)
		(width 0.1651)
		(layer "In9.Cu")
		(net "P5E_PEX0_STN1_TX_DP<23>")
	)
	(segment
		(start 27.261312 -131.652518)
		(end 27.261312 -137.570718)
		(width 0.1651)
		(layer "In9.Cu")
		(net "P5E_PEX0_STN1_TX_DP<23>")
	)
	(segment
		(start 27.261312 -137.570718)
		(end 29.8196 -143.746474)
		(width 0.1651)
		(layer "In9.Cu")
		(net "P5E_PEX0_STN1_TX_DP<23>")
	)
	(segment
		(start 32.186626 -117.283484)
		(end 31.997142 -117.740938)
		(width 0.1651)
		(layer "In9.Cu")
		(net "P5E_PEX0_STN1_TX_DP<23>")
	)
	(segment
		(start 31.869634 -118.348252)
		(end 31.720028 -118.409974)
		(width 0.1651)
		(layer "In9.Cu")
		(net "P5E_PEX0_STN1_TX_DP<23>")
	)
	(segment
		(start 32.992314 -115.63731)
		(end 32.80283 -116.095272)
		(width 0.1651)
		(layer "In9.Cu")
		(net "P5E_PEX0_STN1_TX_DP<23>")
	)
	(segment
		(start 31.997142 -117.740938)
		(end 32.059118 -117.89029)
		(width 0.1651)
		(layer "In9.Cu")
		(net "P5E_PEX0_STN1_TX_DP<23>")
	)
	(segment
		(start 33.269428 -114.968782)
		(end 33.119822 -115.030504)
		(width 0.1651)
		(layer "In9.Cu")
		(net "P5E_PEX0_STN1_TX_DP<23>")
	)
	(segment
		(start 65.920112 -280.025856)
		(end 66.023744 -280.129488)
		(width 0.1143)
		(layer "In9.Cu")
		(net "P5E_PEX0_STN1_TX_DP<23>")
	)
	(segment
		(start 31.403036 -119.474742)
		(end 31.25343 -119.536464)
		(width 0.1651)
		(layer "In9.Cu")
		(net "P5E_PEX0_STN1_TX_DP<23>")
	)
	(segment
		(start 30.786832 -120.662954)
		(end 30.597348 -121.120408)
		(width 0.1651)
		(layer "In9.Cu")
		(net "P5E_PEX0_STN1_TX_DP<23>")
	)
	(segment
		(start 34.83483 -112.493552)
		(end 34.252154 -112.493552)
		(width 0.1651)
		(layer "In9.Cu")
		(net "P5E_PEX0_STN1_TX_DP<23>")
	)
	(segment
		(start 33.119822 -115.030504)
		(end 32.930338 -115.487958)
		(width 0.1651)
		(layer "In9.Cu")
		(net "P5E_PEX0_STN1_TX_DP<23>")
	)
	(segment
		(start 66.023744 -280.129488)
		(end 66.185542 -280.129488)
		(width 0.1143)
		(layer "In9.Cu")
		(net "P5E_PEX0_STN1_TX_DP<23>")
	)
	(segment
		(start 31.59252 -119.01678)
		(end 31.403036 -119.474742)
		(width 0.1651)
		(layer "In9.Cu")
		(net "P5E_PEX0_STN1_TX_DP<23>")
	)
	(segment
		(start 65.920112 -271.600168)
		(end 65.920112 -280.025856)
		(width 0.1143)
		(layer "In9.Cu")
		(net "P5E_PEX0_STN1_TX_DP<23>")
	)
	(segment
		(start 32.80283 -116.095272)
		(end 32.653224 -116.156994)
		(width 0.1651)
		(layer "In9.Cu")
		(net "P5E_PEX0_STN1_TX_DP<23>")
	)
	(segment
		(start 31.125922 -120.14327)
		(end 30.936438 -120.601232)
		(width 0.1651)
		(layer "In9.Cu")
		(net "P5E_PEX0_STN1_TX_DP<23>")
	)
	(segment
		(start 30.070552 -122.392186)
		(end 27.261312 -131.652518)
		(width 0.1651)
		(layer "In9.Cu")
		(net "P5E_PEX0_STN1_TX_DP<23>")
	)
	(segment
		(start 31.720028 -118.409974)
		(end 31.530544 -118.867428)
		(width 0.1651)
		(layer "In9.Cu")
		(net "P5E_PEX0_STN1_TX_DP<23>")
	)
	(segment
		(start 31.063946 -119.993918)
		(end 31.125922 -120.14327)
		(width 0.1651)
		(layer "In9.Cu")
		(net "P5E_PEX0_STN1_TX_DP<23>")
	)
	(segment
		(start 33.736026 -113.842292)
		(end 33.58642 -113.904014)
		(width 0.1651)
		(layer "In9.Cu")
		(net "P5E_PEX0_STN1_TX_DP<23>")
	)
	(segment
		(start 32.525716 -116.7638)
		(end 32.336232 -117.221762)
		(width 0.1651)
		(layer "In9.Cu")
		(net "P5E_PEX0_STN1_TX_DP<23>")
	)
	(segment
		(start 30.936438 -120.601232)
		(end 30.786832 -120.662954)
		(width 0.1651)
		(layer "In9.Cu")
		(net "P5E_PEX0_STN1_TX_DP<23>")
	)
	(segment
		(start 31.25343 -119.536464)
		(end 31.063946 -119.993918)
		(width 0.1651)
		(layer "In9.Cu")
		(net "P5E_PEX0_STN1_TX_DP<23>")
	)
	(segment
		(start 32.336232 -117.221762)
		(end 32.186626 -117.283484)
		(width 0.1651)
		(layer "In9.Cu")
		(net "P5E_PEX0_STN1_TX_DP<23>")
	)
	(segment
		(start 30.550612 -158.62681)
		(end 31.127192 -161.525712)
		(width 0.1651)
		(layer "In9.Cu")
		(net "P5E_PEX0_STN1_TX_DP<23>")
	)
	(segment
		(start 31.127192 -161.525712)
		(end 65.965832 -264.448036)
		(width 0.1651)
		(layer "In9.Cu")
		(net "P5E_PEX0_STN1_TX_DP<23>")
	)
	(segment
		(start 29.8196 -143.746474)
		(end 30.550612 -158.62681)
		(width 0.1651)
		(layer "In9.Cu")
		(net "P5E_PEX0_STN1_TX_DP<23>")
	)
	(segment
		(start 32.653224 -116.156994)
		(end 32.46374 -116.614448)
		(width 0.1651)
		(layer "In9.Cu")
		(net "P5E_PEX0_STN1_TX_DP<23>")
	)
	(segment
		(start 34.252154 -112.493552)
		(end 34.112962 -112.632744)
		(width 0.1651)
		(layer "In9.Cu")
		(net "P5E_PEX0_STN1_TX_DP<23>")
	)
	(segment
		(start 66.185542 -280.129488)
		(end 66.299842 -280.015188)
		(width 0.1143)
		(layer "In9.Cu")
		(net "P5E_PEX0_STN1_TX_DP<23>")
	)
	(segment
		(start 33.458912 -114.51082)
		(end 33.269428 -114.968782)
		(width 0.1651)
		(layer "In9.Cu")
		(net "P5E_PEX0_STN1_TX_DP<23>")
	)
	(segment
		(start 30.597348 -121.120408)
		(end 30.659324 -121.26976)
		(width 0.1651)
		(layer "In9.Cu")
		(net "P5E_PEX0_STN1_TX_DP<23>")
	)
	(segment
		(start 30.659324 -121.26976)
		(end 30.46984 -121.727722)
		(width 0.1651)
		(layer "In9.Cu")
		(net "P5E_PEX0_STN1_TX_DP<23>")
	)
	(segment
		(start 66.299842 -280.015188)
		(end 66.299842 -279.749504)
		(width 0.1143)
		(layer "In9.Cu")
		(net "P5E_PEX0_STN1_TX_DP<23>")
	)
	(segment
		(start 33.396936 -114.361468)
		(end 33.458912 -114.51082)
		(width 0.1651)
		(layer "In9.Cu")
		(net "P5E_PEX0_STN1_TX_DP<23>")
	)
	(segment
		(start 33.58642 -113.904014)
		(end 33.396936 -114.361468)
		(width 0.1651)
		(layer "In9.Cu")
		(net "P5E_PEX0_STN1_TX_DP<23>")
	)
	(segment
		(start 32.059118 -117.89029)
		(end 31.869634 -118.348252)
		(width 0.1651)
		(layer "In9.Cu")
		(net "P5E_PEX0_STN1_TX_DP<23>")
	)
	(segment
		(start 34.112962 -112.632744)
		(end 33.863534 -113.234978)
		(width 0.1651)
		(layer "In9.Cu")
		(net "P5E_PEX0_STN1_TX_DP<23>")
	)
	(segment
		(start 35.12566 -112.784382)
		(end 34.83483 -112.493552)
		(width 0.1651)
		(layer "In9.Cu")
		(net "P5E_PEX0_STN1_TX_DP<23>")
	)
	(segment
		(start 31.530544 -118.867428)
		(end 31.59252 -119.01678)
		(width 0.1651)
		(layer "In9.Cu")
		(net "P5E_PEX0_STN1_TX_DP<23>")
	)
	(segment
		(start 65.965832 -271.526)
		(end 65.965832 -271.554448)
		(width 0.1143)
		(layer "In9.Cu")
		(net "P5E_PEX0_STN1_TX_DP<23>")
	)
	(segment
		(start 65.965832 -271.554448)
		(end 65.920112 -271.600168)
		(width 0.1143)
		(layer "In9.Cu")
		(net "P5E_PEX0_STN1_TX_DP<23>")
	)
	(segment
		(start 33.92551 -113.38433)
		(end 33.736026 -113.842292)
		(width 0.1651)
		(layer "In9.Cu")
		(net "P5E_PEX0_STN1_TX_DP<23>")
	)
	(segment
		(start 32.930338 -115.487958)
		(end 32.992314 -115.63731)
		(width 0.1651)
		(layer "In9.Cu")
		(net "P5E_PEX0_STN1_TX_DP<23>")
	)
	(segment
		(start 32.46374 -116.614448)
		(end 32.525716 -116.7638)
		(width 0.1651)
		(layer "In9.Cu")
		(net "P5E_PEX0_STN1_TX_DP<23>")
	)
	(segment
		(start 33.863534 -113.234978)
		(end 33.92551 -113.38433)
		(width 0.1651)
		(layer "In9.Cu")
		(net "P5E_PEX0_STN1_TX_DP<23>")
	)
	(segment
		(start 30.320234 -121.789444)
		(end 30.070552 -122.392186)
		(width 0.1651)
		(layer "In9.Cu")
		(net "P5E_PEX0_STN1_TX_DP<23>")
	)
	(segment
		(start 152.761188 -101.689662)
		(end 152.129744 -101.689662)
		(width 0.13462)
		(layer "F.Cu")
		(net "P5E_PEX1_STN1_TX_DP<17>")
	)
	(segment
		(start 153.081228 -102.009702)
		(end 152.761188 -101.689662)
		(width 0.13462)
		(layer "F.Cu")
		(net "P5E_PEX1_STN1_TX_DP<17>")
	)
	(segment
		(start 152.129744 -101.689662)
		(end 151.835104 -101.984302)
		(width 0.13462)
		(layer "F.Cu")
		(net "P5E_PEX1_STN1_TX_DP<17>")
	)
	(segment
		(start 150.485094 -101.946964)
		(end 151.09698 -101.693472)
		(width 0.1651)
		(layer "In9.Cu")
		(net "P5E_PEX1_STN1_TX_DP<17>")
	)
	(segment
		(start 144.49806 -109.281468)
		(end 144.687544 -108.824014)
		(width 0.1651)
		(layer "In9.Cu")
		(net "P5E_PEX1_STN1_TX_DP<17>")
	)
	(segment
		(start 176.365916 -265.72464)
		(end 141.420596 -162.482276)
		(width 0.1651)
		(layer "In9.Cu")
		(net "P5E_PEX1_STN1_TX_DP<17>")
	)
	(segment
		(start 144.964658 -108.154978)
		(end 145.450814 -106.981244)
		(width 0.1651)
		(layer "In9.Cu")
		(net "P5E_PEX1_STN1_TX_DP<17>")
	)
	(segment
		(start 141.420596 -162.482276)
		(end 140.855954 -159.643064)
		(width 0.1651)
		(layer "In9.Cu")
		(net "P5E_PEX1_STN1_TX_DP<17>")
	)
	(segment
		(start 143.28775 -112.203484)
		(end 143.409416 -112.153192)
		(width 0.1651)
		(layer "In9.Cu")
		(net "P5E_PEX1_STN1_TX_DP<17>")
	)
	(segment
		(start 140.855954 -159.643064)
		(end 140.13942 -145.063718)
		(width 0.1651)
		(layer "In9.Cu")
		(net "P5E_PEX1_STN1_TX_DP<17>")
	)
	(segment
		(start 151.544274 -101.693472)
		(end 151.835104 -101.984302)
		(width 0.1651)
		(layer "In9.Cu")
		(net "P5E_PEX1_STN1_TX_DP<17>")
	)
	(segment
		(start 176.699926 -280.015188)
		(end 176.585626 -280.129488)
		(width 0.1143)
		(layer "In9.Cu")
		(net "P5E_PEX1_STN1_TX_DP<17>")
	)
	(segment
		(start 147.498308 -104.93375)
		(end 147.84832 -104.583738)
		(width 0.1651)
		(layer "In9.Cu")
		(net "P5E_PEX1_STN1_TX_DP<17>")
	)
	(segment
		(start 137.55497 -138.823954)
		(end 137.55497 -130.86207)
		(width 0.1651)
		(layer "In9.Cu")
		(net "P5E_PEX1_STN1_TX_DP<17>")
	)
	(segment
		(start 144.83715 -108.762292)
		(end 145.026634 -108.30433)
		(width 0.1651)
		(layer "In9.Cu")
		(net "P5E_PEX1_STN1_TX_DP<17>")
	)
	(segment
		(start 148.836126 -103.721408)
		(end 149.177756 -103.380032)
		(width 0.1651)
		(layer "In9.Cu")
		(net "P5E_PEX1_STN1_TX_DP<17>")
	)
	(segment
		(start 146.635978 -105.957878)
		(end 146.635978 -105.79608)
		(width 0.1651)
		(layer "In9.Cu")
		(net "P5E_PEX1_STN1_TX_DP<17>")
	)
	(segment
		(start 149.177756 -103.380032)
		(end 149.177756 -103.254302)
		(width 0.1651)
		(layer "In9.Cu")
		(net "P5E_PEX1_STN1_TX_DP<17>")
	)
	(segment
		(start 176.699926 -279.749504)
		(end 176.699926 -280.015188)
		(width 0.1143)
		(layer "In9.Cu")
		(net "P5E_PEX1_STN1_TX_DP<17>")
	)
	(segment
		(start 147.147788 -105.446068)
		(end 147.498308 -105.095548)
		(width 0.1651)
		(layer "In9.Cu")
		(net "P5E_PEX1_STN1_TX_DP<17>")
	)
	(segment
		(start 148.360638 -104.07142)
		(end 148.71065 -103.721408)
		(width 0.1651)
		(layer "In9.Cu")
		(net "P5E_PEX1_STN1_TX_DP<17>")
	)
	(segment
		(start 151.09698 -101.693472)
		(end 151.544274 -101.693472)
		(width 0.1651)
		(layer "In9.Cu")
		(net "P5E_PEX1_STN1_TX_DP<17>")
	)
	(segment
		(start 147.498308 -105.095548)
		(end 147.498308 -104.93375)
		(width 0.1651)
		(layer "In9.Cu")
		(net "P5E_PEX1_STN1_TX_DP<17>")
	)
	(segment
		(start 145.026634 -108.30433)
		(end 144.964658 -108.154978)
		(width 0.1651)
		(layer "In9.Cu")
		(net "P5E_PEX1_STN1_TX_DP<17>")
	)
	(segment
		(start 143.409416 -112.153192)
		(end 143.615156 -111.65586)
		(width 0.1651)
		(layer "In9.Cu")
		(net "P5E_PEX1_STN1_TX_DP<17>")
	)
	(segment
		(start 145.450814 -106.981244)
		(end 146.12366 -106.308398)
		(width 0.1651)
		(layer "In9.Cu")
		(net "P5E_PEX1_STN1_TX_DP<17>")
	)
	(segment
		(start 176.585626 -280.129488)
		(end 176.423828 -280.129488)
		(width 0.1143)
		(layer "In9.Cu")
		(net "P5E_PEX1_STN1_TX_DP<17>")
	)
	(segment
		(start 146.635978 -105.79608)
		(end 146.98599 -105.446068)
		(width 0.1651)
		(layer "In9.Cu")
		(net "P5E_PEX1_STN1_TX_DP<17>")
	)
	(segment
		(start 176.320196 -271.600168)
		(end 176.365916 -271.554448)
		(width 0.1143)
		(layer "In9.Cu")
		(net "P5E_PEX1_STN1_TX_DP<17>")
	)
	(segment
		(start 149.986238 -102.57155)
		(end 149.986238 -102.44582)
		(width 0.1651)
		(layer "In9.Cu")
		(net "P5E_PEX1_STN1_TX_DP<17>")
	)
	(segment
		(start 143.016732 -112.857788)
		(end 143.28775 -112.203484)
		(width 0.1651)
		(layer "In9.Cu")
		(net "P5E_PEX1_STN1_TX_DP<17>")
	)
	(segment
		(start 137.55497 -130.86207)
		(end 143.016732 -112.857788)
		(width 0.1651)
		(layer "In9.Cu")
		(net "P5E_PEX1_STN1_TX_DP<17>")
	)
	(segment
		(start 176.365916 -271.526)
		(end 176.365916 -265.72464)
		(width 0.1651)
		(layer "In9.Cu")
		(net "P5E_PEX1_STN1_TX_DP<17>")
	)
	(segment
		(start 146.12366 -106.308398)
		(end 146.285458 -106.308398)
		(width 0.1651)
		(layer "In9.Cu")
		(net "P5E_PEX1_STN1_TX_DP<17>")
	)
	(segment
		(start 140.13942 -145.063718)
		(end 137.55497 -138.823954)
		(width 0.1651)
		(layer "In9.Cu")
		(net "P5E_PEX1_STN1_TX_DP<17>")
	)
	(segment
		(start 143.615156 -111.65586)
		(end 143.564864 -111.534448)
		(width 0.1651)
		(layer "In9.Cu")
		(net "P5E_PEX1_STN1_TX_DP<17>")
	)
	(segment
		(start 149.177756 -103.254302)
		(end 149.518878 -102.91318)
		(width 0.1651)
		(layer "In9.Cu")
		(net "P5E_PEX1_STN1_TX_DP<17>")
	)
	(segment
		(start 143.88211 -111.024162)
		(end 144.084294 -110.535466)
		(width 0.1651)
		(layer "In9.Cu")
		(net "P5E_PEX1_STN1_TX_DP<17>")
	)
	(segment
		(start 144.220946 -109.950504)
		(end 144.370552 -109.888782)
		(width 0.1651)
		(layer "In9.Cu")
		(net "P5E_PEX1_STN1_TX_DP<17>")
	)
	(segment
		(start 148.360638 -104.233218)
		(end 148.360638 -104.07142)
		(width 0.1651)
		(layer "In9.Cu")
		(net "P5E_PEX1_STN1_TX_DP<17>")
	)
	(segment
		(start 176.320196 -280.025856)
		(end 176.320196 -271.600168)
		(width 0.1143)
		(layer "In9.Cu")
		(net "P5E_PEX1_STN1_TX_DP<17>")
	)
	(segment
		(start 146.98599 -105.446068)
		(end 147.147788 -105.446068)
		(width 0.1651)
		(layer "In9.Cu")
		(net "P5E_PEX1_STN1_TX_DP<17>")
	)
	(segment
		(start 147.84832 -104.583738)
		(end 148.010118 -104.583738)
		(width 0.1651)
		(layer "In9.Cu")
		(net "P5E_PEX1_STN1_TX_DP<17>")
	)
	(segment
		(start 144.370552 -109.888782)
		(end 144.560036 -109.43082)
		(width 0.1651)
		(layer "In9.Cu")
		(net "P5E_PEX1_STN1_TX_DP<17>")
	)
	(segment
		(start 144.084294 -110.535466)
		(end 144.031462 -110.407958)
		(width 0.1651)
		(layer "In9.Cu")
		(net "P5E_PEX1_STN1_TX_DP<17>")
	)
	(segment
		(start 144.560036 -109.43082)
		(end 144.49806 -109.281468)
		(width 0.1651)
		(layer "In9.Cu")
		(net "P5E_PEX1_STN1_TX_DP<17>")
	)
	(segment
		(start 144.687544 -108.824014)
		(end 144.83715 -108.762292)
		(width 0.1651)
		(layer "In9.Cu")
		(net "P5E_PEX1_STN1_TX_DP<17>")
	)
	(segment
		(start 144.031462 -110.407958)
		(end 144.220946 -109.950504)
		(width 0.1651)
		(layer "In9.Cu")
		(net "P5E_PEX1_STN1_TX_DP<17>")
	)
	(segment
		(start 143.754348 -111.076994)
		(end 143.88211 -111.024162)
		(width 0.1651)
		(layer "In9.Cu")
		(net "P5E_PEX1_STN1_TX_DP<17>")
	)
	(segment
		(start 149.644608 -102.91318)
		(end 149.986238 -102.57155)
		(width 0.1651)
		(layer "In9.Cu")
		(net "P5E_PEX1_STN1_TX_DP<17>")
	)
	(segment
		(start 149.986238 -102.44582)
		(end 150.485094 -101.946964)
		(width 0.1651)
		(layer "In9.Cu")
		(net "P5E_PEX1_STN1_TX_DP<17>")
	)
	(segment
		(start 143.564864 -111.534448)
		(end 143.754348 -111.076994)
		(width 0.1651)
		(layer "In9.Cu")
		(net "P5E_PEX1_STN1_TX_DP<17>")
	)
	(segment
		(start 149.518878 -102.91318)
		(end 149.644608 -102.91318)
		(width 0.1651)
		(layer "In9.Cu")
		(net "P5E_PEX1_STN1_TX_DP<17>")
	)
	(segment
		(start 176.423828 -280.129488)
		(end 176.320196 -280.025856)
		(width 0.1143)
		(layer "In9.Cu")
		(net "P5E_PEX1_STN1_TX_DP<17>")
	)
	(segment
		(start 148.010118 -104.583738)
		(end 148.360638 -104.233218)
		(width 0.1651)
		(layer "In9.Cu")
		(net "P5E_PEX1_STN1_TX_DP<17>")
	)
	(segment
		(start 176.365916 -271.554448)
		(end 176.365916 -271.526)
		(width 0.1143)
		(layer "In9.Cu")
		(net "P5E_PEX1_STN1_TX_DP<17>")
	)
	(segment
		(start 148.71065 -103.721408)
		(end 148.836126 -103.721408)
		(width 0.1651)
		(layer "In9.Cu")
		(net "P5E_PEX1_STN1_TX_DP<17>")
	)
	(segment
		(start 146.285458 -106.308398)
		(end 146.635978 -105.957878)
		(width 0.1651)
		(layer "In9.Cu")
		(net "P5E_PEX1_STN1_TX_DP<17>")
	)
	(segment
		(start 161.826702 -363.802676)
		(end 161.849308 -363.642656)
		(width 0.1651)
		(layer "In9.Cu")
		(net "P5E_PEX1_STN7_RX_DN<122>")
	)
	(segment
		(start 153.28392 -324.581266)
		(end 153.28392 -318.950848)
		(width 0.1651)
		(layer "In9.Cu")
		(net "P5E_PEX1_STN7_RX_DN<122>")
	)
	(segment
		(start 164.32657 -367.119916)
		(end 164.028374 -366.724184)
		(width 0.1651)
		(layer "In9.Cu")
		(net "P5E_PEX1_STN7_RX_DN<122>")
	)
	(segment
		(start 164.48659 -367.142522)
		(end 164.32657 -367.119916)
		(width 0.1651)
		(layer "In9.Cu")
		(net "P5E_PEX1_STN7_RX_DN<122>")
	)
	(segment
		(start 164.659056 -382.699006)
		(end 165.19271 -382.165352)
		(width 0.1651)
		(layer "In9.Cu")
		(net "P5E_PEX1_STN7_RX_DN<122>")
	)
	(segment
		(start 164.31006 -382.18999)
		(end 164.31006 -382.572006)
		(width 0.1651)
		(layer "In9.Cu")
		(net "P5E_PEX1_STN7_RX_DN<122>")
	)
	(segment
		(start 163.592764 -366.146334)
		(end 163.294314 -365.750348)
		(width 0.1651)
		(layer "In9.Cu")
		(net "P5E_PEX1_STN7_RX_DN<122>")
	)
	(segment
		(start 161.849308 -363.642656)
		(end 161.551366 -363.247178)
		(width 0.1651)
		(layer "In9.Cu")
		(net "P5E_PEX1_STN7_RX_DN<122>")
	)
	(segment
		(start 162.858958 -365.172498)
		(end 162.560508 -364.776512)
		(width 0.1651)
		(layer "In9.Cu")
		(net "P5E_PEX1_STN7_RX_DN<122>")
	)
	(segment
		(start 163.018978 -365.19485)
		(end 162.858958 -365.172498)
		(width 0.1651)
		(layer "In9.Cu")
		(net "P5E_PEX1_STN7_RX_DN<122>")
	)
	(segment
		(start 157.776926 -357.853234)
		(end 153.28392 -324.581266)
		(width 0.1651)
		(layer "In9.Cu")
		(net "P5E_PEX1_STN7_RX_DN<122>")
	)
	(segment
		(start 153.32964 -316.888622)
		(end 153.24074 -316.799722)
		(width 0.1143)
		(layer "In9.Cu")
		(net "P5E_PEX1_STN7_RX_DN<122>")
	)
	(segment
		(start 162.285172 -364.221014)
		(end 162.125152 -364.198662)
		(width 0.1651)
		(layer "In9.Cu")
		(net "P5E_PEX1_STN7_RX_DN<122>")
	)
	(segment
		(start 163.31692 -365.590328)
		(end 163.018978 -365.19485)
		(width 0.1651)
		(layer "In9.Cu")
		(net "P5E_PEX1_STN7_RX_DN<122>")
	)
	(segment
		(start 164.050726 -366.564164)
		(end 163.752784 -366.168686)
		(width 0.1651)
		(layer "In9.Cu")
		(net "P5E_PEX1_STN7_RX_DN<122>")
	)
	(segment
		(start 164.43706 -382.699006)
		(end 164.659056 -382.699006)
		(width 0.1651)
		(layer "In9.Cu")
		(net "P5E_PEX1_STN7_RX_DN<122>")
	)
	(segment
		(start 160.39465 -361.860084)
		(end 160.412176 -361.735624)
		(width 0.1651)
		(layer "In9.Cu")
		(net "P5E_PEX1_STN7_RX_DN<122>")
	)
	(segment
		(start 160.412176 -361.735624)
		(end 158.185104 -358.780842)
		(width 0.1651)
		(layer "In9.Cu")
		(net "P5E_PEX1_STN7_RX_DN<122>")
	)
	(segment
		(start 162.560508 -364.776512)
		(end 162.583114 -364.616492)
		(width 0.1651)
		(layer "In9.Cu")
		(net "P5E_PEX1_STN7_RX_DN<122>")
	)
	(segment
		(start 161.092896 -362.82884)
		(end 161.115502 -362.66882)
		(width 0.1651)
		(layer "In9.Cu")
		(net "P5E_PEX1_STN7_RX_DN<122>")
	)
	(segment
		(start 153.32964 -318.87668)
		(end 153.32964 -316.888622)
		(width 0.1143)
		(layer "In9.Cu")
		(net "P5E_PEX1_STN7_RX_DN<122>")
	)
	(segment
		(start 161.115502 -362.66882)
		(end 160.81756 -362.273342)
		(width 0.1651)
		(layer "In9.Cu")
		(net "P5E_PEX1_STN7_RX_DN<122>")
	)
	(segment
		(start 158.185104 -358.780842)
		(end 157.776926 -357.853234)
		(width 0.1651)
		(layer "In9.Cu")
		(net "P5E_PEX1_STN7_RX_DN<122>")
	)
	(segment
		(start 160.81756 -362.273342)
		(end 160.6931 -362.255816)
		(width 0.1651)
		(layer "In9.Cu")
		(net "P5E_PEX1_STN7_RX_DN<122>")
	)
	(segment
		(start 164.31006 -382.572006)
		(end 164.43706 -382.699006)
		(width 0.1651)
		(layer "In9.Cu")
		(net "P5E_PEX1_STN7_RX_DN<122>")
	)
	(segment
		(start 161.391346 -363.224826)
		(end 161.092896 -362.82884)
		(width 0.1651)
		(layer "In9.Cu")
		(net "P5E_PEX1_STN7_RX_DN<122>")
	)
	(segment
		(start 163.294314 -365.750348)
		(end 163.31692 -365.590328)
		(width 0.1651)
		(layer "In9.Cu")
		(net "P5E_PEX1_STN7_RX_DN<122>")
	)
	(segment
		(start 153.28392 -318.950848)
		(end 153.28392 -318.9224)
		(width 0.1143)
		(layer "In9.Cu")
		(net "P5E_PEX1_STN7_RX_DN<122>")
	)
	(segment
		(start 161.551366 -363.247178)
		(end 161.391346 -363.224826)
		(width 0.1651)
		(layer "In9.Cu")
		(net "P5E_PEX1_STN7_RX_DN<122>")
	)
	(segment
		(start 153.24074 -316.799722)
		(end 152.94991 -316.799722)
		(width 0.1143)
		(layer "In9.Cu")
		(net "P5E_PEX1_STN7_RX_DN<122>")
	)
	(segment
		(start 164.028374 -366.724184)
		(end 164.050726 -366.564164)
		(width 0.1651)
		(layer "In9.Cu")
		(net "P5E_PEX1_STN7_RX_DN<122>")
	)
	(segment
		(start 163.752784 -366.168686)
		(end 163.592764 -366.146334)
		(width 0.1651)
		(layer "In9.Cu")
		(net "P5E_PEX1_STN7_RX_DN<122>")
	)
	(segment
		(start 162.583114 -364.616492)
		(end 162.285172 -364.221014)
		(width 0.1651)
		(layer "In9.Cu")
		(net "P5E_PEX1_STN7_RX_DN<122>")
	)
	(segment
		(start 165.19271 -368.319812)
		(end 165.047422 -367.886488)
		(width 0.1651)
		(layer "In9.Cu")
		(net "P5E_PEX1_STN7_RX_DN<122>")
	)
	(segment
		(start 153.28392 -318.9224)
		(end 153.32964 -318.87668)
		(width 0.1143)
		(layer "In9.Cu")
		(net "P5E_PEX1_STN7_RX_DN<122>")
	)
	(segment
		(start 165.19271 -382.165352)
		(end 165.19271 -368.319812)
		(width 0.1651)
		(layer "In9.Cu")
		(net "P5E_PEX1_STN7_RX_DN<122>")
	)
	(segment
		(start 165.047422 -367.886488)
		(end 164.48659 -367.142522)
		(width 0.1651)
		(layer "In9.Cu")
		(net "P5E_PEX1_STN7_RX_DN<122>")
	)
	(segment
		(start 160.6931 -362.255816)
		(end 160.39465 -361.860084)
		(width 0.1651)
		(layer "In9.Cu")
		(net "P5E_PEX1_STN7_RX_DN<122>")
	)
	(segment
		(start 162.125152 -364.198662)
		(end 161.826702 -363.802676)
		(width 0.1651)
		(layer "In9.Cu")
		(net "P5E_PEX1_STN7_RX_DN<122>")
	)
	(segment
		(start 65.344802 -345.465146)
		(end 65.050162 -345.170506)
		(width 0.13462)
		(layer "F.Cu")
		(net "P5E_PEX0_STN5_TX_C_DN<81>")
	)
	(segment
		(start 65.050162 -344.539062)
		(end 65.370202 -344.219022)
		(width 0.13462)
		(layer "F.Cu")
		(net "P5E_PEX0_STN5_TX_C_DN<81>")
	)
	(segment
		(start 65.050162 -345.170506)
		(end 65.050162 -344.539062)
		(width 0.13462)
		(layer "F.Cu")
		(net "P5E_PEX0_STN5_TX_C_DN<81>")
	)
	(segment
		(start 74.767948 -406.181052)
		(end 75.28433 -405.66467)
		(width 0.1651)
		(layer "In7.Cu")
		(net "P5E_PEX0_STN5_TX_C_DN<81>")
	)
	(segment
		(start 65.053972 -345.755976)
		(end 65.344802 -345.465146)
		(width 0.1651)
		(layer "In7.Cu")
		(net "P5E_PEX0_STN5_TX_C_DN<81>")
	)
	(segment
		(start 74.109834 -406.690068)
		(end 74.109834 -406.308052)
		(width 0.1651)
		(layer "In7.Cu")
		(net "P5E_PEX0_STN5_TX_C_DN<81>")
	)
	(segment
		(start 74.109834 -406.308052)
		(end 74.236834 -406.181052)
		(width 0.1651)
		(layer "In7.Cu")
		(net "P5E_PEX0_STN5_TX_C_DN<81>")
	)
	(segment
		(start 75.28433 -405.66467)
		(end 75.28433 -394.587984)
		(width 0.1651)
		(layer "In7.Cu")
		(net "P5E_PEX0_STN5_TX_C_DN<81>")
	)
	(segment
		(start 63.499492 -357.778304)
		(end 63.499492 -348.029022)
		(width 0.1651)
		(layer "In7.Cu")
		(net "P5E_PEX0_STN5_TX_C_DN<81>")
	)
	(segment
		(start 63.499492 -348.029022)
		(end 65.053972 -346.474542)
		(width 0.1651)
		(layer "In7.Cu")
		(net "P5E_PEX0_STN5_TX_C_DN<81>")
	)
	(segment
		(start 75.28433 -394.587984)
		(end 73.880218 -393.183872)
		(width 0.1651)
		(layer "In7.Cu")
		(net "P5E_PEX0_STN5_TX_C_DN<81>")
	)
	(segment
		(start 65.053972 -346.474542)
		(end 65.053972 -345.755976)
		(width 0.1651)
		(layer "In7.Cu")
		(net "P5E_PEX0_STN5_TX_C_DN<81>")
	)
	(segment
		(start 66.31178 -388.629906)
		(end 64.995044 -385.450842)
		(width 0.1651)
		(layer "In7.Cu")
		(net "P5E_PEX0_STN5_TX_C_DN<81>")
	)
	(segment
		(start 73.880218 -393.183872)
		(end 68.734432 -391.052558)
		(width 0.1651)
		(layer "In7.Cu")
		(net "P5E_PEX0_STN5_TX_C_DN<81>")
	)
	(segment
		(start 64.995044 -385.450842)
		(end 63.499492 -357.778304)
		(width 0.1651)
		(layer "In7.Cu")
		(net "P5E_PEX0_STN5_TX_C_DN<81>")
	)
	(segment
		(start 74.236834 -406.181052)
		(end 74.767948 -406.181052)
		(width 0.1651)
		(layer "In7.Cu")
		(net "P5E_PEX0_STN5_TX_C_DN<81>")
	)
	(segment
		(start 68.734432 -391.052558)
		(end 66.31178 -388.629906)
		(width 0.1651)
		(layer "In7.Cu")
		(net "P5E_PEX0_STN5_TX_C_DN<81>")
	)
	(segment
		(start 83.87969 -121.071132)
		(end 84.17433 -121.365772)
		(width 0.13462)
		(layer "F.Cu")
		(net "P5E_PEX0_STN0_TX_DP<1>")
	)
	(segment
		(start 82.928206 -121.391172)
		(end 83.248246 -121.071132)
		(width 0.13462)
		(layer "F.Cu")
		(net "P5E_PEX0_STN0_TX_DP<1>")
	)
	(segment
		(start 83.248246 -121.071132)
		(end 83.87969 -121.071132)
		(width 0.13462)
		(layer "F.Cu")
		(net "P5E_PEX0_STN0_TX_DP<1>")
	)
	(segment
		(start 74.84999 -287.349946)
		(end 74.849736 -287.349946)
		(width 0.13462)
		(layer "F.Cu")
		(net "P5E_PEX0_STN0_TX_DP<1>")
	)
	(segment
		(start 88.695784 -285.443422)
		(end 85.580982 -286.733742)
		(width 0.1651)
		(layer "In9.Cu")
		(net "P5E_PEX0_STN0_TX_DP<1>")
	)
	(segment
		(start 89.143078 -129.282698)
		(end 89.088214 -129.41554)
		(width 0.1651)
		(layer "In9.Cu")
		(net "P5E_PEX0_STN0_TX_DP<1>")
	)
	(segment
		(start 98.660458 -160.780222)
		(end 90.037412 -175.723042)
		(width 0.1651)
		(layer "In9.Cu")
		(net "P5E_PEX0_STN0_TX_DP<1>")
	)
	(segment
		(start 98.921824 -159.802068)
		(end 98.660458 -160.780222)
		(width 0.1651)
		(layer "In9.Cu")
		(net "P5E_PEX0_STN0_TX_DP<1>")
	)
	(segment
		(start 89.126568 -179.117498)
		(end 85.409024 -221.611444)
		(width 0.1651)
		(layer "In9.Cu")
		(net "P5E_PEX0_STN0_TX_DP<1>")
	)
	(segment
		(start 87.804752 -126.317502)
		(end 87.979758 -126.740158)
		(width 0.1651)
		(layer "In9.Cu")
		(net "P5E_PEX0_STN0_TX_DP<1>")
	)
	(segment
		(start 89.396062 -129.89306)
		(end 90.04681 -131.463796)
		(width 0.1651)
		(layer "In9.Cu")
		(net "P5E_PEX0_STN0_TX_DP<1>")
	)
	(segment
		(start 88.835484 -128.805432)
		(end 88.968326 -128.86055)
		(width 0.1651)
		(layer "In9.Cu")
		(net "P5E_PEX0_STN0_TX_DP<1>")
	)
	(segment
		(start 88.287606 -127.21717)
		(end 88.232742 -127.350012)
		(width 0.1651)
		(layer "In9.Cu")
		(net "P5E_PEX0_STN0_TX_DP<1>")
	)
	(segment
		(start 88.1126 -126.795022)
		(end 88.287352 -127.21717)
		(width 0.1651)
		(layer "In9.Cu")
		(net "P5E_PEX0_STN0_TX_DP<1>")
	)
	(segment
		(start 89.396316 -129.89306)
		(end 89.396062 -129.89306)
		(width 0.1651)
		(layer "In9.Cu")
		(net "P5E_PEX0_STN0_TX_DP<1>")
	)
	(segment
		(start 85.41131 -221.635828)
		(end 87.862664 -249.726958)
		(width 0.1651)
		(layer "In9.Cu")
		(net "P5E_PEX0_STN0_TX_DP<1>")
	)
	(segment
		(start 86.55177 -123.292616)
		(end 86.684612 -123.347734)
		(width 0.1651)
		(layer "In9.Cu")
		(net "P5E_PEX0_STN0_TX_DP<1>")
	)
	(segment
		(start 75.115166 -287.349946)
		(end 74.849736 -287.349946)
		(width 0.1143)
		(layer "In9.Cu")
		(net "P5E_PEX0_STN0_TX_DP<1>")
	)
	(segment
		(start 85.411056 -221.635828)
		(end 85.41131 -221.635828)
		(width 0.1651)
		(layer "In9.Cu")
		(net "P5E_PEX0_STN0_TX_DP<1>")
	)
	(segment
		(start 97.92716 -276.212046)
		(end 88.695784 -285.443422)
		(width 0.1651)
		(layer "In9.Cu")
		(net "P5E_PEX0_STN0_TX_DP<1>")
	)
	(segment
		(start 86.431628 -122.737118)
		(end 86.376764 -122.86996)
		(width 0.1651)
		(layer "In9.Cu")
		(net "P5E_PEX0_STN0_TX_DP<1>")
	)
	(segment
		(start 88.715342 -128.249934)
		(end 88.660478 -128.382776)
		(width 0.1651)
		(layer "In9.Cu")
		(net "P5E_PEX0_STN0_TX_DP<1>")
	)
	(segment
		(start 83.819492 -286.779462)
		(end 75.444858 -286.779462)
		(width 0.1143)
		(layer "In9.Cu")
		(net "P5E_PEX0_STN0_TX_DP<1>")
	)
	(segment
		(start 87.685118 -125.762512)
		(end 87.684864 -125.762512)
		(width 0.1651)
		(layer "In9.Cu")
		(net "P5E_PEX0_STN0_TX_DP<1>")
	)
	(segment
		(start 85.016848 -121.074942)
		(end 85.466428 -121.524522)
		(width 0.1651)
		(layer "In9.Cu")
		(net "P5E_PEX0_STN0_TX_DP<1>")
	)
	(segment
		(start 90.317066 -131.734306)
		(end 98.921824 -152.507442)
		(width 0.1651)
		(layer "In9.Cu")
		(net "P5E_PEX0_STN0_TX_DP<1>")
	)
	(segment
		(start 87.377016 -125.284738)
		(end 87.552022 -125.707394)
		(width 0.1651)
		(layer "In9.Cu")
		(net "P5E_PEX0_STN0_TX_DP<1>")
	)
	(segment
		(start 75.229466 -286.994854)
		(end 75.229466 -287.235646)
		(width 0.1143)
		(layer "In9.Cu")
		(net "P5E_PEX0_STN0_TX_DP<1>")
	)
	(segment
		(start 86.376764 -122.86996)
		(end 86.55177 -123.292616)
		(width 0.1651)
		(layer "In9.Cu")
		(net "P5E_PEX0_STN0_TX_DP<1>")
	)
	(segment
		(start 90.31732 -131.734306)
		(end 90.317066 -131.734306)
		(width 0.1651)
		(layer "In9.Cu")
		(net "P5E_PEX0_STN0_TX_DP<1>")
	)
	(segment
		(start 88.112854 -126.795022)
		(end 88.1126 -126.795022)
		(width 0.1651)
		(layer "In9.Cu")
		(net "P5E_PEX0_STN0_TX_DP<1>")
	)
	(segment
		(start 83.865212 -286.733742)
		(end 83.819492 -286.779462)
		(width 0.1143)
		(layer "In9.Cu")
		(net "P5E_PEX0_STN0_TX_DP<1>")
	)
	(segment
		(start 75.229466 -287.235646)
		(end 75.115166 -287.349946)
		(width 0.1143)
		(layer "In9.Cu")
		(net "P5E_PEX0_STN0_TX_DP<1>")
	)
	(segment
		(start 87.859616 -126.18466)
		(end 87.804752 -126.317502)
		(width 0.1651)
		(layer "In9.Cu")
		(net "P5E_PEX0_STN0_TX_DP<1>")
	)
	(segment
		(start 75.444858 -286.779462)
		(end 75.229466 -286.994854)
		(width 0.1143)
		(layer "In9.Cu")
		(net "P5E_PEX0_STN0_TX_DP<1>")
	)
	(segment
		(start 86.684612 -123.347734)
		(end 87.43188 -125.15215)
		(width 0.1651)
		(layer "In9.Cu")
		(net "P5E_PEX0_STN0_TX_DP<1>")
	)
	(segment
		(start 90.04681 -131.463796)
		(end 90.31732 -131.734306)
		(width 0.1651)
		(layer "In9.Cu")
		(net "P5E_PEX0_STN0_TX_DP<1>")
	)
	(segment
		(start 88.407748 -127.772668)
		(end 88.54059 -127.827786)
		(width 0.1651)
		(layer "In9.Cu")
		(net "P5E_PEX0_STN0_TX_DP<1>")
	)
	(segment
		(start 89.088214 -129.41554)
		(end 89.26322 -129.838196)
		(width 0.1651)
		(layer "In9.Cu")
		(net "P5E_PEX0_STN0_TX_DP<1>")
	)
	(segment
		(start 88.660478 -128.382776)
		(end 88.835484 -128.805432)
		(width 0.1651)
		(layer "In9.Cu")
		(net "P5E_PEX0_STN0_TX_DP<1>")
	)
	(segment
		(start 87.684864 -125.762512)
		(end 87.859616 -126.18466)
		(width 0.1651)
		(layer "In9.Cu")
		(net "P5E_PEX0_STN0_TX_DP<1>")
	)
	(segment
		(start 98.921824 -152.507442)
		(end 98.921824 -159.802068)
		(width 0.1651)
		(layer "In9.Cu")
		(net "P5E_PEX0_STN0_TX_DP<1>")
	)
	(segment
		(start 87.43188 -125.15215)
		(end 87.377016 -125.284738)
		(width 0.1651)
		(layer "In9.Cu")
		(net "P5E_PEX0_STN0_TX_DP<1>")
	)
	(segment
		(start 85.466428 -121.524522)
		(end 85.466428 -121.668286)
		(width 0.1651)
		(layer "In9.Cu")
		(net "P5E_PEX0_STN0_TX_DP<1>")
	)
	(segment
		(start 88.232742 -127.350012)
		(end 88.407748 -127.772668)
		(width 0.1651)
		(layer "In9.Cu")
		(net "P5E_PEX0_STN0_TX_DP<1>")
	)
	(segment
		(start 88.54059 -127.827786)
		(end 88.715342 -128.249934)
		(width 0.1651)
		(layer "In9.Cu")
		(net "P5E_PEX0_STN0_TX_DP<1>")
	)
	(segment
		(start 89.26322 -129.838196)
		(end 89.396316 -129.89306)
		(width 0.1651)
		(layer "In9.Cu")
		(net "P5E_PEX0_STN0_TX_DP<1>")
	)
	(segment
		(start 83.89366 -286.733742)
		(end 83.865212 -286.733742)
		(width 0.1143)
		(layer "In9.Cu")
		(net "P5E_PEX0_STN0_TX_DP<1>")
	)
	(segment
		(start 85.790024 -121.991882)
		(end 85.933788 -121.991882)
		(width 0.1651)
		(layer "In9.Cu")
		(net "P5E_PEX0_STN0_TX_DP<1>")
	)
	(segment
		(start 85.466428 -121.668286)
		(end 85.790024 -121.991882)
		(width 0.1651)
		(layer "In9.Cu")
		(net "P5E_PEX0_STN0_TX_DP<1>")
	)
	(segment
		(start 99.002596 -267.52931)
		(end 99.442524 -272.553176)
		(width 0.1651)
		(layer "In9.Cu")
		(net "P5E_PEX0_STN0_TX_DP<1>")
	)
	(segment
		(start 97.769172 -264.552176)
		(end 98.385884 -266.04087)
		(width 0.1651)
		(layer "In9.Cu")
		(net "P5E_PEX0_STN0_TX_DP<1>")
	)
	(segment
		(start 98.385884 -266.04087)
		(end 99.002596 -267.52931)
		(width 0.1651)
		(layer "In9.Cu")
		(net "P5E_PEX0_STN0_TX_DP<1>")
	)
	(segment
		(start 85.933788 -121.991882)
		(end 86.256876 -122.31497)
		(width 0.1651)
		(layer "In9.Cu")
		(net "P5E_PEX0_STN0_TX_DP<1>")
	)
	(segment
		(start 88.968326 -128.86055)
		(end 89.143078 -129.282698)
		(width 0.1651)
		(layer "In9.Cu")
		(net "P5E_PEX0_STN0_TX_DP<1>")
	)
	(segment
		(start 90.037412 -175.723042)
		(end 89.126568 -179.117498)
		(width 0.1651)
		(layer "In9.Cu")
		(net "P5E_PEX0_STN0_TX_DP<1>")
	)
	(segment
		(start 87.979758 -126.740158)
		(end 88.112854 -126.795022)
		(width 0.1651)
		(layer "In9.Cu")
		(net "P5E_PEX0_STN0_TX_DP<1>")
	)
	(segment
		(start 87.862664 -249.726958)
		(end 97.769172 -264.552176)
		(width 0.1651)
		(layer "In9.Cu")
		(net "P5E_PEX0_STN0_TX_DP<1>")
	)
	(segment
		(start 99.442524 -272.553176)
		(end 97.92716 -276.212046)
		(width 0.1651)
		(layer "In9.Cu")
		(net "P5E_PEX0_STN0_TX_DP<1>")
	)
	(segment
		(start 86.256876 -122.31497)
		(end 86.431628 -122.737118)
		(width 0.1651)
		(layer "In9.Cu")
		(net "P5E_PEX0_STN0_TX_DP<1>")
	)
	(segment
		(start 87.552022 -125.707394)
		(end 87.685118 -125.762512)
		(width 0.1651)
		(layer "In9.Cu")
		(net "P5E_PEX0_STN0_TX_DP<1>")
	)
	(segment
		(start 85.580982 -286.733742)
		(end 83.89366 -286.733742)
		(width 0.1651)
		(layer "In9.Cu")
		(net "P5E_PEX0_STN0_TX_DP<1>")
	)
	(segment
		(start 84.17433 -121.365772)
		(end 84.46516 -121.074942)
		(width 0.1651)
		(layer "In9.Cu")
		(net "P5E_PEX0_STN0_TX_DP<1>")
	)
	(segment
		(start 85.409024 -221.611444)
		(end 85.411056 -221.635828)
		(width 0.1651)
		(layer "In9.Cu")
		(net "P5E_PEX0_STN0_TX_DP<1>")
	)
	(segment
		(start 84.46516 -121.074942)
		(end 85.016848 -121.074942)
		(width 0.1651)
		(layer "In9.Cu")
		(net "P5E_PEX0_STN0_TX_DP<1>")
	)
	(segment
		(start 88.287352 -127.21717)
		(end 88.287606 -127.21717)
		(width 0.1651)
		(layer "In9.Cu")
		(net "P5E_PEX0_STN0_TX_DP<1>")
	)
	(segment
		(start 23.330408 -343.685622)
		(end 23.010368 -343.365582)
		(width 0.13462)
		(layer "F.Cu")
		(net "P5E_PEX0_STN7_TX_DN<113>")
	)
	(segment
		(start 23.010368 -343.365582)
		(end 23.010368 -342.734138)
		(width 0.13462)
		(layer "F.Cu")
		(net "P5E_PEX0_STN7_TX_DN<113>")
	)
	(segment
		(start 23.010368 -342.734138)
		(end 23.305008 -342.439498)
		(width 0.13462)
		(layer "F.Cu")
		(net "P5E_PEX0_STN7_TX_DN<113>")
	)
	(segment
		(start 18.49628 -325.56958)
		(end 18.35658 -325.495158)
		(width 0.1651)
		(layer "In7.Cu")
		(net "P5E_PEX0_STN7_TX_DN<113>")
	)
	(segment
		(start 19.61007 -314.489846)
		(end 26.044144 -304.86096)
		(width 0.1651)
		(layer "In7.Cu")
		(net "P5E_PEX0_STN7_TX_DN<113>")
	)
	(segment
		(start 43.765216 -302.549814)
		(end 43.499786 -302.549814)
		(width 0.1143)
		(layer "In7.Cu")
		(net "P5E_PEX0_STN7_TX_DN<113>")
	)
	(segment
		(start 19.186906 -327.844912)
		(end 19.047206 -327.77049)
		(width 0.1651)
		(layer "In7.Cu")
		(net "P5E_PEX0_STN7_TX_DN<113>")
	)
	(segment
		(start 31.459932 -302.215804)
		(end 35.633152 -302.215804)
		(width 0.1651)
		(layer "In7.Cu")
		(net "P5E_PEX0_STN7_TX_DN<113>")
	)
	(segment
		(start 18.84172 -326.707246)
		(end 18.70202 -326.632824)
		(width 0.1651)
		(layer "In7.Cu")
		(net "P5E_PEX0_STN7_TX_DN<113>")
	)
	(segment
		(start 18.132044 -324.754494)
		(end 18.132044 -319.601342)
		(width 0.1651)
		(layer "In7.Cu")
		(net "P5E_PEX0_STN7_TX_DN<113>")
	)
	(segment
		(start 43.879516 -302.435514)
		(end 43.765216 -302.549814)
		(width 0.1143)
		(layer "In7.Cu")
		(net "P5E_PEX0_STN7_TX_DN<113>")
	)
	(segment
		(start 18.722086 -316.634114)
		(end 19.61007 -314.489846)
		(width 0.1651)
		(layer "In7.Cu")
		(net "P5E_PEX0_STN7_TX_DN<113>")
	)
	(segment
		(start 18.244566 -325.124826)
		(end 18.132044 -324.754494)
		(width 0.1651)
		(layer "In7.Cu")
		(net "P5E_PEX0_STN7_TX_DN<113>")
	)
	(segment
		(start 23.014178 -342.148668)
		(end 23.014178 -340.844886)
		(width 0.1651)
		(layer "In7.Cu")
		(net "P5E_PEX0_STN7_TX_DN<113>")
	)
	(segment
		(start 27.032712 -304.049684)
		(end 31.459932 -302.215804)
		(width 0.1651)
		(layer "In7.Cu")
		(net "P5E_PEX0_STN7_TX_DN<113>")
	)
	(segment
		(start 19.327114 -328.306938)
		(end 19.186906 -327.844912)
		(width 0.1651)
		(layer "In7.Cu")
		(net "P5E_PEX0_STN7_TX_DN<113>")
	)
	(segment
		(start 43.765216 -302.170084)
		(end 43.879516 -302.284384)
		(width 0.1143)
		(layer "In7.Cu")
		(net "P5E_PEX0_STN7_TX_DN<113>")
	)
	(segment
		(start 19.047206 -327.77049)
		(end 18.907252 -327.308718)
		(width 0.1651)
		(layer "In7.Cu")
		(net "P5E_PEX0_STN7_TX_DN<113>")
	)
	(segment
		(start 18.132044 -319.601342)
		(end 18.722086 -316.634114)
		(width 0.1651)
		(layer "In7.Cu")
		(net "P5E_PEX0_STN7_TX_DN<113>")
	)
	(segment
		(start 19.252438 -328.446384)
		(end 19.327114 -328.306938)
		(width 0.1651)
		(layer "In7.Cu")
		(net "P5E_PEX0_STN7_TX_DN<113>")
	)
	(segment
		(start 26.044144 -304.86096)
		(end 27.032712 -304.049684)
		(width 0.1651)
		(layer "In7.Cu")
		(net "P5E_PEX0_STN7_TX_DN<113>")
	)
	(segment
		(start 18.70202 -326.632824)
		(end 18.562066 -326.171052)
		(width 0.1651)
		(layer "In7.Cu")
		(net "P5E_PEX0_STN7_TX_DN<113>")
	)
	(segment
		(start 18.636488 -326.03186)
		(end 18.49628 -325.56958)
		(width 0.1651)
		(layer "In7.Cu")
		(net "P5E_PEX0_STN7_TX_DN<113>")
	)
	(segment
		(start 18.35658 -325.495158)
		(end 18.244312 -325.124826)
		(width 0.1651)
		(layer "In7.Cu")
		(net "P5E_PEX0_STN7_TX_DN<113>")
	)
	(segment
		(start 23.014178 -340.844886)
		(end 19.252438 -328.446384)
		(width 0.1651)
		(layer "In7.Cu")
		(net "P5E_PEX0_STN7_TX_DN<113>")
	)
	(segment
		(start 35.6616 -302.215804)
		(end 35.70732 -302.170084)
		(width 0.1143)
		(layer "In7.Cu")
		(net "P5E_PEX0_STN7_TX_DN<113>")
	)
	(segment
		(start 18.981928 -327.169272)
		(end 18.84172 -326.707246)
		(width 0.1651)
		(layer "In7.Cu")
		(net "P5E_PEX0_STN7_TX_DN<113>")
	)
	(segment
		(start 35.70732 -302.170084)
		(end 43.765216 -302.170084)
		(width 0.1143)
		(layer "In7.Cu")
		(net "P5E_PEX0_STN7_TX_DN<113>")
	)
	(segment
		(start 18.907252 -327.308718)
		(end 18.981928 -327.169272)
		(width 0.1651)
		(layer "In7.Cu")
		(net "P5E_PEX0_STN7_TX_DN<113>")
	)
	(segment
		(start 18.562066 -326.171052)
		(end 18.636488 -326.03186)
		(width 0.1651)
		(layer "In7.Cu")
		(net "P5E_PEX0_STN7_TX_DN<113>")
	)
	(segment
		(start 35.633152 -302.215804)
		(end 35.6616 -302.215804)
		(width 0.1143)
		(layer "In7.Cu")
		(net "P5E_PEX0_STN7_TX_DN<113>")
	)
	(segment
		(start 23.305008 -342.439498)
		(end 23.014178 -342.148668)
		(width 0.1651)
		(layer "In7.Cu")
		(net "P5E_PEX0_STN7_TX_DN<113>")
	)
	(segment
		(start 43.879516 -302.284384)
		(end 43.879516 -302.435514)
		(width 0.1143)
		(layer "In7.Cu")
		(net "P5E_PEX0_STN7_TX_DN<113>")
	)
	(segment
		(start 18.244312 -325.124826)
		(end 18.244566 -325.124826)
		(width 0.1651)
		(layer "In7.Cu")
		(net "P5E_PEX0_STN7_TX_DN<113>")
	)
	(segment
		(start 154.162252 -124.925582)
		(end 153.867612 -124.630942)
		(width 0.13462)
		(layer "F.Cu")
		(net "P5E_PEX1_STN1_TX_DN<27>")
	)
	(segment
		(start 154.793696 -124.925582)
		(end 154.162252 -124.925582)
		(width 0.13462)
		(layer "F.Cu")
		(net "P5E_PEX1_STN1_TX_DN<27>")
	)
	(segment
		(start 155.113736 -124.605542)
		(end 154.793696 -124.925582)
		(width 0.13462)
		(layer "F.Cu")
		(net "P5E_PEX1_STN1_TX_DN<27>")
	)
	(segment
		(start 153.576782 -124.921772)
		(end 152.892506 -124.921772)
		(width 0.1651)
		(layer "In9.Cu")
		(net "P5E_PEX1_STN1_TX_DN<27>")
	)
	(segment
		(start 152.892506 -124.921772)
		(end 151.869902 -125.944376)
		(width 0.1651)
		(layer "In9.Cu")
		(net "P5E_PEX1_STN1_TX_DN<27>")
	)
	(segment
		(start 149.528276 -143.053816)
		(end 150.232872 -157.375606)
		(width 0.1651)
		(layer "In9.Cu")
		(net "P5E_PEX1_STN1_TX_DN<27>")
	)
	(segment
		(start 185.584084 -263.64311)
		(end 185.584084 -271.526)
		(width 0.1651)
		(layer "In9.Cu")
		(net "P5E_PEX1_STN1_TX_DN<27>")
	)
	(segment
		(start 186.085734 -280.319988)
		(end 186.200034 -280.434288)
		(width 0.1143)
		(layer "In9.Cu")
		(net "P5E_PEX1_STN1_TX_DN<27>")
	)
	(segment
		(start 147.781518 -132.062728)
		(end 146.95043 -134.069582)
		(width 0.1651)
		(layer "In9.Cu")
		(net "P5E_PEX1_STN1_TX_DN<27>")
	)
	(segment
		(start 146.95043 -136.830562)
		(end 149.528276 -143.053816)
		(width 0.1651)
		(layer "In9.Cu")
		(net "P5E_PEX1_STN1_TX_DN<27>")
	)
	(segment
		(start 186.200034 -280.434288)
		(end 186.200034 -280.699718)
		(width 0.1143)
		(layer "In9.Cu")
		(net "P5E_PEX1_STN1_TX_DN<27>")
	)
	(segment
		(start 185.629804 -280.10485)
		(end 185.844942 -280.319988)
		(width 0.1143)
		(layer "In9.Cu")
		(net "P5E_PEX1_STN1_TX_DN<27>")
	)
	(segment
		(start 146.95043 -134.069582)
		(end 146.95043 -136.830562)
		(width 0.1651)
		(layer "In9.Cu")
		(net "P5E_PEX1_STN1_TX_DN<27>")
	)
	(segment
		(start 185.844942 -280.319988)
		(end 186.085734 -280.319988)
		(width 0.1143)
		(layer "In9.Cu")
		(net "P5E_PEX1_STN1_TX_DN<27>")
	)
	(segment
		(start 185.584084 -271.526)
		(end 185.584084 -271.554448)
		(width 0.1143)
		(layer "In9.Cu")
		(net "P5E_PEX1_STN1_TX_DN<27>")
	)
	(segment
		(start 151.869902 -125.944376)
		(end 147.781518 -132.062728)
		(width 0.1651)
		(layer "In9.Cu")
		(net "P5E_PEX1_STN1_TX_DN<27>")
	)
	(segment
		(start 185.584084 -271.554448)
		(end 185.629804 -271.600168)
		(width 0.1143)
		(layer "In9.Cu")
		(net "P5E_PEX1_STN1_TX_DN<27>")
	)
	(segment
		(start 150.232872 -157.375606)
		(end 151.117808 -161.825178)
		(width 0.1651)
		(layer "In9.Cu")
		(net "P5E_PEX1_STN1_TX_DN<27>")
	)
	(segment
		(start 153.867612 -124.630942)
		(end 153.576782 -124.921772)
		(width 0.1651)
		(layer "In9.Cu")
		(net "P5E_PEX1_STN1_TX_DN<27>")
	)
	(segment
		(start 185.629804 -271.600168)
		(end 185.629804 -280.10485)
		(width 0.1143)
		(layer "In9.Cu")
		(net "P5E_PEX1_STN1_TX_DN<27>")
	)
	(segment
		(start 151.117808 -161.825178)
		(end 185.584084 -263.64311)
		(width 0.1651)
		(layer "In9.Cu")
		(net "P5E_PEX1_STN1_TX_DN<27>")
	)
	(segment
		(start 167.384984 -369.140994)
		(end 167.0558 -367.963958)
		(width 0.1651)
		(layer "In9.Cu")
		(net "P5E_PEX1_STN7_RX_DP<123>")
	)
	(segment
		(start 166.636954 -383.79908)
		(end 166.858442 -383.79908)
		(width 0.1651)
		(layer "In9.Cu")
		(net "P5E_PEX1_STN7_RX_DP<123>")
	)
	(segment
		(start 165.744906 -365.86033)
		(end 165.587426 -365.823754)
		(width 0.1651)
		(layer "In9.Cu")
		(net "P5E_PEX1_STN7_RX_DP<123>")
	)
	(segment
		(start 154.279854 -319.81648)
		(end 154.279854 -318.36868)
		(width 0.1143)
		(layer "In9.Cu")
		(net "P5E_PEX1_STN7_RX_DP<123>")
	)
	(segment
		(start 167.0558 -367.963958)
		(end 165.744906 -365.86033)
		(width 0.1651)
		(layer "In9.Cu")
		(net "P5E_PEX1_STN7_RX_DP<123>")
	)
	(segment
		(start 166.509954 -383.290064)
		(end 166.509954 -383.67208)
		(width 0.1651)
		(layer "In9.Cu")
		(net "P5E_PEX1_STN7_RX_DP<123>")
	)
	(segment
		(start 166.509954 -383.67208)
		(end 166.636954 -383.79908)
		(width 0.1651)
		(layer "In9.Cu")
		(net "P5E_PEX1_STN7_RX_DP<123>")
	)
	(segment
		(start 154.850084 -318.040766)
		(end 154.850084 -317.749936)
		(width 0.1143)
		(layer "In9.Cu")
		(net "P5E_PEX1_STN7_RX_DP<123>")
	)
	(segment
		(start 154.234134 -319.890648)
		(end 154.234134 -319.8622)
		(width 0.1143)
		(layer "In9.Cu")
		(net "P5E_PEX1_STN7_RX_DP<123>")
	)
	(segment
		(start 154.598878 -324.827646)
		(end 154.234134 -321.429888)
		(width 0.1651)
		(layer "In9.Cu")
		(net "P5E_PEX1_STN7_RX_DP<123>")
	)
	(segment
		(start 160.922462 -353.93884)
		(end 154.598878 -324.827646)
		(width 0.1651)
		(layer "In9.Cu")
		(net "P5E_PEX1_STN7_RX_DP<123>")
	)
	(segment
		(start 154.234134 -319.8622)
		(end 154.279854 -319.81648)
		(width 0.1143)
		(layer "In9.Cu")
		(net "P5E_PEX1_STN7_RX_DP<123>")
	)
	(segment
		(start 165.361874 -365.24565)
		(end 161.047684 -358.322626)
		(width 0.1651)
		(layer "In9.Cu")
		(net "P5E_PEX1_STN7_RX_DP<123>")
	)
	(segment
		(start 154.761184 -318.129666)
		(end 154.850084 -318.040766)
		(width 0.1143)
		(layer "In9.Cu")
		(net "P5E_PEX1_STN7_RX_DP<123>")
	)
	(segment
		(start 167.384984 -383.272538)
		(end 167.384984 -369.140994)
		(width 0.1651)
		(layer "In9.Cu")
		(net "P5E_PEX1_STN7_RX_DP<123>")
	)
	(segment
		(start 166.858442 -383.79908)
		(end 167.384984 -383.272538)
		(width 0.1651)
		(layer "In9.Cu")
		(net "P5E_PEX1_STN7_RX_DP<123>")
	)
	(segment
		(start 154.234134 -321.429888)
		(end 154.234134 -319.890648)
		(width 0.1651)
		(layer "In9.Cu")
		(net "P5E_PEX1_STN7_RX_DP<123>")
	)
	(segment
		(start 165.325298 -365.40313)
		(end 165.361874 -365.24565)
		(width 0.1651)
		(layer "In9.Cu")
		(net "P5E_PEX1_STN7_RX_DP<123>")
	)
	(segment
		(start 154.279854 -318.36868)
		(end 154.518868 -318.129666)
		(width 0.1143)
		(layer "In9.Cu")
		(net "P5E_PEX1_STN7_RX_DP<123>")
	)
	(segment
		(start 161.047684 -358.322626)
		(end 160.922462 -357.88473)
		(width 0.1651)
		(layer "In9.Cu")
		(net "P5E_PEX1_STN7_RX_DP<123>")
	)
	(segment
		(start 154.518868 -318.129666)
		(end 154.761184 -318.129666)
		(width 0.1143)
		(layer "In9.Cu")
		(net "P5E_PEX1_STN7_RX_DP<123>")
	)
	(segment
		(start 165.587426 -365.823754)
		(end 165.325298 -365.40313)
		(width 0.1651)
		(layer "In9.Cu")
		(net "P5E_PEX1_STN7_RX_DP<123>")
	)
	(segment
		(start 160.922462 -357.88473)
		(end 160.922462 -353.93884)
		(width 0.1651)
		(layer "In9.Cu")
		(net "P5E_PEX1_STN7_RX_DP<123>")
	)
	(segment
		(start 86.812882 -350.685354)
		(end 87.132922 -350.365314)
		(width 0.13462)
		(layer "F.Cu")
		(net "P5E_PEX0_STN5_TX_C_DN<92>")
	)
	(segment
		(start 87.107522 -351.611438)
		(end 86.812882 -351.316798)
		(width 0.13462)
		(layer "F.Cu")
		(net "P5E_PEX0_STN5_TX_C_DN<92>")
	)
	(segment
		(start 86.812882 -351.316798)
		(end 86.812882 -350.685354)
		(width 0.13462)
		(layer "F.Cu")
		(net "P5E_PEX0_STN5_TX_C_DN<92>")
	)
	(segment
		(start 80.710024 -379.590046)
		(end 80.710024 -379.20803)
		(width 0.1651)
		(layer "In7.Cu")
		(net "P5E_PEX0_STN5_TX_C_DN<92>")
	)
	(segment
		(start 80.837024 -379.08103)
		(end 81.29016 -379.08103)
		(width 0.1651)
		(layer "In7.Cu")
		(net "P5E_PEX0_STN5_TX_C_DN<92>")
	)
	(segment
		(start 86.816692 -351.902268)
		(end 87.107522 -351.611438)
		(width 0.1651)
		(layer "In7.Cu")
		(net "P5E_PEX0_STN5_TX_C_DN<92>")
	)
	(segment
		(start 85.262212 -354.107242)
		(end 86.816692 -352.552762)
		(width 0.1651)
		(layer "In7.Cu")
		(net "P5E_PEX0_STN5_TX_C_DN<92>")
	)
	(segment
		(start 80.710024 -379.20803)
		(end 80.837024 -379.08103)
		(width 0.1651)
		(layer "In7.Cu")
		(net "P5E_PEX0_STN5_TX_C_DN<92>")
	)
	(segment
		(start 86.816692 -352.552762)
		(end 86.816692 -351.902268)
		(width 0.1651)
		(layer "In7.Cu")
		(net "P5E_PEX0_STN5_TX_C_DN<92>")
	)
	(segment
		(start 85.262212 -358.091994)
		(end 85.262212 -354.107242)
		(width 0.1651)
		(layer "In7.Cu")
		(net "P5E_PEX0_STN5_TX_C_DN<92>")
	)
	(segment
		(start 81.29016 -379.08103)
		(end 81.884266 -378.486924)
		(width 0.1651)
		(layer "In7.Cu")
		(net "P5E_PEX0_STN5_TX_C_DN<92>")
	)
	(segment
		(start 81.884266 -378.486924)
		(end 81.884266 -369.227354)
		(width 0.1651)
		(layer "In7.Cu")
		(net "P5E_PEX0_STN5_TX_C_DN<92>")
	)
	(segment
		(start 81.884266 -369.227354)
		(end 85.262212 -358.091994)
		(width 0.1651)
		(layer "In7.Cu")
		(net "P5E_PEX0_STN5_TX_C_DN<92>")
	)
	(segment
		(start 172.376592 -351.611438)
		(end 172.081952 -351.316798)
		(width 0.13462)
		(layer "F.Cu")
		(net "P5E_PEX1_STN7_TX_C_DN<117>")
	)
	(segment
		(start 172.081952 -351.316798)
		(end 172.081952 -350.685354)
		(width 0.13462)
		(layer "F.Cu")
		(net "P5E_PEX1_STN7_TX_C_DN<117>")
	)
	(segment
		(start 172.081952 -350.685354)
		(end 172.401992 -350.365314)
		(width 0.13462)
		(layer "F.Cu")
		(net "P5E_PEX1_STN7_TX_C_DN<117>")
	)
	(segment
		(start 160.220152 -388.53745)
		(end 157.771592 -386.720334)
		(width 0.1651)
		(layer "In11.Cu")
		(net "P5E_PEX1_STN7_TX_C_DN<117>")
	)
	(segment
		(start 172.085762 -352.664776)
		(end 172.085762 -351.902268)
		(width 0.1651)
		(layer "In11.Cu")
		(net "P5E_PEX1_STN7_TX_C_DN<117>")
	)
	(segment
		(start 156.983684 -384.770376)
		(end 156.779976 -382.415796)
		(width 0.1651)
		(layer "In11.Cu")
		(net "P5E_PEX1_STN7_TX_C_DN<117>")
	)
	(segment
		(start 163.773104 -389.710676)
		(end 160.220152 -388.53745)
		(width 0.1651)
		(layer "In11.Cu")
		(net "P5E_PEX1_STN7_TX_C_DN<117>")
	)
	(segment
		(start 170.531282 -359.096818)
		(end 170.531282 -354.219256)
		(width 0.1651)
		(layer "In11.Cu")
		(net "P5E_PEX1_STN7_TX_C_DN<117>")
	)
	(segment
		(start 157.61716 -366.889538)
		(end 159.458406 -364.999778)
		(width 0.1651)
		(layer "In11.Cu")
		(net "P5E_PEX1_STN7_TX_C_DN<117>")
	)
	(segment
		(start 159.458406 -364.999778)
		(end 168.368472 -361.259628)
		(width 0.1651)
		(layer "In11.Cu")
		(net "P5E_PEX1_STN7_TX_C_DN<117>")
	)
	(segment
		(start 157.771592 -386.720334)
		(end 156.983684 -384.770376)
		(width 0.1651)
		(layer "In11.Cu")
		(net "P5E_PEX1_STN7_TX_C_DN<117>")
	)
	(segment
		(start 170.531282 -354.219256)
		(end 172.085762 -352.664776)
		(width 0.1651)
		(layer "In11.Cu")
		(net "P5E_PEX1_STN7_TX_C_DN<117>")
	)
	(segment
		(start 172.085762 -351.902268)
		(end 172.376592 -351.611438)
		(width 0.1651)
		(layer "In11.Cu")
		(net "P5E_PEX1_STN7_TX_C_DN<117>")
	)
	(segment
		(start 170.909996 -402.790152)
		(end 170.909996 -402.408136)
		(width 0.1651)
		(layer "In11.Cu")
		(net "P5E_PEX1_STN7_TX_C_DN<117>")
	)
	(segment
		(start 171.769532 -402.281136)
		(end 172.075094 -401.975574)
		(width 0.1651)
		(layer "In11.Cu")
		(net "P5E_PEX1_STN7_TX_C_DN<117>")
	)
	(segment
		(start 165.76421 -390.637268)
		(end 163.773104 -389.710676)
		(width 0.1651)
		(layer "In11.Cu")
		(net "P5E_PEX1_STN7_TX_C_DN<117>")
	)
	(segment
		(start 172.075094 -401.975574)
		(end 172.075094 -395.125956)
		(width 0.1651)
		(layer "In11.Cu")
		(net "P5E_PEX1_STN7_TX_C_DN<117>")
	)
	(segment
		(start 171.036996 -402.281136)
		(end 171.769532 -402.281136)
		(width 0.1651)
		(layer "In11.Cu")
		(net "P5E_PEX1_STN7_TX_C_DN<117>")
	)
	(segment
		(start 172.075094 -395.125956)
		(end 170.511978 -393.56284)
		(width 0.1651)
		(layer "In11.Cu")
		(net "P5E_PEX1_STN7_TX_C_DN<117>")
	)
	(segment
		(start 156.94787 -368.65941)
		(end 157.61716 -366.889538)
		(width 0.1651)
		(layer "In11.Cu")
		(net "P5E_PEX1_STN7_TX_C_DN<117>")
	)
	(segment
		(start 168.368472 -361.259628)
		(end 170.531282 -359.096818)
		(width 0.1651)
		(layer "In11.Cu")
		(net "P5E_PEX1_STN7_TX_C_DN<117>")
	)
	(segment
		(start 156.779976 -382.415796)
		(end 156.94787 -368.65941)
		(width 0.1651)
		(layer "In11.Cu")
		(net "P5E_PEX1_STN7_TX_C_DN<117>")
	)
	(segment
		(start 170.909996 -402.408136)
		(end 171.036996 -402.281136)
		(width 0.1651)
		(layer "In11.Cu")
		(net "P5E_PEX1_STN7_TX_C_DN<117>")
	)
	(segment
		(start 170.511978 -393.56284)
		(end 165.76421 -390.637268)
		(width 0.1651)
		(layer "In11.Cu")
		(net "P5E_PEX1_STN7_TX_C_DN<117>")
	)
	(segment
		(start 82.928206 -135.28675)
		(end 83.248246 -135.60679)
		(width 0.13462)
		(layer "F.Cu")
		(net "P5E_PEX0_STN0_TX_DN<7>")
	)
	(segment
		(start 83.248246 -135.60679)
		(end 83.87969 -135.60679)
		(width 0.13462)
		(layer "F.Cu")
		(net "P5E_PEX0_STN0_TX_DN<7>")
	)
	(segment
		(start 83.87969 -135.60679)
		(end 84.17433 -135.31215)
		(width 0.13462)
		(layer "F.Cu")
		(net "P5E_PEX0_STN0_TX_DN<7>")
	)
	(segment
		(start 82.995262 -279.153874)
		(end 82.780886 -279.36825)
		(width 0.1143)
		(layer "In9.Cu")
		(net "P5E_PEX0_STN0_TX_DN<7>")
	)
	(segment
		(start 79.84109 -221.581218)
		(end 82.029046 -246.62638)
		(width 0.1651)
		(layer "In9.Cu")
		(net "P5E_PEX0_STN0_TX_DN<7>")
	)
	(segment
		(start 93.397324 -158.760414)
		(end 84.841588 -173.584108)
		(width 0.1651)
		(layer "In9.Cu")
		(net "P5E_PEX0_STN0_TX_DN<7>")
	)
	(segment
		(start 85.461094 -135.902954)
		(end 89.360756 -145.317464)
		(width 0.1651)
		(layer "In9.Cu")
		(net "P5E_PEX0_STN0_TX_DN<7>")
	)
	(segment
		(start 84.46516 -135.60298)
		(end 85.16112 -135.60298)
		(width 0.1651)
		(layer "In9.Cu")
		(net "P5E_PEX0_STN0_TX_DN<7>")
	)
	(segment
		(start 93.397324 -154.11577)
		(end 93.397324 -158.760414)
		(width 0.1651)
		(layer "In9.Cu")
		(net "P5E_PEX0_STN0_TX_DN<7>")
	)
	(segment
		(start 83.651598 -178.021488)
		(end 79.84109 -221.581218)
		(width 0.1651)
		(layer "In9.Cu")
		(net "P5E_PEX0_STN0_TX_DN<7>")
	)
	(segment
		(start 82.184494 -279.749758)
		(end 82.449924 -279.749758)
		(width 0.1143)
		(layer "In9.Cu")
		(net "P5E_PEX0_STN0_TX_DN<7>")
	)
	(segment
		(start 90.0303 -145.987008)
		(end 93.397324 -154.11577)
		(width 0.1651)
		(layer "In9.Cu")
		(net "P5E_PEX0_STN0_TX_DN<7>")
	)
	(segment
		(start 82.780886 -279.36825)
		(end 82.180938 -279.36825)
		(width 0.1143)
		(layer "In9.Cu")
		(net "P5E_PEX0_STN0_TX_DN<7>")
	)
	(segment
		(start 84.09305 -277.344632)
		(end 83.337146 -278.87676)
		(width 0.1651)
		(layer "In9.Cu")
		(net "P5E_PEX0_STN0_TX_DN<7>")
	)
	(segment
		(start 83.337146 -278.87676)
		(end 83.070446 -279.143714)
		(width 0.1651)
		(layer "In9.Cu")
		(net "P5E_PEX0_STN0_TX_DN<7>")
	)
	(segment
		(start 82.180938 -279.36825)
		(end 82.070194 -279.479248)
		(width 0.1143)
		(layer "In9.Cu")
		(net "P5E_PEX0_STN0_TX_DN<7>")
	)
	(segment
		(start 84.17433 -135.31215)
		(end 84.46516 -135.60298)
		(width 0.1651)
		(layer "In9.Cu")
		(net "P5E_PEX0_STN0_TX_DN<7>")
	)
	(segment
		(start 89.360756 -145.317464)
		(end 90.0303 -145.987008)
		(width 0.1651)
		(layer "In9.Cu")
		(net "P5E_PEX0_STN0_TX_DN<7>")
	)
	(segment
		(start 82.070194 -279.635458)
		(end 82.184494 -279.749758)
		(width 0.1143)
		(layer "In9.Cu")
		(net "P5E_PEX0_STN0_TX_DN<7>")
	)
	(segment
		(start 83.070446 -279.143714)
		(end 83.060286 -279.153874)
		(width 0.1143)
		(layer "In9.Cu")
		(net "P5E_PEX0_STN0_TX_DN<7>")
	)
	(segment
		(start 84.217256 -271.674336)
		(end 84.09305 -277.344632)
		(width 0.1651)
		(layer "In9.Cu")
		(net "P5E_PEX0_STN0_TX_DN<7>")
	)
	(segment
		(start 83.060286 -279.153874)
		(end 82.995262 -279.153874)
		(width 0.1143)
		(layer "In9.Cu")
		(net "P5E_PEX0_STN0_TX_DN<7>")
	)
	(segment
		(start 84.841588 -173.584108)
		(end 83.651598 -178.021488)
		(width 0.1651)
		(layer "In9.Cu")
		(net "P5E_PEX0_STN0_TX_DN<7>")
	)
	(segment
		(start 82.029046 -246.62638)
		(end 82.0293 -246.62638)
		(width 0.1651)
		(layer "In9.Cu")
		(net "P5E_PEX0_STN0_TX_DN<7>")
	)
	(segment
		(start 85.16112 -135.60298)
		(end 85.461094 -135.902954)
		(width 0.1651)
		(layer "In9.Cu")
		(net "P5E_PEX0_STN0_TX_DN<7>")
	)
	(segment
		(start 82.0293 -246.62638)
		(end 84.217256 -271.674336)
		(width 0.1651)
		(layer "In9.Cu")
		(net "P5E_PEX0_STN0_TX_DN<7>")
	)
	(segment
		(start 82.070194 -279.479248)
		(end 82.070194 -279.635458)
		(width 0.1143)
		(layer "In9.Cu")
		(net "P5E_PEX0_STN0_TX_DN<7>")
	)
	(segment
		(start 26.119328 -348.88043)
		(end 26.413968 -348.58579)
		(width 0.13462)
		(layer "F.Cu")
		(net "P5E_PEX0_STN7_TX_DN<115>")
	)
	(segment
		(start 26.119328 -349.511874)
		(end 26.119328 -348.88043)
		(width 0.13462)
		(layer "F.Cu")
		(net "P5E_PEX0_STN7_TX_DN<115>")
	)
	(segment
		(start 26.439368 -349.831914)
		(end 26.119328 -349.511874)
		(width 0.13462)
		(layer "F.Cu")
		(net "P5E_PEX0_STN7_TX_DN<115>")
	)
	(segment
		(start 35.687 -304.115724)
		(end 35.73272 -304.070004)
		(width 0.1143)
		(layer "In7.Cu")
		(net "P5E_PEX0_STN7_TX_DN<115>")
	)
	(segment
		(start 27.049476 -307.316124)
		(end 27.390598 -306.975002)
		(width 0.1651)
		(layer "In7.Cu")
		(net "P5E_PEX0_STN7_TX_DN<115>")
	)
	(segment
		(start 43.765216 -304.449734)
		(end 43.499786 -304.449734)
		(width 0.1143)
		(layer "In7.Cu")
		(net "P5E_PEX0_STN7_TX_DN<115>")
	)
	(segment
		(start 35.658552 -304.115724)
		(end 35.687 -304.115724)
		(width 0.1143)
		(layer "In7.Cu")
		(net "P5E_PEX0_STN7_TX_DN<115>")
	)
	(segment
		(start 20.042124 -323.183504)
		(end 20.042124 -319.945004)
		(width 0.1651)
		(layer "In7.Cu")
		(net "P5E_PEX0_STN7_TX_DN<115>")
	)
	(segment
		(start 35.73272 -304.070004)
		(end 43.765216 -304.070004)
		(width 0.1143)
		(layer "In7.Cu")
		(net "P5E_PEX0_STN7_TX_DN<115>")
	)
	(segment
		(start 32.120586 -304.115724)
		(end 35.658552 -304.115724)
		(width 0.1651)
		(layer "In7.Cu")
		(net "P5E_PEX0_STN7_TX_DN<115>")
	)
	(segment
		(start 26.281634 -308.083966)
		(end 26.549858 -307.815742)
		(width 0.1651)
		(layer "In7.Cu")
		(net "P5E_PEX0_STN7_TX_DN<115>")
	)
	(segment
		(start 27.390598 -306.975002)
		(end 27.548586 -306.975002)
		(width 0.1651)
		(layer "In7.Cu")
		(net "P5E_PEX0_STN7_TX_DN<115>")
	)
	(segment
		(start 27.890216 -306.633372)
		(end 27.890216 -306.475384)
		(width 0.1651)
		(layer "In7.Cu")
		(net "P5E_PEX0_STN7_TX_DN<115>")
	)
	(segment
		(start 20.042124 -319.945004)
		(end 20.51939 -317.545212)
		(width 0.1651)
		(layer "In7.Cu")
		(net "P5E_PEX0_STN7_TX_DN<115>")
	)
	(segment
		(start 26.707846 -307.815742)
		(end 27.049476 -307.474112)
		(width 0.1651)
		(layer "In7.Cu")
		(net "P5E_PEX0_STN7_TX_DN<115>")
	)
	(segment
		(start 27.677618 -346.103702)
		(end 27.677618 -341.6173)
		(width 0.1651)
		(layer "In7.Cu")
		(net "P5E_PEX0_STN7_TX_DN<115>")
	)
	(segment
		(start 43.879516 -304.184304)
		(end 43.879516 -304.335434)
		(width 0.1143)
		(layer "In7.Cu")
		(net "P5E_PEX0_STN7_TX_DN<115>")
	)
	(segment
		(start 26.123138 -347.658182)
		(end 27.677618 -346.103702)
		(width 0.1651)
		(layer "In7.Cu")
		(net "P5E_PEX0_STN7_TX_DN<115>")
	)
	(segment
		(start 43.765216 -304.070004)
		(end 43.879516 -304.184304)
		(width 0.1143)
		(layer "In7.Cu")
		(net "P5E_PEX0_STN7_TX_DN<115>")
	)
	(segment
		(start 28.389326 -306.134262)
		(end 28.730956 -305.792632)
		(width 0.1651)
		(layer "In7.Cu")
		(net "P5E_PEX0_STN7_TX_DN<115>")
	)
	(segment
		(start 27.677618 -341.6173)
		(end 20.042124 -323.183504)
		(width 0.1651)
		(layer "In7.Cu")
		(net "P5E_PEX0_STN7_TX_DN<115>")
	)
	(segment
		(start 27.548586 -306.975002)
		(end 27.890216 -306.633372)
		(width 0.1651)
		(layer "In7.Cu")
		(net "P5E_PEX0_STN7_TX_DN<115>")
	)
	(segment
		(start 26.549858 -307.815742)
		(end 26.707846 -307.815742)
		(width 0.1651)
		(layer "In7.Cu")
		(net "P5E_PEX0_STN7_TX_DN<115>")
	)
	(segment
		(start 28.730956 -305.634644)
		(end 28.927044 -305.438556)
		(width 0.1651)
		(layer "In7.Cu")
		(net "P5E_PEX0_STN7_TX_DN<115>")
	)
	(segment
		(start 27.049476 -307.474112)
		(end 27.049476 -307.316124)
		(width 0.1651)
		(layer "In7.Cu")
		(net "P5E_PEX0_STN7_TX_DN<115>")
	)
	(segment
		(start 21.432266 -315.341508)
		(end 26.281634 -308.083966)
		(width 0.1651)
		(layer "In7.Cu")
		(net "P5E_PEX0_STN7_TX_DN<115>")
	)
	(segment
		(start 26.123138 -348.29496)
		(end 26.123138 -347.658182)
		(width 0.1651)
		(layer "In7.Cu")
		(net "P5E_PEX0_STN7_TX_DN<115>")
	)
	(segment
		(start 28.231338 -306.134262)
		(end 28.389326 -306.134262)
		(width 0.1651)
		(layer "In7.Cu")
		(net "P5E_PEX0_STN7_TX_DN<115>")
	)
	(segment
		(start 20.51939 -317.545212)
		(end 21.432266 -315.341508)
		(width 0.1651)
		(layer "In7.Cu")
		(net "P5E_PEX0_STN7_TX_DN<115>")
	)
	(segment
		(start 27.890216 -306.475384)
		(end 28.231338 -306.134262)
		(width 0.1651)
		(layer "In7.Cu")
		(net "P5E_PEX0_STN7_TX_DN<115>")
	)
	(segment
		(start 28.927044 -305.438556)
		(end 32.120586 -304.115724)
		(width 0.1651)
		(layer "In7.Cu")
		(net "P5E_PEX0_STN7_TX_DN<115>")
	)
	(segment
		(start 43.879516 -304.335434)
		(end 43.765216 -304.449734)
		(width 0.1143)
		(layer "In7.Cu")
		(net "P5E_PEX0_STN7_TX_DN<115>")
	)
	(segment
		(start 26.413968 -348.58579)
		(end 26.123138 -348.29496)
		(width 0.1651)
		(layer "In7.Cu")
		(net "P5E_PEX0_STN7_TX_DN<115>")
	)
	(segment
		(start 28.730956 -305.792632)
		(end 28.730956 -305.634644)
		(width 0.1651)
		(layer "In7.Cu")
		(net "P5E_PEX0_STN7_TX_DN<115>")
	)
	(segment
		(start 152.471628 -104.695498)
		(end 152.151588 -105.015538)
		(width 0.13462)
		(layer "F.Cu")
		(net "P5E_PEX1_STN1_TX_DN<19>")
	)
	(segment
		(start 152.151588 -105.015538)
		(end 151.520144 -105.015538)
		(width 0.13462)
		(layer "F.Cu")
		(net "P5E_PEX1_STN1_TX_DN<19>")
	)
	(segment
		(start 151.520144 -105.015538)
		(end 151.225504 -104.720898)
		(width 0.13462)
		(layer "F.Cu")
		(net "P5E_PEX1_STN1_TX_DN<19>")
	)
	(segment
		(start 141.770862 -144.659096)
		(end 142.127986 -151.935942)
		(width 0.1651)
		(layer "In9.Cu")
		(net "P5E_PEX1_STN1_TX_DN<19>")
	)
	(segment
		(start 139.20851 -131.059428)
		(end 139.20851 -138.47318)
		(width 0.1651)
		(layer "In9.Cu")
		(net "P5E_PEX1_STN1_TX_DN<19>")
	)
	(segment
		(start 142.485364 -159.213042)
		(end 143.091916 -162.262312)
		(width 0.1651)
		(layer "In9.Cu")
		(net "P5E_PEX1_STN1_TX_DN<19>")
	)
	(segment
		(start 178.599846 -280.434288)
		(end 178.599846 -280.699718)
		(width 0.1143)
		(layer "In9.Cu")
		(net "P5E_PEX1_STN1_TX_DN<19>")
	)
	(segment
		(start 146.922236 -108.362242)
		(end 143.82623 -115.837462)
		(width 0.1651)
		(layer "In9.Cu")
		(net "P5E_PEX1_STN1_TX_DN<19>")
	)
	(segment
		(start 142.127986 -151.935688)
		(end 142.306294 -155.565094)
		(width 0.1651)
		(layer "In9.Cu")
		(net "P5E_PEX1_STN1_TX_DN<19>")
	)
	(segment
		(start 177.983896 -271.554448)
		(end 178.029616 -271.600168)
		(width 0.1143)
		(layer "In9.Cu")
		(net "P5E_PEX1_STN1_TX_DN<19>")
	)
	(segment
		(start 150.934674 -105.011728)
		(end 150.27275 -105.011728)
		(width 0.1651)
		(layer "In9.Cu")
		(net "P5E_PEX1_STN1_TX_DN<19>")
	)
	(segment
		(start 178.029616 -271.600168)
		(end 178.029616 -280.10485)
		(width 0.1143)
		(layer "In9.Cu")
		(net "P5E_PEX1_STN1_TX_DN<19>")
	)
	(segment
		(start 139.20851 -138.47318)
		(end 141.770862 -144.659096)
		(width 0.1651)
		(layer "In9.Cu")
		(net "P5E_PEX1_STN1_TX_DN<19>")
	)
	(segment
		(start 142.306294 -155.565094)
		(end 142.485364 -159.213042)
		(width 0.1651)
		(layer "In9.Cu")
		(net "P5E_PEX1_STN1_TX_DN<19>")
	)
	(segment
		(start 143.091916 -162.262312)
		(end 177.983896 -265.345164)
		(width 0.1651)
		(layer "In9.Cu")
		(net "P5E_PEX1_STN1_TX_DN<19>")
	)
	(segment
		(start 177.983896 -271.526)
		(end 177.983896 -271.554448)
		(width 0.1143)
		(layer "In9.Cu")
		(net "P5E_PEX1_STN1_TX_DN<19>")
	)
	(segment
		(start 178.485546 -280.319988)
		(end 178.599846 -280.434288)
		(width 0.1143)
		(layer "In9.Cu")
		(net "P5E_PEX1_STN1_TX_DN<19>")
	)
	(segment
		(start 178.244754 -280.319988)
		(end 178.485546 -280.319988)
		(width 0.1143)
		(layer "In9.Cu")
		(net "P5E_PEX1_STN1_TX_DN<19>")
	)
	(segment
		(start 143.82623 -115.837462)
		(end 139.20851 -131.059428)
		(width 0.1651)
		(layer "In9.Cu")
		(net "P5E_PEX1_STN1_TX_DN<19>")
	)
	(segment
		(start 151.225504 -104.720898)
		(end 150.934674 -105.011728)
		(width 0.1651)
		(layer "In9.Cu")
		(net "P5E_PEX1_STN1_TX_DN<19>")
	)
	(segment
		(start 178.029616 -280.10485)
		(end 178.244754 -280.319988)
		(width 0.1143)
		(layer "In9.Cu")
		(net "P5E_PEX1_STN1_TX_DN<19>")
	)
	(segment
		(start 142.127986 -151.935942)
		(end 142.127986 -151.935688)
		(width 0.1651)
		(layer "In9.Cu")
		(net "P5E_PEX1_STN1_TX_DN<19>")
	)
	(segment
		(start 150.27275 -105.011728)
		(end 146.922236 -108.362242)
		(width 0.1651)
		(layer "In9.Cu")
		(net "P5E_PEX1_STN1_TX_DN<19>")
	)
	(segment
		(start 177.983896 -265.345164)
		(end 177.983896 -271.526)
		(width 0.1651)
		(layer "In9.Cu")
		(net "P5E_PEX1_STN1_TX_DN<19>")
	)
	(segment
		(start 150.076154 -311.286906)
		(end 150.042118 -311.781444)
		(width 0.1651)
		(layer "In9.Cu")
		(net "P5E_PEX1_STN7_RX_DN<120>")
	)
	(segment
		(start 159.910018 -383.107946)
		(end 159.910018 -383.490216)
		(width 0.1651)
		(layer "In9.Cu")
		(net "P5E_PEX1_STN7_RX_DN<120>")
	)
	(segment
		(start 150.907242 -308.96814)
		(end 150.386288 -309.489094)
		(width 0.1651)
		(layer "In9.Cu")
		(net "P5E_PEX1_STN7_RX_DN<120>")
	)
	(segment
		(start 150.407878 -316.97803)
		(end 150.332694 -317.100712)
		(width 0.1651)
		(layer "In9.Cu")
		(net "P5E_PEX1_STN7_RX_DN<120>")
	)
	(segment
		(start 151.154384 -308.865778)
		(end 150.907242 -308.96814)
		(width 0.1651)
		(layer "In9.Cu")
		(net "P5E_PEX1_STN7_RX_DN<120>")
	)
	(segment
		(start 149.83714 -313.278774)
		(end 149.914356 -314.384436)
		(width 0.1651)
		(layer "In9.Cu")
		(net "P5E_PEX1_STN7_RX_DN<120>")
	)
	(segment
		(start 150.01113 -315.76772)
		(end 150.168864 -316.421516)
		(width 0.1651)
		(layer "In9.Cu")
		(net "P5E_PEX1_STN7_RX_DN<120>")
	)
	(segment
		(start 160.375854 -382.980946)
		(end 160.037018 -382.980946)
		(width 0.1651)
		(layer "In9.Cu")
		(net "P5E_PEX1_STN7_RX_DN<120>")
	)
	(segment
		(start 154.850084 -309.199788)
		(end 155.140914 -309.199788)
		(width 0.1143)
		(layer "In9.Cu")
		(net "P5E_PEX1_STN7_RX_DN<120>")
	)
	(segment
		(start 161.074608 -382.282192)
		(end 160.375854 -382.980946)
		(width 0.1651)
		(layer "In9.Cu")
		(net "P5E_PEX1_STN7_RX_DN<120>")
	)
	(segment
		(start 150.168864 -316.421516)
		(end 150.291546 -316.496446)
		(width 0.1651)
		(layer "In9.Cu")
		(net "P5E_PEX1_STN7_RX_DN<120>")
	)
	(segment
		(start 149.981666 -311.178702)
		(end 150.076154 -311.286906)
		(width 0.1651)
		(layer "In9.Cu")
		(net "P5E_PEX1_STN7_RX_DN<120>")
	)
	(segment
		(start 150.910798 -319.496694)
		(end 156.14777 -358.276144)
		(width 0.1651)
		(layer "In9.Cu")
		(net "P5E_PEX1_STN7_RX_DN<120>")
	)
	(segment
		(start 150.023068 -314.47867)
		(end 150.057612 -314.973208)
		(width 0.1651)
		(layer "In9.Cu")
		(net "P5E_PEX1_STN7_RX_DN<120>")
	)
	(segment
		(start 160.947608 -369.170458)
		(end 161.074608 -369.773708)
		(width 0.1651)
		(layer "In9.Cu")
		(net "P5E_PEX1_STN7_RX_DN<120>")
	)
	(segment
		(start 150.332694 -317.100712)
		(end 150.910798 -319.496694)
		(width 0.1651)
		(layer "In9.Cu")
		(net "P5E_PEX1_STN7_RX_DN<120>")
	)
	(segment
		(start 150.042118 -311.781444)
		(end 149.933406 -311.875678)
		(width 0.1651)
		(layer "In9.Cu")
		(net "P5E_PEX1_STN7_RX_DN<120>")
	)
	(segment
		(start 149.933406 -311.875678)
		(end 149.83714 -313.278774)
		(width 0.1651)
		(layer "In9.Cu")
		(net "P5E_PEX1_STN7_RX_DN<120>")
	)
	(segment
		(start 150.291546 -316.496446)
		(end 150.407878 -316.97803)
		(width 0.1651)
		(layer "In9.Cu")
		(net "P5E_PEX1_STN7_RX_DN<120>")
	)
	(segment
		(start 151.751284 -308.865778)
		(end 151.154384 -308.865778)
		(width 0.1651)
		(layer "In9.Cu")
		(net "P5E_PEX1_STN7_RX_DN<120>")
	)
	(segment
		(start 161.074608 -369.773708)
		(end 161.074608 -382.282192)
		(width 0.1651)
		(layer "In9.Cu")
		(net "P5E_PEX1_STN7_RX_DN<120>")
	)
	(segment
		(start 150.057612 -314.973208)
		(end 149.963378 -315.081412)
		(width 0.1651)
		(layer "In9.Cu")
		(net "P5E_PEX1_STN7_RX_DN<120>")
	)
	(segment
		(start 150.04034 -310.32323)
		(end 149.981666 -311.178702)
		(width 0.1651)
		(layer "In9.Cu")
		(net "P5E_PEX1_STN7_RX_DN<120>")
	)
	(segment
		(start 150.386288 -309.489094)
		(end 150.04034 -310.32323)
		(width 0.1651)
		(layer "In9.Cu")
		(net "P5E_PEX1_STN7_RX_DN<120>")
	)
	(segment
		(start 151.779732 -308.865778)
		(end 151.751284 -308.865778)
		(width 0.1143)
		(layer "In9.Cu")
		(net "P5E_PEX1_STN7_RX_DN<120>")
	)
	(segment
		(start 151.825452 -308.820058)
		(end 151.779732 -308.865778)
		(width 0.1143)
		(layer "In9.Cu")
		(net "P5E_PEX1_STN7_RX_DN<120>")
	)
	(segment
		(start 155.229814 -309.110888)
		(end 155.229814 -308.9529)
		(width 0.1143)
		(layer "In9.Cu")
		(net "P5E_PEX1_STN7_RX_DN<120>")
	)
	(segment
		(start 155.140914 -309.199788)
		(end 155.229814 -309.110888)
		(width 0.1143)
		(layer "In9.Cu")
		(net "P5E_PEX1_STN7_RX_DN<120>")
	)
	(segment
		(start 155.229814 -308.9529)
		(end 155.096972 -308.820058)
		(width 0.1143)
		(layer "In9.Cu")
		(net "P5E_PEX1_STN7_RX_DN<120>")
	)
	(segment
		(start 149.914356 -314.384436)
		(end 150.023068 -314.47867)
		(width 0.1651)
		(layer "In9.Cu")
		(net "P5E_PEX1_STN7_RX_DN<120>")
	)
	(segment
		(start 149.963378 -315.081412)
		(end 150.01113 -315.76772)
		(width 0.1651)
		(layer "In9.Cu")
		(net "P5E_PEX1_STN7_RX_DN<120>")
	)
	(segment
		(start 156.14777 -358.276144)
		(end 160.947608 -369.170458)
		(width 0.1651)
		(layer "In9.Cu")
		(net "P5E_PEX1_STN7_RX_DN<120>")
	)
	(segment
		(start 160.037018 -382.980946)
		(end 159.910018 -383.107946)
		(width 0.1651)
		(layer "In9.Cu")
		(net "P5E_PEX1_STN7_RX_DN<120>")
	)
	(segment
		(start 155.096972 -308.820058)
		(end 151.825452 -308.820058)
		(width 0.1143)
		(layer "In9.Cu")
		(net "P5E_PEX1_STN7_RX_DN<120>")
	)
	(segment
		(start 137.302748 -350.685354)
		(end 137.622788 -350.365314)
		(width 0.13462)
		(layer "F.Cu")
		(net "P5E_PEX1_STN5_TX_C_DN<84>")
	)
	(segment
		(start 137.597388 -351.611438)
		(end 137.302748 -351.316798)
		(width 0.13462)
		(layer "F.Cu")
		(net "P5E_PEX1_STN5_TX_C_DN<84>")
	)
	(segment
		(start 137.302748 -351.316798)
		(end 137.302748 -350.685354)
		(width 0.13462)
		(layer "F.Cu")
		(net "P5E_PEX1_STN5_TX_C_DN<84>")
	)
	(segment
		(start 125.186186 -405.080724)
		(end 125.769624 -404.497286)
		(width 0.1651)
		(layer "In7.Cu")
		(net "P5E_PEX1_STN5_TX_C_DN<84>")
	)
	(segment
		(start 128.253998 -393.403582)
		(end 136.968738 -389.730996)
		(width 0.1651)
		(layer "In7.Cu")
		(net "P5E_PEX1_STN5_TX_C_DN<84>")
	)
	(segment
		(start 135.752078 -358.346502)
		(end 135.752078 -354.092002)
		(width 0.1651)
		(layer "In7.Cu")
		(net "P5E_PEX1_STN5_TX_C_DN<84>")
	)
	(segment
		(start 140.05814 -383.888996)
		(end 140.05814 -383.223516)
		(width 0.1651)
		(layer "In7.Cu")
		(net "P5E_PEX1_STN5_TX_C_DN<84>")
	)
	(segment
		(start 140.388848 -369.80876)
		(end 140.388848 -369.540282)
		(width 0.1651)
		(layer "In7.Cu")
		(net "P5E_PEX1_STN5_TX_C_DN<84>")
	)
	(segment
		(start 140.388848 -369.540282)
		(end 135.752078 -358.346502)
		(width 0.1651)
		(layer "In7.Cu")
		(net "P5E_PEX1_STN5_TX_C_DN<84>")
	)
	(segment
		(start 137.920476 -389.181086)
		(end 139.078716 -388.217918)
		(width 0.1651)
		(layer "In7.Cu")
		(net "P5E_PEX1_STN5_TX_C_DN<84>")
	)
	(segment
		(start 124.837444 -405.080724)
		(end 125.186186 -405.080724)
		(width 0.1651)
		(layer "In7.Cu")
		(net "P5E_PEX1_STN5_TX_C_DN<84>")
	)
	(segment
		(start 125.769624 -395.887956)
		(end 128.253998 -393.403582)
		(width 0.1651)
		(layer "In7.Cu")
		(net "P5E_PEX1_STN5_TX_C_DN<84>")
	)
	(segment
		(start 125.769624 -404.497286)
		(end 125.769624 -395.887956)
		(width 0.1651)
		(layer "In7.Cu")
		(net "P5E_PEX1_STN5_TX_C_DN<84>")
	)
	(segment
		(start 135.752078 -354.092002)
		(end 137.306558 -352.537522)
		(width 0.1651)
		(layer "In7.Cu")
		(net "P5E_PEX1_STN5_TX_C_DN<84>")
	)
	(segment
		(start 139.078716 -388.217918)
		(end 139.52982 -387.35889)
		(width 0.1651)
		(layer "In7.Cu")
		(net "P5E_PEX1_STN5_TX_C_DN<84>")
	)
	(segment
		(start 124.71019 -405.207978)
		(end 124.837444 -405.080724)
		(width 0.1651)
		(layer "In7.Cu")
		(net "P5E_PEX1_STN5_TX_C_DN<84>")
	)
	(segment
		(start 124.71019 -405.589994)
		(end 124.71019 -405.207978)
		(width 0.1651)
		(layer "In7.Cu")
		(net "P5E_PEX1_STN5_TX_C_DN<84>")
	)
	(segment
		(start 140.05814 -383.223516)
		(end 140.388848 -369.80876)
		(width 0.1651)
		(layer "In7.Cu")
		(net "P5E_PEX1_STN5_TX_C_DN<84>")
	)
	(segment
		(start 136.968738 -389.730996)
		(end 137.920476 -389.181086)
		(width 0.1651)
		(layer "In7.Cu")
		(net "P5E_PEX1_STN5_TX_C_DN<84>")
	)
	(segment
		(start 139.802616 -386.456174)
		(end 140.05814 -383.888996)
		(width 0.1651)
		(layer "In7.Cu")
		(net "P5E_PEX1_STN5_TX_C_DN<84>")
	)
	(segment
		(start 137.306558 -351.902268)
		(end 137.597388 -351.611438)
		(width 0.1651)
		(layer "In7.Cu")
		(net "P5E_PEX1_STN5_TX_C_DN<84>")
	)
	(segment
		(start 139.52982 -387.35889)
		(end 139.802616 -386.456174)
		(width 0.1651)
		(layer "In7.Cu")
		(net "P5E_PEX1_STN5_TX_C_DN<84>")
	)
	(segment
		(start 137.306558 -352.537522)
		(end 137.306558 -351.902268)
		(width 0.1651)
		(layer "In7.Cu")
		(net "P5E_PEX1_STN5_TX_C_DN<84>")
	)
	(segment
		(start 36.371784 -123.71324)
		(end 36.051744 -123.3932)
		(width 0.13462)
		(layer "F.Cu")
		(net "P5E_PEX0_STN1_TX_DN<26>")
	)
	(segment
		(start 36.051744 -123.3932)
		(end 35.4203 -123.3932)
		(width 0.13462)
		(layer "F.Cu")
		(net "P5E_PEX0_STN1_TX_DN<26>")
	)
	(segment
		(start 35.4203 -123.3932)
		(end 35.12566 -123.68784)
		(width 0.13462)
		(layer "F.Cu")
		(net "P5E_PEX0_STN1_TX_DN<26>")
	)
	(segment
		(start 30.398974 -132.232146)
		(end 30.164532 -132.797296)
		(width 0.1651)
		(layer "In9.Cu")
		(net "P5E_PEX0_STN1_TX_DN<26>")
	)
	(segment
		(start 33.449006 -124.86767)
		(end 33.264348 -125.31344)
		(width 0.1651)
		(layer "In9.Cu")
		(net "P5E_PEX0_STN1_TX_DN<26>")
	)
	(segment
		(start 31.49854 -129.875534)
		(end 31.313882 -130.321558)
		(width 0.1651)
		(layer "In9.Cu")
		(net "P5E_PEX0_STN1_TX_DN<26>")
	)
	(segment
		(start 30.39872 -132.232146)
		(end 30.398974 -132.232146)
		(width 0.1651)
		(layer "In9.Cu")
		(net "P5E_PEX0_STN1_TX_DN<26>")
	)
	(segment
		(start 68.770246 -271.546066)
		(end 68.770246 -278.12619)
		(width 0.1143)
		(layer "In9.Cu")
		(net "P5E_PEX0_STN1_TX_DN<26>")
	)
	(segment
		(start 34.83483 -123.39701)
		(end 34.19856 -123.39701)
		(width 0.1651)
		(layer "In9.Cu")
		(net "P5E_PEX0_STN1_TX_DN<26>")
	)
	(segment
		(start 32.535114 -127.074168)
		(end 32.350456 -127.519938)
		(width 0.1651)
		(layer "In9.Cu")
		(net "P5E_PEX0_STN1_TX_DN<26>")
	)
	(segment
		(start 31.770828 -129.218436)
		(end 31.621222 -129.280412)
		(width 0.1651)
		(layer "In9.Cu")
		(net "P5E_PEX0_STN1_TX_DN<26>")
	)
	(segment
		(start 30.6324 -131.66725)
		(end 30.632654 -131.66725)
		(width 0.1651)
		(layer "In9.Cu")
		(net "P5E_PEX0_STN1_TX_DN<26>")
	)
	(segment
		(start 30.632654 -131.66725)
		(end 30.39872 -132.232146)
		(width 0.1651)
		(layer "In9.Cu")
		(net "P5E_PEX0_STN1_TX_DN<26>")
	)
	(segment
		(start 31.313882 -130.321558)
		(end 31.164276 -130.383534)
		(width 0.1651)
		(layer "In9.Cu")
		(net "P5E_PEX0_STN1_TX_DN<26>")
	)
	(segment
		(start 32.078168 -128.17729)
		(end 31.89351 -128.62306)
		(width 0.1651)
		(layer "In9.Cu")
		(net "P5E_PEX0_STN1_TX_DN<26>")
	)
	(segment
		(start 31.621222 -129.280412)
		(end 31.436564 -129.726182)
		(width 0.1651)
		(layer "In9.Cu")
		(net "P5E_PEX0_STN1_TX_DN<26>")
	)
	(segment
		(start 68.873624 -278.229568)
		(end 69.035422 -278.229568)
		(width 0.1143)
		(layer "In9.Cu")
		(net "P5E_PEX0_STN1_TX_DN<26>")
	)
	(segment
		(start 68.815966 -271.471898)
		(end 68.815966 -271.500346)
		(width 0.1143)
		(layer "In9.Cu")
		(net "P5E_PEX0_STN1_TX_DN<26>")
	)
	(segment
		(start 32.350456 -127.519938)
		(end 32.412432 -127.66929)
		(width 0.1651)
		(layer "In9.Cu")
		(net "P5E_PEX0_STN1_TX_DN<26>")
	)
	(segment
		(start 33.855152 -159.487108)
		(end 33.949386 -159.960564)
		(width 0.1651)
		(layer "In9.Cu")
		(net "P5E_PEX0_STN1_TX_DN<26>")
	)
	(segment
		(start 68.815966 -271.500346)
		(end 68.770246 -271.546066)
		(width 0.1143)
		(layer "In9.Cu")
		(net "P5E_PEX0_STN1_TX_DN<26>")
	)
	(segment
		(start 32.535114 -127.073914)
		(end 32.535114 -127.074168)
		(width 0.1651)
		(layer "In9.Cu")
		(net "P5E_PEX0_STN1_TX_DN<26>")
	)
	(segment
		(start 34.106612 -161.272474)
		(end 68.815966 -263.80948)
		(width 0.1651)
		(layer "In9.Cu")
		(net "P5E_PEX0_STN1_TX_DN<26>")
	)
	(segment
		(start 32.99206 -125.970792)
		(end 32.807402 -126.416562)
		(width 0.1651)
		(layer "In9.Cu")
		(net "P5E_PEX0_STN1_TX_DN<26>")
	)
	(segment
		(start 35.12566 -123.68784)
		(end 34.83483 -123.39701)
		(width 0.1651)
		(layer "In9.Cu")
		(net "P5E_PEX0_STN1_TX_DN<26>")
	)
	(segment
		(start 31.955486 -128.772412)
		(end 31.770828 -129.218436)
		(width 0.1651)
		(layer "In9.Cu")
		(net "P5E_PEX0_STN1_TX_DN<26>")
	)
	(segment
		(start 31.164276 -130.383788)
		(end 30.904942 -131.010152)
		(width 0.1651)
		(layer "In9.Cu")
		(net "P5E_PEX0_STN1_TX_DN<26>")
	)
	(segment
		(start 30.164532 -136.961118)
		(end 32.733234 -143.16202)
		(width 0.1651)
		(layer "In9.Cu")
		(net "P5E_PEX0_STN1_TX_DN<26>")
	)
	(segment
		(start 33.326324 -125.462792)
		(end 33.141666 -125.908816)
		(width 0.1651)
		(layer "In9.Cu")
		(net "P5E_PEX0_STN1_TX_DN<26>")
	)
	(segment
		(start 33.949386 -159.960564)
		(end 33.869376 -160.079944)
		(width 0.1651)
		(layer "In9.Cu")
		(net "P5E_PEX0_STN1_TX_DN<26>")
	)
	(segment
		(start 33.78327 -124.35967)
		(end 33.598612 -124.805694)
		(width 0.1651)
		(layer "In9.Cu")
		(net "P5E_PEX0_STN1_TX_DN<26>")
	)
	(segment
		(start 32.807402 -126.416562)
		(end 32.869378 -126.565914)
		(width 0.1651)
		(layer "In9.Cu")
		(net "P5E_PEX0_STN1_TX_DN<26>")
	)
	(segment
		(start 30.164532 -132.797296)
		(end 30.164532 -136.961118)
		(width 0.1651)
		(layer "In9.Cu")
		(net "P5E_PEX0_STN1_TX_DN<26>")
	)
	(segment
		(start 33.958784 -123.636786)
		(end 33.721294 -124.210318)
		(width 0.1651)
		(layer "In9.Cu")
		(net "P5E_PEX0_STN1_TX_DN<26>")
	)
	(segment
		(start 33.264348 -125.31344)
		(end 33.326324 -125.462792)
		(width 0.1651)
		(layer "In9.Cu")
		(net "P5E_PEX0_STN1_TX_DN<26>")
	)
	(segment
		(start 33.141666 -125.908816)
		(end 32.99206 -125.970792)
		(width 0.1651)
		(layer "In9.Cu")
		(net "P5E_PEX0_STN1_TX_DN<26>")
	)
	(segment
		(start 69.035422 -278.229568)
		(end 69.149722 -278.115268)
		(width 0.1143)
		(layer "In9.Cu")
		(net "P5E_PEX0_STN1_TX_DN<26>")
	)
	(segment
		(start 32.733234 -143.16202)
		(end 33.46577 -158.050738)
		(width 0.1651)
		(layer "In9.Cu")
		(net "P5E_PEX0_STN1_TX_DN<26>")
	)
	(segment
		(start 30.966918 -131.159504)
		(end 30.782006 -131.605528)
		(width 0.1651)
		(layer "In9.Cu")
		(net "P5E_PEX0_STN1_TX_DN<26>")
	)
	(segment
		(start 33.46577 -158.050738)
		(end 33.735518 -159.407098)
		(width 0.1651)
		(layer "In9.Cu")
		(net "P5E_PEX0_STN1_TX_DN<26>")
	)
	(segment
		(start 32.68472 -127.011938)
		(end 32.535114 -127.073914)
		(width 0.1651)
		(layer "In9.Cu")
		(net "P5E_PEX0_STN1_TX_DN<26>")
	)
	(segment
		(start 68.770246 -278.12619)
		(end 68.873624 -278.229568)
		(width 0.1143)
		(layer "In9.Cu")
		(net "P5E_PEX0_STN1_TX_DN<26>")
	)
	(segment
		(start 31.436564 -129.726182)
		(end 31.49854 -129.875534)
		(width 0.1651)
		(layer "In9.Cu")
		(net "P5E_PEX0_STN1_TX_DN<26>")
	)
	(segment
		(start 30.904942 -131.010152)
		(end 30.966918 -131.159504)
		(width 0.1651)
		(layer "In9.Cu")
		(net "P5E_PEX0_STN1_TX_DN<26>")
	)
	(segment
		(start 32.869378 -126.565914)
		(end 32.68472 -127.011938)
		(width 0.1651)
		(layer "In9.Cu")
		(net "P5E_PEX0_STN1_TX_DN<26>")
	)
	(segment
		(start 32.227774 -128.115314)
		(end 32.078168 -128.17729)
		(width 0.1651)
		(layer "In9.Cu")
		(net "P5E_PEX0_STN1_TX_DN<26>")
	)
	(segment
		(start 34.19856 -123.39701)
		(end 33.958784 -123.636786)
		(width 0.1651)
		(layer "In9.Cu")
		(net "P5E_PEX0_STN1_TX_DN<26>")
	)
	(segment
		(start 31.164276 -130.383534)
		(end 31.164276 -130.383788)
		(width 0.1651)
		(layer "In9.Cu")
		(net "P5E_PEX0_STN1_TX_DN<26>")
	)
	(segment
		(start 31.89351 -128.62306)
		(end 31.955486 -128.772412)
		(width 0.1651)
		(layer "In9.Cu")
		(net "P5E_PEX0_STN1_TX_DN<26>")
	)
	(segment
		(start 32.412432 -127.66929)
		(end 32.227774 -128.115314)
		(width 0.1651)
		(layer "In9.Cu")
		(net "P5E_PEX0_STN1_TX_DN<26>")
	)
	(segment
		(start 33.735518 -159.407098)
		(end 33.855152 -159.487108)
		(width 0.1651)
		(layer "In9.Cu")
		(net "P5E_PEX0_STN1_TX_DN<26>")
	)
	(segment
		(start 30.782006 -131.605528)
		(end 30.6324 -131.66725)
		(width 0.1651)
		(layer "In9.Cu")
		(net "P5E_PEX0_STN1_TX_DN<26>")
	)
	(segment
		(start 33.869376 -160.079944)
		(end 34.106612 -161.272474)
		(width 0.1651)
		(layer "In9.Cu")
		(net "P5E_PEX0_STN1_TX_DN<26>")
	)
	(segment
		(start 33.598612 -124.805694)
		(end 33.449006 -124.86767)
		(width 0.1651)
		(layer "In9.Cu")
		(net "P5E_PEX0_STN1_TX_DN<26>")
	)
	(segment
		(start 68.815966 -263.80948)
		(end 68.815966 -271.471898)
		(width 0.1651)
		(layer "In9.Cu")
		(net "P5E_PEX0_STN1_TX_DN<26>")
	)
	(segment
		(start 33.721294 -124.210318)
		(end 33.78327 -124.35967)
		(width 0.1651)
		(layer "In9.Cu")
		(net "P5E_PEX0_STN1_TX_DN<26>")
	)
	(segment
		(start 69.149722 -278.115268)
		(end 69.149722 -277.849838)
		(width 0.1143)
		(layer "In9.Cu")
		(net "P5E_PEX0_STN1_TX_DN<26>")
	)
	(segment
		(start 199.34809 -121.071132)
		(end 199.979534 -121.071132)
		(width 0.13462)
		(layer "F.Cu")
		(net "P5E_PEX1_STN0_TX_DP<1>")
	)
	(segment
		(start 199.02805 -121.391172)
		(end 199.34809 -121.071132)
		(width 0.13462)
		(layer "F.Cu")
		(net "P5E_PEX1_STN0_TX_DP<1>")
	)
	(segment
		(start 199.979534 -121.071132)
		(end 200.274174 -121.365772)
		(width 0.13462)
		(layer "F.Cu")
		(net "P5E_PEX1_STN0_TX_DP<1>")
	)
	(segment
		(start 202.476862 -122.86996)
		(end 202.651868 -123.292616)
		(width 0.1651)
		(layer "In9.Cu")
		(net "P5E_PEX1_STN0_TX_DP<1>")
	)
	(segment
		(start 205.068424 -128.86055)
		(end 205.243176 -129.282698)
		(width 0.1651)
		(layer "In9.Cu")
		(net "P5E_PEX1_STN0_TX_DP<1>")
	)
	(segment
		(start 204.795882 -285.443422)
		(end 201.68108 -286.733742)
		(width 0.1651)
		(layer "In9.Cu")
		(net "P5E_PEX1_STN0_TX_DP<1>")
	)
	(segment
		(start 204.33284 -127.350012)
		(end 204.507846 -127.772668)
		(width 0.1651)
		(layer "In9.Cu")
		(net "P5E_PEX1_STN0_TX_DP<1>")
	)
	(segment
		(start 206.417418 -131.734306)
		(end 206.417164 -131.734306)
		(width 0.1651)
		(layer "In9.Cu")
		(net "P5E_PEX1_STN0_TX_DP<1>")
	)
	(segment
		(start 201.511408 -221.635828)
		(end 203.962762 -249.726958)
		(width 0.1651)
		(layer "In9.Cu")
		(net "P5E_PEX1_STN0_TX_DP<1>")
	)
	(segment
		(start 205.243176 -129.282698)
		(end 205.188312 -129.41554)
		(width 0.1651)
		(layer "In9.Cu")
		(net "P5E_PEX1_STN0_TX_DP<1>")
	)
	(segment
		(start 199.91959 -286.779462)
		(end 191.544956 -286.779462)
		(width 0.1143)
		(layer "In9.Cu")
		(net "P5E_PEX1_STN0_TX_DP<1>")
	)
	(segment
		(start 214.027258 -276.212046)
		(end 204.795882 -285.443422)
		(width 0.1651)
		(layer "In9.Cu")
		(net "P5E_PEX1_STN0_TX_DP<1>")
	)
	(segment
		(start 204.935582 -128.805432)
		(end 205.068424 -128.86055)
		(width 0.1651)
		(layer "In9.Cu")
		(net "P5E_PEX1_STN0_TX_DP<1>")
	)
	(segment
		(start 202.356974 -122.31497)
		(end 202.531726 -122.737118)
		(width 0.1651)
		(layer "In9.Cu")
		(net "P5E_PEX1_STN0_TX_DP<1>")
	)
	(segment
		(start 206.146908 -131.463796)
		(end 206.417418 -131.734306)
		(width 0.1651)
		(layer "In9.Cu")
		(net "P5E_PEX1_STN0_TX_DP<1>")
	)
	(segment
		(start 215.102694 -267.52931)
		(end 215.542622 -272.553176)
		(width 0.1651)
		(layer "In9.Cu")
		(net "P5E_PEX1_STN0_TX_DP<1>")
	)
	(segment
		(start 203.477114 -125.284738)
		(end 203.65212 -125.707394)
		(width 0.1651)
		(layer "In9.Cu")
		(net "P5E_PEX1_STN0_TX_DP<1>")
	)
	(segment
		(start 203.784962 -125.762512)
		(end 203.959714 -126.18466)
		(width 0.1651)
		(layer "In9.Cu")
		(net "P5E_PEX1_STN0_TX_DP<1>")
	)
	(segment
		(start 199.993758 -286.733742)
		(end 199.96531 -286.733742)
		(width 0.1143)
		(layer "In9.Cu")
		(net "P5E_PEX1_STN0_TX_DP<1>")
	)
	(segment
		(start 202.033886 -121.991882)
		(end 202.356974 -122.31497)
		(width 0.1651)
		(layer "In9.Cu")
		(net "P5E_PEX1_STN0_TX_DP<1>")
	)
	(segment
		(start 205.226666 -179.117498)
		(end 201.509122 -221.611444)
		(width 0.1651)
		(layer "In9.Cu")
		(net "P5E_PEX1_STN0_TX_DP<1>")
	)
	(segment
		(start 201.566526 -121.524522)
		(end 201.566526 -121.668286)
		(width 0.1651)
		(layer "In9.Cu")
		(net "P5E_PEX1_STN0_TX_DP<1>")
	)
	(segment
		(start 203.785216 -125.762512)
		(end 203.784962 -125.762512)
		(width 0.1651)
		(layer "In9.Cu")
		(net "P5E_PEX1_STN0_TX_DP<1>")
	)
	(segment
		(start 203.962762 -249.726958)
		(end 213.86927 -264.552176)
		(width 0.1651)
		(layer "In9.Cu")
		(net "P5E_PEX1_STN0_TX_DP<1>")
	)
	(segment
		(start 204.507846 -127.772668)
		(end 204.640688 -127.827786)
		(width 0.1651)
		(layer "In9.Cu")
		(net "P5E_PEX1_STN0_TX_DP<1>")
	)
	(segment
		(start 203.90485 -126.317502)
		(end 204.079856 -126.740158)
		(width 0.1651)
		(layer "In9.Cu")
		(net "P5E_PEX1_STN0_TX_DP<1>")
	)
	(segment
		(start 205.49616 -129.89306)
		(end 206.146908 -131.463796)
		(width 0.1651)
		(layer "In9.Cu")
		(net "P5E_PEX1_STN0_TX_DP<1>")
	)
	(segment
		(start 200.274174 -121.365772)
		(end 200.565004 -121.074942)
		(width 0.1651)
		(layer "In9.Cu")
		(net "P5E_PEX1_STN0_TX_DP<1>")
	)
	(segment
		(start 201.509122 -221.611444)
		(end 201.511154 -221.635828)
		(width 0.1651)
		(layer "In9.Cu")
		(net "P5E_PEX1_STN0_TX_DP<1>")
	)
	(segment
		(start 205.496414 -129.89306)
		(end 205.49616 -129.89306)
		(width 0.1651)
		(layer "In9.Cu")
		(net "P5E_PEX1_STN0_TX_DP<1>")
	)
	(segment
		(start 214.760556 -160.780222)
		(end 206.13751 -175.723042)
		(width 0.1651)
		(layer "In9.Cu")
		(net "P5E_PEX1_STN0_TX_DP<1>")
	)
	(segment
		(start 191.329564 -287.235646)
		(end 191.215264 -287.349946)
		(width 0.1143)
		(layer "In9.Cu")
		(net "P5E_PEX1_STN0_TX_DP<1>")
	)
	(segment
		(start 201.890122 -121.991882)
		(end 202.033886 -121.991882)
		(width 0.1651)
		(layer "In9.Cu")
		(net "P5E_PEX1_STN0_TX_DP<1>")
	)
	(segment
		(start 191.329564 -286.994854)
		(end 191.329564 -287.235646)
		(width 0.1143)
		(layer "In9.Cu")
		(net "P5E_PEX1_STN0_TX_DP<1>")
	)
	(segment
		(start 201.566526 -121.668286)
		(end 201.890122 -121.991882)
		(width 0.1651)
		(layer "In9.Cu")
		(net "P5E_PEX1_STN0_TX_DP<1>")
	)
	(segment
		(start 204.212952 -126.795022)
		(end 204.212698 -126.795022)
		(width 0.1651)
		(layer "In9.Cu")
		(net "P5E_PEX1_STN0_TX_DP<1>")
	)
	(segment
		(start 215.542622 -272.553176)
		(end 214.027258 -276.212046)
		(width 0.1651)
		(layer "In9.Cu")
		(net "P5E_PEX1_STN0_TX_DP<1>")
	)
	(segment
		(start 204.640688 -127.827786)
		(end 204.81544 -128.249934)
		(width 0.1651)
		(layer "In9.Cu")
		(net "P5E_PEX1_STN0_TX_DP<1>")
	)
	(segment
		(start 201.116946 -121.074942)
		(end 201.566526 -121.524522)
		(width 0.1651)
		(layer "In9.Cu")
		(net "P5E_PEX1_STN0_TX_DP<1>")
	)
	(segment
		(start 201.68108 -286.733742)
		(end 199.993758 -286.733742)
		(width 0.1651)
		(layer "In9.Cu")
		(net "P5E_PEX1_STN0_TX_DP<1>")
	)
	(segment
		(start 204.38745 -127.21717)
		(end 204.387704 -127.21717)
		(width 0.1651)
		(layer "In9.Cu")
		(net "P5E_PEX1_STN0_TX_DP<1>")
	)
	(segment
		(start 213.86927 -264.552176)
		(end 214.485982 -266.04087)
		(width 0.1651)
		(layer "In9.Cu")
		(net "P5E_PEX1_STN0_TX_DP<1>")
	)
	(segment
		(start 191.544956 -286.779462)
		(end 191.329564 -286.994854)
		(width 0.1143)
		(layer "In9.Cu")
		(net "P5E_PEX1_STN0_TX_DP<1>")
	)
	(segment
		(start 214.485982 -266.04087)
		(end 215.102694 -267.52931)
		(width 0.1651)
		(layer "In9.Cu")
		(net "P5E_PEX1_STN0_TX_DP<1>")
	)
	(segment
		(start 200.565004 -121.074942)
		(end 201.116946 -121.074942)
		(width 0.1651)
		(layer "In9.Cu")
		(net "P5E_PEX1_STN0_TX_DP<1>")
	)
	(segment
		(start 203.531978 -125.15215)
		(end 203.477114 -125.284738)
		(width 0.1651)
		(layer "In9.Cu")
		(net "P5E_PEX1_STN0_TX_DP<1>")
	)
	(segment
		(start 215.021922 -159.802068)
		(end 214.760556 -160.780222)
		(width 0.1651)
		(layer "In9.Cu")
		(net "P5E_PEX1_STN0_TX_DP<1>")
	)
	(segment
		(start 206.417164 -131.734306)
		(end 215.021922 -152.507442)
		(width 0.1651)
		(layer "In9.Cu")
		(net "P5E_PEX1_STN0_TX_DP<1>")
	)
	(segment
		(start 203.959714 -126.18466)
		(end 203.90485 -126.317502)
		(width 0.1651)
		(layer "In9.Cu")
		(net "P5E_PEX1_STN0_TX_DP<1>")
	)
	(segment
		(start 202.78471 -123.347734)
		(end 203.531978 -125.15215)
		(width 0.1651)
		(layer "In9.Cu")
		(net "P5E_PEX1_STN0_TX_DP<1>")
	)
	(segment
		(start 204.079856 -126.740158)
		(end 204.212952 -126.795022)
		(width 0.1651)
		(layer "In9.Cu")
		(net "P5E_PEX1_STN0_TX_DP<1>")
	)
	(segment
		(start 206.13751 -175.723042)
		(end 205.226666 -179.117498)
		(width 0.1651)
		(layer "In9.Cu")
		(net "P5E_PEX1_STN0_TX_DP<1>")
	)
	(segment
		(start 205.188312 -129.41554)
		(end 205.363318 -129.838196)
		(width 0.1651)
		(layer "In9.Cu")
		(net "P5E_PEX1_STN0_TX_DP<1>")
	)
	(segment
		(start 191.215264 -287.349946)
		(end 190.949834 -287.349946)
		(width 0.1143)
		(layer "In9.Cu")
		(net "P5E_PEX1_STN0_TX_DP<1>")
	)
	(segment
		(start 215.021922 -152.507442)
		(end 215.021922 -159.802068)
		(width 0.1651)
		(layer "In9.Cu")
		(net "P5E_PEX1_STN0_TX_DP<1>")
	)
	(segment
		(start 199.96531 -286.733742)
		(end 199.91959 -286.779462)
		(width 0.1143)
		(layer "In9.Cu")
		(net "P5E_PEX1_STN0_TX_DP<1>")
	)
	(segment
		(start 204.387704 -127.21717)
		(end 204.33284 -127.350012)
		(width 0.1651)
		(layer "In9.Cu")
		(net "P5E_PEX1_STN0_TX_DP<1>")
	)
	(segment
		(start 202.651868 -123.292616)
		(end 202.78471 -123.347734)
		(width 0.1651)
		(layer "In9.Cu")
		(net "P5E_PEX1_STN0_TX_DP<1>")
	)
	(segment
		(start 204.212698 -126.795022)
		(end 204.38745 -127.21717)
		(width 0.1651)
		(layer "In9.Cu")
		(net "P5E_PEX1_STN0_TX_DP<1>")
	)
	(segment
		(start 205.363318 -129.838196)
		(end 205.496414 -129.89306)
		(width 0.1651)
		(layer "In9.Cu")
		(net "P5E_PEX1_STN0_TX_DP<1>")
	)
	(segment
		(start 202.531726 -122.737118)
		(end 202.476862 -122.86996)
		(width 0.1651)
		(layer "In9.Cu")
		(net "P5E_PEX1_STN0_TX_DP<1>")
	)
	(segment
		(start 203.65212 -125.707394)
		(end 203.785216 -125.762512)
		(width 0.1651)
		(layer "In9.Cu")
		(net "P5E_PEX1_STN0_TX_DP<1>")
	)
	(segment
		(start 204.760576 -128.382776)
		(end 204.935582 -128.805432)
		(width 0.1651)
		(layer "In9.Cu")
		(net "P5E_PEX1_STN0_TX_DP<1>")
	)
	(segment
		(start 204.81544 -128.249934)
		(end 204.760576 -128.382776)
		(width 0.1651)
		(layer "In9.Cu")
		(net "P5E_PEX1_STN0_TX_DP<1>")
	)
	(segment
		(start 201.511154 -221.635828)
		(end 201.511408 -221.635828)
		(width 0.1651)
		(layer "In9.Cu")
		(net "P5E_PEX1_STN0_TX_DP<1>")
	)
	(segment
		(start 137.179558 -365.933736)
		(end 137.29843 -365.974884)
		(width 0.1651)
		(layer "In15.Cu")
		(net "P5E_PEX1_STN5_RX_DP<95>")
	)
	(segment
		(start 131.658614 -372.099078)
		(end 132.217922 -371.53977)
		(width 0.1651)
		(layer "In15.Cu")
		(net "P5E_PEX1_STN5_RX_DP<95>")
	)
	(segment
		(start 188.479684 -318.406272)
		(end 188.75629 -318.129666)
		(width 0.1143)
		(layer "In15.Cu")
		(net "P5E_PEX1_STN5_RX_DP<95>")
	)
	(segment
		(start 188.961014 -318.129666)
		(end 189.049914 -318.040766)
		(width 0.1143)
		(layer "In15.Cu")
		(net "P5E_PEX1_STN5_RX_DP<95>")
	)
	(segment
		(start 131.310126 -371.590062)
		(end 131.310126 -371.972078)
		(width 0.1651)
		(layer "In15.Cu")
		(net "P5E_PEX1_STN5_RX_DP<95>")
	)
	(segment
		(start 132.217922 -371.53977)
		(end 132.217922 -369.156234)
		(width 0.1651)
		(layer "In15.Cu")
		(net "P5E_PEX1_STN5_RX_DP<95>")
	)
	(segment
		(start 188.433964 -321.500754)
		(end 188.433964 -319.916048)
		(width 0.1651)
		(layer "In15.Cu")
		(net "P5E_PEX1_STN5_RX_DP<95>")
	)
	(segment
		(start 182.663338 -328.454004)
		(end 186.957208 -324.160134)
		(width 0.1651)
		(layer "In15.Cu")
		(net "P5E_PEX1_STN5_RX_DP<95>")
	)
	(segment
		(start 136.12876 -366.444784)
		(end 136.247632 -366.485932)
		(width 0.1651)
		(layer "In15.Cu")
		(net "P5E_PEX1_STN5_RX_DP<95>")
	)
	(segment
		(start 135.642096 -366.780572)
		(end 135.68299 -366.6617)
		(width 0.1651)
		(layer "In15.Cu")
		(net "P5E_PEX1_STN5_RX_DP<95>")
	)
	(segment
		(start 136.692894 -366.269524)
		(end 136.734042 -366.150652)
		(width 0.1651)
		(layer "In15.Cu")
		(net "P5E_PEX1_STN5_RX_DP<95>")
	)
	(segment
		(start 186.957208 -324.160134)
		(end 188.164978 -322.198746)
		(width 0.1651)
		(layer "In15.Cu")
		(net "P5E_PEX1_STN5_RX_DP<95>")
	)
	(segment
		(start 136.69264 -366.269524)
		(end 136.692894 -366.269524)
		(width 0.1651)
		(layer "In15.Cu")
		(net "P5E_PEX1_STN5_RX_DP<95>")
	)
	(segment
		(start 135.68299 -366.6617)
		(end 136.12876 -366.444784)
		(width 0.1651)
		(layer "In15.Cu")
		(net "P5E_PEX1_STN5_RX_DP<95>")
	)
	(segment
		(start 169.55135 -337.149186)
		(end 182.663338 -328.454004)
		(width 0.1651)
		(layer "In15.Cu")
		(net "P5E_PEX1_STN5_RX_DP<95>")
	)
	(segment
		(start 188.433964 -319.8876)
		(end 188.479684 -319.84188)
		(width 0.1143)
		(layer "In15.Cu")
		(net "P5E_PEX1_STN5_RX_DP<95>")
	)
	(segment
		(start 137.743692 -365.758476)
		(end 137.78484 -365.639604)
		(width 0.1651)
		(layer "In15.Cu")
		(net "P5E_PEX1_STN5_RX_DP<95>")
	)
	(segment
		(start 137.29843 -365.974884)
		(end 137.743692 -365.758476)
		(width 0.1651)
		(layer "In15.Cu")
		(net "P5E_PEX1_STN5_RX_DP<95>")
	)
	(segment
		(start 163.371784 -342.289638)
		(end 169.55135 -337.149186)
		(width 0.1651)
		(layer "In15.Cu")
		(net "P5E_PEX1_STN5_RX_DP<95>")
	)
	(segment
		(start 188.75629 -318.129666)
		(end 188.961014 -318.129666)
		(width 0.1143)
		(layer "In15.Cu")
		(net "P5E_PEX1_STN5_RX_DP<95>")
	)
	(segment
		(start 138.23061 -365.422688)
		(end 138.349228 -365.463836)
		(width 0.1651)
		(layer "In15.Cu")
		(net "P5E_PEX1_STN5_RX_DP<95>")
	)
	(segment
		(start 135.642096 -366.780318)
		(end 135.642096 -366.780572)
		(width 0.1651)
		(layer "In15.Cu")
		(net "P5E_PEX1_STN5_RX_DP<95>")
	)
	(segment
		(start 146.606514 -360.615738)
		(end 148.244814 -358.657144)
		(width 0.1651)
		(layer "In15.Cu")
		(net "P5E_PEX1_STN5_RX_DP<95>")
	)
	(segment
		(start 133.19887 -367.96853)
		(end 135.642096 -366.780318)
		(width 0.1651)
		(layer "In15.Cu")
		(net "P5E_PEX1_STN5_RX_DP<95>")
	)
	(segment
		(start 132.217922 -369.156234)
		(end 132.654802 -368.45748)
		(width 0.1651)
		(layer "In15.Cu")
		(net "P5E_PEX1_STN5_RX_DP<95>")
	)
	(segment
		(start 136.734042 -366.150652)
		(end 137.179558 -365.933736)
		(width 0.1651)
		(layer "In15.Cu")
		(net "P5E_PEX1_STN5_RX_DP<95>")
	)
	(segment
		(start 136.247632 -366.485932)
		(end 136.69264 -366.269524)
		(width 0.1651)
		(layer "In15.Cu")
		(net "P5E_PEX1_STN5_RX_DP<95>")
	)
	(segment
		(start 148.244814 -358.657144)
		(end 163.371784 -342.289638)
		(width 0.1651)
		(layer "In15.Cu")
		(net "P5E_PEX1_STN5_RX_DP<95>")
	)
	(segment
		(start 189.049914 -318.040766)
		(end 189.049914 -317.749936)
		(width 0.1143)
		(layer "In15.Cu")
		(net "P5E_PEX1_STN5_RX_DP<95>")
	)
	(segment
		(start 188.479684 -319.84188)
		(end 188.479684 -318.406272)
		(width 0.1143)
		(layer "In15.Cu")
		(net "P5E_PEX1_STN5_RX_DP<95>")
	)
	(segment
		(start 188.433964 -319.916048)
		(end 188.433964 -319.8876)
		(width 0.1143)
		(layer "In15.Cu")
		(net "P5E_PEX1_STN5_RX_DP<95>")
	)
	(segment
		(start 131.310126 -371.972078)
		(end 131.437126 -372.099078)
		(width 0.1651)
		(layer "In15.Cu")
		(net "P5E_PEX1_STN5_RX_DP<95>")
	)
	(segment
		(start 143.78686 -362.819696)
		(end 146.606514 -360.615738)
		(width 0.1651)
		(layer "In15.Cu")
		(net "P5E_PEX1_STN5_RX_DP<95>")
	)
	(segment
		(start 188.164978 -322.198746)
		(end 188.433964 -321.500754)
		(width 0.1651)
		(layer "In15.Cu")
		(net "P5E_PEX1_STN5_RX_DP<95>")
	)
	(segment
		(start 131.437126 -372.099078)
		(end 131.658614 -372.099078)
		(width 0.1651)
		(layer "In15.Cu")
		(net "P5E_PEX1_STN5_RX_DP<95>")
	)
	(segment
		(start 132.654802 -368.45748)
		(end 133.19887 -367.96853)
		(width 0.1651)
		(layer "In15.Cu")
		(net "P5E_PEX1_STN5_RX_DP<95>")
	)
	(segment
		(start 137.78484 -365.639604)
		(end 138.23061 -365.422688)
		(width 0.1651)
		(layer "In15.Cu")
		(net "P5E_PEX1_STN5_RX_DP<95>")
	)
	(segment
		(start 138.349228 -365.463836)
		(end 143.78686 -362.819696)
		(width 0.1651)
		(layer "In15.Cu")
		(net "P5E_PEX1_STN5_RX_DP<95>")
	)
	(segment
		(start 90.216482 -357.75773)
		(end 89.921842 -357.46309)
		(width 0.13462)
		(layer "F.Cu")
		(net "P5E_PEX0_STN5_TX_C_DN<94>")
	)
	(segment
		(start 89.921842 -357.46309)
		(end 89.921842 -356.831646)
		(width 0.13462)
		(layer "F.Cu")
		(net "P5E_PEX0_STN5_TX_C_DN<94>")
	)
	(segment
		(start 89.921842 -356.831646)
		(end 90.241882 -356.511606)
		(width 0.13462)
		(layer "F.Cu")
		(net "P5E_PEX0_STN5_TX_C_DN<94>")
	)
	(segment
		(start 85.689948 -379.08103)
		(end 86.284054 -378.486924)
		(width 0.1651)
		(layer "In7.Cu")
		(net "P5E_PEX0_STN5_TX_C_DN<94>")
	)
	(segment
		(start 85.236812 -379.08103)
		(end 85.689948 -379.08103)
		(width 0.1651)
		(layer "In7.Cu")
		(net "P5E_PEX0_STN5_TX_C_DN<94>")
	)
	(segment
		(start 86.284054 -378.486924)
		(end 86.284054 -367.916968)
		(width 0.1651)
		(layer "In7.Cu")
		(net "P5E_PEX0_STN5_TX_C_DN<94>")
	)
	(segment
		(start 86.284054 -367.916968)
		(end 89.904316 -359.177082)
		(width 0.1651)
		(layer "In7.Cu")
		(net "P5E_PEX0_STN5_TX_C_DN<94>")
	)
	(segment
		(start 85.109812 -379.20803)
		(end 85.236812 -379.08103)
		(width 0.1651)
		(layer "In7.Cu")
		(net "P5E_PEX0_STN5_TX_C_DN<94>")
	)
	(segment
		(start 85.109812 -379.590046)
		(end 85.109812 -379.20803)
		(width 0.1651)
		(layer "In7.Cu")
		(net "P5E_PEX0_STN5_TX_C_DN<94>")
	)
	(segment
		(start 89.925652 -358.04856)
		(end 90.216482 -357.75773)
		(width 0.1651)
		(layer "In7.Cu")
		(net "P5E_PEX0_STN5_TX_C_DN<94>")
	)
	(segment
		(start 89.925652 -359.155746)
		(end 89.925652 -358.04856)
		(width 0.1651)
		(layer "In7.Cu")
		(net "P5E_PEX0_STN5_TX_C_DN<94>")
	)
	(segment
		(start 89.904316 -359.177082)
		(end 89.925652 -359.155746)
		(width 0.1651)
		(layer "In7.Cu")
		(net "P5E_PEX0_STN5_TX_C_DN<94>")
	)
	(segment
		(start 36.051744 -131.003294)
		(end 35.4203 -131.003294)
		(width 0.13462)
		(layer "F.Cu")
		(net "P5E_PEX0_STN1_TX_DN<28>")
	)
	(segment
		(start 36.371784 -131.323334)
		(end 36.051744 -131.003294)
		(width 0.13462)
		(layer "F.Cu")
		(net "P5E_PEX0_STN1_TX_DN<28>")
	)
	(segment
		(start 35.4203 -131.003294)
		(end 35.12566 -131.297934)
		(width 0.13462)
		(layer "F.Cu")
		(net "P5E_PEX0_STN1_TX_DN<28>")
	)
	(segment
		(start 32.556958 -137.09777)
		(end 32.618934 -136.948418)
		(width 0.1651)
		(layer "In9.Cu")
		(net "P5E_PEX0_STN1_TX_DN<28>")
	)
	(segment
		(start 71.049642 -277.849838)
		(end 71.049642 -278.115268)
		(width 0.1143)
		(layer "In9.Cu")
		(net "P5E_PEX0_STN1_TX_DN<28>")
	)
	(segment
		(start 70.773544 -278.229568)
		(end 70.670166 -278.12619)
		(width 0.1143)
		(layer "In9.Cu")
		(net "P5E_PEX0_STN1_TX_DN<28>")
	)
	(segment
		(start 33.245044 -132.56387)
		(end 33.213548 -132.40512)
		(width 0.1651)
		(layer "In9.Cu")
		(net "P5E_PEX0_STN1_TX_DN<28>")
	)
	(segment
		(start 33.481518 -132.004054)
		(end 33.640014 -131.972558)
		(width 0.1651)
		(layer "In9.Cu")
		(net "P5E_PEX0_STN1_TX_DN<28>")
	)
	(segment
		(start 33.013904 -138.200892)
		(end 33.07588 -138.05154)
		(width 0.1651)
		(layer "In9.Cu")
		(net "P5E_PEX0_STN1_TX_DN<28>")
	)
	(segment
		(start 33.07588 -138.05154)
		(end 32.891222 -137.605262)
		(width 0.1651)
		(layer "In9.Cu")
		(net "P5E_PEX0_STN1_TX_DN<28>")
	)
	(segment
		(start 32.28467 -136.440418)
		(end 32.100012 -135.994648)
		(width 0.1651)
		(layer "In9.Cu")
		(net "P5E_PEX0_STN1_TX_DN<28>")
	)
	(segment
		(start 70.670166 -278.12619)
		(end 70.670166 -271.546066)
		(width 0.1143)
		(layer "In9.Cu")
		(net "P5E_PEX0_STN1_TX_DN<28>")
	)
	(segment
		(start 36.249356 -161.566352)
		(end 35.966654 -160.144714)
		(width 0.1651)
		(layer "In9.Cu")
		(net "P5E_PEX0_STN1_TX_DN<28>")
	)
	(segment
		(start 33.198562 -138.646662)
		(end 33.013904 -138.200892)
		(width 0.1651)
		(layer "In9.Cu")
		(net "P5E_PEX0_STN1_TX_DN<28>")
	)
	(segment
		(start 33.80486 -139.811506)
		(end 33.655508 -139.749784)
		(width 0.1651)
		(layer "In9.Cu")
		(net "P5E_PEX0_STN1_TX_DN<28>")
	)
	(segment
		(start 32.818324 -132.99694)
		(end 32.97682 -132.96519)
		(width 0.1651)
		(layer "In9.Cu")
		(net "P5E_PEX0_STN1_TX_DN<28>")
	)
	(segment
		(start 71.049642 -278.115268)
		(end 70.935342 -278.229568)
		(width 0.1143)
		(layer "In9.Cu")
		(net "P5E_PEX0_STN1_TX_DN<28>")
	)
	(segment
		(start 70.670166 -271.546066)
		(end 70.715886 -271.500346)
		(width 0.1143)
		(layer "In9.Cu")
		(net "P5E_PEX0_STN1_TX_DN<28>")
	)
	(segment
		(start 33.989518 -140.257784)
		(end 33.80486 -139.811506)
		(width 0.1651)
		(layer "In9.Cu")
		(net "P5E_PEX0_STN1_TX_DN<28>")
	)
	(segment
		(start 33.655508 -139.749784)
		(end 33.47085 -139.304014)
		(width 0.1651)
		(layer "In9.Cu")
		(net "P5E_PEX0_STN1_TX_DN<28>")
	)
	(segment
		(start 34.1122 -140.852906)
		(end 33.927796 -140.407136)
		(width 0.1651)
		(layer "In9.Cu")
		(net "P5E_PEX0_STN1_TX_DN<28>")
	)
	(segment
		(start 35.966654 -160.144714)
		(end 35.684206 -158.72333)
		(width 0.1651)
		(layer "In9.Cu")
		(net "P5E_PEX0_STN1_TX_DN<28>")
	)
	(segment
		(start 70.935342 -278.229568)
		(end 70.773544 -278.229568)
		(width 0.1143)
		(layer "In9.Cu")
		(net "P5E_PEX0_STN1_TX_DN<28>")
	)
	(segment
		(start 35.545522 -158.025592)
		(end 35.451288 -157.55239)
		(width 0.1651)
		(layer "In9.Cu")
		(net "P5E_PEX0_STN1_TX_DN<28>")
	)
	(segment
		(start 32.434276 -136.50214)
		(end 32.28467 -136.440418)
		(width 0.1651)
		(layer "In9.Cu")
		(net "P5E_PEX0_STN1_TX_DN<28>")
	)
	(segment
		(start 33.640014 -131.972558)
		(end 33.908492 -131.570984)
		(width 0.1651)
		(layer "In9.Cu")
		(net "P5E_PEX0_STN1_TX_DN<28>")
	)
	(segment
		(start 34.699702 -142.270734)
		(end 34.384742 -141.510258)
		(width 0.1651)
		(layer "In9.Cu")
		(net "P5E_PEX0_STN1_TX_DN<28>")
	)
	(segment
		(start 32.618934 -136.948418)
		(end 32.434276 -136.50214)
		(width 0.1651)
		(layer "In9.Cu")
		(net "P5E_PEX0_STN1_TX_DN<28>")
	)
	(segment
		(start 70.715886 -263.383776)
		(end 36.249356 -161.566352)
		(width 0.1651)
		(layer "In9.Cu")
		(net "P5E_PEX0_STN1_TX_DN<28>")
	)
	(segment
		(start 34.446464 -141.360906)
		(end 34.261806 -140.914882)
		(width 0.1651)
		(layer "In9.Cu")
		(net "P5E_PEX0_STN1_TX_DN<28>")
	)
	(segment
		(start 32.891222 -137.605262)
		(end 32.741616 -137.54354)
		(width 0.1651)
		(layer "In9.Cu")
		(net "P5E_PEX0_STN1_TX_DN<28>")
	)
	(segment
		(start 35.774122 -158.588964)
		(end 35.679888 -158.115508)
		(width 0.1651)
		(layer "In9.Cu")
		(net "P5E_PEX0_STN1_TX_DN<28>")
	)
	(segment
		(start 70.715886 -271.471898)
		(end 70.715886 -263.383776)
		(width 0.1651)
		(layer "In9.Cu")
		(net "P5E_PEX0_STN1_TX_DN<28>")
	)
	(segment
		(start 33.927796 -140.407136)
		(end 33.989518 -140.257784)
		(width 0.1651)
		(layer "In9.Cu")
		(net "P5E_PEX0_STN1_TX_DN<28>")
	)
	(segment
		(start 35.684206 -158.72333)
		(end 35.774122 -158.588964)
		(width 0.1651)
		(layer "In9.Cu")
		(net "P5E_PEX0_STN1_TX_DN<28>")
	)
	(segment
		(start 34.83483 -131.007104)
		(end 35.12566 -131.297934)
		(width 0.1651)
		(layer "In9.Cu")
		(net "P5E_PEX0_STN1_TX_DN<28>")
	)
	(segment
		(start 34.384742 -141.510258)
		(end 34.446464 -141.360906)
		(width 0.1651)
		(layer "In9.Cu")
		(net "P5E_PEX0_STN1_TX_DN<28>")
	)
	(segment
		(start 35.679888 -158.115508)
		(end 35.545268 -158.025592)
		(width 0.1651)
		(layer "In9.Cu")
		(net "P5E_PEX0_STN1_TX_DN<28>")
	)
	(segment
		(start 32.97682 -132.96519)
		(end 33.245044 -132.56387)
		(width 0.1651)
		(layer "In9.Cu")
		(net "P5E_PEX0_STN1_TX_DN<28>")
	)
	(segment
		(start 32.343852 -133.707124)
		(end 32.818324 -132.99694)
		(width 0.1651)
		(layer "In9.Cu")
		(net "P5E_PEX0_STN1_TX_DN<28>")
	)
	(segment
		(start 34.26079 -131.007104)
		(end 34.83483 -131.007104)
		(width 0.1651)
		(layer "In9.Cu")
		(net "P5E_PEX0_STN1_TX_DN<28>")
	)
	(segment
		(start 32.741616 -137.54354)
		(end 32.556958 -137.09777)
		(width 0.1651)
		(layer "In9.Cu")
		(net "P5E_PEX0_STN1_TX_DN<28>")
	)
	(segment
		(start 33.908492 -131.570984)
		(end 33.876996 -131.412488)
		(width 0.1651)
		(layer "In9.Cu")
		(net "P5E_PEX0_STN1_TX_DN<28>")
	)
	(segment
		(start 33.532826 -139.154662)
		(end 33.348168 -138.708384)
		(width 0.1651)
		(layer "In9.Cu")
		(net "P5E_PEX0_STN1_TX_DN<28>")
	)
	(segment
		(start 32.100012 -134.295642)
		(end 32.343852 -133.707124)
		(width 0.1651)
		(layer "In9.Cu")
		(net "P5E_PEX0_STN1_TX_DN<28>")
	)
	(segment
		(start 33.47085 -139.304014)
		(end 33.532826 -139.154662)
		(width 0.1651)
		(layer "In9.Cu")
		(net "P5E_PEX0_STN1_TX_DN<28>")
	)
	(segment
		(start 33.213548 -132.40512)
		(end 33.481518 -132.004054)
		(width 0.1651)
		(layer "In9.Cu")
		(net "P5E_PEX0_STN1_TX_DN<28>")
	)
	(segment
		(start 33.876996 -131.412488)
		(end 34.085022 -131.101084)
		(width 0.1651)
		(layer "In9.Cu")
		(net "P5E_PEX0_STN1_TX_DN<28>")
	)
	(segment
		(start 33.348168 -138.708384)
		(end 33.198562 -138.646662)
		(width 0.1651)
		(layer "In9.Cu")
		(net "P5E_PEX0_STN1_TX_DN<28>")
	)
	(segment
		(start 35.545268 -158.025592)
		(end 35.545522 -158.025592)
		(width 0.1651)
		(layer "In9.Cu")
		(net "P5E_PEX0_STN1_TX_DN<28>")
	)
	(segment
		(start 34.085022 -131.101084)
		(end 34.26079 -131.007104)
		(width 0.1651)
		(layer "In9.Cu")
		(net "P5E_PEX0_STN1_TX_DN<28>")
	)
	(segment
		(start 34.261806 -140.914882)
		(end 34.1122 -140.852906)
		(width 0.1651)
		(layer "In9.Cu")
		(net "P5E_PEX0_STN1_TX_DN<28>")
	)
	(segment
		(start 70.715886 -271.500346)
		(end 70.715886 -271.471898)
		(width 0.1143)
		(layer "In9.Cu")
		(net "P5E_PEX0_STN1_TX_DN<28>")
	)
	(segment
		(start 35.451288 -157.55239)
		(end 34.699702 -142.270734)
		(width 0.1651)
		(layer "In9.Cu")
		(net "P5E_PEX0_STN1_TX_DN<28>")
	)
	(segment
		(start 32.100012 -135.994648)
		(end 32.100012 -134.295642)
		(width 0.1651)
		(layer "In9.Cu")
		(net "P5E_PEX0_STN1_TX_DN<28>")
	)
	(segment
		(start 22.416008 -355.978206)
		(end 22.736048 -355.658166)
		(width 0.13462)
		(layer "F.Cu")
		(net "P5E_PEX0_STN7_TX_DP<114>")
	)
	(segment
		(start 22.736048 -355.658166)
		(end 22.736048 -355.026722)
		(width 0.13462)
		(layer "F.Cu")
		(net "P5E_PEX0_STN7_TX_DP<114>")
	)
	(segment
		(start 22.736048 -355.026722)
		(end 22.441408 -354.732082)
		(width 0.13462)
		(layer "F.Cu")
		(net "P5E_PEX0_STN7_TX_DP<114>")
	)
	(segment
		(start 24.286718 -352.270822)
		(end 24.286718 -341.904066)
		(width 0.1651)
		(layer "In7.Cu")
		(net "P5E_PEX0_STN7_TX_DP<114>")
	)
	(segment
		(start 35.65652 -302.929544)
		(end 41.94429 -302.929544)
		(width 0.1143)
		(layer "In7.Cu")
		(net "P5E_PEX0_STN7_TX_DP<114>")
	)
	(segment
		(start 22.732238 -354.441252)
		(end 22.732238 -353.825302)
		(width 0.1651)
		(layer "In7.Cu")
		(net "P5E_PEX0_STN7_TX_DP<114>")
	)
	(segment
		(start 22.441408 -354.732082)
		(end 22.732238 -354.441252)
		(width 0.1651)
		(layer "In7.Cu")
		(net "P5E_PEX0_STN7_TX_DP<114>")
	)
	(segment
		(start 24.286718 -341.904066)
		(end 18.805144 -323.833998)
		(width 0.1651)
		(layer "In7.Cu")
		(net "P5E_PEX0_STN7_TX_DP<114>")
	)
	(segment
		(start 27.36723 -304.66792)
		(end 31.674816 -302.883824)
		(width 0.1651)
		(layer "In7.Cu")
		(net "P5E_PEX0_STN7_TX_DP<114>")
	)
	(segment
		(start 35.582352 -302.883824)
		(end 35.6108 -302.883824)
		(width 0.1143)
		(layer "In7.Cu")
		(net "P5E_PEX0_STN7_TX_DP<114>")
	)
	(segment
		(start 22.732238 -353.825302)
		(end 24.286718 -352.270822)
		(width 0.1651)
		(layer "In7.Cu")
		(net "P5E_PEX0_STN7_TX_DP<114>")
	)
	(segment
		(start 20.282662 -314.776104)
		(end 23.455122 -310.028082)
		(width 0.1651)
		(layer "In7.Cu")
		(net "P5E_PEX0_STN7_TX_DP<114>")
	)
	(segment
		(start 41.94429 -302.929544)
		(end 42.170096 -303.15535)
		(width 0.1143)
		(layer "In7.Cu")
		(net "P5E_PEX0_STN7_TX_DP<114>")
	)
	(segment
		(start 31.674816 -302.883824)
		(end 35.582352 -302.883824)
		(width 0.1651)
		(layer "In7.Cu")
		(net "P5E_PEX0_STN7_TX_DP<114>")
	)
	(segment
		(start 26.634948 -305.268884)
		(end 27.36723 -304.66792)
		(width 0.1651)
		(layer "In7.Cu")
		(net "P5E_PEX0_STN7_TX_DP<114>")
	)
	(segment
		(start 42.170096 -303.15535)
		(end 42.170096 -303.385474)
		(width 0.1143)
		(layer "In7.Cu")
		(net "P5E_PEX0_STN7_TX_DP<114>")
	)
	(segment
		(start 18.805144 -319.69964)
		(end 19.324066 -317.08979)
		(width 0.1651)
		(layer "In7.Cu")
		(net "P5E_PEX0_STN7_TX_DP<114>")
	)
	(segment
		(start 23.455122 -310.028082)
		(end 26.634948 -305.268884)
		(width 0.1651)
		(layer "In7.Cu")
		(net "P5E_PEX0_STN7_TX_DP<114>")
	)
	(segment
		(start 19.324066 -317.08979)
		(end 20.282662 -314.776104)
		(width 0.1651)
		(layer "In7.Cu")
		(net "P5E_PEX0_STN7_TX_DP<114>")
	)
	(segment
		(start 18.805144 -323.833998)
		(end 18.805144 -319.69964)
		(width 0.1651)
		(layer "In7.Cu")
		(net "P5E_PEX0_STN7_TX_DP<114>")
	)
	(segment
		(start 42.170096 -303.385474)
		(end 42.284396 -303.499774)
		(width 0.1143)
		(layer "In7.Cu")
		(net "P5E_PEX0_STN7_TX_DP<114>")
	)
	(segment
		(start 42.284396 -303.499774)
		(end 42.549826 -303.499774)
		(width 0.1143)
		(layer "In7.Cu")
		(net "P5E_PEX0_STN7_TX_DP<114>")
	)
	(segment
		(start 35.6108 -302.883824)
		(end 35.65652 -302.929544)
		(width 0.1143)
		(layer "In7.Cu")
		(net "P5E_PEX0_STN7_TX_DP<114>")
	)
	(segment
		(start 154.793696 -121.599706)
		(end 154.162252 -121.599706)
		(width 0.13462)
		(layer "F.Cu")
		(net "P5E_PEX1_STN1_TX_DP<25>")
	)
	(segment
		(start 154.162252 -121.599706)
		(end 153.867612 -121.894346)
		(width 0.13462)
		(layer "F.Cu")
		(net "P5E_PEX1_STN1_TX_DP<25>")
	)
	(segment
		(start 155.113736 -121.919746)
		(end 154.793696 -121.599706)
		(width 0.13462)
		(layer "F.Cu")
		(net "P5E_PEX1_STN1_TX_DP<25>")
	)
	(segment
		(start 149.17166 -161.233104)
		(end 183.96585 -264.021824)
		(width 0.1651)
		(layer "In9.Cu")
		(net "P5E_PEX1_STN1_TX_DP<25>")
	)
	(segment
		(start 148.011134 -126.057406)
		(end 147.82165 -126.515368)
		(width 0.1651)
		(layer "In9.Cu")
		(net "P5E_PEX1_STN1_TX_DP<25>")
	)
	(segment
		(start 183.96585 -264.021824)
		(end 183.96585 -271.526)
		(width 0.1651)
		(layer "In9.Cu")
		(net "P5E_PEX1_STN1_TX_DP<25>")
	)
	(segment
		(start 148.569426 -158.205678)
		(end 149.17166 -161.233104)
		(width 0.1651)
		(layer "In9.Cu")
		(net "P5E_PEX1_STN1_TX_DP<25>")
	)
	(segment
		(start 145.805652 -131.08305)
		(end 145.29689 -132.31114)
		(width 0.1651)
		(layer "In9.Cu")
		(net "P5E_PEX1_STN1_TX_DP<25>")
	)
	(segment
		(start 146.61134 -129.436876)
		(end 146.421856 -129.894838)
		(width 0.1651)
		(layer "In9.Cu")
		(net "P5E_PEX1_STN1_TX_DP<25>")
	)
	(segment
		(start 147.205446 -127.70358)
		(end 147.015962 -128.161034)
		(width 0.1651)
		(layer "In9.Cu")
		(net "P5E_PEX1_STN1_TX_DP<25>")
	)
	(segment
		(start 148.138642 -125.4506)
		(end 147.949158 -125.908054)
		(width 0.1651)
		(layer "In9.Cu")
		(net "P5E_PEX1_STN1_TX_DP<25>")
	)
	(segment
		(start 145.92046 -131.035552)
		(end 145.805652 -131.08305)
		(width 0.1651)
		(layer "In9.Cu")
		(net "P5E_PEX1_STN1_TX_DP<25>")
	)
	(segment
		(start 184.18556 -280.129488)
		(end 184.29986 -280.015188)
		(width 0.1143)
		(layer "In9.Cu")
		(net "P5E_PEX1_STN1_TX_DP<25>")
	)
	(segment
		(start 183.92013 -271.600168)
		(end 183.92013 -280.025856)
		(width 0.1143)
		(layer "In9.Cu")
		(net "P5E_PEX1_STN1_TX_DP<25>")
	)
	(segment
		(start 148.754846 -124.262388)
		(end 148.60524 -124.32411)
		(width 0.1651)
		(layer "In9.Cu")
		(net "P5E_PEX1_STN1_TX_DP<25>")
	)
	(segment
		(start 184.29986 -280.015188)
		(end 184.29986 -279.749504)
		(width 0.1143)
		(layer "In9.Cu")
		(net "P5E_PEX1_STN1_TX_DP<25>")
	)
	(segment
		(start 147.838414 -143.330422)
		(end 148.569426 -158.205678)
		(width 0.1651)
		(layer "In9.Cu")
		(net "P5E_PEX1_STN1_TX_DP<25>")
	)
	(segment
		(start 151.225758 -121.603516)
		(end 150.665942 -121.603516)
		(width 0.1651)
		(layer "In9.Cu")
		(net "P5E_PEX1_STN1_TX_DP<25>")
	)
	(segment
		(start 148.288248 -125.388878)
		(end 148.138642 -125.4506)
		(width 0.1651)
		(layer "In9.Cu")
		(net "P5E_PEX1_STN1_TX_DP<25>")
	)
	(segment
		(start 148.882354 -123.655074)
		(end 148.94433 -123.804426)
		(width 0.1651)
		(layer "In9.Cu")
		(net "P5E_PEX1_STN1_TX_DP<25>")
	)
	(segment
		(start 147.077938 -128.310386)
		(end 146.888454 -128.768348)
		(width 0.1651)
		(layer "In9.Cu")
		(net "P5E_PEX1_STN1_TX_DP<25>")
	)
	(segment
		(start 146.082766 -130.414014)
		(end 146.130518 -130.528822)
		(width 0.1651)
		(layer "In9.Cu")
		(net "P5E_PEX1_STN1_TX_DP<25>")
	)
	(segment
		(start 146.549364 -129.287524)
		(end 146.61134 -129.436876)
		(width 0.1651)
		(layer "In9.Cu")
		(net "P5E_PEX1_STN1_TX_DP<25>")
	)
	(segment
		(start 152.800558 -121.603516)
		(end 152.711658 -121.692416)
		(width 0.1651)
		(layer "In9.Cu")
		(net "P5E_PEX1_STN1_TX_DP<25>")
	)
	(segment
		(start 146.27225 -129.95656)
		(end 146.082766 -130.414014)
		(width 0.1651)
		(layer "In9.Cu")
		(net "P5E_PEX1_STN1_TX_DP<25>")
	)
	(segment
		(start 146.738848 -128.83007)
		(end 146.549364 -129.287524)
		(width 0.1651)
		(layer "In9.Cu")
		(net "P5E_PEX1_STN1_TX_DP<25>")
	)
	(segment
		(start 151.314658 -121.692416)
		(end 151.225758 -121.603516)
		(width 0.1651)
		(layer "In9.Cu")
		(net "P5E_PEX1_STN1_TX_DP<25>")
	)
	(segment
		(start 147.544536 -127.183896)
		(end 147.355052 -127.641858)
		(width 0.1651)
		(layer "In9.Cu")
		(net "P5E_PEX1_STN1_TX_DP<25>")
	)
	(segment
		(start 183.92013 -280.025856)
		(end 184.023762 -280.129488)
		(width 0.1143)
		(layer "In9.Cu")
		(net "P5E_PEX1_STN1_TX_DP<25>")
	)
	(segment
		(start 149.071838 -123.19762)
		(end 148.882354 -123.655074)
		(width 0.1651)
		(layer "In9.Cu")
		(net "P5E_PEX1_STN1_TX_DP<25>")
	)
	(segment
		(start 151.721058 -121.692416)
		(end 151.314658 -121.692416)
		(width 0.1651)
		(layer "In9.Cu")
		(net "P5E_PEX1_STN1_TX_DP<25>")
	)
	(segment
		(start 145.29689 -137.195052)
		(end 147.838414 -143.330422)
		(width 0.1651)
		(layer "In9.Cu")
		(net "P5E_PEX1_STN1_TX_DP<25>")
	)
	(segment
		(start 147.48256 -127.034544)
		(end 147.544536 -127.183896)
		(width 0.1651)
		(layer "In9.Cu")
		(net "P5E_PEX1_STN1_TX_DP<25>")
	)
	(segment
		(start 146.888454 -128.768348)
		(end 146.738848 -128.83007)
		(width 0.1651)
		(layer "In9.Cu")
		(net "P5E_PEX1_STN1_TX_DP<25>")
	)
	(segment
		(start 183.96585 -271.526)
		(end 183.96585 -271.554448)
		(width 0.1143)
		(layer "In9.Cu")
		(net "P5E_PEX1_STN1_TX_DP<25>")
	)
	(segment
		(start 148.60524 -124.32411)
		(end 148.415756 -124.781564)
		(width 0.1651)
		(layer "In9.Cu")
		(net "P5E_PEX1_STN1_TX_DP<25>")
	)
	(segment
		(start 152.305258 -121.692416)
		(end 152.216358 -121.603516)
		(width 0.1651)
		(layer "In9.Cu")
		(net "P5E_PEX1_STN1_TX_DP<25>")
	)
	(segment
		(start 147.672044 -126.57709)
		(end 147.48256 -127.034544)
		(width 0.1651)
		(layer "In9.Cu")
		(net "P5E_PEX1_STN1_TX_DP<25>")
	)
	(segment
		(start 148.477732 -124.930916)
		(end 148.288248 -125.388878)
		(width 0.1651)
		(layer "In9.Cu")
		(net "P5E_PEX1_STN1_TX_DP<25>")
	)
	(segment
		(start 153.867612 -121.894346)
		(end 153.576782 -121.603516)
		(width 0.1651)
		(layer "In9.Cu")
		(net "P5E_PEX1_STN1_TX_DP<25>")
	)
	(segment
		(start 145.29689 -132.31114)
		(end 145.29689 -137.195052)
		(width 0.1651)
		(layer "In9.Cu")
		(net "P5E_PEX1_STN1_TX_DP<25>")
	)
	(segment
		(start 147.949158 -125.908054)
		(end 148.011134 -126.057406)
		(width 0.1651)
		(layer "In9.Cu")
		(net "P5E_PEX1_STN1_TX_DP<25>")
	)
	(segment
		(start 148.94433 -123.804426)
		(end 148.754846 -124.262388)
		(width 0.1651)
		(layer "In9.Cu")
		(net "P5E_PEX1_STN1_TX_DP<25>")
	)
	(segment
		(start 147.015962 -128.161034)
		(end 147.077938 -128.310386)
		(width 0.1651)
		(layer "In9.Cu")
		(net "P5E_PEX1_STN1_TX_DP<25>")
	)
	(segment
		(start 151.809958 -121.603516)
		(end 151.721058 -121.692416)
		(width 0.1651)
		(layer "In9.Cu")
		(net "P5E_PEX1_STN1_TX_DP<25>")
	)
	(segment
		(start 148.415756 -124.781564)
		(end 148.477732 -124.930916)
		(width 0.1651)
		(layer "In9.Cu")
		(net "P5E_PEX1_STN1_TX_DP<25>")
	)
	(segment
		(start 184.023762 -280.129488)
		(end 184.18556 -280.129488)
		(width 0.1143)
		(layer "In9.Cu")
		(net "P5E_PEX1_STN1_TX_DP<25>")
	)
	(segment
		(start 152.711658 -121.692416)
		(end 152.305258 -121.692416)
		(width 0.1651)
		(layer "In9.Cu")
		(net "P5E_PEX1_STN1_TX_DP<25>")
	)
	(segment
		(start 146.130518 -130.528822)
		(end 145.92046 -131.035552)
		(width 0.1651)
		(layer "In9.Cu")
		(net "P5E_PEX1_STN1_TX_DP<25>")
	)
	(segment
		(start 150.665942 -121.603516)
		(end 149.071838 -123.19762)
		(width 0.1651)
		(layer "In9.Cu")
		(net "P5E_PEX1_STN1_TX_DP<25>")
	)
	(segment
		(start 147.82165 -126.515368)
		(end 147.672044 -126.57709)
		(width 0.1651)
		(layer "In9.Cu")
		(net "P5E_PEX1_STN1_TX_DP<25>")
	)
	(segment
		(start 153.576782 -121.603516)
		(end 152.800558 -121.603516)
		(width 0.1651)
		(layer "In9.Cu")
		(net "P5E_PEX1_STN1_TX_DP<25>")
	)
	(segment
		(start 147.355052 -127.641858)
		(end 147.205446 -127.70358)
		(width 0.1651)
		(layer "In9.Cu")
		(net "P5E_PEX1_STN1_TX_DP<25>")
	)
	(segment
		(start 183.96585 -271.554448)
		(end 183.92013 -271.600168)
		(width 0.1143)
		(layer "In9.Cu")
		(net "P5E_PEX1_STN1_TX_DP<25>")
	)
	(segment
		(start 152.216358 -121.603516)
		(end 151.809958 -121.603516)
		(width 0.1651)
		(layer "In9.Cu")
		(net "P5E_PEX1_STN1_TX_DP<25>")
	)
	(segment
		(start 146.421856 -129.894838)
		(end 146.27225 -129.95656)
		(width 0.1651)
		(layer "In9.Cu")
		(net "P5E_PEX1_STN1_TX_DP<25>")
	)
	(segment
		(start 155.230068 -319.86728)
		(end 155.230068 -316.489588)
		(width 0.1143)
		(layer "In9.Cu")
		(net "P5E_PEX1_STN7_RX_DP<124>")
	)
	(segment
		(start 169.171874 -367.95075)
		(end 167.940482 -365.6203)
		(width 0.1651)
		(layer "In9.Cu")
		(net "P5E_PEX1_STN7_RX_DP<124>")
	)
	(segment
		(start 167.273986 -364.549944)
		(end 167.042338 -364.111794)
		(width 0.1651)
		(layer "In9.Cu")
		(net "P5E_PEX1_STN7_RX_DP<124>")
	)
	(segment
		(start 169.585132 -369.617752)
		(end 169.171874 -367.95075)
		(width 0.1651)
		(layer "In9.Cu")
		(net "P5E_PEX1_STN7_RX_DP<124>")
	)
	(segment
		(start 167.82034 -365.583216)
		(end 167.588692 -365.145066)
		(width 0.1651)
		(layer "In9.Cu")
		(net "P5E_PEX1_STN7_RX_DP<124>")
	)
	(segment
		(start 167.588692 -365.145066)
		(end 167.625522 -365.024924)
		(width 0.1651)
		(layer "In9.Cu")
		(net "P5E_PEX1_STN7_RX_DP<124>")
	)
	(segment
		(start 164.17925 -358.50322)
		(end 164.031422 -357.906574)
		(width 0.1651)
		(layer "In9.Cu")
		(net "P5E_PEX1_STN7_RX_DP<124>")
	)
	(segment
		(start 164.031422 -347.735398)
		(end 163.329874 -343.893648)
		(width 0.1651)
		(layer "In9.Cu")
		(net "P5E_PEX1_STN7_RX_DP<124>")
	)
	(segment
		(start 168.710102 -382.57226)
		(end 168.837102 -382.69926)
		(width 0.1651)
		(layer "In9.Cu")
		(net "P5E_PEX1_STN7_RX_DP<124>")
	)
	(segment
		(start 169.058844 -382.69926)
		(end 169.585132 -382.172972)
		(width 0.1651)
		(layer "In9.Cu")
		(net "P5E_PEX1_STN7_RX_DP<124>")
	)
	(segment
		(start 168.837102 -382.69926)
		(end 169.058844 -382.69926)
		(width 0.1651)
		(layer "In9.Cu")
		(net "P5E_PEX1_STN7_RX_DP<124>")
	)
	(segment
		(start 164.031422 -357.906574)
		(end 164.031422 -347.735398)
		(width 0.1651)
		(layer "In9.Cu")
		(net "P5E_PEX1_STN7_RX_DP<124>")
	)
	(segment
		(start 167.940482 -365.6203)
		(end 167.82034 -365.583216)
		(width 0.1651)
		(layer "In9.Cu")
		(net "P5E_PEX1_STN7_RX_DP<124>")
	)
	(segment
		(start 155.800044 -316.140592)
		(end 155.800044 -315.849762)
		(width 0.1143)
		(layer "In9.Cu")
		(net "P5E_PEX1_STN7_RX_DP<124>")
	)
	(segment
		(start 166.848028 -363.553756)
		(end 166.727886 -363.516672)
		(width 0.1651)
		(layer "In9.Cu")
		(net "P5E_PEX1_STN7_RX_DP<124>")
	)
	(segment
		(start 166.533322 -362.95838)
		(end 164.17925 -358.50322)
		(width 0.1651)
		(layer "In9.Cu")
		(net "P5E_PEX1_STN7_RX_DP<124>")
	)
	(segment
		(start 167.042338 -364.111794)
		(end 167.079422 -363.991652)
		(width 0.1651)
		(layer "In9.Cu")
		(net "P5E_PEX1_STN7_RX_DP<124>")
	)
	(segment
		(start 169.585132 -382.172972)
		(end 169.585132 -369.617752)
		(width 0.1651)
		(layer "In9.Cu")
		(net "P5E_PEX1_STN7_RX_DP<124>")
	)
	(segment
		(start 163.329874 -343.893648)
		(end 155.56484 -323.343524)
		(width 0.1651)
		(layer "In9.Cu")
		(net "P5E_PEX1_STN7_RX_DP<124>")
	)
	(segment
		(start 155.184348 -319.913)
		(end 155.230068 -319.86728)
		(width 0.1143)
		(layer "In9.Cu")
		(net "P5E_PEX1_STN7_RX_DP<124>")
	)
	(segment
		(start 155.56484 -323.343524)
		(end 155.184348 -321.26047)
		(width 0.1651)
		(layer "In9.Cu")
		(net "P5E_PEX1_STN7_RX_DP<124>")
	)
	(segment
		(start 155.230068 -316.489588)
		(end 155.490164 -316.229492)
		(width 0.1143)
		(layer "In9.Cu")
		(net "P5E_PEX1_STN7_RX_DP<124>")
	)
	(segment
		(start 168.710102 -382.18999)
		(end 168.710102 -382.57226)
		(width 0.1651)
		(layer "In9.Cu")
		(net "P5E_PEX1_STN7_RX_DP<124>")
	)
	(segment
		(start 155.184348 -321.26047)
		(end 155.184348 -319.941448)
		(width 0.1651)
		(layer "In9.Cu")
		(net "P5E_PEX1_STN7_RX_DP<124>")
	)
	(segment
		(start 167.079422 -363.991652)
		(end 166.848028 -363.553756)
		(width 0.1651)
		(layer "In9.Cu")
		(net "P5E_PEX1_STN7_RX_DP<124>")
	)
	(segment
		(start 155.184348 -319.941448)
		(end 155.184348 -319.913)
		(width 0.1143)
		(layer "In9.Cu")
		(net "P5E_PEX1_STN7_RX_DP<124>")
	)
	(segment
		(start 167.394128 -364.587028)
		(end 167.273986 -364.549944)
		(width 0.1651)
		(layer "In9.Cu")
		(net "P5E_PEX1_STN7_RX_DP<124>")
	)
	(segment
		(start 166.727886 -363.516672)
		(end 166.496238 -363.078522)
		(width 0.1651)
		(layer "In9.Cu")
		(net "P5E_PEX1_STN7_RX_DP<124>")
	)
	(segment
		(start 166.496238 -363.078522)
		(end 166.533322 -362.95838)
		(width 0.1651)
		(layer "In9.Cu")
		(net "P5E_PEX1_STN7_RX_DP<124>")
	)
	(segment
		(start 167.625522 -365.024924)
		(end 167.394128 -364.587028)
		(width 0.1651)
		(layer "In9.Cu")
		(net "P5E_PEX1_STN7_RX_DP<124>")
	)
	(segment
		(start 155.490164 -316.229492)
		(end 155.711144 -316.229492)
		(width 0.1143)
		(layer "In9.Cu")
		(net "P5E_PEX1_STN7_RX_DP<124>")
	)
	(segment
		(start 155.711144 -316.229492)
		(end 155.800044 -316.140592)
		(width 0.1143)
		(layer "In9.Cu")
		(net "P5E_PEX1_STN7_RX_DP<124>")
	)
	(segment
		(start 92.461842 -351.611438)
		(end 92.756482 -351.316798)
		(width 0.13462)
		(layer "F.Cu")
		(net "P5E_PEX0_STN5_TX_C_DP<95>")
	)
	(segment
		(start 92.756482 -350.685354)
		(end 92.436442 -350.365314)
		(width 0.13462)
		(layer "F.Cu")
		(net "P5E_PEX0_STN5_TX_C_DP<95>")
	)
	(segment
		(start 92.756482 -351.316798)
		(end 92.756482 -350.685354)
		(width 0.13462)
		(layer "F.Cu")
		(net "P5E_PEX0_STN5_TX_C_DP<95>")
	)
	(segment
		(start 91.198192 -353.990402)
		(end 92.752672 -352.435922)
		(width 0.1651)
		(layer "In7.Cu")
		(net "P5E_PEX0_STN5_TX_C_DP<95>")
	)
	(segment
		(start 87.30996 -379.772164)
		(end 87.43696 -379.899164)
		(width 0.1651)
		(layer "In7.Cu")
		(net "P5E_PEX0_STN5_TX_C_DP<95>")
	)
	(segment
		(start 92.752672 -351.902268)
		(end 92.461842 -351.611438)
		(width 0.1651)
		(layer "In7.Cu")
		(net "P5E_PEX0_STN5_TX_C_DP<95>")
	)
	(segment
		(start 87.851234 -379.899164)
		(end 88.202262 -379.548136)
		(width 0.1651)
		(layer "In7.Cu")
		(net "P5E_PEX0_STN5_TX_C_DP<95>")
	)
	(segment
		(start 88.879426 -366.561624)
		(end 88.974676 -366.510824)
		(width 0.1651)
		(layer "In7.Cu")
		(net "P5E_PEX0_STN5_TX_C_DP<95>")
	)
	(segment
		(start 87.43696 -379.899164)
		(end 87.851234 -379.899164)
		(width 0.1651)
		(layer "In7.Cu")
		(net "P5E_PEX0_STN5_TX_C_DP<95>")
	)
	(segment
		(start 91.198192 -359.181146)
		(end 91.198192 -353.990402)
		(width 0.1651)
		(layer "In7.Cu")
		(net "P5E_PEX0_STN5_TX_C_DP<95>")
	)
	(segment
		(start 92.752672 -352.435922)
		(end 92.752672 -351.902268)
		(width 0.1651)
		(layer "In7.Cu")
		(net "P5E_PEX0_STN5_TX_C_DP<95>")
	)
	(segment
		(start 88.202262 -379.548136)
		(end 88.202262 -369.057174)
		(width 0.1651)
		(layer "In7.Cu")
		(net "P5E_PEX0_STN5_TX_C_DP<95>")
	)
	(segment
		(start 88.202262 -369.057174)
		(end 88.786462 -367.130838)
		(width 0.1651)
		(layer "In7.Cu")
		(net "P5E_PEX0_STN5_TX_C_DP<95>")
	)
	(segment
		(start 88.786462 -367.130838)
		(end 88.735662 -367.035842)
		(width 0.1651)
		(layer "In7.Cu")
		(net "P5E_PEX0_STN5_TX_C_DP<95>")
	)
	(segment
		(start 88.974676 -366.510824)
		(end 91.198192 -359.181146)
		(width 0.1651)
		(layer "In7.Cu")
		(net "P5E_PEX0_STN5_TX_C_DP<95>")
	)
	(segment
		(start 88.735662 -367.035842)
		(end 88.879426 -366.561624)
		(width 0.1651)
		(layer "In7.Cu")
		(net "P5E_PEX0_STN5_TX_C_DP<95>")
	)
	(segment
		(start 87.30996 -379.390148)
		(end 87.30996 -379.772164)
		(width 0.1651)
		(layer "In7.Cu")
		(net "P5E_PEX0_STN5_TX_C_DP<95>")
	)
	(segment
		(start 80.286098 -149.79015)
		(end 80.606138 -150.11019)
		(width 0.13462)
		(layer "F.Cu")
		(net "P5E_PEX0_STN0_TX_DP<12>")
	)
	(segment
		(start 81.237582 -150.11019)
		(end 81.532222 -149.81555)
		(width 0.13462)
		(layer "F.Cu")
		(net "P5E_PEX0_STN0_TX_DP<12>")
	)
	(segment
		(start 80.606138 -150.11019)
		(end 81.237582 -150.11019)
		(width 0.13462)
		(layer "F.Cu")
		(net "P5E_PEX0_STN0_TX_DP<12>")
	)
	(segment
		(start 77.423772 -280.129488)
		(end 77.58557 -280.129488)
		(width 0.1143)
		(layer "In9.Cu")
		(net "P5E_PEX0_STN0_TX_DP<12>")
	)
	(segment
		(start 77.58557 -280.129488)
		(end 77.69987 -280.015188)
		(width 0.1143)
		(layer "In9.Cu")
		(net "P5E_PEX0_STN0_TX_DP<12>")
	)
	(segment
		(start 74.908156 -222.097346)
		(end 78.293468 -260.81736)
		(width 0.1651)
		(layer "In9.Cu")
		(net "P5E_PEX0_STN0_TX_DP<12>")
	)
	(segment
		(start 77.36586 -271.526)
		(end 77.36586 -271.554448)
		(width 0.1143)
		(layer "In9.Cu")
		(net "P5E_PEX0_STN0_TX_DP<12>")
	)
	(segment
		(start 81.823052 -150.10638)
		(end 84.27212 -150.10638)
		(width 0.1651)
		(layer "In9.Cu")
		(net "P5E_PEX0_STN0_TX_DP<12>")
	)
	(segment
		(start 77.32014 -271.600168)
		(end 77.32014 -280.025856)
		(width 0.1143)
		(layer "In9.Cu")
		(net "P5E_PEX0_STN0_TX_DP<12>")
	)
	(segment
		(start 84.27212 -150.10638)
		(end 85.616542 -150.663402)
		(width 0.1651)
		(layer "In9.Cu")
		(net "P5E_PEX0_STN0_TX_DP<12>")
	)
	(segment
		(start 77.69987 -280.015188)
		(end 77.69987 -279.749504)
		(width 0.1143)
		(layer "In9.Cu")
		(net "P5E_PEX0_STN0_TX_DP<12>")
	)
	(segment
		(start 86.357968 -151.404828)
		(end 88.033098 -153.9113)
		(width 0.1651)
		(layer "In9.Cu")
		(net "P5E_PEX0_STN0_TX_DP<12>")
	)
	(segment
		(start 81.532222 -149.81555)
		(end 81.823052 -150.10638)
		(width 0.1651)
		(layer "In9.Cu")
		(net "P5E_PEX0_STN0_TX_DP<12>")
	)
	(segment
		(start 77.36586 -270.37284)
		(end 77.36586 -271.526)
		(width 0.1651)
		(layer "In9.Cu")
		(net "P5E_PEX0_STN0_TX_DP<12>")
	)
	(segment
		(start 78.8416 -177.137568)
		(end 74.908156 -222.097346)
		(width 0.1651)
		(layer "In9.Cu")
		(net "P5E_PEX0_STN0_TX_DP<12>")
	)
	(segment
		(start 88.558624 -155.180792)
		(end 88.558624 -157.417516)
		(width 0.1651)
		(layer "In9.Cu")
		(net "P5E_PEX0_STN0_TX_DP<12>")
	)
	(segment
		(start 78.293468 -268.133068)
		(end 77.36586 -270.37284)
		(width 0.1651)
		(layer "In9.Cu")
		(net "P5E_PEX0_STN0_TX_DP<12>")
	)
	(segment
		(start 77.36586 -271.554448)
		(end 77.32014 -271.600168)
		(width 0.1143)
		(layer "In9.Cu")
		(net "P5E_PEX0_STN0_TX_DP<12>")
	)
	(segment
		(start 80.286098 -171.747942)
		(end 78.8416 -177.137568)
		(width 0.1651)
		(layer "In9.Cu")
		(net "P5E_PEX0_STN0_TX_DP<12>")
	)
	(segment
		(start 88.558624 -157.417516)
		(end 80.286098 -171.747942)
		(width 0.1651)
		(layer "In9.Cu")
		(net "P5E_PEX0_STN0_TX_DP<12>")
	)
	(segment
		(start 85.616542 -150.663402)
		(end 86.357968 -151.404828)
		(width 0.1651)
		(layer "In9.Cu")
		(net "P5E_PEX0_STN0_TX_DP<12>")
	)
	(segment
		(start 77.32014 -280.025856)
		(end 77.423772 -280.129488)
		(width 0.1143)
		(layer "In9.Cu")
		(net "P5E_PEX0_STN0_TX_DP<12>")
	)
	(segment
		(start 78.293468 -260.81736)
		(end 78.293468 -268.133068)
		(width 0.1651)
		(layer "In9.Cu")
		(net "P5E_PEX0_STN0_TX_DP<12>")
	)
	(segment
		(start 88.033098 -153.9113)
		(end 88.558624 -155.180792)
		(width 0.1651)
		(layer "In9.Cu")
		(net "P5E_PEX0_STN0_TX_DP<12>")
	)
	(segment
		(start 44.178728 -349.831914)
		(end 44.498768 -349.511874)
		(width 0.13462)
		(layer "F.Cu")
		(net "P5E_PEX0_STN7_TX_DP<124>")
	)
	(segment
		(start 44.498768 -348.88043)
		(end 44.204128 -348.58579)
		(width 0.13462)
		(layer "F.Cu")
		(net "P5E_PEX0_STN7_TX_DP<124>")
	)
	(segment
		(start 44.498768 -349.511874)
		(end 44.498768 -348.88043)
		(width 0.13462)
		(layer "F.Cu")
		(net "P5E_PEX0_STN7_TX_DP<124>")
	)
	(segment
		(start 46.049438 -342.194134)
		(end 45.602652 -339.91169)
		(width 0.1651)
		(layer "In7.Cu")
		(net "P5E_PEX0_STN7_TX_DP<124>")
	)
	(segment
		(start 46.049438 -344.39606)
		(end 45.974 -344.320622)
		(width 0.1651)
		(layer "In7.Cu")
		(net "P5E_PEX0_STN7_TX_DP<124>")
	)
	(segment
		(start 39.083996 -319.865248)
		(end 39.083996 -319.8368)
		(width 0.1143)
		(layer "In7.Cu")
		(net "P5E_PEX0_STN7_TX_DP<124>")
	)
	(segment
		(start 39.699946 -311.365392)
		(end 39.699946 -311.099962)
		(width 0.1143)
		(layer "In7.Cu")
		(net "P5E_PEX0_STN7_TX_DP<124>")
	)
	(segment
		(start 39.083996 -319.8368)
		(end 39.129716 -319.79108)
		(width 0.1143)
		(layer "In7.Cu")
		(net "P5E_PEX0_STN7_TX_DP<124>")
	)
	(segment
		(start 44.494958 -347.541342)
		(end 46.049438 -345.986862)
		(width 0.1651)
		(layer "In7.Cu")
		(net "P5E_PEX0_STN7_TX_DP<124>")
	)
	(segment
		(start 39.262304 -324.336664)
		(end 39.083996 -323.543422)
		(width 0.1651)
		(layer "In7.Cu")
		(net "P5E_PEX0_STN7_TX_DP<124>")
	)
	(segment
		(start 46.049438 -345.986862)
		(end 46.049438 -344.39606)
		(width 0.1651)
		(layer "In7.Cu")
		(net "P5E_PEX0_STN7_TX_DP<124>")
	)
	(segment
		(start 39.083996 -323.543422)
		(end 39.083996 -319.865248)
		(width 0.1651)
		(layer "In7.Cu")
		(net "P5E_PEX0_STN7_TX_DP<124>")
	)
	(segment
		(start 39.585646 -311.479692)
		(end 39.699946 -311.365392)
		(width 0.1143)
		(layer "In7.Cu")
		(net "P5E_PEX0_STN7_TX_DP<124>")
	)
	(segment
		(start 44.204128 -348.58579)
		(end 44.494958 -348.29496)
		(width 0.1651)
		(layer "In7.Cu")
		(net "P5E_PEX0_STN7_TX_DP<124>")
	)
	(segment
		(start 44.494958 -348.29496)
		(end 44.494958 -347.541342)
		(width 0.1651)
		(layer "In7.Cu")
		(net "P5E_PEX0_STN7_TX_DP<124>")
	)
	(segment
		(start 45.602652 -339.91169)
		(end 39.262304 -324.336664)
		(width 0.1651)
		(layer "In7.Cu")
		(net "P5E_PEX0_STN7_TX_DP<124>")
	)
	(segment
		(start 39.129716 -319.79108)
		(end 39.129716 -311.705498)
		(width 0.1143)
		(layer "In7.Cu")
		(net "P5E_PEX0_STN7_TX_DP<124>")
	)
	(segment
		(start 46.049438 -343.68994)
		(end 46.049438 -342.194134)
		(width 0.1651)
		(layer "In7.Cu")
		(net "P5E_PEX0_STN7_TX_DP<124>")
	)
	(segment
		(start 45.974 -344.320622)
		(end 45.974 -343.765378)
		(width 0.1651)
		(layer "In7.Cu")
		(net "P5E_PEX0_STN7_TX_DP<124>")
	)
	(segment
		(start 45.974 -343.765378)
		(end 46.049438 -343.68994)
		(width 0.1651)
		(layer "In7.Cu")
		(net "P5E_PEX0_STN7_TX_DP<124>")
	)
	(segment
		(start 39.129716 -311.705498)
		(end 39.355522 -311.479692)
		(width 0.1143)
		(layer "In7.Cu")
		(net "P5E_PEX0_STN7_TX_DP<124>")
	)
	(segment
		(start 39.355522 -311.479692)
		(end 39.585646 -311.479692)
		(width 0.1143)
		(layer "In7.Cu")
		(net "P5E_PEX0_STN7_TX_DP<124>")
	)
	(segment
		(start 155.113736 -107.403138)
		(end 154.793696 -107.083098)
		(width 0.13462)
		(layer "F.Cu")
		(net "P5E_PEX1_STN1_TX_DN<20>")
	)
	(segment
		(start 154.162252 -107.083098)
		(end 153.867612 -107.377738)
		(width 0.13462)
		(layer "F.Cu")
		(net "P5E_PEX1_STN1_TX_DN<20>")
	)
	(segment
		(start 154.793696 -107.083098)
		(end 154.162252 -107.083098)
		(width 0.13462)
		(layer "F.Cu")
		(net "P5E_PEX1_STN1_TX_DN<20>")
	)
	(segment
		(start 149.341332 -108.43387)
		(end 148.999702 -108.7755)
		(width 0.1651)
		(layer "In9.Cu")
		(net "P5E_PEX1_STN1_TX_DN<20>")
	)
	(segment
		(start 179.17033 -278.12619)
		(end 179.273708 -278.229568)
		(width 0.1143)
		(layer "In9.Cu")
		(net "P5E_PEX1_STN1_TX_DN<20>")
	)
	(segment
		(start 147.33143 -110.955328)
		(end 147.146772 -111.401098)
		(width 0.1651)
		(layer "In9.Cu")
		(net "P5E_PEX1_STN1_TX_DN<20>")
	)
	(segment
		(start 147.756626 -109.929168)
		(end 147.756372 -109.929168)
		(width 0.1651)
		(layer "In9.Cu")
		(net "P5E_PEX1_STN1_TX_DN<20>")
	)
	(segment
		(start 147.665694 -110.447328)
		(end 147.481036 -110.893352)
		(width 0.1651)
		(layer "In9.Cu")
		(net "P5E_PEX1_STN1_TX_DN<20>")
	)
	(segment
		(start 145.286476 -116.191284)
		(end 145.101818 -116.637308)
		(width 0.1651)
		(layer "In9.Cu")
		(net "P5E_PEX1_STN1_TX_DN<20>")
	)
	(segment
		(start 144.952212 -116.699284)
		(end 144.610836 -117.523768)
		(width 0.1651)
		(layer "In9.Cu")
		(net "P5E_PEX1_STN1_TX_DN<20>")
	)
	(segment
		(start 148.999702 -108.7755)
		(end 148.838158 -108.7755)
		(width 0.1651)
		(layer "In9.Cu")
		(net "P5E_PEX1_STN1_TX_DN<20>")
	)
	(segment
		(start 146.230086 -113.6142)
		(end 146.292062 -113.763552)
		(width 0.1651)
		(layer "In9.Cu")
		(net "P5E_PEX1_STN1_TX_DN<20>")
	)
	(segment
		(start 144.32407 -162.004248)
		(end 179.21605 -265.086338)
		(width 0.1651)
		(layer "In9.Cu")
		(net "P5E_PEX1_STN1_TX_DN<20>")
	)
	(segment
		(start 149.682454 -107.931204)
		(end 149.341332 -108.272326)
		(width 0.1651)
		(layer "In9.Cu")
		(net "P5E_PEX1_STN1_TX_DN<20>")
	)
	(segment
		(start 147.756372 -109.929168)
		(end 147.603718 -110.297976)
		(width 0.1651)
		(layer "In9.Cu")
		(net "P5E_PEX1_STN1_TX_DN<20>")
	)
	(segment
		(start 140.45819 -131.214368)
		(end 140.45819 -138.197844)
		(width 0.1651)
		(layer "In9.Cu")
		(net "P5E_PEX1_STN1_TX_DN<20>")
	)
	(segment
		(start 179.549806 -278.115268)
		(end 179.549806 -277.849838)
		(width 0.1143)
		(layer "In9.Cu")
		(net "P5E_PEX1_STN1_TX_DN<20>")
	)
	(segment
		(start 151.720804 -107.086908)
		(end 149.682454 -107.931204)
		(width 0.1651)
		(layer "In9.Cu")
		(net "P5E_PEX1_STN1_TX_DN<20>")
	)
	(segment
		(start 146.414744 -113.16843)
		(end 146.230086 -113.6142)
		(width 0.1651)
		(layer "In9.Cu")
		(net "P5E_PEX1_STN1_TX_DN<20>")
	)
	(segment
		(start 148.838158 -108.7755)
		(end 147.807426 -109.806232)
		(width 0.1651)
		(layer "In9.Cu")
		(net "P5E_PEX1_STN1_TX_DN<20>")
	)
	(segment
		(start 179.21605 -271.471898)
		(end 179.21605 -271.500346)
		(width 0.1143)
		(layer "In9.Cu")
		(net "P5E_PEX1_STN1_TX_DN<20>")
	)
	(segment
		(start 146.292062 -113.763552)
		(end 146.107404 -114.209576)
		(width 0.1651)
		(layer "In9.Cu")
		(net "P5E_PEX1_STN1_TX_DN<20>")
	)
	(segment
		(start 146.874484 -112.05845)
		(end 146.687032 -112.511332)
		(width 0.1651)
		(layer "In9.Cu")
		(net "P5E_PEX1_STN1_TX_DN<20>")
	)
	(segment
		(start 145.650458 -115.312698)
		(end 145.500852 -115.374674)
		(width 0.1651)
		(layer "In9.Cu")
		(net "P5E_PEX1_STN1_TX_DN<20>")
	)
	(segment
		(start 146.749008 -112.660684)
		(end 146.564096 -113.106708)
		(width 0.1651)
		(layer "In9.Cu")
		(net "P5E_PEX1_STN1_TX_DN<20>")
	)
	(segment
		(start 145.957798 -114.271552)
		(end 145.77314 -114.717322)
		(width 0.1651)
		(layer "In9.Cu")
		(net "P5E_PEX1_STN1_TX_DN<20>")
	)
	(segment
		(start 147.481036 -110.893352)
		(end 147.33143 -110.955328)
		(width 0.1651)
		(layer "In9.Cu")
		(net "P5E_PEX1_STN1_TX_DN<20>")
	)
	(segment
		(start 145.500852 -115.374674)
		(end 145.2245 -116.041932)
		(width 0.1651)
		(layer "In9.Cu")
		(net "P5E_PEX1_STN1_TX_DN<20>")
	)
	(segment
		(start 146.564096 -113.106708)
		(end 146.414744 -113.16843)
		(width 0.1651)
		(layer "In9.Cu")
		(net "P5E_PEX1_STN1_TX_DN<20>")
	)
	(segment
		(start 143.038068 -144.425924)
		(end 143.763746 -159.187134)
		(width 0.1651)
		(layer "In9.Cu")
		(net "P5E_PEX1_STN1_TX_DN<20>")
	)
	(segment
		(start 145.101818 -116.637308)
		(end 144.952212 -116.699284)
		(width 0.1651)
		(layer "In9.Cu")
		(net "P5E_PEX1_STN1_TX_DN<20>")
	)
	(segment
		(start 145.835116 -114.866674)
		(end 145.650458 -115.312698)
		(width 0.1651)
		(layer "In9.Cu")
		(net "P5E_PEX1_STN1_TX_DN<20>")
	)
	(segment
		(start 140.45819 -138.197844)
		(end 143.038068 -144.425924)
		(width 0.1651)
		(layer "In9.Cu")
		(net "P5E_PEX1_STN1_TX_DN<20>")
	)
	(segment
		(start 147.02409 -111.996474)
		(end 146.874484 -112.05845)
		(width 0.1651)
		(layer "In9.Cu")
		(net "P5E_PEX1_STN1_TX_DN<20>")
	)
	(segment
		(start 179.21605 -265.086338)
		(end 179.21605 -271.471898)
		(width 0.1651)
		(layer "In9.Cu")
		(net "P5E_PEX1_STN1_TX_DN<20>")
	)
	(segment
		(start 149.341332 -108.272326)
		(end 149.341332 -108.43387)
		(width 0.1651)
		(layer "In9.Cu")
		(net "P5E_PEX1_STN1_TX_DN<20>")
	)
	(segment
		(start 152.317958 -107.201208)
		(end 152.203658 -107.086908)
		(width 0.1651)
		(layer "In9.Cu")
		(net "P5E_PEX1_STN1_TX_DN<20>")
	)
	(segment
		(start 147.603718 -110.297976)
		(end 147.665694 -110.447328)
		(width 0.1651)
		(layer "In9.Cu")
		(net "P5E_PEX1_STN1_TX_DN<20>")
	)
	(segment
		(start 179.435506 -278.229568)
		(end 179.549806 -278.115268)
		(width 0.1143)
		(layer "In9.Cu")
		(net "P5E_PEX1_STN1_TX_DN<20>")
	)
	(segment
		(start 152.914858 -107.086908)
		(end 152.800558 -107.201208)
		(width 0.1651)
		(layer "In9.Cu")
		(net "P5E_PEX1_STN1_TX_DN<20>")
	)
	(segment
		(start 146.107404 -114.209576)
		(end 145.957798 -114.271552)
		(width 0.1651)
		(layer "In9.Cu")
		(net "P5E_PEX1_STN1_TX_DN<20>")
	)
	(segment
		(start 179.17033 -271.546066)
		(end 179.17033 -278.12619)
		(width 0.1143)
		(layer "In9.Cu")
		(net "P5E_PEX1_STN1_TX_DN<20>")
	)
	(segment
		(start 144.610836 -117.523768)
		(end 140.45819 -131.214368)
		(width 0.1651)
		(layer "In9.Cu")
		(net "P5E_PEX1_STN1_TX_DN<20>")
	)
	(segment
		(start 179.273708 -278.229568)
		(end 179.435506 -278.229568)
		(width 0.1143)
		(layer "In9.Cu")
		(net "P5E_PEX1_STN1_TX_DN<20>")
	)
	(segment
		(start 152.800558 -107.201208)
		(end 152.317958 -107.201208)
		(width 0.1651)
		(layer "In9.Cu")
		(net "P5E_PEX1_STN1_TX_DN<20>")
	)
	(segment
		(start 145.2245 -116.041932)
		(end 145.286476 -116.191284)
		(width 0.1651)
		(layer "In9.Cu")
		(net "P5E_PEX1_STN1_TX_DN<20>")
	)
	(segment
		(start 153.867612 -107.377738)
		(end 153.576782 -107.086908)
		(width 0.1651)
		(layer "In9.Cu")
		(net "P5E_PEX1_STN1_TX_DN<20>")
	)
	(segment
		(start 147.146772 -111.401098)
		(end 147.208748 -111.55045)
		(width 0.1651)
		(layer "In9.Cu")
		(net "P5E_PEX1_STN1_TX_DN<20>")
	)
	(segment
		(start 153.576782 -107.086908)
		(end 152.914858 -107.086908)
		(width 0.1651)
		(layer "In9.Cu")
		(net "P5E_PEX1_STN1_TX_DN<20>")
	)
	(segment
		(start 147.807426 -109.806232)
		(end 147.756626 -109.929168)
		(width 0.1651)
		(layer "In9.Cu")
		(net "P5E_PEX1_STN1_TX_DN<20>")
	)
	(segment
		(start 146.687032 -112.511332)
		(end 146.749008 -112.660684)
		(width 0.1651)
		(layer "In9.Cu")
		(net "P5E_PEX1_STN1_TX_DN<20>")
	)
	(segment
		(start 145.77314 -114.717322)
		(end 145.835116 -114.866674)
		(width 0.1651)
		(layer "In9.Cu")
		(net "P5E_PEX1_STN1_TX_DN<20>")
	)
	(segment
		(start 152.203658 -107.086908)
		(end 151.720804 -107.086908)
		(width 0.1651)
		(layer "In9.Cu")
		(net "P5E_PEX1_STN1_TX_DN<20>")
	)
	(segment
		(start 143.763746 -159.187134)
		(end 144.32407 -162.004248)
		(width 0.1651)
		(layer "In9.Cu")
		(net "P5E_PEX1_STN1_TX_DN<20>")
	)
	(segment
		(start 179.21605 -271.500346)
		(end 179.17033 -271.546066)
		(width 0.1143)
		(layer "In9.Cu")
		(net "P5E_PEX1_STN1_TX_DN<20>")
	)
	(segment
		(start 147.208748 -111.55045)
		(end 147.02409 -111.996474)
		(width 0.1651)
		(layer "In9.Cu")
		(net "P5E_PEX1_STN1_TX_DN<20>")
	)
	(segment
		(start 120.310148 -371.790214)
		(end 120.310148 -371.408198)
		(width 0.1651)
		(layer "In15.Cu")
		(net "P5E_PEX1_STN5_RX_DN<90>")
	)
	(segment
		(start 122.12193 -368.051588)
		(end 126.563882 -365.211868)
		(width 0.1651)
		(layer "In15.Cu")
		(net "P5E_PEX1_STN5_RX_DN<90>")
	)
	(segment
		(start 121.500138 -370.61267)
		(end 121.500138 -369.187222)
		(width 0.1651)
		(layer "In15.Cu")
		(net "P5E_PEX1_STN5_RX_DN<90>")
	)
	(segment
		(start 183.92013 -319.84188)
		(end 183.92013 -316.585092)
		(width 0.1143)
		(layer "In15.Cu")
		(net "P5E_PEX1_STN5_RX_DN<90>")
	)
	(segment
		(start 120.310148 -371.408198)
		(end 120.437148 -371.281198)
		(width 0.1651)
		(layer "In15.Cu")
		(net "P5E_PEX1_STN5_RX_DN<90>")
	)
	(segment
		(start 139.078716 -341.676482)
		(end 139.295632 -341.35441)
		(width 0.1651)
		(layer "In15.Cu")
		(net "P5E_PEX1_STN5_RX_DN<90>")
	)
	(segment
		(start 183.92013 -316.585092)
		(end 184.08523 -316.419992)
		(width 0.1143)
		(layer "In15.Cu")
		(net "P5E_PEX1_STN5_RX_DN<90>")
	)
	(segment
		(start 183.96585 -320.582544)
		(end 183.96585 -319.916048)
		(width 0.1651)
		(layer "In15.Cu")
		(net "P5E_PEX1_STN5_RX_DN<90>")
	)
	(segment
		(start 138.861038 -341.999062)
		(end 139.078462 -341.676736)
		(width 0.1651)
		(layer "In15.Cu")
		(net "P5E_PEX1_STN5_RX_DN<90>")
	)
	(segment
		(start 138.217402 -359.163112)
		(end 138.861038 -358.103932)
		(width 0.1651)
		(layer "In15.Cu")
		(net "P5E_PEX1_STN5_RX_DN<90>")
	)
	(segment
		(start 182.202836 -322.510912)
		(end 183.84901 -320.864738)
		(width 0.1651)
		(layer "In15.Cu")
		(net "P5E_PEX1_STN5_RX_DN<90>")
	)
	(segment
		(start 126.563882 -365.211868)
		(end 138.217402 -359.163112)
		(width 0.1651)
		(layer "In15.Cu")
		(net "P5E_PEX1_STN5_RX_DN<90>")
	)
	(segment
		(start 184.29986 -316.508892)
		(end 184.29986 -316.799722)
		(width 0.1143)
		(layer "In15.Cu")
		(net "P5E_PEX1_STN5_RX_DN<90>")
	)
	(segment
		(start 120.83161 -371.281198)
		(end 121.500138 -370.61267)
		(width 0.1651)
		(layer "In15.Cu")
		(net "P5E_PEX1_STN5_RX_DN<90>")
	)
	(segment
		(start 184.21096 -316.419992)
		(end 184.29986 -316.508892)
		(width 0.1143)
		(layer "In15.Cu")
		(net "P5E_PEX1_STN5_RX_DN<90>")
	)
	(segment
		(start 138.861038 -358.103932)
		(end 138.861038 -341.999062)
		(width 0.1651)
		(layer "In15.Cu")
		(net "P5E_PEX1_STN5_RX_DN<90>")
	)
	(segment
		(start 139.295632 -341.35441)
		(end 141.537182 -340.032594)
		(width 0.1651)
		(layer "In15.Cu")
		(net "P5E_PEX1_STN5_RX_DN<90>")
	)
	(segment
		(start 120.437148 -371.281198)
		(end 120.83161 -371.281198)
		(width 0.1651)
		(layer "In15.Cu")
		(net "P5E_PEX1_STN5_RX_DN<90>")
	)
	(segment
		(start 141.537182 -340.032594)
		(end 178.098958 -325.232522)
		(width 0.1651)
		(layer "In15.Cu")
		(net "P5E_PEX1_STN5_RX_DN<90>")
	)
	(segment
		(start 183.96585 -319.916048)
		(end 183.96585 -319.8876)
		(width 0.1143)
		(layer "In15.Cu")
		(net "P5E_PEX1_STN5_RX_DN<90>")
	)
	(segment
		(start 183.96585 -319.8876)
		(end 183.92013 -319.84188)
		(width 0.1143)
		(layer "In15.Cu")
		(net "P5E_PEX1_STN5_RX_DN<90>")
	)
	(segment
		(start 139.078462 -341.676736)
		(end 139.078716 -341.676482)
		(width 0.1651)
		(layer "In15.Cu")
		(net "P5E_PEX1_STN5_RX_DN<90>")
	)
	(segment
		(start 121.500138 -369.187222)
		(end 122.12193 -368.051588)
		(width 0.1651)
		(layer "In15.Cu")
		(net "P5E_PEX1_STN5_RX_DN<90>")
	)
	(segment
		(start 178.098958 -325.232522)
		(end 182.202836 -322.510912)
		(width 0.1651)
		(layer "In15.Cu")
		(net "P5E_PEX1_STN5_RX_DN<90>")
	)
	(segment
		(start 184.08523 -316.419992)
		(end 184.21096 -316.419992)
		(width 0.1143)
		(layer "In15.Cu")
		(net "P5E_PEX1_STN5_RX_DN<90>")
	)
	(segment
		(start 183.84901 -320.864738)
		(end 183.96585 -320.582544)
		(width 0.1651)
		(layer "In15.Cu")
		(net "P5E_PEX1_STN5_RX_DN<90>")
	)
	(segment
		(start 174.916592 -356.831646)
		(end 174.596552 -356.511606)
		(width 0.13462)
		(layer "F.Cu")
		(net "P5E_PEX1_STN7_TX_C_DP<119>")
	)
	(segment
		(start 174.916592 -357.46309)
		(end 174.916592 -356.831646)
		(width 0.13462)
		(layer "F.Cu")
		(net "P5E_PEX1_STN7_TX_C_DP<119>")
	)
	(segment
		(start 174.621952 -357.75773)
		(end 174.916592 -357.46309)
		(width 0.13462)
		(layer "F.Cu")
		(net "P5E_PEX1_STN7_TX_C_DP<119>")
	)
	(segment
		(start 167.3606 -389.449056)
		(end 167.809418 -389.657844)
		(width 0.1651)
		(layer "In11.Cu")
		(net "P5E_PEX1_STN7_TX_C_DP<119>")
	)
	(segment
		(start 174.402496 -393.568682)
		(end 174.402496 -393.712446)
		(width 0.1651)
		(layer "In11.Cu")
		(net "P5E_PEX1_STN7_TX_C_DP<119>")
	)
	(segment
		(start 159.032702 -367.88979)
		(end 158.58109 -369.08359)
		(width 0.1651)
		(layer "In11.Cu")
		(net "P5E_PEX1_STN7_TX_C_DP<119>")
	)
	(segment
		(start 167.858694 -389.792972)
		(end 168.30802 -390.002268)
		(width 0.1651)
		(layer "In11.Cu")
		(net "P5E_PEX1_STN7_TX_C_DP<119>")
	)
	(segment
		(start 169.525696 -390.456674)
		(end 170.444922 -390.88441)
		(width 0.1651)
		(layer "In11.Cu")
		(net "P5E_PEX1_STN7_TX_C_DP<119>")
	)
	(segment
		(start 166.776146 -389.289036)
		(end 167.225472 -389.498332)
		(width 0.1651)
		(layer "In11.Cu")
		(net "P5E_PEX1_STN7_TX_C_DP<119>")
	)
	(segment
		(start 159.190944 -385.743196)
		(end 160.919668 -387.02615)
		(width 0.1651)
		(layer "In11.Cu")
		(net "P5E_PEX1_STN7_TX_C_DP<119>")
	)
	(segment
		(start 173.762162 -392.928348)
		(end 174.402496 -393.568682)
		(width 0.1651)
		(layer "In11.Cu")
		(net "P5E_PEX1_STN7_TX_C_DP<119>")
	)
	(segment
		(start 174.912782 -358.04856)
		(end 174.912782 -358.767634)
		(width 0.1651)
		(layer "In11.Cu")
		(net "P5E_PEX1_STN7_TX_C_DP<119>")
	)
	(segment
		(start 160.919668 -387.02615)
		(end 165.173152 -388.431024)
		(width 0.1651)
		(layer "In11.Cu")
		(net "P5E_PEX1_STN7_TX_C_DP<119>")
	)
	(segment
		(start 175.246792 -394.412978)
		(end 175.246792 -394.556488)
		(width 0.1651)
		(layer "In11.Cu")
		(net "P5E_PEX1_STN7_TX_C_DP<119>")
	)
	(segment
		(start 174.89678 -394.062966)
		(end 175.246792 -394.412978)
		(width 0.1651)
		(layer "In11.Cu")
		(net "P5E_PEX1_STN7_TX_C_DP<119>")
	)
	(segment
		(start 174.753016 -394.062966)
		(end 174.89678 -394.062966)
		(width 0.1651)
		(layer "In11.Cu")
		(net "P5E_PEX1_STN7_TX_C_DP<119>")
	)
	(segment
		(start 174.621952 -357.75773)
		(end 174.912782 -358.04856)
		(width 0.1651)
		(layer "In11.Cu")
		(net "P5E_PEX1_STN7_TX_C_DP<119>")
	)
	(segment
		(start 167.225472 -389.498332)
		(end 167.3606 -389.449056)
		(width 0.1651)
		(layer "In11.Cu")
		(net "P5E_PEX1_STN7_TX_C_DP<119>")
	)
	(segment
		(start 169.390568 -390.50595)
		(end 169.525696 -390.456674)
		(width 0.1651)
		(layer "In11.Cu")
		(net "P5E_PEX1_STN7_TX_C_DP<119>")
	)
	(segment
		(start 174.912782 -358.767634)
		(end 172.043344 -361.637072)
		(width 0.1651)
		(layer "In11.Cu")
		(net "P5E_PEX1_STN7_TX_C_DP<119>")
	)
	(segment
		(start 174.402496 -393.712446)
		(end 174.753016 -394.062966)
		(width 0.1651)
		(layer "In11.Cu")
		(net "P5E_PEX1_STN7_TX_C_DP<119>")
	)
	(segment
		(start 168.941242 -390.296654)
		(end 169.390568 -390.50595)
		(width 0.1651)
		(layer "In11.Cu")
		(net "P5E_PEX1_STN7_TX_C_DP<119>")
	)
	(segment
		(start 158.58109 -369.08359)
		(end 158.420054 -382.267206)
		(width 0.1651)
		(layer "In11.Cu")
		(net "P5E_PEX1_STN7_TX_C_DP<119>")
	)
	(segment
		(start 168.30802 -390.002268)
		(end 168.443148 -389.952992)
		(width 0.1651)
		(layer "In11.Cu")
		(net "P5E_PEX1_STN7_TX_C_DP<119>")
	)
	(segment
		(start 175.659542 -401.999196)
		(end 175.437038 -401.999196)
		(width 0.1651)
		(layer "In11.Cu")
		(net "P5E_PEX1_STN7_TX_C_DP<119>")
	)
	(segment
		(start 165.173152 -388.431024)
		(end 166.72687 -389.154162)
		(width 0.1651)
		(layer "In11.Cu")
		(net "P5E_PEX1_STN7_TX_C_DP<119>")
	)
	(segment
		(start 175.597312 -394.907008)
		(end 175.740822 -394.907008)
		(width 0.1651)
		(layer "In11.Cu")
		(net "P5E_PEX1_STN7_TX_C_DP<119>")
	)
	(segment
		(start 175.437038 -401.999196)
		(end 175.310038 -401.872196)
		(width 0.1651)
		(layer "In11.Cu")
		(net "P5E_PEX1_STN7_TX_C_DP<119>")
	)
	(segment
		(start 168.891966 -390.16178)
		(end 168.941242 -390.296654)
		(width 0.1651)
		(layer "In11.Cu")
		(net "P5E_PEX1_STN7_TX_C_DP<119>")
	)
	(segment
		(start 160.337246 -366.550956)
		(end 159.032702 -367.88979)
		(width 0.1651)
		(layer "In11.Cu")
		(net "P5E_PEX1_STN7_TX_C_DP<119>")
	)
	(segment
		(start 176.185576 -395.351762)
		(end 176.185576 -401.473162)
		(width 0.1651)
		(layer "In11.Cu")
		(net "P5E_PEX1_STN7_TX_C_DP<119>")
	)
	(segment
		(start 158.592266 -384.266694)
		(end 159.190944 -385.743196)
		(width 0.1651)
		(layer "In11.Cu")
		(net "P5E_PEX1_STN7_TX_C_DP<119>")
	)
	(segment
		(start 172.043344 -361.637072)
		(end 160.337246 -366.550956)
		(width 0.1651)
		(layer "In11.Cu")
		(net "P5E_PEX1_STN7_TX_C_DP<119>")
	)
	(segment
		(start 166.72687 -389.154162)
		(end 166.776146 -389.289036)
		(width 0.1651)
		(layer "In11.Cu")
		(net "P5E_PEX1_STN7_TX_C_DP<119>")
	)
	(segment
		(start 158.420054 -382.267206)
		(end 158.592266 -384.266694)
		(width 0.1651)
		(layer "In11.Cu")
		(net "P5E_PEX1_STN7_TX_C_DP<119>")
	)
	(segment
		(start 168.443148 -389.952992)
		(end 168.891966 -390.16178)
		(width 0.1651)
		(layer "In11.Cu")
		(net "P5E_PEX1_STN7_TX_C_DP<119>")
	)
	(segment
		(start 175.740822 -394.907008)
		(end 176.185576 -395.351762)
		(width 0.1651)
		(layer "In11.Cu")
		(net "P5E_PEX1_STN7_TX_C_DP<119>")
	)
	(segment
		(start 175.246792 -394.556488)
		(end 175.597312 -394.907008)
		(width 0.1651)
		(layer "In11.Cu")
		(net "P5E_PEX1_STN7_TX_C_DP<119>")
	)
	(segment
		(start 176.185576 -401.473162)
		(end 175.659542 -401.999196)
		(width 0.1651)
		(layer "In11.Cu")
		(net "P5E_PEX1_STN7_TX_C_DP<119>")
	)
	(segment
		(start 170.444922 -390.88441)
		(end 173.762162 -392.928348)
		(width 0.1651)
		(layer "In11.Cu")
		(net "P5E_PEX1_STN7_TX_C_DP<119>")
	)
	(segment
		(start 167.809418 -389.657844)
		(end 167.858694 -389.792972)
		(width 0.1651)
		(layer "In11.Cu")
		(net "P5E_PEX1_STN7_TX_C_DP<119>")
	)
	(segment
		(start 175.310038 -401.872196)
		(end 175.310038 -401.49018)
		(width 0.1651)
		(layer "In11.Cu")
		(net "P5E_PEX1_STN7_TX_C_DP<119>")
	)
	(segment
		(start 83.87969 -148.31695)
		(end 84.17433 -148.02231)
		(width 0.13462)
		(layer "F.Cu")
		(net "P5E_PEX0_STN0_TX_DN<11>")
	)
	(segment
		(start 83.248246 -148.31695)
		(end 83.87969 -148.31695)
		(width 0.13462)
		(layer "F.Cu")
		(net "P5E_PEX0_STN0_TX_DN<11>")
	)
	(segment
		(start 82.928206 -147.99691)
		(end 83.248246 -148.31695)
		(width 0.13462)
		(layer "F.Cu")
		(net "P5E_PEX0_STN0_TX_DN<11>")
	)
	(segment
		(start 78.649576 -278.115268)
		(end 78.649576 -277.849838)
		(width 0.1143)
		(layer "In9.Cu")
		(net "P5E_PEX0_STN0_TX_DN<11>")
	)
	(segment
		(start 79.804768 -177.303684)
		(end 75.882754 -222.13189)
		(width 0.1651)
		(layer "In9.Cu")
		(net "P5E_PEX0_STN0_TX_DN<11>")
	)
	(segment
		(start 89.5223 -157.763464)
		(end 81.16062 -172.248576)
		(width 0.1651)
		(layer "In9.Cu")
		(net "P5E_PEX0_STN0_TX_DN<11>")
	)
	(segment
		(start 81.16062 -172.248576)
		(end 79.804768 -177.303684)
		(width 0.1651)
		(layer "In9.Cu")
		(net "P5E_PEX0_STN0_TX_DN<11>")
	)
	(segment
		(start 78.31582 -270.929608)
		(end 78.31582 -271.471898)
		(width 0.1651)
		(layer "In9.Cu")
		(net "P5E_PEX0_STN0_TX_DN<11>")
	)
	(segment
		(start 84.17433 -148.02231)
		(end 84.46516 -148.31314)
		(width 0.1651)
		(layer "In9.Cu")
		(net "P5E_PEX0_STN0_TX_DN<11>")
	)
	(segment
		(start 89.5223 -154.959558)
		(end 89.5223 -157.763464)
		(width 0.1651)
		(layer "In9.Cu")
		(net "P5E_PEX0_STN0_TX_DN<11>")
	)
	(segment
		(start 78.31582 -271.471898)
		(end 78.31582 -271.500346)
		(width 0.1143)
		(layer "In9.Cu")
		(net "P5E_PEX0_STN0_TX_DN<11>")
	)
	(segment
		(start 85.269832 -148.31314)
		(end 86.793324 -149.836632)
		(width 0.1651)
		(layer "In9.Cu")
		(net "P5E_PEX0_STN0_TX_DN<11>")
	)
	(segment
		(start 78.31582 -271.500346)
		(end 78.2701 -271.546066)
		(width 0.1143)
		(layer "In9.Cu")
		(net "P5E_PEX0_STN0_TX_DN<11>")
	)
	(segment
		(start 87.558626 -150.981664)
		(end 88.389968 -152.22601)
		(width 0.1651)
		(layer "In9.Cu")
		(net "P5E_PEX0_STN0_TX_DN<11>")
	)
	(segment
		(start 84.46516 -148.31314)
		(end 85.269832 -148.31314)
		(width 0.1651)
		(layer "In9.Cu")
		(net "P5E_PEX0_STN0_TX_DN<11>")
	)
	(segment
		(start 88.389968 -152.22601)
		(end 89.5223 -154.959558)
		(width 0.1651)
		(layer "In9.Cu")
		(net "P5E_PEX0_STN0_TX_DN<11>")
	)
	(segment
		(start 75.882754 -222.13189)
		(end 79.261208 -260.775704)
		(width 0.1651)
		(layer "In9.Cu")
		(net "P5E_PEX0_STN0_TX_DN<11>")
	)
	(segment
		(start 79.261208 -260.775704)
		(end 79.261208 -268.64691)
		(width 0.1651)
		(layer "In9.Cu")
		(net "P5E_PEX0_STN0_TX_DN<11>")
	)
	(segment
		(start 78.373478 -278.229568)
		(end 78.535276 -278.229568)
		(width 0.1143)
		(layer "In9.Cu")
		(net "P5E_PEX0_STN0_TX_DN<11>")
	)
	(segment
		(start 87.558372 -150.98141)
		(end 87.558626 -150.981664)
		(width 0.1651)
		(layer "In9.Cu")
		(net "P5E_PEX0_STN0_TX_DN<11>")
	)
	(segment
		(start 79.261208 -268.64691)
		(end 78.31582 -270.929608)
		(width 0.1651)
		(layer "In9.Cu")
		(net "P5E_PEX0_STN0_TX_DN<11>")
	)
	(segment
		(start 78.535276 -278.229568)
		(end 78.649576 -278.115268)
		(width 0.1143)
		(layer "In9.Cu")
		(net "P5E_PEX0_STN0_TX_DN<11>")
	)
	(segment
		(start 86.793324 -149.836632)
		(end 87.558372 -150.98141)
		(width 0.1651)
		(layer "In9.Cu")
		(net "P5E_PEX0_STN0_TX_DN<11>")
	)
	(segment
		(start 78.2701 -278.12619)
		(end 78.373478 -278.229568)
		(width 0.1143)
		(layer "In9.Cu")
		(net "P5E_PEX0_STN0_TX_DN<11>")
	)
	(segment
		(start 78.2701 -271.546066)
		(end 78.2701 -278.12619)
		(width 0.1143)
		(layer "In9.Cu")
		(net "P5E_PEX0_STN0_TX_DN<11>")
	)
	(segment
		(start 22.736048 -342.734138)
		(end 22.441408 -342.439498)
		(width 0.13462)
		(layer "F.Cu")
		(net "P5E_PEX0_STN7_TX_DP<113>")
	)
	(segment
		(start 22.736048 -343.365582)
		(end 22.736048 -342.734138)
		(width 0.13462)
		(layer "F.Cu")
		(net "P5E_PEX0_STN7_TX_DP<113>")
	)
	(segment
		(start 22.416008 -343.685622)
		(end 22.736048 -343.365582)
		(width 0.13462)
		(layer "F.Cu")
		(net "P5E_PEX0_STN7_TX_DP<113>")
	)
	(segment
		(start 31.403798 -301.933864)
		(end 35.633152 -301.933864)
		(width 0.1651)
		(layer "In7.Cu")
		(net "P5E_PEX0_STN7_TX_DP<113>")
	)
	(segment
		(start 22.592792 -309.518304)
		(end 25.832816 -304.669444)
		(width 0.1651)
		(layer "In7.Cu")
		(net "P5E_PEX0_STN7_TX_DP<113>")
	)
	(segment
		(start 44.070016 -302.20539)
		(end 44.070016 -302.435514)
		(width 0.1143)
		(layer "In7.Cu")
		(net "P5E_PEX0_STN7_TX_DP<113>")
	)
	(segment
		(start 17.850104 -319.573402)
		(end 18.450814 -316.551818)
		(width 0.1651)
		(layer "In7.Cu")
		(net "P5E_PEX0_STN7_TX_DP<113>")
	)
	(segment
		(start 22.732238 -340.886796)
		(end 17.850104 -324.796404)
		(width 0.1651)
		(layer "In7.Cu")
		(net "P5E_PEX0_STN7_TX_DP<113>")
	)
	(segment
		(start 44.070016 -302.435514)
		(end 44.184316 -302.549814)
		(width 0.1143)
		(layer "In7.Cu")
		(net "P5E_PEX0_STN7_TX_DP<113>")
	)
	(segment
		(start 43.84421 -301.979584)
		(end 44.070016 -302.20539)
		(width 0.1143)
		(layer "In7.Cu")
		(net "P5E_PEX0_STN7_TX_DP<113>")
	)
	(segment
		(start 44.184316 -302.549814)
		(end 44.449746 -302.549814)
		(width 0.1143)
		(layer "In7.Cu")
		(net "P5E_PEX0_STN7_TX_DP<113>")
	)
	(segment
		(start 19.360134 -314.356242)
		(end 22.592792 -309.518304)
		(width 0.1651)
		(layer "In7.Cu")
		(net "P5E_PEX0_STN7_TX_DP<113>")
	)
	(segment
		(start 35.6616 -301.933864)
		(end 35.70732 -301.979584)
		(width 0.1143)
		(layer "In7.Cu")
		(net "P5E_PEX0_STN7_TX_DP<113>")
	)
	(segment
		(start 22.441408 -342.439498)
		(end 22.732238 -342.148668)
		(width 0.1651)
		(layer "In7.Cu")
		(net "P5E_PEX0_STN7_TX_DP<113>")
	)
	(segment
		(start 17.850104 -324.796404)
		(end 17.850104 -319.573402)
		(width 0.1651)
		(layer "In7.Cu")
		(net "P5E_PEX0_STN7_TX_DP<113>")
	)
	(segment
		(start 35.633152 -301.933864)
		(end 35.6616 -301.933864)
		(width 0.1143)
		(layer "In7.Cu")
		(net "P5E_PEX0_STN7_TX_DP<113>")
	)
	(segment
		(start 18.450814 -316.551818)
		(end 19.360134 -314.356242)
		(width 0.1651)
		(layer "In7.Cu")
		(net "P5E_PEX0_STN7_TX_DP<113>")
	)
	(segment
		(start 26.886154 -303.805082)
		(end 31.403798 -301.933864)
		(width 0.1651)
		(layer "In7.Cu")
		(net "P5E_PEX0_STN7_TX_DP<113>")
	)
	(segment
		(start 25.832816 -304.669444)
		(end 26.886154 -303.805082)
		(width 0.1651)
		(layer "In7.Cu")
		(net "P5E_PEX0_STN7_TX_DP<113>")
	)
	(segment
		(start 35.70732 -301.979584)
		(end 43.84421 -301.979584)
		(width 0.1143)
		(layer "In7.Cu")
		(net "P5E_PEX0_STN7_TX_DP<113>")
	)
	(segment
		(start 22.732238 -342.148668)
		(end 22.732238 -340.886796)
		(width 0.1651)
		(layer "In7.Cu")
		(net "P5E_PEX0_STN7_TX_DP<113>")
	)
	(segment
		(start 154.793696 -110.408974)
		(end 154.162252 -110.408974)
		(width 0.13462)
		(layer "F.Cu")
		(net "P5E_PEX1_STN1_TX_DP<22>")
	)
	(segment
		(start 154.162252 -110.408974)
		(end 153.867612 -110.114334)
		(width 0.13462)
		(layer "F.Cu")
		(net "P5E_PEX1_STN1_TX_DP<22>")
	)
	(segment
		(start 155.113736 -110.088934)
		(end 154.793696 -110.408974)
		(width 0.13462)
		(layer "F.Cu")
		(net "P5E_PEX1_STN1_TX_DP<22>")
	)
	(segment
		(start 144.683734 -144.015714)
		(end 145.230342 -155.152598)
		(width 0.1651)
		(layer "In9.Cu")
		(net "P5E_PEX1_STN1_TX_DP<22>")
	)
	(segment
		(start 142.11173 -137.806684)
		(end 144.683734 -144.015714)
		(width 0.1651)
		(layer "In9.Cu")
		(net "P5E_PEX1_STN1_TX_DP<22>")
	)
	(segment
		(start 145.230342 -155.152598)
		(end 145.413476 -158.879032)
		(width 0.1651)
		(layer "In9.Cu")
		(net "P5E_PEX1_STN1_TX_DP<22>")
	)
	(segment
		(start 181.449726 -278.534368)
		(end 181.449726 -278.799798)
		(width 0.1143)
		(layer "In9.Cu")
		(net "P5E_PEX1_STN1_TX_DP<22>")
	)
	(segment
		(start 145.413476 -158.879032)
		(end 145.985992 -161.757614)
		(width 0.1651)
		(layer "In9.Cu")
		(net "P5E_PEX1_STN1_TX_DP<22>")
	)
	(segment
		(start 153.576782 -110.405164)
		(end 151.40813 -110.405164)
		(width 0.1651)
		(layer "In9.Cu")
		(net "P5E_PEX1_STN1_TX_DP<22>")
	)
	(segment
		(start 180.83403 -271.500346)
		(end 180.87975 -271.546066)
		(width 0.1143)
		(layer "In9.Cu")
		(net "P5E_PEX1_STN1_TX_DP<22>")
	)
	(segment
		(start 145.985992 -161.757614)
		(end 180.83403 -264.707116)
		(width 0.1651)
		(layer "In9.Cu")
		(net "P5E_PEX1_STN1_TX_DP<22>")
	)
	(segment
		(start 149.498304 -111.196374)
		(end 149.196806 -111.497872)
		(width 0.1651)
		(layer "In9.Cu")
		(net "P5E_PEX1_STN1_TX_DP<22>")
	)
	(segment
		(start 180.87975 -278.205184)
		(end 181.094634 -278.420068)
		(width 0.1143)
		(layer "In9.Cu")
		(net "P5E_PEX1_STN1_TX_DP<22>")
	)
	(segment
		(start 149.196806 -111.497872)
		(end 145.339816 -120.810782)
		(width 0.1651)
		(layer "In9.Cu")
		(net "P5E_PEX1_STN1_TX_DP<22>")
	)
	(segment
		(start 150.361142 -110.838742)
		(end 149.498304 -111.196374)
		(width 0.1651)
		(layer "In9.Cu")
		(net "P5E_PEX1_STN1_TX_DP<22>")
	)
	(segment
		(start 145.339816 -120.810782)
		(end 142.11173 -131.45135)
		(width 0.1651)
		(layer "In9.Cu")
		(net "P5E_PEX1_STN1_TX_DP<22>")
	)
	(segment
		(start 181.094634 -278.420068)
		(end 181.335426 -278.420068)
		(width 0.1143)
		(layer "In9.Cu")
		(net "P5E_PEX1_STN1_TX_DP<22>")
	)
	(segment
		(start 151.40813 -110.405164)
		(end 150.361396 -110.838742)
		(width 0.1651)
		(layer "In9.Cu")
		(net "P5E_PEX1_STN1_TX_DP<22>")
	)
	(segment
		(start 180.87975 -271.546066)
		(end 180.87975 -278.205184)
		(width 0.1143)
		(layer "In9.Cu")
		(net "P5E_PEX1_STN1_TX_DP<22>")
	)
	(segment
		(start 142.11173 -131.45135)
		(end 142.11173 -137.806684)
		(width 0.1651)
		(layer "In9.Cu")
		(net "P5E_PEX1_STN1_TX_DP<22>")
	)
	(segment
		(start 180.83403 -271.471898)
		(end 180.83403 -271.500346)
		(width 0.1143)
		(layer "In9.Cu")
		(net "P5E_PEX1_STN1_TX_DP<22>")
	)
	(segment
		(start 181.335426 -278.420068)
		(end 181.449726 -278.534368)
		(width 0.1143)
		(layer "In9.Cu")
		(net "P5E_PEX1_STN1_TX_DP<22>")
	)
	(segment
		(start 150.361396 -110.838742)
		(end 150.361142 -110.838742)
		(width 0.1651)
		(layer "In9.Cu")
		(net "P5E_PEX1_STN1_TX_DP<22>")
	)
	(segment
		(start 180.83403 -264.707116)
		(end 180.83403 -271.471898)
		(width 0.1651)
		(layer "In9.Cu")
		(net "P5E_PEX1_STN1_TX_DP<22>")
	)
	(segment
		(start 153.867612 -110.114334)
		(end 153.576782 -110.405164)
		(width 0.1651)
		(layer "In9.Cu")
		(net "P5E_PEX1_STN1_TX_DP<22>")
	)
	(segment
		(start 125.61824 -370.49583)
		(end 125.114812 -370.999258)
		(width 0.1651)
		(layer "In15.Cu")
		(net "P5E_PEX1_STN5_RX_DP<92>")
	)
	(segment
		(start 135.490712 -363.059472)
		(end 135.43788 -363.21238)
		(width 0.1651)
		(layer "In15.Cu")
		(net "P5E_PEX1_STN5_RX_DP<92>")
	)
	(segment
		(start 133.244844 -364.27918)
		(end 133.244844 -364.278926)
		(width 0.1651)
		(layer "In15.Cu")
		(net "P5E_PEX1_STN5_RX_DP<92>")
	)
	(segment
		(start 124.83719 -370.999258)
		(end 124.71019 -370.872258)
		(width 0.1651)
		(layer "In15.Cu")
		(net "P5E_PEX1_STN5_RX_DP<92>")
	)
	(segment
		(start 161.377884 -340.151212)
		(end 145.745708 -357.06558)
		(width 0.1651)
		(layer "In15.Cu")
		(net "P5E_PEX1_STN5_RX_DP<92>")
	)
	(segment
		(start 135.936482 -362.842556)
		(end 135.490712 -363.059472)
		(width 0.1651)
		(layer "In15.Cu")
		(net "P5E_PEX1_STN5_RX_DP<92>")
	)
	(segment
		(start 128.329944 -366.669574)
		(end 126.65202 -367.802922)
		(width 0.1651)
		(layer "In15.Cu")
		(net "P5E_PEX1_STN5_RX_DP<92>")
	)
	(segment
		(start 186.111134 -316.229492)
		(end 185.90641 -316.229492)
		(width 0.1143)
		(layer "In15.Cu")
		(net "P5E_PEX1_STN5_RX_DP<92>")
	)
	(segment
		(start 134.394194 -363.592872)
		(end 134.341362 -363.74578)
		(width 0.1651)
		(layer "In15.Cu")
		(net "P5E_PEX1_STN5_RX_DP<92>")
	)
	(segment
		(start 184.671208 -322.363338)
		(end 180.79974 -326.234806)
		(width 0.1651)
		(layer "In15.Cu")
		(net "P5E_PEX1_STN5_RX_DP<92>")
	)
	(segment
		(start 133.743446 -363.909356)
		(end 133.297676 -364.126272)
		(width 0.1651)
		(layer "In15.Cu")
		(net "P5E_PEX1_STN5_RX_DP<92>")
	)
	(segment
		(start 185.629804 -319.84188)
		(end 185.584084 -319.8876)
		(width 0.1143)
		(layer "In15.Cu")
		(net "P5E_PEX1_STN5_RX_DP<92>")
	)
	(segment
		(start 144.464278 -358.597454)
		(end 143.70558 -359.191052)
		(width 0.1651)
		(layer "In15.Cu")
		(net "P5E_PEX1_STN5_RX_DP<92>")
	)
	(segment
		(start 186.200034 -316.140592)
		(end 186.111134 -316.229492)
		(width 0.1143)
		(layer "In15.Cu")
		(net "P5E_PEX1_STN5_RX_DP<92>")
	)
	(segment
		(start 133.244844 -364.278926)
		(end 128.329944 -366.669574)
		(width 0.1651)
		(layer "In15.Cu")
		(net "P5E_PEX1_STN5_RX_DP<92>")
	)
	(segment
		(start 125.114812 -370.999258)
		(end 124.83719 -370.999258)
		(width 0.1651)
		(layer "In15.Cu")
		(net "P5E_PEX1_STN5_RX_DP<92>")
	)
	(segment
		(start 185.584084 -319.916048)
		(end 185.584084 -320.88074)
		(width 0.1651)
		(layer "In15.Cu")
		(net "P5E_PEX1_STN5_RX_DP<92>")
	)
	(segment
		(start 185.584084 -320.88074)
		(end 184.671208 -322.363338)
		(width 0.1651)
		(layer "In15.Cu")
		(net "P5E_PEX1_STN5_RX_DP<92>")
	)
	(segment
		(start 145.745708 -357.06558)
		(end 144.464278 -358.597454)
		(width 0.1651)
		(layer "In15.Cu")
		(net "P5E_PEX1_STN5_RX_DP<92>")
	)
	(segment
		(start 126.65202 -367.802922)
		(end 125.88875 -368.651028)
		(width 0.1651)
		(layer "In15.Cu")
		(net "P5E_PEX1_STN5_RX_DP<92>")
	)
	(segment
		(start 125.88875 -368.651028)
		(end 125.61824 -369.16106)
		(width 0.1651)
		(layer "In15.Cu")
		(net "P5E_PEX1_STN5_RX_DP<92>")
	)
	(segment
		(start 185.584084 -319.8876)
		(end 185.584084 -319.916048)
		(width 0.1143)
		(layer "In15.Cu")
		(net "P5E_PEX1_STN5_RX_DP<92>")
	)
	(segment
		(start 143.70558 -359.191052)
		(end 136.089136 -362.895388)
		(width 0.1651)
		(layer "In15.Cu")
		(net "P5E_PEX1_STN5_RX_DP<92>")
	)
	(segment
		(start 124.71019 -370.872258)
		(end 124.71019 -370.489988)
		(width 0.1651)
		(layer "In15.Cu")
		(net "P5E_PEX1_STN5_RX_DP<92>")
	)
	(segment
		(start 167.52951 -335.034382)
		(end 161.377884 -340.151212)
		(width 0.1651)
		(layer "In15.Cu")
		(net "P5E_PEX1_STN5_RX_DP<92>")
	)
	(segment
		(start 185.629804 -316.506098)
		(end 185.629804 -319.84188)
		(width 0.1143)
		(layer "In15.Cu")
		(net "P5E_PEX1_STN5_RX_DP<92>")
	)
	(segment
		(start 134.341362 -363.74578)
		(end 133.8961 -363.962188)
		(width 0.1651)
		(layer "In15.Cu")
		(net "P5E_PEX1_STN5_RX_DP<92>")
	)
	(segment
		(start 133.297676 -364.126272)
		(end 133.244844 -364.27918)
		(width 0.1651)
		(layer "In15.Cu")
		(net "P5E_PEX1_STN5_RX_DP<92>")
	)
	(segment
		(start 180.79974 -326.234806)
		(end 167.52951 -335.034382)
		(width 0.1651)
		(layer "In15.Cu")
		(net "P5E_PEX1_STN5_RX_DP<92>")
	)
	(segment
		(start 133.8961 -363.962188)
		(end 133.743446 -363.909356)
		(width 0.1651)
		(layer "In15.Cu")
		(net "P5E_PEX1_STN5_RX_DP<92>")
	)
	(segment
		(start 134.992618 -363.428788)
		(end 134.839964 -363.375956)
		(width 0.1651)
		(layer "In15.Cu")
		(net "P5E_PEX1_STN5_RX_DP<92>")
	)
	(segment
		(start 136.089136 -362.895388)
		(end 135.936482 -362.842556)
		(width 0.1651)
		(layer "In15.Cu")
		(net "P5E_PEX1_STN5_RX_DP<92>")
	)
	(segment
		(start 185.90641 -316.229492)
		(end 185.629804 -316.506098)
		(width 0.1143)
		(layer "In15.Cu")
		(net "P5E_PEX1_STN5_RX_DP<92>")
	)
	(segment
		(start 135.43788 -363.21238)
		(end 134.992618 -363.428788)
		(width 0.1651)
		(layer "In15.Cu")
		(net "P5E_PEX1_STN5_RX_DP<92>")
	)
	(segment
		(start 125.61824 -369.16106)
		(end 125.61824 -370.49583)
		(width 0.1651)
		(layer "In15.Cu")
		(net "P5E_PEX1_STN5_RX_DP<92>")
	)
	(segment
		(start 134.839964 -363.375956)
		(end 134.394194 -363.592872)
		(width 0.1651)
		(layer "In15.Cu")
		(net "P5E_PEX1_STN5_RX_DP<92>")
	)
	(segment
		(start 186.200034 -315.849762)
		(end 186.200034 -316.140592)
		(width 0.1143)
		(layer "In15.Cu")
		(net "P5E_PEX1_STN5_RX_DP<92>")
	)
	(segment
		(start 174.916592 -345.170506)
		(end 174.916592 -344.539062)
		(width 0.13462)
		(layer "F.Cu")
		(net "P5E_PEX1_STN7_TX_C_DP<118>")
	)
	(segment
		(start 174.916592 -344.539062)
		(end 174.596552 -344.219022)
		(width 0.13462)
		(layer "F.Cu")
		(net "P5E_PEX1_STN7_TX_C_DP<118>")
	)
	(segment
		(start 174.621952 -345.465146)
		(end 174.916592 -345.170506)
		(width 0.13462)
		(layer "F.Cu")
		(net "P5E_PEX1_STN7_TX_C_DP<118>")
	)
	(segment
		(start 174.912782 -346.397326)
		(end 174.912782 -345.755976)
		(width 0.1651)
		(layer "In11.Cu")
		(net "P5E_PEX1_STN7_TX_C_DP<118>")
	)
	(segment
		(start 173.358302 -347.951806)
		(end 174.912782 -346.397326)
		(width 0.1651)
		(layer "In11.Cu")
		(net "P5E_PEX1_STN7_TX_C_DP<118>")
	)
	(segment
		(start 160.504124 -387.908546)
		(end 158.355284 -386.313934)
		(width 0.1651)
		(layer "In11.Cu")
		(net "P5E_PEX1_STN7_TX_C_DP<118>")
	)
	(segment
		(start 170.971972 -392.363452)
		(end 170.538902 -392.096752)
		(width 0.1651)
		(layer "In11.Cu")
		(net "P5E_PEX1_STN7_TX_C_DP<118>")
	)
	(segment
		(start 169.884344 -391.90422)
		(end 169.435018 -391.694924)
		(width 0.1651)
		(layer "In11.Cu")
		(net "P5E_PEX1_STN7_TX_C_DP<118>")
	)
	(segment
		(start 170.019472 -391.854944)
		(end 169.884344 -391.90422)
		(width 0.1651)
		(layer "In11.Cu")
		(net "P5E_PEX1_STN7_TX_C_DP<118>")
	)
	(segment
		(start 158.203138 -367.312702)
		(end 159.8168 -365.656368)
		(width 0.1651)
		(layer "In11.Cu")
		(net "P5E_PEX1_STN7_TX_C_DP<118>")
	)
	(segment
		(start 169.385996 -391.56005)
		(end 168.937178 -391.351262)
		(width 0.1651)
		(layer "In11.Cu")
		(net "P5E_PEX1_STN7_TX_C_DP<118>")
	)
	(segment
		(start 173.993048 -394.994384)
		(end 173.273974 -394.27531)
		(width 0.1651)
		(layer "In11.Cu")
		(net "P5E_PEX1_STN7_TX_C_DP<118>")
	)
	(segment
		(start 167.719502 -390.896602)
		(end 167.270176 -390.687306)
		(width 0.1651)
		(layer "In11.Cu")
		(net "P5E_PEX1_STN7_TX_C_DP<118>")
	)
	(segment
		(start 170.538902 -392.096752)
		(end 170.019472 -391.854944)
		(width 0.1651)
		(layer "In11.Cu")
		(net "P5E_PEX1_STN7_TX_C_DP<118>")
	)
	(segment
		(start 159.8168 -365.656368)
		(end 170.776138 -361.056174)
		(width 0.1651)
		(layer "In11.Cu")
		(net "P5E_PEX1_STN7_TX_C_DP<118>")
	)
	(segment
		(start 171.42714 -392.763248)
		(end 171.005246 -392.503406)
		(width 0.1651)
		(layer "In11.Cu")
		(net "P5E_PEX1_STN7_TX_C_DP<118>")
	)
	(segment
		(start 173.358302 -358.47401)
		(end 173.358302 -347.951806)
		(width 0.1651)
		(layer "In11.Cu")
		(net "P5E_PEX1_STN7_TX_C_DP<118>")
	)
	(segment
		(start 173.273974 -394.27531)
		(end 173.13021 -394.27531)
		(width 0.1651)
		(layer "In11.Cu")
		(net "P5E_PEX1_STN7_TX_C_DP<118>")
	)
	(segment
		(start 167.270176 -390.687306)
		(end 167.2209 -390.552178)
		(width 0.1651)
		(layer "In11.Cu")
		(net "P5E_PEX1_STN7_TX_C_DP<118>")
	)
	(segment
		(start 173.23689 -400.899122)
		(end 173.852586 -400.899122)
		(width 0.1651)
		(layer "In11.Cu")
		(net "P5E_PEX1_STN7_TX_C_DP<118>")
	)
	(segment
		(start 167.220646 -390.552432)
		(end 164.07257 -389.087106)
		(width 0.1651)
		(layer "In11.Cu")
		(net "P5E_PEX1_STN7_TX_C_DP<118>")
	)
	(segment
		(start 173.993048 -400.75866)
		(end 173.993048 -394.994384)
		(width 0.1651)
		(layer "In11.Cu")
		(net "P5E_PEX1_STN7_TX_C_DP<118>")
	)
	(segment
		(start 173.852586 -400.899122)
		(end 173.993048 -400.75866)
		(width 0.1651)
		(layer "In11.Cu")
		(net "P5E_PEX1_STN7_TX_C_DP<118>")
	)
	(segment
		(start 167.85463 -390.847326)
		(end 167.719502 -390.896602)
		(width 0.1651)
		(layer "In11.Cu")
		(net "P5E_PEX1_STN7_TX_C_DP<118>")
	)
	(segment
		(start 173.10989 -400.772122)
		(end 173.23689 -400.899122)
		(width 0.1651)
		(layer "In11.Cu")
		(net "P5E_PEX1_STN7_TX_C_DP<118>")
	)
	(segment
		(start 173.10989 -400.390106)
		(end 173.10989 -400.772122)
		(width 0.1651)
		(layer "In11.Cu")
		(net "P5E_PEX1_STN7_TX_C_DP<118>")
	)
	(segment
		(start 172.77969 -393.92479)
		(end 172.77969 -393.781026)
		(width 0.1651)
		(layer "In11.Cu")
		(net "P5E_PEX1_STN7_TX_C_DP<118>")
	)
	(segment
		(start 157.458918 -382.31572)
		(end 157.623764 -368.845084)
		(width 0.1651)
		(layer "In11.Cu")
		(net "P5E_PEX1_STN7_TX_C_DP<118>")
	)
	(segment
		(start 164.07257 -389.087106)
		(end 160.504124 -387.908546)
		(width 0.1651)
		(layer "In11.Cu")
		(net "P5E_PEX1_STN7_TX_C_DP<118>")
	)
	(segment
		(start 167.2209 -390.552178)
		(end 167.220646 -390.552432)
		(width 0.1651)
		(layer "In11.Cu")
		(net "P5E_PEX1_STN7_TX_C_DP<118>")
	)
	(segment
		(start 174.912782 -345.755976)
		(end 174.621952 -345.465146)
		(width 0.1651)
		(layer "In11.Cu")
		(net "P5E_PEX1_STN7_TX_C_DP<118>")
	)
	(segment
		(start 168.80205 -391.400538)
		(end 168.352724 -391.191242)
		(width 0.1651)
		(layer "In11.Cu")
		(net "P5E_PEX1_STN7_TX_C_DP<118>")
	)
	(segment
		(start 170.776138 -361.056174)
		(end 173.358302 -358.47401)
		(width 0.1651)
		(layer "In11.Cu")
		(net "P5E_PEX1_STN7_TX_C_DP<118>")
	)
	(segment
		(start 171.98848 -392.989816)
		(end 171.56684 -392.730228)
		(width 0.1651)
		(layer "In11.Cu")
		(net "P5E_PEX1_STN7_TX_C_DP<118>")
	)
	(segment
		(start 169.435018 -391.694924)
		(end 169.385996 -391.56005)
		(width 0.1651)
		(layer "In11.Cu")
		(net "P5E_PEX1_STN7_TX_C_DP<118>")
	)
	(segment
		(start 172.77969 -393.781026)
		(end 171.98848 -392.989816)
		(width 0.1651)
		(layer "In11.Cu")
		(net "P5E_PEX1_STN7_TX_C_DP<118>")
	)
	(segment
		(start 171.005246 -392.503406)
		(end 170.971972 -392.363452)
		(width 0.1651)
		(layer "In11.Cu")
		(net "P5E_PEX1_STN7_TX_C_DP<118>")
	)
	(segment
		(start 157.623764 -368.845084)
		(end 158.203138 -367.312702)
		(width 0.1651)
		(layer "In11.Cu")
		(net "P5E_PEX1_STN7_TX_C_DP<118>")
	)
	(segment
		(start 168.352724 -391.191242)
		(end 168.303448 -391.056114)
		(width 0.1651)
		(layer "In11.Cu")
		(net "P5E_PEX1_STN7_TX_C_DP<118>")
	)
	(segment
		(start 173.13021 -394.27531)
		(end 172.77969 -393.92479)
		(width 0.1651)
		(layer "In11.Cu")
		(net "P5E_PEX1_STN7_TX_C_DP<118>")
	)
	(segment
		(start 171.56684 -392.730228)
		(end 171.42714 -392.763248)
		(width 0.1651)
		(layer "In11.Cu")
		(net "P5E_PEX1_STN7_TX_C_DP<118>")
	)
	(segment
		(start 168.937178 -391.351262)
		(end 168.80205 -391.400538)
		(width 0.1651)
		(layer "In11.Cu")
		(net "P5E_PEX1_STN7_TX_C_DP<118>")
	)
	(segment
		(start 157.655514 -384.583686)
		(end 157.458918 -382.31572)
		(width 0.1651)
		(layer "In11.Cu")
		(net "P5E_PEX1_STN7_TX_C_DP<118>")
	)
	(segment
		(start 168.303448 -391.056114)
		(end 167.85463 -390.847326)
		(width 0.1651)
		(layer "In11.Cu")
		(net "P5E_PEX1_STN7_TX_C_DP<118>")
	)
	(segment
		(start 158.355284 -386.313934)
		(end 157.655514 -384.583686)
		(width 0.1651)
		(layer "In11.Cu")
		(net "P5E_PEX1_STN7_TX_C_DP<118>")
	)
	(segment
		(start 82.928206 -124.076714)
		(end 83.248246 -124.396754)
		(width 0.13462)
		(layer "F.Cu")
		(net "P5E_PEX0_STN0_TX_DN<3>")
	)
	(segment
		(start 83.87969 -124.396754)
		(end 84.17433 -124.102114)
		(width 0.13462)
		(layer "F.Cu")
		(net "P5E_PEX0_STN0_TX_DN<3>")
	)
	(segment
		(start 83.248246 -124.396754)
		(end 83.87969 -124.396754)
		(width 0.13462)
		(layer "F.Cu")
		(net "P5E_PEX0_STN0_TX_DN<3>")
	)
	(segment
		(start 97.268284 -159.583628)
		(end 97.115376 -160.15589)
		(width 0.1651)
		(layer "In9.Cu")
		(net "P5E_PEX0_STN0_TX_DN<3>")
	)
	(segment
		(start 75.534266 -285.449772)
		(end 75.79995 -285.449772)
		(width 0.1143)
		(layer "In9.Cu")
		(net "P5E_PEX0_STN0_TX_DN<3>")
	)
	(segment
		(start 84.17433 -124.102114)
		(end 84.46516 -124.392944)
		(width 0.1651)
		(layer "In9.Cu")
		(net "P5E_PEX0_STN0_TX_DN<3>")
	)
	(segment
		(start 85.127338 -124.392944)
		(end 85.462364 -124.72797)
		(width 0.1651)
		(layer "In9.Cu")
		(net "P5E_PEX0_STN0_TX_DN<3>")
	)
	(segment
		(start 84.46516 -124.392944)
		(end 85.127338 -124.392944)
		(width 0.1651)
		(layer "In9.Cu")
		(net "P5E_PEX0_STN0_TX_DN<3>")
	)
	(segment
		(start 75.523852 -285.069788)
		(end 75.419966 -285.173674)
		(width 0.1143)
		(layer "In9.Cu")
		(net "P5E_PEX0_STN0_TX_DN<3>")
	)
	(segment
		(start 87.772494 -284.06344)
		(end 85.232748 -285.115508)
		(width 0.1651)
		(layer "In9.Cu")
		(net "P5E_PEX0_STN0_TX_DN<3>")
	)
	(segment
		(start 97.268284 -153.132536)
		(end 97.268284 -159.583628)
		(width 0.1651)
		(layer "In9.Cu")
		(net "P5E_PEX0_STN0_TX_DN<3>")
	)
	(segment
		(start 85.930486 -126.538228)
		(end 88.353646 -132.285486)
		(width 0.1651)
		(layer "In9.Cu")
		(net "P5E_PEX0_STN0_TX_DN<3>")
	)
	(segment
		(start 88.353646 -132.285486)
		(end 88.83142 -132.763514)
		(width 0.1651)
		(layer "In9.Cu")
		(net "P5E_PEX0_STN0_TX_DN<3>")
	)
	(segment
		(start 75.419966 -285.173674)
		(end 75.419966 -285.335472)
		(width 0.1143)
		(layer "In9.Cu")
		(net "P5E_PEX0_STN0_TX_DN<3>")
	)
	(segment
		(start 97.78365 -272.302224)
		(end 96.546162 -275.289772)
		(width 0.1651)
		(layer "In9.Cu")
		(net "P5E_PEX0_STN0_TX_DN<3>")
	)
	(segment
		(start 88.457278 -175.158908)
		(end 87.472266 -178.830478)
		(width 0.1651)
		(layer "In9.Cu")
		(net "P5E_PEX0_STN0_TX_DN<3>")
	)
	(segment
		(start 85.462364 -124.72797)
		(end 85.670644 -125.230636)
		(width 0.1651)
		(layer "In9.Cu")
		(net "P5E_PEX0_STN0_TX_DN<3>")
	)
	(segment
		(start 97.592134 -270.102838)
		(end 97.78365 -272.302224)
		(width 0.1651)
		(layer "In9.Cu")
		(net "P5E_PEX0_STN0_TX_DN<3>")
	)
	(segment
		(start 86.238334 -250.391168)
		(end 96.498664 -265.745722)
		(width 0.1651)
		(layer "In9.Cu")
		(net "P5E_PEX0_STN0_TX_DN<3>")
	)
	(segment
		(start 83.89366 -285.115508)
		(end 83.865212 -285.115508)
		(width 0.1143)
		(layer "In9.Cu")
		(net "P5E_PEX0_STN0_TX_DN<3>")
	)
	(segment
		(start 85.232748 -285.115508)
		(end 83.89366 -285.115508)
		(width 0.1651)
		(layer "In9.Cu")
		(net "P5E_PEX0_STN0_TX_DN<3>")
	)
	(segment
		(start 83.72729 -221.628208)
		(end 86.238334 -250.391168)
		(width 0.1651)
		(layer "In9.Cu")
		(net "P5E_PEX0_STN0_TX_DN<3>")
	)
	(segment
		(start 83.865212 -285.115508)
		(end 83.819492 -285.069788)
		(width 0.1143)
		(layer "In9.Cu")
		(net "P5E_PEX0_STN0_TX_DN<3>")
	)
	(segment
		(start 75.419966 -285.335472)
		(end 75.534266 -285.449772)
		(width 0.1143)
		(layer "In9.Cu")
		(net "P5E_PEX0_STN0_TX_DN<3>")
	)
	(segment
		(start 96.546162 -275.289772)
		(end 87.772494 -284.06344)
		(width 0.1651)
		(layer "In9.Cu")
		(net "P5E_PEX0_STN0_TX_DN<3>")
	)
	(segment
		(start 97.40265 -267.928344)
		(end 97.592134 -270.102838)
		(width 0.1651)
		(layer "In9.Cu")
		(net "P5E_PEX0_STN0_TX_DN<3>")
	)
	(segment
		(start 96.498664 -265.745722)
		(end 97.40265 -267.928344)
		(width 0.1651)
		(layer "In9.Cu")
		(net "P5E_PEX0_STN0_TX_DN<3>")
	)
	(segment
		(start 88.83142 -132.763514)
		(end 97.268284 -153.132536)
		(width 0.1651)
		(layer "In9.Cu")
		(net "P5E_PEX0_STN0_TX_DN<3>")
	)
	(segment
		(start 83.819492 -285.069788)
		(end 75.523852 -285.069788)
		(width 0.1143)
		(layer "In9.Cu")
		(net "P5E_PEX0_STN0_TX_DN<3>")
	)
	(segment
		(start 97.115376 -160.15589)
		(end 88.457278 -175.158908)
		(width 0.1651)
		(layer "In9.Cu")
		(net "P5E_PEX0_STN0_TX_DN<3>")
	)
	(segment
		(start 87.472266 -178.830478)
		(end 83.72729 -221.628208)
		(width 0.1651)
		(layer "In9.Cu")
		(net "P5E_PEX0_STN0_TX_DN<3>")
	)
	(segment
		(start 85.670644 -125.230636)
		(end 85.930486 -126.538228)
		(width 0.1651)
		(layer "In9.Cu")
		(net "P5E_PEX0_STN0_TX_DN<3>")
	)
	(segment
		(start 171.793916 -368.102896)
		(end 172.066966 -369.401598)
		(width 0.1651)
		(layer "In9.Cu")
		(net "P5E_PEX1_STN7_RX_DN<125>")
	)
	(segment
		(start 171.375324 -384.08102)
		(end 171.036996 -384.08102)
		(width 0.1651)
		(layer "In9.Cu")
		(net "P5E_PEX1_STN7_RX_DN<125>")
	)
	(segment
		(start 167.422322 -340.81847)
		(end 167.422322 -358.167178)
		(width 0.1651)
		(layer "In9.Cu")
		(net "P5E_PEX1_STN7_RX_DN<125>")
	)
	(segment
		(start 156.750004 -318.409066)
		(end 156.661104 -318.320166)
		(width 0.1143)
		(layer "In9.Cu")
		(net "P5E_PEX1_STN7_RX_DN<125>")
	)
	(segment
		(start 156.49829 -318.320166)
		(end 156.370274 -318.448182)
		(width 0.1143)
		(layer "In9.Cu")
		(net "P5E_PEX1_STN7_RX_DN<125>")
	)
	(segment
		(start 172.066966 -383.389378)
		(end 171.375324 -384.08102)
		(width 0.1651)
		(layer "In9.Cu")
		(net "P5E_PEX1_STN7_RX_DN<125>")
	)
	(segment
		(start 156.415994 -321.044062)
		(end 156.798518 -322.468494)
		(width 0.1651)
		(layer "In9.Cu")
		(net "P5E_PEX1_STN7_RX_DN<125>")
	)
	(segment
		(start 156.661104 -318.320166)
		(end 156.49829 -318.320166)
		(width 0.1143)
		(layer "In9.Cu")
		(net "P5E_PEX1_STN7_RX_DN<125>")
	)
	(segment
		(start 167.422322 -358.167178)
		(end 171.793916 -368.102896)
		(width 0.1651)
		(layer "In9.Cu")
		(net "P5E_PEX1_STN7_RX_DN<125>")
	)
	(segment
		(start 156.750004 -318.699896)
		(end 156.750004 -318.409066)
		(width 0.1143)
		(layer "In9.Cu")
		(net "P5E_PEX1_STN7_RX_DN<125>")
	)
	(segment
		(start 156.798518 -322.468494)
		(end 167.422322 -340.81847)
		(width 0.1651)
		(layer "In9.Cu")
		(net "P5E_PEX1_STN7_RX_DN<125>")
	)
	(segment
		(start 156.370274 -318.448182)
		(end 156.370274 -319.81648)
		(width 0.1143)
		(layer "In9.Cu")
		(net "P5E_PEX1_STN7_RX_DN<125>")
	)
	(segment
		(start 156.370274 -319.81648)
		(end 156.415994 -319.8622)
		(width 0.1143)
		(layer "In9.Cu")
		(net "P5E_PEX1_STN7_RX_DN<125>")
	)
	(segment
		(start 156.415994 -319.8622)
		(end 156.415994 -319.890648)
		(width 0.1143)
		(layer "In9.Cu")
		(net "P5E_PEX1_STN7_RX_DN<125>")
	)
	(segment
		(start 170.909996 -384.20802)
		(end 170.909996 -384.590036)
		(width 0.1651)
		(layer "In9.Cu")
		(net "P5E_PEX1_STN7_RX_DN<125>")
	)
	(segment
		(start 156.415994 -319.890648)
		(end 156.415994 -321.044062)
		(width 0.1651)
		(layer "In9.Cu")
		(net "P5E_PEX1_STN7_RX_DN<125>")
	)
	(segment
		(start 171.036996 -384.08102)
		(end 170.909996 -384.20802)
		(width 0.1651)
		(layer "In9.Cu")
		(net "P5E_PEX1_STN7_RX_DN<125>")
	)
	(segment
		(start 172.066966 -369.401598)
		(end 172.066966 -383.389378)
		(width 0.1651)
		(layer "In9.Cu")
		(net "P5E_PEX1_STN7_RX_DN<125>")
	)
	(segment
		(start 89.647522 -356.831646)
		(end 89.327482 -356.511606)
		(width 0.13462)
		(layer "F.Cu")
		(net "P5E_PEX0_STN5_TX_C_DP<94>")
	)
	(segment
		(start 89.352882 -357.75773)
		(end 89.647522 -357.46309)
		(width 0.13462)
		(layer "F.Cu")
		(net "P5E_PEX0_STN5_TX_C_DP<94>")
	)
	(segment
		(start 89.647522 -357.46309)
		(end 89.647522 -356.831646)
		(width 0.13462)
		(layer "F.Cu")
		(net "P5E_PEX0_STN5_TX_C_DP<94>")
	)
	(segment
		(start 85.109812 -378.67209)
		(end 85.236812 -378.79909)
		(width 0.1651)
		(layer "In7.Cu")
		(net "P5E_PEX0_STN5_TX_C_DP<94>")
	)
	(segment
		(start 86.35873 -366.99952)
		(end 86.303866 -366.866678)
		(width 0.1651)
		(layer "In7.Cu")
		(net "P5E_PEX0_STN5_TX_C_DP<94>")
	)
	(segment
		(start 86.493604 -366.40897)
		(end 86.626446 -366.353852)
		(width 0.1651)
		(layer "In7.Cu")
		(net "P5E_PEX0_STN5_TX_C_DP<94>")
	)
	(segment
		(start 87.083392 -365.25073)
		(end 87.083138 -365.25073)
		(width 0.1651)
		(layer "In7.Cu")
		(net "P5E_PEX0_STN5_TX_C_DP<94>")
	)
	(segment
		(start 86.626446 -366.353852)
		(end 86.81593 -365.896398)
		(width 0.1651)
		(layer "In7.Cu")
		(net "P5E_PEX0_STN5_TX_C_DP<94>")
	)
	(segment
		(start 89.643712 -359.069386)
		(end 89.643712 -358.04856)
		(width 0.1651)
		(layer "In7.Cu")
		(net "P5E_PEX0_STN5_TX_C_DP<94>")
	)
	(segment
		(start 87.231474 -364.693708)
		(end 87.421466 -364.235746)
		(width 0.1651)
		(layer "In7.Cu")
		(net "P5E_PEX0_STN5_TX_C_DP<94>")
	)
	(segment
		(start 86.760812 -365.763556)
		(end 86.95055 -365.305848)
		(width 0.1651)
		(layer "In7.Cu")
		(net "P5E_PEX0_STN5_TX_C_DP<94>")
	)
	(segment
		(start 87.272622 -364.793276)
		(end 87.272876 -364.793276)
		(width 0.1651)
		(layer "In7.Cu")
		(net "P5E_PEX0_STN5_TX_C_DP<94>")
	)
	(segment
		(start 87.272876 -364.793276)
		(end 87.231474 -364.693708)
		(width 0.1651)
		(layer "In7.Cu")
		(net "P5E_PEX0_STN5_TX_C_DP<94>")
	)
	(segment
		(start 86.81593 -365.896398)
		(end 86.760812 -365.763556)
		(width 0.1651)
		(layer "In7.Cu")
		(net "P5E_PEX0_STN5_TX_C_DP<94>")
	)
	(segment
		(start 86.002114 -378.370084)
		(end 86.002114 -367.860834)
		(width 0.1651)
		(layer "In7.Cu")
		(net "P5E_PEX0_STN5_TX_C_DP<94>")
	)
	(segment
		(start 87.52078 -364.194344)
		(end 89.643712 -359.069386)
		(width 0.1651)
		(layer "In7.Cu")
		(net "P5E_PEX0_STN5_TX_C_DP<94>")
	)
	(segment
		(start 89.643712 -358.04856)
		(end 89.352882 -357.75773)
		(width 0.1651)
		(layer "In7.Cu")
		(net "P5E_PEX0_STN5_TX_C_DP<94>")
	)
	(segment
		(start 85.109812 -378.290074)
		(end 85.109812 -378.67209)
		(width 0.1651)
		(layer "In7.Cu")
		(net "P5E_PEX0_STN5_TX_C_DP<94>")
	)
	(segment
		(start 87.083138 -365.25073)
		(end 87.272622 -364.793276)
		(width 0.1651)
		(layer "In7.Cu")
		(net "P5E_PEX0_STN5_TX_C_DP<94>")
	)
	(segment
		(start 87.521034 -364.194598)
		(end 87.52078 -364.194344)
		(width 0.1651)
		(layer "In7.Cu")
		(net "P5E_PEX0_STN5_TX_C_DP<94>")
	)
	(segment
		(start 85.236812 -378.79909)
		(end 85.573108 -378.79909)
		(width 0.1651)
		(layer "In7.Cu")
		(net "P5E_PEX0_STN5_TX_C_DP<94>")
	)
	(segment
		(start 86.95055 -365.305848)
		(end 87.083392 -365.25073)
		(width 0.1651)
		(layer "In7.Cu")
		(net "P5E_PEX0_STN5_TX_C_DP<94>")
	)
	(segment
		(start 85.573108 -378.79909)
		(end 86.002114 -378.370084)
		(width 0.1651)
		(layer "In7.Cu")
		(net "P5E_PEX0_STN5_TX_C_DP<94>")
	)
	(segment
		(start 87.421466 -364.235746)
		(end 87.521034 -364.194598)
		(width 0.1651)
		(layer "In7.Cu")
		(net "P5E_PEX0_STN5_TX_C_DP<94>")
	)
	(segment
		(start 86.002114 -367.860834)
		(end 86.35873 -366.99952)
		(width 0.1651)
		(layer "In7.Cu")
		(net "P5E_PEX0_STN5_TX_C_DP<94>")
	)
	(segment
		(start 86.303866 -366.866678)
		(end 86.493604 -366.40897)
		(width 0.1651)
		(layer "In7.Cu")
		(net "P5E_PEX0_STN5_TX_C_DP<94>")
	)
	(segment
		(start 140.706348 -357.75773)
		(end 140.411708 -357.46309)
		(width 0.13462)
		(layer "F.Cu")
		(net "P5E_PEX1_STN5_TX_C_DN<86>")
	)
	(segment
		(start 140.411708 -357.46309)
		(end 140.411708 -356.831646)
		(width 0.13462)
		(layer "F.Cu")
		(net "P5E_PEX1_STN5_TX_C_DN<86>")
	)
	(segment
		(start 140.411708 -356.831646)
		(end 140.731748 -356.511606)
		(width 0.13462)
		(layer "F.Cu")
		(net "P5E_PEX1_STN5_TX_C_DN<86>")
	)
	(segment
		(start 142.03934 -383.965704)
		(end 141.787626 -386.49402)
		(width 0.1651)
		(layer "In7.Cu")
		(net "P5E_PEX1_STN5_TX_C_DN<86>")
	)
	(segment
		(start 129.585974 -405.080724)
		(end 129.237232 -405.080724)
		(width 0.1651)
		(layer "In7.Cu")
		(net "P5E_PEX1_STN5_TX_C_DN<86>")
	)
	(segment
		(start 130.169666 -396.311882)
		(end 130.169412 -396.312136)
		(width 0.1651)
		(layer "In7.Cu")
		(net "P5E_PEX1_STN5_TX_C_DN<86>")
	)
	(segment
		(start 138.788648 -390.967214)
		(end 137.88009 -391.49274)
		(width 0.1651)
		(layer "In7.Cu")
		(net "P5E_PEX1_STN5_TX_C_DN<86>")
	)
	(segment
		(start 140.706348 -357.75773)
		(end 140.415518 -358.04856)
		(width 0.1651)
		(layer "In7.Cu")
		(net "P5E_PEX1_STN5_TX_C_DN<86>")
	)
	(segment
		(start 137.88009 -391.49274)
		(end 132.141722 -393.910312)
		(width 0.1651)
		(layer "In7.Cu")
		(net "P5E_PEX1_STN5_TX_C_DN<86>")
	)
	(segment
		(start 142.370048 -369.857274)
		(end 142.03934 -383.245106)
		(width 0.1651)
		(layer "In7.Cu")
		(net "P5E_PEX1_STN5_TX_C_DN<86>")
	)
	(segment
		(start 140.570458 -389.485886)
		(end 138.788648 -390.967214)
		(width 0.1651)
		(layer "In7.Cu")
		(net "P5E_PEX1_STN5_TX_C_DN<86>")
	)
	(segment
		(start 141.305788 -388.086092)
		(end 140.945108 -388.772908)
		(width 0.1651)
		(layer "In7.Cu")
		(net "P5E_PEX1_STN5_TX_C_DN<86>")
	)
	(segment
		(start 141.787626 -386.49402)
		(end 141.305788 -388.086092)
		(width 0.1651)
		(layer "In7.Cu")
		(net "P5E_PEX1_STN5_TX_C_DN<86>")
	)
	(segment
		(start 129.237232 -405.080724)
		(end 129.109978 -405.207978)
		(width 0.1651)
		(layer "In7.Cu")
		(net "P5E_PEX1_STN5_TX_C_DN<86>")
	)
	(segment
		(start 142.370048 -368.700812)
		(end 142.370048 -369.857274)
		(width 0.1651)
		(layer "In7.Cu")
		(net "P5E_PEX1_STN5_TX_C_DN<86>")
	)
	(segment
		(start 132.141722 -393.910312)
		(end 130.640328 -394.922248)
		(width 0.1651)
		(layer "In7.Cu")
		(net "P5E_PEX1_STN5_TX_C_DN<86>")
	)
	(segment
		(start 130.169412 -396.312136)
		(end 130.169412 -404.497286)
		(width 0.1651)
		(layer "In7.Cu")
		(net "P5E_PEX1_STN5_TX_C_DN<86>")
	)
	(segment
		(start 140.415518 -358.875838)
		(end 142.370048 -368.700812)
		(width 0.1651)
		(layer "In7.Cu")
		(net "P5E_PEX1_STN5_TX_C_DN<86>")
	)
	(segment
		(start 129.109978 -405.207978)
		(end 129.109978 -405.589994)
		(width 0.1651)
		(layer "In7.Cu")
		(net "P5E_PEX1_STN5_TX_C_DN<86>")
	)
	(segment
		(start 140.945108 -388.772908)
		(end 140.570458 -389.485886)
		(width 0.1651)
		(layer "In7.Cu")
		(net "P5E_PEX1_STN5_TX_C_DN<86>")
	)
	(segment
		(start 142.03934 -383.245106)
		(end 142.03934 -383.965704)
		(width 0.1651)
		(layer "In7.Cu")
		(net "P5E_PEX1_STN5_TX_C_DN<86>")
	)
	(segment
		(start 130.640328 -394.922248)
		(end 130.169666 -396.311882)
		(width 0.1651)
		(layer "In7.Cu")
		(net "P5E_PEX1_STN5_TX_C_DN<86>")
	)
	(segment
		(start 140.415518 -358.04856)
		(end 140.415518 -358.875838)
		(width 0.1651)
		(layer "In7.Cu")
		(net "P5E_PEX1_STN5_TX_C_DN<86>")
	)
	(segment
		(start 130.169412 -404.497286)
		(end 129.585974 -405.080724)
		(width 0.1651)
		(layer "In7.Cu")
		(net "P5E_PEX1_STN5_TX_C_DN<86>")
	)
	(segment
		(start 36.371784 -111.895382)
		(end 36.051744 -112.215422)
		(width 0.13462)
		(layer "F.Cu")
		(net "P5E_PEX0_STN1_TX_DN<23>")
	)
	(segment
		(start 36.051744 -112.215422)
		(end 35.4203 -112.215422)
		(width 0.13462)
		(layer "F.Cu")
		(net "P5E_PEX0_STN1_TX_DN<23>")
	)
	(segment
		(start 35.4203 -112.215422)
		(end 35.12566 -111.920782)
		(width 0.13462)
		(layer "F.Cu")
		(net "P5E_PEX0_STN1_TX_DN<23>")
	)
	(segment
		(start 33.873948 -112.472978)
		(end 34.135314 -112.211612)
		(width 0.1651)
		(layer "In9.Cu")
		(net "P5E_PEX0_STN1_TX_DN<23>")
	)
	(segment
		(start 66.299842 -280.699718)
		(end 66.299842 -280.434288)
		(width 0.1143)
		(layer "In9.Cu")
		(net "P5E_PEX0_STN1_TX_DN<23>")
	)
	(segment
		(start 65.683892 -271.554448)
		(end 65.683892 -271.526)
		(width 0.1143)
		(layer "In9.Cu")
		(net "P5E_PEX0_STN1_TX_DN<23>")
	)
	(segment
		(start 65.729612 -271.600168)
		(end 65.683892 -271.554448)
		(width 0.1143)
		(layer "In9.Cu")
		(net "P5E_PEX0_STN1_TX_DN<23>")
	)
	(segment
		(start 65.683892 -264.494518)
		(end 30.854142 -161.59861)
		(width 0.1651)
		(layer "In9.Cu")
		(net "P5E_PEX0_STN1_TX_DN<23>")
	)
	(segment
		(start 65.729612 -280.10485)
		(end 65.729612 -271.600168)
		(width 0.1143)
		(layer "In9.Cu")
		(net "P5E_PEX0_STN1_TX_DN<23>")
	)
	(segment
		(start 29.904944 -151.234902)
		(end 29.904944 -151.235156)
		(width 0.1651)
		(layer "In9.Cu")
		(net "P5E_PEX0_STN1_TX_DN<23>")
	)
	(segment
		(start 66.185542 -280.319988)
		(end 65.94475 -280.319988)
		(width 0.1143)
		(layer "In9.Cu")
		(net "P5E_PEX0_STN1_TX_DN<23>")
	)
	(segment
		(start 29.5402 -143.809212)
		(end 26.979372 -137.626852)
		(width 0.1651)
		(layer "In9.Cu")
		(net "P5E_PEX0_STN1_TX_DN<23>")
	)
	(segment
		(start 26.979372 -131.610608)
		(end 29.804614 -122.296936)
		(width 0.1651)
		(layer "In9.Cu")
		(net "P5E_PEX0_STN1_TX_DN<23>")
	)
	(segment
		(start 29.804614 -122.296936)
		(end 33.873948 -112.472978)
		(width 0.1651)
		(layer "In9.Cu")
		(net "P5E_PEX0_STN1_TX_DN<23>")
	)
	(segment
		(start 26.979372 -137.626852)
		(end 26.979372 -131.610608)
		(width 0.1651)
		(layer "In9.Cu")
		(net "P5E_PEX0_STN1_TX_DN<23>")
	)
	(segment
		(start 29.904944 -151.235156)
		(end 29.5402 -143.809212)
		(width 0.1651)
		(layer "In9.Cu")
		(net "P5E_PEX0_STN1_TX_DN<23>")
	)
	(segment
		(start 34.135314 -112.211612)
		(end 34.83483 -112.211612)
		(width 0.1651)
		(layer "In9.Cu")
		(net "P5E_PEX0_STN1_TX_DN<23>")
	)
	(segment
		(start 65.94475 -280.319988)
		(end 65.729612 -280.10485)
		(width 0.1143)
		(layer "In9.Cu")
		(net "P5E_PEX0_STN1_TX_DN<23>")
	)
	(segment
		(start 34.83483 -112.211612)
		(end 35.12566 -111.920782)
		(width 0.1651)
		(layer "In9.Cu")
		(net "P5E_PEX0_STN1_TX_DN<23>")
	)
	(segment
		(start 30.854142 -161.59861)
		(end 30.269942 -158.661354)
		(width 0.1651)
		(layer "In9.Cu")
		(net "P5E_PEX0_STN1_TX_DN<23>")
	)
	(segment
		(start 66.299842 -280.434288)
		(end 66.185542 -280.319988)
		(width 0.1143)
		(layer "In9.Cu")
		(net "P5E_PEX0_STN1_TX_DN<23>")
	)
	(segment
		(start 65.683892 -271.526)
		(end 65.683892 -264.494518)
		(width 0.1651)
		(layer "In9.Cu")
		(net "P5E_PEX0_STN1_TX_DN<23>")
	)
	(segment
		(start 30.269942 -158.661354)
		(end 29.904944 -151.234902)
		(width 0.1651)
		(layer "In9.Cu")
		(net "P5E_PEX0_STN1_TX_DN<23>")
	)
	(segment
		(start 184.916064 -319.916048)
		(end 184.916064 -319.8876)
		(width 0.1143)
		(layer "In15.Cu")
		(net "P5E_PEX1_STN5_RX_DN<91>")
	)
	(segment
		(start 123.699778 -371.65661)
		(end 123.699778 -369.138454)
		(width 0.1651)
		(layer "In15.Cu")
		(net "P5E_PEX1_STN5_RX_DN<91>")
	)
	(segment
		(start 142.428214 -341.097108)
		(end 144.445736 -339.907372)
		(width 0.1651)
		(layer "In15.Cu")
		(net "P5E_PEX1_STN5_RX_DN<91>")
	)
	(segment
		(start 144.445736 -339.907372)
		(end 178.668426 -326.054466)
		(width 0.1651)
		(layer "In15.Cu")
		(net "P5E_PEX1_STN5_RX_DN<91>")
	)
	(segment
		(start 122.510042 -372.508018)
		(end 122.637042 -372.381018)
		(width 0.1651)
		(layer "In15.Cu")
		(net "P5E_PEX1_STN5_RX_DN<91>")
	)
	(segment
		(start 124.162058 -368.273838)
		(end 127.50419 -366.04194)
		(width 0.1651)
		(layer "In15.Cu")
		(net "P5E_PEX1_STN5_RX_DN<91>")
	)
	(segment
		(start 141.969998 -341.776812)
		(end 142.199106 -341.43696)
		(width 0.1651)
		(layer "In15.Cu")
		(net "P5E_PEX1_STN5_RX_DN<91>")
	)
	(segment
		(start 184.916064 -320.626994)
		(end 184.916064 -319.916048)
		(width 0.1651)
		(layer "In15.Cu")
		(net "P5E_PEX1_STN5_RX_DN<91>")
	)
	(segment
		(start 141.969998 -358.140508)
		(end 141.969998 -341.776812)
		(width 0.1651)
		(layer "In15.Cu")
		(net "P5E_PEX1_STN5_RX_DN<91>")
	)
	(segment
		(start 123.699778 -369.138454)
		(end 124.162058 -368.273838)
		(width 0.1651)
		(layer "In15.Cu")
		(net "P5E_PEX1_STN5_RX_DN<91>")
	)
	(segment
		(start 127.50419 -366.04194)
		(end 141.296136 -359.225342)
		(width 0.1651)
		(layer "In15.Cu")
		(net "P5E_PEX1_STN5_RX_DN<91>")
	)
	(segment
		(start 185.250074 -318.409066)
		(end 185.250074 -318.699896)
		(width 0.1143)
		(layer "In15.Cu")
		(net "P5E_PEX1_STN5_RX_DN<91>")
	)
	(segment
		(start 185.035444 -318.320166)
		(end 185.161174 -318.320166)
		(width 0.1143)
		(layer "In15.Cu")
		(net "P5E_PEX1_STN5_RX_DN<91>")
	)
	(segment
		(start 142.19936 -341.436706)
		(end 142.428214 -341.097108)
		(width 0.1651)
		(layer "In15.Cu")
		(net "P5E_PEX1_STN5_RX_DN<91>")
	)
	(segment
		(start 122.510042 -372.890034)
		(end 122.510042 -372.508018)
		(width 0.1651)
		(layer "In15.Cu")
		(net "P5E_PEX1_STN5_RX_DN<91>")
	)
	(segment
		(start 184.870344 -319.84188)
		(end 184.870344 -318.485266)
		(width 0.1143)
		(layer "In15.Cu")
		(net "P5E_PEX1_STN5_RX_DN<91>")
	)
	(segment
		(start 185.161174 -318.320166)
		(end 185.250074 -318.409066)
		(width 0.1143)
		(layer "In15.Cu")
		(net "P5E_PEX1_STN5_RX_DN<91>")
	)
	(segment
		(start 141.296136 -359.225342)
		(end 141.969998 -358.140508)
		(width 0.1651)
		(layer "In15.Cu")
		(net "P5E_PEX1_STN5_RX_DN<91>")
	)
	(segment
		(start 182.67553 -323.396864)
		(end 184.069228 -322.003166)
		(width 0.1651)
		(layer "In15.Cu")
		(net "P5E_PEX1_STN5_RX_DN<91>")
	)
	(segment
		(start 184.069228 -322.003166)
		(end 184.916064 -320.626994)
		(width 0.1651)
		(layer "In15.Cu")
		(net "P5E_PEX1_STN5_RX_DN<91>")
	)
	(segment
		(start 122.637042 -372.381018)
		(end 122.97537 -372.381018)
		(width 0.1651)
		(layer "In15.Cu")
		(net "P5E_PEX1_STN5_RX_DN<91>")
	)
	(segment
		(start 122.97537 -372.381018)
		(end 123.699778 -371.65661)
		(width 0.1651)
		(layer "In15.Cu")
		(net "P5E_PEX1_STN5_RX_DN<91>")
	)
	(segment
		(start 184.870344 -318.485266)
		(end 185.035444 -318.320166)
		(width 0.1143)
		(layer "In15.Cu")
		(net "P5E_PEX1_STN5_RX_DN<91>")
	)
	(segment
		(start 184.916064 -319.8876)
		(end 184.870344 -319.84188)
		(width 0.1143)
		(layer "In15.Cu")
		(net "P5E_PEX1_STN5_RX_DN<91>")
	)
	(segment
		(start 142.199106 -341.43696)
		(end 142.19936 -341.436706)
		(width 0.1651)
		(layer "In15.Cu")
		(net "P5E_PEX1_STN5_RX_DN<91>")
	)
	(segment
		(start 178.668426 -326.054466)
		(end 182.67553 -323.396864)
		(width 0.1651)
		(layer "In15.Cu")
		(net "P5E_PEX1_STN5_RX_DN<91>")
	)
	(segment
		(start 38.693852 -136.409684)
		(end 38.062408 -136.409684)
		(width 0.13462)
		(layer "F.Cu")
		(net "P5E_PEX0_STN1_TX_DP<31>")
	)
	(segment
		(start 38.062408 -136.409684)
		(end 37.767768 -136.704324)
		(width 0.13462)
		(layer "F.Cu")
		(net "P5E_PEX0_STN1_TX_DP<31>")
	)
	(segment
		(start 39.013892 -136.729724)
		(end 38.693852 -136.409684)
		(width 0.13462)
		(layer "F.Cu")
		(net "P5E_PEX0_STN1_TX_DP<31>")
	)
	(segment
		(start 37.152072 -137.480802)
		(end 37.008562 -137.480802)
		(width 0.1651)
		(layer "In9.Cu")
		(net "P5E_PEX0_STN1_TX_DP<31>")
	)
	(segment
		(start 39.322248 -144.59966)
		(end 39.225982 -144.114012)
		(width 0.1651)
		(layer "In9.Cu")
		(net "P5E_PEX0_STN1_TX_DP<31>")
	)
	(segment
		(start 39.089584 -143.42872)
		(end 38.993318 -142.943072)
		(width 0.1651)
		(layer "In9.Cu")
		(net "P5E_PEX0_STN1_TX_DP<31>")
	)
	(segment
		(start 39.771066 -146.336512)
		(end 39.6748 -145.85061)
		(width 0.1651)
		(layer "In9.Cu")
		(net "P5E_PEX0_STN1_TX_DP<31>")
	)
	(segment
		(start 37.476938 -136.413494)
		(end 37.767768 -136.704324)
		(width 0.1651)
		(layer "In9.Cu")
		(net "P5E_PEX0_STN1_TX_DP<31>")
	)
	(segment
		(start 38.607746 -140.481812)
		(end 38.513766 -140.008102)
		(width 0.1651)
		(layer "In9.Cu")
		(net "P5E_PEX0_STN1_TX_DP<31>")
	)
	(segment
		(start 40.161464 -148.822918)
		(end 40.25138 -148.688552)
		(width 0.1651)
		(layer "In9.Cu")
		(net "P5E_PEX0_STN1_TX_DP<31>")
	)
	(segment
		(start 73.565766 -271.554448)
		(end 73.565766 -271.526)
		(width 0.1143)
		(layer "In9.Cu")
		(net "P5E_PEX0_STN1_TX_DP<31>")
	)
	(segment
		(start 73.899776 -280.015188)
		(end 73.785476 -280.129488)
		(width 0.1143)
		(layer "In9.Cu")
		(net "P5E_PEX0_STN1_TX_DP<31>")
	)
	(segment
		(start 38.760654 -141.772132)
		(end 38.84041 -141.652752)
		(width 0.1651)
		(layer "In9.Cu")
		(net "P5E_PEX0_STN1_TX_DP<31>")
	)
	(segment
		(start 38.993318 -142.943072)
		(end 39.073074 -142.823692)
		(width 0.1651)
		(layer "In9.Cu")
		(net "P5E_PEX0_STN1_TX_DP<31>")
	)
	(segment
		(start 40.02024 -148.11248)
		(end 39.923974 -147.626832)
		(width 0.1651)
		(layer "In9.Cu")
		(net "P5E_PEX0_STN1_TX_DP<31>")
	)
	(segment
		(start 38.85692 -142.25778)
		(end 38.760654 -141.772132)
		(width 0.1651)
		(layer "In9.Cu")
		(net "P5E_PEX0_STN1_TX_DP<31>")
	)
	(segment
		(start 39.225982 -144.114012)
		(end 39.305738 -143.994632)
		(width 0.1651)
		(layer "In9.Cu")
		(net "P5E_PEX0_STN1_TX_DP<31>")
	)
	(segment
		(start 36.867592 -136.413494)
		(end 37.476938 -136.413494)
		(width 0.1651)
		(layer "In9.Cu")
		(net "P5E_PEX0_STN1_TX_DP<31>")
	)
	(segment
		(start 39.6748 -145.85061)
		(end 39.554912 -145.7706)
		(width 0.1651)
		(layer "In9.Cu")
		(net "P5E_PEX0_STN1_TX_DP<31>")
	)
	(segment
		(start 47.397416 -185.260488)
		(end 40.161464 -148.822918)
		(width 0.1651)
		(layer "In9.Cu")
		(net "P5E_PEX0_STN1_TX_DP<31>")
	)
	(segment
		(start 38.84041 -141.652752)
		(end 38.744144 -141.16685)
		(width 0.1651)
		(layer "In9.Cu")
		(net "P5E_PEX0_STN1_TX_DP<31>")
	)
	(segment
		(start 38.394132 -139.928346)
		(end 38.290754 -139.407392)
		(width 0.1651)
		(layer "In9.Cu")
		(net "P5E_PEX0_STN1_TX_DP<31>")
	)
	(segment
		(start 38.744144 -141.16685)
		(end 38.624256 -141.08684)
		(width 0.1651)
		(layer "In9.Cu")
		(net "P5E_PEX0_STN1_TX_DP<31>")
	)
	(segment
		(start 73.899776 -279.749504)
		(end 73.899776 -280.015188)
		(width 0.1143)
		(layer "In9.Cu")
		(net "P5E_PEX0_STN1_TX_DP<31>")
	)
	(segment
		(start 38.52799 -140.601192)
		(end 38.607746 -140.481812)
		(width 0.1651)
		(layer "In9.Cu")
		(net "P5E_PEX0_STN1_TX_DP<31>")
	)
	(segment
		(start 40.00373 -147.507452)
		(end 39.907464 -147.02155)
		(width 0.1651)
		(layer "In9.Cu")
		(net "P5E_PEX0_STN1_TX_DP<31>")
	)
	(segment
		(start 36.6395 -136.641586)
		(end 36.867592 -136.413494)
		(width 0.1651)
		(layer "In9.Cu")
		(net "P5E_PEX0_STN1_TX_DP<31>")
	)
	(segment
		(start 39.554912 -145.7706)
		(end 39.458646 -145.284952)
		(width 0.1651)
		(layer "In9.Cu")
		(net "P5E_PEX0_STN1_TX_DP<31>")
	)
	(segment
		(start 39.538402 -145.165572)
		(end 39.442136 -144.67967)
		(width 0.1651)
		(layer "In9.Cu")
		(net "P5E_PEX0_STN1_TX_DP<31>")
	)
	(segment
		(start 37.493702 -137.965942)
		(end 37.493702 -137.822178)
		(width 0.1651)
		(layer "In9.Cu")
		(net "P5E_PEX0_STN1_TX_DP<31>")
	)
	(segment
		(start 73.785476 -280.129488)
		(end 73.623678 -280.129488)
		(width 0.1143)
		(layer "In9.Cu")
		(net "P5E_PEX0_STN1_TX_DP<31>")
	)
	(segment
		(start 40.25138 -148.688552)
		(end 40.15486 -148.202396)
		(width 0.1651)
		(layer "In9.Cu")
		(net "P5E_PEX0_STN1_TX_DP<31>")
	)
	(segment
		(start 39.69131 -146.455892)
		(end 39.771066 -146.336512)
		(width 0.1651)
		(layer "In9.Cu")
		(net "P5E_PEX0_STN1_TX_DP<31>")
	)
	(segment
		(start 39.458646 -145.284952)
		(end 39.538402 -145.165572)
		(width 0.1651)
		(layer "In9.Cu")
		(net "P5E_PEX0_STN1_TX_DP<31>")
	)
	(segment
		(start 73.623678 -280.129488)
		(end 73.520046 -280.025856)
		(width 0.1143)
		(layer "In9.Cu")
		(net "P5E_PEX0_STN1_TX_DP<31>")
	)
	(segment
		(start 39.907464 -147.02155)
		(end 39.787576 -146.94154)
		(width 0.1651)
		(layer "In9.Cu")
		(net "P5E_PEX0_STN1_TX_DP<31>")
	)
	(segment
		(start 38.290754 -139.407392)
		(end 37.834824 -138.307064)
		(width 0.1651)
		(layer "In9.Cu")
		(net "P5E_PEX0_STN1_TX_DP<31>")
	)
	(segment
		(start 39.305738 -143.994632)
		(end 39.209472 -143.50873)
		(width 0.1651)
		(layer "In9.Cu")
		(net "P5E_PEX0_STN1_TX_DP<31>")
	)
	(segment
		(start 36.6395 -137.11174)
		(end 36.6395 -136.641586)
		(width 0.1651)
		(layer "In9.Cu")
		(net "P5E_PEX0_STN1_TX_DP<31>")
	)
	(segment
		(start 39.442136 -144.67967)
		(end 39.322248 -144.59966)
		(width 0.1651)
		(layer "In9.Cu")
		(net "P5E_PEX0_STN1_TX_DP<31>")
	)
	(segment
		(start 38.976808 -142.33779)
		(end 38.85692 -142.25778)
		(width 0.1651)
		(layer "In9.Cu")
		(net "P5E_PEX0_STN1_TX_DP<31>")
	)
	(segment
		(start 40.15486 -148.202396)
		(end 40.02024 -148.11248)
		(width 0.1651)
		(layer "In9.Cu")
		(net "P5E_PEX0_STN1_TX_DP<31>")
	)
	(segment
		(start 38.513766 -140.008102)
		(end 38.394132 -139.928346)
		(width 0.1651)
		(layer "In9.Cu")
		(net "P5E_PEX0_STN1_TX_DP<31>")
	)
	(segment
		(start 39.209472 -143.50873)
		(end 39.089584 -143.42872)
		(width 0.1651)
		(layer "In9.Cu")
		(net "P5E_PEX0_STN1_TX_DP<31>")
	)
	(segment
		(start 37.834824 -138.307064)
		(end 37.493702 -137.965942)
		(width 0.1651)
		(layer "In9.Cu")
		(net "P5E_PEX0_STN1_TX_DP<31>")
	)
	(segment
		(start 38.624256 -141.08684)
		(end 38.52799 -140.601192)
		(width 0.1651)
		(layer "In9.Cu")
		(net "P5E_PEX0_STN1_TX_DP<31>")
	)
	(segment
		(start 73.565766 -262.564118)
		(end 47.397416 -185.260488)
		(width 0.1651)
		(layer "In9.Cu")
		(net "P5E_PEX0_STN1_TX_DP<31>")
	)
	(segment
		(start 73.565766 -271.526)
		(end 73.565766 -262.564118)
		(width 0.1651)
		(layer "In9.Cu")
		(net "P5E_PEX0_STN1_TX_DP<31>")
	)
	(segment
		(start 39.923974 -147.626832)
		(end 40.00373 -147.507452)
		(width 0.1651)
		(layer "In9.Cu")
		(net "P5E_PEX0_STN1_TX_DP<31>")
	)
	(segment
		(start 39.073074 -142.823692)
		(end 38.976808 -142.33779)
		(width 0.1651)
		(layer "In9.Cu")
		(net "P5E_PEX0_STN1_TX_DP<31>")
	)
	(segment
		(start 39.787576 -146.94154)
		(end 39.69131 -146.455892)
		(width 0.1651)
		(layer "In9.Cu")
		(net "P5E_PEX0_STN1_TX_DP<31>")
	)
	(segment
		(start 73.520046 -280.025856)
		(end 73.520046 -271.600168)
		(width 0.1143)
		(layer "In9.Cu")
		(net "P5E_PEX0_STN1_TX_DP<31>")
	)
	(segment
		(start 37.008562 -137.480802)
		(end 36.6395 -137.11174)
		(width 0.1651)
		(layer "In9.Cu")
		(net "P5E_PEX0_STN1_TX_DP<31>")
	)
	(segment
		(start 37.493702 -137.822178)
		(end 37.152072 -137.480802)
		(width 0.1651)
		(layer "In9.Cu")
		(net "P5E_PEX0_STN1_TX_DP<31>")
	)
	(segment
		(start 73.520046 -271.600168)
		(end 73.565766 -271.554448)
		(width 0.1143)
		(layer "In9.Cu")
		(net "P5E_PEX0_STN1_TX_DP<31>")
	)
	(segment
		(start 155.711144 -316.419992)
		(end 155.800044 -316.508892)
		(width 0.1143)
		(layer "In9.Cu")
		(net "P5E_PEX1_STN7_RX_DN<124>")
	)
	(segment
		(start 169.437304 -367.849404)
		(end 164.44468 -358.401874)
		(width 0.1651)
		(layer "In9.Cu")
		(net "P5E_PEX1_STN7_RX_DN<124>")
	)
	(segment
		(start 164.44468 -358.401874)
		(end 164.313362 -357.87203)
		(width 0.1651)
		(layer "In9.Cu")
		(net "P5E_PEX1_STN7_RX_DN<124>")
	)
	(segment
		(start 169.867072 -382.289812)
		(end 169.867072 -369.583208)
		(width 0.1651)
		(layer "In9.Cu")
		(net "P5E_PEX1_STN7_RX_DN<124>")
	)
	(segment
		(start 155.420568 -316.568582)
		(end 155.569158 -316.419992)
		(width 0.1143)
		(layer "In9.Cu")
		(net "P5E_PEX1_STN7_RX_DN<124>")
	)
	(segment
		(start 169.175684 -382.9812)
		(end 169.867072 -382.289812)
		(width 0.1651)
		(layer "In9.Cu")
		(net "P5E_PEX1_STN7_RX_DN<124>")
	)
	(segment
		(start 164.313362 -347.709744)
		(end 163.60267 -343.817956)
		(width 0.1651)
		(layer "In9.Cu")
		(net "P5E_PEX1_STN7_RX_DN<124>")
	)
	(segment
		(start 155.466288 -321.234816)
		(end 155.466288 -319.941448)
		(width 0.1651)
		(layer "In9.Cu")
		(net "P5E_PEX1_STN7_RX_DN<124>")
	)
	(segment
		(start 155.466288 -319.913)
		(end 155.420568 -319.86728)
		(width 0.1143)
		(layer "In9.Cu")
		(net "P5E_PEX1_STN7_RX_DN<124>")
	)
	(segment
		(start 155.837636 -323.267832)
		(end 155.466288 -321.234816)
		(width 0.1651)
		(layer "In9.Cu")
		(net "P5E_PEX1_STN7_RX_DN<124>")
	)
	(segment
		(start 155.800044 -316.508892)
		(end 155.800044 -316.799722)
		(width 0.1143)
		(layer "In9.Cu")
		(net "P5E_PEX1_STN7_RX_DN<124>")
	)
	(segment
		(start 169.867072 -369.583208)
		(end 169.437304 -367.849404)
		(width 0.1651)
		(layer "In9.Cu")
		(net "P5E_PEX1_STN7_RX_DN<124>")
	)
	(segment
		(start 155.569158 -316.419992)
		(end 155.711144 -316.419992)
		(width 0.1143)
		(layer "In9.Cu")
		(net "P5E_PEX1_STN7_RX_DN<124>")
	)
	(segment
		(start 155.466288 -319.941448)
		(end 155.466288 -319.913)
		(width 0.1143)
		(layer "In9.Cu")
		(net "P5E_PEX1_STN7_RX_DN<124>")
	)
	(segment
		(start 164.313362 -357.87203)
		(end 164.313362 -347.709744)
		(width 0.1651)
		(layer "In9.Cu")
		(net "P5E_PEX1_STN7_RX_DN<124>")
	)
	(segment
		(start 163.60267 -343.817956)
		(end 155.837636 -323.267832)
		(width 0.1651)
		(layer "In9.Cu")
		(net "P5E_PEX1_STN7_RX_DN<124>")
	)
	(segment
		(start 155.420568 -319.86728)
		(end 155.420568 -316.568582)
		(width 0.1143)
		(layer "In9.Cu")
		(net "P5E_PEX1_STN7_RX_DN<124>")
	)
	(segment
		(start 168.710102 -383.1082)
		(end 168.837102 -382.9812)
		(width 0.1651)
		(layer "In9.Cu")
		(net "P5E_PEX1_STN7_RX_DN<124>")
	)
	(segment
		(start 168.837102 -382.9812)
		(end 169.175684 -382.9812)
		(width 0.1651)
		(layer "In9.Cu")
		(net "P5E_PEX1_STN7_RX_DN<124>")
	)
	(segment
		(start 168.710102 -383.490216)
		(end 168.710102 -383.1082)
		(width 0.1651)
		(layer "In9.Cu")
		(net "P5E_PEX1_STN7_RX_DN<124>")
	)
	(segment
		(start 93.030802 -351.316798)
		(end 93.030802 -350.685354)
		(width 0.13462)
		(layer "F.Cu")
		(net "P5E_PEX0_STN5_TX_C_DN<95>")
	)
	(segment
		(start 93.030802 -350.685354)
		(end 93.350842 -350.365314)
		(width 0.13462)
		(layer "F.Cu")
		(net "P5E_PEX0_STN5_TX_C_DN<95>")
	)
	(segment
		(start 93.325442 -351.611438)
		(end 93.030802 -351.316798)
		(width 0.13462)
		(layer "F.Cu")
		(net "P5E_PEX0_STN5_TX_C_DN<95>")
	)
	(segment
		(start 87.30996 -380.308104)
		(end 87.43696 -380.181104)
		(width 0.1651)
		(layer "In7.Cu")
		(net "P5E_PEX0_STN5_TX_C_DN<95>")
	)
	(segment
		(start 91.480132 -354.107242)
		(end 93.034612 -352.552762)
		(width 0.1651)
		(layer "In7.Cu")
		(net "P5E_PEX0_STN5_TX_C_DN<95>")
	)
	(segment
		(start 93.034612 -352.552762)
		(end 93.034612 -351.902268)
		(width 0.1651)
		(layer "In7.Cu")
		(net "P5E_PEX0_STN5_TX_C_DN<95>")
	)
	(segment
		(start 87.30996 -380.69012)
		(end 87.30996 -380.308104)
		(width 0.1651)
		(layer "In7.Cu")
		(net "P5E_PEX0_STN5_TX_C_DN<95>")
	)
	(segment
		(start 87.968074 -380.181104)
		(end 88.484202 -379.664976)
		(width 0.1651)
		(layer "In7.Cu")
		(net "P5E_PEX0_STN5_TX_C_DN<95>")
	)
	(segment
		(start 88.484202 -379.664976)
		(end 88.484202 -369.099084)
		(width 0.1651)
		(layer "In7.Cu")
		(net "P5E_PEX0_STN5_TX_C_DN<95>")
	)
	(segment
		(start 88.484202 -369.099084)
		(end 91.480132 -359.223056)
		(width 0.1651)
		(layer "In7.Cu")
		(net "P5E_PEX0_STN5_TX_C_DN<95>")
	)
	(segment
		(start 93.034612 -351.902268)
		(end 93.325442 -351.611438)
		(width 0.1651)
		(layer "In7.Cu")
		(net "P5E_PEX0_STN5_TX_C_DN<95>")
	)
	(segment
		(start 87.43696 -380.181104)
		(end 87.968074 -380.181104)
		(width 0.1651)
		(layer "In7.Cu")
		(net "P5E_PEX0_STN5_TX_C_DN<95>")
	)
	(segment
		(start 91.480132 -359.223056)
		(end 91.480132 -354.107242)
		(width 0.1651)
		(layer "In7.Cu")
		(net "P5E_PEX0_STN5_TX_C_DN<95>")
	)
	(segment
		(start 38.693852 -132.535422)
		(end 38.062408 -132.535422)
		(width 0.13462)
		(layer "F.Cu")
		(net "P5E_PEX0_STN1_TX_DN<29>")
	)
	(segment
		(start 39.013892 -132.215382)
		(end 38.693852 -132.535422)
		(width 0.13462)
		(layer "F.Cu")
		(net "P5E_PEX0_STN1_TX_DN<29>")
	)
	(segment
		(start 38.062408 -132.535422)
		(end 37.767768 -132.240782)
		(width 0.13462)
		(layer "F.Cu")
		(net "P5E_PEX0_STN1_TX_DN<29>")
	)
	(segment
		(start 36.104576 -156.69641)
		(end 35.371786 -141.801342)
		(width 0.1651)
		(layer "In9.Cu")
		(net "P5E_PEX0_STN1_TX_DN<29>")
	)
	(segment
		(start 37.476938 -132.531612)
		(end 37.767768 -132.240782)
		(width 0.1651)
		(layer "In9.Cu")
		(net "P5E_PEX0_STN1_TX_DN<29>")
	)
	(segment
		(start 71.383906 -271.526)
		(end 71.383906 -263.217406)
		(width 0.1651)
		(layer "In9.Cu")
		(net "P5E_PEX0_STN1_TX_DN<29>")
	)
	(segment
		(start 71.383906 -271.554448)
		(end 71.383906 -271.526)
		(width 0.1143)
		(layer "In9.Cu")
		(net "P5E_PEX0_STN1_TX_DN<29>")
	)
	(segment
		(start 71.999856 -280.699718)
		(end 71.999856 -280.434288)
		(width 0.1143)
		(layer "In9.Cu")
		(net "P5E_PEX0_STN1_TX_DN<29>")
	)
	(segment
		(start 71.429626 -271.600168)
		(end 71.383906 -271.554448)
		(width 0.1143)
		(layer "In9.Cu")
		(net "P5E_PEX0_STN1_TX_DN<29>")
	)
	(segment
		(start 71.383906 -263.217406)
		(end 37.215572 -162.281108)
		(width 0.1651)
		(layer "In9.Cu")
		(net "P5E_PEX0_STN1_TX_DN<29>")
	)
	(segment
		(start 34.170112 -132.972048)
		(end 35.233356 -132.531612)
		(width 0.1651)
		(layer "In9.Cu")
		(net "P5E_PEX0_STN1_TX_DN<29>")
	)
	(segment
		(start 35.371786 -141.801342)
		(end 32.77362 -135.529828)
		(width 0.1651)
		(layer "In9.Cu")
		(net "P5E_PEX0_STN1_TX_DN<29>")
	)
	(segment
		(start 71.885556 -280.319988)
		(end 71.644764 -280.319988)
		(width 0.1143)
		(layer "In9.Cu")
		(net "P5E_PEX0_STN1_TX_DN<29>")
	)
	(segment
		(start 37.215572 -162.281108)
		(end 36.104576 -156.69641)
		(width 0.1651)
		(layer "In9.Cu")
		(net "P5E_PEX0_STN1_TX_DN<29>")
	)
	(segment
		(start 32.77362 -135.529828)
		(end 32.77362 -134.743444)
		(width 0.1651)
		(layer "In9.Cu")
		(net "P5E_PEX0_STN1_TX_DN<29>")
	)
	(segment
		(start 32.77362 -134.743444)
		(end 33.038796 -134.103364)
		(width 0.1651)
		(layer "In9.Cu")
		(net "P5E_PEX0_STN1_TX_DN<29>")
	)
	(segment
		(start 35.233356 -132.531612)
		(end 37.476938 -132.531612)
		(width 0.1651)
		(layer "In9.Cu")
		(net "P5E_PEX0_STN1_TX_DN<29>")
	)
	(segment
		(start 71.644764 -280.319988)
		(end 71.429626 -280.10485)
		(width 0.1143)
		(layer "In9.Cu")
		(net "P5E_PEX0_STN1_TX_DN<29>")
	)
	(segment
		(start 33.038796 -134.103364)
		(end 34.170112 -132.972048)
		(width 0.1651)
		(layer "In9.Cu")
		(net "P5E_PEX0_STN1_TX_DN<29>")
	)
	(segment
		(start 71.999856 -280.434288)
		(end 71.885556 -280.319988)
		(width 0.1143)
		(layer "In9.Cu")
		(net "P5E_PEX0_STN1_TX_DN<29>")
	)
	(segment
		(start 71.429626 -280.10485)
		(end 71.429626 -271.600168)
		(width 0.1143)
		(layer "In9.Cu")
		(net "P5E_PEX0_STN1_TX_DN<29>")
	)
	(segment
		(start 161.308034 -358.206802)
		(end 161.308034 -358.207056)
		(width 0.1651)
		(layer "In9.Cu")
		(net "P5E_PEX1_STN7_RX_DN<123>")
	)
	(segment
		(start 167.316658 -367.84915)
		(end 167.666924 -369.102132)
		(width 0.1651)
		(layer "In9.Cu")
		(net "P5E_PEX1_STN7_RX_DN<123>")
	)
	(segment
		(start 154.470354 -319.81648)
		(end 154.516074 -319.8622)
		(width 0.1143)
		(layer "In9.Cu")
		(net "P5E_PEX1_STN7_RX_DN<123>")
	)
	(segment
		(start 154.516074 -321.414648)
		(end 154.87777 -324.782434)
		(width 0.1651)
		(layer "In9.Cu")
		(net "P5E_PEX1_STN7_RX_DN<123>")
	)
	(segment
		(start 154.87777 -324.782434)
		(end 161.204402 -353.90836)
		(width 0.1651)
		(layer "In9.Cu")
		(net "P5E_PEX1_STN7_RX_DN<123>")
	)
	(segment
		(start 154.516074 -319.8622)
		(end 154.516074 -319.890648)
		(width 0.1143)
		(layer "In9.Cu")
		(net "P5E_PEX1_STN7_RX_DN<123>")
	)
	(segment
		(start 166.636954 -384.08102)
		(end 166.509954 -384.20802)
		(width 0.1651)
		(layer "In9.Cu")
		(net "P5E_PEX1_STN7_RX_DN<123>")
	)
	(segment
		(start 166.509954 -384.20802)
		(end 166.509954 -384.590036)
		(width 0.1651)
		(layer "In9.Cu")
		(net "P5E_PEX1_STN7_RX_DN<123>")
	)
	(segment
		(start 154.761184 -318.320166)
		(end 154.597862 -318.320166)
		(width 0.1143)
		(layer "In9.Cu")
		(net "P5E_PEX1_STN7_RX_DN<123>")
	)
	(segment
		(start 154.850084 -318.409066)
		(end 154.761184 -318.320166)
		(width 0.1143)
		(layer "In9.Cu")
		(net "P5E_PEX1_STN7_RX_DN<123>")
	)
	(segment
		(start 167.666924 -383.389378)
		(end 166.975282 -384.08102)
		(width 0.1651)
		(layer "In9.Cu")
		(net "P5E_PEX1_STN7_RX_DN<123>")
	)
	(segment
		(start 166.975282 -384.08102)
		(end 166.636954 -384.08102)
		(width 0.1651)
		(layer "In9.Cu")
		(net "P5E_PEX1_STN7_RX_DN<123>")
	)
	(segment
		(start 161.308034 -358.207056)
		(end 167.316658 -367.848896)
		(width 0.1651)
		(layer "In9.Cu")
		(net "P5E_PEX1_STN7_RX_DN<123>")
	)
	(segment
		(start 154.516074 -319.890648)
		(end 154.516074 -321.414648)
		(width 0.1651)
		(layer "In9.Cu")
		(net "P5E_PEX1_STN7_RX_DN<123>")
	)
	(segment
		(start 154.850084 -318.699896)
		(end 154.850084 -318.409066)
		(width 0.1143)
		(layer "In9.Cu")
		(net "P5E_PEX1_STN7_RX_DN<123>")
	)
	(segment
		(start 154.597862 -318.320166)
		(end 154.470354 -318.447674)
		(width 0.1143)
		(layer "In9.Cu")
		(net "P5E_PEX1_STN7_RX_DN<123>")
	)
	(segment
		(start 167.666924 -369.102132)
		(end 167.666924 -383.389378)
		(width 0.1651)
		(layer "In9.Cu")
		(net "P5E_PEX1_STN7_RX_DN<123>")
	)
	(segment
		(start 154.470354 -318.447674)
		(end 154.470354 -319.81648)
		(width 0.1143)
		(layer "In9.Cu")
		(net "P5E_PEX1_STN7_RX_DN<123>")
	)
	(segment
		(start 161.204402 -357.845106)
		(end 161.308034 -358.206802)
		(width 0.1651)
		(layer "In9.Cu")
		(net "P5E_PEX1_STN7_RX_DN<123>")
	)
	(segment
		(start 167.316658 -367.848896)
		(end 167.316658 -367.84915)
		(width 0.1651)
		(layer "In9.Cu")
		(net "P5E_PEX1_STN7_RX_DN<123>")
	)
	(segment
		(start 161.204402 -353.90836)
		(end 161.204402 -357.845106)
		(width 0.1651)
		(layer "In9.Cu")
		(net "P5E_PEX1_STN7_RX_DN<123>")
	)
	(segment
		(start 38.062408 -110.683294)
		(end 37.767768 -110.977934)
		(width 0.13462)
		(layer "F.Cu")
		(net "P5E_PEX0_STN1_TX_DN<22>")
	)
	(segment
		(start 38.693852 -110.683294)
		(end 38.062408 -110.683294)
		(width 0.13462)
		(layer "F.Cu")
		(net "P5E_PEX0_STN1_TX_DN<22>")
	)
	(segment
		(start 39.013892 -111.003334)
		(end 38.693852 -110.683294)
		(width 0.13462)
		(layer "F.Cu")
		(net "P5E_PEX0_STN1_TX_DN<22>")
	)
	(segment
		(start 36.77666 -110.801404)
		(end 36.89096 -110.687104)
		(width 0.1651)
		(layer "In9.Cu")
		(net "P5E_PEX0_STN1_TX_DN<22>")
	)
	(segment
		(start 31.200852 -117.11178)
		(end 31.38551 -116.665756)
		(width 0.1651)
		(layer "In9.Cu")
		(net "P5E_PEX0_STN1_TX_DN<22>")
	)
	(segment
		(start 31.508192 -116.070634)
		(end 31.507938 -116.070634)
		(width 0.1651)
		(layer "In9.Cu")
		(net "P5E_PEX0_STN1_TX_DN<22>")
	)
	(segment
		(start 32.571436 -113.80216)
		(end 32.756094 -113.356136)
		(width 0.1651)
		(layer "In9.Cu")
		(net "P5E_PEX0_STN1_TX_DN<22>")
	)
	(segment
		(start 65.015872 -271.500346)
		(end 65.015872 -271.471898)
		(width 0.1143)
		(layer "In9.Cu")
		(net "P5E_PEX0_STN1_TX_DN<22>")
	)
	(segment
		(start 28.863036 -143.952976)
		(end 26.293572 -137.75055)
		(width 0.1651)
		(layer "In9.Cu")
		(net "P5E_PEX0_STN1_TX_DN<22>")
	)
	(segment
		(start 32.42183 -113.864136)
		(end 32.571436 -113.80216)
		(width 0.1651)
		(layer "In9.Cu")
		(net "P5E_PEX0_STN1_TX_DN<22>")
	)
	(segment
		(start 65.349628 -278.115268)
		(end 65.235328 -278.229568)
		(width 0.1143)
		(layer "In9.Cu")
		(net "P5E_PEX0_STN1_TX_DN<22>")
	)
	(segment
		(start 36.17976 -110.687104)
		(end 36.29406 -110.801404)
		(width 0.1651)
		(layer "In9.Cu")
		(net "P5E_PEX0_STN1_TX_DN<22>")
	)
	(segment
		(start 26.293572 -137.75055)
		(end 26.293572 -131.49326)
		(width 0.1651)
		(layer "In9.Cu")
		(net "P5E_PEX0_STN1_TX_DN<22>")
	)
	(segment
		(start 31.38551 -116.665756)
		(end 31.323534 -116.516404)
		(width 0.1651)
		(layer "In9.Cu")
		(net "P5E_PEX0_STN1_TX_DN<22>")
	)
	(segment
		(start 35.364166 -110.687104)
		(end 36.17976 -110.687104)
		(width 0.1651)
		(layer "In9.Cu")
		(net "P5E_PEX0_STN1_TX_DN<22>")
	)
	(segment
		(start 33.335722 -111.657638)
		(end 33.557972 -111.435388)
		(width 0.1651)
		(layer "In9.Cu")
		(net "P5E_PEX0_STN1_TX_DN<22>")
	)
	(segment
		(start 30.928564 -117.768878)
		(end 30.866842 -117.619526)
		(width 0.1651)
		(layer "In9.Cu")
		(net "P5E_PEX0_STN1_TX_DN<22>")
	)
	(segment
		(start 32.11449 -114.905536)
		(end 32.299148 -114.459512)
		(width 0.1651)
		(layer "In9.Cu")
		(net "P5E_PEX0_STN1_TX_DN<22>")
	)
	(segment
		(start 31.964884 -114.967512)
		(end 32.11449 -114.905536)
		(width 0.1651)
		(layer "In9.Cu")
		(net "P5E_PEX0_STN1_TX_DN<22>")
	)
	(segment
		(start 32.299148 -114.459512)
		(end 32.237426 -114.31016)
		(width 0.1651)
		(layer "In9.Cu")
		(net "P5E_PEX0_STN1_TX_DN<22>")
	)
	(segment
		(start 31.78048 -115.413282)
		(end 31.964884 -114.967512)
		(width 0.1651)
		(layer "In9.Cu")
		(net "P5E_PEX0_STN1_TX_DN<22>")
	)
	(segment
		(start 36.29406 -110.801404)
		(end 36.77666 -110.801404)
		(width 0.1651)
		(layer "In9.Cu")
		(net "P5E_PEX0_STN1_TX_DN<22>")
	)
	(segment
		(start 34.856674 -111.021368)
		(end 34.918396 -110.871762)
		(width 0.1651)
		(layer "In9.Cu")
		(net "P5E_PEX0_STN1_TX_DN<22>")
	)
	(segment
		(start 26.293572 -131.49326)
		(end 29.505656 -120.906032)
		(width 0.1651)
		(layer "In9.Cu")
		(net "P5E_PEX0_STN1_TX_DN<22>")
	)
	(segment
		(start 30.743906 -118.214902)
		(end 30.928564 -117.768878)
		(width 0.1651)
		(layer "In9.Cu")
		(net "P5E_PEX0_STN1_TX_DN<22>")
	)
	(segment
		(start 64.970152 -271.546066)
		(end 65.015872 -271.500346)
		(width 0.1143)
		(layer "In9.Cu")
		(net "P5E_PEX0_STN1_TX_DN<22>")
	)
	(segment
		(start 32.237426 -114.31016)
		(end 32.42183 -113.86439)
		(width 0.1651)
		(layer "In9.Cu")
		(net "P5E_PEX0_STN1_TX_DN<22>")
	)
	(segment
		(start 33.557972 -111.435388)
		(end 34.261044 -111.14405)
		(width 0.1651)
		(layer "In9.Cu")
		(net "P5E_PEX0_STN1_TX_DN<22>")
	)
	(segment
		(start 32.878776 -112.761014)
		(end 32.878776 -112.76076)
		(width 0.1651)
		(layer "In9.Cu")
		(net "P5E_PEX0_STN1_TX_DN<22>")
	)
	(segment
		(start 64.970152 -278.12619)
		(end 64.970152 -271.546066)
		(width 0.1143)
		(layer "In9.Cu")
		(net "P5E_PEX0_STN1_TX_DN<22>")
	)
	(segment
		(start 30.158944 -161.684716)
		(end 29.594048 -158.844488)
		(width 0.1651)
		(layer "In9.Cu")
		(net "P5E_PEX0_STN1_TX_DN<22>")
	)
	(segment
		(start 30.5943 -118.276878)
		(end 30.743906 -118.214902)
		(width 0.1651)
		(layer "In9.Cu")
		(net "P5E_PEX0_STN1_TX_DN<22>")
	)
	(segment
		(start 37.476938 -110.687104)
		(end 37.767768 -110.977934)
		(width 0.1651)
		(layer "In9.Cu")
		(net "P5E_PEX0_STN1_TX_DN<22>")
	)
	(segment
		(start 65.349628 -277.849838)
		(end 65.349628 -278.115268)
		(width 0.1143)
		(layer "In9.Cu")
		(net "P5E_PEX0_STN1_TX_DN<22>")
	)
	(segment
		(start 34.261044 -111.14405)
		(end 34.410396 -111.206026)
		(width 0.1651)
		(layer "In9.Cu")
		(net "P5E_PEX0_STN1_TX_DN<22>")
	)
	(segment
		(start 34.918396 -110.871762)
		(end 35.364166 -110.687104)
		(width 0.1651)
		(layer "In9.Cu")
		(net "P5E_PEX0_STN1_TX_DN<22>")
	)
	(segment
		(start 65.07353 -278.229568)
		(end 64.970152 -278.12619)
		(width 0.1143)
		(layer "In9.Cu")
		(net "P5E_PEX0_STN1_TX_DN<22>")
	)
	(segment
		(start 32.694372 -113.206784)
		(end 32.878776 -112.761014)
		(width 0.1651)
		(layer "In9.Cu")
		(net "P5E_PEX0_STN1_TX_DN<22>")
	)
	(segment
		(start 65.015872 -264.660634)
		(end 30.158944 -161.684716)
		(width 0.1651)
		(layer "In9.Cu")
		(net "P5E_PEX0_STN1_TX_DN<22>")
	)
	(segment
		(start 33.151318 -112.103408)
		(end 33.335722 -111.657638)
		(width 0.1651)
		(layer "In9.Cu")
		(net "P5E_PEX0_STN1_TX_DN<22>")
	)
	(segment
		(start 29.230066 -151.43353)
		(end 29.230066 -151.433276)
		(width 0.1651)
		(layer "In9.Cu")
		(net "P5E_PEX0_STN1_TX_DN<22>")
	)
	(segment
		(start 32.756094 -113.356136)
		(end 32.694372 -113.206784)
		(width 0.1651)
		(layer "In9.Cu")
		(net "P5E_PEX0_STN1_TX_DN<22>")
	)
	(segment
		(start 29.594048 -158.844488)
		(end 29.230066 -151.43353)
		(width 0.1651)
		(layer "In9.Cu")
		(net "P5E_PEX0_STN1_TX_DN<22>")
	)
	(segment
		(start 31.051246 -117.173756)
		(end 31.200852 -117.11178)
		(width 0.1651)
		(layer "In9.Cu")
		(net "P5E_PEX0_STN1_TX_DN<22>")
	)
	(segment
		(start 33.028382 -112.698784)
		(end 33.21304 -112.25276)
		(width 0.1651)
		(layer "In9.Cu")
		(net "P5E_PEX0_STN1_TX_DN<22>")
	)
	(segment
		(start 65.235328 -278.229568)
		(end 65.07353 -278.229568)
		(width 0.1143)
		(layer "In9.Cu")
		(net "P5E_PEX0_STN1_TX_DN<22>")
	)
	(segment
		(start 30.5943 -118.277386)
		(end 30.5943 -118.276878)
		(width 0.1651)
		(layer "In9.Cu")
		(net "P5E_PEX0_STN1_TX_DN<22>")
	)
	(segment
		(start 31.842202 -115.562634)
		(end 31.78048 -115.413282)
		(width 0.1651)
		(layer "In9.Cu")
		(net "P5E_PEX0_STN1_TX_DN<22>")
	)
	(segment
		(start 65.015872 -271.471898)
		(end 65.015872 -264.660634)
		(width 0.1651)
		(layer "In9.Cu")
		(net "P5E_PEX0_STN1_TX_DN<22>")
	)
	(segment
		(start 30.866842 -117.619526)
		(end 31.051246 -117.173756)
		(width 0.1651)
		(layer "In9.Cu")
		(net "P5E_PEX0_STN1_TX_DN<22>")
	)
	(segment
		(start 36.89096 -110.687104)
		(end 37.476938 -110.687104)
		(width 0.1651)
		(layer "In9.Cu")
		(net "P5E_PEX0_STN1_TX_DN<22>")
	)
	(segment
		(start 34.410396 -111.206026)
		(end 34.856674 -111.021368)
		(width 0.1651)
		(layer "In9.Cu")
		(net "P5E_PEX0_STN1_TX_DN<22>")
	)
	(segment
		(start 32.878776 -112.76076)
		(end 33.028382 -112.698784)
		(width 0.1651)
		(layer "In9.Cu")
		(net "P5E_PEX0_STN1_TX_DN<22>")
	)
	(segment
		(start 31.323534 -116.516404)
		(end 31.508192 -116.070634)
		(width 0.1651)
		(layer "In9.Cu")
		(net "P5E_PEX0_STN1_TX_DN<22>")
	)
	(segment
		(start 32.42183 -113.86439)
		(end 32.42183 -113.864136)
		(width 0.1651)
		(layer "In9.Cu")
		(net "P5E_PEX0_STN1_TX_DN<22>")
	)
	(segment
		(start 29.505656 -120.906032)
		(end 30.5943 -118.277386)
		(width 0.1651)
		(layer "In9.Cu")
		(net "P5E_PEX0_STN1_TX_DN<22>")
	)
	(segment
		(start 31.507938 -116.070634)
		(end 31.657544 -116.008658)
		(width 0.1651)
		(layer "In9.Cu")
		(net "P5E_PEX0_STN1_TX_DN<22>")
	)
	(segment
		(start 29.230066 -151.433276)
		(end 28.863036 -143.952976)
		(width 0.1651)
		(layer "In9.Cu")
		(net "P5E_PEX0_STN1_TX_DN<22>")
	)
	(segment
		(start 31.657544 -116.008658)
		(end 31.842202 -115.562634)
		(width 0.1651)
		(layer "In9.Cu")
		(net "P5E_PEX0_STN1_TX_DN<22>")
	)
	(segment
		(start 33.21304 -112.25276)
		(end 33.151318 -112.103408)
		(width 0.1651)
		(layer "In9.Cu")
		(net "P5E_PEX0_STN1_TX_DN<22>")
	)
	(segment
		(start 184.29986 -316.140592)
		(end 184.29986 -315.849762)
		(width 0.1143)
		(layer "In15.Cu")
		(net "P5E_PEX1_STN5_RX_DP<90>")
	)
	(segment
		(start 138.579098 -341.912702)
		(end 139.097512 -341.143844)
		(width 0.1651)
		(layer "In15.Cu")
		(net "P5E_PEX1_STN5_RX_DP<90>")
	)
	(segment
		(start 184.21096 -316.229492)
		(end 184.29986 -316.140592)
		(width 0.1143)
		(layer "In15.Cu")
		(net "P5E_PEX1_STN5_RX_DP<90>")
	)
	(segment
		(start 132.846826 -361.6325)
		(end 133.286246 -361.404408)
		(width 0.1651)
		(layer "In15.Cu")
		(net "P5E_PEX1_STN5_RX_DP<90>")
	)
	(segment
		(start 138.579098 -358.024938)
		(end 138.579098 -341.912702)
		(width 0.1651)
		(layer "In15.Cu")
		(net "P5E_PEX1_STN5_RX_DP<90>")
	)
	(segment
		(start 132.226558 -361.954572)
		(end 132.269992 -361.817666)
		(width 0.1651)
		(layer "In15.Cu")
		(net "P5E_PEX1_STN5_RX_DP<90>")
	)
	(segment
		(start 183.609996 -320.704972)
		(end 183.68391 -320.52641)
		(width 0.1651)
		(layer "In15.Cu")
		(net "P5E_PEX1_STN5_RX_DP<90>")
	)
	(segment
		(start 139.097512 -341.143844)
		(end 141.41196 -339.779102)
		(width 0.1651)
		(layer "In15.Cu")
		(net "P5E_PEX1_STN5_RX_DP<90>")
	)
	(segment
		(start 141.41196 -339.779102)
		(end 177.966624 -324.98157)
		(width 0.1651)
		(layer "In15.Cu")
		(net "P5E_PEX1_STN5_RX_DP<90>")
	)
	(segment
		(start 131.787138 -362.182664)
		(end 132.226558 -361.954572)
		(width 0.1651)
		(layer "In15.Cu")
		(net "P5E_PEX1_STN5_RX_DP<90>")
	)
	(segment
		(start 120.437148 -370.999258)
		(end 120.71477 -370.999258)
		(width 0.1651)
		(layer "In15.Cu")
		(net "P5E_PEX1_STN5_RX_DP<90>")
	)
	(segment
		(start 183.68391 -320.52641)
		(end 183.68391 -319.916048)
		(width 0.1651)
		(layer "In15.Cu")
		(net "P5E_PEX1_STN5_RX_DP<90>")
	)
	(segment
		(start 120.71477 -370.999258)
		(end 121.218198 -370.49583)
		(width 0.1651)
		(layer "In15.Cu")
		(net "P5E_PEX1_STN5_RX_DP<90>")
	)
	(segment
		(start 133.906514 -361.082336)
		(end 138.01725 -358.94899)
		(width 0.1651)
		(layer "In15.Cu")
		(net "P5E_PEX1_STN5_RX_DP<90>")
	)
	(segment
		(start 120.310148 -370.489988)
		(end 120.310148 -370.872258)
		(width 0.1651)
		(layer "In15.Cu")
		(net "P5E_PEX1_STN5_RX_DP<90>")
	)
	(segment
		(start 183.72963 -319.84188)
		(end 183.72963 -316.506098)
		(width 0.1143)
		(layer "In15.Cu")
		(net "P5E_PEX1_STN5_RX_DP<90>")
	)
	(segment
		(start 120.310148 -370.872258)
		(end 120.437148 -370.999258)
		(width 0.1651)
		(layer "In15.Cu")
		(net "P5E_PEX1_STN5_RX_DP<90>")
	)
	(segment
		(start 133.286246 -361.404408)
		(end 133.32968 -361.267502)
		(width 0.1651)
		(layer "In15.Cu")
		(net "P5E_PEX1_STN5_RX_DP<90>")
	)
	(segment
		(start 177.966624 -324.98157)
		(end 182.023512 -322.291456)
		(width 0.1651)
		(layer "In15.Cu")
		(net "P5E_PEX1_STN5_RX_DP<90>")
	)
	(segment
		(start 183.68391 -319.916048)
		(end 183.68391 -319.8876)
		(width 0.1143)
		(layer "In15.Cu")
		(net "P5E_PEX1_STN5_RX_DP<90>")
	)
	(segment
		(start 131.16687 -362.504736)
		(end 131.210304 -362.36783)
		(width 0.1651)
		(layer "In15.Cu")
		(net "P5E_PEX1_STN5_RX_DP<90>")
	)
	(segment
		(start 121.218198 -370.49583)
		(end 121.218198 -369.115086)
		(width 0.1651)
		(layer "In15.Cu")
		(net "P5E_PEX1_STN5_RX_DP<90>")
	)
	(segment
		(start 184.006236 -316.229492)
		(end 184.21096 -316.229492)
		(width 0.1143)
		(layer "In15.Cu")
		(net "P5E_PEX1_STN5_RX_DP<90>")
	)
	(segment
		(start 121.909078 -367.852706)
		(end 126.422658 -364.967266)
		(width 0.1651)
		(layer "In15.Cu")
		(net "P5E_PEX1_STN5_RX_DP<90>")
	)
	(segment
		(start 133.769608 -361.039156)
		(end 133.906514 -361.082336)
		(width 0.1651)
		(layer "In15.Cu")
		(net "P5E_PEX1_STN5_RX_DP<90>")
	)
	(segment
		(start 131.210304 -362.36783)
		(end 131.650232 -362.139484)
		(width 0.1651)
		(layer "In15.Cu")
		(net "P5E_PEX1_STN5_RX_DP<90>")
	)
	(segment
		(start 131.650232 -362.139484)
		(end 131.787138 -362.182664)
		(width 0.1651)
		(layer "In15.Cu")
		(net "P5E_PEX1_STN5_RX_DP<90>")
	)
	(segment
		(start 121.218198 -369.115086)
		(end 121.909078 -367.852706)
		(width 0.1651)
		(layer "In15.Cu")
		(net "P5E_PEX1_STN5_RX_DP<90>")
	)
	(segment
		(start 126.422658 -364.967266)
		(end 131.16687 -362.504736)
		(width 0.1651)
		(layer "In15.Cu")
		(net "P5E_PEX1_STN5_RX_DP<90>")
	)
	(segment
		(start 133.32968 -361.267502)
		(end 133.769608 -361.039156)
		(width 0.1651)
		(layer "In15.Cu")
		(net "P5E_PEX1_STN5_RX_DP<90>")
	)
	(segment
		(start 132.269992 -361.817666)
		(end 132.70992 -361.58932)
		(width 0.1651)
		(layer "In15.Cu")
		(net "P5E_PEX1_STN5_RX_DP<90>")
	)
	(segment
		(start 183.72963 -316.506098)
		(end 184.006236 -316.229492)
		(width 0.1143)
		(layer "In15.Cu")
		(net "P5E_PEX1_STN5_RX_DP<90>")
	)
	(segment
		(start 182.023512 -322.291456)
		(end 183.609996 -320.704972)
		(width 0.1651)
		(layer "In15.Cu")
		(net "P5E_PEX1_STN5_RX_DP<90>")
	)
	(segment
		(start 132.70992 -361.58932)
		(end 132.846826 -361.6325)
		(width 0.1651)
		(layer "In15.Cu")
		(net "P5E_PEX1_STN5_RX_DP<90>")
	)
	(segment
		(start 183.68391 -319.8876)
		(end 183.72963 -319.84188)
		(width 0.1143)
		(layer "In15.Cu")
		(net "P5E_PEX1_STN5_RX_DP<90>")
	)
	(segment
		(start 138.01725 -358.94899)
		(end 138.579098 -358.024938)
		(width 0.1651)
		(layer "In15.Cu")
		(net "P5E_PEX1_STN5_RX_DP<90>")
	)
	(segment
		(start 90.216482 -345.465146)
		(end 89.921842 -345.170506)
		(width 0.13462)
		(layer "F.Cu")
		(net "P5E_PEX0_STN5_TX_C_DN<93>")
	)
	(segment
		(start 89.921842 -344.539062)
		(end 90.241882 -344.219022)
		(width 0.13462)
		(layer "F.Cu")
		(net "P5E_PEX0_STN5_TX_C_DN<93>")
	)
	(segment
		(start 89.921842 -345.170506)
		(end 89.921842 -344.539062)
		(width 0.13462)
		(layer "F.Cu")
		(net "P5E_PEX0_STN5_TX_C_DN<93>")
	)
	(segment
		(start 88.371172 -348.029022)
		(end 89.925652 -346.474542)
		(width 0.1651)
		(layer "In7.Cu")
		(net "P5E_PEX0_STN5_TX_C_DN<93>")
	)
	(segment
		(start 84.08416 -379.664976)
		(end 84.08416 -368.682778)
		(width 0.1651)
		(layer "In7.Cu")
		(net "P5E_PEX0_STN5_TX_C_DN<93>")
	)
	(segment
		(start 83.568032 -380.181104)
		(end 84.08416 -379.664976)
		(width 0.1651)
		(layer "In7.Cu")
		(net "P5E_PEX0_STN5_TX_C_DN<93>")
	)
	(segment
		(start 84.08416 -368.682778)
		(end 88.371172 -358.332786)
		(width 0.1651)
		(layer "In7.Cu")
		(net "P5E_PEX0_STN5_TX_C_DN<93>")
	)
	(segment
		(start 89.925652 -346.474542)
		(end 89.925652 -345.755976)
		(width 0.1651)
		(layer "In7.Cu")
		(net "P5E_PEX0_STN5_TX_C_DN<93>")
	)
	(segment
		(start 82.909918 -380.69012)
		(end 82.909918 -380.308104)
		(width 0.1651)
		(layer "In7.Cu")
		(net "P5E_PEX0_STN5_TX_C_DN<93>")
	)
	(segment
		(start 89.925652 -345.755976)
		(end 90.216482 -345.465146)
		(width 0.1651)
		(layer "In7.Cu")
		(net "P5E_PEX0_STN5_TX_C_DN<93>")
	)
	(segment
		(start 88.371172 -358.332786)
		(end 88.371172 -348.029022)
		(width 0.1651)
		(layer "In7.Cu")
		(net "P5E_PEX0_STN5_TX_C_DN<93>")
	)
	(segment
		(start 82.909918 -380.308104)
		(end 83.036918 -380.181104)
		(width 0.1651)
		(layer "In7.Cu")
		(net "P5E_PEX0_STN5_TX_C_DN<93>")
	)
	(segment
		(start 83.036918 -380.181104)
		(end 83.568032 -380.181104)
		(width 0.1651)
		(layer "In7.Cu")
		(net "P5E_PEX0_STN5_TX_C_DN<93>")
	)
	(segment
		(start 168.972992 -357.46309)
		(end 168.972992 -356.831646)
		(width 0.13462)
		(layer "F.Cu")
		(net "P5E_PEX1_STN7_TX_C_DN<116>")
	)
	(segment
		(start 168.972992 -356.831646)
		(end 169.293032 -356.511606)
		(width 0.13462)
		(layer "F.Cu")
		(net "P5E_PEX1_STN7_TX_C_DN<116>")
	)
	(segment
		(start 169.267632 -357.75773)
		(end 168.972992 -357.46309)
		(width 0.13462)
		(layer "F.Cu")
		(net "P5E_PEX1_STN7_TX_C_DN<116>")
	)
	(segment
		(start 168.976802 -358.778048)
		(end 168.976802 -358.04856)
		(width 0.1651)
		(layer "In11.Cu")
		(net "P5E_PEX1_STN7_TX_C_DN<116>")
	)
	(segment
		(start 158.93796 -364.10519)
		(end 167.058594 -360.696256)
		(width 0.1651)
		(layer "In11.Cu")
		(net "P5E_PEX1_STN7_TX_C_DN<116>")
	)
	(segment
		(start 163.289234 -390.570466)
		(end 159.804608 -389.419846)
		(width 0.1651)
		(layer "In11.Cu")
		(net "P5E_PEX1_STN7_TX_C_DN<116>")
	)
	(segment
		(start 169.8752 -394.835888)
		(end 169.334942 -394.29563)
		(width 0.1651)
		(layer "In11.Cu")
		(net "P5E_PEX1_STN7_TX_C_DN<116>")
	)
	(segment
		(start 155.818586 -382.4859)
		(end 155.990544 -368.42065)
		(width 0.1651)
		(layer "In11.Cu")
		(net "P5E_PEX1_STN7_TX_C_DN<116>")
	)
	(segment
		(start 159.804608 -389.419846)
		(end 156.970984 -387.317234)
		(width 0.1651)
		(layer "In11.Cu")
		(net "P5E_PEX1_STN7_TX_C_DN<116>")
	)
	(segment
		(start 168.710102 -401.308062)
		(end 168.837102 -401.181062)
		(width 0.1651)
		(layer "In11.Cu")
		(net "P5E_PEX1_STN7_TX_C_DN<116>")
	)
	(segment
		(start 169.334942 -394.29563)
		(end 163.289234 -390.570466)
		(width 0.1651)
		(layer "In11.Cu")
		(net "P5E_PEX1_STN7_TX_C_DN<116>")
	)
	(segment
		(start 168.710102 -401.690078)
		(end 168.710102 -401.308062)
		(width 0.1651)
		(layer "In11.Cu")
		(net "P5E_PEX1_STN7_TX_C_DN<116>")
	)
	(segment
		(start 167.058594 -360.696256)
		(end 168.976802 -358.778048)
		(width 0.1651)
		(layer "In11.Cu")
		(net "P5E_PEX1_STN7_TX_C_DN<116>")
	)
	(segment
		(start 156.970984 -387.317234)
		(end 156.03728 -385.00812)
		(width 0.1651)
		(layer "In11.Cu")
		(net "P5E_PEX1_STN7_TX_C_DN<116>")
	)
	(segment
		(start 156.78785 -366.311942)
		(end 158.93796 -364.10519)
		(width 0.1651)
		(layer "In11.Cu")
		(net "P5E_PEX1_STN7_TX_C_DN<116>")
	)
	(segment
		(start 168.976802 -358.04856)
		(end 169.267632 -357.75773)
		(width 0.1651)
		(layer "In11.Cu")
		(net "P5E_PEX1_STN7_TX_C_DN<116>")
	)
	(segment
		(start 169.8752 -400.8755)
		(end 169.8752 -394.835888)
		(width 0.1651)
		(layer "In11.Cu")
		(net "P5E_PEX1_STN7_TX_C_DN<116>")
	)
	(segment
		(start 168.837102 -401.181062)
		(end 169.569638 -401.181062)
		(width 0.1651)
		(layer "In11.Cu")
		(net "P5E_PEX1_STN7_TX_C_DN<116>")
	)
	(segment
		(start 169.569638 -401.181062)
		(end 169.8752 -400.8755)
		(width 0.1651)
		(layer "In11.Cu")
		(net "P5E_PEX1_STN7_TX_C_DN<116>")
	)
	(segment
		(start 155.990544 -368.42065)
		(end 156.78785 -366.311942)
		(width 0.1651)
		(layer "In11.Cu")
		(net "P5E_PEX1_STN7_TX_C_DN<116>")
	)
	(segment
		(start 156.03728 -385.00812)
		(end 155.818586 -382.4859)
		(width 0.1651)
		(layer "In11.Cu")
		(net "P5E_PEX1_STN7_TX_C_DN<116>")
	)
	(segment
		(start 80.606138 -146.784568)
		(end 81.237582 -146.784568)
		(width 0.13462)
		(layer "F.Cu")
		(net "P5E_PEX0_STN0_TX_DP<10>")
	)
	(segment
		(start 80.286098 -147.104608)
		(end 80.606138 -146.784568)
		(width 0.13462)
		(layer "F.Cu")
		(net "P5E_PEX0_STN0_TX_DP<10>")
	)
	(segment
		(start 81.237582 -146.784568)
		(end 81.532222 -147.079208)
		(width 0.13462)
		(layer "F.Cu")
		(net "P5E_PEX0_STN0_TX_DP<10>")
	)
	(segment
		(start 79.48549 -280.319988)
		(end 79.59979 -280.434288)
		(width 0.1143)
		(layer "In9.Cu")
		(net "P5E_PEX0_STN0_TX_DP<10>")
	)
	(segment
		(start 88.03767 -150.26513)
		(end 88.013032 -150.38832)
		(width 0.1651)
		(layer "In9.Cu")
		(net "P5E_PEX0_STN0_TX_DP<10>")
	)
	(segment
		(start 90.212164 -154.836622)
		(end 90.212164 -157.940248)
		(width 0.1651)
		(layer "In9.Cu")
		(net "P5E_PEX0_STN0_TX_DP<10>")
	)
	(segment
		(start 81.811876 -172.492162)
		(end 80.474566 -177.47996)
		(width 0.1651)
		(layer "In9.Cu")
		(net "P5E_PEX0_STN0_TX_DP<10>")
	)
	(segment
		(start 79.02956 -280.10485)
		(end 79.244698 -280.319988)
		(width 0.1143)
		(layer "In9.Cu")
		(net "P5E_PEX0_STN0_TX_DP<10>")
	)
	(segment
		(start 79.947008 -260.76529)
		(end 79.947008 -268.773402)
		(width 0.1651)
		(layer "In9.Cu")
		(net "P5E_PEX0_STN0_TX_DP<10>")
	)
	(segment
		(start 78.98384 -271.526)
		(end 78.98384 -271.554448)
		(width 0.1143)
		(layer "In9.Cu")
		(net "P5E_PEX0_STN0_TX_DP<10>")
	)
	(segment
		(start 88.777064 -151.371808)
		(end 90.212164 -154.836622)
		(width 0.1651)
		(layer "In9.Cu")
		(net "P5E_PEX0_STN0_TX_DP<10>")
	)
	(segment
		(start 80.474566 -177.47996)
		(end 80.47228 -177.504852)
		(width 0.1651)
		(layer "In9.Cu")
		(net "P5E_PEX0_STN0_TX_DP<10>")
	)
	(segment
		(start 81.532222 -147.079208)
		(end 81.823052 -146.788378)
		(width 0.1651)
		(layer "In9.Cu")
		(net "P5E_PEX0_STN0_TX_DP<10>")
	)
	(segment
		(start 87.639398 -149.829012)
		(end 87.762588 -149.853396)
		(width 0.1651)
		(layer "In9.Cu")
		(net "P5E_PEX0_STN0_TX_DP<10>")
	)
	(segment
		(start 87.363808 -149.41677)
		(end 87.639398 -149.829012)
		(width 0.1651)
		(layer "In9.Cu")
		(net "P5E_PEX0_STN0_TX_DP<10>")
	)
	(segment
		(start 79.02956 -271.600168)
		(end 79.02956 -280.10485)
		(width 0.1143)
		(layer "In9.Cu")
		(net "P5E_PEX0_STN0_TX_DP<10>")
	)
	(segment
		(start 88.411812 -150.824946)
		(end 88.777064 -151.371808)
		(width 0.1651)
		(layer "In9.Cu")
		(net "P5E_PEX0_STN0_TX_DP<10>")
	)
	(segment
		(start 90.212164 -157.940248)
		(end 81.811876 -172.492162)
		(width 0.1651)
		(layer "In9.Cu")
		(net "P5E_PEX0_STN0_TX_DP<10>")
	)
	(segment
		(start 79.244698 -280.319988)
		(end 79.48549 -280.319988)
		(width 0.1143)
		(layer "In9.Cu")
		(net "P5E_PEX0_STN0_TX_DP<10>")
	)
	(segment
		(start 87.388446 -149.29358)
		(end 87.363808 -149.41677)
		(width 0.1651)
		(layer "In9.Cu")
		(net "P5E_PEX0_STN0_TX_DP<10>")
	)
	(segment
		(start 78.98384 -271.554448)
		(end 79.02956 -271.600168)
		(width 0.1143)
		(layer "In9.Cu")
		(net "P5E_PEX0_STN0_TX_DP<10>")
	)
	(segment
		(start 88.288368 -150.800562)
		(end 88.411812 -150.824946)
		(width 0.1651)
		(layer "In9.Cu")
		(net "P5E_PEX0_STN0_TX_DP<10>")
	)
	(segment
		(start 87.762588 -149.853396)
		(end 88.03767 -150.26513)
		(width 0.1651)
		(layer "In9.Cu")
		(net "P5E_PEX0_STN0_TX_DP<10>")
	)
	(segment
		(start 80.47228 -177.504852)
		(end 80.472534 -177.504852)
		(width 0.1651)
		(layer "In9.Cu")
		(net "P5E_PEX0_STN0_TX_DP<10>")
	)
	(segment
		(start 79.59979 -280.434288)
		(end 79.59979 -280.699718)
		(width 0.1143)
		(layer "In9.Cu")
		(net "P5E_PEX0_STN0_TX_DP<10>")
	)
	(segment
		(start 76.566776 -222.099124)
		(end 79.947008 -260.76529)
		(width 0.1651)
		(layer "In9.Cu")
		(net "P5E_PEX0_STN0_TX_DP<10>")
	)
	(segment
		(start 78.98384 -271.09928)
		(end 78.98384 -271.526)
		(width 0.1651)
		(layer "In9.Cu")
		(net "P5E_PEX0_STN0_TX_DP<10>")
	)
	(segment
		(start 81.823052 -146.788378)
		(end 83.942428 -146.788378)
		(width 0.1651)
		(layer "In9.Cu")
		(net "P5E_PEX0_STN0_TX_DP<10>")
	)
	(segment
		(start 88.013032 -150.38832)
		(end 88.288368 -150.800562)
		(width 0.1651)
		(layer "In9.Cu")
		(net "P5E_PEX0_STN0_TX_DP<10>")
	)
	(segment
		(start 79.947008 -268.773402)
		(end 78.98384 -271.09928)
		(width 0.1651)
		(layer "In9.Cu")
		(net "P5E_PEX0_STN0_TX_DP<10>")
	)
	(segment
		(start 80.472534 -177.504852)
		(end 76.566776 -222.099124)
		(width 0.1651)
		(layer "In9.Cu")
		(net "P5E_PEX0_STN0_TX_DP<10>")
	)
	(segment
		(start 83.942428 -146.788378)
		(end 85.781642 -147.550124)
		(width 0.1651)
		(layer "In9.Cu")
		(net "P5E_PEX0_STN0_TX_DP<10>")
	)
	(segment
		(start 87.113364 -148.881846)
		(end 87.388446 -149.29358)
		(width 0.1651)
		(layer "In9.Cu")
		(net "P5E_PEX0_STN0_TX_DP<10>")
	)
	(segment
		(start 85.781642 -147.550124)
		(end 87.113364 -148.881846)
		(width 0.1651)
		(layer "In9.Cu")
		(net "P5E_PEX0_STN0_TX_DP<10>")
	)
	(segment
		(start 29.228288 -355.658166)
		(end 29.228288 -355.026722)
		(width 0.13462)
		(layer "F.Cu")
		(net "P5E_PEX0_STN7_TX_DN<117>")
	)
	(segment
		(start 29.228288 -355.026722)
		(end 29.522928 -354.732082)
		(width 0.13462)
		(layer "F.Cu")
		(net "P5E_PEX0_STN7_TX_DN<117>")
	)
	(segment
		(start 29.548328 -355.978206)
		(end 29.228288 -355.658166)
		(width 0.13462)
		(layer "F.Cu")
		(net "P5E_PEX0_STN7_TX_DN<117>")
	)
	(segment
		(start 33.940496 -306.015898)
		(end 35.582352 -306.015898)
		(width 0.1651)
		(layer "In7.Cu")
		(net "P5E_PEX0_STN7_TX_DN<117>")
	)
	(segment
		(start 28.93949 -309.80126)
		(end 28.93949 -309.69331)
		(width 0.1651)
		(layer "In7.Cu")
		(net "P5E_PEX0_STN7_TX_DN<117>")
	)
	(segment
		(start 43.879516 -306.235608)
		(end 43.765216 -306.349908)
		(width 0.1143)
		(layer "In7.Cu")
		(net "P5E_PEX0_STN7_TX_DN<117>")
	)
	(segment
		(start 35.582352 -306.015898)
		(end 35.6108 -306.015898)
		(width 0.1143)
		(layer "In7.Cu")
		(net "P5E_PEX0_STN7_TX_DN<117>")
	)
	(segment
		(start 27.91333 -334.62722)
		(end 27.792934 -334.590898)
		(width 0.1651)
		(layer "In7.Cu")
		(net "P5E_PEX0_STN7_TX_DN<117>")
	)
	(segment
		(start 23.230332 -316.135004)
		(end 26.583132 -312.049668)
		(width 0.1651)
		(layer "In7.Cu")
		(net "P5E_PEX0_STN7_TX_DN<117>")
	)
	(segment
		(start 35.6108 -306.015898)
		(end 35.65652 -305.970178)
		(width 0.1143)
		(layer "In7.Cu")
		(net "P5E_PEX0_STN7_TX_DN<117>")
	)
	(segment
		(start 30.786578 -352.387662)
		(end 30.786578 -342.116664)
		(width 0.1651)
		(layer "In7.Cu")
		(net "P5E_PEX0_STN7_TX_DN<117>")
	)
	(segment
		(start 28.464256 -335.657698)
		(end 28.34386 -335.621376)
		(width 0.1651)
		(layer "In7.Cu")
		(net "P5E_PEX0_STN7_TX_DN<117>")
	)
	(segment
		(start 29.232098 -353.942142)
		(end 30.786578 -352.387662)
		(width 0.1651)
		(layer "In7.Cu")
		(net "P5E_PEX0_STN7_TX_DN<117>")
	)
	(segment
		(start 29.289502 -309.343298)
		(end 29.415232 -309.343298)
		(width 0.1651)
		(layer "In7.Cu")
		(net "P5E_PEX0_STN7_TX_DN<117>")
	)
	(segment
		(start 21.952204 -322.74764)
		(end 21.952204 -320.137028)
		(width 0.1651)
		(layer "In7.Cu")
		(net "P5E_PEX0_STN7_TX_DN<117>")
	)
	(segment
		(start 27.242008 -333.56042)
		(end 23.639018 -326.820022)
		(width 0.1651)
		(layer "In7.Cu")
		(net "P5E_PEX0_STN7_TX_DN<117>")
	)
	(segment
		(start 23.639018 -326.820022)
		(end 21.952204 -322.74764)
		(width 0.1651)
		(layer "In7.Cu")
		(net "P5E_PEX0_STN7_TX_DN<117>")
	)
	(segment
		(start 27.792934 -334.590898)
		(end 27.559508 -334.154272)
		(width 0.1651)
		(layer "In7.Cu")
		(net "P5E_PEX0_STN7_TX_DN<117>")
	)
	(segment
		(start 29.232098 -354.441252)
		(end 29.232098 -353.942142)
		(width 0.1651)
		(layer "In7.Cu")
		(net "P5E_PEX0_STN7_TX_DN<117>")
	)
	(segment
		(start 26.583132 -312.049668)
		(end 28.481274 -310.151526)
		(width 0.1651)
		(layer "In7.Cu")
		(net "P5E_PEX0_STN7_TX_DN<117>")
	)
	(segment
		(start 43.765216 -306.349908)
		(end 43.499786 -306.349908)
		(width 0.1143)
		(layer "In7.Cu")
		(net "P5E_PEX0_STN7_TX_DN<117>")
	)
	(segment
		(start 28.58897 -310.151526)
		(end 28.93949 -309.80126)
		(width 0.1651)
		(layer "In7.Cu")
		(net "P5E_PEX0_STN7_TX_DN<117>")
	)
	(segment
		(start 35.65652 -305.970178)
		(end 43.765216 -305.970178)
		(width 0.1143)
		(layer "In7.Cu")
		(net "P5E_PEX0_STN7_TX_DN<117>")
	)
	(segment
		(start 28.697936 -336.094832)
		(end 28.464256 -335.657698)
		(width 0.1651)
		(layer "In7.Cu")
		(net "P5E_PEX0_STN7_TX_DN<117>")
	)
	(segment
		(start 28.481274 -310.151526)
		(end 28.58897 -310.151526)
		(width 0.1651)
		(layer "In7.Cu")
		(net "P5E_PEX0_STN7_TX_DN<117>")
	)
	(segment
		(start 30.786578 -342.116664)
		(end 29.878528 -338.49183)
		(width 0.1651)
		(layer "In7.Cu")
		(net "P5E_PEX0_STN7_TX_DN<117>")
	)
	(segment
		(start 21.952204 -320.137028)
		(end 22.302978 -318.373506)
		(width 0.1651)
		(layer "In7.Cu")
		(net "P5E_PEX0_STN7_TX_DN<117>")
	)
	(segment
		(start 28.661614 -336.215228)
		(end 28.697936 -336.094832)
		(width 0.1651)
		(layer "In7.Cu")
		(net "P5E_PEX0_STN7_TX_DN<117>")
	)
	(segment
		(start 27.362404 -333.596742)
		(end 27.242008 -333.56042)
		(width 0.1651)
		(layer "In7.Cu")
		(net "P5E_PEX0_STN7_TX_DN<117>")
	)
	(segment
		(start 31.680912 -306.951888)
		(end 33.940496 -306.015898)
		(width 0.1651)
		(layer "In7.Cu")
		(net "P5E_PEX0_STN7_TX_DN<117>")
	)
	(segment
		(start 28.14701 -335.064354)
		(end 27.91333 -334.62722)
		(width 0.1651)
		(layer "In7.Cu")
		(net "P5E_PEX0_STN7_TX_DN<117>")
	)
	(segment
		(start 29.765498 -308.867302)
		(end 31.680912 -306.951888)
		(width 0.1651)
		(layer "In7.Cu")
		(net "P5E_PEX0_STN7_TX_DN<117>")
	)
	(segment
		(start 29.415232 -309.343298)
		(end 29.765498 -308.993032)
		(width 0.1651)
		(layer "In7.Cu")
		(net "P5E_PEX0_STN7_TX_DN<117>")
	)
	(segment
		(start 22.302978 -318.373506)
		(end 23.230332 -316.135004)
		(width 0.1651)
		(layer "In7.Cu")
		(net "P5E_PEX0_STN7_TX_DN<117>")
	)
	(segment
		(start 29.765498 -308.993032)
		(end 29.765498 -308.867302)
		(width 0.1651)
		(layer "In7.Cu")
		(net "P5E_PEX0_STN7_TX_DN<117>")
	)
	(segment
		(start 43.879516 -306.084478)
		(end 43.879516 -306.235608)
		(width 0.1143)
		(layer "In7.Cu")
		(net "P5E_PEX0_STN7_TX_DN<117>")
	)
	(segment
		(start 27.596084 -334.033876)
		(end 27.362404 -333.596742)
		(width 0.1651)
		(layer "In7.Cu")
		(net "P5E_PEX0_STN7_TX_DN<117>")
	)
	(segment
		(start 27.559508 -334.154272)
		(end 27.596084 -334.033876)
		(width 0.1651)
		(layer "In7.Cu")
		(net "P5E_PEX0_STN7_TX_DN<117>")
	)
	(segment
		(start 28.93949 -309.69331)
		(end 29.289502 -309.343298)
		(width 0.1651)
		(layer "In7.Cu")
		(net "P5E_PEX0_STN7_TX_DN<117>")
	)
	(segment
		(start 28.110434 -335.18475)
		(end 28.14701 -335.064354)
		(width 0.1651)
		(layer "In7.Cu")
		(net "P5E_PEX0_STN7_TX_DN<117>")
	)
	(segment
		(start 29.522928 -354.732082)
		(end 29.232098 -354.441252)
		(width 0.1651)
		(layer "In7.Cu")
		(net "P5E_PEX0_STN7_TX_DN<117>")
	)
	(segment
		(start 28.34386 -335.621376)
		(end 28.110434 -335.18475)
		(width 0.1651)
		(layer "In7.Cu")
		(net "P5E_PEX0_STN7_TX_DN<117>")
	)
	(segment
		(start 43.765216 -305.970178)
		(end 43.879516 -306.084478)
		(width 0.1143)
		(layer "In7.Cu")
		(net "P5E_PEX0_STN7_TX_DN<117>")
	)
	(segment
		(start 29.878528 -338.49183)
		(end 28.661614 -336.215228)
		(width 0.1651)
		(layer "In7.Cu")
		(net "P5E_PEX0_STN7_TX_DN<117>")
	)
	(segment
		(start 130.299968 -369.234974)
		(end 130.626104 -368.713766)
		(width 0.1651)
		(layer "In15.Cu")
		(net "P5E_PEX1_STN5_RX_DN<94>")
	)
	(segment
		(start 131.579874 -367.85677)
		(end 143.845788 -361.891326)
		(width 0.1651)
		(layer "In15.Cu")
		(net "P5E_PEX1_STN5_RX_DN<94>")
	)
	(segment
		(start 130.299968 -370.61267)
		(end 130.299968 -369.234974)
		(width 0.1651)
		(layer "In15.Cu")
		(net "P5E_PEX1_STN5_RX_DN<94>")
	)
	(segment
		(start 187.765944 -319.8876)
		(end 187.720224 -319.84188)
		(width 0.1143)
		(layer "In15.Cu")
		(net "P5E_PEX1_STN5_RX_DN<94>")
	)
	(segment
		(start 187.765944 -319.916048)
		(end 187.765944 -319.8876)
		(width 0.1143)
		(layer "In15.Cu")
		(net "P5E_PEX1_STN5_RX_DN<94>")
	)
	(segment
		(start 188.099954 -316.508892)
		(end 188.099954 -316.799722)
		(width 0.1143)
		(layer "In15.Cu")
		(net "P5E_PEX1_STN5_RX_DN<94>")
	)
	(segment
		(start 146.200114 -360.051604)
		(end 147.944332 -357.966264)
		(width 0.1651)
		(layer "In15.Cu")
		(net "P5E_PEX1_STN5_RX_DN<94>")
	)
	(segment
		(start 129.109978 -371.408198)
		(end 129.236978 -371.281198)
		(width 0.1651)
		(layer "In15.Cu")
		(net "P5E_PEX1_STN5_RX_DN<94>")
	)
	(segment
		(start 169.142918 -336.606642)
		(end 182.221378 -327.933812)
		(width 0.1651)
		(layer "In15.Cu")
		(net "P5E_PEX1_STN5_RX_DN<94>")
	)
	(segment
		(start 187.765944 -321.193922)
		(end 187.765944 -319.916048)
		(width 0.1651)
		(layer "In15.Cu")
		(net "P5E_PEX1_STN5_RX_DN<94>")
	)
	(segment
		(start 129.236978 -371.281198)
		(end 129.63144 -371.281198)
		(width 0.1651)
		(layer "In15.Cu")
		(net "P5E_PEX1_STN5_RX_DN<94>")
	)
	(segment
		(start 187.720224 -316.585092)
		(end 187.885324 -316.419992)
		(width 0.1143)
		(layer "In15.Cu")
		(net "P5E_PEX1_STN5_RX_DN<94>")
	)
	(segment
		(start 187.720224 -319.84188)
		(end 187.720224 -316.585092)
		(width 0.1143)
		(layer "In15.Cu")
		(net "P5E_PEX1_STN5_RX_DN<94>")
	)
	(segment
		(start 187.885324 -316.419992)
		(end 188.011054 -316.419992)
		(width 0.1143)
		(layer "In15.Cu")
		(net "P5E_PEX1_STN5_RX_DN<94>")
	)
	(segment
		(start 129.63144 -371.281198)
		(end 130.299968 -370.61267)
		(width 0.1651)
		(layer "In15.Cu")
		(net "P5E_PEX1_STN5_RX_DN<94>")
	)
	(segment
		(start 186.41822 -323.73697)
		(end 187.400184 -322.141596)
		(width 0.1651)
		(layer "In15.Cu")
		(net "P5E_PEX1_STN5_RX_DN<94>")
	)
	(segment
		(start 143.845788 -361.891326)
		(end 146.200114 -360.051604)
		(width 0.1651)
		(layer "In15.Cu")
		(net "P5E_PEX1_STN5_RX_DN<94>")
	)
	(segment
		(start 147.944332 -357.966264)
		(end 162.83051 -341.858854)
		(width 0.1651)
		(layer "In15.Cu")
		(net "P5E_PEX1_STN5_RX_DN<94>")
	)
	(segment
		(start 130.626104 -368.713766)
		(end 131.579874 -367.85677)
		(width 0.1651)
		(layer "In15.Cu")
		(net "P5E_PEX1_STN5_RX_DN<94>")
	)
	(segment
		(start 182.221378 -327.933812)
		(end 186.41822 -323.73697)
		(width 0.1651)
		(layer "In15.Cu")
		(net "P5E_PEX1_STN5_RX_DN<94>")
	)
	(segment
		(start 187.400184 -322.141596)
		(end 187.765944 -321.193922)
		(width 0.1651)
		(layer "In15.Cu")
		(net "P5E_PEX1_STN5_RX_DN<94>")
	)
	(segment
		(start 162.83051 -341.858854)
		(end 169.142918 -336.606642)
		(width 0.1651)
		(layer "In15.Cu")
		(net "P5E_PEX1_STN5_RX_DN<94>")
	)
	(segment
		(start 188.011054 -316.419992)
		(end 188.099954 -316.508892)
		(width 0.1143)
		(layer "In15.Cu")
		(net "P5E_PEX1_STN5_RX_DN<94>")
	)
	(segment
		(start 129.109978 -371.790214)
		(end 129.109978 -371.408198)
		(width 0.1651)
		(layer "In15.Cu")
		(net "P5E_PEX1_STN5_RX_DN<94>")
	)
	(segment
		(start 77.211682 -345.170506)
		(end 77.211682 -344.539062)
		(width 0.13462)
		(layer "F.Cu")
		(net "P5E_PEX0_STN5_TX_C_DP<87>")
	)
	(segment
		(start 77.211682 -344.539062)
		(end 76.891642 -344.219022)
		(width 0.13462)
		(layer "F.Cu")
		(net "P5E_PEX0_STN5_TX_C_DP<87>")
	)
	(segment
		(start 76.917042 -345.465146)
		(end 77.211682 -345.170506)
		(width 0.13462)
		(layer "F.Cu")
		(net "P5E_PEX0_STN5_TX_C_DP<87>")
	)
	(segment
		(start 77.207872 -346.357702)
		(end 77.207872 -345.755976)
		(width 0.1651)
		(layer "In7.Cu")
		(net "P5E_PEX0_STN5_TX_C_DP<87>")
	)
	(segment
		(start 75.653392 -347.912182)
		(end 77.207872 -346.357702)
		(width 0.1651)
		(layer "In7.Cu")
		(net "P5E_PEX0_STN5_TX_C_DP<87>")
	)
	(segment
		(start 87.851234 -405.899112)
		(end 88.202262 -405.548084)
		(width 0.1651)
		(layer "In7.Cu")
		(net "P5E_PEX0_STN5_TX_C_DP<87>")
	)
	(segment
		(start 75.653392 -357.989124)
		(end 75.653392 -347.912182)
		(width 0.1651)
		(layer "In7.Cu")
		(net "P5E_PEX0_STN5_TX_C_DP<87>")
	)
	(segment
		(start 88.202262 -405.548084)
		(end 88.202262 -394.544042)
		(width 0.1651)
		(layer "In7.Cu")
		(net "P5E_PEX0_STN5_TX_C_DP<87>")
	)
	(segment
		(start 71.96836 -365.620046)
		(end 72.200008 -365.181896)
		(width 0.1651)
		(layer "In7.Cu")
		(net "P5E_PEX0_STN5_TX_C_DP<87>")
	)
	(segment
		(start 87.30996 -405.772112)
		(end 87.43696 -405.899112)
		(width 0.1651)
		(layer "In7.Cu")
		(net "P5E_PEX0_STN5_TX_C_DP<87>")
	)
	(segment
		(start 70.602348 -378.974858)
		(end 70.467982 -368.650774)
		(width 0.1651)
		(layer "In7.Cu")
		(net "P5E_PEX0_STN5_TX_C_DP<87>")
	)
	(segment
		(start 71.748396 -385.964938)
		(end 70.974458 -385.191)
		(width 0.1651)
		(layer "In7.Cu")
		(net "P5E_PEX0_STN5_TX_C_DP<87>")
	)
	(segment
		(start 72.200008 -365.181896)
		(end 72.32015 -365.144812)
		(width 0.1651)
		(layer "In7.Cu")
		(net "P5E_PEX0_STN5_TX_C_DP<87>")
	)
	(segment
		(start 88.202262 -394.544042)
		(end 85.191854 -391.533634)
		(width 0.1651)
		(layer "In7.Cu")
		(net "P5E_PEX0_STN5_TX_C_DP<87>")
	)
	(segment
		(start 75.258168 -359.582974)
		(end 75.653392 -357.989124)
		(width 0.1651)
		(layer "In7.Cu")
		(net "P5E_PEX0_STN5_TX_C_DP<87>")
	)
	(segment
		(start 70.974458 -385.191)
		(end 70.602348 -384.292602)
		(width 0.1651)
		(layer "In7.Cu")
		(net "P5E_PEX0_STN5_TX_C_DP<87>")
	)
	(segment
		(start 72.32015 -365.144812)
		(end 75.258168 -359.582974)
		(width 0.1651)
		(layer "In7.Cu")
		(net "P5E_PEX0_STN5_TX_C_DP<87>")
	)
	(segment
		(start 70.467982 -368.650774)
		(end 72.005444 -365.740188)
		(width 0.1651)
		(layer "In7.Cu")
		(net "P5E_PEX0_STN5_TX_C_DP<87>")
	)
	(segment
		(start 87.30996 -405.390096)
		(end 87.30996 -405.772112)
		(width 0.1651)
		(layer "In7.Cu")
		(net "P5E_PEX0_STN5_TX_C_DP<87>")
	)
	(segment
		(start 85.191854 -391.533634)
		(end 71.748396 -385.964938)
		(width 0.1651)
		(layer "In7.Cu")
		(net "P5E_PEX0_STN5_TX_C_DP<87>")
	)
	(segment
		(start 72.005444 -365.740188)
		(end 71.96836 -365.620046)
		(width 0.1651)
		(layer "In7.Cu")
		(net "P5E_PEX0_STN5_TX_C_DP<87>")
	)
	(segment
		(start 87.43696 -405.899112)
		(end 87.851234 -405.899112)
		(width 0.1651)
		(layer "In7.Cu")
		(net "P5E_PEX0_STN5_TX_C_DP<87>")
	)
	(segment
		(start 70.602348 -384.292602)
		(end 70.602348 -378.974858)
		(width 0.1651)
		(layer "In7.Cu")
		(net "P5E_PEX0_STN5_TX_C_DP<87>")
	)
	(segment
		(start 77.207872 -345.755976)
		(end 76.917042 -345.465146)
		(width 0.1651)
		(layer "In7.Cu")
		(net "P5E_PEX0_STN5_TX_C_DP<87>")
	)
	(segment
		(start 39.013892 -124.605542)
		(end 38.693852 -124.925582)
		(width 0.13462)
		(layer "F.Cu")
		(net "P5E_PEX0_STN1_TX_DN<27>")
	)
	(segment
		(start 38.062408 -124.925582)
		(end 37.767768 -124.630942)
		(width 0.13462)
		(layer "F.Cu")
		(net "P5E_PEX0_STN1_TX_DN<27>")
	)
	(segment
		(start 38.693852 -124.925582)
		(end 38.062408 -124.925582)
		(width 0.13462)
		(layer "F.Cu")
		(net "P5E_PEX0_STN1_TX_DN<27>")
	)
	(segment
		(start 69.483986 -271.554448)
		(end 69.483986 -271.526)
		(width 0.1143)
		(layer "In9.Cu")
		(net "P5E_PEX0_STN1_TX_DN<27>")
	)
	(segment
		(start 30.850332 -134.069582)
		(end 31.68142 -132.062728)
		(width 0.1651)
		(layer "In9.Cu")
		(net "P5E_PEX0_STN1_TX_DN<27>")
	)
	(segment
		(start 36.792408 -124.921772)
		(end 37.476938 -124.921772)
		(width 0.1651)
		(layer "In9.Cu")
		(net "P5E_PEX0_STN1_TX_DN<27>")
	)
	(segment
		(start 69.529706 -280.10485)
		(end 69.529706 -271.600168)
		(width 0.1143)
		(layer "In9.Cu")
		(net "P5E_PEX0_STN1_TX_DN<27>")
	)
	(segment
		(start 30.850332 -136.830562)
		(end 30.850332 -134.069582)
		(width 0.1651)
		(layer "In9.Cu")
		(net "P5E_PEX0_STN1_TX_DN<27>")
	)
	(segment
		(start 69.985636 -280.319988)
		(end 69.744844 -280.319988)
		(width 0.1143)
		(layer "In9.Cu")
		(net "P5E_PEX0_STN1_TX_DN<27>")
	)
	(segment
		(start 33.428178 -143.053816)
		(end 30.850332 -136.830562)
		(width 0.1651)
		(layer "In9.Cu")
		(net "P5E_PEX0_STN1_TX_DN<27>")
	)
	(segment
		(start 69.483986 -271.526)
		(end 69.483986 -263.64311)
		(width 0.1651)
		(layer "In9.Cu")
		(net "P5E_PEX0_STN1_TX_DN<27>")
	)
	(segment
		(start 34.132774 -157.375606)
		(end 33.428178 -143.053816)
		(width 0.1651)
		(layer "In9.Cu")
		(net "P5E_PEX0_STN1_TX_DN<27>")
	)
	(segment
		(start 69.529706 -271.600168)
		(end 69.483986 -271.554448)
		(width 0.1143)
		(layer "In9.Cu")
		(net "P5E_PEX0_STN1_TX_DN<27>")
	)
	(segment
		(start 70.099936 -280.699718)
		(end 70.099936 -280.434288)
		(width 0.1143)
		(layer "In9.Cu")
		(net "P5E_PEX0_STN1_TX_DN<27>")
	)
	(segment
		(start 35.01771 -161.825178)
		(end 34.132774 -157.375606)
		(width 0.1651)
		(layer "In9.Cu")
		(net "P5E_PEX0_STN1_TX_DN<27>")
	)
	(segment
		(start 70.099936 -280.434288)
		(end 69.985636 -280.319988)
		(width 0.1143)
		(layer "In9.Cu")
		(net "P5E_PEX0_STN1_TX_DN<27>")
	)
	(segment
		(start 37.476938 -124.921772)
		(end 37.767768 -124.630942)
		(width 0.1651)
		(layer "In9.Cu")
		(net "P5E_PEX0_STN1_TX_DN<27>")
	)
	(segment
		(start 31.68142 -132.062728)
		(end 35.769804 -125.944376)
		(width 0.1651)
		(layer "In9.Cu")
		(net "P5E_PEX0_STN1_TX_DN<27>")
	)
	(segment
		(start 35.769804 -125.944376)
		(end 36.792408 -124.921772)
		(width 0.1651)
		(layer "In9.Cu")
		(net "P5E_PEX0_STN1_TX_DN<27>")
	)
	(segment
		(start 69.744844 -280.319988)
		(end 69.529706 -280.10485)
		(width 0.1143)
		(layer "In9.Cu")
		(net "P5E_PEX0_STN1_TX_DN<27>")
	)
	(segment
		(start 69.483986 -263.64311)
		(end 35.01771 -161.825178)
		(width 0.1651)
		(layer "In9.Cu")
		(net "P5E_PEX0_STN1_TX_DN<27>")
	)
	(segment
		(start 29.548328 -343.685622)
		(end 29.228288 -343.365582)
		(width 0.13462)
		(layer "F.Cu")
		(net "P5E_PEX0_STN7_TX_DN<116>")
	)
	(segment
		(start 29.228288 -342.734138)
		(end 29.522928 -342.439498)
		(width 0.13462)
		(layer "F.Cu")
		(net "P5E_PEX0_STN7_TX_DN<116>")
	)
	(segment
		(start 29.228288 -343.365582)
		(end 29.228288 -342.734138)
		(width 0.13462)
		(layer "F.Cu")
		(net "P5E_PEX0_STN7_TX_DN<116>")
	)
	(segment
		(start 20.997164 -322.953126)
		(end 20.997164 -320.041778)
		(width 0.1651)
		(layer "In7.Cu")
		(net "P5E_PEX0_STN7_TX_DN<116>")
	)
	(segment
		(start 26.504646 -309.489602)
		(end 26.504646 -309.489348)
		(width 0.1651)
		(layer "In7.Cu")
		(net "P5E_PEX0_STN7_TX_DN<116>")
	)
	(segment
		(start 26.714958 -309.174388)
		(end 29.679392 -306.210208)
		(width 0.1651)
		(layer "In7.Cu")
		(net "P5E_PEX0_STN7_TX_DN<116>")
	)
	(segment
		(start 29.232098 -342.148668)
		(end 29.232098 -341.537798)
		(width 0.1651)
		(layer "In7.Cu")
		(net "P5E_PEX0_STN7_TX_DN<116>")
	)
	(segment
		(start 24.999442 -311.916318)
		(end 24.972772 -311.781952)
		(width 0.1651)
		(layer "In7.Cu")
		(net "P5E_PEX0_STN7_TX_DN<116>")
	)
	(segment
		(start 35.687 -305.065938)
		(end 35.73272 -305.020218)
		(width 0.1143)
		(layer "In7.Cu")
		(net "P5E_PEX0_STN7_TX_DN<116>")
	)
	(segment
		(start 24.714454 -312.34253)
		(end 24.999442 -311.916318)
		(width 0.1651)
		(layer "In7.Cu")
		(net "P5E_PEX0_STN7_TX_DN<116>")
	)
	(segment
		(start 29.679392 -306.210208)
		(end 32.44215 -305.065938)
		(width 0.1651)
		(layer "In7.Cu")
		(net "P5E_PEX0_STN7_TX_DN<116>")
	)
	(segment
		(start 20.997164 -320.041778)
		(end 21.414486 -317.942976)
		(width 0.1651)
		(layer "In7.Cu")
		(net "P5E_PEX0_STN7_TX_DN<116>")
	)
	(segment
		(start 28.219654 -337.496404)
		(end 22.895052 -327.53554)
		(width 0.1651)
		(layer "In7.Cu")
		(net "P5E_PEX0_STN7_TX_DN<116>")
	)
	(segment
		(start 35.658552 -305.065938)
		(end 35.687 -305.065938)
		(width 0.1143)
		(layer "In7.Cu")
		(net "P5E_PEX0_STN7_TX_DN<116>")
	)
	(segment
		(start 41.979596 -305.134518)
		(end 41.979596 -305.285648)
		(width 0.1143)
		(layer "In7.Cu")
		(net "P5E_PEX0_STN7_TX_DN<116>")
	)
	(segment
		(start 24.972772 -311.781952)
		(end 25.240742 -311.380886)
		(width 0.1651)
		(layer "In7.Cu")
		(net "P5E_PEX0_STN7_TX_DN<116>")
	)
	(segment
		(start 25.66416 -310.948578)
		(end 25.633426 -310.793384)
		(width 0.1651)
		(layer "In7.Cu")
		(net "P5E_PEX0_STN7_TX_DN<116>")
	)
	(segment
		(start 25.240742 -311.380886)
		(end 25.395936 -311.349898)
		(width 0.1651)
		(layer "In7.Cu")
		(net "P5E_PEX0_STN7_TX_DN<116>")
	)
	(segment
		(start 26.29408 -309.804816)
		(end 26.504646 -309.489602)
		(width 0.1651)
		(layer "In7.Cu")
		(net "P5E_PEX0_STN7_TX_DN<116>")
	)
	(segment
		(start 26.05659 -310.36133)
		(end 26.324814 -309.96001)
		(width 0.1651)
		(layer "In7.Cu")
		(net "P5E_PEX0_STN7_TX_DN<116>")
	)
	(segment
		(start 26.504646 -309.489348)
		(end 26.714958 -309.174388)
		(width 0.1651)
		(layer "In7.Cu")
		(net "P5E_PEX0_STN7_TX_DN<116>")
	)
	(segment
		(start 41.865296 -305.020218)
		(end 41.979596 -305.134518)
		(width 0.1143)
		(layer "In7.Cu")
		(net "P5E_PEX0_STN7_TX_DN<116>")
	)
	(segment
		(start 35.73272 -305.020218)
		(end 41.865296 -305.020218)
		(width 0.1143)
		(layer "In7.Cu")
		(net "P5E_PEX0_STN7_TX_DN<116>")
	)
	(segment
		(start 21.414486 -317.942976)
		(end 22.325584 -315.74359)
		(width 0.1651)
		(layer "In7.Cu")
		(net "P5E_PEX0_STN7_TX_DN<116>")
	)
	(segment
		(start 41.979596 -305.285648)
		(end 41.865296 -305.399948)
		(width 0.1143)
		(layer "In7.Cu")
		(net "P5E_PEX0_STN7_TX_DN<116>")
	)
	(segment
		(start 29.522928 -342.439498)
		(end 29.232098 -342.148668)
		(width 0.1651)
		(layer "In7.Cu")
		(net "P5E_PEX0_STN7_TX_DN<116>")
	)
	(segment
		(start 25.901396 -310.392318)
		(end 26.05659 -310.36133)
		(width 0.1651)
		(layer "In7.Cu")
		(net "P5E_PEX0_STN7_TX_DN<116>")
	)
	(segment
		(start 24.580088 -312.369454)
		(end 24.714454 -312.34253)
		(width 0.1651)
		(layer "In7.Cu")
		(net "P5E_PEX0_STN7_TX_DN<116>")
	)
	(segment
		(start 25.633426 -310.793384)
		(end 25.901396 -310.392318)
		(width 0.1651)
		(layer "In7.Cu")
		(net "P5E_PEX0_STN7_TX_DN<116>")
	)
	(segment
		(start 29.232098 -341.537798)
		(end 28.219654 -337.496404)
		(width 0.1651)
		(layer "In7.Cu")
		(net "P5E_PEX0_STN7_TX_DN<116>")
	)
	(segment
		(start 26.324814 -309.96001)
		(end 26.29408 -309.804816)
		(width 0.1651)
		(layer "In7.Cu")
		(net "P5E_PEX0_STN7_TX_DN<116>")
	)
	(segment
		(start 22.895052 -327.53554)
		(end 20.997164 -322.953126)
		(width 0.1651)
		(layer "In7.Cu")
		(net "P5E_PEX0_STN7_TX_DN<116>")
	)
	(segment
		(start 32.44215 -305.065938)
		(end 35.658552 -305.065938)
		(width 0.1651)
		(layer "In7.Cu")
		(net "P5E_PEX0_STN7_TX_DN<116>")
	)
	(segment
		(start 41.865296 -305.399948)
		(end 41.599866 -305.399948)
		(width 0.1143)
		(layer "In7.Cu")
		(net "P5E_PEX0_STN7_TX_DN<116>")
	)
	(segment
		(start 25.395936 -311.349898)
		(end 25.66416 -310.948578)
		(width 0.1651)
		(layer "In7.Cu")
		(net "P5E_PEX0_STN7_TX_DN<116>")
	)
	(segment
		(start 22.325584 -315.74359)
		(end 24.580088 -312.369454)
		(width 0.1651)
		(layer "In7.Cu")
		(net "P5E_PEX0_STN7_TX_DN<116>")
	)
	(segment
		(start 182.042054 -327.714356)
		(end 186.195462 -323.560948)
		(width 0.1651)
		(layer "In15.Cu")
		(net "P5E_PEX1_STN5_RX_DP<94>")
	)
	(segment
		(start 130.018028 -370.49583)
		(end 130.018028 -369.153948)
		(width 0.1651)
		(layer "In15.Cu")
		(net "P5E_PEX1_STN5_RX_DP<94>")
	)
	(segment
		(start 186.195462 -323.560948)
		(end 187.146438 -322.015866)
		(width 0.1651)
		(layer "In15.Cu")
		(net "P5E_PEX1_STN5_RX_DP<94>")
	)
	(segment
		(start 130.018028 -369.153948)
		(end 130.407918 -368.530378)
		(width 0.1651)
		(layer "In15.Cu")
		(net "P5E_PEX1_STN5_RX_DP<94>")
	)
	(segment
		(start 129.236978 -370.999258)
		(end 129.5146 -370.999258)
		(width 0.1651)
		(layer "In15.Cu")
		(net "P5E_PEX1_STN5_RX_DP<94>")
	)
	(segment
		(start 143.695674 -361.650788)
		(end 146.002756 -359.847642)
		(width 0.1651)
		(layer "In15.Cu")
		(net "P5E_PEX1_STN5_RX_DP<94>")
	)
	(segment
		(start 137.13206 -364.715806)
		(end 137.57783 -364.49889)
		(width 0.1651)
		(layer "In15.Cu")
		(net "P5E_PEX1_STN5_RX_DP<94>")
	)
	(segment
		(start 134.885938 -365.93526)
		(end 134.886192 -365.93526)
		(width 0.1651)
		(layer "In15.Cu")
		(net "P5E_PEX1_STN5_RX_DP<94>")
	)
	(segment
		(start 187.484004 -321.141344)
		(end 187.484004 -319.916048)
		(width 0.1651)
		(layer "In15.Cu")
		(net "P5E_PEX1_STN5_RX_DP<94>")
	)
	(segment
		(start 135.98271 -365.402114)
		(end 136.035542 -365.249206)
		(width 0.1651)
		(layer "In15.Cu")
		(net "P5E_PEX1_STN5_RX_DP<94>")
	)
	(segment
		(start 187.80633 -316.229492)
		(end 188.011054 -316.229492)
		(width 0.1143)
		(layer "In15.Cu")
		(net "P5E_PEX1_STN5_RX_DP<94>")
	)
	(segment
		(start 136.633966 -365.085122)
		(end 137.079228 -364.868714)
		(width 0.1651)
		(layer "In15.Cu")
		(net "P5E_PEX1_STN5_RX_DP<94>")
	)
	(segment
		(start 129.109978 -370.872258)
		(end 129.236978 -370.999258)
		(width 0.1651)
		(layer "In15.Cu")
		(net "P5E_PEX1_STN5_RX_DP<94>")
	)
	(segment
		(start 135.537194 -365.618522)
		(end 135.982456 -365.40186)
		(width 0.1651)
		(layer "In15.Cu")
		(net "P5E_PEX1_STN5_RX_DP<94>")
	)
	(segment
		(start 168.974262 -336.380074)
		(end 182.042054 -327.714356)
		(width 0.1651)
		(layer "In15.Cu")
		(net "P5E_PEX1_STN5_RX_DP<94>")
	)
	(segment
		(start 187.529724 -319.84188)
		(end 187.529724 -316.506098)
		(width 0.1143)
		(layer "In15.Cu")
		(net "P5E_PEX1_STN5_RX_DP<94>")
	)
	(segment
		(start 146.002756 -359.847642)
		(end 147.732242 -357.779828)
		(width 0.1651)
		(layer "In15.Cu")
		(net "P5E_PEX1_STN5_RX_DP<94>")
	)
	(segment
		(start 187.484004 -319.8876)
		(end 187.529724 -319.84188)
		(width 0.1143)
		(layer "In15.Cu")
		(net "P5E_PEX1_STN5_RX_DP<94>")
	)
	(segment
		(start 131.42087 -367.62055)
		(end 134.885938 -365.93526)
		(width 0.1651)
		(layer "In15.Cu")
		(net "P5E_PEX1_STN5_RX_DP<94>")
	)
	(segment
		(start 129.109978 -370.489988)
		(end 129.109978 -370.872258)
		(width 0.1651)
		(layer "In15.Cu")
		(net "P5E_PEX1_STN5_RX_DP<94>")
	)
	(segment
		(start 137.57783 -364.49889)
		(end 137.730484 -364.551722)
		(width 0.1651)
		(layer "In15.Cu")
		(net "P5E_PEX1_STN5_RX_DP<94>")
	)
	(segment
		(start 162.620198 -341.670894)
		(end 162.65017 -341.641938)
		(width 0.1651)
		(layer "In15.Cu")
		(net "P5E_PEX1_STN5_RX_DP<94>")
	)
	(segment
		(start 130.407918 -368.530378)
		(end 131.42087 -367.62055)
		(width 0.1651)
		(layer "In15.Cu")
		(net "P5E_PEX1_STN5_RX_DP<94>")
	)
	(segment
		(start 129.5146 -370.999258)
		(end 130.018028 -370.49583)
		(width 0.1651)
		(layer "In15.Cu")
		(net "P5E_PEX1_STN5_RX_DP<94>")
	)
	(segment
		(start 135.982456 -365.40186)
		(end 135.98271 -365.402114)
		(width 0.1651)
		(layer "In15.Cu")
		(net "P5E_PEX1_STN5_RX_DP<94>")
	)
	(segment
		(start 188.011054 -316.229492)
		(end 188.099954 -316.140592)
		(width 0.1143)
		(layer "In15.Cu")
		(net "P5E_PEX1_STN5_RX_DP<94>")
	)
	(segment
		(start 137.730484 -364.551722)
		(end 143.695674 -361.650788)
		(width 0.1651)
		(layer "In15.Cu")
		(net "P5E_PEX1_STN5_RX_DP<94>")
	)
	(segment
		(start 162.65017 -341.641938)
		(end 168.974262 -336.380074)
		(width 0.1651)
		(layer "In15.Cu")
		(net "P5E_PEX1_STN5_RX_DP<94>")
	)
	(segment
		(start 136.481312 -365.03229)
		(end 136.633966 -365.085122)
		(width 0.1651)
		(layer "In15.Cu")
		(net "P5E_PEX1_STN5_RX_DP<94>")
	)
	(segment
		(start 187.529724 -316.506098)
		(end 187.80633 -316.229492)
		(width 0.1143)
		(layer "In15.Cu")
		(net "P5E_PEX1_STN5_RX_DP<94>")
	)
	(segment
		(start 187.484004 -319.916048)
		(end 187.484004 -319.8876)
		(width 0.1143)
		(layer "In15.Cu")
		(net "P5E_PEX1_STN5_RX_DP<94>")
	)
	(segment
		(start 147.732242 -357.779828)
		(end 162.620198 -341.670894)
		(width 0.1651)
		(layer "In15.Cu")
		(net "P5E_PEX1_STN5_RX_DP<94>")
	)
	(segment
		(start 187.146438 -322.015866)
		(end 187.484004 -321.141344)
		(width 0.1651)
		(layer "In15.Cu")
		(net "P5E_PEX1_STN5_RX_DP<94>")
	)
	(segment
		(start 136.035542 -365.249206)
		(end 136.481312 -365.03229)
		(width 0.1651)
		(layer "In15.Cu")
		(net "P5E_PEX1_STN5_RX_DP<94>")
	)
	(segment
		(start 188.099954 -316.140592)
		(end 188.099954 -315.849762)
		(width 0.1143)
		(layer "In15.Cu")
		(net "P5E_PEX1_STN5_RX_DP<94>")
	)
	(segment
		(start 137.079228 -364.868714)
		(end 137.13206 -364.715806)
		(width 0.1651)
		(layer "In15.Cu")
		(net "P5E_PEX1_STN5_RX_DP<94>")
	)
	(segment
		(start 134.886192 -365.93526)
		(end 134.939024 -365.782606)
		(width 0.1651)
		(layer "In15.Cu")
		(net "P5E_PEX1_STN5_RX_DP<94>")
	)
	(segment
		(start 134.939024 -365.782606)
		(end 135.38454 -365.56569)
		(width 0.1651)
		(layer "In15.Cu")
		(net "P5E_PEX1_STN5_RX_DP<94>")
	)
	(segment
		(start 135.38454 -365.56569)
		(end 135.537194 -365.618522)
		(width 0.1651)
		(layer "In15.Cu")
		(net "P5E_PEX1_STN5_RX_DP<94>")
	)
	(segment
		(start 64.481202 -345.465146)
		(end 64.775842 -345.170506)
		(width 0.13462)
		(layer "F.Cu")
		(net "P5E_PEX0_STN5_TX_C_DP<81>")
	)
	(segment
		(start 64.775842 -345.170506)
		(end 64.775842 -344.539062)
		(width 0.13462)
		(layer "F.Cu")
		(net "P5E_PEX0_STN5_TX_C_DP<81>")
	)
	(segment
		(start 64.775842 -344.539062)
		(end 64.455802 -344.219022)
		(width 0.13462)
		(layer "F.Cu")
		(net "P5E_PEX0_STN5_TX_C_DP<81>")
	)
	(segment
		(start 64.715898 -385.514342)
		(end 66.072766 -388.789672)
		(width 0.1651)
		(layer "In7.Cu")
		(net "P5E_PEX0_STN5_TX_C_DP<81>")
	)
	(segment
		(start 73.720452 -393.422886)
		(end 74.176128 -393.878562)
		(width 0.1651)
		(layer "In7.Cu")
		(net "P5E_PEX0_STN5_TX_C_DP<81>")
	)
	(segment
		(start 74.176128 -393.878562)
		(end 74.176128 -394.004292)
		(width 0.1651)
		(layer "In7.Cu")
		(net "P5E_PEX0_STN5_TX_C_DP<81>")
	)
	(segment
		(start 75.00239 -405.54783)
		(end 74.651108 -405.899112)
		(width 0.1651)
		(layer "In7.Cu")
		(net "P5E_PEX0_STN5_TX_C_DP<81>")
	)
	(segment
		(start 74.176128 -394.004292)
		(end 74.526648 -394.354812)
		(width 0.1651)
		(layer "In7.Cu")
		(net "P5E_PEX0_STN5_TX_C_DP<81>")
	)
	(segment
		(start 74.651108 -405.899112)
		(end 74.236834 -405.899112)
		(width 0.1651)
		(layer "In7.Cu")
		(net "P5E_PEX0_STN5_TX_C_DP<81>")
	)
	(segment
		(start 63.217552 -347.912182)
		(end 63.217552 -357.785924)
		(width 0.1651)
		(layer "In7.Cu")
		(net "P5E_PEX0_STN5_TX_C_DP<81>")
	)
	(segment
		(start 74.109834 -405.772112)
		(end 74.109834 -405.390096)
		(width 0.1651)
		(layer "In7.Cu")
		(net "P5E_PEX0_STN5_TX_C_DP<81>")
	)
	(segment
		(start 74.526648 -394.354812)
		(end 74.652378 -394.354812)
		(width 0.1651)
		(layer "In7.Cu")
		(net "P5E_PEX0_STN5_TX_C_DP<81>")
	)
	(segment
		(start 64.772032 -345.755976)
		(end 64.772032 -346.357702)
		(width 0.1651)
		(layer "In7.Cu")
		(net "P5E_PEX0_STN5_TX_C_DP<81>")
	)
	(segment
		(start 74.652378 -394.354812)
		(end 75.00239 -394.704824)
		(width 0.1651)
		(layer "In7.Cu")
		(net "P5E_PEX0_STN5_TX_C_DP<81>")
	)
	(segment
		(start 75.00239 -394.704824)
		(end 75.00239 -405.54783)
		(width 0.1651)
		(layer "In7.Cu")
		(net "P5E_PEX0_STN5_TX_C_DP<81>")
	)
	(segment
		(start 66.072766 -388.789672)
		(end 68.574666 -391.291572)
		(width 0.1651)
		(layer "In7.Cu")
		(net "P5E_PEX0_STN5_TX_C_DP<81>")
	)
	(segment
		(start 64.772032 -346.357702)
		(end 63.217552 -347.912182)
		(width 0.1651)
		(layer "In7.Cu")
		(net "P5E_PEX0_STN5_TX_C_DP<81>")
	)
	(segment
		(start 63.217552 -357.785924)
		(end 64.715898 -385.514342)
		(width 0.1651)
		(layer "In7.Cu")
		(net "P5E_PEX0_STN5_TX_C_DP<81>")
	)
	(segment
		(start 68.574666 -391.291572)
		(end 73.720452 -393.422886)
		(width 0.1651)
		(layer "In7.Cu")
		(net "P5E_PEX0_STN5_TX_C_DP<81>")
	)
	(segment
		(start 74.236834 -405.899112)
		(end 74.109834 -405.772112)
		(width 0.1651)
		(layer "In7.Cu")
		(net "P5E_PEX0_STN5_TX_C_DP<81>")
	)
	(segment
		(start 64.481202 -345.465146)
		(end 64.772032 -345.755976)
		(width 0.1651)
		(layer "In7.Cu")
		(net "P5E_PEX0_STN5_TX_C_DP<81>")
	)
	(segment
		(start 80.286098 -134.394702)
		(end 80.606138 -134.074662)
		(width 0.13462)
		(layer "F.Cu")
		(net "P5E_PEX0_STN0_TX_DP<6>")
	)
	(segment
		(start 81.237582 -134.074662)
		(end 81.532222 -134.369302)
		(width 0.13462)
		(layer "F.Cu")
		(net "P5E_PEX0_STN0_TX_DP<6>")
	)
	(segment
		(start 80.606138 -134.074662)
		(end 81.237582 -134.074662)
		(width 0.13462)
		(layer "F.Cu")
		(net "P5E_PEX0_STN0_TX_DP<6>")
	)
	(segment
		(start 94.083124 -153.984706)
		(end 94.083124 -158.922212)
		(width 0.1651)
		(layer "In9.Cu")
		(net "P5E_PEX0_STN0_TX_DP<6>")
	)
	(segment
		(start 87.738966 -139.58443)
		(end 87.872062 -139.639294)
		(width 0.1651)
		(layer "In9.Cu")
		(net "P5E_PEX0_STN0_TX_DP<6>")
	)
	(segment
		(start 77.344778 -282.029662)
		(end 77.12964 -282.2448)
		(width 0.1143)
		(layer "In9.Cu")
		(net "P5E_PEX0_STN0_TX_DP<6>")
	)
	(segment
		(start 86.883494 -137.518902)
		(end 87.016336 -137.57402)
		(width 0.1651)
		(layer "In9.Cu")
		(net "P5E_PEX0_STN0_TX_DP<6>")
	)
	(segment
		(start 81.532222 -134.369302)
		(end 81.823052 -134.078472)
		(width 0.1651)
		(layer "In9.Cu")
		(net "P5E_PEX0_STN0_TX_DP<6>")
	)
	(segment
		(start 80.529684 -221.640654)
		(end 80.531716 -221.665038)
		(width 0.1651)
		(layer "In9.Cu")
		(net "P5E_PEX0_STN0_TX_DP<6>")
	)
	(segment
		(start 87.872062 -139.639294)
		(end 88.046814 -140.061442)
		(width 0.1651)
		(layer "In9.Cu")
		(net "P5E_PEX0_STN0_TX_DP<6>")
	)
	(segment
		(start 94.557342 -271.54632)
		(end 93.824552 -273.559524)
		(width 0.1651)
		(layer "In9.Cu")
		(net "P5E_PEX0_STN0_TX_DP<6>")
	)
	(segment
		(start 83.719924 -134.078472)
		(end 84.142326 -134.253478)
		(width 0.1651)
		(layer "In9.Cu")
		(net "P5E_PEX0_STN0_TX_DP<6>")
	)
	(segment
		(start 84.142326 -134.253478)
		(end 84.142326 -134.253224)
		(width 0.1651)
		(layer "In9.Cu")
		(net "P5E_PEX0_STN0_TX_DP<6>")
	)
	(segment
		(start 84.142326 -134.253224)
		(end 84.200238 -134.392924)
		(width 0.1651)
		(layer "In9.Cu")
		(net "P5E_PEX0_STN0_TX_DP<6>")
	)
	(segment
		(start 87.016336 -137.57402)
		(end 87.191088 -137.996168)
		(width 0.1651)
		(layer "In9.Cu")
		(net "P5E_PEX0_STN0_TX_DP<6>")
	)
	(segment
		(start 82.699098 -134.185152)
		(end 83.156298 -134.185152)
		(width 0.1651)
		(layer "In9.Cu")
		(net "P5E_PEX0_STN0_TX_DP<6>")
	)
	(segment
		(start 88.299798 -140.672058)
		(end 90.148664 -145.135346)
		(width 0.1651)
		(layer "In9.Cu")
		(net "P5E_PEX0_STN0_TX_DP<6>")
	)
	(segment
		(start 87.31123 -138.551666)
		(end 87.444072 -138.606784)
		(width 0.1651)
		(layer "In9.Cu")
		(net "P5E_PEX0_STN0_TX_DP<6>")
	)
	(segment
		(start 85.506306 -173.78172)
		(end 84.334604 -178.151028)
		(width 0.1651)
		(layer "In9.Cu")
		(net "P5E_PEX0_STN0_TX_DP<6>")
	)
	(segment
		(start 84.334604 -178.151028)
		(end 80.529684 -221.640654)
		(width 0.1651)
		(layer "In9.Cu")
		(net "P5E_PEX0_STN0_TX_DP<6>")
	)
	(segment
		(start 87.444072 -138.606784)
		(end 87.618824 -139.028932)
		(width 0.1651)
		(layer "In9.Cu")
		(net "P5E_PEX0_STN0_TX_DP<6>")
	)
	(segment
		(start 86.449154 -136.483344)
		(end 86.588854 -136.541256)
		(width 0.1651)
		(layer "In9.Cu")
		(net "P5E_PEX0_STN0_TX_DP<6>")
	)
	(segment
		(start 88.47074 -259.504434)
		(end 93.74505 -267.397992)
		(width 0.1651)
		(layer "In9.Cu")
		(net "P5E_PEX0_STN0_TX_DP<6>")
	)
	(segment
		(start 81.823052 -134.078472)
		(end 82.592418 -134.078472)
		(width 0.1651)
		(layer "In9.Cu")
		(net "P5E_PEX0_STN0_TX_DP<6>")
	)
	(segment
		(start 86.588854 -136.541256)
		(end 86.5886 -136.541256)
		(width 0.1651)
		(layer "In9.Cu")
		(net "P5E_PEX0_STN0_TX_DP<6>")
	)
	(segment
		(start 94.083124 -158.922212)
		(end 85.506306 -173.78172)
		(width 0.1651)
		(layer "In9.Cu")
		(net "P5E_PEX0_STN0_TX_DP<6>")
	)
	(segment
		(start 85.454998 -134.797038)
		(end 86.157054 -135.499094)
		(width 0.1651)
		(layer "In9.Cu")
		(net "P5E_PEX0_STN0_TX_DP<6>")
	)
	(segment
		(start 84.76234 -134.510272)
		(end 85.454998 -134.797038)
		(width 0.1651)
		(layer "In9.Cu")
		(net "P5E_PEX0_STN0_TX_DP<6>")
	)
	(segment
		(start 87.56396 -139.161774)
		(end 87.738966 -139.58443)
		(width 0.1651)
		(layer "In9.Cu")
		(net "P5E_PEX0_STN0_TX_DP<6>")
	)
	(segment
		(start 88.046814 -140.061442)
		(end 87.99195 -140.194284)
		(width 0.1651)
		(layer "In9.Cu")
		(net "P5E_PEX0_STN0_TX_DP<6>")
	)
	(segment
		(start 90.148664 -145.135346)
		(end 90.607896 -145.594578)
		(width 0.1651)
		(layer "In9.Cu")
		(net "P5E_PEX0_STN0_TX_DP<6>")
	)
	(segment
		(start 84.200238 -134.392924)
		(end 84.622894 -134.56793)
		(width 0.1651)
		(layer "In9.Cu")
		(net "P5E_PEX0_STN0_TX_DP<6>")
	)
	(segment
		(start 86.157054 -135.499094)
		(end 86.331806 -135.921242)
		(width 0.1651)
		(layer "In9.Cu")
		(net "P5E_PEX0_STN0_TX_DP<6>")
	)
	(segment
		(start 87.99195 -140.194284)
		(end 88.166956 -140.61694)
		(width 0.1651)
		(layer "In9.Cu")
		(net "P5E_PEX0_STN0_TX_DP<6>")
	)
	(segment
		(start 86.5886 -136.541256)
		(end 86.763352 -136.963404)
		(width 0.1651)
		(layer "In9.Cu")
		(net "P5E_PEX0_STN0_TX_DP<6>")
	)
	(segment
		(start 83.843368 -282.029662)
		(end 77.344778 -282.029662)
		(width 0.1143)
		(layer "In9.Cu")
		(net "P5E_PEX0_STN0_TX_DP<6>")
	)
	(segment
		(start 82.592418 -134.078472)
		(end 82.699098 -134.185152)
		(width 0.1651)
		(layer "In9.Cu")
		(net "P5E_PEX0_STN0_TX_DP<6>")
	)
	(segment
		(start 87.618824 -139.028932)
		(end 87.56396 -139.161774)
		(width 0.1651)
		(layer "In9.Cu")
		(net "P5E_PEX0_STN0_TX_DP<6>")
	)
	(segment
		(start 83.917536 -281.983942)
		(end 83.889088 -281.983942)
		(width 0.1143)
		(layer "In9.Cu")
		(net "P5E_PEX0_STN0_TX_DP<6>")
	)
	(segment
		(start 93.74505 -267.397992)
		(end 94.314264 -268.772386)
		(width 0.1651)
		(layer "In9.Cu")
		(net "P5E_PEX0_STN0_TX_DP<6>")
	)
	(segment
		(start 86.708488 -137.096246)
		(end 86.883494 -137.518902)
		(width 0.1651)
		(layer "In9.Cu")
		(net "P5E_PEX0_STN0_TX_DP<6>")
	)
	(segment
		(start 83.889088 -281.983942)
		(end 83.843368 -282.029662)
		(width 0.1143)
		(layer "In9.Cu")
		(net "P5E_PEX0_STN0_TX_DP<6>")
	)
	(segment
		(start 83.156298 -134.185152)
		(end 83.262978 -134.078472)
		(width 0.1651)
		(layer "In9.Cu")
		(net "P5E_PEX0_STN0_TX_DP<6>")
	)
	(segment
		(start 85.988652 -281.395424)
		(end 84.567522 -281.983942)
		(width 0.1651)
		(layer "In9.Cu")
		(net "P5E_PEX0_STN0_TX_DP<6>")
	)
	(segment
		(start 87.191088 -137.996168)
		(end 87.136224 -138.12901)
		(width 0.1651)
		(layer "In9.Cu")
		(net "P5E_PEX0_STN0_TX_DP<6>")
	)
	(segment
		(start 90.607896 -145.594578)
		(end 94.083124 -153.984706)
		(width 0.1651)
		(layer "In9.Cu")
		(net "P5E_PEX0_STN0_TX_DP<6>")
	)
	(segment
		(start 80.53197 -221.665038)
		(end 83.140296 -251.527056)
		(width 0.1651)
		(layer "In9.Cu")
		(net "P5E_PEX0_STN0_TX_DP<6>")
	)
	(segment
		(start 77.12964 -282.485592)
		(end 77.01534 -282.599892)
		(width 0.1143)
		(layer "In9.Cu")
		(net "P5E_PEX0_STN0_TX_DP<6>")
	)
	(segment
		(start 94.314264 -268.772386)
		(end 94.557342 -271.54632)
		(width 0.1651)
		(layer "In9.Cu")
		(net "P5E_PEX0_STN0_TX_DP<6>")
	)
	(segment
		(start 86.763352 -136.963404)
		(end 86.708488 -137.096246)
		(width 0.1651)
		(layer "In9.Cu")
		(net "P5E_PEX0_STN0_TX_DP<6>")
	)
	(segment
		(start 80.531716 -221.665038)
		(end 80.53197 -221.665038)
		(width 0.1651)
		(layer "In9.Cu")
		(net "P5E_PEX0_STN0_TX_DP<6>")
	)
	(segment
		(start 86.274148 -136.060688)
		(end 86.449154 -136.483344)
		(width 0.1651)
		(layer "In9.Cu")
		(net "P5E_PEX0_STN0_TX_DP<6>")
	)
	(segment
		(start 84.567522 -281.983942)
		(end 83.917536 -281.983942)
		(width 0.1651)
		(layer "In9.Cu")
		(net "P5E_PEX0_STN0_TX_DP<6>")
	)
	(segment
		(start 84.622894 -134.56793)
		(end 84.76234 -134.510272)
		(width 0.1651)
		(layer "In9.Cu")
		(net "P5E_PEX0_STN0_TX_DP<6>")
	)
	(segment
		(start 77.12964 -282.2448)
		(end 77.12964 -282.485592)
		(width 0.1143)
		(layer "In9.Cu")
		(net "P5E_PEX0_STN0_TX_DP<6>")
	)
	(segment
		(start 93.824552 -273.559524)
		(end 85.988652 -281.395424)
		(width 0.1651)
		(layer "In9.Cu")
		(net "P5E_PEX0_STN0_TX_DP<6>")
	)
	(segment
		(start 77.01534 -282.599892)
		(end 76.74991 -282.599892)
		(width 0.1143)
		(layer "In9.Cu")
		(net "P5E_PEX0_STN0_TX_DP<6>")
	)
	(segment
		(start 83.140296 -251.527056)
		(end 88.47074 -259.504434)
		(width 0.1651)
		(layer "In9.Cu")
		(net "P5E_PEX0_STN0_TX_DP<6>")
	)
	(segment
		(start 88.166956 -140.61694)
		(end 88.299798 -140.672058)
		(width 0.1651)
		(layer "In9.Cu")
		(net "P5E_PEX0_STN0_TX_DP<6>")
	)
	(segment
		(start 87.136224 -138.12901)
		(end 87.31123 -138.551666)
		(width 0.1651)
		(layer "In9.Cu")
		(net "P5E_PEX0_STN0_TX_DP<6>")
	)
	(segment
		(start 86.331806 -135.921242)
		(end 86.274148 -136.060688)
		(width 0.1651)
		(layer "In9.Cu")
		(net "P5E_PEX0_STN0_TX_DP<6>")
	)
	(segment
		(start 83.262978 -134.078472)
		(end 83.719924 -134.078472)
		(width 0.1651)
		(layer "In9.Cu")
		(net "P5E_PEX0_STN0_TX_DP<6>")
	)
	(segment
		(start 47.607728 -355.026722)
		(end 47.313088 -354.732082)
		(width 0.13462)
		(layer "F.Cu")
		(net "P5E_PEX0_STN7_TX_DP<126>")
	)
	(segment
		(start 47.607728 -355.658166)
		(end 47.607728 -355.026722)
		(width 0.13462)
		(layer "F.Cu")
		(net "P5E_PEX0_STN7_TX_DP<126>")
	)
	(segment
		(start 47.287688 -355.978206)
		(end 47.607728 -355.658166)
		(width 0.13462)
		(layer "F.Cu")
		(net "P5E_PEX0_STN7_TX_DP<126>")
	)
	(segment
		(start 42.008806 -324.504812)
		(end 41.80205 -324.068186)
		(width 0.1651)
		(layer "In7.Cu")
		(net "P5E_PEX0_STN7_TX_DP<126>")
	)
	(segment
		(start 41.029636 -319.84188)
		(end 41.029636 -311.705498)
		(width 0.1143)
		(layer "In7.Cu")
		(net "P5E_PEX0_STN7_TX_DP<126>")
	)
	(segment
		(start 48.574198 -339.408008)
		(end 46.954694 -334.701134)
		(width 0.1651)
		(layer "In7.Cu")
		(net "P5E_PEX0_STN7_TX_DP<126>")
	)
	(segment
		(start 47.603918 -353.825302)
		(end 49.158398 -352.270822)
		(width 0.1651)
		(layer "In7.Cu")
		(net "P5E_PEX0_STN7_TX_DP<126>")
	)
	(segment
		(start 40.978836 -319.916048)
		(end 40.983916 -319.910968)
		(width 0.1143)
		(layer "In7.Cu")
		(net "P5E_PEX0_STN7_TX_DP<126>")
	)
	(segment
		(start 49.158398 -352.270822)
		(end 49.158398 -342.009476)
		(width 0.1651)
		(layer "In7.Cu")
		(net "P5E_PEX0_STN7_TX_DP<126>")
	)
	(segment
		(start 49.158398 -342.009476)
		(end 48.574198 -339.408008)
		(width 0.1651)
		(layer "In7.Cu")
		(net "P5E_PEX0_STN7_TX_DP<126>")
	)
	(segment
		(start 41.85539 -323.919342)
		(end 41.649142 -323.483224)
		(width 0.1651)
		(layer "In7.Cu")
		(net "P5E_PEX0_STN7_TX_DP<126>")
	)
	(segment
		(start 41.649142 -323.483224)
		(end 41.500298 -323.430138)
		(width 0.1651)
		(layer "In7.Cu")
		(net "P5E_PEX0_STN7_TX_DP<126>")
	)
	(segment
		(start 41.500298 -323.430138)
		(end 41.293796 -322.993512)
		(width 0.1651)
		(layer "In7.Cu")
		(net "P5E_PEX0_STN7_TX_DP<126>")
	)
	(segment
		(start 47.313088 -354.732082)
		(end 47.603918 -354.441252)
		(width 0.1651)
		(layer "In7.Cu")
		(net "P5E_PEX0_STN7_TX_DP<126>")
	)
	(segment
		(start 41.255442 -311.479692)
		(end 41.485566 -311.479692)
		(width 0.1143)
		(layer "In7.Cu")
		(net "P5E_PEX0_STN7_TX_DP<126>")
	)
	(segment
		(start 40.978836 -322.065904)
		(end 40.978836 -319.916048)
		(width 0.1651)
		(layer "In7.Cu")
		(net "P5E_PEX0_STN7_TX_DP<126>")
	)
	(segment
		(start 41.029636 -311.705498)
		(end 41.255442 -311.479692)
		(width 0.1143)
		(layer "In7.Cu")
		(net "P5E_PEX0_STN7_TX_DP<126>")
	)
	(segment
		(start 41.347136 -322.844668)
		(end 40.978836 -322.065904)
		(width 0.1651)
		(layer "In7.Cu")
		(net "P5E_PEX0_STN7_TX_DP<126>")
	)
	(segment
		(start 40.983916 -319.8876)
		(end 41.029636 -319.84188)
		(width 0.1143)
		(layer "In7.Cu")
		(net "P5E_PEX0_STN7_TX_DP<126>")
	)
	(segment
		(start 42.157396 -324.557898)
		(end 42.008806 -324.504812)
		(width 0.1651)
		(layer "In7.Cu")
		(net "P5E_PEX0_STN7_TX_DP<126>")
	)
	(segment
		(start 41.293796 -322.993512)
		(end 41.347136 -322.844668)
		(width 0.1651)
		(layer "In7.Cu")
		(net "P5E_PEX0_STN7_TX_DP<126>")
	)
	(segment
		(start 46.954694 -334.701134)
		(end 42.157396 -324.557898)
		(width 0.1651)
		(layer "In7.Cu")
		(net "P5E_PEX0_STN7_TX_DP<126>")
	)
	(segment
		(start 41.599866 -311.365392)
		(end 41.599866 -311.099962)
		(width 0.1143)
		(layer "In7.Cu")
		(net "P5E_PEX0_STN7_TX_DP<126>")
	)
	(segment
		(start 47.603918 -354.441252)
		(end 47.603918 -353.825302)
		(width 0.1651)
		(layer "In7.Cu")
		(net "P5E_PEX0_STN7_TX_DP<126>")
	)
	(segment
		(start 41.80205 -324.068186)
		(end 41.85539 -323.919342)
		(width 0.1651)
		(layer "In7.Cu")
		(net "P5E_PEX0_STN7_TX_DP<126>")
	)
	(segment
		(start 40.983916 -319.910968)
		(end 40.983916 -319.8876)
		(width 0.1143)
		(layer "In7.Cu")
		(net "P5E_PEX0_STN7_TX_DP<126>")
	)
	(segment
		(start 41.485566 -311.479692)
		(end 41.599866 -311.365392)
		(width 0.1143)
		(layer "In7.Cu")
		(net "P5E_PEX0_STN7_TX_DP<126>")
	)
	(segment
		(start 158.649924 -318.040766)
		(end 158.649924 -317.749936)
		(width 0.1143)
		(layer "In9.Cu")
		(net "P5E_PEX1_STN7_RX_DP<127>")
	)
	(segment
		(start 158.3563 -318.129666)
		(end 158.561024 -318.129666)
		(width 0.1143)
		(layer "In9.Cu")
		(net "P5E_PEX1_STN7_RX_DP<127>")
	)
	(segment
		(start 175.351948 -365.461296)
		(end 175.211232 -365.38154)
		(width 0.1651)
		(layer "In9.Cu")
		(net "P5E_PEX1_STN7_RX_DP<127>")
	)
	(segment
		(start 175.978566 -367.735612)
		(end 175.351948 -365.461296)
		(width 0.1651)
		(layer "In9.Cu")
		(net "P5E_PEX1_STN7_RX_DP<127>")
	)
	(segment
		(start 158.033974 -320.60642)
		(end 158.033974 -319.865248)
		(width 0.1651)
		(layer "In9.Cu")
		(net "P5E_PEX1_STN7_RX_DP<127>")
	)
	(segment
		(start 175.310038 -383.290064)
		(end 175.310038 -383.67208)
		(width 0.1651)
		(layer "In9.Cu")
		(net "P5E_PEX1_STN7_RX_DP<127>")
	)
	(segment
		(start 175.310038 -383.67208)
		(end 175.437038 -383.79908)
		(width 0.1651)
		(layer "In9.Cu")
		(net "P5E_PEX1_STN7_RX_DP<127>")
	)
	(segment
		(start 173.358302 -341.982044)
		(end 164.600636 -329.00874)
		(width 0.1651)
		(layer "In9.Cu")
		(net "P5E_PEX1_STN7_RX_DP<127>")
	)
	(segment
		(start 158.033974 -319.8368)
		(end 158.079694 -319.79108)
		(width 0.1143)
		(layer "In9.Cu")
		(net "P5E_PEX1_STN7_RX_DP<127>")
	)
	(segment
		(start 158.079694 -319.79108)
		(end 158.079694 -318.406272)
		(width 0.1143)
		(layer "In9.Cu")
		(net "P5E_PEX1_STN7_RX_DP<127>")
	)
	(segment
		(start 175.211232 -365.38154)
		(end 175.07966 -364.903766)
		(width 0.1651)
		(layer "In9.Cu")
		(net "P5E_PEX1_STN7_RX_DP<127>")
	)
	(segment
		(start 175.437038 -383.79908)
		(end 175.658526 -383.79908)
		(width 0.1651)
		(layer "In9.Cu")
		(net "P5E_PEX1_STN7_RX_DP<127>")
	)
	(segment
		(start 175.658526 -383.79908)
		(end 176.185068 -383.272538)
		(width 0.1651)
		(layer "In9.Cu")
		(net "P5E_PEX1_STN7_RX_DP<127>")
	)
	(segment
		(start 158.312358 -321.381882)
		(end 158.033974 -320.60642)
		(width 0.1651)
		(layer "In9.Cu")
		(net "P5E_PEX1_STN7_RX_DP<127>")
	)
	(segment
		(start 176.185068 -369.261644)
		(end 175.978566 -367.735612)
		(width 0.1651)
		(layer "In9.Cu")
		(net "P5E_PEX1_STN7_RX_DP<127>")
	)
	(segment
		(start 158.561024 -318.129666)
		(end 158.649924 -318.040766)
		(width 0.1143)
		(layer "In9.Cu")
		(net "P5E_PEX1_STN7_RX_DP<127>")
	)
	(segment
		(start 176.185068 -383.272538)
		(end 176.185068 -369.261644)
		(width 0.1651)
		(layer "In9.Cu")
		(net "P5E_PEX1_STN7_RX_DP<127>")
	)
	(segment
		(start 158.079694 -318.406272)
		(end 158.3563 -318.129666)
		(width 0.1143)
		(layer "In9.Cu")
		(net "P5E_PEX1_STN7_RX_DP<127>")
	)
	(segment
		(start 175.159416 -364.76305)
		(end 173.358302 -358.226614)
		(width 0.1651)
		(layer "In9.Cu")
		(net "P5E_PEX1_STN7_RX_DP<127>")
	)
	(segment
		(start 175.07966 -364.903766)
		(end 175.159416 -364.76305)
		(width 0.1651)
		(layer "In9.Cu")
		(net "P5E_PEX1_STN7_RX_DP<127>")
	)
	(segment
		(start 173.358302 -358.226614)
		(end 173.358302 -341.982044)
		(width 0.1651)
		(layer "In9.Cu")
		(net "P5E_PEX1_STN7_RX_DP<127>")
	)
	(segment
		(start 158.033974 -319.865248)
		(end 158.033974 -319.8368)
		(width 0.1143)
		(layer "In9.Cu")
		(net "P5E_PEX1_STN7_RX_DP<127>")
	)
	(segment
		(start 164.600636 -329.00874)
		(end 158.312358 -321.381882)
		(width 0.1651)
		(layer "In9.Cu")
		(net "P5E_PEX1_STN7_RX_DP<127>")
	)
	(segment
		(start 77.780642 -345.465146)
		(end 77.486002 -345.170506)
		(width 0.13462)
		(layer "F.Cu")
		(net "P5E_PEX0_STN5_TX_C_DN<87>")
	)
	(segment
		(start 77.486002 -345.170506)
		(end 77.486002 -344.539062)
		(width 0.13462)
		(layer "F.Cu")
		(net "P5E_PEX0_STN5_TX_C_DN<87>")
	)
	(segment
		(start 77.486002 -344.539062)
		(end 77.806042 -344.219022)
		(width 0.13462)
		(layer "F.Cu")
		(net "P5E_PEX0_STN5_TX_C_DN<87>")
	)
	(segment
		(start 88.484202 -405.664924)
		(end 88.484202 -394.427202)
		(width 0.1651)
		(layer "In7.Cu")
		(net "P5E_PEX0_STN5_TX_C_DN<87>")
	)
	(segment
		(start 87.43696 -406.181052)
		(end 87.968074 -406.181052)
		(width 0.1651)
		(layer "In7.Cu")
		(net "P5E_PEX0_STN5_TX_C_DN<87>")
	)
	(segment
		(start 70.750938 -368.718846)
		(end 75.523598 -359.68432)
		(width 0.1651)
		(layer "In7.Cu")
		(net "P5E_PEX0_STN5_TX_C_DN<87>")
	)
	(segment
		(start 71.213472 -385.031234)
		(end 70.884288 -384.236468)
		(width 0.1651)
		(layer "In7.Cu")
		(net "P5E_PEX0_STN5_TX_C_DN<87>")
	)
	(segment
		(start 88.484202 -394.427202)
		(end 85.35162 -391.29462)
		(width 0.1651)
		(layer "In7.Cu")
		(net "P5E_PEX0_STN5_TX_C_DN<87>")
	)
	(segment
		(start 77.489812 -346.474542)
		(end 77.489812 -345.755976)
		(width 0.1651)
		(layer "In7.Cu")
		(net "P5E_PEX0_STN5_TX_C_DN<87>")
	)
	(segment
		(start 75.523598 -359.68432)
		(end 75.935332 -358.023668)
		(width 0.1651)
		(layer "In7.Cu")
		(net "P5E_PEX0_STN5_TX_C_DN<87>")
	)
	(segment
		(start 87.968074 -406.181052)
		(end 88.484202 -405.664924)
		(width 0.1651)
		(layer "In7.Cu")
		(net "P5E_PEX0_STN5_TX_C_DN<87>")
	)
	(segment
		(start 71.908162 -385.725924)
		(end 71.213472 -385.031234)
		(width 0.1651)
		(layer "In7.Cu")
		(net "P5E_PEX0_STN5_TX_C_DN<87>")
	)
	(segment
		(start 75.935332 -358.023668)
		(end 75.935332 -348.029022)
		(width 0.1651)
		(layer "In7.Cu")
		(net "P5E_PEX0_STN5_TX_C_DN<87>")
	)
	(segment
		(start 70.884288 -384.236468)
		(end 70.884288 -378.972826)
		(width 0.1651)
		(layer "In7.Cu")
		(net "P5E_PEX0_STN5_TX_C_DN<87>")
	)
	(segment
		(start 75.935332 -348.029022)
		(end 77.489812 -346.474542)
		(width 0.1651)
		(layer "In7.Cu")
		(net "P5E_PEX0_STN5_TX_C_DN<87>")
	)
	(segment
		(start 87.30996 -406.690068)
		(end 87.30996 -406.308052)
		(width 0.1651)
		(layer "In7.Cu")
		(net "P5E_PEX0_STN5_TX_C_DN<87>")
	)
	(segment
		(start 77.489812 -345.755976)
		(end 77.780642 -345.465146)
		(width 0.1651)
		(layer "In7.Cu")
		(net "P5E_PEX0_STN5_TX_C_DN<87>")
	)
	(segment
		(start 87.30996 -406.308052)
		(end 87.43696 -406.181052)
		(width 0.1651)
		(layer "In7.Cu")
		(net "P5E_PEX0_STN5_TX_C_DN<87>")
	)
	(segment
		(start 85.35162 -391.29462)
		(end 71.908162 -385.725924)
		(width 0.1651)
		(layer "In7.Cu")
		(net "P5E_PEX0_STN5_TX_C_DN<87>")
	)
	(segment
		(start 70.884288 -378.972826)
		(end 70.750938 -368.718846)
		(width 0.1651)
		(layer "In7.Cu")
		(net "P5E_PEX0_STN5_TX_C_DN<87>")
	)
	(segment
		(start 143.520668 -351.316798)
		(end 143.520668 -350.685354)
		(width 0.13462)
		(layer "F.Cu")
		(net "P5E_PEX1_STN5_TX_C_DN<87>")
	)
	(segment
		(start 143.815308 -351.611438)
		(end 143.520668 -351.316798)
		(width 0.13462)
		(layer "F.Cu")
		(net "P5E_PEX1_STN5_TX_C_DN<87>")
	)
	(segment
		(start 143.520668 -350.685354)
		(end 143.840708 -350.365314)
		(width 0.13462)
		(layer "F.Cu")
		(net "P5E_PEX1_STN5_TX_C_DN<87>")
	)
	(segment
		(start 132.36956 -405.59736)
		(end 132.36956 -396.288514)
		(width 0.1651)
		(layer "In7.Cu")
		(net "P5E_PEX1_STN5_TX_C_DN<87>")
	)
	(segment
		(start 141.560296 -389.905494)
		(end 142.250414 -388.31266)
		(width 0.1651)
		(layer "In7.Cu")
		(net "P5E_PEX1_STN5_TX_C_DN<87>")
	)
	(segment
		(start 143.00454 -383.97053)
		(end 143.00454 -383.2606)
		(width 0.1651)
		(layer "In7.Cu")
		(net "P5E_PEX1_STN5_TX_C_DN<87>")
	)
	(segment
		(start 132.57149 -395.058646)
		(end 132.949442 -394.700506)
		(width 0.1651)
		(layer "In7.Cu")
		(net "P5E_PEX1_STN5_TX_C_DN<87>")
	)
	(segment
		(start 131.786122 -406.180798)
		(end 132.36956 -405.59736)
		(width 0.1651)
		(layer "In7.Cu")
		(net "P5E_PEX1_STN5_TX_C_DN<87>")
	)
	(segment
		(start 132.36956 -396.288514)
		(end 132.57149 -395.058646)
		(width 0.1651)
		(layer "In7.Cu")
		(net "P5E_PEX1_STN5_TX_C_DN<87>")
	)
	(segment
		(start 143.00454 -383.2606)
		(end 143.335248 -369.880896)
		(width 0.1651)
		(layer "In7.Cu")
		(net "P5E_PEX1_STN5_TX_C_DN<87>")
	)
	(segment
		(start 143.524478 -351.902268)
		(end 143.815308 -351.611438)
		(width 0.1651)
		(layer "In7.Cu")
		(net "P5E_PEX1_STN5_TX_C_DN<87>")
	)
	(segment
		(start 140.956538 -390.454388)
		(end 141.560296 -389.905494)
		(width 0.1651)
		(layer "In7.Cu")
		(net "P5E_PEX1_STN5_TX_C_DN<87>")
	)
	(segment
		(start 141.969998 -358.420162)
		(end 141.969998 -354.092002)
		(width 0.1651)
		(layer "In7.Cu")
		(net "P5E_PEX1_STN5_TX_C_DN<87>")
	)
	(segment
		(start 143.335248 -369.880896)
		(end 143.335248 -367.624614)
		(width 0.1651)
		(layer "In7.Cu")
		(net "P5E_PEX1_STN5_TX_C_DN<87>")
	)
	(segment
		(start 131.310126 -406.690068)
		(end 131.310126 -406.308052)
		(width 0.1651)
		(layer "In7.Cu")
		(net "P5E_PEX1_STN5_TX_C_DN<87>")
	)
	(segment
		(start 132.949442 -394.700506)
		(end 138.850116 -392.1125)
		(width 0.1651)
		(layer "In7.Cu")
		(net "P5E_PEX1_STN5_TX_C_DN<87>")
	)
	(segment
		(start 131.43738 -406.180798)
		(end 131.786122 -406.180798)
		(width 0.1651)
		(layer "In7.Cu")
		(net "P5E_PEX1_STN5_TX_C_DN<87>")
	)
	(segment
		(start 143.335248 -367.624614)
		(end 141.969998 -358.420162)
		(width 0.1651)
		(layer "In7.Cu")
		(net "P5E_PEX1_STN5_TX_C_DN<87>")
	)
	(segment
		(start 142.79118 -386.613654)
		(end 143.00454 -383.97053)
		(width 0.1651)
		(layer "In7.Cu")
		(net "P5E_PEX1_STN5_TX_C_DN<87>")
	)
	(segment
		(start 142.250414 -388.31266)
		(end 142.79118 -386.613654)
		(width 0.1651)
		(layer "In7.Cu")
		(net "P5E_PEX1_STN5_TX_C_DN<87>")
	)
	(segment
		(start 131.310126 -406.308052)
		(end 131.43738 -406.180798)
		(width 0.1651)
		(layer "In7.Cu")
		(net "P5E_PEX1_STN5_TX_C_DN<87>")
	)
	(segment
		(start 141.969998 -354.092002)
		(end 143.524478 -352.537522)
		(width 0.1651)
		(layer "In7.Cu")
		(net "P5E_PEX1_STN5_TX_C_DN<87>")
	)
	(segment
		(start 138.850116 -392.1125)
		(end 140.387324 -390.971786)
		(width 0.1651)
		(layer "In7.Cu")
		(net "P5E_PEX1_STN5_TX_C_DN<87>")
	)
	(segment
		(start 143.524478 -352.537522)
		(end 143.524478 -351.902268)
		(width 0.1651)
		(layer "In7.Cu")
		(net "P5E_PEX1_STN5_TX_C_DN<87>")
	)
	(segment
		(start 140.387324 -390.971786)
		(end 140.956538 -390.454388)
		(width 0.1651)
		(layer "In7.Cu")
		(net "P5E_PEX1_STN5_TX_C_DN<87>")
	)
	(segment
		(start 38.693852 -103.483156)
		(end 38.062408 -103.483156)
		(width 0.13462)
		(layer "F.Cu")
		(net "P5E_PEX0_STN1_TX_DN<18>")
	)
	(segment
		(start 38.062408 -103.483156)
		(end 37.767768 -103.777796)
		(width 0.13462)
		(layer "F.Cu")
		(net "P5E_PEX0_STN1_TX_DN<18>")
	)
	(segment
		(start 39.013892 -103.803196)
		(end 38.693852 -103.483156)
		(width 0.13462)
		(layer "F.Cu")
		(net "P5E_PEX0_STN1_TX_DN<18>")
	)
	(segment
		(start 32.03829 -105.995724)
		(end 32.199834 -105.995724)
		(width 0.1651)
		(layer "In9.Cu")
		(net "P5E_PEX0_STN1_TX_DN<18>")
	)
	(segment
		(start 32.541464 -105.654094)
		(end 32.541464 -105.49255)
		(width 0.1651)
		(layer "In9.Cu")
		(net "P5E_PEX0_STN1_TX_DN<18>")
	)
	(segment
		(start 24.995886 -144.84985)
		(end 22.422612 -138.637518)
		(width 0.1651)
		(layer "In9.Cu")
		(net "P5E_PEX0_STN1_TX_DN<18>")
	)
	(segment
		(start 61.549534 -278.115268)
		(end 61.435234 -278.229568)
		(width 0.1143)
		(layer "In9.Cu")
		(net "P5E_PEX0_STN1_TX_DN<18>")
	)
	(segment
		(start 28.974034 -111.08436)
		(end 28.912058 -110.935008)
		(width 0.1651)
		(layer "In9.Cu")
		(net "P5E_PEX0_STN1_TX_DN<18>")
	)
	(segment
		(start 31.355538 -106.84002)
		(end 31.697168 -106.49839)
		(width 0.1651)
		(layer "In9.Cu")
		(net "P5E_PEX0_STN1_TX_DN<18>")
	)
	(segment
		(start 29.845254 -108.682028)
		(end 30.193996 -107.840018)
		(width 0.1651)
		(layer "In9.Cu")
		(net "P5E_PEX0_STN1_TX_DN<18>")
	)
	(segment
		(start 61.215778 -271.471898)
		(end 61.215778 -265.511534)
		(width 0.1651)
		(layer "In9.Cu")
		(net "P5E_PEX0_STN1_TX_DN<18>")
	)
	(segment
		(start 31.697168 -106.336846)
		(end 32.03829 -105.995724)
		(width 0.1651)
		(layer "In9.Cu")
		(net "P5E_PEX0_STN1_TX_DN<18>")
	)
	(segment
		(start 29.717746 -109.289088)
		(end 29.90723 -108.83138)
		(width 0.1651)
		(layer "In9.Cu")
		(net "P5E_PEX0_STN1_TX_DN<18>")
	)
	(segment
		(start 61.170058 -278.12619)
		(end 61.170058 -271.546066)
		(width 0.1143)
		(layer "In9.Cu")
		(net "P5E_PEX0_STN1_TX_DN<18>")
	)
	(segment
		(start 34.52241 -103.977694)
		(end 34.671762 -104.039416)
		(width 0.1651)
		(layer "In9.Cu")
		(net "P5E_PEX0_STN1_TX_DN<18>")
	)
	(segment
		(start 61.549534 -277.849838)
		(end 61.549534 -278.115268)
		(width 0.1143)
		(layer "In9.Cu")
		(net "P5E_PEX0_STN1_TX_DN<18>")
	)
	(segment
		(start 33.04413 -105.151428)
		(end 33.38576 -104.809798)
		(width 0.1651)
		(layer "In9.Cu")
		(net "P5E_PEX0_STN1_TX_DN<18>")
	)
	(segment
		(start 36.106354 -103.486966)
		(end 36.220654 -103.601266)
		(width 0.1651)
		(layer "In9.Cu")
		(net "P5E_PEX0_STN1_TX_DN<18>")
	)
	(segment
		(start 33.726882 -104.307132)
		(end 34.52241 -103.977694)
		(width 0.1651)
		(layer "In9.Cu")
		(net "P5E_PEX0_STN1_TX_DN<18>")
	)
	(segment
		(start 36.817554 -103.486966)
		(end 37.476938 -103.486966)
		(width 0.1651)
		(layer "In9.Cu")
		(net "P5E_PEX0_STN1_TX_DN<18>")
	)
	(segment
		(start 61.215778 -271.500346)
		(end 61.215778 -271.471898)
		(width 0.1143)
		(layer "In9.Cu")
		(net "P5E_PEX0_STN1_TX_DN<18>")
	)
	(segment
		(start 32.882586 -105.151428)
		(end 33.04413 -105.151428)
		(width 0.1651)
		(layer "In9.Cu")
		(net "P5E_PEX0_STN1_TX_DN<18>")
	)
	(segment
		(start 22.422612 -130.990848)
		(end 27.397202 -114.592862)
		(width 0.1651)
		(layer "In9.Cu")
		(net "P5E_PEX0_STN1_TX_DN<18>")
	)
	(segment
		(start 27.397202 -114.592862)
		(end 28.634944 -111.604044)
		(width 0.1651)
		(layer "In9.Cu")
		(net "P5E_PEX0_STN1_TX_DN<18>")
	)
	(segment
		(start 36.220654 -103.601266)
		(end 36.703254 -103.601266)
		(width 0.1651)
		(layer "In9.Cu")
		(net "P5E_PEX0_STN1_TX_DN<18>")
	)
	(segment
		(start 61.273436 -278.229568)
		(end 61.170058 -278.12619)
		(width 0.1143)
		(layer "In9.Cu")
		(net "P5E_PEX0_STN1_TX_DN<18>")
	)
	(segment
		(start 35.706812 -103.486966)
		(end 36.106354 -103.486966)
		(width 0.1651)
		(layer "In9.Cu")
		(net "P5E_PEX0_STN1_TX_DN<18>")
	)
	(segment
		(start 28.912058 -110.935008)
		(end 29.101542 -110.477554)
		(width 0.1651)
		(layer "In9.Cu")
		(net "P5E_PEX0_STN1_TX_DN<18>")
	)
	(segment
		(start 61.435234 -278.229568)
		(end 61.273436 -278.229568)
		(width 0.1143)
		(layer "In9.Cu")
		(net "P5E_PEX0_STN1_TX_DN<18>")
	)
	(segment
		(start 25.712674 -159.428434)
		(end 24.995886 -144.84985)
		(width 0.1651)
		(layer "In9.Cu")
		(net "P5E_PEX0_STN1_TX_DN<18>")
	)
	(segment
		(start 29.101542 -110.477554)
		(end 29.251148 -110.415832)
		(width 0.1651)
		(layer "In9.Cu")
		(net "P5E_PEX0_STN1_TX_DN<18>")
	)
	(segment
		(start 61.215778 -265.511534)
		(end 26.288492 -162.323272)
		(width 0.1651)
		(layer "In9.Cu")
		(net "P5E_PEX0_STN1_TX_DN<18>")
	)
	(segment
		(start 31.697168 -106.49839)
		(end 31.697168 -106.336846)
		(width 0.1651)
		(layer "In9.Cu")
		(net "P5E_PEX0_STN1_TX_DN<18>")
	)
	(segment
		(start 35.117786 -103.854758)
		(end 35.179762 -103.705152)
		(width 0.1651)
		(layer "In9.Cu")
		(net "P5E_PEX0_STN1_TX_DN<18>")
	)
	(segment
		(start 29.251148 -110.415832)
		(end 29.440632 -109.95787)
		(width 0.1651)
		(layer "In9.Cu")
		(net "P5E_PEX0_STN1_TX_DN<18>")
	)
	(segment
		(start 33.38576 -104.809798)
		(end 33.38576 -104.648254)
		(width 0.1651)
		(layer "In9.Cu")
		(net "P5E_PEX0_STN1_TX_DN<18>")
	)
	(segment
		(start 29.440632 -109.95787)
		(end 29.378656 -109.808518)
		(width 0.1651)
		(layer "In9.Cu")
		(net "P5E_PEX0_STN1_TX_DN<18>")
	)
	(segment
		(start 29.56814 -109.351064)
		(end 29.717746 -109.289088)
		(width 0.1651)
		(layer "In9.Cu")
		(net "P5E_PEX0_STN1_TX_DN<18>")
	)
	(segment
		(start 34.671762 -104.039416)
		(end 35.117786 -103.854758)
		(width 0.1651)
		(layer "In9.Cu")
		(net "P5E_PEX0_STN1_TX_DN<18>")
	)
	(segment
		(start 26.288492 -162.323272)
		(end 25.712674 -159.428434)
		(width 0.1651)
		(layer "In9.Cu")
		(net "P5E_PEX0_STN1_TX_DN<18>")
	)
	(segment
		(start 35.179762 -103.70566)
		(end 35.706812 -103.486966)
		(width 0.1651)
		(layer "In9.Cu")
		(net "P5E_PEX0_STN1_TX_DN<18>")
	)
	(segment
		(start 31.193994 -106.84002)
		(end 31.355538 -106.84002)
		(width 0.1651)
		(layer "In9.Cu")
		(net "P5E_PEX0_STN1_TX_DN<18>")
	)
	(segment
		(start 36.703254 -103.601266)
		(end 36.817554 -103.486966)
		(width 0.1651)
		(layer "In9.Cu")
		(net "P5E_PEX0_STN1_TX_DN<18>")
	)
	(segment
		(start 29.378656 -109.808518)
		(end 29.56814 -109.351064)
		(width 0.1651)
		(layer "In9.Cu")
		(net "P5E_PEX0_STN1_TX_DN<18>")
	)
	(segment
		(start 28.634944 -111.604044)
		(end 28.78455 -111.542322)
		(width 0.1651)
		(layer "In9.Cu")
		(net "P5E_PEX0_STN1_TX_DN<18>")
	)
	(segment
		(start 32.541464 -105.49255)
		(end 32.882586 -105.151428)
		(width 0.1651)
		(layer "In9.Cu")
		(net "P5E_PEX0_STN1_TX_DN<18>")
	)
	(segment
		(start 30.193996 -107.840018)
		(end 31.193994 -106.84002)
		(width 0.1651)
		(layer "In9.Cu")
		(net "P5E_PEX0_STN1_TX_DN<18>")
	)
	(segment
		(start 32.199834 -105.995724)
		(end 32.541464 -105.654094)
		(width 0.1651)
		(layer "In9.Cu")
		(net "P5E_PEX0_STN1_TX_DN<18>")
	)
	(segment
		(start 37.476938 -103.486966)
		(end 37.767768 -103.777796)
		(width 0.1651)
		(layer "In9.Cu")
		(net "P5E_PEX0_STN1_TX_DN<18>")
	)
	(segment
		(start 28.78455 -111.542322)
		(end 28.974034 -111.08436)
		(width 0.1651)
		(layer "In9.Cu")
		(net "P5E_PEX0_STN1_TX_DN<18>")
	)
	(segment
		(start 29.90723 -108.83138)
		(end 29.845254 -108.682028)
		(width 0.1651)
		(layer "In9.Cu")
		(net "P5E_PEX0_STN1_TX_DN<18>")
	)
	(segment
		(start 22.422612 -138.637518)
		(end 22.422612 -130.990848)
		(width 0.1651)
		(layer "In9.Cu")
		(net "P5E_PEX0_STN1_TX_DN<18>")
	)
	(segment
		(start 61.170058 -271.546066)
		(end 61.215778 -271.500346)
		(width 0.1143)
		(layer "In9.Cu")
		(net "P5E_PEX0_STN1_TX_DN<18>")
	)
	(segment
		(start 35.179762 -103.705152)
		(end 35.179762 -103.70566)
		(width 0.1651)
		(layer "In9.Cu")
		(net "P5E_PEX0_STN1_TX_DN<18>")
	)
	(segment
		(start 33.38576 -104.648254)
		(end 33.726882 -104.307132)
		(width 0.1651)
		(layer "In9.Cu")
		(net "P5E_PEX0_STN1_TX_DN<18>")
	)
	(segment
		(start 170.531282 -340.811866)
		(end 170.531282 -357.921052)
		(width 0.1651)
		(layer "In9.Cu")
		(net "P5E_PEX1_STN7_RX_DN<126>")
	)
	(segment
		(start 174.26686 -369.68303)
		(end 174.26686 -382.289812)
		(width 0.1651)
		(layer "In9.Cu")
		(net "P5E_PEX1_STN7_RX_DN<126>")
	)
	(segment
		(start 157.699964 -316.799722)
		(end 157.700218 -316.799468)
		(width 0.1143)
		(layer "In9.Cu")
		(net "P5E_PEX1_STN7_RX_DN<126>")
	)
	(segment
		(start 170.531282 -357.921052)
		(end 173.792642 -366.968786)
		(width 0.1651)
		(layer "In9.Cu")
		(net "P5E_PEX1_STN7_RX_DN<126>")
	)
	(segment
		(start 157.700218 -316.799468)
		(end 157.700218 -316.508892)
		(width 0.1143)
		(layer "In9.Cu")
		(net "P5E_PEX1_STN7_RX_DN<126>")
	)
	(segment
		(start 157.320488 -316.564772)
		(end 157.320488 -319.81648)
		(width 0.1143)
		(layer "In9.Cu")
		(net "P5E_PEX1_STN7_RX_DN<126>")
	)
	(segment
		(start 157.320488 -319.81648)
		(end 157.366208 -319.8622)
		(width 0.1143)
		(layer "In9.Cu")
		(net "P5E_PEX1_STN7_RX_DN<126>")
	)
	(segment
		(start 173.23689 -382.9812)
		(end 173.10989 -383.1082)
		(width 0.1651)
		(layer "In9.Cu")
		(net "P5E_PEX1_STN7_RX_DN<126>")
	)
	(segment
		(start 157.611318 -316.419992)
		(end 157.465268 -316.419992)
		(width 0.1143)
		(layer "In9.Cu")
		(net "P5E_PEX1_STN7_RX_DN<126>")
	)
	(segment
		(start 157.465268 -316.419992)
		(end 157.320488 -316.564772)
		(width 0.1143)
		(layer "In9.Cu")
		(net "P5E_PEX1_STN7_RX_DN<126>")
	)
	(segment
		(start 173.792642 -366.968786)
		(end 174.26686 -369.68303)
		(width 0.1651)
		(layer "In9.Cu")
		(net "P5E_PEX1_STN7_RX_DN<126>")
	)
	(segment
		(start 173.10989 -383.1082)
		(end 173.10989 -383.490216)
		(width 0.1651)
		(layer "In9.Cu")
		(net "P5E_PEX1_STN7_RX_DN<126>")
	)
	(segment
		(start 157.366208 -320.783712)
		(end 157.741366 -322.002658)
		(width 0.1651)
		(layer "In9.Cu")
		(net "P5E_PEX1_STN7_RX_DN<126>")
	)
	(segment
		(start 157.366208 -319.890648)
		(end 157.366208 -320.783712)
		(width 0.1651)
		(layer "In9.Cu")
		(net "P5E_PEX1_STN7_RX_DN<126>")
	)
	(segment
		(start 157.700218 -316.508892)
		(end 157.611318 -316.419992)
		(width 0.1143)
		(layer "In9.Cu")
		(net "P5E_PEX1_STN7_RX_DN<126>")
	)
	(segment
		(start 157.741366 -322.002658)
		(end 170.531282 -340.811866)
		(width 0.1651)
		(layer "In9.Cu")
		(net "P5E_PEX1_STN7_RX_DN<126>")
	)
	(segment
		(start 157.366208 -319.8622)
		(end 157.366208 -319.890648)
		(width 0.1143)
		(layer "In9.Cu")
		(net "P5E_PEX1_STN7_RX_DN<126>")
	)
	(segment
		(start 174.26686 -382.289812)
		(end 173.575472 -382.9812)
		(width 0.1651)
		(layer "In9.Cu")
		(net "P5E_PEX1_STN7_RX_DN<126>")
	)
	(segment
		(start 173.575472 -382.9812)
		(end 173.23689 -382.9812)
		(width 0.1651)
		(layer "In9.Cu")
		(net "P5E_PEX1_STN7_RX_DN<126>")
	)
	(segment
		(start 171.807632 -351.316798)
		(end 171.807632 -350.685354)
		(width 0.13462)
		(layer "F.Cu")
		(net "P5E_PEX1_STN7_TX_C_DP<117>")
	)
	(segment
		(start 171.807632 -350.685354)
		(end 171.487592 -350.365314)
		(width 0.13462)
		(layer "F.Cu")
		(net "P5E_PEX1_STN7_TX_C_DP<117>")
	)
	(segment
		(start 171.512992 -351.611438)
		(end 171.807632 -351.316798)
		(width 0.13462)
		(layer "F.Cu")
		(net "P5E_PEX1_STN7_TX_C_DP<117>")
	)
	(segment
		(start 171.793154 -401.858734)
		(end 171.652692 -401.999196)
		(width 0.1651)
		(layer "In11.Cu")
		(net "P5E_PEX1_STN7_TX_C_DP<117>")
	)
	(segment
		(start 159.296354 -364.76178)
		(end 157.374082 -366.734598)
		(width 0.1651)
		(layer "In11.Cu")
		(net "P5E_PEX1_STN7_TX_C_DP<117>")
	)
	(segment
		(start 168.897808 -392.899646)
		(end 169.319448 -393.159234)
		(width 0.1651)
		(layer "In11.Cu")
		(net "P5E_PEX1_STN7_TX_C_DP<117>")
	)
	(segment
		(start 171.512992 -351.611438)
		(end 171.803822 -351.902268)
		(width 0.1651)
		(layer "In11.Cu")
		(net "P5E_PEX1_STN7_TX_C_DP<117>")
	)
	(segment
		(start 170.335956 -393.785598)
		(end 170.946064 -394.395706)
		(width 0.1651)
		(layer "In11.Cu")
		(net "P5E_PEX1_STN7_TX_C_DP<117>")
	)
	(segment
		(start 156.706316 -384.836924)
		(end 157.53969 -386.899658)
		(width 0.1651)
		(layer "In11.Cu")
		(net "P5E_PEX1_STN7_TX_C_DP<117>")
	)
	(segment
		(start 171.793154 -395.242796)
		(end 171.793154 -401.858734)
		(width 0.1651)
		(layer "In11.Cu")
		(net "P5E_PEX1_STN7_TX_C_DP<117>")
	)
	(segment
		(start 171.296584 -394.889736)
		(end 171.440094 -394.889736)
		(width 0.1651)
		(layer "In11.Cu")
		(net "P5E_PEX1_STN7_TX_C_DP<117>")
	)
	(segment
		(start 157.374082 -366.734598)
		(end 156.666438 -368.606324)
		(width 0.1651)
		(layer "In11.Cu")
		(net "P5E_PEX1_STN7_TX_C_DP<117>")
	)
	(segment
		(start 171.440094 -394.889736)
		(end 171.793154 -395.242796)
		(width 0.1651)
		(layer "In11.Cu")
		(net "P5E_PEX1_STN7_TX_C_DP<117>")
	)
	(segment
		(start 157.53969 -386.899658)
		(end 160.08858 -388.790942)
		(width 0.1651)
		(layer "In11.Cu")
		(net "P5E_PEX1_STN7_TX_C_DP<117>")
	)
	(segment
		(start 169.352722 -393.298934)
		(end 169.774616 -393.55903)
		(width 0.1651)
		(layer "In11.Cu")
		(net "P5E_PEX1_STN7_TX_C_DP<117>")
	)
	(segment
		(start 166.303198 -391.420096)
		(end 166.725092 -391.680192)
		(width 0.1651)
		(layer "In11.Cu")
		(net "P5E_PEX1_STN7_TX_C_DP<117>")
	)
	(segment
		(start 160.08858 -388.790942)
		(end 163.668964 -389.973312)
		(width 0.1651)
		(layer "In11.Cu")
		(net "P5E_PEX1_STN7_TX_C_DP<117>")
	)
	(segment
		(start 167.319706 -392.04646)
		(end 167.7416 -392.306302)
		(width 0.1651)
		(layer "In11.Cu")
		(net "P5E_PEX1_STN7_TX_C_DP<117>")
	)
	(segment
		(start 165.630098 -390.886188)
		(end 166.269924 -391.280142)
		(width 0.1651)
		(layer "In11.Cu")
		(net "P5E_PEX1_STN7_TX_C_DP<117>")
	)
	(segment
		(start 168.208198 -361.021122)
		(end 159.296354 -364.76178)
		(width 0.1651)
		(layer "In11.Cu")
		(net "P5E_PEX1_STN7_TX_C_DP<117>")
	)
	(segment
		(start 169.774616 -393.55903)
		(end 169.914316 -393.52601)
		(width 0.1651)
		(layer "In11.Cu")
		(net "P5E_PEX1_STN7_TX_C_DP<117>")
	)
	(segment
		(start 170.946064 -394.395706)
		(end 170.946064 -394.539216)
		(width 0.1651)
		(layer "In11.Cu")
		(net "P5E_PEX1_STN7_TX_C_DP<117>")
	)
	(segment
		(start 166.725092 -391.680192)
		(end 166.864792 -391.646918)
		(width 0.1651)
		(layer "In11.Cu")
		(net "P5E_PEX1_STN7_TX_C_DP<117>")
	)
	(segment
		(start 166.269924 -391.280142)
		(end 166.303198 -391.420096)
		(width 0.1651)
		(layer "In11.Cu")
		(net "P5E_PEX1_STN7_TX_C_DP<117>")
	)
	(segment
		(start 168.336214 -392.672824)
		(end 168.758108 -392.932666)
		(width 0.1651)
		(layer "In11.Cu")
		(net "P5E_PEX1_STN7_TX_C_DP<117>")
	)
	(segment
		(start 166.864792 -391.646918)
		(end 167.286432 -391.906506)
		(width 0.1651)
		(layer "In11.Cu")
		(net "P5E_PEX1_STN7_TX_C_DP<117>")
	)
	(segment
		(start 170.249342 -358.979978)
		(end 168.208198 -361.021122)
		(width 0.1651)
		(layer "In11.Cu")
		(net "P5E_PEX1_STN7_TX_C_DP<117>")
	)
	(segment
		(start 171.036996 -401.999196)
		(end 170.909996 -401.872196)
		(width 0.1651)
		(layer "In11.Cu")
		(net "P5E_PEX1_STN7_TX_C_DP<117>")
	)
	(segment
		(start 169.914316 -393.52601)
		(end 170.335956 -393.785598)
		(width 0.1651)
		(layer "In11.Cu")
		(net "P5E_PEX1_STN7_TX_C_DP<117>")
	)
	(segment
		(start 167.7416 -392.306302)
		(end 167.8813 -392.273282)
		(width 0.1651)
		(layer "In11.Cu")
		(net "P5E_PEX1_STN7_TX_C_DP<117>")
	)
	(segment
		(start 171.803822 -352.547936)
		(end 170.249342 -354.102416)
		(width 0.1651)
		(layer "In11.Cu")
		(net "P5E_PEX1_STN7_TX_C_DP<117>")
	)
	(segment
		(start 169.319448 -393.159234)
		(end 169.352722 -393.298934)
		(width 0.1651)
		(layer "In11.Cu")
		(net "P5E_PEX1_STN7_TX_C_DP<117>")
	)
	(segment
		(start 171.803822 -351.902268)
		(end 171.803822 -352.547936)
		(width 0.1651)
		(layer "In11.Cu")
		(net "P5E_PEX1_STN7_TX_C_DP<117>")
	)
	(segment
		(start 170.909996 -401.872196)
		(end 170.909996 -401.49018)
		(width 0.1651)
		(layer "In11.Cu")
		(net "P5E_PEX1_STN7_TX_C_DP<117>")
	)
	(segment
		(start 170.946064 -394.539216)
		(end 171.296584 -394.889736)
		(width 0.1651)
		(layer "In11.Cu")
		(net "P5E_PEX1_STN7_TX_C_DP<117>")
	)
	(segment
		(start 167.8813 -392.273282)
		(end 168.30294 -392.53287)
		(width 0.1651)
		(layer "In11.Cu")
		(net "P5E_PEX1_STN7_TX_C_DP<117>")
	)
	(segment
		(start 167.286432 -391.906506)
		(end 167.319706 -392.04646)
		(width 0.1651)
		(layer "In11.Cu")
		(net "P5E_PEX1_STN7_TX_C_DP<117>")
	)
	(segment
		(start 156.666438 -368.606324)
		(end 156.497782 -382.42621)
		(width 0.1651)
		(layer "In11.Cu")
		(net "P5E_PEX1_STN7_TX_C_DP<117>")
	)
	(segment
		(start 156.497782 -382.42621)
		(end 156.706316 -384.836924)
		(width 0.1651)
		(layer "In11.Cu")
		(net "P5E_PEX1_STN7_TX_C_DP<117>")
	)
	(segment
		(start 168.30294 -392.53287)
		(end 168.336214 -392.672824)
		(width 0.1651)
		(layer "In11.Cu")
		(net "P5E_PEX1_STN7_TX_C_DP<117>")
	)
	(segment
		(start 168.758108 -392.932666)
		(end 168.897808 -392.899646)
		(width 0.1651)
		(layer "In11.Cu")
		(net "P5E_PEX1_STN7_TX_C_DP<117>")
	)
	(segment
		(start 170.249342 -354.102416)
		(end 170.249342 -358.979978)
		(width 0.1651)
		(layer "In11.Cu")
		(net "P5E_PEX1_STN7_TX_C_DP<117>")
	)
	(segment
		(start 171.652692 -401.999196)
		(end 171.036996 -401.999196)
		(width 0.1651)
		(layer "In11.Cu")
		(net "P5E_PEX1_STN7_TX_C_DP<117>")
	)
	(segment
		(start 163.668964 -389.973312)
		(end 165.630098 -390.886188)
		(width 0.1651)
		(layer "In11.Cu")
		(net "P5E_PEX1_STN7_TX_C_DP<117>")
	)
	(segment
		(start 83.87969 -155.791154)
		(end 84.17433 -156.085794)
		(width 0.13462)
		(layer "F.Cu")
		(net "P5E_PEX0_STN0_TX_DP<15>")
	)
	(segment
		(start 82.928206 -156.111194)
		(end 83.248246 -155.791154)
		(width 0.13462)
		(layer "F.Cu")
		(net "P5E_PEX0_STN0_TX_DP<15>")
	)
	(segment
		(start 83.248246 -155.791154)
		(end 83.87969 -155.791154)
		(width 0.13462)
		(layer "F.Cu")
		(net "P5E_PEX0_STN0_TX_DP<15>")
	)
	(segment
		(start 72.463914 -230.515922)
		(end 75.108308 -260.7437)
		(width 0.1651)
		(layer "In9.Cu")
		(net "P5E_PEX0_STN0_TX_DP<15>")
	)
	(segment
		(start 74.849736 -278.534368)
		(end 74.849736 -278.799798)
		(width 0.1143)
		(layer "In9.Cu")
		(net "P5E_PEX0_STN0_TX_DP<15>")
	)
	(segment
		(start 83.946746 -158.791656)
		(end 83.979512 -158.913068)
		(width 0.1651)
		(layer "In9.Cu")
		(net "P5E_PEX0_STN0_TX_DP<15>")
	)
	(segment
		(start 85.375242 -156.49575)
		(end 84.900516 -157.317948)
		(width 0.1651)
		(layer "In9.Cu")
		(net "P5E_PEX0_STN0_TX_DP<15>")
	)
	(segment
		(start 84.900516 -157.317948)
		(end 84.779104 -157.350714)
		(width 0.1651)
		(layer "In9.Cu")
		(net "P5E_PEX0_STN0_TX_DP<15>")
	)
	(segment
		(start 74.27976 -271.546066)
		(end 74.27976 -278.205184)
		(width 0.1143)
		(layer "In9.Cu")
		(net "P5E_PEX0_STN0_TX_DP<15>")
	)
	(segment
		(start 84.563712 -157.901132)
		(end 84.316316 -158.329884)
		(width 0.1651)
		(layer "In9.Cu")
		(net "P5E_PEX0_STN0_TX_DP<15>")
	)
	(segment
		(start 75.393042 -176.821846)
		(end 75.390756 -176.846738)
		(width 0.1651)
		(layer "In9.Cu")
		(net "P5E_PEX0_STN0_TX_DP<15>")
	)
	(segment
		(start 84.19465 -158.362396)
		(end 83.946746 -158.791656)
		(width 0.1651)
		(layer "In9.Cu")
		(net "P5E_PEX0_STN0_TX_DP<15>")
	)
	(segment
		(start 84.779104 -157.350714)
		(end 84.5312 -157.77972)
		(width 0.1651)
		(layer "In9.Cu")
		(net "P5E_PEX0_STN0_TX_DP<15>")
	)
	(segment
		(start 84.316316 -158.329884)
		(end 84.19465 -158.362396)
		(width 0.1651)
		(layer "In9.Cu")
		(net "P5E_PEX0_STN0_TX_DP<15>")
	)
	(segment
		(start 84.17433 -156.085794)
		(end 84.46516 -155.794964)
		(width 0.1651)
		(layer "In9.Cu")
		(net "P5E_PEX0_STN0_TX_DP<15>")
	)
	(segment
		(start 71.57974 -220.410278)
		(end 72.463914 -230.515922)
		(width 0.1651)
		(layer "In9.Cu")
		(net "P5E_PEX0_STN0_TX_DP<15>")
	)
	(segment
		(start 74.27976 -278.205184)
		(end 74.494644 -278.420068)
		(width 0.1143)
		(layer "In9.Cu")
		(net "P5E_PEX0_STN0_TX_DP<15>")
	)
	(segment
		(start 75.108308 -260.7437)
		(end 75.108308 -267.41755)
		(width 0.1651)
		(layer "In9.Cu")
		(net "P5E_PEX0_STN0_TX_DP<15>")
	)
	(segment
		(start 74.23404 -269.528798)
		(end 74.23404 -271.471898)
		(width 0.1651)
		(layer "In9.Cu")
		(net "P5E_PEX0_STN0_TX_DP<15>")
	)
	(segment
		(start 74.23404 -271.471898)
		(end 74.23404 -271.500346)
		(width 0.1143)
		(layer "In9.Cu")
		(net "P5E_PEX0_STN0_TX_DP<15>")
	)
	(segment
		(start 74.735436 -278.420068)
		(end 74.849736 -278.534368)
		(width 0.1143)
		(layer "In9.Cu")
		(net "P5E_PEX0_STN0_TX_DP<15>")
	)
	(segment
		(start 84.46516 -155.794964)
		(end 85.073998 -155.794964)
		(width 0.1651)
		(layer "In9.Cu")
		(net "P5E_PEX0_STN0_TX_DP<15>")
	)
	(segment
		(start 84.5312 -157.77972)
		(end 84.563712 -157.901132)
		(width 0.1651)
		(layer "In9.Cu")
		(net "P5E_PEX0_STN0_TX_DP<15>")
	)
	(segment
		(start 75.108308 -267.41755)
		(end 74.23404 -269.528798)
		(width 0.1651)
		(layer "In9.Cu")
		(net "P5E_PEX0_STN0_TX_DP<15>")
	)
	(segment
		(start 75.390756 -176.846738)
		(end 75.39101 -176.846738)
		(width 0.1651)
		(layer "In9.Cu")
		(net "P5E_PEX0_STN0_TX_DP<15>")
	)
	(segment
		(start 85.073998 -155.794964)
		(end 85.375242 -156.096208)
		(width 0.1651)
		(layer "In9.Cu")
		(net "P5E_PEX0_STN0_TX_DP<15>")
	)
	(segment
		(start 74.23404 -271.500346)
		(end 74.27976 -271.546066)
		(width 0.1143)
		(layer "In9.Cu")
		(net "P5E_PEX0_STN0_TX_DP<15>")
	)
	(segment
		(start 85.375242 -156.096208)
		(end 85.375242 -156.49575)
		(width 0.1651)
		(layer "In9.Cu")
		(net "P5E_PEX0_STN0_TX_DP<15>")
	)
	(segment
		(start 76.911454 -171.156122)
		(end 75.393042 -176.821846)
		(width 0.1651)
		(layer "In9.Cu")
		(net "P5E_PEX0_STN0_TX_DP<15>")
	)
	(segment
		(start 75.39101 -176.846738)
		(end 71.57974 -220.410278)
		(width 0.1651)
		(layer "In9.Cu")
		(net "P5E_PEX0_STN0_TX_DP<15>")
	)
	(segment
		(start 74.494644 -278.420068)
		(end 74.735436 -278.420068)
		(width 0.1143)
		(layer "In9.Cu")
		(net "P5E_PEX0_STN0_TX_DP<15>")
	)
	(segment
		(start 83.979512 -158.913068)
		(end 76.911454 -171.156122)
		(width 0.1651)
		(layer "In9.Cu")
		(net "P5E_PEX0_STN0_TX_DP<15>")
	)
	(segment
		(start 135.946642 -341.741506)
		(end 135.752078 -342.030304)
		(width 0.1651)
		(layer "In15.Cu")
		(net "P5E_PEX1_STN5_RX_DN<89>")
	)
	(segment
		(start 183.3499 -318.699896)
		(end 183.3499 -318.409066)
		(width 0.1143)
		(layer "In15.Cu")
		(net "P5E_PEX1_STN5_RX_DN<89>")
	)
	(segment
		(start 135.752078 -358.058466)
		(end 135.212074 -358.958642)
		(width 0.1651)
		(layer "In15.Cu")
		(net "P5E_PEX1_STN5_RX_DN<89>")
	)
	(segment
		(start 182.97017 -318.485266)
		(end 182.97017 -319.99428)
		(width 0.1143)
		(layer "In15.Cu")
		(net "P5E_PEX1_STN5_RX_DN<89>")
	)
	(segment
		(start 118.11 -372.508018)
		(end 118.11 -372.890034)
		(width 0.1651)
		(layer "In15.Cu")
		(net "P5E_PEX1_STN5_RX_DN<89>")
	)
	(segment
		(start 183.261 -318.320166)
		(end 183.13527 -318.320166)
		(width 0.1143)
		(layer "In15.Cu")
		(net "P5E_PEX1_STN5_RX_DN<89>")
	)
	(segment
		(start 127.93345 -362.83773)
		(end 119.566944 -368.48923)
		(width 0.1651)
		(layer "In15.Cu")
		(net "P5E_PEX1_STN5_RX_DN<89>")
	)
	(segment
		(start 119.299736 -368.992404)
		(end 119.299736 -371.65661)
		(width 0.1651)
		(layer "In15.Cu")
		(net "P5E_PEX1_STN5_RX_DN<89>")
	)
	(segment
		(start 177.809398 -324.24243)
		(end 137.99947 -340.357206)
		(width 0.1651)
		(layer "In15.Cu")
		(net "P5E_PEX1_STN5_RX_DN<89>")
	)
	(segment
		(start 136.141206 -341.452962)
		(end 135.946896 -341.741252)
		(width 0.1651)
		(layer "In15.Cu")
		(net "P5E_PEX1_STN5_RX_DN<89>")
	)
	(segment
		(start 137.99947 -340.357206)
		(end 136.141206 -341.452962)
		(width 0.1651)
		(layer "In15.Cu")
		(net "P5E_PEX1_STN5_RX_DN<89>")
	)
	(segment
		(start 118.575328 -372.381018)
		(end 118.237 -372.381018)
		(width 0.1651)
		(layer "In15.Cu")
		(net "P5E_PEX1_STN5_RX_DN<89>")
	)
	(segment
		(start 119.566944 -368.48923)
		(end 119.299736 -368.992404)
		(width 0.1651)
		(layer "In15.Cu")
		(net "P5E_PEX1_STN5_RX_DN<89>")
	)
	(segment
		(start 135.946896 -341.741252)
		(end 135.946642 -341.741506)
		(width 0.1651)
		(layer "In15.Cu")
		(net "P5E_PEX1_STN5_RX_DN<89>")
	)
	(segment
		(start 183.3499 -318.409066)
		(end 183.261 -318.320166)
		(width 0.1143)
		(layer "In15.Cu")
		(net "P5E_PEX1_STN5_RX_DN<89>")
	)
	(segment
		(start 135.212074 -358.958642)
		(end 127.93345 -362.83773)
		(width 0.1651)
		(layer "In15.Cu")
		(net "P5E_PEX1_STN5_RX_DN<89>")
	)
	(segment
		(start 118.237 -372.381018)
		(end 118.11 -372.508018)
		(width 0.1651)
		(layer "In15.Cu")
		(net "P5E_PEX1_STN5_RX_DN<89>")
	)
	(segment
		(start 182.97017 -319.99428)
		(end 183.01589 -320.04)
		(width 0.1143)
		(layer "In15.Cu")
		(net "P5E_PEX1_STN5_RX_DN<89>")
	)
	(segment
		(start 183.01589 -320.068448)
		(end 183.01589 -320.287904)
		(width 0.1651)
		(layer "In15.Cu")
		(net "P5E_PEX1_STN5_RX_DN<89>")
	)
	(segment
		(start 135.752078 -342.030304)
		(end 135.752078 -358.058466)
		(width 0.1651)
		(layer "In15.Cu")
		(net "P5E_PEX1_STN5_RX_DN<89>")
	)
	(segment
		(start 183.01589 -320.04)
		(end 183.01589 -320.068448)
		(width 0.1143)
		(layer "In15.Cu")
		(net "P5E_PEX1_STN5_RX_DN<89>")
	)
	(segment
		(start 183.13527 -318.320166)
		(end 182.97017 -318.485266)
		(width 0.1143)
		(layer "In15.Cu")
		(net "P5E_PEX1_STN5_RX_DN<89>")
	)
	(segment
		(start 183.01589 -320.287904)
		(end 181.52999 -321.773804)
		(width 0.1651)
		(layer "In15.Cu")
		(net "P5E_PEX1_STN5_RX_DN<89>")
	)
	(segment
		(start 181.52999 -321.773804)
		(end 177.809398 -324.24243)
		(width 0.1651)
		(layer "In15.Cu")
		(net "P5E_PEX1_STN5_RX_DN<89>")
	)
	(segment
		(start 119.299736 -371.65661)
		(end 118.575328 -372.381018)
		(width 0.1651)
		(layer "In15.Cu")
		(net "P5E_PEX1_STN5_RX_DN<89>")
	)
	(segment
		(start 137.028428 -350.685354)
		(end 136.708388 -350.365314)
		(width 0.13462)
		(layer "F.Cu")
		(net "P5E_PEX1_STN5_TX_C_DP<84>")
	)
	(segment
		(start 136.733788 -351.611438)
		(end 137.028428 -351.316798)
		(width 0.13462)
		(layer "F.Cu")
		(net "P5E_PEX1_STN5_TX_C_DP<84>")
	)
	(segment
		(start 137.028428 -351.316798)
		(end 137.028428 -350.685354)
		(width 0.13462)
		(layer "F.Cu")
		(net "P5E_PEX1_STN5_TX_C_DP<84>")
	)
	(segment
		(start 125.487684 -395.771116)
		(end 125.487684 -404.380446)
		(width 0.1651)
		(layer "In7.Cu")
		(net "P5E_PEX1_STN5_TX_C_DP<84>")
	)
	(segment
		(start 136.843008 -389.478012)
		(end 128.093724 -393.165076)
		(width 0.1651)
		(layer "In7.Cu")
		(net "P5E_PEX1_STN5_TX_C_DP<84>")
	)
	(segment
		(start 138.855196 -388.03707)
		(end 137.758678 -388.94893)
		(width 0.1651)
		(layer "In7.Cu")
		(net "P5E_PEX1_STN5_TX_C_DP<84>")
	)
	(segment
		(start 137.024618 -352.420682)
		(end 135.470138 -353.975162)
		(width 0.1651)
		(layer "In7.Cu")
		(net "P5E_PEX1_STN5_TX_C_DP<84>")
	)
	(segment
		(start 139.52474 -386.400802)
		(end 139.267438 -387.251448)
		(width 0.1651)
		(layer "In7.Cu")
		(net "P5E_PEX1_STN5_TX_C_DP<84>")
	)
	(segment
		(start 125.069346 -404.798784)
		(end 124.83719 -404.798784)
		(width 0.1651)
		(layer "In7.Cu")
		(net "P5E_PEX1_STN5_TX_C_DP<84>")
	)
	(segment
		(start 138.148822 -365.068104)
		(end 138.24839 -365.109506)
		(width 0.1651)
		(layer "In7.Cu")
		(net "P5E_PEX1_STN5_TX_C_DP<84>")
	)
	(segment
		(start 137.0838 -362.498132)
		(end 137.273538 -362.956094)
		(width 0.1651)
		(layer "In7.Cu")
		(net "P5E_PEX1_STN5_TX_C_DP<84>")
	)
	(segment
		(start 137.521442 -363.554264)
		(end 137.71118 -364.012226)
		(width 0.1651)
		(layer "In7.Cu")
		(net "P5E_PEX1_STN5_TX_C_DP<84>")
	)
	(segment
		(start 137.758678 -388.94893)
		(end 136.843008 -389.478012)
		(width 0.1651)
		(layer "In7.Cu")
		(net "P5E_PEX1_STN5_TX_C_DP<84>")
	)
	(segment
		(start 140.106908 -369.805204)
		(end 139.7762 -383.21996)
		(width 0.1651)
		(layer "In7.Cu")
		(net "P5E_PEX1_STN5_TX_C_DP<84>")
	)
	(segment
		(start 137.810748 -364.053374)
		(end 138.000232 -364.510828)
		(width 0.1651)
		(layer "In7.Cu")
		(net "P5E_PEX1_STN5_TX_C_DP<84>")
	)
	(segment
		(start 125.487684 -404.380446)
		(end 125.069346 -404.798784)
		(width 0.1651)
		(layer "In7.Cu")
		(net "P5E_PEX1_STN5_TX_C_DP<84>")
	)
	(segment
		(start 136.733788 -351.611438)
		(end 137.024618 -351.902268)
		(width 0.1651)
		(layer "In7.Cu")
		(net "P5E_PEX1_STN5_TX_C_DP<84>")
	)
	(segment
		(start 137.373106 -362.997242)
		(end 137.56259 -363.454696)
		(width 0.1651)
		(layer "In7.Cu")
		(net "P5E_PEX1_STN5_TX_C_DP<84>")
	)
	(segment
		(start 137.273538 -362.956094)
		(end 137.373106 -362.997242)
		(width 0.1651)
		(layer "In7.Cu")
		(net "P5E_PEX1_STN5_TX_C_DP<84>")
	)
	(segment
		(start 135.470138 -358.402636)
		(end 137.125202 -362.398564)
		(width 0.1651)
		(layer "In7.Cu")
		(net "P5E_PEX1_STN5_TX_C_DP<84>")
	)
	(segment
		(start 137.125202 -362.398564)
		(end 137.0838 -362.498132)
		(width 0.1651)
		(layer "In7.Cu")
		(net "P5E_PEX1_STN5_TX_C_DP<84>")
	)
	(segment
		(start 135.470138 -353.975162)
		(end 135.470138 -358.402636)
		(width 0.1651)
		(layer "In7.Cu")
		(net "P5E_PEX1_STN5_TX_C_DP<84>")
	)
	(segment
		(start 139.267438 -387.251448)
		(end 138.855196 -388.03707)
		(width 0.1651)
		(layer "In7.Cu")
		(net "P5E_PEX1_STN5_TX_C_DP<84>")
	)
	(segment
		(start 124.71019 -404.671784)
		(end 124.71019 -404.290022)
		(width 0.1651)
		(layer "In7.Cu")
		(net "P5E_PEX1_STN5_TX_C_DP<84>")
	)
	(segment
		(start 137.024618 -351.902268)
		(end 137.024618 -352.420682)
		(width 0.1651)
		(layer "In7.Cu")
		(net "P5E_PEX1_STN5_TX_C_DP<84>")
	)
	(segment
		(start 124.83719 -404.798784)
		(end 124.71019 -404.671784)
		(width 0.1651)
		(layer "In7.Cu")
		(net "P5E_PEX1_STN5_TX_C_DP<84>")
	)
	(segment
		(start 137.56259 -363.454696)
		(end 137.521442 -363.554264)
		(width 0.1651)
		(layer "In7.Cu")
		(net "P5E_PEX1_STN5_TX_C_DP<84>")
	)
	(segment
		(start 139.7762 -383.874772)
		(end 139.52474 -386.400802)
		(width 0.1651)
		(layer "In7.Cu")
		(net "P5E_PEX1_STN5_TX_C_DP<84>")
	)
	(segment
		(start 138.000232 -364.510828)
		(end 137.959084 -364.610396)
		(width 0.1651)
		(layer "In7.Cu")
		(net "P5E_PEX1_STN5_TX_C_DP<84>")
	)
	(segment
		(start 140.106908 -369.596416)
		(end 140.106908 -369.805204)
		(width 0.1651)
		(layer "In7.Cu")
		(net "P5E_PEX1_STN5_TX_C_DP<84>")
	)
	(segment
		(start 138.24839 -365.109506)
		(end 140.106908 -369.596416)
		(width 0.1651)
		(layer "In7.Cu")
		(net "P5E_PEX1_STN5_TX_C_DP<84>")
	)
	(segment
		(start 128.093724 -393.165076)
		(end 125.487684 -395.771116)
		(width 0.1651)
		(layer "In7.Cu")
		(net "P5E_PEX1_STN5_TX_C_DP<84>")
	)
	(segment
		(start 139.7762 -383.21996)
		(end 139.7762 -383.874772)
		(width 0.1651)
		(layer "In7.Cu")
		(net "P5E_PEX1_STN5_TX_C_DP<84>")
	)
	(segment
		(start 137.71118 -364.012226)
		(end 137.810748 -364.053374)
		(width 0.1651)
		(layer "In7.Cu")
		(net "P5E_PEX1_STN5_TX_C_DP<84>")
	)
	(segment
		(start 137.959084 -364.610396)
		(end 138.148822 -365.068104)
		(width 0.1651)
		(layer "In7.Cu")
		(net "P5E_PEX1_STN5_TX_C_DP<84>")
	)
	(segment
		(start 35.4203 -123.11888)
		(end 35.12566 -122.82424)
		(width 0.13462)
		(layer "F.Cu")
		(net "P5E_PEX0_STN1_TX_DP<26>")
	)
	(segment
		(start 36.051744 -123.11888)
		(end 35.4203 -123.11888)
		(width 0.13462)
		(layer "F.Cu")
		(net "P5E_PEX0_STN1_TX_DP<26>")
	)
	(segment
		(start 36.371784 -122.79884)
		(end 36.051744 -123.11888)
		(width 0.13462)
		(layer "F.Cu")
		(net "P5E_PEX0_STN1_TX_DP<26>")
	)
	(segment
		(start 34.08172 -123.11507)
		(end 33.71977 -123.47702)
		(width 0.1651)
		(layer "In9.Cu")
		(net "P5E_PEX0_STN1_TX_DP<26>")
	)
	(segment
		(start 68.579746 -271.546066)
		(end 68.579746 -278.205184)
		(width 0.1143)
		(layer "In9.Cu")
		(net "P5E_PEX0_STN1_TX_DP<26>")
	)
	(segment
		(start 33.1851 -158.085282)
		(end 33.833562 -161.345626)
		(width 0.1651)
		(layer "In9.Cu")
		(net "P5E_PEX0_STN1_TX_DP<26>")
	)
	(segment
		(start 68.79463 -278.420068)
		(end 69.035422 -278.420068)
		(width 0.1143)
		(layer "In9.Cu")
		(net "P5E_PEX0_STN1_TX_DP<26>")
	)
	(segment
		(start 69.149722 -278.534368)
		(end 69.149722 -278.799798)
		(width 0.1143)
		(layer "In9.Cu")
		(net "P5E_PEX0_STN1_TX_DP<26>")
	)
	(segment
		(start 32.453834 -143.224758)
		(end 33.1851 -158.085282)
		(width 0.1651)
		(layer "In9.Cu")
		(net "P5E_PEX0_STN1_TX_DP<26>")
	)
	(segment
		(start 29.882592 -132.741162)
		(end 29.882592 -137.017252)
		(width 0.1651)
		(layer "In9.Cu")
		(net "P5E_PEX0_STN1_TX_DP<26>")
	)
	(segment
		(start 68.534026 -271.500346)
		(end 68.579746 -271.546066)
		(width 0.1143)
		(layer "In9.Cu")
		(net "P5E_PEX0_STN1_TX_DP<26>")
	)
	(segment
		(start 33.833562 -161.345626)
		(end 68.534026 -263.855962)
		(width 0.1651)
		(layer "In9.Cu")
		(net "P5E_PEX0_STN1_TX_DP<26>")
	)
	(segment
		(start 33.71977 -123.47702)
		(end 29.882592 -132.741162)
		(width 0.1651)
		(layer "In9.Cu")
		(net "P5E_PEX0_STN1_TX_DP<26>")
	)
	(segment
		(start 34.83483 -123.11507)
		(end 34.08172 -123.11507)
		(width 0.1651)
		(layer "In9.Cu")
		(net "P5E_PEX0_STN1_TX_DP<26>")
	)
	(segment
		(start 69.035422 -278.420068)
		(end 69.149722 -278.534368)
		(width 0.1143)
		(layer "In9.Cu")
		(net "P5E_PEX0_STN1_TX_DP<26>")
	)
	(segment
		(start 68.534026 -271.471898)
		(end 68.534026 -271.500346)
		(width 0.1143)
		(layer "In9.Cu")
		(net "P5E_PEX0_STN1_TX_DP<26>")
	)
	(segment
		(start 29.882592 -137.017252)
		(end 32.453834 -143.224758)
		(width 0.1651)
		(layer "In9.Cu")
		(net "P5E_PEX0_STN1_TX_DP<26>")
	)
	(segment
		(start 35.12566 -122.82424)
		(end 34.83483 -123.11507)
		(width 0.1651)
		(layer "In9.Cu")
		(net "P5E_PEX0_STN1_TX_DP<26>")
	)
	(segment
		(start 68.534026 -263.855962)
		(end 68.534026 -271.471898)
		(width 0.1651)
		(layer "In9.Cu")
		(net "P5E_PEX0_STN1_TX_DP<26>")
	)
	(segment
		(start 68.579746 -278.205184)
		(end 68.79463 -278.420068)
		(width 0.1143)
		(layer "In9.Cu")
		(net "P5E_PEX0_STN1_TX_DP<26>")
	)
	(segment
		(start 19.307048 -349.831914)
		(end 19.627088 -349.511874)
		(width 0.13462)
		(layer "F.Cu")
		(net "P5E_PEX0_STN7_TX_DP<112>")
	)
	(segment
		(start 19.627088 -349.511874)
		(end 19.627088 -348.88043)
		(width 0.13462)
		(layer "F.Cu")
		(net "P5E_PEX0_STN7_TX_DP<112>")
	)
	(segment
		(start 19.627088 -348.88043)
		(end 19.332448 -348.58579)
		(width 0.13462)
		(layer "F.Cu")
		(net "P5E_PEX0_STN7_TX_DP<112>")
	)
	(segment
		(start 16.895064 -319.476374)
		(end 17.559274 -316.136782)
		(width 0.1651)
		(layer "In7.Cu")
		(net "P5E_PEX0_STN7_TX_DP<112>")
	)
	(segment
		(start 36.3728 -300.983904)
		(end 36.41852 -301.029624)
		(width 0.1143)
		(layer "In7.Cu")
		(net "P5E_PEX0_STN7_TX_DP<112>")
	)
	(segment
		(start 31.180786 -300.983904)
		(end 36.344352 -300.983904)
		(width 0.1651)
		(layer "In7.Cu")
		(net "P5E_PEX0_STN7_TX_DP<112>")
	)
	(segment
		(start 17.559274 -316.136782)
		(end 18.483326 -313.9059)
		(width 0.1651)
		(layer "In7.Cu")
		(net "P5E_PEX0_STN7_TX_DP<112>")
	)
	(segment
		(start 42.284396 -301.599854)
		(end 42.549826 -301.599854)
		(width 0.1143)
		(layer "In7.Cu")
		(net "P5E_PEX0_STN7_TX_DP<112>")
	)
	(segment
		(start 42.167048 -301.482506)
		(end 42.284396 -301.599854)
		(width 0.1143)
		(layer "In7.Cu")
		(net "P5E_PEX0_STN7_TX_DP<112>")
	)
	(segment
		(start 16.895064 -327.210674)
		(end 16.895064 -319.476374)
		(width 0.1651)
		(layer "In7.Cu")
		(net "P5E_PEX0_STN7_TX_DP<112>")
	)
	(segment
		(start 25.115774 -303.979326)
		(end 26.305002 -303.003458)
		(width 0.1651)
		(layer "In7.Cu")
		(net "P5E_PEX0_STN7_TX_DP<112>")
	)
	(segment
		(start 18.068798 -343.121996)
		(end 16.895064 -327.210674)
		(width 0.1651)
		(layer "In7.Cu")
		(net "P5E_PEX0_STN7_TX_DP<112>")
	)
	(segment
		(start 36.344352 -300.983904)
		(end 36.3728 -300.983904)
		(width 0.1143)
		(layer "In7.Cu")
		(net "P5E_PEX0_STN7_TX_DP<112>")
	)
	(segment
		(start 19.332448 -348.58579)
		(end 19.623278 -348.29496)
		(width 0.1651)
		(layer "In7.Cu")
		(net "P5E_PEX0_STN7_TX_DP<112>")
	)
	(segment
		(start 18.483326 -313.9059)
		(end 21.79574 -308.948328)
		(width 0.1651)
		(layer "In7.Cu")
		(net "P5E_PEX0_STN7_TX_DP<112>")
	)
	(segment
		(start 26.305002 -303.003458)
		(end 31.180786 -300.983904)
		(width 0.1651)
		(layer "In7.Cu")
		(net "P5E_PEX0_STN7_TX_DP<112>")
	)
	(segment
		(start 21.79574 -308.948328)
		(end 25.115774 -303.979326)
		(width 0.1651)
		(layer "In7.Cu")
		(net "P5E_PEX0_STN7_TX_DP<112>")
	)
	(segment
		(start 18.068798 -346.220542)
		(end 18.068798 -343.121996)
		(width 0.1651)
		(layer "In7.Cu")
		(net "P5E_PEX0_STN7_TX_DP<112>")
	)
	(segment
		(start 19.623278 -347.775022)
		(end 18.068798 -346.220542)
		(width 0.1651)
		(layer "In7.Cu")
		(net "P5E_PEX0_STN7_TX_DP<112>")
	)
	(segment
		(start 36.41852 -301.029624)
		(end 41.907714 -301.029624)
		(width 0.1143)
		(layer "In7.Cu")
		(net "P5E_PEX0_STN7_TX_DP<112>")
	)
	(segment
		(start 19.623278 -348.29496)
		(end 19.623278 -347.775022)
		(width 0.1651)
		(layer "In7.Cu")
		(net "P5E_PEX0_STN7_TX_DP<112>")
	)
	(segment
		(start 42.167048 -301.288958)
		(end 42.167048 -301.482506)
		(width 0.1143)
		(layer "In7.Cu")
		(net "P5E_PEX0_STN7_TX_DP<112>")
	)
	(segment
		(start 41.907714 -301.029624)
		(end 42.167048 -301.288958)
		(width 0.1143)
		(layer "In7.Cu")
		(net "P5E_PEX0_STN7_TX_DP<112>")
	)
	(segment
		(start 126.978918 -362.125768)
		(end 117.677438 -368.408966)
		(width 0.1651)
		(layer "In15.Cu")
		(net "P5E_PEX1_STN5_RX_DN<88>")
	)
	(segment
		(start 177.495708 -323.228208)
		(end 133.262624 -341.132668)
		(width 0.1651)
		(layer "In15.Cu")
		(net "P5E_PEX1_STN5_RX_DN<88>")
	)
	(segment
		(start 181.96179 -320.266822)
		(end 177.495708 -323.228208)
		(width 0.1651)
		(layer "In15.Cu")
		(net "P5E_PEX1_STN5_RX_DN<88>")
	)
	(segment
		(start 133.262624 -341.132668)
		(end 132.643118 -342.059768)
		(width 0.1651)
		(layer "In15.Cu")
		(net "P5E_PEX1_STN5_RX_DN<88>")
	)
	(segment
		(start 182.02021 -319.84188)
		(end 182.06593 -319.8876)
		(width 0.1143)
		(layer "In15.Cu")
		(net "P5E_PEX1_STN5_RX_DN<88>")
	)
	(segment
		(start 182.06593 -319.8876)
		(end 182.06593 -319.916048)
		(width 0.1143)
		(layer "In15.Cu")
		(net "P5E_PEX1_STN5_RX_DN<88>")
	)
	(segment
		(start 182.18531 -316.419992)
		(end 182.02021 -316.585092)
		(width 0.1143)
		(layer "In15.Cu")
		(net "P5E_PEX1_STN5_RX_DN<88>")
	)
	(segment
		(start 132.643118 -342.059768)
		(end 132.643118 -358.018842)
		(width 0.1651)
		(layer "In15.Cu")
		(net "P5E_PEX1_STN5_RX_DN<88>")
	)
	(segment
		(start 182.39994 -316.799722)
		(end 182.39994 -316.508892)
		(width 0.1143)
		(layer "In15.Cu")
		(net "P5E_PEX1_STN5_RX_DN<88>")
	)
	(segment
		(start 182.02021 -316.585092)
		(end 182.02021 -319.84188)
		(width 0.1143)
		(layer "In15.Cu")
		(net "P5E_PEX1_STN5_RX_DN<88>")
	)
	(segment
		(start 117.677438 -368.408966)
		(end 117.100096 -369.495578)
		(width 0.1651)
		(layer "In15.Cu")
		(net "P5E_PEX1_STN5_RX_DN<88>")
	)
	(segment
		(start 117.100096 -369.495578)
		(end 117.100096 -370.61267)
		(width 0.1651)
		(layer "In15.Cu")
		(net "P5E_PEX1_STN5_RX_DN<88>")
	)
	(segment
		(start 116.037106 -371.281198)
		(end 115.910106 -371.408198)
		(width 0.1651)
		(layer "In15.Cu")
		(net "P5E_PEX1_STN5_RX_DN<88>")
	)
	(segment
		(start 182.39994 -316.508892)
		(end 182.31104 -316.419992)
		(width 0.1143)
		(layer "In15.Cu")
		(net "P5E_PEX1_STN5_RX_DN<88>")
	)
	(segment
		(start 117.100096 -370.61267)
		(end 116.431568 -371.281198)
		(width 0.1651)
		(layer "In15.Cu")
		(net "P5E_PEX1_STN5_RX_DN<88>")
	)
	(segment
		(start 182.06593 -320.162682)
		(end 181.96179 -320.266822)
		(width 0.1651)
		(layer "In15.Cu")
		(net "P5E_PEX1_STN5_RX_DN<88>")
	)
	(segment
		(start 182.31104 -316.419992)
		(end 182.18531 -316.419992)
		(width 0.1143)
		(layer "In15.Cu")
		(net "P5E_PEX1_STN5_RX_DN<88>")
	)
	(segment
		(start 115.910106 -371.408198)
		(end 115.910106 -371.790214)
		(width 0.1651)
		(layer "In15.Cu")
		(net "P5E_PEX1_STN5_RX_DN<88>")
	)
	(segment
		(start 116.431568 -371.281198)
		(end 116.037106 -371.281198)
		(width 0.1651)
		(layer "In15.Cu")
		(net "P5E_PEX1_STN5_RX_DN<88>")
	)
	(segment
		(start 131.875022 -359.340658)
		(end 126.978918 -362.125768)
		(width 0.1651)
		(layer "In15.Cu")
		(net "P5E_PEX1_STN5_RX_DN<88>")
	)
	(segment
		(start 132.643118 -358.018842)
		(end 131.875022 -359.340658)
		(width 0.1651)
		(layer "In15.Cu")
		(net "P5E_PEX1_STN5_RX_DN<88>")
	)
	(segment
		(start 182.06593 -319.916048)
		(end 182.06593 -320.162682)
		(width 0.1651)
		(layer "In15.Cu")
		(net "P5E_PEX1_STN5_RX_DN<88>")
	)
	(segment
		(start 81.237582 -130.200146)
		(end 81.532222 -129.905506)
		(width 0.13462)
		(layer "F.Cu")
		(net "P5E_PEX0_STN0_TX_DN<4>")
	)
	(segment
		(start 80.606138 -130.200146)
		(end 81.237582 -130.200146)
		(width 0.13462)
		(layer "F.Cu")
		(net "P5E_PEX0_STN0_TX_DN<4>")
	)
	(segment
		(start 80.286098 -129.880106)
		(end 80.606138 -130.200146)
		(width 0.13462)
		(layer "F.Cu")
		(net "P5E_PEX0_STN0_TX_DN<4>")
	)
	(segment
		(start 87.230966 -283.253942)
		(end 85.029802 -284.165802)
		(width 0.1651)
		(layer "In9.Cu")
		(net "P5E_PEX0_STN0_TX_DN<4>")
	)
	(segment
		(start 83.917536 -284.165802)
		(end 83.889088 -284.165802)
		(width 0.1143)
		(layer "In9.Cu")
		(net "P5E_PEX0_STN0_TX_DN<4>")
	)
	(segment
		(start 77.43444 -284.499812)
		(end 77.69987 -284.499812)
		(width 0.1143)
		(layer "In9.Cu")
		(net "P5E_PEX0_STN0_TX_DN<4>")
	)
	(segment
		(start 86.508082 -178.670712)
		(end 82.752692 -221.593156)
		(width 0.1651)
		(layer "In9.Cu")
		(net "P5E_PEX0_STN0_TX_DN<4>")
	)
	(segment
		(start 81.532222 -129.905506)
		(end 81.823052 -130.196336)
		(width 0.1651)
		(layer "In9.Cu")
		(net "P5E_PEX0_STN0_TX_DN<4>")
	)
	(segment
		(start 96.300544 -153.386282)
		(end 96.300544 -159.455866)
		(width 0.1651)
		(layer "In9.Cu")
		(net "P5E_PEX0_STN0_TX_DN<4>")
	)
	(segment
		(start 96.464628 -268.181582)
		(end 96.811592 -272.151602)
		(width 0.1651)
		(layer "In9.Cu")
		(net "P5E_PEX0_STN0_TX_DN<4>")
	)
	(segment
		(start 87.802212 -133.113272)
		(end 92.426282 -144.276572)
		(width 0.1651)
		(layer "In9.Cu")
		(net "P5E_PEX0_STN0_TX_DN<4>")
	)
	(segment
		(start 77.32014 -284.385512)
		(end 77.43444 -284.499812)
		(width 0.1143)
		(layer "In9.Cu")
		(net "P5E_PEX0_STN0_TX_DN<4>")
	)
	(segment
		(start 85.32749 -130.63855)
		(end 87.802212 -133.113272)
		(width 0.1651)
		(layer "In9.Cu")
		(net "P5E_PEX0_STN0_TX_DN<4>")
	)
	(segment
		(start 85.296756 -250.731782)
		(end 95.663766 -266.247626)
		(width 0.1651)
		(layer "In9.Cu")
		(net "P5E_PEX0_STN0_TX_DN<4>")
	)
	(segment
		(start 85.029802 -284.165802)
		(end 83.917536 -284.165802)
		(width 0.1651)
		(layer "In9.Cu")
		(net "P5E_PEX0_STN0_TX_DN<4>")
	)
	(segment
		(start 77.32014 -284.223714)
		(end 77.32014 -284.385512)
		(width 0.1143)
		(layer "In9.Cu")
		(net "P5E_PEX0_STN0_TX_DN<4>")
	)
	(segment
		(start 96.811592 -272.151602)
		(end 95.73514 -274.749768)
		(width 0.1651)
		(layer "In9.Cu")
		(net "P5E_PEX0_STN0_TX_DN<4>")
	)
	(segment
		(start 92.598494 -144.448784)
		(end 96.300544 -153.386282)
		(width 0.1651)
		(layer "In9.Cu")
		(net "P5E_PEX0_STN0_TX_DN<4>")
	)
	(segment
		(start 83.843368 -284.120082)
		(end 77.423772 -284.120082)
		(width 0.1143)
		(layer "In9.Cu")
		(net "P5E_PEX0_STN0_TX_DN<4>")
	)
	(segment
		(start 84.260182 -130.196336)
		(end 85.32749 -130.63855)
		(width 0.1651)
		(layer "In9.Cu")
		(net "P5E_PEX0_STN0_TX_DN<4>")
	)
	(segment
		(start 81.823052 -130.196336)
		(end 84.260182 -130.196336)
		(width 0.1651)
		(layer "In9.Cu")
		(net "P5E_PEX0_STN0_TX_DN<4>")
	)
	(segment
		(start 77.423772 -284.120082)
		(end 77.32014 -284.223714)
		(width 0.1143)
		(layer "In9.Cu")
		(net "P5E_PEX0_STN0_TX_DN<4>")
	)
	(segment
		(start 82.752692 -221.593156)
		(end 85.296756 -250.731782)
		(width 0.1651)
		(layer "In9.Cu")
		(net "P5E_PEX0_STN0_TX_DN<4>")
	)
	(segment
		(start 92.426282 -144.276572)
		(end 92.598494 -144.448784)
		(width 0.1651)
		(layer "In9.Cu")
		(net "P5E_PEX0_STN0_TX_DN<4>")
	)
	(segment
		(start 83.889088 -284.165802)
		(end 83.843368 -284.120082)
		(width 0.1143)
		(layer "In9.Cu")
		(net "P5E_PEX0_STN0_TX_DN<4>")
	)
	(segment
		(start 95.73514 -274.749768)
		(end 87.230966 -283.253942)
		(width 0.1651)
		(layer "In9.Cu")
		(net "P5E_PEX0_STN0_TX_DN<4>")
	)
	(segment
		(start 87.553038 -174.772828)
		(end 86.508082 -178.670712)
		(width 0.1651)
		(layer "In9.Cu")
		(net "P5E_PEX0_STN0_TX_DN<4>")
	)
	(segment
		(start 95.663766 -266.247626)
		(end 96.464628 -268.181582)
		(width 0.1651)
		(layer "In9.Cu")
		(net "P5E_PEX0_STN0_TX_DN<4>")
	)
	(segment
		(start 96.221296 -159.752792)
		(end 87.553038 -174.772828)
		(width 0.1651)
		(layer "In9.Cu")
		(net "P5E_PEX0_STN0_TX_DN<4>")
	)
	(segment
		(start 96.300544 -159.455866)
		(end 96.221296 -159.752792)
		(width 0.1651)
		(layer "In9.Cu")
		(net "P5E_PEX0_STN0_TX_DN<4>")
	)
	(segment
		(start 172.825156 -365.377984)
		(end 172.656754 -364.911894)
		(width 0.1651)
		(layer "In9.Cu")
		(net "P5E_PEX1_STN7_RX_DP<126>")
	)
	(segment
		(start 172.314108 -363.69879)
		(end 172.146214 -363.232954)
		(width 0.1651)
		(layer "In9.Cu")
		(net "P5E_PEX1_STN7_RX_DP<126>")
	)
	(segment
		(start 170.249342 -357.970328)
		(end 170.249342 -340.898734)
		(width 0.1651)
		(layer "In9.Cu")
		(net "P5E_PEX1_STN7_RX_DP<126>")
	)
	(segment
		(start 173.458632 -382.69926)
		(end 173.98492 -382.172972)
		(width 0.1651)
		(layer "In9.Cu")
		(net "P5E_PEX1_STN7_RX_DP<126>")
	)
	(segment
		(start 157.084268 -319.8622)
		(end 157.129988 -319.81648)
		(width 0.1143)
		(layer "In9.Cu")
		(net "P5E_PEX1_STN7_RX_DP<126>")
	)
	(segment
		(start 157.484318 -322.126102)
		(end 157.084268 -320.82613)
		(width 0.1651)
		(layer "In9.Cu")
		(net "P5E_PEX1_STN7_RX_DP<126>")
	)
	(segment
		(start 157.700218 -316.140592)
		(end 157.700218 -315.850016)
		(width 0.1143)
		(layer "In9.Cu")
		(net "P5E_PEX1_STN7_RX_DP<126>")
	)
	(segment
		(start 157.129988 -319.81648)
		(end 157.129988 -316.485778)
		(width 0.1143)
		(layer "In9.Cu")
		(net "P5E_PEX1_STN7_RX_DP<126>")
	)
	(segment
		(start 173.10989 -382.18999)
		(end 173.10989 -382.57226)
		(width 0.1651)
		(layer "In9.Cu")
		(net "P5E_PEX1_STN7_RX_DP<126>")
	)
	(segment
		(start 173.98492 -382.172972)
		(end 173.98492 -369.707668)
		(width 0.1651)
		(layer "In9.Cu")
		(net "P5E_PEX1_STN7_RX_DP<126>")
	)
	(segment
		(start 172.032422 -363.17936)
		(end 171.864274 -362.71327)
		(width 0.1651)
		(layer "In9.Cu")
		(net "P5E_PEX1_STN7_RX_DP<126>")
	)
	(segment
		(start 170.249342 -340.898734)
		(end 157.484318 -322.126102)
		(width 0.1651)
		(layer "In9.Cu")
		(net "P5E_PEX1_STN7_RX_DP<126>")
	)
	(segment
		(start 172.656754 -364.911894)
		(end 172.710348 -364.798102)
		(width 0.1651)
		(layer "In9.Cu")
		(net "P5E_PEX1_STN7_RX_DP<126>")
	)
	(segment
		(start 173.519084 -367.04143)
		(end 172.938948 -365.431578)
		(width 0.1651)
		(layer "In9.Cu")
		(net "P5E_PEX1_STN7_RX_DP<126>")
	)
	(segment
		(start 173.10989 -382.57226)
		(end 173.23689 -382.69926)
		(width 0.1651)
		(layer "In9.Cu")
		(net "P5E_PEX1_STN7_RX_DP<126>")
	)
	(segment
		(start 172.938948 -365.431578)
		(end 172.825156 -365.377984)
		(width 0.1651)
		(layer "In9.Cu")
		(net "P5E_PEX1_STN7_RX_DP<126>")
	)
	(segment
		(start 171.864274 -362.71327)
		(end 171.917868 -362.599478)
		(width 0.1651)
		(layer "In9.Cu")
		(net "P5E_PEX1_STN7_RX_DP<126>")
	)
	(segment
		(start 157.386274 -316.229492)
		(end 157.611318 -316.229492)
		(width 0.1143)
		(layer "In9.Cu")
		(net "P5E_PEX1_STN7_RX_DP<126>")
	)
	(segment
		(start 157.084268 -320.82613)
		(end 157.084268 -319.890648)
		(width 0.1651)
		(layer "In9.Cu")
		(net "P5E_PEX1_STN7_RX_DP<126>")
	)
	(segment
		(start 172.428662 -364.278672)
		(end 172.260514 -363.812582)
		(width 0.1651)
		(layer "In9.Cu")
		(net "P5E_PEX1_STN7_RX_DP<126>")
	)
	(segment
		(start 173.98492 -369.707668)
		(end 173.519084 -367.04143)
		(width 0.1651)
		(layer "In9.Cu")
		(net "P5E_PEX1_STN7_RX_DP<126>")
	)
	(segment
		(start 157.700218 -315.850016)
		(end 157.699964 -315.849762)
		(width 0.1143)
		(layer "In9.Cu")
		(net "P5E_PEX1_STN7_RX_DP<126>")
	)
	(segment
		(start 172.146214 -363.232954)
		(end 172.032422 -363.17936)
		(width 0.1651)
		(layer "In9.Cu")
		(net "P5E_PEX1_STN7_RX_DP<126>")
	)
	(segment
		(start 172.710348 -364.798102)
		(end 172.542454 -364.332266)
		(width 0.1651)
		(layer "In9.Cu")
		(net "P5E_PEX1_STN7_RX_DP<126>")
	)
	(segment
		(start 173.23689 -382.69926)
		(end 173.458632 -382.69926)
		(width 0.1651)
		(layer "In9.Cu")
		(net "P5E_PEX1_STN7_RX_DP<126>")
	)
	(segment
		(start 157.129988 -316.485778)
		(end 157.386274 -316.229492)
		(width 0.1143)
		(layer "In9.Cu")
		(net "P5E_PEX1_STN7_RX_DP<126>")
	)
	(segment
		(start 157.611318 -316.229492)
		(end 157.700218 -316.140592)
		(width 0.1143)
		(layer "In9.Cu")
		(net "P5E_PEX1_STN7_RX_DP<126>")
	)
	(segment
		(start 171.917868 -362.599478)
		(end 170.249342 -357.970328)
		(width 0.1651)
		(layer "In9.Cu")
		(net "P5E_PEX1_STN7_RX_DP<126>")
	)
	(segment
		(start 172.260514 -363.812582)
		(end 172.314108 -363.69879)
		(width 0.1651)
		(layer "In9.Cu")
		(net "P5E_PEX1_STN7_RX_DP<126>")
	)
	(segment
		(start 157.084268 -319.890648)
		(end 157.084268 -319.8622)
		(width 0.1143)
		(layer "In9.Cu")
		(net "P5E_PEX1_STN7_RX_DP<126>")
	)
	(segment
		(start 172.542454 -364.332266)
		(end 172.428662 -364.278672)
		(width 0.1651)
		(layer "In9.Cu")
		(net "P5E_PEX1_STN7_RX_DP<126>")
	)
	(segment
		(start 81.237582 -142.910306)
		(end 81.532222 -142.615666)
		(width 0.13462)
		(layer "F.Cu")
		(net "P5E_PEX0_STN0_TX_DN<8>")
	)
	(segment
		(start 80.606138 -142.910306)
		(end 81.237582 -142.910306)
		(width 0.13462)
		(layer "F.Cu")
		(net "P5E_PEX0_STN0_TX_DN<8>")
	)
	(segment
		(start 80.286098 -142.590266)
		(end 80.606138 -142.910306)
		(width 0.13462)
		(layer "F.Cu")
		(net "P5E_PEX0_STN0_TX_DN<8>")
	)
	(segment
		(start 90.10904 -148.674074)
		(end 92.429584 -154.276552)
		(width 0.1651)
		(layer "In9.Cu")
		(net "P5E_PEX0_STN0_TX_DN<8>")
	)
	(segment
		(start 82.070194 -276.785578)
		(end 82.184494 -276.899878)
		(width 0.1143)
		(layer "In9.Cu")
		(net "P5E_PEX0_STN0_TX_DN<8>")
	)
	(segment
		(start 82.184494 -276.899878)
		(end 82.449924 -276.899878)
		(width 0.1143)
		(layer "In9.Cu")
		(net "P5E_PEX0_STN0_TX_DN<8>")
	)
	(segment
		(start 92.429584 -154.276552)
		(end 92.429584 -158.516574)
		(width 0.1651)
		(layer "In9.Cu")
		(net "P5E_PEX0_STN0_TX_DN<8>")
	)
	(segment
		(start 88.992456 -147.003516)
		(end 90.10904 -148.674074)
		(width 0.1651)
		(layer "In9.Cu")
		(net "P5E_PEX0_STN0_TX_DN<8>")
	)
	(segment
		(start 92.429584 -158.516574)
		(end 83.904328 -173.28642)
		(width 0.1651)
		(layer "In9.Cu")
		(net "P5E_PEX0_STN0_TX_DN<8>")
	)
	(segment
		(start 82.242152 -142.906496)
		(end 82.753962 -142.69466)
		(width 0.1651)
		(layer "In9.Cu")
		(net "P5E_PEX0_STN0_TX_DN<8>")
	)
	(segment
		(start 82.206846 -276.507448)
		(end 82.070194 -276.6441)
		(width 0.1143)
		(layer "In9.Cu")
		(net "P5E_PEX0_STN0_TX_DN<8>")
	)
	(segment
		(start 83.066128 -271.776952)
		(end 83.066128 -271.8054)
		(width 0.1143)
		(layer "In9.Cu")
		(net "P5E_PEX0_STN0_TX_DN<8>")
	)
	(segment
		(start 85.419438 -143.430498)
		(end 88.992456 -147.003516)
		(width 0.1651)
		(layer "In9.Cu")
		(net "P5E_PEX0_STN0_TX_DN<8>")
	)
	(segment
		(start 82.753962 -142.69466)
		(end 83.642962 -142.69466)
		(width 0.1651)
		(layer "In9.Cu")
		(net "P5E_PEX0_STN0_TX_DN<8>")
	)
	(segment
		(start 82.69732 -177.788062)
		(end 78.82509 -222.047308)
		(width 0.1651)
		(layer "In9.Cu")
		(net "P5E_PEX0_STN0_TX_DN<8>")
	)
	(segment
		(start 83.642962 -142.69466)
		(end 85.419438 -143.430498)
		(width 0.1651)
		(layer "In9.Cu")
		(net "P5E_PEX0_STN0_TX_DN<8>")
	)
	(segment
		(start 82.164428 -261.20217)
		(end 83.066128 -270.358108)
		(width 0.1651)
		(layer "In9.Cu")
		(net "P5E_PEX0_STN0_TX_DN<8>")
	)
	(segment
		(start 83.020408 -271.85112)
		(end 83.020408 -276.262592)
		(width 0.1143)
		(layer "In9.Cu")
		(net "P5E_PEX0_STN0_TX_DN<8>")
	)
	(segment
		(start 81.532222 -142.615666)
		(end 81.823052 -142.906496)
		(width 0.1651)
		(layer "In9.Cu")
		(net "P5E_PEX0_STN0_TX_DN<8>")
	)
	(segment
		(start 83.066128 -271.8054)
		(end 83.020408 -271.85112)
		(width 0.1143)
		(layer "In9.Cu")
		(net "P5E_PEX0_STN0_TX_DN<8>")
	)
	(segment
		(start 82.164428 -260.268466)
		(end 82.164428 -261.20217)
		(width 0.1651)
		(layer "In9.Cu")
		(net "P5E_PEX0_STN0_TX_DN<8>")
	)
	(segment
		(start 82.775552 -276.507448)
		(end 82.206846 -276.507448)
		(width 0.1143)
		(layer "In9.Cu")
		(net "P5E_PEX0_STN0_TX_DN<8>")
	)
	(segment
		(start 82.070194 -276.6441)
		(end 82.070194 -276.785578)
		(width 0.1143)
		(layer "In9.Cu")
		(net "P5E_PEX0_STN0_TX_DN<8>")
	)
	(segment
		(start 83.066128 -270.358108)
		(end 83.066128 -271.776952)
		(width 0.1651)
		(layer "In9.Cu")
		(net "P5E_PEX0_STN0_TX_DN<8>")
	)
	(segment
		(start 83.020408 -276.262592)
		(end 82.775552 -276.507448)
		(width 0.1143)
		(layer "In9.Cu")
		(net "P5E_PEX0_STN0_TX_DN<8>")
	)
	(segment
		(start 83.904328 -173.28642)
		(end 82.69732 -177.788062)
		(width 0.1651)
		(layer "In9.Cu")
		(net "P5E_PEX0_STN0_TX_DN<8>")
	)
	(segment
		(start 78.82509 -222.047308)
		(end 82.164428 -260.268466)
		(width 0.1651)
		(layer "In9.Cu")
		(net "P5E_PEX0_STN0_TX_DN<8>")
	)
	(segment
		(start 81.823052 -142.906496)
		(end 82.242152 -142.906496)
		(width 0.1651)
		(layer "In9.Cu")
		(net "P5E_PEX0_STN0_TX_DN<8>")
	)
	(segment
		(start 182.73395 -320.171064)
		(end 181.350412 -321.554348)
		(width 0.1651)
		(layer "In15.Cu")
		(net "P5E_PEX1_STN5_RX_DP<89>")
	)
	(segment
		(start 183.056276 -318.129666)
		(end 182.77967 -318.406272)
		(width 0.1143)
		(layer "In15.Cu")
		(net "P5E_PEX1_STN5_RX_DP<89>")
	)
	(segment
		(start 132.627878 -359.900728)
		(end 132.19049 -360.1339)
		(width 0.1651)
		(layer "In15.Cu")
		(net "P5E_PEX1_STN5_RX_DP<89>")
	)
	(segment
		(start 183.3499 -317.749936)
		(end 183.3499 -318.040766)
		(width 0.1143)
		(layer "In15.Cu")
		(net "P5E_PEX1_STN5_RX_DP<89>")
	)
	(segment
		(start 182.73395 -320.068448)
		(end 182.73395 -320.171064)
		(width 0.1651)
		(layer "In15.Cu")
		(net "P5E_PEX1_STN5_RX_DP<89>")
	)
	(segment
		(start 131.7117 -360.504232)
		(end 131.574286 -360.462322)
		(width 0.1651)
		(layer "In15.Cu")
		(net "P5E_PEX1_STN5_RX_DP<89>")
	)
	(segment
		(start 119.35079 -368.29492)
		(end 119.017796 -368.922046)
		(width 0.1651)
		(layer "In15.Cu")
		(net "P5E_PEX1_STN5_RX_DP<89>")
	)
	(segment
		(start 130.546856 -361.032044)
		(end 130.052826 -361.295442)
		(width 0.1651)
		(layer "In15.Cu")
		(net "P5E_PEX1_STN5_RX_DP<89>")
	)
	(segment
		(start 135.010398 -358.746298)
		(end 132.765292 -359.942638)
		(width 0.1651)
		(layer "In15.Cu")
		(net "P5E_PEX1_STN5_RX_DP<89>")
	)
	(segment
		(start 131.136898 -360.695494)
		(end 131.094988 -360.833162)
		(width 0.1651)
		(layer "In15.Cu")
		(net "P5E_PEX1_STN5_RX_DP<89>")
	)
	(segment
		(start 137.874248 -340.103714)
		(end 135.943086 -341.242396)
		(width 0.1651)
		(layer "In15.Cu")
		(net "P5E_PEX1_STN5_RX_DP<89>")
	)
	(segment
		(start 182.77967 -319.99428)
		(end 182.73395 -320.04)
		(width 0.1143)
		(layer "In15.Cu")
		(net "P5E_PEX1_STN5_RX_DP<89>")
	)
	(segment
		(start 132.765292 -359.942638)
		(end 132.627878 -359.900728)
		(width 0.1651)
		(layer "In15.Cu")
		(net "P5E_PEX1_STN5_RX_DP<89>")
	)
	(segment
		(start 132.19049 -360.1339)
		(end 132.14858 -360.271314)
		(width 0.1651)
		(layer "In15.Cu")
		(net "P5E_PEX1_STN5_RX_DP<89>")
	)
	(segment
		(start 132.14858 -360.271314)
		(end 131.7117 -360.504232)
		(width 0.1651)
		(layer "In15.Cu")
		(net "P5E_PEX1_STN5_RX_DP<89>")
	)
	(segment
		(start 181.350412 -321.554348)
		(end 177.677064 -323.991478)
		(width 0.1651)
		(layer "In15.Cu")
		(net "P5E_PEX1_STN5_RX_DP<89>")
	)
	(segment
		(start 119.017796 -371.53977)
		(end 118.458488 -372.099078)
		(width 0.1651)
		(layer "In15.Cu")
		(net "P5E_PEX1_STN5_RX_DP<89>")
	)
	(segment
		(start 130.052826 -361.295442)
		(end 130.01879 -361.406694)
		(width 0.1651)
		(layer "In15.Cu")
		(net "P5E_PEX1_STN5_RX_DP<89>")
	)
	(segment
		(start 118.458488 -372.099078)
		(end 118.237 -372.099078)
		(width 0.1651)
		(layer "In15.Cu")
		(net "P5E_PEX1_STN5_RX_DP<89>")
	)
	(segment
		(start 182.73395 -320.04)
		(end 182.73395 -320.068448)
		(width 0.1143)
		(layer "In15.Cu")
		(net "P5E_PEX1_STN5_RX_DP<89>")
	)
	(segment
		(start 135.470138 -341.943944)
		(end 135.470138 -357.980234)
		(width 0.1651)
		(layer "In15.Cu")
		(net "P5E_PEX1_STN5_RX_DP<89>")
	)
	(segment
		(start 130.658108 -361.06608)
		(end 130.546856 -361.032044)
		(width 0.1651)
		(layer "In15.Cu")
		(net "P5E_PEX1_STN5_RX_DP<89>")
	)
	(segment
		(start 131.574286 -360.462322)
		(end 131.136898 -360.695494)
		(width 0.1651)
		(layer "In15.Cu")
		(net "P5E_PEX1_STN5_RX_DP<89>")
	)
	(segment
		(start 118.11 -371.972078)
		(end 118.11 -371.590062)
		(width 0.1651)
		(layer "In15.Cu")
		(net "P5E_PEX1_STN5_RX_DP<89>")
	)
	(segment
		(start 177.677064 -323.991478)
		(end 137.874248 -340.103714)
		(width 0.1651)
		(layer "In15.Cu")
		(net "P5E_PEX1_STN5_RX_DP<89>")
	)
	(segment
		(start 131.094988 -360.833162)
		(end 130.658108 -361.06608)
		(width 0.1651)
		(layer "In15.Cu")
		(net "P5E_PEX1_STN5_RX_DP<89>")
	)
	(segment
		(start 130.01879 -361.406694)
		(end 127.787654 -362.595668)
		(width 0.1651)
		(layer "In15.Cu")
		(net "P5E_PEX1_STN5_RX_DP<89>")
	)
	(segment
		(start 135.943086 -341.242396)
		(end 135.470138 -341.943944)
		(width 0.1651)
		(layer "In15.Cu")
		(net "P5E_PEX1_STN5_RX_DP<89>")
	)
	(segment
		(start 135.470138 -357.980234)
		(end 135.010398 -358.746298)
		(width 0.1651)
		(layer "In15.Cu")
		(net "P5E_PEX1_STN5_RX_DP<89>")
	)
	(segment
		(start 118.237 -372.099078)
		(end 118.11 -371.972078)
		(width 0.1651)
		(layer "In15.Cu")
		(net "P5E_PEX1_STN5_RX_DP<89>")
	)
	(segment
		(start 127.787654 -362.595668)
		(end 119.35079 -368.29492)
		(width 0.1651)
		(layer "In15.Cu")
		(net "P5E_PEX1_STN5_RX_DP<89>")
	)
	(segment
		(start 119.017796 -368.922046)
		(end 119.017796 -371.53977)
		(width 0.1651)
		(layer "In15.Cu")
		(net "P5E_PEX1_STN5_RX_DP<89>")
	)
	(segment
		(start 182.77967 -318.406272)
		(end 182.77967 -319.99428)
		(width 0.1143)
		(layer "In15.Cu")
		(net "P5E_PEX1_STN5_RX_DP<89>")
	)
	(segment
		(start 183.261 -318.129666)
		(end 183.056276 -318.129666)
		(width 0.1143)
		(layer "In15.Cu")
		(net "P5E_PEX1_STN5_RX_DP<89>")
	)
	(segment
		(start 183.3499 -318.040766)
		(end 183.261 -318.129666)
		(width 0.1143)
		(layer "In15.Cu")
		(net "P5E_PEX1_STN5_RX_DP<89>")
	)
	(segment
		(start 35.4203 -134.603236)
		(end 35.12566 -134.897876)
		(width 0.13462)
		(layer "F.Cu")
		(net "P5E_PEX0_STN1_TX_DN<30>")
	)
	(segment
		(start 36.371784 -134.923276)
		(end 36.051744 -134.603236)
		(width 0.13462)
		(layer "F.Cu")
		(net "P5E_PEX0_STN1_TX_DN<30>")
	)
	(segment
		(start 36.051744 -134.603236)
		(end 35.4203 -134.603236)
		(width 0.13462)
		(layer "F.Cu")
		(net "P5E_PEX0_STN1_TX_DN<30>")
	)
	(segment
		(start 38.540436 -146.969226)
		(end 38.450774 -147.103846)
		(width 0.1651)
		(layer "In9.Cu")
		(net "P5E_PEX0_STN1_TX_DN<30>")
	)
	(segment
		(start 37.596064 -142.805658)
		(end 37.730938 -142.895574)
		(width 0.1651)
		(layer "In9.Cu")
		(net "P5E_PEX0_STN1_TX_DN<30>")
	)
	(segment
		(start 37.968682 -144.091406)
		(end 38.064948 -144.577308)
		(width 0.1651)
		(layer "In9.Cu")
		(net "P5E_PEX0_STN1_TX_DN<30>")
	)
	(segment
		(start 34.542222 -136.2202)
		(end 34.480246 -136.369552)
		(width 0.1651)
		(layer "In9.Cu")
		(net "P5E_PEX0_STN1_TX_DN<30>")
	)
	(segment
		(start 37.25545 -140.50391)
		(end 37.35197 -140.989812)
		(width 0.1651)
		(layer "In9.Cu")
		(net "P5E_PEX0_STN1_TX_DN<30>")
	)
	(segment
		(start 37.35197 -140.989812)
		(end 37.262054 -141.124178)
		(width 0.1651)
		(layer "In9.Cu")
		(net "P5E_PEX0_STN1_TX_DN<30>")
	)
	(segment
		(start 38.443916 -146.483324)
		(end 38.540436 -146.969226)
		(width 0.1651)
		(layer "In9.Cu")
		(net "P5E_PEX0_STN1_TX_DN<30>")
	)
	(segment
		(start 72.835262 -278.229568)
		(end 72.949562 -278.115268)
		(width 0.1143)
		(layer "In9.Cu")
		(net "P5E_PEX0_STN1_TX_DN<30>")
	)
	(segment
		(start 37.827204 -143.381476)
		(end 37.737542 -143.515842)
		(width 0.1651)
		(layer "In9.Cu")
		(net "P5E_PEX0_STN1_TX_DN<30>")
	)
	(segment
		(start 34.207958 -135.711946)
		(end 34.207958 -135.7122)
		(width 0.1651)
		(layer "In9.Cu")
		(net "P5E_PEX0_STN1_TX_DN<30>")
	)
	(segment
		(start 34.480246 -136.369552)
		(end 34.812986 -137.172446)
		(width 0.1651)
		(layer "In9.Cu")
		(net "P5E_PEX0_STN1_TX_DN<30>")
	)
	(segment
		(start 37.499798 -142.32001)
		(end 37.596064 -142.805658)
		(width 0.1651)
		(layer "In9.Cu")
		(net "P5E_PEX0_STN1_TX_DN<30>")
	)
	(segment
		(start 34.103564 -134.818882)
		(end 34.0233 -135.01243)
		(width 0.1651)
		(layer "In9.Cu")
		(net "P5E_PEX0_STN1_TX_DN<30>")
	)
	(segment
		(start 35.657282 -138.016742)
		(end 36.638992 -138.998452)
		(width 0.1651)
		(layer "In9.Cu")
		(net "P5E_PEX0_STN1_TX_DN<30>")
	)
	(segment
		(start 37.02431 -139.928346)
		(end 37.120576 -140.413994)
		(width 0.1651)
		(layer "In9.Cu")
		(net "P5E_PEX0_STN1_TX_DN<30>")
	)
	(segment
		(start 72.615806 -271.471898)
		(end 72.615806 -271.500346)
		(width 0.1143)
		(layer "In9.Cu")
		(net "P5E_PEX0_STN1_TX_DN<30>")
	)
	(segment
		(start 35.154108 -137.513568)
		(end 35.315652 -137.513568)
		(width 0.1651)
		(layer "In9.Cu")
		(net "P5E_PEX0_STN1_TX_DN<30>")
	)
	(segment
		(start 37.589714 -142.185644)
		(end 37.499798 -142.32001)
		(width 0.1651)
		(layer "In9.Cu")
		(net "P5E_PEX0_STN1_TX_DN<30>")
	)
	(segment
		(start 38.309296 -146.393408)
		(end 38.443916 -146.483324)
		(width 0.1651)
		(layer "In9.Cu")
		(net "P5E_PEX0_STN1_TX_DN<30>")
	)
	(segment
		(start 35.657282 -137.855198)
		(end 35.657282 -138.016742)
		(width 0.1651)
		(layer "In9.Cu")
		(net "P5E_PEX0_STN1_TX_DN<30>")
	)
	(segment
		(start 35.12566 -134.897876)
		(end 34.83483 -134.607046)
		(width 0.1651)
		(layer "In9.Cu")
		(net "P5E_PEX0_STN1_TX_DN<30>")
	)
	(segment
		(start 72.570086 -278.12619)
		(end 72.673464 -278.229568)
		(width 0.1143)
		(layer "In9.Cu")
		(net "P5E_PEX0_STN1_TX_DN<30>")
	)
	(segment
		(start 34.357564 -135.773922)
		(end 34.542222 -136.2202)
		(width 0.1651)
		(layer "In9.Cu")
		(net "P5E_PEX0_STN1_TX_DN<30>")
	)
	(segment
		(start 72.949562 -278.115268)
		(end 72.949562 -277.849838)
		(width 0.1143)
		(layer "In9.Cu")
		(net "P5E_PEX0_STN1_TX_DN<30>")
	)
	(segment
		(start 35.315652 -137.513568)
		(end 35.657282 -137.855198)
		(width 0.1651)
		(layer "In9.Cu")
		(net "P5E_PEX0_STN1_TX_DN<30>")
	)
	(segment
		(start 36.638992 -138.998452)
		(end 37.02431 -139.928346)
		(width 0.1651)
		(layer "In9.Cu")
		(net "P5E_PEX0_STN1_TX_DN<30>")
	)
	(segment
		(start 38.302692 -145.77314)
		(end 38.21303 -145.90776)
		(width 0.1651)
		(layer "In9.Cu")
		(net "P5E_PEX0_STN1_TX_DN<30>")
	)
	(segment
		(start 37.833808 -144.00149)
		(end 37.968682 -144.091406)
		(width 0.1651)
		(layer "In9.Cu")
		(net "P5E_PEX0_STN1_TX_DN<30>")
	)
	(segment
		(start 38.450774 -147.103846)
		(end 45.621702 -183.203088)
		(width 0.1651)
		(layer "In9.Cu")
		(net "P5E_PEX0_STN1_TX_DN<30>")
	)
	(segment
		(start 34.83483 -134.607046)
		(end 34.3154 -134.607046)
		(width 0.1651)
		(layer "In9.Cu")
		(net "P5E_PEX0_STN1_TX_DN<30>")
	)
	(segment
		(start 37.493194 -141.699742)
		(end 37.589714 -142.185644)
		(width 0.1651)
		(layer "In9.Cu")
		(net "P5E_PEX0_STN1_TX_DN<30>")
	)
	(segment
		(start 34.0233 -135.01243)
		(end 34.0233 -135.266938)
		(width 0.1651)
		(layer "In9.Cu")
		(net "P5E_PEX0_STN1_TX_DN<30>")
	)
	(segment
		(start 34.812986 -137.172446)
		(end 35.154108 -137.513568)
		(width 0.1651)
		(layer "In9.Cu")
		(net "P5E_PEX0_STN1_TX_DN<30>")
	)
	(segment
		(start 37.262054 -141.124178)
		(end 37.35832 -141.609826)
		(width 0.1651)
		(layer "In9.Cu")
		(net "P5E_PEX0_STN1_TX_DN<30>")
	)
	(segment
		(start 34.0233 -135.266938)
		(end 34.207958 -135.711946)
		(width 0.1651)
		(layer "In9.Cu")
		(net "P5E_PEX0_STN1_TX_DN<30>")
	)
	(segment
		(start 72.615806 -271.500346)
		(end 72.570086 -271.546066)
		(width 0.1143)
		(layer "In9.Cu")
		(net "P5E_PEX0_STN1_TX_DN<30>")
	)
	(segment
		(start 37.35832 -141.609826)
		(end 37.493194 -141.699742)
		(width 0.1651)
		(layer "In9.Cu")
		(net "P5E_PEX0_STN1_TX_DN<30>")
	)
	(segment
		(start 72.673464 -278.229568)
		(end 72.835262 -278.229568)
		(width 0.1143)
		(layer "In9.Cu")
		(net "P5E_PEX0_STN1_TX_DN<30>")
	)
	(segment
		(start 38.21303 -145.90776)
		(end 38.309296 -146.393408)
		(width 0.1651)
		(layer "In9.Cu")
		(net "P5E_PEX0_STN1_TX_DN<30>")
	)
	(segment
		(start 38.206426 -145.287238)
		(end 38.302692 -145.77314)
		(width 0.1651)
		(layer "In9.Cu")
		(net "P5E_PEX0_STN1_TX_DN<30>")
	)
	(segment
		(start 38.064948 -144.577308)
		(end 37.975286 -144.711674)
		(width 0.1651)
		(layer "In9.Cu")
		(net "P5E_PEX0_STN1_TX_DN<30>")
	)
	(segment
		(start 38.071552 -145.197322)
		(end 38.206426 -145.287238)
		(width 0.1651)
		(layer "In9.Cu")
		(net "P5E_PEX0_STN1_TX_DN<30>")
	)
	(segment
		(start 37.975286 -144.711674)
		(end 38.071552 -145.197322)
		(width 0.1651)
		(layer "In9.Cu")
		(net "P5E_PEX0_STN1_TX_DN<30>")
	)
	(segment
		(start 72.570086 -271.546066)
		(end 72.570086 -278.12619)
		(width 0.1143)
		(layer "In9.Cu")
		(net "P5E_PEX0_STN1_TX_DN<30>")
	)
	(segment
		(start 37.120576 -140.413994)
		(end 37.25545 -140.50391)
		(width 0.1651)
		(layer "In9.Cu")
		(net "P5E_PEX0_STN1_TX_DN<30>")
	)
	(segment
		(start 45.621702 -183.203088)
		(end 72.615806 -262.946896)
		(width 0.1651)
		(layer "In9.Cu")
		(net "P5E_PEX0_STN1_TX_DN<30>")
	)
	(segment
		(start 37.730938 -142.895574)
		(end 37.827204 -143.381476)
		(width 0.1651)
		(layer "In9.Cu")
		(net "P5E_PEX0_STN1_TX_DN<30>")
	)
	(segment
		(start 34.3154 -134.607046)
		(end 34.103564 -134.818882)
		(width 0.1651)
		(layer "In9.Cu")
		(net "P5E_PEX0_STN1_TX_DN<30>")
	)
	(segment
		(start 37.737542 -143.515842)
		(end 37.833808 -144.00149)
		(width 0.1651)
		(layer "In9.Cu")
		(net "P5E_PEX0_STN1_TX_DN<30>")
	)
	(segment
		(start 72.615806 -262.946896)
		(end 72.615806 -271.471898)
		(width 0.1651)
		(layer "In9.Cu")
		(net "P5E_PEX0_STN1_TX_DN<30>")
	)
	(segment
		(start 34.207958 -135.7122)
		(end 34.357564 -135.773922)
		(width 0.1651)
		(layer "In9.Cu")
		(net "P5E_PEX0_STN1_TX_DN<30>")
	)
	(segment
		(start 156.419296 -318.129666)
		(end 156.661104 -318.129666)
		(width 0.1143)
		(layer "In9.Cu")
		(net "P5E_PEX1_STN7_RX_DP<125>")
	)
	(segment
		(start 171.036996 -383.79908)
		(end 171.258484 -383.79908)
		(width 0.1651)
		(layer "In9.Cu")
		(net "P5E_PEX1_STN7_RX_DP<125>")
	)
	(segment
		(start 170.315636 -365.727234)
		(end 170.374056 -365.576612)
		(width 0.1651)
		(layer "In9.Cu")
		(net "P5E_PEX1_STN7_RX_DP<125>")
	)
	(segment
		(start 156.179774 -318.369188)
		(end 156.419296 -318.129666)
		(width 0.1143)
		(layer "In9.Cu")
		(net "P5E_PEX1_STN7_RX_DP<125>")
	)
	(segment
		(start 171.785026 -383.272538)
		(end 171.785026 -369.431062)
		(width 0.1651)
		(layer "In9.Cu")
		(net "P5E_PEX1_STN7_RX_DP<125>")
	)
	(segment
		(start 167.140382 -358.226614)
		(end 167.140382 -340.894416)
		(width 0.1651)
		(layer "In9.Cu")
		(net "P5E_PEX1_STN7_RX_DP<125>")
	)
	(segment
		(start 170.909996 -383.67208)
		(end 171.036996 -383.79908)
		(width 0.1651)
		(layer "In9.Cu")
		(net "P5E_PEX1_STN7_RX_DP<125>")
	)
	(segment
		(start 170.909996 -383.290064)
		(end 170.909996 -383.67208)
		(width 0.1651)
		(layer "In9.Cu")
		(net "P5E_PEX1_STN7_RX_DP<125>")
	)
	(segment
		(start 171.523914 -368.189764)
		(end 170.665902 -366.239552)
		(width 0.1651)
		(layer "In9.Cu")
		(net "P5E_PEX1_STN7_RX_DP<125>")
	)
	(segment
		(start 170.515026 -366.180878)
		(end 170.315636 -365.727234)
		(width 0.1651)
		(layer "In9.Cu")
		(net "P5E_PEX1_STN7_RX_DP<125>")
	)
	(segment
		(start 171.785026 -369.431062)
		(end 171.523914 -368.189764)
		(width 0.1651)
		(layer "In9.Cu")
		(net "P5E_PEX1_STN7_RX_DP<125>")
	)
	(segment
		(start 171.258484 -383.79908)
		(end 171.785026 -383.272538)
		(width 0.1651)
		(layer "In9.Cu")
		(net "P5E_PEX1_STN7_RX_DP<125>")
	)
	(segment
		(start 156.179774 -319.81648)
		(end 156.179774 -318.369188)
		(width 0.1143)
		(layer "In9.Cu")
		(net "P5E_PEX1_STN7_RX_DP<125>")
	)
	(segment
		(start 156.134054 -321.0814)
		(end 156.134054 -319.890648)
		(width 0.1651)
		(layer "In9.Cu")
		(net "P5E_PEX1_STN7_RX_DP<125>")
	)
	(segment
		(start 156.661104 -318.129666)
		(end 156.750004 -318.040766)
		(width 0.1143)
		(layer "In9.Cu")
		(net "P5E_PEX1_STN7_RX_DP<125>")
	)
	(segment
		(start 156.134054 -319.8622)
		(end 156.179774 -319.81648)
		(width 0.1143)
		(layer "In9.Cu")
		(net "P5E_PEX1_STN7_RX_DP<125>")
	)
	(segment
		(start 156.535628 -322.577714)
		(end 156.134054 -321.0814)
		(width 0.1651)
		(layer "In9.Cu")
		(net "P5E_PEX1_STN7_RX_DP<125>")
	)
	(segment
		(start 156.750004 -318.040766)
		(end 156.750004 -317.749936)
		(width 0.1143)
		(layer "In9.Cu")
		(net "P5E_PEX1_STN7_RX_DP<125>")
	)
	(segment
		(start 170.374056 -365.576612)
		(end 167.140382 -358.226614)
		(width 0.1651)
		(layer "In9.Cu")
		(net "P5E_PEX1_STN7_RX_DP<125>")
	)
	(segment
		(start 167.140382 -340.894416)
		(end 156.535628 -322.577714)
		(width 0.1651)
		(layer "In9.Cu")
		(net "P5E_PEX1_STN7_RX_DP<125>")
	)
	(segment
		(start 156.134054 -319.890648)
		(end 156.134054 -319.8622)
		(width 0.1143)
		(layer "In9.Cu")
		(net "P5E_PEX1_STN7_RX_DP<125>")
	)
	(segment
		(start 170.665902 -366.239552)
		(end 170.515026 -366.180878)
		(width 0.1651)
		(layer "In9.Cu")
		(net "P5E_PEX1_STN7_RX_DP<125>")
	)
	(segment
		(start 36.0299 -101.415342)
		(end 35.73526 -101.120702)
		(width 0.13462)
		(layer "F.Cu")
		(net "P5E_PEX0_STN1_TX_DN<17>")
	)
	(segment
		(start 36.981384 -101.095302)
		(end 36.661344 -101.415342)
		(width 0.13462)
		(layer "F.Cu")
		(net "P5E_PEX0_STN1_TX_DN<17>")
	)
	(segment
		(start 36.661344 -101.415342)
		(end 36.0299 -101.415342)
		(width 0.13462)
		(layer "F.Cu")
		(net "P5E_PEX0_STN1_TX_DN<17>")
	)
	(segment
		(start 35.44443 -101.411532)
		(end 34.940748 -101.411532)
		(width 0.1651)
		(layer "In9.Cu")
		(net "P5E_PEX0_STN1_TX_DN<17>")
	)
	(segment
		(start 34.22523 -101.70795)
		(end 29.10586 -106.82732)
		(width 0.1651)
		(layer "In9.Cu")
		(net "P5E_PEX0_STN1_TX_DN<17>")
	)
	(segment
		(start 34.940748 -101.411532)
		(end 34.22523 -101.70795)
		(width 0.1651)
		(layer "In9.Cu")
		(net "P5E_PEX0_STN1_TX_DN<17>")
	)
	(segment
		(start 59.983878 -265.771122)
		(end 59.983878 -271.526)
		(width 0.1651)
		(layer "In9.Cu")
		(net "P5E_PEX0_STN1_TX_DN<17>")
	)
	(segment
		(start 59.983878 -271.554448)
		(end 60.029598 -271.600168)
		(width 0.1143)
		(layer "In9.Cu")
		(net "P5E_PEX0_STN1_TX_DN<17>")
	)
	(segment
		(start 29.10586 -106.82732)
		(end 29.10586 -106.8578)
		(width 0.1651)
		(layer "In9.Cu")
		(net "P5E_PEX0_STN1_TX_DN<17>")
	)
	(segment
		(start 60.244736 -280.319988)
		(end 60.485528 -280.319988)
		(width 0.1143)
		(layer "In9.Cu")
		(net "P5E_PEX0_STN1_TX_DN<17>")
	)
	(segment
		(start 29.10586 -106.8578)
		(end 26.625804 -112.84458)
		(width 0.1651)
		(layer "In9.Cu")
		(net "P5E_PEX0_STN1_TX_DN<17>")
	)
	(segment
		(start 35.73526 -101.120702)
		(end 35.44443 -101.411532)
		(width 0.1651)
		(layer "In9.Cu")
		(net "P5E_PEX0_STN1_TX_DN<17>")
	)
	(segment
		(start 24.475186 -159.677608)
		(end 25.047448 -162.555174)
		(width 0.1651)
		(layer "In9.Cu")
		(net "P5E_PEX0_STN1_TX_DN<17>")
	)
	(segment
		(start 59.983878 -271.526)
		(end 59.983878 -271.554448)
		(width 0.1143)
		(layer "In9.Cu")
		(net "P5E_PEX0_STN1_TX_DN<17>")
	)
	(segment
		(start 25.047448 -162.555174)
		(end 59.983878 -265.771122)
		(width 0.1651)
		(layer "In9.Cu")
		(net "P5E_PEX0_STN1_TX_DN<17>")
	)
	(segment
		(start 23.759922 -145.126456)
		(end 24.475186 -159.677608)
		(width 0.1651)
		(layer "In9.Cu")
		(net "P5E_PEX0_STN1_TX_DN<17>")
	)
	(segment
		(start 21.172932 -138.880088)
		(end 23.759922 -145.126456)
		(width 0.1651)
		(layer "In9.Cu")
		(net "P5E_PEX0_STN1_TX_DN<17>")
	)
	(segment
		(start 21.172932 -130.82016)
		(end 21.172932 -138.880088)
		(width 0.1651)
		(layer "In9.Cu")
		(net "P5E_PEX0_STN1_TX_DN<17>")
	)
	(segment
		(start 60.485528 -280.319988)
		(end 60.599828 -280.434288)
		(width 0.1143)
		(layer "In9.Cu")
		(net "P5E_PEX0_STN1_TX_DN<17>")
	)
	(segment
		(start 60.029598 -280.10485)
		(end 60.244736 -280.319988)
		(width 0.1143)
		(layer "In9.Cu")
		(net "P5E_PEX0_STN1_TX_DN<17>")
	)
	(segment
		(start 60.599828 -280.434288)
		(end 60.599828 -280.699718)
		(width 0.1143)
		(layer "In9.Cu")
		(net "P5E_PEX0_STN1_TX_DN<17>")
	)
	(segment
		(start 26.625804 -112.84458)
		(end 21.172932 -130.82016)
		(width 0.1651)
		(layer "In9.Cu")
		(net "P5E_PEX0_STN1_TX_DN<17>")
	)
	(segment
		(start 60.029598 -271.600168)
		(end 60.029598 -280.10485)
		(width 0.1143)
		(layer "In9.Cu")
		(net "P5E_PEX0_STN1_TX_DN<17>")
	)
	(segment
		(start 32.337248 -349.511874)
		(end 32.337248 -348.88043)
		(width 0.13462)
		(layer "F.Cu")
		(net "P5E_PEX0_STN7_TX_DN<118>")
	)
	(segment
		(start 32.337248 -348.88043)
		(end 32.631888 -348.58579)
		(width 0.13462)
		(layer "F.Cu")
		(net "P5E_PEX0_STN7_TX_DN<118>")
	)
	(segment
		(start 32.657288 -349.831914)
		(end 32.337248 -349.511874)
		(width 0.13462)
		(layer "F.Cu")
		(net "P5E_PEX0_STN7_TX_DN<118>")
	)
	(segment
		(start 22.907244 -320.232278)
		(end 23.20417 -318.739774)
		(width 0.1651)
		(layer "In7.Cu")
		(net "P5E_PEX0_STN7_TX_DN<118>")
	)
	(segment
		(start 32.631888 -348.58579)
		(end 32.341058 -348.29496)
		(width 0.1651)
		(layer "In7.Cu")
		(net "P5E_PEX0_STN7_TX_DN<118>")
	)
	(segment
		(start 32.512254 -338.431378)
		(end 30.11932 -334.849978)
		(width 0.1651)
		(layer "In7.Cu")
		(net "P5E_PEX0_STN7_TX_DN<118>")
	)
	(segment
		(start 32.341058 -348.29496)
		(end 32.341058 -347.658182)
		(width 0.1651)
		(layer "In7.Cu")
		(net "P5E_PEX0_STN7_TX_DN<118>")
	)
	(segment
		(start 28.820872 -332.906878)
		(end 28.84551 -332.783688)
		(width 0.1651)
		(layer "In7.Cu")
		(net "P5E_PEX0_STN7_TX_DN<118>")
	)
	(segment
		(start 28.84551 -332.783688)
		(end 28.56992 -332.371446)
		(width 0.1651)
		(layer "In7.Cu")
		(net "P5E_PEX0_STN7_TX_DN<118>")
	)
	(segment
		(start 30.143704 -334.726788)
		(end 29.868368 -334.314546)
		(width 0.1651)
		(layer "In7.Cu")
		(net "P5E_PEX0_STN7_TX_DN<118>")
	)
	(segment
		(start 28.56992 -332.371446)
		(end 28.44673 -332.347062)
		(width 0.1651)
		(layer "In7.Cu")
		(net "P5E_PEX0_STN7_TX_DN<118>")
	)
	(segment
		(start 26.133044 -314.524136)
		(end 26.483056 -314.174124)
		(width 0.1651)
		(layer "In7.Cu")
		(net "P5E_PEX0_STN7_TX_DN<118>")
	)
	(segment
		(start 27.507184 -313.311794)
		(end 27.857704 -312.961274)
		(width 0.1651)
		(layer "In7.Cu")
		(net "P5E_PEX0_STN7_TX_DN<118>")
	)
	(segment
		(start 29.745178 -334.290162)
		(end 29.470096 -333.878428)
		(width 0.1651)
		(layer "In7.Cu")
		(net "P5E_PEX0_STN7_TX_DN<118>")
	)
	(segment
		(start 23.20417 -318.739774)
		(end 23.931372 -316.984126)
		(width 0.1651)
		(layer "In7.Cu")
		(net "P5E_PEX0_STN7_TX_DN<118>")
	)
	(segment
		(start 26.995374 -313.661806)
		(end 27.345386 -313.311794)
		(width 0.1651)
		(layer "In7.Cu")
		(net "P5E_PEX0_STN7_TX_DN<118>")
	)
	(segment
		(start 24.950674 -315.864494)
		(end 25.292304 -315.522864)
		(width 0.1651)
		(layer "In7.Cu")
		(net "P5E_PEX0_STN7_TX_DN<118>")
	)
	(segment
		(start 23.931372 -316.984126)
		(end 24.451564 -316.205616)
		(width 0.1651)
		(layer "In7.Cu")
		(net "P5E_PEX0_STN7_TX_DN<118>")
	)
	(segment
		(start 24.603202 -326.594724)
		(end 22.907244 -322.500498)
		(width 0.1651)
		(layer "In7.Cu")
		(net "P5E_PEX0_STN7_TX_DN<118>")
	)
	(segment
		(start 41.979596 -307.034438)
		(end 41.979596 -307.185568)
		(width 0.1143)
		(layer "In7.Cu")
		(net "P5E_PEX0_STN7_TX_DN<118>")
	)
	(segment
		(start 25.292304 -315.364876)
		(end 25.633426 -315.023754)
		(width 0.1651)
		(layer "In7.Cu")
		(net "P5E_PEX0_STN7_TX_DN<118>")
	)
	(segment
		(start 24.792686 -315.864494)
		(end 24.950674 -315.864494)
		(width 0.1651)
		(layer "In7.Cu")
		(net "P5E_PEX0_STN7_TX_DN<118>")
	)
	(segment
		(start 33.15843 -307.49875)
		(end 34.444686 -306.965858)
		(width 0.1651)
		(layer "In7.Cu")
		(net "P5E_PEX0_STN7_TX_DN<118>")
	)
	(segment
		(start 29.470096 -333.878428)
		(end 29.494734 -333.755238)
		(width 0.1651)
		(layer "In7.Cu")
		(net "P5E_PEX0_STN7_TX_DN<118>")
	)
	(segment
		(start 27.857704 -312.799476)
		(end 33.15843 -307.49875)
		(width 0.1651)
		(layer "In7.Cu")
		(net "P5E_PEX0_STN7_TX_DN<118>")
	)
	(segment
		(start 25.791414 -315.023754)
		(end 26.133044 -314.682124)
		(width 0.1651)
		(layer "In7.Cu")
		(net "P5E_PEX0_STN7_TX_DN<118>")
	)
	(segment
		(start 33.895538 -346.103702)
		(end 33.895538 -341.770208)
		(width 0.1651)
		(layer "In7.Cu")
		(net "P5E_PEX0_STN7_TX_DN<118>")
	)
	(segment
		(start 29.095954 -333.318612)
		(end 28.820872 -332.906878)
		(width 0.1651)
		(layer "In7.Cu")
		(net "P5E_PEX0_STN7_TX_DN<118>")
	)
	(segment
		(start 25.633426 -315.023754)
		(end 25.791414 -315.023754)
		(width 0.1651)
		(layer "In7.Cu")
		(net "P5E_PEX0_STN7_TX_DN<118>")
	)
	(segment
		(start 30.11932 -334.849978)
		(end 30.143704 -334.726788)
		(width 0.1651)
		(layer "In7.Cu")
		(net "P5E_PEX0_STN7_TX_DN<118>")
	)
	(segment
		(start 41.979596 -307.185568)
		(end 41.865296 -307.299868)
		(width 0.1143)
		(layer "In7.Cu")
		(net "P5E_PEX0_STN7_TX_DN<118>")
	)
	(segment
		(start 28.44673 -332.347062)
		(end 24.603202 -326.594724)
		(width 0.1651)
		(layer "In7.Cu")
		(net "P5E_PEX0_STN7_TX_DN<118>")
	)
	(segment
		(start 26.995374 -313.823604)
		(end 26.995374 -313.661806)
		(width 0.1651)
		(layer "In7.Cu")
		(net "P5E_PEX0_STN7_TX_DN<118>")
	)
	(segment
		(start 29.494734 -333.755238)
		(end 29.219144 -333.342996)
		(width 0.1651)
		(layer "In7.Cu")
		(net "P5E_PEX0_STN7_TX_DN<118>")
	)
	(segment
		(start 35.73272 -306.920138)
		(end 41.865296 -306.920138)
		(width 0.1143)
		(layer "In7.Cu")
		(net "P5E_PEX0_STN7_TX_DN<118>")
	)
	(segment
		(start 35.658552 -306.965858)
		(end 35.687 -306.965858)
		(width 0.1143)
		(layer "In7.Cu")
		(net "P5E_PEX0_STN7_TX_DN<118>")
	)
	(segment
		(start 41.865296 -307.299868)
		(end 41.599866 -307.299868)
		(width 0.1143)
		(layer "In7.Cu")
		(net "P5E_PEX0_STN7_TX_DN<118>")
	)
	(segment
		(start 25.292304 -315.522864)
		(end 25.292304 -315.364876)
		(width 0.1651)
		(layer "In7.Cu")
		(net "P5E_PEX0_STN7_TX_DN<118>")
	)
	(segment
		(start 29.868368 -334.314546)
		(end 29.745178 -334.290162)
		(width 0.1651)
		(layer "In7.Cu")
		(net "P5E_PEX0_STN7_TX_DN<118>")
	)
	(segment
		(start 26.644854 -314.174124)
		(end 26.995374 -313.823604)
		(width 0.1651)
		(layer "In7.Cu")
		(net "P5E_PEX0_STN7_TX_DN<118>")
	)
	(segment
		(start 26.483056 -314.174124)
		(end 26.644854 -314.174124)
		(width 0.1651)
		(layer "In7.Cu")
		(net "P5E_PEX0_STN7_TX_DN<118>")
	)
	(segment
		(start 35.687 -306.965858)
		(end 35.73272 -306.920138)
		(width 0.1143)
		(layer "In7.Cu")
		(net "P5E_PEX0_STN7_TX_DN<118>")
	)
	(segment
		(start 27.345386 -313.311794)
		(end 27.507184 -313.311794)
		(width 0.1651)
		(layer "In7.Cu")
		(net "P5E_PEX0_STN7_TX_DN<118>")
	)
	(segment
		(start 41.865296 -306.920138)
		(end 41.979596 -307.034438)
		(width 0.1143)
		(layer "In7.Cu")
		(net "P5E_PEX0_STN7_TX_DN<118>")
	)
	(segment
		(start 27.857704 -312.961274)
		(end 27.857704 -312.799476)
		(width 0.1651)
		(layer "In7.Cu")
		(net "P5E_PEX0_STN7_TX_DN<118>")
	)
	(segment
		(start 26.133044 -314.682124)
		(end 26.133044 -314.524136)
		(width 0.1651)
		(layer "In7.Cu")
		(net "P5E_PEX0_STN7_TX_DN<118>")
	)
	(segment
		(start 22.907244 -322.500498)
		(end 22.907244 -320.232278)
		(width 0.1651)
		(layer "In7.Cu")
		(net "P5E_PEX0_STN7_TX_DN<118>")
	)
	(segment
		(start 34.444686 -306.965858)
		(end 35.658552 -306.965858)
		(width 0.1651)
		(layer "In7.Cu")
		(net "P5E_PEX0_STN7_TX_DN<118>")
	)
	(segment
		(start 33.895538 -341.770208)
		(end 32.512254 -338.431378)
		(width 0.1651)
		(layer "In7.Cu")
		(net "P5E_PEX0_STN7_TX_DN<118>")
	)
	(segment
		(start 29.219144 -333.342996)
		(end 29.095954 -333.318612)
		(width 0.1651)
		(layer "In7.Cu")
		(net "P5E_PEX0_STN7_TX_DN<118>")
	)
	(segment
		(start 32.341058 -347.658182)
		(end 33.895538 -346.103702)
		(width 0.1651)
		(layer "In7.Cu")
		(net "P5E_PEX0_STN7_TX_DN<118>")
	)
	(segment
		(start 24.451564 -316.205616)
		(end 24.792686 -315.864494)
		(width 0.1651)
		(layer "In7.Cu")
		(net "P5E_PEX0_STN7_TX_DN<118>")
	)
	(segment
		(start 128.48082 -360.946954)
		(end 128.523746 -360.790998)
		(width 0.1651)
		(layer "In15.Cu")
		(net "P5E_PEX1_STN5_RX_DP<88>")
	)
	(segment
		(start 117.461284 -368.214402)
		(end 126.830074 -361.885992)
		(width 0.1651)
		(layer "In15.Cu")
		(net "P5E_PEX1_STN5_RX_DP<88>")
	)
	(segment
		(start 116.818156 -369.42522)
		(end 117.461284 -368.214402)
		(width 0.1651)
		(layer "In15.Cu")
		(net "P5E_PEX1_STN5_RX_DP<88>")
	)
	(segment
		(start 133.076188 -340.903814)
		(end 177.363374 -322.977256)
		(width 0.1651)
		(layer "In15.Cu")
		(net "P5E_PEX1_STN5_RX_DP<88>")
	)
	(segment
		(start 181.78399 -319.916048)
		(end 181.78399 -319.90157)
		(width 0.1143)
		(layer "In15.Cu")
		(net "P5E_PEX1_STN5_RX_DP<88>")
	)
	(segment
		(start 116.818156 -370.49583)
		(end 116.818156 -369.42522)
		(width 0.1651)
		(layer "In15.Cu")
		(net "P5E_PEX1_STN5_RX_DP<88>")
	)
	(segment
		(start 181.82971 -319.85585)
		(end 181.82971 -316.506098)
		(width 0.1143)
		(layer "In15.Cu")
		(net "P5E_PEX1_STN5_RX_DP<88>")
	)
	(segment
		(start 129.540508 -360.343958)
		(end 129.583434 -360.188256)
		(width 0.1651)
		(layer "In15.Cu")
		(net "P5E_PEX1_STN5_RX_DP<88>")
	)
	(segment
		(start 131.669282 -359.13314)
		(end 132.361178 -357.942642)
		(width 0.1651)
		(layer "In15.Cu")
		(net "P5E_PEX1_STN5_RX_DP<88>")
	)
	(segment
		(start 132.361178 -357.942642)
		(end 132.361178 -341.97417)
		(width 0.1651)
		(layer "In15.Cu")
		(net "P5E_PEX1_STN5_RX_DP<88>")
	)
	(segment
		(start 182.39994 -316.140592)
		(end 182.39994 -315.849762)
		(width 0.1143)
		(layer "In15.Cu")
		(net "P5E_PEX1_STN5_RX_DP<88>")
	)
	(segment
		(start 130.170174 -359.985818)
		(end 131.669282 -359.13314)
		(width 0.1651)
		(layer "In15.Cu")
		(net "P5E_PEX1_STN5_RX_DP<88>")
	)
	(segment
		(start 182.31104 -316.229492)
		(end 182.39994 -316.140592)
		(width 0.1143)
		(layer "In15.Cu")
		(net "P5E_PEX1_STN5_RX_DP<88>")
	)
	(segment
		(start 115.910106 -370.872258)
		(end 116.037106 -370.999258)
		(width 0.1651)
		(layer "In15.Cu")
		(net "P5E_PEX1_STN5_RX_DP<88>")
	)
	(segment
		(start 130.014218 -359.943146)
		(end 130.170174 -359.985818)
		(width 0.1651)
		(layer "In15.Cu")
		(net "P5E_PEX1_STN5_RX_DP<88>")
	)
	(segment
		(start 127.894588 -361.148884)
		(end 128.050544 -361.19181)
		(width 0.1651)
		(layer "In15.Cu")
		(net "P5E_PEX1_STN5_RX_DP<88>")
	)
	(segment
		(start 132.361178 -341.97417)
		(end 133.076188 -340.903814)
		(width 0.1651)
		(layer "In15.Cu")
		(net "P5E_PEX1_STN5_RX_DP<88>")
	)
	(segment
		(start 126.830074 -361.885992)
		(end 127.420878 -361.54995)
		(width 0.1651)
		(layer "In15.Cu")
		(net "P5E_PEX1_STN5_RX_DP<88>")
	)
	(segment
		(start 181.782466 -320.047366)
		(end 181.78399 -320.045842)
		(width 0.1651)
		(layer "In15.Cu")
		(net "P5E_PEX1_STN5_RX_DP<88>")
	)
	(segment
		(start 129.583434 -360.188256)
		(end 130.014218 -359.943146)
		(width 0.1651)
		(layer "In15.Cu")
		(net "P5E_PEX1_STN5_RX_DP<88>")
	)
	(segment
		(start 116.314728 -370.999258)
		(end 116.818156 -370.49583)
		(width 0.1651)
		(layer "In15.Cu")
		(net "P5E_PEX1_STN5_RX_DP<88>")
	)
	(segment
		(start 129.110232 -360.588814)
		(end 129.540508 -360.343958)
		(width 0.1651)
		(layer "In15.Cu")
		(net "P5E_PEX1_STN5_RX_DP<88>")
	)
	(segment
		(start 127.463804 -361.393994)
		(end 127.894588 -361.148884)
		(width 0.1651)
		(layer "In15.Cu")
		(net "P5E_PEX1_STN5_RX_DP<88>")
	)
	(segment
		(start 115.910106 -370.489988)
		(end 115.910106 -370.872258)
		(width 0.1651)
		(layer "In15.Cu")
		(net "P5E_PEX1_STN5_RX_DP<88>")
	)
	(segment
		(start 128.523746 -360.790998)
		(end 128.95453 -360.545888)
		(width 0.1651)
		(layer "In15.Cu")
		(net "P5E_PEX1_STN5_RX_DP<88>")
	)
	(segment
		(start 177.363374 -322.977256)
		(end 181.782466 -320.047366)
		(width 0.1651)
		(layer "In15.Cu")
		(net "P5E_PEX1_STN5_RX_DP<88>")
	)
	(segment
		(start 127.420878 -361.54995)
		(end 127.463804 -361.393994)
		(width 0.1651)
		(layer "In15.Cu")
		(net "P5E_PEX1_STN5_RX_DP<88>")
	)
	(segment
		(start 128.95453 -360.545888)
		(end 129.110232 -360.588814)
		(width 0.1651)
		(layer "In15.Cu")
		(net "P5E_PEX1_STN5_RX_DP<88>")
	)
	(segment
		(start 182.106316 -316.229492)
		(end 182.31104 -316.229492)
		(width 0.1143)
		(layer "In15.Cu")
		(net "P5E_PEX1_STN5_RX_DP<88>")
	)
	(segment
		(start 128.050544 -361.19181)
		(end 128.48082 -360.946954)
		(width 0.1651)
		(layer "In15.Cu")
		(net "P5E_PEX1_STN5_RX_DP<88>")
	)
	(segment
		(start 181.78399 -319.90157)
		(end 181.82971 -319.85585)
		(width 0.1143)
		(layer "In15.Cu")
		(net "P5E_PEX1_STN5_RX_DP<88>")
	)
	(segment
		(start 181.78399 -320.045842)
		(end 181.78399 -319.916048)
		(width 0.1651)
		(layer "In15.Cu")
		(net "P5E_PEX1_STN5_RX_DP<88>")
	)
	(segment
		(start 116.037106 -370.999258)
		(end 116.314728 -370.999258)
		(width 0.1651)
		(layer "In15.Cu")
		(net "P5E_PEX1_STN5_RX_DP<88>")
	)
	(segment
		(start 181.82971 -316.506098)
		(end 182.106316 -316.229492)
		(width 0.1143)
		(layer "In15.Cu")
		(net "P5E_PEX1_STN5_RX_DP<88>")
	)
	(segment
		(start 80.606138 -150.38451)
		(end 81.237582 -150.38451)
		(width 0.13462)
		(layer "F.Cu")
		(net "P5E_PEX0_STN0_TX_DN<12>")
	)
	(segment
		(start 80.286098 -150.70455)
		(end 80.606138 -150.38451)
		(width 0.13462)
		(layer "F.Cu")
		(net "P5E_PEX0_STN0_TX_DN<12>")
	)
	(segment
		(start 81.237582 -150.38451)
		(end 81.532222 -150.67915)
		(width 0.13462)
		(layer "F.Cu")
		(net "P5E_PEX0_STN0_TX_DN<12>")
	)
	(segment
		(start 77.69987 -280.699718)
		(end 77.69987 -280.434288)
		(width 0.1143)
		(layer "In9.Cu")
		(net "P5E_PEX0_STN0_TX_DN<12>")
	)
	(segment
		(start 78.525116 -177.518314)
		(end 78.562708 -177.088292)
		(width 0.1651)
		(layer "In9.Cu")
		(net "P5E_PEX0_STN0_TX_DN<12>")
	)
	(segment
		(start 77.232002 -269.759684)
		(end 77.42174 -269.301722)
		(width 0.1651)
		(layer "In9.Cu")
		(net "P5E_PEX0_STN0_TX_DN<12>")
	)
	(segment
		(start 78.363572 -178.05273)
		(end 78.401164 -177.6222)
		(width 0.1651)
		(layer "In9.Cu")
		(net "P5E_PEX0_STN0_TX_DN<12>")
	)
	(segment
		(start 78.011528 -260.829806)
		(end 74.624946 -222.097346)
		(width 0.1651)
		(layer "In9.Cu")
		(net "P5E_PEX0_STN0_TX_DN<12>")
	)
	(segment
		(start 74.624946 -222.097346)
		(end 76.547472 -200.12406)
		(width 0.1651)
		(layer "In9.Cu")
		(net "P5E_PEX0_STN0_TX_DN<12>")
	)
	(segment
		(start 77.12964 -280.10485)
		(end 77.12964 -271.600168)
		(width 0.1143)
		(layer "In9.Cu")
		(net "P5E_PEX0_STN0_TX_DN<12>")
	)
	(segment
		(start 87.783162 -154.044904)
		(end 86.13902 -151.58466)
		(width 0.1651)
		(layer "In9.Cu")
		(net "P5E_PEX0_STN0_TX_DN<12>")
	)
	(segment
		(start 77.344778 -280.319988)
		(end 77.12964 -280.10485)
		(width 0.1143)
		(layer "In9.Cu")
		(net "P5E_PEX0_STN0_TX_DN<12>")
	)
	(segment
		(start 77.521308 -269.260574)
		(end 78.011528 -268.076934)
		(width 0.1651)
		(layer "In9.Cu")
		(net "P5E_PEX0_STN0_TX_DN<12>")
	)
	(segment
		(start 78.011528 -268.076934)
		(end 78.011528 -260.829806)
		(width 0.1651)
		(layer "In9.Cu")
		(net "P5E_PEX0_STN0_TX_DN<12>")
	)
	(segment
		(start 88.276684 -157.341824)
		(end 88.276684 -155.236926)
		(width 0.1651)
		(layer "In9.Cu")
		(net "P5E_PEX0_STN0_TX_DN<12>")
	)
	(segment
		(start 80.023208 -171.638976)
		(end 88.276684 -157.341824)
		(width 0.1651)
		(layer "In9.Cu")
		(net "P5E_PEX0_STN0_TX_DN<12>")
	)
	(segment
		(start 76.547472 -200.12406)
		(end 78.467458 -178.176428)
		(width 0.1651)
		(layer "In9.Cu")
		(net "P5E_PEX0_STN0_TX_DN<12>")
	)
	(segment
		(start 77.69987 -280.434288)
		(end 77.58557 -280.319988)
		(width 0.1143)
		(layer "In9.Cu")
		(net "P5E_PEX0_STN0_TX_DN<12>")
	)
	(segment
		(start 81.823052 -150.38832)
		(end 81.532222 -150.67915)
		(width 0.1651)
		(layer "In9.Cu")
		(net "P5E_PEX0_STN0_TX_DN<12>")
	)
	(segment
		(start 77.08392 -271.526)
		(end 77.08392 -270.316706)
		(width 0.1651)
		(layer "In9.Cu")
		(net "P5E_PEX0_STN0_TX_DN<12>")
	)
	(segment
		(start 77.273404 -269.859252)
		(end 77.232002 -269.759684)
		(width 0.1651)
		(layer "In9.Cu")
		(net "P5E_PEX0_STN0_TX_DN<12>")
	)
	(segment
		(start 78.562708 -177.088292)
		(end 80.023208 -171.638976)
		(width 0.1651)
		(layer "In9.Cu")
		(net "P5E_PEX0_STN0_TX_DN<12>")
	)
	(segment
		(start 86.13902 -151.58466)
		(end 85.456776 -150.902416)
		(width 0.1651)
		(layer "In9.Cu")
		(net "P5E_PEX0_STN0_TX_DN<12>")
	)
	(segment
		(start 78.467458 -178.176428)
		(end 78.363572 -178.05273)
		(width 0.1651)
		(layer "In9.Cu")
		(net "P5E_PEX0_STN0_TX_DN<12>")
	)
	(segment
		(start 77.08392 -270.316706)
		(end 77.273404 -269.859252)
		(width 0.1651)
		(layer "In9.Cu")
		(net "P5E_PEX0_STN0_TX_DN<12>")
	)
	(segment
		(start 77.08392 -271.554448)
		(end 77.08392 -271.526)
		(width 0.1143)
		(layer "In9.Cu")
		(net "P5E_PEX0_STN0_TX_DN<12>")
	)
	(segment
		(start 77.42174 -269.301722)
		(end 77.521308 -269.260574)
		(width 0.1651)
		(layer "In9.Cu")
		(net "P5E_PEX0_STN0_TX_DN<12>")
	)
	(segment
		(start 88.276684 -155.236926)
		(end 87.783162 -154.044904)
		(width 0.1651)
		(layer "In9.Cu")
		(net "P5E_PEX0_STN0_TX_DN<12>")
	)
	(segment
		(start 77.12964 -271.600168)
		(end 77.08392 -271.554448)
		(width 0.1143)
		(layer "In9.Cu")
		(net "P5E_PEX0_STN0_TX_DN<12>")
	)
	(segment
		(start 85.456776 -150.902416)
		(end 84.215986 -150.38832)
		(width 0.1651)
		(layer "In9.Cu")
		(net "P5E_PEX0_STN0_TX_DN<12>")
	)
	(segment
		(start 78.401164 -177.6222)
		(end 78.525116 -177.518314)
		(width 0.1651)
		(layer "In9.Cu")
		(net "P5E_PEX0_STN0_TX_DN<12>")
	)
	(segment
		(start 84.215986 -150.38832)
		(end 81.823052 -150.38832)
		(width 0.1651)
		(layer "In9.Cu")
		(net "P5E_PEX0_STN0_TX_DN<12>")
	)
	(segment
		(start 77.58557 -280.319988)
		(end 77.344778 -280.319988)
		(width 0.1143)
		(layer "In9.Cu")
		(net "P5E_PEX0_STN0_TX_DN<12>")
	)
	(segment
		(start 35.446208 -342.734138)
		(end 35.740848 -342.439498)
		(width 0.13462)
		(layer "F.Cu")
		(net "P5E_PEX0_STN7_TX_DN<119>")
	)
	(segment
		(start 35.446208 -343.365582)
		(end 35.446208 -342.734138)
		(width 0.13462)
		(layer "F.Cu")
		(net "P5E_PEX0_STN7_TX_DN<119>")
	)
	(segment
		(start 35.766248 -343.685622)
		(end 35.446208 -343.365582)
		(width 0.13462)
		(layer "F.Cu")
		(net "P5E_PEX0_STN7_TX_DN<119>")
	)
	(segment
		(start 34.998914 -340.542118)
		(end 33.556448 -337.995514)
		(width 0.1651)
		(layer "In7.Cu")
		(net "P5E_PEX0_STN7_TX_DN<119>")
	)
	(segment
		(start 26.898092 -315.283342)
		(end 27.023822 -315.283342)
		(width 0.1651)
		(layer "In7.Cu")
		(net "P5E_PEX0_STN7_TX_DN<119>")
	)
	(segment
		(start 33.556448 -337.995514)
		(end 31.395416 -334.761078)
		(width 0.1651)
		(layer "In7.Cu")
		(net "P5E_PEX0_STN7_TX_DN<119>")
	)
	(segment
		(start 25.210008 -325.504302)
		(end 23.862284 -322.250562)
		(width 0.1651)
		(layer "In7.Cu")
		(net "P5E_PEX0_STN7_TX_DN<119>")
	)
	(segment
		(start 43.879516 -307.984398)
		(end 43.879516 -308.135528)
		(width 0.1143)
		(layer "In7.Cu")
		(net "P5E_PEX0_STN7_TX_DN<119>")
	)
	(segment
		(start 26.305256 -327.143618)
		(end 26.030174 -326.731884)
		(width 0.1651)
		(layer "In7.Cu")
		(net "P5E_PEX0_STN7_TX_DN<119>")
	)
	(segment
		(start 31.420054 -334.637888)
		(end 31.144464 -334.225646)
		(width 0.1651)
		(layer "In7.Cu")
		(net "P5E_PEX0_STN7_TX_DN<119>")
	)
	(segment
		(start 35.658552 -307.915818)
		(end 35.687 -307.915818)
		(width 0.1143)
		(layer "In7.Cu")
		(net "P5E_PEX0_STN7_TX_DN<119>")
	)
	(segment
		(start 25.670256 -326.19315)
		(end 25.210008 -325.504302)
		(width 0.1651)
		(layer "In7.Cu")
		(net "P5E_PEX0_STN7_TX_DN<119>")
	)
	(segment
		(start 30.495494 -333.254096)
		(end 30.37205 -333.229712)
		(width 0.1651)
		(layer "In7.Cu")
		(net "P5E_PEX0_STN7_TX_DN<119>")
	)
	(segment
		(start 35.450018 -341.7951)
		(end 35.34156 -341.38235)
		(width 0.1651)
		(layer "In7.Cu")
		(net "P5E_PEX0_STN7_TX_DN<119>")
	)
	(segment
		(start 27.935936 -329.583288)
		(end 27.956764 -329.477624)
		(width 0.1651)
		(layer "In7.Cu")
		(net "P5E_PEX0_STN7_TX_DN<119>")
	)
	(segment
		(start 25.77592 -326.213978)
		(end 25.670256 -326.19315)
		(width 0.1651)
		(layer "In7.Cu")
		(net "P5E_PEX0_STN7_TX_DN<119>")
	)
	(segment
		(start 34.714434 -307.915818)
		(end 35.658552 -307.915818)
		(width 0.1651)
		(layer "In7.Cu")
		(net "P5E_PEX0_STN7_TX_DN<119>")
	)
	(segment
		(start 30.37205 -333.229712)
		(end 30.096968 -332.817978)
		(width 0.1651)
		(layer "In7.Cu")
		(net "P5E_PEX0_STN7_TX_DN<119>")
	)
	(segment
		(start 26.030174 -326.731884)
		(end 26.051256 -326.62622)
		(width 0.1651)
		(layer "In7.Cu")
		(net "P5E_PEX0_STN7_TX_DN<119>")
	)
	(segment
		(start 27.046174 -328.115168)
		(end 26.94051 -328.094086)
		(width 0.1651)
		(layer "In7.Cu")
		(net "P5E_PEX0_STN7_TX_DN<119>")
	)
	(segment
		(start 27.956764 -329.477624)
		(end 27.681428 -329.065636)
		(width 0.1651)
		(layer "In7.Cu")
		(net "P5E_PEX0_STN7_TX_DN<119>")
	)
	(segment
		(start 27.32151 -328.527156)
		(end 27.046174 -328.115168)
		(width 0.1651)
		(layer "In7.Cu")
		(net "P5E_PEX0_STN7_TX_DN<119>")
	)
	(segment
		(start 26.686256 -327.576688)
		(end 26.41092 -327.1647)
		(width 0.1651)
		(layer "In7.Cu")
		(net "P5E_PEX0_STN7_TX_DN<119>")
	)
	(segment
		(start 29.722826 -332.258162)
		(end 27.935936 -329.583288)
		(width 0.1651)
		(layer "In7.Cu")
		(net "P5E_PEX0_STN7_TX_DN<119>")
	)
	(segment
		(start 31.021274 -334.201262)
		(end 30.746192 -333.789528)
		(width 0.1651)
		(layer "In7.Cu")
		(net "P5E_PEX0_STN7_TX_DN<119>")
	)
	(segment
		(start 35.73272 -307.870098)
		(end 43.765216 -307.870098)
		(width 0.1143)
		(layer "In7.Cu")
		(net "P5E_PEX0_STN7_TX_DN<119>")
	)
	(segment
		(start 27.724354 -314.45708)
		(end 27.850084 -314.45708)
		(width 0.1651)
		(layer "In7.Cu")
		(net "P5E_PEX0_STN7_TX_DN<119>")
	)
	(segment
		(start 27.374342 -314.932822)
		(end 27.374342 -314.807092)
		(width 0.1651)
		(layer "In7.Cu")
		(net "P5E_PEX0_STN7_TX_DN<119>")
	)
	(segment
		(start 27.575764 -329.044554)
		(end 27.300682 -328.63282)
		(width 0.1651)
		(layer "In7.Cu")
		(net "P5E_PEX0_STN7_TX_DN<119>")
	)
	(segment
		(start 23.862284 -322.250562)
		(end 23.862284 -320.327528)
		(width 0.1651)
		(layer "In7.Cu")
		(net "P5E_PEX0_STN7_TX_DN<119>")
	)
	(segment
		(start 35.450018 -342.148668)
		(end 35.450018 -341.7951)
		(width 0.1651)
		(layer "In7.Cu")
		(net "P5E_PEX0_STN7_TX_DN<119>")
	)
	(segment
		(start 43.879516 -308.135528)
		(end 43.765216 -308.249828)
		(width 0.1143)
		(layer "In7.Cu")
		(net "P5E_PEX0_STN7_TX_DN<119>")
	)
	(segment
		(start 27.681428 -329.065636)
		(end 27.575764 -329.044554)
		(width 0.1651)
		(layer "In7.Cu")
		(net "P5E_PEX0_STN7_TX_DN<119>")
	)
	(segment
		(start 29.84627 -332.282546)
		(end 29.722826 -332.258162)
		(width 0.1651)
		(layer "In7.Cu")
		(net "P5E_PEX0_STN7_TX_DN<119>")
	)
	(segment
		(start 27.300682 -328.63282)
		(end 27.32151 -328.527156)
		(width 0.1651)
		(layer "In7.Cu")
		(net "P5E_PEX0_STN7_TX_DN<119>")
	)
	(segment
		(start 30.121606 -332.694788)
		(end 29.84627 -332.282546)
		(width 0.1651)
		(layer "In7.Cu")
		(net "P5E_PEX0_STN7_TX_DN<119>")
	)
	(segment
		(start 35.687 -307.915818)
		(end 35.73272 -307.870098)
		(width 0.1143)
		(layer "In7.Cu")
		(net "P5E_PEX0_STN7_TX_DN<119>")
	)
	(segment
		(start 25.213564 -316.968124)
		(end 26.898092 -315.283342)
		(width 0.1651)
		(layer "In7.Cu")
		(net "P5E_PEX0_STN7_TX_DN<119>")
	)
	(segment
		(start 26.94051 -328.094086)
		(end 26.665428 -327.682352)
		(width 0.1651)
		(layer "In7.Cu")
		(net "P5E_PEX0_STN7_TX_DN<119>")
	)
	(segment
		(start 28.200604 -313.98083)
		(end 33.948116 -308.233318)
		(width 0.1651)
		(layer "In7.Cu")
		(net "P5E_PEX0_STN7_TX_DN<119>")
	)
	(segment
		(start 23.982934 -319.721738)
		(end 24.10333 -319.116202)
		(width 0.1651)
		(layer "In7.Cu")
		(net "P5E_PEX0_STN7_TX_DN<119>")
	)
	(segment
		(start 26.051256 -326.62622)
		(end 25.77592 -326.213978)
		(width 0.1651)
		(layer "In7.Cu")
		(net "P5E_PEX0_STN7_TX_DN<119>")
	)
	(segment
		(start 35.34156 -341.38235)
		(end 34.998914 -340.542118)
		(width 0.1651)
		(layer "In7.Cu")
		(net "P5E_PEX0_STN7_TX_DN<119>")
	)
	(segment
		(start 27.374342 -314.807092)
		(end 27.724354 -314.45708)
		(width 0.1651)
		(layer "In7.Cu")
		(net "P5E_PEX0_STN7_TX_DN<119>")
	)
	(segment
		(start 26.41092 -327.1647)
		(end 26.305256 -327.143618)
		(width 0.1651)
		(layer "In7.Cu")
		(net "P5E_PEX0_STN7_TX_DN<119>")
	)
	(segment
		(start 43.765216 -308.249828)
		(end 43.499786 -308.249828)
		(width 0.1143)
		(layer "In7.Cu")
		(net "P5E_PEX0_STN7_TX_DN<119>")
	)
	(segment
		(start 30.746192 -333.789528)
		(end 30.77083 -333.666338)
		(width 0.1651)
		(layer "In7.Cu")
		(net "P5E_PEX0_STN7_TX_DN<119>")
	)
	(segment
		(start 31.395416 -334.761078)
		(end 31.420054 -334.637888)
		(width 0.1651)
		(layer "In7.Cu")
		(net "P5E_PEX0_STN7_TX_DN<119>")
	)
	(segment
		(start 35.740848 -342.439498)
		(end 35.450018 -342.148668)
		(width 0.1651)
		(layer "In7.Cu")
		(net "P5E_PEX0_STN7_TX_DN<119>")
	)
	(segment
		(start 30.096968 -332.817978)
		(end 30.121606 -332.694788)
		(width 0.1651)
		(layer "In7.Cu")
		(net "P5E_PEX0_STN7_TX_DN<119>")
	)
	(segment
		(start 28.200604 -314.10656)
		(end 28.200604 -313.98083)
		(width 0.1651)
		(layer "In7.Cu")
		(net "P5E_PEX0_STN7_TX_DN<119>")
	)
	(segment
		(start 24.63292 -317.83782)
		(end 25.213564 -316.968124)
		(width 0.1651)
		(layer "In7.Cu")
		(net "P5E_PEX0_STN7_TX_DN<119>")
	)
	(segment
		(start 24.10333 -319.116202)
		(end 24.63292 -317.83782)
		(width 0.1651)
		(layer "In7.Cu")
		(net "P5E_PEX0_STN7_TX_DN<119>")
	)
	(segment
		(start 30.77083 -333.666338)
		(end 30.495494 -333.254096)
		(width 0.1651)
		(layer "In7.Cu")
		(net "P5E_PEX0_STN7_TX_DN<119>")
	)
	(segment
		(start 31.144464 -334.225646)
		(end 31.021274 -334.201262)
		(width 0.1651)
		(layer "In7.Cu")
		(net "P5E_PEX0_STN7_TX_DN<119>")
	)
	(segment
		(start 23.862284 -320.327528)
		(end 23.982934 -319.721738)
		(width 0.1651)
		(layer "In7.Cu")
		(net "P5E_PEX0_STN7_TX_DN<119>")
	)
	(segment
		(start 26.665428 -327.682352)
		(end 26.686256 -327.576688)
		(width 0.1651)
		(layer "In7.Cu")
		(net "P5E_PEX0_STN7_TX_DN<119>")
	)
	(segment
		(start 27.023822 -315.283342)
		(end 27.374342 -314.932822)
		(width 0.1651)
		(layer "In7.Cu")
		(net "P5E_PEX0_STN7_TX_DN<119>")
	)
	(segment
		(start 27.850084 -314.45708)
		(end 28.200604 -314.10656)
		(width 0.1651)
		(layer "In7.Cu")
		(net "P5E_PEX0_STN7_TX_DN<119>")
	)
	(segment
		(start 33.948116 -308.233318)
		(end 34.714434 -307.915818)
		(width 0.1651)
		(layer "In7.Cu")
		(net "P5E_PEX0_STN7_TX_DN<119>")
	)
	(segment
		(start 43.765216 -307.870098)
		(end 43.879516 -307.984398)
		(width 0.1143)
		(layer "In7.Cu")
		(net "P5E_PEX0_STN7_TX_DN<119>")
	)
	(segment
		(start 158.051246 -357.776018)
		(end 153.56586 -324.562216)
		(width 0.1651)
		(layer "In9.Cu")
		(net "P5E_PEX1_STN7_RX_DP<122>")
	)
	(segment
		(start 164.43706 -382.980946)
		(end 164.775896 -382.980946)
		(width 0.1651)
		(layer "In9.Cu")
		(net "P5E_PEX1_STN7_RX_DP<122>")
	)
	(segment
		(start 153.56586 -324.562216)
		(end 153.56586 -318.950848)
		(width 0.1651)
		(layer "In9.Cu")
		(net "P5E_PEX1_STN7_RX_DP<122>")
	)
	(segment
		(start 164.31006 -383.490216)
		(end 164.31006 -383.107946)
		(width 0.1651)
		(layer "In9.Cu")
		(net "P5E_PEX1_STN7_RX_DP<122>")
	)
	(segment
		(start 153.56586 -318.9224)
		(end 153.52014 -318.87668)
		(width 0.1143)
		(layer "In9.Cu")
		(net "P5E_PEX1_STN7_RX_DP<122>")
	)
	(segment
		(start 165.47465 -368.273838)
		(end 165.300406 -367.753392)
		(width 0.1651)
		(layer "In9.Cu")
		(net "P5E_PEX1_STN7_RX_DP<122>")
	)
	(segment
		(start 158.430214 -358.637078)
		(end 158.051246 -357.776018)
		(width 0.1651)
		(layer "In9.Cu")
		(net "P5E_PEX1_STN7_RX_DP<122>")
	)
	(segment
		(start 153.60904 -316.799722)
		(end 153.89987 -316.799722)
		(width 0.1143)
		(layer "In9.Cu")
		(net "P5E_PEX1_STN7_RX_DP<122>")
	)
	(segment
		(start 165.300406 -367.753392)
		(end 158.430214 -358.637078)
		(width 0.1651)
		(layer "In9.Cu")
		(net "P5E_PEX1_STN7_RX_DP<122>")
	)
	(segment
		(start 164.31006 -383.107946)
		(end 164.43706 -382.980946)
		(width 0.1651)
		(layer "In9.Cu")
		(net "P5E_PEX1_STN7_RX_DP<122>")
	)
	(segment
		(start 153.52014 -316.888622)
		(end 153.60904 -316.799722)
		(width 0.1143)
		(layer "In9.Cu")
		(net "P5E_PEX1_STN7_RX_DP<122>")
	)
	(segment
		(start 153.56586 -318.950848)
		(end 153.56586 -318.9224)
		(width 0.1143)
		(layer "In9.Cu")
		(net "P5E_PEX1_STN7_RX_DP<122>")
	)
	(segment
		(start 164.775896 -382.980946)
		(end 165.47465 -382.282192)
		(width 0.1651)
		(layer "In9.Cu")
		(net "P5E_PEX1_STN7_RX_DP<122>")
	)
	(segment
		(start 153.52014 -318.87668)
		(end 153.52014 -316.888622)
		(width 0.1143)
		(layer "In9.Cu")
		(net "P5E_PEX1_STN7_RX_DP<122>")
	)
	(segment
		(start 165.47465 -382.282192)
		(end 165.47465 -368.273838)
		(width 0.1651)
		(layer "In9.Cu")
		(net "P5E_PEX1_STN7_RX_DP<122>")
	)
	(segment
		(start 411.57779 -113.251742)
		(end 411.57779 -112.630204)
		(width 0.13208)
		(layer "F.Cu")
		(net "RST_SMB_NIC7_MUX_ISO_N")
	)
	(segment
		(start 411.57779 -112.630204)
		(end 411.69717 -112.510824)
		(width 0.13208)
		(layer "F.Cu")
		(net "RST_SMB_NIC7_MUX_ISO_N")
	)
	(segment
		(start 411.57779 -115.283742)
		(end 411.57779 -114.267742)
		(width 0.13208)
		(layer "F.Cu")
		(net "RST_SMB_NIC7_MUX_ISO_N")
	)
	(segment
		(start 411.57779 -114.267742)
		(end 411.57779 -113.251742)
		(width 0.13208)
		(layer "F.Cu")
		(net "RST_SMB_NIC7_MUX_ISO_N")
	)
	(segment
		(start 411.69717 -112.510824)
		(end 412.48457 -112.510824)
		(width 0.13208)
		(layer "F.Cu")
		(net "RST_SMB_NIC7_MUX_ISO_N")
	)
	(via
		(at 412.48457 -112.510824)
		(size 0.508)
		(drill 0.254)
		(layers "F.Cu" "B.Cu")
		(net "RST_SMB_NIC7_MUX_ISO_N")
	)
	(segment
		(start 416.799268 -115.937284)
		(end 416.678618 -115.816634)
		(width 0.13208)
		(layer "B.Cu")
		(net "RST_SMB_NIC7_MUX_ISO_N")
	)
	(segment
		(start 416.799268 -116.513356)
		(end 416.799268 -115.937284)
		(width 0.13208)
		(layer "B.Cu")
		(net "RST_SMB_NIC7_MUX_ISO_N")
	)
	(segment
		(start 416.678618 -115.816634)
		(end 414.483804 -115.816634)
		(width 0.13208)
		(layer "B.Cu")
		(net "RST_SMB_NIC7_MUX_ISO_N")
	)
	(segment
		(start 413.159702 -112.510824)
		(end 412.48457 -112.510824)
		(width 0.13208)
		(layer "B.Cu")
		(net "RST_SMB_NIC7_MUX_ISO_N")
	)
	(segment
		(start 413.675068 -115.007898)
		(end 413.675068 -113.02619)
		(width 0.13208)
		(layer "B.Cu")
		(net "RST_SMB_NIC7_MUX_ISO_N")
	)
	(segment
		(start 414.483804 -115.816634)
		(end 413.675068 -115.007898)
		(width 0.13208)
		(layer "B.Cu")
		(net "RST_SMB_NIC7_MUX_ISO_N")
	)
	(segment
		(start 413.675068 -113.02619)
		(end 413.159702 -112.510824)
		(width 0.13208)
		(layer "B.Cu")
		(net "RST_SMB_NIC7_MUX_ISO_N")
	)
	(segment
		(start 35.4203 -108.8898)
		(end 35.12566 -109.18444)
		(width 0.13462)
		(layer "F.Cu")
		(net "P5E_PEX0_STN1_TX_DP<21>")
	)
	(segment
		(start 36.371784 -109.20984)
		(end 36.051744 -108.8898)
		(width 0.13462)
		(layer "F.Cu")
		(net "P5E_PEX0_STN1_TX_DP<21>")
	)
	(segment
		(start 36.051744 -108.8898)
		(end 35.4203 -108.8898)
		(width 0.13462)
		(layer "F.Cu")
		(net "P5E_PEX0_STN1_TX_DP<21>")
	)
	(segment
		(start 32.518858 -110.811818)
		(end 32.708342 -110.354364)
		(width 0.1651)
		(layer "In9.Cu")
		(net "P5E_PEX0_STN1_TX_DP<21>")
	)
	(segment
		(start 64.020192 -280.025856)
		(end 64.020192 -271.600168)
		(width 0.1143)
		(layer "In9.Cu")
		(net "P5E_PEX0_STN1_TX_DP<21>")
	)
	(segment
		(start 30.289246 -116.46027)
		(end 30.234128 -116.327428)
		(width 0.1651)
		(layer "In9.Cu")
		(net "P5E_PEX0_STN1_TX_DP<21>")
	)
	(segment
		(start 29.191712 -161.844736)
		(end 28.619196 -158.966408)
		(width 0.1651)
		(layer "In9.Cu")
		(net "P5E_PEX0_STN1_TX_DP<21>")
	)
	(segment
		(start 27.891994 -144.166082)
		(end 25.325832 -137.971022)
		(width 0.1651)
		(layer "In9.Cu")
		(net "P5E_PEX0_STN1_TX_DP<21>")
	)
	(segment
		(start 64.167512 -269.25905)
		(end 64.167512 -268.76375)
		(width 0.1651)
		(layer "In9.Cu")
		(net "P5E_PEX0_STN1_TX_DP<21>")
	)
	(segment
		(start 32.061912 -111.91494)
		(end 32.251396 -111.457486)
		(width 0.1651)
		(layer "In9.Cu")
		(net "P5E_PEX0_STN1_TX_DP<21>")
	)
	(segment
		(start 64.065912 -271.526)
		(end 64.065912 -269.36065)
		(width 0.1651)
		(layer "In9.Cu")
		(net "P5E_PEX0_STN1_TX_DP<21>")
	)
	(segment
		(start 34.169096 -108.89361)
		(end 34.83483 -108.89361)
		(width 0.1651)
		(layer "In9.Cu")
		(net "P5E_PEX0_STN1_TX_DP<21>")
	)
	(segment
		(start 64.399922 -279.749504)
		(end 64.399922 -280.015188)
		(width 0.1143)
		(layer "In9.Cu")
		(net "P5E_PEX0_STN1_TX_DP<21>")
	)
	(segment
		(start 64.167512 -268.76375)
		(end 64.065912 -268.66215)
		(width 0.1651)
		(layer "In9.Cu")
		(net "P5E_PEX0_STN1_TX_DP<21>")
	)
	(segment
		(start 31.013146 -114.711734)
		(end 31.203138 -114.254026)
		(width 0.1651)
		(layer "In9.Cu")
		(net "P5E_PEX0_STN1_TX_DP<21>")
	)
	(segment
		(start 64.285622 -280.129488)
		(end 64.123824 -280.129488)
		(width 0.1143)
		(layer "In9.Cu")
		(net "P5E_PEX0_STN1_TX_DP<21>")
	)
	(segment
		(start 32.11703 -112.047782)
		(end 32.061912 -111.91494)
		(width 0.1651)
		(layer "In9.Cu")
		(net "P5E_PEX0_STN1_TX_DP<21>")
	)
	(segment
		(start 31.927038 -112.50549)
		(end 32.11703 -112.047782)
		(width 0.1651)
		(layer "In9.Cu")
		(net "P5E_PEX0_STN1_TX_DP<21>")
	)
	(segment
		(start 64.065912 -264.873486)
		(end 29.191712 -161.844736)
		(width 0.1651)
		(layer "In9.Cu")
		(net "P5E_PEX0_STN1_TX_DP<21>")
	)
	(segment
		(start 64.065912 -271.554448)
		(end 64.065912 -271.526)
		(width 0.1143)
		(layer "In9.Cu")
		(net "P5E_PEX0_STN1_TX_DP<21>")
	)
	(segment
		(start 30.746192 -115.357148)
		(end 30.691074 -115.224306)
		(width 0.1651)
		(layer "In9.Cu")
		(net "P5E_PEX0_STN1_TX_DP<21>")
	)
	(segment
		(start 31.470092 -113.608612)
		(end 31.660084 -113.150904)
		(width 0.1651)
		(layer "In9.Cu")
		(net "P5E_PEX0_STN1_TX_DP<21>")
	)
	(segment
		(start 29.777182 -117.43055)
		(end 29.966666 -116.973096)
		(width 0.1651)
		(layer "In9.Cu")
		(net "P5E_PEX0_STN1_TX_DP<21>")
	)
	(segment
		(start 31.203138 -114.254026)
		(end 31.14802 -114.121184)
		(width 0.1651)
		(layer "In9.Cu")
		(net "P5E_PEX0_STN1_TX_DP<21>")
	)
	(segment
		(start 33.827974 -109.35335)
		(end 33.827974 -109.234732)
		(width 0.1651)
		(layer "In9.Cu")
		(net "P5E_PEX0_STN1_TX_DP<21>")
	)
	(segment
		(start 25.325832 -137.971022)
		(end 25.325832 -131.318762)
		(width 0.1651)
		(layer "In9.Cu")
		(net "P5E_PEX0_STN1_TX_DP<21>")
	)
	(segment
		(start 32.573976 -110.94466)
		(end 32.518858 -110.811818)
		(width 0.1651)
		(layer "In9.Cu")
		(net "P5E_PEX0_STN1_TX_DP<21>")
	)
	(segment
		(start 30.099254 -116.917978)
		(end 30.289246 -116.46027)
		(width 0.1651)
		(layer "In9.Cu")
		(net "P5E_PEX0_STN1_TX_DP<21>")
	)
	(segment
		(start 31.660084 -113.150904)
		(end 31.604966 -113.018062)
		(width 0.1651)
		(layer "In9.Cu")
		(net "P5E_PEX0_STN1_TX_DP<21>")
	)
	(segment
		(start 31.79445 -112.560608)
		(end 31.927038 -112.50549)
		(width 0.1651)
		(layer "In9.Cu")
		(net "P5E_PEX0_STN1_TX_DP<21>")
	)
	(segment
		(start 32.383984 -111.402368)
		(end 32.573976 -110.94466)
		(width 0.1651)
		(layer "In9.Cu")
		(net "P5E_PEX0_STN1_TX_DP<21>")
	)
	(segment
		(start 29.966666 -116.973096)
		(end 30.099254 -116.917978)
		(width 0.1651)
		(layer "In9.Cu")
		(net "P5E_PEX0_STN1_TX_DP<21>")
	)
	(segment
		(start 30.880558 -114.766852)
		(end 31.013146 -114.711734)
		(width 0.1651)
		(layer "In9.Cu")
		(net "P5E_PEX0_STN1_TX_DP<21>")
	)
	(segment
		(start 31.604966 -113.018062)
		(end 31.79445 -112.560608)
		(width 0.1651)
		(layer "In9.Cu")
		(net "P5E_PEX0_STN1_TX_DP<21>")
	)
	(segment
		(start 29.8323 -117.563392)
		(end 29.777182 -117.43055)
		(width 0.1651)
		(layer "In9.Cu")
		(net "P5E_PEX0_STN1_TX_DP<21>")
	)
	(segment
		(start 30.423612 -115.869974)
		(end 30.5562 -115.814856)
		(width 0.1651)
		(layer "In9.Cu")
		(net "P5E_PEX0_STN1_TX_DP<21>")
	)
	(segment
		(start 31.14802 -114.121184)
		(end 31.337504 -113.66373)
		(width 0.1651)
		(layer "In9.Cu")
		(net "P5E_PEX0_STN1_TX_DP<21>")
	)
	(segment
		(start 64.399922 -280.015188)
		(end 64.285622 -280.129488)
		(width 0.1143)
		(layer "In9.Cu")
		(net "P5E_PEX0_STN1_TX_DP<21>")
	)
	(segment
		(start 64.065912 -268.66215)
		(end 64.065912 -264.873486)
		(width 0.1651)
		(layer "In9.Cu")
		(net "P5E_PEX0_STN1_TX_DP<21>")
	)
	(segment
		(start 33.827974 -109.234732)
		(end 34.169096 -108.89361)
		(width 0.1651)
		(layer "In9.Cu")
		(net "P5E_PEX0_STN1_TX_DP<21>")
	)
	(segment
		(start 31.337504 -113.66373)
		(end 31.470092 -113.608612)
		(width 0.1651)
		(layer "In9.Cu")
		(net "P5E_PEX0_STN1_TX_DP<21>")
	)
	(segment
		(start 64.123824 -280.129488)
		(end 64.020192 -280.025856)
		(width 0.1143)
		(layer "In9.Cu")
		(net "P5E_PEX0_STN1_TX_DP<21>")
	)
	(segment
		(start 33.486344 -109.694726)
		(end 33.827974 -109.35335)
		(width 0.1651)
		(layer "In9.Cu")
		(net "P5E_PEX0_STN1_TX_DP<21>")
	)
	(segment
		(start 30.234128 -116.327428)
		(end 30.423612 -115.869974)
		(width 0.1651)
		(layer "In9.Cu")
		(net "P5E_PEX0_STN1_TX_DP<21>")
	)
	(segment
		(start 25.325832 -131.318762)
		(end 28.885642 -119.582946)
		(width 0.1651)
		(layer "In9.Cu")
		(net "P5E_PEX0_STN1_TX_DP<21>")
	)
	(segment
		(start 32.708342 -110.354364)
		(end 33.36798 -109.694726)
		(width 0.1651)
		(layer "In9.Cu")
		(net "P5E_PEX0_STN1_TX_DP<21>")
	)
	(segment
		(start 28.619196 -158.966408)
		(end 27.891994 -144.166082)
		(width 0.1651)
		(layer "In9.Cu")
		(net "P5E_PEX0_STN1_TX_DP<21>")
	)
	(segment
		(start 28.885642 -119.582946)
		(end 29.50972 -118.076218)
		(width 0.1651)
		(layer "In9.Cu")
		(net "P5E_PEX0_STN1_TX_DP<21>")
	)
	(segment
		(start 34.83483 -108.89361)
		(end 35.12566 -109.18444)
		(width 0.1651)
		(layer "In9.Cu")
		(net "P5E_PEX0_STN1_TX_DP<21>")
	)
	(segment
		(start 64.065912 -269.36065)
		(end 64.167512 -269.25905)
		(width 0.1651)
		(layer "In9.Cu")
		(net "P5E_PEX0_STN1_TX_DP<21>")
	)
	(segment
		(start 30.691074 -115.224306)
		(end 30.880558 -114.766852)
		(width 0.1651)
		(layer "In9.Cu")
		(net "P5E_PEX0_STN1_TX_DP<21>")
	)
	(segment
		(start 29.642308 -118.0211)
		(end 29.8323 -117.563392)
		(width 0.1651)
		(layer "In9.Cu")
		(net "P5E_PEX0_STN1_TX_DP<21>")
	)
	(segment
		(start 29.50972 -118.076218)
		(end 29.642308 -118.0211)
		(width 0.1651)
		(layer "In9.Cu")
		(net "P5E_PEX0_STN1_TX_DP<21>")
	)
	(segment
		(start 30.5562 -115.814856)
		(end 30.746192 -115.357148)
		(width 0.1651)
		(layer "In9.Cu")
		(net "P5E_PEX0_STN1_TX_DP<21>")
	)
	(segment
		(start 32.251396 -111.457486)
		(end 32.383984 -111.402368)
		(width 0.1651)
		(layer "In9.Cu")
		(net "P5E_PEX0_STN1_TX_DP<21>")
	)
	(segment
		(start 64.020192 -271.600168)
		(end 64.065912 -271.554448)
		(width 0.1143)
		(layer "In9.Cu")
		(net "P5E_PEX0_STN1_TX_DP<21>")
	)
	(segment
		(start 33.36798 -109.694726)
		(end 33.486344 -109.694726)
		(width 0.1651)
		(layer "In9.Cu")
		(net "P5E_PEX0_STN1_TX_DP<21>")
	)
	(segment
		(start 38.280848 -348.88043)
		(end 37.986208 -348.58579)
		(width 0.13462)
		(layer "F.Cu")
		(net "P5E_PEX0_STN7_TX_DN<121>")
	)
	(segment
		(start 38.280848 -349.511874)
		(end 38.280848 -348.88043)
		(width 0.13462)
		(layer "F.Cu")
		(net "P5E_PEX0_STN7_TX_DN<121>")
	)
	(segment
		(start 37.960808 -349.831914)
		(end 38.280848 -349.511874)
		(width 0.13462)
		(layer "F.Cu")
		(net "P5E_PEX0_STN7_TX_DN<121>")
	)
	(segment
		(start 37.115242 -312.049922)
		(end 36.849812 -312.049922)
		(width 0.1143)
		(layer "In7.Cu")
		(net "P5E_PEX0_STN7_TX_DN<121>")
	)
	(segment
		(start 37.115242 -312.429652)
		(end 37.229542 -312.315352)
		(width 0.1143)
		(layer "In7.Cu")
		(net "P5E_PEX0_STN7_TX_DN<121>")
	)
	(segment
		(start 37.229542 -312.164222)
		(end 37.115242 -312.049922)
		(width 0.1143)
		(layer "In7.Cu")
		(net "P5E_PEX0_STN7_TX_DN<121>")
	)
	(segment
		(start 35.029394 -322.667884)
		(end 35.09772 -322.539868)
		(width 0.1651)
		(layer "In7.Cu")
		(net "P5E_PEX0_STN7_TX_DN<121>")
	)
	(segment
		(start 34.0614 -316.091062)
		(end 34.590228 -314.613036)
		(width 0.1651)
		(layer "In7.Cu")
		(net "P5E_PEX0_STN7_TX_DN<121>")
	)
	(segment
		(start 35.302952 -323.215762)
		(end 35.174428 -323.147436)
		(width 0.1651)
		(layer "In7.Cu")
		(net "P5E_PEX0_STN7_TX_DN<121>")
	)
	(segment
		(start 38.863524 -334.952594)
		(end 35.302952 -323.215762)
		(width 0.1651)
		(layer "In7.Cu")
		(net "P5E_PEX0_STN7_TX_DN<121>")
	)
	(segment
		(start 38.277038 -347.541342)
		(end 39.831518 -345.986862)
		(width 0.1651)
		(layer "In7.Cu")
		(net "P5E_PEX0_STN7_TX_DN<121>")
	)
	(segment
		(start 36.209732 -312.717688)
		(end 36.27374 -312.717688)
		(width 0.1143)
		(layer "In7.Cu")
		(net "P5E_PEX0_STN7_TX_DN<121>")
	)
	(segment
		(start 34.752534 -321.402202)
		(end 34.61258 -320.94043)
		(width 0.1651)
		(layer "In7.Cu")
		(net "P5E_PEX0_STN7_TX_DN<121>")
	)
	(segment
		(start 34.957766 -322.078096)
		(end 34.858452 -322.025264)
		(width 0.1651)
		(layer "In7.Cu")
		(net "P5E_PEX0_STN7_TX_DN<121>")
	)
	(segment
		(start 36.561776 -312.429652)
		(end 37.115242 -312.429652)
		(width 0.1143)
		(layer "In7.Cu")
		(net "P5E_PEX0_STN7_TX_DN<121>")
	)
	(segment
		(start 35.174428 -323.147436)
		(end 35.029394 -322.667884)
		(width 0.1651)
		(layer "In7.Cu")
		(net "P5E_PEX0_STN7_TX_DN<121>")
	)
	(segment
		(start 36.189666 -312.737754)
		(end 36.209732 -312.717688)
		(width 0.1143)
		(layer "In7.Cu")
		(net "P5E_PEX0_STN7_TX_DN<121>")
	)
	(segment
		(start 35.09772 -322.539868)
		(end 34.957766 -322.078096)
		(width 0.1651)
		(layer "In7.Cu")
		(net "P5E_PEX0_STN7_TX_DN<121>")
	)
	(segment
		(start 38.277038 -348.29496)
		(end 38.277038 -347.541342)
		(width 0.1651)
		(layer "In7.Cu")
		(net "P5E_PEX0_STN7_TX_DN<121>")
	)
	(segment
		(start 37.986208 -348.58579)
		(end 38.277038 -348.29496)
		(width 0.1651)
		(layer "In7.Cu")
		(net "P5E_PEX0_STN7_TX_DN<121>")
	)
	(segment
		(start 34.61258 -320.94043)
		(end 34.0614 -318.168274)
		(width 0.1651)
		(layer "In7.Cu")
		(net "P5E_PEX0_STN7_TX_DN<121>")
	)
	(segment
		(start 34.858452 -322.025264)
		(end 34.699702 -321.501008)
		(width 0.1651)
		(layer "In7.Cu")
		(net "P5E_PEX0_STN7_TX_DN<121>")
	)
	(segment
		(start 34.0614 -318.168274)
		(end 34.0614 -316.091062)
		(width 0.1651)
		(layer "In7.Cu")
		(net "P5E_PEX0_STN7_TX_DN<121>")
	)
	(segment
		(start 37.229542 -312.315352)
		(end 37.229542 -312.164222)
		(width 0.1143)
		(layer "In7.Cu")
		(net "P5E_PEX0_STN7_TX_DN<121>")
	)
	(segment
		(start 36.27374 -312.717688)
		(end 36.561776 -312.429652)
		(width 0.1143)
		(layer "In7.Cu")
		(net "P5E_PEX0_STN7_TX_DN<121>")
	)
	(segment
		(start 35.854132 -313.073288)
		(end 36.189666 -312.737754)
		(width 0.1651)
		(layer "In7.Cu")
		(net "P5E_PEX0_STN7_TX_DN<121>")
	)
	(segment
		(start 34.699702 -321.501008)
		(end 34.752534 -321.402202)
		(width 0.1651)
		(layer "In7.Cu")
		(net "P5E_PEX0_STN7_TX_DN<121>")
	)
	(segment
		(start 39.831518 -341.477854)
		(end 38.863524 -334.952594)
		(width 0.1651)
		(layer "In7.Cu")
		(net "P5E_PEX0_STN7_TX_DN<121>")
	)
	(segment
		(start 39.831518 -345.986862)
		(end 39.831518 -341.477854)
		(width 0.1651)
		(layer "In7.Cu")
		(net "P5E_PEX0_STN7_TX_DN<121>")
	)
	(segment
		(start 34.590228 -314.613036)
		(end 35.854132 -313.073288)
		(width 0.1651)
		(layer "In7.Cu")
		(net "P5E_PEX0_STN7_TX_DN<121>")
	)
	(segment
		(start 153.60904 -310.149748)
		(end 153.52014 -310.238648)
		(width 0.1143)
		(layer "In9.Cu")
		(net "P5E_PEX1_STN7_RX_DP<121>")
	)
	(segment
		(start 152.688798 -310.719978)
		(end 152.529286 -310.87949)
		(width 0.1143)
		(layer "In9.Cu")
		(net "P5E_PEX1_STN7_RX_DP<121>")
	)
	(segment
		(start 151.53132 -316.798706)
		(end 157.10281 -358.055926)
		(width 0.1651)
		(layer "In9.Cu")
		(net "P5E_PEX1_STN7_RX_DP<121>")
	)
	(segment
		(start 153.89987 -310.149748)
		(end 153.60904 -310.149748)
		(width 0.1143)
		(layer "In9.Cu")
		(net "P5E_PEX1_STN7_RX_DP<121>")
	)
	(segment
		(start 162.109912 -384.191256)
		(end 162.109912 -384.590036)
		(width 0.1651)
		(layer "In9.Cu")
		(net "P5E_PEX1_STN7_RX_DP<121>")
	)
	(segment
		(start 163.116768 -368.440462)
		(end 163.11753 -368.44224)
		(width 0.1651)
		(layer "In9.Cu")
		(net "P5E_PEX1_STN7_RX_DP<121>")
	)
	(segment
		(start 163.12007 -368.443256)
		(end 163.266882 -369.153186)
		(width 0.1651)
		(layer "In9.Cu")
		(net "P5E_PEX1_STN7_RX_DP<121>")
	)
	(segment
		(start 163.266882 -369.153186)
		(end 163.266882 -383.389378)
		(width 0.1651)
		(layer "In9.Cu")
		(net "P5E_PEX1_STN7_RX_DP<121>")
	)
	(segment
		(start 152.529286 -310.87949)
		(end 152.529286 -310.944514)
		(width 0.1143)
		(layer "In9.Cu")
		(net "P5E_PEX1_STN7_RX_DP<121>")
	)
	(segment
		(start 162.236912 -384.064256)
		(end 162.109912 -384.191256)
		(width 0.1651)
		(layer "In9.Cu")
		(net "P5E_PEX1_STN7_RX_DP<121>")
	)
	(segment
		(start 152.50922 -310.96458)
		(end 151.53132 -311.94248)
		(width 0.1651)
		(layer "In9.Cu")
		(net "P5E_PEX1_STN7_RX_DP<121>")
	)
	(segment
		(start 163.266882 -383.389378)
		(end 162.592004 -384.064256)
		(width 0.1651)
		(layer "In9.Cu")
		(net "P5E_PEX1_STN7_RX_DP<121>")
	)
	(segment
		(start 157.10281 -358.055926)
		(end 157.592014 -359.167176)
		(width 0.1651)
		(layer "In9.Cu")
		(net "P5E_PEX1_STN7_RX_DP<121>")
	)
	(segment
		(start 153.52014 -310.443372)
		(end 153.243534 -310.719978)
		(width 0.1143)
		(layer "In9.Cu")
		(net "P5E_PEX1_STN7_RX_DP<121>")
	)
	(segment
		(start 153.243534 -310.719978)
		(end 152.688798 -310.719978)
		(width 0.1143)
		(layer "In9.Cu")
		(net "P5E_PEX1_STN7_RX_DP<121>")
	)
	(segment
		(start 151.53132 -311.94248)
		(end 151.53132 -316.798706)
		(width 0.1651)
		(layer "In9.Cu")
		(net "P5E_PEX1_STN7_RX_DP<121>")
	)
	(segment
		(start 157.592014 -359.167176)
		(end 162.934396 -367.957608)
		(width 0.1651)
		(layer "In9.Cu")
		(net "P5E_PEX1_STN7_RX_DP<121>")
	)
	(segment
		(start 152.529286 -310.944514)
		(end 152.50922 -310.96458)
		(width 0.1143)
		(layer "In9.Cu")
		(net "P5E_PEX1_STN7_RX_DP<121>")
	)
	(segment
		(start 163.11753 -368.44224)
		(end 163.12007 -368.443256)
		(width 0.1651)
		(layer "In9.Cu")
		(net "P5E_PEX1_STN7_RX_DP<121>")
	)
	(segment
		(start 162.934396 -367.957608)
		(end 163.116768 -368.440462)
		(width 0.1651)
		(layer "In9.Cu")
		(net "P5E_PEX1_STN7_RX_DP<121>")
	)
	(segment
		(start 153.52014 -310.238648)
		(end 153.52014 -310.443372)
		(width 0.1143)
		(layer "In9.Cu")
		(net "P5E_PEX1_STN7_RX_DP<121>")
	)
	(segment
		(start 162.592004 -384.064256)
		(end 162.236912 -384.064256)
		(width 0.1651)
		(layer "In9.Cu")
		(net "P5E_PEX1_STN7_RX_DP<121>")
	)
	(via
		(at 414.1851 -112.53089)
		(size 0.6604)
		(drill 0.3302)
		(layers "F.Cu" "B.Cu")
		(net "RST_SMB_NIC7_MUX_N")
	)
	(segment
		(start 414.834324 -114.021616)
		(end 417.292282 -114.021616)
		(width 0.13208)
		(layer "B.Cu")
		(net "RST_SMB_NIC7_MUX_N")
	)
	(segment
		(start 414.1851 -112.478312)
		(end 414.1851 -112.53089)
		(width 0.13208)
		(layer "B.Cu")
		(net "RST_SMB_NIC7_MUX_N")
	)
	(segment
		(start 417.292282 -114.021616)
		(end 417.54933 -114.278664)
		(width 0.13208)
		(layer "B.Cu")
		(net "RST_SMB_NIC7_MUX_N")
	)
	(segment
		(start 417.54933 -114.278664)
		(end 417.54933 -114.713512)
		(width 0.13208)
		(layer "B.Cu")
		(net "RST_SMB_NIC7_MUX_N")
	)
	(segment
		(start 414.776666 -111.334042)
		(end 414.776666 -111.886746)
		(width 0.13208)
		(layer "B.Cu")
		(net "RST_SMB_NIC7_MUX_N")
	)
	(segment
		(start 414.776666 -111.886746)
		(end 414.1851 -112.478312)
		(width 0.13208)
		(layer "B.Cu")
		(net "RST_SMB_NIC7_MUX_N")
	)
	(segment
		(start 414.1851 -113.372392)
		(end 414.834324 -114.021616)
		(width 0.13208)
		(layer "B.Cu")
		(net "RST_SMB_NIC7_MUX_N")
	)
	(segment
		(start 414.1851 -112.53089)
		(end 414.1851 -113.372392)
		(width 0.13208)
		(layer "B.Cu")
		(net "RST_SMB_NIC7_MUX_N")
	)
	(segment
		(start 82.928206 -152.511252)
		(end 83.248246 -152.191212)
		(width 0.13462)
		(layer "F.Cu")
		(net "P5E_PEX0_STN0_TX_DP<13>")
	)
	(segment
		(start 83.87969 -152.191212)
		(end 84.17433 -152.485852)
		(width 0.13462)
		(layer "F.Cu")
		(net "P5E_PEX0_STN0_TX_DP<13>")
	)
	(segment
		(start 83.248246 -152.191212)
		(end 83.87969 -152.191212)
		(width 0.13462)
		(layer "F.Cu")
		(net "P5E_PEX0_STN0_TX_DP<13>")
	)
	(segment
		(start 86.248494 -153.873454)
		(end 86.276688 -153.732484)
		(width 0.1651)
		(layer "In9.Cu")
		(net "P5E_PEX0_STN0_TX_DP<13>")
	)
	(segment
		(start 76.17968 -271.546066)
		(end 76.13396 -271.500346)
		(width 0.1143)
		(layer "In9.Cu")
		(net "P5E_PEX0_STN0_TX_DP<13>")
	)
	(segment
		(start 86.050882 -153.394664)
		(end 86.051136 -153.394664)
		(width 0.1651)
		(layer "In9.Cu")
		(net "P5E_PEX0_STN0_TX_DP<13>")
	)
	(segment
		(start 76.13396 -271.500346)
		(end 76.13396 -271.471898)
		(width 0.1143)
		(layer "In9.Cu")
		(net "P5E_PEX0_STN0_TX_DP<13>")
	)
	(segment
		(start 76.394564 -278.420068)
		(end 76.17968 -278.205184)
		(width 0.1143)
		(layer "In9.Cu")
		(net "P5E_PEX0_STN0_TX_DP<13>")
	)
	(segment
		(start 87.308944 -155.632658)
		(end 86.921848 -154.697938)
		(width 0.1651)
		(layer "In9.Cu")
		(net "P5E_PEX0_STN0_TX_DP<13>")
	)
	(segment
		(start 77.043788 -260.763004)
		(end 73.597516 -221.36227)
		(width 0.1651)
		(layer "In9.Cu")
		(net "P5E_PEX0_STN0_TX_DP<13>")
	)
	(segment
		(start 85.712046 -152.88768)
		(end 85.486494 -152.54986)
		(width 0.1651)
		(layer "In9.Cu")
		(net "P5E_PEX0_STN0_TX_DP<13>")
	)
	(segment
		(start 76.749656 -278.534368)
		(end 76.635356 -278.420068)
		(width 0.1143)
		(layer "In9.Cu")
		(net "P5E_PEX0_STN0_TX_DP<13>")
	)
	(segment
		(start 85.684106 -153.02865)
		(end 85.712046 -152.88768)
		(width 0.1651)
		(layer "In9.Cu")
		(net "P5E_PEX0_STN0_TX_DP<13>")
	)
	(segment
		(start 85.910166 -153.366724)
		(end 85.684106 -153.02865)
		(width 0.1651)
		(layer "In9.Cu")
		(net "P5E_PEX0_STN0_TX_DP<13>")
	)
	(segment
		(start 86.474554 -154.211528)
		(end 86.248494 -153.873454)
		(width 0.1651)
		(layer "In9.Cu")
		(net "P5E_PEX0_STN0_TX_DP<13>")
	)
	(segment
		(start 86.051136 -153.394664)
		(end 85.910166 -153.366724)
		(width 0.1651)
		(layer "In9.Cu")
		(net "P5E_PEX0_STN0_TX_DP<13>")
	)
	(segment
		(start 76.13396 -271.471898)
		(end 76.13396 -269.98803)
		(width 0.1651)
		(layer "In9.Cu")
		(net "P5E_PEX0_STN0_TX_DP<13>")
	)
	(segment
		(start 76.749656 -278.799798)
		(end 76.749656 -278.534368)
		(width 0.1143)
		(layer "In9.Cu")
		(net "P5E_PEX0_STN0_TX_DP<13>")
	)
	(segment
		(start 76.635356 -278.420068)
		(end 76.394564 -278.420068)
		(width 0.1143)
		(layer "In9.Cu")
		(net "P5E_PEX0_STN0_TX_DP<13>")
	)
	(segment
		(start 77.043788 -267.79093)
		(end 77.043788 -260.763004)
		(width 0.1651)
		(layer "In9.Cu")
		(net "P5E_PEX0_STN0_TX_DP<13>")
	)
	(segment
		(start 84.46516 -152.195022)
		(end 84.17433 -152.485852)
		(width 0.1651)
		(layer "In9.Cu")
		(net "P5E_PEX0_STN0_TX_DP<13>")
	)
	(segment
		(start 86.921848 -154.697938)
		(end 86.615524 -154.239468)
		(width 0.1651)
		(layer "In9.Cu")
		(net "P5E_PEX0_STN0_TX_DP<13>")
	)
	(segment
		(start 86.276688 -153.732484)
		(end 86.050882 -153.394664)
		(width 0.1651)
		(layer "In9.Cu")
		(net "P5E_PEX0_STN0_TX_DP<13>")
	)
	(segment
		(start 76.13396 -269.98803)
		(end 77.043788 -267.79093)
		(width 0.1651)
		(layer "In9.Cu")
		(net "P5E_PEX0_STN0_TX_DP<13>")
	)
	(segment
		(start 86.615524 -154.239468)
		(end 86.474554 -154.211528)
		(width 0.1651)
		(layer "In9.Cu")
		(net "P5E_PEX0_STN0_TX_DP<13>")
	)
	(segment
		(start 85.131656 -152.195022)
		(end 84.46516 -152.195022)
		(width 0.1651)
		(layer "In9.Cu")
		(net "P5E_PEX0_STN0_TX_DP<13>")
	)
	(segment
		(start 78.938374 -171.523152)
		(end 87.308944 -157.023562)
		(width 0.1651)
		(layer "In9.Cu")
		(net "P5E_PEX0_STN0_TX_DP<13>")
	)
	(segment
		(start 73.597516 -221.36227)
		(end 77.483462 -176.952402)
		(width 0.1651)
		(layer "In9.Cu")
		(net "P5E_PEX0_STN0_TX_DP<13>")
	)
	(segment
		(start 87.308944 -157.023562)
		(end 87.308944 -155.632658)
		(width 0.1651)
		(layer "In9.Cu")
		(net "P5E_PEX0_STN0_TX_DP<13>")
	)
	(segment
		(start 76.17968 -278.205184)
		(end 76.17968 -271.546066)
		(width 0.1143)
		(layer "In9.Cu")
		(net "P5E_PEX0_STN0_TX_DP<13>")
	)
	(segment
		(start 77.483462 -176.952402)
		(end 78.938374 -171.523152)
		(width 0.1651)
		(layer "In9.Cu")
		(net "P5E_PEX0_STN0_TX_DP<13>")
	)
	(segment
		(start 85.486494 -152.54986)
		(end 85.131656 -152.195022)
		(width 0.1651)
		(layer "In9.Cu")
		(net "P5E_PEX0_STN0_TX_DP<13>")
	)
	(segment
		(start 25.524968 -349.831914)
		(end 25.845008 -349.511874)
		(width 0.13462)
		(layer "F.Cu")
		(net "P5E_PEX0_STN7_TX_DP<115>")
	)
	(segment
		(start 25.845008 -348.88043)
		(end 25.550368 -348.58579)
		(width 0.13462)
		(layer "F.Cu")
		(net "P5E_PEX0_STN7_TX_DP<115>")
	)
	(segment
		(start 25.845008 -349.511874)
		(end 25.845008 -348.88043)
		(width 0.13462)
		(layer "F.Cu")
		(net "P5E_PEX0_STN7_TX_DP<115>")
	)
	(segment
		(start 19.760184 -323.239638)
		(end 19.760184 -319.917064)
		(width 0.1651)
		(layer "In7.Cu")
		(net "P5E_PEX0_STN7_TX_DP<115>")
	)
	(segment
		(start 27.395678 -341.673434)
		(end 19.760184 -323.239638)
		(width 0.1651)
		(layer "In7.Cu")
		(net "P5E_PEX0_STN7_TX_DP<115>")
	)
	(segment
		(start 35.687 -303.833784)
		(end 35.73272 -303.879504)
		(width 0.1143)
		(layer "In7.Cu")
		(net "P5E_PEX0_STN7_TX_DP<115>")
	)
	(segment
		(start 25.550368 -348.58579)
		(end 25.841198 -348.29496)
		(width 0.1651)
		(layer "In7.Cu")
		(net "P5E_PEX0_STN7_TX_DP<115>")
	)
	(segment
		(start 44.184316 -304.449734)
		(end 44.449746 -304.449734)
		(width 0.1143)
		(layer "In7.Cu")
		(net "P5E_PEX0_STN7_TX_DP<115>")
	)
	(segment
		(start 26.062686 -307.904134)
		(end 28.767278 -305.199542)
		(width 0.1651)
		(layer "In7.Cu")
		(net "P5E_PEX0_STN7_TX_DP<115>")
	)
	(segment
		(start 21.18233 -315.207904)
		(end 26.062686 -307.904134)
		(width 0.1651)
		(layer "In7.Cu")
		(net "P5E_PEX0_STN7_TX_DP<115>")
	)
	(segment
		(start 35.658552 -303.833784)
		(end 35.687 -303.833784)
		(width 0.1143)
		(layer "In7.Cu")
		(net "P5E_PEX0_STN7_TX_DP<115>")
	)
	(segment
		(start 25.841198 -348.29496)
		(end 25.841198 -347.541342)
		(width 0.1651)
		(layer "In7.Cu")
		(net "P5E_PEX0_STN7_TX_DP<115>")
	)
	(segment
		(start 28.767278 -305.199542)
		(end 32.064452 -303.833784)
		(width 0.1651)
		(layer "In7.Cu")
		(net "P5E_PEX0_STN7_TX_DP<115>")
	)
	(segment
		(start 20.248118 -317.462916)
		(end 21.18233 -315.207904)
		(width 0.1651)
		(layer "In7.Cu")
		(net "P5E_PEX0_STN7_TX_DP<115>")
	)
	(segment
		(start 27.395678 -345.986862)
		(end 27.395678 -341.673434)
		(width 0.1651)
		(layer "In7.Cu")
		(net "P5E_PEX0_STN7_TX_DP<115>")
	)
	(segment
		(start 32.064452 -303.833784)
		(end 35.658552 -303.833784)
		(width 0.1651)
		(layer "In7.Cu")
		(net "P5E_PEX0_STN7_TX_DP<115>")
	)
	(segment
		(start 44.070016 -304.10531)
		(end 44.070016 -304.335434)
		(width 0.1143)
		(layer "In7.Cu")
		(net "P5E_PEX0_STN7_TX_DP<115>")
	)
	(segment
		(start 44.070016 -304.335434)
		(end 44.184316 -304.449734)
		(width 0.1143)
		(layer "In7.Cu")
		(net "P5E_PEX0_STN7_TX_DP<115>")
	)
	(segment
		(start 25.841198 -347.541342)
		(end 27.395678 -345.986862)
		(width 0.1651)
		(layer "In7.Cu")
		(net "P5E_PEX0_STN7_TX_DP<115>")
	)
	(segment
		(start 19.760184 -319.917064)
		(end 20.248118 -317.462916)
		(width 0.1651)
		(layer "In7.Cu")
		(net "P5E_PEX0_STN7_TX_DP<115>")
	)
	(segment
		(start 43.84421 -303.879504)
		(end 44.070016 -304.10531)
		(width 0.1143)
		(layer "In7.Cu")
		(net "P5E_PEX0_STN7_TX_DP<115>")
	)
	(segment
		(start 35.73272 -303.879504)
		(end 43.84421 -303.879504)
		(width 0.1143)
		(layer "In7.Cu")
		(net "P5E_PEX0_STN7_TX_DP<115>")
	)
	(segment
		(start 146.803872 -360.8197)
		(end 148.456904 -358.84358)
		(width 0.1651)
		(layer "In15.Cu")
		(net "P5E_PEX1_STN5_RX_DN<95>")
	)
	(segment
		(start 131.775454 -372.381018)
		(end 132.499862 -371.65661)
		(width 0.1651)
		(layer "In15.Cu")
		(net "P5E_PEX1_STN5_RX_DN<95>")
	)
	(segment
		(start 131.437126 -372.381018)
		(end 131.775454 -372.381018)
		(width 0.1651)
		(layer "In15.Cu")
		(net "P5E_PEX1_STN5_RX_DN<95>")
	)
	(segment
		(start 189.049914 -318.409066)
		(end 189.049914 -318.699896)
		(width 0.1143)
		(layer "In15.Cu")
		(net "P5E_PEX1_STN5_RX_DN<95>")
	)
	(segment
		(start 188.715904 -319.916048)
		(end 188.715904 -319.8876)
		(width 0.1143)
		(layer "In15.Cu")
		(net "P5E_PEX1_STN5_RX_DN<95>")
	)
	(segment
		(start 188.715904 -321.553332)
		(end 188.715904 -319.916048)
		(width 0.1651)
		(layer "In15.Cu")
		(net "P5E_PEX1_STN5_RX_DN<95>")
	)
	(segment
		(start 131.310126 -372.890034)
		(end 131.310126 -372.508018)
		(width 0.1651)
		(layer "In15.Cu")
		(net "P5E_PEX1_STN5_RX_DN<95>")
	)
	(segment
		(start 163.566094 -342.49487)
		(end 163.566856 -342.494362)
		(width 0.1651)
		(layer "In15.Cu")
		(net "P5E_PEX1_STN5_RX_DN<95>")
	)
	(segment
		(start 188.670184 -318.485266)
		(end 188.835284 -318.320166)
		(width 0.1143)
		(layer "In15.Cu")
		(net "P5E_PEX1_STN5_RX_DN<95>")
	)
	(segment
		(start 163.566856 -342.494362)
		(end 163.566856 -342.494108)
		(width 0.1651)
		(layer "In15.Cu")
		(net "P5E_PEX1_STN5_RX_DN<95>")
	)
	(segment
		(start 143.936974 -363.060234)
		(end 146.803872 -360.8197)
		(width 0.1651)
		(layer "In15.Cu")
		(net "P5E_PEX1_STN5_RX_DN<95>")
	)
	(segment
		(start 188.961014 -318.320166)
		(end 189.049914 -318.409066)
		(width 0.1143)
		(layer "In15.Cu")
		(net "P5E_PEX1_STN5_RX_DN<95>")
	)
	(segment
		(start 163.566856 -342.494108)
		(end 169.720006 -337.375754)
		(width 0.1651)
		(layer "In15.Cu")
		(net "P5E_PEX1_STN5_RX_DN<95>")
	)
	(segment
		(start 182.842662 -328.67346)
		(end 187.179966 -324.336156)
		(width 0.1651)
		(layer "In15.Cu")
		(net "P5E_PEX1_STN5_RX_DN<95>")
	)
	(segment
		(start 148.456904 -358.84358)
		(end 163.566094 -342.49487)
		(width 0.1651)
		(layer "In15.Cu")
		(net "P5E_PEX1_STN5_RX_DN<95>")
	)
	(segment
		(start 188.835284 -318.320166)
		(end 188.961014 -318.320166)
		(width 0.1143)
		(layer "In15.Cu")
		(net "P5E_PEX1_STN5_RX_DN<95>")
	)
	(segment
		(start 188.715904 -319.8876)
		(end 188.670184 -319.84188)
		(width 0.1143)
		(layer "In15.Cu")
		(net "P5E_PEX1_STN5_RX_DN<95>")
	)
	(segment
		(start 188.418724 -322.324476)
		(end 188.715904 -321.553332)
		(width 0.1651)
		(layer "In15.Cu")
		(net "P5E_PEX1_STN5_RX_DN<95>")
	)
	(segment
		(start 187.179966 -324.336156)
		(end 188.418724 -322.324476)
		(width 0.1651)
		(layer "In15.Cu")
		(net "P5E_PEX1_STN5_RX_DN<95>")
	)
	(segment
		(start 132.499862 -371.65661)
		(end 132.499862 -369.23726)
		(width 0.1651)
		(layer "In15.Cu")
		(net "P5E_PEX1_STN5_RX_DN<95>")
	)
	(segment
		(start 133.357874 -368.20475)
		(end 143.936974 -363.060234)
		(width 0.1651)
		(layer "In15.Cu")
		(net "P5E_PEX1_STN5_RX_DN<95>")
	)
	(segment
		(start 132.872988 -368.640868)
		(end 133.357874 -368.20475)
		(width 0.1651)
		(layer "In15.Cu")
		(net "P5E_PEX1_STN5_RX_DN<95>")
	)
	(segment
		(start 188.670184 -319.84188)
		(end 188.670184 -318.485266)
		(width 0.1143)
		(layer "In15.Cu")
		(net "P5E_PEX1_STN5_RX_DN<95>")
	)
	(segment
		(start 131.310126 -372.508018)
		(end 131.437126 -372.381018)
		(width 0.1651)
		(layer "In15.Cu")
		(net "P5E_PEX1_STN5_RX_DN<95>")
	)
	(segment
		(start 169.720006 -337.375754)
		(end 182.842662 -328.67346)
		(width 0.1651)
		(layer "In15.Cu")
		(net "P5E_PEX1_STN5_RX_DN<95>")
	)
	(segment
		(start 132.499862 -369.23726)
		(end 132.872988 -368.640868)
		(width 0.1651)
		(layer "In15.Cu")
		(net "P5E_PEX1_STN5_RX_DN<95>")
	)
	(segment
		(start 36.051744 -108.61548)
		(end 35.4203 -108.61548)
		(width 0.13462)
		(layer "F.Cu")
		(net "P5E_PEX0_STN1_TX_DN<21>")
	)
	(segment
		(start 36.371784 -108.29544)
		(end 36.051744 -108.61548)
		(width 0.13462)
		(layer "F.Cu")
		(net "P5E_PEX0_STN1_TX_DN<21>")
	)
	(segment
		(start 35.4203 -108.61548)
		(end 35.12566 -108.32084)
		(width 0.13462)
		(layer "F.Cu")
		(net "P5E_PEX0_STN1_TX_DN<21>")
	)
	(segment
		(start 63.783972 -264.919968)
		(end 63.783972 -271.526)
		(width 0.1651)
		(layer "In9.Cu")
		(net "P5E_PEX0_STN1_TX_DN<21>")
	)
	(segment
		(start 64.399922 -280.434288)
		(end 64.399922 -280.699718)
		(width 0.1143)
		(layer "In9.Cu")
		(net "P5E_PEX0_STN1_TX_DN<21>")
	)
	(segment
		(start 63.783972 -271.526)
		(end 63.783972 -271.554448)
		(width 0.1143)
		(layer "In9.Cu")
		(net "P5E_PEX0_STN1_TX_DN<21>")
	)
	(segment
		(start 63.829692 -271.600168)
		(end 63.829692 -280.10485)
		(width 0.1143)
		(layer "In9.Cu")
		(net "P5E_PEX0_STN1_TX_DN<21>")
	)
	(segment
		(start 63.829692 -280.10485)
		(end 64.04483 -280.319988)
		(width 0.1143)
		(layer "In9.Cu")
		(net "P5E_PEX0_STN1_TX_DN<21>")
	)
	(segment
		(start 34.83483 -108.61167)
		(end 34.052256 -108.61167)
		(width 0.1651)
		(layer "In9.Cu")
		(net "P5E_PEX0_STN1_TX_DN<21>")
	)
	(segment
		(start 64.285622 -280.319988)
		(end 64.399922 -280.434288)
		(width 0.1143)
		(layer "In9.Cu")
		(net "P5E_PEX0_STN1_TX_DN<21>")
	)
	(segment
		(start 25.043892 -138.027156)
		(end 27.612594 -144.22882)
		(width 0.1651)
		(layer "In9.Cu")
		(net "P5E_PEX0_STN1_TX_DN<21>")
	)
	(segment
		(start 27.612594 -144.22882)
		(end 28.156408 -155.297378)
		(width 0.1651)
		(layer "In9.Cu")
		(net "P5E_PEX0_STN1_TX_DN<21>")
	)
	(segment
		(start 34.052256 -108.61167)
		(end 32.469328 -110.194598)
		(width 0.1651)
		(layer "In9.Cu")
		(net "P5E_PEX0_STN1_TX_DN<21>")
	)
	(segment
		(start 28.156408 -155.297378)
		(end 28.338526 -159.000952)
		(width 0.1651)
		(layer "In9.Cu")
		(net "P5E_PEX0_STN1_TX_DN<21>")
	)
	(segment
		(start 64.04483 -280.319988)
		(end 64.285622 -280.319988)
		(width 0.1143)
		(layer "In9.Cu")
		(net "P5E_PEX0_STN1_TX_DN<21>")
	)
	(segment
		(start 25.043892 -131.276852)
		(end 25.043892 -138.027156)
		(width 0.1651)
		(layer "In9.Cu")
		(net "P5E_PEX0_STN1_TX_DN<21>")
	)
	(segment
		(start 28.338526 -159.000952)
		(end 28.918662 -161.917634)
		(width 0.1651)
		(layer "In9.Cu")
		(net "P5E_PEX0_STN1_TX_DN<21>")
	)
	(segment
		(start 63.783972 -271.554448)
		(end 63.829692 -271.600168)
		(width 0.1143)
		(layer "In9.Cu")
		(net "P5E_PEX0_STN1_TX_DN<21>")
	)
	(segment
		(start 35.12566 -108.32084)
		(end 34.83483 -108.61167)
		(width 0.1651)
		(layer "In9.Cu")
		(net "P5E_PEX0_STN1_TX_DN<21>")
	)
	(segment
		(start 28.918662 -161.917634)
		(end 63.783972 -264.919968)
		(width 0.1651)
		(layer "In9.Cu")
		(net "P5E_PEX0_STN1_TX_DN<21>")
	)
	(segment
		(start 32.469328 -110.194598)
		(end 28.619704 -119.487696)
		(width 0.1651)
		(layer "In9.Cu")
		(net "P5E_PEX0_STN1_TX_DN<21>")
	)
	(segment
		(start 28.619704 -119.487696)
		(end 25.043892 -131.276852)
		(width 0.1651)
		(layer "In9.Cu")
		(net "P5E_PEX0_STN1_TX_DN<21>")
	)
	(segment
		(start 152.393904 -310.745378)
		(end 152.329896 -310.745124)
		(width 0.1143)
		(layer "In9.Cu")
		(net "P5E_PEX1_STN7_RX_DN<121>")
	)
	(segment
		(start 160.721294 -365.028988)
		(end 160.842452 -365.058452)
		(width 0.1651)
		(layer "In9.Cu")
		(net "P5E_PEX1_STN7_RX_DN<121>")
	)
	(segment
		(start 162.852862 -368.540284)
		(end 162.853624 -368.542062)
		(width 0.1651)
		(layer "In9.Cu")
		(net "P5E_PEX1_STN7_RX_DN<121>")
	)
	(segment
		(start 162.236912 -383.782316)
		(end 162.109912 -383.655316)
		(width 0.1651)
		(layer "In9.Cu")
		(net "P5E_PEX1_STN7_RX_DN<121>")
	)
	(segment
		(start 161.06521 -365.621316)
		(end 161.322766 -366.044734)
		(width 0.1651)
		(layer "In9.Cu")
		(net "P5E_PEX1_STN7_RX_DN<121>")
	)
	(segment
		(start 162.679126 -368.080544)
		(end 162.67938 -368.081306)
		(width 0.1651)
		(layer "In9.Cu")
		(net "P5E_PEX1_STN7_RX_DN<121>")
	)
	(segment
		(start 162.109912 -383.655316)
		(end 162.109912 -383.290064)
		(width 0.1651)
		(layer "In9.Cu")
		(net "P5E_PEX1_STN7_RX_DN<121>")
	)
	(segment
		(start 152.30983 -310.76519)
		(end 151.24938 -311.82564)
		(width 0.1651)
		(layer "In9.Cu")
		(net "P5E_PEX1_STN7_RX_DN<121>")
	)
	(segment
		(start 152.94991 -310.149748)
		(end 153.24074 -310.149748)
		(width 0.1143)
		(layer "In9.Cu")
		(net "P5E_PEX1_STN7_RX_DN<121>")
	)
	(segment
		(start 162.984942 -383.272538)
		(end 162.475164 -383.782316)
		(width 0.1651)
		(layer "In9.Cu")
		(net "P5E_PEX1_STN7_RX_DN<121>")
	)
	(segment
		(start 162.8521 -368.54257)
		(end 162.852862 -368.544348)
		(width 0.1651)
		(layer "In9.Cu")
		(net "P5E_PEX1_STN7_RX_DN<121>")
	)
	(segment
		(start 161.462466 -366.07877)
		(end 161.719514 -366.501934)
		(width 0.1651)
		(layer "In9.Cu")
		(net "P5E_PEX1_STN7_RX_DN<121>")
	)
	(segment
		(start 151.24938 -315.19495)
		(end 151.14778 -315.29655)
		(width 0.1651)
		(layer "In9.Cu")
		(net "P5E_PEX1_STN7_RX_DN<121>")
	)
	(segment
		(start 153.24074 -310.149748)
		(end 153.32964 -310.238648)
		(width 0.1143)
		(layer "In9.Cu")
		(net "P5E_PEX1_STN7_RX_DN<121>")
	)
	(segment
		(start 161.719514 -366.501934)
		(end 161.685478 -366.64138)
		(width 0.1651)
		(layer "In9.Cu")
		(net "P5E_PEX1_STN7_RX_DN<121>")
	)
	(segment
		(start 151.24938 -315.89345)
		(end 151.24938 -316.817756)
		(width 0.1651)
		(layer "In9.Cu")
		(net "P5E_PEX1_STN7_RX_DN<121>")
	)
	(segment
		(start 162.082734 -367.099088)
		(end 162.679126 -368.080544)
		(width 0.1651)
		(layer "In9.Cu")
		(net "P5E_PEX1_STN7_RX_DN<121>")
	)
	(segment
		(start 161.943034 -367.065052)
		(end 162.082734 -367.099088)
		(width 0.1651)
		(layer "In9.Cu")
		(net "P5E_PEX1_STN7_RX_DN<121>")
	)
	(segment
		(start 157.341316 -359.297986)
		(end 160.479232 -364.461298)
		(width 0.1651)
		(layer "In9.Cu")
		(net "P5E_PEX1_STN7_RX_DN<121>")
	)
	(segment
		(start 156.82849 -358.133142)
		(end 157.341316 -359.297986)
		(width 0.1651)
		(layer "In9.Cu")
		(net "P5E_PEX1_STN7_RX_DN<121>")
	)
	(segment
		(start 152.329896 -310.745124)
		(end 152.30983 -310.76519)
		(width 0.1143)
		(layer "In9.Cu")
		(net "P5E_PEX1_STN7_RX_DN<121>")
	)
	(segment
		(start 153.32964 -310.364378)
		(end 153.16454 -310.529478)
		(width 0.1143)
		(layer "In9.Cu")
		(net "P5E_PEX1_STN7_RX_DN<121>")
	)
	(segment
		(start 151.14778 -315.29655)
		(end 151.14778 -315.79185)
		(width 0.1651)
		(layer "In9.Cu")
		(net "P5E_PEX1_STN7_RX_DN<121>")
	)
	(segment
		(start 162.984942 -369.182142)
		(end 162.984942 -383.272538)
		(width 0.1651)
		(layer "In9.Cu")
		(net "P5E_PEX1_STN7_RX_DN<121>")
	)
	(segment
		(start 151.24938 -316.817756)
		(end 156.82849 -358.133142)
		(width 0.1651)
		(layer "In9.Cu")
		(net "P5E_PEX1_STN7_RX_DN<121>")
	)
	(segment
		(start 162.852862 -368.544348)
		(end 162.984942 -369.182142)
		(width 0.1651)
		(layer "In9.Cu")
		(net "P5E_PEX1_STN7_RX_DN<121>")
	)
	(segment
		(start 162.475164 -383.782316)
		(end 162.236912 -383.782316)
		(width 0.1651)
		(layer "In9.Cu")
		(net "P5E_PEX1_STN7_RX_DN<121>")
	)
	(segment
		(start 151.14778 -314.10275)
		(end 151.14778 -314.59805)
		(width 0.1651)
		(layer "In9.Cu")
		(net "P5E_PEX1_STN7_RX_DN<121>")
	)
	(segment
		(start 153.32964 -310.238648)
		(end 153.32964 -310.364378)
		(width 0.1143)
		(layer "In9.Cu")
		(net "P5E_PEX1_STN7_RX_DN<121>")
	)
	(segment
		(start 160.842452 -365.058452)
		(end 161.0995 -365.481616)
		(width 0.1651)
		(layer "In9.Cu")
		(net "P5E_PEX1_STN7_RX_DN<121>")
	)
	(segment
		(start 160.449768 -364.582456)
		(end 160.721294 -365.028988)
		(width 0.1651)
		(layer "In9.Cu")
		(net "P5E_PEX1_STN7_RX_DN<121>")
	)
	(segment
		(start 160.479232 -364.461298)
		(end 160.449768 -364.582456)
		(width 0.1651)
		(layer "In9.Cu")
		(net "P5E_PEX1_STN7_RX_DN<121>")
	)
	(segment
		(start 151.24938 -314.69965)
		(end 151.24938 -315.19495)
		(width 0.1651)
		(layer "In9.Cu")
		(net "P5E_PEX1_STN7_RX_DN<121>")
	)
	(segment
		(start 151.14778 -314.59805)
		(end 151.24938 -314.69965)
		(width 0.1651)
		(layer "In9.Cu")
		(net "P5E_PEX1_STN7_RX_DN<121>")
	)
	(segment
		(start 161.685478 -366.64138)
		(end 161.943034 -367.065052)
		(width 0.1651)
		(layer "In9.Cu")
		(net "P5E_PEX1_STN7_RX_DN<121>")
	)
	(segment
		(start 152.609804 -310.529478)
		(end 152.393904 -310.745378)
		(width 0.1143)
		(layer "In9.Cu")
		(net "P5E_PEX1_STN7_RX_DN<121>")
	)
	(segment
		(start 151.24938 -311.82564)
		(end 151.24938 -314.00115)
		(width 0.1651)
		(layer "In9.Cu")
		(net "P5E_PEX1_STN7_RX_DN<121>")
	)
	(segment
		(start 162.853624 -368.542062)
		(end 162.8521 -368.54257)
		(width 0.1651)
		(layer "In9.Cu")
		(net "P5E_PEX1_STN7_RX_DN<121>")
	)
	(segment
		(start 151.24938 -314.00115)
		(end 151.14778 -314.10275)
		(width 0.1651)
		(layer "In9.Cu")
		(net "P5E_PEX1_STN7_RX_DN<121>")
	)
	(segment
		(start 153.16454 -310.529478)
		(end 152.609804 -310.529478)
		(width 0.1143)
		(layer "In9.Cu")
		(net "P5E_PEX1_STN7_RX_DN<121>")
	)
	(segment
		(start 151.14778 -315.79185)
		(end 151.24938 -315.89345)
		(width 0.1651)
		(layer "In9.Cu")
		(net "P5E_PEX1_STN7_RX_DN<121>")
	)
	(segment
		(start 161.0995 -365.481616)
		(end 161.06521 -365.621316)
		(width 0.1651)
		(layer "In9.Cu")
		(net "P5E_PEX1_STN7_RX_DN<121>")
	)
	(segment
		(start 161.322766 -366.044734)
		(end 161.462466 -366.07877)
		(width 0.1651)
		(layer "In9.Cu")
		(net "P5E_PEX1_STN7_RX_DN<121>")
	)
	(segment
		(start 162.67938 -368.081306)
		(end 162.852862 -368.540284)
		(width 0.1651)
		(layer "In9.Cu")
		(net "P5E_PEX1_STN7_RX_DN<121>")
	)
	(segment
		(start 74.84999 -283.549852)
		(end 74.849736 -283.549852)
		(width 0.13462)
		(layer "F.Cu")
		(net "P5E_PEX0_STN0_TX_DP<5>")
	)
	(segment
		(start 82.928206 -132.601208)
		(end 83.248246 -132.281168)
		(width 0.13462)
		(layer "F.Cu")
		(net "P5E_PEX0_STN0_TX_DP<5>")
	)
	(segment
		(start 83.248246 -132.281168)
		(end 83.87969 -132.281168)
		(width 0.13462)
		(layer "F.Cu")
		(net "P5E_PEX0_STN0_TX_DP<5>")
	)
	(segment
		(start 83.87969 -132.281168)
		(end 84.17433 -132.575808)
		(width 0.13462)
		(layer "F.Cu")
		(net "P5E_PEX0_STN0_TX_DP<5>")
	)
	(segment
		(start 75.444858 -282.979368)
		(end 75.229466 -283.19476)
		(width 0.1143)
		(layer "In9.Cu")
		(net "P5E_PEX0_STN0_TX_DP<5>")
	)
	(segment
		(start 91.558364 -145.17624)
		(end 91.55811 -145.17624)
		(width 0.1651)
		(layer "In9.Cu")
		(net "P5E_PEX0_STN0_TX_DP<5>")
	)
	(segment
		(start 75.229466 -283.19476)
		(end 75.229466 -283.435552)
		(width 0.1143)
		(layer "In9.Cu")
		(net "P5E_PEX0_STN0_TX_DP<5>")
	)
	(segment
		(start 86.00694 -133.240526)
		(end 86.654386 -133.887972)
		(width 0.1651)
		(layer "In9.Cu")
		(net "P5E_PEX0_STN0_TX_DP<5>")
	)
	(segment
		(start 84.46516 -132.284978)
		(end 85.051392 -132.284978)
		(width 0.1651)
		(layer "In9.Cu")
		(net "P5E_PEX0_STN0_TX_DP<5>")
	)
	(segment
		(start 81.502758 -221.652592)
		(end 84.078318 -251.144532)
		(width 0.1651)
		(layer "In9.Cu")
		(net "P5E_PEX0_STN0_TX_DP<5>")
	)
	(segment
		(start 87.959438 -137.304526)
		(end 88.09228 -137.359644)
		(width 0.1651)
		(layer "In9.Cu")
		(net "P5E_PEX0_STN0_TX_DP<5>")
	)
	(segment
		(start 86.92896 -134.816596)
		(end 87.103966 -135.239252)
		(width 0.1651)
		(layer "In9.Cu")
		(net "P5E_PEX0_STN0_TX_DP<5>")
	)
	(segment
		(start 88.09228 -137.359644)
		(end 88.267032 -137.781792)
		(width 0.1651)
		(layer "In9.Cu")
		(net "P5E_PEX0_STN0_TX_DP<5>")
	)
	(segment
		(start 88.947752 -139.425172)
		(end 89.122504 -139.84732)
		(width 0.1651)
		(layer "In9.Cu")
		(net "P5E_PEX0_STN0_TX_DP<5>")
	)
	(segment
		(start 88.387174 -138.33729)
		(end 88.520016 -138.392408)
		(width 0.1651)
		(layer "In9.Cu")
		(net "P5E_PEX0_STN0_TX_DP<5>")
	)
	(segment
		(start 75.229466 -283.435552)
		(end 75.115166 -283.549852)
		(width 0.1143)
		(layer "In9.Cu")
		(net "P5E_PEX0_STN0_TX_DP<5>")
	)
	(segment
		(start 91.55811 -145.17624)
		(end 95.050864 -153.608024)
		(width 0.1651)
		(layer "In9.Cu")
		(net "P5E_PEX0_STN0_TX_DP<5>")
	)
	(segment
		(start 95.050864 -153.608024)
		(end 95.050864 -159.252412)
		(width 0.1651)
		(layer "In9.Cu")
		(net "P5E_PEX0_STN0_TX_DP<5>")
	)
	(segment
		(start 86.414356 -174.217076)
		(end 85.283802 -178.432968)
		(width 0.1651)
		(layer "In9.Cu")
		(net "P5E_PEX0_STN0_TX_DP<5>")
	)
	(segment
		(start 91.168982 -144.786858)
		(end 91.558364 -145.17624)
		(width 0.1651)
		(layer "In9.Cu")
		(net "P5E_PEX0_STN0_TX_DP<5>")
	)
	(segment
		(start 83.819492 -282.979368)
		(end 75.444858 -282.979368)
		(width 0.1143)
		(layer "In9.Cu")
		(net "P5E_PEX0_STN0_TX_DP<5>")
	)
	(segment
		(start 87.356696 -135.849106)
		(end 87.531702 -136.271762)
		(width 0.1651)
		(layer "In9.Cu")
		(net "P5E_PEX0_STN0_TX_DP<5>")
	)
	(segment
		(start 85.283802 -178.432968)
		(end 81.502758 -221.652592)
		(width 0.1651)
		(layer "In9.Cu")
		(net "P5E_PEX0_STN0_TX_DP<5>")
	)
	(segment
		(start 87.41156 -135.716264)
		(end 87.356696 -135.849106)
		(width 0.1651)
		(layer "In9.Cu")
		(net "P5E_PEX0_STN0_TX_DP<5>")
	)
	(segment
		(start 89.122504 -139.84732)
		(end 89.06764 -139.980162)
		(width 0.1651)
		(layer "In9.Cu")
		(net "P5E_PEX0_STN0_TX_DP<5>")
	)
	(segment
		(start 89.06764 -139.980162)
		(end 89.242646 -140.402818)
		(width 0.1651)
		(layer "In9.Cu")
		(net "P5E_PEX0_STN0_TX_DP<5>")
	)
	(segment
		(start 84.17433 -132.575808)
		(end 84.46516 -132.284978)
		(width 0.1651)
		(layer "In9.Cu")
		(net "P5E_PEX0_STN0_TX_DP<5>")
	)
	(segment
		(start 94.686374 -274.048728)
		(end 86.529926 -282.205176)
		(width 0.1651)
		(layer "In9.Cu")
		(net "P5E_PEX0_STN0_TX_DP<5>")
	)
	(segment
		(start 95.050864 -159.252412)
		(end 86.414356 -174.217076)
		(width 0.1651)
		(layer "In9.Cu")
		(net "P5E_PEX0_STN0_TX_DP<5>")
	)
	(segment
		(start 88.520016 -138.392408)
		(end 88.694768 -138.814556)
		(width 0.1651)
		(layer "In9.Cu")
		(net "P5E_PEX0_STN0_TX_DP<5>")
	)
	(segment
		(start 88.81491 -139.370054)
		(end 88.947752 -139.425172)
		(width 0.1651)
		(layer "In9.Cu")
		(net "P5E_PEX0_STN0_TX_DP<5>")
	)
	(segment
		(start 87.103966 -135.239252)
		(end 87.236808 -135.294116)
		(width 0.1651)
		(layer "In9.Cu")
		(net "P5E_PEX0_STN0_TX_DP<5>")
	)
	(segment
		(start 87.839296 -136.749028)
		(end 87.784432 -136.88187)
		(width 0.1651)
		(layer "In9.Cu")
		(net "P5E_PEX0_STN0_TX_DP<5>")
	)
	(segment
		(start 95.552514 -271.958054)
		(end 94.686374 -274.048728)
		(width 0.1651)
		(layer "In9.Cu")
		(net "P5E_PEX0_STN0_TX_DP<5>")
	)
	(segment
		(start 83.865212 -282.933648)
		(end 83.819492 -282.979368)
		(width 0.1143)
		(layer "In9.Cu")
		(net "P5E_PEX0_STN0_TX_DP<5>")
	)
	(segment
		(start 95.248222 -268.480286)
		(end 95.552514 -271.958054)
		(width 0.1651)
		(layer "In9.Cu")
		(net "P5E_PEX0_STN0_TX_DP<5>")
	)
	(segment
		(start 86.983824 -134.683754)
		(end 86.92896 -134.816596)
		(width 0.1651)
		(layer "In9.Cu")
		(net "P5E_PEX0_STN0_TX_DP<5>")
	)
	(segment
		(start 85.051392 -132.284978)
		(end 85.539834 -132.77342)
		(width 0.1651)
		(layer "In9.Cu")
		(net "P5E_PEX0_STN0_TX_DP<5>")
	)
	(segment
		(start 86.654386 -133.887972)
		(end 86.983824 -134.683754)
		(width 0.1651)
		(layer "In9.Cu")
		(net "P5E_PEX0_STN0_TX_DP<5>")
	)
	(segment
		(start 88.694768 -138.814556)
		(end 88.639904 -138.947398)
		(width 0.1651)
		(layer "In9.Cu")
		(net "P5E_PEX0_STN0_TX_DP<5>")
	)
	(segment
		(start 75.115166 -283.549852)
		(end 74.849736 -283.549852)
		(width 0.1143)
		(layer "In9.Cu")
		(net "P5E_PEX0_STN0_TX_DP<5>")
	)
	(segment
		(start 89.375742 -140.457682)
		(end 91.168982 -144.786858)
		(width 0.1651)
		(layer "In9.Cu")
		(net "P5E_PEX0_STN0_TX_DP<5>")
	)
	(segment
		(start 88.267032 -137.781792)
		(end 88.212168 -137.914634)
		(width 0.1651)
		(layer "In9.Cu")
		(net "P5E_PEX0_STN0_TX_DP<5>")
	)
	(segment
		(start 87.784432 -136.88187)
		(end 87.959438 -137.304526)
		(width 0.1651)
		(layer "In9.Cu")
		(net "P5E_PEX0_STN0_TX_DP<5>")
	)
	(segment
		(start 89.242646 -140.402818)
		(end 89.375742 -140.457682)
		(width 0.1651)
		(layer "In9.Cu")
		(net "P5E_PEX0_STN0_TX_DP<5>")
	)
	(segment
		(start 87.531702 -136.271762)
		(end 87.664544 -136.32688)
		(width 0.1651)
		(layer "In9.Cu")
		(net "P5E_PEX0_STN0_TX_DP<5>")
	)
	(segment
		(start 86.529926 -282.205176)
		(end 84.771484 -282.933648)
		(width 0.1651)
		(layer "In9.Cu")
		(net "P5E_PEX0_STN0_TX_DP<5>")
	)
	(segment
		(start 85.86343 -133.240526)
		(end 86.00694 -133.240526)
		(width 0.1651)
		(layer "In9.Cu")
		(net "P5E_PEX0_STN0_TX_DP<5>")
	)
	(segment
		(start 94.573598 -266.851384)
		(end 95.248222 -268.480286)
		(width 0.1651)
		(layer "In9.Cu")
		(net "P5E_PEX0_STN0_TX_DP<5>")
	)
	(segment
		(start 87.664544 -136.32688)
		(end 87.839296 -136.749028)
		(width 0.1651)
		(layer "In9.Cu")
		(net "P5E_PEX0_STN0_TX_DP<5>")
	)
	(segment
		(start 85.539834 -132.91693)
		(end 85.86343 -133.240526)
		(width 0.1651)
		(layer "In9.Cu")
		(net "P5E_PEX0_STN0_TX_DP<5>")
	)
	(segment
		(start 85.539834 -132.77342)
		(end 85.539834 -132.91693)
		(width 0.1651)
		(layer "In9.Cu")
		(net "P5E_PEX0_STN0_TX_DP<5>")
	)
	(segment
		(start 84.771484 -282.933648)
		(end 83.89366 -282.933648)
		(width 0.1651)
		(layer "In9.Cu")
		(net "P5E_PEX0_STN0_TX_DP<5>")
	)
	(segment
		(start 88.212168 -137.914634)
		(end 88.387174 -138.33729)
		(width 0.1651)
		(layer "In9.Cu")
		(net "P5E_PEX0_STN0_TX_DP<5>")
	)
	(segment
		(start 87.236808 -135.294116)
		(end 87.41156 -135.716264)
		(width 0.1651)
		(layer "In9.Cu")
		(net "P5E_PEX0_STN0_TX_DP<5>")
	)
	(segment
		(start 84.078318 -251.144532)
		(end 94.573598 -266.851384)
		(width 0.1651)
		(layer "In9.Cu")
		(net "P5E_PEX0_STN0_TX_DP<5>")
	)
	(segment
		(start 88.639904 -138.947398)
		(end 88.81491 -139.370054)
		(width 0.1651)
		(layer "In9.Cu")
		(net "P5E_PEX0_STN0_TX_DP<5>")
	)
	(segment
		(start 83.89366 -282.933648)
		(end 83.865212 -282.933648)
		(width 0.1143)
		(layer "In9.Cu")
		(net "P5E_PEX0_STN0_TX_DP<5>")
	)
	(segment
		(start 185.820304 -316.585092)
		(end 185.820304 -319.84188)
		(width 0.1143)
		(layer "In15.Cu")
		(net "P5E_PEX1_STN5_RX_DN<92>")
	)
	(segment
		(start 186.111134 -316.419992)
		(end 185.985404 -316.419992)
		(width 0.1143)
		(layer "In15.Cu")
		(net "P5E_PEX1_STN5_RX_DN<92>")
	)
	(segment
		(start 185.866024 -320.96075)
		(end 184.893966 -322.53936)
		(width 0.1651)
		(layer "In15.Cu")
		(net "P5E_PEX1_STN5_RX_DN<92>")
	)
	(segment
		(start 185.985404 -316.419992)
		(end 185.820304 -316.585092)
		(width 0.1143)
		(layer "In15.Cu")
		(net "P5E_PEX1_STN5_RX_DN<92>")
	)
	(segment
		(start 185.866024 -319.916048)
		(end 185.866024 -320.96075)
		(width 0.1651)
		(layer "In15.Cu")
		(net "P5E_PEX1_STN5_RX_DN<92>")
	)
	(segment
		(start 125.90018 -369.231418)
		(end 125.90018 -370.61267)
		(width 0.1651)
		(layer "In15.Cu")
		(net "P5E_PEX1_STN5_RX_DN<92>")
	)
	(segment
		(start 145.957798 -357.252016)
		(end 144.661636 -358.801416)
		(width 0.1651)
		(layer "In15.Cu")
		(net "P5E_PEX1_STN5_RX_DN<92>")
	)
	(segment
		(start 167.698166 -335.26095)
		(end 161.572448 -340.35619)
		(width 0.1651)
		(layer "In15.Cu")
		(net "P5E_PEX1_STN5_RX_DN<92>")
	)
	(segment
		(start 185.866024 -319.8876)
		(end 185.866024 -319.916048)
		(width 0.1143)
		(layer "In15.Cu")
		(net "P5E_PEX1_STN5_RX_DN<92>")
	)
	(segment
		(start 161.572448 -340.35619)
		(end 145.957798 -357.252016)
		(width 0.1651)
		(layer "In15.Cu")
		(net "P5E_PEX1_STN5_RX_DN<92>")
	)
	(segment
		(start 125.231652 -371.281198)
		(end 124.83719 -371.281198)
		(width 0.1651)
		(layer "In15.Cu")
		(net "P5E_PEX1_STN5_RX_DN<92>")
	)
	(segment
		(start 186.200034 -316.508892)
		(end 186.111134 -316.419992)
		(width 0.1143)
		(layer "In15.Cu")
		(net "P5E_PEX1_STN5_RX_DN<92>")
	)
	(segment
		(start 186.200034 -316.799722)
		(end 186.200034 -316.508892)
		(width 0.1143)
		(layer "In15.Cu")
		(net "P5E_PEX1_STN5_RX_DN<92>")
	)
	(segment
		(start 180.979064 -326.454262)
		(end 167.698166 -335.26095)
		(width 0.1651)
		(layer "In15.Cu")
		(net "P5E_PEX1_STN5_RX_DN<92>")
	)
	(segment
		(start 124.83719 -371.281198)
		(end 124.71019 -371.408198)
		(width 0.1651)
		(layer "In15.Cu")
		(net "P5E_PEX1_STN5_RX_DN<92>")
	)
	(segment
		(start 128.471168 -366.91443)
		(end 126.838456 -368.017298)
		(width 0.1651)
		(layer "In15.Cu")
		(net "P5E_PEX1_STN5_RX_DN<92>")
	)
	(segment
		(start 184.893966 -322.53936)
		(end 180.979064 -326.454262)
		(width 0.1651)
		(layer "In15.Cu")
		(net "P5E_PEX1_STN5_RX_DN<92>")
	)
	(segment
		(start 126.838456 -368.017298)
		(end 126.121668 -368.814096)
		(width 0.1651)
		(layer "In15.Cu")
		(net "P5E_PEX1_STN5_RX_DN<92>")
	)
	(segment
		(start 144.661636 -358.801416)
		(end 143.855694 -359.43159)
		(width 0.1651)
		(layer "In15.Cu")
		(net "P5E_PEX1_STN5_RX_DN<92>")
	)
	(segment
		(start 126.121668 -368.814096)
		(end 125.90018 -369.231418)
		(width 0.1651)
		(layer "In15.Cu")
		(net "P5E_PEX1_STN5_RX_DN<92>")
	)
	(segment
		(start 143.855694 -359.43159)
		(end 128.471168 -366.91443)
		(width 0.1651)
		(layer "In15.Cu")
		(net "P5E_PEX1_STN5_RX_DN<92>")
	)
	(segment
		(start 185.820304 -319.84188)
		(end 185.866024 -319.8876)
		(width 0.1143)
		(layer "In15.Cu")
		(net "P5E_PEX1_STN5_RX_DN<92>")
	)
	(segment
		(start 124.71019 -371.408198)
		(end 124.71019 -371.790214)
		(width 0.1651)
		(layer "In15.Cu")
		(net "P5E_PEX1_STN5_RX_DN<92>")
	)
	(segment
		(start 125.90018 -370.61267)
		(end 125.231652 -371.281198)
		(width 0.1651)
		(layer "In15.Cu")
		(net "P5E_PEX1_STN5_RX_DN<92>")
	)
	(segment
		(start 80.606138 -122.864626)
		(end 81.237582 -122.864626)
		(width 0.13462)
		(layer "F.Cu")
		(net "P5E_PEX0_STN0_TX_DP<2>")
	)
	(segment
		(start 80.286098 -123.184666)
		(end 80.606138 -122.864626)
		(width 0.13462)
		(layer "F.Cu")
		(net "P5E_PEX0_STN0_TX_DP<2>")
	)
	(segment
		(start 81.237582 -122.864626)
		(end 81.532222 -123.159266)
		(width 0.13462)
		(layer "F.Cu")
		(net "P5E_PEX0_STN0_TX_DP<2>")
	)
	(segment
		(start 98.063812 -267.760958)
		(end 98.470466 -272.403824)
		(width 0.1651)
		(layer "In9.Cu")
		(net "P5E_PEX0_STN0_TX_DP<2>")
	)
	(segment
		(start 88.174068 -129.788158)
		(end 88.173814 -129.788158)
		(width 0.1651)
		(layer "In9.Cu")
		(net "P5E_PEX0_STN0_TX_DP<2>")
	)
	(segment
		(start 86.445852 -125.617478)
		(end 86.637368 -126.080012)
		(width 0.1651)
		(layer "In9.Cu")
		(net "P5E_PEX0_STN0_TX_DP<2>")
	)
	(segment
		(start 83.889088 -285.784036)
		(end 83.843368 -285.829756)
		(width 0.1143)
		(layer "In9.Cu")
		(net "P5E_PEX0_STN0_TX_DP<2>")
	)
	(segment
		(start 84.433664 -221.67723)
		(end 84.435696 -221.701614)
		(width 0.1651)
		(layer "In9.Cu")
		(net "P5E_PEX0_STN0_TX_DP<2>")
	)
	(segment
		(start 88.179402 -178.865784)
		(end 84.433664 -221.67723)
		(width 0.1651)
		(layer "In9.Cu")
		(net "P5E_PEX0_STN0_TX_DP<2>")
	)
	(segment
		(start 77.344778 -285.829756)
		(end 77.12964 -286.044894)
		(width 0.1143)
		(layer "In9.Cu")
		(net "P5E_PEX0_STN0_TX_DP<2>")
	)
	(segment
		(start 97.116646 -275.671534)
		(end 88.154256 -284.633924)
		(width 0.1651)
		(layer "In9.Cu")
		(net "P5E_PEX0_STN0_TX_DP<2>")
	)
	(segment
		(start 86.582504 -126.2126)
		(end 86.75751 -126.635256)
		(width 0.1651)
		(layer "In9.Cu")
		(net "P5E_PEX0_STN0_TX_DP<2>")
	)
	(segment
		(start 87.01024 -127.245364)
		(end 87.185246 -127.66802)
		(width 0.1651)
		(layer "In9.Cu")
		(net "P5E_PEX0_STN0_TX_DP<2>")
	)
	(segment
		(start 86.018878 -124.286518)
		(end 86.33079 -125.040136)
		(width 0.1651)
		(layer "In9.Cu")
		(net "P5E_PEX0_STN0_TX_DP<2>")
	)
	(segment
		(start 87.613236 -128.70053)
		(end 87.746332 -128.755394)
		(width 0.1651)
		(layer "In9.Cu")
		(net "P5E_PEX0_STN0_TX_DP<2>")
	)
	(segment
		(start 87.921084 -129.177796)
		(end 87.865966 -129.310638)
		(width 0.1651)
		(layer "In9.Cu")
		(net "P5E_PEX0_STN0_TX_DP<2>")
	)
	(segment
		(start 89.723976 -132.811012)
		(end 89.669112 -132.943854)
		(width 0.1651)
		(layer "In9.Cu")
		(net "P5E_PEX0_STN0_TX_DP<2>")
	)
	(segment
		(start 87.493094 -128.145032)
		(end 87.43823 -128.277874)
		(width 0.1651)
		(layer "In9.Cu")
		(net "P5E_PEX0_STN0_TX_DP<2>")
	)
	(segment
		(start 83.44916 -122.970036)
		(end 83.90636 -122.970036)
		(width 0.1651)
		(layer "In9.Cu")
		(net "P5E_PEX0_STN0_TX_DP<2>")
	)
	(segment
		(start 85.378036 -285.784036)
		(end 83.917536 -285.784036)
		(width 0.1651)
		(layer "In9.Cu")
		(net "P5E_PEX0_STN0_TX_DP<2>")
	)
	(segment
		(start 89.669112 -132.943854)
		(end 89.844118 -133.36651)
		(width 0.1651)
		(layer "In9.Cu")
		(net "P5E_PEX0_STN0_TX_DP<2>")
	)
	(segment
		(start 83.34756 -122.868436)
		(end 83.44916 -122.970036)
		(width 0.1651)
		(layer "In9.Cu")
		(net "P5E_PEX0_STN0_TX_DP<2>")
	)
	(segment
		(start 97.954084 -152.6794)
		(end 97.954084 -159.674306)
		(width 0.1651)
		(layer "In9.Cu")
		(net "P5E_PEX0_STN0_TX_DP<2>")
	)
	(segment
		(start 87.318342 -127.722884)
		(end 87.493094 -128.145032)
		(width 0.1651)
		(layer "In9.Cu")
		(net "P5E_PEX0_STN0_TX_DP<2>")
	)
	(segment
		(start 83.843368 -285.829756)
		(end 77.344778 -285.829756)
		(width 0.1143)
		(layer "In9.Cu")
		(net "P5E_PEX0_STN0_TX_DP<2>")
	)
	(segment
		(start 87.865966 -129.310638)
		(end 88.040972 -129.733294)
		(width 0.1651)
		(layer "In9.Cu")
		(net "P5E_PEX0_STN0_TX_DP<2>")
	)
	(segment
		(start 98.470466 -272.403824)
		(end 97.116646 -275.671534)
		(width 0.1651)
		(layer "In9.Cu")
		(net "P5E_PEX0_STN0_TX_DP<2>")
	)
	(segment
		(start 83.917536 -285.784036)
		(end 83.889088 -285.784036)
		(width 0.1143)
		(layer "In9.Cu")
		(net "P5E_PEX0_STN0_TX_DP<2>")
	)
	(segment
		(start 88.601804 -130.820668)
		(end 89.04097 -131.88061)
		(width 0.1651)
		(layer "In9.Cu")
		(net "P5E_PEX0_STN0_TX_DP<2>")
	)
	(segment
		(start 97.025206 -265.25347)
		(end 98.063812 -267.760958)
		(width 0.1651)
		(layer "In9.Cu")
		(net "P5E_PEX0_STN0_TX_DP<2>")
	)
	(segment
		(start 87.746332 -128.755394)
		(end 87.746078 -128.755648)
		(width 0.1651)
		(layer "In9.Cu")
		(net "P5E_PEX0_STN0_TX_DP<2>")
	)
	(segment
		(start 84.00796 -122.868436)
		(end 84.600796 -122.868436)
		(width 0.1651)
		(layer "In9.Cu")
		(net "P5E_PEX0_STN0_TX_DP<2>")
	)
	(segment
		(start 87.43823 -128.277874)
		(end 87.613236 -128.70053)
		(width 0.1651)
		(layer "In9.Cu")
		(net "P5E_PEX0_STN0_TX_DP<2>")
	)
	(segment
		(start 87.185246 -127.66802)
		(end 87.318342 -127.722884)
		(width 0.1651)
		(layer "In9.Cu")
		(net "P5E_PEX0_STN0_TX_DP<2>")
	)
	(segment
		(start 88.154256 -284.633924)
		(end 85.378036 -285.784036)
		(width 0.1651)
		(layer "In9.Cu")
		(net "P5E_PEX0_STN0_TX_DP<2>")
	)
	(segment
		(start 86.75751 -126.635256)
		(end 86.890352 -126.690374)
		(width 0.1651)
		(layer "In9.Cu")
		(net "P5E_PEX0_STN0_TX_DP<2>")
	)
	(segment
		(start 88.040972 -129.733294)
		(end 88.174068 -129.788158)
		(width 0.1651)
		(layer "In9.Cu")
		(net "P5E_PEX0_STN0_TX_DP<2>")
	)
	(segment
		(start 77.01534 -286.399986)
		(end 76.74991 -286.399986)
		(width 0.1143)
		(layer "In9.Cu")
		(net "P5E_PEX0_STN0_TX_DP<2>")
	)
	(segment
		(start 87.746078 -128.755648)
		(end 87.921084 -129.177796)
		(width 0.1651)
		(layer "In9.Cu")
		(net "P5E_PEX0_STN0_TX_DP<2>")
	)
	(segment
		(start 77.12964 -286.285686)
		(end 77.01534 -286.399986)
		(width 0.1143)
		(layer "In9.Cu")
		(net "P5E_PEX0_STN0_TX_DP<2>")
	)
	(segment
		(start 89.97696 -133.421628)
		(end 97.954084 -152.6794)
		(width 0.1651)
		(layer "In9.Cu")
		(net "P5E_PEX0_STN0_TX_DP<2>")
	)
	(segment
		(start 83.90636 -122.970036)
		(end 84.00796 -122.868436)
		(width 0.1651)
		(layer "In9.Cu")
		(net "P5E_PEX0_STN0_TX_DP<2>")
	)
	(segment
		(start 77.12964 -286.044894)
		(end 77.12964 -286.285686)
		(width 0.1143)
		(layer "In9.Cu")
		(net "P5E_PEX0_STN0_TX_DP<2>")
	)
	(segment
		(start 84.43595 -221.701614)
		(end 86.916768 -250.126246)
		(width 0.1651)
		(layer "In9.Cu")
		(net "P5E_PEX0_STN0_TX_DP<2>")
	)
	(segment
		(start 97.954084 -159.674306)
		(end 97.75063 -160.435544)
		(width 0.1651)
		(layer "In9.Cu")
		(net "P5E_PEX0_STN0_TX_DP<2>")
	)
	(segment
		(start 88.173814 -129.788158)
		(end 88.34882 -130.210306)
		(width 0.1651)
		(layer "In9.Cu")
		(net "P5E_PEX0_STN0_TX_DP<2>")
	)
	(segment
		(start 89.549224 -132.388864)
		(end 89.723976 -132.811012)
		(width 0.1651)
		(layer "In9.Cu")
		(net "P5E_PEX0_STN0_TX_DP<2>")
	)
	(segment
		(start 88.293702 -130.343148)
		(end 88.468708 -130.765804)
		(width 0.1651)
		(layer "In9.Cu")
		(net "P5E_PEX0_STN0_TX_DP<2>")
	)
	(segment
		(start 97.75063 -160.435544)
		(end 89.104216 -175.418242)
		(width 0.1651)
		(layer "In9.Cu")
		(net "P5E_PEX0_STN0_TX_DP<2>")
	)
	(segment
		(start 87.065358 -127.112522)
		(end 87.01024 -127.245364)
		(width 0.1651)
		(layer "In9.Cu")
		(net "P5E_PEX0_STN0_TX_DP<2>")
	)
	(segment
		(start 89.844118 -133.36651)
		(end 89.97696 -133.421628)
		(width 0.1651)
		(layer "In9.Cu")
		(net "P5E_PEX0_STN0_TX_DP<2>")
	)
	(segment
		(start 84.435696 -221.701614)
		(end 84.43595 -221.701614)
		(width 0.1651)
		(layer "In9.Cu")
		(net "P5E_PEX0_STN0_TX_DP<2>")
	)
	(segment
		(start 81.823052 -122.868436)
		(end 83.34756 -122.868436)
		(width 0.1651)
		(layer "In9.Cu")
		(net "P5E_PEX0_STN0_TX_DP<2>")
	)
	(segment
		(start 86.33079 -125.040136)
		(end 86.445852 -125.617478)
		(width 0.1651)
		(layer "In9.Cu")
		(net "P5E_PEX0_STN0_TX_DP<2>")
	)
	(segment
		(start 86.890352 -126.690374)
		(end 87.065358 -127.112522)
		(width 0.1651)
		(layer "In9.Cu")
		(net "P5E_PEX0_STN0_TX_DP<2>")
	)
	(segment
		(start 86.637368 -126.080012)
		(end 86.582504 -126.2126)
		(width 0.1651)
		(layer "In9.Cu")
		(net "P5E_PEX0_STN0_TX_DP<2>")
	)
	(segment
		(start 88.468708 -130.765804)
		(end 88.601804 -130.820668)
		(width 0.1651)
		(layer "In9.Cu")
		(net "P5E_PEX0_STN0_TX_DP<2>")
	)
	(segment
		(start 81.532222 -123.159266)
		(end 81.823052 -122.868436)
		(width 0.1651)
		(layer "In9.Cu")
		(net "P5E_PEX0_STN0_TX_DP<2>")
	)
	(segment
		(start 88.34882 -130.210306)
		(end 88.293702 -130.343148)
		(width 0.1651)
		(layer "In9.Cu")
		(net "P5E_PEX0_STN0_TX_DP<2>")
	)
	(segment
		(start 89.104216 -175.418242)
		(end 88.179402 -178.865784)
		(width 0.1651)
		(layer "In9.Cu")
		(net "P5E_PEX0_STN0_TX_DP<2>")
	)
	(segment
		(start 84.600796 -122.868436)
		(end 86.018878 -124.286518)
		(width 0.1651)
		(layer "In9.Cu")
		(net "P5E_PEX0_STN0_TX_DP<2>")
	)
	(segment
		(start 86.916768 -250.126246)
		(end 97.025206 -265.25347)
		(width 0.1651)
		(layer "In9.Cu")
		(net "P5E_PEX0_STN0_TX_DP<2>")
	)
	(segment
		(start 89.04097 -131.88061)
		(end 89.549224 -132.388864)
		(width 0.1651)
		(layer "In9.Cu")
		(net "P5E_PEX0_STN0_TX_DP<2>")
	)
	(segment
		(start 23.010368 -355.026722)
		(end 23.305008 -354.732082)
		(width 0.13462)
		(layer "F.Cu")
		(net "P5E_PEX0_STN7_TX_DN<114>")
	)
	(segment
		(start 23.330408 -355.978206)
		(end 23.010368 -355.658166)
		(width 0.13462)
		(layer "F.Cu")
		(net "P5E_PEX0_STN7_TX_DN<114>")
	)
	(segment
		(start 23.010368 -355.658166)
		(end 23.010368 -355.026722)
		(width 0.13462)
		(layer "F.Cu")
		(net "P5E_PEX0_STN7_TX_DN<114>")
	)
	(segment
		(start 19.595338 -317.172086)
		(end 20.532598 -314.909708)
		(width 0.1651)
		(layer "In7.Cu")
		(net "P5E_PEX0_STN7_TX_DN<114>")
	)
	(segment
		(start 31.73095 -303.165764)
		(end 35.582352 -303.165764)
		(width 0.1651)
		(layer "In7.Cu")
		(net "P5E_PEX0_STN7_TX_DN<114>")
	)
	(segment
		(start 20.344384 -327.93686)
		(end 19.087084 -323.792088)
		(width 0.1651)
		(layer "In7.Cu")
		(net "P5E_PEX0_STN7_TX_DN<114>")
	)
	(segment
		(start 20.583398 -328.461878)
		(end 20.439634 -327.98766)
		(width 0.1651)
		(layer "In7.Cu")
		(net "P5E_PEX0_STN7_TX_DN<114>")
	)
	(segment
		(start 35.582352 -303.165764)
		(end 35.6108 -303.165764)
		(width 0.1143)
		(layer "In7.Cu")
		(net "P5E_PEX0_STN7_TX_DN<114>")
	)
	(segment
		(start 23.10384 -336.769964)
		(end 23.00859 -336.719164)
		(width 0.1651)
		(layer "In7.Cu")
		(net "P5E_PEX0_STN7_TX_DN<114>")
	)
	(segment
		(start 20.771612 -329.081638)
		(end 20.676362 -329.030838)
		(width 0.1651)
		(layer "In7.Cu")
		(net "P5E_PEX0_STN7_TX_DN<114>")
	)
	(segment
		(start 19.087084 -323.792088)
		(end 19.087084 -319.72758)
		(width 0.1651)
		(layer "In7.Cu")
		(net "P5E_PEX0_STN7_TX_DN<114>")
	)
	(segment
		(start 23.247604 -337.244182)
		(end 23.10384 -336.769964)
		(width 0.1651)
		(layer "In7.Cu")
		(net "P5E_PEX0_STN7_TX_DN<114>")
	)
	(segment
		(start 23.196804 -337.339178)
		(end 23.247604 -337.244182)
		(width 0.1651)
		(layer "In7.Cu")
		(net "P5E_PEX0_STN7_TX_DN<114>")
	)
	(segment
		(start 23.00859 -336.719164)
		(end 21.196554 -330.74483)
		(width 0.1651)
		(layer "In7.Cu")
		(net "P5E_PEX0_STN7_TX_DN<114>")
	)
	(segment
		(start 41.979596 -303.385474)
		(end 41.865296 -303.499774)
		(width 0.1143)
		(layer "In7.Cu")
		(net "P5E_PEX0_STN7_TX_DN<114>")
	)
	(segment
		(start 23.014178 -354.441252)
		(end 23.014178 -353.942142)
		(width 0.1651)
		(layer "In7.Cu")
		(net "P5E_PEX0_STN7_TX_DN<114>")
	)
	(segment
		(start 20.439634 -327.98766)
		(end 20.344384 -327.93686)
		(width 0.1651)
		(layer "In7.Cu")
		(net "P5E_PEX0_STN7_TX_DN<114>")
	)
	(segment
		(start 27.513788 -304.912522)
		(end 31.73095 -303.165764)
		(width 0.1651)
		(layer "In7.Cu")
		(net "P5E_PEX0_STN7_TX_DN<114>")
	)
	(segment
		(start 25.93086 -306.967636)
		(end 26.206196 -306.555394)
		(width 0.1651)
		(layer "In7.Cu")
		(net "P5E_PEX0_STN7_TX_DN<114>")
	)
	(segment
		(start 20.532598 -328.556874)
		(end 20.583398 -328.461878)
		(width 0.1651)
		(layer "In7.Cu")
		(net "P5E_PEX0_STN7_TX_DN<114>")
	)
	(segment
		(start 21.196554 -330.74483)
		(end 21.247354 -330.649834)
		(width 0.1651)
		(layer "In7.Cu")
		(net "P5E_PEX0_STN7_TX_DN<114>")
	)
	(segment
		(start 23.305008 -354.732082)
		(end 23.014178 -354.441252)
		(width 0.1651)
		(layer "In7.Cu")
		(net "P5E_PEX0_STN7_TX_DN<114>")
	)
	(segment
		(start 19.087084 -319.72758)
		(end 19.595338 -317.172086)
		(width 0.1651)
		(layer "In7.Cu")
		(net "P5E_PEX0_STN7_TX_DN<114>")
	)
	(segment
		(start 25.825196 -306.988464)
		(end 25.93086 -306.967636)
		(width 0.1651)
		(layer "In7.Cu")
		(net "P5E_PEX0_STN7_TX_DN<114>")
	)
	(segment
		(start 21.247354 -330.649834)
		(end 21.10359 -330.175616)
		(width 0.1651)
		(layer "In7.Cu")
		(net "P5E_PEX0_STN7_TX_DN<114>")
	)
	(segment
		(start 21.10359 -330.175616)
		(end 21.00834 -330.124816)
		(width 0.1651)
		(layer "In7.Cu")
		(net "P5E_PEX0_STN7_TX_DN<114>")
	)
	(segment
		(start 41.865296 -303.120044)
		(end 41.979596 -303.234344)
		(width 0.1143)
		(layer "In7.Cu")
		(net "P5E_PEX0_STN7_TX_DN<114>")
	)
	(segment
		(start 21.00834 -330.124816)
		(end 20.864576 -329.650852)
		(width 0.1651)
		(layer "In7.Cu")
		(net "P5E_PEX0_STN7_TX_DN<114>")
	)
	(segment
		(start 26.846276 -305.4604)
		(end 27.513788 -304.912522)
		(width 0.1651)
		(layer "In7.Cu")
		(net "P5E_PEX0_STN7_TX_DN<114>")
	)
	(segment
		(start 35.6108 -303.165764)
		(end 35.65652 -303.120044)
		(width 0.1143)
		(layer "In7.Cu")
		(net "P5E_PEX0_STN7_TX_DN<114>")
	)
	(segment
		(start 41.979596 -303.234344)
		(end 41.979596 -303.385474)
		(width 0.1143)
		(layer "In7.Cu")
		(net "P5E_PEX0_STN7_TX_DN<114>")
	)
	(segment
		(start 24.568658 -352.387662)
		(end 24.568658 -341.862156)
		(width 0.1651)
		(layer "In7.Cu")
		(net "P5E_PEX0_STN7_TX_DN<114>")
	)
	(segment
		(start 24.568658 -341.862156)
		(end 23.196804 -337.339178)
		(width 0.1651)
		(layer "In7.Cu")
		(net "P5E_PEX0_STN7_TX_DN<114>")
	)
	(segment
		(start 20.915376 -329.555856)
		(end 20.771612 -329.081638)
		(width 0.1651)
		(layer "In7.Cu")
		(net "P5E_PEX0_STN7_TX_DN<114>")
	)
	(segment
		(start 20.532598 -314.909708)
		(end 25.825196 -306.988464)
		(width 0.1651)
		(layer "In7.Cu")
		(net "P5E_PEX0_STN7_TX_DN<114>")
	)
	(segment
		(start 35.65652 -303.120044)
		(end 41.865296 -303.120044)
		(width 0.1143)
		(layer "In7.Cu")
		(net "P5E_PEX0_STN7_TX_DN<114>")
	)
	(segment
		(start 23.014178 -353.942142)
		(end 24.568658 -352.387662)
		(width 0.1651)
		(layer "In7.Cu")
		(net "P5E_PEX0_STN7_TX_DN<114>")
	)
	(segment
		(start 26.206196 -306.555394)
		(end 26.185368 -306.44973)
		(width 0.1651)
		(layer "In7.Cu")
		(net "P5E_PEX0_STN7_TX_DN<114>")
	)
	(segment
		(start 20.864576 -329.650852)
		(end 20.915376 -329.555856)
		(width 0.1651)
		(layer "In7.Cu")
		(net "P5E_PEX0_STN7_TX_DN<114>")
	)
	(segment
		(start 41.865296 -303.499774)
		(end 41.599866 -303.499774)
		(width 0.1143)
		(layer "In7.Cu")
		(net "P5E_PEX0_STN7_TX_DN<114>")
	)
	(segment
		(start 26.185368 -306.44973)
		(end 26.846276 -305.4604)
		(width 0.1651)
		(layer "In7.Cu")
		(net "P5E_PEX0_STN7_TX_DN<114>")
	)
	(segment
		(start 20.676362 -329.030838)
		(end 20.532598 -328.556874)
		(width 0.1651)
		(layer "In7.Cu")
		(net "P5E_PEX0_STN7_TX_DN<114>")
	)
	(segment
		(start 158.315914 -319.8368)
		(end 158.315914 -319.865248)
		(width 0.1143)
		(layer "In9.Cu")
		(net "P5E_PEX1_STN7_RX_DN<127>")
	)
	(segment
		(start 164.82695 -328.839576)
		(end 173.640242 -341.895684)
		(width 0.1651)
		(layer "In9.Cu")
		(net "P5E_PEX1_STN7_RX_DN<127>")
	)
	(segment
		(start 158.561024 -318.320166)
		(end 158.435294 -318.320166)
		(width 0.1143)
		(layer "In9.Cu")
		(net "P5E_PEX1_STN7_RX_DN<127>")
	)
	(segment
		(start 176.467008 -369.242594)
		(end 176.467008 -383.389378)
		(width 0.1651)
		(layer "In9.Cu")
		(net "P5E_PEX1_STN7_RX_DN<127>")
	)
	(segment
		(start 158.649924 -318.699896)
		(end 158.649924 -318.409066)
		(width 0.1143)
		(layer "In9.Cu")
		(net "P5E_PEX1_STN7_RX_DN<127>")
	)
	(segment
		(start 158.270194 -318.485266)
		(end 158.270194 -319.79108)
		(width 0.1143)
		(layer "In9.Cu")
		(net "P5E_PEX1_STN7_RX_DN<127>")
	)
	(segment
		(start 173.640242 -341.895684)
		(end 173.640242 -358.18826)
		(width 0.1651)
		(layer "In9.Cu")
		(net "P5E_PEX1_STN7_RX_DN<127>")
	)
	(segment
		(start 176.255426 -367.67897)
		(end 176.467008 -369.242594)
		(width 0.1651)
		(layer "In9.Cu")
		(net "P5E_PEX1_STN7_RX_DN<127>")
	)
	(segment
		(start 158.561278 -321.240404)
		(end 164.82695 -328.839576)
		(width 0.1651)
		(layer "In9.Cu")
		(net "P5E_PEX1_STN7_RX_DN<127>")
	)
	(segment
		(start 176.467008 -383.389378)
		(end 175.775366 -384.08102)
		(width 0.1651)
		(layer "In9.Cu")
		(net "P5E_PEX1_STN7_RX_DN<127>")
	)
	(segment
		(start 173.640242 -358.18826)
		(end 176.255426 -367.67897)
		(width 0.1651)
		(layer "In9.Cu")
		(net "P5E_PEX1_STN7_RX_DN<127>")
	)
	(segment
		(start 175.775366 -384.08102)
		(end 175.437038 -384.08102)
		(width 0.1651)
		(layer "In9.Cu")
		(net "P5E_PEX1_STN7_RX_DN<127>")
	)
	(segment
		(start 175.437038 -384.08102)
		(end 175.310038 -384.20802)
		(width 0.1651)
		(layer "In9.Cu")
		(net "P5E_PEX1_STN7_RX_DN<127>")
	)
	(segment
		(start 158.435294 -318.320166)
		(end 158.270194 -318.485266)
		(width 0.1143)
		(layer "In9.Cu")
		(net "P5E_PEX1_STN7_RX_DN<127>")
	)
	(segment
		(start 158.270194 -319.79108)
		(end 158.315914 -319.8368)
		(width 0.1143)
		(layer "In9.Cu")
		(net "P5E_PEX1_STN7_RX_DN<127>")
	)
	(segment
		(start 175.310038 -384.20802)
		(end 175.310038 -384.590036)
		(width 0.1651)
		(layer "In9.Cu")
		(net "P5E_PEX1_STN7_RX_DN<127>")
	)
	(segment
		(start 158.315914 -320.557144)
		(end 158.561278 -321.240404)
		(width 0.1651)
		(layer "In9.Cu")
		(net "P5E_PEX1_STN7_RX_DN<127>")
	)
	(segment
		(start 158.649924 -318.409066)
		(end 158.561024 -318.320166)
		(width 0.1143)
		(layer "In9.Cu")
		(net "P5E_PEX1_STN7_RX_DN<127>")
	)
	(segment
		(start 158.315914 -319.865248)
		(end 158.315914 -320.557144)
		(width 0.1651)
		(layer "In9.Cu")
		(net "P5E_PEX1_STN7_RX_DN<127>")
	)
	(segment
		(start 397.49984 -290.199826)
		(end 397.02486 -289.724846)
		(width 0.13208)
		(layer "F.Cu")
		(net "VSSA_SENSE")
	)
	(segment
		(start 49.1998 -290.199826)
		(end 48.72482 -289.724846)
		(width 0.13208)
		(layer "F.Cu")
		(net "VSSA_SENSE")
	)
	(segment
		(start 165.299898 -290.199826)
		(end 164.824918 -289.724846)
		(width 0.13208)
		(layer "F.Cu")
		(net "VSSA_SENSE")
	)
	(segment
		(start 281.399742 -290.199826)
		(end 280.924762 -289.724846)
		(width 0.13208)
		(layer "F.Cu")
		(net "VSSA_SENSE")
	)
	(via
		(at 157.884368 -262.600948)
		(size 0.508)
		(drill 0.254)
		(layers "F.Cu" "B.Cu")
		(net "VSSA_SENSE")
	)
	(via
		(at 389.126222 -268.339062)
		(size 0.508)
		(drill 0.254)
		(layers "F.Cu" "B.Cu")
		(net "VSSA_SENSE")
	)
	(via
		(at 40.826182 -268.374876)
		(size 0.508)
		(drill 0.254)
		(layers "F.Cu" "B.Cu")
		(net "VSSA_SENSE")
	)
	(via
		(at 48.72482 -289.724846)
		(size 0.4064)
		(drill 0.2032)
		(layers "F.Cu" "B.Cu")
		(net "VSSA_SENSE")
	)
	(via
		(at 280.924762 -289.724846)
		(size 0.4064)
		(drill 0.2032)
		(layers "F.Cu" "B.Cu")
		(net "VSSA_SENSE")
	)
	(via
		(at 164.824918 -289.724846)
		(size 0.4064)
		(drill 0.2032)
		(layers "F.Cu" "B.Cu")
		(net "VSSA_SENSE")
	)
	(via
		(at 273.524472 -266.012422)
		(size 0.508)
		(drill 0.254)
		(layers "F.Cu" "B.Cu")
		(net "VSSA_SENSE")
	)
	(via
		(at 397.02486 -289.724846)
		(size 0.4064)
		(drill 0.2032)
		(layers "F.Cu" "B.Cu")
		(net "VSSA_SENSE")
	)
	(segment
		(start 48.24984 -282.3718)
		(end 48.24984 -289.249866)
		(width 0.13208)
		(layer "B.Cu")
		(net "VSSA_SENSE")
	)
	(segment
		(start 164.349938 -282.804616)
		(end 164.145214 -282.599892)
		(width 0.13208)
		(layer "B.Cu")
		(net "VSSA_SENSE")
	)
	(segment
		(start 391.804398 -282.388564)
		(end 391.804398 -280.826718)
		(width 0.13208)
		(layer "B.Cu")
		(net "VSSA_SENSE")
	)
	(segment
		(start 41.43375 -268.374876)
		(end 42.759884 -269.70101)
		(width 0.13208)
		(layer "B.Cu")
		(net "VSSA_SENSE")
	)
	(segment
		(start 391.677398 -280.699718)
		(end 391.009632 -280.699718)
		(width 0.13208)
		(layer "B.Cu")
		(net "VSSA_SENSE")
	)
	(segment
		(start 42.549826 -271.92351)
		(end 42.549826 -278.67356)
		(width 0.13208)
		(layer "B.Cu")
		(net "VSSA_SENSE")
	)
	(segment
		(start 392.015726 -282.599892)
		(end 391.804398 -282.388564)
		(width 0.13208)
		(layer "B.Cu")
		(net "VSSA_SENSE")
	)
	(segment
		(start 42.759884 -271.713452)
		(end 42.549826 -271.92351)
		(width 0.13208)
		(layer "B.Cu")
		(net "VSSA_SENSE")
	)
	(segment
		(start 396.54988 -289.249866)
		(end 396.54988 -282.804616)
		(width 0.13208)
		(layer "B.Cu")
		(net "VSSA_SENSE")
	)
	(segment
		(start 274.749768 -267.237718)
		(end 273.524472 -266.012422)
		(width 0.13208)
		(layer "B.Cu")
		(net "VSSA_SENSE")
	)
	(segment
		(start 42.549826 -278.67356)
		(end 43.098466 -279.2222)
		(width 0.13208)
		(layer "B.Cu")
		(net "VSSA_SENSE")
	)
	(segment
		(start 274.936966 -282.599892)
		(end 274.749768 -282.412694)
		(width 0.13208)
		(layer "B.Cu")
		(net "VSSA_SENSE")
	)
	(segment
		(start 280.245058 -282.599892)
		(end 274.936966 -282.599892)
		(width 0.13208)
		(layer "B.Cu")
		(net "VSSA_SENSE")
	)
	(segment
		(start 46.736 -279.2222)
		(end 46.863 -279.3492)
		(width 0.13208)
		(layer "B.Cu")
		(net "VSSA_SENSE")
	)
	(segment
		(start 396.345156 -282.599892)
		(end 392.015726 -282.599892)
		(width 0.13208)
		(layer "B.Cu")
		(net "VSSA_SENSE")
	)
	(segment
		(start 397.02486 -289.724846)
		(end 396.54988 -289.249866)
		(width 0.13208)
		(layer "B.Cu")
		(net "VSSA_SENSE")
	)
	(segment
		(start 164.145214 -282.599892)
		(end 159.917892 -282.599892)
		(width 0.13208)
		(layer "B.Cu")
		(net "VSSA_SENSE")
	)
	(segment
		(start 43.098466 -279.2222)
		(end 46.736 -279.2222)
		(width 0.13208)
		(layer "B.Cu")
		(net "VSSA_SENSE")
	)
	(segment
		(start 159.917892 -282.599892)
		(end 159.6136 -282.2956)
		(width 0.13208)
		(layer "B.Cu")
		(net "VSSA_SENSE")
	)
	(segment
		(start 47.1424 -282.2448)
		(end 48.12284 -282.2448)
		(width 0.13208)
		(layer "B.Cu")
		(net "VSSA_SENSE")
	)
	(segment
		(start 280.449782 -289.249866)
		(end 280.449782 -282.804616)
		(width 0.13208)
		(layer "B.Cu")
		(net "VSSA_SENSE")
	)
	(segment
		(start 390.206484 -268.339062)
		(end 389.126222 -268.339062)
		(width 0.13208)
		(layer "B.Cu")
		(net "VSSA_SENSE")
	)
	(segment
		(start 158.649924 -263.366504)
		(end 157.884368 -262.600948)
		(width 0.13208)
		(layer "B.Cu")
		(net "VSSA_SENSE")
	)
	(segment
		(start 46.863 -279.3492)
		(end 46.863 -281.9654)
		(width 0.13208)
		(layer "B.Cu")
		(net "VSSA_SENSE")
	)
	(segment
		(start 391.804398 -280.826718)
		(end 391.677398 -280.699718)
		(width 0.13208)
		(layer "B.Cu")
		(net "VSSA_SENSE")
	)
	(segment
		(start 40.826182 -268.374876)
		(end 41.43375 -268.374876)
		(width 0.13208)
		(layer "B.Cu")
		(net "VSSA_SENSE")
	)
	(segment
		(start 391.009632 -280.699718)
		(end 390.849866 -280.539952)
		(width 0.13208)
		(layer "B.Cu")
		(net "VSSA_SENSE")
	)
	(segment
		(start 280.924762 -289.724846)
		(end 280.449782 -289.249866)
		(width 0.13208)
		(layer "B.Cu")
		(net "VSSA_SENSE")
	)
	(segment
		(start 274.749768 -282.412694)
		(end 274.749768 -267.237718)
		(width 0.13208)
		(layer "B.Cu")
		(net "VSSA_SENSE")
	)
	(segment
		(start 158.649924 -280.539952)
		(end 158.649924 -263.366504)
		(width 0.13208)
		(layer "B.Cu")
		(net "VSSA_SENSE")
	)
	(segment
		(start 42.759884 -269.70101)
		(end 42.759884 -271.713452)
		(width 0.13208)
		(layer "B.Cu")
		(net "VSSA_SENSE")
	)
	(segment
		(start 159.4866 -280.699718)
		(end 158.80969 -280.699718)
		(width 0.13208)
		(layer "B.Cu")
		(net "VSSA_SENSE")
	)
	(segment
		(start 164.824918 -289.724846)
		(end 164.349938 -289.249866)
		(width 0.13208)
		(layer "B.Cu")
		(net "VSSA_SENSE")
	)
	(segment
		(start 396.54988 -282.804616)
		(end 396.345156 -282.599892)
		(width 0.13208)
		(layer "B.Cu")
		(net "VSSA_SENSE")
	)
	(segment
		(start 164.349938 -289.249866)
		(end 164.349938 -282.804616)
		(width 0.13208)
		(layer "B.Cu")
		(net "VSSA_SENSE")
	)
	(segment
		(start 48.12284 -282.2448)
		(end 48.24984 -282.3718)
		(width 0.13208)
		(layer "B.Cu")
		(net "VSSA_SENSE")
	)
	(segment
		(start 159.6136 -282.2956)
		(end 159.6136 -280.826718)
		(width 0.13208)
		(layer "B.Cu")
		(net "VSSA_SENSE")
	)
	(segment
		(start 390.849866 -280.539952)
		(end 390.849866 -268.982444)
		(width 0.13208)
		(layer "B.Cu")
		(net "VSSA_SENSE")
	)
	(segment
		(start 390.849866 -268.982444)
		(end 390.206484 -268.339062)
		(width 0.13208)
		(layer "B.Cu")
		(net "VSSA_SENSE")
	)
	(segment
		(start 48.24984 -289.249866)
		(end 48.72482 -289.724846)
		(width 0.13208)
		(layer "B.Cu")
		(net "VSSA_SENSE")
	)
	(segment
		(start 159.6136 -280.826718)
		(end 159.4866 -280.699718)
		(width 0.13208)
		(layer "B.Cu")
		(net "VSSA_SENSE")
	)
	(segment
		(start 280.449782 -282.804616)
		(end 280.245058 -282.599892)
		(width 0.13208)
		(layer "B.Cu")
		(net "VSSA_SENSE")
	)
	(segment
		(start 46.863 -281.9654)
		(end 47.1424 -282.2448)
		(width 0.13208)
		(layer "B.Cu")
		(net "VSSA_SENSE")
	)
	(segment
		(start 158.80969 -280.699718)
		(end 158.649924 -280.539952)
		(width 0.13208)
		(layer "B.Cu")
		(net "VSSA_SENSE")
	)
	(segment
		(start 351.0534 -251.2568)
		(end 349.741744 -252.568456)
		(width 0.15494)
		(layer "In13.Cu")
		(net "VSSA_SENSE")
	)
	(segment
		(start 354.01123 -251.2568)
		(end 351.0534 -251.2568)
		(width 0.15494)
		(layer "In13.Cu")
		(net "VSSA_SENSE")
	)
	(segment
		(start 355.693726 -249.6312)
		(end 354.01123 -251.2568)
		(width 0.15494)
		(layer "In13.Cu")
		(net "VSSA_SENSE")
	)
	(segment
		(start 98.2218 -260.7564)
		(end 112.836706 -246.141494)
		(width 0.15494)
		(layer "In13.Cu")
		(net "VSSA_SENSE")
	)
	(segment
		(start 209.984594 -256.71526)
		(end 211.879942 -254.819912)
		(width 0.15494)
		(layer "In13.Cu")
		(net "VSSA_SENSE")
	)
	(segment
		(start 266.606528 -264.148824)
		(end 268.470126 -266.012422)
		(width 0.15494)
		(layer "In13.Cu")
		(net "VSSA_SENSE")
	)
	(segment
		(start 319.51676 -262.404606)
		(end 319.49644 -262.424926)
		(width 0.15494)
		(layer "In13.Cu")
		(net "VSSA_SENSE")
	)
	(segment
		(start 279.782016 -261.618984)
		(end 275.388578 -266.012422)
		(width 0.15494)
		(layer "In13.Cu")
		(net "VSSA_SENSE")
	)
	(segment
		(start 370.617496 -263.820402)
		(end 368.663982 -261.866888)
		(width 0.15494)
		(layer "In13.Cu")
		(net "VSSA_SENSE")
	)
	(segment
		(start 112.836706 -246.141494)
		(end 137.288524 -246.141494)
		(width 0.15494)
		(layer "In13.Cu")
		(net "VSSA_SENSE")
	)
	(segment
		(start 382.845056 -263.820402)
		(end 370.617496 -263.820402)
		(width 0.15494)
		(layer "In13.Cu")
		(net "VSSA_SENSE")
	)
	(segment
		(start 230.196136 -255.88595)
		(end 230.583232 -256.273046)
		(width 0.15494)
		(layer "In13.Cu")
		(net "VSSA_SENSE")
	)
	(segment
		(start 341.11946 -259.74294)
		(end 334.817212 -259.74294)
		(width 0.15494)
		(layer "In13.Cu")
		(net "VSSA_SENSE")
	)
	(segment
		(start 368.663982 -261.866888)
		(end 368.663982 -255.69545)
		(width 0.15494)
		(layer "In13.Cu")
		(net "VSSA_SENSE")
	)
	(segment
		(start 169.35196 -256.7432)
		(end 169.3799 -256.71526)
		(width 0.15494)
		(layer "In13.Cu")
		(net "VSSA_SENSE")
	)
	(segment
		(start 268.470126 -266.012422)
		(end 273.524472 -266.012422)
		(width 0.15494)
		(layer "In13.Cu")
		(net "VSSA_SENSE")
	)
	(segment
		(start 157.302962 -247.700292)
		(end 159.140652 -249.537982)
		(width 0.15494)
		(layer "In13.Cu")
		(net "VSSA_SENSE")
	)
	(segment
		(start 168.985946 -256.7432)
		(end 169.35196 -256.7432)
		(width 0.15494)
		(layer "In13.Cu")
		(net "VSSA_SENSE")
	)
	(segment
		(start 157.221428 -261.938008)
		(end 157.884368 -262.600948)
		(width 0.15494)
		(layer "In13.Cu")
		(net "VSSA_SENSE")
	)
	(segment
		(start 349.741744 -255.10871)
		(end 349.047054 -255.8034)
		(width 0.15494)
		(layer "In13.Cu")
		(net "VSSA_SENSE")
	)
	(segment
		(start 219.835984 -254.819912)
		(end 220.902022 -255.88595)
		(width 0.15494)
		(layer "In13.Cu")
		(net "VSSA_SENSE")
	)
	(segment
		(start 387.363716 -268.339062)
		(end 382.845056 -263.820402)
		(width 0.15494)
		(layer "In13.Cu")
		(net "VSSA_SENSE")
	)
	(segment
		(start 149.513036 -247.37695)
		(end 149.836378 -247.700292)
		(width 0.15494)
		(layer "In13.Cu")
		(net "VSSA_SENSE")
	)
	(segment
		(start 320.477134 -261.51459)
		(end 319.587118 -262.404606)
		(width 0.15494)
		(layer "In13.Cu")
		(net "VSSA_SENSE")
	)
	(segment
		(start 137.288524 -246.141494)
		(end 138.52398 -247.37695)
		(width 0.15494)
		(layer "In13.Cu")
		(net "VSSA_SENSE")
	)
	(segment
		(start 157.884368 -262.600948)
		(end 163.128198 -262.600948)
		(width 0.15494)
		(layer "In13.Cu")
		(net "VSSA_SENSE")
	)
	(segment
		(start 159.140652 -249.537982)
		(end 159.140652 -257.973576)
		(width 0.15494)
		(layer "In13.Cu")
		(net "VSSA_SENSE")
	)
	(segment
		(start 230.583232 -256.273046)
		(end 244.441472 -256.273046)
		(width 0.15494)
		(layer "In13.Cu")
		(net "VSSA_SENSE")
	)
	(segment
		(start 220.902022 -255.88595)
		(end 230.196136 -255.88595)
		(width 0.15494)
		(layer "In13.Cu")
		(net "VSSA_SENSE")
	)
	(segment
		(start 149.836378 -247.700292)
		(end 157.302962 -247.700292)
		(width 0.15494)
		(layer "In13.Cu")
		(net "VSSA_SENSE")
	)
	(segment
		(start 163.128198 -262.600948)
		(end 168.985946 -256.7432)
		(width 0.15494)
		(layer "In13.Cu")
		(net "VSSA_SENSE")
	)
	(segment
		(start 345.059 -255.8034)
		(end 341.11946 -259.74294)
		(width 0.15494)
		(layer "In13.Cu")
		(net "VSSA_SENSE")
	)
	(segment
		(start 169.3799 -256.71526)
		(end 209.984594 -256.71526)
		(width 0.15494)
		(layer "In13.Cu")
		(net "VSSA_SENSE")
	)
	(segment
		(start 244.441472 -256.273046)
		(end 252.31725 -264.148824)
		(width 0.15494)
		(layer "In13.Cu")
		(net "VSSA_SENSE")
	)
	(segment
		(start 349.741744 -252.568456)
		(end 349.741744 -255.10871)
		(width 0.15494)
		(layer "In13.Cu")
		(net "VSSA_SENSE")
	)
	(segment
		(start 299.72 -264.0838)
		(end 297.255184 -261.618984)
		(width 0.15494)
		(layer "In13.Cu")
		(net "VSSA_SENSE")
	)
	(segment
		(start 368.663982 -255.69545)
		(end 362.599732 -249.6312)
		(width 0.15494)
		(layer "In13.Cu")
		(net "VSSA_SENSE")
	)
	(segment
		(start 319.49644 -262.424926)
		(end 313.819794 -262.424926)
		(width 0.15494)
		(layer "In13.Cu")
		(net "VSSA_SENSE")
	)
	(segment
		(start 40.826182 -268.374876)
		(end 41.891204 -268.374876)
		(width 0.15494)
		(layer "In13.Cu")
		(net "VSSA_SENSE")
	)
	(segment
		(start 349.047054 -255.8034)
		(end 345.059 -255.8034)
		(width 0.15494)
		(layer "In13.Cu")
		(net "VSSA_SENSE")
	)
	(segment
		(start 312.16092 -264.0838)
		(end 299.72 -264.0838)
		(width 0.15494)
		(layer "In13.Cu")
		(net "VSSA_SENSE")
	)
	(segment
		(start 138.52398 -247.37695)
		(end 149.513036 -247.37695)
		(width 0.15494)
		(layer "In13.Cu")
		(net "VSSA_SENSE")
	)
	(segment
		(start 362.599732 -249.6312)
		(end 355.693726 -249.6312)
		(width 0.15494)
		(layer "In13.Cu")
		(net "VSSA_SENSE")
	)
	(segment
		(start 313.819794 -262.424926)
		(end 312.16092 -264.0838)
		(width 0.15494)
		(layer "In13.Cu")
		(net "VSSA_SENSE")
	)
	(segment
		(start 297.255184 -261.618984)
		(end 279.782016 -261.618984)
		(width 0.15494)
		(layer "In13.Cu")
		(net "VSSA_SENSE")
	)
	(segment
		(start 389.126222 -268.339062)
		(end 387.363716 -268.339062)
		(width 0.15494)
		(layer "In13.Cu")
		(net "VSSA_SENSE")
	)
	(segment
		(start 333.045562 -261.51459)
		(end 320.477134 -261.51459)
		(width 0.15494)
		(layer "In13.Cu")
		(net "VSSA_SENSE")
	)
	(segment
		(start 252.31725 -264.148824)
		(end 266.606528 -264.148824)
		(width 0.15494)
		(layer "In13.Cu")
		(net "VSSA_SENSE")
	)
	(segment
		(start 41.891204 -268.374876)
		(end 49.50968 -260.7564)
		(width 0.15494)
		(layer "In13.Cu")
		(net "VSSA_SENSE")
	)
	(segment
		(start 334.817212 -259.74294)
		(end 333.045562 -261.51459)
		(width 0.15494)
		(layer "In13.Cu")
		(net "VSSA_SENSE")
	)
	(segment
		(start 319.587118 -262.404606)
		(end 319.51676 -262.404606)
		(width 0.15494)
		(layer "In13.Cu")
		(net "VSSA_SENSE")
	)
	(segment
		(start 159.140652 -257.973576)
		(end 157.221428 -259.8928)
		(width 0.15494)
		(layer "In13.Cu")
		(net "VSSA_SENSE")
	)
	(segment
		(start 49.50968 -260.7564)
		(end 98.2218 -260.7564)
		(width 0.15494)
		(layer "In13.Cu")
		(net "VSSA_SENSE")
	)
	(segment
		(start 275.388578 -266.012422)
		(end 273.524472 -266.012422)
		(width 0.15494)
		(layer "In13.Cu")
		(net "VSSA_SENSE")
	)
	(segment
		(start 157.221428 -259.8928)
		(end 157.221428 -261.938008)
		(width 0.15494)
		(layer "In13.Cu")
		(net "VSSA_SENSE")
	)
	(segment
		(start 211.879942 -254.819912)
		(end 219.835984 -254.819912)
		(width 0.15494)
		(layer "In13.Cu")
		(net "VSSA_SENSE")
	)
	(segment
		(start 82.928206 -131.686808)
		(end 83.248246 -132.006848)
		(width 0.13462)
		(layer "F.Cu")
		(net "P5E_PEX0_STN0_TX_DN<5>")
	)
	(segment
		(start 83.87969 -132.006848)
		(end 84.17433 -131.712208)
		(width 0.13462)
		(layer "F.Cu")
		(net "P5E_PEX0_STN0_TX_DN<5>")
	)
	(segment
		(start 83.248246 -132.006848)
		(end 83.87969 -132.006848)
		(width 0.13462)
		(layer "F.Cu")
		(net "P5E_PEX0_STN0_TX_DN<5>")
	)
	(segment
		(start 83.819492 -283.169868)
		(end 75.523852 -283.169868)
		(width 0.1143)
		(layer "In9.Cu")
		(net "P5E_PEX0_STN0_TX_DN<5>")
	)
	(segment
		(start 75.523852 -283.169868)
		(end 75.419966 -283.273754)
		(width 0.1143)
		(layer "In9.Cu")
		(net "P5E_PEX0_STN0_TX_DN<5>")
	)
	(segment
		(start 94.925388 -274.208494)
		(end 86.689692 -282.44419)
		(width 0.1651)
		(layer "In9.Cu")
		(net "P5E_PEX0_STN0_TX_DN<5>")
	)
	(segment
		(start 85.562694 -178.482244)
		(end 81.785968 -221.652592)
		(width 0.1651)
		(layer "In9.Cu")
		(net "P5E_PEX0_STN0_TX_DN<5>")
	)
	(segment
		(start 83.89366 -283.215588)
		(end 83.865212 -283.215588)
		(width 0.1143)
		(layer "In9.Cu")
		(net "P5E_PEX0_STN0_TX_DN<5>")
	)
	(segment
		(start 86.677246 -174.326042)
		(end 85.562694 -178.482244)
		(width 0.1651)
		(layer "In9.Cu")
		(net "P5E_PEX0_STN0_TX_DN<5>")
	)
	(segment
		(start 95.839534 -272.00225)
		(end 94.925388 -274.208494)
		(width 0.1651)
		(layer "In9.Cu")
		(net "P5E_PEX0_STN0_TX_DN<5>")
	)
	(segment
		(start 75.534266 -283.549852)
		(end 75.79995 -283.549852)
		(width 0.1143)
		(layer "In9.Cu")
		(net "P5E_PEX0_STN0_TX_DN<5>")
	)
	(segment
		(start 84.17433 -131.712208)
		(end 84.46516 -132.003038)
		(width 0.1651)
		(layer "In9.Cu")
		(net "P5E_PEX0_STN0_TX_DN<5>")
	)
	(segment
		(start 86.689692 -282.44419)
		(end 84.827618 -283.215588)
		(width 0.1651)
		(layer "In9.Cu")
		(net "P5E_PEX0_STN0_TX_DN<5>")
	)
	(segment
		(start 81.785968 -221.652592)
		(end 84.353146 -251.048012)
		(width 0.1651)
		(layer "In9.Cu")
		(net "P5E_PEX0_STN0_TX_DN<5>")
	)
	(segment
		(start 95.525336 -268.412468)
		(end 95.839534 -272.00225)
		(width 0.1651)
		(layer "In9.Cu")
		(net "P5E_PEX0_STN0_TX_DN<5>")
	)
	(segment
		(start 83.865212 -283.215588)
		(end 83.819492 -283.169868)
		(width 0.1143)
		(layer "In9.Cu")
		(net "P5E_PEX0_STN0_TX_DN<5>")
	)
	(segment
		(start 86.8934 -133.728206)
		(end 91.407996 -144.627092)
		(width 0.1651)
		(layer "In9.Cu")
		(net "P5E_PEX0_STN0_TX_DN<5>")
	)
	(segment
		(start 95.332804 -159.328104)
		(end 86.677246 -174.326042)
		(width 0.1651)
		(layer "In9.Cu")
		(net "P5E_PEX0_STN0_TX_DN<5>")
	)
	(segment
		(start 75.419966 -283.435552)
		(end 75.534266 -283.549852)
		(width 0.1143)
		(layer "In9.Cu")
		(net "P5E_PEX0_STN0_TX_DN<5>")
	)
	(segment
		(start 94.823534 -266.71778)
		(end 95.525336 -268.412468)
		(width 0.1651)
		(layer "In9.Cu")
		(net "P5E_PEX0_STN0_TX_DN<5>")
	)
	(segment
		(start 75.419966 -283.273754)
		(end 75.419966 -283.435552)
		(width 0.1143)
		(layer "In9.Cu")
		(net "P5E_PEX0_STN0_TX_DN<5>")
	)
	(segment
		(start 84.353146 -251.048012)
		(end 94.823534 -266.71778)
		(width 0.1651)
		(layer "In9.Cu")
		(net "P5E_PEX0_STN0_TX_DN<5>")
	)
	(segment
		(start 95.332804 -153.55189)
		(end 95.332804 -159.328104)
		(width 0.1651)
		(layer "In9.Cu")
		(net "P5E_PEX0_STN0_TX_DN<5>")
	)
	(segment
		(start 85.168232 -132.003038)
		(end 86.8934 -133.728206)
		(width 0.1651)
		(layer "In9.Cu")
		(net "P5E_PEX0_STN0_TX_DN<5>")
	)
	(segment
		(start 84.827618 -283.215588)
		(end 83.89366 -283.215588)
		(width 0.1651)
		(layer "In9.Cu")
		(net "P5E_PEX0_STN0_TX_DN<5>")
	)
	(segment
		(start 91.797378 -145.016474)
		(end 95.332804 -153.55189)
		(width 0.1651)
		(layer "In9.Cu")
		(net "P5E_PEX0_STN0_TX_DN<5>")
	)
	(segment
		(start 91.407996 -144.627092)
		(end 91.797378 -145.016474)
		(width 0.1651)
		(layer "In9.Cu")
		(net "P5E_PEX0_STN0_TX_DN<5>")
	)
	(segment
		(start 84.46516 -132.003038)
		(end 85.168232 -132.003038)
		(width 0.1651)
		(layer "In9.Cu")
		(net "P5E_PEX0_STN0_TX_DN<5>")
	)
	(segment
		(start 151.09825 -308.583838)
		(end 150.747476 -308.729126)
		(width 0.1651)
		(layer "In9.Cu")
		(net "P5E_PEX1_STN7_RX_DP<120>")
	)
	(segment
		(start 155.420314 -308.873906)
		(end 155.175966 -308.629558)
		(width 0.1143)
		(layer "In9.Cu")
		(net "P5E_PEX1_STN7_RX_DP<120>")
	)
	(segment
		(start 160.677606 -369.257326)
		(end 160.792668 -369.803172)
		(width 0.1651)
		(layer "In9.Cu")
		(net "P5E_PEX1_STN7_RX_DP<120>")
	)
	(segment
		(start 149.761956 -310.257698)
		(end 149.554438 -313.279028)
		(width 0.1651)
		(layer "In9.Cu")
		(net "P5E_PEX1_STN7_RX_DP<120>")
	)
	(segment
		(start 149.554438 -313.279028)
		(end 149.731476 -315.8109)
		(width 0.1651)
		(layer "In9.Cu")
		(net "P5E_PEX1_STN7_RX_DP<120>")
	)
	(segment
		(start 150.633176 -319.548764)
		(end 155.87345 -358.35336)
		(width 0.1651)
		(layer "In9.Cu")
		(net "P5E_PEX1_STN7_RX_DP<120>")
	)
	(segment
		(start 160.792668 -369.803172)
		(end 160.792668 -382.165352)
		(width 0.1651)
		(layer "In9.Cu")
		(net "P5E_PEX1_STN7_RX_DP<120>")
	)
	(segment
		(start 155.800044 -309.199788)
		(end 155.509214 -309.199788)
		(width 0.1143)
		(layer "In9.Cu")
		(net "P5E_PEX1_STN7_RX_DP<120>")
	)
	(segment
		(start 149.731476 -315.8109)
		(end 150.633176 -319.548764)
		(width 0.1651)
		(layer "In9.Cu")
		(net "P5E_PEX1_STN7_RX_DP<120>")
	)
	(segment
		(start 150.747476 -308.729126)
		(end 150.147274 -309.329328)
		(width 0.1651)
		(layer "In9.Cu")
		(net "P5E_PEX1_STN7_RX_DP<120>")
	)
	(segment
		(start 160.037018 -382.699006)
		(end 159.910018 -382.572006)
		(width 0.1651)
		(layer "In9.Cu")
		(net "P5E_PEX1_STN7_RX_DP<120>")
	)
	(segment
		(start 151.779732 -308.583838)
		(end 151.751284 -308.583838)
		(width 0.1143)
		(layer "In9.Cu")
		(net "P5E_PEX1_STN7_RX_DP<120>")
	)
	(segment
		(start 150.147274 -309.329328)
		(end 149.761956 -310.257698)
		(width 0.1651)
		(layer "In9.Cu")
		(net "P5E_PEX1_STN7_RX_DP<120>")
	)
	(segment
		(start 155.420314 -309.110888)
		(end 155.420314 -308.873906)
		(width 0.1143)
		(layer "In9.Cu")
		(net "P5E_PEX1_STN7_RX_DP<120>")
	)
	(segment
		(start 155.87345 -358.35336)
		(end 160.677606 -369.257326)
		(width 0.1651)
		(layer "In9.Cu")
		(net "P5E_PEX1_STN7_RX_DP<120>")
	)
	(segment
		(start 151.751284 -308.583838)
		(end 151.09825 -308.583838)
		(width 0.1651)
		(layer "In9.Cu")
		(net "P5E_PEX1_STN7_RX_DP<120>")
	)
	(segment
		(start 160.792668 -382.165352)
		(end 160.259014 -382.699006)
		(width 0.1651)
		(layer "In9.Cu")
		(net "P5E_PEX1_STN7_RX_DP<120>")
	)
	(segment
		(start 155.175966 -308.629558)
		(end 151.825452 -308.629558)
		(width 0.1143)
		(layer "In9.Cu")
		(net "P5E_PEX1_STN7_RX_DP<120>")
	)
	(segment
		(start 160.259014 -382.699006)
		(end 160.037018 -382.699006)
		(width 0.1651)
		(layer "In9.Cu")
		(net "P5E_PEX1_STN7_RX_DP<120>")
	)
	(segment
		(start 151.825452 -308.629558)
		(end 151.779732 -308.583838)
		(width 0.1143)
		(layer "In9.Cu")
		(net "P5E_PEX1_STN7_RX_DP<120>")
	)
	(segment
		(start 159.910018 -382.572006)
		(end 159.910018 -382.18999)
		(width 0.1651)
		(layer "In9.Cu")
		(net "P5E_PEX1_STN7_RX_DP<120>")
	)
	(segment
		(start 155.509214 -309.199788)
		(end 155.420314 -309.110888)
		(width 0.1143)
		(layer "In9.Cu")
		(net "P5E_PEX1_STN7_RX_DP<120>")
	)
	(segment
		(start 36.051744 -105.289858)
		(end 35.4203 -105.289858)
		(width 0.13462)
		(layer "F.Cu")
		(net "P5E_PEX0_STN1_TX_DP<19>")
	)
	(segment
		(start 36.371784 -105.609898)
		(end 36.051744 -105.289858)
		(width 0.13462)
		(layer "F.Cu")
		(net "P5E_PEX0_STN1_TX_DP<19>")
	)
	(segment
		(start 35.4203 -105.289858)
		(end 35.12566 -105.584498)
		(width 0.13462)
		(layer "F.Cu")
		(net "P5E_PEX0_STN1_TX_DP<19>")
	)
	(segment
		(start 29.168344 -113.284254)
		(end 28.97886 -113.741708)
		(width 0.1651)
		(layer "In9.Cu")
		(net "P5E_PEX0_STN1_TX_DP<19>")
	)
	(segment
		(start 27.774138 -116.651278)
		(end 23.390352 -131.101338)
		(width 0.1651)
		(layer "In9.Cu")
		(net "P5E_PEX0_STN1_TX_DP<19>")
	)
	(segment
		(start 62.385448 -280.129488)
		(end 62.499748 -280.015188)
		(width 0.1143)
		(layer "In9.Cu")
		(net "P5E_PEX0_STN1_TX_DP<19>")
	)
	(segment
		(start 23.390352 -131.101338)
		(end 23.390352 -138.417046)
		(width 0.1651)
		(layer "In9.Cu")
		(net "P5E_PEX0_STN1_TX_DP<19>")
	)
	(segment
		(start 31.8643 -107.862624)
		(end 31.720536 -107.862624)
		(width 0.1651)
		(layer "In9.Cu")
		(net "P5E_PEX0_STN1_TX_DP<19>")
	)
	(segment
		(start 62.22365 -280.129488)
		(end 62.385448 -280.129488)
		(width 0.1143)
		(layer "In9.Cu")
		(net "P5E_PEX0_STN1_TX_DP<19>")
	)
	(segment
		(start 30.3784 -110.362238)
		(end 30.440376 -110.51159)
		(width 0.1651)
		(layer "In9.Cu")
		(net "P5E_PEX0_STN1_TX_DP<19>")
	)
	(segment
		(start 62.120018 -280.025856)
		(end 62.22365 -280.129488)
		(width 0.1143)
		(layer "In9.Cu")
		(net "P5E_PEX0_STN1_TX_DP<19>")
	)
	(segment
		(start 30.844998 -109.235748)
		(end 30.906974 -109.3851)
		(width 0.1651)
		(layer "In9.Cu")
		(net "P5E_PEX0_STN1_TX_DP<19>")
	)
	(segment
		(start 28.701746 -114.410744)
		(end 28.702 -114.410744)
		(width 0.1651)
		(layer "In9.Cu")
		(net "P5E_PEX0_STN1_TX_DP<19>")
	)
	(segment
		(start 29.507434 -112.76457)
		(end 29.31795 -113.222532)
		(width 0.1651)
		(layer "In9.Cu")
		(net "P5E_PEX0_STN1_TX_DP<19>")
	)
	(segment
		(start 62.499748 -280.015188)
		(end 62.499748 -279.749504)
		(width 0.1143)
		(layer "In9.Cu")
		(net "P5E_PEX0_STN1_TX_DP<19>")
	)
	(segment
		(start 29.973778 -111.63808)
		(end 29.784294 -112.096042)
		(width 0.1651)
		(layer "In9.Cu")
		(net "P5E_PEX0_STN1_TX_DP<19>")
	)
	(segment
		(start 25.950164 -144.596358)
		(end 26.665936 -159.178498)
		(width 0.1651)
		(layer "In9.Cu")
		(net "P5E_PEX0_STN1_TX_DP<19>")
	)
	(segment
		(start 32.21482 -107.36834)
		(end 32.21482 -107.512104)
		(width 0.1651)
		(layer "In9.Cu")
		(net "P5E_PEX0_STN1_TX_DP<19>")
	)
	(segment
		(start 31.197296 -108.385864)
		(end 31.197042 -108.385864)
		(width 0.1651)
		(layer "In9.Cu")
		(net "P5E_PEX0_STN1_TX_DP<19>")
	)
	(segment
		(start 34.289492 -105.293668)
		(end 33.93948 -105.64368)
		(width 0.1651)
		(layer "In9.Cu")
		(net "P5E_PEX0_STN1_TX_DP<19>")
	)
	(segment
		(start 28.97886 -113.741708)
		(end 29.040836 -113.89106)
		(width 0.1651)
		(layer "In9.Cu")
		(net "P5E_PEX0_STN1_TX_DP<19>")
	)
	(segment
		(start 33.07715 -106.50601)
		(end 33.07715 -106.667808)
		(width 0.1651)
		(layer "In9.Cu")
		(net "P5E_PEX0_STN1_TX_DP<19>")
	)
	(segment
		(start 23.390352 -138.417046)
		(end 25.950164 -144.596358)
		(width 0.1651)
		(layer "In9.Cu")
		(net "P5E_PEX0_STN1_TX_DP<19>")
	)
	(segment
		(start 29.634688 -112.157764)
		(end 29.634942 -112.157764)
		(width 0.1651)
		(layer "In9.Cu")
		(net "P5E_PEX0_STN1_TX_DP<19>")
	)
	(segment
		(start 33.427162 -106.155998)
		(end 33.07715 -106.50601)
		(width 0.1651)
		(layer "In9.Cu")
		(net "P5E_PEX0_STN1_TX_DP<19>")
	)
	(segment
		(start 30.567884 -109.904784)
		(end 30.3784 -110.362238)
		(width 0.1651)
		(layer "In9.Cu")
		(net "P5E_PEX0_STN1_TX_DP<19>")
	)
	(segment
		(start 32.564832 -107.018328)
		(end 32.21482 -107.36834)
		(width 0.1651)
		(layer "In9.Cu")
		(net "P5E_PEX0_STN1_TX_DP<19>")
	)
	(segment
		(start 62.165738 -271.526)
		(end 62.165738 -271.554448)
		(width 0.1143)
		(layer "In9.Cu")
		(net "P5E_PEX0_STN1_TX_DP<19>")
	)
	(segment
		(start 26.665936 -159.178498)
		(end 27.264868 -162.189414)
		(width 0.1651)
		(layer "In9.Cu")
		(net "P5E_PEX0_STN1_TX_DP<19>")
	)
	(segment
		(start 30.101286 -111.031274)
		(end 30.10154 -111.031274)
		(width 0.1651)
		(layer "In9.Cu")
		(net "P5E_PEX0_STN1_TX_DP<19>")
	)
	(segment
		(start 33.58896 -106.155998)
		(end 33.427162 -106.155998)
		(width 0.1651)
		(layer "In9.Cu")
		(net "P5E_PEX0_STN1_TX_DP<19>")
	)
	(segment
		(start 29.31795 -113.222532)
		(end 29.168344 -113.284254)
		(width 0.1651)
		(layer "In9.Cu")
		(net "P5E_PEX0_STN1_TX_DP<19>")
	)
	(segment
		(start 29.911802 -111.488728)
		(end 29.973778 -111.63808)
		(width 0.1651)
		(layer "In9.Cu")
		(net "P5E_PEX0_STN1_TX_DP<19>")
	)
	(segment
		(start 29.784294 -112.096042)
		(end 29.634688 -112.157764)
		(width 0.1651)
		(layer "In9.Cu")
		(net "P5E_PEX0_STN1_TX_DP<19>")
	)
	(segment
		(start 31.197042 -108.385864)
		(end 30.844998 -109.235748)
		(width 0.1651)
		(layer "In9.Cu")
		(net "P5E_PEX0_STN1_TX_DP<19>")
	)
	(segment
		(start 32.72663 -107.018328)
		(end 32.564832 -107.018328)
		(width 0.1651)
		(layer "In9.Cu")
		(net "P5E_PEX0_STN1_TX_DP<19>")
	)
	(segment
		(start 32.21482 -107.512104)
		(end 31.8643 -107.862624)
		(width 0.1651)
		(layer "In9.Cu")
		(net "P5E_PEX0_STN1_TX_DP<19>")
	)
	(segment
		(start 33.93948 -105.805478)
		(end 33.58896 -106.155998)
		(width 0.1651)
		(layer "In9.Cu")
		(net "P5E_PEX0_STN1_TX_DP<19>")
	)
	(segment
		(start 30.10154 -111.031274)
		(end 29.912056 -111.488728)
		(width 0.1651)
		(layer "In9.Cu")
		(net "P5E_PEX0_STN1_TX_DP<19>")
	)
	(segment
		(start 29.634942 -112.157764)
		(end 29.445458 -112.615218)
		(width 0.1651)
		(layer "In9.Cu")
		(net "P5E_PEX0_STN1_TX_DP<19>")
	)
	(segment
		(start 62.120018 -271.600168)
		(end 62.120018 -280.025856)
		(width 0.1143)
		(layer "In9.Cu")
		(net "P5E_PEX0_STN1_TX_DP<19>")
	)
	(segment
		(start 28.702 -114.410744)
		(end 27.774138 -116.651278)
		(width 0.1651)
		(layer "In9.Cu")
		(net "P5E_PEX0_STN1_TX_DP<19>")
	)
	(segment
		(start 35.12566 -105.584498)
		(end 34.83483 -105.293668)
		(width 0.1651)
		(layer "In9.Cu")
		(net "P5E_PEX0_STN1_TX_DP<19>")
	)
	(segment
		(start 29.040836 -113.89106)
		(end 28.851352 -114.349022)
		(width 0.1651)
		(layer "In9.Cu")
		(net "P5E_PEX0_STN1_TX_DP<19>")
	)
	(segment
		(start 28.851352 -114.349022)
		(end 28.701746 -114.410744)
		(width 0.1651)
		(layer "In9.Cu")
		(net "P5E_PEX0_STN1_TX_DP<19>")
	)
	(segment
		(start 30.71749 -109.843062)
		(end 30.567884 -109.904784)
		(width 0.1651)
		(layer "In9.Cu")
		(net "P5E_PEX0_STN1_TX_DP<19>")
	)
	(segment
		(start 34.83483 -105.293668)
		(end 34.289492 -105.293668)
		(width 0.1651)
		(layer "In9.Cu")
		(net "P5E_PEX0_STN1_TX_DP<19>")
	)
	(segment
		(start 27.264868 -162.189414)
		(end 62.165738 -265.298682)
		(width 0.1651)
		(layer "In9.Cu")
		(net "P5E_PEX0_STN1_TX_DP<19>")
	)
	(segment
		(start 30.250892 -110.969552)
		(end 30.101286 -111.031274)
		(width 0.1651)
		(layer "In9.Cu")
		(net "P5E_PEX0_STN1_TX_DP<19>")
	)
	(segment
		(start 62.165738 -271.554448)
		(end 62.120018 -271.600168)
		(width 0.1143)
		(layer "In9.Cu")
		(net "P5E_PEX0_STN1_TX_DP<19>")
	)
	(segment
		(start 30.440376 -110.51159)
		(end 30.250892 -110.969552)
		(width 0.1651)
		(layer "In9.Cu")
		(net "P5E_PEX0_STN1_TX_DP<19>")
	)
	(segment
		(start 31.720536 -107.862624)
		(end 31.197296 -108.385864)
		(width 0.1651)
		(layer "In9.Cu")
		(net "P5E_PEX0_STN1_TX_DP<19>")
	)
	(segment
		(start 33.07715 -106.667808)
		(end 32.72663 -107.018328)
		(width 0.1651)
		(layer "In9.Cu")
		(net "P5E_PEX0_STN1_TX_DP<19>")
	)
	(segment
		(start 33.93948 -105.64368)
		(end 33.93948 -105.805478)
		(width 0.1651)
		(layer "In9.Cu")
		(net "P5E_PEX0_STN1_TX_DP<19>")
	)
	(segment
		(start 29.912056 -111.488728)
		(end 29.911802 -111.488728)
		(width 0.1651)
		(layer "In9.Cu")
		(net "P5E_PEX0_STN1_TX_DP<19>")
	)
	(segment
		(start 62.165738 -265.298682)
		(end 62.165738 -271.526)
		(width 0.1651)
		(layer "In9.Cu")
		(net "P5E_PEX0_STN1_TX_DP<19>")
	)
	(segment
		(start 29.445458 -112.615218)
		(end 29.507434 -112.76457)
		(width 0.1651)
		(layer "In9.Cu")
		(net "P5E_PEX0_STN1_TX_DP<19>")
	)
	(segment
		(start 30.906974 -109.3851)
		(end 30.71749 -109.843062)
		(width 0.1651)
		(layer "In9.Cu")
		(net "P5E_PEX0_STN1_TX_DP<19>")
	)
	(segment
		(start 141.099032 -359.008172)
		(end 141.688058 -358.05999)
		(width 0.1651)
		(layer "In15.Cu")
		(net "P5E_PEX1_STN5_RX_DP<91>")
	)
	(segment
		(start 122.637042 -372.099078)
		(end 122.85853 -372.099078)
		(width 0.1651)
		(layer "In15.Cu")
		(net "P5E_PEX1_STN5_RX_DP<91>")
	)
	(segment
		(start 123.946666 -368.078512)
		(end 127.362712 -365.797084)
		(width 0.1651)
		(layer "In15.Cu")
		(net "P5E_PEX1_STN5_RX_DP<91>")
	)
	(segment
		(start 135.003794 -361.935522)
		(end 135.105902 -361.970066)
		(width 0.1651)
		(layer "In15.Cu")
		(net "P5E_PEX1_STN5_RX_DP<91>")
	)
	(segment
		(start 184.634124 -319.916048)
		(end 184.634124 -319.8876)
		(width 0.1143)
		(layer "In15.Cu")
		(net "P5E_PEX1_STN5_RX_DP<91>")
	)
	(segment
		(start 184.679844 -318.406272)
		(end 184.95645 -318.129666)
		(width 0.1143)
		(layer "In15.Cu")
		(net "P5E_PEX1_STN5_RX_DP<91>")
	)
	(segment
		(start 184.634124 -319.8876)
		(end 184.679844 -319.84188)
		(width 0.1143)
		(layer "In15.Cu")
		(net "P5E_PEX1_STN5_RX_DP<91>")
	)
	(segment
		(start 132.874766 -362.959396)
		(end 133.010656 -363.005624)
		(width 0.1651)
		(layer "In15.Cu")
		(net "P5E_PEX1_STN5_RX_DP<91>")
	)
	(segment
		(start 133.454648 -362.786422)
		(end 133.500622 -362.650278)
		(width 0.1651)
		(layer "In15.Cu")
		(net "P5E_PEX1_STN5_RX_DP<91>")
	)
	(segment
		(start 185.161174 -318.129666)
		(end 185.250074 -318.040766)
		(width 0.1143)
		(layer "In15.Cu")
		(net "P5E_PEX1_STN5_RX_DP<91>")
	)
	(segment
		(start 185.250074 -318.040766)
		(end 185.250074 -317.749936)
		(width 0.1143)
		(layer "In15.Cu")
		(net "P5E_PEX1_STN5_RX_DP<91>")
	)
	(segment
		(start 178.536092 -325.803514)
		(end 182.496206 -323.177408)
		(width 0.1651)
		(layer "In15.Cu")
		(net "P5E_PEX1_STN5_RX_DP<91>")
	)
	(segment
		(start 184.95645 -318.129666)
		(end 185.161174 -318.129666)
		(width 0.1143)
		(layer "In15.Cu")
		(net "P5E_PEX1_STN5_RX_DP<91>")
	)
	(segment
		(start 184.634124 -320.546984)
		(end 184.634124 -319.916048)
		(width 0.1651)
		(layer "In15.Cu")
		(net "P5E_PEX1_STN5_RX_DP<91>")
	)
	(segment
		(start 134.081012 -362.476542)
		(end 134.525004 -362.25734)
		(width 0.1651)
		(layer "In15.Cu")
		(net "P5E_PEX1_STN5_RX_DP<91>")
	)
	(segment
		(start 122.510042 -371.590062)
		(end 122.510042 -371.972078)
		(width 0.1651)
		(layer "In15.Cu")
		(net "P5E_PEX1_STN5_RX_DP<91>")
	)
	(segment
		(start 144.320514 -339.65388)
		(end 178.536092 -325.803514)
		(width 0.1651)
		(layer "In15.Cu")
		(net "P5E_PEX1_STN5_RX_DP<91>")
	)
	(segment
		(start 134.559548 -362.155232)
		(end 135.003794 -361.935522)
		(width 0.1651)
		(layer "In15.Cu")
		(net "P5E_PEX1_STN5_RX_DP<91>")
	)
	(segment
		(start 122.510042 -371.972078)
		(end 122.637042 -372.099078)
		(width 0.1651)
		(layer "In15.Cu")
		(net "P5E_PEX1_STN5_RX_DP<91>")
	)
	(segment
		(start 122.85853 -372.099078)
		(end 123.417838 -371.53977)
		(width 0.1651)
		(layer "In15.Cu")
		(net "P5E_PEX1_STN5_RX_DP<91>")
	)
	(segment
		(start 183.84647 -321.827144)
		(end 184.634124 -320.546984)
		(width 0.1651)
		(layer "In15.Cu")
		(net "P5E_PEX1_STN5_RX_DP<91>")
	)
	(segment
		(start 123.417838 -369.067588)
		(end 123.946666 -368.078512)
		(width 0.1651)
		(layer "In15.Cu")
		(net "P5E_PEX1_STN5_RX_DP<91>")
	)
	(segment
		(start 132.384292 -363.31525)
		(end 132.430266 -363.179106)
		(width 0.1651)
		(layer "In15.Cu")
		(net "P5E_PEX1_STN5_RX_DP<91>")
	)
	(segment
		(start 182.496206 -323.177408)
		(end 183.84647 -321.827144)
		(width 0.1651)
		(layer "In15.Cu")
		(net "P5E_PEX1_STN5_RX_DP<91>")
	)
	(segment
		(start 133.500622 -362.650278)
		(end 133.944868 -362.430568)
		(width 0.1651)
		(layer "In15.Cu")
		(net "P5E_PEX1_STN5_RX_DP<91>")
	)
	(segment
		(start 133.944868 -362.430568)
		(end 134.081012 -362.476542)
		(width 0.1651)
		(layer "In15.Cu")
		(net "P5E_PEX1_STN5_RX_DP<91>")
	)
	(segment
		(start 141.688058 -358.05999)
		(end 141.688058 -341.690452)
		(width 0.1651)
		(layer "In15.Cu")
		(net "P5E_PEX1_STN5_RX_DP<91>")
	)
	(segment
		(start 135.105902 -361.970066)
		(end 141.099032 -359.008172)
		(width 0.1651)
		(layer "In15.Cu")
		(net "P5E_PEX1_STN5_RX_DP<91>")
	)
	(segment
		(start 133.010656 -363.005624)
		(end 133.454648 -362.786422)
		(width 0.1651)
		(layer "In15.Cu")
		(net "P5E_PEX1_STN5_RX_DP<91>")
	)
	(segment
		(start 134.525004 -362.25734)
		(end 134.559548 -362.155232)
		(width 0.1651)
		(layer "In15.Cu")
		(net "P5E_PEX1_STN5_RX_DP<91>")
	)
	(segment
		(start 132.430266 -363.179106)
		(end 132.874766 -362.959396)
		(width 0.1651)
		(layer "In15.Cu")
		(net "P5E_PEX1_STN5_RX_DP<91>")
	)
	(segment
		(start 184.679844 -319.84188)
		(end 184.679844 -318.406272)
		(width 0.1143)
		(layer "In15.Cu")
		(net "P5E_PEX1_STN5_RX_DP<91>")
	)
	(segment
		(start 127.362712 -365.797084)
		(end 132.384292 -363.31525)
		(width 0.1651)
		(layer "In15.Cu")
		(net "P5E_PEX1_STN5_RX_DP<91>")
	)
	(segment
		(start 123.417838 -371.53977)
		(end 123.417838 -369.067588)
		(width 0.1651)
		(layer "In15.Cu")
		(net "P5E_PEX1_STN5_RX_DP<91>")
	)
	(segment
		(start 142.230094 -340.886542)
		(end 144.320514 -339.65388)
		(width 0.1651)
		(layer "In15.Cu")
		(net "P5E_PEX1_STN5_RX_DP<91>")
	)
	(segment
		(start 141.688058 -341.690452)
		(end 142.230094 -340.886542)
		(width 0.1651)
		(layer "In15.Cu")
		(net "P5E_PEX1_STN5_RX_DP<91>")
	)
	(segment
		(start 63.27775 -113.251742)
		(end 63.27775 -112.630204)
		(width 0.13208)
		(layer "F.Cu")
		(net "RST_SMB_NIC1_MUX_ISO_N")
	)
	(segment
		(start 63.39713 -112.510824)
		(end 64.18453 -112.510824)
		(width 0.13208)
		(layer "F.Cu")
		(net "RST_SMB_NIC1_MUX_ISO_N")
	)
	(segment
		(start 63.27775 -115.283742)
		(end 63.27775 -114.267742)
		(width 0.13208)
		(layer "F.Cu")
		(net "RST_SMB_NIC1_MUX_ISO_N")
	)
	(segment
		(start 63.27775 -112.630204)
		(end 63.39713 -112.510824)
		(width 0.13208)
		(layer "F.Cu")
		(net "RST_SMB_NIC1_MUX_ISO_N")
	)
	(segment
		(start 63.27775 -114.267742)
		(end 63.27775 -113.251742)
		(width 0.13208)
		(layer "F.Cu")
		(net "RST_SMB_NIC1_MUX_ISO_N")
	)
	(via
		(at 64.18453 -112.510824)
		(size 0.508)
		(drill 0.254)
		(layers "F.Cu" "B.Cu")
		(net "RST_SMB_NIC1_MUX_ISO_N")
	)
	(segment
		(start 66.183764 -115.816634)
		(end 68.378578 -115.816634)
		(width 0.13208)
		(layer "B.Cu")
		(net "RST_SMB_NIC1_MUX_ISO_N")
	)
	(segment
		(start 65.616328 -115.240054)
		(end 65.635124 -115.267994)
		(width 0.13208)
		(layer "B.Cu")
		(net "RST_SMB_NIC1_MUX_ISO_N")
	)
	(segment
		(start 65.167002 -112.45469)
		(end 65.41135 -112.699038)
		(width 0.13208)
		(layer "B.Cu")
		(net "RST_SMB_NIC1_MUX_ISO_N")
	)
	(segment
		(start 68.499228 -115.937284)
		(end 68.499228 -116.513356)
		(width 0.13208)
		(layer "B.Cu")
		(net "RST_SMB_NIC1_MUX_ISO_N")
	)
	(segment
		(start 68.378578 -115.816634)
		(end 68.499228 -115.937284)
		(width 0.13208)
		(layer "B.Cu")
		(net "RST_SMB_NIC1_MUX_ISO_N")
	)
	(segment
		(start 64.240664 -112.45469)
		(end 65.167002 -112.45469)
		(width 0.13208)
		(layer "B.Cu")
		(net "RST_SMB_NIC1_MUX_ISO_N")
	)
	(segment
		(start 65.573402 -115.197382)
		(end 65.616328 -115.240054)
		(width 0.13208)
		(layer "B.Cu")
		(net "RST_SMB_NIC1_MUX_ISO_N")
	)
	(segment
		(start 65.41135 -112.699038)
		(end 65.41135 -115.03533)
		(width 0.13208)
		(layer "B.Cu")
		(net "RST_SMB_NIC1_MUX_ISO_N")
	)
	(segment
		(start 65.635124 -115.267994)
		(end 66.183764 -115.816634)
		(width 0.13208)
		(layer "B.Cu")
		(net "RST_SMB_NIC1_MUX_ISO_N")
	)
	(segment
		(start 65.41135 -115.03533)
		(end 65.573402 -115.197382)
		(width 0.13208)
		(layer "B.Cu")
		(net "RST_SMB_NIC1_MUX_ISO_N")
	)
	(segment
		(start 64.18453 -112.510824)
		(end 64.240664 -112.45469)
		(width 0.13208)
		(layer "B.Cu")
		(net "RST_SMB_NIC1_MUX_ISO_N")
	)
	(segment
		(start 83.87969 -135.88111)
		(end 84.17433 -136.17575)
		(width 0.13462)
		(layer "F.Cu")
		(net "P5E_PEX0_STN0_TX_DP<7>")
	)
	(segment
		(start 82.928206 -136.20115)
		(end 83.248246 -135.88111)
		(width 0.13462)
		(layer "F.Cu")
		(net "P5E_PEX0_STN0_TX_DP<7>")
	)
	(segment
		(start 83.248246 -135.88111)
		(end 83.87969 -135.88111)
		(width 0.13462)
		(layer "F.Cu")
		(net "P5E_PEX0_STN0_TX_DP<7>")
	)
	(segment
		(start 84.46516 -135.88492)
		(end 85.04428 -135.88492)
		(width 0.1651)
		(layer "In9.Cu")
		(net "P5E_PEX0_STN0_TX_DP<7>")
	)
	(segment
		(start 83.527392 -177.393854)
		(end 83.527646 -177.393854)
		(width 0.1651)
		(layer "In9.Cu")
		(net "P5E_PEX0_STN0_TX_DP<7>")
	)
	(segment
		(start 89.791032 -146.146774)
		(end 93.115384 -154.171904)
		(width 0.1651)
		(layer "In9.Cu")
		(net "P5E_PEX0_STN0_TX_DP<7>")
	)
	(segment
		(start 81.747868 -246.652034)
		(end 81.748122 -246.652034)
		(width 0.1651)
		(layer "In9.Cu")
		(net "P5E_PEX0_STN0_TX_DP<7>")
	)
	(segment
		(start 81.765394 -279.749758)
		(end 81.499964 -279.749758)
		(width 0.1143)
		(layer "In9.Cu")
		(net "P5E_PEX0_STN0_TX_DP<7>")
	)
	(segment
		(start 85.946234 -137.81151)
		(end 85.888576 -137.950702)
		(width 0.1651)
		(layer "In9.Cu")
		(net "P5E_PEX0_STN0_TX_DP<7>")
	)
	(segment
		(start 86.495128 -139.41552)
		(end 86.634828 -139.473178)
		(width 0.1651)
		(layer "In9.Cu")
		(net "P5E_PEX0_STN0_TX_DP<7>")
	)
	(segment
		(start 81.748122 -246.652034)
		(end 83.934808 -271.68348)
		(width 0.1651)
		(layer "In9.Cu")
		(net "P5E_PEX0_STN0_TX_DP<7>")
	)
	(segment
		(start 84.17433 -136.17575)
		(end 84.46516 -135.88492)
		(width 0.1651)
		(layer "In9.Cu")
		(net "P5E_PEX0_STN0_TX_DP<7>")
	)
	(segment
		(start 87.92972 -142.599156)
		(end 87.929466 -142.599156)
		(width 0.1651)
		(layer "In9.Cu")
		(net "P5E_PEX0_STN0_TX_DP<7>")
	)
	(segment
		(start 87.49792 -141.556994)
		(end 87.672672 -141.979142)
		(width 0.1651)
		(layer "In9.Cu")
		(net "P5E_PEX0_STN0_TX_DP<7>")
	)
	(segment
		(start 83.973924 -175.729646)
		(end 83.974178 -175.729646)
		(width 0.1651)
		(layer "In9.Cu")
		(net "P5E_PEX0_STN0_TX_DP<7>")
	)
	(segment
		(start 81.879694 -279.635458)
		(end 81.765394 -279.749758)
		(width 0.1143)
		(layer "In9.Cu")
		(net "P5E_PEX0_STN0_TX_DP<7>")
	)
	(segment
		(start 87.06612 -140.515086)
		(end 87.240872 -140.937234)
		(width 0.1651)
		(layer "In9.Cu")
		(net "P5E_PEX0_STN0_TX_DP<7>")
	)
	(segment
		(start 83.527646 -177.393854)
		(end 83.372706 -177.972212)
		(width 0.1651)
		(layer "In9.Cu")
		(net "P5E_PEX0_STN0_TX_DP<7>")
	)
	(segment
		(start 93.115384 -154.171904)
		(end 93.115384 -158.684722)
		(width 0.1651)
		(layer "In9.Cu")
		(net "P5E_PEX0_STN0_TX_DP<7>")
	)
	(segment
		(start 86.203028 -138.43127)
		(end 86.37778 -138.853418)
		(width 0.1651)
		(layer "In9.Cu")
		(net "P5E_PEX0_STN0_TX_DP<7>")
	)
	(segment
		(start 83.372706 -177.972212)
		(end 79.55788 -221.581218)
		(width 0.1651)
		(layer "In9.Cu")
		(net "P5E_PEX0_STN0_TX_DP<7>")
	)
	(segment
		(start 82.85099 -278.96439)
		(end 82.85099 -279.028652)
		(width 0.1143)
		(layer "In9.Cu")
		(net "P5E_PEX0_STN0_TX_DP<7>")
	)
	(segment
		(start 82.701892 -279.17775)
		(end 82.10169 -279.17775)
		(width 0.1143)
		(layer "In9.Cu")
		(net "P5E_PEX0_STN0_TX_DP<7>")
	)
	(segment
		(start 86.37778 -138.853418)
		(end 86.320122 -138.992864)
		(width 0.1651)
		(layer "In9.Cu")
		(net "P5E_PEX0_STN0_TX_DP<7>")
	)
	(segment
		(start 89.791286 -146.146774)
		(end 89.791032 -146.146774)
		(width 0.1651)
		(layer "In9.Cu")
		(net "P5E_PEX0_STN0_TX_DP<7>")
	)
	(segment
		(start 85.888576 -137.950702)
		(end 86.063582 -138.373358)
		(width 0.1651)
		(layer "In9.Cu")
		(net "P5E_PEX0_STN0_TX_DP<7>")
	)
	(segment
		(start 86.320122 -138.992864)
		(end 86.495128 -139.41552)
		(width 0.1651)
		(layer "In9.Cu")
		(net "P5E_PEX0_STN0_TX_DP<7>")
	)
	(segment
		(start 85.757512 -137.355326)
		(end 85.946234 -137.81151)
		(width 0.1651)
		(layer "In9.Cu")
		(net "P5E_PEX0_STN0_TX_DP<7>")
	)
	(segment
		(start 93.115384 -158.684722)
		(end 84.578698 -173.475142)
		(width 0.1651)
		(layer "In9.Cu")
		(net "P5E_PEX0_STN0_TX_DP<7>")
	)
	(segment
		(start 85.617812 -137.297414)
		(end 85.757512 -137.355326)
		(width 0.1651)
		(layer "In9.Cu")
		(net "P5E_PEX0_STN0_TX_DP<7>")
	)
	(segment
		(start 83.934808 -271.68348)
		(end 83.81238 -277.275798)
		(width 0.1651)
		(layer "In9.Cu")
		(net "P5E_PEX0_STN0_TX_DP<7>")
	)
	(segment
		(start 87.183214 -141.07668)
		(end 87.35822 -141.499336)
		(width 0.1651)
		(layer "In9.Cu")
		(net "P5E_PEX0_STN0_TX_DP<7>")
	)
	(segment
		(start 81.879694 -279.400254)
		(end 81.879694 -279.635458)
		(width 0.1143)
		(layer "In9.Cu")
		(net "P5E_PEX0_STN0_TX_DP<7>")
	)
	(segment
		(start 83.676236 -176.839118)
		(end 83.527392 -177.393854)
		(width 0.1651)
		(layer "In9.Cu")
		(net "P5E_PEX0_STN0_TX_DP<7>")
	)
	(segment
		(start 84.578698 -173.475142)
		(end 83.973924 -175.729646)
		(width 0.1651)
		(layer "In9.Cu")
		(net "P5E_PEX0_STN0_TX_DP<7>")
	)
	(segment
		(start 86.809326 -139.895326)
		(end 86.751668 -140.034772)
		(width 0.1651)
		(layer "In9.Cu")
		(net "P5E_PEX0_STN0_TX_DP<7>")
	)
	(segment
		(start 85.44306 -136.874758)
		(end 85.617812 -137.297414)
		(width 0.1651)
		(layer "In9.Cu")
		(net "P5E_PEX0_STN0_TX_DP<7>")
	)
	(segment
		(start 83.974178 -175.729646)
		(end 83.67649 -176.839118)
		(width 0.1651)
		(layer "In9.Cu")
		(net "P5E_PEX0_STN0_TX_DP<7>")
	)
	(segment
		(start 86.926674 -140.457428)
		(end 87.066374 -140.515086)
		(width 0.1651)
		(layer "In9.Cu")
		(net "P5E_PEX0_STN0_TX_DP<7>")
	)
	(segment
		(start 86.634828 -139.473178)
		(end 86.634574 -139.473178)
		(width 0.1651)
		(layer "In9.Cu")
		(net "P5E_PEX0_STN0_TX_DP<7>")
	)
	(segment
		(start 85.22208 -136.06272)
		(end 85.500718 -136.735566)
		(width 0.1651)
		(layer "In9.Cu")
		(net "P5E_PEX0_STN0_TX_DP<7>")
	)
	(segment
		(start 87.672672 -141.979142)
		(end 87.615014 -142.118588)
		(width 0.1651)
		(layer "In9.Cu")
		(net "P5E_PEX0_STN0_TX_DP<7>")
	)
	(segment
		(start 82.871056 -278.944324)
		(end 82.85099 -278.96439)
		(width 0.1143)
		(layer "In9.Cu")
		(net "P5E_PEX0_STN0_TX_DP<7>")
	)
	(segment
		(start 86.751668 -140.034772)
		(end 86.926674 -140.457428)
		(width 0.1651)
		(layer "In9.Cu")
		(net "P5E_PEX0_STN0_TX_DP<7>")
	)
	(segment
		(start 87.929466 -142.599156)
		(end 89.121742 -145.47723)
		(width 0.1651)
		(layer "In9.Cu")
		(net "P5E_PEX0_STN0_TX_DP<7>")
	)
	(segment
		(start 89.121742 -145.47723)
		(end 89.791286 -146.146774)
		(width 0.1651)
		(layer "In9.Cu")
		(net "P5E_PEX0_STN0_TX_DP<7>")
	)
	(segment
		(start 82.10169 -279.17775)
		(end 81.879694 -279.400254)
		(width 0.1143)
		(layer "In9.Cu")
		(net "P5E_PEX0_STN0_TX_DP<7>")
	)
	(segment
		(start 87.79002 -142.541244)
		(end 87.92972 -142.599156)
		(width 0.1651)
		(layer "In9.Cu")
		(net "P5E_PEX0_STN0_TX_DP<7>")
	)
	(segment
		(start 87.066374 -140.515086)
		(end 87.06612 -140.515086)
		(width 0.1651)
		(layer "In9.Cu")
		(net "P5E_PEX0_STN0_TX_DP<7>")
	)
	(segment
		(start 87.35822 -141.499336)
		(end 87.49792 -141.556994)
		(width 0.1651)
		(layer "In9.Cu")
		(net "P5E_PEX0_STN0_TX_DP<7>")
	)
	(segment
		(start 79.55788 -221.581218)
		(end 81.747868 -246.652034)
		(width 0.1651)
		(layer "In9.Cu")
		(net "P5E_PEX0_STN0_TX_DP<7>")
	)
	(segment
		(start 82.85099 -279.028652)
		(end 82.701892 -279.17775)
		(width 0.1143)
		(layer "In9.Cu")
		(net "P5E_PEX0_STN0_TX_DP<7>")
	)
	(segment
		(start 86.063582 -138.373358)
		(end 86.203282 -138.43127)
		(width 0.1651)
		(layer "In9.Cu")
		(net "P5E_PEX0_STN0_TX_DP<7>")
	)
	(segment
		(start 83.67649 -176.839118)
		(end 83.676236 -176.839118)
		(width 0.1651)
		(layer "In9.Cu")
		(net "P5E_PEX0_STN0_TX_DP<7>")
	)
	(segment
		(start 83.81238 -277.275798)
		(end 83.104736 -278.71039)
		(width 0.1651)
		(layer "In9.Cu")
		(net "P5E_PEX0_STN0_TX_DP<7>")
	)
	(segment
		(start 87.615014 -142.118588)
		(end 87.79002 -142.541244)
		(width 0.1651)
		(layer "In9.Cu")
		(net "P5E_PEX0_STN0_TX_DP<7>")
	)
	(segment
		(start 86.203282 -138.43127)
		(end 86.203028 -138.43127)
		(width 0.1651)
		(layer "In9.Cu")
		(net "P5E_PEX0_STN0_TX_DP<7>")
	)
	(segment
		(start 85.04428 -135.88492)
		(end 85.22208 -136.06272)
		(width 0.1651)
		(layer "In9.Cu")
		(net "P5E_PEX0_STN0_TX_DP<7>")
	)
	(segment
		(start 86.634574 -139.473178)
		(end 86.809326 -139.895326)
		(width 0.1651)
		(layer "In9.Cu")
		(net "P5E_PEX0_STN0_TX_DP<7>")
	)
	(segment
		(start 83.104736 -278.71039)
		(end 82.871056 -278.944324)
		(width 0.1651)
		(layer "In9.Cu")
		(net "P5E_PEX0_STN0_TX_DP<7>")
	)
	(segment
		(start 85.500718 -136.735566)
		(end 85.44306 -136.874758)
		(width 0.1651)
		(layer "In9.Cu")
		(net "P5E_PEX0_STN0_TX_DP<7>")
	)
	(segment
		(start 87.240872 -140.937234)
		(end 87.183214 -141.07668)
		(width 0.1651)
		(layer "In9.Cu")
		(net "P5E_PEX0_STN0_TX_DP<7>")
	)
	(segment
		(start 39.015416 -301.599854)
		(end 38.749986 -301.599854)
		(width 0.1143)
		(layer "In5.Cu")
		(net "P5E_PEX0_STN7_RX_DN<112>")
	)
	(segment
		(start 29.05887 -395.380464)
		(end 28.6512 -394.395452)
		(width 0.1651)
		(layer "In5.Cu")
		(net "P5E_PEX0_STN7_RX_DN<112>")
	)
	(segment
		(start 21.789644 -309.477156)
		(end 21.747988 -309.339742)
		(width 0.1651)
		(layer "In5.Cu")
		(net "P5E_PEX0_STN7_RX_DN<112>")
	)
	(segment
		(start 29.05887 -408.40533)
		(end 29.05887 -395.380464)
		(width 0.1651)
		(layer "In5.Cu")
		(net "P5E_PEX0_STN7_RX_DN<112>")
	)
	(segment
		(start 28.037028 -408.981148)
		(end 28.483052 -408.981148)
		(width 0.1651)
		(layer "In5.Cu")
		(net "P5E_PEX0_STN7_RX_DN<112>")
	)
	(segment
		(start 17.108424 -369.673378)
		(end 14.4018 -351.42805)
		(width 0.1651)
		(layer "In5.Cu")
		(net "P5E_PEX0_STN7_RX_DN<112>")
	)
	(segment
		(start 28.933648 -302.009556)
		(end 32.672782 -301.265844)
		(width 0.1651)
		(layer "In5.Cu")
		(net "P5E_PEX0_STN7_RX_DN<112>")
	)
	(segment
		(start 18.385536 -317.687452)
		(end 18.8595 -315.89091)
		(width 0.1651)
		(layer "In5.Cu")
		(net "P5E_PEX0_STN7_RX_DN<112>")
	)
	(segment
		(start 21.47443 -388.850632)
		(end 20.413726 -386.290312)
		(width 0.1651)
		(layer "In5.Cu")
		(net "P5E_PEX0_STN7_RX_DN<112>")
	)
	(segment
		(start 27.455114 -302.731932)
		(end 27.510232 -302.599344)
		(width 0.1651)
		(layer "In5.Cu")
		(net "P5E_PEX0_STN7_RX_DN<112>")
	)
	(segment
		(start 23.73249 -391.108692)
		(end 21.47443 -388.850632)
		(width 0.1651)
		(layer "In5.Cu")
		(net "P5E_PEX0_STN7_RX_DN<112>")
	)
	(segment
		(start 14.4018 -342.63711)
		(end 15.863316 -330.786486)
		(width 0.1651)
		(layer "In5.Cu")
		(net "P5E_PEX0_STN7_RX_DN<112>")
	)
	(segment
		(start 24.515318 -304.897282)
		(end 26.320496 -303.092104)
		(width 0.1651)
		(layer "In5.Cu")
		(net "P5E_PEX0_STN7_RX_DN<112>")
	)
	(segment
		(start 27.910028 -409.490164)
		(end 27.910028 -409.108148)
		(width 0.1651)
		(layer "In5.Cu")
		(net "P5E_PEX0_STN7_RX_DN<112>")
	)
	(segment
		(start 21.981414 -308.903116)
		(end 22.118828 -308.861206)
		(width 0.1651)
		(layer "In5.Cu")
		(net "P5E_PEX0_STN7_RX_DN<112>")
	)
	(segment
		(start 36.3474 -301.265844)
		(end 36.39312 -301.220124)
		(width 0.1143)
		(layer "In5.Cu")
		(net "P5E_PEX0_STN7_RX_DN<112>")
	)
	(segment
		(start 28.483052 -408.981148)
		(end 29.05887 -408.40533)
		(width 0.1651)
		(layer "In5.Cu")
		(net "P5E_PEX0_STN7_RX_DN<112>")
	)
	(segment
		(start 20.971002 -310.793384)
		(end 21.41855 -309.955946)
		(width 0.1651)
		(layer "In5.Cu")
		(net "P5E_PEX0_STN7_RX_DN<112>")
	)
	(segment
		(start 26.320496 -303.092104)
		(end 26.864564 -302.866806)
		(width 0.1651)
		(layer "In5.Cu")
		(net "P5E_PEX0_STN7_RX_DN<112>")
	)
	(segment
		(start 20.413726 -386.290312)
		(end 17.108424 -369.673378)
		(width 0.1651)
		(layer "In5.Cu")
		(net "P5E_PEX0_STN7_RX_DN<112>")
	)
	(segment
		(start 39.129716 -301.485554)
		(end 39.015416 -301.599854)
		(width 0.1143)
		(layer "In5.Cu")
		(net "P5E_PEX0_STN7_RX_DN<112>")
	)
	(segment
		(start 27.910028 -409.108148)
		(end 28.037028 -408.981148)
		(width 0.1651)
		(layer "In5.Cu")
		(net "P5E_PEX0_STN7_RX_DN<112>")
	)
	(segment
		(start 39.015416 -301.220124)
		(end 39.129716 -301.334424)
		(width 0.1143)
		(layer "In5.Cu")
		(net "P5E_PEX0_STN7_RX_DN<112>")
	)
	(segment
		(start 39.129716 -301.334424)
		(end 39.129716 -301.485554)
		(width 0.1143)
		(layer "In5.Cu")
		(net "P5E_PEX0_STN7_RX_DN<112>")
	)
	(segment
		(start 22.310852 -308.286658)
		(end 22.548088 -307.842412)
		(width 0.1651)
		(layer "In5.Cu")
		(net "P5E_PEX0_STN7_RX_DN<112>")
	)
	(segment
		(start 32.672782 -301.265844)
		(end 36.318952 -301.265844)
		(width 0.1651)
		(layer "In5.Cu")
		(net "P5E_PEX0_STN7_RX_DN<112>")
	)
	(segment
		(start 14.4018 -351.42805)
		(end 14.4018 -342.63711)
		(width 0.1651)
		(layer "In5.Cu")
		(net "P5E_PEX0_STN7_RX_DN<112>")
	)
	(segment
		(start 28.6512 -394.395452)
		(end 23.73249 -391.108692)
		(width 0.1651)
		(layer "In5.Cu")
		(net "P5E_PEX0_STN7_RX_DN<112>")
	)
	(segment
		(start 21.41855 -309.955946)
		(end 21.555964 -309.91429)
		(width 0.1651)
		(layer "In5.Cu")
		(net "P5E_PEX0_STN7_RX_DN<112>")
	)
	(segment
		(start 22.118828 -308.861206)
		(end 22.352508 -308.424326)
		(width 0.1651)
		(layer "In5.Cu")
		(net "P5E_PEX0_STN7_RX_DN<112>")
	)
	(segment
		(start 27.510232 -302.599344)
		(end 28.933648 -302.009556)
		(width 0.1651)
		(layer "In5.Cu")
		(net "P5E_PEX0_STN7_RX_DN<112>")
	)
	(segment
		(start 36.318952 -301.265844)
		(end 36.3474 -301.265844)
		(width 0.1143)
		(layer "In5.Cu")
		(net "P5E_PEX0_STN7_RX_DN<112>")
	)
	(segment
		(start 21.555964 -309.91429)
		(end 21.789644 -309.477156)
		(width 0.1651)
		(layer "In5.Cu")
		(net "P5E_PEX0_STN7_RX_DN<112>")
	)
	(segment
		(start 22.548088 -307.842412)
		(end 24.515318 -304.897282)
		(width 0.1651)
		(layer "In5.Cu")
		(net "P5E_PEX0_STN7_RX_DN<112>")
	)
	(segment
		(start 15.863316 -330.786486)
		(end 18.385536 -317.687452)
		(width 0.1651)
		(layer "In5.Cu")
		(net "P5E_PEX0_STN7_RX_DN<112>")
	)
	(segment
		(start 21.747988 -309.339742)
		(end 21.981414 -308.903116)
		(width 0.1651)
		(layer "In5.Cu")
		(net "P5E_PEX0_STN7_RX_DN<112>")
	)
	(segment
		(start 26.997406 -302.921924)
		(end 27.455114 -302.731932)
		(width 0.1651)
		(layer "In5.Cu")
		(net "P5E_PEX0_STN7_RX_DN<112>")
	)
	(segment
		(start 18.8595 -315.89091)
		(end 20.971002 -310.793384)
		(width 0.1651)
		(layer "In5.Cu")
		(net "P5E_PEX0_STN7_RX_DN<112>")
	)
	(segment
		(start 22.352508 -308.424326)
		(end 22.310852 -308.286658)
		(width 0.1651)
		(layer "In5.Cu")
		(net "P5E_PEX0_STN7_RX_DN<112>")
	)
	(segment
		(start 36.39312 -301.220124)
		(end 39.015416 -301.220124)
		(width 0.1143)
		(layer "In5.Cu")
		(net "P5E_PEX0_STN7_RX_DN<112>")
	)
	(segment
		(start 26.864564 -302.866806)
		(end 26.997406 -302.921924)
		(width 0.1651)
		(layer "In5.Cu")
		(net "P5E_PEX0_STN7_RX_DN<112>")
	)
	(via
		(at 66.068194 -112.67059)
		(size 0.6604)
		(drill 0.3302)
		(layers "F.Cu" "B.Cu")
		(net "RST_SMB_NIC1_MUX_N")
	)
	(segment
		(start 66.476626 -111.727234)
		(end 66.068194 -112.135666)
		(width 0.13208)
		(layer "B.Cu")
		(net "RST_SMB_NIC1_MUX_N")
	)
	(segment
		(start 66.823844 -114.021616)
		(end 68.992242 -114.021616)
		(width 0.13208)
		(layer "B.Cu")
		(net "RST_SMB_NIC1_MUX_N")
	)
	(segment
		(start 68.992242 -114.021616)
		(end 69.24929 -114.278664)
		(width 0.13208)
		(layer "B.Cu")
		(net "RST_SMB_NIC1_MUX_N")
	)
	(segment
		(start 66.068194 -113.265966)
		(end 66.823844 -114.021616)
		(width 0.13208)
		(layer "B.Cu")
		(net "RST_SMB_NIC1_MUX_N")
	)
	(segment
		(start 69.24929 -114.278664)
		(end 69.24929 -114.713512)
		(width 0.13208)
		(layer "B.Cu")
		(net "RST_SMB_NIC1_MUX_N")
	)
	(segment
		(start 66.068194 -112.67059)
		(end 66.068194 -113.265966)
		(width 0.13208)
		(layer "B.Cu")
		(net "RST_SMB_NIC1_MUX_N")
	)
	(segment
		(start 66.476626 -111.334042)
		(end 66.476626 -111.727234)
		(width 0.13208)
		(layer "B.Cu")
		(net "RST_SMB_NIC1_MUX_N")
	)
	(segment
		(start 66.068194 -112.135666)
		(end 66.068194 -112.67059)
		(width 0.13208)
		(layer "B.Cu")
		(net "RST_SMB_NIC1_MUX_N")
	)
	(segment
		(start 39.013892 -107.403138)
		(end 38.693852 -107.083098)
		(width 0.13462)
		(layer "F.Cu")
		(net "P5E_PEX0_STN1_TX_DN<20>")
	)
	(segment
		(start 38.062408 -107.083098)
		(end 37.767768 -107.377738)
		(width 0.13462)
		(layer "F.Cu")
		(net "P5E_PEX0_STN1_TX_DN<20>")
	)
	(segment
		(start 38.693852 -107.083098)
		(end 38.062408 -107.083098)
		(width 0.13462)
		(layer "F.Cu")
		(net "P5E_PEX0_STN1_TX_DN<20>")
	)
	(segment
		(start 30.818328 -112.102392)
		(end 30.967934 -112.040416)
		(width 0.1651)
		(layer "In9.Cu")
		(net "P5E_PEX0_STN1_TX_DN<20>")
	)
	(segment
		(start 32.899604 -108.7755)
		(end 33.241234 -108.43387)
		(width 0.1651)
		(layer "In9.Cu")
		(net "P5E_PEX0_STN1_TX_DN<20>")
	)
	(segment
		(start 30.967934 -112.040416)
		(end 31.152592 -111.594392)
		(width 0.1651)
		(layer "In9.Cu")
		(net "P5E_PEX0_STN1_TX_DN<20>")
	)
	(segment
		(start 32.73806 -108.7755)
		(end 32.899604 -108.7755)
		(width 0.1651)
		(layer "In9.Cu")
		(net "P5E_PEX0_STN1_TX_DN<20>")
	)
	(segment
		(start 24.358092 -131.214368)
		(end 28.340812 -118.084092)
		(width 0.1651)
		(layer "In9.Cu")
		(net "P5E_PEX0_STN1_TX_DN<20>")
	)
	(segment
		(start 30.358588 -113.212372)
		(end 30.50794 -113.15065)
		(width 0.1651)
		(layer "In9.Cu")
		(net "P5E_PEX0_STN1_TX_DN<20>")
	)
	(segment
		(start 31.609538 -110.49127)
		(end 31.547562 -110.341918)
		(width 0.1651)
		(layer "In9.Cu")
		(net "P5E_PEX0_STN1_TX_DN<20>")
	)
	(segment
		(start 31.152592 -111.594392)
		(end 31.090616 -111.44504)
		(width 0.1651)
		(layer "In9.Cu")
		(net "P5E_PEX0_STN1_TX_DN<20>")
	)
	(segment
		(start 26.93797 -144.425924)
		(end 24.358092 -138.197844)
		(width 0.1651)
		(layer "In9.Cu")
		(net "P5E_PEX0_STN1_TX_DN<20>")
	)
	(segment
		(start 37.476938 -107.086908)
		(end 37.767768 -107.377738)
		(width 0.1651)
		(layer "In9.Cu")
		(net "P5E_PEX0_STN1_TX_DN<20>")
	)
	(segment
		(start 27.663648 -159.187134)
		(end 26.93797 -144.425924)
		(width 0.1651)
		(layer "In9.Cu")
		(net "P5E_PEX0_STN1_TX_DN<20>")
	)
	(segment
		(start 35.620706 -107.086908)
		(end 36.10356 -107.086908)
		(width 0.1651)
		(layer "In9.Cu")
		(net "P5E_PEX0_STN1_TX_DN<20>")
	)
	(segment
		(start 63.335408 -278.229568)
		(end 63.17361 -278.229568)
		(width 0.1143)
		(layer "In9.Cu")
		(net "P5E_PEX0_STN1_TX_DN<20>")
	)
	(segment
		(start 63.115952 -271.471898)
		(end 63.115952 -265.086338)
		(width 0.1651)
		(layer "In9.Cu")
		(net "P5E_PEX0_STN1_TX_DN<20>")
	)
	(segment
		(start 63.115952 -265.086338)
		(end 28.223972 -162.004248)
		(width 0.1651)
		(layer "In9.Cu")
		(net "P5E_PEX0_STN1_TX_DN<20>")
	)
	(segment
		(start 30.051248 -114.253518)
		(end 30.235906 -113.807494)
		(width 0.1651)
		(layer "In9.Cu")
		(net "P5E_PEX0_STN1_TX_DN<20>")
	)
	(segment
		(start 31.813246 -109.700314)
		(end 32.73806 -108.7755)
		(width 0.1651)
		(layer "In9.Cu")
		(net "P5E_PEX0_STN1_TX_DN<20>")
	)
	(segment
		(start 24.358092 -138.197844)
		(end 24.358092 -131.214368)
		(width 0.1651)
		(layer "In9.Cu")
		(net "P5E_PEX0_STN1_TX_DN<20>")
	)
	(segment
		(start 63.115952 -271.500346)
		(end 63.115952 -271.471898)
		(width 0.1143)
		(layer "In9.Cu")
		(net "P5E_PEX0_STN1_TX_DN<20>")
	)
	(segment
		(start 30.50794 -113.15065)
		(end 30.692852 -112.704626)
		(width 0.1651)
		(layer "In9.Cu")
		(net "P5E_PEX0_STN1_TX_DN<20>")
	)
	(segment
		(start 30.630876 -112.555274)
		(end 30.818328 -112.102392)
		(width 0.1651)
		(layer "In9.Cu")
		(net "P5E_PEX0_STN1_TX_DN<20>")
	)
	(segment
		(start 36.70046 -107.201208)
		(end 36.81476 -107.086908)
		(width 0.1651)
		(layer "In9.Cu")
		(net "P5E_PEX0_STN1_TX_DN<20>")
	)
	(segment
		(start 31.275274 -110.99927)
		(end 31.42488 -110.937294)
		(width 0.1651)
		(layer "In9.Cu")
		(net "P5E_PEX0_STN1_TX_DN<20>")
	)
	(segment
		(start 31.547562 -110.341918)
		(end 31.813246 -109.700314)
		(width 0.1651)
		(layer "In9.Cu")
		(net "P5E_PEX0_STN1_TX_DN<20>")
	)
	(segment
		(start 29.168344 -116.085874)
		(end 29.444696 -115.418616)
		(width 0.1651)
		(layer "In9.Cu")
		(net "P5E_PEX0_STN1_TX_DN<20>")
	)
	(segment
		(start 63.070232 -271.546066)
		(end 63.115952 -271.500346)
		(width 0.1143)
		(layer "In9.Cu")
		(net "P5E_PEX0_STN1_TX_DN<20>")
	)
	(segment
		(start 29.716984 -114.761264)
		(end 29.901642 -114.315494)
		(width 0.1651)
		(layer "In9.Cu")
		(net "P5E_PEX0_STN1_TX_DN<20>")
	)
	(segment
		(start 63.449708 -278.115268)
		(end 63.335408 -278.229568)
		(width 0.1143)
		(layer "In9.Cu")
		(net "P5E_PEX0_STN1_TX_DN<20>")
	)
	(segment
		(start 29.045662 -116.68125)
		(end 29.23032 -116.235226)
		(width 0.1651)
		(layer "In9.Cu")
		(net "P5E_PEX0_STN1_TX_DN<20>")
	)
	(segment
		(start 63.449708 -277.849838)
		(end 63.449708 -278.115268)
		(width 0.1143)
		(layer "In9.Cu")
		(net "P5E_PEX0_STN1_TX_DN<20>")
	)
	(segment
		(start 28.223972 -162.004248)
		(end 27.663648 -159.187134)
		(width 0.1651)
		(layer "In9.Cu")
		(net "P5E_PEX0_STN1_TX_DN<20>")
	)
	(segment
		(start 29.77896 -114.910616)
		(end 29.716984 -114.761264)
		(width 0.1651)
		(layer "In9.Cu")
		(net "P5E_PEX0_STN1_TX_DN<20>")
	)
	(segment
		(start 31.42488 -110.937294)
		(end 31.609538 -110.49127)
		(width 0.1651)
		(layer "In9.Cu")
		(net "P5E_PEX0_STN1_TX_DN<20>")
	)
	(segment
		(start 30.692852 -112.704626)
		(end 30.630876 -112.555274)
		(width 0.1651)
		(layer "In9.Cu")
		(net "P5E_PEX0_STN1_TX_DN<20>")
	)
	(segment
		(start 29.901642 -114.315494)
		(end 30.051248 -114.253518)
		(width 0.1651)
		(layer "In9.Cu")
		(net "P5E_PEX0_STN1_TX_DN<20>")
	)
	(segment
		(start 63.070232 -278.12619)
		(end 63.070232 -271.546066)
		(width 0.1143)
		(layer "In9.Cu")
		(net "P5E_PEX0_STN1_TX_DN<20>")
	)
	(segment
		(start 28.340812 -118.084092)
		(end 28.896056 -116.743226)
		(width 0.1651)
		(layer "In9.Cu")
		(net "P5E_PEX0_STN1_TX_DN<20>")
	)
	(segment
		(start 30.17393 -113.658142)
		(end 30.358588 -113.212372)
		(width 0.1651)
		(layer "In9.Cu")
		(net "P5E_PEX0_STN1_TX_DN<20>")
	)
	(segment
		(start 36.10356 -107.086908)
		(end 36.21786 -107.201208)
		(width 0.1651)
		(layer "In9.Cu")
		(net "P5E_PEX0_STN1_TX_DN<20>")
	)
	(segment
		(start 29.594302 -115.35664)
		(end 29.77896 -114.910616)
		(width 0.1651)
		(layer "In9.Cu")
		(net "P5E_PEX0_STN1_TX_DN<20>")
	)
	(segment
		(start 29.444696 -115.418616)
		(end 29.594302 -115.35664)
		(width 0.1651)
		(layer "In9.Cu")
		(net "P5E_PEX0_STN1_TX_DN<20>")
	)
	(segment
		(start 30.235906 -113.807494)
		(end 30.17393 -113.658142)
		(width 0.1651)
		(layer "In9.Cu")
		(net "P5E_PEX0_STN1_TX_DN<20>")
	)
	(segment
		(start 29.23032 -116.235226)
		(end 29.168344 -116.085874)
		(width 0.1651)
		(layer "In9.Cu")
		(net "P5E_PEX0_STN1_TX_DN<20>")
	)
	(segment
		(start 63.17361 -278.229568)
		(end 63.070232 -278.12619)
		(width 0.1143)
		(layer "In9.Cu")
		(net "P5E_PEX0_STN1_TX_DN<20>")
	)
	(segment
		(start 36.81476 -107.086908)
		(end 37.476938 -107.086908)
		(width 0.1651)
		(layer "In9.Cu")
		(net "P5E_PEX0_STN1_TX_DN<20>")
	)
	(segment
		(start 31.090616 -111.44504)
		(end 31.275274 -110.99927)
		(width 0.1651)
		(layer "In9.Cu")
		(net "P5E_PEX0_STN1_TX_DN<20>")
	)
	(segment
		(start 28.896056 -116.743226)
		(end 29.045662 -116.68125)
		(width 0.1651)
		(layer "In9.Cu")
		(net "P5E_PEX0_STN1_TX_DN<20>")
	)
	(segment
		(start 33.241234 -108.272326)
		(end 33.582356 -107.931204)
		(width 0.1651)
		(layer "In9.Cu")
		(net "P5E_PEX0_STN1_TX_DN<20>")
	)
	(segment
		(start 33.241234 -108.43387)
		(end 33.241234 -108.272326)
		(width 0.1651)
		(layer "In9.Cu")
		(net "P5E_PEX0_STN1_TX_DN<20>")
	)
	(segment
		(start 33.582356 -107.931204)
		(end 35.620706 -107.086908)
		(width 0.1651)
		(layer "In9.Cu")
		(net "P5E_PEX0_STN1_TX_DN<20>")
	)
	(segment
		(start 36.21786 -107.201208)
		(end 36.70046 -107.201208)
		(width 0.1651)
		(layer "In9.Cu")
		(net "P5E_PEX0_STN1_TX_DN<20>")
	)
	(segment
		(start 31.742888 -349.831914)
		(end 32.062928 -349.511874)
		(width 0.13462)
		(layer "F.Cu")
		(net "P5E_PEX0_STN7_TX_DP<118>")
	)
	(segment
		(start 32.062928 -348.88043)
		(end 31.768288 -348.58579)
		(width 0.13462)
		(layer "F.Cu")
		(net "P5E_PEX0_STN7_TX_DP<118>")
	)
	(segment
		(start 32.062928 -349.511874)
		(end 32.062928 -348.88043)
		(width 0.13462)
		(layer "F.Cu")
		(net "P5E_PEX0_STN7_TX_DP<118>")
	)
	(segment
		(start 32.059118 -348.29496)
		(end 32.059118 -347.541342)
		(width 0.1651)
		(layer "In7.Cu")
		(net "P5E_PEX0_STN7_TX_DP<118>")
	)
	(segment
		(start 42.170096 -307.185568)
		(end 42.284396 -307.299868)
		(width 0.1143)
		(layer "In7.Cu")
		(net "P5E_PEX0_STN7_TX_DP<118>")
	)
	(segment
		(start 35.687 -306.683918)
		(end 35.73272 -306.729638)
		(width 0.1143)
		(layer "In7.Cu")
		(net "P5E_PEX0_STN7_TX_DP<118>")
	)
	(segment
		(start 32.059118 -347.541342)
		(end 33.613598 -345.986862)
		(width 0.1651)
		(layer "In7.Cu")
		(net "P5E_PEX0_STN7_TX_DP<118>")
	)
	(segment
		(start 35.658552 -306.683918)
		(end 35.687 -306.683918)
		(width 0.1143)
		(layer "In7.Cu")
		(net "P5E_PEX0_STN7_TX_DP<118>")
	)
	(segment
		(start 42.284396 -307.299868)
		(end 42.549826 -307.299868)
		(width 0.1143)
		(layer "In7.Cu")
		(net "P5E_PEX0_STN7_TX_DP<118>")
	)
	(segment
		(start 33.613598 -345.986862)
		(end 33.613598 -341.826596)
		(width 0.1651)
		(layer "In7.Cu")
		(net "P5E_PEX0_STN7_TX_DP<118>")
	)
	(segment
		(start 23.681436 -316.850522)
		(end 24.232616 -316.025784)
		(width 0.1651)
		(layer "In7.Cu")
		(net "P5E_PEX0_STN7_TX_DP<118>")
	)
	(segment
		(start 33.613598 -341.826342)
		(end 32.262318 -338.564982)
		(width 0.1651)
		(layer "In7.Cu")
		(net "P5E_PEX0_STN7_TX_DP<118>")
	)
	(segment
		(start 22.625304 -322.556632)
		(end 22.625304 -320.204338)
		(width 0.1651)
		(layer "In7.Cu")
		(net "P5E_PEX0_STN7_TX_DP<118>")
	)
	(segment
		(start 22.625304 -320.204338)
		(end 22.932898 -318.657478)
		(width 0.1651)
		(layer "In7.Cu")
		(net "P5E_PEX0_STN7_TX_DP<118>")
	)
	(segment
		(start 33.613344 -341.826342)
		(end 33.613598 -341.826342)
		(width 0.1651)
		(layer "In7.Cu")
		(net "P5E_PEX0_STN7_TX_DP<118>")
	)
	(segment
		(start 42.170096 -306.955444)
		(end 42.170096 -307.185568)
		(width 0.1143)
		(layer "In7.Cu")
		(net "P5E_PEX0_STN7_TX_DP<118>")
	)
	(segment
		(start 32.998664 -307.259736)
		(end 34.388552 -306.683918)
		(width 0.1651)
		(layer "In7.Cu")
		(net "P5E_PEX0_STN7_TX_DP<118>")
	)
	(segment
		(start 41.94429 -306.729638)
		(end 42.170096 -306.955444)
		(width 0.1143)
		(layer "In7.Cu")
		(net "P5E_PEX0_STN7_TX_DP<118>")
	)
	(segment
		(start 34.388552 -306.683918)
		(end 35.658552 -306.683918)
		(width 0.1651)
		(layer "In7.Cu")
		(net "P5E_PEX0_STN7_TX_DP<118>")
	)
	(segment
		(start 22.932898 -318.657478)
		(end 23.681436 -316.850522)
		(width 0.1651)
		(layer "In7.Cu")
		(net "P5E_PEX0_STN7_TX_DP<118>")
	)
	(segment
		(start 31.768288 -348.58579)
		(end 32.059118 -348.29496)
		(width 0.1651)
		(layer "In7.Cu")
		(net "P5E_PEX0_STN7_TX_DP<118>")
	)
	(segment
		(start 24.232616 -316.025784)
		(end 32.998664 -307.259736)
		(width 0.1651)
		(layer "In7.Cu")
		(net "P5E_PEX0_STN7_TX_DP<118>")
	)
	(segment
		(start 33.613598 -341.826596)
		(end 33.613344 -341.826342)
		(width 0.1651)
		(layer "In7.Cu")
		(net "P5E_PEX0_STN7_TX_DP<118>")
	)
	(segment
		(start 24.353266 -326.728328)
		(end 22.625304 -322.556632)
		(width 0.1651)
		(layer "In7.Cu")
		(net "P5E_PEX0_STN7_TX_DP<118>")
	)
	(segment
		(start 35.73272 -306.729638)
		(end 41.94429 -306.729638)
		(width 0.1143)
		(layer "In7.Cu")
		(net "P5E_PEX0_STN7_TX_DP<118>")
	)
	(segment
		(start 32.262318 -338.564982)
		(end 24.353266 -326.728328)
		(width 0.1651)
		(layer "In7.Cu")
		(net "P5E_PEX0_STN7_TX_DP<118>")
	)
	(segment
		(start 29.937456 -310.743854)
		(end 29.937456 -310.618124)
		(width 0.1651)
		(layer "In5.Cu")
		(net "P5E_PEX0_STN7_RX_DN<118>")
	)
	(segment
		(start 32.065722 -308.615588)
		(end 32.415988 -308.265322)
		(width 0.1651)
		(layer "In5.Cu")
		(net "P5E_PEX0_STN7_RX_DN<118>")
	)
	(segment
		(start 29.461206 -311.094374)
		(end 29.586936 -311.094374)
		(width 0.1651)
		(layer "In5.Cu")
		(net "P5E_PEX0_STN7_RX_DN<118>")
	)
	(segment
		(start 39.129716 -307.185568)
		(end 39.015416 -307.299868)
		(width 0.1143)
		(layer "In5.Cu")
		(net "P5E_PEX0_STN7_RX_DN<118>")
	)
	(segment
		(start 24.158194 -327.890886)
		(end 24.051514 -327.794366)
		(width 0.1651)
		(layer "In5.Cu")
		(net "P5E_PEX0_STN7_RX_DN<118>")
	)
	(segment
		(start 23.993094 -326.60209)
		(end 23.862284 -323.94144)
		(width 0.1651)
		(layer "In5.Cu")
		(net "P5E_PEX0_STN7_RX_DN<118>")
	)
	(segment
		(start 42.258742 -395.264386)
		(end 42.07383 -394.817854)
		(width 0.1651)
		(layer "In5.Cu")
		(net "P5E_PEX0_STN7_RX_DN<118>")
	)
	(segment
		(start 39.129716 -307.034438)
		(end 39.129716 -307.185568)
		(width 0.1143)
		(layer "In5.Cu")
		(net "P5E_PEX0_STN7_RX_DN<118>")
	)
	(segment
		(start 41.002712 -393.746482)
		(end 27.118818 -386.325618)
		(width 0.1651)
		(layer "In5.Cu")
		(net "P5E_PEX0_STN7_RX_DN<118>")
	)
	(segment
		(start 30.763718 -309.917592)
		(end 30.763718 -309.791862)
		(width 0.1651)
		(layer "In5.Cu")
		(net "P5E_PEX0_STN7_RX_DN<118>")
	)
	(segment
		(start 42.258742 -408.40533)
		(end 42.258742 -395.264386)
		(width 0.1651)
		(layer "In5.Cu")
		(net "P5E_PEX0_STN7_RX_DN<118>")
	)
	(segment
		(start 27.118818 -386.325618)
		(end 26.482294 -385.689094)
		(width 0.1651)
		(layer "In5.Cu")
		(net "P5E_PEX0_STN7_RX_DN<118>")
	)
	(segment
		(start 34.220404 -306.965858)
		(end 35.56 -306.965858)
		(width 0.1651)
		(layer "In5.Cu")
		(net "P5E_PEX0_STN7_RX_DN<118>")
	)
	(segment
		(start 24.568658 -338.321142)
		(end 24.086058 -328.492358)
		(width 0.1651)
		(layer "In5.Cu")
		(net "P5E_PEX0_STN7_RX_DN<118>")
	)
	(segment
		(start 29.937456 -310.618124)
		(end 30.287468 -310.268112)
		(width 0.1651)
		(layer "In5.Cu")
		(net "P5E_PEX0_STN7_RX_DN<118>")
	)
	(segment
		(start 35.588448 -306.965858)
		(end 35.634168 -306.920138)
		(width 0.1143)
		(layer "In5.Cu")
		(net "P5E_PEX0_STN7_RX_DN<118>")
	)
	(segment
		(start 41.1099 -409.108148)
		(end 41.2369 -408.981148)
		(width 0.1651)
		(layer "In5.Cu")
		(net "P5E_PEX0_STN7_RX_DN<118>")
	)
	(segment
		(start 25.82926 -383.431288)
		(end 24.568658 -357.76789)
		(width 0.1651)
		(layer "In5.Cu")
		(net "P5E_PEX0_STN7_RX_DN<118>")
	)
	(segment
		(start 31.58998 -309.09133)
		(end 31.58998 -308.9656)
		(width 0.1651)
		(layer "In5.Cu")
		(net "P5E_PEX0_STN7_RX_DN<118>")
	)
	(segment
		(start 24.565356 -318.050418)
		(end 28.714192 -311.841388)
		(width 0.1651)
		(layer "In5.Cu")
		(net "P5E_PEX0_STN7_RX_DN<118>")
	)
	(segment
		(start 39.015416 -307.299868)
		(end 38.749986 -307.299868)
		(width 0.1143)
		(layer "In5.Cu")
		(net "P5E_PEX0_STN7_RX_DN<118>")
	)
	(segment
		(start 39.015416 -306.920138)
		(end 39.129716 -307.034438)
		(width 0.1143)
		(layer "In5.Cu")
		(net "P5E_PEX0_STN7_RX_DN<118>")
	)
	(segment
		(start 31.939992 -308.615588)
		(end 32.065722 -308.615588)
		(width 0.1651)
		(layer "In5.Cu")
		(net "P5E_PEX0_STN7_RX_DN<118>")
	)
	(segment
		(start 32.415988 -308.139592)
		(end 33.143698 -307.411882)
		(width 0.1651)
		(layer "In5.Cu")
		(net "P5E_PEX0_STN7_RX_DN<118>")
	)
	(segment
		(start 24.027384 -327.299828)
		(end 24.123904 -327.193402)
		(width 0.1651)
		(layer "In5.Cu")
		(net "P5E_PEX0_STN7_RX_DN<118>")
	)
	(segment
		(start 31.58998 -308.9656)
		(end 31.939992 -308.615588)
		(width 0.1651)
		(layer "In5.Cu")
		(net "P5E_PEX0_STN7_RX_DN<118>")
	)
	(segment
		(start 41.682924 -408.981148)
		(end 42.258742 -408.40533)
		(width 0.1651)
		(layer "In5.Cu")
		(net "P5E_PEX0_STN7_RX_DN<118>")
	)
	(segment
		(start 24.086058 -328.492358)
		(end 24.182578 -328.385932)
		(width 0.1651)
		(layer "In5.Cu")
		(net "P5E_PEX0_STN7_RX_DN<118>")
	)
	(segment
		(start 23.862284 -323.94144)
		(end 23.862284 -319.747646)
		(width 0.1651)
		(layer "In5.Cu")
		(net "P5E_PEX0_STN7_RX_DN<118>")
	)
	(segment
		(start 32.415988 -308.265322)
		(end 32.415988 -308.139592)
		(width 0.1651)
		(layer "In5.Cu")
		(net "P5E_PEX0_STN7_RX_DN<118>")
	)
	(segment
		(start 30.763718 -309.791862)
		(end 31.11373 -309.44185)
		(width 0.1651)
		(layer "In5.Cu")
		(net "P5E_PEX0_STN7_RX_DN<118>")
	)
	(segment
		(start 25.917652 -384.325876)
		(end 25.82926 -383.431288)
		(width 0.1651)
		(layer "In5.Cu")
		(net "P5E_PEX0_STN7_RX_DN<118>")
	)
	(segment
		(start 35.56 -306.965858)
		(end 35.588448 -306.965858)
		(width 0.1143)
		(layer "In5.Cu")
		(net "P5E_PEX0_STN7_RX_DN<118>")
	)
	(segment
		(start 23.862284 -319.747646)
		(end 24.565356 -318.050418)
		(width 0.1651)
		(layer "In5.Cu")
		(net "P5E_PEX0_STN7_RX_DN<118>")
	)
	(segment
		(start 24.182578 -328.385932)
		(end 24.158194 -327.890886)
		(width 0.1651)
		(layer "In5.Cu")
		(net "P5E_PEX0_STN7_RX_DN<118>")
	)
	(segment
		(start 31.11373 -309.44185)
		(end 31.23946 -309.44185)
		(width 0.1651)
		(layer "In5.Cu")
		(net "P5E_PEX0_STN7_RX_DN<118>")
	)
	(segment
		(start 30.413198 -310.268112)
		(end 30.763718 -309.917592)
		(width 0.1651)
		(layer "In5.Cu")
		(net "P5E_PEX0_STN7_RX_DN<118>")
	)
	(segment
		(start 28.714192 -311.841388)
		(end 29.461206 -311.094374)
		(width 0.1651)
		(layer "In5.Cu")
		(net "P5E_PEX0_STN7_RX_DN<118>")
	)
	(segment
		(start 23.99284 -326.60209)
		(end 23.993094 -326.60209)
		(width 0.1651)
		(layer "In5.Cu")
		(net "P5E_PEX0_STN7_RX_DN<118>")
	)
	(segment
		(start 31.23946 -309.44185)
		(end 31.58998 -309.09133)
		(width 0.1651)
		(layer "In5.Cu")
		(net "P5E_PEX0_STN7_RX_DN<118>")
	)
	(segment
		(start 30.287468 -310.268112)
		(end 30.413198 -310.268112)
		(width 0.1651)
		(layer "In5.Cu")
		(net "P5E_PEX0_STN7_RX_DN<118>")
	)
	(segment
		(start 42.07383 -394.817854)
		(end 41.002712 -393.746482)
		(width 0.1651)
		(layer "In5.Cu")
		(net "P5E_PEX0_STN7_RX_DN<118>")
	)
	(segment
		(start 24.051514 -327.794366)
		(end 24.027384 -327.299828)
		(width 0.1651)
		(layer "In5.Cu")
		(net "P5E_PEX0_STN7_RX_DN<118>")
	)
	(segment
		(start 24.09952 -326.698356)
		(end 23.99284 -326.60209)
		(width 0.1651)
		(layer "In5.Cu")
		(net "P5E_PEX0_STN7_RX_DN<118>")
	)
	(segment
		(start 33.143698 -307.411882)
		(end 34.220404 -306.965858)
		(width 0.1651)
		(layer "In5.Cu")
		(net "P5E_PEX0_STN7_RX_DN<118>")
	)
	(segment
		(start 24.123904 -327.193402)
		(end 24.09952 -326.698356)
		(width 0.1651)
		(layer "In5.Cu")
		(net "P5E_PEX0_STN7_RX_DN<118>")
	)
	(segment
		(start 35.634168 -306.920138)
		(end 39.015416 -306.920138)
		(width 0.1143)
		(layer "In5.Cu")
		(net "P5E_PEX0_STN7_RX_DN<118>")
	)
	(segment
		(start 41.1099 -409.490164)
		(end 41.1099 -409.108148)
		(width 0.1651)
		(layer "In5.Cu")
		(net "P5E_PEX0_STN7_RX_DN<118>")
	)
	(segment
		(start 24.568658 -357.76789)
		(end 24.568658 -338.321142)
		(width 0.1651)
		(layer "In5.Cu")
		(net "P5E_PEX0_STN7_RX_DN<118>")
	)
	(segment
		(start 29.586936 -311.094374)
		(end 29.937456 -310.743854)
		(width 0.1651)
		(layer "In5.Cu")
		(net "P5E_PEX0_STN7_RX_DN<118>")
	)
	(segment
		(start 26.482294 -385.689094)
		(end 25.917652 -384.325876)
		(width 0.1651)
		(layer "In5.Cu")
		(net "P5E_PEX0_STN7_RX_DN<118>")
	)
	(segment
		(start 41.2369 -408.981148)
		(end 41.682924 -408.981148)
		(width 0.1651)
		(layer "In5.Cu")
		(net "P5E_PEX0_STN7_RX_DN<118>")
	)
	(segment
		(start 290.664392 -139.6238)
		(end 290.664392 -140.6398)
		(width 0.13208)
		(layer "F.Cu")
		(net "RST_SMB_NIC4_MUX_ISO_N")
	)
	(segment
		(start 290.664392 -140.6398)
		(end 290.664392 -141.6558)
		(width 0.13208)
		(layer "F.Cu")
		(net "RST_SMB_NIC4_MUX_ISO_N")
	)
	(segment
		(start 290.664392 -142.57655)
		(end 290.664392 -141.6558)
		(width 0.13208)
		(layer "F.Cu")
		(net "RST_SMB_NIC4_MUX_ISO_N")
	)
	(segment
		(start 288.968942 -144.272)
		(end 290.664392 -142.57655)
		(width 0.13208)
		(layer "F.Cu")
		(net "RST_SMB_NIC4_MUX_ISO_N")
	)
	(via
		(at 288.968942 -144.272)
		(size 0.508)
		(drill 0.254)
		(layers "F.Cu" "B.Cu")
		(net "RST_SMB_NIC4_MUX_ISO_N")
	)
	(segment
		(start 287.964626 -143.267684)
		(end 287.964626 -141.6812)
		(width 0.13208)
		(layer "B.Cu")
		(net "RST_SMB_NIC4_MUX_ISO_N")
	)
	(segment
		(start 288.968942 -144.272)
		(end 287.964626 -143.267684)
		(width 0.13208)
		(layer "B.Cu")
		(net "RST_SMB_NIC4_MUX_ISO_N")
	)
	(segment
		(start 168.945052 -175.182276)
		(end 171.301664 -175.182276)
		(width 0.13208)
		(layer "F.Cu")
		(net "HP_NIC2_PWRGD")
	)
	(segment
		(start 179.747926 -170.920918)
		(end 180.067204 -171.240196)
		(width 0.13208)
		(layer "F.Cu")
		(net "HP_NIC2_PWRGD")
	)
	(segment
		(start 180.067204 -171.240196)
		(end 180.067204 -171.675806)
		(width 0.13208)
		(layer "F.Cu")
		(net "HP_NIC2_PWRGD")
	)
	(segment
		(start 180.067204 -172.586396)
		(end 180.067204 -171.675806)
		(width 0.13208)
		(layer "F.Cu")
		(net "HP_NIC2_PWRGD")
	)
	(segment
		(start 179.747926 -170.157902)
		(end 179.747926 -170.920918)
		(width 0.13208)
		(layer "F.Cu")
		(net "HP_NIC2_PWRGD")
	)
	(segment
		(start 177.471324 -175.182276)
		(end 180.067204 -172.586396)
		(width 0.13208)
		(layer "F.Cu")
		(net "HP_NIC2_PWRGD")
	)
	(segment
		(start 171.301664 -175.182276)
		(end 177.471324 -175.182276)
		(width 0.13208)
		(layer "F.Cu")
		(net "HP_NIC2_PWRGD")
	)
	(via
		(at 171.301664 -175.182276)
		(size 0.762)
		(drill 0.381)
		(layers "F.Cu" "B.Cu")
		(net "HP_NIC2_PWRGD")
	)
	(segment
		(start 83.248246 -148.59127)
		(end 83.87969 -148.59127)
		(width 0.13462)
		(layer "F.Cu")
		(net "P5E_PEX0_STN0_TX_DP<11>")
	)
	(segment
		(start 82.928206 -148.91131)
		(end 83.248246 -148.59127)
		(width 0.13462)
		(layer "F.Cu")
		(net "P5E_PEX0_STN0_TX_DP<11>")
	)
	(segment
		(start 83.87969 -148.59127)
		(end 84.17433 -148.88591)
		(width 0.13462)
		(layer "F.Cu")
		(net "P5E_PEX0_STN0_TX_DP<11>")
	)
	(segment
		(start 85.152992 -148.59508)
		(end 85.503766 -148.945854)
		(width 0.1651)
		(layer "In9.Cu")
		(net "P5E_PEX0_STN0_TX_DP<11>")
	)
	(segment
		(start 85.503766 -148.945854)
		(end 85.503766 -149.089618)
		(width 0.1651)
		(layer "In9.Cu")
		(net "P5E_PEX0_STN0_TX_DP<11>")
	)
	(segment
		(start 87.247984 -151.207724)
		(end 87.388954 -151.235664)
		(width 0.1651)
		(layer "In9.Cu")
		(net "P5E_PEX0_STN0_TX_DP<11>")
	)
	(segment
		(start 78.03388 -270.873474)
		(end 78.03388 -271.471898)
		(width 0.1651)
		(layer "In9.Cu")
		(net "P5E_PEX0_STN0_TX_DP<11>")
	)
	(segment
		(start 85.988906 -149.430994)
		(end 86.574376 -150.016464)
		(width 0.1651)
		(layer "In9.Cu")
		(net "P5E_PEX0_STN0_TX_DP<11>")
	)
	(segment
		(start 84.46516 -148.59508)
		(end 85.152992 -148.59508)
		(width 0.1651)
		(layer "In9.Cu")
		(net "P5E_PEX0_STN0_TX_DP<11>")
	)
	(segment
		(start 78.03388 -271.471898)
		(end 78.03388 -271.500346)
		(width 0.1143)
		(layer "In9.Cu")
		(net "P5E_PEX0_STN0_TX_DP<11>")
	)
	(segment
		(start 78.535276 -278.420068)
		(end 78.649576 -278.534368)
		(width 0.1143)
		(layer "In9.Cu")
		(net "P5E_PEX0_STN0_TX_DP<11>")
	)
	(segment
		(start 80.89773 -172.13961)
		(end 79.525876 -177.254408)
		(width 0.1651)
		(layer "In9.Cu")
		(net "P5E_PEX0_STN0_TX_DP<11>")
	)
	(segment
		(start 87.388954 -151.235664)
		(end 88.140032 -152.359614)
		(width 0.1651)
		(layer "In9.Cu")
		(net "P5E_PEX0_STN0_TX_DP<11>")
	)
	(segment
		(start 85.845142 -149.430994)
		(end 85.988906 -149.430994)
		(width 0.1651)
		(layer "In9.Cu")
		(net "P5E_PEX0_STN0_TX_DP<11>")
	)
	(segment
		(start 78.0796 -271.546066)
		(end 78.0796 -278.205184)
		(width 0.1143)
		(layer "In9.Cu")
		(net "P5E_PEX0_STN0_TX_DP<11>")
	)
	(segment
		(start 77.562456 -199.693276)
		(end 77.56271 -199.693276)
		(width 0.1651)
		(layer "In9.Cu")
		(net "P5E_PEX0_STN0_TX_DP<11>")
	)
	(segment
		(start 78.294484 -278.420068)
		(end 78.535276 -278.420068)
		(width 0.1143)
		(layer "In9.Cu")
		(net "P5E_PEX0_STN0_TX_DP<11>")
	)
	(segment
		(start 78.649576 -278.534368)
		(end 78.649576 -278.799798)
		(width 0.1143)
		(layer "In9.Cu")
		(net "P5E_PEX0_STN0_TX_DP<11>")
	)
	(segment
		(start 85.503766 -149.089618)
		(end 85.845142 -149.430994)
		(width 0.1651)
		(layer "In9.Cu")
		(net "P5E_PEX0_STN0_TX_DP<11>")
	)
	(segment
		(start 79.525876 -177.254408)
		(end 77.562456 -199.693276)
		(width 0.1651)
		(layer "In9.Cu")
		(net "P5E_PEX0_STN0_TX_DP<11>")
	)
	(segment
		(start 78.979268 -260.78815)
		(end 78.979268 -268.590776)
		(width 0.1651)
		(layer "In9.Cu")
		(net "P5E_PEX0_STN0_TX_DP<11>")
	)
	(segment
		(start 78.979268 -268.590776)
		(end 78.03388 -270.873474)
		(width 0.1651)
		(layer "In9.Cu")
		(net "P5E_PEX0_STN0_TX_DP<11>")
	)
	(segment
		(start 77.56271 -199.693276)
		(end 75.599544 -222.13189)
		(width 0.1651)
		(layer "In9.Cu")
		(net "P5E_PEX0_STN0_TX_DP<11>")
	)
	(segment
		(start 89.24036 -155.015692)
		(end 89.24036 -157.687772)
		(width 0.1651)
		(layer "In9.Cu")
		(net "P5E_PEX0_STN0_TX_DP<11>")
	)
	(segment
		(start 84.17433 -148.88591)
		(end 84.46516 -148.59508)
		(width 0.1651)
		(layer "In9.Cu")
		(net "P5E_PEX0_STN0_TX_DP<11>")
	)
	(segment
		(start 89.24036 -157.687772)
		(end 80.89773 -172.13961)
		(width 0.1651)
		(layer "In9.Cu")
		(net "P5E_PEX0_STN0_TX_DP<11>")
	)
	(segment
		(start 87.0077 -150.66518)
		(end 86.97976 -150.80615)
		(width 0.1651)
		(layer "In9.Cu")
		(net "P5E_PEX0_STN0_TX_DP<11>")
	)
	(segment
		(start 86.574376 -150.016464)
		(end 87.0077 -150.66518)
		(width 0.1651)
		(layer "In9.Cu")
		(net "P5E_PEX0_STN0_TX_DP<11>")
	)
	(segment
		(start 88.140032 -152.359614)
		(end 89.24036 -155.015692)
		(width 0.1651)
		(layer "In9.Cu")
		(net "P5E_PEX0_STN0_TX_DP<11>")
	)
	(segment
		(start 78.03388 -271.500346)
		(end 78.0796 -271.546066)
		(width 0.1143)
		(layer "In9.Cu")
		(net "P5E_PEX0_STN0_TX_DP<11>")
	)
	(segment
		(start 78.0796 -278.205184)
		(end 78.294484 -278.420068)
		(width 0.1143)
		(layer "In9.Cu")
		(net "P5E_PEX0_STN0_TX_DP<11>")
	)
	(segment
		(start 75.599544 -222.13189)
		(end 78.979268 -260.78815)
		(width 0.1651)
		(layer "In9.Cu")
		(net "P5E_PEX0_STN0_TX_DP<11>")
	)
	(segment
		(start 86.97976 -150.80615)
		(end 87.247984 -151.207724)
		(width 0.1651)
		(layer "In9.Cu")
		(net "P5E_PEX0_STN0_TX_DP<11>")
	)
	(segment
		(start 20.221448 -349.831914)
		(end 19.901408 -349.511874)
		(width 0.13462)
		(layer "F.Cu")
		(net "P5E_PEX0_STN7_TX_DN<112>")
	)
	(segment
		(start 19.901408 -349.511874)
		(end 19.901408 -348.88043)
		(width 0.13462)
		(layer "F.Cu")
		(net "P5E_PEX0_STN7_TX_DN<112>")
	)
	(segment
		(start 19.901408 -348.88043)
		(end 20.196048 -348.58579)
		(width 0.13462)
		(layer "F.Cu")
		(net "P5E_PEX0_STN7_TX_DN<112>")
	)
	(segment
		(start 19.905218 -348.29496)
		(end 19.905218 -347.658182)
		(width 0.1651)
		(layer "In7.Cu")
		(net "P5E_PEX0_STN7_TX_DN<112>")
	)
	(segment
		(start 18.733262 -314.039504)
		(end 25.327102 -304.170842)
		(width 0.1651)
		(layer "In7.Cu")
		(net "P5E_PEX0_STN7_TX_DN<112>")
	)
	(segment
		(start 17.264634 -328.385932)
		(end 17.367758 -328.266298)
		(width 0.1651)
		(layer "In7.Cu")
		(net "P5E_PEX0_STN7_TX_DN<112>")
	)
	(segment
		(start 18.350738 -346.103702)
		(end 18.350738 -343.111582)
		(width 0.1651)
		(layer "In7.Cu")
		(net "P5E_PEX0_STN7_TX_DN<112>")
	)
	(segment
		(start 26.45156 -303.24806)
		(end 31.23692 -301.265844)
		(width 0.1651)
		(layer "In7.Cu")
		(net "P5E_PEX0_STN7_TX_DN<112>")
	)
	(segment
		(start 17.455388 -329.45197)
		(end 17.419828 -328.970386)
		(width 0.1651)
		(layer "In7.Cu")
		(net "P5E_PEX0_STN7_TX_DN<112>")
	)
	(segment
		(start 17.177004 -327.20026)
		(end 17.177004 -319.504314)
		(width 0.1651)
		(layer "In7.Cu")
		(net "P5E_PEX0_STN7_TX_DN<112>")
	)
	(segment
		(start 17.830546 -316.219078)
		(end 18.733262 -314.039504)
		(width 0.1651)
		(layer "In7.Cu")
		(net "P5E_PEX0_STN7_TX_DN<112>")
	)
	(segment
		(start 17.38757 -330.05268)
		(end 17.352264 -329.571604)
		(width 0.1651)
		(layer "In7.Cu")
		(net "P5E_PEX0_STN7_TX_DN<112>")
	)
	(segment
		(start 41.976548 -301.367952)
		(end 41.976548 -301.482506)
		(width 0.1143)
		(layer "In7.Cu")
		(net "P5E_PEX0_STN7_TX_DN<112>")
	)
	(segment
		(start 25.327102 -304.170842)
		(end 26.45156 -303.24806)
		(width 0.1651)
		(layer "In7.Cu")
		(net "P5E_PEX0_STN7_TX_DN<112>")
	)
	(segment
		(start 41.976548 -301.482506)
		(end 41.8592 -301.599854)
		(width 0.1143)
		(layer "In7.Cu")
		(net "P5E_PEX0_STN7_TX_DN<112>")
	)
	(segment
		(start 17.507458 -330.156058)
		(end 17.38757 -330.05268)
		(width 0.1651)
		(layer "In7.Cu")
		(net "P5E_PEX0_STN7_TX_DN<112>")
	)
	(segment
		(start 17.177004 -319.504314)
		(end 17.830546 -316.219078)
		(width 0.1651)
		(layer "In7.Cu")
		(net "P5E_PEX0_STN7_TX_DN<112>")
	)
	(segment
		(start 20.196048 -348.58579)
		(end 19.905218 -348.29496)
		(width 0.1651)
		(layer "In7.Cu")
		(net "P5E_PEX0_STN7_TX_DN<112>")
	)
	(segment
		(start 17.367758 -328.266298)
		(end 17.332198 -327.784714)
		(width 0.1651)
		(layer "In7.Cu")
		(net "P5E_PEX0_STN7_TX_DN<112>")
	)
	(segment
		(start 17.419828 -328.970386)
		(end 17.29994 -328.867008)
		(width 0.1651)
		(layer "In7.Cu")
		(net "P5E_PEX0_STN7_TX_DN<112>")
	)
	(segment
		(start 17.439894 -330.757276)
		(end 17.543018 -330.637642)
		(width 0.1651)
		(layer "In7.Cu")
		(net "P5E_PEX0_STN7_TX_DN<112>")
	)
	(segment
		(start 17.352264 -329.571604)
		(end 17.455388 -329.45197)
		(width 0.1651)
		(layer "In7.Cu")
		(net "P5E_PEX0_STN7_TX_DN<112>")
	)
	(segment
		(start 36.41852 -301.220124)
		(end 41.82872 -301.220124)
		(width 0.1143)
		(layer "In7.Cu")
		(net "P5E_PEX0_STN7_TX_DN<112>")
	)
	(segment
		(start 41.8592 -301.599854)
		(end 41.599866 -301.599854)
		(width 0.1143)
		(layer "In7.Cu")
		(net "P5E_PEX0_STN7_TX_DN<112>")
	)
	(segment
		(start 36.3728 -301.265844)
		(end 36.41852 -301.220124)
		(width 0.1143)
		(layer "In7.Cu")
		(net "P5E_PEX0_STN7_TX_DN<112>")
	)
	(segment
		(start 31.23692 -301.265844)
		(end 36.344352 -301.265844)
		(width 0.1651)
		(layer "In7.Cu")
		(net "P5E_PEX0_STN7_TX_DN<112>")
	)
	(segment
		(start 17.29994 -328.867008)
		(end 17.264634 -328.385932)
		(width 0.1651)
		(layer "In7.Cu")
		(net "P5E_PEX0_STN7_TX_DN<112>")
	)
	(segment
		(start 17.332198 -327.784714)
		(end 17.21231 -327.681336)
		(width 0.1651)
		(layer "In7.Cu")
		(net "P5E_PEX0_STN7_TX_DN<112>")
	)
	(segment
		(start 36.344352 -301.265844)
		(end 36.3728 -301.265844)
		(width 0.1143)
		(layer "In7.Cu")
		(net "P5E_PEX0_STN7_TX_DN<112>")
	)
	(segment
		(start 17.21231 -327.681336)
		(end 17.177004 -327.20026)
		(width 0.1651)
		(layer "In7.Cu")
		(net "P5E_PEX0_STN7_TX_DN<112>")
	)
	(segment
		(start 18.350738 -343.111582)
		(end 17.439894 -330.757276)
		(width 0.1651)
		(layer "In7.Cu")
		(net "P5E_PEX0_STN7_TX_DN<112>")
	)
	(segment
		(start 41.82872 -301.220124)
		(end 41.976548 -301.367952)
		(width 0.1143)
		(layer "In7.Cu")
		(net "P5E_PEX0_STN7_TX_DN<112>")
	)
	(segment
		(start 17.543018 -330.637642)
		(end 17.507458 -330.156058)
		(width 0.1651)
		(layer "In7.Cu")
		(net "P5E_PEX0_STN7_TX_DN<112>")
	)
	(segment
		(start 19.905218 -347.658182)
		(end 18.350738 -346.103702)
		(width 0.1651)
		(layer "In7.Cu")
		(net "P5E_PEX0_STN7_TX_DN<112>")
	)
	(segment
		(start 39.777162 -396.651734)
		(end 39.294308 -395.486128)
		(width 0.1651)
		(layer "In5.Cu")
		(net "P5E_PEX0_STN7_RX_DP<117>")
	)
	(segment
		(start 25.421844 -386.399024)
		(end 24.689562 -384.631946)
		(width 0.1651)
		(layer "In5.Cu")
		(net "P5E_PEX0_STN7_RX_DP<117>")
	)
	(segment
		(start 39.777162 -409.440888)
		(end 39.777162 -396.651734)
		(width 0.1651)
		(layer "In5.Cu")
		(net "P5E_PEX0_STN7_RX_DP<117>")
	)
	(segment
		(start 39.037006 -409.799028)
		(end 39.419022 -409.799028)
		(width 0.1651)
		(layer "In5.Cu")
		(net "P5E_PEX0_STN7_RX_DP<117>")
	)
	(segment
		(start 22.104858 -367.205514)
		(end 21.177758 -357.792274)
		(width 0.1651)
		(layer "In5.Cu")
		(net "P5E_PEX0_STN7_RX_DP<117>")
	)
	(segment
		(start 37.534342 -306.349908)
		(end 37.799772 -306.349908)
		(width 0.1143)
		(layer "In5.Cu")
		(net "P5E_PEX0_STN7_RX_DP<117>")
	)
	(segment
		(start 35.212274 -392.07821)
		(end 26.379678 -387.357112)
		(width 0.1651)
		(layer "In5.Cu")
		(net "P5E_PEX0_STN7_RX_DP<117>")
	)
	(segment
		(start 37.243766 -393.435586)
		(end 35.212274 -392.07821)
		(width 0.1651)
		(layer "In5.Cu")
		(net "P5E_PEX0_STN7_RX_DP<117>")
	)
	(segment
		(start 35.56 -305.733958)
		(end 35.588448 -305.733958)
		(width 0.1143)
		(layer "In5.Cu")
		(net "P5E_PEX0_STN7_RX_DP<117>")
	)
	(segment
		(start 35.588448 -305.733958)
		(end 35.634168 -305.779678)
		(width 0.1143)
		(layer "In5.Cu")
		(net "P5E_PEX0_STN7_RX_DP<117>")
	)
	(segment
		(start 24.689562 -384.631946)
		(end 22.104858 -367.205514)
		(width 0.1651)
		(layer "In5.Cu")
		(net "P5E_PEX0_STN7_RX_DP<117>")
	)
	(segment
		(start 37.420042 -306.005484)
		(end 37.420042 -306.235608)
		(width 0.1143)
		(layer "In5.Cu")
		(net "P5E_PEX0_STN7_RX_DP<117>")
	)
	(segment
		(start 31.85922 -306.533296)
		(end 33.10509 -306.017168)
		(width 0.1651)
		(layer "In5.Cu")
		(net "P5E_PEX0_STN7_RX_DP<117>")
	)
	(segment
		(start 39.419022 -409.799028)
		(end 39.777162 -409.440888)
		(width 0.1651)
		(layer "In5.Cu")
		(net "P5E_PEX0_STN7_RX_DP<117>")
	)
	(segment
		(start 34.527998 -305.733958)
		(end 35.56 -305.733958)
		(width 0.1651)
		(layer "In5.Cu")
		(net "P5E_PEX0_STN7_RX_DP<117>")
	)
	(segment
		(start 22.62505 -319.501266)
		(end 23.709376 -316.883796)
		(width 0.1651)
		(layer "In5.Cu")
		(net "P5E_PEX0_STN7_RX_DP<117>")
	)
	(segment
		(start 38.910006 -409.672028)
		(end 39.037006 -409.799028)
		(width 0.1651)
		(layer "In5.Cu")
		(net "P5E_PEX0_STN7_RX_DP<117>")
	)
	(segment
		(start 39.294308 -395.486128)
		(end 37.243766 -393.435586)
		(width 0.1651)
		(layer "In5.Cu")
		(net "P5E_PEX0_STN7_RX_DP<117>")
	)
	(segment
		(start 28.141676 -310.25084)
		(end 31.85922 -306.533296)
		(width 0.1651)
		(layer "In5.Cu")
		(net "P5E_PEX0_STN7_RX_DP<117>")
	)
	(segment
		(start 21.177758 -357.792274)
		(end 21.177758 -341.87765)
		(width 0.1651)
		(layer "In5.Cu")
		(net "P5E_PEX0_STN7_RX_DP<117>")
	)
	(segment
		(start 37.194236 -305.779678)
		(end 37.420042 -306.005484)
		(width 0.1143)
		(layer "In5.Cu")
		(net "P5E_PEX0_STN7_RX_DP<117>")
	)
	(segment
		(start 33.10509 -306.017168)
		(end 34.527998 -305.733958)
		(width 0.1651)
		(layer "In5.Cu")
		(net "P5E_PEX0_STN7_RX_DP<117>")
	)
	(segment
		(start 21.872448 -334.823308)
		(end 22.62505 -319.501266)
		(width 0.1651)
		(layer "In5.Cu")
		(net "P5E_PEX0_STN7_RX_DP<117>")
	)
	(segment
		(start 38.910006 -409.290012)
		(end 38.910006 -409.672028)
		(width 0.1651)
		(layer "In5.Cu")
		(net "P5E_PEX0_STN7_RX_DP<117>")
	)
	(segment
		(start 26.379678 -387.357112)
		(end 25.421844 -386.399024)
		(width 0.1651)
		(layer "In5.Cu")
		(net "P5E_PEX0_STN7_RX_DP<117>")
	)
	(segment
		(start 35.634168 -305.779678)
		(end 37.194236 -305.779678)
		(width 0.1143)
		(layer "In5.Cu")
		(net "P5E_PEX0_STN7_RX_DP<117>")
	)
	(segment
		(start 23.709376 -316.883796)
		(end 28.141676 -310.25084)
		(width 0.1651)
		(layer "In5.Cu")
		(net "P5E_PEX0_STN7_RX_DP<117>")
	)
	(segment
		(start 37.420042 -306.235608)
		(end 37.534342 -306.349908)
		(width 0.1143)
		(layer "In5.Cu")
		(net "P5E_PEX0_STN7_RX_DP<117>")
	)
	(segment
		(start 21.177758 -341.87765)
		(end 21.872448 -334.823308)
		(width 0.1651)
		(layer "In5.Cu")
		(net "P5E_PEX0_STN7_RX_DP<117>")
	)
	(via
		(at 286.936942 -138.176)
		(size 0.6604)
		(drill 0.3302)
		(layers "F.Cu" "B.Cu")
		(net "RST_SMB_NIC4_MUX_N")
	)
	(segment
		(start 287.298892 -137.05205)
		(end 288.206942 -137.05205)
		(width 0.13208)
		(layer "B.Cu")
		(net "RST_SMB_NIC4_MUX_N")
	)
	(segment
		(start 286.809942 -140.931138)
		(end 286.936942 -140.804138)
		(width 0.13208)
		(layer "B.Cu")
		(net "RST_SMB_NIC4_MUX_N")
	)
	(segment
		(start 286.936942 -137.414)
		(end 287.298892 -137.05205)
		(width 0.13208)
		(layer "B.Cu")
		(net "RST_SMB_NIC4_MUX_N")
	)
	(segment
		(start 286.936942 -140.804138)
		(end 286.936942 -138.176)
		(width 0.13208)
		(layer "B.Cu")
		(net "RST_SMB_NIC4_MUX_N")
	)
	(segment
		(start 286.164782 -140.931138)
		(end 286.809942 -140.931138)
		(width 0.13208)
		(layer "B.Cu")
		(net "RST_SMB_NIC4_MUX_N")
	)
	(segment
		(start 286.936942 -138.176)
		(end 286.936942 -137.414)
		(width 0.13208)
		(layer "B.Cu")
		(net "RST_SMB_NIC4_MUX_N")
	)
	(segment
		(start 172.379894 -138.6332)
		(end 172.379894 -137.414)
		(width 0.13208)
		(layer "F.Cu")
		(net "PRSNT_NIC2_N")
	)
	(segment
		(start 153.38552 -117.09654)
		(end 153.38552 -116.888006)
		(width 0.13208)
		(layer "F.Cu")
		(net "PRSNT_NIC2_N")
	)
	(segment
		(start 148.417534 -117.37086)
		(end 149.207474 -118.1608)
		(width 0.13208)
		(layer "F.Cu")
		(net "PRSNT_NIC2_N")
	)
	(segment
		(start 168.599866 -116.92509)
		(end 169.705782 -115.819174)
		(width 0.13208)
		(layer "F.Cu")
		(net "PRSNT_NIC2_N")
	)
	(segment
		(start 154.460194 -116.341652)
		(end 154.587194 -116.214652)
		(width 0.13208)
		(layer "F.Cu")
		(net "PRSNT_NIC2_N")
	)
	(segment
		(start 157.395672 -116.214652)
		(end 158.10611 -116.92509)
		(width 0.13208)
		(layer "F.Cu")
		(net "PRSNT_NIC2_N")
	)
	(segment
		(start 169.705782 -115.819174)
		(end 172.329094 -115.819174)
		(width 0.13208)
		(layer "F.Cu")
		(net "PRSNT_NIC2_N")
	)
	(segment
		(start 148.417534 -115.736624)
		(end 148.417534 -117.37086)
		(width 0.13208)
		(layer "F.Cu")
		(net "PRSNT_NIC2_N")
	)
	(segment
		(start 152.32126 -118.1608)
		(end 153.38552 -117.09654)
		(width 0.13208)
		(layer "F.Cu")
		(net "PRSNT_NIC2_N")
	)
	(segment
		(start 172.329094 -115.819174)
		(end 172.329094 -116.5352)
		(width 0.13208)
		(layer "F.Cu")
		(net "PRSNT_NIC2_N")
	)
	(segment
		(start 153.962354 -116.7384)
		(end 154.460194 -116.7384)
		(width 0.13208)
		(layer "F.Cu")
		(net "PRSNT_NIC2_N")
	)
	(segment
		(start 154.460194 -116.7384)
		(end 154.460194 -116.341652)
		(width 0.13208)
		(layer "F.Cu")
		(net "PRSNT_NIC2_N")
	)
	(segment
		(start 172.506894 -137.287)
		(end 173.249844 -137.287)
		(width 0.13208)
		(layer "F.Cu")
		(net "PRSNT_NIC2_N")
	)
	(segment
		(start 153.736548 -116.536978)
		(end 153.736548 -116.512594)
		(width 0.13208)
		(layer "F.Cu")
		(net "PRSNT_NIC2_N")
	)
	(segment
		(start 158.10611 -116.92509)
		(end 168.599866 -116.92509)
		(width 0.13208)
		(layer "F.Cu")
		(net "PRSNT_NIC2_N")
	)
	(segment
		(start 154.587194 -116.214652)
		(end 157.395672 -116.214652)
		(width 0.13208)
		(layer "F.Cu")
		(net "PRSNT_NIC2_N")
	)
	(segment
		(start 153.38552 -116.888006)
		(end 153.736548 -116.536978)
		(width 0.13208)
		(layer "F.Cu")
		(net "PRSNT_NIC2_N")
	)
	(segment
		(start 149.207474 -118.1608)
		(end 152.32126 -118.1608)
		(width 0.13208)
		(layer "F.Cu")
		(net "PRSNT_NIC2_N")
	)
	(segment
		(start 153.707338 -96.1644)
		(end 154.460194 -96.1644)
		(width 0.13208)
		(layer "F.Cu")
		(net "PRSNT_NIC2_N")
	)
	(segment
		(start 153.736548 -116.512594)
		(end 153.962354 -116.7384)
		(width 0.13208)
		(layer "F.Cu")
		(net "PRSNT_NIC2_N")
	)
	(segment
		(start 172.379894 -137.414)
		(end 172.506894 -137.287)
		(width 0.13208)
		(layer "F.Cu")
		(net "PRSNT_NIC2_N")
	)
	(via
		(at 173.249844 -137.287)
		(size 0.508)
		(drill 0.254)
		(layers "F.Cu" "B.Cu")
		(net "PRSNT_NIC2_N")
	)
	(via
		(at 172.329094 -115.819174)
		(size 0.508)
		(drill 0.254)
		(layers "F.Cu" "B.Cu")
		(net "PRSNT_NIC2_N")
	)
	(via
		(at 153.736548 -116.512594)
		(size 0.508)
		(drill 0.254)
		(layers "F.Cu" "B.Cu")
		(net "PRSNT_NIC2_N")
	)
	(via
		(at 153.707338 -96.1644)
		(size 0.508)
		(drill 0.254)
		(layers "F.Cu" "B.Cu")
		(net "PRSNT_NIC2_N")
	)
	(segment
		(start 155.38323 -97.840292)
		(end 155.38323 -112.019334)
		(width 0.15494)
		(layer "In9.Cu")
		(net "PRSNT_NIC2_N")
	)
	(segment
		(start 172.456094 -115.946174)
		(end 172.329094 -115.819174)
		(width 0.15494)
		(layer "In9.Cu")
		(net "PRSNT_NIC2_N")
	)
	(segment
		(start 153.303986 -114.098578)
		(end 153.303986 -116.080032)
		(width 0.15494)
		(layer "In9.Cu")
		(net "PRSNT_NIC2_N")
	)
	(segment
		(start 153.707338 -96.1644)
		(end 155.38323 -97.840292)
		(width 0.15494)
		(layer "In9.Cu")
		(net "PRSNT_NIC2_N")
	)
	(segment
		(start 172.456094 -136.49325)
		(end 172.456094 -115.946174)
		(width 0.15494)
		(layer "In9.Cu")
		(net "PRSNT_NIC2_N")
	)
	(segment
		(start 153.303986 -116.080032)
		(end 153.736548 -116.512594)
		(width 0.15494)
		(layer "In9.Cu")
		(net "PRSNT_NIC2_N")
	)
	(segment
		(start 155.38323 -112.019334)
		(end 153.303986 -114.098578)
		(width 0.15494)
		(layer "In9.Cu")
		(net "PRSNT_NIC2_N")
	)
	(segment
		(start 173.249844 -137.287)
		(end 172.456094 -136.49325)
		(width 0.15494)
		(layer "In9.Cu")
		(net "PRSNT_NIC2_N")
	)
	(segment
		(start 80.606138 -133.800342)
		(end 81.237582 -133.800342)
		(width 0.13462)
		(layer "F.Cu")
		(net "P5E_PEX0_STN0_TX_DN<6>")
	)
	(segment
		(start 81.237582 -133.800342)
		(end 81.532222 -133.505702)
		(width 0.13462)
		(layer "F.Cu")
		(net "P5E_PEX0_STN0_TX_DN<6>")
	)
	(segment
		(start 80.286098 -133.480302)
		(end 80.606138 -133.800342)
		(width 0.13462)
		(layer "F.Cu")
		(net "P5E_PEX0_STN0_TX_DN<6>")
	)
	(segment
		(start 83.415124 -251.430536)
		(end 93.994986 -267.264388)
		(width 0.1651)
		(layer "In9.Cu")
		(net "P5E_PEX0_STN0_TX_DN<6>")
	)
	(segment
		(start 86.148418 -281.634438)
		(end 84.623656 -282.265882)
		(width 0.1651)
		(layer "In9.Cu")
		(net "P5E_PEX0_STN0_TX_DN<6>")
	)
	(segment
		(start 86.396068 -135.339328)
		(end 90.387678 -144.97558)
		(width 0.1651)
		(layer "In9.Cu")
		(net "P5E_PEX0_STN0_TX_DN<6>")
	)
	(segment
		(start 77.43444 -282.599892)
		(end 77.69987 -282.599892)
		(width 0.1143)
		(layer "In9.Cu")
		(net "P5E_PEX0_STN0_TX_DN<6>")
	)
	(segment
		(start 84.623656 -282.265882)
		(end 83.917536 -282.265882)
		(width 0.1651)
		(layer "In9.Cu")
		(net "P5E_PEX0_STN0_TX_DN<6>")
	)
	(segment
		(start 94.365064 -158.997904)
		(end 85.769196 -173.890686)
		(width 0.1651)
		(layer "In9.Cu")
		(net "P5E_PEX0_STN0_TX_DN<6>")
	)
	(segment
		(start 85.614764 -134.558024)
		(end 86.396068 -135.339328)
		(width 0.1651)
		(layer "In9.Cu")
		(net "P5E_PEX0_STN0_TX_DN<6>")
	)
	(segment
		(start 83.843368 -282.220162)
		(end 77.423772 -282.220162)
		(width 0.1143)
		(layer "In9.Cu")
		(net "P5E_PEX0_STN0_TX_DN<6>")
	)
	(segment
		(start 90.387678 -144.97558)
		(end 90.84691 -145.434812)
		(width 0.1651)
		(layer "In9.Cu")
		(net "P5E_PEX0_STN0_TX_DN<6>")
	)
	(segment
		(start 77.32014 -282.323794)
		(end 77.32014 -282.485592)
		(width 0.1143)
		(layer "In9.Cu")
		(net "P5E_PEX0_STN0_TX_DN<6>")
	)
	(segment
		(start 81.532222 -133.505702)
		(end 81.823052 -133.796532)
		(width 0.1651)
		(layer "In9.Cu")
		(net "P5E_PEX0_STN0_TX_DN<6>")
	)
	(segment
		(start 94.068138 -273.714718)
		(end 86.148418 -281.634438)
		(width 0.1651)
		(layer "In9.Cu")
		(net "P5E_PEX0_STN0_TX_DN<6>")
	)
	(segment
		(start 94.843854 -271.584166)
		(end 94.068138 -273.714718)
		(width 0.1651)
		(layer "In9.Cu")
		(net "P5E_PEX0_STN0_TX_DN<6>")
	)
	(segment
		(start 84.613496 -178.200304)
		(end 80.812894 -221.640654)
		(width 0.1651)
		(layer "In9.Cu")
		(net "P5E_PEX0_STN0_TX_DN<6>")
	)
	(segment
		(start 80.812894 -221.640654)
		(end 83.415124 -251.430536)
		(width 0.1651)
		(layer "In9.Cu")
		(net "P5E_PEX0_STN0_TX_DN<6>")
	)
	(segment
		(start 77.32014 -282.485592)
		(end 77.43444 -282.599892)
		(width 0.1143)
		(layer "In9.Cu")
		(net "P5E_PEX0_STN0_TX_DN<6>")
	)
	(segment
		(start 85.769196 -173.890686)
		(end 84.613496 -178.200304)
		(width 0.1651)
		(layer "In9.Cu")
		(net "P5E_PEX0_STN0_TX_DN<6>")
	)
	(segment
		(start 93.994986 -267.264388)
		(end 94.591378 -268.704568)
		(width 0.1651)
		(layer "In9.Cu")
		(net "P5E_PEX0_STN0_TX_DN<6>")
	)
	(segment
		(start 90.84691 -145.434812)
		(end 94.365064 -153.928572)
		(width 0.1651)
		(layer "In9.Cu")
		(net "P5E_PEX0_STN0_TX_DN<6>")
	)
	(segment
		(start 83.889088 -282.265882)
		(end 83.843368 -282.220162)
		(width 0.1143)
		(layer "In9.Cu")
		(net "P5E_PEX0_STN0_TX_DN<6>")
	)
	(segment
		(start 94.365064 -153.928572)
		(end 94.365064 -158.997904)
		(width 0.1651)
		(layer "In9.Cu")
		(net "P5E_PEX0_STN0_TX_DN<6>")
	)
	(segment
		(start 94.591378 -268.704568)
		(end 94.843854 -271.584166)
		(width 0.1651)
		(layer "In9.Cu")
		(net "P5E_PEX0_STN0_TX_DN<6>")
	)
	(segment
		(start 83.776312 -133.796532)
		(end 85.614764 -134.558024)
		(width 0.1651)
		(layer "In9.Cu")
		(net "P5E_PEX0_STN0_TX_DN<6>")
	)
	(segment
		(start 81.823052 -133.796532)
		(end 83.776312 -133.796532)
		(width 0.1651)
		(layer "In9.Cu")
		(net "P5E_PEX0_STN0_TX_DN<6>")
	)
	(segment
		(start 77.423772 -282.220162)
		(end 77.32014 -282.323794)
		(width 0.1143)
		(layer "In9.Cu")
		(net "P5E_PEX0_STN0_TX_DN<6>")
	)
	(segment
		(start 83.917536 -282.265882)
		(end 83.889088 -282.265882)
		(width 0.1143)
		(layer "In9.Cu")
		(net "P5E_PEX0_STN0_TX_DN<6>")
	)
	(segment
		(start 48.202088 -343.685622)
		(end 47.882048 -343.365582)
		(width 0.13462)
		(layer "F.Cu")
		(net "P5E_PEX0_STN7_TX_DN<125>")
	)
	(segment
		(start 47.882048 -342.734138)
		(end 48.176688 -342.439498)
		(width 0.13462)
		(layer "F.Cu")
		(net "P5E_PEX0_STN7_TX_DN<125>")
	)
	(segment
		(start 47.882048 -343.365582)
		(end 47.882048 -342.734138)
		(width 0.13462)
		(layer "F.Cu")
		(net "P5E_PEX0_STN7_TX_DN<125>")
	)
	(segment
		(start 40.315896 -322.76415)
		(end 40.315896 -319.890648)
		(width 0.1651)
		(layer "In7.Cu")
		(net "P5E_PEX0_STN7_TX_DN<125>")
	)
	(segment
		(start 40.403526 -322.949062)
		(end 40.315896 -322.76415)
		(width 0.1651)
		(layer "In7.Cu")
		(net "P5E_PEX0_STN7_TX_DN<125>")
	)
	(segment
		(start 40.649906 -313.684412)
		(end 40.649906 -313.949842)
		(width 0.1143)
		(layer "In7.Cu")
		(net "P5E_PEX0_STN7_TX_DN<125>")
	)
	(segment
		(start 40.270176 -319.81648)
		(end 40.270176 -313.684412)
		(width 0.1143)
		(layer "In7.Cu")
		(net "P5E_PEX0_STN7_TX_DN<125>")
	)
	(segment
		(start 40.315896 -319.8622)
		(end 40.270176 -319.81648)
		(width 0.1143)
		(layer "In7.Cu")
		(net "P5E_PEX0_STN7_TX_DN<125>")
	)
	(segment
		(start 40.535606 -313.570112)
		(end 40.649906 -313.684412)
		(width 0.1143)
		(layer "In7.Cu")
		(net "P5E_PEX0_STN7_TX_DN<125>")
	)
	(segment
		(start 40.403526 -322.948808)
		(end 40.403526 -322.949062)
		(width 0.1651)
		(layer "In7.Cu")
		(net "P5E_PEX0_STN7_TX_DN<125>")
	)
	(segment
		(start 40.384476 -313.570112)
		(end 40.535606 -313.570112)
		(width 0.1143)
		(layer "In7.Cu")
		(net "P5E_PEX0_STN7_TX_DN<125>")
	)
	(segment
		(start 47.885858 -340.6394)
		(end 45.525182 -333.777082)
		(width 0.1651)
		(layer "In7.Cu")
		(net "P5E_PEX0_STN7_TX_DN<125>")
	)
	(segment
		(start 40.315896 -319.890648)
		(end 40.315896 -319.8622)
		(width 0.1143)
		(layer "In7.Cu")
		(net "P5E_PEX0_STN7_TX_DN<125>")
	)
	(segment
		(start 45.525182 -333.777082)
		(end 40.403526 -322.948808)
		(width 0.1651)
		(layer "In7.Cu")
		(net "P5E_PEX0_STN7_TX_DN<125>")
	)
	(segment
		(start 47.885858 -342.148668)
		(end 47.885858 -340.6394)
		(width 0.1651)
		(layer "In7.Cu")
		(net "P5E_PEX0_STN7_TX_DN<125>")
	)
	(segment
		(start 48.176688 -342.439498)
		(end 47.885858 -342.148668)
		(width 0.1651)
		(layer "In7.Cu")
		(net "P5E_PEX0_STN7_TX_DN<125>")
	)
	(segment
		(start 40.270176 -313.684412)
		(end 40.384476 -313.570112)
		(width 0.1143)
		(layer "In7.Cu")
		(net "P5E_PEX0_STN7_TX_DN<125>")
	)
	(segment
		(start 37.369242 -392.225022)
		(end 37.33292 -392.104626)
		(width 0.1651)
		(layer "In5.Cu")
		(net "P5E_PEX0_STN7_RX_DP<118>")
	)
	(segment
		(start 35.56 -306.683918)
		(end 35.588448 -306.683918)
		(width 0.1143)
		(layer "In5.Cu")
		(net "P5E_PEX0_STN7_RX_DP<118>")
	)
	(segment
		(start 23.804118 -328.50582)
		(end 23.804118 -328.504042)
		(width 0.1651)
		(layer "In5.Cu")
		(net "P5E_PEX0_STN7_RX_DP<118>")
	)
	(segment
		(start 38.95725 -392.973052)
		(end 38.836854 -393.009628)
		(width 0.1651)
		(layer "In5.Cu")
		(net "P5E_PEX0_STN7_RX_DP<118>")
	)
	(segment
		(start 23.580344 -319.691512)
		(end 24.31542 -317.916814)
		(width 0.1651)
		(layer "In5.Cu")
		(net "P5E_PEX0_STN7_RX_DP<118>")
	)
	(segment
		(start 37.332666 -392.10488)
		(end 26.948892 -386.554726)
		(width 0.1651)
		(layer "In5.Cu")
		(net "P5E_PEX0_STN7_RX_DP<118>")
	)
	(segment
		(start 23.580344 -323.948552)
		(end 23.580344 -319.691512)
		(width 0.1651)
		(layer "In5.Cu")
		(net "P5E_PEX0_STN7_RX_DP<118>")
	)
	(segment
		(start 41.566084 -408.699208)
		(end 41.976802 -408.28849)
		(width 0.1651)
		(layer "In5.Cu")
		(net "P5E_PEX0_STN7_RX_DP<118>")
	)
	(segment
		(start 38.836854 -393.009628)
		(end 38.39972 -392.775948)
		(width 0.1651)
		(layer "In5.Cu")
		(net "P5E_PEX0_STN7_RX_DP<118>")
	)
	(segment
		(start 41.2369 -408.699208)
		(end 41.566084 -408.699208)
		(width 0.1651)
		(layer "In5.Cu")
		(net "P5E_PEX0_STN7_RX_DP<118>")
	)
	(segment
		(start 34.16427 -306.683918)
		(end 35.56 -306.683918)
		(width 0.1651)
		(layer "In5.Cu")
		(net "P5E_PEX0_STN7_RX_DP<118>")
	)
	(segment
		(start 39.393876 -393.206478)
		(end 38.95725 -392.973052)
		(width 0.1651)
		(layer "In5.Cu")
		(net "P5E_PEX0_STN7_RX_DP<118>")
	)
	(segment
		(start 41.1099 -408.190192)
		(end 41.1099 -408.572208)
		(width 0.1651)
		(layer "In5.Cu")
		(net "P5E_PEX0_STN7_RX_DP<118>")
	)
	(segment
		(start 37.806376 -392.458702)
		(end 37.369242 -392.225022)
		(width 0.1651)
		(layer "In5.Cu")
		(net "P5E_PEX0_STN7_RX_DP<118>")
	)
	(segment
		(start 24.286718 -338.328254)
		(end 23.804372 -328.506074)
		(width 0.1651)
		(layer "In5.Cu")
		(net "P5E_PEX0_STN7_RX_DP<118>")
	)
	(segment
		(start 39.434516 -307.299868)
		(end 39.699946 -307.299868)
		(width 0.1143)
		(layer "In5.Cu")
		(net "P5E_PEX0_STN7_RX_DP<118>")
	)
	(segment
		(start 39.320216 -306.955444)
		(end 39.320216 -307.185568)
		(width 0.1143)
		(layer "In5.Cu")
		(net "P5E_PEX0_STN7_RX_DP<118>")
	)
	(segment
		(start 39.987728 -393.523978)
		(end 39.867332 -393.560554)
		(width 0.1651)
		(layer "In5.Cu")
		(net "P5E_PEX0_STN7_RX_DP<118>")
	)
	(segment
		(start 23.804372 -328.506074)
		(end 23.804118 -328.50582)
		(width 0.1651)
		(layer "In5.Cu")
		(net "P5E_PEX0_STN7_RX_DP<118>")
	)
	(segment
		(start 37.926772 -392.422126)
		(end 37.806376 -392.458702)
		(width 0.1651)
		(layer "In5.Cu")
		(net "P5E_PEX0_STN7_RX_DP<118>")
	)
	(segment
		(start 24.31542 -317.916814)
		(end 28.47975 -311.68467)
		(width 0.1651)
		(layer "In5.Cu")
		(net "P5E_PEX0_STN7_RX_DP<118>")
	)
	(segment
		(start 26.948892 -386.554726)
		(end 26.24328 -385.84886)
		(width 0.1651)
		(layer "In5.Cu")
		(net "P5E_PEX0_STN7_RX_DP<118>")
	)
	(segment
		(start 23.804118 -328.504042)
		(end 23.580344 -323.948552)
		(width 0.1651)
		(layer "In5.Cu")
		(net "P5E_PEX0_STN7_RX_DP<118>")
	)
	(segment
		(start 41.976802 -408.28849)
		(end 41.976802 -395.32052)
		(width 0.1651)
		(layer "In5.Cu")
		(net "P5E_PEX0_STN7_RX_DP<118>")
	)
	(segment
		(start 35.634168 -306.729638)
		(end 39.09441 -306.729638)
		(width 0.1143)
		(layer "In5.Cu")
		(net "P5E_PEX0_STN7_RX_DP<118>")
	)
	(segment
		(start 28.47975 -311.68467)
		(end 28.47975 -311.67705)
		(width 0.1651)
		(layer "In5.Cu")
		(net "P5E_PEX0_STN7_RX_DP<118>")
	)
	(segment
		(start 28.47975 -311.67705)
		(end 32.983932 -307.172868)
		(width 0.1651)
		(layer "In5.Cu")
		(net "P5E_PEX0_STN7_RX_DP<118>")
	)
	(segment
		(start 38.363398 -392.655552)
		(end 37.926772 -392.422126)
		(width 0.1651)
		(layer "In5.Cu")
		(net "P5E_PEX0_STN7_RX_DP<118>")
	)
	(segment
		(start 25.547828 -383.452116)
		(end 24.286718 -357.775002)
		(width 0.1651)
		(layer "In5.Cu")
		(net "P5E_PEX0_STN7_RX_DP<118>")
	)
	(segment
		(start 38.39972 -392.775948)
		(end 38.363398 -392.655552)
		(width 0.1651)
		(layer "In5.Cu")
		(net "P5E_PEX0_STN7_RX_DP<118>")
	)
	(segment
		(start 39.320216 -307.185568)
		(end 39.434516 -307.299868)
		(width 0.1143)
		(layer "In5.Cu")
		(net "P5E_PEX0_STN7_RX_DP<118>")
	)
	(segment
		(start 35.588448 -306.683918)
		(end 35.634168 -306.729638)
		(width 0.1143)
		(layer "In5.Cu")
		(net "P5E_PEX0_STN7_RX_DP<118>")
	)
	(segment
		(start 32.983932 -307.172868)
		(end 34.16427 -306.683918)
		(width 0.1651)
		(layer "In5.Cu")
		(net "P5E_PEX0_STN7_RX_DP<118>")
	)
	(segment
		(start 40.832786 -393.97559)
		(end 39.987728 -393.523978)
		(width 0.1651)
		(layer "In5.Cu")
		(net "P5E_PEX0_STN7_RX_DP<118>")
	)
	(segment
		(start 41.1099 -408.572208)
		(end 41.2369 -408.699208)
		(width 0.1651)
		(layer "In5.Cu")
		(net "P5E_PEX0_STN7_RX_DP<118>")
	)
	(segment
		(start 37.33292 -392.104626)
		(end 37.332666 -392.10488)
		(width 0.1651)
		(layer "In5.Cu")
		(net "P5E_PEX0_STN7_RX_DP<118>")
	)
	(segment
		(start 24.286718 -357.775002)
		(end 24.286718 -338.328254)
		(width 0.1651)
		(layer "In5.Cu")
		(net "P5E_PEX0_STN7_RX_DP<118>")
	)
	(segment
		(start 41.834816 -394.97762)
		(end 40.832786 -393.97559)
		(width 0.1651)
		(layer "In5.Cu")
		(net "P5E_PEX0_STN7_RX_DP<118>")
	)
	(segment
		(start 39.430452 -393.326874)
		(end 39.393876 -393.206478)
		(width 0.1651)
		(layer "In5.Cu")
		(net "P5E_PEX0_STN7_RX_DP<118>")
	)
	(segment
		(start 39.867332 -393.560554)
		(end 39.430452 -393.326874)
		(width 0.1651)
		(layer "In5.Cu")
		(net "P5E_PEX0_STN7_RX_DP<118>")
	)
	(segment
		(start 25.641046 -384.395218)
		(end 25.547828 -383.452116)
		(width 0.1651)
		(layer "In5.Cu")
		(net "P5E_PEX0_STN7_RX_DP<118>")
	)
	(segment
		(start 41.976802 -395.32052)
		(end 41.834816 -394.97762)
		(width 0.1651)
		(layer "In5.Cu")
		(net "P5E_PEX0_STN7_RX_DP<118>")
	)
	(segment
		(start 39.09441 -306.729638)
		(end 39.320216 -306.955444)
		(width 0.1143)
		(layer "In5.Cu")
		(net "P5E_PEX0_STN7_RX_DP<118>")
	)
	(segment
		(start 26.24328 -385.84886)
		(end 25.641046 -384.395218)
		(width 0.1651)
		(layer "In5.Cu")
		(net "P5E_PEX0_STN7_RX_DP<118>")
	)
	(segment
		(start 295.270682 -139.2047)
		(end 295.480486 -139.414504)
		(width 0.13208)
		(layer "F.Cu")
		(net "PRSNT_NIC5_N")
	)
	(segment
		(start 310.204104 -139.185396)
		(end 312.919618 -139.185396)
		(width 0.13208)
		(layer "F.Cu")
		(net "PRSNT_NIC5_N")
	)
	(segment
		(start 309.493666 -138.474958)
		(end 310.204104 -139.185396)
		(width 0.13208)
		(layer "F.Cu")
		(net "PRSNT_NIC5_N")
	)
	(segment
		(start 316.850522 -138.359134)
		(end 318.046354 -139.554966)
		(width 0.13208)
		(layer "F.Cu")
		(net "PRSNT_NIC5_N")
	)
	(segment
		(start 313.139582 -138.965432)
		(end 313.139582 -138.661648)
		(width 0.13208)
		(layer "F.Cu")
		(net "PRSNT_NIC5_N")
	)
	(segment
		(start 313.139582 -138.661648)
		(end 313.442096 -138.359134)
		(width 0.13208)
		(layer "F.Cu")
		(net "PRSNT_NIC5_N")
	)
	(segment
		(start 295.480486 -139.414504)
		(end 298.060364 -139.414504)
		(width 0.13208)
		(layer "F.Cu")
		(net "PRSNT_NIC5_N")
	)
	(segment
		(start 313.92622 -159.062166)
		(end 313.752738 -159.235648)
		(width 0.13208)
		(layer "F.Cu")
		(net "PRSNT_NIC5_N")
	)
	(segment
		(start 298.060364 -139.414504)
		(end 298.99991 -138.474958)
		(width 0.13208)
		(layer "F.Cu")
		(net "PRSNT_NIC5_N")
	)
	(segment
		(start 298.99991 -138.474958)
		(end 309.493666 -138.474958)
		(width 0.13208)
		(layer "F.Cu")
		(net "PRSNT_NIC5_N")
	)
	(segment
		(start 295.270682 -138.864848)
		(end 294.52189 -138.864848)
		(width 0.13208)
		(layer "F.Cu")
		(net "PRSNT_NIC5_N")
	)
	(segment
		(start 313.752738 -159.235648)
		(end 313.139582 -159.235648)
		(width 0.13208)
		(layer "F.Cu")
		(net "PRSNT_NIC5_N")
	)
	(segment
		(start 318.046354 -140.24991)
		(end 318.284098 -140.487654)
		(width 0.13208)
		(layer "F.Cu")
		(net "PRSNT_NIC5_N")
	)
	(segment
		(start 295.477692 -118.331996)
		(end 295.477692 -117.566186)
		(width 0.13208)
		(layer "F.Cu")
		(net "PRSNT_NIC5_N")
	)
	(segment
		(start 318.801242 -141.004798)
		(end 318.284098 -140.487654)
		(width 0.13208)
		(layer "F.Cu")
		(net "PRSNT_NIC5_N")
	)
	(segment
		(start 312.919618 -139.185396)
		(end 313.139582 -138.965432)
		(width 0.13208)
		(layer "F.Cu")
		(net "PRSNT_NIC5_N")
	)
	(segment
		(start 295.270682 -138.864848)
		(end 295.270682 -139.2047)
		(width 0.13208)
		(layer "F.Cu")
		(net "PRSNT_NIC5_N")
	)
	(segment
		(start 313.442096 -138.359134)
		(end 316.850522 -138.359134)
		(width 0.13208)
		(layer "F.Cu")
		(net "PRSNT_NIC5_N")
	)
	(segment
		(start 318.046354 -139.554966)
		(end 318.046354 -140.24991)
		(width 0.13208)
		(layer "F.Cu")
		(net "PRSNT_NIC5_N")
	)
	(segment
		(start 319.140332 -141.004798)
		(end 318.801242 -141.004798)
		(width 0.13208)
		(layer "F.Cu")
		(net "PRSNT_NIC5_N")
	)
	(via
		(at 295.477692 -118.331996)
		(size 0.508)
		(drill 0.254)
		(layers "F.Cu" "B.Cu")
		(net "PRSNT_NIC5_N")
	)
	(via
		(at 294.52189 -138.864848)
		(size 0.508)
		(drill 0.254)
		(layers "F.Cu" "B.Cu")
		(net "PRSNT_NIC5_N")
	)
	(via
		(at 318.284098 -140.487654)
		(size 0.508)
		(drill 0.254)
		(layers "F.Cu" "B.Cu")
		(net "PRSNT_NIC5_N")
	)
	(via
		(at 313.92622 -159.062166)
		(size 0.508)
		(drill 0.254)
		(layers "F.Cu" "B.Cu")
		(net "PRSNT_NIC5_N")
	)
	(segment
		(start 313.92622 -159.062166)
		(end 315.090048 -157.898338)
		(width 0.15494)
		(layer "In7.Cu")
		(net "PRSNT_NIC5_N")
	)
	(segment
		(start 315.090048 -157.898338)
		(end 316.77991 -157.898338)
		(width 0.15494)
		(layer "In7.Cu")
		(net "PRSNT_NIC5_N")
	)
	(segment
		(start 316.77991 -157.898338)
		(end 318.284098 -156.39415)
		(width 0.15494)
		(layer "In7.Cu")
		(net "PRSNT_NIC5_N")
	)
	(segment
		(start 318.284098 -156.39415)
		(end 318.284098 -140.487654)
		(width 0.15494)
		(layer "In7.Cu")
		(net "PRSNT_NIC5_N")
	)
	(segment
		(start 294.52189 -138.864848)
		(end 295.074086 -138.312652)
		(width 0.15494)
		(layer "In9.Cu")
		(net "PRSNT_NIC5_N")
	)
	(segment
		(start 295.074086 -118.735602)
		(end 295.477692 -118.331996)
		(width 0.15494)
		(layer "In9.Cu")
		(net "PRSNT_NIC5_N")
	)
	(segment
		(start 295.074086 -138.312652)
		(end 295.074086 -118.735602)
		(width 0.15494)
		(layer "In9.Cu")
		(net "PRSNT_NIC5_N")
	)
	(segment
		(start 166.608506 -180.372766)
		(end 165.791896 -179.556156)
		(width 0.13208)
		(layer "F.Cu")
		(net "HP_NIC2_HSC_PWRGD_N")
	)
	(segment
		(start 167.439086 -178.378358)
		(end 167.439086 -179.465224)
		(width 0.13208)
		(layer "F.Cu")
		(net "HP_NIC2_HSC_PWRGD_N")
	)
	(segment
		(start 167.439086 -179.465224)
		(end 167.098472 -179.805838)
		(width 0.13208)
		(layer "F.Cu")
		(net "HP_NIC2_HSC_PWRGD_N")
	)
	(segment
		(start 166.037514 -178.378358)
		(end 165.506908 -178.908964)
		(width 0.13208)
		(layer "F.Cu")
		(net "HP_NIC2_HSC_PWRGD_N")
	)
	(segment
		(start 166.7891 -178.378358)
		(end 166.037514 -178.378358)
		(width 0.13208)
		(layer "F.Cu")
		(net "HP_NIC2_HSC_PWRGD_N")
	)
	(segment
		(start 165.791896 -179.556156)
		(end 165.791896 -179.193952)
		(width 0.13208)
		(layer "F.Cu")
		(net "HP_NIC2_HSC_PWRGD_N")
	)
	(segment
		(start 167.098472 -179.805838)
		(end 167.098472 -180.372766)
		(width 0.13208)
		(layer "F.Cu")
		(net "HP_NIC2_HSC_PWRGD_N")
	)
	(segment
		(start 165.791896 -179.193952)
		(end 165.506908 -178.908964)
		(width 0.13208)
		(layer "F.Cu")
		(net "HP_NIC2_HSC_PWRGD_N")
	)
	(segment
		(start 167.098472 -180.372766)
		(end 166.608506 -180.372766)
		(width 0.13208)
		(layer "F.Cu")
		(net "HP_NIC2_HSC_PWRGD_N")
	)
	(via
		(at 165.506908 -178.908964)
		(size 0.762)
		(drill 0.381)
		(layers "F.Cu" "B.Cu")
		(net "HP_NIC2_HSC_PWRGD_N")
	)
	(segment
		(start 81.237582 -153.710386)
		(end 81.532222 -153.415746)
		(width 0.13462)
		(layer "F.Cu")
		(net "P5E_PEX0_STN0_TX_DP<14>")
	)
	(segment
		(start 80.606138 -153.710386)
		(end 81.237582 -153.710386)
		(width 0.13462)
		(layer "F.Cu")
		(net "P5E_PEX0_STN0_TX_DP<14>")
	)
	(segment
		(start 80.286098 -153.390346)
		(end 80.606138 -153.710386)
		(width 0.13462)
		(layer "F.Cu")
		(net "P5E_PEX0_STN0_TX_DP<14>")
	)
	(segment
		(start 76.576936 -179.342288)
		(end 72.910954 -221.249748)
		(width 0.1651)
		(layer "In9.Cu")
		(net "P5E_PEX0_STN0_TX_DP<14>")
	)
	(segment
		(start 75.42022 -280.025856)
		(end 75.523852 -280.129488)
		(width 0.1143)
		(layer "In9.Cu")
		(net "P5E_PEX0_STN0_TX_DP<14>")
	)
	(segment
		(start 81.532222 -153.415746)
		(end 81.823052 -153.706576)
		(width 0.1651)
		(layer "In9.Cu")
		(net "P5E_PEX0_STN0_TX_DP<14>")
	)
	(segment
		(start 78.28788 -171.273724)
		(end 76.79563 -176.843436)
		(width 0.1651)
		(layer "In9.Cu")
		(net "P5E_PEX0_STN0_TX_DP<14>")
	)
	(segment
		(start 76.57719 -179.342288)
		(end 76.576936 -179.342288)
		(width 0.1651)
		(layer "In9.Cu")
		(net "P5E_PEX0_STN0_TX_DP<14>")
	)
	(segment
		(start 86.325964 -155.09494)
		(end 86.623144 -155.81249)
		(width 0.1651)
		(layer "In9.Cu")
		(net "P5E_PEX0_STN0_TX_DP<14>")
	)
	(segment
		(start 75.941936 -268.665198)
		(end 75.983338 -268.764766)
		(width 0.1651)
		(layer "In9.Cu")
		(net "P5E_PEX0_STN0_TX_DP<14>")
	)
	(segment
		(start 72.910954 -221.249748)
		(end 76.357988 -260.666992)
		(width 0.1651)
		(layer "In9.Cu")
		(net "P5E_PEX0_STN0_TX_DP<14>")
	)
	(segment
		(start 75.46594 -269.814548)
		(end 75.46594 -271.526)
		(width 0.1651)
		(layer "In9.Cu")
		(net "P5E_PEX0_STN0_TX_DP<14>")
	)
	(segment
		(start 76.607924 -178.988974)
		(end 76.57719 -179.342288)
		(width 0.1651)
		(layer "In9.Cu")
		(net "P5E_PEX0_STN0_TX_DP<14>")
	)
	(segment
		(start 75.793346 -269.222728)
		(end 75.694032 -269.263876)
		(width 0.1651)
		(layer "In9.Cu")
		(net "P5E_PEX0_STN0_TX_DP<14>")
	)
	(segment
		(start 75.68565 -280.129488)
		(end 75.79995 -280.015188)
		(width 0.1143)
		(layer "In9.Cu")
		(net "P5E_PEX0_STN0_TX_DP<14>")
	)
	(segment
		(start 84.9376 -153.706576)
		(end 86.325964 -155.09494)
		(width 0.1651)
		(layer "In9.Cu")
		(net "P5E_PEX0_STN0_TX_DP<14>")
	)
	(segment
		(start 81.823052 -153.706576)
		(end 84.9376 -153.706576)
		(width 0.1651)
		(layer "In9.Cu")
		(net "P5E_PEX0_STN0_TX_DP<14>")
	)
	(segment
		(start 86.623144 -156.835856)
		(end 78.28788 -171.27347)
		(width 0.1651)
		(layer "In9.Cu")
		(net "P5E_PEX0_STN0_TX_DP<14>")
	)
	(segment
		(start 76.357988 -267.660374)
		(end 75.941936 -268.665198)
		(width 0.1651)
		(layer "In9.Cu")
		(net "P5E_PEX0_STN0_TX_DP<14>")
	)
	(segment
		(start 75.523852 -280.129488)
		(end 75.68565 -280.129488)
		(width 0.1143)
		(layer "In9.Cu")
		(net "P5E_PEX0_STN0_TX_DP<14>")
	)
	(segment
		(start 78.28788 -171.27347)
		(end 78.28788 -171.273724)
		(width 0.1651)
		(layer "In9.Cu")
		(net "P5E_PEX0_STN0_TX_DP<14>")
	)
	(segment
		(start 75.46594 -271.526)
		(end 75.46594 -271.554448)
		(width 0.1143)
		(layer "In9.Cu")
		(net "P5E_PEX0_STN0_TX_DP<14>")
	)
	(segment
		(start 86.623144 -155.81249)
		(end 86.623144 -156.835856)
		(width 0.1651)
		(layer "In9.Cu")
		(net "P5E_PEX0_STN0_TX_DP<14>")
	)
	(segment
		(start 75.42022 -271.600168)
		(end 75.42022 -280.025856)
		(width 0.1143)
		(layer "In9.Cu")
		(net "P5E_PEX0_STN0_TX_DP<14>")
	)
	(segment
		(start 75.983338 -268.764766)
		(end 75.793346 -269.222728)
		(width 0.1651)
		(layer "In9.Cu")
		(net "P5E_PEX0_STN0_TX_DP<14>")
	)
	(segment
		(start 75.46594 -271.554448)
		(end 75.42022 -271.600168)
		(width 0.1143)
		(layer "In9.Cu")
		(net "P5E_PEX0_STN0_TX_DP<14>")
	)
	(segment
		(start 76.79563 -176.843436)
		(end 76.607924 -178.988974)
		(width 0.1651)
		(layer "In9.Cu")
		(net "P5E_PEX0_STN0_TX_DP<14>")
	)
	(segment
		(start 75.694032 -269.263876)
		(end 75.46594 -269.814548)
		(width 0.1651)
		(layer "In9.Cu")
		(net "P5E_PEX0_STN0_TX_DP<14>")
	)
	(segment
		(start 76.357988 -260.666992)
		(end 76.357988 -267.660374)
		(width 0.1651)
		(layer "In9.Cu")
		(net "P5E_PEX0_STN0_TX_DP<14>")
	)
	(segment
		(start 75.79995 -280.015188)
		(end 75.79995 -279.749504)
		(width 0.1143)
		(layer "In9.Cu")
		(net "P5E_PEX0_STN0_TX_DP<14>")
	)
	(segment
		(start 64.106298 -316.229492)
		(end 63.829692 -316.506098)
		(width 0.1143)
		(layer "In9.Cu")
		(net "P5E_PEX0_STN5_RX_DP<86>")
	)
	(segment
		(start 69.830696 -323.765672)
		(end 94.499684 -340.249256)
		(width 0.1651)
		(layer "In9.Cu")
		(net "P5E_PEX0_STN5_RX_DP<86>")
	)
	(segment
		(start 97.761298 -366.000792)
		(end 98.5012 -369.721638)
		(width 0.1651)
		(layer "In9.Cu")
		(net "P5E_PEX0_STN5_RX_DP<86>")
	)
	(segment
		(start 66.039746 -322.19519)
		(end 69.830696 -323.765672)
		(width 0.1651)
		(layer "In9.Cu")
		(net "P5E_PEX0_STN5_RX_DP<86>")
	)
	(segment
		(start 89.285318 -393.11072)
		(end 87.678514 -393.430506)
		(width 0.1651)
		(layer "In9.Cu")
		(net "P5E_PEX0_STN5_RX_DP<86>")
	)
	(segment
		(start 85.236812 -396.999206)
		(end 85.109812 -396.872206)
		(width 0.1651)
		(layer "In9.Cu")
		(net "P5E_PEX0_STN5_RX_DP<86>")
	)
	(segment
		(start 85.109812 -396.872206)
		(end 85.109812 -396.49019)
		(width 0.1651)
		(layer "In9.Cu")
		(net "P5E_PEX0_STN5_RX_DP<86>")
	)
	(segment
		(start 98.17862 -387.203442)
		(end 98.178366 -387.203696)
		(width 0.1651)
		(layer "In9.Cu")
		(net "P5E_PEX0_STN5_RX_DP<86>")
	)
	(segment
		(start 98.5012 -371.069616)
		(end 98.17862 -385.481576)
		(width 0.1651)
		(layer "In9.Cu")
		(net "P5E_PEX0_STN5_RX_DP<86>")
	)
	(segment
		(start 64.050418 -320.659252)
		(end 64.550544 -321.090544)
		(width 0.1651)
		(layer "In9.Cu")
		(net "P5E_PEX0_STN5_RX_DP<86>")
	)
	(segment
		(start 86.85276 -394.25626)
		(end 86.745064 -394.25626)
		(width 0.1651)
		(layer "In9.Cu")
		(net "P5E_PEX0_STN5_RX_DP<86>")
	)
	(segment
		(start 64.399922 -316.140592)
		(end 64.311022 -316.229492)
		(width 0.1143)
		(layer "In9.Cu")
		(net "P5E_PEX0_STN5_RX_DP<86>")
	)
	(segment
		(start 86.394544 -394.714476)
		(end 86.044532 -395.064488)
		(width 0.1651)
		(layer "In9.Cu")
		(net "P5E_PEX0_STN5_RX_DP<86>")
	)
	(segment
		(start 94.499684 -340.249256)
		(end 95.36811 -341.698326)
		(width 0.1651)
		(layer "In9.Cu")
		(net "P5E_PEX0_STN5_RX_DP<86>")
	)
	(segment
		(start 92.75445 -392.420602)
		(end 89.920826 -392.984228)
		(width 0.1651)
		(layer "In9.Cu")
		(net "P5E_PEX0_STN5_RX_DP<86>")
	)
	(segment
		(start 87.678514 -393.430506)
		(end 86.85276 -394.25626)
		(width 0.1651)
		(layer "In9.Cu")
		(net "P5E_PEX0_STN5_RX_DP<86>")
	)
	(segment
		(start 86.745064 -394.25626)
		(end 86.394544 -394.606526)
		(width 0.1651)
		(layer "In9.Cu")
		(net "P5E_PEX0_STN5_RX_DP<86>")
	)
	(segment
		(start 89.345262 -393.020804)
		(end 89.285318 -393.11072)
		(width 0.1651)
		(layer "In9.Cu")
		(net "P5E_PEX0_STN5_RX_DP<86>")
	)
	(segment
		(start 63.783972 -319.890648)
		(end 63.783972 -320.078354)
		(width 0.1651)
		(layer "In9.Cu")
		(net "P5E_PEX0_STN5_RX_DP<86>")
	)
	(segment
		(start 63.829692 -319.81648)
		(end 63.783972 -319.8622)
		(width 0.1143)
		(layer "In9.Cu")
		(net "P5E_PEX0_STN5_RX_DP<86>")
	)
	(segment
		(start 86.394544 -394.606526)
		(end 86.394544 -394.714476)
		(width 0.1651)
		(layer "In9.Cu")
		(net "P5E_PEX0_STN5_RX_DP<86>")
	)
	(segment
		(start 95.36811 -341.698326)
		(end 97.761298 -366.000792)
		(width 0.1651)
		(layer "In9.Cu")
		(net "P5E_PEX0_STN5_RX_DP<86>")
	)
	(segment
		(start 97.286064 -389.358632)
		(end 95.2627 -391.381996)
		(width 0.1651)
		(layer "In9.Cu")
		(net "P5E_PEX0_STN5_RX_DP<86>")
	)
	(segment
		(start 86.044532 -396.580614)
		(end 85.62594 -396.999206)
		(width 0.1651)
		(layer "In9.Cu")
		(net "P5E_PEX0_STN5_RX_DP<86>")
	)
	(segment
		(start 85.62594 -396.999206)
		(end 85.236812 -396.999206)
		(width 0.1651)
		(layer "In9.Cu")
		(net "P5E_PEX0_STN5_RX_DP<86>")
	)
	(segment
		(start 98.5012 -369.721638)
		(end 98.5012 -371.069616)
		(width 0.1651)
		(layer "In9.Cu")
		(net "P5E_PEX0_STN5_RX_DP<86>")
	)
	(segment
		(start 63.783972 -319.8622)
		(end 63.783972 -319.890648)
		(width 0.1143)
		(layer "In9.Cu")
		(net "P5E_PEX0_STN5_RX_DP<86>")
	)
	(segment
		(start 64.550544 -321.090544)
		(end 66.039746 -322.19519)
		(width 0.1651)
		(layer "In9.Cu")
		(net "P5E_PEX0_STN5_RX_DP<86>")
	)
	(segment
		(start 98.178366 -387.203696)
		(end 97.286064 -389.358632)
		(width 0.1651)
		(layer "In9.Cu")
		(net "P5E_PEX0_STN5_RX_DP<86>")
	)
	(segment
		(start 86.044532 -395.064488)
		(end 86.044532 -396.580614)
		(width 0.1651)
		(layer "In9.Cu")
		(net "P5E_PEX0_STN5_RX_DP<86>")
	)
	(segment
		(start 64.311022 -316.229492)
		(end 64.106298 -316.229492)
		(width 0.1143)
		(layer "In9.Cu")
		(net "P5E_PEX0_STN5_RX_DP<86>")
	)
	(segment
		(start 89.920826 -392.984228)
		(end 89.831164 -392.924284)
		(width 0.1651)
		(layer "In9.Cu")
		(net "P5E_PEX0_STN5_RX_DP<86>")
	)
	(segment
		(start 95.2627 -391.381996)
		(end 92.75445 -392.420602)
		(width 0.1651)
		(layer "In9.Cu")
		(net "P5E_PEX0_STN5_RX_DP<86>")
	)
	(segment
		(start 64.399922 -315.849762)
		(end 64.399922 -316.140592)
		(width 0.1143)
		(layer "In9.Cu")
		(net "P5E_PEX0_STN5_RX_DP<86>")
	)
	(segment
		(start 98.17862 -385.481576)
		(end 98.17862 -387.203442)
		(width 0.1651)
		(layer "In9.Cu")
		(net "P5E_PEX0_STN5_RX_DP<86>")
	)
	(segment
		(start 63.783972 -320.078354)
		(end 64.050418 -320.659252)
		(width 0.1651)
		(layer "In9.Cu")
		(net "P5E_PEX0_STN5_RX_DP<86>")
	)
	(segment
		(start 63.829692 -316.506098)
		(end 63.829692 -319.81648)
		(width 0.1143)
		(layer "In9.Cu")
		(net "P5E_PEX0_STN5_RX_DP<86>")
	)
	(segment
		(start 89.831164 -392.924284)
		(end 89.345262 -393.020804)
		(width 0.1651)
		(layer "In9.Cu")
		(net "P5E_PEX0_STN5_RX_DP<86>")
	)
	(segment
		(start 312.230008 -79.98206)
		(end 312.748422 -79.463646)
		(width 0.13208)
		(layer "F.Cu")
		(net "HP_NIC5_PWRGD")
	)
	(segment
		(start 311.514744 -80.95996)
		(end 311.514744 -79.98206)
		(width 0.13208)
		(layer "F.Cu")
		(net "HP_NIC5_PWRGD")
	)
	(segment
		(start 311.514744 -79.98206)
		(end 312.230008 -79.98206)
		(width 0.13208)
		(layer "F.Cu")
		(net "HP_NIC5_PWRGD")
	)
	(segment
		(start 312.748422 -79.463646)
		(end 313.3344 -79.463646)
		(width 0.13208)
		(layer "F.Cu")
		(net "HP_NIC5_PWRGD")
	)
	(via
		(at 312.230008 -79.98206)
		(size 0.508)
		(drill 0.254)
		(layers "F.Cu" "B.Cu")
		(net "HP_NIC5_PWRGD")
	)
	(segment
		(start 165.986968 -165.902894)
		(end 165.75913 -165.902894)
		(width 0.13208)
		(layer "F.Cu")
		(net "RST_HP_NIC2_BUF_N")
	)
	(segment
		(start 169.073322 -166.46652)
		(end 168.836848 -166.702994)
		(width 0.13208)
		(layer "F.Cu")
		(net "RST_HP_NIC2_BUF_N")
	)
	(segment
		(start 172.481494 -158.8516)
		(end 172.481494 -160.689798)
		(width 0.13208)
		(layer "F.Cu")
		(net "RST_HP_NIC2_BUF_N")
	)
	(segment
		(start 168.164256 -166.702994)
		(end 167.148256 -166.702994)
		(width 0.13208)
		(layer "F.Cu")
		(net "RST_HP_NIC2_BUF_N")
	)
	(segment
		(start 169.073322 -164.09797)
		(end 169.073322 -166.46652)
		(width 0.13208)
		(layer "F.Cu")
		(net "RST_HP_NIC2_BUF_N")
	)
	(segment
		(start 167.148256 -166.702994)
		(end 166.787068 -166.702994)
		(width 0.13208)
		(layer "F.Cu")
		(net "RST_HP_NIC2_BUF_N")
	)
	(segment
		(start 168.836848 -166.702994)
		(end 168.164256 -166.702994)
		(width 0.13208)
		(layer "F.Cu")
		(net "RST_HP_NIC2_BUF_N")
	)
	(segment
		(start 172.481494 -160.689798)
		(end 169.073322 -164.09797)
		(width 0.13208)
		(layer "F.Cu")
		(net "RST_HP_NIC2_BUF_N")
	)
	(segment
		(start 166.787068 -166.702994)
		(end 165.986968 -165.902894)
		(width 0.13208)
		(layer "F.Cu")
		(net "RST_HP_NIC2_BUF_N")
	)
	(segment
		(start 172.481494 -157.8356)
		(end 172.481494 -158.8516)
		(width 0.13208)
		(layer "F.Cu")
		(net "RST_HP_NIC2_BUF_N")
	)
	(via
		(at 169.073322 -164.09797)
		(size 0.508)
		(drill 0.254)
		(layers "F.Cu" "B.Cu")
		(net "RST_HP_NIC2_BUF_N")
	)
	(segment
		(start 38.693852 -110.408974)
		(end 38.062408 -110.408974)
		(width 0.13462)
		(layer "F.Cu")
		(net "P5E_PEX0_STN1_TX_DP<22>")
	)
	(segment
		(start 38.062408 -110.408974)
		(end 37.767768 -110.114334)
		(width 0.13462)
		(layer "F.Cu")
		(net "P5E_PEX0_STN1_TX_DP<22>")
	)
	(segment
		(start 39.013892 -110.088934)
		(end 38.693852 -110.408974)
		(width 0.13462)
		(layer "F.Cu")
		(net "P5E_PEX0_STN1_TX_DP<22>")
	)
	(segment
		(start 34.261044 -110.838742)
		(end 34.261298 -110.838742)
		(width 0.1651)
		(layer "In9.Cu")
		(net "P5E_PEX0_STN1_TX_DP<22>")
	)
	(segment
		(start 33.096708 -111.497872)
		(end 33.398206 -111.196374)
		(width 0.1651)
		(layer "In9.Cu")
		(net "P5E_PEX0_STN1_TX_DP<22>")
	)
	(segment
		(start 65.235328 -278.420068)
		(end 64.994536 -278.420068)
		(width 0.1143)
		(layer "In9.Cu")
		(net "P5E_PEX0_STN1_TX_DP<22>")
	)
	(segment
		(start 64.994536 -278.420068)
		(end 64.779652 -278.205184)
		(width 0.1143)
		(layer "In9.Cu")
		(net "P5E_PEX0_STN1_TX_DP<22>")
	)
	(segment
		(start 65.349628 -278.799798)
		(end 65.349628 -278.534368)
		(width 0.1143)
		(layer "In9.Cu")
		(net "P5E_PEX0_STN1_TX_DP<22>")
	)
	(segment
		(start 26.011632 -131.45135)
		(end 29.239718 -120.810782)
		(width 0.1651)
		(layer "In9.Cu")
		(net "P5E_PEX0_STN1_TX_DP<22>")
	)
	(segment
		(start 64.733932 -271.471898)
		(end 64.733932 -264.707116)
		(width 0.1651)
		(layer "In9.Cu")
		(net "P5E_PEX0_STN1_TX_DP<22>")
	)
	(segment
		(start 29.130244 -155.152598)
		(end 28.583636 -144.015714)
		(width 0.1651)
		(layer "In9.Cu")
		(net "P5E_PEX0_STN1_TX_DP<22>")
	)
	(segment
		(start 28.583636 -144.015714)
		(end 26.011632 -137.806684)
		(width 0.1651)
		(layer "In9.Cu")
		(net "P5E_PEX0_STN1_TX_DP<22>")
	)
	(segment
		(start 65.349628 -278.534368)
		(end 65.235328 -278.420068)
		(width 0.1143)
		(layer "In9.Cu")
		(net "P5E_PEX0_STN1_TX_DP<22>")
	)
	(segment
		(start 37.476938 -110.405164)
		(end 37.767768 -110.114334)
		(width 0.1651)
		(layer "In9.Cu")
		(net "P5E_PEX0_STN1_TX_DP<22>")
	)
	(segment
		(start 64.779652 -271.546066)
		(end 64.733932 -271.500346)
		(width 0.1143)
		(layer "In9.Cu")
		(net "P5E_PEX0_STN1_TX_DP<22>")
	)
	(segment
		(start 64.779652 -278.205184)
		(end 64.779652 -271.546066)
		(width 0.1143)
		(layer "In9.Cu")
		(net "P5E_PEX0_STN1_TX_DP<22>")
	)
	(segment
		(start 64.733932 -264.707116)
		(end 29.885894 -161.757614)
		(width 0.1651)
		(layer "In9.Cu")
		(net "P5E_PEX0_STN1_TX_DP<22>")
	)
	(segment
		(start 34.261298 -110.838742)
		(end 35.308032 -110.405164)
		(width 0.1651)
		(layer "In9.Cu")
		(net "P5E_PEX0_STN1_TX_DP<22>")
	)
	(segment
		(start 29.885894 -161.757614)
		(end 29.313378 -158.879032)
		(width 0.1651)
		(layer "In9.Cu")
		(net "P5E_PEX0_STN1_TX_DP<22>")
	)
	(segment
		(start 64.733932 -271.500346)
		(end 64.733932 -271.471898)
		(width 0.1143)
		(layer "In9.Cu")
		(net "P5E_PEX0_STN1_TX_DP<22>")
	)
	(segment
		(start 33.398206 -111.196374)
		(end 34.261044 -110.838742)
		(width 0.1651)
		(layer "In9.Cu")
		(net "P5E_PEX0_STN1_TX_DP<22>")
	)
	(segment
		(start 26.011632 -137.806684)
		(end 26.011632 -131.45135)
		(width 0.1651)
		(layer "In9.Cu")
		(net "P5E_PEX0_STN1_TX_DP<22>")
	)
	(segment
		(start 29.239718 -120.810782)
		(end 33.096708 -111.497872)
		(width 0.1651)
		(layer "In9.Cu")
		(net "P5E_PEX0_STN1_TX_DP<22>")
	)
	(segment
		(start 35.308032 -110.405164)
		(end 37.476938 -110.405164)
		(width 0.1651)
		(layer "In9.Cu")
		(net "P5E_PEX0_STN1_TX_DP<22>")
	)
	(segment
		(start 29.313378 -158.879032)
		(end 29.130244 -155.152598)
		(width 0.1651)
		(layer "In9.Cu")
		(net "P5E_PEX0_STN1_TX_DP<22>")
	)
	(segment
		(start 61.215778 -319.865248)
		(end 61.170058 -319.819528)
		(width 0.1143)
		(layer "In9.Cu")
		(net "P5E_PEX0_STN5_RX_DN<83>")
	)
	(segment
		(start 95.012002 -387.978396)
		(end 95.56496 -386.642864)
		(width 0.1651)
		(layer "In9.Cu")
		(net "P5E_PEX0_STN5_RX_DN<83>")
	)
	(segment
		(start 61.215778 -320.63055)
		(end 61.215778 -319.893696)
		(width 0.1651)
		(layer "In9.Cu")
		(net "P5E_PEX0_STN5_RX_DN<83>")
	)
	(segment
		(start 95.56496 -385.451096)
		(end 95.88754 -371.002052)
		(width 0.1651)
		(layer "In9.Cu")
		(net "P5E_PEX0_STN5_RX_DN<83>")
	)
	(segment
		(start 61.170058 -318.485266)
		(end 61.335158 -318.320166)
		(width 0.1143)
		(layer "In9.Cu")
		(net "P5E_PEX0_STN5_RX_DN<83>")
	)
	(segment
		(start 95.88754 -370.931948)
		(end 95.459804 -368.780568)
		(width 0.1651)
		(layer "In9.Cu")
		(net "P5E_PEX0_STN5_RX_DN<83>")
	)
	(segment
		(start 95.56496 -386.642864)
		(end 95.56496 -385.451096)
		(width 0.1651)
		(layer "In9.Cu")
		(net "P5E_PEX0_STN5_RX_DN<83>")
	)
	(segment
		(start 95.88754 -371.002052)
		(end 95.88754 -370.931948)
		(width 0.1651)
		(layer "In9.Cu")
		(net "P5E_PEX0_STN5_RX_DN<83>")
	)
	(segment
		(start 93.012768 -389.516874)
		(end 93.799152 -389.191246)
		(width 0.1651)
		(layer "In9.Cu")
		(net "P5E_PEX0_STN5_RX_DN<83>")
	)
	(segment
		(start 79.684372 -394.813028)
		(end 82.98561 -391.51179)
		(width 0.1651)
		(layer "In9.Cu")
		(net "P5E_PEX0_STN5_RX_DN<83>")
	)
	(segment
		(start 82.98561 -391.51179)
		(end 93.012768 -389.516874)
		(width 0.1651)
		(layer "In9.Cu")
		(net "P5E_PEX0_STN5_RX_DN<83>")
	)
	(segment
		(start 61.549788 -318.409066)
		(end 61.549788 -318.699896)
		(width 0.1143)
		(layer "In9.Cu")
		(net "P5E_PEX0_STN5_RX_DN<83>")
	)
	(segment
		(start 61.85154 -322.164456)
		(end 61.215778 -320.63055)
		(width 0.1651)
		(layer "In9.Cu")
		(net "P5E_PEX0_STN5_RX_DN<83>")
	)
	(segment
		(start 63.948564 -324.26148)
		(end 61.85154 -322.164456)
		(width 0.1651)
		(layer "In9.Cu")
		(net "P5E_PEX0_STN5_RX_DN<83>")
	)
	(segment
		(start 88.371172 -342.034368)
		(end 87.980774 -341.091774)
		(width 0.1651)
		(layer "In9.Cu")
		(net "P5E_PEX0_STN5_RX_DN<83>")
	)
	(segment
		(start 95.235014 -367.485422)
		(end 94.789752 -366.24133)
		(width 0.1651)
		(layer "In9.Cu")
		(net "P5E_PEX0_STN5_RX_DN<83>")
	)
	(segment
		(start 95.459804 -368.780568)
		(end 95.235014 -367.485422)
		(width 0.1651)
		(layer "In9.Cu")
		(net "P5E_PEX0_STN5_RX_DN<83>")
	)
	(segment
		(start 88.650064 -358.760268)
		(end 88.371172 -357.980742)
		(width 0.1651)
		(layer "In9.Cu")
		(net "P5E_PEX0_STN5_RX_DN<83>")
	)
	(segment
		(start 85.653118 -338.764118)
		(end 63.948564 -324.26148)
		(width 0.1651)
		(layer "In9.Cu")
		(net "P5E_PEX0_STN5_RX_DN<83>")
	)
	(segment
		(start 61.460888 -318.320166)
		(end 61.549788 -318.409066)
		(width 0.1143)
		(layer "In9.Cu")
		(net "P5E_PEX0_STN5_RX_DN<83>")
	)
	(segment
		(start 78.509876 -398.507966)
		(end 78.636876 -398.380966)
		(width 0.1651)
		(layer "In9.Cu")
		(net "P5E_PEX0_STN5_RX_DN<83>")
	)
	(segment
		(start 78.509876 -398.890236)
		(end 78.509876 -398.507966)
		(width 0.1651)
		(layer "In9.Cu")
		(net "P5E_PEX0_STN5_RX_DN<83>")
	)
	(segment
		(start 93.799152 -389.191246)
		(end 95.012002 -387.978396)
		(width 0.1651)
		(layer "In9.Cu")
		(net "P5E_PEX0_STN5_RX_DN<83>")
	)
	(segment
		(start 79.093822 -398.380966)
		(end 79.684372 -397.790416)
		(width 0.1651)
		(layer "In9.Cu")
		(net "P5E_PEX0_STN5_RX_DN<83>")
	)
	(segment
		(start 79.684372 -397.790416)
		(end 79.684372 -394.813028)
		(width 0.1651)
		(layer "In9.Cu")
		(net "P5E_PEX0_STN5_RX_DN<83>")
	)
	(segment
		(start 78.636876 -398.380966)
		(end 79.093822 -398.380966)
		(width 0.1651)
		(layer "In9.Cu")
		(net "P5E_PEX0_STN5_RX_DN<83>")
	)
	(segment
		(start 88.371172 -357.980742)
		(end 88.371172 -342.034368)
		(width 0.1651)
		(layer "In9.Cu")
		(net "P5E_PEX0_STN5_RX_DN<83>")
	)
	(segment
		(start 61.335158 -318.320166)
		(end 61.460888 -318.320166)
		(width 0.1143)
		(layer "In9.Cu")
		(net "P5E_PEX0_STN5_RX_DN<83>")
	)
	(segment
		(start 61.170058 -319.819528)
		(end 61.170058 -318.485266)
		(width 0.1143)
		(layer "In9.Cu")
		(net "P5E_PEX0_STN5_RX_DN<83>")
	)
	(segment
		(start 87.980774 -341.091774)
		(end 85.653118 -338.764118)
		(width 0.1651)
		(layer "In9.Cu")
		(net "P5E_PEX0_STN5_RX_DN<83>")
	)
	(segment
		(start 61.215778 -319.893696)
		(end 61.215778 -319.865248)
		(width 0.1143)
		(layer "In9.Cu")
		(net "P5E_PEX0_STN5_RX_DN<83>")
	)
	(segment
		(start 94.789752 -366.24133)
		(end 88.650064 -358.760268)
		(width 0.1651)
		(layer "In9.Cu")
		(net "P5E_PEX0_STN5_RX_DN<83>")
	)
	(segment
		(start 314.598558 -90.134694)
		(end 314.598558 -87.076026)
		(width 0.13208)
		(layer "F.Cu")
		(net "RST_HP_NIC5_BUF_N")
	)
	(segment
		(start 290.921948 -94.869762)
		(end 290.794948 -94.996762)
		(width 0.13208)
		(layer "F.Cu")
		(net "RST_HP_NIC5_BUF_N")
	)
	(segment
		(start 311.43448 -86.949026)
		(end 312.823606 -86.949026)
		(width 0.13208)
		(layer "F.Cu")
		(net "RST_HP_NIC5_BUF_N")
	)
	(segment
		(start 314.019438 -90.713814)
		(end 314.598558 -90.134694)
		(width 0.13208)
		(layer "F.Cu")
		(net "RST_HP_NIC5_BUF_N")
	)
	(segment
		(start 314.598558 -87.076026)
		(end 314.471558 -86.949026)
		(width 0.13208)
		(layer "F.Cu")
		(net "RST_HP_NIC5_BUF_N")
	)
	(segment
		(start 297.095672 -94.869762)
		(end 290.921948 -94.869762)
		(width 0.13208)
		(layer "F.Cu")
		(net "RST_HP_NIC5_BUF_N")
	)
	(segment
		(start 297.91279 -94.052644)
		(end 297.91279 -93.250766)
		(width 0.13208)
		(layer "F.Cu")
		(net "RST_HP_NIC5_BUF_N")
	)
	(segment
		(start 312.823606 -86.949026)
		(end 313.839606 -86.949026)
		(width 0.13208)
		(layer "F.Cu")
		(net "RST_HP_NIC5_BUF_N")
	)
	(segment
		(start 297.91279 -93.250766)
		(end 300.449742 -90.713814)
		(width 0.13208)
		(layer "F.Cu")
		(net "RST_HP_NIC5_BUF_N")
	)
	(segment
		(start 314.471558 -86.949026)
		(end 313.839606 -86.949026)
		(width 0.13208)
		(layer "F.Cu")
		(net "RST_HP_NIC5_BUF_N")
	)
	(segment
		(start 300.449742 -90.713814)
		(end 314.019438 -90.713814)
		(width 0.13208)
		(layer "F.Cu")
		(net "RST_HP_NIC5_BUF_N")
	)
	(segment
		(start 290.794948 -96.702372)
		(end 290.794948 -97.718372)
		(width 0.13208)
		(layer "F.Cu")
		(net "RST_HP_NIC5_BUF_N")
	)
	(segment
		(start 297.095672 -94.869762)
		(end 297.91279 -94.052644)
		(width 0.13208)
		(layer "F.Cu")
		(net "RST_HP_NIC5_BUF_N")
	)
	(segment
		(start 290.794948 -94.996762)
		(end 290.794948 -96.702372)
		(width 0.13208)
		(layer "F.Cu")
		(net "RST_HP_NIC5_BUF_N")
	)
	(via
		(at 297.095672 -94.869762)
		(size 0.762)
		(drill 0.381)
		(layers "F.Cu" "B.Cu")
		(net "RST_HP_NIC5_BUF_N")
	)
	(segment
		(start 83.87969 -144.716754)
		(end 84.17433 -144.422114)
		(width 0.13462)
		(layer "F.Cu")
		(net "P5E_PEX0_STN0_TX_DN<9>")
	)
	(segment
		(start 83.248246 -144.716754)
		(end 83.87969 -144.716754)
		(width 0.13462)
		(layer "F.Cu")
		(net "P5E_PEX0_STN0_TX_DN<9>")
	)
	(segment
		(start 82.928206 -144.396714)
		(end 83.248246 -144.716754)
		(width 0.13462)
		(layer "F.Cu")
		(net "P5E_PEX0_STN0_TX_DN<9>")
	)
	(segment
		(start 80.273652 -278.229568)
		(end 80.43545 -278.229568)
		(width 0.1143)
		(layer "In9.Cu")
		(net "P5E_PEX0_STN0_TX_DN<9>")
	)
	(segment
		(start 80.215994 -271.357344)
		(end 80.215994 -271.471898)
		(width 0.1651)
		(layer "In9.Cu")
		(net "P5E_PEX0_STN0_TX_DN<9>")
	)
	(segment
		(start 80.170274 -278.12619)
		(end 80.273652 -278.229568)
		(width 0.1143)
		(layer "In9.Cu")
		(net "P5E_PEX0_STN0_TX_DN<9>")
	)
	(segment
		(start 80.43545 -278.229568)
		(end 80.54975 -278.115268)
		(width 0.1143)
		(layer "In9.Cu")
		(net "P5E_PEX0_STN0_TX_DN<9>")
	)
	(segment
		(start 80.215994 -271.500346)
		(end 80.170274 -271.546066)
		(width 0.1143)
		(layer "In9.Cu")
		(net "P5E_PEX0_STN0_TX_DN<9>")
	)
	(segment
		(start 91.461844 -154.593036)
		(end 91.461844 -158.27502)
		(width 0.1651)
		(layer "In9.Cu")
		(net "P5E_PEX0_STN0_TX_DN<9>")
	)
	(segment
		(start 87.327486 -146.867626)
		(end 89.785444 -150.546054)
		(width 0.1651)
		(layer "In9.Cu")
		(net "P5E_PEX0_STN0_TX_DN<9>")
	)
	(segment
		(start 80.170274 -271.546066)
		(end 80.170274 -278.12619)
		(width 0.1143)
		(layer "In9.Cu")
		(net "P5E_PEX0_STN0_TX_DN<9>")
	)
	(segment
		(start 89.785444 -150.546054)
		(end 91.461844 -154.593036)
		(width 0.1651)
		(layer "In9.Cu")
		(net "P5E_PEX0_STN0_TX_DN<9>")
	)
	(segment
		(start 91.461844 -158.27502)
		(end 82.978498 -172.971714)
		(width 0.1651)
		(layer "In9.Cu")
		(net "P5E_PEX0_STN0_TX_DN<9>")
	)
	(segment
		(start 85.172804 -144.712944)
		(end 87.327486 -146.867626)
		(width 0.1651)
		(layer "In9.Cu")
		(net "P5E_PEX0_STN0_TX_DN<9>")
	)
	(segment
		(start 84.17433 -144.422114)
		(end 84.46516 -144.712944)
		(width 0.1651)
		(layer "In9.Cu")
		(net "P5E_PEX0_STN0_TX_DN<9>")
	)
	(segment
		(start 81.698592 -177.74412)
		(end 77.835506 -221.85376)
		(width 0.1651)
		(layer "In9.Cu")
		(net "P5E_PEX0_STN0_TX_DN<9>")
	)
	(segment
		(start 81.196688 -260.314694)
		(end 81.196688 -268.989302)
		(width 0.1651)
		(layer "In9.Cu")
		(net "P5E_PEX0_STN0_TX_DN<9>")
	)
	(segment
		(start 81.196688 -268.989302)
		(end 80.215994 -271.357344)
		(width 0.1651)
		(layer "In9.Cu")
		(net "P5E_PEX0_STN0_TX_DN<9>")
	)
	(segment
		(start 82.978498 -172.971714)
		(end 81.698592 -177.74412)
		(width 0.1651)
		(layer "In9.Cu")
		(net "P5E_PEX0_STN0_TX_DN<9>")
	)
	(segment
		(start 84.46516 -144.712944)
		(end 85.172804 -144.712944)
		(width 0.1651)
		(layer "In9.Cu")
		(net "P5E_PEX0_STN0_TX_DN<9>")
	)
	(segment
		(start 77.835506 -221.85376)
		(end 81.196688 -260.314694)
		(width 0.1651)
		(layer "In9.Cu")
		(net "P5E_PEX0_STN0_TX_DN<9>")
	)
	(segment
		(start 80.215994 -271.471898)
		(end 80.215994 -271.500346)
		(width 0.1143)
		(layer "In9.Cu")
		(net "P5E_PEX0_STN0_TX_DN<9>")
	)
	(segment
		(start 80.54975 -278.115268)
		(end 80.54975 -277.849838)
		(width 0.1143)
		(layer "In9.Cu")
		(net "P5E_PEX0_STN0_TX_DN<9>")
	)
	(segment
		(start 73.1266 -394.5636)
		(end 78.137258 -389.552942)
		(width 0.1651)
		(layer "In9.Cu")
		(net "P5E_PEX0_STN5_RX_DN<80>")
	)
	(segment
		(start 58.485278 -316.419992)
		(end 58.611008 -316.419992)
		(width 0.1143)
		(layer "In9.Cu")
		(net "P5E_PEX0_STN5_RX_DN<80>")
	)
	(segment
		(start 78.137258 -389.552942)
		(end 92.176854 -386.76072)
		(width 0.1651)
		(layer "In9.Cu")
		(net "P5E_PEX0_STN5_RX_DN<80>")
	)
	(segment
		(start 58.320178 -316.585092)
		(end 58.485278 -316.419992)
		(width 0.1143)
		(layer "In9.Cu")
		(net "P5E_PEX0_STN5_RX_DN<80>")
	)
	(segment
		(start 92.51061 -386.426456)
		(end 92.654628 -386.078222)
		(width 0.1651)
		(layer "In9.Cu")
		(net "P5E_PEX0_STN5_RX_DN<80>")
	)
	(segment
		(start 92.976192 -370.985034)
		(end 92.505276 -368.616484)
		(width 0.1651)
		(layer "In9.Cu")
		(net "P5E_PEX0_STN5_RX_DN<80>")
	)
	(segment
		(start 79.044292 -358.444292)
		(end 79.044292 -342.079072)
		(width 0.1651)
		(layer "In9.Cu")
		(net "P5E_PEX0_STN5_RX_DN<80>")
	)
	(segment
		(start 58.611008 -316.419992)
		(end 58.699908 -316.508892)
		(width 0.1143)
		(layer "In9.Cu")
		(net "P5E_PEX0_STN5_RX_DN<80>")
	)
	(segment
		(start 71.90994 -397.408146)
		(end 72.03694 -397.281146)
		(width 0.1651)
		(layer "In9.Cu")
		(net "P5E_PEX0_STN5_RX_DN<80>")
	)
	(segment
		(start 63.901574 -328.266806)
		(end 59.191906 -323.557138)
		(width 0.1651)
		(layer "In9.Cu")
		(net "P5E_PEX0_STN5_RX_DN<80>")
	)
	(segment
		(start 70.644004 -332.772004)
		(end 63.901574 -328.266806)
		(width 0.1651)
		(layer "In9.Cu")
		(net "P5E_PEX0_STN5_RX_DN<80>")
	)
	(segment
		(start 73.1266 -396.697454)
		(end 73.1266 -394.5636)
		(width 0.1651)
		(layer "In9.Cu")
		(net "P5E_PEX0_STN5_RX_DN<80>")
	)
	(segment
		(start 71.90994 -397.790162)
		(end 71.90994 -397.408146)
		(width 0.1651)
		(layer "In9.Cu")
		(net "P5E_PEX0_STN5_RX_DN<80>")
	)
	(segment
		(start 58.365898 -321.562984)
		(end 58.365898 -319.944496)
		(width 0.1651)
		(layer "In9.Cu")
		(net "P5E_PEX0_STN5_RX_DN<80>")
	)
	(segment
		(start 58.365898 -319.916048)
		(end 58.320178 -319.870328)
		(width 0.1143)
		(layer "In9.Cu")
		(net "P5E_PEX0_STN5_RX_DN<80>")
	)
	(segment
		(start 92.505276 -368.616484)
		(end 92.21851 -367.923826)
		(width 0.1651)
		(layer "In9.Cu")
		(net "P5E_PEX0_STN5_RX_DN<80>")
	)
	(segment
		(start 92.654628 -386.078222)
		(end 92.654628 -385.418584)
		(width 0.1651)
		(layer "In9.Cu")
		(net "P5E_PEX0_STN5_RX_DN<80>")
	)
	(segment
		(start 92.654628 -385.418584)
		(end 92.976192 -370.985034)
		(width 0.1651)
		(layer "In9.Cu")
		(net "P5E_PEX0_STN5_RX_DN<80>")
	)
	(segment
		(start 78.403196 -340.531196)
		(end 70.644004 -332.772004)
		(width 0.1651)
		(layer "In9.Cu")
		(net "P5E_PEX0_STN5_RX_DN<80>")
	)
	(segment
		(start 58.699908 -316.508892)
		(end 58.699908 -316.799722)
		(width 0.1143)
		(layer "In9.Cu")
		(net "P5E_PEX0_STN5_RX_DN<80>")
	)
	(segment
		(start 81.686654 -360.886756)
		(end 80.571848 -359.971848)
		(width 0.1651)
		(layer "In9.Cu")
		(net "P5E_PEX0_STN5_RX_DN<80>")
	)
	(segment
		(start 72.03694 -397.281146)
		(end 72.542908 -397.281146)
		(width 0.1651)
		(layer "In9.Cu")
		(net "P5E_PEX0_STN5_RX_DN<80>")
	)
	(segment
		(start 59.191906 -323.557138)
		(end 58.365898 -321.562984)
		(width 0.1651)
		(layer "In9.Cu")
		(net "P5E_PEX0_STN5_RX_DN<80>")
	)
	(segment
		(start 58.365898 -319.944496)
		(end 58.365898 -319.916048)
		(width 0.1143)
		(layer "In9.Cu")
		(net "P5E_PEX0_STN5_RX_DN<80>")
	)
	(segment
		(start 80.571848 -359.971848)
		(end 79.044292 -358.444292)
		(width 0.1651)
		(layer "In9.Cu")
		(net "P5E_PEX0_STN5_RX_DN<80>")
	)
	(segment
		(start 92.21851 -367.923826)
		(end 81.686654 -360.886756)
		(width 0.1651)
		(layer "In9.Cu")
		(net "P5E_PEX0_STN5_RX_DN<80>")
	)
	(segment
		(start 92.176854 -386.76072)
		(end 92.51061 -386.426456)
		(width 0.1651)
		(layer "In9.Cu")
		(net "P5E_PEX0_STN5_RX_DN<80>")
	)
	(segment
		(start 58.320178 -319.870328)
		(end 58.320178 -316.585092)
		(width 0.1143)
		(layer "In9.Cu")
		(net "P5E_PEX0_STN5_RX_DN<80>")
	)
	(segment
		(start 72.542908 -397.281146)
		(end 73.1266 -396.697454)
		(width 0.1651)
		(layer "In9.Cu")
		(net "P5E_PEX0_STN5_RX_DN<80>")
	)
	(segment
		(start 79.044292 -342.079072)
		(end 78.403196 -340.531196)
		(width 0.1651)
		(layer "In9.Cu")
		(net "P5E_PEX0_STN5_RX_DN<80>")
	)
	(segment
		(start 305.892454 -80.749394)
		(end 307.089556 -80.749394)
		(width 0.13208)
		(layer "F.Cu")
		(net "HP_NIC5_HSC_PWRGD_N")
	)
	(segment
		(start 307.439822 -81.09966)
		(end 307.089556 -80.749394)
		(width 0.13208)
		(layer "F.Cu")
		(net "HP_NIC5_HSC_PWRGD_N")
	)
	(segment
		(start 307.089556 -80.749394)
		(end 307.389276 -80.449674)
		(width 0.13208)
		(layer "F.Cu")
		(net "HP_NIC5_HSC_PWRGD_N")
	)
	(segment
		(start 307.389276 -80.449674)
		(end 308.357524 -80.449674)
		(width 0.13208)
		(layer "F.Cu")
		(net "HP_NIC5_HSC_PWRGD_N")
	)
	(segment
		(start 305.882802 -80.739742)
		(end 305.892454 -80.749394)
		(width 0.13208)
		(layer "F.Cu")
		(net "HP_NIC5_HSC_PWRGD_N")
	)
	(segment
		(start 308.357524 -81.09966)
		(end 307.439822 -81.09966)
		(width 0.13208)
		(layer "F.Cu")
		(net "HP_NIC5_HSC_PWRGD_N")
	)
	(via
		(at 307.089556 -80.749394)
		(size 0.762)
		(drill 0.381)
		(layers "F.Cu" "B.Cu")
		(net "HP_NIC5_HSC_PWRGD_N")
	)
	(segment
		(start 83.87969 -155.516834)
		(end 84.17433 -155.222194)
		(width 0.13462)
		(layer "F.Cu")
		(net "P5E_PEX0_STN0_TX_DN<15>")
	)
	(segment
		(start 82.928206 -155.196794)
		(end 83.248246 -155.516834)
		(width 0.13462)
		(layer "F.Cu")
		(net "P5E_PEX0_STN0_TX_DN<15>")
	)
	(segment
		(start 83.248246 -155.516834)
		(end 83.87969 -155.516834)
		(width 0.13462)
		(layer "F.Cu")
		(net "P5E_PEX0_STN0_TX_DN<15>")
	)
	(segment
		(start 74.51598 -271.500346)
		(end 74.47026 -271.546066)
		(width 0.1143)
		(layer "In9.Cu")
		(net "P5E_PEX0_STN0_TX_DN<15>")
	)
	(segment
		(start 74.735436 -278.229568)
		(end 74.849736 -278.115268)
		(width 0.1143)
		(layer "In9.Cu")
		(net "P5E_PEX0_STN0_TX_DN<15>")
	)
	(segment
		(start 84.17433 -155.222194)
		(end 84.46516 -155.513024)
		(width 0.1651)
		(layer "In9.Cu")
		(net "P5E_PEX0_STN0_TX_DN<15>")
	)
	(segment
		(start 85.657182 -156.571442)
		(end 77.174344 -171.265088)
		(width 0.1651)
		(layer "In9.Cu")
		(net "P5E_PEX0_STN0_TX_DN<15>")
	)
	(segment
		(start 74.573638 -278.229568)
		(end 74.735436 -278.229568)
		(width 0.1143)
		(layer "In9.Cu")
		(net "P5E_PEX0_STN0_TX_DN<15>")
	)
	(segment
		(start 75.390248 -267.473684)
		(end 74.51598 -269.584932)
		(width 0.1651)
		(layer "In9.Cu")
		(net "P5E_PEX0_STN0_TX_DN<15>")
	)
	(segment
		(start 84.46516 -155.513024)
		(end 85.190838 -155.513024)
		(width 0.1651)
		(layer "In9.Cu")
		(net "P5E_PEX0_STN0_TX_DN<15>")
	)
	(segment
		(start 75.390248 -260.731254)
		(end 75.390248 -267.473684)
		(width 0.1651)
		(layer "In9.Cu")
		(net "P5E_PEX0_STN0_TX_DN<15>")
	)
	(segment
		(start 74.51598 -269.584932)
		(end 74.51598 -271.471898)
		(width 0.1651)
		(layer "In9.Cu")
		(net "P5E_PEX0_STN0_TX_DN<15>")
	)
	(segment
		(start 71.86295 -220.410278)
		(end 75.390248 -260.731254)
		(width 0.1651)
		(layer "In9.Cu")
		(net "P5E_PEX0_STN0_TX_DN<15>")
	)
	(segment
		(start 74.47026 -278.12619)
		(end 74.573638 -278.229568)
		(width 0.1143)
		(layer "In9.Cu")
		(net "P5E_PEX0_STN0_TX_DN<15>")
	)
	(segment
		(start 75.671934 -176.871122)
		(end 71.86295 -220.410278)
		(width 0.1651)
		(layer "In9.Cu")
		(net "P5E_PEX0_STN0_TX_DN<15>")
	)
	(segment
		(start 85.190838 -155.513024)
		(end 85.657182 -155.979368)
		(width 0.1651)
		(layer "In9.Cu")
		(net "P5E_PEX0_STN0_TX_DN<15>")
	)
	(segment
		(start 74.849736 -278.115268)
		(end 74.849736 -277.849838)
		(width 0.1143)
		(layer "In9.Cu")
		(net "P5E_PEX0_STN0_TX_DN<15>")
	)
	(segment
		(start 77.174344 -171.265088)
		(end 75.671934 -176.871122)
		(width 0.1651)
		(layer "In9.Cu")
		(net "P5E_PEX0_STN0_TX_DN<15>")
	)
	(segment
		(start 85.657182 -155.979368)
		(end 85.657182 -156.571442)
		(width 0.1651)
		(layer "In9.Cu")
		(net "P5E_PEX0_STN0_TX_DN<15>")
	)
	(segment
		(start 74.51598 -271.471898)
		(end 74.51598 -271.500346)
		(width 0.1143)
		(layer "In9.Cu")
		(net "P5E_PEX0_STN0_TX_DN<15>")
	)
	(segment
		(start 74.47026 -271.546066)
		(end 74.47026 -278.12619)
		(width 0.1143)
		(layer "In9.Cu")
		(net "P5E_PEX0_STN0_TX_DN<15>")
	)
	(segment
		(start 17.751806 -331.086968)
		(end 20.111974 -318.830706)
		(width 0.1651)
		(layer "In5.Cu")
		(net "P5E_PEX0_STN7_RX_DN<114>")
	)
	(segment
		(start 24.58466 -308.913276)
		(end 24.81834 -308.476142)
		(width 0.1651)
		(layer "In5.Cu")
		(net "P5E_PEX0_STN7_RX_DN<114>")
	)
	(segment
		(start 32.31007 -409.490164)
		(end 32.31007 -409.108148)
		(width 0.1651)
		(layer "In5.Cu")
		(net "P5E_PEX0_STN7_RX_DN<114>")
	)
	(segment
		(start 35.56 -303.165764)
		(end 35.588448 -303.165764)
		(width 0.1143)
		(layer "In5.Cu")
		(net "P5E_PEX0_STN7_RX_DN<114>")
	)
	(segment
		(start 16.4084 -341.980012)
		(end 17.751806 -331.086968)
		(width 0.1651)
		(layer "In5.Cu")
		(net "P5E_PEX0_STN7_RX_DN<114>")
	)
	(segment
		(start 20.363688 -317.877698)
		(end 22.724364 -312.179208)
		(width 0.1651)
		(layer "In5.Cu")
		(net "P5E_PEX0_STN7_RX_DN<114>")
	)
	(segment
		(start 33.458912 -395.494764)
		(end 33.111186 -394.655294)
		(width 0.1651)
		(layer "In5.Cu")
		(net "P5E_PEX0_STN7_RX_DN<114>")
	)
	(segment
		(start 27.528774 -304.94097)
		(end 30.57144 -303.679098)
		(width 0.1651)
		(layer "In5.Cu")
		(net "P5E_PEX0_STN7_RX_DN<114>")
	)
	(segment
		(start 22.207728 -385.515358)
		(end 19.112992 -369.955318)
		(width 0.1651)
		(layer "In5.Cu")
		(net "P5E_PEX0_STN7_RX_DN<114>")
	)
	(segment
		(start 24.25573 -309.529226)
		(end 24.21382 -309.391558)
		(width 0.1651)
		(layer "In5.Cu")
		(net "P5E_PEX0_STN7_RX_DN<114>")
	)
	(segment
		(start 24.447246 -308.954932)
		(end 24.58466 -308.913276)
		(width 0.1651)
		(layer "In5.Cu")
		(net "P5E_PEX0_STN7_RX_DN<114>")
	)
	(segment
		(start 20.111974 -318.830706)
		(end 20.363688 -317.877698)
		(width 0.1651)
		(layer "In5.Cu")
		(net "P5E_PEX0_STN7_RX_DN<114>")
	)
	(segment
		(start 24.21382 -309.391558)
		(end 24.447246 -308.954932)
		(width 0.1651)
		(layer "In5.Cu")
		(net "P5E_PEX0_STN7_RX_DN<114>")
	)
	(segment
		(start 32.623506 -394.167614)
		(end 24.808942 -389.483346)
		(width 0.1651)
		(layer "In5.Cu")
		(net "P5E_PEX0_STN7_RX_DN<114>")
	)
	(segment
		(start 39.129716 -303.385474)
		(end 39.015416 -303.499774)
		(width 0.1143)
		(layer "In5.Cu")
		(net "P5E_PEX0_STN7_RX_DN<114>")
	)
	(segment
		(start 39.015416 -303.499774)
		(end 38.749986 -303.499774)
		(width 0.1143)
		(layer "In5.Cu")
		(net "P5E_PEX0_STN7_RX_DN<114>")
	)
	(segment
		(start 16.4084 -351.724214)
		(end 16.4084 -341.980012)
		(width 0.1651)
		(layer "In5.Cu")
		(net "P5E_PEX0_STN7_RX_DN<114>")
	)
	(segment
		(start 25.840182 -306.629562)
		(end 27.528774 -304.94097)
		(width 0.1651)
		(layer "In5.Cu")
		(net "P5E_PEX0_STN7_RX_DN<114>")
	)
	(segment
		(start 23.321772 -311.0611)
		(end 23.459186 -311.019444)
		(width 0.1651)
		(layer "In5.Cu")
		(net "P5E_PEX0_STN7_RX_DN<114>")
	)
	(segment
		(start 22.724364 -312.179208)
		(end 23.321772 -311.0611)
		(width 0.1651)
		(layer "In5.Cu")
		(net "P5E_PEX0_STN7_RX_DN<114>")
	)
	(segment
		(start 33.111186 -394.655294)
		(end 32.623506 -394.167614)
		(width 0.1651)
		(layer "In5.Cu")
		(net "P5E_PEX0_STN7_RX_DN<114>")
	)
	(segment
		(start 23.17496 -387.849364)
		(end 22.207728 -385.515358)
		(width 0.1651)
		(layer "In5.Cu")
		(net "P5E_PEX0_STN7_RX_DN<114>")
	)
	(segment
		(start 35.634168 -303.120044)
		(end 39.015416 -303.120044)
		(width 0.1143)
		(layer "In5.Cu")
		(net "P5E_PEX0_STN7_RX_DN<114>")
	)
	(segment
		(start 39.129716 -303.234344)
		(end 39.129716 -303.385474)
		(width 0.1143)
		(layer "In5.Cu")
		(net "P5E_PEX0_STN7_RX_DN<114>")
	)
	(segment
		(start 32.883094 -408.981148)
		(end 33.458912 -408.40533)
		(width 0.1651)
		(layer "In5.Cu")
		(net "P5E_PEX0_STN7_RX_DN<114>")
	)
	(segment
		(start 30.57144 -303.679098)
		(end 33.147508 -303.165764)
		(width 0.1651)
		(layer "In5.Cu")
		(net "P5E_PEX0_STN7_RX_DN<114>")
	)
	(segment
		(start 35.588448 -303.165764)
		(end 35.634168 -303.120044)
		(width 0.1143)
		(layer "In5.Cu")
		(net "P5E_PEX0_STN7_RX_DN<114>")
	)
	(segment
		(start 39.015416 -303.120044)
		(end 39.129716 -303.234344)
		(width 0.1143)
		(layer "In5.Cu")
		(net "P5E_PEX0_STN7_RX_DN<114>")
	)
	(segment
		(start 33.458912 -408.40533)
		(end 33.458912 -395.494764)
		(width 0.1651)
		(layer "In5.Cu")
		(net "P5E_PEX0_STN7_RX_DN<114>")
	)
	(segment
		(start 24.776684 -308.338728)
		(end 25.09139 -307.749702)
		(width 0.1651)
		(layer "In5.Cu")
		(net "P5E_PEX0_STN7_RX_DN<114>")
	)
	(segment
		(start 19.112992 -369.955318)
		(end 16.4084 -351.724214)
		(width 0.1651)
		(layer "In5.Cu")
		(net "P5E_PEX0_STN7_RX_DN<114>")
	)
	(segment
		(start 23.692866 -310.58231)
		(end 23.65121 -310.444642)
		(width 0.1651)
		(layer "In5.Cu")
		(net "P5E_PEX0_STN7_RX_DN<114>")
	)
	(segment
		(start 25.09139 -307.749702)
		(end 25.840182 -306.629562)
		(width 0.1651)
		(layer "In5.Cu")
		(net "P5E_PEX0_STN7_RX_DN<114>")
	)
	(segment
		(start 23.65121 -310.444642)
		(end 23.884382 -310.008016)
		(width 0.1651)
		(layer "In5.Cu")
		(net "P5E_PEX0_STN7_RX_DN<114>")
	)
	(segment
		(start 24.808942 -389.483346)
		(end 23.17496 -387.849364)
		(width 0.1651)
		(layer "In5.Cu")
		(net "P5E_PEX0_STN7_RX_DN<114>")
	)
	(segment
		(start 24.02205 -309.96636)
		(end 24.25573 -309.529226)
		(width 0.1651)
		(layer "In5.Cu")
		(net "P5E_PEX0_STN7_RX_DN<114>")
	)
	(segment
		(start 23.459186 -311.019444)
		(end 23.692866 -310.58231)
		(width 0.1651)
		(layer "In5.Cu")
		(net "P5E_PEX0_STN7_RX_DN<114>")
	)
	(segment
		(start 32.43707 -408.981148)
		(end 32.883094 -408.981148)
		(width 0.1651)
		(layer "In5.Cu")
		(net "P5E_PEX0_STN7_RX_DN<114>")
	)
	(segment
		(start 24.81834 -308.476142)
		(end 24.776684 -308.338728)
		(width 0.1651)
		(layer "In5.Cu")
		(net "P5E_PEX0_STN7_RX_DN<114>")
	)
	(segment
		(start 32.31007 -409.108148)
		(end 32.43707 -408.981148)
		(width 0.1651)
		(layer "In5.Cu")
		(net "P5E_PEX0_STN7_RX_DN<114>")
	)
	(segment
		(start 23.884382 -310.008016)
		(end 24.02205 -309.96636)
		(width 0.1651)
		(layer "In5.Cu")
		(net "P5E_PEX0_STN7_RX_DN<114>")
	)
	(segment
		(start 33.147508 -303.165764)
		(end 35.56 -303.165764)
		(width 0.1651)
		(layer "In5.Cu")
		(net "P5E_PEX0_STN7_RX_DN<114>")
	)
	(segment
		(start 38.693852 -106.808778)
		(end 38.062408 -106.808778)
		(width 0.13462)
		(layer "F.Cu")
		(net "P5E_PEX0_STN1_TX_DP<20>")
	)
	(segment
		(start 39.013892 -106.488738)
		(end 38.693852 -106.808778)
		(width 0.13462)
		(layer "F.Cu")
		(net "P5E_PEX0_STN1_TX_DP<20>")
	)
	(segment
		(start 38.062408 -106.808778)
		(end 37.767768 -106.514138)
		(width 0.13462)
		(layer "F.Cu")
		(net "P5E_PEX0_STN1_TX_DP<20>")
	)
	(segment
		(start 26.65857 -144.488662)
		(end 27.382978 -159.221678)
		(width 0.1651)
		(layer "In9.Cu")
		(net "P5E_PEX0_STN1_TX_DP<20>")
	)
	(segment
		(start 28.074874 -117.988842)
		(end 24.076152 -131.172458)
		(width 0.1651)
		(layer "In9.Cu")
		(net "P5E_PEX0_STN1_TX_DP<20>")
	)
	(segment
		(start 62.879732 -278.205184)
		(end 63.094616 -278.420068)
		(width 0.1143)
		(layer "In9.Cu")
		(net "P5E_PEX0_STN1_TX_DP<20>")
	)
	(segment
		(start 62.879732 -271.546066)
		(end 62.879732 -278.205184)
		(width 0.1143)
		(layer "In9.Cu")
		(net "P5E_PEX0_STN1_TX_DP<20>")
	)
	(segment
		(start 62.834012 -265.13282)
		(end 62.834012 -271.471898)
		(width 0.1651)
		(layer "In9.Cu")
		(net "P5E_PEX0_STN1_TX_DP<20>")
	)
	(segment
		(start 31.574232 -109.540548)
		(end 28.074874 -117.988842)
		(width 0.1651)
		(layer "In9.Cu")
		(net "P5E_PEX0_STN1_TX_DP<20>")
	)
	(segment
		(start 37.767768 -106.514138)
		(end 37.476938 -106.804968)
		(width 0.1651)
		(layer "In9.Cu")
		(net "P5E_PEX0_STN1_TX_DP<20>")
	)
	(segment
		(start 63.094616 -278.420068)
		(end 63.335408 -278.420068)
		(width 0.1143)
		(layer "In9.Cu")
		(net "P5E_PEX0_STN1_TX_DP<20>")
	)
	(segment
		(start 33.42259 -107.69219)
		(end 31.574232 -109.540548)
		(width 0.1651)
		(layer "In9.Cu")
		(net "P5E_PEX0_STN1_TX_DP<20>")
	)
	(segment
		(start 27.382978 -159.221678)
		(end 27.950922 -162.077146)
		(width 0.1651)
		(layer "In9.Cu")
		(net "P5E_PEX0_STN1_TX_DP<20>")
	)
	(segment
		(start 24.076152 -131.172458)
		(end 24.076152 -138.253978)
		(width 0.1651)
		(layer "In9.Cu")
		(net "P5E_PEX0_STN1_TX_DP<20>")
	)
	(segment
		(start 63.335408 -278.420068)
		(end 63.449708 -278.534368)
		(width 0.1143)
		(layer "In9.Cu")
		(net "P5E_PEX0_STN1_TX_DP<20>")
	)
	(segment
		(start 27.950922 -162.077146)
		(end 62.834012 -265.13282)
		(width 0.1651)
		(layer "In9.Cu")
		(net "P5E_PEX0_STN1_TX_DP<20>")
	)
	(segment
		(start 35.564572 -106.804968)
		(end 33.42259 -107.69219)
		(width 0.1651)
		(layer "In9.Cu")
		(net "P5E_PEX0_STN1_TX_DP<20>")
	)
	(segment
		(start 62.834012 -271.500346)
		(end 62.879732 -271.546066)
		(width 0.1143)
		(layer "In9.Cu")
		(net "P5E_PEX0_STN1_TX_DP<20>")
	)
	(segment
		(start 62.834012 -271.471898)
		(end 62.834012 -271.500346)
		(width 0.1143)
		(layer "In9.Cu")
		(net "P5E_PEX0_STN1_TX_DP<20>")
	)
	(segment
		(start 37.476938 -106.804968)
		(end 35.564572 -106.804968)
		(width 0.1651)
		(layer "In9.Cu")
		(net "P5E_PEX0_STN1_TX_DP<20>")
	)
	(segment
		(start 63.449708 -278.534368)
		(end 63.449708 -278.799798)
		(width 0.1143)
		(layer "In9.Cu")
		(net "P5E_PEX0_STN1_TX_DP<20>")
	)
	(segment
		(start 24.076152 -138.253978)
		(end 26.65857 -144.488662)
		(width 0.1651)
		(layer "In9.Cu")
		(net "P5E_PEX0_STN1_TX_DP<20>")
	)
	(segment
		(start 60.599828 -316.140592)
		(end 60.599828 -315.849762)
		(width 0.1143)
		(layer "In9.Cu")
		(net "P5E_PEX0_STN5_RX_DP<82>")
	)
	(segment
		(start 60.755784 -322.818252)
		(end 59.983878 -320.954908)
		(width 0.1651)
		(layer "In9.Cu")
		(net "P5E_PEX0_STN5_RX_DP<82>")
	)
	(segment
		(start 79.645764 -336.330544)
		(end 63.438786 -325.501254)
		(width 0.1651)
		(layer "In9.Cu")
		(net "P5E_PEX0_STN5_RX_DP<82>")
	)
	(segment
		(start 60.029598 -316.506098)
		(end 60.306204 -316.229492)
		(width 0.1143)
		(layer "In9.Cu")
		(net "P5E_PEX0_STN5_RX_DP<82>")
	)
	(segment
		(start 94.6404 -371.423184)
		(end 94.6404 -371.004338)
		(width 0.1651)
		(layer "In9.Cu")
		(net "P5E_PEX0_STN5_RX_DP<82>")
	)
	(segment
		(start 63.438786 -325.501254)
		(end 60.755784 -322.818252)
		(width 0.1651)
		(layer "In9.Cu")
		(net "P5E_PEX0_STN5_RX_DP<82>")
	)
	(segment
		(start 76.436982 -396.999206)
		(end 76.82611 -396.999206)
		(width 0.1651)
		(layer "In9.Cu")
		(net "P5E_PEX0_STN5_RX_DP<82>")
	)
	(segment
		(start 94.327726 -386.319776)
		(end 94.327726 -385.436872)
		(width 0.1651)
		(layer "In9.Cu")
		(net "P5E_PEX0_STN5_RX_DP<82>")
	)
	(segment
		(start 79.42707 -392.168634)
		(end 79.534766 -392.168634)
		(width 0.1651)
		(layer "In9.Cu")
		(net "P5E_PEX0_STN5_RX_DP<82>")
	)
	(segment
		(start 78.726538 -392.976862)
		(end 79.07655 -392.62685)
		(width 0.1651)
		(layer "In9.Cu")
		(net "P5E_PEX0_STN5_RX_DP<82>")
	)
	(segment
		(start 59.983878 -319.916048)
		(end 60.029598 -319.870328)
		(width 0.1143)
		(layer "In9.Cu")
		(net "P5E_PEX0_STN5_RX_DP<82>")
	)
	(segment
		(start 59.983878 -320.954908)
		(end 59.983878 -319.944496)
		(width 0.1651)
		(layer "In9.Cu")
		(net "P5E_PEX0_STN5_RX_DP<82>")
	)
	(segment
		(start 79.534766 -392.168634)
		(end 81.073752 -390.629648)
		(width 0.1651)
		(layer "In9.Cu")
		(net "P5E_PEX0_STN5_RX_DP<82>")
	)
	(segment
		(start 81.073752 -390.629648)
		(end 92.65285 -388.32663)
		(width 0.1651)
		(layer "In9.Cu")
		(net "P5E_PEX0_STN5_RX_DP<82>")
	)
	(segment
		(start 60.029598 -319.870328)
		(end 60.029598 -316.506098)
		(width 0.1143)
		(layer "In9.Cu")
		(net "P5E_PEX0_STN5_RX_DP<82>")
	)
	(segment
		(start 79.07655 -392.62685)
		(end 79.07655 -392.5189)
		(width 0.1651)
		(layer "In9.Cu")
		(net "P5E_PEX0_STN5_RX_DP<82>")
	)
	(segment
		(start 76.82611 -396.999206)
		(end 77.244702 -396.580614)
		(width 0.1651)
		(layer "In9.Cu")
		(net "P5E_PEX0_STN5_RX_DP<82>")
	)
	(segment
		(start 60.510928 -316.229492)
		(end 60.599828 -316.140592)
		(width 0.1143)
		(layer "In9.Cu")
		(net "P5E_PEX0_STN5_RX_DP<82>")
	)
	(segment
		(start 78.618842 -392.976862)
		(end 78.726538 -392.976862)
		(width 0.1651)
		(layer "In9.Cu")
		(net "P5E_PEX0_STN5_RX_DP<82>")
	)
	(segment
		(start 94.6404 -371.004338)
		(end 94.03969 -367.983262)
		(width 0.1651)
		(layer "In9.Cu")
		(net "P5E_PEX0_STN5_RX_DP<82>")
	)
	(segment
		(start 79.07655 -392.5189)
		(end 79.42707 -392.168634)
		(width 0.1651)
		(layer "In9.Cu")
		(net "P5E_PEX0_STN5_RX_DP<82>")
	)
	(segment
		(start 78.268322 -393.435078)
		(end 78.268322 -393.327382)
		(width 0.1651)
		(layer "In9.Cu")
		(net "P5E_PEX0_STN5_RX_DP<82>")
	)
	(segment
		(start 92.65285 -388.32663)
		(end 93.09862 -388.141972)
		(width 0.1651)
		(layer "In9.Cu")
		(net "P5E_PEX0_STN5_RX_DP<82>")
	)
	(segment
		(start 76.309982 -396.49019)
		(end 76.309982 -396.872206)
		(width 0.1651)
		(layer "In9.Cu")
		(net "P5E_PEX0_STN5_RX_DP<82>")
	)
	(segment
		(start 94.327726 -385.436872)
		(end 94.6404 -371.423184)
		(width 0.1651)
		(layer "In9.Cu")
		(net "P5E_PEX0_STN5_RX_DP<82>")
	)
	(segment
		(start 84.980272 -342.250014)
		(end 84.56676 -341.25154)
		(width 0.1651)
		(layer "In9.Cu")
		(net "P5E_PEX0_STN5_RX_DP<82>")
	)
	(segment
		(start 60.306204 -316.229492)
		(end 60.510928 -316.229492)
		(width 0.1143)
		(layer "In9.Cu")
		(net "P5E_PEX0_STN5_RX_DP<82>")
	)
	(segment
		(start 93.09862 -388.141972)
		(end 93.908372 -387.33222)
		(width 0.1651)
		(layer "In9.Cu")
		(net "P5E_PEX0_STN5_RX_DP<82>")
	)
	(segment
		(start 77.244702 -396.580614)
		(end 77.244702 -394.458698)
		(width 0.1651)
		(layer "In9.Cu")
		(net "P5E_PEX0_STN5_RX_DP<82>")
	)
	(segment
		(start 94.03969 -367.983262)
		(end 93.656912 -367.059464)
		(width 0.1651)
		(layer "In9.Cu")
		(net "P5E_PEX0_STN5_RX_DP<82>")
	)
	(segment
		(start 78.268322 -393.327382)
		(end 78.618842 -392.976862)
		(width 0.1651)
		(layer "In9.Cu")
		(net "P5E_PEX0_STN5_RX_DP<82>")
	)
	(segment
		(start 59.983878 -319.944496)
		(end 59.983878 -319.916048)
		(width 0.1143)
		(layer "In9.Cu")
		(net "P5E_PEX0_STN5_RX_DP<82>")
	)
	(segment
		(start 84.56676 -341.25154)
		(end 79.645764 -336.330544)
		(width 0.1651)
		(layer "In9.Cu")
		(net "P5E_PEX0_STN5_RX_DP<82>")
	)
	(segment
		(start 77.244702 -394.458698)
		(end 78.268322 -393.435078)
		(width 0.1651)
		(layer "In9.Cu")
		(net "P5E_PEX0_STN5_RX_DP<82>")
	)
	(segment
		(start 84.980272 -358.382824)
		(end 84.980272 -342.250014)
		(width 0.1651)
		(layer "In9.Cu")
		(net "P5E_PEX0_STN5_RX_DP<82>")
	)
	(segment
		(start 93.908372 -387.33222)
		(end 94.327726 -386.319776)
		(width 0.1651)
		(layer "In9.Cu")
		(net "P5E_PEX0_STN5_RX_DP<82>")
	)
	(segment
		(start 93.656912 -367.059464)
		(end 84.980272 -358.382824)
		(width 0.1651)
		(layer "In9.Cu")
		(net "P5E_PEX0_STN5_RX_DP<82>")
	)
	(segment
		(start 76.309982 -396.872206)
		(end 76.436982 -396.999206)
		(width 0.1651)
		(layer "In9.Cu")
		(net "P5E_PEX0_STN5_RX_DP<82>")
	)
	(segment
		(start 36.981384 -102.009702)
		(end 36.661344 -101.689662)
		(width 0.13462)
		(layer "F.Cu")
		(net "P5E_PEX0_STN1_TX_DP<17>")
	)
	(segment
		(start 36.0299 -101.689662)
		(end 35.73526 -101.984302)
		(width 0.13462)
		(layer "F.Cu")
		(net "P5E_PEX0_STN1_TX_DP<17>")
	)
	(segment
		(start 36.661344 -101.689662)
		(end 36.0299 -101.689662)
		(width 0.13462)
		(layer "F.Cu")
		(net "P5E_PEX0_STN1_TX_DP<17>")
	)
	(segment
		(start 33.88614 -102.44582)
		(end 34.384996 -101.946964)
		(width 0.1651)
		(layer "In9.Cu")
		(net "P5E_PEX0_STN1_TX_DP<17>")
	)
	(segment
		(start 34.384996 -101.946964)
		(end 34.996882 -101.693472)
		(width 0.1651)
		(layer "In9.Cu")
		(net "P5E_PEX0_STN1_TX_DP<17>")
	)
	(segment
		(start 60.32373 -280.129488)
		(end 60.220098 -280.025856)
		(width 0.1143)
		(layer "In9.Cu")
		(net "P5E_PEX0_STN1_TX_DP<17>")
	)
	(segment
		(start 28.552648 -108.930186)
		(end 28.742132 -108.472732)
		(width 0.1651)
		(layer "In9.Cu")
		(net "P5E_PEX0_STN1_TX_DP<17>")
	)
	(segment
		(start 31.416244 -104.915716)
		(end 31.766256 -104.565704)
		(width 0.1651)
		(layer "In9.Cu")
		(net "P5E_PEX0_STN1_TX_DP<17>")
	)
	(segment
		(start 31.766256 -104.565704)
		(end 31.91002 -104.565704)
		(width 0.1651)
		(layer "In9.Cu")
		(net "P5E_PEX0_STN1_TX_DP<17>")
	)
	(segment
		(start 28.742132 -108.472478)
		(end 28.874974 -108.417614)
		(width 0.1651)
		(layer "In9.Cu")
		(net "P5E_PEX0_STN1_TX_DP<17>")
	)
	(segment
		(start 28.417774 -109.520736)
		(end 28.607766 -109.063028)
		(width 0.1651)
		(layer "In9.Cu")
		(net "P5E_PEX0_STN1_TX_DP<17>")
	)
	(segment
		(start 30.92196 -105.41)
		(end 31.065724 -105.41)
		(width 0.1651)
		(layer "In9.Cu")
		(net "P5E_PEX0_STN1_TX_DP<17>")
	)
	(segment
		(start 31.91002 -104.565704)
		(end 32.26054 -104.215184)
		(width 0.1651)
		(layer "In9.Cu")
		(net "P5E_PEX0_STN1_TX_DP<17>")
	)
	(segment
		(start 29.366464 -106.965496)
		(end 30.077664 -106.254296)
		(width 0.1651)
		(layer "In9.Cu")
		(net "P5E_PEX0_STN1_TX_DP<17>")
	)
	(segment
		(start 30.571948 -105.903776)
		(end 30.571948 -105.760012)
		(width 0.1651)
		(layer "In9.Cu")
		(net "P5E_PEX0_STN1_TX_DP<17>")
	)
	(segment
		(start 60.599828 -280.015188)
		(end 60.485528 -280.129488)
		(width 0.1143)
		(layer "In9.Cu")
		(net "P5E_PEX0_STN1_TX_DP<17>")
	)
	(segment
		(start 33.077658 -103.254302)
		(end 33.41878 -102.91318)
		(width 0.1651)
		(layer "In9.Cu")
		(net "P5E_PEX0_STN1_TX_DP<17>")
	)
	(segment
		(start 29.064712 -107.959652)
		(end 29.009594 -107.827064)
		(width 0.1651)
		(layer "In9.Cu")
		(net "P5E_PEX0_STN1_TX_DP<17>")
	)
	(segment
		(start 24.755856 -159.643064)
		(end 24.039322 -145.063718)
		(width 0.1651)
		(layer "In9.Cu")
		(net "P5E_PEX0_STN1_TX_DP<17>")
	)
	(segment
		(start 60.485528 -280.129488)
		(end 60.32373 -280.129488)
		(width 0.1143)
		(layer "In9.Cu")
		(net "P5E_PEX0_STN1_TX_DP<17>")
	)
	(segment
		(start 30.221428 -106.254296)
		(end 30.571948 -105.903776)
		(width 0.1651)
		(layer "In9.Cu")
		(net "P5E_PEX0_STN1_TX_DP<17>")
	)
	(segment
		(start 33.54451 -102.91318)
		(end 33.88614 -102.57155)
		(width 0.1651)
		(layer "In9.Cu")
		(net "P5E_PEX0_STN1_TX_DP<17>")
	)
	(segment
		(start 27.82824 -110.678976)
		(end 27.960828 -110.623858)
		(width 0.1651)
		(layer "In9.Cu")
		(net "P5E_PEX0_STN1_TX_DP<17>")
	)
	(segment
		(start 32.26054 -104.07142)
		(end 32.610552 -103.721408)
		(width 0.1651)
		(layer "In9.Cu")
		(net "P5E_PEX0_STN1_TX_DP<17>")
	)
	(segment
		(start 27.638756 -111.13643)
		(end 27.82824 -110.678976)
		(width 0.1651)
		(layer "In9.Cu")
		(net "P5E_PEX0_STN1_TX_DP<17>")
	)
	(segment
		(start 60.599828 -279.749504)
		(end 60.599828 -280.015188)
		(width 0.1143)
		(layer "In9.Cu")
		(net "P5E_PEX0_STN1_TX_DP<17>")
	)
	(segment
		(start 28.095702 -110.033308)
		(end 28.285186 -109.575854)
		(width 0.1651)
		(layer "In9.Cu")
		(net "P5E_PEX0_STN1_TX_DP<17>")
	)
	(segment
		(start 28.742132 -108.472732)
		(end 28.742132 -108.472478)
		(width 0.1651)
		(layer "In9.Cu")
		(net "P5E_PEX0_STN1_TX_DP<17>")
	)
	(segment
		(start 60.265818 -265.72464)
		(end 25.320498 -162.482276)
		(width 0.1651)
		(layer "In9.Cu")
		(net "P5E_PEX0_STN1_TX_DP<17>")
	)
	(segment
		(start 32.26054 -104.215184)
		(end 32.26054 -104.07142)
		(width 0.1651)
		(layer "In9.Cu")
		(net "P5E_PEX0_STN1_TX_DP<17>")
	)
	(segment
		(start 32.736028 -103.721408)
		(end 33.077658 -103.380032)
		(width 0.1651)
		(layer "In9.Cu")
		(net "P5E_PEX0_STN1_TX_DP<17>")
	)
	(segment
		(start 32.610552 -103.721408)
		(end 32.736028 -103.721408)
		(width 0.1651)
		(layer "In9.Cu")
		(net "P5E_PEX0_STN1_TX_DP<17>")
	)
	(segment
		(start 24.039322 -145.063718)
		(end 21.454872 -138.823954)
		(width 0.1651)
		(layer "In9.Cu")
		(net "P5E_PEX0_STN1_TX_DP<17>")
	)
	(segment
		(start 33.88614 -102.57155)
		(end 33.88614 -102.44582)
		(width 0.1651)
		(layer "In9.Cu")
		(net "P5E_PEX0_STN1_TX_DP<17>")
	)
	(segment
		(start 25.320498 -162.482276)
		(end 24.755856 -159.643064)
		(width 0.1651)
		(layer "In9.Cu")
		(net "P5E_PEX0_STN1_TX_DP<17>")
	)
	(segment
		(start 21.454872 -138.823954)
		(end 21.454872 -130.86207)
		(width 0.1651)
		(layer "In9.Cu")
		(net "P5E_PEX0_STN1_TX_DP<17>")
	)
	(segment
		(start 28.285186 -109.575854)
		(end 28.417774 -109.520736)
		(width 0.1651)
		(layer "In9.Cu")
		(net "P5E_PEX0_STN1_TX_DP<17>")
	)
	(segment
		(start 29.009594 -107.827064)
		(end 29.366464 -106.965496)
		(width 0.1651)
		(layer "In9.Cu")
		(net "P5E_PEX0_STN1_TX_DP<17>")
	)
	(segment
		(start 60.220098 -271.600168)
		(end 60.265818 -271.554448)
		(width 0.1143)
		(layer "In9.Cu")
		(net "P5E_PEX0_STN1_TX_DP<17>")
	)
	(segment
		(start 60.265818 -271.554448)
		(end 60.265818 -271.526)
		(width 0.1143)
		(layer "In9.Cu")
		(net "P5E_PEX0_STN1_TX_DP<17>")
	)
	(segment
		(start 60.220098 -280.025856)
		(end 60.220098 -271.600168)
		(width 0.1143)
		(layer "In9.Cu")
		(net "P5E_PEX0_STN1_TX_DP<17>")
	)
	(segment
		(start 33.41878 -102.91318)
		(end 33.54451 -102.91318)
		(width 0.1651)
		(layer "In9.Cu")
		(net "P5E_PEX0_STN1_TX_DP<17>")
	)
	(segment
		(start 33.077658 -103.380032)
		(end 33.077658 -103.254302)
		(width 0.1651)
		(layer "In9.Cu")
		(net "P5E_PEX0_STN1_TX_DP<17>")
	)
	(segment
		(start 27.371294 -111.782098)
		(end 27.503882 -111.72698)
		(width 0.1651)
		(layer "In9.Cu")
		(net "P5E_PEX0_STN1_TX_DP<17>")
	)
	(segment
		(start 30.571948 -105.760012)
		(end 30.92196 -105.41)
		(width 0.1651)
		(layer "In9.Cu")
		(net "P5E_PEX0_STN1_TX_DP<17>")
	)
	(segment
		(start 21.454872 -130.86207)
		(end 26.891742 -112.93983)
		(width 0.1651)
		(layer "In9.Cu")
		(net "P5E_PEX0_STN1_TX_DP<17>")
	)
	(segment
		(start 27.960828 -110.623858)
		(end 28.15082 -110.16615)
		(width 0.1651)
		(layer "In9.Cu")
		(net "P5E_PEX0_STN1_TX_DP<17>")
	)
	(segment
		(start 35.44443 -101.693472)
		(end 35.73526 -101.984302)
		(width 0.1651)
		(layer "In9.Cu")
		(net "P5E_PEX0_STN1_TX_DP<17>")
	)
	(segment
		(start 26.891742 -112.93983)
		(end 27.371294 -111.782098)
		(width 0.1651)
		(layer "In9.Cu")
		(net "P5E_PEX0_STN1_TX_DP<17>")
	)
	(segment
		(start 28.15082 -110.16615)
		(end 28.095702 -110.033308)
		(width 0.1651)
		(layer "In9.Cu")
		(net "P5E_PEX0_STN1_TX_DP<17>")
	)
	(segment
		(start 30.077664 -106.254296)
		(end 30.221428 -106.254296)
		(width 0.1651)
		(layer "In9.Cu")
		(net "P5E_PEX0_STN1_TX_DP<17>")
	)
	(segment
		(start 60.265818 -271.526)
		(end 60.265818 -265.72464)
		(width 0.1651)
		(layer "In9.Cu")
		(net "P5E_PEX0_STN1_TX_DP<17>")
	)
	(segment
		(start 31.065724 -105.41)
		(end 31.416244 -105.05948)
		(width 0.1651)
		(layer "In9.Cu")
		(net "P5E_PEX0_STN1_TX_DP<17>")
	)
	(segment
		(start 27.693874 -111.269272)
		(end 27.638756 -111.13643)
		(width 0.1651)
		(layer "In9.Cu")
		(net "P5E_PEX0_STN1_TX_DP<17>")
	)
	(segment
		(start 34.996882 -101.693472)
		(end 35.44443 -101.693472)
		(width 0.1651)
		(layer "In9.Cu")
		(net "P5E_PEX0_STN1_TX_DP<17>")
	)
	(segment
		(start 31.416244 -105.05948)
		(end 31.416244 -104.915716)
		(width 0.1651)
		(layer "In9.Cu")
		(net "P5E_PEX0_STN1_TX_DP<17>")
	)
	(segment
		(start 28.874974 -108.417614)
		(end 29.064712 -107.959652)
		(width 0.1651)
		(layer "In9.Cu")
		(net "P5E_PEX0_STN1_TX_DP<17>")
	)
	(segment
		(start 27.503882 -111.72698)
		(end 27.693874 -111.269272)
		(width 0.1651)
		(layer "In9.Cu")
		(net "P5E_PEX0_STN1_TX_DP<17>")
	)
	(segment
		(start 28.607766 -109.063028)
		(end 28.552648 -108.930186)
		(width 0.1651)
		(layer "In9.Cu")
		(net "P5E_PEX0_STN1_TX_DP<17>")
	)
	(segment
		(start 92.717366 -387.57098)
		(end 93.320108 -386.968238)
		(width 0.1651)
		(layer "In9.Cu")
		(net "P5E_PEX0_STN5_RX_DN<81>")
	)
	(segment
		(start 59.315858 -319.916048)
		(end 59.270138 -319.870328)
		(width 0.1143)
		(layer "In9.Cu")
		(net "P5E_PEX0_STN5_RX_DN<81>")
	)
	(segment
		(start 59.315858 -319.944496)
		(end 59.315858 -319.916048)
		(width 0.1143)
		(layer "In9.Cu")
		(net "P5E_PEX0_STN5_RX_DN<81>")
	)
	(segment
		(start 59.270138 -318.485266)
		(end 59.435238 -318.320166)
		(width 0.1143)
		(layer "In9.Cu")
		(net "P5E_PEX0_STN5_RX_DN<81>")
	)
	(segment
		(start 74.236834 -398.380966)
		(end 74.69378 -398.380966)
		(width 0.1651)
		(layer "In9.Cu")
		(net "P5E_PEX0_STN5_RX_DN<81>")
	)
	(segment
		(start 74.365866 -333.674466)
		(end 63.197486 -326.211946)
		(width 0.1651)
		(layer "In9.Cu")
		(net "P5E_PEX0_STN5_RX_DN<81>")
	)
	(segment
		(start 93.618812 -386.247132)
		(end 93.618812 -385.429506)
		(width 0.1651)
		(layer "In9.Cu")
		(net "P5E_PEX0_STN5_RX_DN<81>")
	)
	(segment
		(start 59.435238 -318.320166)
		(end 59.560968 -318.320166)
		(width 0.1143)
		(layer "In9.Cu")
		(net "P5E_PEX0_STN5_RX_DN<81>")
	)
	(segment
		(start 74.109834 -398.507966)
		(end 74.236834 -398.380966)
		(width 0.1651)
		(layer "In9.Cu")
		(net "P5E_PEX0_STN5_RX_DN<81>")
	)
	(segment
		(start 93.93174 -370.891816)
		(end 93.396562 -368.200432)
		(width 0.1651)
		(layer "In9.Cu")
		(net "P5E_PEX0_STN5_RX_DN<81>")
	)
	(segment
		(start 59.649868 -318.409066)
		(end 59.649868 -318.699896)
		(width 0.1143)
		(layer "In9.Cu")
		(net "P5E_PEX0_STN5_RX_DN<81>")
	)
	(segment
		(start 93.320108 -386.968238)
		(end 93.618812 -386.247132)
		(width 0.1651)
		(layer "In9.Cu")
		(net "P5E_PEX0_STN5_RX_DN<81>")
	)
	(segment
		(start 82.153252 -342.006174)
		(end 81.768188 -341.076788)
		(width 0.1651)
		(layer "In9.Cu")
		(net "P5E_PEX0_STN5_RX_DN<81>")
	)
	(segment
		(start 79.92364 -390.17194)
		(end 92.456508 -387.679184)
		(width 0.1651)
		(layer "In9.Cu")
		(net "P5E_PEX0_STN5_RX_DN<81>")
	)
	(segment
		(start 82.450178 -358.598978)
		(end 82.153252 -357.88219)
		(width 0.1651)
		(layer "In9.Cu")
		(net "P5E_PEX0_STN5_RX_DN<81>")
	)
	(segment
		(start 93.079062 -367.433606)
		(end 91.946222 -366.300766)
		(width 0.1651)
		(layer "In9.Cu")
		(net "P5E_PEX0_STN5_RX_DN<81>")
	)
	(segment
		(start 92.456508 -387.679184)
		(end 92.717366 -387.57098)
		(width 0.1651)
		(layer "In9.Cu")
		(net "P5E_PEX0_STN5_RX_DN<81>")
	)
	(segment
		(start 75.28433 -394.81125)
		(end 79.92364 -390.17194)
		(width 0.1651)
		(layer "In9.Cu")
		(net "P5E_PEX0_STN5_RX_DN<81>")
	)
	(segment
		(start 93.618812 -385.429506)
		(end 93.93174 -371.399308)
		(width 0.1651)
		(layer "In9.Cu")
		(net "P5E_PEX0_STN5_RX_DN<81>")
	)
	(segment
		(start 82.153252 -357.88219)
		(end 82.153252 -342.006174)
		(width 0.1651)
		(layer "In9.Cu")
		(net "P5E_PEX0_STN5_RX_DN<81>")
	)
	(segment
		(start 93.396562 -368.200432)
		(end 93.079062 -367.433606)
		(width 0.1651)
		(layer "In9.Cu")
		(net "P5E_PEX0_STN5_RX_DN<81>")
	)
	(segment
		(start 59.560968 -318.320166)
		(end 59.649868 -318.409066)
		(width 0.1143)
		(layer "In9.Cu")
		(net "P5E_PEX0_STN5_RX_DN<81>")
	)
	(segment
		(start 74.109834 -398.890236)
		(end 74.109834 -398.507966)
		(width 0.1651)
		(layer "In9.Cu")
		(net "P5E_PEX0_STN5_RX_DN<81>")
	)
	(segment
		(start 59.270138 -319.870328)
		(end 59.270138 -318.485266)
		(width 0.1143)
		(layer "In9.Cu")
		(net "P5E_PEX0_STN5_RX_DN<81>")
	)
	(segment
		(start 75.28433 -397.790416)
		(end 75.28433 -394.81125)
		(width 0.1651)
		(layer "In9.Cu")
		(net "P5E_PEX0_STN5_RX_DN<81>")
	)
	(segment
		(start 91.946222 -366.300766)
		(end 89.90584 -364.937294)
		(width 0.1651)
		(layer "In9.Cu")
		(net "P5E_PEX0_STN5_RX_DN<81>")
	)
	(segment
		(start 74.69378 -398.380966)
		(end 75.28433 -397.790416)
		(width 0.1651)
		(layer "In9.Cu")
		(net "P5E_PEX0_STN5_RX_DN<81>")
	)
	(segment
		(start 83.675728 -359.824528)
		(end 82.450178 -358.598978)
		(width 0.1651)
		(layer "In9.Cu")
		(net "P5E_PEX0_STN5_RX_DN<81>")
	)
	(segment
		(start 60.064396 -323.078856)
		(end 59.315858 -321.2719)
		(width 0.1651)
		(layer "In9.Cu")
		(net "P5E_PEX0_STN5_RX_DN<81>")
	)
	(segment
		(start 59.315858 -321.2719)
		(end 59.315858 -319.944496)
		(width 0.1651)
		(layer "In9.Cu")
		(net "P5E_PEX0_STN5_RX_DN<81>")
	)
	(segment
		(start 93.93174 -371.399308)
		(end 93.93174 -370.891816)
		(width 0.1651)
		(layer "In9.Cu")
		(net "P5E_PEX0_STN5_RX_DN<81>")
	)
	(segment
		(start 63.197486 -326.211946)
		(end 60.064396 -323.078856)
		(width 0.1651)
		(layer "In9.Cu")
		(net "P5E_PEX0_STN5_RX_DN<81>")
	)
	(segment
		(start 89.90584 -364.937294)
		(end 83.675728 -359.824528)
		(width 0.1651)
		(layer "In9.Cu")
		(net "P5E_PEX0_STN5_RX_DN<81>")
	)
	(segment
		(start 81.768188 -341.076788)
		(end 74.365866 -333.674466)
		(width 0.1651)
		(layer "In9.Cu")
		(net "P5E_PEX0_STN5_RX_DN<81>")
	)
	(segment
		(start 38.062408 -132.809742)
		(end 37.767768 -133.104382)
		(width 0.13462)
		(layer "F.Cu")
		(net "P5E_PEX0_STN1_TX_DP<29>")
	)
	(segment
		(start 39.013892 -133.129782)
		(end 38.693852 -132.809742)
		(width 0.13462)
		(layer "F.Cu")
		(net "P5E_PEX0_STN1_TX_DP<29>")
	)
	(segment
		(start 38.693852 -132.809742)
		(end 38.062408 -132.809742)
		(width 0.13462)
		(layer "F.Cu")
		(net "P5E_PEX0_STN1_TX_DP<29>")
	)
	(segment
		(start 33.05556 -135.473694)
		(end 33.05556 -134.799578)
		(width 0.1651)
		(layer "In9.Cu")
		(net "P5E_PEX0_STN1_TX_DP<29>")
	)
	(segment
		(start 71.665846 -271.554448)
		(end 71.665846 -271.526)
		(width 0.1143)
		(layer "In9.Cu")
		(net "P5E_PEX0_STN1_TX_DP<29>")
	)
	(segment
		(start 37.476938 -132.813552)
		(end 37.767768 -133.104382)
		(width 0.1651)
		(layer "In9.Cu")
		(net "P5E_PEX0_STN1_TX_DP<29>")
	)
	(segment
		(start 71.885556 -280.129488)
		(end 71.723758 -280.129488)
		(width 0.1143)
		(layer "In9.Cu")
		(net "P5E_PEX0_STN1_TX_DP<29>")
	)
	(segment
		(start 71.723758 -280.129488)
		(end 71.620126 -280.025856)
		(width 0.1143)
		(layer "In9.Cu")
		(net "P5E_PEX0_STN1_TX_DP<29>")
	)
	(segment
		(start 35.903154 -144.530064)
		(end 35.783012 -144.421606)
		(width 0.1651)
		(layer "In9.Cu")
		(net "P5E_PEX0_STN1_TX_DP<29>")
	)
	(segment
		(start 36.10737 -148.678646)
		(end 36.082986 -148.183854)
		(width 0.1651)
		(layer "In9.Cu")
		(net "P5E_PEX0_STN1_TX_DP<29>")
	)
	(segment
		(start 35.757612 -143.900652)
		(end 35.866324 -143.781018)
		(width 0.1651)
		(layer "In9.Cu")
		(net "P5E_PEX0_STN1_TX_DP<29>")
	)
	(segment
		(start 35.96386 -132.927852)
		(end 36.44646 -132.927852)
		(width 0.1651)
		(layer "In9.Cu")
		(net "P5E_PEX0_STN1_TX_DP<29>")
	)
	(segment
		(start 37.488622 -162.20821)
		(end 36.385246 -156.661866)
		(width 0.1651)
		(layer "In9.Cu")
		(net "P5E_PEX0_STN1_TX_DP<29>")
	)
	(segment
		(start 35.963098 -145.74774)
		(end 35.842956 -145.639282)
		(width 0.1651)
		(layer "In9.Cu")
		(net "P5E_PEX0_STN1_TX_DP<29>")
	)
	(segment
		(start 36.385246 -156.661866)
		(end 35.998658 -148.798534)
		(width 0.1651)
		(layer "In9.Cu")
		(net "P5E_PEX0_STN1_TX_DP<29>")
	)
	(segment
		(start 35.962844 -148.075142)
		(end 35.938714 -147.580604)
		(width 0.1651)
		(layer "In9.Cu")
		(net "P5E_PEX0_STN1_TX_DP<29>")
	)
	(segment
		(start 35.651186 -141.738604)
		(end 35.017456 -140.208508)
		(width 0.1651)
		(layer "In9.Cu")
		(net "P5E_PEX0_STN1_TX_DP<29>")
	)
	(segment
		(start 34.550604 -139.082018)
		(end 34.612326 -138.932666)
		(width 0.1651)
		(layer "In9.Cu")
		(net "P5E_PEX0_STN1_TX_DP<29>")
	)
	(segment
		(start 71.665846 -271.526)
		(end 71.665846 -263.170924)
		(width 0.1651)
		(layer "In9.Cu")
		(net "P5E_PEX0_STN1_TX_DP<29>")
	)
	(segment
		(start 34.889694 -139.601448)
		(end 34.740088 -139.539472)
		(width 0.1651)
		(layer "In9.Cu")
		(net "P5E_PEX0_STN1_TX_DP<29>")
	)
	(segment
		(start 35.87877 -146.362674)
		(end 35.987482 -146.242786)
		(width 0.1651)
		(layer "In9.Cu")
		(net "P5E_PEX0_STN1_TX_DP<29>")
	)
	(segment
		(start 71.999856 -280.015188)
		(end 71.885556 -280.129488)
		(width 0.1143)
		(layer "In9.Cu")
		(net "P5E_PEX0_STN1_TX_DP<29>")
	)
	(segment
		(start 35.84956 -132.813552)
		(end 35.96386 -132.927852)
		(width 0.1651)
		(layer "In9.Cu")
		(net "P5E_PEX0_STN1_TX_DP<29>")
	)
	(segment
		(start 34.422842 -138.474704)
		(end 34.273236 -138.412982)
		(width 0.1651)
		(layer "In9.Cu")
		(net "P5E_PEX0_STN1_TX_DP<29>")
	)
	(segment
		(start 71.999856 -279.749504)
		(end 71.999856 -280.015188)
		(width 0.1143)
		(layer "In9.Cu")
		(net "P5E_PEX0_STN1_TX_DP<29>")
	)
	(segment
		(start 35.783012 -144.421606)
		(end 35.757612 -143.900652)
		(width 0.1651)
		(layer "In9.Cu")
		(net "P5E_PEX0_STN1_TX_DP<29>")
	)
	(segment
		(start 36.047426 -147.460716)
		(end 36.023042 -146.965924)
		(width 0.1651)
		(layer "In9.Cu")
		(net "P5E_PEX0_STN1_TX_DP<29>")
	)
	(segment
		(start 35.866324 -143.781018)
		(end 35.84194 -143.285972)
		(width 0.1651)
		(layer "In9.Cu")
		(net "P5E_PEX0_STN1_TX_DP<29>")
	)
	(segment
		(start 35.84194 -143.285972)
		(end 35.721798 -143.177514)
		(width 0.1651)
		(layer "In9.Cu")
		(net "P5E_PEX0_STN1_TX_DP<29>")
	)
	(segment
		(start 36.44646 -132.927852)
		(end 36.56076 -132.813552)
		(width 0.1651)
		(layer "In9.Cu")
		(net "P5E_PEX0_STN1_TX_DP<29>")
	)
	(segment
		(start 35.927538 -145.02511)
		(end 35.903154 -144.530064)
		(width 0.1651)
		(layer "In9.Cu")
		(net "P5E_PEX0_STN1_TX_DP<29>")
	)
	(segment
		(start 35.721798 -143.177514)
		(end 35.651186 -141.738604)
		(width 0.1651)
		(layer "In9.Cu")
		(net "P5E_PEX0_STN1_TX_DP<29>")
	)
	(segment
		(start 35.017456 -140.208508)
		(end 35.079178 -140.059156)
		(width 0.1651)
		(layer "In9.Cu")
		(net "P5E_PEX0_STN1_TX_DP<29>")
	)
	(segment
		(start 35.842956 -145.639282)
		(end 35.818826 -145.144744)
		(width 0.1651)
		(layer "In9.Cu")
		(net "P5E_PEX0_STN1_TX_DP<29>")
	)
	(segment
		(start 33.05556 -134.799578)
		(end 33.27781 -134.26313)
		(width 0.1651)
		(layer "In9.Cu")
		(net "P5E_PEX0_STN1_TX_DP<29>")
	)
	(segment
		(start 34.329878 -133.211062)
		(end 35.28949 -132.813552)
		(width 0.1651)
		(layer "In9.Cu")
		(net "P5E_PEX0_STN1_TX_DP<29>")
	)
	(segment
		(start 34.740088 -139.539472)
		(end 34.550604 -139.082018)
		(width 0.1651)
		(layer "In9.Cu")
		(net "P5E_PEX0_STN1_TX_DP<29>")
	)
	(segment
		(start 35.998658 -148.798534)
		(end 36.10737 -148.678646)
		(width 0.1651)
		(layer "In9.Cu")
		(net "P5E_PEX0_STN1_TX_DP<29>")
	)
	(segment
		(start 71.620126 -271.600168)
		(end 71.665846 -271.554448)
		(width 0.1143)
		(layer "In9.Cu")
		(net "P5E_PEX0_STN1_TX_DP<29>")
	)
	(segment
		(start 33.27781 -134.26313)
		(end 34.329878 -133.211062)
		(width 0.1651)
		(layer "In9.Cu")
		(net "P5E_PEX0_STN1_TX_DP<29>")
	)
	(segment
		(start 71.620126 -280.025856)
		(end 71.620126 -271.600168)
		(width 0.1143)
		(layer "In9.Cu")
		(net "P5E_PEX0_STN1_TX_DP<29>")
	)
	(segment
		(start 36.56076 -132.813552)
		(end 37.476938 -132.813552)
		(width 0.1651)
		(layer "In9.Cu")
		(net "P5E_PEX0_STN1_TX_DP<29>")
	)
	(segment
		(start 71.665846 -263.170924)
		(end 37.488622 -162.20821)
		(width 0.1651)
		(layer "In9.Cu")
		(net "P5E_PEX0_STN1_TX_DP<29>")
	)
	(segment
		(start 35.079178 -140.059156)
		(end 34.889694 -139.601448)
		(width 0.1651)
		(layer "In9.Cu")
		(net "P5E_PEX0_STN1_TX_DP<29>")
	)
	(segment
		(start 34.612326 -138.932666)
		(end 34.422842 -138.474704)
		(width 0.1651)
		(layer "In9.Cu")
		(net "P5E_PEX0_STN1_TX_DP<29>")
	)
	(segment
		(start 36.023042 -146.965924)
		(end 35.9029 -146.857212)
		(width 0.1651)
		(layer "In9.Cu")
		(net "P5E_PEX0_STN1_TX_DP<29>")
	)
	(segment
		(start 35.9029 -146.857212)
		(end 35.87877 -146.362674)
		(width 0.1651)
		(layer "In9.Cu")
		(net "P5E_PEX0_STN1_TX_DP<29>")
	)
	(segment
		(start 35.938714 -147.580604)
		(end 36.047426 -147.460716)
		(width 0.1651)
		(layer "In9.Cu")
		(net "P5E_PEX0_STN1_TX_DP<29>")
	)
	(segment
		(start 35.818826 -145.144744)
		(end 35.927538 -145.02511)
		(width 0.1651)
		(layer "In9.Cu")
		(net "P5E_PEX0_STN1_TX_DP<29>")
	)
	(segment
		(start 35.987482 -146.242786)
		(end 35.963098 -145.74774)
		(width 0.1651)
		(layer "In9.Cu")
		(net "P5E_PEX0_STN1_TX_DP<29>")
	)
	(segment
		(start 34.273236 -138.412982)
		(end 33.05556 -135.473694)
		(width 0.1651)
		(layer "In9.Cu")
		(net "P5E_PEX0_STN1_TX_DP<29>")
	)
	(segment
		(start 36.082986 -148.183854)
		(end 35.962844 -148.075142)
		(width 0.1651)
		(layer "In9.Cu")
		(net "P5E_PEX0_STN1_TX_DP<29>")
	)
	(segment
		(start 35.28949 -132.813552)
		(end 35.84956 -132.813552)
		(width 0.1651)
		(layer "In9.Cu")
		(net "P5E_PEX0_STN1_TX_DP<29>")
	)
	(segment
		(start 27.19451 -312.377074)
		(end 27.462734 -311.975754)
		(width 0.1651)
		(layer "In5.Cu")
		(net "P5E_PEX0_STN7_RX_DN<117>")
	)
	(segment
		(start 27.039316 -312.408062)
		(end 27.19451 -312.377074)
		(width 0.1651)
		(layer "In5.Cu")
		(net "P5E_PEX0_STN7_RX_DN<117>")
	)
	(segment
		(start 29.435044 -309.502556)
		(end 29.435044 -309.356252)
		(width 0.1651)
		(layer "In5.Cu")
		(net "P5E_PEX0_STN7_RX_DN<117>")
	)
	(segment
		(start 21.459698 -341.89162)
		(end 22.15388 -334.844136)
		(width 0.1651)
		(layer "In5.Cu")
		(net "P5E_PEX0_STN7_RX_DN<117>")
	)
	(segment
		(start 29.08173 -309.85587)
		(end 29.435044 -309.502556)
		(width 0.1651)
		(layer "In5.Cu")
		(net "P5E_PEX0_STN7_RX_DN<117>")
	)
	(segment
		(start 26.549604 -387.128004)
		(end 25.660858 -386.239258)
		(width 0.1651)
		(layer "In5.Cu")
		(net "P5E_PEX0_STN7_RX_DN<117>")
	)
	(segment
		(start 22.384766 -367.17097)
		(end 21.459698 -357.778304)
		(width 0.1651)
		(layer "In5.Cu")
		(net "P5E_PEX0_STN7_RX_DN<117>")
	)
	(segment
		(start 31.293054 -307.65623)
		(end 31.63443 -307.314854)
		(width 0.1651)
		(layer "In5.Cu")
		(net "P5E_PEX0_STN7_RX_DN<117>")
	)
	(segment
		(start 38.910006 -410.207968)
		(end 39.037006 -410.080968)
		(width 0.1651)
		(layer "In5.Cu")
		(net "P5E_PEX0_STN7_RX_DN<117>")
	)
	(segment
		(start 27.462734 -311.975754)
		(end 27.432 -311.82056)
		(width 0.1651)
		(layer "In5.Cu")
		(net "P5E_PEX0_STN7_RX_DN<117>")
	)
	(segment
		(start 40.059102 -396.5956)
		(end 39.533322 -395.326362)
		(width 0.1651)
		(layer "In5.Cu")
		(net "P5E_PEX0_STN7_RX_DN<117>")
	)
	(segment
		(start 35.56 -306.015898)
		(end 35.588448 -306.015898)
		(width 0.1143)
		(layer "In5.Cu")
		(net "P5E_PEX0_STN7_RX_DN<117>")
	)
	(segment
		(start 37.229542 -306.084478)
		(end 37.229542 -306.235608)
		(width 0.1143)
		(layer "In5.Cu")
		(net "P5E_PEX0_STN7_RX_DN<117>")
	)
	(segment
		(start 28.935426 -309.85587)
		(end 29.08173 -309.85587)
		(width 0.1651)
		(layer "In5.Cu")
		(net "P5E_PEX0_STN7_RX_DN<117>")
	)
	(segment
		(start 37.229542 -306.235608)
		(end 37.115242 -306.349908)
		(width 0.1143)
		(layer "In5.Cu")
		(net "P5E_PEX0_STN7_RX_DN<117>")
	)
	(segment
		(start 32.018986 -306.77231)
		(end 33.187386 -306.28844)
		(width 0.1651)
		(layer "In5.Cu")
		(net "P5E_PEX0_STN7_RX_DN<117>")
	)
	(segment
		(start 31.135066 -307.65623)
		(end 31.293054 -307.65623)
		(width 0.1651)
		(layer "In5.Cu")
		(net "P5E_PEX0_STN7_RX_DN<117>")
	)
	(segment
		(start 27.69997 -311.419494)
		(end 27.69997 -311.41924)
		(width 0.1651)
		(layer "In5.Cu")
		(net "P5E_PEX0_STN7_RX_DN<117>")
	)
	(segment
		(start 28.092654 -310.831738)
		(end 28.360624 -310.430672)
		(width 0.1651)
		(layer "In5.Cu")
		(net "P5E_PEX0_STN7_RX_DN<117>")
	)
	(segment
		(start 24.963628 -384.556)
		(end 22.384766 -367.17097)
		(width 0.1651)
		(layer "In5.Cu")
		(net "P5E_PEX0_STN7_RX_DN<117>")
	)
	(segment
		(start 39.037006 -410.080968)
		(end 39.535862 -410.080968)
		(width 0.1651)
		(layer "In5.Cu")
		(net "P5E_PEX0_STN7_RX_DN<117>")
	)
	(segment
		(start 38.910006 -410.589984)
		(end 38.910006 -410.207968)
		(width 0.1651)
		(layer "In5.Cu")
		(net "P5E_PEX0_STN7_RX_DN<117>")
	)
	(segment
		(start 35.357562 -391.835894)
		(end 26.549604 -387.128004)
		(width 0.1651)
		(layer "In5.Cu")
		(net "P5E_PEX0_STN7_RX_DN<117>")
	)
	(segment
		(start 27.855164 -311.388252)
		(end 28.123388 -310.986932)
		(width 0.1651)
		(layer "In5.Cu")
		(net "P5E_PEX0_STN7_RX_DN<117>")
	)
	(segment
		(start 29.435044 -309.356252)
		(end 29.776166 -309.01513)
		(width 0.1651)
		(layer "In5.Cu")
		(net "P5E_PEX0_STN7_RX_DN<117>")
	)
	(segment
		(start 30.27553 -308.515766)
		(end 31.135066 -307.65623)
		(width 0.1651)
		(layer "In5.Cu")
		(net "P5E_PEX0_STN7_RX_DN<117>")
	)
	(segment
		(start 23.959312 -317.0174)
		(end 27.039316 -312.408062)
		(width 0.1651)
		(layer "In5.Cu")
		(net "P5E_PEX0_STN7_RX_DN<117>")
	)
	(segment
		(start 28.123388 -310.986932)
		(end 28.092654 -310.831738)
		(width 0.1651)
		(layer "In5.Cu")
		(net "P5E_PEX0_STN7_RX_DN<117>")
	)
	(segment
		(start 25.660858 -386.239258)
		(end 24.963628 -384.556)
		(width 0.1651)
		(layer "In5.Cu")
		(net "P5E_PEX0_STN7_RX_DN<117>")
	)
	(segment
		(start 29.97327 -309.01513)
		(end 30.27553 -308.71287)
		(width 0.1651)
		(layer "In5.Cu")
		(net "P5E_PEX0_STN7_RX_DN<117>")
	)
	(segment
		(start 37.423598 -393.216638)
		(end 35.357562 -391.835894)
		(width 0.1651)
		(layer "In5.Cu")
		(net "P5E_PEX0_STN7_RX_DN<117>")
	)
	(segment
		(start 31.63443 -307.156866)
		(end 32.018986 -306.77231)
		(width 0.1651)
		(layer "In5.Cu")
		(net "P5E_PEX0_STN7_RX_DN<117>")
	)
	(segment
		(start 40.059102 -409.557728)
		(end 40.059102 -396.5956)
		(width 0.1651)
		(layer "In5.Cu")
		(net "P5E_PEX0_STN7_RX_DN<117>")
	)
	(segment
		(start 22.15388 -334.844136)
		(end 22.90445 -319.564004)
		(width 0.1651)
		(layer "In5.Cu")
		(net "P5E_PEX0_STN7_RX_DN<117>")
	)
	(segment
		(start 22.90445 -319.564004)
		(end 23.959312 -317.0174)
		(width 0.1651)
		(layer "In5.Cu")
		(net "P5E_PEX0_STN7_RX_DN<117>")
	)
	(segment
		(start 35.634168 -305.970178)
		(end 37.115242 -305.970178)
		(width 0.1143)
		(layer "In5.Cu")
		(net "P5E_PEX0_STN7_RX_DN<117>")
	)
	(segment
		(start 27.432 -311.82056)
		(end 27.69997 -311.419494)
		(width 0.1651)
		(layer "In5.Cu")
		(net "P5E_PEX0_STN7_RX_DN<117>")
	)
	(segment
		(start 39.535862 -410.080968)
		(end 40.059102 -409.557728)
		(width 0.1651)
		(layer "In5.Cu")
		(net "P5E_PEX0_STN7_RX_DN<117>")
	)
	(segment
		(start 27.69997 -311.41924)
		(end 27.855164 -311.388252)
		(width 0.1651)
		(layer "In5.Cu")
		(net "P5E_PEX0_STN7_RX_DN<117>")
	)
	(segment
		(start 34.555938 -306.015898)
		(end 35.56 -306.015898)
		(width 0.1651)
		(layer "In5.Cu")
		(net "P5E_PEX0_STN7_RX_DN<117>")
	)
	(segment
		(start 30.27553 -308.71287)
		(end 30.27553 -308.515766)
		(width 0.1651)
		(layer "In5.Cu")
		(net "P5E_PEX0_STN7_RX_DN<117>")
	)
	(segment
		(start 29.776166 -309.01513)
		(end 29.97327 -309.01513)
		(width 0.1651)
		(layer "In5.Cu")
		(net "P5E_PEX0_STN7_RX_DN<117>")
	)
	(segment
		(start 28.360624 -310.430672)
		(end 28.935426 -309.85587)
		(width 0.1651)
		(layer "In5.Cu")
		(net "P5E_PEX0_STN7_RX_DN<117>")
	)
	(segment
		(start 37.115242 -306.349908)
		(end 36.849812 -306.349908)
		(width 0.1143)
		(layer "In5.Cu")
		(net "P5E_PEX0_STN7_RX_DN<117>")
	)
	(segment
		(start 31.63443 -307.314854)
		(end 31.63443 -307.156866)
		(width 0.1651)
		(layer "In5.Cu")
		(net "P5E_PEX0_STN7_RX_DN<117>")
	)
	(segment
		(start 33.187386 -306.28844)
		(end 34.555938 -306.015898)
		(width 0.1651)
		(layer "In5.Cu")
		(net "P5E_PEX0_STN7_RX_DN<117>")
	)
	(segment
		(start 21.459698 -357.778304)
		(end 21.459698 -341.89162)
		(width 0.1651)
		(layer "In5.Cu")
		(net "P5E_PEX0_STN7_RX_DN<117>")
	)
	(segment
		(start 35.588448 -306.015898)
		(end 35.634168 -305.970178)
		(width 0.1143)
		(layer "In5.Cu")
		(net "P5E_PEX0_STN7_RX_DN<117>")
	)
	(segment
		(start 39.533322 -395.326362)
		(end 37.423598 -393.216638)
		(width 0.1651)
		(layer "In5.Cu")
		(net "P5E_PEX0_STN7_RX_DN<117>")
	)
	(segment
		(start 37.115242 -305.970178)
		(end 37.229542 -306.084478)
		(width 0.1143)
		(layer "In5.Cu")
		(net "P5E_PEX0_STN7_RX_DN<117>")
	)
	(segment
		(start 80.286098 -119.584724)
		(end 80.606138 -119.264684)
		(width 0.13462)
		(layer "F.Cu")
		(net "P5E_PEX0_STN0_TX_DP<0>")
	)
	(segment
		(start 80.606138 -119.264684)
		(end 81.237582 -119.264684)
		(width 0.13462)
		(layer "F.Cu")
		(net "P5E_PEX0_STN0_TX_DP<0>")
	)
	(segment
		(start 81.237582 -119.264684)
		(end 81.532222 -119.559324)
		(width 0.13462)
		(layer "F.Cu")
		(net "P5E_PEX0_STN0_TX_DP<0>")
	)
	(segment
		(start 83.577176 -119.370094)
		(end 83.678776 -119.268494)
		(width 0.1651)
		(layer "In9.Cu")
		(net "P5E_PEX0_STN0_TX_DP<0>")
	)
	(segment
		(start 83.889088 -287.683956)
		(end 83.843368 -287.729676)
		(width 0.1143)
		(layer "In9.Cu")
		(net "P5E_PEX0_STN0_TX_DP<0>")
	)
	(segment
		(start 98.73742 -276.752812)
		(end 89.237058 -286.253174)
		(width 0.1651)
		(layer "In9.Cu")
		(net "P5E_PEX0_STN0_TX_DP<0>")
	)
	(segment
		(start 77.12964 -288.185606)
		(end 77.01534 -288.299906)
		(width 0.1143)
		(layer "In9.Cu")
		(net "P5E_PEX0_STN0_TX_DP<0>")
	)
	(segment
		(start 81.823052 -119.268494)
		(end 83.018376 -119.268494)
		(width 0.1651)
		(layer "In9.Cu")
		(net "P5E_PEX0_STN0_TX_DP<0>")
	)
	(segment
		(start 89.113614 -126.658878)
		(end 89.246456 -126.713996)
		(width 0.1651)
		(layer "In9.Cu")
		(net "P5E_PEX0_STN0_TX_DP<0>")
	)
	(segment
		(start 87.989156 -123.943872)
		(end 88.164162 -124.366528)
		(width 0.1651)
		(layer "In9.Cu")
		(net "P5E_PEX0_STN0_TX_DP<0>")
	)
	(segment
		(start 89.237058 -286.253174)
		(end 85.782658 -287.683956)
		(width 0.1651)
		(layer "In9.Cu")
		(net "P5E_PEX0_STN0_TX_DP<0>")
	)
	(segment
		(start 83.917536 -287.683956)
		(end 83.889088 -287.683956)
		(width 0.1143)
		(layer "In9.Cu")
		(net "P5E_PEX0_STN0_TX_DP<0>")
	)
	(segment
		(start 98.599498 -264.044684)
		(end 99.944682 -267.29182)
		(width 0.1651)
		(layer "In9.Cu")
		(net "P5E_PEX0_STN0_TX_DP<0>")
	)
	(segment
		(start 88.803734 -249.385836)
		(end 98.599498 -264.044684)
		(width 0.1651)
		(layer "In9.Cu")
		(net "P5E_PEX0_STN0_TX_DP<0>")
	)
	(segment
		(start 89.246456 -126.713996)
		(end 90.992452 -130.928872)
		(width 0.1651)
		(layer "In9.Cu")
		(net "P5E_PEX0_STN0_TX_DP<0>")
	)
	(segment
		(start 87.869268 -123.388882)
		(end 88.04402 -123.811284)
		(width 0.1651)
		(layer "In9.Cu")
		(net "P5E_PEX0_STN0_TX_DP<0>")
	)
	(segment
		(start 90.986864 -176.023778)
		(end 90.121994 -179.192428)
		(width 0.1651)
		(layer "In9.Cu")
		(net "P5E_PEX0_STN0_TX_DP<0>")
	)
	(segment
		(start 83.843368 -287.729676)
		(end 77.344778 -287.729676)
		(width 0.1143)
		(layer "In9.Cu")
		(net "P5E_PEX0_STN0_TX_DP<0>")
	)
	(segment
		(start 85.880194 -120.433592)
		(end 85.908388 -120.574562)
		(width 0.1651)
		(layer "In9.Cu")
		(net "P5E_PEX0_STN0_TX_DP<0>")
	)
	(segment
		(start 87.736426 -123.333764)
		(end 87.869268 -123.388882)
		(width 0.1651)
		(layer "In9.Cu")
		(net "P5E_PEX0_STN0_TX_DP<0>")
	)
	(segment
		(start 86.395306 -221.785942)
		(end 88.803734 -249.385836)
		(width 0.1651)
		(layer "In9.Cu")
		(net "P5E_PEX0_STN0_TX_DP<0>")
	)
	(segment
		(start 87.616284 -122.77852)
		(end 87.56142 -122.911108)
		(width 0.1651)
		(layer "In9.Cu")
		(net "P5E_PEX0_STN0_TX_DP<0>")
	)
	(segment
		(start 83.018376 -119.268494)
		(end 83.119976 -119.370094)
		(width 0.1651)
		(layer "In9.Cu")
		(net "P5E_PEX0_STN0_TX_DP<0>")
	)
	(segment
		(start 88.416892 -124.976636)
		(end 88.591898 -125.399292)
		(width 0.1651)
		(layer "In9.Cu")
		(net "P5E_PEX0_STN0_TX_DP<0>")
	)
	(segment
		(start 86.288626 -120.828816)
		(end 86.429596 -120.800876)
		(width 0.1651)
		(layer "In9.Cu")
		(net "P5E_PEX0_STN0_TX_DP<0>")
	)
	(segment
		(start 90.121994 -179.192428)
		(end 86.395306 -221.785942)
		(width 0.1651)
		(layer "In9.Cu")
		(net "P5E_PEX0_STN0_TX_DP<0>")
	)
	(segment
		(start 99.889564 -151.961596)
		(end 99.889564 -159.92983)
		(width 0.1651)
		(layer "In9.Cu")
		(net "P5E_PEX0_STN0_TX_DP<0>")
	)
	(segment
		(start 77.12964 -287.944814)
		(end 77.12964 -288.185606)
		(width 0.1143)
		(layer "In9.Cu")
		(net "P5E_PEX0_STN0_TX_DP<0>")
	)
	(segment
		(start 85.908388 -120.574562)
		(end 86.288626 -120.828816)
		(width 0.1651)
		(layer "In9.Cu")
		(net "P5E_PEX0_STN0_TX_DP<0>")
	)
	(segment
		(start 88.04402 -123.811284)
		(end 87.989156 -123.943872)
		(width 0.1651)
		(layer "In9.Cu")
		(net "P5E_PEX0_STN0_TX_DP<0>")
	)
	(segment
		(start 88.591898 -125.399292)
		(end 88.72474 -125.45441)
		(width 0.1651)
		(layer "In9.Cu")
		(net "P5E_PEX0_STN0_TX_DP<0>")
	)
	(segment
		(start 88.993472 -126.10338)
		(end 88.938608 -126.236222)
		(width 0.1651)
		(layer "In9.Cu")
		(net "P5E_PEX0_STN0_TX_DP<0>")
	)
	(segment
		(start 86.429596 -120.800876)
		(end 86.93785 -121.14022)
		(width 0.1651)
		(layer "In9.Cu")
		(net "P5E_PEX0_STN0_TX_DP<0>")
	)
	(segment
		(start 85.782658 -287.683956)
		(end 83.917536 -287.683956)
		(width 0.1651)
		(layer "In9.Cu")
		(net "P5E_PEX0_STN0_TX_DP<0>")
	)
	(segment
		(start 84.135976 -119.268494)
		(end 85.880194 -120.433592)
		(width 0.1651)
		(layer "In9.Cu")
		(net "P5E_PEX0_STN0_TX_DP<0>")
	)
	(segment
		(start 87.441532 -122.356118)
		(end 87.616284 -122.77852)
		(width 0.1651)
		(layer "In9.Cu")
		(net "P5E_PEX0_STN0_TX_DP<0>")
	)
	(segment
		(start 99.889564 -159.92983)
		(end 99.558348 -161.16935)
		(width 0.1651)
		(layer "In9.Cu")
		(net "P5E_PEX0_STN0_TX_DP<0>")
	)
	(segment
		(start 86.93785 -121.14022)
		(end 87.188548 -121.745756)
		(width 0.1651)
		(layer "In9.Cu")
		(net "P5E_PEX0_STN0_TX_DP<0>")
	)
	(segment
		(start 87.30869 -122.301254)
		(end 87.441532 -122.356118)
		(width 0.1651)
		(layer "In9.Cu")
		(net "P5E_PEX0_STN0_TX_DP<0>")
	)
	(segment
		(start 100.415344 -272.702782)
		(end 98.73742 -276.752812)
		(width 0.1651)
		(layer "In9.Cu")
		(net "P5E_PEX0_STN0_TX_DP<0>")
	)
	(segment
		(start 88.938608 -126.236222)
		(end 89.113614 -126.658878)
		(width 0.1651)
		(layer "In9.Cu")
		(net "P5E_PEX0_STN0_TX_DP<0>")
	)
	(segment
		(start 99.944682 -267.29182)
		(end 100.415344 -272.702782)
		(width 0.1651)
		(layer "In9.Cu")
		(net "P5E_PEX0_STN0_TX_DP<0>")
	)
	(segment
		(start 90.992452 -130.928872)
		(end 91.30792 -131.24434)
		(width 0.1651)
		(layer "In9.Cu")
		(net "P5E_PEX0_STN0_TX_DP<0>")
	)
	(segment
		(start 77.01534 -288.299906)
		(end 76.74991 -288.299906)
		(width 0.1143)
		(layer "In9.Cu")
		(net "P5E_PEX0_STN0_TX_DP<0>")
	)
	(segment
		(start 83.678776 -119.268494)
		(end 84.135976 -119.268494)
		(width 0.1651)
		(layer "In9.Cu")
		(net "P5E_PEX0_STN0_TX_DP<0>")
	)
	(segment
		(start 83.119976 -119.370094)
		(end 83.577176 -119.370094)
		(width 0.1651)
		(layer "In9.Cu")
		(net "P5E_PEX0_STN0_TX_DP<0>")
	)
	(segment
		(start 99.558348 -161.16935)
		(end 90.986864 -176.023778)
		(width 0.1651)
		(layer "In9.Cu")
		(net "P5E_PEX0_STN0_TX_DP<0>")
	)
	(segment
		(start 88.471756 -124.843794)
		(end 88.416892 -124.976636)
		(width 0.1651)
		(layer "In9.Cu")
		(net "P5E_PEX0_STN0_TX_DP<0>")
	)
	(segment
		(start 87.56142 -122.911108)
		(end 87.736426 -123.333764)
		(width 0.1651)
		(layer "In9.Cu")
		(net "P5E_PEX0_STN0_TX_DP<0>")
	)
	(segment
		(start 87.188548 -121.745756)
		(end 87.133684 -121.878598)
		(width 0.1651)
		(layer "In9.Cu")
		(net "P5E_PEX0_STN0_TX_DP<0>")
	)
	(segment
		(start 87.133684 -121.878598)
		(end 87.30869 -122.301254)
		(width 0.1651)
		(layer "In9.Cu")
		(net "P5E_PEX0_STN0_TX_DP<0>")
	)
	(segment
		(start 88.164162 -124.366528)
		(end 88.297004 -124.421646)
		(width 0.1651)
		(layer "In9.Cu")
		(net "P5E_PEX0_STN0_TX_DP<0>")
	)
	(segment
		(start 88.72474 -125.45441)
		(end 88.993472 -126.10338)
		(width 0.1651)
		(layer "In9.Cu")
		(net "P5E_PEX0_STN0_TX_DP<0>")
	)
	(segment
		(start 91.30792 -131.24434)
		(end 99.889564 -151.961596)
		(width 0.1651)
		(layer "In9.Cu")
		(net "P5E_PEX0_STN0_TX_DP<0>")
	)
	(segment
		(start 88.297004 -124.421646)
		(end 88.471756 -124.843794)
		(width 0.1651)
		(layer "In9.Cu")
		(net "P5E_PEX0_STN0_TX_DP<0>")
	)
	(segment
		(start 77.344778 -287.729676)
		(end 77.12964 -287.944814)
		(width 0.1143)
		(layer "In9.Cu")
		(net "P5E_PEX0_STN0_TX_DP<0>")
	)
	(segment
		(start 81.532222 -119.559324)
		(end 81.823052 -119.268494)
		(width 0.1651)
		(layer "In9.Cu")
		(net "P5E_PEX0_STN0_TX_DP<0>")
	)
	(segment
		(start 19.84121 -370.120672)
		(end 17.09166 -351.585022)
		(width 0.1651)
		(layer "In5.Cu")
		(net "P5E_PEX0_STN7_RX_DP<115>")
	)
	(segment
		(start 25.58161 -308.515512)
		(end 26.014934 -307.868066)
		(width 0.1651)
		(layer "In5.Cu")
		(net "P5E_PEX0_STN7_RX_DP<115>")
	)
	(segment
		(start 17.7546 -336.563716)
		(end 18.417032 -331.19314)
		(width 0.1651)
		(layer "In5.Cu")
		(net "P5E_PEX0_STN7_RX_DP<115>")
	)
	(segment
		(start 23.395178 -312.606436)
		(end 25.580848 -308.515258)
		(width 0.1651)
		(layer "In5.Cu")
		(net "P5E_PEX0_STN7_RX_DP<115>")
	)
	(segment
		(start 35.37712 -396.651226)
		(end 34.610294 -394.800074)
		(width 0.1651)
		(layer "In5.Cu")
		(net "P5E_PEX0_STN7_RX_DP<115>")
	)
	(segment
		(start 37.420042 -304.10531)
		(end 37.420042 -304.335434)
		(width 0.1143)
		(layer "In5.Cu")
		(net "P5E_PEX0_STN7_RX_DP<115>")
	)
	(segment
		(start 23.75154 -387.47192)
		(end 22.868636 -385.341368)
		(width 0.1651)
		(layer "In5.Cu")
		(net "P5E_PEX0_STN7_RX_DP<115>")
	)
	(segment
		(start 22.868636 -385.341368)
		(end 19.84121 -370.120672)
		(width 0.1651)
		(layer "In5.Cu")
		(net "P5E_PEX0_STN7_RX_DP<115>")
	)
	(segment
		(start 17.754854 -336.563716)
		(end 17.7546 -336.563716)
		(width 0.1651)
		(layer "In5.Cu")
		(net "P5E_PEX0_STN7_RX_DP<115>")
	)
	(segment
		(start 33.94964 -394.13942)
		(end 25.135586 -388.855966)
		(width 0.1651)
		(layer "In5.Cu")
		(net "P5E_PEX0_STN7_RX_DP<115>")
	)
	(segment
		(start 37.420042 -304.335434)
		(end 37.534342 -304.449734)
		(width 0.1143)
		(layer "In5.Cu")
		(net "P5E_PEX0_STN7_RX_DP<115>")
	)
	(segment
		(start 35.01898 -409.799028)
		(end 35.37712 -409.440888)
		(width 0.1651)
		(layer "In5.Cu")
		(net "P5E_PEX0_STN7_RX_DP<115>")
	)
	(segment
		(start 35.588448 -303.833784)
		(end 35.634168 -303.879504)
		(width 0.1143)
		(layer "In5.Cu")
		(net "P5E_PEX0_STN7_RX_DP<115>")
	)
	(segment
		(start 37.534342 -304.449734)
		(end 37.799772 -304.449734)
		(width 0.1143)
		(layer "In5.Cu")
		(net "P5E_PEX0_STN7_RX_DP<115>")
	)
	(segment
		(start 34.636964 -409.799028)
		(end 35.01898 -409.799028)
		(width 0.1651)
		(layer "In5.Cu")
		(net "P5E_PEX0_STN7_RX_DP<115>")
	)
	(segment
		(start 17.09166 -341.941658)
		(end 17.754854 -336.563716)
		(width 0.1651)
		(layer "In5.Cu")
		(net "P5E_PEX0_STN7_RX_DP<115>")
	)
	(segment
		(start 20.76831 -318.982598)
		(end 20.793964 -318.885316)
		(width 0.1651)
		(layer "In5.Cu")
		(net "P5E_PEX0_STN7_RX_DP<115>")
	)
	(segment
		(start 17.09166 -351.585022)
		(end 17.09166 -341.941658)
		(width 0.1651)
		(layer "In5.Cu")
		(net "P5E_PEX0_STN7_RX_DP<115>")
	)
	(segment
		(start 25.580848 -308.515258)
		(end 25.58161 -308.515512)
		(width 0.1651)
		(layer "In5.Cu")
		(net "P5E_PEX0_STN7_RX_DP<115>")
	)
	(segment
		(start 34.610294 -394.800074)
		(end 33.94964 -394.13942)
		(width 0.1651)
		(layer "In5.Cu")
		(net "P5E_PEX0_STN7_RX_DP<115>")
	)
	(segment
		(start 26.014934 -307.868066)
		(end 28.688538 -305.194462)
		(width 0.1651)
		(layer "In5.Cu")
		(net "P5E_PEX0_STN7_RX_DP<115>")
	)
	(segment
		(start 20.793964 -318.885316)
		(end 23.395178 -312.606436)
		(width 0.1651)
		(layer "In5.Cu")
		(net "P5E_PEX0_STN7_RX_DP<115>")
	)
	(segment
		(start 34.509964 -409.672028)
		(end 34.636964 -409.799028)
		(width 0.1651)
		(layer "In5.Cu")
		(net "P5E_PEX0_STN7_RX_DP<115>")
	)
	(segment
		(start 34.509964 -409.290012)
		(end 34.509964 -409.672028)
		(width 0.1651)
		(layer "In5.Cu")
		(net "P5E_PEX0_STN7_RX_DP<115>")
	)
	(segment
		(start 28.688538 -305.194462)
		(end 30.470348 -304.456338)
		(width 0.1651)
		(layer "In5.Cu")
		(net "P5E_PEX0_STN7_RX_DP<115>")
	)
	(segment
		(start 35.37712 -409.440888)
		(end 35.37712 -396.651226)
		(width 0.1651)
		(layer "In5.Cu")
		(net "P5E_PEX0_STN7_RX_DP<115>")
	)
	(segment
		(start 30.470348 -304.456338)
		(end 33.597596 -303.833784)
		(width 0.1651)
		(layer "In5.Cu")
		(net "P5E_PEX0_STN7_RX_DP<115>")
	)
	(segment
		(start 33.597596 -303.833784)
		(end 35.56 -303.833784)
		(width 0.1651)
		(layer "In5.Cu")
		(net "P5E_PEX0_STN7_RX_DP<115>")
	)
	(segment
		(start 37.194236 -303.879504)
		(end 37.420042 -304.10531)
		(width 0.1143)
		(layer "In5.Cu")
		(net "P5E_PEX0_STN7_RX_DP<115>")
	)
	(segment
		(start 35.56 -303.833784)
		(end 35.588448 -303.833784)
		(width 0.1143)
		(layer "In5.Cu")
		(net "P5E_PEX0_STN7_RX_DP<115>")
	)
	(segment
		(start 18.417032 -331.19314)
		(end 20.76831 -318.982598)
		(width 0.1651)
		(layer "In5.Cu")
		(net "P5E_PEX0_STN7_RX_DP<115>")
	)
	(segment
		(start 35.634168 -303.879504)
		(end 37.194236 -303.879504)
		(width 0.1143)
		(layer "In5.Cu")
		(net "P5E_PEX0_STN7_RX_DP<115>")
	)
	(segment
		(start 25.135586 -388.855966)
		(end 23.75154 -387.47192)
		(width 0.1651)
		(layer "In5.Cu")
		(net "P5E_PEX0_STN7_RX_DP<115>")
	)
	(segment
		(start 74.84999 -285.449772)
		(end 74.849736 -285.449772)
		(width 0.13462)
		(layer "F.Cu")
		(net "P5E_PEX0_STN0_TX_DP<3>")
	)
	(segment
		(start 82.928206 -124.991114)
		(end 83.248246 -124.671074)
		(width 0.13462)
		(layer "F.Cu")
		(net "P5E_PEX0_STN0_TX_DP<3>")
	)
	(segment
		(start 83.87969 -124.671074)
		(end 84.17433 -124.965714)
		(width 0.13462)
		(layer "F.Cu")
		(net "P5E_PEX0_STN0_TX_DP<3>")
	)
	(segment
		(start 83.248246 -124.671074)
		(end 83.87969 -124.671074)
		(width 0.13462)
		(layer "F.Cu")
		(net "P5E_PEX0_STN0_TX_DP<3>")
	)
	(segment
		(start 96.986344 -159.546544)
		(end 96.852486 -160.047178)
		(width 0.1651)
		(layer "In9.Cu")
		(net "P5E_PEX0_STN0_TX_DP<3>")
	)
	(segment
		(start 96.852486 -160.047178)
		(end 88.194388 -175.049942)
		(width 0.1651)
		(layer "In9.Cu")
		(net "P5E_PEX0_STN0_TX_DP<3>")
	)
	(segment
		(start 86.705694 -129.102358)
		(end 86.651592 -129.235454)
		(width 0.1651)
		(layer "In9.Cu")
		(net "P5E_PEX0_STN0_TX_DP<3>")
	)
	(segment
		(start 87.520018 -131.295648)
		(end 87.697564 -131.717288)
		(width 0.1651)
		(layer "In9.Cu")
		(net "P5E_PEX0_STN0_TX_DP<3>")
	)
	(segment
		(start 86.271354 -128.072388)
		(end 86.217252 -128.205484)
		(width 0.1651)
		(layer "In9.Cu")
		(net "P5E_PEX0_STN0_TX_DP<3>")
	)
	(segment
		(start 88.772492 -133.358636)
		(end 88.717628 -133.491224)
		(width 0.1651)
		(layer "In9.Cu")
		(net "P5E_PEX0_STN0_TX_DP<3>")
	)
	(segment
		(start 87.263224 -130.687318)
		(end 87.396574 -130.74142)
		(width 0.1651)
		(layer "In9.Cu")
		(net "P5E_PEX0_STN0_TX_DP<3>")
	)
	(segment
		(start 83.819492 -284.879288)
		(end 75.444858 -284.879288)
		(width 0.1143)
		(layer "In9.Cu")
		(net "P5E_PEX0_STN0_TX_DP<3>")
	)
	(segment
		(start 75.229466 -285.09468)
		(end 75.229466 -285.335472)
		(width 0.1143)
		(layer "In9.Cu")
		(net "P5E_PEX0_STN0_TX_DP<3>")
	)
	(segment
		(start 86.962488 -129.711196)
		(end 86.962234 -129.71145)
		(width 0.1651)
		(layer "In9.Cu")
		(net "P5E_PEX0_STN0_TX_DP<3>")
	)
	(segment
		(start 89.200228 -134.391146)
		(end 89.145364 -134.523988)
		(width 0.1651)
		(layer "In9.Cu")
		(net "P5E_PEX0_STN0_TX_DP<3>")
	)
	(segment
		(start 89.025476 -133.968998)
		(end 89.200228 -134.391146)
		(width 0.1651)
		(layer "In9.Cu")
		(net "P5E_PEX0_STN0_TX_DP<3>")
	)
	(segment
		(start 86.962234 -129.71145)
		(end 87.13978 -130.132582)
		(width 0.1651)
		(layer "In9.Cu")
		(net "P5E_PEX0_STN0_TX_DP<3>")
	)
	(segment
		(start 89.32037 -134.946644)
		(end 89.453212 -135.001762)
		(width 0.1651)
		(layer "In9.Cu")
		(net "P5E_PEX0_STN0_TX_DP<3>")
	)
	(segment
		(start 75.115166 -285.449772)
		(end 74.849736 -285.449772)
		(width 0.1143)
		(layer "In9.Cu")
		(net "P5E_PEX0_STN0_TX_DP<3>")
	)
	(segment
		(start 86.093808 -127.651256)
		(end 86.093554 -127.651256)
		(width 0.1651)
		(layer "In9.Cu")
		(net "P5E_PEX0_STN0_TX_DP<3>")
	)
	(segment
		(start 85.659468 -126.621286)
		(end 85.837014 -127.042418)
		(width 0.1651)
		(layer "In9.Cu")
		(net "P5E_PEX0_STN0_TX_DP<3>")
	)
	(segment
		(start 85.010498 -124.674884)
		(end 85.22335 -124.887736)
		(width 0.1651)
		(layer "In9.Cu")
		(net "P5E_PEX0_STN0_TX_DP<3>")
	)
	(segment
		(start 85.960458 -127.597154)
		(end 86.093808 -127.651256)
		(width 0.1651)
		(layer "In9.Cu")
		(net "P5E_PEX0_STN0_TX_DP<3>")
	)
	(segment
		(start 84.46516 -124.674884)
		(end 85.010498 -124.674884)
		(width 0.1651)
		(layer "In9.Cu")
		(net "P5E_PEX0_STN0_TX_DP<3>")
	)
	(segment
		(start 86.093554 -127.651256)
		(end 86.2711 -128.072388)
		(width 0.1651)
		(layer "In9.Cu")
		(net "P5E_PEX0_STN0_TX_DP<3>")
	)
	(segment
		(start 96.986344 -153.18867)
		(end 96.986344 -159.546544)
		(width 0.1651)
		(layer "In9.Cu")
		(net "P5E_PEX0_STN0_TX_DP<3>")
	)
	(segment
		(start 87.697564 -131.717288)
		(end 87.830914 -131.77139)
		(width 0.1651)
		(layer "In9.Cu")
		(net "P5E_PEX0_STN0_TX_DP<3>")
	)
	(segment
		(start 87.396574 -130.74142)
		(end 87.57412 -131.162552)
		(width 0.1651)
		(layer "In9.Cu")
		(net "P5E_PEX0_STN0_TX_DP<3>")
	)
	(segment
		(start 88.11514 -132.44576)
		(end 88.592406 -132.92328)
		(width 0.1651)
		(layer "In9.Cu")
		(net "P5E_PEX0_STN0_TX_DP<3>")
	)
	(segment
		(start 87.830914 -131.77139)
		(end 88.11514 -132.44576)
		(width 0.1651)
		(layer "In9.Cu")
		(net "P5E_PEX0_STN0_TX_DP<3>")
	)
	(segment
		(start 86.2711 -128.072388)
		(end 86.271354 -128.072388)
		(width 0.1651)
		(layer "In9.Cu")
		(net "P5E_PEX0_STN0_TX_DP<3>")
	)
	(segment
		(start 86.70544 -129.102358)
		(end 86.705694 -129.102358)
		(width 0.1651)
		(layer "In9.Cu")
		(net "P5E_PEX0_STN0_TX_DP<3>")
	)
	(segment
		(start 85.22335 -124.887736)
		(end 85.399372 -125.312932)
		(width 0.1651)
		(layer "In9.Cu")
		(net "P5E_PEX0_STN0_TX_DP<3>")
	)
	(segment
		(start 85.176614 -284.833568)
		(end 83.89366 -284.833568)
		(width 0.1651)
		(layer "In9.Cu")
		(net "P5E_PEX0_STN0_TX_DP<3>")
	)
	(segment
		(start 88.592406 -132.92328)
		(end 88.772492 -133.358636)
		(width 0.1651)
		(layer "In9.Cu")
		(net "P5E_PEX0_STN0_TX_DP<3>")
	)
	(segment
		(start 88.194388 -175.049942)
		(end 87.193374 -178.781202)
		(width 0.1651)
		(layer "In9.Cu")
		(net "P5E_PEX0_STN0_TX_DP<3>")
	)
	(segment
		(start 97.49663 -272.258028)
		(end 96.307148 -275.130006)
		(width 0.1651)
		(layer "In9.Cu")
		(net "P5E_PEX0_STN0_TX_DP<3>")
	)
	(segment
		(start 83.89366 -284.833568)
		(end 83.865212 -284.833568)
		(width 0.1143)
		(layer "In9.Cu")
		(net "P5E_PEX0_STN0_TX_DP<3>")
	)
	(segment
		(start 89.453212 -135.001762)
		(end 96.986344 -153.18867)
		(width 0.1651)
		(layer "In9.Cu")
		(net "P5E_PEX0_STN0_TX_DP<3>")
	)
	(segment
		(start 88.892634 -133.91388)
		(end 89.025476 -133.968998)
		(width 0.1651)
		(layer "In9.Cu")
		(net "P5E_PEX0_STN0_TX_DP<3>")
	)
	(segment
		(start 85.837014 -127.042418)
		(end 85.782912 -127.175514)
		(width 0.1651)
		(layer "In9.Cu")
		(net "P5E_PEX0_STN0_TX_DP<3>")
	)
	(segment
		(start 87.085678 -130.265678)
		(end 87.263224 -130.687318)
		(width 0.1651)
		(layer "In9.Cu")
		(net "P5E_PEX0_STN0_TX_DP<3>")
	)
	(segment
		(start 89.145364 -134.523988)
		(end 89.32037 -134.946644)
		(width 0.1651)
		(layer "In9.Cu")
		(net "P5E_PEX0_STN0_TX_DP<3>")
	)
	(segment
		(start 87.57412 -131.162552)
		(end 87.520018 -131.295648)
		(width 0.1651)
		(layer "In9.Cu")
		(net "P5E_PEX0_STN0_TX_DP<3>")
	)
	(segment
		(start 83.44408 -221.628208)
		(end 85.963506 -250.487688)
		(width 0.1651)
		(layer "In9.Cu")
		(net "P5E_PEX0_STN0_TX_DP<3>")
	)
	(segment
		(start 85.963506 -250.487688)
		(end 96.248728 -265.879326)
		(width 0.1651)
		(layer "In9.Cu")
		(net "P5E_PEX0_STN0_TX_DP<3>")
	)
	(segment
		(start 88.717628 -133.491224)
		(end 88.892634 -133.91388)
		(width 0.1651)
		(layer "In9.Cu")
		(net "P5E_PEX0_STN0_TX_DP<3>")
	)
	(segment
		(start 86.528148 -128.681226)
		(end 86.527894 -128.681226)
		(width 0.1651)
		(layer "In9.Cu")
		(net "P5E_PEX0_STN0_TX_DP<3>")
	)
	(segment
		(start 84.17433 -124.965714)
		(end 84.46516 -124.674884)
		(width 0.1651)
		(layer "In9.Cu")
		(net "P5E_PEX0_STN0_TX_DP<3>")
	)
	(segment
		(start 86.651592 -129.235454)
		(end 86.829138 -129.657094)
		(width 0.1651)
		(layer "In9.Cu")
		(net "P5E_PEX0_STN0_TX_DP<3>")
	)
	(segment
		(start 75.229466 -285.335472)
		(end 75.115166 -285.449772)
		(width 0.1143)
		(layer "In9.Cu")
		(net "P5E_PEX0_STN0_TX_DP<3>")
	)
	(segment
		(start 87.612728 -283.824426)
		(end 85.176614 -284.833568)
		(width 0.1651)
		(layer "In9.Cu")
		(net "P5E_PEX0_STN0_TX_DP<3>")
	)
	(segment
		(start 96.307148 -275.130006)
		(end 87.612728 -283.824426)
		(width 0.1651)
		(layer "In9.Cu")
		(net "P5E_PEX0_STN0_TX_DP<3>")
	)
	(segment
		(start 87.13978 -130.132582)
		(end 87.085678 -130.265678)
		(width 0.1651)
		(layer "In9.Cu")
		(net "P5E_PEX0_STN0_TX_DP<3>")
	)
	(segment
		(start 87.193374 -178.781202)
		(end 83.44408 -221.628208)
		(width 0.1651)
		(layer "In9.Cu")
		(net "P5E_PEX0_STN0_TX_DP<3>")
	)
	(segment
		(start 86.527894 -128.681226)
		(end 86.70544 -129.102358)
		(width 0.1651)
		(layer "In9.Cu")
		(net "P5E_PEX0_STN0_TX_DP<3>")
	)
	(segment
		(start 75.444858 -284.879288)
		(end 75.229466 -285.09468)
		(width 0.1143)
		(layer "In9.Cu")
		(net "P5E_PEX0_STN0_TX_DP<3>")
	)
	(segment
		(start 85.399372 -125.312932)
		(end 85.659468 -126.621286)
		(width 0.1651)
		(layer "In9.Cu")
		(net "P5E_PEX0_STN0_TX_DP<3>")
	)
	(segment
		(start 83.865212 -284.833568)
		(end 83.819492 -284.879288)
		(width 0.1143)
		(layer "In9.Cu")
		(net "P5E_PEX0_STN0_TX_DP<3>")
	)
	(segment
		(start 86.829138 -129.657094)
		(end 86.962488 -129.711196)
		(width 0.1651)
		(layer "In9.Cu")
		(net "P5E_PEX0_STN0_TX_DP<3>")
	)
	(segment
		(start 86.217252 -128.205484)
		(end 86.394798 -128.627124)
		(width 0.1651)
		(layer "In9.Cu")
		(net "P5E_PEX0_STN0_TX_DP<3>")
	)
	(segment
		(start 97.125536 -267.996162)
		(end 97.49663 -272.258028)
		(width 0.1651)
		(layer "In9.Cu")
		(net "P5E_PEX0_STN0_TX_DP<3>")
	)
	(segment
		(start 96.248728 -265.879326)
		(end 97.125536 -267.996162)
		(width 0.1651)
		(layer "In9.Cu")
		(net "P5E_PEX0_STN0_TX_DP<3>")
	)
	(segment
		(start 86.394798 -128.627124)
		(end 86.528148 -128.681226)
		(width 0.1651)
		(layer "In9.Cu")
		(net "P5E_PEX0_STN0_TX_DP<3>")
	)
	(segment
		(start 85.782912 -127.175514)
		(end 85.960458 -127.597154)
		(width 0.1651)
		(layer "In9.Cu")
		(net "P5E_PEX0_STN0_TX_DP<3>")
	)
	(segment
		(start 63.449962 -318.409066)
		(end 63.361062 -318.320166)
		(width 0.1143)
		(layer "In9.Cu")
		(net "P5E_PEX0_STN5_RX_DN<85>")
	)
	(segment
		(start 63.070232 -319.91808)
		(end 63.115952 -319.9638)
		(width 0.1143)
		(layer "In9.Cu")
		(net "P5E_PEX0_STN5_RX_DN<85>")
	)
	(segment
		(start 83.493864 -398.380966)
		(end 83.036918 -398.380966)
		(width 0.1651)
		(layer "In9.Cu")
		(net "P5E_PEX0_STN5_RX_DN<85>")
	)
	(segment
		(start 96.703388 -388.989062)
		(end 94.8817 -390.81075)
		(width 0.1651)
		(layer "In9.Cu")
		(net "P5E_PEX0_STN5_RX_DN<85>")
	)
	(segment
		(start 84.08416 -397.79067)
		(end 83.493864 -398.380966)
		(width 0.1651)
		(layer "In9.Cu")
		(net "P5E_PEX0_STN5_RX_DN<85>")
	)
	(segment
		(start 93.567504 -391.355326)
		(end 86.188042 -392.822938)
		(width 0.1651)
		(layer "In9.Cu")
		(net "P5E_PEX0_STN5_RX_DN<85>")
	)
	(segment
		(start 86.188042 -392.822938)
		(end 84.08416 -394.92682)
		(width 0.1651)
		(layer "In9.Cu")
		(net "P5E_PEX0_STN5_RX_DN<85>")
	)
	(segment
		(start 63.070232 -318.485266)
		(end 63.070232 -319.91808)
		(width 0.1143)
		(layer "In9.Cu")
		(net "P5E_PEX0_STN5_RX_DN<85>")
	)
	(segment
		(start 63.115952 -320.212466)
		(end 63.479426 -321.090798)
		(width 0.1651)
		(layer "In9.Cu")
		(net "P5E_PEX0_STN5_RX_DN<85>")
	)
	(segment
		(start 97.81794 -369.750594)
		(end 97.81794 -371.051836)
		(width 0.1651)
		(layer "In9.Cu")
		(net "P5E_PEX0_STN5_RX_DN<85>")
	)
	(segment
		(start 94.691708 -342.046306)
		(end 97.200466 -367.517426)
		(width 0.1651)
		(layer "In9.Cu")
		(net "P5E_PEX0_STN5_RX_DN<85>")
	)
	(segment
		(start 83.036918 -398.380966)
		(end 82.909918 -398.507966)
		(width 0.1651)
		(layer "In9.Cu")
		(net "P5E_PEX0_STN5_RX_DN<85>")
	)
	(segment
		(start 64.810386 -322.421758)
		(end 68.62318 -324.00113)
		(width 0.1651)
		(layer "In9.Cu")
		(net "P5E_PEX0_STN5_RX_DN<85>")
	)
	(segment
		(start 82.909918 -398.507966)
		(end 82.909918 -398.890236)
		(width 0.1651)
		(layer "In9.Cu")
		(net "P5E_PEX0_STN5_RX_DN<85>")
	)
	(segment
		(start 97.200466 -367.517426)
		(end 97.81794 -369.750594)
		(width 0.1651)
		(layer "In9.Cu")
		(net "P5E_PEX0_STN5_RX_DN<85>")
	)
	(segment
		(start 63.479426 -321.090798)
		(end 64.810386 -322.421758)
		(width 0.1651)
		(layer "In9.Cu")
		(net "P5E_PEX0_STN5_RX_DN<85>")
	)
	(segment
		(start 94.8817 -390.81075)
		(end 93.567504 -391.355326)
		(width 0.1651)
		(layer "In9.Cu")
		(net "P5E_PEX0_STN5_RX_DN<85>")
	)
	(segment
		(start 63.449962 -318.699896)
		(end 63.449962 -318.409066)
		(width 0.1143)
		(layer "In9.Cu")
		(net "P5E_PEX0_STN5_RX_DN<85>")
	)
	(segment
		(start 68.62318 -324.00113)
		(end 94.065598 -341.00135)
		(width 0.1651)
		(layer "In9.Cu")
		(net "P5E_PEX0_STN5_RX_DN<85>")
	)
	(segment
		(start 97.81794 -371.051836)
		(end 97.49536 -385.473956)
		(width 0.1651)
		(layer "In9.Cu")
		(net "P5E_PEX0_STN5_RX_DN<85>")
	)
	(segment
		(start 63.235332 -318.320166)
		(end 63.070232 -318.485266)
		(width 0.1143)
		(layer "In9.Cu")
		(net "P5E_PEX0_STN5_RX_DN<85>")
	)
	(segment
		(start 63.361062 -318.320166)
		(end 63.235332 -318.320166)
		(width 0.1143)
		(layer "In9.Cu")
		(net "P5E_PEX0_STN5_RX_DN<85>")
	)
	(segment
		(start 97.49536 -387.07695)
		(end 96.703388 -388.989062)
		(width 0.1651)
		(layer "In9.Cu")
		(net "P5E_PEX0_STN5_RX_DN<85>")
	)
	(segment
		(start 84.08416 -394.92682)
		(end 84.08416 -397.79067)
		(width 0.1651)
		(layer "In9.Cu")
		(net "P5E_PEX0_STN5_RX_DN<85>")
	)
	(segment
		(start 94.065598 -341.00135)
		(end 94.691708 -342.046306)
		(width 0.1651)
		(layer "In9.Cu")
		(net "P5E_PEX0_STN5_RX_DN<85>")
	)
	(segment
		(start 97.49536 -385.473956)
		(end 97.49536 -387.07695)
		(width 0.1651)
		(layer "In9.Cu")
		(net "P5E_PEX0_STN5_RX_DN<85>")
	)
	(segment
		(start 63.115952 -319.9638)
		(end 63.115952 -319.992248)
		(width 0.1143)
		(layer "In9.Cu")
		(net "P5E_PEX0_STN5_RX_DN<85>")
	)
	(segment
		(start 63.115952 -319.992248)
		(end 63.115952 -320.212466)
		(width 0.1651)
		(layer "In9.Cu")
		(net "P5E_PEX0_STN5_RX_DN<85>")
	)
	(segment
		(start 29.228288 -344.539062)
		(end 29.548328 -344.219022)
		(width 0.13462)
		(layer "F.Cu")
		(net "P5E_PEX0_STN7_TX_C_DN<116>")
	)
	(segment
		(start 29.522928 -345.465146)
		(end 29.228288 -345.170506)
		(width 0.13462)
		(layer "F.Cu")
		(net "P5E_PEX0_STN7_TX_C_DN<116>")
	)
	(segment
		(start 29.228288 -345.170506)
		(end 29.228288 -344.539062)
		(width 0.13462)
		(layer "F.Cu")
		(net "P5E_PEX0_STN7_TX_C_DN<116>")
	)
	(segment
		(start 27.677618 -348.029022)
		(end 29.232098 -346.474542)
		(width 0.1651)
		(layer "In7.Cu")
		(net "P5E_PEX0_STN7_TX_C_DN<116>")
	)
	(segment
		(start 36.837112 -401.181062)
		(end 37.310568 -401.181062)
		(width 0.1651)
		(layer "In7.Cu")
		(net "P5E_PEX0_STN7_TX_C_DN<116>")
	)
	(segment
		(start 26.327354 -388.197344)
		(end 24.9428 -386.81279)
		(width 0.1651)
		(layer "In7.Cu")
		(net "P5E_PEX0_STN7_TX_C_DN<116>")
	)
	(segment
		(start 37.884354 -394.271754)
		(end 35.686238 -392.073638)
		(width 0.1651)
		(layer "In7.Cu")
		(net "P5E_PEX0_STN7_TX_C_DN<116>")
	)
	(segment
		(start 37.310568 -401.181062)
		(end 37.884354 -400.607276)
		(width 0.1651)
		(layer "In7.Cu")
		(net "P5E_PEX0_STN7_TX_C_DN<116>")
	)
	(segment
		(start 29.232098 -345.755976)
		(end 29.522928 -345.465146)
		(width 0.1651)
		(layer "In7.Cu")
		(net "P5E_PEX0_STN7_TX_C_DN<116>")
	)
	(segment
		(start 37.884354 -400.607276)
		(end 37.884354 -394.271754)
		(width 0.1651)
		(layer "In7.Cu")
		(net "P5E_PEX0_STN7_TX_C_DN<116>")
	)
	(segment
		(start 23.40356 -375.57964)
		(end 23.40356 -371.10543)
		(width 0.1651)
		(layer "In7.Cu")
		(net "P5E_PEX0_STN7_TX_C_DN<116>")
	)
	(segment
		(start 27.419554 -359.19664)
		(end 27.677618 -357.899208)
		(width 0.1651)
		(layer "In7.Cu")
		(net "P5E_PEX0_STN7_TX_C_DN<116>")
	)
	(segment
		(start 35.686238 -392.073638)
		(end 26.327354 -388.197344)
		(width 0.1651)
		(layer "In7.Cu")
		(net "P5E_PEX0_STN7_TX_C_DN<116>")
	)
	(segment
		(start 27.677618 -357.899208)
		(end 27.677618 -348.029022)
		(width 0.1651)
		(layer "In7.Cu")
		(net "P5E_PEX0_STN7_TX_C_DN<116>")
	)
	(segment
		(start 23.946612 -384.598418)
		(end 23.40356 -375.57964)
		(width 0.1651)
		(layer "In7.Cu")
		(net "P5E_PEX0_STN7_TX_C_DN<116>")
	)
	(segment
		(start 23.40356 -371.10543)
		(end 24.25065 -366.84712)
		(width 0.1651)
		(layer "In7.Cu")
		(net "P5E_PEX0_STN7_TX_C_DN<116>")
	)
	(segment
		(start 36.710112 -401.690078)
		(end 36.710112 -401.308062)
		(width 0.1651)
		(layer "In7.Cu")
		(net "P5E_PEX0_STN7_TX_C_DN<116>")
	)
	(segment
		(start 36.710112 -401.308062)
		(end 36.837112 -401.181062)
		(width 0.1651)
		(layer "In7.Cu")
		(net "P5E_PEX0_STN7_TX_C_DN<116>")
	)
	(segment
		(start 24.25065 -366.84712)
		(end 27.419554 -359.19664)
		(width 0.1651)
		(layer "In7.Cu")
		(net "P5E_PEX0_STN7_TX_C_DN<116>")
	)
	(segment
		(start 24.9428 -386.81279)
		(end 23.946612 -384.598418)
		(width 0.1651)
		(layer "In7.Cu")
		(net "P5E_PEX0_STN7_TX_C_DN<116>")
	)
	(segment
		(start 29.232098 -346.474542)
		(end 29.232098 -345.755976)
		(width 0.1651)
		(layer "In7.Cu")
		(net "P5E_PEX0_STN7_TX_C_DN<116>")
	)
	(segment
		(start 38.693852 -99.608894)
		(end 39.013892 -99.288854)
		(width 0.13462)
		(layer "F.Cu")
		(net "P5E_PEX0_STN1_TX_DP<16>")
	)
	(segment
		(start 38.062408 -99.608894)
		(end 38.693852 -99.608894)
		(width 0.13462)
		(layer "F.Cu")
		(net "P5E_PEX0_STN1_TX_DP<16>")
	)
	(segment
		(start 37.767768 -99.314254)
		(end 38.062408 -99.608894)
		(width 0.13462)
		(layer "F.Cu")
		(net "P5E_PEX0_STN1_TX_DP<16>")
	)
	(segment
		(start 59.079638 -271.546066)
		(end 59.079638 -278.205184)
		(width 0.1143)
		(layer "In9.Cu")
		(net "P5E_PEX0_STN1_TX_DP<16>")
	)
	(segment
		(start 28.189174 -106.220006)
		(end 26.122376 -111.209582)
		(width 0.1651)
		(layer "In9.Cu")
		(net "P5E_PEX0_STN1_TX_DP<16>")
	)
	(segment
		(start 22.80539 -145.421858)
		(end 23.515066 -159.875728)
		(width 0.1651)
		(layer "In9.Cu")
		(net "P5E_PEX0_STN1_TX_DP<16>")
	)
	(segment
		(start 36.256722 -99.605084)
		(end 33.776666 -100.632514)
		(width 0.1651)
		(layer "In9.Cu")
		(net "P5E_PEX0_STN1_TX_DP<16>")
	)
	(segment
		(start 23.515066 -159.875728)
		(end 24.079708 -162.714432)
		(width 0.1651)
		(layer "In9.Cu")
		(net "P5E_PEX0_STN1_TX_DP<16>")
	)
	(segment
		(start 59.649614 -278.534368)
		(end 59.649614 -278.799798)
		(width 0.1143)
		(layer "In9.Cu")
		(net "P5E_PEX0_STN1_TX_DP<16>")
	)
	(segment
		(start 26.122376 -111.209582)
		(end 20.205192 -130.71475)
		(width 0.1651)
		(layer "In9.Cu")
		(net "P5E_PEX0_STN1_TX_DP<16>")
	)
	(segment
		(start 59.535314 -278.420068)
		(end 59.649614 -278.534368)
		(width 0.1143)
		(layer "In9.Cu")
		(net "P5E_PEX0_STN1_TX_DP<16>")
	)
	(segment
		(start 59.033918 -265.983974)
		(end 59.033918 -271.471898)
		(width 0.1651)
		(layer "In9.Cu")
		(net "P5E_PEX0_STN1_TX_DP<16>")
	)
	(segment
		(start 59.033918 -271.500346)
		(end 59.079638 -271.546066)
		(width 0.1143)
		(layer "In9.Cu")
		(net "P5E_PEX0_STN1_TX_DP<16>")
	)
	(segment
		(start 37.476938 -99.605084)
		(end 36.256722 -99.605084)
		(width 0.1651)
		(layer "In9.Cu")
		(net "P5E_PEX0_STN1_TX_DP<16>")
	)
	(segment
		(start 59.079638 -278.205184)
		(end 59.294522 -278.420068)
		(width 0.1143)
		(layer "In9.Cu")
		(net "P5E_PEX0_STN1_TX_DP<16>")
	)
	(segment
		(start 24.079708 -162.714432)
		(end 59.033918 -265.983974)
		(width 0.1651)
		(layer "In9.Cu")
		(net "P5E_PEX0_STN1_TX_DP<16>")
	)
	(segment
		(start 37.767768 -99.314254)
		(end 37.476938 -99.605084)
		(width 0.1651)
		(layer "In9.Cu")
		(net "P5E_PEX0_STN1_TX_DP<16>")
	)
	(segment
		(start 59.033918 -271.471898)
		(end 59.033918 -271.500346)
		(width 0.1143)
		(layer "In9.Cu")
		(net "P5E_PEX0_STN1_TX_DP<16>")
	)
	(segment
		(start 20.205192 -130.71475)
		(end 20.205192 -139.143994)
		(width 0.1651)
		(layer "In9.Cu")
		(net "P5E_PEX0_STN1_TX_DP<16>")
	)
	(segment
		(start 33.776666 -100.632514)
		(end 28.189174 -106.220006)
		(width 0.1651)
		(layer "In9.Cu")
		(net "P5E_PEX0_STN1_TX_DP<16>")
	)
	(segment
		(start 20.205192 -139.143994)
		(end 22.80539 -145.421858)
		(width 0.1651)
		(layer "In9.Cu")
		(net "P5E_PEX0_STN1_TX_DP<16>")
	)
	(segment
		(start 59.294522 -278.420068)
		(end 59.535314 -278.420068)
		(width 0.1143)
		(layer "In9.Cu")
		(net "P5E_PEX0_STN1_TX_DP<16>")
	)
	(segment
		(start 30.236922 -409.799028)
		(end 30.618938 -409.799028)
		(width 0.1651)
		(layer "In5.Cu")
		(net "P5E_PEX0_STN7_RX_DP<113>")
	)
	(segment
		(start 23.763478 -307.391562)
		(end 24.997664 -305.544728)
		(width 0.1651)
		(layer "In5.Cu")
		(net "P5E_PEX0_STN7_RX_DP<113>")
	)
	(segment
		(start 30.541976 -395.585696)
		(end 30.541722 -395.585442)
		(width 0.1651)
		(layer "In5.Cu")
		(net "P5E_PEX0_STN7_RX_DP<113>")
	)
	(segment
		(start 18.964656 -318.240918)
		(end 19.332448 -316.852554)
		(width 0.1651)
		(layer "In5.Cu")
		(net "P5E_PEX0_STN7_RX_DP<113>")
	)
	(segment
		(start 15.13586 -351.786952)
		(end 15.13586 -342.187276)
		(width 0.1651)
		(layer "In5.Cu")
		(net "P5E_PEX0_STN7_RX_DP<113>")
	)
	(segment
		(start 35.56 -301.933864)
		(end 35.588448 -301.933864)
		(width 0.1143)
		(layer "In5.Cu")
		(net "P5E_PEX0_STN7_RX_DP<113>")
	)
	(segment
		(start 21.057362 -386.075682)
		(end 17.770856 -369.549426)
		(width 0.1651)
		(layer "In5.Cu")
		(net "P5E_PEX0_STN7_RX_DP<113>")
	)
	(segment
		(start 30.977078 -396.63624)
		(end 30.541976 -395.585696)
		(width 0.1651)
		(layer "In5.Cu")
		(net "P5E_PEX0_STN7_RX_DP<113>")
	)
	(segment
		(start 26.78303 -303.759362)
		(end 29.66974 -302.562514)
		(width 0.1651)
		(layer "In5.Cu")
		(net "P5E_PEX0_STN7_RX_DP<113>")
	)
	(segment
		(start 30.109922 -409.290012)
		(end 30.109922 -409.672028)
		(width 0.1651)
		(layer "In5.Cu")
		(net "P5E_PEX0_STN7_RX_DP<113>")
	)
	(segment
		(start 30.618938 -409.799028)
		(end 30.977078 -409.440888)
		(width 0.1651)
		(layer "In5.Cu")
		(net "P5E_PEX0_STN7_RX_DP<113>")
	)
	(segment
		(start 32.827722 -301.933864)
		(end 35.56 -301.933864)
		(width 0.1651)
		(layer "In5.Cu")
		(net "P5E_PEX0_STN7_RX_DP<113>")
	)
	(segment
		(start 37.420042 -302.20539)
		(end 37.420042 -302.435514)
		(width 0.1143)
		(layer "In5.Cu")
		(net "P5E_PEX0_STN7_RX_DP<113>")
	)
	(segment
		(start 21.484844 -311.654698)
		(end 23.763478 -307.391562)
		(width 0.1651)
		(layer "In5.Cu")
		(net "P5E_PEX0_STN7_RX_DP<113>")
	)
	(segment
		(start 35.634168 -301.979584)
		(end 37.194236 -301.979584)
		(width 0.1143)
		(layer "In5.Cu")
		(net "P5E_PEX0_STN7_RX_DP<113>")
	)
	(segment
		(start 37.420042 -302.435514)
		(end 37.534342 -302.549814)
		(width 0.1143)
		(layer "In5.Cu")
		(net "P5E_PEX0_STN7_RX_DP<113>")
	)
	(segment
		(start 30.106874 -394.535406)
		(end 24.092154 -390.516364)
		(width 0.1651)
		(layer "In5.Cu")
		(net "P5E_PEX0_STN7_RX_DP<113>")
	)
	(segment
		(start 30.109922 -409.672028)
		(end 30.236922 -409.799028)
		(width 0.1651)
		(layer "In5.Cu")
		(net "P5E_PEX0_STN7_RX_DP<113>")
	)
	(segment
		(start 35.588448 -301.933864)
		(end 35.634168 -301.979584)
		(width 0.1143)
		(layer "In5.Cu")
		(net "P5E_PEX0_STN7_RX_DP<113>")
	)
	(segment
		(start 37.534342 -302.549814)
		(end 37.799772 -302.549814)
		(width 0.1143)
		(layer "In5.Cu")
		(net "P5E_PEX0_STN7_RX_DP<113>")
	)
	(segment
		(start 24.997664 -305.544728)
		(end 26.78303 -303.759362)
		(width 0.1651)
		(layer "In5.Cu")
		(net "P5E_PEX0_STN7_RX_DP<113>")
	)
	(segment
		(start 30.541722 -395.585442)
		(end 30.106874 -394.535406)
		(width 0.1651)
		(layer "In5.Cu")
		(net "P5E_PEX0_STN7_RX_DP<113>")
	)
	(segment
		(start 17.770856 -369.549426)
		(end 15.13586 -351.786952)
		(width 0.1651)
		(layer "In5.Cu")
		(net "P5E_PEX0_STN7_RX_DP<113>")
	)
	(segment
		(start 37.194236 -301.979584)
		(end 37.420042 -302.20539)
		(width 0.1143)
		(layer "In5.Cu")
		(net "P5E_PEX0_STN7_RX_DP<113>")
	)
	(segment
		(start 24.092154 -390.516364)
		(end 22.051264 -388.475474)
		(width 0.1651)
		(layer "In5.Cu")
		(net "P5E_PEX0_STN7_RX_DP<113>")
	)
	(segment
		(start 16.528542 -330.895198)
		(end 18.964656 -318.240918)
		(width 0.1651)
		(layer "In5.Cu")
		(net "P5E_PEX0_STN7_RX_DP<113>")
	)
	(segment
		(start 30.977078 -409.440888)
		(end 30.977078 -396.63624)
		(width 0.1651)
		(layer "In5.Cu")
		(net "P5E_PEX0_STN7_RX_DP<113>")
	)
	(segment
		(start 22.051264 -388.475474)
		(end 21.057362 -386.075682)
		(width 0.1651)
		(layer "In5.Cu")
		(net "P5E_PEX0_STN7_RX_DP<113>")
	)
	(segment
		(start 15.13586 -342.187276)
		(end 16.528542 -330.895198)
		(width 0.1651)
		(layer "In5.Cu")
		(net "P5E_PEX0_STN7_RX_DP<113>")
	)
	(segment
		(start 19.332448 -316.852554)
		(end 21.484844 -311.654698)
		(width 0.1651)
		(layer "In5.Cu")
		(net "P5E_PEX0_STN7_RX_DP<113>")
	)
	(segment
		(start 29.66974 -302.562514)
		(end 32.827722 -301.933864)
		(width 0.1651)
		(layer "In5.Cu")
		(net "P5E_PEX0_STN7_RX_DP<113>")
	)
	(segment
		(start 29.228288 -357.46309)
		(end 29.228288 -356.831646)
		(width 0.13462)
		(layer "F.Cu")
		(net "P5E_PEX0_STN7_TX_C_DN<117>")
	)
	(segment
		(start 29.228288 -356.831646)
		(end 29.548328 -356.511606)
		(width 0.13462)
		(layer "F.Cu")
		(net "P5E_PEX0_STN7_TX_C_DN<117>")
	)
	(segment
		(start 29.522928 -357.75773)
		(end 29.228288 -357.46309)
		(width 0.13462)
		(layer "F.Cu")
		(net "P5E_PEX0_STN7_TX_C_DN<117>")
	)
	(segment
		(start 40.084248 -401.876006)
		(end 40.084248 -394.269468)
		(width 0.1651)
		(layer "In7.Cu")
		(net "P5E_PEX0_STN7_TX_C_DN<117>")
	)
	(segment
		(start 25.12441 -367.633504)
		(end 26.297382 -364.948724)
		(width 0.1651)
		(layer "In7.Cu")
		(net "P5E_PEX0_STN7_TX_C_DN<117>")
	)
	(segment
		(start 37.641022 -391.826242)
		(end 26.828242 -387.34746)
		(width 0.1651)
		(layer "In7.Cu")
		(net "P5E_PEX0_STN7_TX_C_DN<117>")
	)
	(segment
		(start 29.232098 -358.04856)
		(end 29.522928 -357.75773)
		(width 0.1651)
		(layer "In7.Cu")
		(net "P5E_PEX0_STN7_TX_C_DN<117>")
	)
	(segment
		(start 24.596344 -379.23343)
		(end 24.596344 -379.232414)
		(width 0.1651)
		(layer "In7.Cu")
		(net "P5E_PEX0_STN7_TX_C_DN<117>")
	)
	(segment
		(start 26.297382 -364.948724)
		(end 29.232098 -358.743758)
		(width 0.1651)
		(layer "In7.Cu")
		(net "P5E_PEX0_STN7_TX_C_DN<117>")
	)
	(segment
		(start 39.679118 -402.281136)
		(end 40.084248 -401.876006)
		(width 0.1651)
		(layer "In7.Cu")
		(net "P5E_PEX0_STN7_TX_C_DN<117>")
	)
	(segment
		(start 26.828242 -387.34746)
		(end 25.742646 -386.261864)
		(width 0.1651)
		(layer "In7.Cu")
		(net "P5E_PEX0_STN7_TX_C_DN<117>")
	)
	(segment
		(start 38.910006 -402.790152)
		(end 38.910006 -402.408136)
		(width 0.1651)
		(layer "In7.Cu")
		(net "P5E_PEX0_STN7_TX_C_DN<117>")
	)
	(segment
		(start 24.907748 -384.405886)
		(end 24.596344 -379.23343)
		(width 0.1651)
		(layer "In7.Cu")
		(net "P5E_PEX0_STN7_TX_C_DN<117>")
	)
	(segment
		(start 40.084248 -394.269468)
		(end 37.641022 -391.826242)
		(width 0.1651)
		(layer "In7.Cu")
		(net "P5E_PEX0_STN7_TX_C_DN<117>")
	)
	(segment
		(start 24.3586 -371.484144)
		(end 25.12441 -367.633504)
		(width 0.1651)
		(layer "In7.Cu")
		(net "P5E_PEX0_STN7_TX_C_DN<117>")
	)
	(segment
		(start 24.596344 -379.232414)
		(end 24.3586 -375.282968)
		(width 0.1651)
		(layer "In7.Cu")
		(net "P5E_PEX0_STN7_TX_C_DN<117>")
	)
	(segment
		(start 29.232098 -358.743758)
		(end 29.232098 -358.04856)
		(width 0.1651)
		(layer "In7.Cu")
		(net "P5E_PEX0_STN7_TX_C_DN<117>")
	)
	(segment
		(start 39.037006 -402.281136)
		(end 39.679118 -402.281136)
		(width 0.1651)
		(layer "In7.Cu")
		(net "P5E_PEX0_STN7_TX_C_DN<117>")
	)
	(segment
		(start 25.742646 -386.261864)
		(end 24.907748 -384.405886)
		(width 0.1651)
		(layer "In7.Cu")
		(net "P5E_PEX0_STN7_TX_C_DN<117>")
	)
	(segment
		(start 24.3586 -375.282968)
		(end 24.3586 -371.484144)
		(width 0.1651)
		(layer "In7.Cu")
		(net "P5E_PEX0_STN7_TX_C_DN<117>")
	)
	(segment
		(start 38.910006 -402.408136)
		(end 39.037006 -402.281136)
		(width 0.1651)
		(layer "In7.Cu")
		(net "P5E_PEX0_STN7_TX_C_DN<117>")
	)
	(segment
		(start 38.062408 -103.208836)
		(end 37.767768 -102.914196)
		(width 0.13462)
		(layer "F.Cu")
		(net "P5E_PEX0_STN1_TX_DP<18>")
	)
	(segment
		(start 38.693852 -103.208836)
		(end 38.062408 -103.208836)
		(width 0.13462)
		(layer "F.Cu")
		(net "P5E_PEX0_STN1_TX_DP<18>")
	)
	(segment
		(start 39.013892 -102.888796)
		(end 38.693852 -103.208836)
		(width 0.13462)
		(layer "F.Cu")
		(net "P5E_PEX0_STN1_TX_DP<18>")
	)
	(segment
		(start 25.25268 -155.81503)
		(end 25.432004 -159.462978)
		(width 0.1651)
		(layer "In9.Cu")
		(net "P5E_PEX0_STN1_TX_DP<18>")
	)
	(segment
		(start 60.933838 -265.558016)
		(end 60.933838 -271.471898)
		(width 0.1651)
		(layer "In9.Cu")
		(net "P5E_PEX0_STN1_TX_DP<18>")
	)
	(segment
		(start 33.567116 -104.068118)
		(end 29.954982 -107.680252)
		(width 0.1651)
		(layer "In9.Cu")
		(net "P5E_PEX0_STN1_TX_DP<18>")
	)
	(segment
		(start 37.476938 -103.205026)
		(end 35.650678 -103.205026)
		(width 0.1651)
		(layer "In9.Cu")
		(net "P5E_PEX0_STN1_TX_DP<18>")
	)
	(segment
		(start 34.522156 -103.672386)
		(end 34.52241 -103.672386)
		(width 0.1651)
		(layer "In9.Cu")
		(net "P5E_PEX0_STN1_TX_DP<18>")
	)
	(segment
		(start 60.933838 -271.500346)
		(end 60.979558 -271.546066)
		(width 0.1143)
		(layer "In9.Cu")
		(net "P5E_PEX0_STN1_TX_DP<18>")
	)
	(segment
		(start 25.432004 -159.462978)
		(end 26.015442 -162.39617)
		(width 0.1651)
		(layer "In9.Cu")
		(net "P5E_PEX0_STN1_TX_DP<18>")
	)
	(segment
		(start 27.131264 -114.497612)
		(end 22.140672 -130.948938)
		(width 0.1651)
		(layer "In9.Cu")
		(net "P5E_PEX0_STN1_TX_DP<18>")
	)
	(segment
		(start 34.52241 -103.672386)
		(end 33.567116 -104.068118)
		(width 0.1651)
		(layer "In9.Cu")
		(net "P5E_PEX0_STN1_TX_DP<18>")
	)
	(segment
		(start 26.015442 -162.39617)
		(end 60.933838 -265.558016)
		(width 0.1651)
		(layer "In9.Cu")
		(net "P5E_PEX0_STN1_TX_DP<18>")
	)
	(segment
		(start 60.933838 -271.471898)
		(end 60.933838 -271.500346)
		(width 0.1143)
		(layer "In9.Cu")
		(net "P5E_PEX0_STN1_TX_DP<18>")
	)
	(segment
		(start 61.549534 -278.534368)
		(end 61.549534 -278.799798)
		(width 0.1143)
		(layer "In9.Cu")
		(net "P5E_PEX0_STN1_TX_DP<18>")
	)
	(segment
		(start 29.954982 -107.680252)
		(end 27.131264 -114.497612)
		(width 0.1651)
		(layer "In9.Cu")
		(net "P5E_PEX0_STN1_TX_DP<18>")
	)
	(segment
		(start 60.979558 -278.205184)
		(end 61.194442 -278.420068)
		(width 0.1143)
		(layer "In9.Cu")
		(net "P5E_PEX0_STN1_TX_DP<18>")
	)
	(segment
		(start 22.140672 -130.948938)
		(end 22.140672 -138.693652)
		(width 0.1651)
		(layer "In9.Cu")
		(net "P5E_PEX0_STN1_TX_DP<18>")
	)
	(segment
		(start 24.716486 -144.912588)
		(end 25.25268 -155.81503)
		(width 0.1651)
		(layer "In9.Cu")
		(net "P5E_PEX0_STN1_TX_DP<18>")
	)
	(segment
		(start 35.650678 -103.205026)
		(end 34.522156 -103.672386)
		(width 0.1651)
		(layer "In9.Cu")
		(net "P5E_PEX0_STN1_TX_DP<18>")
	)
	(segment
		(start 37.767768 -102.914196)
		(end 37.476938 -103.205026)
		(width 0.1651)
		(layer "In9.Cu")
		(net "P5E_PEX0_STN1_TX_DP<18>")
	)
	(segment
		(start 61.435234 -278.420068)
		(end 61.549534 -278.534368)
		(width 0.1143)
		(layer "In9.Cu")
		(net "P5E_PEX0_STN1_TX_DP<18>")
	)
	(segment
		(start 22.140672 -138.693652)
		(end 24.716486 -144.912588)
		(width 0.1651)
		(layer "In9.Cu")
		(net "P5E_PEX0_STN1_TX_DP<18>")
	)
	(segment
		(start 61.194442 -278.420068)
		(end 61.435234 -278.420068)
		(width 0.1143)
		(layer "In9.Cu")
		(net "P5E_PEX0_STN1_TX_DP<18>")
	)
	(segment
		(start 60.979558 -271.546066)
		(end 60.979558 -278.205184)
		(width 0.1143)
		(layer "In9.Cu")
		(net "P5E_PEX0_STN1_TX_DP<18>")
	)
	(segment
		(start 37.3126 -394.456412)
		(end 33.663382 -392.017758)
		(width 0.1651)
		(layer "In5.Cu")
		(net "P5E_PEX0_STN7_RX_DN<116>")
	)
	(segment
		(start 24.941784 -312.61812)
		(end 25.09647 -312.57113)
		(width 0.1651)
		(layer "In5.Cu")
		(net "P5E_PEX0_STN7_RX_DN<116>")
	)
	(segment
		(start 35.588448 -305.065938)
		(end 35.634168 -305.020218)
		(width 0.1143)
		(layer "In5.Cu")
		(net "P5E_PEX0_STN7_RX_DN<116>")
	)
	(segment
		(start 33.663382 -392.017758)
		(end 25.939242 -387.889242)
		(width 0.1651)
		(layer "In5.Cu")
		(net "P5E_PEX0_STN7_RX_DN<116>")
	)
	(segment
		(start 37.858954 -408.40533)
		(end 37.858954 -395.49451)
		(width 0.1651)
		(layer "In5.Cu")
		(net "P5E_PEX0_STN7_RX_DN<116>")
	)
	(segment
		(start 25.09647 -312.57113)
		(end 25.33015 -312.13425)
		(width 0.1651)
		(layer "In5.Cu")
		(net "P5E_PEX0_STN7_RX_DN<116>")
	)
	(segment
		(start 25.671526 -311.495948)
		(end 25.905206 -311.058814)
		(width 0.1651)
		(layer "In5.Cu")
		(net "P5E_PEX0_STN7_RX_DN<116>")
	)
	(segment
		(start 39.015416 -305.399948)
		(end 38.749986 -305.399948)
		(width 0.1143)
		(layer "In5.Cu")
		(net "P5E_PEX0_STN7_RX_DN<116>")
	)
	(segment
		(start 39.129716 -305.134518)
		(end 39.129716 -305.285648)
		(width 0.1143)
		(layer "In5.Cu")
		(net "P5E_PEX0_STN7_RX_DN<116>")
	)
	(segment
		(start 36.710112 -409.490164)
		(end 36.710112 -409.108148)
		(width 0.1651)
		(layer "In5.Cu")
		(net "P5E_PEX0_STN7_RX_DN<116>")
	)
	(segment
		(start 36.710112 -409.108148)
		(end 36.837112 -408.981148)
		(width 0.1651)
		(layer "In5.Cu")
		(net "P5E_PEX0_STN7_RX_DN<116>")
	)
	(segment
		(start 21.034756 -369.735608)
		(end 18.3388 -351.561908)
		(width 0.1651)
		(layer "In5.Cu")
		(net "P5E_PEX0_STN7_RX_DN<116>")
	)
	(segment
		(start 23.539958 -315.490352)
		(end 24.56434 -313.324494)
		(width 0.1651)
		(layer "In5.Cu")
		(net "P5E_PEX0_STN7_RX_DN<116>")
	)
	(segment
		(start 21.127974 -326.137778)
		(end 21.975572 -319.26784)
		(width 0.1651)
		(layer "In5.Cu")
		(net "P5E_PEX0_STN7_RX_DN<116>")
	)
	(segment
		(start 36.837112 -408.981148)
		(end 37.283136 -408.981148)
		(width 0.1651)
		(layer "In5.Cu")
		(net "P5E_PEX0_STN7_RX_DN<116>")
	)
	(segment
		(start 28.725622 -307.156358)
		(end 29.61005 -306.27193)
		(width 0.1651)
		(layer "In5.Cu")
		(net "P5E_PEX0_STN7_RX_DN<116>")
	)
	(segment
		(start 24.823674 -386.773674)
		(end 24.054816 -384.918204)
		(width 0.1651)
		(layer "In5.Cu")
		(net "P5E_PEX0_STN7_RX_DN<116>")
	)
	(segment
		(start 25.939242 -387.889242)
		(end 24.823674 -386.773674)
		(width 0.1651)
		(layer "In5.Cu")
		(net "P5E_PEX0_STN7_RX_DN<116>")
	)
	(segment
		(start 37.283136 -408.981148)
		(end 37.858954 -408.40533)
		(width 0.1651)
		(layer "In5.Cu")
		(net "P5E_PEX0_STN7_RX_DN<116>")
	)
	(segment
		(start 18.3388 -341.94369)
		(end 21.127974 -326.137778)
		(width 0.1651)
		(layer "In5.Cu")
		(net "P5E_PEX0_STN7_RX_DN<116>")
	)
	(segment
		(start 28.213558 -307.668422)
		(end 28.375102 -307.668422)
		(width 0.1651)
		(layer "In5.Cu")
		(net "P5E_PEX0_STN7_RX_DN<116>")
	)
	(segment
		(start 25.33015 -312.13425)
		(end 25.283414 -311.979564)
		(width 0.1651)
		(layer "In5.Cu")
		(net "P5E_PEX0_STN7_RX_DN<116>")
	)
	(segment
		(start 26.868628 -309.013352)
		(end 28.213558 -307.668422)
		(width 0.1651)
		(layer "In5.Cu")
		(net "P5E_PEX0_STN7_RX_DN<116>")
	)
	(segment
		(start 39.015416 -305.020218)
		(end 39.129716 -305.134518)
		(width 0.1143)
		(layer "In5.Cu")
		(net "P5E_PEX0_STN7_RX_DN<116>")
	)
	(segment
		(start 35.634168 -305.020218)
		(end 39.015416 -305.020218)
		(width 0.1143)
		(layer "In5.Cu")
		(net "P5E_PEX0_STN7_RX_DN<116>")
	)
	(segment
		(start 28.375102 -307.668422)
		(end 28.725622 -307.317902)
		(width 0.1651)
		(layer "In5.Cu")
		(net "P5E_PEX0_STN7_RX_DN<116>")
	)
	(segment
		(start 39.129716 -305.285648)
		(end 39.015416 -305.399948)
		(width 0.1143)
		(layer "In5.Cu")
		(net "P5E_PEX0_STN7_RX_DN<116>")
	)
	(segment
		(start 25.905206 -311.058814)
		(end 25.858216 -310.904128)
		(width 0.1651)
		(layer "In5.Cu")
		(net "P5E_PEX0_STN7_RX_DN<116>")
	)
	(segment
		(start 34.00933 -305.065938)
		(end 35.56 -305.065938)
		(width 0.1651)
		(layer "In5.Cu")
		(net "P5E_PEX0_STN7_RX_DN<116>")
	)
	(segment
		(start 24.56434 -313.324494)
		(end 24.941784 -312.61812)
		(width 0.1651)
		(layer "In5.Cu")
		(net "P5E_PEX0_STN7_RX_DN<116>")
	)
	(segment
		(start 25.51684 -311.542938)
		(end 25.671526 -311.495948)
		(width 0.1651)
		(layer "In5.Cu")
		(net "P5E_PEX0_STN7_RX_DN<116>")
	)
	(segment
		(start 21.975572 -319.26784)
		(end 23.539958 -315.490352)
		(width 0.1651)
		(layer "In5.Cu")
		(net "P5E_PEX0_STN7_RX_DN<116>")
	)
	(segment
		(start 24.054816 -384.918204)
		(end 21.034756 -369.735608)
		(width 0.1651)
		(layer "In5.Cu")
		(net "P5E_PEX0_STN7_RX_DN<116>")
	)
	(segment
		(start 28.725622 -307.317902)
		(end 28.725622 -307.156358)
		(width 0.1651)
		(layer "In5.Cu")
		(net "P5E_PEX0_STN7_RX_DN<116>")
	)
	(segment
		(start 35.56 -305.065938)
		(end 35.588448 -305.065938)
		(width 0.1143)
		(layer "In5.Cu")
		(net "P5E_PEX0_STN7_RX_DN<116>")
	)
	(segment
		(start 37.858954 -395.49451)
		(end 37.511228 -394.65504)
		(width 0.1651)
		(layer "In5.Cu")
		(net "P5E_PEX0_STN7_RX_DN<116>")
	)
	(segment
		(start 25.858216 -310.904128)
		(end 26.868628 -309.013352)
		(width 0.1651)
		(layer "In5.Cu")
		(net "P5E_PEX0_STN7_RX_DN<116>")
	)
	(segment
		(start 37.511228 -394.65504)
		(end 37.3126 -394.456412)
		(width 0.1651)
		(layer "In5.Cu")
		(net "P5E_PEX0_STN7_RX_DN<116>")
	)
	(segment
		(start 31.145988 -305.63566)
		(end 34.00933 -305.065938)
		(width 0.1651)
		(layer "In5.Cu")
		(net "P5E_PEX0_STN7_RX_DN<116>")
	)
	(segment
		(start 29.61005 -306.27193)
		(end 31.145988 -305.63566)
		(width 0.1651)
		(layer "In5.Cu")
		(net "P5E_PEX0_STN7_RX_DN<116>")
	)
	(segment
		(start 25.283414 -311.979564)
		(end 25.51684 -311.542938)
		(width 0.1651)
		(layer "In5.Cu")
		(net "P5E_PEX0_STN7_RX_DN<116>")
	)
	(segment
		(start 18.3388 -351.561908)
		(end 18.3388 -341.94369)
		(width 0.1651)
		(layer "In5.Cu")
		(net "P5E_PEX0_STN7_RX_DN<116>")
	)
	(segment
		(start 80.286098 -154.304746)
		(end 80.606138 -153.984706)
		(width 0.13462)
		(layer "F.Cu")
		(net "P5E_PEX0_STN0_TX_DN<14>")
	)
	(segment
		(start 80.606138 -153.984706)
		(end 81.237582 -153.984706)
		(width 0.13462)
		(layer "F.Cu")
		(net "P5E_PEX0_STN0_TX_DN<14>")
	)
	(segment
		(start 81.237582 -153.984706)
		(end 81.532222 -154.279346)
		(width 0.13462)
		(layer "F.Cu")
		(net "P5E_PEX0_STN0_TX_DN<14>")
	)
	(segment
		(start 76.357988 -178.608736)
		(end 76.234036 -178.712622)
		(width 0.1651)
		(layer "In9.Cu")
		(net "P5E_PEX0_STN0_TX_DN<14>")
	)
	(segment
		(start 78.02499 -171.164758)
		(end 76.516738 -176.794414)
		(width 0.1651)
		(layer "In9.Cu")
		(net "P5E_PEX0_STN0_TX_DN<14>")
	)
	(segment
		(start 76.234036 -178.712622)
		(end 76.191872 -179.193698)
		(width 0.1651)
		(layer "In9.Cu")
		(net "P5E_PEX0_STN0_TX_DN<14>")
	)
	(segment
		(start 76.466446 -177.371248)
		(end 76.34224 -177.475134)
		(width 0.1651)
		(layer "In9.Cu")
		(net "P5E_PEX0_STN0_TX_DN<14>")
	)
	(segment
		(start 75.184 -271.526)
		(end 75.184 -271.554448)
		(width 0.1143)
		(layer "In9.Cu")
		(net "P5E_PEX0_STN0_TX_DN<14>")
	)
	(segment
		(start 86.08695 -155.254706)
		(end 86.341204 -155.868624)
		(width 0.1651)
		(layer "In9.Cu")
		(net "P5E_PEX0_STN0_TX_DN<14>")
	)
	(segment
		(start 75.68565 -280.319988)
		(end 75.79995 -280.434288)
		(width 0.1143)
		(layer "In9.Cu")
		(net "P5E_PEX0_STN0_TX_DN<14>")
	)
	(segment
		(start 81.823052 -153.988516)
		(end 84.82076 -153.988516)
		(width 0.1651)
		(layer "In9.Cu")
		(net "P5E_PEX0_STN0_TX_DN<14>")
	)
	(segment
		(start 75.22972 -271.600168)
		(end 75.22972 -280.10485)
		(width 0.1143)
		(layer "In9.Cu")
		(net "P5E_PEX0_STN0_TX_DN<14>")
	)
	(segment
		(start 76.295758 -179.317396)
		(end 76.296012 -179.31765)
		(width 0.1651)
		(layer "In9.Cu")
		(net "P5E_PEX0_STN0_TX_DN<14>")
	)
	(segment
		(start 76.076048 -260.679438)
		(end 76.076048 -267.60424)
		(width 0.1651)
		(layer "In9.Cu")
		(net "P5E_PEX0_STN0_TX_DN<14>")
	)
	(segment
		(start 75.184 -271.554448)
		(end 75.22972 -271.600168)
		(width 0.1143)
		(layer "In9.Cu")
		(net "P5E_PEX0_STN0_TX_DN<14>")
	)
	(segment
		(start 76.516738 -176.794414)
		(end 76.466446 -177.371248)
		(width 0.1651)
		(layer "In9.Cu")
		(net "P5E_PEX0_STN0_TX_DN<14>")
	)
	(segment
		(start 86.341204 -156.760164)
		(end 78.02499 -171.164758)
		(width 0.1651)
		(layer "In9.Cu")
		(net "P5E_PEX0_STN0_TX_DN<14>")
	)
	(segment
		(start 75.22972 -280.10485)
		(end 75.444858 -280.319988)
		(width 0.1143)
		(layer "In9.Cu")
		(net "P5E_PEX0_STN0_TX_DN<14>")
	)
	(segment
		(start 81.532222 -154.279346)
		(end 81.823052 -153.988516)
		(width 0.1651)
		(layer "In9.Cu")
		(net "P5E_PEX0_STN0_TX_DN<14>")
	)
	(segment
		(start 76.296012 -179.31765)
		(end 72.627744 -221.249748)
		(width 0.1651)
		(layer "In9.Cu")
		(net "P5E_PEX0_STN0_TX_DN<14>")
	)
	(segment
		(start 76.30033 -177.95621)
		(end 76.404216 -178.080162)
		(width 0.1651)
		(layer "In9.Cu")
		(net "P5E_PEX0_STN0_TX_DN<14>")
	)
	(segment
		(start 75.444858 -280.319988)
		(end 75.68565 -280.319988)
		(width 0.1143)
		(layer "In9.Cu")
		(net "P5E_PEX0_STN0_TX_DN<14>")
	)
	(segment
		(start 75.184 -269.758414)
		(end 75.184 -271.526)
		(width 0.1651)
		(layer "In9.Cu")
		(net "P5E_PEX0_STN0_TX_DN<14>")
	)
	(segment
		(start 75.79995 -280.434288)
		(end 75.79995 -280.699718)
		(width 0.1143)
		(layer "In9.Cu")
		(net "P5E_PEX0_STN0_TX_DN<14>")
	)
	(segment
		(start 86.341204 -155.868624)
		(end 86.341204 -156.760164)
		(width 0.1651)
		(layer "In9.Cu")
		(net "P5E_PEX0_STN0_TX_DN<14>")
	)
	(segment
		(start 76.191872 -179.193698)
		(end 76.295758 -179.317396)
		(width 0.1651)
		(layer "In9.Cu")
		(net "P5E_PEX0_STN0_TX_DN<14>")
	)
	(segment
		(start 76.404216 -178.080162)
		(end 76.357988 -178.608736)
		(width 0.1651)
		(layer "In9.Cu")
		(net "P5E_PEX0_STN0_TX_DN<14>")
	)
	(segment
		(start 84.82076 -153.988516)
		(end 86.08695 -155.254706)
		(width 0.1651)
		(layer "In9.Cu")
		(net "P5E_PEX0_STN0_TX_DN<14>")
	)
	(segment
		(start 72.627744 -221.249748)
		(end 76.076048 -260.679438)
		(width 0.1651)
		(layer "In9.Cu")
		(net "P5E_PEX0_STN0_TX_DN<14>")
	)
	(segment
		(start 76.076048 -267.60424)
		(end 75.184 -269.758414)
		(width 0.1651)
		(layer "In9.Cu")
		(net "P5E_PEX0_STN0_TX_DN<14>")
	)
	(segment
		(start 76.34224 -177.475134)
		(end 76.30033 -177.95621)
		(width 0.1651)
		(layer "In9.Cu")
		(net "P5E_PEX0_STN0_TX_DN<14>")
	)
	(segment
		(start 22.484334 -310.38292)
		(end 22.71776 -309.946294)
		(width 0.1651)
		(layer "In5.Cu")
		(net "P5E_PEX0_STN7_RX_DN<113>")
	)
	(segment
		(start 30.334712 -394.348462)
		(end 24.271986 -390.297416)
		(width 0.1651)
		(layer "In5.Cu")
		(net "P5E_PEX0_STN7_RX_DN<113>")
	)
	(segment
		(start 24.005794 -307.53685)
		(end 25.216612 -305.72456)
		(width 0.1651)
		(layer "In5.Cu")
		(net "P5E_PEX0_STN7_RX_DN<113>")
	)
	(segment
		(start 22.855174 -309.904638)
		(end 23.088854 -309.467758)
		(width 0.1651)
		(layer "In5.Cu")
		(net "P5E_PEX0_STN7_RX_DN<113>")
	)
	(segment
		(start 18.048732 -369.501166)
		(end 15.4178 -351.766124)
		(width 0.1651)
		(layer "In5.Cu")
		(net "P5E_PEX0_STN7_RX_DN<113>")
	)
	(segment
		(start 27.533092 -303.863756)
		(end 27.9908 -303.673764)
		(width 0.1651)
		(layer "In5.Cu")
		(net "P5E_PEX0_STN7_RX_DN<113>")
	)
	(segment
		(start 31.259018 -409.557728)
		(end 31.259018 -396.580106)
		(width 0.1651)
		(layer "In5.Cu")
		(net "P5E_PEX0_STN7_RX_DN<113>")
	)
	(segment
		(start 27.9908 -303.673764)
		(end 28.045664 -303.541176)
		(width 0.1651)
		(layer "In5.Cu")
		(net "P5E_PEX0_STN7_RX_DN<113>")
	)
	(segment
		(start 22.52599 -310.520588)
		(end 22.484334 -310.38292)
		(width 0.1651)
		(layer "In5.Cu")
		(net "P5E_PEX0_STN7_RX_DN<113>")
	)
	(segment
		(start 31.259018 -396.580106)
		(end 30.334712 -394.348462)
		(width 0.1651)
		(layer "In5.Cu")
		(net "P5E_PEX0_STN7_RX_DN<113>")
	)
	(segment
		(start 32.855662 -302.215804)
		(end 35.56 -302.215804)
		(width 0.1651)
		(layer "In5.Cu")
		(net "P5E_PEX0_STN7_RX_DN<113>")
	)
	(segment
		(start 22.71776 -309.946294)
		(end 22.855174 -309.904638)
		(width 0.1651)
		(layer "In5.Cu")
		(net "P5E_PEX0_STN7_RX_DN<113>")
	)
	(segment
		(start 19.600164 -316.942978)
		(end 21.740114 -311.775348)
		(width 0.1651)
		(layer "In5.Cu")
		(net "P5E_PEX0_STN7_RX_DN<113>")
	)
	(segment
		(start 23.610062 -308.277006)
		(end 24.005794 -307.53685)
		(width 0.1651)
		(layer "In5.Cu")
		(net "P5E_PEX0_STN7_RX_DN<113>")
	)
	(segment
		(start 26.942796 -303.998376)
		(end 27.40025 -303.808892)
		(width 0.1651)
		(layer "In5.Cu")
		(net "P5E_PEX0_STN7_RX_DN<113>")
	)
	(segment
		(start 28.045664 -303.541176)
		(end 28.503118 -303.351692)
		(width 0.1651)
		(layer "In5.Cu")
		(net "P5E_PEX0_STN7_RX_DN<113>")
	)
	(segment
		(start 37.115242 -302.170084)
		(end 37.229542 -302.284384)
		(width 0.1143)
		(layer "In5.Cu")
		(net "P5E_PEX0_STN7_RX_DN<113>")
	)
	(segment
		(start 22.154896 -310.999378)
		(end 22.29231 -310.957468)
		(width 0.1651)
		(layer "In5.Cu")
		(net "P5E_PEX0_STN7_RX_DN<113>")
	)
	(segment
		(start 26.70683 -304.234342)
		(end 26.942796 -303.998376)
		(width 0.1651)
		(layer "In5.Cu")
		(net "P5E_PEX0_STN7_RX_DN<113>")
	)
	(segment
		(start 26.3652 -304.73396)
		(end 26.70683 -304.39233)
		(width 0.1651)
		(layer "In5.Cu")
		(net "P5E_PEX0_STN7_RX_DN<113>")
	)
	(segment
		(start 19.239738 -318.303656)
		(end 19.600164 -316.942978)
		(width 0.1651)
		(layer "In5.Cu")
		(net "P5E_PEX0_STN7_RX_DN<113>")
	)
	(segment
		(start 35.56 -302.215804)
		(end 35.588448 -302.215804)
		(width 0.1143)
		(layer "In5.Cu")
		(net "P5E_PEX0_STN7_RX_DN<113>")
	)
	(segment
		(start 30.109922 -410.589984)
		(end 30.109922 -410.207968)
		(width 0.1651)
		(layer "In5.Cu")
		(net "P5E_PEX0_STN7_RX_DN<113>")
	)
	(segment
		(start 25.216612 -305.72456)
		(end 26.207212 -304.73396)
		(width 0.1651)
		(layer "In5.Cu")
		(net "P5E_PEX0_STN7_RX_DN<113>")
	)
	(segment
		(start 26.207212 -304.73396)
		(end 26.3652 -304.73396)
		(width 0.1651)
		(layer "In5.Cu")
		(net "P5E_PEX0_STN7_RX_DN<113>")
	)
	(segment
		(start 22.290278 -388.315708)
		(end 21.328634 -385.993386)
		(width 0.1651)
		(layer "In5.Cu")
		(net "P5E_PEX0_STN7_RX_DN<113>")
	)
	(segment
		(start 35.588448 -302.215804)
		(end 35.634168 -302.170084)
		(width 0.1143)
		(layer "In5.Cu")
		(net "P5E_PEX0_STN7_RX_DN<113>")
	)
	(segment
		(start 15.4178 -351.766124)
		(end 15.4178 -342.204802)
		(width 0.1651)
		(layer "In5.Cu")
		(net "P5E_PEX0_STN7_RX_DN<113>")
	)
	(segment
		(start 23.088854 -309.467758)
		(end 23.047198 -309.33009)
		(width 0.1651)
		(layer "In5.Cu")
		(net "P5E_PEX0_STN7_RX_DN<113>")
	)
	(segment
		(start 21.328634 -385.993386)
		(end 18.048732 -369.501166)
		(width 0.1651)
		(layer "In5.Cu")
		(net "P5E_PEX0_STN7_RX_DN<113>")
	)
	(segment
		(start 29.752036 -302.833786)
		(end 32.855662 -302.215804)
		(width 0.1651)
		(layer "In5.Cu")
		(net "P5E_PEX0_STN7_RX_DN<113>")
	)
	(segment
		(start 35.634168 -302.170084)
		(end 37.115242 -302.170084)
		(width 0.1143)
		(layer "In5.Cu")
		(net "P5E_PEX0_STN7_RX_DN<113>")
	)
	(segment
		(start 37.115242 -302.549814)
		(end 36.849812 -302.549814)
		(width 0.1143)
		(layer "In5.Cu")
		(net "P5E_PEX0_STN7_RX_DN<113>")
	)
	(segment
		(start 28.63596 -303.406556)
		(end 29.093668 -303.216564)
		(width 0.1651)
		(layer "In5.Cu")
		(net "P5E_PEX0_STN7_RX_DN<113>")
	)
	(segment
		(start 23.280624 -308.893464)
		(end 23.418038 -308.851554)
		(width 0.1651)
		(layer "In5.Cu")
		(net "P5E_PEX0_STN7_RX_DN<113>")
	)
	(segment
		(start 27.40025 -303.808892)
		(end 27.533092 -303.863756)
		(width 0.1651)
		(layer "In5.Cu")
		(net "P5E_PEX0_STN7_RX_DN<113>")
	)
	(segment
		(start 28.503118 -303.351692)
		(end 28.63596 -303.406556)
		(width 0.1651)
		(layer "In5.Cu")
		(net "P5E_PEX0_STN7_RX_DN<113>")
	)
	(segment
		(start 22.29231 -310.957468)
		(end 22.52599 -310.520588)
		(width 0.1651)
		(layer "In5.Cu")
		(net "P5E_PEX0_STN7_RX_DN<113>")
	)
	(segment
		(start 30.735778 -410.080968)
		(end 31.259018 -409.557728)
		(width 0.1651)
		(layer "In5.Cu")
		(net "P5E_PEX0_STN7_RX_DN<113>")
	)
	(segment
		(start 30.236922 -410.080968)
		(end 30.735778 -410.080968)
		(width 0.1651)
		(layer "In5.Cu")
		(net "P5E_PEX0_STN7_RX_DN<113>")
	)
	(segment
		(start 37.229542 -302.284384)
		(end 37.229542 -302.435514)
		(width 0.1143)
		(layer "In5.Cu")
		(net "P5E_PEX0_STN7_RX_DN<113>")
	)
	(segment
		(start 29.148532 -303.083976)
		(end 29.752036 -302.833786)
		(width 0.1651)
		(layer "In5.Cu")
		(net "P5E_PEX0_STN7_RX_DN<113>")
	)
	(segment
		(start 29.093668 -303.216564)
		(end 29.148532 -303.083976)
		(width 0.1651)
		(layer "In5.Cu")
		(net "P5E_PEX0_STN7_RX_DN<113>")
	)
	(segment
		(start 23.047198 -309.33009)
		(end 23.280624 -308.893464)
		(width 0.1651)
		(layer "In5.Cu")
		(net "P5E_PEX0_STN7_RX_DN<113>")
	)
	(segment
		(start 30.109922 -410.207968)
		(end 30.236922 -410.080968)
		(width 0.1651)
		(layer "In5.Cu")
		(net "P5E_PEX0_STN7_RX_DN<113>")
	)
	(segment
		(start 23.651972 -308.414674)
		(end 23.610062 -308.277006)
		(width 0.1651)
		(layer "In5.Cu")
		(net "P5E_PEX0_STN7_RX_DN<113>")
	)
	(segment
		(start 16.807434 -330.93914)
		(end 19.239738 -318.303656)
		(width 0.1651)
		(layer "In5.Cu")
		(net "P5E_PEX0_STN7_RX_DN<113>")
	)
	(segment
		(start 37.229542 -302.435514)
		(end 37.115242 -302.549814)
		(width 0.1143)
		(layer "In5.Cu")
		(net "P5E_PEX0_STN7_RX_DN<113>")
	)
	(segment
		(start 15.4178 -342.204802)
		(end 16.807434 -330.93914)
		(width 0.1651)
		(layer "In5.Cu")
		(net "P5E_PEX0_STN7_RX_DN<113>")
	)
	(segment
		(start 26.70683 -304.39233)
		(end 26.70683 -304.234342)
		(width 0.1651)
		(layer "In5.Cu")
		(net "P5E_PEX0_STN7_RX_DN<113>")
	)
	(segment
		(start 21.740114 -311.775348)
		(end 22.154896 -310.999378)
		(width 0.1651)
		(layer "In5.Cu")
		(net "P5E_PEX0_STN7_RX_DN<113>")
	)
	(segment
		(start 23.418038 -308.851554)
		(end 23.651972 -308.414674)
		(width 0.1651)
		(layer "In5.Cu")
		(net "P5E_PEX0_STN7_RX_DN<113>")
	)
	(segment
		(start 24.271986 -390.297416)
		(end 22.290278 -388.315708)
		(width 0.1651)
		(layer "In5.Cu")
		(net "P5E_PEX0_STN7_RX_DN<113>")
	)
	(segment
		(start 28.953968 -357.46309)
		(end 28.953968 -356.831646)
		(width 0.13462)
		(layer "F.Cu")
		(net "P5E_PEX0_STN7_TX_C_DP<117>")
	)
	(segment
		(start 28.659328 -357.75773)
		(end 28.953968 -357.46309)
		(width 0.13462)
		(layer "F.Cu")
		(net "P5E_PEX0_STN7_TX_C_DP<117>")
	)
	(segment
		(start 28.953968 -356.831646)
		(end 28.633928 -356.511606)
		(width 0.13462)
		(layer "F.Cu")
		(net "P5E_PEX0_STN7_TX_C_DP<117>")
	)
	(segment
		(start 39.802308 -394.386308)
		(end 39.802308 -401.759166)
		(width 0.1651)
		(layer "In7.Cu")
		(net "P5E_PEX0_STN7_TX_C_DP<117>")
	)
	(segment
		(start 24.307292 -379.127766)
		(end 24.314658 -379.24994)
		(width 0.1651)
		(layer "In7.Cu")
		(net "P5E_PEX0_STN7_TX_C_DP<117>")
	)
	(segment
		(start 24.314658 -379.24994)
		(end 24.314912 -379.250448)
		(width 0.1651)
		(layer "In7.Cu")
		(net "P5E_PEX0_STN7_TX_C_DP<117>")
	)
	(segment
		(start 26.668476 -387.586474)
		(end 37.481256 -392.065256)
		(width 0.1651)
		(layer "In7.Cu")
		(net "P5E_PEX0_STN7_TX_C_DP<117>")
	)
	(segment
		(start 37.481256 -392.065256)
		(end 38.293802 -392.877802)
		(width 0.1651)
		(layer "In7.Cu")
		(net "P5E_PEX0_STN7_TX_C_DP<117>")
	)
	(segment
		(start 38.293802 -392.877802)
		(end 38.293802 -393.003532)
		(width 0.1651)
		(layer "In7.Cu")
		(net "P5E_PEX0_STN7_TX_C_DP<117>")
	)
	(segment
		(start 24.852884 -367.551208)
		(end 24.853138 -367.551208)
		(width 0.1651)
		(layer "In7.Cu")
		(net "P5E_PEX0_STN7_TX_C_DP<117>")
	)
	(segment
		(start 24.853646 -367.548414)
		(end 24.852884 -367.551208)
		(width 0.1651)
		(layer "In7.Cu")
		(net "P5E_PEX0_STN7_TX_C_DP<117>")
	)
	(segment
		(start 38.293802 -393.003532)
		(end 38.644068 -393.353798)
		(width 0.1651)
		(layer "In7.Cu")
		(net "P5E_PEX0_STN7_TX_C_DP<117>")
	)
	(segment
		(start 39.802308 -401.759166)
		(end 39.562278 -401.999196)
		(width 0.1651)
		(layer "In7.Cu")
		(net "P5E_PEX0_STN7_TX_C_DP<117>")
	)
	(segment
		(start 24.314912 -379.250448)
		(end 24.629364 -384.474466)
		(width 0.1651)
		(layer "In7.Cu")
		(net "P5E_PEX0_STN7_TX_C_DP<117>")
	)
	(segment
		(start 28.950158 -358.04856)
		(end 28.950158 -358.680258)
		(width 0.1651)
		(layer "In7.Cu")
		(net "P5E_PEX0_STN7_TX_C_DP<117>")
	)
	(segment
		(start 39.562278 -401.999196)
		(end 39.037006 -401.999196)
		(width 0.1651)
		(layer "In7.Cu")
		(net "P5E_PEX0_STN7_TX_C_DP<117>")
	)
	(segment
		(start 38.644068 -393.353798)
		(end 38.769798 -393.353798)
		(width 0.1651)
		(layer "In7.Cu")
		(net "P5E_PEX0_STN7_TX_C_DP<117>")
	)
	(segment
		(start 24.07666 -375.291604)
		(end 24.307546 -379.127766)
		(width 0.1651)
		(layer "In7.Cu")
		(net "P5E_PEX0_STN7_TX_C_DP<117>")
	)
	(segment
		(start 24.853138 -367.551208)
		(end 24.07666 -371.456204)
		(width 0.1651)
		(layer "In7.Cu")
		(net "P5E_PEX0_STN7_TX_C_DP<117>")
	)
	(segment
		(start 28.950158 -358.680258)
		(end 26.040588 -364.831884)
		(width 0.1651)
		(layer "In7.Cu")
		(net "P5E_PEX0_STN7_TX_C_DP<117>")
	)
	(segment
		(start 24.07666 -371.456204)
		(end 24.07666 -375.291604)
		(width 0.1651)
		(layer "In7.Cu")
		(net "P5E_PEX0_STN7_TX_C_DP<117>")
	)
	(segment
		(start 28.659328 -357.75773)
		(end 28.950158 -358.04856)
		(width 0.1651)
		(layer "In7.Cu")
		(net "P5E_PEX0_STN7_TX_C_DP<117>")
	)
	(segment
		(start 24.629364 -384.474466)
		(end 25.50668 -386.424678)
		(width 0.1651)
		(layer "In7.Cu")
		(net "P5E_PEX0_STN7_TX_C_DP<117>")
	)
	(segment
		(start 39.037006 -401.999196)
		(end 38.910006 -401.872196)
		(width 0.1651)
		(layer "In7.Cu")
		(net "P5E_PEX0_STN7_TX_C_DP<117>")
	)
	(segment
		(start 26.040588 -364.831884)
		(end 24.853646 -367.548414)
		(width 0.1651)
		(layer "In7.Cu")
		(net "P5E_PEX0_STN7_TX_C_DP<117>")
	)
	(segment
		(start 38.910006 -401.872196)
		(end 38.910006 -401.49018)
		(width 0.1651)
		(layer "In7.Cu")
		(net "P5E_PEX0_STN7_TX_C_DP<117>")
	)
	(segment
		(start 24.307546 -379.127766)
		(end 24.307292 -379.127766)
		(width 0.1651)
		(layer "In7.Cu")
		(net "P5E_PEX0_STN7_TX_C_DP<117>")
	)
	(segment
		(start 25.50668 -386.424678)
		(end 26.668476 -387.586474)
		(width 0.1651)
		(layer "In7.Cu")
		(net "P5E_PEX0_STN7_TX_C_DP<117>")
	)
	(segment
		(start 38.769798 -393.353798)
		(end 39.802308 -394.386308)
		(width 0.1651)
		(layer "In7.Cu")
		(net "P5E_PEX0_STN7_TX_C_DP<117>")
	)
	(segment
		(start 80.606138 -118.990364)
		(end 81.237582 -118.990364)
		(width 0.13462)
		(layer "F.Cu")
		(net "P5E_PEX0_STN0_TX_DN<0>")
	)
	(segment
		(start 81.237582 -118.990364)
		(end 81.532222 -118.695724)
		(width 0.13462)
		(layer "F.Cu")
		(net "P5E_PEX0_STN0_TX_DN<0>")
	)
	(segment
		(start 80.286098 -118.670324)
		(end 80.606138 -118.990364)
		(width 0.13462)
		(layer "F.Cu")
		(net "P5E_PEX0_STN0_TX_DN<0>")
	)
	(segment
		(start 100.461064 -269.973044)
		(end 100.702364 -272.746978)
		(width 0.1651)
		(layer "In9.Cu")
		(net "P5E_PEX0_STN0_TX_DN<0>")
	)
	(segment
		(start 98.976434 -276.912578)
		(end 89.396824 -286.492188)
		(width 0.1651)
		(layer "In9.Cu")
		(net "P5E_PEX0_STN0_TX_DN<0>")
	)
	(segment
		(start 100.221796 -267.224002)
		(end 100.461064 -269.973044)
		(width 0.1651)
		(layer "In9.Cu")
		(net "P5E_PEX0_STN0_TX_DN<0>")
	)
	(segment
		(start 100.171504 -151.905462)
		(end 100.171504 -159.966914)
		(width 0.1651)
		(layer "In9.Cu")
		(net "P5E_PEX0_STN0_TX_DN<0>")
	)
	(segment
		(start 98.849434 -263.91108)
		(end 99.532694 -265.560556)
		(width 0.1651)
		(layer "In9.Cu")
		(net "P5E_PEX0_STN0_TX_DN<0>")
	)
	(segment
		(start 83.889088 -287.965896)
		(end 83.843368 -287.920176)
		(width 0.1143)
		(layer "In9.Cu")
		(net "P5E_PEX0_STN0_TX_DN<0>")
	)
	(segment
		(start 87.165688 -120.953276)
		(end 91.231466 -130.769106)
		(width 0.1651)
		(layer "In9.Cu")
		(net "P5E_PEX0_STN0_TX_DN<0>")
	)
	(segment
		(start 100.702364 -272.746978)
		(end 98.976434 -276.912578)
		(width 0.1651)
		(layer "In9.Cu")
		(net "P5E_PEX0_STN0_TX_DN<0>")
	)
	(segment
		(start 99.532694 -265.560556)
		(end 100.221796 -267.224002)
		(width 0.1651)
		(layer "In9.Cu")
		(net "P5E_PEX0_STN0_TX_DN<0>")
	)
	(segment
		(start 89.078562 -249.289316)
		(end 98.849434 -263.91108)
		(width 0.1651)
		(layer "In9.Cu")
		(net "P5E_PEX0_STN0_TX_DN<0>")
	)
	(segment
		(start 91.249246 -176.133252)
		(end 90.400886 -179.242212)
		(width 0.1651)
		(layer "In9.Cu")
		(net "P5E_PEX0_STN0_TX_DN<0>")
	)
	(segment
		(start 83.917536 -287.965896)
		(end 83.889088 -287.965896)
		(width 0.1143)
		(layer "In9.Cu")
		(net "P5E_PEX0_STN0_TX_DN<0>")
	)
	(segment
		(start 81.823052 -118.986554)
		(end 84.221828 -118.986554)
		(width 0.1651)
		(layer "In9.Cu")
		(net "P5E_PEX0_STN0_TX_DN<0>")
	)
	(segment
		(start 85.838792 -287.965896)
		(end 83.917536 -287.965896)
		(width 0.1651)
		(layer "In9.Cu")
		(net "P5E_PEX0_STN0_TX_DN<0>")
	)
	(segment
		(start 90.400886 -179.242212)
		(end 86.678516 -221.785942)
		(width 0.1651)
		(layer "In9.Cu")
		(net "P5E_PEX0_STN0_TX_DN<0>")
	)
	(segment
		(start 84.221828 -118.986554)
		(end 87.165688 -120.953276)
		(width 0.1651)
		(layer "In9.Cu")
		(net "P5E_PEX0_STN0_TX_DN<0>")
	)
	(segment
		(start 86.678516 -221.785942)
		(end 89.078562 -249.289316)
		(width 0.1651)
		(layer "In9.Cu")
		(net "P5E_PEX0_STN0_TX_DN<0>")
	)
	(segment
		(start 89.396824 -286.492188)
		(end 85.838792 -287.965896)
		(width 0.1651)
		(layer "In9.Cu")
		(net "P5E_PEX0_STN0_TX_DN<0>")
	)
	(segment
		(start 83.843368 -287.920176)
		(end 77.423772 -287.920176)
		(width 0.1143)
		(layer "In9.Cu")
		(net "P5E_PEX0_STN0_TX_DN<0>")
	)
	(segment
		(start 100.171504 -159.966914)
		(end 99.821238 -161.278062)
		(width 0.1651)
		(layer "In9.Cu")
		(net "P5E_PEX0_STN0_TX_DN<0>")
	)
	(segment
		(start 91.546934 -131.084574)
		(end 100.171504 -151.905462)
		(width 0.1651)
		(layer "In9.Cu")
		(net "P5E_PEX0_STN0_TX_DN<0>")
	)
	(segment
		(start 77.43444 -288.299906)
		(end 77.69987 -288.299906)
		(width 0.1143)
		(layer "In9.Cu")
		(net "P5E_PEX0_STN0_TX_DN<0>")
	)
	(segment
		(start 77.32014 -288.185606)
		(end 77.43444 -288.299906)
		(width 0.1143)
		(layer "In9.Cu")
		(net "P5E_PEX0_STN0_TX_DN<0>")
	)
	(segment
		(start 81.532222 -118.695724)
		(end 81.823052 -118.986554)
		(width 0.1651)
		(layer "In9.Cu")
		(net "P5E_PEX0_STN0_TX_DN<0>")
	)
	(segment
		(start 91.231466 -130.769106)
		(end 91.546934 -131.084574)
		(width 0.1651)
		(layer "In9.Cu")
		(net "P5E_PEX0_STN0_TX_DN<0>")
	)
	(segment
		(start 77.32014 -288.023808)
		(end 77.32014 -288.185606)
		(width 0.1143)
		(layer "In9.Cu")
		(net "P5E_PEX0_STN0_TX_DN<0>")
	)
	(segment
		(start 99.821238 -161.278062)
		(end 91.249246 -176.133252)
		(width 0.1651)
		(layer "In9.Cu")
		(net "P5E_PEX0_STN0_TX_DN<0>")
	)
	(segment
		(start 77.423772 -287.920176)
		(end 77.32014 -288.023808)
		(width 0.1143)
		(layer "In9.Cu")
		(net "P5E_PEX0_STN0_TX_DN<0>")
	)
	(segment
		(start 22.305772 -307.697124)
		(end 24.29637 -304.71745)
		(width 0.1651)
		(layer "In5.Cu")
		(net "P5E_PEX0_STN7_RX_DP<112>")
	)
	(segment
		(start 26.864564 -302.561498)
		(end 26.86431 -302.561498)
		(width 0.1651)
		(layer "In5.Cu")
		(net "P5E_PEX0_STN7_RX_DP<112>")
	)
	(segment
		(start 15.584424 -330.742544)
		(end 18.110454 -317.624714)
		(width 0.1651)
		(layer "In5.Cu")
		(net "P5E_PEX0_STN7_RX_DP<112>")
	)
	(segment
		(start 21.235416 -389.010398)
		(end 20.142454 -386.372608)
		(width 0.1651)
		(layer "In5.Cu")
		(net "P5E_PEX0_STN7_RX_DP<112>")
	)
	(segment
		(start 20.142454 -386.372608)
		(end 16.830548 -369.721638)
		(width 0.1651)
		(layer "In5.Cu")
		(net "P5E_PEX0_STN7_RX_DP<112>")
	)
	(segment
		(start 28.851352 -301.738284)
		(end 32.644842 -300.983904)
		(width 0.1651)
		(layer "In5.Cu")
		(net "P5E_PEX0_STN7_RX_DP<112>")
	)
	(segment
		(start 39.320216 -301.25543)
		(end 39.320216 -301.485554)
		(width 0.1143)
		(layer "In5.Cu")
		(net "P5E_PEX0_STN7_RX_DP<112>")
	)
	(segment
		(start 16.830548 -369.721638)
		(end 14.11986 -351.448878)
		(width 0.1651)
		(layer "In5.Cu")
		(net "P5E_PEX0_STN7_RX_DP<112>")
	)
	(segment
		(start 28.77693 -395.436598)
		(end 28.600146 -395.00937)
		(width 0.1651)
		(layer "In5.Cu")
		(net "P5E_PEX0_STN7_RX_DP<112>")
	)
	(segment
		(start 27.910028 -408.190192)
		(end 27.910028 -408.572208)
		(width 0.1651)
		(layer "In5.Cu")
		(net "P5E_PEX0_STN7_RX_DP<112>")
	)
	(segment
		(start 28.600146 -395.00937)
		(end 28.599892 -395.009116)
		(width 0.1651)
		(layer "In5.Cu")
		(net "P5E_PEX0_STN7_RX_DP<112>")
	)
	(segment
		(start 28.77693 -408.28849)
		(end 28.77693 -395.436598)
		(width 0.1651)
		(layer "In5.Cu")
		(net "P5E_PEX0_STN7_RX_DP<112>")
	)
	(segment
		(start 39.320216 -301.485554)
		(end 39.434516 -301.599854)
		(width 0.1143)
		(layer "In5.Cu")
		(net "P5E_PEX0_STN7_RX_DP<112>")
	)
	(segment
		(start 20.715732 -310.672734)
		(end 22.305772 -307.697124)
		(width 0.1651)
		(layer "In5.Cu")
		(net "P5E_PEX0_STN7_RX_DP<112>")
	)
	(segment
		(start 36.39312 -301.029624)
		(end 39.09441 -301.029624)
		(width 0.1143)
		(layer "In5.Cu")
		(net "P5E_PEX0_STN7_RX_DP<112>")
	)
	(segment
		(start 28.423362 -394.582396)
		(end 23.552658 -391.32764)
		(width 0.1651)
		(layer "In5.Cu")
		(net "P5E_PEX0_STN7_RX_DP<112>")
	)
	(segment
		(start 26.16073 -302.852836)
		(end 26.864564 -302.561498)
		(width 0.1651)
		(layer "In5.Cu")
		(net "P5E_PEX0_STN7_RX_DP<112>")
	)
	(segment
		(start 39.09441 -301.029624)
		(end 39.320216 -301.25543)
		(width 0.1143)
		(layer "In5.Cu")
		(net "P5E_PEX0_STN7_RX_DP<112>")
	)
	(segment
		(start 27.910028 -408.572208)
		(end 28.037028 -408.699208)
		(width 0.1651)
		(layer "In5.Cu")
		(net "P5E_PEX0_STN7_RX_DP<112>")
	)
	(segment
		(start 24.29637 -304.71745)
		(end 26.121106 -302.892714)
		(width 0.1651)
		(layer "In5.Cu")
		(net "P5E_PEX0_STN7_RX_DP<112>")
	)
	(segment
		(start 26.120852 -302.892714)
		(end 26.16073 -302.852836)
		(width 0.1651)
		(layer "In5.Cu")
		(net "P5E_PEX0_STN7_RX_DP<112>")
	)
	(segment
		(start 32.644842 -300.983904)
		(end 36.318952 -300.983904)
		(width 0.1651)
		(layer "In5.Cu")
		(net "P5E_PEX0_STN7_RX_DP<112>")
	)
	(segment
		(start 18.59153 -315.800486)
		(end 20.715732 -310.672734)
		(width 0.1651)
		(layer "In5.Cu")
		(net "P5E_PEX0_STN7_RX_DP<112>")
	)
	(segment
		(start 23.552658 -391.32764)
		(end 21.235416 -389.010398)
		(width 0.1651)
		(layer "In5.Cu")
		(net "P5E_PEX0_STN7_RX_DP<112>")
	)
	(segment
		(start 26.121106 -302.892714)
		(end 26.120852 -302.892714)
		(width 0.1651)
		(layer "In5.Cu")
		(net "P5E_PEX0_STN7_RX_DP<112>")
	)
	(segment
		(start 39.434516 -301.599854)
		(end 39.699946 -301.599854)
		(width 0.1143)
		(layer "In5.Cu")
		(net "P5E_PEX0_STN7_RX_DP<112>")
	)
	(segment
		(start 28.366212 -408.699208)
		(end 28.77693 -408.28849)
		(width 0.1651)
		(layer "In5.Cu")
		(net "P5E_PEX0_STN7_RX_DP<112>")
	)
	(segment
		(start 18.110454 -317.624714)
		(end 18.59153 -315.800486)
		(width 0.1651)
		(layer "In5.Cu")
		(net "P5E_PEX0_STN7_RX_DP<112>")
	)
	(segment
		(start 26.86431 -302.561498)
		(end 28.851352 -301.738284)
		(width 0.1651)
		(layer "In5.Cu")
		(net "P5E_PEX0_STN7_RX_DP<112>")
	)
	(segment
		(start 14.11986 -342.619584)
		(end 15.584424 -330.742544)
		(width 0.1651)
		(layer "In5.Cu")
		(net "P5E_PEX0_STN7_RX_DP<112>")
	)
	(segment
		(start 36.3474 -300.983904)
		(end 36.39312 -301.029624)
		(width 0.1143)
		(layer "In5.Cu")
		(net "P5E_PEX0_STN7_RX_DP<112>")
	)
	(segment
		(start 28.037028 -408.699208)
		(end 28.366212 -408.699208)
		(width 0.1651)
		(layer "In5.Cu")
		(net "P5E_PEX0_STN7_RX_DP<112>")
	)
	(segment
		(start 36.318952 -300.983904)
		(end 36.3474 -300.983904)
		(width 0.1143)
		(layer "In5.Cu")
		(net "P5E_PEX0_STN7_RX_DP<112>")
	)
	(segment
		(start 14.11986 -351.448878)
		(end 14.11986 -342.619584)
		(width 0.1651)
		(layer "In5.Cu")
		(net "P5E_PEX0_STN7_RX_DP<112>")
	)
	(segment
		(start 28.599892 -395.009116)
		(end 28.423362 -394.582396)
		(width 0.1651)
		(layer "In5.Cu")
		(net "P5E_PEX0_STN7_RX_DP<112>")
	)
	(segment
		(start 36.371784 -104.695498)
		(end 36.051744 -105.015538)
		(width 0.13462)
		(layer "F.Cu")
		(net "P5E_PEX0_STN1_TX_DN<19>")
	)
	(segment
		(start 36.051744 -105.015538)
		(end 35.4203 -105.015538)
		(width 0.13462)
		(layer "F.Cu")
		(net "P5E_PEX0_STN1_TX_DN<19>")
	)
	(segment
		(start 35.4203 -105.015538)
		(end 35.12566 -104.720898)
		(width 0.13462)
		(layer "F.Cu")
		(net "P5E_PEX0_STN1_TX_DN<19>")
	)
	(segment
		(start 26.991818 -162.262312)
		(end 61.883798 -265.345164)
		(width 0.1651)
		(layer "In9.Cu")
		(net "P5E_PEX0_STN1_TX_DN<19>")
	)
	(segment
		(start 62.385448 -280.319988)
		(end 62.499748 -280.434288)
		(width 0.1143)
		(layer "In9.Cu")
		(net "P5E_PEX0_STN1_TX_DN<19>")
	)
	(segment
		(start 26.206196 -155.565094)
		(end 26.385266 -159.213042)
		(width 0.1651)
		(layer "In9.Cu")
		(net "P5E_PEX0_STN1_TX_DN<19>")
	)
	(segment
		(start 26.027888 -151.935942)
		(end 26.027888 -151.935688)
		(width 0.1651)
		(layer "In9.Cu")
		(net "P5E_PEX0_STN1_TX_DN<19>")
	)
	(segment
		(start 25.670764 -144.659096)
		(end 26.027888 -151.935942)
		(width 0.1651)
		(layer "In9.Cu")
		(net "P5E_PEX0_STN1_TX_DN<19>")
	)
	(segment
		(start 26.385266 -159.213042)
		(end 26.991818 -162.262312)
		(width 0.1651)
		(layer "In9.Cu")
		(net "P5E_PEX0_STN1_TX_DN<19>")
	)
	(segment
		(start 61.883798 -271.526)
		(end 61.883798 -271.554448)
		(width 0.1143)
		(layer "In9.Cu")
		(net "P5E_PEX0_STN1_TX_DN<19>")
	)
	(segment
		(start 30.957774 -108.226098)
		(end 27.5082 -116.556028)
		(width 0.1651)
		(layer "In9.Cu")
		(net "P5E_PEX0_STN1_TX_DN<19>")
	)
	(segment
		(start 23.108412 -138.47318)
		(end 25.670764 -144.659096)
		(width 0.1651)
		(layer "In9.Cu")
		(net "P5E_PEX0_STN1_TX_DN<19>")
	)
	(segment
		(start 34.172652 -105.011728)
		(end 30.958282 -108.226098)
		(width 0.1651)
		(layer "In9.Cu")
		(net "P5E_PEX0_STN1_TX_DN<19>")
	)
	(segment
		(start 61.929518 -271.600168)
		(end 61.929518 -280.10485)
		(width 0.1143)
		(layer "In9.Cu")
		(net "P5E_PEX0_STN1_TX_DN<19>")
	)
	(segment
		(start 30.958282 -108.226098)
		(end 30.957774 -108.226098)
		(width 0.1651)
		(layer "In9.Cu")
		(net "P5E_PEX0_STN1_TX_DN<19>")
	)
	(segment
		(start 26.027888 -151.935688)
		(end 26.206196 -155.565094)
		(width 0.1651)
		(layer "In9.Cu")
		(net "P5E_PEX0_STN1_TX_DN<19>")
	)
	(segment
		(start 35.12566 -104.720898)
		(end 34.83483 -105.011728)
		(width 0.1651)
		(layer "In9.Cu")
		(net "P5E_PEX0_STN1_TX_DN<19>")
	)
	(segment
		(start 61.883798 -265.345164)
		(end 61.883798 -271.526)
		(width 0.1651)
		(layer "In9.Cu")
		(net "P5E_PEX0_STN1_TX_DN<19>")
	)
	(segment
		(start 62.499748 -280.434288)
		(end 62.499748 -280.699718)
		(width 0.1143)
		(layer "In9.Cu")
		(net "P5E_PEX0_STN1_TX_DN<19>")
	)
	(segment
		(start 34.83483 -105.011728)
		(end 34.172652 -105.011728)
		(width 0.1651)
		(layer "In9.Cu")
		(net "P5E_PEX0_STN1_TX_DN<19>")
	)
	(segment
		(start 62.144656 -280.319988)
		(end 62.385448 -280.319988)
		(width 0.1143)
		(layer "In9.Cu")
		(net "P5E_PEX0_STN1_TX_DN<19>")
	)
	(segment
		(start 23.108412 -131.059428)
		(end 23.108412 -138.47318)
		(width 0.1651)
		(layer "In9.Cu")
		(net "P5E_PEX0_STN1_TX_DN<19>")
	)
	(segment
		(start 27.5082 -116.556028)
		(end 23.108412 -131.059428)
		(width 0.1651)
		(layer "In9.Cu")
		(net "P5E_PEX0_STN1_TX_DN<19>")
	)
	(segment
		(start 61.883798 -271.554448)
		(end 61.929518 -271.600168)
		(width 0.1143)
		(layer "In9.Cu")
		(net "P5E_PEX0_STN1_TX_DN<19>")
	)
	(segment
		(start 61.929518 -280.10485)
		(end 62.144656 -280.319988)
		(width 0.1143)
		(layer "In9.Cu")
		(net "P5E_PEX0_STN1_TX_DN<19>")
	)
	(segment
		(start 95.018098 -338.731098)
		(end 95.75927 -339.47227)
		(width 0.1651)
		(layer "In9.Cu")
		(net "P5E_PEX0_STN5_RX_DN<87>")
	)
	(segment
		(start 88.484202 -397.79067)
		(end 87.893906 -398.380966)
		(width 0.1651)
		(layer "In9.Cu")
		(net "P5E_PEX0_STN5_RX_DN<87>")
	)
	(segment
		(start 65.260982 -318.320166)
		(end 65.135252 -318.320166)
		(width 0.1143)
		(layer "In9.Cu")
		(net "P5E_PEX0_STN5_RX_DN<87>")
	)
	(segment
		(start 96.602042 -341.253318)
		(end 99.050094 -366.111282)
		(width 0.1651)
		(layer "In9.Cu")
		(net "P5E_PEX0_STN5_RX_DN<87>")
	)
	(segment
		(start 99.74834 -371.094)
		(end 99.42576 -385.4958)
		(width 0.1651)
		(layer "In9.Cu")
		(net "P5E_PEX0_STN5_RX_DN<87>")
	)
	(segment
		(start 89.116916 -394.491464)
		(end 88.484202 -395.124178)
		(width 0.1651)
		(layer "In9.Cu")
		(net "P5E_PEX0_STN5_RX_DN<87>")
	)
	(segment
		(start 99.42576 -387.486144)
		(end 98.37801 -390.016238)
		(width 0.1651)
		(layer "In9.Cu")
		(net "P5E_PEX0_STN5_RX_DN<87>")
	)
	(segment
		(start 88.484202 -395.124178)
		(end 88.484202 -397.79067)
		(width 0.1651)
		(layer "In9.Cu")
		(net "P5E_PEX0_STN5_RX_DN<87>")
	)
	(segment
		(start 93.35008 -393.649708)
		(end 89.116916 -394.491464)
		(width 0.1651)
		(layer "In9.Cu")
		(net "P5E_PEX0_STN5_RX_DN<87>")
	)
	(segment
		(start 65.349882 -318.409066)
		(end 65.260982 -318.320166)
		(width 0.1143)
		(layer "In9.Cu")
		(net "P5E_PEX0_STN5_RX_DN<87>")
	)
	(segment
		(start 66.82359 -321.105276)
		(end 71.60133 -323.08419)
		(width 0.1651)
		(layer "In9.Cu")
		(net "P5E_PEX0_STN5_RX_DN<87>")
	)
	(segment
		(start 99.050094 -366.111282)
		(end 99.74834 -369.62334)
		(width 0.1651)
		(layer "In9.Cu")
		(net "P5E_PEX0_STN5_RX_DN<87>")
	)
	(segment
		(start 87.43696 -398.380966)
		(end 87.30996 -398.507966)
		(width 0.1651)
		(layer "In9.Cu")
		(net "P5E_PEX0_STN5_RX_DN<87>")
	)
	(segment
		(start 87.30996 -398.507966)
		(end 87.30996 -398.890236)
		(width 0.1651)
		(layer "In9.Cu")
		(net "P5E_PEX0_STN5_RX_DN<87>")
	)
	(segment
		(start 65.208658 -320.035428)
		(end 65.273682 -320.035428)
		(width 0.1143)
		(layer "In9.Cu")
		(net "P5E_PEX0_STN5_RX_DN<87>")
	)
	(segment
		(start 65.135252 -318.320166)
		(end 64.970152 -318.485266)
		(width 0.1143)
		(layer "In9.Cu")
		(net "P5E_PEX0_STN5_RX_DN<87>")
	)
	(segment
		(start 87.893906 -398.380966)
		(end 87.43696 -398.380966)
		(width 0.1651)
		(layer "In9.Cu")
		(net "P5E_PEX0_STN5_RX_DN<87>")
	)
	(segment
		(start 71.60133 -323.08419)
		(end 95.018098 -338.731098)
		(width 0.1651)
		(layer "In9.Cu")
		(net "P5E_PEX0_STN5_RX_DN<87>")
	)
	(segment
		(start 95.730568 -392.66368)
		(end 93.35008 -393.649708)
		(width 0.1651)
		(layer "In9.Cu")
		(net "P5E_PEX0_STN5_RX_DN<87>")
	)
	(segment
		(start 65.376552 -320.138552)
		(end 66.82359 -321.105276)
		(width 0.1651)
		(layer "In9.Cu")
		(net "P5E_PEX0_STN5_RX_DN<87>")
	)
	(segment
		(start 98.37801 -390.016238)
		(end 95.730568 -392.66368)
		(width 0.1651)
		(layer "In9.Cu")
		(net "P5E_PEX0_STN5_RX_DN<87>")
	)
	(segment
		(start 65.283842 -320.045588)
		(end 65.283842 -320.045842)
		(width 0.1143)
		(layer "In9.Cu")
		(net "P5E_PEX0_STN5_RX_DN<87>")
	)
	(segment
		(start 64.970152 -319.796922)
		(end 65.208658 -320.035428)
		(width 0.1143)
		(layer "In9.Cu")
		(net "P5E_PEX0_STN5_RX_DN<87>")
	)
	(segment
		(start 64.970152 -318.485266)
		(end 64.970152 -319.796922)
		(width 0.1143)
		(layer "In9.Cu")
		(net "P5E_PEX0_STN5_RX_DN<87>")
	)
	(segment
		(start 65.283842 -320.045842)
		(end 65.376552 -320.138552)
		(width 0.1651)
		(layer "In9.Cu")
		(net "P5E_PEX0_STN5_RX_DN<87>")
	)
	(segment
		(start 65.273682 -320.035428)
		(end 65.283842 -320.045588)
		(width 0.1143)
		(layer "In9.Cu")
		(net "P5E_PEX0_STN5_RX_DN<87>")
	)
	(segment
		(start 99.42576 -385.4958)
		(end 99.42576 -387.486144)
		(width 0.1651)
		(layer "In9.Cu")
		(net "P5E_PEX0_STN5_RX_DN<87>")
	)
	(segment
		(start 95.75927 -339.47227)
		(end 96.602042 -341.253318)
		(width 0.1651)
		(layer "In9.Cu")
		(net "P5E_PEX0_STN5_RX_DN<87>")
	)
	(segment
		(start 65.349882 -318.699896)
		(end 65.349882 -318.409066)
		(width 0.1143)
		(layer "In9.Cu")
		(net "P5E_PEX0_STN5_RX_DN<87>")
	)
	(segment
		(start 99.74834 -369.62334)
		(end 99.74834 -371.094)
		(width 0.1651)
		(layer "In9.Cu")
		(net "P5E_PEX0_STN5_RX_DN<87>")
	)
	(segment
		(start 32.337248 -350.685354)
		(end 32.657288 -350.365314)
		(width 0.13462)
		(layer "F.Cu")
		(net "P5E_PEX0_STN7_TX_C_DN<118>")
	)
	(segment
		(start 32.337248 -351.316798)
		(end 32.337248 -350.685354)
		(width 0.13462)
		(layer "F.Cu")
		(net "P5E_PEX0_STN7_TX_C_DN<118>")
	)
	(segment
		(start 32.631888 -351.611438)
		(end 32.337248 -351.316798)
		(width 0.13462)
		(layer "F.Cu")
		(net "P5E_PEX0_STN7_TX_C_DN<118>")
	)
	(segment
		(start 41.2369 -401.181062)
		(end 41.710356 -401.181062)
		(width 0.1651)
		(layer "In7.Cu")
		(net "P5E_PEX0_STN7_TX_C_DN<118>")
	)
	(segment
		(start 30.553406 -358.884474)
		(end 30.786578 -357.845868)
		(width 0.1651)
		(layer "In7.Cu")
		(net "P5E_PEX0_STN7_TX_C_DN<118>")
	)
	(segment
		(start 25.31364 -374.629934)
		(end 25.31364 -371.782848)
		(width 0.1651)
		(layer "In7.Cu")
		(net "P5E_PEX0_STN7_TX_C_DN<118>")
	)
	(segment
		(start 41.1099 -401.308062)
		(end 41.2369 -401.181062)
		(width 0.1651)
		(layer "In7.Cu")
		(net "P5E_PEX0_STN7_TX_C_DN<118>")
	)
	(segment
		(start 26.09215 -368.31651)
		(end 30.553406 -358.884474)
		(width 0.1651)
		(layer "In7.Cu")
		(net "P5E_PEX0_STN7_TX_C_DN<118>")
	)
	(segment
		(start 32.341058 -352.552762)
		(end 32.341058 -351.902268)
		(width 0.1651)
		(layer "In7.Cu")
		(net "P5E_PEX0_STN7_TX_C_DN<118>")
	)
	(segment
		(start 42.284142 -394.564362)
		(end 38.919658 -391.199878)
		(width 0.1651)
		(layer "In7.Cu")
		(net "P5E_PEX0_STN7_TX_C_DN<118>")
	)
	(segment
		(start 26.542492 -385.710938)
		(end 25.893522 -384.268472)
		(width 0.1651)
		(layer "In7.Cu")
		(net "P5E_PEX0_STN7_TX_C_DN<118>")
	)
	(segment
		(start 30.552136 -387.734556)
		(end 30.300422 -387.734556)
		(width 0.1651)
		(layer "In7.Cu")
		(net "P5E_PEX0_STN7_TX_C_DN<118>")
	)
	(segment
		(start 25.893522 -384.268472)
		(end 25.31364 -374.629934)
		(width 0.1651)
		(layer "In7.Cu")
		(net "P5E_PEX0_STN7_TX_C_DN<118>")
	)
	(segment
		(start 38.919658 -391.199878)
		(end 30.552136 -387.734556)
		(width 0.1651)
		(layer "In7.Cu")
		(net "P5E_PEX0_STN7_TX_C_DN<118>")
	)
	(segment
		(start 30.300422 -387.734556)
		(end 27.339798 -386.508244)
		(width 0.1651)
		(layer "In7.Cu")
		(net "P5E_PEX0_STN7_TX_C_DN<118>")
	)
	(segment
		(start 25.31364 -371.782848)
		(end 26.09215 -368.31651)
		(width 0.1651)
		(layer "In7.Cu")
		(net "P5E_PEX0_STN7_TX_C_DN<118>")
	)
	(segment
		(start 41.1099 -401.690078)
		(end 41.1099 -401.308062)
		(width 0.1651)
		(layer "In7.Cu")
		(net "P5E_PEX0_STN7_TX_C_DN<118>")
	)
	(segment
		(start 30.786578 -357.845868)
		(end 30.786578 -354.107242)
		(width 0.1651)
		(layer "In7.Cu")
		(net "P5E_PEX0_STN7_TX_C_DN<118>")
	)
	(segment
		(start 41.710356 -401.181062)
		(end 42.284142 -400.607276)
		(width 0.1651)
		(layer "In7.Cu")
		(net "P5E_PEX0_STN7_TX_C_DN<118>")
	)
	(segment
		(start 30.786578 -354.107242)
		(end 32.341058 -352.552762)
		(width 0.1651)
		(layer "In7.Cu")
		(net "P5E_PEX0_STN7_TX_C_DN<118>")
	)
	(segment
		(start 32.341058 -351.902268)
		(end 32.631888 -351.611438)
		(width 0.1651)
		(layer "In7.Cu")
		(net "P5E_PEX0_STN7_TX_C_DN<118>")
	)
	(segment
		(start 27.339798 -386.508244)
		(end 26.542492 -385.710938)
		(width 0.1651)
		(layer "In7.Cu")
		(net "P5E_PEX0_STN7_TX_C_DN<118>")
	)
	(segment
		(start 42.284142 -400.607276)
		(end 42.284142 -394.564362)
		(width 0.1651)
		(layer "In7.Cu")
		(net "P5E_PEX0_STN7_TX_C_DN<118>")
	)
	(segment
		(start 133.919468 -357.46309)
		(end 133.919468 -356.831646)
		(width 0.13462)
		(layer "F.Cu")
		(net "P5E_PEX1_STN5_TX_C_DP<83>")
	)
	(segment
		(start 133.919468 -356.831646)
		(end 133.599428 -356.511606)
		(width 0.13462)
		(layer "F.Cu")
		(net "P5E_PEX1_STN5_TX_C_DP<83>")
	)
	(segment
		(start 133.624828 -357.75773)
		(end 133.919468 -357.46309)
		(width 0.13462)
		(layer "F.Cu")
		(net "P5E_PEX1_STN5_TX_C_DP<83>")
	)
	(segment
		(start 123.287536 -394.999464)
		(end 123.287536 -405.48052)
		(width 0.1651)
		(layer "In7.Cu")
		(net "P5E_PEX1_STN5_TX_C_DP<83>")
	)
	(segment
		(start 138.534902 -386.373116)
		(end 138.378438 -386.889244)
		(width 0.1651)
		(layer "In7.Cu")
		(net "P5E_PEX1_STN5_TX_C_DP<83>")
	)
	(segment
		(start 136.530334 -388.547864)
		(end 134.399528 -389.235696)
		(width 0.1651)
		(layer "In7.Cu")
		(net "P5E_PEX1_STN5_TX_C_DP<83>")
	)
	(segment
		(start 133.915658 -358.04856)
		(end 133.915658 -358.705404)
		(width 0.1651)
		(layer "In7.Cu")
		(net "P5E_PEX1_STN5_TX_C_DP<83>")
	)
	(segment
		(start 122.637042 -405.898858)
		(end 122.510042 -405.771858)
		(width 0.1651)
		(layer "In7.Cu")
		(net "P5E_PEX1_STN5_TX_C_DP<83>")
	)
	(segment
		(start 136.045194 -363.537754)
		(end 136.251696 -363.98835)
		(width 0.1651)
		(layer "In7.Cu")
		(net "P5E_PEX1_STN5_TX_C_DP<83>")
	)
	(segment
		(start 136.352788 -364.025688)
		(end 138.871706 -369.524788)
		(width 0.1651)
		(layer "In7.Cu")
		(net "P5E_PEX1_STN5_TX_C_DP<83>")
	)
	(segment
		(start 138.871706 -369.524788)
		(end 138.534902 -383.201418)
		(width 0.1651)
		(layer "In7.Cu")
		(net "P5E_PEX1_STN5_TX_C_DP<83>")
	)
	(segment
		(start 137.238994 -388.138924)
		(end 136.530334 -388.547864)
		(width 0.1651)
		(layer "In7.Cu")
		(net "P5E_PEX1_STN5_TX_C_DP<83>")
	)
	(segment
		(start 122.869198 -405.898858)
		(end 122.637042 -405.898858)
		(width 0.1651)
		(layer "In7.Cu")
		(net "P5E_PEX1_STN5_TX_C_DP<83>")
	)
	(segment
		(start 136.082786 -363.436662)
		(end 136.045194 -363.537754)
		(width 0.1651)
		(layer "In7.Cu")
		(net "P5E_PEX1_STN5_TX_C_DP<83>")
	)
	(segment
		(start 138.378438 -386.889244)
		(end 138.378692 -386.889244)
		(width 0.1651)
		(layer "In7.Cu")
		(net "P5E_PEX1_STN5_TX_C_DP<83>")
	)
	(segment
		(start 138.097514 -387.424676)
		(end 137.238994 -388.138924)
		(width 0.1651)
		(layer "In7.Cu")
		(net "P5E_PEX1_STN5_TX_C_DP<83>")
	)
	(segment
		(start 122.510042 -405.771858)
		(end 122.510042 -405.390096)
		(width 0.1651)
		(layer "In7.Cu")
		(net "P5E_PEX1_STN5_TX_C_DP<83>")
	)
	(segment
		(start 123.287536 -405.48052)
		(end 122.869198 -405.898858)
		(width 0.1651)
		(layer "In7.Cu")
		(net "P5E_PEX1_STN5_TX_C_DP<83>")
	)
	(segment
		(start 138.378692 -386.889244)
		(end 138.097514 -387.424676)
		(width 0.1651)
		(layer "In7.Cu")
		(net "P5E_PEX1_STN5_TX_C_DP<83>")
	)
	(segment
		(start 138.534902 -383.201418)
		(end 138.534902 -386.373116)
		(width 0.1651)
		(layer "In7.Cu")
		(net "P5E_PEX1_STN5_TX_C_DP<83>")
	)
	(segment
		(start 133.624828 -357.75773)
		(end 133.915658 -358.04856)
		(width 0.1651)
		(layer "In7.Cu")
		(net "P5E_PEX1_STN5_TX_C_DP<83>")
	)
	(segment
		(start 134.399528 -389.235696)
		(end 125.156976 -393.130024)
		(width 0.1651)
		(layer "In7.Cu")
		(net "P5E_PEX1_STN5_TX_C_DP<83>")
	)
	(segment
		(start 125.156976 -393.130024)
		(end 123.287536 -394.999464)
		(width 0.1651)
		(layer "In7.Cu")
		(net "P5E_PEX1_STN5_TX_C_DP<83>")
	)
	(segment
		(start 133.915658 -358.705404)
		(end 136.082786 -363.436662)
		(width 0.1651)
		(layer "In7.Cu")
		(net "P5E_PEX1_STN5_TX_C_DP<83>")
	)
	(segment
		(start 136.251696 -363.98835)
		(end 136.352788 -364.025688)
		(width 0.1651)
		(layer "In7.Cu")
		(net "P5E_PEX1_STN5_TX_C_DP<83>")
	)
	(segment
		(start 38.062408 -99.883214)
		(end 37.767768 -100.177854)
		(width 0.13462)
		(layer "F.Cu")
		(net "P5E_PEX0_STN1_TX_DN<16>")
	)
	(segment
		(start 38.693852 -99.883214)
		(end 38.062408 -99.883214)
		(width 0.13462)
		(layer "F.Cu")
		(net "P5E_PEX0_STN1_TX_DN<16>")
	)
	(segment
		(start 39.013892 -100.203254)
		(end 38.693852 -99.883214)
		(width 0.13462)
		(layer "F.Cu")
		(net "P5E_PEX0_STN1_TX_DN<16>")
	)
	(segment
		(start 30.837886 -104.131618)
		(end 30.496256 -104.473248)
		(width 0.1651)
		(layer "In9.Cu")
		(net "P5E_PEX0_STN1_TX_DN<16>")
	)
	(segment
		(start 23.08479 -145.35912)
		(end 23.795736 -159.841184)
		(width 0.1651)
		(layer "In9.Cu")
		(net "P5E_PEX0_STN1_TX_DN<16>")
	)
	(segment
		(start 31.179008 -103.628952)
		(end 30.837886 -103.970074)
		(width 0.1651)
		(layer "In9.Cu")
		(net "P5E_PEX0_STN1_TX_DN<16>")
	)
	(segment
		(start 27.38374 -109.200442)
		(end 27.194256 -109.658404)
		(width 0.1651)
		(layer "In9.Cu")
		(net "P5E_PEX0_STN1_TX_DN<16>")
	)
	(segment
		(start 59.535314 -278.229568)
		(end 59.649614 -278.115268)
		(width 0.1143)
		(layer "In9.Cu")
		(net "P5E_PEX0_STN1_TX_DN<16>")
	)
	(segment
		(start 27.194256 -109.658404)
		(end 27.04465 -109.720126)
		(width 0.1651)
		(layer "In9.Cu")
		(net "P5E_PEX0_STN1_TX_DN<16>")
	)
	(segment
		(start 59.270138 -278.12619)
		(end 59.373516 -278.229568)
		(width 0.1143)
		(layer "In9.Cu")
		(net "P5E_PEX0_STN1_TX_DN<16>")
	)
	(segment
		(start 33.936432 -100.871528)
		(end 33.37052 -101.43744)
		(width 0.1651)
		(layer "In9.Cu")
		(net "P5E_PEX0_STN1_TX_DN<16>")
	)
	(segment
		(start 59.270138 -271.546066)
		(end 59.270138 -278.12619)
		(width 0.1143)
		(layer "In9.Cu")
		(net "P5E_PEX0_STN1_TX_DN<16>")
	)
	(segment
		(start 37.476938 -99.887024)
		(end 36.314126 -99.887024)
		(width 0.1651)
		(layer "In9.Cu")
		(net "P5E_PEX0_STN1_TX_DN<16>")
	)
	(segment
		(start 29.99359 -104.81437)
		(end 29.99359 -104.975914)
		(width 0.1651)
		(layer "In9.Cu")
		(net "P5E_PEX0_STN1_TX_DN<16>")
	)
	(segment
		(start 59.315858 -271.500346)
		(end 59.270138 -271.546066)
		(width 0.1143)
		(layer "In9.Cu")
		(net "P5E_PEX0_STN1_TX_DN<16>")
	)
	(segment
		(start 59.315858 -271.471898)
		(end 59.315858 -271.500346)
		(width 0.1143)
		(layer "In9.Cu")
		(net "P5E_PEX0_STN1_TX_DN<16>")
	)
	(segment
		(start 59.649614 -278.115268)
		(end 59.649614 -277.849838)
		(width 0.1143)
		(layer "In9.Cu")
		(net "P5E_PEX0_STN1_TX_DN<16>")
	)
	(segment
		(start 29.65196 -105.317544)
		(end 29.490416 -105.317544)
		(width 0.1651)
		(layer "In9.Cu")
		(net "P5E_PEX0_STN1_TX_DN<16>")
	)
	(segment
		(start 36.314126 -99.887024)
		(end 35.867086 -100.071936)
		(width 0.1651)
		(layer "In9.Cu")
		(net "P5E_PEX0_STN1_TX_DN<16>")
	)
	(segment
		(start 29.490416 -105.317544)
		(end 28.428188 -106.379772)
		(width 0.1651)
		(layer "In9.Cu")
		(net "P5E_PEX0_STN1_TX_DN<16>")
	)
	(segment
		(start 30.334712 -104.473248)
		(end 29.99359 -104.81437)
		(width 0.1651)
		(layer "In9.Cu")
		(net "P5E_PEX0_STN1_TX_DN<16>")
	)
	(segment
		(start 29.99359 -104.975914)
		(end 29.65196 -105.317544)
		(width 0.1651)
		(layer "In9.Cu")
		(net "P5E_PEX0_STN1_TX_DN<16>")
	)
	(segment
		(start 35.359086 -100.4062)
		(end 35.209734 -100.344224)
		(width 0.1651)
		(layer "In9.Cu")
		(net "P5E_PEX0_STN1_TX_DN<16>")
	)
	(segment
		(start 20.487132 -130.75666)
		(end 20.487132 -139.08786)
		(width 0.1651)
		(layer "In9.Cu")
		(net "P5E_PEX0_STN1_TX_DN<16>")
	)
	(segment
		(start 28.428188 -106.379772)
		(end 27.788362 -107.9246)
		(width 0.1651)
		(layer "In9.Cu")
		(net "P5E_PEX0_STN1_TX_DN<16>")
	)
	(segment
		(start 33.029144 -101.94036)
		(end 32.8676 -101.94036)
		(width 0.1651)
		(layer "In9.Cu")
		(net "P5E_PEX0_STN1_TX_DN<16>")
	)
	(segment
		(start 27.660854 -108.53166)
		(end 27.511248 -108.593636)
		(width 0.1651)
		(layer "In9.Cu")
		(net "P5E_PEX0_STN1_TX_DN<16>")
	)
	(segment
		(start 33.37052 -101.43744)
		(end 33.37052 -101.598984)
		(width 0.1651)
		(layer "In9.Cu")
		(net "P5E_PEX0_STN1_TX_DN<16>")
	)
	(segment
		(start 32.184848 -102.784656)
		(end 32.023304 -102.784656)
		(width 0.1651)
		(layer "In9.Cu")
		(net "P5E_PEX0_STN1_TX_DN<16>")
	)
	(segment
		(start 35.805364 -100.221542)
		(end 35.359086 -100.4062)
		(width 0.1651)
		(layer "In9.Cu")
		(net "P5E_PEX0_STN1_TX_DN<16>")
	)
	(segment
		(start 31.682182 -103.287322)
		(end 31.340552 -103.628952)
		(width 0.1651)
		(layer "In9.Cu")
		(net "P5E_PEX0_STN1_TX_DN<16>")
	)
	(segment
		(start 27.788362 -107.9246)
		(end 27.850338 -108.073952)
		(width 0.1651)
		(layer "In9.Cu")
		(net "P5E_PEX0_STN1_TX_DN<16>")
	)
	(segment
		(start 26.388314 -111.304832)
		(end 20.487132 -130.75666)
		(width 0.1651)
		(layer "In9.Cu")
		(net "P5E_PEX0_STN1_TX_DN<16>")
	)
	(segment
		(start 32.023304 -102.784656)
		(end 31.682182 -103.125778)
		(width 0.1651)
		(layer "In9.Cu")
		(net "P5E_PEX0_STN1_TX_DN<16>")
	)
	(segment
		(start 32.8676 -101.94036)
		(end 32.526478 -102.281482)
		(width 0.1651)
		(layer "In9.Cu")
		(net "P5E_PEX0_STN1_TX_DN<16>")
	)
	(segment
		(start 30.496256 -104.473248)
		(end 30.334712 -104.473248)
		(width 0.1651)
		(layer "In9.Cu")
		(net "P5E_PEX0_STN1_TX_DN<16>")
	)
	(segment
		(start 35.867086 -100.071936)
		(end 35.805364 -100.221542)
		(width 0.1651)
		(layer "In9.Cu")
		(net "P5E_PEX0_STN1_TX_DN<16>")
	)
	(segment
		(start 27.321764 -109.05109)
		(end 27.38374 -109.200442)
		(width 0.1651)
		(layer "In9.Cu")
		(net "P5E_PEX0_STN1_TX_DN<16>")
	)
	(segment
		(start 37.767768 -100.177854)
		(end 37.476938 -99.887024)
		(width 0.1651)
		(layer "In9.Cu")
		(net "P5E_PEX0_STN1_TX_DN<16>")
	)
	(segment
		(start 35.209734 -100.344224)
		(end 33.936432 -100.871528)
		(width 0.1651)
		(layer "In9.Cu")
		(net "P5E_PEX0_STN1_TX_DN<16>")
	)
	(segment
		(start 27.04465 -109.720126)
		(end 26.388314 -111.304832)
		(width 0.1651)
		(layer "In9.Cu")
		(net "P5E_PEX0_STN1_TX_DN<16>")
	)
	(segment
		(start 59.315858 -265.937492)
		(end 59.315858 -271.471898)
		(width 0.1651)
		(layer "In9.Cu")
		(net "P5E_PEX0_STN1_TX_DN<16>")
	)
	(segment
		(start 24.352758 -162.641534)
		(end 59.315858 -265.937492)
		(width 0.1651)
		(layer "In9.Cu")
		(net "P5E_PEX0_STN1_TX_DN<16>")
	)
	(segment
		(start 33.37052 -101.598984)
		(end 33.029144 -101.94036)
		(width 0.1651)
		(layer "In9.Cu")
		(net "P5E_PEX0_STN1_TX_DN<16>")
	)
	(segment
		(start 20.487132 -139.08786)
		(end 23.08479 -145.35912)
		(width 0.1651)
		(layer "In9.Cu")
		(net "P5E_PEX0_STN1_TX_DN<16>")
	)
	(segment
		(start 31.682182 -103.125778)
		(end 31.682182 -103.287322)
		(width 0.1651)
		(layer "In9.Cu")
		(net "P5E_PEX0_STN1_TX_DN<16>")
	)
	(segment
		(start 23.795736 -159.841184)
		(end 24.352758 -162.641534)
		(width 0.1651)
		(layer "In9.Cu")
		(net "P5E_PEX0_STN1_TX_DN<16>")
	)
	(segment
		(start 32.526478 -102.281482)
		(end 32.526478 -102.443026)
		(width 0.1651)
		(layer "In9.Cu")
		(net "P5E_PEX0_STN1_TX_DN<16>")
	)
	(segment
		(start 27.850338 -108.073952)
		(end 27.660854 -108.53166)
		(width 0.1651)
		(layer "In9.Cu")
		(net "P5E_PEX0_STN1_TX_DN<16>")
	)
	(segment
		(start 31.340552 -103.628952)
		(end 31.179008 -103.628952)
		(width 0.1651)
		(layer "In9.Cu")
		(net "P5E_PEX0_STN1_TX_DN<16>")
	)
	(segment
		(start 27.511248 -108.593636)
		(end 27.321764 -109.05109)
		(width 0.1651)
		(layer "In9.Cu")
		(net "P5E_PEX0_STN1_TX_DN<16>")
	)
	(segment
		(start 30.837886 -103.970074)
		(end 30.837886 -104.131618)
		(width 0.1651)
		(layer "In9.Cu")
		(net "P5E_PEX0_STN1_TX_DN<16>")
	)
	(segment
		(start 59.373516 -278.229568)
		(end 59.535314 -278.229568)
		(width 0.1143)
		(layer "In9.Cu")
		(net "P5E_PEX0_STN1_TX_DN<16>")
	)
	(segment
		(start 32.526478 -102.443026)
		(end 32.184848 -102.784656)
		(width 0.1651)
		(layer "In9.Cu")
		(net "P5E_PEX0_STN1_TX_DN<16>")
	)
	(segment
		(start 98.46056 -387.25983)
		(end 97.525078 -389.518398)
		(width 0.1651)
		(layer "In9.Cu")
		(net "P5E_PEX0_STN5_RX_DN<86>")
	)
	(segment
		(start 64.311022 -316.419992)
		(end 64.185292 -316.419992)
		(width 0.1143)
		(layer "In9.Cu")
		(net "P5E_PEX0_STN5_RX_DN<86>")
	)
	(segment
		(start 64.065912 -320.016632)
		(end 64.28105 -320.48577)
		(width 0.1651)
		(layer "In9.Cu")
		(net "P5E_PEX0_STN5_RX_DN<86>")
	)
	(segment
		(start 98.46056 -385.484878)
		(end 98.46056 -387.25983)
		(width 0.1651)
		(layer "In9.Cu")
		(net "P5E_PEX0_STN5_RX_DN<86>")
	)
	(segment
		(start 85.109812 -397.408146)
		(end 85.109812 -397.790162)
		(width 0.1651)
		(layer "In9.Cu")
		(net "P5E_PEX0_STN5_RX_DN<86>")
	)
	(segment
		(start 66.179954 -321.947794)
		(end 69.9643 -323.515736)
		(width 0.1651)
		(layer "In9.Cu")
		(net "P5E_PEX0_STN5_RX_DN<86>")
	)
	(segment
		(start 85.236812 -397.281146)
		(end 85.109812 -397.408146)
		(width 0.1651)
		(layer "In9.Cu")
		(net "P5E_PEX0_STN5_RX_DN<86>")
	)
	(segment
		(start 69.9643 -323.515736)
		(end 94.70898 -340.049866)
		(width 0.1651)
		(layer "In9.Cu")
		(net "P5E_PEX0_STN5_RX_DN<86>")
	)
	(segment
		(start 85.74278 -397.281146)
		(end 85.236812 -397.281146)
		(width 0.1651)
		(layer "In9.Cu")
		(net "P5E_PEX0_STN5_RX_DN<86>")
	)
	(segment
		(start 94.70898 -340.049866)
		(end 95.642684 -341.607648)
		(width 0.1651)
		(layer "In9.Cu")
		(net "P5E_PEX0_STN5_RX_DN<86>")
	)
	(segment
		(start 86.326472 -396.697454)
		(end 85.74278 -397.281146)
		(width 0.1651)
		(layer "In9.Cu")
		(net "P5E_PEX0_STN5_RX_DN<86>")
	)
	(segment
		(start 86.326472 -395.181328)
		(end 86.326472 -396.697454)
		(width 0.1651)
		(layer "In9.Cu")
		(net "P5E_PEX0_STN5_RX_DN<86>")
	)
	(segment
		(start 64.065912 -319.8622)
		(end 64.065912 -319.890648)
		(width 0.1143)
		(layer "In9.Cu")
		(net "P5E_PEX0_STN5_RX_DN<86>")
	)
	(segment
		(start 92.836746 -392.691874)
		(end 87.817452 -393.690348)
		(width 0.1651)
		(layer "In9.Cu")
		(net "P5E_PEX0_STN5_RX_DN<86>")
	)
	(segment
		(start 64.399922 -316.508892)
		(end 64.311022 -316.419992)
		(width 0.1143)
		(layer "In9.Cu")
		(net "P5E_PEX0_STN5_RX_DN<86>")
	)
	(segment
		(start 64.727074 -320.870072)
		(end 66.179954 -321.947794)
		(width 0.1651)
		(layer "In9.Cu")
		(net "P5E_PEX0_STN5_RX_DN<86>")
	)
	(segment
		(start 64.065912 -319.890648)
		(end 64.065912 -320.016632)
		(width 0.1651)
		(layer "In9.Cu")
		(net "P5E_PEX0_STN5_RX_DN<86>")
	)
	(segment
		(start 64.020192 -319.81648)
		(end 64.065912 -319.8622)
		(width 0.1143)
		(layer "In9.Cu")
		(net "P5E_PEX0_STN5_RX_DN<86>")
	)
	(segment
		(start 64.28105 -320.48577)
		(end 64.727074 -320.870072)
		(width 0.1651)
		(layer "In9.Cu")
		(net "P5E_PEX0_STN5_RX_DN<86>")
	)
	(segment
		(start 95.642684 -341.607648)
		(end 98.040698 -365.95939)
		(width 0.1651)
		(layer "In9.Cu")
		(net "P5E_PEX0_STN5_RX_DN<86>")
	)
	(segment
		(start 98.78314 -371.072918)
		(end 98.46056 -385.484878)
		(width 0.1651)
		(layer "In9.Cu")
		(net "P5E_PEX0_STN5_RX_DN<86>")
	)
	(segment
		(start 98.78314 -369.693698)
		(end 98.78314 -371.072918)
		(width 0.1651)
		(layer "In9.Cu")
		(net "P5E_PEX0_STN5_RX_DN<86>")
	)
	(segment
		(start 97.525078 -389.518398)
		(end 95.422466 -391.62101)
		(width 0.1651)
		(layer "In9.Cu")
		(net "P5E_PEX0_STN5_RX_DN<86>")
	)
	(segment
		(start 95.422466 -391.62101)
		(end 92.836746 -392.691874)
		(width 0.1651)
		(layer "In9.Cu")
		(net "P5E_PEX0_STN5_RX_DN<86>")
	)
	(segment
		(start 64.399922 -316.799722)
		(end 64.399922 -316.508892)
		(width 0.1143)
		(layer "In9.Cu")
		(net "P5E_PEX0_STN5_RX_DN<86>")
	)
	(segment
		(start 64.020192 -316.585092)
		(end 64.020192 -319.81648)
		(width 0.1143)
		(layer "In9.Cu")
		(net "P5E_PEX0_STN5_RX_DN<86>")
	)
	(segment
		(start 98.040698 -365.95939)
		(end 98.78314 -369.693698)
		(width 0.1651)
		(layer "In9.Cu")
		(net "P5E_PEX0_STN5_RX_DN<86>")
	)
	(segment
		(start 87.817452 -393.690348)
		(end 86.326472 -395.181328)
		(width 0.1651)
		(layer "In9.Cu")
		(net "P5E_PEX0_STN5_RX_DN<86>")
	)
	(segment
		(start 64.185292 -316.419992)
		(end 64.020192 -316.585092)
		(width 0.1143)
		(layer "In9.Cu")
		(net "P5E_PEX0_STN5_RX_DN<86>")
	)
	(segment
		(start 127.701548 -357.46309)
		(end 127.701548 -356.831646)
		(width 0.13462)
		(layer "F.Cu")
		(net "P5E_PEX1_STN5_TX_C_DP<80>")
	)
	(segment
		(start 127.406908 -357.75773)
		(end 127.701548 -357.46309)
		(width 0.13462)
		(layer "F.Cu")
		(net "P5E_PEX1_STN5_TX_C_DP<80>")
	)
	(segment
		(start 127.701548 -356.831646)
		(end 127.381508 -356.511606)
		(width 0.13462)
		(layer "F.Cu")
		(net "P5E_PEX1_STN5_TX_C_DP<80>")
	)
	(segment
		(start 132.096002 -365.836708)
		(end 132.071364 -365.959898)
		(width 0.1651)
		(layer "In7.Cu")
		(net "P5E_PEX1_STN5_TX_C_DP<80>")
	)
	(segment
		(start 117.3988 -394.4874)
		(end 116.6876 -396.2146)
		(width 0.1651)
		(layer "In7.Cu")
		(net "P5E_PEX1_STN5_TX_C_DP<80>")
	)
	(segment
		(start 116.6876 -404.380446)
		(end 116.269262 -404.798784)
		(width 0.1651)
		(layer "In7.Cu")
		(net "P5E_PEX1_STN5_TX_C_DP<80>")
	)
	(segment
		(start 131.82092 -365.424974)
		(end 132.096002 -365.836708)
		(width 0.1651)
		(layer "In7.Cu")
		(net "P5E_PEX1_STN5_TX_C_DP<80>")
	)
	(segment
		(start 132.470144 -366.396524)
		(end 132.745226 -366.808258)
		(width 0.1651)
		(layer "In7.Cu")
		(net "P5E_PEX1_STN5_TX_C_DP<80>")
	)
	(segment
		(start 133.119622 -367.368074)
		(end 134.469124 -369.387882)
		(width 0.1651)
		(layer "In7.Cu")
		(net "P5E_PEX1_STN5_TX_C_DP<80>")
	)
	(segment
		(start 132.071364 -365.959898)
		(end 132.346954 -366.37214)
		(width 0.1651)
		(layer "In7.Cu")
		(net "P5E_PEX1_STN5_TX_C_DP<80>")
	)
	(segment
		(start 127.406908 -357.75773)
		(end 127.697738 -358.04856)
		(width 0.1651)
		(layer "In7.Cu")
		(net "P5E_PEX1_STN5_TX_C_DP<80>")
	)
	(segment
		(start 116.269262 -404.798784)
		(end 116.037106 -404.798784)
		(width 0.1651)
		(layer "In7.Cu")
		(net "P5E_PEX1_STN5_TX_C_DP<80>")
	)
	(segment
		(start 116.6876 -396.2146)
		(end 116.6876 -404.380446)
		(width 0.1651)
		(layer "In7.Cu")
		(net "P5E_PEX1_STN5_TX_C_DP<80>")
	)
	(segment
		(start 131.42214 -364.988348)
		(end 131.69773 -365.40059)
		(width 0.1651)
		(layer "In7.Cu")
		(net "P5E_PEX1_STN5_TX_C_DP<80>")
	)
	(segment
		(start 132.745226 -366.808258)
		(end 132.720842 -366.931448)
		(width 0.1651)
		(layer "In7.Cu")
		(net "P5E_PEX1_STN5_TX_C_DP<80>")
	)
	(segment
		(start 127.697738 -358.761792)
		(end 127.971804 -359.664762)
		(width 0.1651)
		(layer "In7.Cu")
		(net "P5E_PEX1_STN5_TX_C_DP<80>")
	)
	(segment
		(start 122.5296 -390.906)
		(end 117.3988 -394.4874)
		(width 0.1651)
		(layer "In7.Cu")
		(net "P5E_PEX1_STN5_TX_C_DP<80>")
	)
	(segment
		(start 115.910106 -404.671784)
		(end 115.910106 -404.290022)
		(width 0.1651)
		(layer "In7.Cu")
		(net "P5E_PEX1_STN5_TX_C_DP<80>")
	)
	(segment
		(start 132.720842 -366.931448)
		(end 132.996178 -367.34369)
		(width 0.1651)
		(layer "In7.Cu")
		(net "P5E_PEX1_STN5_TX_C_DP<80>")
	)
	(segment
		(start 127.971804 -359.664762)
		(end 131.446778 -364.865158)
		(width 0.1651)
		(layer "In7.Cu")
		(net "P5E_PEX1_STN5_TX_C_DP<80>")
	)
	(segment
		(start 134.3406 -385.3688)
		(end 131.8006 -387.0452)
		(width 0.1651)
		(layer "In7.Cu")
		(net "P5E_PEX1_STN5_TX_C_DP<80>")
	)
	(segment
		(start 131.446778 -364.865158)
		(end 131.42214 -364.988348)
		(width 0.1651)
		(layer "In7.Cu")
		(net "P5E_PEX1_STN5_TX_C_DP<80>")
	)
	(segment
		(start 116.037106 -404.798784)
		(end 115.910106 -404.671784)
		(width 0.1651)
		(layer "In7.Cu")
		(net "P5E_PEX1_STN5_TX_C_DP<80>")
	)
	(segment
		(start 131.8006 -387.0452)
		(end 122.5296 -390.906)
		(width 0.1651)
		(layer "In7.Cu")
		(net "P5E_PEX1_STN5_TX_C_DP<80>")
	)
	(segment
		(start 132.996178 -367.34369)
		(end 133.119622 -367.368074)
		(width 0.1651)
		(layer "In7.Cu")
		(net "P5E_PEX1_STN5_TX_C_DP<80>")
	)
	(segment
		(start 134.469124 -385.169156)
		(end 134.3406 -385.3688)
		(width 0.1651)
		(layer "In7.Cu")
		(net "P5E_PEX1_STN5_TX_C_DP<80>")
	)
	(segment
		(start 127.697738 -358.04856)
		(end 127.697738 -358.761792)
		(width 0.1651)
		(layer "In7.Cu")
		(net "P5E_PEX1_STN5_TX_C_DP<80>")
	)
	(segment
		(start 132.346954 -366.37214)
		(end 132.470144 -366.396524)
		(width 0.1651)
		(layer "In7.Cu")
		(net "P5E_PEX1_STN5_TX_C_DP<80>")
	)
	(segment
		(start 134.469124 -369.387882)
		(end 134.469124 -385.169156)
		(width 0.1651)
		(layer "In7.Cu")
		(net "P5E_PEX1_STN5_TX_C_DP<80>")
	)
	(segment
		(start 131.69773 -365.40059)
		(end 131.82092 -365.424974)
		(width 0.1651)
		(layer "In7.Cu")
		(net "P5E_PEX1_STN5_TX_C_DP<80>")
	)
	(segment
		(start 38.693852 -121.325386)
		(end 38.062408 -121.325386)
		(width 0.13462)
		(layer "F.Cu")
		(net "P5E_PEX0_STN1_TX_DN<25>")
	)
	(segment
		(start 38.062408 -121.325386)
		(end 37.767768 -121.030746)
		(width 0.13462)
		(layer "F.Cu")
		(net "P5E_PEX0_STN1_TX_DN<25>")
	)
	(segment
		(start 39.013892 -121.005346)
		(end 38.693852 -121.325386)
		(width 0.13462)
		(layer "F.Cu")
		(net "P5E_PEX0_STN1_TX_DN<25>")
	)
	(segment
		(start 67.583812 -271.526)
		(end 67.583812 -271.554448)
		(width 0.1143)
		(layer "In9.Cu")
		(net "P5E_PEX0_STN1_TX_DN<25>")
	)
	(segment
		(start 32.861758 -122.797062)
		(end 28.914852 -132.325872)
		(width 0.1651)
		(layer "In9.Cu")
		(net "P5E_PEX0_STN1_TX_DN<25>")
	)
	(segment
		(start 28.914852 -132.325872)
		(end 28.914852 -137.251186)
		(width 0.1651)
		(layer "In9.Cu")
		(net "P5E_PEX0_STN1_TX_DN<25>")
	)
	(segment
		(start 67.84467 -280.319988)
		(end 68.085462 -280.319988)
		(width 0.1143)
		(layer "In9.Cu")
		(net "P5E_PEX0_STN1_TX_DN<25>")
	)
	(segment
		(start 34.337244 -121.321576)
		(end 32.861758 -122.797062)
		(width 0.1651)
		(layer "In9.Cu")
		(net "P5E_PEX0_STN1_TX_DN<25>")
	)
	(segment
		(start 28.914852 -137.251186)
		(end 31.458916 -143.39316)
		(width 0.1651)
		(layer "In9.Cu")
		(net "P5E_PEX0_STN1_TX_DN<25>")
	)
	(segment
		(start 32.798512 -161.306002)
		(end 67.583812 -264.068306)
		(width 0.1651)
		(layer "In9.Cu")
		(net "P5E_PEX0_STN1_TX_DN<25>")
	)
	(segment
		(start 68.085462 -280.319988)
		(end 68.199762 -280.434288)
		(width 0.1143)
		(layer "In9.Cu")
		(net "P5E_PEX0_STN1_TX_DN<25>")
	)
	(segment
		(start 67.629532 -280.10485)
		(end 67.84467 -280.319988)
		(width 0.1143)
		(layer "In9.Cu")
		(net "P5E_PEX0_STN1_TX_DN<25>")
	)
	(segment
		(start 67.629532 -271.600168)
		(end 67.629532 -280.10485)
		(width 0.1143)
		(layer "In9.Cu")
		(net "P5E_PEX0_STN1_TX_DN<25>")
	)
	(segment
		(start 67.583812 -271.554448)
		(end 67.629532 -271.600168)
		(width 0.1143)
		(layer "In9.Cu")
		(net "P5E_PEX0_STN1_TX_DN<25>")
	)
	(segment
		(start 67.583812 -264.068306)
		(end 67.583812 -271.526)
		(width 0.1651)
		(layer "In9.Cu")
		(net "P5E_PEX0_STN1_TX_DN<25>")
	)
	(segment
		(start 37.767768 -121.030746)
		(end 37.476938 -121.321576)
		(width 0.1651)
		(layer "In9.Cu")
		(net "P5E_PEX0_STN1_TX_DN<25>")
	)
	(segment
		(start 31.458916 -143.39316)
		(end 32.188658 -158.240222)
		(width 0.1651)
		(layer "In9.Cu")
		(net "P5E_PEX0_STN1_TX_DN<25>")
	)
	(segment
		(start 68.199762 -280.434288)
		(end 68.199762 -280.699718)
		(width 0.1143)
		(layer "In9.Cu")
		(net "P5E_PEX0_STN1_TX_DN<25>")
	)
	(segment
		(start 37.476938 -121.321576)
		(end 34.337244 -121.321576)
		(width 0.1651)
		(layer "In9.Cu")
		(net "P5E_PEX0_STN1_TX_DN<25>")
	)
	(segment
		(start 32.188658 -158.240222)
		(end 32.798512 -161.306002)
		(width 0.1651)
		(layer "In9.Cu")
		(net "P5E_PEX0_STN1_TX_DN<25>")
	)
	(segment
		(start 93.725238 -393.188952)
		(end 93.267784 -393.378436)
		(width 0.1651)
		(layer "In9.Cu")
		(net "P5E_PEX0_STN5_RX_DP<87>")
	)
	(segment
		(start 99.4664 -369.65128)
		(end 99.4664 -371.090698)
		(width 0.1651)
		(layer "In9.Cu")
		(net "P5E_PEX0_STN5_RX_DP<87>")
	)
	(segment
		(start 66.689986 -321.355212)
		(end 71.467726 -323.334126)
		(width 0.1651)
		(layer "In9.Cu")
		(net "P5E_PEX0_STN5_RX_DP<87>")
	)
	(segment
		(start 95.525336 -339.637116)
		(end 96.325944 -341.329772)
		(width 0.1651)
		(layer "In9.Cu")
		(net "P5E_PEX0_STN5_RX_DP<87>")
	)
	(segment
		(start 95.570802 -392.424666)
		(end 94.323916 -392.941048)
		(width 0.1651)
		(layer "In9.Cu")
		(net "P5E_PEX0_STN5_RX_DP<87>")
	)
	(segment
		(start 65.064386 -320.225166)
		(end 65.084452 -320.245232)
		(width 0.1143)
		(layer "In9.Cu")
		(net "P5E_PEX0_STN5_RX_DP<87>")
	)
	(segment
		(start 64.779652 -319.875916)
		(end 65.064132 -320.160396)
		(width 0.1143)
		(layer "In9.Cu")
		(net "P5E_PEX0_STN5_RX_DP<87>")
	)
	(segment
		(start 71.467726 -323.334126)
		(end 94.838266 -338.950046)
		(width 0.1651)
		(layer "In9.Cu")
		(net "P5E_PEX0_STN5_RX_DP<87>")
	)
	(segment
		(start 89.463626 -394.135102)
		(end 88.977978 -394.231622)
		(width 0.1651)
		(layer "In9.Cu")
		(net "P5E_PEX0_STN5_RX_DP<87>")
	)
	(segment
		(start 91.22029 -393.785344)
		(end 91.130628 -393.725654)
		(width 0.1651)
		(layer "In9.Cu")
		(net "P5E_PEX0_STN5_RX_DP<87>")
	)
	(segment
		(start 98.770694 -366.152684)
		(end 99.4664 -369.65128)
		(width 0.1651)
		(layer "In9.Cu")
		(net "P5E_PEX0_STN5_RX_DP<87>")
	)
	(segment
		(start 99.14382 -385.492498)
		(end 99.14382 -387.43001)
		(width 0.1651)
		(layer "In9.Cu")
		(net "P5E_PEX0_STN5_RX_DP<87>")
	)
	(segment
		(start 93.267784 -393.378436)
		(end 91.22029 -393.785344)
		(width 0.1651)
		(layer "In9.Cu")
		(net "P5E_PEX0_STN5_RX_DP<87>")
	)
	(segment
		(start 65.084452 -320.245232)
		(end 65.19672 -320.3575)
		(width 0.1651)
		(layer "In9.Cu")
		(net "P5E_PEX0_STN5_RX_DP<87>")
	)
	(segment
		(start 64.779652 -318.406272)
		(end 64.779652 -319.875916)
		(width 0.1143)
		(layer "In9.Cu")
		(net "P5E_PEX0_STN5_RX_DP<87>")
	)
	(segment
		(start 87.777066 -398.099026)
		(end 87.43696 -398.099026)
		(width 0.1651)
		(layer "In9.Cu")
		(net "P5E_PEX0_STN5_RX_DP<87>")
	)
	(segment
		(start 98.138996 -389.856472)
		(end 95.570802 -392.424666)
		(width 0.1651)
		(layer "In9.Cu")
		(net "P5E_PEX0_STN5_RX_DP<87>")
	)
	(segment
		(start 94.838266 -338.950046)
		(end 95.525336 -339.637116)
		(width 0.1651)
		(layer "In9.Cu")
		(net "P5E_PEX0_STN5_RX_DP<87>")
	)
	(segment
		(start 89.52357 -394.045186)
		(end 89.463626 -394.135102)
		(width 0.1651)
		(layer "In9.Cu")
		(net "P5E_PEX0_STN5_RX_DP<87>")
	)
	(segment
		(start 96.325944 -341.329772)
		(end 98.770694 -366.152684)
		(width 0.1651)
		(layer "In9.Cu")
		(net "P5E_PEX0_STN5_RX_DP<87>")
	)
	(segment
		(start 65.260982 -318.129666)
		(end 65.056258 -318.129666)
		(width 0.1143)
		(layer "In9.Cu")
		(net "P5E_PEX0_STN5_RX_DP<87>")
	)
	(segment
		(start 94.224348 -392.899646)
		(end 93.766386 -393.089384)
		(width 0.1651)
		(layer "In9.Cu")
		(net "P5E_PEX0_STN5_RX_DP<87>")
	)
	(segment
		(start 91.130628 -393.725654)
		(end 90.644726 -393.822174)
		(width 0.1651)
		(layer "In9.Cu")
		(net "P5E_PEX0_STN5_RX_DP<87>")
	)
	(segment
		(start 99.4664 -371.090698)
		(end 99.14382 -385.492498)
		(width 0.1651)
		(layer "In9.Cu")
		(net "P5E_PEX0_STN5_RX_DP<87>")
	)
	(segment
		(start 90.009472 -393.948666)
		(end 89.52357 -394.045186)
		(width 0.1651)
		(layer "In9.Cu")
		(net "P5E_PEX0_STN5_RX_DP<87>")
	)
	(segment
		(start 87.30996 -397.972026)
		(end 87.30996 -397.59001)
		(width 0.1651)
		(layer "In9.Cu")
		(net "P5E_PEX0_STN5_RX_DP<87>")
	)
	(segment
		(start 87.43696 -398.099026)
		(end 87.30996 -397.972026)
		(width 0.1651)
		(layer "In9.Cu")
		(net "P5E_PEX0_STN5_RX_DP<87>")
	)
	(segment
		(start 65.064132 -320.160396)
		(end 65.064132 -320.16065)
		(width 0.1143)
		(layer "In9.Cu")
		(net "P5E_PEX0_STN5_RX_DP<87>")
	)
	(segment
		(start 88.977978 -394.231622)
		(end 88.202262 -395.007338)
		(width 0.1651)
		(layer "In9.Cu")
		(net "P5E_PEX0_STN5_RX_DP<87>")
	)
	(segment
		(start 65.19672 -320.3575)
		(end 66.689986 -321.355212)
		(width 0.1651)
		(layer "In9.Cu")
		(net "P5E_PEX0_STN5_RX_DP<87>")
	)
	(segment
		(start 90.644726 -393.822174)
		(end 90.584782 -393.91209)
		(width 0.1651)
		(layer "In9.Cu")
		(net "P5E_PEX0_STN5_RX_DP<87>")
	)
	(segment
		(start 93.766386 -393.089384)
		(end 93.725238 -393.188952)
		(width 0.1651)
		(layer "In9.Cu")
		(net "P5E_PEX0_STN5_RX_DP<87>")
	)
	(segment
		(start 99.14382 -387.43001)
		(end 98.138996 -389.856472)
		(width 0.1651)
		(layer "In9.Cu")
		(net "P5E_PEX0_STN5_RX_DP<87>")
	)
	(segment
		(start 90.584782 -393.91209)
		(end 90.099134 -394.00861)
		(width 0.1651)
		(layer "In9.Cu")
		(net "P5E_PEX0_STN5_RX_DP<87>")
	)
	(segment
		(start 65.064386 -320.160904)
		(end 65.064386 -320.225166)
		(width 0.1143)
		(layer "In9.Cu")
		(net "P5E_PEX0_STN5_RX_DP<87>")
	)
	(segment
		(start 90.099134 -394.00861)
		(end 90.009472 -393.948666)
		(width 0.1651)
		(layer "In9.Cu")
		(net "P5E_PEX0_STN5_RX_DP<87>")
	)
	(segment
		(start 65.056258 -318.129666)
		(end 64.779652 -318.406272)
		(width 0.1143)
		(layer "In9.Cu")
		(net "P5E_PEX0_STN5_RX_DP<87>")
	)
	(segment
		(start 65.349882 -317.749936)
		(end 65.349882 -318.040766)
		(width 0.1143)
		(layer "In9.Cu")
		(net "P5E_PEX0_STN5_RX_DP<87>")
	)
	(segment
		(start 94.323916 -392.941048)
		(end 94.224348 -392.899646)
		(width 0.1651)
		(layer "In9.Cu")
		(net "P5E_PEX0_STN5_RX_DP<87>")
	)
	(segment
		(start 65.349882 -318.040766)
		(end 65.260982 -318.129666)
		(width 0.1143)
		(layer "In9.Cu")
		(net "P5E_PEX0_STN5_RX_DP<87>")
	)
	(segment
		(start 65.064132 -320.16065)
		(end 65.064386 -320.160904)
		(width 0.1143)
		(layer "In9.Cu")
		(net "P5E_PEX0_STN5_RX_DP<87>")
	)
	(segment
		(start 88.202262 -397.67383)
		(end 87.777066 -398.099026)
		(width 0.1651)
		(layer "In9.Cu")
		(net "P5E_PEX0_STN5_RX_DP<87>")
	)
	(segment
		(start 88.202262 -395.007338)
		(end 88.202262 -397.67383)
		(width 0.1651)
		(layer "In9.Cu")
		(net "P5E_PEX0_STN5_RX_DP<87>")
	)
	(segment
		(start 80.286098 -143.504666)
		(end 80.606138 -143.184626)
		(width 0.13462)
		(layer "F.Cu")
		(net "P5E_PEX0_STN0_TX_DP<8>")
	)
	(segment
		(start 80.606138 -143.184626)
		(end 81.237582 -143.184626)
		(width 0.13462)
		(layer "F.Cu")
		(net "P5E_PEX0_STN0_TX_DP<8>")
	)
	(segment
		(start 81.237582 -143.184626)
		(end 81.532222 -143.479266)
		(width 0.13462)
		(layer "F.Cu")
		(net "P5E_PEX0_STN0_TX_DP<8>")
	)
	(segment
		(start 82.127852 -276.316948)
		(end 81.879694 -276.565106)
		(width 0.1143)
		(layer "In9.Cu")
		(net "P5E_PEX0_STN0_TX_DP<8>")
	)
	(segment
		(start 87.668862 -146.078702)
		(end 88.070182 -146.480022)
		(width 0.1651)
		(layer "In9.Cu")
		(net "P5E_PEX0_STN0_TX_DP<8>")
	)
	(segment
		(start 81.882488 -260.280912)
		(end 81.882488 -261.21614)
		(width 0.1651)
		(layer "In9.Cu")
		(net "P5E_PEX0_STN0_TX_DP<8>")
	)
	(segment
		(start 92.147644 -154.332686)
		(end 92.147644 -158.440882)
		(width 0.1651)
		(layer "In9.Cu")
		(net "P5E_PEX0_STN0_TX_DP<8>")
	)
	(segment
		(start 83.641438 -173.177454)
		(end 82.418428 -177.738786)
		(width 0.1651)
		(layer "In9.Cu")
		(net "P5E_PEX0_STN0_TX_DP<8>")
	)
	(segment
		(start 89.422732 -148.154898)
		(end 89.859104 -148.807678)
		(width 0.1651)
		(layer "In9.Cu")
		(net "P5E_PEX0_STN0_TX_DP<8>")
	)
	(segment
		(start 82.784188 -271.8054)
		(end 82.829908 -271.85112)
		(width 0.1143)
		(layer "In9.Cu")
		(net "P5E_PEX0_STN0_TX_DP<8>")
	)
	(segment
		(start 87.543132 -146.078702)
		(end 87.668862 -146.078702)
		(width 0.1651)
		(layer "In9.Cu")
		(net "P5E_PEX0_STN0_TX_DP<8>")
	)
	(segment
		(start 80.4799 -199.893174)
		(end 80.480154 -199.893174)
		(width 0.1651)
		(layer "In9.Cu")
		(net "P5E_PEX0_STN0_TX_DP<8>")
	)
	(segment
		(start 81.879694 -276.565106)
		(end 81.879694 -276.785578)
		(width 0.1143)
		(layer "In9.Cu")
		(net "P5E_PEX0_STN0_TX_DP<8>")
	)
	(segment
		(start 90.306398 -149.887178)
		(end 90.306144 -149.887178)
		(width 0.1651)
		(layer "In9.Cu")
		(net "P5E_PEX0_STN0_TX_DP<8>")
	)
	(segment
		(start 83.586828 -142.9766)
		(end 84.044282 -143.166084)
		(width 0.1651)
		(layer "In9.Cu")
		(net "P5E_PEX0_STN0_TX_DP<8>")
	)
	(segment
		(start 82.298286 -143.188436)
		(end 82.810096 -142.9766)
		(width 0.1651)
		(layer "In9.Cu")
		(net "P5E_PEX0_STN0_TX_DP<8>")
	)
	(segment
		(start 90.048588 -149.265132)
		(end 90.000328 -149.38121)
		(width 0.1651)
		(layer "In9.Cu")
		(net "P5E_PEX0_STN0_TX_DP<8>")
	)
	(segment
		(start 85.259672 -143.669512)
		(end 86.36635 -144.77619)
		(width 0.1651)
		(layer "In9.Cu")
		(net "P5E_PEX0_STN0_TX_DP<8>")
	)
	(segment
		(start 89.04859 -147.595082)
		(end 89.024206 -147.718272)
		(width 0.1651)
		(layer "In9.Cu")
		(net "P5E_PEX0_STN0_TX_DP<8>")
	)
	(segment
		(start 82.784188 -271.776952)
		(end 82.784188 -271.8054)
		(width 0.1143)
		(layer "In9.Cu")
		(net "P5E_PEX0_STN0_TX_DP<8>")
	)
	(segment
		(start 81.882488 -261.21614)
		(end 82.784188 -270.372078)
		(width 0.1651)
		(layer "In9.Cu")
		(net "P5E_PEX0_STN0_TX_DP<8>")
	)
	(segment
		(start 90.19032 -149.839172)
		(end 90.306398 -149.887178)
		(width 0.1651)
		(layer "In9.Cu")
		(net "P5E_PEX0_STN0_TX_DP<8>")
	)
	(segment
		(start 89.024206 -147.718272)
		(end 89.299542 -148.13026)
		(width 0.1651)
		(layer "In9.Cu")
		(net "P5E_PEX0_STN0_TX_DP<8>")
	)
	(segment
		(start 88.070182 -146.605752)
		(end 88.420448 -146.956018)
		(width 0.1651)
		(layer "In9.Cu")
		(net "P5E_PEX0_STN0_TX_DP<8>")
	)
	(segment
		(start 89.859104 -148.807678)
		(end 90.048588 -149.265132)
		(width 0.1651)
		(layer "In9.Cu")
		(net "P5E_PEX0_STN0_TX_DP<8>")
	)
	(segment
		(start 87.192612 -145.728182)
		(end 87.543132 -146.078702)
		(width 0.1651)
		(layer "In9.Cu")
		(net "P5E_PEX0_STN0_TX_DP<8>")
	)
	(segment
		(start 84.044282 -143.166084)
		(end 84.092288 -143.282162)
		(width 0.1651)
		(layer "In9.Cu")
		(net "P5E_PEX0_STN0_TX_DP<8>")
	)
	(segment
		(start 82.829908 -271.85112)
		(end 82.829908 -276.183598)
		(width 0.1143)
		(layer "In9.Cu")
		(net "P5E_PEX0_STN0_TX_DP<8>")
	)
	(segment
		(start 90.306144 -149.887178)
		(end 92.147644 -154.332686)
		(width 0.1651)
		(layer "In9.Cu")
		(net "P5E_PEX0_STN0_TX_DP<8>")
	)
	(segment
		(start 81.765394 -276.899878)
		(end 81.499964 -276.899878)
		(width 0.1143)
		(layer "In9.Cu")
		(net "P5E_PEX0_STN0_TX_DP<8>")
	)
	(segment
		(start 90.000328 -149.38121)
		(end 90.19032 -149.839172)
		(width 0.1651)
		(layer "In9.Cu")
		(net "P5E_PEX0_STN0_TX_DP<8>")
	)
	(segment
		(start 88.773508 -147.183348)
		(end 89.04859 -147.595082)
		(width 0.1651)
		(layer "In9.Cu")
		(net "P5E_PEX0_STN0_TX_DP<8>")
	)
	(segment
		(start 86.36635 -144.77619)
		(end 86.36635 -144.90192)
		(width 0.1651)
		(layer "In9.Cu")
		(net "P5E_PEX0_STN0_TX_DP<8>")
	)
	(segment
		(start 89.422986 -148.154898)
		(end 89.422732 -148.154898)
		(width 0.1651)
		(layer "In9.Cu")
		(net "P5E_PEX0_STN0_TX_DP<8>")
	)
	(segment
		(start 87.192612 -145.602452)
		(end 87.192612 -145.728182)
		(width 0.1651)
		(layer "In9.Cu")
		(net "P5E_PEX0_STN0_TX_DP<8>")
	)
	(segment
		(start 82.810096 -142.9766)
		(end 83.586828 -142.9766)
		(width 0.1651)
		(layer "In9.Cu")
		(net "P5E_PEX0_STN0_TX_DP<8>")
	)
	(segment
		(start 82.696558 -276.316948)
		(end 82.127852 -276.316948)
		(width 0.1143)
		(layer "In9.Cu")
		(net "P5E_PEX0_STN0_TX_DP<8>")
	)
	(segment
		(start 78.54188 -222.047308)
		(end 81.882488 -260.280912)
		(width 0.1651)
		(layer "In9.Cu")
		(net "P5E_PEX0_STN0_TX_DP<8>")
	)
	(segment
		(start 80.480154 -199.893174)
		(end 78.54188 -222.047308)
		(width 0.1651)
		(layer "In9.Cu")
		(net "P5E_PEX0_STN0_TX_DP<8>")
	)
	(segment
		(start 81.879694 -276.785578)
		(end 81.765394 -276.899878)
		(width 0.1143)
		(layer "In9.Cu")
		(net "P5E_PEX0_STN0_TX_DP<8>")
	)
	(segment
		(start 86.36635 -144.90192)
		(end 86.71687 -145.25244)
		(width 0.1651)
		(layer "In9.Cu")
		(net "P5E_PEX0_STN0_TX_DP<8>")
	)
	(segment
		(start 88.546178 -146.956018)
		(end 88.773508 -147.183348)
		(width 0.1651)
		(layer "In9.Cu")
		(net "P5E_PEX0_STN0_TX_DP<8>")
	)
	(segment
		(start 81.823052 -143.188436)
		(end 82.298286 -143.188436)
		(width 0.1651)
		(layer "In9.Cu")
		(net "P5E_PEX0_STN0_TX_DP<8>")
	)
	(segment
		(start 88.420448 -146.956018)
		(end 88.546178 -146.956018)
		(width 0.1651)
		(layer "In9.Cu")
		(net "P5E_PEX0_STN0_TX_DP<8>")
	)
	(segment
		(start 88.070182 -146.480022)
		(end 88.070182 -146.605752)
		(width 0.1651)
		(layer "In9.Cu")
		(net "P5E_PEX0_STN0_TX_DP<8>")
	)
	(segment
		(start 84.55025 -143.4719)
		(end 84.666328 -143.423894)
		(width 0.1651)
		(layer "In9.Cu")
		(net "P5E_PEX0_STN0_TX_DP<8>")
	)
	(segment
		(start 89.299542 -148.13026)
		(end 89.422986 -148.154898)
		(width 0.1651)
		(layer "In9.Cu")
		(net "P5E_PEX0_STN0_TX_DP<8>")
	)
	(segment
		(start 86.8426 -145.25244)
		(end 87.192612 -145.602452)
		(width 0.1651)
		(layer "In9.Cu")
		(net "P5E_PEX0_STN0_TX_DP<8>")
	)
	(segment
		(start 81.532222 -143.479266)
		(end 81.823052 -143.188436)
		(width 0.1651)
		(layer "In9.Cu")
		(net "P5E_PEX0_STN0_TX_DP<8>")
	)
	(segment
		(start 86.71687 -145.25244)
		(end 86.8426 -145.25244)
		(width 0.1651)
		(layer "In9.Cu")
		(net "P5E_PEX0_STN0_TX_DP<8>")
	)
	(segment
		(start 82.418428 -177.738786)
		(end 80.4799 -199.893174)
		(width 0.1651)
		(layer "In9.Cu")
		(net "P5E_PEX0_STN0_TX_DP<8>")
	)
	(segment
		(start 84.092288 -143.282162)
		(end 84.55025 -143.4719)
		(width 0.1651)
		(layer "In9.Cu")
		(net "P5E_PEX0_STN0_TX_DP<8>")
	)
	(segment
		(start 82.829908 -276.183598)
		(end 82.696558 -276.316948)
		(width 0.1143)
		(layer "In9.Cu")
		(net "P5E_PEX0_STN0_TX_DP<8>")
	)
	(segment
		(start 92.147644 -158.440882)
		(end 83.641438 -173.177454)
		(width 0.1651)
		(layer "In9.Cu")
		(net "P5E_PEX0_STN0_TX_DP<8>")
	)
	(segment
		(start 84.666328 -143.423894)
		(end 85.259672 -143.669512)
		(width 0.1651)
		(layer "In9.Cu")
		(net "P5E_PEX0_STN0_TX_DP<8>")
	)
	(segment
		(start 82.784188 -270.372078)
		(end 82.784188 -271.776952)
		(width 0.1651)
		(layer "In9.Cu")
		(net "P5E_PEX0_STN0_TX_DP<8>")
	)
	(segment
		(start 90.395806 -339.745066)
		(end 68.315078 -324.991222)
		(width 0.1651)
		(layer "In9.Cu")
		(net "P5E_PEX0_STN5_RX_DN<84>")
	)
	(segment
		(start 91.480132 -341.773764)
		(end 90.395806 -339.745066)
		(width 0.1651)
		(layer "In9.Cu")
		(net "P5E_PEX0_STN5_RX_DN<84>")
	)
	(segment
		(start 62.665864 -321.628008)
		(end 62.165738 -320.420746)
		(width 0.1651)
		(layer "In9.Cu")
		(net "P5E_PEX0_STN5_RX_DN<84>")
	)
	(segment
		(start 68.315078 -324.991222)
		(end 64.412368 -323.374512)
		(width 0.1651)
		(layer "In9.Cu")
		(net "P5E_PEX0_STN5_RX_DN<84>")
	)
	(segment
		(start 81.926684 -394.696696)
		(end 84.423758 -392.199622)
		(width 0.1651)
		(layer "In9.Cu")
		(net "P5E_PEX0_STN5_RX_DN<84>")
	)
	(segment
		(start 62.165738 -320.420746)
		(end 62.165738 -319.995296)
		(width 0.1651)
		(layer "In9.Cu")
		(net "P5E_PEX0_STN5_RX_DN<84>")
	)
	(segment
		(start 91.480132 -357.820722)
		(end 91.480132 -341.773764)
		(width 0.1651)
		(layer "In9.Cu")
		(net "P5E_PEX0_STN5_RX_DN<84>")
	)
	(segment
		(start 62.165738 -319.995296)
		(end 62.165738 -319.966848)
		(width 0.1143)
		(layer "In9.Cu")
		(net "P5E_PEX0_STN5_RX_DN<84>")
	)
	(segment
		(start 96.85274 -371.030754)
		(end 96.85274 -370.722144)
		(width 0.1651)
		(layer "In9.Cu")
		(net "P5E_PEX0_STN5_RX_DN<84>")
	)
	(segment
		(start 80.837024 -397.281146)
		(end 81.342992 -397.281146)
		(width 0.1651)
		(layer "In9.Cu")
		(net "P5E_PEX0_STN5_RX_DN<84>")
	)
	(segment
		(start 62.499748 -316.508892)
		(end 62.499748 -316.799722)
		(width 0.1143)
		(layer "In9.Cu")
		(net "P5E_PEX0_STN5_RX_DN<84>")
	)
	(segment
		(start 95.248476 -363.837728)
		(end 91.689936 -358.51211)
		(width 0.1651)
		(layer "In9.Cu")
		(net "P5E_PEX0_STN5_RX_DN<84>")
	)
	(segment
		(start 80.710024 -397.790162)
		(end 80.710024 -397.408146)
		(width 0.1651)
		(layer "In9.Cu")
		(net "P5E_PEX0_STN5_RX_DN<84>")
	)
	(segment
		(start 96.53016 -386.865622)
		(end 96.53016 -385.463034)
		(width 0.1651)
		(layer "In9.Cu")
		(net "P5E_PEX0_STN5_RX_DN<84>")
	)
	(segment
		(start 81.342992 -397.281146)
		(end 81.926684 -396.697454)
		(width 0.1651)
		(layer "In9.Cu")
		(net "P5E_PEX0_STN5_RX_DN<84>")
	)
	(segment
		(start 84.423758 -392.199622)
		(end 93.290136 -390.4361)
		(width 0.1651)
		(layer "In9.Cu")
		(net "P5E_PEX0_STN5_RX_DN<84>")
	)
	(segment
		(start 94.34068 -390.000744)
		(end 95.861632 -388.479792)
		(width 0.1651)
		(layer "In9.Cu")
		(net "P5E_PEX0_STN5_RX_DN<84>")
	)
	(segment
		(start 81.926684 -396.697454)
		(end 81.926684 -394.696696)
		(width 0.1651)
		(layer "In9.Cu")
		(net "P5E_PEX0_STN5_RX_DN<84>")
	)
	(segment
		(start 93.290136 -390.4361)
		(end 94.34068 -390.000744)
		(width 0.1651)
		(layer "In9.Cu")
		(net "P5E_PEX0_STN5_RX_DN<84>")
	)
	(segment
		(start 62.120018 -319.921128)
		(end 62.120018 -316.585092)
		(width 0.1143)
		(layer "In9.Cu")
		(net "P5E_PEX0_STN5_RX_DN<84>")
	)
	(segment
		(start 62.120018 -316.585092)
		(end 62.285118 -316.419992)
		(width 0.1143)
		(layer "In9.Cu")
		(net "P5E_PEX0_STN5_RX_DN<84>")
	)
	(segment
		(start 62.410848 -316.419992)
		(end 62.499748 -316.508892)
		(width 0.1143)
		(layer "In9.Cu")
		(net "P5E_PEX0_STN5_RX_DN<84>")
	)
	(segment
		(start 95.861632 -388.479792)
		(end 96.53016 -386.865622)
		(width 0.1651)
		(layer "In9.Cu")
		(net "P5E_PEX0_STN5_RX_DN<84>")
	)
	(segment
		(start 80.710024 -397.408146)
		(end 80.837024 -397.281146)
		(width 0.1651)
		(layer "In9.Cu")
		(net "P5E_PEX0_STN5_RX_DN<84>")
	)
	(segment
		(start 96.53016 -385.463034)
		(end 96.85274 -371.030754)
		(width 0.1651)
		(layer "In9.Cu")
		(net "P5E_PEX0_STN5_RX_DN<84>")
	)
	(segment
		(start 91.689936 -358.51211)
		(end 91.480132 -357.820722)
		(width 0.1651)
		(layer "In9.Cu")
		(net "P5E_PEX0_STN5_RX_DN<84>")
	)
	(segment
		(start 62.165738 -319.966848)
		(end 62.120018 -319.921128)
		(width 0.1143)
		(layer "In9.Cu")
		(net "P5E_PEX0_STN5_RX_DN<84>")
	)
	(segment
		(start 95.931736 -366.0902)
		(end 95.248476 -363.837728)
		(width 0.1651)
		(layer "In9.Cu")
		(net "P5E_PEX0_STN5_RX_DN<84>")
	)
	(segment
		(start 62.285118 -316.419992)
		(end 62.410848 -316.419992)
		(width 0.1143)
		(layer "In9.Cu")
		(net "P5E_PEX0_STN5_RX_DN<84>")
	)
	(segment
		(start 64.412368 -323.374512)
		(end 62.665864 -321.628008)
		(width 0.1651)
		(layer "In9.Cu")
		(net "P5E_PEX0_STN5_RX_DN<84>")
	)
	(segment
		(start 96.85274 -370.722144)
		(end 95.931736 -366.0902)
		(width 0.1651)
		(layer "In9.Cu")
		(net "P5E_PEX0_STN5_RX_DN<84>")
	)
	(segment
		(start 32.062928 -350.685354)
		(end 31.742888 -350.365314)
		(width 0.13462)
		(layer "F.Cu")
		(net "P5E_PEX0_STN7_TX_C_DP<118>")
	)
	(segment
		(start 31.768288 -351.611438)
		(end 32.062928 -351.316798)
		(width 0.13462)
		(layer "F.Cu")
		(net "P5E_PEX0_STN7_TX_C_DP<118>")
	)
	(segment
		(start 32.062928 -351.316798)
		(end 32.062928 -350.685354)
		(width 0.13462)
		(layer "F.Cu")
		(net "P5E_PEX0_STN7_TX_C_DP<118>")
	)
	(segment
		(start 41.151302 -393.956032)
		(end 41.151302 -393.830302)
		(width 0.1651)
		(layer "In7.Cu")
		(net "P5E_PEX0_STN7_TX_C_DP<118>")
	)
	(segment
		(start 38.302438 -391.249408)
		(end 38.18636 -391.297668)
		(width 0.1651)
		(layer "In7.Cu")
		(net "P5E_PEX0_STN7_TX_C_DP<118>")
	)
	(segment
		(start 37.222938 -390.802114)
		(end 37.10686 -390.850374)
		(width 0.1651)
		(layer "In7.Cu")
		(net "P5E_PEX0_STN7_TX_C_DP<118>")
	)
	(segment
		(start 39.975028 -392.654028)
		(end 39.849298 -392.654028)
		(width 0.1651)
		(layer "In7.Cu")
		(net "P5E_PEX0_STN7_TX_C_DP<118>")
	)
	(segment
		(start 30.244288 -388.016496)
		(end 27.180032 -386.747258)
		(width 0.1651)
		(layer "In7.Cu")
		(net "P5E_PEX0_STN7_TX_C_DP<118>")
	)
	(segment
		(start 25.0317 -371.751352)
		(end 25.823672 -368.224054)
		(width 0.1651)
		(layer "In7.Cu")
		(net "P5E_PEX0_STN7_TX_C_DP<118>")
	)
	(segment
		(start 41.1099 -400.390106)
		(end 41.1099 -400.772122)
		(width 0.1651)
		(layer "In7.Cu")
		(net "P5E_PEX0_STN7_TX_C_DP<118>")
	)
	(segment
		(start 30.504638 -353.990402)
		(end 32.059118 -352.435922)
		(width 0.1651)
		(layer "In7.Cu")
		(net "P5E_PEX0_STN7_TX_C_DP<118>")
	)
	(segment
		(start 37.10686 -390.850374)
		(end 36.648898 -390.660636)
		(width 0.1651)
		(layer "In7.Cu")
		(net "P5E_PEX0_STN7_TX_C_DP<118>")
	)
	(segment
		(start 36.600384 -390.544558)
		(end 30.496002 -388.016496)
		(width 0.1651)
		(layer "In7.Cu")
		(net "P5E_PEX0_STN7_TX_C_DP<118>")
	)
	(segment
		(start 30.284928 -358.792018)
		(end 30.504638 -357.814372)
		(width 0.1651)
		(layer "In7.Cu")
		(net "P5E_PEX0_STN7_TX_C_DP<118>")
	)
	(segment
		(start 40.67556 -393.48029)
		(end 40.32504 -393.12977)
		(width 0.1651)
		(layer "In7.Cu")
		(net "P5E_PEX0_STN7_TX_C_DP<118>")
	)
	(segment
		(start 38.759892 -391.438892)
		(end 38.302438 -391.249408)
		(width 0.1651)
		(layer "In7.Cu")
		(net "P5E_PEX0_STN7_TX_C_DP<118>")
	)
	(segment
		(start 30.496002 -388.016496)
		(end 30.244288 -388.016496)
		(width 0.1651)
		(layer "In7.Cu")
		(net "P5E_PEX0_STN7_TX_C_DP<118>")
	)
	(segment
		(start 30.504638 -357.814372)
		(end 30.504638 -353.990402)
		(width 0.1651)
		(layer "In7.Cu")
		(net "P5E_PEX0_STN7_TX_C_DP<118>")
	)
	(segment
		(start 41.2369 -400.899122)
		(end 41.593516 -400.899122)
		(width 0.1651)
		(layer "In7.Cu")
		(net "P5E_PEX0_STN7_TX_C_DP<118>")
	)
	(segment
		(start 26.306526 -385.873752)
		(end 25.615138 -384.337052)
		(width 0.1651)
		(layer "In7.Cu")
		(net "P5E_PEX0_STN7_TX_C_DP<118>")
	)
	(segment
		(start 41.151302 -393.830302)
		(end 40.80129 -393.48029)
		(width 0.1651)
		(layer "In7.Cu")
		(net "P5E_PEX0_STN7_TX_C_DP<118>")
	)
	(segment
		(start 36.648898 -390.660636)
		(end 36.600638 -390.544558)
		(width 0.1651)
		(layer "In7.Cu")
		(net "P5E_PEX0_STN7_TX_C_DP<118>")
	)
	(segment
		(start 25.0317 -374.63857)
		(end 25.0317 -371.751352)
		(width 0.1651)
		(layer "In7.Cu")
		(net "P5E_PEX0_STN7_TX_C_DP<118>")
	)
	(segment
		(start 40.80129 -393.48029)
		(end 40.67556 -393.48029)
		(width 0.1651)
		(layer "In7.Cu")
		(net "P5E_PEX0_STN7_TX_C_DP<118>")
	)
	(segment
		(start 39.498778 -392.177778)
		(end 38.759892 -391.438892)
		(width 0.1651)
		(layer "In7.Cu")
		(net "P5E_PEX0_STN7_TX_C_DP<118>")
	)
	(segment
		(start 42.002202 -394.681202)
		(end 41.627298 -394.306298)
		(width 0.1651)
		(layer "In7.Cu")
		(net "P5E_PEX0_STN7_TX_C_DP<118>")
	)
	(segment
		(start 40.32504 -393.00404)
		(end 39.975028 -392.654028)
		(width 0.1651)
		(layer "In7.Cu")
		(net "P5E_PEX0_STN7_TX_C_DP<118>")
	)
	(segment
		(start 25.823672 -368.224054)
		(end 30.284928 -358.792018)
		(width 0.1651)
		(layer "In7.Cu")
		(net "P5E_PEX0_STN7_TX_C_DP<118>")
	)
	(segment
		(start 38.18636 -391.297668)
		(end 37.728398 -391.10793)
		(width 0.1651)
		(layer "In7.Cu")
		(net "P5E_PEX0_STN7_TX_C_DP<118>")
	)
	(segment
		(start 39.849298 -392.654028)
		(end 39.498778 -392.303508)
		(width 0.1651)
		(layer "In7.Cu")
		(net "P5E_PEX0_STN7_TX_C_DP<118>")
	)
	(segment
		(start 39.498778 -392.303508)
		(end 39.498778 -392.177778)
		(width 0.1651)
		(layer "In7.Cu")
		(net "P5E_PEX0_STN7_TX_C_DP<118>")
	)
	(segment
		(start 32.059118 -351.902268)
		(end 31.768288 -351.611438)
		(width 0.1651)
		(layer "In7.Cu")
		(net "P5E_PEX0_STN7_TX_C_DP<118>")
	)
	(segment
		(start 41.627298 -394.306298)
		(end 41.501568 -394.306298)
		(width 0.1651)
		(layer "In7.Cu")
		(net "P5E_PEX0_STN7_TX_C_DP<118>")
	)
	(segment
		(start 41.1099 -400.772122)
		(end 41.2369 -400.899122)
		(width 0.1651)
		(layer "In7.Cu")
		(net "P5E_PEX0_STN7_TX_C_DP<118>")
	)
	(segment
		(start 37.680392 -390.991598)
		(end 37.222938 -390.802114)
		(width 0.1651)
		(layer "In7.Cu")
		(net "P5E_PEX0_STN7_TX_C_DP<118>")
	)
	(segment
		(start 42.002202 -400.490436)
		(end 42.002202 -394.681202)
		(width 0.1651)
		(layer "In7.Cu")
		(net "P5E_PEX0_STN7_TX_C_DP<118>")
	)
	(segment
		(start 32.059118 -352.435922)
		(end 32.059118 -351.902268)
		(width 0.1651)
		(layer "In7.Cu")
		(net "P5E_PEX0_STN7_TX_C_DP<118>")
	)
	(segment
		(start 36.600638 -390.544558)
		(end 36.600384 -390.544558)
		(width 0.1651)
		(layer "In7.Cu")
		(net "P5E_PEX0_STN7_TX_C_DP<118>")
	)
	(segment
		(start 37.728398 -391.10793)
		(end 37.680392 -390.991598)
		(width 0.1651)
		(layer "In7.Cu")
		(net "P5E_PEX0_STN7_TX_C_DP<118>")
	)
	(segment
		(start 41.593516 -400.899122)
		(end 42.002202 -400.490436)
		(width 0.1651)
		(layer "In7.Cu")
		(net "P5E_PEX0_STN7_TX_C_DP<118>")
	)
	(segment
		(start 27.180032 -386.747258)
		(end 26.306526 -385.873752)
		(width 0.1651)
		(layer "In7.Cu")
		(net "P5E_PEX0_STN7_TX_C_DP<118>")
	)
	(segment
		(start 41.501568 -394.306298)
		(end 41.151302 -393.956032)
		(width 0.1651)
		(layer "In7.Cu")
		(net "P5E_PEX0_STN7_TX_C_DP<118>")
	)
	(segment
		(start 25.615138 -384.337052)
		(end 25.0317 -374.63857)
		(width 0.1651)
		(layer "In7.Cu")
		(net "P5E_PEX0_STN7_TX_C_DP<118>")
	)
	(segment
		(start 40.32504 -393.12977)
		(end 40.32504 -393.00404)
		(width 0.1651)
		(layer "In7.Cu")
		(net "P5E_PEX0_STN7_TX_C_DP<118>")
	)
	(segment
		(start 70.699122 -357.75773)
		(end 70.993762 -357.46309)
		(width 0.13462)
		(layer "F.Cu")
		(net "P5E_PEX0_STN5_TX_C_DP<85>")
	)
	(segment
		(start 70.993762 -357.46309)
		(end 70.993762 -356.831646)
		(width 0.13462)
		(layer "F.Cu")
		(net "P5E_PEX0_STN5_TX_C_DP<85>")
	)
	(segment
		(start 70.993762 -356.831646)
		(end 70.673722 -356.511606)
		(width 0.13462)
		(layer "F.Cu")
		(net "P5E_PEX0_STN5_TX_C_DP<85>")
	)
	(segment
		(start 82.07629 -392.49604)
		(end 81.960212 -392.5443)
		(width 0.1651)
		(layer "In7.Cu")
		(net "P5E_PEX0_STN5_TX_C_DP<85>")
	)
	(segment
		(start 83.036918 -405.899112)
		(end 83.451192 -405.899112)
		(width 0.1651)
		(layer "In7.Cu")
		(net "P5E_PEX0_STN5_TX_C_DP<85>")
	)
	(segment
		(start 82.909918 -405.390096)
		(end 82.909918 -405.772112)
		(width 0.1651)
		(layer "In7.Cu")
		(net "P5E_PEX0_STN5_TX_C_DP<85>")
	)
	(segment
		(start 82.533744 -392.685524)
		(end 82.07629 -392.49604)
		(width 0.1651)
		(layer "In7.Cu")
		(net "P5E_PEX0_STN5_TX_C_DP<85>")
	)
	(segment
		(start 68.689982 -384.744976)
		(end 68.689982 -378.988066)
		(width 0.1651)
		(layer "In7.Cu")
		(net "P5E_PEX0_STN5_TX_C_DP<85>")
	)
	(segment
		(start 81.960212 -392.5443)
		(end 81.50225 -392.354308)
		(width 0.1651)
		(layer "In7.Cu")
		(net "P5E_PEX0_STN5_TX_C_DP<85>")
	)
	(segment
		(start 83.80222 -393.954)
		(end 82.533744 -392.685524)
		(width 0.1651)
		(layer "In7.Cu")
		(net "P5E_PEX0_STN5_TX_C_DP<85>")
	)
	(segment
		(start 82.909918 -405.772112)
		(end 83.036918 -405.899112)
		(width 0.1651)
		(layer "In7.Cu")
		(net "P5E_PEX0_STN5_TX_C_DP<85>")
	)
	(segment
		(start 68.534026 -367.03635)
		(end 70.989952 -358.69753)
		(width 0.1651)
		(layer "In7.Cu")
		(net "P5E_PEX0_STN5_TX_C_DP<85>")
	)
	(segment
		(start 83.80222 -405.548084)
		(end 83.80222 -393.954)
		(width 0.1651)
		(layer "In7.Cu")
		(net "P5E_PEX0_STN5_TX_C_DP<85>")
	)
	(segment
		(start 81.454244 -392.238484)
		(end 70.825868 -387.835902)
		(width 0.1651)
		(layer "In7.Cu")
		(net "P5E_PEX0_STN5_TX_C_DP<85>")
	)
	(segment
		(start 70.989952 -358.04856)
		(end 70.699122 -357.75773)
		(width 0.1651)
		(layer "In7.Cu")
		(net "P5E_PEX0_STN5_TX_C_DP<85>")
	)
	(segment
		(start 81.50225 -392.354308)
		(end 81.454244 -392.23823)
		(width 0.1651)
		(layer "In7.Cu")
		(net "P5E_PEX0_STN5_TX_C_DP<85>")
	)
	(segment
		(start 68.689982 -378.988066)
		(end 68.534026 -367.03635)
		(width 0.1651)
		(layer "In7.Cu")
		(net "P5E_PEX0_STN5_TX_C_DP<85>")
	)
	(segment
		(start 81.454244 -392.23823)
		(end 81.454244 -392.238484)
		(width 0.1651)
		(layer "In7.Cu")
		(net "P5E_PEX0_STN5_TX_C_DP<85>")
	)
	(segment
		(start 70.825868 -387.835902)
		(end 69.365114 -386.375148)
		(width 0.1651)
		(layer "In7.Cu")
		(net "P5E_PEX0_STN5_TX_C_DP<85>")
	)
	(segment
		(start 69.365114 -386.375148)
		(end 68.689982 -384.744976)
		(width 0.1651)
		(layer "In7.Cu")
		(net "P5E_PEX0_STN5_TX_C_DP<85>")
	)
	(segment
		(start 70.989952 -358.69753)
		(end 70.989952 -358.04856)
		(width 0.1651)
		(layer "In7.Cu")
		(net "P5E_PEX0_STN5_TX_C_DP<85>")
	)
	(segment
		(start 83.451192 -405.899112)
		(end 83.80222 -405.548084)
		(width 0.1651)
		(layer "In7.Cu")
		(net "P5E_PEX0_STN5_TX_C_DP<85>")
	)
	(segment
		(start 80.286098 -146.190208)
		(end 80.606138 -146.510248)
		(width 0.13462)
		(layer "F.Cu")
		(net "P5E_PEX0_STN0_TX_DN<10>")
	)
	(segment
		(start 80.606138 -146.510248)
		(end 81.237582 -146.510248)
		(width 0.13462)
		(layer "F.Cu")
		(net "P5E_PEX0_STN0_TX_DN<10>")
	)
	(segment
		(start 81.237582 -146.510248)
		(end 81.532222 -146.215608)
		(width 0.13462)
		(layer "F.Cu")
		(net "P5E_PEX0_STN0_TX_DN<10>")
	)
	(segment
		(start 81.532222 -146.215608)
		(end 81.823052 -146.506438)
		(width 0.1651)
		(layer "In9.Cu")
		(net "P5E_PEX0_STN0_TX_DN<10>")
	)
	(segment
		(start 76.849986 -222.099124)
		(end 80.228948 -260.752844)
		(width 0.1651)
		(layer "In9.Cu")
		(net "P5E_PEX0_STN0_TX_DN<10>")
	)
	(segment
		(start 79.22006 -280.025856)
		(end 79.323692 -280.129488)
		(width 0.1143)
		(layer "In9.Cu")
		(net "P5E_PEX0_STN0_TX_DN<10>")
	)
	(segment
		(start 80.228948 -260.752844)
		(end 80.228948 -268.829536)
		(width 0.1651)
		(layer "In9.Cu")
		(net "P5E_PEX0_STN0_TX_DN<10>")
	)
	(segment
		(start 79.59979 -280.015188)
		(end 79.59979 -279.749758)
		(width 0.1143)
		(layer "In9.Cu")
		(net "P5E_PEX0_STN0_TX_DN<10>")
	)
	(segment
		(start 84.028788 -146.506438)
		(end 84.050124 -146.527774)
		(width 0.1651)
		(layer "In9.Cu")
		(net "P5E_PEX0_STN0_TX_DN<10>")
	)
	(segment
		(start 82.074766 -172.601128)
		(end 80.753458 -177.529236)
		(width 0.1651)
		(layer "In9.Cu")
		(net "P5E_PEX0_STN0_TX_DN<10>")
	)
	(segment
		(start 79.22006 -271.600168)
		(end 79.22006 -280.025856)
		(width 0.1143)
		(layer "In9.Cu")
		(net "P5E_PEX0_STN0_TX_DN<10>")
	)
	(segment
		(start 85.941408 -147.31111)
		(end 87.347806 -148.717508)
		(width 0.1651)
		(layer "In9.Cu")
		(net "P5E_PEX0_STN0_TX_DN<10>")
	)
	(segment
		(start 79.26578 -271.155414)
		(end 79.26578 -271.526)
		(width 0.1651)
		(layer "In9.Cu")
		(net "P5E_PEX0_STN0_TX_DN<10>")
	)
	(segment
		(start 89.027 -151.238204)
		(end 90.494104 -154.780488)
		(width 0.1651)
		(layer "In9.Cu")
		(net "P5E_PEX0_STN0_TX_DN<10>")
	)
	(segment
		(start 87.347806 -148.725128)
		(end 89.027 -151.238204)
		(width 0.1651)
		(layer "In9.Cu")
		(net "P5E_PEX0_STN0_TX_DN<10>")
	)
	(segment
		(start 80.753458 -177.529236)
		(end 76.849986 -222.099124)
		(width 0.1651)
		(layer "In9.Cu")
		(net "P5E_PEX0_STN0_TX_DN<10>")
	)
	(segment
		(start 90.494104 -154.780488)
		(end 90.494104 -158.01594)
		(width 0.1651)
		(layer "In9.Cu")
		(net "P5E_PEX0_STN0_TX_DN<10>")
	)
	(segment
		(start 87.347806 -148.717508)
		(end 87.347806 -148.725128)
		(width 0.1651)
		(layer "In9.Cu")
		(net "P5E_PEX0_STN0_TX_DN<10>")
	)
	(segment
		(start 79.26578 -271.526)
		(end 79.26578 -271.554448)
		(width 0.1143)
		(layer "In9.Cu")
		(net "P5E_PEX0_STN0_TX_DN<10>")
	)
	(segment
		(start 79.48549 -280.129488)
		(end 79.59979 -280.015188)
		(width 0.1143)
		(layer "In9.Cu")
		(net "P5E_PEX0_STN0_TX_DN<10>")
	)
	(segment
		(start 84.050124 -146.527774)
		(end 85.941408 -147.31111)
		(width 0.1651)
		(layer "In9.Cu")
		(net "P5E_PEX0_STN0_TX_DN<10>")
	)
	(segment
		(start 90.494104 -158.01594)
		(end 82.074766 -172.601128)
		(width 0.1651)
		(layer "In9.Cu")
		(net "P5E_PEX0_STN0_TX_DN<10>")
	)
	(segment
		(start 79.323692 -280.129488)
		(end 79.48549 -280.129488)
		(width 0.1143)
		(layer "In9.Cu")
		(net "P5E_PEX0_STN0_TX_DN<10>")
	)
	(segment
		(start 80.228948 -268.829536)
		(end 79.26578 -271.155414)
		(width 0.1651)
		(layer "In9.Cu")
		(net "P5E_PEX0_STN0_TX_DN<10>")
	)
	(segment
		(start 81.823052 -146.506438)
		(end 84.028788 -146.506438)
		(width 0.1651)
		(layer "In9.Cu")
		(net "P5E_PEX0_STN0_TX_DN<10>")
	)
	(segment
		(start 79.26578 -271.554448)
		(end 79.22006 -271.600168)
		(width 0.1143)
		(layer "In9.Cu")
		(net "P5E_PEX0_STN0_TX_DN<10>")
	)
	(segment
		(start 28.293568 -305.988212)
		(end 28.848304 -305.433476)
		(width 0.1651)
		(layer "In5.Cu")
		(net "P5E_PEX0_STN7_RX_DN<115>")
	)
	(segment
		(start 33.625536 -304.115724)
		(end 35.56 -304.115724)
		(width 0.1651)
		(layer "In5.Cu")
		(net "P5E_PEX0_STN7_RX_DN<115>")
	)
	(segment
		(start 29.882592 -305.11496)
		(end 29.93771 -304.982372)
		(width 0.1651)
		(layer "In5.Cu")
		(net "P5E_PEX0_STN7_RX_DN<115>")
	)
	(segment
		(start 21.043646 -319.045082)
		(end 21.061934 -318.975232)
		(width 0.1651)
		(layer "In5.Cu")
		(net "P5E_PEX0_STN7_RX_DN<115>")
	)
	(segment
		(start 37.115242 -304.449734)
		(end 36.849812 -304.449734)
		(width 0.1143)
		(layer "In5.Cu")
		(net "P5E_PEX0_STN7_RX_DN<115>")
	)
	(segment
		(start 27.951938 -306.48783)
		(end 28.293568 -306.1462)
		(width 0.1651)
		(layer "In5.Cu")
		(net "P5E_PEX0_STN7_RX_DN<115>")
	)
	(segment
		(start 23.990554 -387.312154)
		(end 23.139908 -385.259072)
		(width 0.1651)
		(layer "In5.Cu")
		(net "P5E_PEX0_STN7_RX_DN<115>")
	)
	(segment
		(start 34.509964 -410.207968)
		(end 34.636964 -410.080968)
		(width 0.1651)
		(layer "In5.Cu")
		(net "P5E_PEX0_STN7_RX_DN<115>")
	)
	(segment
		(start 29.93771 -304.982372)
		(end 30.552644 -304.72761)
		(width 0.1651)
		(layer "In5.Cu")
		(net "P5E_PEX0_STN7_RX_DN<115>")
	)
	(segment
		(start 35.588448 -304.115724)
		(end 35.634168 -304.070004)
		(width 0.1143)
		(layer "In5.Cu")
		(net "P5E_PEX0_STN7_RX_DN<115>")
	)
	(segment
		(start 18.695924 -331.237082)
		(end 21.043646 -319.045082)
		(width 0.1651)
		(layer "In5.Cu")
		(net "P5E_PEX0_STN7_RX_DN<115>")
	)
	(segment
		(start 35.13582 -410.080968)
		(end 35.65906 -409.557728)
		(width 0.1651)
		(layer "In5.Cu")
		(net "P5E_PEX0_STN7_RX_DN<115>")
	)
	(segment
		(start 23.946358 -312.173112)
		(end 24.083772 -312.131456)
		(width 0.1651)
		(layer "In5.Cu")
		(net "P5E_PEX0_STN7_RX_DN<115>")
	)
	(segment
		(start 27.79395 -306.48783)
		(end 27.951938 -306.48783)
		(width 0.1651)
		(layer "In5.Cu")
		(net "P5E_PEX0_STN7_RX_DN<115>")
	)
	(segment
		(start 27.443938 -306.837842)
		(end 27.79395 -306.48783)
		(width 0.1651)
		(layer "In5.Cu")
		(net "P5E_PEX0_STN7_RX_DN<115>")
	)
	(segment
		(start 24.317452 -311.694322)
		(end 24.275796 -311.556654)
		(width 0.1651)
		(layer "In5.Cu")
		(net "P5E_PEX0_STN7_RX_DN<115>")
	)
	(segment
		(start 27.093418 -307.332126)
		(end 27.443938 -306.981606)
		(width 0.1651)
		(layer "In5.Cu")
		(net "P5E_PEX0_STN7_RX_DN<115>")
	)
	(segment
		(start 25.310338 -388.631938)
		(end 23.990554 -387.312154)
		(width 0.1651)
		(layer "In5.Cu")
		(net "P5E_PEX0_STN7_RX_DN<115>")
	)
	(segment
		(start 25.823672 -308.6608)
		(end 26.233882 -308.047898)
		(width 0.1651)
		(layer "In5.Cu")
		(net "P5E_PEX0_STN7_RX_DN<115>")
	)
	(segment
		(start 23.139908 -385.259072)
		(end 20.119086 -370.072412)
		(width 0.1651)
		(layer "In5.Cu")
		(net "P5E_PEX0_STN7_RX_DN<115>")
	)
	(segment
		(start 34.636964 -410.080968)
		(end 35.13582 -410.080968)
		(width 0.1651)
		(layer "In5.Cu")
		(net "P5E_PEX0_STN7_RX_DN<115>")
	)
	(segment
		(start 28.293568 -306.1462)
		(end 28.293568 -305.988212)
		(width 0.1651)
		(layer "In5.Cu")
		(net "P5E_PEX0_STN7_RX_DN<115>")
	)
	(segment
		(start 28.848304 -305.433476)
		(end 29.292042 -305.249834)
		(width 0.1651)
		(layer "In5.Cu")
		(net "P5E_PEX0_STN7_RX_DN<115>")
	)
	(segment
		(start 34.509964 -410.589984)
		(end 34.509964 -410.207968)
		(width 0.1651)
		(layer "In5.Cu")
		(net "P5E_PEX0_STN7_RX_DN<115>")
	)
	(segment
		(start 25.82291 -308.6608)
		(end 25.823672 -308.6608)
		(width 0.1651)
		(layer "In5.Cu")
		(net "P5E_PEX0_STN7_RX_DN<115>")
	)
	(segment
		(start 24.646382 -311.078372)
		(end 24.880062 -310.641238)
		(width 0.1651)
		(layer "In5.Cu")
		(net "P5E_PEX0_STN7_RX_DN<115>")
	)
	(segment
		(start 24.275796 -311.556654)
		(end 24.508968 -311.120028)
		(width 0.1651)
		(layer "In5.Cu")
		(net "P5E_PEX0_STN7_RX_DN<115>")
	)
	(segment
		(start 37.229542 -304.184304)
		(end 37.229542 -304.335434)
		(width 0.1143)
		(layer "In5.Cu")
		(net "P5E_PEX0_STN7_RX_DN<115>")
	)
	(segment
		(start 23.650448 -312.727086)
		(end 23.946358 -312.173112)
		(width 0.1651)
		(layer "In5.Cu")
		(net "P5E_PEX0_STN7_RX_DN<115>")
	)
	(segment
		(start 26.949654 -307.332126)
		(end 27.093418 -307.332126)
		(width 0.1651)
		(layer "In5.Cu")
		(net "P5E_PEX0_STN7_RX_DN<115>")
	)
	(segment
		(start 35.65906 -409.557728)
		(end 35.65906 -396.595092)
		(width 0.1651)
		(layer "In5.Cu")
		(net "P5E_PEX0_STN7_RX_DN<115>")
	)
	(segment
		(start 24.880062 -310.641238)
		(end 24.838406 -310.50357)
		(width 0.1651)
		(layer "In5.Cu")
		(net "P5E_PEX0_STN7_RX_DN<115>")
	)
	(segment
		(start 29.292042 -305.249834)
		(end 29.424884 -305.304952)
		(width 0.1651)
		(layer "In5.Cu")
		(net "P5E_PEX0_STN7_RX_DN<115>")
	)
	(segment
		(start 35.65906 -396.595092)
		(end 34.849308 -394.640308)
		(width 0.1651)
		(layer "In5.Cu")
		(net "P5E_PEX0_STN7_RX_DN<115>")
	)
	(segment
		(start 25.071578 -310.066944)
		(end 25.208992 -310.025288)
		(width 0.1651)
		(layer "In5.Cu")
		(net "P5E_PEX0_STN7_RX_DN<115>")
	)
	(segment
		(start 35.634168 -304.070004)
		(end 37.115242 -304.070004)
		(width 0.1143)
		(layer "In5.Cu")
		(net "P5E_PEX0_STN7_RX_DN<115>")
	)
	(segment
		(start 34.849308 -394.640308)
		(end 34.124392 -393.915392)
		(width 0.1651)
		(layer "In5.Cu")
		(net "P5E_PEX0_STN7_RX_DN<115>")
	)
	(segment
		(start 20.119086 -370.072412)
		(end 17.3736 -351.564194)
		(width 0.1651)
		(layer "In5.Cu")
		(net "P5E_PEX0_STN7_RX_DN<115>")
	)
	(segment
		(start 27.443938 -306.981606)
		(end 27.443938 -306.837842)
		(width 0.1651)
		(layer "In5.Cu")
		(net "P5E_PEX0_STN7_RX_DN<115>")
	)
	(segment
		(start 24.838406 -310.50357)
		(end 25.071578 -310.066944)
		(width 0.1651)
		(layer "In5.Cu")
		(net "P5E_PEX0_STN7_RX_DN<115>")
	)
	(segment
		(start 24.508968 -311.120028)
		(end 24.646382 -311.078372)
		(width 0.1651)
		(layer "In5.Cu")
		(net "P5E_PEX0_STN7_RX_DN<115>")
	)
	(segment
		(start 26.233882 -308.047898)
		(end 26.949654 -307.332126)
		(width 0.1651)
		(layer "In5.Cu")
		(net "P5E_PEX0_STN7_RX_DN<115>")
	)
	(segment
		(start 30.552644 -304.72761)
		(end 33.625536 -304.115724)
		(width 0.1651)
		(layer "In5.Cu")
		(net "P5E_PEX0_STN7_RX_DN<115>")
	)
	(segment
		(start 25.208992 -310.025288)
		(end 25.442672 -309.588154)
		(width 0.1651)
		(layer "In5.Cu")
		(net "P5E_PEX0_STN7_RX_DN<115>")
	)
	(segment
		(start 29.424884 -305.304952)
		(end 29.882592 -305.11496)
		(width 0.1651)
		(layer "In5.Cu")
		(net "P5E_PEX0_STN7_RX_DN<115>")
	)
	(segment
		(start 35.56 -304.115724)
		(end 35.588448 -304.115724)
		(width 0.1143)
		(layer "In5.Cu")
		(net "P5E_PEX0_STN7_RX_DN<115>")
	)
	(segment
		(start 24.083772 -312.131456)
		(end 24.317452 -311.694322)
		(width 0.1651)
		(layer "In5.Cu")
		(net "P5E_PEX0_STN7_RX_DN<115>")
	)
	(segment
		(start 37.229542 -304.335434)
		(end 37.115242 -304.449734)
		(width 0.1143)
		(layer "In5.Cu")
		(net "P5E_PEX0_STN7_RX_DN<115>")
	)
	(segment
		(start 17.3736 -351.564194)
		(end 17.3736 -341.959184)
		(width 0.1651)
		(layer "In5.Cu")
		(net "P5E_PEX0_STN7_RX_DN<115>")
	)
	(segment
		(start 34.124392 -393.915392)
		(end 25.310338 -388.631938)
		(width 0.1651)
		(layer "In5.Cu")
		(net "P5E_PEX0_STN7_RX_DN<115>")
	)
	(segment
		(start 21.061934 -318.975232)
		(end 23.650448 -312.727086)
		(width 0.1651)
		(layer "In5.Cu")
		(net "P5E_PEX0_STN7_RX_DN<115>")
	)
	(segment
		(start 37.115242 -304.070004)
		(end 37.229542 -304.184304)
		(width 0.1143)
		(layer "In5.Cu")
		(net "P5E_PEX0_STN7_RX_DN<115>")
	)
	(segment
		(start 25.401016 -309.45074)
		(end 25.82291 -308.6608)
		(width 0.1651)
		(layer "In5.Cu")
		(net "P5E_PEX0_STN7_RX_DN<115>")
	)
	(segment
		(start 17.3736 -341.959184)
		(end 18.695924 -331.237082)
		(width 0.1651)
		(layer "In5.Cu")
		(net "P5E_PEX0_STN7_RX_DN<115>")
	)
	(segment
		(start 25.442672 -309.588154)
		(end 25.401016 -309.45074)
		(width 0.1651)
		(layer "In5.Cu")
		(net "P5E_PEX0_STN7_RX_DN<115>")
	)
	(segment
		(start 80.286098 -122.270266)
		(end 80.606138 -122.590306)
		(width 0.13462)
		(layer "F.Cu")
		(net "P5E_PEX0_STN0_TX_DN<2>")
	)
	(segment
		(start 81.237582 -122.590306)
		(end 81.532222 -122.295666)
		(width 0.13462)
		(layer "F.Cu")
		(net "P5E_PEX0_STN0_TX_DN<2>")
	)
	(segment
		(start 80.606138 -122.590306)
		(end 81.237582 -122.590306)
		(width 0.13462)
		(layer "F.Cu")
		(net "P5E_PEX0_STN0_TX_DN<2>")
	)
	(segment
		(start 81.532222 -122.295666)
		(end 81.823052 -122.586496)
		(width 0.1651)
		(layer "In9.Cu")
		(net "P5E_PEX0_STN0_TX_DN<2>")
	)
	(segment
		(start 83.917536 -286.065976)
		(end 83.889088 -286.065976)
		(width 0.1143)
		(layer "In9.Cu")
		(net "P5E_PEX0_STN0_TX_DN<2>")
	)
	(segment
		(start 89.367106 -175.527208)
		(end 88.458294 -178.91506)
		(width 0.1651)
		(layer "In9.Cu")
		(net "P5E_PEX0_STN0_TX_DN<2>")
	)
	(segment
		(start 84.717636 -122.586496)
		(end 86.257892 -124.126752)
		(width 0.1651)
		(layer "In9.Cu")
		(net "P5E_PEX0_STN0_TX_DN<2>")
	)
	(segment
		(start 86.257892 -124.126752)
		(end 86.602062 -124.95784)
		(width 0.1651)
		(layer "In9.Cu")
		(net "P5E_PEX0_STN0_TX_DN<2>")
	)
	(segment
		(start 84.716874 -221.67723)
		(end 87.191596 -250.029726)
		(width 0.1651)
		(layer "In9.Cu")
		(net "P5E_PEX0_STN0_TX_DN<2>")
	)
	(segment
		(start 98.757486 -272.44802)
		(end 97.35566 -275.8313)
		(width 0.1651)
		(layer "In9.Cu")
		(net "P5E_PEX0_STN0_TX_DN<2>")
	)
	(segment
		(start 77.423772 -286.020256)
		(end 77.32014 -286.123888)
		(width 0.1143)
		(layer "In9.Cu")
		(net "P5E_PEX0_STN0_TX_DN<2>")
	)
	(segment
		(start 98.340926 -267.69314)
		(end 98.757486 -272.44802)
		(width 0.1651)
		(layer "In9.Cu")
		(net "P5E_PEX0_STN0_TX_DN<2>")
	)
	(segment
		(start 98.236024 -159.71139)
		(end 98.01352 -160.544256)
		(width 0.1651)
		(layer "In9.Cu")
		(net "P5E_PEX0_STN0_TX_DN<2>")
	)
	(segment
		(start 89.279984 -131.720844)
		(end 89.788238 -132.229098)
		(width 0.1651)
		(layer "In9.Cu")
		(net "P5E_PEX0_STN0_TX_DN<2>")
	)
	(segment
		(start 97.35566 -275.8313)
		(end 88.314022 -284.872938)
		(width 0.1651)
		(layer "In9.Cu")
		(net "P5E_PEX0_STN0_TX_DN<2>")
	)
	(segment
		(start 77.32014 -286.123888)
		(end 77.32014 -286.285686)
		(width 0.1143)
		(layer "In9.Cu")
		(net "P5E_PEX0_STN0_TX_DN<2>")
	)
	(segment
		(start 98.01352 -160.544256)
		(end 89.367106 -175.527208)
		(width 0.1651)
		(layer "In9.Cu")
		(net "P5E_PEX0_STN0_TX_DN<2>")
	)
	(segment
		(start 88.314022 -284.872938)
		(end 85.43417 -286.065976)
		(width 0.1651)
		(layer "In9.Cu")
		(net "P5E_PEX0_STN0_TX_DN<2>")
	)
	(segment
		(start 97.275142 -265.119866)
		(end 98.340926 -267.69314)
		(width 0.1651)
		(layer "In9.Cu")
		(net "P5E_PEX0_STN0_TX_DN<2>")
	)
	(segment
		(start 86.717124 -125.535182)
		(end 89.279984 -131.720844)
		(width 0.1651)
		(layer "In9.Cu")
		(net "P5E_PEX0_STN0_TX_DN<2>")
	)
	(segment
		(start 77.43444 -286.399986)
		(end 77.69987 -286.399986)
		(width 0.1143)
		(layer "In9.Cu")
		(net "P5E_PEX0_STN0_TX_DN<2>")
	)
	(segment
		(start 86.602062 -124.95784)
		(end 86.717124 -125.535182)
		(width 0.1651)
		(layer "In9.Cu")
		(net "P5E_PEX0_STN0_TX_DN<2>")
	)
	(segment
		(start 85.43417 -286.065976)
		(end 83.917536 -286.065976)
		(width 0.1651)
		(layer "In9.Cu")
		(net "P5E_PEX0_STN0_TX_DN<2>")
	)
	(segment
		(start 83.843368 -286.020256)
		(end 77.423772 -286.020256)
		(width 0.1143)
		(layer "In9.Cu")
		(net "P5E_PEX0_STN0_TX_DN<2>")
	)
	(segment
		(start 88.458294 -178.91506)
		(end 84.716874 -221.67723)
		(width 0.1651)
		(layer "In9.Cu")
		(net "P5E_PEX0_STN0_TX_DN<2>")
	)
	(segment
		(start 87.191596 -250.029726)
		(end 97.275142 -265.119866)
		(width 0.1651)
		(layer "In9.Cu")
		(net "P5E_PEX0_STN0_TX_DN<2>")
	)
	(segment
		(start 98.236024 -152.623266)
		(end 98.236024 -159.71139)
		(width 0.1651)
		(layer "In9.Cu")
		(net "P5E_PEX0_STN0_TX_DN<2>")
	)
	(segment
		(start 83.889088 -286.065976)
		(end 83.843368 -286.020256)
		(width 0.1143)
		(layer "In9.Cu")
		(net "P5E_PEX0_STN0_TX_DN<2>")
	)
	(segment
		(start 89.788238 -132.229098)
		(end 98.236024 -152.623266)
		(width 0.1651)
		(layer "In9.Cu")
		(net "P5E_PEX0_STN0_TX_DN<2>")
	)
	(segment
		(start 81.823052 -122.586496)
		(end 84.717636 -122.586496)
		(width 0.1651)
		(layer "In9.Cu")
		(net "P5E_PEX0_STN0_TX_DN<2>")
	)
	(segment
		(start 77.32014 -286.285686)
		(end 77.43444 -286.399986)
		(width 0.1143)
		(layer "In9.Cu")
		(net "P5E_PEX0_STN0_TX_DN<2>")
	)
	(segment
		(start 74.109834 -397.59001)
		(end 74.109834 -397.972026)
		(width 0.1651)
		(layer "In9.Cu")
		(net "P5E_PEX0_STN5_RX_DP<81>")
	)
	(segment
		(start 92.840048 -367.593372)
		(end 91.76639 -366.519714)
		(width 0.1651)
		(layer "In9.Cu")
		(net "P5E_PEX0_STN5_RX_DP<81>")
	)
	(segment
		(start 93.081094 -386.808472)
		(end 93.336872 -386.190998)
		(width 0.1651)
		(layer "In9.Cu")
		(net "P5E_PEX0_STN5_RX_DP<81>")
	)
	(segment
		(start 59.079638 -318.406272)
		(end 59.356244 -318.129666)
		(width 0.1143)
		(layer "In9.Cu")
		(net "P5E_PEX0_STN5_RX_DP<81>")
	)
	(segment
		(start 77.07376 -392.51509)
		(end 77.42428 -392.164824)
		(width 0.1651)
		(layer "In9.Cu")
		(net "P5E_PEX0_STN5_RX_DP<81>")
	)
	(segment
		(start 93.12529 -368.282728)
		(end 92.840048 -367.593372)
		(width 0.1651)
		(layer "In9.Cu")
		(net "P5E_PEX0_STN5_RX_DP<81>")
	)
	(segment
		(start 59.033918 -319.944496)
		(end 59.033918 -319.916048)
		(width 0.1143)
		(layer "In9.Cu")
		(net "P5E_PEX0_STN5_RX_DP<81>")
	)
	(segment
		(start 91.76639 -366.519714)
		(end 89.737692 -365.164116)
		(width 0.1651)
		(layer "In9.Cu")
		(net "P5E_PEX0_STN5_RX_DP<81>")
	)
	(segment
		(start 93.336872 -386.190998)
		(end 93.336872 -385.426204)
		(width 0.1651)
		(layer "In9.Cu")
		(net "P5E_PEX0_STN5_RX_DP<81>")
	)
	(segment
		(start 77.42428 -392.164824)
		(end 77.531976 -392.164824)
		(width 0.1651)
		(layer "In9.Cu")
		(net "P5E_PEX0_STN5_RX_DP<81>")
	)
	(segment
		(start 76.616052 -392.973052)
		(end 76.723748 -392.973052)
		(width 0.1651)
		(layer "In9.Cu")
		(net "P5E_PEX0_STN5_RX_DP<81>")
	)
	(segment
		(start 79.784702 -389.912098)
		(end 92.374212 -387.407912)
		(width 0.1651)
		(layer "In9.Cu")
		(net "P5E_PEX0_STN5_RX_DP<81>")
	)
	(segment
		(start 76.723748 -392.973052)
		(end 77.07376 -392.62304)
		(width 0.1651)
		(layer "In9.Cu")
		(net "P5E_PEX0_STN5_RX_DP<81>")
	)
	(segment
		(start 59.033918 -319.916048)
		(end 59.079638 -319.870328)
		(width 0.1143)
		(layer "In9.Cu")
		(net "P5E_PEX0_STN5_RX_DP<81>")
	)
	(segment
		(start 59.560968 -318.129666)
		(end 59.649868 -318.040766)
		(width 0.1143)
		(layer "In9.Cu")
		(net "P5E_PEX0_STN5_RX_DP<81>")
	)
	(segment
		(start 77.07376 -392.62304)
		(end 77.07376 -392.51509)
		(width 0.1651)
		(layer "In9.Cu")
		(net "P5E_PEX0_STN5_RX_DP<81>")
	)
	(segment
		(start 76.265532 -393.323572)
		(end 76.616052 -392.973052)
		(width 0.1651)
		(layer "In9.Cu")
		(net "P5E_PEX0_STN5_RX_DP<81>")
	)
	(segment
		(start 59.825382 -323.238622)
		(end 59.033918 -321.328034)
		(width 0.1651)
		(layer "In9.Cu")
		(net "P5E_PEX0_STN5_RX_DP<81>")
	)
	(segment
		(start 74.109834 -397.972026)
		(end 74.236834 -398.099026)
		(width 0.1651)
		(layer "In9.Cu")
		(net "P5E_PEX0_STN5_RX_DP<81>")
	)
	(segment
		(start 92.5576 -387.331966)
		(end 93.081094 -386.808472)
		(width 0.1651)
		(layer "In9.Cu")
		(net "P5E_PEX0_STN5_RX_DP<81>")
	)
	(segment
		(start 59.356244 -318.129666)
		(end 59.560968 -318.129666)
		(width 0.1143)
		(layer "In9.Cu")
		(net "P5E_PEX0_STN5_RX_DP<81>")
	)
	(segment
		(start 74.57694 -398.099026)
		(end 75.00239 -397.673576)
		(width 0.1651)
		(layer "In9.Cu")
		(net "P5E_PEX0_STN5_RX_DP<81>")
	)
	(segment
		(start 93.6498 -370.919756)
		(end 93.12529 -368.282728)
		(width 0.1651)
		(layer "In9.Cu")
		(net "P5E_PEX0_STN5_RX_DP<81>")
	)
	(segment
		(start 74.186034 -333.893414)
		(end 63.017654 -326.430894)
		(width 0.1651)
		(layer "In9.Cu")
		(net "P5E_PEX0_STN5_RX_DP<81>")
	)
	(segment
		(start 89.737692 -365.164116)
		(end 83.48599 -360.033824)
		(width 0.1651)
		(layer "In9.Cu")
		(net "P5E_PEX0_STN5_RX_DP<81>")
	)
	(segment
		(start 59.079638 -319.870328)
		(end 59.079638 -318.406272)
		(width 0.1143)
		(layer "In9.Cu")
		(net "P5E_PEX0_STN5_RX_DP<81>")
	)
	(segment
		(start 93.6498 -371.396006)
		(end 93.6498 -370.919756)
		(width 0.1651)
		(layer "In9.Cu")
		(net "P5E_PEX0_STN5_RX_DP<81>")
	)
	(segment
		(start 93.336872 -385.426204)
		(end 93.6498 -371.396006)
		(width 0.1651)
		(layer "In9.Cu")
		(net "P5E_PEX0_STN5_RX_DP<81>")
	)
	(segment
		(start 83.48599 -360.033824)
		(end 82.211164 -358.758744)
		(width 0.1651)
		(layer "In9.Cu")
		(net "P5E_PEX0_STN5_RX_DP<81>")
	)
	(segment
		(start 82.211164 -358.758744)
		(end 81.871312 -357.938324)
		(width 0.1651)
		(layer "In9.Cu")
		(net "P5E_PEX0_STN5_RX_DP<81>")
	)
	(segment
		(start 75.00239 -394.69441)
		(end 76.265532 -393.431268)
		(width 0.1651)
		(layer "In9.Cu")
		(net "P5E_PEX0_STN5_RX_DP<81>")
	)
	(segment
		(start 76.265532 -393.431268)
		(end 76.265532 -393.323572)
		(width 0.1651)
		(layer "In9.Cu")
		(net "P5E_PEX0_STN5_RX_DP<81>")
	)
	(segment
		(start 75.00239 -397.673576)
		(end 75.00239 -394.69441)
		(width 0.1651)
		(layer "In9.Cu")
		(net "P5E_PEX0_STN5_RX_DP<81>")
	)
	(segment
		(start 81.871312 -357.938324)
		(end 81.871312 -342.062308)
		(width 0.1651)
		(layer "In9.Cu")
		(net "P5E_PEX0_STN5_RX_DP<81>")
	)
	(segment
		(start 92.374212 -387.407912)
		(end 92.5576 -387.331966)
		(width 0.1651)
		(layer "In9.Cu")
		(net "P5E_PEX0_STN5_RX_DP<81>")
	)
	(segment
		(start 63.017654 -326.430894)
		(end 59.825382 -323.238622)
		(width 0.1651)
		(layer "In9.Cu")
		(net "P5E_PEX0_STN5_RX_DP<81>")
	)
	(segment
		(start 74.236834 -398.099026)
		(end 74.57694 -398.099026)
		(width 0.1651)
		(layer "In9.Cu")
		(net "P5E_PEX0_STN5_RX_DP<81>")
	)
	(segment
		(start 59.033918 -321.328034)
		(end 59.033918 -319.944496)
		(width 0.1651)
		(layer "In9.Cu")
		(net "P5E_PEX0_STN5_RX_DP<81>")
	)
	(segment
		(start 77.531976 -392.164824)
		(end 79.784702 -389.912098)
		(width 0.1651)
		(layer "In9.Cu")
		(net "P5E_PEX0_STN5_RX_DP<81>")
	)
	(segment
		(start 59.649868 -318.040766)
		(end 59.649868 -317.749936)
		(width 0.1143)
		(layer "In9.Cu")
		(net "P5E_PEX0_STN5_RX_DP<81>")
	)
	(segment
		(start 81.529174 -341.236554)
		(end 74.186034 -333.893414)
		(width 0.1651)
		(layer "In9.Cu")
		(net "P5E_PEX0_STN5_RX_DP<81>")
	)
	(segment
		(start 81.871312 -342.062308)
		(end 81.529174 -341.236554)
		(width 0.1651)
		(layer "In9.Cu")
		(net "P5E_PEX0_STN5_RX_DP<81>")
	)
	(segment
		(start 74.102722 -342.734138)
		(end 73.808082 -342.439498)
		(width 0.13462)
		(layer "F.Cu")
		(net "P5E_PEX0_STN6_TX_DP<106>")
	)
	(segment
		(start 73.782682 -343.685622)
		(end 74.102722 -343.365582)
		(width 0.13462)
		(layer "F.Cu")
		(net "P5E_PEX0_STN6_TX_DP<106>")
	)
	(segment
		(start 74.102722 -343.365582)
		(end 74.102722 -342.734138)
		(width 0.13462)
		(layer "F.Cu")
		(net "P5E_PEX0_STN6_TX_DP<106>")
	)
	(segment
		(start 47.63389 -320.105024)
		(end 47.67961 -320.059304)
		(width 0.1143)
		(layer "In13.Cu")
		(net "P5E_PEX0_STN6_TX_DP<106>")
	)
	(segment
		(start 74.098912 -341.394796)
		(end 74.01687 -341.258144)
		(width 0.1651)
		(layer "In13.Cu")
		(net "P5E_PEX0_STN6_TX_DP<106>")
	)
	(segment
		(start 48.24984 -313.290712)
		(end 48.24984 -312.999882)
		(width 0.1143)
		(layer "In13.Cu")
		(net "P5E_PEX0_STN6_TX_DP<106>")
	)
	(segment
		(start 74.01687 -341.258144)
		(end 53.207158 -330.134468)
		(width 0.1651)
		(layer "In13.Cu")
		(net "P5E_PEX0_STN6_TX_DP<106>")
	)
	(segment
		(start 49.016412 -326.778112)
		(end 47.63389 -323.440298)
		(width 0.1651)
		(layer "In13.Cu")
		(net "P5E_PEX0_STN6_TX_DP<106>")
	)
	(segment
		(start 73.808082 -342.439498)
		(end 74.098912 -342.148668)
		(width 0.1651)
		(layer "In13.Cu")
		(net "P5E_PEX0_STN6_TX_DP<106>")
	)
	(segment
		(start 74.098912 -342.148668)
		(end 74.098912 -341.394796)
		(width 0.1651)
		(layer "In13.Cu")
		(net "P5E_PEX0_STN6_TX_DP<106>")
	)
	(segment
		(start 48.16094 -313.379612)
		(end 48.24984 -313.290712)
		(width 0.1143)
		(layer "In13.Cu")
		(net "P5E_PEX0_STN6_TX_DP<106>")
	)
	(segment
		(start 51.782726 -329.544426)
		(end 49.016412 -326.778112)
		(width 0.1651)
		(layer "In13.Cu")
		(net "P5E_PEX0_STN6_TX_DP<106>")
	)
	(segment
		(start 47.918116 -313.379612)
		(end 48.16094 -313.379612)
		(width 0.1143)
		(layer "In13.Cu")
		(net "P5E_PEX0_STN6_TX_DP<106>")
	)
	(segment
		(start 47.63389 -323.440298)
		(end 47.63389 -320.127122)
		(width 0.1651)
		(layer "In13.Cu")
		(net "P5E_PEX0_STN6_TX_DP<106>")
	)
	(segment
		(start 47.67961 -320.059304)
		(end 47.67961 -313.618118)
		(width 0.1143)
		(layer "In13.Cu")
		(net "P5E_PEX0_STN6_TX_DP<106>")
	)
	(segment
		(start 53.207158 -330.134468)
		(end 51.782726 -329.544426)
		(width 0.1651)
		(layer "In13.Cu")
		(net "P5E_PEX0_STN6_TX_DP<106>")
	)
	(segment
		(start 47.63389 -320.127122)
		(end 47.63389 -320.105024)
		(width 0.1143)
		(layer "In13.Cu")
		(net "P5E_PEX0_STN6_TX_DP<106>")
	)
	(segment
		(start 47.67961 -313.618118)
		(end 47.918116 -313.379612)
		(width 0.1143)
		(layer "In13.Cu")
		(net "P5E_PEX0_STN6_TX_DP<106>")
	)
	(segment
		(start 28.659328 -345.465146)
		(end 28.953968 -345.170506)
		(width 0.13462)
		(layer "F.Cu")
		(net "P5E_PEX0_STN7_TX_C_DP<116>")
	)
	(segment
		(start 28.953968 -345.170506)
		(end 28.953968 -344.539062)
		(width 0.13462)
		(layer "F.Cu")
		(net "P5E_PEX0_STN7_TX_C_DP<116>")
	)
	(segment
		(start 28.953968 -344.539062)
		(end 28.633928 -344.219022)
		(width 0.13462)
		(layer "F.Cu")
		(net "P5E_PEX0_STN7_TX_C_DP<116>")
	)
	(segment
		(start 23.12162 -375.588276)
		(end 23.12162 -371.07749)
		(width 0.1651)
		(layer "In7.Cu")
		(net "P5E_PEX0_STN7_TX_C_DP<116>")
	)
	(segment
		(start 28.950158 -345.755976)
		(end 28.659328 -345.465146)
		(width 0.1651)
		(layer "In7.Cu")
		(net "P5E_PEX0_STN7_TX_C_DP<116>")
	)
	(segment
		(start 37.602414 -400.490436)
		(end 37.602414 -394.388594)
		(width 0.1651)
		(layer "In7.Cu")
		(net "P5E_PEX0_STN7_TX_C_DP<116>")
	)
	(segment
		(start 27.395678 -357.871268)
		(end 27.395678 -347.912182)
		(width 0.1651)
		(layer "In7.Cu")
		(net "P5E_PEX0_STN7_TX_C_DP<116>")
	)
	(segment
		(start 35.526472 -392.312652)
		(end 26.167588 -388.436358)
		(width 0.1651)
		(layer "In7.Cu")
		(net "P5E_PEX0_STN7_TX_C_DP<116>")
	)
	(segment
		(start 36.710112 -400.390106)
		(end 36.710112 -400.772122)
		(width 0.1651)
		(layer "In7.Cu")
		(net "P5E_PEX0_STN7_TX_C_DP<116>")
	)
	(segment
		(start 23.979378 -366.764824)
		(end 27.148282 -359.114344)
		(width 0.1651)
		(layer "In7.Cu")
		(net "P5E_PEX0_STN7_TX_C_DP<116>")
	)
	(segment
		(start 23.12162 -371.07749)
		(end 23.979378 -366.764824)
		(width 0.1651)
		(layer "In7.Cu")
		(net "P5E_PEX0_STN7_TX_C_DP<116>")
	)
	(segment
		(start 27.148282 -359.114344)
		(end 27.395678 -357.871268)
		(width 0.1651)
		(layer "In7.Cu")
		(net "P5E_PEX0_STN7_TX_C_DP<116>")
	)
	(segment
		(start 26.167588 -388.436358)
		(end 24.706834 -386.975604)
		(width 0.1651)
		(layer "In7.Cu")
		(net "P5E_PEX0_STN7_TX_C_DP<116>")
	)
	(segment
		(start 23.668228 -384.666998)
		(end 23.12162 -375.588276)
		(width 0.1651)
		(layer "In7.Cu")
		(net "P5E_PEX0_STN7_TX_C_DP<116>")
	)
	(segment
		(start 27.395678 -347.912182)
		(end 28.950158 -346.357702)
		(width 0.1651)
		(layer "In7.Cu")
		(net "P5E_PEX0_STN7_TX_C_DP<116>")
	)
	(segment
		(start 28.950158 -346.357702)
		(end 28.950158 -345.755976)
		(width 0.1651)
		(layer "In7.Cu")
		(net "P5E_PEX0_STN7_TX_C_DP<116>")
	)
	(segment
		(start 37.193728 -400.899122)
		(end 37.602414 -400.490436)
		(width 0.1651)
		(layer "In7.Cu")
		(net "P5E_PEX0_STN7_TX_C_DP<116>")
	)
	(segment
		(start 37.602414 -394.388594)
		(end 35.526472 -392.312652)
		(width 0.1651)
		(layer "In7.Cu")
		(net "P5E_PEX0_STN7_TX_C_DP<116>")
	)
	(segment
		(start 36.837112 -400.899122)
		(end 37.193728 -400.899122)
		(width 0.1651)
		(layer "In7.Cu")
		(net "P5E_PEX0_STN7_TX_C_DP<116>")
	)
	(segment
		(start 24.706834 -386.975604)
		(end 23.668228 -384.666998)
		(width 0.1651)
		(layer "In7.Cu")
		(net "P5E_PEX0_STN7_TX_C_DP<116>")
	)
	(segment
		(start 36.710112 -400.772122)
		(end 36.837112 -400.899122)
		(width 0.1651)
		(layer "In7.Cu")
		(net "P5E_PEX0_STN7_TX_C_DP<116>")
	)
	(segment
		(start 165.589712 -350.685354)
		(end 165.269672 -350.365314)
		(width 0.13462)
		(layer "F.Cu")
		(net "P5E_PEX1_STN7_TX_C_DP<114>")
	)
	(segment
		(start 165.589712 -351.316798)
		(end 165.589712 -350.685354)
		(width 0.13462)
		(layer "F.Cu")
		(net "P5E_PEX1_STN7_TX_C_DP<114>")
	)
	(segment
		(start 165.295072 -351.611438)
		(end 165.589712 -351.316798)
		(width 0.13462)
		(layer "F.Cu")
		(net "P5E_PEX1_STN7_TX_C_DP<114>")
	)
	(segment
		(start 162.479482 -393.296394)
		(end 162.61461 -393.247118)
		(width 0.1651)
		(layer "In11.Cu")
		(net "P5E_PEX1_STN7_TX_C_DP<114>")
	)
	(segment
		(start 153.864056 -385.56311)
		(end 155.123388 -388.678674)
		(width 0.1651)
		(layer "In11.Cu")
		(net "P5E_PEX1_STN7_TX_C_DP<114>")
	)
	(segment
		(start 164.031422 -358.43972)
		(end 163.113212 -359.820718)
		(width 0.1651)
		(layer "In11.Cu")
		(net "P5E_PEX1_STN7_TX_C_DP<114>")
	)
	(segment
		(start 155.123388 -388.678674)
		(end 159.03448 -391.580878)
		(width 0.1651)
		(layer "In11.Cu")
		(net "P5E_PEX1_STN7_TX_C_DP<114>")
	)
	(segment
		(start 160.449514 -392.2395)
		(end 160.898332 -392.448288)
		(width 0.1651)
		(layer "In11.Cu")
		(net "P5E_PEX1_STN7_TX_C_DP<114>")
	)
	(segment
		(start 163.063428 -393.455906)
		(end 163.112704 -393.591034)
		(width 0.1651)
		(layer "In11.Cu")
		(net "P5E_PEX1_STN7_TX_C_DP<114>")
	)
	(segment
		(start 165.585902 -352.547936)
		(end 164.031422 -354.102416)
		(width 0.1651)
		(layer "In11.Cu")
		(net "P5E_PEX1_STN7_TX_C_DP<114>")
	)
	(segment
		(start 165.585902 -351.902268)
		(end 165.585902 -352.547936)
		(width 0.1651)
		(layer "In11.Cu")
		(net "P5E_PEX1_STN7_TX_C_DP<114>")
	)
	(segment
		(start 163.56203 -393.80033)
		(end 163.697158 -393.751054)
		(width 0.1651)
		(layer "In11.Cu")
		(net "P5E_PEX1_STN7_TX_C_DP<114>")
	)
	(segment
		(start 162.030156 -393.087098)
		(end 162.479482 -393.296394)
		(width 0.1651)
		(layer "In11.Cu")
		(net "P5E_PEX1_STN7_TX_C_DP<114>")
	)
	(segment
		(start 165.295072 -351.611438)
		(end 165.585902 -351.902268)
		(width 0.1651)
		(layer "In11.Cu")
		(net "P5E_PEX1_STN7_TX_C_DP<114>")
	)
	(segment
		(start 162.61461 -393.247118)
		(end 163.063428 -393.455906)
		(width 0.1651)
		(layer "In11.Cu")
		(net "P5E_PEX1_STN7_TX_C_DP<114>")
	)
	(segment
		(start 161.98088 -392.95197)
		(end 162.030156 -393.087098)
		(width 0.1651)
		(layer "In11.Cu")
		(net "P5E_PEX1_STN7_TX_C_DP<114>")
	)
	(segment
		(start 163.112704 -393.591034)
		(end 163.56203 -393.80033)
		(width 0.1651)
		(layer "In11.Cu")
		(net "P5E_PEX1_STN7_TX_C_DP<114>")
	)
	(segment
		(start 164.31006 -400.772122)
		(end 164.31006 -400.390106)
		(width 0.1651)
		(layer "In11.Cu")
		(net "P5E_PEX1_STN7_TX_C_DP<114>")
	)
	(segment
		(start 164.43706 -400.899122)
		(end 164.31006 -400.772122)
		(width 0.1651)
		(layer "In11.Cu")
		(net "P5E_PEX1_STN7_TX_C_DP<114>")
	)
	(segment
		(start 159.03448 -391.580878)
		(end 159.815784 -391.944352)
		(width 0.1651)
		(layer "In11.Cu")
		(net "P5E_PEX1_STN7_TX_C_DP<114>")
	)
	(segment
		(start 161.532062 -392.743182)
		(end 161.98088 -392.95197)
		(width 0.1651)
		(layer "In11.Cu")
		(net "P5E_PEX1_STN7_TX_C_DP<114>")
	)
	(segment
		(start 163.113212 -359.820718)
		(end 157.735016 -362.078016)
		(width 0.1651)
		(layer "In11.Cu")
		(net "P5E_PEX1_STN7_TX_C_DP<114>")
	)
	(segment
		(start 161.396934 -392.792458)
		(end 161.532062 -392.743182)
		(width 0.1651)
		(layer "In11.Cu")
		(net "P5E_PEX1_STN7_TX_C_DP<114>")
	)
	(segment
		(start 165.193218 -400.75866)
		(end 165.052756 -400.899122)
		(width 0.1651)
		(layer "In11.Cu")
		(net "P5E_PEX1_STN7_TX_C_DP<114>")
	)
	(segment
		(start 160.314386 -392.288776)
		(end 160.449514 -392.2395)
		(width 0.1651)
		(layer "In11.Cu")
		(net "P5E_PEX1_STN7_TX_C_DP<114>")
	)
	(segment
		(start 153.613866 -382.668272)
		(end 153.864056 -385.56311)
		(width 0.1651)
		(layer "In11.Cu")
		(net "P5E_PEX1_STN7_TX_C_DP<114>")
	)
	(segment
		(start 165.052756 -400.899122)
		(end 164.43706 -400.899122)
		(width 0.1651)
		(layer "In11.Cu")
		(net "P5E_PEX1_STN7_TX_C_DP<114>")
	)
	(segment
		(start 159.86506 -392.07948)
		(end 160.314386 -392.288776)
		(width 0.1651)
		(layer "In11.Cu")
		(net "P5E_PEX1_STN7_TX_C_DP<114>")
	)
	(segment
		(start 163.697158 -393.751054)
		(end 164.145976 -393.959842)
		(width 0.1651)
		(layer "In11.Cu")
		(net "P5E_PEX1_STN7_TX_C_DP<114>")
	)
	(segment
		(start 165.193218 -395.58595)
		(end 165.091618 -395.68755)
		(width 0.1651)
		(layer "In11.Cu")
		(net "P5E_PEX1_STN7_TX_C_DP<114>")
	)
	(segment
		(start 164.14623 -393.959842)
		(end 165.193218 -395.00683)
		(width 0.1651)
		(layer "In11.Cu")
		(net "P5E_PEX1_STN7_TX_C_DP<114>")
	)
	(segment
		(start 165.193218 -396.28445)
		(end 165.193218 -400.75866)
		(width 0.1651)
		(layer "In11.Cu")
		(net "P5E_PEX1_STN7_TX_C_DP<114>")
	)
	(segment
		(start 154.88666 -365.001302)
		(end 153.79446 -367.890044)
		(width 0.1651)
		(layer "In11.Cu")
		(net "P5E_PEX1_STN7_TX_C_DP<114>")
	)
	(segment
		(start 160.898332 -392.448288)
		(end 160.947608 -392.583162)
		(width 0.1651)
		(layer "In11.Cu")
		(net "P5E_PEX1_STN7_TX_C_DP<114>")
	)
	(segment
		(start 160.947608 -392.583162)
		(end 161.396934 -392.792458)
		(width 0.1651)
		(layer "In11.Cu")
		(net "P5E_PEX1_STN7_TX_C_DP<114>")
	)
	(segment
		(start 164.031422 -354.102416)
		(end 164.031422 -358.43972)
		(width 0.1651)
		(layer "In11.Cu")
		(net "P5E_PEX1_STN7_TX_C_DP<114>")
	)
	(segment
		(start 153.79446 -367.890044)
		(end 153.613866 -382.668272)
		(width 0.1651)
		(layer "In11.Cu")
		(net "P5E_PEX1_STN7_TX_C_DP<114>")
	)
	(segment
		(start 164.145976 -393.959842)
		(end 164.14623 -393.959842)
		(width 0.1651)
		(layer "In11.Cu")
		(net "P5E_PEX1_STN7_TX_C_DP<114>")
	)
	(segment
		(start 165.193218 -395.00683)
		(end 165.193218 -395.58595)
		(width 0.1651)
		(layer "In11.Cu")
		(net "P5E_PEX1_STN7_TX_C_DP<114>")
	)
	(segment
		(start 165.091618 -396.18285)
		(end 165.193218 -396.28445)
		(width 0.1651)
		(layer "In11.Cu")
		(net "P5E_PEX1_STN7_TX_C_DP<114>")
	)
	(segment
		(start 157.735016 -362.078016)
		(end 154.88666 -365.001302)
		(width 0.1651)
		(layer "In11.Cu")
		(net "P5E_PEX1_STN7_TX_C_DP<114>")
	)
	(segment
		(start 159.815784 -391.944352)
		(end 159.86506 -392.07948)
		(width 0.1651)
		(layer "In11.Cu")
		(net "P5E_PEX1_STN7_TX_C_DP<114>")
	)
	(segment
		(start 165.091618 -395.68755)
		(end 165.091618 -396.18285)
		(width 0.1651)
		(layer "In11.Cu")
		(net "P5E_PEX1_STN7_TX_C_DP<114>")
	)
	(segment
		(start 80.286098 -130.794506)
		(end 80.606138 -130.474466)
		(width 0.13462)
		(layer "F.Cu")
		(net "P5E_PEX0_STN0_TX_DP<4>")
	)
	(segment
		(start 81.237582 -130.474466)
		(end 81.532222 -130.769106)
		(width 0.13462)
		(layer "F.Cu")
		(net "P5E_PEX0_STN0_TX_DP<4>")
	)
	(segment
		(start 80.606138 -130.474466)
		(end 81.237582 -130.474466)
		(width 0.13462)
		(layer "F.Cu")
		(net "P5E_PEX0_STN0_TX_DP<4>")
	)
	(segment
		(start 95.958406 -159.64408)
		(end 87.290148 -174.663862)
		(width 0.1651)
		(layer "In9.Cu")
		(net "P5E_PEX0_STN0_TX_DP<4>")
	)
	(segment
		(start 87.563198 -133.273038)
		(end 87.73795 -133.695186)
		(width 0.1651)
		(layer "In9.Cu")
		(net "P5E_PEX0_STN0_TX_DP<4>")
	)
	(segment
		(start 84.204048 -130.478276)
		(end 85.167724 -130.877564)
		(width 0.1651)
		(layer "In9.Cu")
		(net "P5E_PEX0_STN0_TX_DP<4>")
	)
	(segment
		(start 95.41383 -266.38123)
		(end 96.187514 -268.2494)
		(width 0.1651)
		(layer "In9.Cu")
		(net "P5E_PEX0_STN0_TX_DP<4>")
	)
	(segment
		(start 82.469482 -221.593156)
		(end 83.7438 -236.187234)
		(width 0.1651)
		(layer "In9.Cu")
		(net "P5E_PEX0_STN0_TX_DP<4>")
	)
	(segment
		(start 87.990934 -134.305802)
		(end 88.165686 -134.72795)
		(width 0.1651)
		(layer "In9.Cu")
		(net "P5E_PEX0_STN0_TX_DP<4>")
	)
	(segment
		(start 85.021928 -250.828302)
		(end 95.41383 -266.38123)
		(width 0.1651)
		(layer "In9.Cu")
		(net "P5E_PEX0_STN0_TX_DP<4>")
	)
	(segment
		(start 81.532222 -130.769106)
		(end 81.823052 -130.478276)
		(width 0.1651)
		(layer "In9.Cu")
		(net "P5E_PEX0_STN0_TX_DP<4>")
	)
	(segment
		(start 89.021158 -136.793478)
		(end 88.966294 -136.92632)
		(width 0.1651)
		(layer "In9.Cu")
		(net "P5E_PEX0_STN0_TX_DP<4>")
	)
	(segment
		(start 88.165686 -134.72795)
		(end 88.110822 -134.860792)
		(width 0.1651)
		(layer "In9.Cu")
		(net "P5E_PEX0_STN0_TX_DP<4>")
	)
	(segment
		(start 83.7438 -236.187234)
		(end 85.021928 -250.828302)
		(width 0.1651)
		(layer "In9.Cu")
		(net "P5E_PEX0_STN0_TX_DP<4>")
	)
	(segment
		(start 87.0712 -283.014928)
		(end 84.973668 -283.883862)
		(width 0.1651)
		(layer "In9.Cu")
		(net "P5E_PEX0_STN0_TX_DP<4>")
	)
	(segment
		(start 83.39836 -130.478276)
		(end 84.204048 -130.478276)
		(width 0.1651)
		(layer "In9.Cu")
		(net "P5E_PEX0_STN0_TX_DP<4>")
	)
	(segment
		(start 89.274142 -137.404094)
		(end 92.187268 -144.436338)
		(width 0.1651)
		(layer "In9.Cu")
		(net "P5E_PEX0_STN0_TX_DP<4>")
	)
	(segment
		(start 88.966294 -136.92632)
		(end 89.1413 -137.348976)
		(width 0.1651)
		(layer "In9.Cu")
		(net "P5E_PEX0_STN0_TX_DP<4>")
	)
	(segment
		(start 83.29676 -130.579876)
		(end 83.39836 -130.478276)
		(width 0.1651)
		(layer "In9.Cu")
		(net "P5E_PEX0_STN0_TX_DP<4>")
	)
	(segment
		(start 88.538558 -135.893556)
		(end 88.713564 -136.316212)
		(width 0.1651)
		(layer "In9.Cu")
		(net "P5E_PEX0_STN0_TX_DP<4>")
	)
	(segment
		(start 88.41867 -135.338566)
		(end 88.593422 -135.760714)
		(width 0.1651)
		(layer "In9.Cu")
		(net "P5E_PEX0_STN0_TX_DP<4>")
	)
	(segment
		(start 92.35948 -144.60855)
		(end 96.018604 -153.442416)
		(width 0.1651)
		(layer "In9.Cu")
		(net "P5E_PEX0_STN0_TX_DP<4>")
	)
	(segment
		(start 77.12964 -284.385512)
		(end 77.01534 -284.499812)
		(width 0.1143)
		(layer "In9.Cu")
		(net "P5E_PEX0_STN0_TX_DP<4>")
	)
	(segment
		(start 88.846406 -136.37133)
		(end 89.021158 -136.793478)
		(width 0.1651)
		(layer "In9.Cu")
		(net "P5E_PEX0_STN0_TX_DP<4>")
	)
	(segment
		(start 86.368128 -132.077968)
		(end 86.368128 -132.221732)
		(width 0.1651)
		(layer "In9.Cu")
		(net "P5E_PEX0_STN0_TX_DP<4>")
	)
	(segment
		(start 85.57768 -131.431284)
		(end 85.901276 -131.75488)
		(width 0.1651)
		(layer "In9.Cu")
		(net "P5E_PEX0_STN0_TX_DP<4>")
	)
	(segment
		(start 96.524572 -272.107406)
		(end 95.496126 -274.590002)
		(width 0.1651)
		(layer "In9.Cu")
		(net "P5E_PEX0_STN0_TX_DP<4>")
	)
	(segment
		(start 86.835488 -132.545328)
		(end 87.563198 -133.273038)
		(width 0.1651)
		(layer "In9.Cu")
		(net "P5E_PEX0_STN0_TX_DP<4>")
	)
	(segment
		(start 85.167724 -130.877564)
		(end 85.57768 -131.28752)
		(width 0.1651)
		(layer "In9.Cu")
		(net "P5E_PEX0_STN0_TX_DP<4>")
	)
	(segment
		(start 92.187268 -144.436338)
		(end 92.35948 -144.60855)
		(width 0.1651)
		(layer "In9.Cu")
		(net "P5E_PEX0_STN0_TX_DP<4>")
	)
	(segment
		(start 86.368128 -132.221732)
		(end 86.691724 -132.545328)
		(width 0.1651)
		(layer "In9.Cu")
		(net "P5E_PEX0_STN0_TX_DP<4>")
	)
	(segment
		(start 83.917536 -283.883862)
		(end 83.889088 -283.883862)
		(width 0.1143)
		(layer "In9.Cu")
		(net "P5E_PEX0_STN0_TX_DP<4>")
	)
	(segment
		(start 88.713564 -136.316212)
		(end 88.846406 -136.37133)
		(width 0.1651)
		(layer "In9.Cu")
		(net "P5E_PEX0_STN0_TX_DP<4>")
	)
	(segment
		(start 77.01534 -284.499812)
		(end 76.74991 -284.499812)
		(width 0.1143)
		(layer "In9.Cu")
		(net "P5E_PEX0_STN0_TX_DP<4>")
	)
	(segment
		(start 87.73795 -133.695186)
		(end 87.683086 -133.828028)
		(width 0.1651)
		(layer "In9.Cu")
		(net "P5E_PEX0_STN0_TX_DP<4>")
	)
	(segment
		(start 77.344778 -283.929582)
		(end 77.12964 -284.14472)
		(width 0.1143)
		(layer "In9.Cu")
		(net "P5E_PEX0_STN0_TX_DP<4>")
	)
	(segment
		(start 87.290148 -174.663862)
		(end 86.22919 -178.621436)
		(width 0.1651)
		(layer "In9.Cu")
		(net "P5E_PEX0_STN0_TX_DP<4>")
	)
	(segment
		(start 83.843368 -283.929582)
		(end 77.344778 -283.929582)
		(width 0.1143)
		(layer "In9.Cu")
		(net "P5E_PEX0_STN0_TX_DP<4>")
	)
	(segment
		(start 82.73796 -130.478276)
		(end 82.83956 -130.579876)
		(width 0.1651)
		(layer "In9.Cu")
		(net "P5E_PEX0_STN0_TX_DP<4>")
	)
	(segment
		(start 84.973668 -283.883862)
		(end 83.917536 -283.883862)
		(width 0.1651)
		(layer "In9.Cu")
		(net "P5E_PEX0_STN0_TX_DP<4>")
	)
	(segment
		(start 83.889088 -283.883862)
		(end 83.843368 -283.929582)
		(width 0.1143)
		(layer "In9.Cu")
		(net "P5E_PEX0_STN0_TX_DP<4>")
	)
	(segment
		(start 82.83956 -130.579876)
		(end 83.29676 -130.579876)
		(width 0.1651)
		(layer "In9.Cu")
		(net "P5E_PEX0_STN0_TX_DP<4>")
	)
	(segment
		(start 88.110822 -134.860792)
		(end 88.285828 -135.283448)
		(width 0.1651)
		(layer "In9.Cu")
		(net "P5E_PEX0_STN0_TX_DP<4>")
	)
	(segment
		(start 88.593422 -135.760714)
		(end 88.538558 -135.893556)
		(width 0.1651)
		(layer "In9.Cu")
		(net "P5E_PEX0_STN0_TX_DP<4>")
	)
	(segment
		(start 86.691724 -132.545328)
		(end 86.835488 -132.545328)
		(width 0.1651)
		(layer "In9.Cu")
		(net "P5E_PEX0_STN0_TX_DP<4>")
	)
	(segment
		(start 96.187514 -268.2494)
		(end 96.524572 -272.107406)
		(width 0.1651)
		(layer "In9.Cu")
		(net "P5E_PEX0_STN0_TX_DP<4>")
	)
	(segment
		(start 95.496126 -274.590002)
		(end 87.0712 -283.014928)
		(width 0.1651)
		(layer "In9.Cu")
		(net "P5E_PEX0_STN0_TX_DP<4>")
	)
	(segment
		(start 85.901276 -131.75488)
		(end 86.04504 -131.75488)
		(width 0.1651)
		(layer "In9.Cu")
		(net "P5E_PEX0_STN0_TX_DP<4>")
	)
	(segment
		(start 89.1413 -137.348976)
		(end 89.274142 -137.404094)
		(width 0.1651)
		(layer "In9.Cu")
		(net "P5E_PEX0_STN0_TX_DP<4>")
	)
	(segment
		(start 85.57768 -131.28752)
		(end 85.57768 -131.431284)
		(width 0.1651)
		(layer "In9.Cu")
		(net "P5E_PEX0_STN0_TX_DP<4>")
	)
	(segment
		(start 96.018604 -159.418782)
		(end 95.958406 -159.64408)
		(width 0.1651)
		(layer "In9.Cu")
		(net "P5E_PEX0_STN0_TX_DP<4>")
	)
	(segment
		(start 88.285828 -135.283448)
		(end 88.41867 -135.338566)
		(width 0.1651)
		(layer "In9.Cu")
		(net "P5E_PEX0_STN0_TX_DP<4>")
	)
	(segment
		(start 87.858092 -134.250684)
		(end 87.990934 -134.305802)
		(width 0.1651)
		(layer "In9.Cu")
		(net "P5E_PEX0_STN0_TX_DP<4>")
	)
	(segment
		(start 86.04504 -131.75488)
		(end 86.368128 -132.077968)
		(width 0.1651)
		(layer "In9.Cu")
		(net "P5E_PEX0_STN0_TX_DP<4>")
	)
	(segment
		(start 96.018604 -153.442416)
		(end 96.018604 -159.418782)
		(width 0.1651)
		(layer "In9.Cu")
		(net "P5E_PEX0_STN0_TX_DP<4>")
	)
	(segment
		(start 86.22919 -178.621436)
		(end 82.469482 -221.593156)
		(width 0.1651)
		(layer "In9.Cu")
		(net "P5E_PEX0_STN0_TX_DP<4>")
	)
	(segment
		(start 87.683086 -133.828028)
		(end 87.858092 -134.250684)
		(width 0.1651)
		(layer "In9.Cu")
		(net "P5E_PEX0_STN0_TX_DP<4>")
	)
	(segment
		(start 77.12964 -284.14472)
		(end 77.12964 -284.385512)
		(width 0.1143)
		(layer "In9.Cu")
		(net "P5E_PEX0_STN0_TX_DP<4>")
	)
	(segment
		(start 81.823052 -130.478276)
		(end 82.73796 -130.478276)
		(width 0.1651)
		(layer "In9.Cu")
		(net "P5E_PEX0_STN0_TX_DP<4>")
	)
	(segment
		(start 95.6056 -370.99875)
		(end 95.6056 -370.959888)
		(width 0.1651)
		(layer "In9.Cu")
		(net "P5E_PEX0_STN5_RX_DP<83>")
	)
	(segment
		(start 78.509876 -397.972026)
		(end 78.636876 -398.099026)
		(width 0.1651)
		(layer "In9.Cu")
		(net "P5E_PEX0_STN5_RX_DP<83>")
	)
	(segment
		(start 60.979558 -318.406272)
		(end 61.256164 -318.129666)
		(width 0.1143)
		(layer "In9.Cu")
		(net "P5E_PEX0_STN5_RX_DP<83>")
	)
	(segment
		(start 60.979558 -319.819528)
		(end 60.979558 -318.406272)
		(width 0.1143)
		(layer "In9.Cu")
		(net "P5E_PEX0_STN5_RX_DP<83>")
	)
	(segment
		(start 88.40089 -358.901492)
		(end 88.089232 -358.029764)
		(width 0.1651)
		(layer "In9.Cu")
		(net "P5E_PEX0_STN5_RX_DP<83>")
	)
	(segment
		(start 81.30286 -392.688064)
		(end 81.410556 -392.688064)
		(width 0.1651)
		(layer "In9.Cu")
		(net "P5E_PEX0_STN5_RX_DP<83>")
	)
	(segment
		(start 60.933838 -319.865248)
		(end 60.979558 -319.819528)
		(width 0.1143)
		(layer "In9.Cu")
		(net "P5E_PEX0_STN5_RX_DP<83>")
	)
	(segment
		(start 61.256164 -318.129666)
		(end 61.460888 -318.129666)
		(width 0.1143)
		(layer "In9.Cu")
		(net "P5E_PEX0_STN5_RX_DP<83>")
	)
	(segment
		(start 78.976982 -398.099026)
		(end 79.402432 -397.673576)
		(width 0.1651)
		(layer "In9.Cu")
		(net "P5E_PEX0_STN5_RX_DP<83>")
	)
	(segment
		(start 79.402432 -394.696188)
		(end 80.144112 -393.954508)
		(width 0.1651)
		(layer "In9.Cu")
		(net "P5E_PEX0_STN5_RX_DP<83>")
	)
	(segment
		(start 94.540578 -366.382554)
		(end 88.40089 -358.901492)
		(width 0.1651)
		(layer "In9.Cu")
		(net "P5E_PEX0_STN5_RX_DP<83>")
	)
	(segment
		(start 60.933838 -320.686684)
		(end 60.933838 -319.893696)
		(width 0.1651)
		(layer "In9.Cu")
		(net "P5E_PEX0_STN5_RX_DP<83>")
	)
	(segment
		(start 95.182436 -368.83213)
		(end 94.961202 -367.557558)
		(width 0.1651)
		(layer "In9.Cu")
		(net "P5E_PEX0_STN5_RX_DP<83>")
	)
	(segment
		(start 61.549788 -318.040766)
		(end 61.549788 -317.749936)
		(width 0.1143)
		(layer "In9.Cu")
		(net "P5E_PEX0_STN5_RX_DP<83>")
	)
	(segment
		(start 61.460888 -318.129666)
		(end 61.549788 -318.040766)
		(width 0.1143)
		(layer "In9.Cu")
		(net "P5E_PEX0_STN5_RX_DP<83>")
	)
	(segment
		(start 80.602328 -393.496292)
		(end 80.95234 -393.14628)
		(width 0.1651)
		(layer "In9.Cu")
		(net "P5E_PEX0_STN5_RX_DP<83>")
	)
	(segment
		(start 79.402432 -397.673576)
		(end 79.402432 -394.696188)
		(width 0.1651)
		(layer "In9.Cu")
		(net "P5E_PEX0_STN5_RX_DP<83>")
	)
	(segment
		(start 80.144112 -393.954508)
		(end 80.144112 -393.846812)
		(width 0.1651)
		(layer "In9.Cu")
		(net "P5E_PEX0_STN5_RX_DP<83>")
	)
	(segment
		(start 95.6056 -370.959888)
		(end 95.182436 -368.83213)
		(width 0.1651)
		(layer "In9.Cu")
		(net "P5E_PEX0_STN5_RX_DP<83>")
	)
	(segment
		(start 80.494632 -393.496292)
		(end 80.602328 -393.496292)
		(width 0.1651)
		(layer "In9.Cu")
		(net "P5E_PEX0_STN5_RX_DP<83>")
	)
	(segment
		(start 87.74176 -341.25154)
		(end 85.473286 -338.983066)
		(width 0.1651)
		(layer "In9.Cu")
		(net "P5E_PEX0_STN5_RX_DP<83>")
	)
	(segment
		(start 60.933838 -319.893696)
		(end 60.933838 -319.865248)
		(width 0.1143)
		(layer "In9.Cu")
		(net "P5E_PEX0_STN5_RX_DP<83>")
	)
	(segment
		(start 82.846672 -391.251948)
		(end 92.930472 -389.245602)
		(width 0.1651)
		(layer "In9.Cu")
		(net "P5E_PEX0_STN5_RX_DP<83>")
	)
	(segment
		(start 80.144112 -393.846812)
		(end 80.494632 -393.496292)
		(width 0.1651)
		(layer "In9.Cu")
		(net "P5E_PEX0_STN5_RX_DP<83>")
	)
	(segment
		(start 80.95234 -393.14628)
		(end 80.95234 -393.03833)
		(width 0.1651)
		(layer "In9.Cu")
		(net "P5E_PEX0_STN5_RX_DP<83>")
	)
	(segment
		(start 94.961202 -367.557558)
		(end 94.540578 -366.382554)
		(width 0.1651)
		(layer "In9.Cu")
		(net "P5E_PEX0_STN5_RX_DP<83>")
	)
	(segment
		(start 95.28302 -385.447794)
		(end 95.6056 -370.99875)
		(width 0.1651)
		(layer "In9.Cu")
		(net "P5E_PEX0_STN5_RX_DP<83>")
	)
	(segment
		(start 78.509876 -397.59001)
		(end 78.509876 -397.972026)
		(width 0.1651)
		(layer "In9.Cu")
		(net "P5E_PEX0_STN5_RX_DP<83>")
	)
	(segment
		(start 85.473286 -338.983066)
		(end 63.768732 -324.480428)
		(width 0.1651)
		(layer "In9.Cu")
		(net "P5E_PEX0_STN5_RX_DP<83>")
	)
	(segment
		(start 95.28302 -386.58673)
		(end 95.28302 -385.447794)
		(width 0.1651)
		(layer "In9.Cu")
		(net "P5E_PEX0_STN5_RX_DP<83>")
	)
	(segment
		(start 61.612526 -322.324222)
		(end 60.933838 -320.686684)
		(width 0.1651)
		(layer "In9.Cu")
		(net "P5E_PEX0_STN5_RX_DP<83>")
	)
	(segment
		(start 78.636876 -398.099026)
		(end 78.976982 -398.099026)
		(width 0.1651)
		(layer "In9.Cu")
		(net "P5E_PEX0_STN5_RX_DP<83>")
	)
	(segment
		(start 88.089232 -342.090502)
		(end 87.74176 -341.25154)
		(width 0.1651)
		(layer "In9.Cu")
		(net "P5E_PEX0_STN5_RX_DP<83>")
	)
	(segment
		(start 81.410556 -392.688064)
		(end 82.846672 -391.251948)
		(width 0.1651)
		(layer "In9.Cu")
		(net "P5E_PEX0_STN5_RX_DP<83>")
	)
	(segment
		(start 94.772988 -387.81863)
		(end 95.28302 -386.58673)
		(width 0.1651)
		(layer "In9.Cu")
		(net "P5E_PEX0_STN5_RX_DP<83>")
	)
	(segment
		(start 92.930472 -389.245602)
		(end 93.639386 -388.952232)
		(width 0.1651)
		(layer "In9.Cu")
		(net "P5E_PEX0_STN5_RX_DP<83>")
	)
	(segment
		(start 88.089232 -358.029764)
		(end 88.089232 -342.090502)
		(width 0.1651)
		(layer "In9.Cu")
		(net "P5E_PEX0_STN5_RX_DP<83>")
	)
	(segment
		(start 80.95234 -393.03833)
		(end 81.30286 -392.688064)
		(width 0.1651)
		(layer "In9.Cu")
		(net "P5E_PEX0_STN5_RX_DP<83>")
	)
	(segment
		(start 93.639386 -388.952232)
		(end 94.772988 -387.81863)
		(width 0.1651)
		(layer "In9.Cu")
		(net "P5E_PEX0_STN5_RX_DP<83>")
	)
	(segment
		(start 63.768732 -324.480428)
		(end 61.612526 -322.324222)
		(width 0.1651)
		(layer "In9.Cu")
		(net "P5E_PEX0_STN5_RX_DP<83>")
	)
	(segment
		(start 93.030802 -355.658166)
		(end 93.030802 -355.026722)
		(width 0.13462)
		(layer "F.Cu")
		(net "P5E_PEX0_STN6_TX_DN<96>")
	)
	(segment
		(start 93.350842 -355.978206)
		(end 93.030802 -355.658166)
		(width 0.13462)
		(layer "F.Cu")
		(net "P5E_PEX0_STN6_TX_DN<96>")
	)
	(segment
		(start 93.030802 -355.026722)
		(end 93.325442 -354.732082)
		(width 0.13462)
		(layer "F.Cu")
		(net "P5E_PEX0_STN6_TX_DN<96>")
	)
	(segment
		(start 94.589092 -352.197924)
		(end 93.034612 -353.752404)
		(width 0.1651)
		(layer "In13.Cu")
		(net "P5E_PEX0_STN6_TX_DN<96>")
	)
	(segment
		(start 57.749948 -313.659012)
		(end 57.661048 -313.570112)
		(width 0.1143)
		(layer "In13.Cu")
		(net "P5E_PEX0_STN6_TX_DN<96>")
	)
	(segment
		(start 91.218004 -337.902804)
		(end 94.037658 -340.722458)
		(width 0.1651)
		(layer "In13.Cu")
		(net "P5E_PEX0_STN6_TX_DN<96>")
	)
	(segment
		(start 57.370218 -313.697366)
		(end 57.370218 -320.130932)
		(width 0.1143)
		(layer "In13.Cu")
		(net "P5E_PEX0_STN6_TX_DN<96>")
	)
	(segment
		(start 57.497472 -313.570112)
		(end 57.370218 -313.697366)
		(width 0.1143)
		(layer "In13.Cu")
		(net "P5E_PEX0_STN6_TX_DN<96>")
	)
	(segment
		(start 57.415938 -320.820034)
		(end 57.796938 -321.390264)
		(width 0.1651)
		(layer "In13.Cu")
		(net "P5E_PEX0_STN6_TX_DN<96>")
	)
	(segment
		(start 57.749948 -313.949842)
		(end 57.749948 -313.659012)
		(width 0.1143)
		(layer "In13.Cu")
		(net "P5E_PEX0_STN6_TX_DN<96>")
	)
	(segment
		(start 57.415938 -320.176652)
		(end 57.415938 -320.19875)
		(width 0.1143)
		(layer "In13.Cu")
		(net "P5E_PEX0_STN6_TX_DN<96>")
	)
	(segment
		(start 94.037658 -340.722458)
		(end 94.589092 -342.053672)
		(width 0.1651)
		(layer "In13.Cu")
		(net "P5E_PEX0_STN6_TX_DN<96>")
	)
	(segment
		(start 93.034612 -353.752404)
		(end 93.034612 -354.441252)
		(width 0.1651)
		(layer "In13.Cu")
		(net "P5E_PEX0_STN6_TX_DN<96>")
	)
	(segment
		(start 57.415938 -320.19875)
		(end 57.415938 -320.820034)
		(width 0.1651)
		(layer "In13.Cu")
		(net "P5E_PEX0_STN6_TX_DN<96>")
	)
	(segment
		(start 57.370218 -320.130932)
		(end 57.415938 -320.176652)
		(width 0.1143)
		(layer "In13.Cu")
		(net "P5E_PEX0_STN6_TX_DN<96>")
	)
	(segment
		(start 57.661048 -313.570112)
		(end 57.497472 -313.570112)
		(width 0.1143)
		(layer "In13.Cu")
		(net "P5E_PEX0_STN6_TX_DN<96>")
	)
	(segment
		(start 57.796938 -321.390264)
		(end 69.026786 -326.041766)
		(width 0.1651)
		(layer "In13.Cu")
		(net "P5E_PEX0_STN6_TX_DN<96>")
	)
	(segment
		(start 93.034612 -354.441252)
		(end 93.325442 -354.732082)
		(width 0.1651)
		(layer "In13.Cu")
		(net "P5E_PEX0_STN6_TX_DN<96>")
	)
	(segment
		(start 94.589092 -342.053672)
		(end 94.589092 -352.197924)
		(width 0.1651)
		(layer "In13.Cu")
		(net "P5E_PEX0_STN6_TX_DN<96>")
	)
	(segment
		(start 69.026786 -326.041766)
		(end 91.218004 -337.902804)
		(width 0.1651)
		(layer "In13.Cu")
		(net "P5E_PEX0_STN6_TX_DN<96>")
	)
	(segment
		(start 168.698672 -345.170506)
		(end 168.698672 -344.539062)
		(width 0.13462)
		(layer "F.Cu")
		(net "P5E_PEX1_STN7_TX_C_DP<115>")
	)
	(segment
		(start 168.404032 -345.465146)
		(end 168.698672 -345.170506)
		(width 0.13462)
		(layer "F.Cu")
		(net "P5E_PEX1_STN7_TX_C_DP<115>")
	)
	(segment
		(start 168.698672 -344.539062)
		(end 168.378632 -344.219022)
		(width 0.13462)
		(layer "F.Cu")
		(net "P5E_PEX1_STN7_TX_C_DP<115>")
	)
	(segment
		(start 159.257492 -390.555734)
		(end 159.727646 -390.710928)
		(width 0.1651)
		(layer "In11.Cu")
		(net "P5E_PEX1_STN7_TX_C_DP<115>")
	)
	(segment
		(start 155.932886 -388.088632)
		(end 159.257492 -390.555734)
		(width 0.1651)
		(layer "In11.Cu")
		(net "P5E_PEX1_STN7_TX_C_DP<115>")
	)
	(segment
		(start 160.262824 -390.9949)
		(end 160.391094 -390.93013)
		(width 0.1651)
		(layer "In11.Cu")
		(net "P5E_PEX1_STN7_TX_C_DP<115>")
	)
	(segment
		(start 162.959796 -392.148568)
		(end 163.099496 -392.115294)
		(width 0.1651)
		(layer "In11.Cu")
		(net "P5E_PEX1_STN7_TX_C_DP<115>")
	)
	(segment
		(start 164.116004 -392.741658)
		(end 165.661594 -393.693904)
		(width 0.1651)
		(layer "In11.Cu")
		(net "P5E_PEX1_STN7_TX_C_DP<115>")
	)
	(segment
		(start 166.509954 -401.872196)
		(end 166.509954 -401.49018)
		(width 0.1651)
		(layer "In11.Cu")
		(net "P5E_PEX1_STN7_TX_C_DP<115>")
	)
	(segment
		(start 167.393112 -395.425168)
		(end 167.393112 -401.858734)
		(width 0.1651)
		(layer "In11.Cu")
		(net "P5E_PEX1_STN7_TX_C_DP<115>")
	)
	(segment
		(start 165.661594 -393.693904)
		(end 165.661848 -393.693904)
		(width 0.1651)
		(layer "In11.Cu")
		(net "P5E_PEX1_STN7_TX_C_DP<115>")
	)
	(segment
		(start 166.22903 -394.261086)
		(end 166.22903 -394.40485)
		(width 0.1651)
		(layer "In11.Cu")
		(net "P5E_PEX1_STN7_TX_C_DP<115>")
	)
	(segment
		(start 165.871652 -359.77576)
		(end 158.255462 -362.972604)
		(width 0.1651)
		(layer "In11.Cu")
		(net "P5E_PEX1_STN7_TX_C_DP<115>")
	)
	(segment
		(start 162.504628 -391.748518)
		(end 162.537648 -391.888472)
		(width 0.1651)
		(layer "In11.Cu")
		(net "P5E_PEX1_STN7_TX_C_DP<115>")
	)
	(segment
		(start 168.694862 -345.755976)
		(end 168.694862 -346.401644)
		(width 0.1651)
		(layer "In11.Cu")
		(net "P5E_PEX1_STN7_TX_C_DP<115>")
	)
	(segment
		(start 163.521136 -392.374882)
		(end 163.554156 -392.514836)
		(width 0.1651)
		(layer "In11.Cu")
		(net "P5E_PEX1_STN7_TX_C_DP<115>")
	)
	(segment
		(start 160.391094 -390.93013)
		(end 160.861248 -391.085324)
		(width 0.1651)
		(layer "In11.Cu")
		(net "P5E_PEX1_STN7_TX_C_DP<115>")
	)
	(segment
		(start 161.396426 -391.369296)
		(end 161.524696 -391.30478)
		(width 0.1651)
		(layer "In11.Cu")
		(net "P5E_PEX1_STN7_TX_C_DP<115>")
	)
	(segment
		(start 155.715716 -365.579406)
		(end 154.751786 -368.129058)
		(width 0.1651)
		(layer "In11.Cu")
		(net "P5E_PEX1_STN7_TX_C_DP<115>")
	)
	(segment
		(start 159.727646 -390.710928)
		(end 159.792162 -390.839452)
		(width 0.1651)
		(layer "In11.Cu")
		(net "P5E_PEX1_STN7_TX_C_DP<115>")
	)
	(segment
		(start 168.694862 -346.401644)
		(end 167.140382 -347.956124)
		(width 0.1651)
		(layer "In11.Cu")
		(net "P5E_PEX1_STN7_TX_C_DP<115>")
	)
	(segment
		(start 167.25265 -401.999196)
		(end 166.636954 -401.999196)
		(width 0.1651)
		(layer "In11.Cu")
		(net "P5E_PEX1_STN7_TX_C_DP<115>")
	)
	(segment
		(start 167.140382 -358.50703)
		(end 165.871652 -359.77576)
		(width 0.1651)
		(layer "In11.Cu")
		(net "P5E_PEX1_STN7_TX_C_DP<115>")
	)
	(segment
		(start 154.813 -385.318508)
		(end 155.932886 -388.088632)
		(width 0.1651)
		(layer "In11.Cu")
		(net "P5E_PEX1_STN7_TX_C_DP<115>")
	)
	(segment
		(start 163.554156 -392.514836)
		(end 163.976304 -392.774932)
		(width 0.1651)
		(layer "In11.Cu")
		(net "P5E_PEX1_STN7_TX_C_DP<115>")
	)
	(segment
		(start 158.255462 -362.972604)
		(end 155.715716 -365.579406)
		(width 0.1651)
		(layer "In11.Cu")
		(net "P5E_PEX1_STN7_TX_C_DP<115>")
	)
	(segment
		(start 163.976304 -392.774932)
		(end 164.116004 -392.741658)
		(width 0.1651)
		(layer "In11.Cu")
		(net "P5E_PEX1_STN7_TX_C_DP<115>")
	)
	(segment
		(start 163.099496 -392.115294)
		(end 163.521136 -392.374882)
		(width 0.1651)
		(layer "In11.Cu")
		(net "P5E_PEX1_STN7_TX_C_DP<115>")
	)
	(segment
		(start 166.57955 -394.75537)
		(end 166.723314 -394.75537)
		(width 0.1651)
		(layer "In11.Cu")
		(net "P5E_PEX1_STN7_TX_C_DP<115>")
	)
	(segment
		(start 167.393112 -401.858734)
		(end 167.25265 -401.999196)
		(width 0.1651)
		(layer "In11.Cu")
		(net "P5E_PEX1_STN7_TX_C_DP<115>")
	)
	(segment
		(start 165.661848 -393.693904)
		(end 166.22903 -394.261086)
		(width 0.1651)
		(layer "In11.Cu")
		(net "P5E_PEX1_STN7_TX_C_DP<115>")
	)
	(segment
		(start 160.861248 -391.085324)
		(end 160.925764 -391.213848)
		(width 0.1651)
		(layer "In11.Cu")
		(net "P5E_PEX1_STN7_TX_C_DP<115>")
	)
	(segment
		(start 161.524696 -391.30478)
		(end 162.082988 -391.48893)
		(width 0.1651)
		(layer "In11.Cu")
		(net "P5E_PEX1_STN7_TX_C_DP<115>")
	)
	(segment
		(start 166.22903 -394.40485)
		(end 166.57955 -394.75537)
		(width 0.1651)
		(layer "In11.Cu")
		(net "P5E_PEX1_STN7_TX_C_DP<115>")
	)
	(segment
		(start 159.792162 -390.839452)
		(end 160.262824 -390.9949)
		(width 0.1651)
		(layer "In11.Cu")
		(net "P5E_PEX1_STN7_TX_C_DP<115>")
	)
	(segment
		(start 166.636954 -401.999196)
		(end 166.509954 -401.872196)
		(width 0.1651)
		(layer "In11.Cu")
		(net "P5E_PEX1_STN7_TX_C_DP<115>")
	)
	(segment
		(start 167.140382 -347.956124)
		(end 167.140382 -358.50703)
		(width 0.1651)
		(layer "In11.Cu")
		(net "P5E_PEX1_STN7_TX_C_DP<115>")
	)
	(segment
		(start 160.925764 -391.213848)
		(end 161.396426 -391.369296)
		(width 0.1651)
		(layer "In11.Cu")
		(net "P5E_PEX1_STN7_TX_C_DP<115>")
	)
	(segment
		(start 166.723314 -394.75537)
		(end 167.393112 -395.425168)
		(width 0.1651)
		(layer "In11.Cu")
		(net "P5E_PEX1_STN7_TX_C_DP<115>")
	)
	(segment
		(start 162.537648 -391.888472)
		(end 162.959796 -392.148568)
		(width 0.1651)
		(layer "In11.Cu")
		(net "P5E_PEX1_STN7_TX_C_DP<115>")
	)
	(segment
		(start 168.404032 -345.465146)
		(end 168.694862 -345.755976)
		(width 0.1651)
		(layer "In11.Cu")
		(net "P5E_PEX1_STN7_TX_C_DP<115>")
	)
	(segment
		(start 154.751786 -368.129058)
		(end 154.575256 -382.573784)
		(width 0.1651)
		(layer "In11.Cu")
		(net "P5E_PEX1_STN7_TX_C_DP<115>")
	)
	(segment
		(start 162.082988 -391.48893)
		(end 162.504628 -391.748518)
		(width 0.1651)
		(layer "In11.Cu")
		(net "P5E_PEX1_STN7_TX_C_DP<115>")
	)
	(segment
		(start 154.575256 -382.573784)
		(end 154.813 -385.318508)
		(width 0.1651)
		(layer "In11.Cu")
		(net "P5E_PEX1_STN7_TX_C_DP<115>")
	)
	(segment
		(start 74.671682 -351.611438)
		(end 74.377042 -351.316798)
		(width 0.13462)
		(layer "F.Cu")
		(net "P5E_PEX0_STN5_TX_C_DN<86>")
	)
	(segment
		(start 74.377042 -350.685354)
		(end 74.697082 -350.365314)
		(width 0.13462)
		(layer "F.Cu")
		(net "P5E_PEX0_STN5_TX_C_DN<86>")
	)
	(segment
		(start 74.377042 -351.316798)
		(end 74.377042 -350.685354)
		(width 0.13462)
		(layer "F.Cu")
		(net "P5E_PEX0_STN5_TX_C_DN<86>")
	)
	(segment
		(start 86.284054 -404.486872)
		(end 86.284054 -393.928854)
		(width 0.1651)
		(layer "In7.Cu")
		(net "P5E_PEX0_STN5_TX_C_DN<86>")
	)
	(segment
		(start 70.428358 -385.642104)
		(end 69.929248 -384.437128)
		(width 0.1651)
		(layer "In7.Cu")
		(net "P5E_PEX0_STN5_TX_C_DN<86>")
	)
	(segment
		(start 86.284054 -393.928854)
		(end 84.311236 -391.956036)
		(width 0.1651)
		(layer "In7.Cu")
		(net "P5E_PEX0_STN5_TX_C_DN<86>")
	)
	(segment
		(start 84.311236 -391.956036)
		(end 71.390002 -386.603748)
		(width 0.1651)
		(layer "In7.Cu")
		(net "P5E_PEX0_STN5_TX_C_DN<86>")
	)
	(segment
		(start 69.793866 -368.581432)
		(end 69.793866 -367.957354)
		(width 0.1651)
		(layer "In7.Cu")
		(net "P5E_PEX0_STN5_TX_C_DN<86>")
	)
	(segment
		(start 85.109812 -405.589994)
		(end 85.109812 -405.207978)
		(width 0.1651)
		(layer "In7.Cu")
		(net "P5E_PEX0_STN5_TX_C_DN<86>")
	)
	(segment
		(start 72.826372 -357.960168)
		(end 72.826372 -354.107242)
		(width 0.1651)
		(layer "In7.Cu")
		(net "P5E_PEX0_STN5_TX_C_DN<86>")
	)
	(segment
		(start 69.929248 -384.437128)
		(end 69.929248 -378.97943)
		(width 0.1651)
		(layer "In7.Cu")
		(net "P5E_PEX0_STN5_TX_C_DN<86>")
	)
	(segment
		(start 85.109812 -405.207978)
		(end 85.236812 -405.080978)
		(width 0.1651)
		(layer "In7.Cu")
		(net "P5E_PEX0_STN5_TX_C_DN<86>")
	)
	(segment
		(start 69.793866 -367.957354)
		(end 72.826372 -357.960168)
		(width 0.1651)
		(layer "In7.Cu")
		(net "P5E_PEX0_STN5_TX_C_DN<86>")
	)
	(segment
		(start 71.390002 -386.603748)
		(end 70.428358 -385.642104)
		(width 0.1651)
		(layer "In7.Cu")
		(net "P5E_PEX0_STN5_TX_C_DN<86>")
	)
	(segment
		(start 72.826372 -354.107242)
		(end 74.380852 -352.552762)
		(width 0.1651)
		(layer "In7.Cu")
		(net "P5E_PEX0_STN5_TX_C_DN<86>")
	)
	(segment
		(start 85.236812 -405.080978)
		(end 85.689948 -405.080978)
		(width 0.1651)
		(layer "In7.Cu")
		(net "P5E_PEX0_STN5_TX_C_DN<86>")
	)
	(segment
		(start 74.380852 -351.902268)
		(end 74.671682 -351.611438)
		(width 0.1651)
		(layer "In7.Cu")
		(net "P5E_PEX0_STN5_TX_C_DN<86>")
	)
	(segment
		(start 74.380852 -352.552762)
		(end 74.380852 -351.902268)
		(width 0.1651)
		(layer "In7.Cu")
		(net "P5E_PEX0_STN5_TX_C_DN<86>")
	)
	(segment
		(start 69.929248 -378.97943)
		(end 69.793866 -368.581432)
		(width 0.1651)
		(layer "In7.Cu")
		(net "P5E_PEX0_STN5_TX_C_DN<86>")
	)
	(segment
		(start 85.689948 -405.080978)
		(end 86.284054 -404.486872)
		(width 0.1651)
		(layer "In7.Cu")
		(net "P5E_PEX0_STN5_TX_C_DN<86>")
	)
	(segment
		(start 36.371784 -119.198898)
		(end 36.051744 -119.518938)
		(width 0.13462)
		(layer "F.Cu")
		(net "P5E_PEX0_STN1_TX_DP<24>")
	)
	(segment
		(start 35.4203 -119.518938)
		(end 35.12566 -119.224298)
		(width 0.13462)
		(layer "F.Cu")
		(net "P5E_PEX0_STN1_TX_DP<24>")
	)
	(segment
		(start 36.051744 -119.518938)
		(end 35.4203 -119.518938)
		(width 0.13462)
		(layer "F.Cu")
		(net "P5E_PEX0_STN1_TX_DP<24>")
	)
	(segment
		(start 66.633852 -271.500346)
		(end 66.633852 -271.471898)
		(width 0.1143)
		(layer "In9.Cu")
		(net "P5E_PEX0_STN1_TX_DP<24>")
	)
	(segment
		(start 66.679572 -278.205184)
		(end 66.679572 -271.546066)
		(width 0.1143)
		(layer "In9.Cu")
		(net "P5E_PEX0_STN1_TX_DP<24>")
	)
	(segment
		(start 66.633852 -264.281666)
		(end 31.821882 -161.439098)
		(width 0.1651)
		(layer "In9.Cu")
		(net "P5E_PEX0_STN1_TX_DP<24>")
	)
	(segment
		(start 34.83483 -119.515128)
		(end 35.12566 -119.224298)
		(width 0.1651)
		(layer "In9.Cu")
		(net "P5E_PEX0_STN1_TX_DP<24>")
	)
	(segment
		(start 32.34309 -121.253758)
		(end 34.08172 -119.515128)
		(width 0.1651)
		(layer "In9.Cu")
		(net "P5E_PEX0_STN1_TX_DP<24>")
	)
	(segment
		(start 67.249548 -278.799798)
		(end 67.249548 -278.534368)
		(width 0.1143)
		(layer "In9.Cu")
		(net "P5E_PEX0_STN1_TX_DP<24>")
	)
	(segment
		(start 66.679572 -271.546066)
		(end 66.633852 -271.500346)
		(width 0.1143)
		(layer "In9.Cu")
		(net "P5E_PEX0_STN1_TX_DP<24>")
	)
	(segment
		(start 67.135248 -278.420068)
		(end 66.894456 -278.420068)
		(width 0.1143)
		(layer "In9.Cu")
		(net "P5E_PEX0_STN1_TX_DP<24>")
	)
	(segment
		(start 27.947112 -131.866386)
		(end 32.34309 -121.253758)
		(width 0.1651)
		(layer "In9.Cu")
		(net "P5E_PEX0_STN1_TX_DP<24>")
	)
	(segment
		(start 27.947112 -137.452608)
		(end 27.947112 -131.866386)
		(width 0.1651)
		(layer "In9.Cu")
		(net "P5E_PEX0_STN1_TX_DP<24>")
	)
	(segment
		(start 31.821882 -161.439098)
		(end 31.23565 -158.49219)
		(width 0.1651)
		(layer "In9.Cu")
		(net "P5E_PEX0_STN1_TX_DP<24>")
	)
	(segment
		(start 66.633852 -271.471898)
		(end 66.633852 -264.281666)
		(width 0.1651)
		(layer "In9.Cu")
		(net "P5E_PEX0_STN1_TX_DP<24>")
	)
	(segment
		(start 31.23565 -158.49219)
		(end 30.504638 -143.627094)
		(width 0.1651)
		(layer "In9.Cu")
		(net "P5E_PEX0_STN1_TX_DP<24>")
	)
	(segment
		(start 66.894456 -278.420068)
		(end 66.679572 -278.205184)
		(width 0.1143)
		(layer "In9.Cu")
		(net "P5E_PEX0_STN1_TX_DP<24>")
	)
	(segment
		(start 34.08172 -119.515128)
		(end 34.83483 -119.515128)
		(width 0.1651)
		(layer "In9.Cu")
		(net "P5E_PEX0_STN1_TX_DP<24>")
	)
	(segment
		(start 30.504638 -143.627094)
		(end 27.947112 -137.452608)
		(width 0.1651)
		(layer "In9.Cu")
		(net "P5E_PEX0_STN1_TX_DP<24>")
	)
	(segment
		(start 67.249548 -278.534368)
		(end 67.135248 -278.420068)
		(width 0.1143)
		(layer "In9.Cu")
		(net "P5E_PEX0_STN1_TX_DP<24>")
	)
	(segment
		(start 63.721742 -328.485754)
		(end 58.952892 -323.716904)
		(width 0.1651)
		(layer "In9.Cu")
		(net "P5E_PEX0_STN5_RX_DP<80>")
	)
	(segment
		(start 58.699908 -316.140592)
		(end 58.699908 -315.849762)
		(width 0.1143)
		(layer "In9.Cu")
		(net "P5E_PEX0_STN5_RX_DP<80>")
	)
	(segment
		(start 91.990672 -368.11077)
		(end 81.518506 -361.113578)
		(width 0.1651)
		(layer "In9.Cu")
		(net "P5E_PEX0_STN5_RX_DP<80>")
	)
	(segment
		(start 77.99832 -389.2931)
		(end 92.037662 -386.500624)
		(width 0.1651)
		(layer "In9.Cu")
		(net "P5E_PEX0_STN5_RX_DP<80>")
	)
	(segment
		(start 72.84466 -394.44676)
		(end 73.870312 -393.421108)
		(width 0.1651)
		(layer "In9.Cu")
		(net "P5E_PEX0_STN5_RX_DP<80>")
	)
	(segment
		(start 78.164182 -340.690962)
		(end 70.464172 -332.990952)
		(width 0.1651)
		(layer "In9.Cu")
		(net "P5E_PEX0_STN5_RX_DP<80>")
	)
	(segment
		(start 58.611008 -316.229492)
		(end 58.699908 -316.140592)
		(width 0.1143)
		(layer "In9.Cu")
		(net "P5E_PEX0_STN5_RX_DP<80>")
	)
	(segment
		(start 81.518506 -361.113578)
		(end 80.38211 -360.181144)
		(width 0.1651)
		(layer "In9.Cu")
		(net "P5E_PEX0_STN5_RX_DP<80>")
	)
	(segment
		(start 78.762352 -358.561132)
		(end 78.762352 -342.135206)
		(width 0.1651)
		(layer "In9.Cu")
		(net "P5E_PEX0_STN5_RX_DP<80>")
	)
	(segment
		(start 74.346308 -392.945112)
		(end 74.69632 -392.5951)
		(width 0.1651)
		(layer "In9.Cu")
		(net "P5E_PEX0_STN5_RX_DP<80>")
	)
	(segment
		(start 72.84466 -396.580614)
		(end 72.84466 -394.44676)
		(width 0.1651)
		(layer "In9.Cu")
		(net "P5E_PEX0_STN5_RX_DP<80>")
	)
	(segment
		(start 92.234004 -368.69878)
		(end 91.990672 -368.11077)
		(width 0.1651)
		(layer "In9.Cu")
		(net "P5E_PEX0_STN5_RX_DP<80>")
	)
	(segment
		(start 92.69349 -371.009672)
		(end 92.234004 -368.69878)
		(width 0.1651)
		(layer "In9.Cu")
		(net "P5E_PEX0_STN5_RX_DP<80>")
	)
	(segment
		(start 92.372688 -386.022088)
		(end 92.372688 -385.415282)
		(width 0.1651)
		(layer "In9.Cu")
		(net "P5E_PEX0_STN5_RX_DP<80>")
	)
	(segment
		(start 75.04684 -392.11885)
		(end 75.17257 -392.11885)
		(width 0.1651)
		(layer "In9.Cu")
		(net "P5E_PEX0_STN5_RX_DP<80>")
	)
	(segment
		(start 72.426068 -396.999206)
		(end 72.84466 -396.580614)
		(width 0.1651)
		(layer "In9.Cu")
		(net "P5E_PEX0_STN5_RX_DP<80>")
	)
	(segment
		(start 58.083958 -321.619118)
		(end 58.083958 -319.944496)
		(width 0.1651)
		(layer "In9.Cu")
		(net "P5E_PEX0_STN5_RX_DP<80>")
	)
	(segment
		(start 74.69632 -392.46937)
		(end 75.04684 -392.11885)
		(width 0.1651)
		(layer "In9.Cu")
		(net "P5E_PEX0_STN5_RX_DP<80>")
	)
	(segment
		(start 78.762352 -342.135206)
		(end 78.164182 -340.690962)
		(width 0.1651)
		(layer "In9.Cu")
		(net "P5E_PEX0_STN5_RX_DP<80>")
	)
	(segment
		(start 71.90994 -396.49019)
		(end 71.90994 -396.872206)
		(width 0.1651)
		(layer "In9.Cu")
		(net "P5E_PEX0_STN5_RX_DP<80>")
	)
	(segment
		(start 92.037662 -386.500624)
		(end 92.271342 -386.266944)
		(width 0.1651)
		(layer "In9.Cu")
		(net "P5E_PEX0_STN5_RX_DP<80>")
	)
	(segment
		(start 92.372688 -385.415282)
		(end 92.69349 -371.009672)
		(width 0.1651)
		(layer "In9.Cu")
		(net "P5E_PEX0_STN5_RX_DP<80>")
	)
	(segment
		(start 73.870312 -393.421108)
		(end 73.870312 -393.295378)
		(width 0.1651)
		(layer "In9.Cu")
		(net "P5E_PEX0_STN5_RX_DP<80>")
	)
	(segment
		(start 58.406284 -316.229492)
		(end 58.611008 -316.229492)
		(width 0.1143)
		(layer "In9.Cu")
		(net "P5E_PEX0_STN5_RX_DP<80>")
	)
	(segment
		(start 71.90994 -396.872206)
		(end 72.03694 -396.999206)
		(width 0.1651)
		(layer "In9.Cu")
		(net "P5E_PEX0_STN5_RX_DP<80>")
	)
	(segment
		(start 80.38211 -360.181144)
		(end 78.762352 -358.561132)
		(width 0.1651)
		(layer "In9.Cu")
		(net "P5E_PEX0_STN5_RX_DP<80>")
	)
	(segment
		(start 58.952892 -323.716904)
		(end 58.083958 -321.619118)
		(width 0.1651)
		(layer "In9.Cu")
		(net "P5E_PEX0_STN5_RX_DP<80>")
	)
	(segment
		(start 75.17257 -392.11885)
		(end 77.99832 -389.2931)
		(width 0.1651)
		(layer "In9.Cu")
		(net "P5E_PEX0_STN5_RX_DP<80>")
	)
	(segment
		(start 58.083958 -319.944496)
		(end 58.083958 -319.916048)
		(width 0.1143)
		(layer "In9.Cu")
		(net "P5E_PEX0_STN5_RX_DP<80>")
	)
	(segment
		(start 58.129678 -319.870328)
		(end 58.129678 -316.506098)
		(width 0.1143)
		(layer "In9.Cu")
		(net "P5E_PEX0_STN5_RX_DP<80>")
	)
	(segment
		(start 74.69632 -392.5951)
		(end 74.69632 -392.46937)
		(width 0.1651)
		(layer "In9.Cu")
		(net "P5E_PEX0_STN5_RX_DP<80>")
	)
	(segment
		(start 74.220578 -392.945112)
		(end 74.346308 -392.945112)
		(width 0.1651)
		(layer "In9.Cu")
		(net "P5E_PEX0_STN5_RX_DP<80>")
	)
	(segment
		(start 70.464172 -332.990952)
		(end 63.721742 -328.485754)
		(width 0.1651)
		(layer "In9.Cu")
		(net "P5E_PEX0_STN5_RX_DP<80>")
	)
	(segment
		(start 73.870312 -393.295378)
		(end 74.220578 -392.945112)
		(width 0.1651)
		(layer "In9.Cu")
		(net "P5E_PEX0_STN5_RX_DP<80>")
	)
	(segment
		(start 58.083958 -319.916048)
		(end 58.129678 -319.870328)
		(width 0.1143)
		(layer "In9.Cu")
		(net "P5E_PEX0_STN5_RX_DP<80>")
	)
	(segment
		(start 58.129678 -316.506098)
		(end 58.406284 -316.229492)
		(width 0.1143)
		(layer "In9.Cu")
		(net "P5E_PEX0_STN5_RX_DP<80>")
	)
	(segment
		(start 92.271342 -386.266944)
		(end 92.372688 -386.022088)
		(width 0.1651)
		(layer "In9.Cu")
		(net "P5E_PEX0_STN5_RX_DP<80>")
	)
	(segment
		(start 72.03694 -396.999206)
		(end 72.426068 -396.999206)
		(width 0.1651)
		(layer "In9.Cu")
		(net "P5E_PEX0_STN5_RX_DP<80>")
	)
	(segment
		(start 71.268082 -356.831646)
		(end 71.588122 -356.511606)
		(width 0.13462)
		(layer "F.Cu")
		(net "P5E_PEX0_STN5_TX_C_DN<85>")
	)
	(segment
		(start 71.562722 -357.75773)
		(end 71.268082 -357.46309)
		(width 0.13462)
		(layer "F.Cu")
		(net "P5E_PEX0_STN5_TX_C_DN<85>")
	)
	(segment
		(start 71.268082 -357.46309)
		(end 71.268082 -356.831646)
		(width 0.13462)
		(layer "F.Cu")
		(net "P5E_PEX0_STN5_TX_C_DN<85>")
	)
	(segment
		(start 69.604128 -386.215382)
		(end 68.971922 -384.688842)
		(width 0.1651)
		(layer "In7.Cu")
		(net "P5E_PEX0_STN5_TX_C_DN<85>")
	)
	(segment
		(start 83.568032 -406.181052)
		(end 84.08416 -405.664924)
		(width 0.1651)
		(layer "In7.Cu")
		(net "P5E_PEX0_STN5_TX_C_DN<85>")
	)
	(segment
		(start 84.08416 -405.664924)
		(end 84.08416 -393.83716)
		(width 0.1651)
		(layer "In7.Cu")
		(net "P5E_PEX0_STN5_TX_C_DN<85>")
	)
	(segment
		(start 83.036918 -406.181052)
		(end 83.568032 -406.181052)
		(width 0.1651)
		(layer "In7.Cu")
		(net "P5E_PEX0_STN5_TX_C_DN<85>")
	)
	(segment
		(start 71.271892 -358.04856)
		(end 71.562722 -357.75773)
		(width 0.1651)
		(layer "In7.Cu")
		(net "P5E_PEX0_STN5_TX_C_DN<85>")
	)
	(segment
		(start 68.816728 -367.075212)
		(end 71.271892 -358.738424)
		(width 0.1651)
		(layer "In7.Cu")
		(net "P5E_PEX0_STN5_TX_C_DN<85>")
	)
	(segment
		(start 84.08416 -393.83716)
		(end 82.69351 -392.44651)
		(width 0.1651)
		(layer "In7.Cu")
		(net "P5E_PEX0_STN5_TX_C_DN<85>")
	)
	(segment
		(start 82.69351 -392.44651)
		(end 70.985634 -387.596888)
		(width 0.1651)
		(layer "In7.Cu")
		(net "P5E_PEX0_STN5_TX_C_DN<85>")
	)
	(segment
		(start 71.271892 -358.738424)
		(end 71.271892 -358.04856)
		(width 0.1651)
		(layer "In7.Cu")
		(net "P5E_PEX0_STN5_TX_C_DN<85>")
	)
	(segment
		(start 70.985634 -387.596888)
		(end 69.604128 -386.215382)
		(width 0.1651)
		(layer "In7.Cu")
		(net "P5E_PEX0_STN5_TX_C_DN<85>")
	)
	(segment
		(start 82.909918 -406.308052)
		(end 83.036918 -406.181052)
		(width 0.1651)
		(layer "In7.Cu")
		(net "P5E_PEX0_STN5_TX_C_DN<85>")
	)
	(segment
		(start 68.971922 -384.688842)
		(end 68.971922 -378.986034)
		(width 0.1651)
		(layer "In7.Cu")
		(net "P5E_PEX0_STN5_TX_C_DN<85>")
	)
	(segment
		(start 68.971922 -378.986034)
		(end 68.816728 -367.075212)
		(width 0.1651)
		(layer "In7.Cu")
		(net "P5E_PEX0_STN5_TX_C_DN<85>")
	)
	(segment
		(start 82.909918 -406.690068)
		(end 82.909918 -406.308052)
		(width 0.1651)
		(layer "In7.Cu")
		(net "P5E_PEX0_STN5_TX_C_DN<85>")
	)
	(segment
		(start 370.247418 -33.657286)
		(end 369.944904 -33.9598)
		(width 0.13462)
		(layer "F.Cu")
		(net "P5E_PEX3_STN2_TX_DN<47>")
	)
	(segment
		(start 369.329208 -33.9598)
		(end 369.001294 -33.631886)
		(width 0.13462)
		(layer "F.Cu")
		(net "P5E_PEX3_STN2_TX_DN<47>")
	)
	(segment
		(start 369.944904 -33.9598)
		(end 369.329208 -33.9598)
		(width 0.13462)
		(layer "F.Cu")
		(net "P5E_PEX3_STN2_TX_DN<47>")
	)
	(segment
		(start 392.635486 -278.229568)
		(end 392.749786 -278.115268)
		(width 0.1143)
		(layer "In11.Cu")
		(net "P5E_PEX3_STN2_TX_DN<47>")
	)
	(segment
		(start 372.794276 -35.183572)
		(end 382.521714 -47.342298)
		(width 0.1651)
		(layer "In11.Cu")
		(net "P5E_PEX3_STN2_TX_DN<47>")
	)
	(segment
		(start 392.473688 -278.229568)
		(end 392.635486 -278.229568)
		(width 0.1143)
		(layer "In11.Cu")
		(net "P5E_PEX3_STN2_TX_DN<47>")
	)
	(segment
		(start 371.49659 -34.151316)
		(end 372.794276 -35.183572)
		(width 0.1651)
		(layer "In11.Cu")
		(net "P5E_PEX3_STN2_TX_DN<47>")
	)
	(segment
		(start 384.040126 -50.623724)
		(end 384.71856 -62.636908)
		(width 0.1651)
		(layer "In11.Cu")
		(net "P5E_PEX3_STN2_TX_DN<47>")
	)
	(segment
		(start 392.415776 -271.399)
		(end 392.415776 -271.427448)
		(width 0.1143)
		(layer "In11.Cu")
		(net "P5E_PEX3_STN2_TX_DN<47>")
	)
	(segment
		(start 392.749786 -278.115268)
		(end 392.749786 -277.849838)
		(width 0.1143)
		(layer "In11.Cu")
		(net "P5E_PEX3_STN2_TX_DN<47>")
	)
	(segment
		(start 379.67031 -117.07495)
		(end 380.183898 -138.226292)
		(width 0.1651)
		(layer "In11.Cu")
		(net "P5E_PEX3_STN2_TX_DN<47>")
	)
	(segment
		(start 370.247418 -33.657286)
		(end 370.44503 -33.854898)
		(width 0.1651)
		(layer "In11.Cu")
		(net "P5E_PEX3_STN2_TX_DN<47>")
	)
	(segment
		(start 370.44503 -33.854898)
		(end 370.670328 -33.948116)
		(width 0.1651)
		(layer "In11.Cu")
		(net "P5E_PEX3_STN2_TX_DN<47>")
	)
	(segment
		(start 391.383012 -264.507726)
		(end 392.415776 -270.728694)
		(width 0.1651)
		(layer "In11.Cu")
		(net "P5E_PEX3_STN2_TX_DN<47>")
	)
	(segment
		(start 392.415776 -270.728694)
		(end 392.415776 -271.399)
		(width 0.1651)
		(layer "In11.Cu")
		(net "P5E_PEX3_STN2_TX_DN<47>")
	)
	(segment
		(start 383.545842 -49.197768)
		(end 384.040126 -50.623724)
		(width 0.1651)
		(layer "In11.Cu")
		(net "P5E_PEX3_STN2_TX_DN<47>")
	)
	(segment
		(start 382.521714 -47.342298)
		(end 383.545842 -49.197768)
		(width 0.1651)
		(layer "In11.Cu")
		(net "P5E_PEX3_STN2_TX_DN<47>")
	)
	(segment
		(start 384.71856 -62.636908)
		(end 383.859024 -78.909926)
		(width 0.1651)
		(layer "In11.Cu")
		(net "P5E_PEX3_STN2_TX_DN<47>")
	)
	(segment
		(start 380.343156 -104.589834)
		(end 379.67031 -117.07495)
		(width 0.1651)
		(layer "In11.Cu")
		(net "P5E_PEX3_STN2_TX_DN<47>")
	)
	(segment
		(start 371.073426 -33.948116)
		(end 371.49659 -34.151316)
		(width 0.1651)
		(layer "In11.Cu")
		(net "P5E_PEX3_STN2_TX_DN<47>")
	)
	(segment
		(start 392.415776 -271.427448)
		(end 392.370056 -271.473168)
		(width 0.1143)
		(layer "In11.Cu")
		(net "P5E_PEX3_STN2_TX_DN<47>")
	)
	(segment
		(start 392.370056 -271.473168)
		(end 392.370056 -278.125936)
		(width 0.1143)
		(layer "In11.Cu")
		(net "P5E_PEX3_STN2_TX_DN<47>")
	)
	(segment
		(start 392.370056 -278.125936)
		(end 392.473688 -278.229568)
		(width 0.1143)
		(layer "In11.Cu")
		(net "P5E_PEX3_STN2_TX_DN<47>")
	)
	(segment
		(start 383.859024 -78.909926)
		(end 380.343156 -104.589834)
		(width 0.1651)
		(layer "In11.Cu")
		(net "P5E_PEX3_STN2_TX_DN<47>")
	)
	(segment
		(start 380.183898 -138.226292)
		(end 391.383012 -264.507726)
		(width 0.1651)
		(layer "In11.Cu")
		(net "P5E_PEX3_STN2_TX_DN<47>")
	)
	(segment
		(start 370.670328 -33.948116)
		(end 371.073426 -33.948116)
		(width 0.1651)
		(layer "In11.Cu")
		(net "P5E_PEX3_STN2_TX_DN<47>")
	)
	(segment
		(start 30.489144 -303.407826)
		(end 33.119568 -302.883824)
		(width 0.1651)
		(layer "In5.Cu")
		(net "P5E_PEX0_STN7_RX_DP<114>")
	)
	(segment
		(start 33.024572 -395.182852)
		(end 33.024318 -395.182598)
		(width 0.1651)
		(layer "In5.Cu")
		(net "P5E_PEX0_STN7_RX_DP<114>")
	)
	(segment
		(start 22.469094 -312.058558)
		(end 24.849074 -307.604414)
		(width 0.1651)
		(layer "In5.Cu")
		(net "P5E_PEX0_STN7_RX_DP<114>")
	)
	(segment
		(start 35.634168 -302.929544)
		(end 39.09441 -302.929544)
		(width 0.1143)
		(layer "In5.Cu")
		(net "P5E_PEX0_STN7_RX_DP<114>")
	)
	(segment
		(start 32.448754 -394.391642)
		(end 24.63419 -389.707374)
		(width 0.1651)
		(layer "In5.Cu")
		(net "P5E_PEX0_STN7_RX_DP<114>")
	)
	(segment
		(start 32.766254 -408.699208)
		(end 33.176972 -408.28849)
		(width 0.1651)
		(layer "In5.Cu")
		(net "P5E_PEX0_STN7_RX_DP<114>")
	)
	(segment
		(start 32.31007 -408.190192)
		(end 32.31007 -408.572208)
		(width 0.1651)
		(layer "In5.Cu")
		(net "P5E_PEX0_STN7_RX_DP<114>")
	)
	(segment
		(start 39.320216 -303.15535)
		(end 39.320216 -303.385474)
		(width 0.1143)
		(layer "In5.Cu")
		(net "P5E_PEX0_STN7_RX_DP<114>")
	)
	(segment
		(start 17.472914 -331.043026)
		(end 19.836892 -318.767968)
		(width 0.1651)
		(layer "In5.Cu")
		(net "P5E_PEX0_STN7_RX_DP<114>")
	)
	(segment
		(start 19.836892 -318.767968)
		(end 20.095718 -317.787274)
		(width 0.1651)
		(layer "In5.Cu")
		(net "P5E_PEX0_STN7_RX_DP<114>")
	)
	(segment
		(start 20.095718 -317.787274)
		(end 22.469094 -312.058558)
		(width 0.1651)
		(layer "In5.Cu")
		(net "P5E_PEX0_STN7_RX_DP<114>")
	)
	(segment
		(start 24.849074 -307.604414)
		(end 25.621234 -306.44973)
		(width 0.1651)
		(layer "In5.Cu")
		(net "P5E_PEX0_STN7_RX_DP<114>")
	)
	(segment
		(start 33.024318 -395.182598)
		(end 32.872172 -394.81506)
		(width 0.1651)
		(layer "In5.Cu")
		(net "P5E_PEX0_STN7_RX_DP<114>")
	)
	(segment
		(start 33.176972 -395.550898)
		(end 33.024572 -395.182852)
		(width 0.1651)
		(layer "In5.Cu")
		(net "P5E_PEX0_STN7_RX_DP<114>")
	)
	(segment
		(start 33.176972 -408.28849)
		(end 33.176972 -395.550898)
		(width 0.1651)
		(layer "In5.Cu")
		(net "P5E_PEX0_STN7_RX_DP<114>")
	)
	(segment
		(start 22.935946 -388.00913)
		(end 21.936456 -385.597654)
		(width 0.1651)
		(layer "In5.Cu")
		(net "P5E_PEX0_STN7_RX_DP<114>")
	)
	(segment
		(start 32.43707 -408.699208)
		(end 32.766254 -408.699208)
		(width 0.1651)
		(layer "In5.Cu")
		(net "P5E_PEX0_STN7_RX_DP<114>")
	)
	(segment
		(start 21.936456 -385.597654)
		(end 18.835116 -370.003578)
		(width 0.1651)
		(layer "In5.Cu")
		(net "P5E_PEX0_STN7_RX_DP<114>")
	)
	(segment
		(start 32.31007 -408.572208)
		(end 32.43707 -408.699208)
		(width 0.1651)
		(layer "In5.Cu")
		(net "P5E_PEX0_STN7_RX_DP<114>")
	)
	(segment
		(start 25.621234 -306.44973)
		(end 27.369008 -304.701956)
		(width 0.1651)
		(layer "In5.Cu")
		(net "P5E_PEX0_STN7_RX_DP<114>")
	)
	(segment
		(start 39.434516 -303.499774)
		(end 39.699946 -303.499774)
		(width 0.1143)
		(layer "In5.Cu")
		(net "P5E_PEX0_STN7_RX_DP<114>")
	)
	(segment
		(start 27.369008 -304.701956)
		(end 30.489144 -303.407826)
		(width 0.1651)
		(layer "In5.Cu")
		(net "P5E_PEX0_STN7_RX_DP<114>")
	)
	(segment
		(start 33.119568 -302.883824)
		(end 35.56 -302.883824)
		(width 0.1651)
		(layer "In5.Cu")
		(net "P5E_PEX0_STN7_RX_DP<114>")
	)
	(segment
		(start 32.872172 -394.81506)
		(end 32.448754 -394.391642)
		(width 0.1651)
		(layer "In5.Cu")
		(net "P5E_PEX0_STN7_RX_DP<114>")
	)
	(segment
		(start 39.320216 -303.385474)
		(end 39.434516 -303.499774)
		(width 0.1143)
		(layer "In5.Cu")
		(net "P5E_PEX0_STN7_RX_DP<114>")
	)
	(segment
		(start 16.12646 -351.745042)
		(end 16.12646 -341.962486)
		(width 0.1651)
		(layer "In5.Cu")
		(net "P5E_PEX0_STN7_RX_DP<114>")
	)
	(segment
		(start 24.63419 -389.707374)
		(end 22.935946 -388.00913)
		(width 0.1651)
		(layer "In5.Cu")
		(net "P5E_PEX0_STN7_RX_DP<114>")
	)
	(segment
		(start 35.588448 -302.883824)
		(end 35.634168 -302.929544)
		(width 0.1143)
		(layer "In5.Cu")
		(net "P5E_PEX0_STN7_RX_DP<114>")
	)
	(segment
		(start 18.835116 -370.003578)
		(end 16.12646 -351.745042)
		(width 0.1651)
		(layer "In5.Cu")
		(net "P5E_PEX0_STN7_RX_DP<114>")
	)
	(segment
		(start 39.09441 -302.929544)
		(end 39.320216 -303.15535)
		(width 0.1143)
		(layer "In5.Cu")
		(net "P5E_PEX0_STN7_RX_DP<114>")
	)
	(segment
		(start 16.12646 -341.962486)
		(end 17.472914 -331.043026)
		(width 0.1651)
		(layer "In5.Cu")
		(net "P5E_PEX0_STN7_RX_DP<114>")
	)
	(segment
		(start 35.56 -302.883824)
		(end 35.588448 -302.883824)
		(width 0.1143)
		(layer "In5.Cu")
		(net "P5E_PEX0_STN7_RX_DP<114>")
	)
	(segment
		(start 74.102722 -355.026722)
		(end 73.808082 -354.732082)
		(width 0.13462)
		(layer "F.Cu")
		(net "P5E_PEX0_STN6_TX_DP<105>")
	)
	(segment
		(start 74.102722 -355.658166)
		(end 74.102722 -355.026722)
		(width 0.13462)
		(layer "F.Cu")
		(net "P5E_PEX0_STN6_TX_DP<105>")
	)
	(segment
		(start 73.782682 -355.978206)
		(end 74.102722 -355.658166)
		(width 0.13462)
		(layer "F.Cu")
		(net "P5E_PEX0_STN6_TX_DP<105>")
	)
	(segment
		(start 74.098912 -354.441252)
		(end 74.098912 -353.635564)
		(width 0.1651)
		(layer "In13.Cu")
		(net "P5E_PEX0_STN6_TX_DP<105>")
	)
	(segment
		(start 52.323492 -328.73442)
		(end 49.887124 -326.298052)
		(width 0.1651)
		(layer "In13.Cu")
		(net "P5E_PEX0_STN6_TX_DP<105>")
	)
	(segment
		(start 48.62957 -320.062352)
		(end 48.62957 -311.718198)
		(width 0.1143)
		(layer "In13.Cu")
		(net "P5E_PEX0_STN6_TX_DP<105>")
	)
	(segment
		(start 49.1109 -311.479692)
		(end 49.1998 -311.390792)
		(width 0.1143)
		(layer "In13.Cu")
		(net "P5E_PEX0_STN6_TX_DP<105>")
	)
	(segment
		(start 75.653392 -352.081084)
		(end 75.653392 -341.564214)
		(width 0.1651)
		(layer "In13.Cu")
		(net "P5E_PEX0_STN6_TX_DP<105>")
	)
	(segment
		(start 48.62957 -311.718198)
		(end 48.868076 -311.479692)
		(width 0.1143)
		(layer "In13.Cu")
		(net "P5E_PEX0_STN6_TX_DP<105>")
	)
	(segment
		(start 48.58385 -323.1515)
		(end 48.58385 -320.13017)
		(width 0.1651)
		(layer "In13.Cu")
		(net "P5E_PEX0_STN6_TX_DP<105>")
	)
	(segment
		(start 54.096158 -329.468734)
		(end 52.323492 -328.73442)
		(width 0.1651)
		(layer "In13.Cu")
		(net "P5E_PEX0_STN6_TX_DP<105>")
	)
	(segment
		(start 74.098912 -353.635564)
		(end 75.653392 -352.081084)
		(width 0.1651)
		(layer "In13.Cu")
		(net "P5E_PEX0_STN6_TX_DP<105>")
	)
	(segment
		(start 49.887124 -326.298052)
		(end 48.58385 -323.1515)
		(width 0.1651)
		(layer "In13.Cu")
		(net "P5E_PEX0_STN6_TX_DP<105>")
	)
	(segment
		(start 75.147932 -340.721442)
		(end 54.096158 -329.468734)
		(width 0.1651)
		(layer "In13.Cu")
		(net "P5E_PEX0_STN6_TX_DP<105>")
	)
	(segment
		(start 48.868076 -311.479692)
		(end 49.1109 -311.479692)
		(width 0.1143)
		(layer "In13.Cu")
		(net "P5E_PEX0_STN6_TX_DP<105>")
	)
	(segment
		(start 49.1998 -311.390792)
		(end 49.1998 -311.099962)
		(width 0.1143)
		(layer "In13.Cu")
		(net "P5E_PEX0_STN6_TX_DP<105>")
	)
	(segment
		(start 48.58385 -320.13017)
		(end 48.58385 -320.108072)
		(width 0.1143)
		(layer "In13.Cu")
		(net "P5E_PEX0_STN6_TX_DP<105>")
	)
	(segment
		(start 75.653392 -341.564214)
		(end 75.147932 -340.721442)
		(width 0.1651)
		(layer "In13.Cu")
		(net "P5E_PEX0_STN6_TX_DP<105>")
	)
	(segment
		(start 48.58385 -320.108072)
		(end 48.62957 -320.062352)
		(width 0.1143)
		(layer "In13.Cu")
		(net "P5E_PEX0_STN6_TX_DP<105>")
	)
	(segment
		(start 73.808082 -354.732082)
		(end 74.098912 -354.441252)
		(width 0.1651)
		(layer "In13.Cu")
		(net "P5E_PEX0_STN6_TX_DP<105>")
	)
	(segment
		(start 66.299842 -316.534292)
		(end 66.299842 -316.799722)
		(width 0.1143)
		(layer "In5.Cu")
		(net "P5E_PEX0_STN5_RX_DN<88>")
	)
	(segment
		(start 65.920112 -319.99428)
		(end 65.920112 -316.534292)
		(width 0.1143)
		(layer "In5.Cu")
		(net "P5E_PEX0_STN5_RX_DN<88>")
	)
	(segment
		(start 73.090786 -367.3856)
		(end 72.826372 -362.000292)
		(width 0.1651)
		(layer "In5.Cu")
		(net "P5E_PEX0_STN5_RX_DN<88>")
	)
	(segment
		(start 72.03694 -371.281198)
		(end 72.653906 -371.281198)
		(width 0.1651)
		(layer "In5.Cu")
		(net "P5E_PEX0_STN5_RX_DN<88>")
	)
	(segment
		(start 66.185542 -316.419992)
		(end 66.299842 -316.534292)
		(width 0.1143)
		(layer "In5.Cu")
		(net "P5E_PEX0_STN5_RX_DN<88>")
	)
	(segment
		(start 71.412608 -337.233514)
		(end 66.84645 -326.210168)
		(width 0.1651)
		(layer "In5.Cu")
		(net "P5E_PEX0_STN5_RX_DN<88>")
	)
	(segment
		(start 71.90994 -371.408198)
		(end 72.03694 -371.281198)
		(width 0.1651)
		(layer "In5.Cu")
		(net "P5E_PEX0_STN5_RX_DN<88>")
	)
	(segment
		(start 72.826372 -341.894668)
		(end 71.412608 -337.233514)
		(width 0.1651)
		(layer "In5.Cu")
		(net "P5E_PEX0_STN5_RX_DN<88>")
	)
	(segment
		(start 71.90994 -371.790214)
		(end 71.90994 -371.408198)
		(width 0.1651)
		(layer "In5.Cu")
		(net "P5E_PEX0_STN5_RX_DN<88>")
	)
	(segment
		(start 73.090786 -370.844318)
		(end 73.090786 -367.3856)
		(width 0.1651)
		(layer "In5.Cu")
		(net "P5E_PEX0_STN5_RX_DN<88>")
	)
	(segment
		(start 72.826372 -362.000292)
		(end 72.826372 -341.894668)
		(width 0.1651)
		(layer "In5.Cu")
		(net "P5E_PEX0_STN5_RX_DN<88>")
	)
	(segment
		(start 65.920112 -316.534292)
		(end 66.034412 -316.419992)
		(width 0.1143)
		(layer "In5.Cu")
		(net "P5E_PEX0_STN5_RX_DN<88>")
	)
	(segment
		(start 66.84645 -326.210168)
		(end 65.965832 -321.784218)
		(width 0.1651)
		(layer "In5.Cu")
		(net "P5E_PEX0_STN5_RX_DN<88>")
	)
	(segment
		(start 72.653906 -371.281198)
		(end 73.090786 -370.844318)
		(width 0.1651)
		(layer "In5.Cu")
		(net "P5E_PEX0_STN5_RX_DN<88>")
	)
	(segment
		(start 65.965832 -320.068448)
		(end 65.965832 -320.04)
		(width 0.1143)
		(layer "In5.Cu")
		(net "P5E_PEX0_STN5_RX_DN<88>")
	)
	(segment
		(start 66.034412 -316.419992)
		(end 66.185542 -316.419992)
		(width 0.1143)
		(layer "In5.Cu")
		(net "P5E_PEX0_STN5_RX_DN<88>")
	)
	(segment
		(start 65.965832 -320.04)
		(end 65.920112 -319.99428)
		(width 0.1143)
		(layer "In5.Cu")
		(net "P5E_PEX0_STN5_RX_DN<88>")
	)
	(segment
		(start 65.965832 -321.784218)
		(end 65.965832 -320.068448)
		(width 0.1651)
		(layer "In5.Cu")
		(net "P5E_PEX0_STN5_RX_DN<88>")
	)
	(segment
		(start 70.699122 -345.465146)
		(end 70.993762 -345.170506)
		(width 0.13462)
		(layer "F.Cu")
		(net "P5E_PEX0_STN5_TX_C_DP<84>")
	)
	(segment
		(start 70.993762 -344.539062)
		(end 70.673722 -344.219022)
		(width 0.13462)
		(layer "F.Cu")
		(net "P5E_PEX0_STN5_TX_C_DP<84>")
	)
	(segment
		(start 70.993762 -345.170506)
		(end 70.993762 -344.539062)
		(width 0.13462)
		(layer "F.Cu")
		(net "P5E_PEX0_STN5_TX_C_DP<84>")
	)
	(segment
		(start 77.622908 -391.71372)
		(end 77.622654 -391.713974)
		(width 0.1651)
		(layer "In7.Cu")
		(net "P5E_PEX0_STN5_TX_C_DP<84>")
	)
	(segment
		(start 79.208376 -392.467084)
		(end 78.750414 -392.277092)
		(width 0.1651)
		(layer "In7.Cu")
		(net "P5E_PEX0_STN5_TX_C_DP<84>")
	)
	(segment
		(start 77.670914 -391.830052)
		(end 77.622908 -391.71372)
		(width 0.1651)
		(layer "In7.Cu")
		(net "P5E_PEX0_STN5_TX_C_DP<84>")
	)
	(segment
		(start 81.602326 -404.370032)
		(end 81.602326 -394.428726)
		(width 0.1651)
		(layer "In7.Cu")
		(net "P5E_PEX0_STN5_TX_C_DP<84>")
	)
	(segment
		(start 68.529454 -386.93598)
		(end 67.732402 -385.011676)
		(width 0.1651)
		(layer "In7.Cu")
		(net "P5E_PEX0_STN5_TX_C_DP<84>")
	)
	(segment
		(start 67.732402 -385.011676)
		(end 67.732402 -378.99467)
		(width 0.1651)
		(layer "In7.Cu")
		(net "P5E_PEX0_STN5_TX_C_DP<84>")
	)
	(segment
		(start 69.435472 -358.158034)
		(end 69.435472 -347.912182)
		(width 0.1651)
		(layer "In7.Cu")
		(net "P5E_PEX0_STN5_TX_C_DP<84>")
	)
	(segment
		(start 78.702408 -392.161268)
		(end 78.244954 -391.971784)
		(width 0.1651)
		(layer "In7.Cu")
		(net "P5E_PEX0_STN5_TX_C_DP<84>")
	)
	(segment
		(start 70.256146 -388.662672)
		(end 68.529454 -386.93598)
		(width 0.1651)
		(layer "In7.Cu")
		(net "P5E_PEX0_STN5_TX_C_DP<84>")
	)
	(segment
		(start 80.710024 -404.672038)
		(end 80.837024 -404.799038)
		(width 0.1651)
		(layer "In7.Cu")
		(net "P5E_PEX0_STN5_TX_C_DP<84>")
	)
	(segment
		(start 70.989952 -345.755976)
		(end 70.699122 -345.465146)
		(width 0.1651)
		(layer "In7.Cu")
		(net "P5E_PEX0_STN5_TX_C_DP<84>")
	)
	(segment
		(start 78.244954 -391.971784)
		(end 78.244954 -391.97153)
		(width 0.1651)
		(layer "In7.Cu")
		(net "P5E_PEX0_STN5_TX_C_DP<84>")
	)
	(segment
		(start 77.622654 -391.713974)
		(end 70.256146 -388.662672)
		(width 0.1651)
		(layer "In7.Cu")
		(net "P5E_PEX0_STN5_TX_C_DP<84>")
	)
	(segment
		(start 80.710024 -404.290022)
		(end 80.710024 -404.672038)
		(width 0.1651)
		(layer "In7.Cu")
		(net "P5E_PEX0_STN5_TX_C_DP<84>")
	)
	(segment
		(start 78.128876 -392.01979)
		(end 77.670914 -391.830052)
		(width 0.1651)
		(layer "In7.Cu")
		(net "P5E_PEX0_STN5_TX_C_DP<84>")
	)
	(segment
		(start 80.837024 -404.799038)
		(end 81.17332 -404.799038)
		(width 0.1651)
		(layer "In7.Cu")
		(net "P5E_PEX0_STN5_TX_C_DP<84>")
	)
	(segment
		(start 80.768698 -393.595098)
		(end 80.642968 -393.595098)
		(width 0.1651)
		(layer "In7.Cu")
		(net "P5E_PEX0_STN5_TX_C_DP<84>")
	)
	(segment
		(start 78.244954 -391.97153)
		(end 78.128876 -392.01979)
		(width 0.1651)
		(layer "In7.Cu")
		(net "P5E_PEX0_STN5_TX_C_DP<84>")
	)
	(segment
		(start 78.750414 -392.277092)
		(end 78.702408 -392.161014)
		(width 0.1651)
		(layer "In7.Cu")
		(net "P5E_PEX0_STN5_TX_C_DP<84>")
	)
	(segment
		(start 81.602326 -394.428726)
		(end 80.768698 -393.595098)
		(width 0.1651)
		(layer "In7.Cu")
		(net "P5E_PEX0_STN5_TX_C_DP<84>")
	)
	(segment
		(start 67.572128 -366.68075)
		(end 69.435472 -358.158034)
		(width 0.1651)
		(layer "In7.Cu")
		(net "P5E_PEX0_STN5_TX_C_DP<84>")
	)
	(segment
		(start 78.702408 -392.161014)
		(end 78.702408 -392.161268)
		(width 0.1651)
		(layer "In7.Cu")
		(net "P5E_PEX0_STN5_TX_C_DP<84>")
	)
	(segment
		(start 69.435472 -347.912182)
		(end 70.989952 -346.357702)
		(width 0.1651)
		(layer "In7.Cu")
		(net "P5E_PEX0_STN5_TX_C_DP<84>")
	)
	(segment
		(start 67.732402 -378.99467)
		(end 67.572128 -366.68075)
		(width 0.1651)
		(layer "In7.Cu")
		(net "P5E_PEX0_STN5_TX_C_DP<84>")
	)
	(segment
		(start 81.17332 -404.799038)
		(end 81.602326 -404.370032)
		(width 0.1651)
		(layer "In7.Cu")
		(net "P5E_PEX0_STN5_TX_C_DP<84>")
	)
	(segment
		(start 70.989952 -346.357702)
		(end 70.989952 -345.755976)
		(width 0.1651)
		(layer "In7.Cu")
		(net "P5E_PEX0_STN5_TX_C_DP<84>")
	)
	(segment
		(start 80.642968 -393.595098)
		(end 80.292702 -393.244832)
		(width 0.1651)
		(layer "In7.Cu")
		(net "P5E_PEX0_STN5_TX_C_DP<84>")
	)
	(segment
		(start 80.292702 -393.244832)
		(end 80.292702 -393.119102)
		(width 0.1651)
		(layer "In7.Cu")
		(net "P5E_PEX0_STN5_TX_C_DP<84>")
	)
	(segment
		(start 79.324454 -392.418824)
		(end 79.208376 -392.467084)
		(width 0.1651)
		(layer "In7.Cu")
		(net "P5E_PEX0_STN5_TX_C_DP<84>")
	)
	(segment
		(start 79.781908 -392.608308)
		(end 79.324454 -392.418824)
		(width 0.1651)
		(layer "In7.Cu")
		(net "P5E_PEX0_STN5_TX_C_DP<84>")
	)
	(segment
		(start 80.292702 -393.119102)
		(end 79.781908 -392.608308)
		(width 0.1651)
		(layer "In7.Cu")
		(net "P5E_PEX0_STN5_TX_C_DP<84>")
	)
	(segment
		(start 369.31346 -34.23412)
		(end 369.001294 -34.546286)
		(width 0.13462)
		(layer "F.Cu")
		(net "P5E_PEX3_STN2_TX_DP<47>")
	)
	(segment
		(start 369.960652 -34.23412)
		(end 369.31346 -34.23412)
		(width 0.13462)
		(layer "F.Cu")
		(net "P5E_PEX3_STN2_TX_DP<47>")
	)
	(segment
		(start 370.247418 -34.520886)
		(end 369.960652 -34.23412)
		(width 0.13462)
		(layer "F.Cu")
		(net "P5E_PEX3_STN2_TX_DP<47>")
	)
	(segment
		(start 373.740934 -36.940236)
		(end 374.05056 -37.327332)
		(width 0.1651)
		(layer "In11.Cu")
		(net "P5E_PEX3_STN2_TX_DP<47>")
	)
	(segment
		(start 392.749786 -278.534368)
		(end 392.749786 -278.799798)
		(width 0.1143)
		(layer "In11.Cu")
		(net "P5E_PEX3_STN2_TX_DP<47>")
	)
	(segment
		(start 370.538248 -34.230056)
		(end 371.009164 -34.230056)
		(width 0.1651)
		(layer "In11.Cu")
		(net "P5E_PEX3_STN2_TX_DP<47>")
	)
	(segment
		(start 392.133836 -271.399)
		(end 392.133836 -271.427448)
		(width 0.1143)
		(layer "In11.Cu")
		(net "P5E_PEX3_STN2_TX_DP<47>")
	)
	(segment
		(start 371.009164 -34.230056)
		(end 371.345968 -34.391854)
		(width 0.1651)
		(layer "In11.Cu")
		(net "P5E_PEX3_STN2_TX_DP<47>")
	)
	(segment
		(start 374.871742 -38.231572)
		(end 374.871488 -38.231572)
		(width 0.1651)
		(layer "In11.Cu")
		(net "P5E_PEX3_STN2_TX_DP<47>")
	)
	(segment
		(start 374.157748 -37.339016)
		(end 374.157494 -37.339016)
		(width 0.1651)
		(layer "In11.Cu")
		(net "P5E_PEX3_STN2_TX_DP<47>")
	)
	(segment
		(start 382.286256 -47.499778)
		(end 383.28727 -49.31283)
		(width 0.1651)
		(layer "In11.Cu")
		(net "P5E_PEX3_STN2_TX_DP<47>")
	)
	(segment
		(start 374.871488 -38.231572)
		(end 382.286256 -47.499778)
		(width 0.1651)
		(layer "In11.Cu")
		(net "P5E_PEX3_STN2_TX_DP<47>")
	)
	(segment
		(start 374.05056 -37.327332)
		(end 374.157748 -37.339016)
		(width 0.1651)
		(layer "In11.Cu")
		(net "P5E_PEX3_STN2_TX_DP<47>")
	)
	(segment
		(start 384.436112 -62.637416)
		(end 383.577846 -78.883256)
		(width 0.1651)
		(layer "In11.Cu")
		(net "P5E_PEX3_STN2_TX_DP<47>")
	)
	(segment
		(start 373.752872 -36.833048)
		(end 373.740934 -36.940236)
		(width 0.1651)
		(layer "In11.Cu")
		(net "P5E_PEX3_STN2_TX_DP<47>")
	)
	(segment
		(start 392.635486 -278.420068)
		(end 392.749786 -278.534368)
		(width 0.1143)
		(layer "In11.Cu")
		(net "P5E_PEX3_STN2_TX_DP<47>")
	)
	(segment
		(start 373.752618 -36.833048)
		(end 373.752872 -36.833048)
		(width 0.1651)
		(layer "In11.Cu")
		(net "P5E_PEX3_STN2_TX_DP<47>")
	)
	(segment
		(start 374.454928 -37.832792)
		(end 374.764554 -38.219888)
		(width 0.1651)
		(layer "In11.Cu")
		(net "P5E_PEX3_STN2_TX_DP<47>")
	)
	(segment
		(start 392.133836 -270.752062)
		(end 392.133836 -271.399)
		(width 0.1651)
		(layer "In11.Cu")
		(net "P5E_PEX3_STN2_TX_DP<47>")
	)
	(segment
		(start 372.59387 -35.384486)
		(end 373.752618 -36.833048)
		(width 0.1651)
		(layer "In11.Cu")
		(net "P5E_PEX3_STN2_TX_DP<47>")
	)
	(segment
		(start 383.760726 -50.678842)
		(end 384.436112 -62.637416)
		(width 0.1651)
		(layer "In11.Cu")
		(net "P5E_PEX3_STN2_TX_DP<47>")
	)
	(segment
		(start 370.247418 -34.520886)
		(end 370.538248 -34.230056)
		(width 0.1651)
		(layer "In11.Cu")
		(net "P5E_PEX3_STN2_TX_DP<47>")
	)
	(segment
		(start 392.179556 -278.20493)
		(end 392.394694 -278.420068)
		(width 0.1143)
		(layer "In11.Cu")
		(net "P5E_PEX3_STN2_TX_DP<47>")
	)
	(segment
		(start 391.103104 -264.543286)
		(end 392.133836 -270.752062)
		(width 0.1651)
		(layer "In11.Cu")
		(net "P5E_PEX3_STN2_TX_DP<47>")
	)
	(segment
		(start 374.466866 -37.725604)
		(end 374.454928 -37.832792)
		(width 0.1651)
		(layer "In11.Cu")
		(net "P5E_PEX3_STN2_TX_DP<47>")
	)
	(segment
		(start 392.179556 -271.473168)
		(end 392.179556 -278.20493)
		(width 0.1143)
		(layer "In11.Cu")
		(net "P5E_PEX3_STN2_TX_DP<47>")
	)
	(segment
		(start 374.157494 -37.339016)
		(end 374.466866 -37.725604)
		(width 0.1651)
		(layer "In11.Cu")
		(net "P5E_PEX3_STN2_TX_DP<47>")
	)
	(segment
		(start 379.388116 -117.070886)
		(end 379.902212 -138.242294)
		(width 0.1651)
		(layer "In11.Cu")
		(net "P5E_PEX3_STN2_TX_DP<47>")
	)
	(segment
		(start 383.28727 -49.31283)
		(end 383.760726 -50.678842)
		(width 0.1651)
		(layer "In11.Cu")
		(net "P5E_PEX3_STN2_TX_DP<47>")
	)
	(segment
		(start 371.345968 -34.391854)
		(end 372.59387 -35.384486)
		(width 0.1651)
		(layer "In11.Cu")
		(net "P5E_PEX3_STN2_TX_DP<47>")
	)
	(segment
		(start 392.133836 -271.427448)
		(end 392.179556 -271.473168)
		(width 0.1143)
		(layer "In11.Cu")
		(net "P5E_PEX3_STN2_TX_DP<47>")
	)
	(segment
		(start 380.062232 -104.563164)
		(end 379.388116 -117.070886)
		(width 0.1651)
		(layer "In11.Cu")
		(net "P5E_PEX3_STN2_TX_DP<47>")
	)
	(segment
		(start 383.577846 -78.883256)
		(end 380.062232 -104.563164)
		(width 0.1651)
		(layer "In11.Cu")
		(net "P5E_PEX3_STN2_TX_DP<47>")
	)
	(segment
		(start 374.764554 -38.219888)
		(end 374.871742 -38.231572)
		(width 0.1651)
		(layer "In11.Cu")
		(net "P5E_PEX3_STN2_TX_DP<47>")
	)
	(segment
		(start 392.394694 -278.420068)
		(end 392.635486 -278.420068)
		(width 0.1143)
		(layer "In11.Cu")
		(net "P5E_PEX3_STN2_TX_DP<47>")
	)
	(segment
		(start 379.902212 -138.242294)
		(end 391.103104 -264.543286)
		(width 0.1651)
		(layer "In11.Cu")
		(net "P5E_PEX3_STN2_TX_DP<47>")
	)
	(segment
		(start 85.31098 -393.193524)
		(end 84.96046 -393.54379)
		(width 0.1651)
		(layer "In9.Cu")
		(net "P5E_PEX0_STN5_RX_DP<85>")
	)
	(segment
		(start 97.536 -369.788948)
		(end 97.536 -371.048534)
		(width 0.1651)
		(layer "In9.Cu")
		(net "P5E_PEX0_STN5_RX_DP<85>")
	)
	(segment
		(start 62.834012 -320.2686)
		(end 63.240412 -321.250564)
		(width 0.1651)
		(layer "In9.Cu")
		(net "P5E_PEX0_STN5_RX_DP<85>")
	)
	(segment
		(start 84.610448 -394.001752)
		(end 84.502752 -394.001752)
		(width 0.1651)
		(layer "In9.Cu")
		(net "P5E_PEX0_STN5_RX_DP<85>")
	)
	(segment
		(start 93.485208 -391.084054)
		(end 86.049104 -392.563096)
		(width 0.1651)
		(layer "In9.Cu")
		(net "P5E_PEX0_STN5_RX_DP<85>")
	)
	(segment
		(start 83.80222 -394.80998)
		(end 83.80222 -397.67383)
		(width 0.1651)
		(layer "In9.Cu")
		(net "P5E_PEX0_STN5_RX_DP<85>")
	)
	(segment
		(start 84.152232 -394.352018)
		(end 84.152232 -394.459968)
		(width 0.1651)
		(layer "In9.Cu")
		(net "P5E_PEX0_STN5_RX_DP<85>")
	)
	(segment
		(start 63.240412 -321.250564)
		(end 64.65062 -322.660772)
		(width 0.1651)
		(layer "In9.Cu")
		(net "P5E_PEX0_STN5_RX_DP<85>")
	)
	(segment
		(start 62.879732 -319.91808)
		(end 62.834012 -319.9638)
		(width 0.1143)
		(layer "In9.Cu")
		(net "P5E_PEX0_STN5_RX_DP<85>")
	)
	(segment
		(start 63.449962 -317.749936)
		(end 63.449962 -318.040766)
		(width 0.1143)
		(layer "In9.Cu")
		(net "P5E_PEX0_STN5_RX_DP<85>")
	)
	(segment
		(start 84.96046 -393.65174)
		(end 84.610448 -394.001752)
		(width 0.1651)
		(layer "In9.Cu")
		(net "P5E_PEX0_STN5_RX_DP<85>")
	)
	(segment
		(start 93.856048 -341.20074)
		(end 94.417134 -342.136984)
		(width 0.1651)
		(layer "In9.Cu")
		(net "P5E_PEX0_STN5_RX_DP<85>")
	)
	(segment
		(start 63.449962 -318.040766)
		(end 63.361062 -318.129666)
		(width 0.1143)
		(layer "In9.Cu")
		(net "P5E_PEX0_STN5_RX_DP<85>")
	)
	(segment
		(start 63.156338 -318.129666)
		(end 62.879732 -318.406272)
		(width 0.1143)
		(layer "In9.Cu")
		(net "P5E_PEX0_STN5_RX_DP<85>")
	)
	(segment
		(start 83.377024 -398.099026)
		(end 83.036918 -398.099026)
		(width 0.1651)
		(layer "In9.Cu")
		(net "P5E_PEX0_STN5_RX_DP<85>")
	)
	(segment
		(start 68.489576 -324.251066)
		(end 93.856048 -341.20074)
		(width 0.1651)
		(layer "In9.Cu")
		(net "P5E_PEX0_STN5_RX_DP<85>")
	)
	(segment
		(start 64.65062 -322.660772)
		(end 68.489576 -324.251066)
		(width 0.1651)
		(layer "In9.Cu")
		(net "P5E_PEX0_STN5_RX_DP<85>")
	)
	(segment
		(start 84.152232 -394.459968)
		(end 83.80222 -394.80998)
		(width 0.1651)
		(layer "In9.Cu")
		(net "P5E_PEX0_STN5_RX_DP<85>")
	)
	(segment
		(start 83.80222 -397.67383)
		(end 83.377024 -398.099026)
		(width 0.1651)
		(layer "In9.Cu")
		(net "P5E_PEX0_STN5_RX_DP<85>")
	)
	(segment
		(start 62.834012 -319.9638)
		(end 62.834012 -319.992248)
		(width 0.1143)
		(layer "In9.Cu")
		(net "P5E_PEX0_STN5_RX_DP<85>")
	)
	(segment
		(start 97.21342 -387.020816)
		(end 96.464374 -388.829296)
		(width 0.1651)
		(layer "In9.Cu")
		(net "P5E_PEX0_STN5_RX_DP<85>")
	)
	(segment
		(start 84.502752 -394.001752)
		(end 84.152232 -394.352018)
		(width 0.1651)
		(layer "In9.Cu")
		(net "P5E_PEX0_STN5_RX_DP<85>")
	)
	(segment
		(start 86.049104 -392.563096)
		(end 85.418676 -393.193524)
		(width 0.1651)
		(layer "In9.Cu")
		(net "P5E_PEX0_STN5_RX_DP<85>")
	)
	(segment
		(start 94.721934 -390.571736)
		(end 93.485208 -391.084054)
		(width 0.1651)
		(layer "In9.Cu")
		(net "P5E_PEX0_STN5_RX_DP<85>")
	)
	(segment
		(start 96.464374 -388.829296)
		(end 94.721934 -390.571736)
		(width 0.1651)
		(layer "In9.Cu")
		(net "P5E_PEX0_STN5_RX_DP<85>")
	)
	(segment
		(start 62.879732 -318.406272)
		(end 62.879732 -319.91808)
		(width 0.1143)
		(layer "In9.Cu")
		(net "P5E_PEX0_STN5_RX_DP<85>")
	)
	(segment
		(start 82.909918 -397.972026)
		(end 82.909918 -397.59001)
		(width 0.1651)
		(layer "In9.Cu")
		(net "P5E_PEX0_STN5_RX_DP<85>")
	)
	(segment
		(start 84.96046 -393.54379)
		(end 84.96046 -393.65174)
		(width 0.1651)
		(layer "In9.Cu")
		(net "P5E_PEX0_STN5_RX_DP<85>")
	)
	(segment
		(start 85.418676 -393.193524)
		(end 85.31098 -393.193524)
		(width 0.1651)
		(layer "In9.Cu")
		(net "P5E_PEX0_STN5_RX_DP<85>")
	)
	(segment
		(start 63.361062 -318.129666)
		(end 63.156338 -318.129666)
		(width 0.1143)
		(layer "In9.Cu")
		(net "P5E_PEX0_STN5_RX_DP<85>")
	)
	(segment
		(start 96.922082 -367.569242)
		(end 97.536 -369.788948)
		(width 0.1651)
		(layer "In9.Cu")
		(net "P5E_PEX0_STN5_RX_DP<85>")
	)
	(segment
		(start 97.21342 -385.470654)
		(end 97.21342 -387.020816)
		(width 0.1651)
		(layer "In9.Cu")
		(net "P5E_PEX0_STN5_RX_DP<85>")
	)
	(segment
		(start 62.834012 -319.992248)
		(end 62.834012 -320.2686)
		(width 0.1651)
		(layer "In9.Cu")
		(net "P5E_PEX0_STN5_RX_DP<85>")
	)
	(segment
		(start 94.417134 -342.136984)
		(end 96.922082 -367.569242)
		(width 0.1651)
		(layer "In9.Cu")
		(net "P5E_PEX0_STN5_RX_DP<85>")
	)
	(segment
		(start 97.536 -371.048534)
		(end 97.21342 -385.470654)
		(width 0.1651)
		(layer "In9.Cu")
		(net "P5E_PEX0_STN5_RX_DP<85>")
	)
	(segment
		(start 83.036918 -398.099026)
		(end 82.909918 -397.972026)
		(width 0.1651)
		(layer "In9.Cu")
		(net "P5E_PEX0_STN5_RX_DP<85>")
	)
	(segment
		(start 337.349084 -350.365314)
		(end 337.669124 -350.685354)
		(width 0.13462)
		(layer "F.Cu")
		(net "P5E_PEX2_STN5_TX_C_DP<92>")
	)
	(segment
		(start 337.669124 -350.685354)
		(end 337.669124 -351.316798)
		(width 0.13462)
		(layer "F.Cu")
		(net "P5E_PEX2_STN5_TX_C_DP<92>")
	)
	(segment
		(start 337.669124 -351.316798)
		(end 337.374484 -351.611438)
		(width 0.13462)
		(layer "F.Cu")
		(net "P5E_PEX2_STN5_TX_C_DP<92>")
	)
	(segment
		(start 336.110834 -353.910646)
		(end 337.665314 -352.356166)
		(width 0.1651)
		(layer "In7.Cu")
		(net "P5E_PEX2_STN5_TX_C_DP<92>")
	)
	(segment
		(start 339.601556 -365.65205)
		(end 339.481922 -365.613442)
		(width 0.1651)
		(layer "In7.Cu")
		(net "P5E_PEX2_STN5_TX_C_DP<92>")
	)
	(segment
		(start 340.41715 -378.79909)
		(end 340.847426 -378.79909)
		(width 0.1651)
		(layer "In7.Cu")
		(net "P5E_PEX2_STN5_TX_C_DP<92>")
	)
	(segment
		(start 340.29015 -378.67209)
		(end 340.41715 -378.79909)
		(width 0.1651)
		(layer "In7.Cu")
		(net "P5E_PEX2_STN5_TX_C_DP<92>")
	)
	(segment
		(start 337.665314 -352.356166)
		(end 337.665314 -351.902268)
		(width 0.1651)
		(layer "In7.Cu")
		(net "P5E_PEX2_STN5_TX_C_DP<92>")
	)
	(segment
		(start 339.294978 -365.052356)
		(end 339.06968 -364.611412)
		(width 0.1651)
		(layer "In7.Cu")
		(net "P5E_PEX2_STN5_TX_C_DP<92>")
	)
	(segment
		(start 340.013798 -366.653826)
		(end 339.788246 -366.212628)
		(width 0.1651)
		(layer "In7.Cu")
		(net "P5E_PEX2_STN5_TX_C_DP<92>")
	)
	(segment
		(start 339.25637 -365.17199)
		(end 339.294978 -365.052356)
		(width 0.1651)
		(layer "In7.Cu")
		(net "P5E_PEX2_STN5_TX_C_DP<92>")
	)
	(segment
		(start 339.826854 -366.092994)
		(end 339.601556 -365.65205)
		(width 0.1651)
		(layer "In7.Cu")
		(net "P5E_PEX2_STN5_TX_C_DP<92>")
	)
	(segment
		(start 338.24291 -362.993686)
		(end 336.110834 -358.821482)
		(width 0.1651)
		(layer "In7.Cu")
		(net "P5E_PEX2_STN5_TX_C_DP<92>")
	)
	(segment
		(start 336.110834 -358.821482)
		(end 336.110834 -353.910646)
		(width 0.1651)
		(layer "In7.Cu")
		(net "P5E_PEX2_STN5_TX_C_DP<92>")
	)
	(segment
		(start 338.209636 -363.096302)
		(end 338.24291 -362.993686)
		(width 0.1651)
		(layer "In7.Cu")
		(net "P5E_PEX2_STN5_TX_C_DP<92>")
	)
	(segment
		(start 341.134192 -378.512324)
		(end 341.134192 -368.650774)
		(width 0.1651)
		(layer "In7.Cu")
		(net "P5E_PEX2_STN5_TX_C_DP<92>")
	)
	(segment
		(start 338.537804 -363.570774)
		(end 338.435442 -363.5375)
		(width 0.1651)
		(layer "In7.Cu")
		(net "P5E_PEX2_STN5_TX_C_DP<92>")
	)
	(segment
		(start 339.788246 -366.212628)
		(end 339.826854 -366.092994)
		(width 0.1651)
		(layer "In7.Cu")
		(net "P5E_PEX2_STN5_TX_C_DP<92>")
	)
	(segment
		(start 339.481922 -365.613442)
		(end 339.25637 -365.17199)
		(width 0.1651)
		(layer "In7.Cu")
		(net "P5E_PEX2_STN5_TX_C_DP<92>")
	)
	(segment
		(start 338.724494 -364.131352)
		(end 338.763102 -364.011718)
		(width 0.1651)
		(layer "In7.Cu")
		(net "P5E_PEX2_STN5_TX_C_DP<92>")
	)
	(segment
		(start 338.950046 -364.572804)
		(end 338.724494 -364.131352)
		(width 0.1651)
		(layer "In7.Cu")
		(net "P5E_PEX2_STN5_TX_C_DP<92>")
	)
	(segment
		(start 341.134192 -368.650774)
		(end 340.133432 -366.692434)
		(width 0.1651)
		(layer "In7.Cu")
		(net "P5E_PEX2_STN5_TX_C_DP<92>")
	)
	(segment
		(start 337.665314 -351.902268)
		(end 337.374484 -351.611438)
		(width 0.1651)
		(layer "In7.Cu")
		(net "P5E_PEX2_STN5_TX_C_DP<92>")
	)
	(segment
		(start 339.06968 -364.611412)
		(end 338.950046 -364.572804)
		(width 0.1651)
		(layer "In7.Cu")
		(net "P5E_PEX2_STN5_TX_C_DP<92>")
	)
	(segment
		(start 340.847426 -378.79909)
		(end 341.134192 -378.512324)
		(width 0.1651)
		(layer "In7.Cu")
		(net "P5E_PEX2_STN5_TX_C_DP<92>")
	)
	(segment
		(start 340.133432 -366.692434)
		(end 340.013798 -366.653826)
		(width 0.1651)
		(layer "In7.Cu")
		(net "P5E_PEX2_STN5_TX_C_DP<92>")
	)
	(segment
		(start 340.29015 -378.290074)
		(end 340.29015 -378.67209)
		(width 0.1651)
		(layer "In7.Cu")
		(net "P5E_PEX2_STN5_TX_C_DP<92>")
	)
	(segment
		(start 338.435442 -363.5375)
		(end 338.209636 -363.096302)
		(width 0.1651)
		(layer "In7.Cu")
		(net "P5E_PEX2_STN5_TX_C_DP<92>")
	)
	(segment
		(start 338.763102 -364.011718)
		(end 338.537804 -363.570774)
		(width 0.1651)
		(layer "In7.Cu")
		(net "P5E_PEX2_STN5_TX_C_DP<92>")
	)
	(segment
		(start 80.915002 -355.978206)
		(end 80.594962 -355.658166)
		(width 0.13462)
		(layer "F.Cu")
		(net "P5E_PEX0_STN6_TX_DN<102>")
	)
	(segment
		(start 80.594962 -355.658166)
		(end 80.594962 -355.026722)
		(width 0.13462)
		(layer "F.Cu")
		(net "P5E_PEX0_STN6_TX_DN<102>")
	)
	(segment
		(start 80.594962 -355.026722)
		(end 80.889602 -354.732082)
		(width 0.13462)
		(layer "F.Cu")
		(net "P5E_PEX0_STN6_TX_DN<102>")
	)
	(segment
		(start 51.961034 -313.570112)
		(end 51.797458 -313.570112)
		(width 0.1143)
		(layer "In13.Cu")
		(net "P5E_PEX0_STN6_TX_DN<102>")
	)
	(segment
		(start 52.049934 -313.659012)
		(end 51.961034 -313.570112)
		(width 0.1143)
		(layer "In13.Cu")
		(net "P5E_PEX0_STN6_TX_DN<102>")
	)
	(segment
		(start 51.715924 -320.23431)
		(end 51.715924 -320.256408)
		(width 0.1143)
		(layer "In13.Cu")
		(net "P5E_PEX0_STN6_TX_DN<102>")
	)
	(segment
		(start 52.846478 -324.80631)
		(end 54.105302 -326.065134)
		(width 0.1651)
		(layer "In13.Cu")
		(net "P5E_PEX0_STN6_TX_DN<102>")
	)
	(segment
		(start 51.715924 -322.07708)
		(end 52.846478 -324.80631)
		(width 0.1651)
		(layer "In13.Cu")
		(net "P5E_PEX0_STN6_TX_DN<102>")
	)
	(segment
		(start 52.049934 -313.949842)
		(end 52.049934 -313.659012)
		(width 0.1143)
		(layer "In13.Cu")
		(net "P5E_PEX0_STN6_TX_DN<102>")
	)
	(segment
		(start 82.153252 -352.197924)
		(end 80.598772 -353.752404)
		(width 0.1651)
		(layer "In13.Cu")
		(net "P5E_PEX0_STN6_TX_DN<102>")
	)
	(segment
		(start 82.153252 -341.841582)
		(end 82.153252 -352.197924)
		(width 0.1651)
		(layer "In13.Cu")
		(net "P5E_PEX0_STN6_TX_DN<102>")
	)
	(segment
		(start 80.598772 -354.441252)
		(end 80.889602 -354.732082)
		(width 0.1651)
		(layer "In13.Cu")
		(net "P5E_PEX0_STN6_TX_DN<102>")
	)
	(segment
		(start 51.797458 -313.570112)
		(end 51.670204 -313.697366)
		(width 0.1143)
		(layer "In13.Cu")
		(net "P5E_PEX0_STN6_TX_DN<102>")
	)
	(segment
		(start 51.670204 -320.18859)
		(end 51.715924 -320.23431)
		(width 0.1143)
		(layer "In13.Cu")
		(net "P5E_PEX0_STN6_TX_DN<102>")
	)
	(segment
		(start 81.096866 -340.079076)
		(end 82.153252 -341.841582)
		(width 0.1651)
		(layer "In13.Cu")
		(net "P5E_PEX0_STN6_TX_DN<102>")
	)
	(segment
		(start 80.598772 -353.752404)
		(end 80.598772 -354.441252)
		(width 0.1651)
		(layer "In13.Cu")
		(net "P5E_PEX0_STN6_TX_DN<102>")
	)
	(segment
		(start 51.715924 -320.256408)
		(end 51.715924 -322.07708)
		(width 0.1651)
		(layer "In13.Cu")
		(net "P5E_PEX0_STN6_TX_DN<102>")
	)
	(segment
		(start 54.105302 -326.065134)
		(end 57.545224 -327.490074)
		(width 0.1651)
		(layer "In13.Cu")
		(net "P5E_PEX0_STN6_TX_DN<102>")
	)
	(segment
		(start 57.545224 -327.490074)
		(end 81.096866 -340.079076)
		(width 0.1651)
		(layer "In13.Cu")
		(net "P5E_PEX0_STN6_TX_DN<102>")
	)
	(segment
		(start 51.670204 -313.697366)
		(end 51.670204 -320.18859)
		(width 0.1143)
		(layer "In13.Cu")
		(net "P5E_PEX0_STN6_TX_DN<102>")
	)
	(segment
		(start 393.605258 -31.850584)
		(end 393.312142 -32.1437)
		(width 0.13462)
		(layer "F.Cu")
		(net "P5E_PEX3_STN2_TX_DN<42>")
	)
	(segment
		(start 393.312142 -32.1437)
		(end 392.67765 -32.1437)
		(width 0.13462)
		(layer "F.Cu")
		(net "P5E_PEX3_STN2_TX_DN<42>")
	)
	(segment
		(start 392.67765 -32.1437)
		(end 392.359134 -31.825184)
		(width 0.13462)
		(layer "F.Cu")
		(net "P5E_PEX3_STN2_TX_DN<42>")
	)
	(segment
		(start 397.16583 -270.426688)
		(end 397.16583 -271.399)
		(width 0.1651)
		(layer "In11.Cu")
		(net "P5E_PEX3_STN2_TX_DN<42>")
	)
	(segment
		(start 393.896088 -32.141414)
		(end 396.765526 -32.141414)
		(width 0.1651)
		(layer "In11.Cu")
		(net "P5E_PEX3_STN2_TX_DN<42>")
	)
	(segment
		(start 411.606746 -60.466732)
		(end 410.110686 -68.660264)
		(width 0.1651)
		(layer "In11.Cu")
		(net "P5E_PEX3_STN2_TX_DN<42>")
	)
	(segment
		(start 397.12011 -271.473168)
		(end 397.12011 -280.025856)
		(width 0.1143)
		(layer "In11.Cu")
		(net "P5E_PEX3_STN2_TX_DN<42>")
	)
	(segment
		(start 397.49984 -280.015188)
		(end 397.49984 -279.749504)
		(width 0.1143)
		(layer "In11.Cu")
		(net "P5E_PEX3_STN2_TX_DN<42>")
	)
	(segment
		(start 396.834868 -267.065252)
		(end 397.16583 -270.426688)
		(width 0.1651)
		(layer "In11.Cu")
		(net "P5E_PEX3_STN2_TX_DN<42>")
	)
	(segment
		(start 393.605258 -31.850584)
		(end 393.896088 -32.141414)
		(width 0.1651)
		(layer "In11.Cu")
		(net "P5E_PEX3_STN2_TX_DN<42>")
	)
	(segment
		(start 397.36141 -32.319468)
		(end 399.597372 -34.599372)
		(width 0.1651)
		(layer "In11.Cu")
		(net "P5E_PEX3_STN2_TX_DN<42>")
	)
	(segment
		(start 394.422122 -116.032026)
		(end 394.682726 -141.886686)
		(width 0.1651)
		(layer "In11.Cu")
		(net "P5E_PEX3_STN2_TX_DN<42>")
	)
	(segment
		(start 393.321794 -161.959544)
		(end 396.834868 -267.065252)
		(width 0.1651)
		(layer "In11.Cu")
		(net "P5E_PEX3_STN2_TX_DN<42>")
	)
	(segment
		(start 397.12011 -280.025856)
		(end 397.223742 -280.129488)
		(width 0.1143)
		(layer "In11.Cu")
		(net "P5E_PEX3_STN2_TX_DN<42>")
	)
	(segment
		(start 410.968952 -50.37074)
		(end 411.606746 -60.466732)
		(width 0.1651)
		(layer "In11.Cu")
		(net "P5E_PEX3_STN2_TX_DN<42>")
	)
	(segment
		(start 397.223742 -280.129488)
		(end 397.38554 -280.129488)
		(width 0.1143)
		(layer "In11.Cu")
		(net "P5E_PEX3_STN2_TX_DN<42>")
	)
	(segment
		(start 399.83283 -95.804736)
		(end 394.422122 -116.032026)
		(width 0.1651)
		(layer "In11.Cu")
		(net "P5E_PEX3_STN2_TX_DN<42>")
	)
	(segment
		(start 410.110686 -68.660264)
		(end 399.83283 -95.804736)
		(width 0.1651)
		(layer "In11.Cu")
		(net "P5E_PEX3_STN2_TX_DN<42>")
	)
	(segment
		(start 410.325316 -48.492156)
		(end 410.968952 -50.37074)
		(width 0.1651)
		(layer "In11.Cu")
		(net "P5E_PEX3_STN2_TX_DN<42>")
	)
	(segment
		(start 394.682726 -141.886686)
		(end 393.321794 -161.959544)
		(width 0.1651)
		(layer "In11.Cu")
		(net "P5E_PEX3_STN2_TX_DN<42>")
	)
	(segment
		(start 399.597372 -34.599372)
		(end 410.325316 -48.492156)
		(width 0.1651)
		(layer "In11.Cu")
		(net "P5E_PEX3_STN2_TX_DN<42>")
	)
	(segment
		(start 397.16583 -271.427448)
		(end 397.12011 -271.473168)
		(width 0.1143)
		(layer "In11.Cu")
		(net "P5E_PEX3_STN2_TX_DN<42>")
	)
	(segment
		(start 397.38554 -280.129488)
		(end 397.49984 -280.015188)
		(width 0.1143)
		(layer "In11.Cu")
		(net "P5E_PEX3_STN2_TX_DN<42>")
	)
	(segment
		(start 397.16583 -271.399)
		(end 397.16583 -271.427448)
		(width 0.1143)
		(layer "In11.Cu")
		(net "P5E_PEX3_STN2_TX_DN<42>")
	)
	(segment
		(start 396.765526 -32.141414)
		(end 397.36141 -32.319468)
		(width 0.1651)
		(layer "In11.Cu")
		(net "P5E_PEX3_STN2_TX_DN<42>")
	)
	(segment
		(start 95.65767 -366.15878)
		(end 94.990666 -363.959648)
		(width 0.1651)
		(layer "In9.Cu")
		(net "P5E_PEX0_STN5_RX_DP<84>")
	)
	(segment
		(start 82.623152 -393.493752)
		(end 82.730848 -393.493752)
		(width 0.1651)
		(layer "In9.Cu")
		(net "P5E_PEX0_STN5_RX_DP<84>")
	)
	(segment
		(start 94.990666 -363.959648)
		(end 91.432126 -358.63403)
		(width 0.1651)
		(layer "In9.Cu")
		(net "P5E_PEX0_STN5_RX_DP<84>")
	)
	(segment
		(start 82.730848 -393.493752)
		(end 83.08086 -393.14374)
		(width 0.1651)
		(layer "In9.Cu")
		(net "P5E_PEX0_STN5_RX_DP<84>")
	)
	(segment
		(start 84.28482 -391.93978)
		(end 93.20784 -390.164828)
		(width 0.1651)
		(layer "In9.Cu")
		(net "P5E_PEX0_STN5_RX_DP<84>")
	)
	(segment
		(start 96.5708 -371.027452)
		(end 96.5708 -370.750084)
		(width 0.1651)
		(layer "In9.Cu")
		(net "P5E_PEX0_STN5_RX_DP<84>")
	)
	(segment
		(start 80.837024 -396.999206)
		(end 81.226152 -396.999206)
		(width 0.1651)
		(layer "In9.Cu")
		(net "P5E_PEX0_STN5_RX_DP<84>")
	)
	(segment
		(start 68.181474 -325.241158)
		(end 64.252602 -323.613526)
		(width 0.1651)
		(layer "In9.Cu")
		(net "P5E_PEX0_STN5_RX_DP<84>")
	)
	(segment
		(start 64.252602 -323.613526)
		(end 62.42685 -321.787774)
		(width 0.1651)
		(layer "In9.Cu")
		(net "P5E_PEX0_STN5_RX_DP<84>")
	)
	(segment
		(start 91.432126 -358.63403)
		(end 91.198192 -357.862632)
		(width 0.1651)
		(layer "In9.Cu")
		(net "P5E_PEX0_STN5_RX_DP<84>")
	)
	(segment
		(start 96.24822 -386.809488)
		(end 96.24822 -385.459732)
		(width 0.1651)
		(layer "In9.Cu")
		(net "P5E_PEX0_STN5_RX_DP<84>")
	)
	(segment
		(start 83.43138 -392.685524)
		(end 83.539076 -392.685524)
		(width 0.1651)
		(layer "In9.Cu")
		(net "P5E_PEX0_STN5_RX_DP<84>")
	)
	(segment
		(start 61.883798 -319.995296)
		(end 61.883798 -319.966848)
		(width 0.1143)
		(layer "In9.Cu")
		(net "P5E_PEX0_STN5_RX_DP<84>")
	)
	(segment
		(start 61.929518 -319.921128)
		(end 61.929518 -316.506098)
		(width 0.1143)
		(layer "In9.Cu")
		(net "P5E_PEX0_STN5_RX_DP<84>")
	)
	(segment
		(start 80.710024 -396.872206)
		(end 80.837024 -396.999206)
		(width 0.1651)
		(layer "In9.Cu")
		(net "P5E_PEX0_STN5_RX_DP<84>")
	)
	(segment
		(start 91.198192 -341.84463)
		(end 90.18016 -339.940392)
		(width 0.1651)
		(layer "In9.Cu")
		(net "P5E_PEX0_STN5_RX_DP<84>")
	)
	(segment
		(start 90.18016 -339.940392)
		(end 68.181474 -325.241158)
		(width 0.1651)
		(layer "In9.Cu")
		(net "P5E_PEX0_STN5_RX_DP<84>")
	)
	(segment
		(start 95.622618 -388.320026)
		(end 96.24822 -386.809488)
		(width 0.1651)
		(layer "In9.Cu")
		(net "P5E_PEX0_STN5_RX_DP<84>")
	)
	(segment
		(start 62.499748 -316.140592)
		(end 62.499748 -315.849762)
		(width 0.1143)
		(layer "In9.Cu")
		(net "P5E_PEX0_STN5_RX_DP<84>")
	)
	(segment
		(start 61.929518 -316.506098)
		(end 62.206124 -316.229492)
		(width 0.1143)
		(layer "In9.Cu")
		(net "P5E_PEX0_STN5_RX_DP<84>")
	)
	(segment
		(start 62.42685 -321.787774)
		(end 61.883798 -320.47688)
		(width 0.1651)
		(layer "In9.Cu")
		(net "P5E_PEX0_STN5_RX_DP<84>")
	)
	(segment
		(start 62.206124 -316.229492)
		(end 62.410848 -316.229492)
		(width 0.1143)
		(layer "In9.Cu")
		(net "P5E_PEX0_STN5_RX_DP<84>")
	)
	(segment
		(start 82.272632 -393.951968)
		(end 82.272632 -393.844272)
		(width 0.1651)
		(layer "In9.Cu")
		(net "P5E_PEX0_STN5_RX_DP<84>")
	)
	(segment
		(start 83.539076 -392.685524)
		(end 84.28482 -391.93978)
		(width 0.1651)
		(layer "In9.Cu")
		(net "P5E_PEX0_STN5_RX_DP<84>")
	)
	(segment
		(start 96.5708 -370.750084)
		(end 95.65767 -366.15878)
		(width 0.1651)
		(layer "In9.Cu")
		(net "P5E_PEX0_STN5_RX_DP<84>")
	)
	(segment
		(start 83.08086 -393.14374)
		(end 83.08086 -393.03579)
		(width 0.1651)
		(layer "In9.Cu")
		(net "P5E_PEX0_STN5_RX_DP<84>")
	)
	(segment
		(start 82.272632 -393.844272)
		(end 82.623152 -393.493752)
		(width 0.1651)
		(layer "In9.Cu")
		(net "P5E_PEX0_STN5_RX_DP<84>")
	)
	(segment
		(start 80.710024 -396.49019)
		(end 80.710024 -396.872206)
		(width 0.1651)
		(layer "In9.Cu")
		(net "P5E_PEX0_STN5_RX_DP<84>")
	)
	(segment
		(start 61.883798 -319.966848)
		(end 61.929518 -319.921128)
		(width 0.1143)
		(layer "In9.Cu")
		(net "P5E_PEX0_STN5_RX_DP<84>")
	)
	(segment
		(start 81.226152 -396.999206)
		(end 81.644744 -396.580614)
		(width 0.1651)
		(layer "In9.Cu")
		(net "P5E_PEX0_STN5_RX_DP<84>")
	)
	(segment
		(start 96.24822 -385.459732)
		(end 96.5708 -371.027452)
		(width 0.1651)
		(layer "In9.Cu")
		(net "P5E_PEX0_STN5_RX_DP<84>")
	)
	(segment
		(start 81.644744 -396.580614)
		(end 81.644744 -394.579856)
		(width 0.1651)
		(layer "In9.Cu")
		(net "P5E_PEX0_STN5_RX_DP<84>")
	)
	(segment
		(start 61.883798 -320.47688)
		(end 61.883798 -319.995296)
		(width 0.1651)
		(layer "In9.Cu")
		(net "P5E_PEX0_STN5_RX_DP<84>")
	)
	(segment
		(start 62.410848 -316.229492)
		(end 62.499748 -316.140592)
		(width 0.1143)
		(layer "In9.Cu")
		(net "P5E_PEX0_STN5_RX_DP<84>")
	)
	(segment
		(start 81.644744 -394.579856)
		(end 82.272632 -393.951968)
		(width 0.1651)
		(layer "In9.Cu")
		(net "P5E_PEX0_STN5_RX_DP<84>")
	)
	(segment
		(start 94.180914 -389.76173)
		(end 95.622618 -388.320026)
		(width 0.1651)
		(layer "In9.Cu")
		(net "P5E_PEX0_STN5_RX_DP<84>")
	)
	(segment
		(start 91.198192 -357.862632)
		(end 91.198192 -341.84463)
		(width 0.1651)
		(layer "In9.Cu")
		(net "P5E_PEX0_STN5_RX_DP<84>")
	)
	(segment
		(start 83.08086 -393.03579)
		(end 83.43138 -392.685524)
		(width 0.1651)
		(layer "In9.Cu")
		(net "P5E_PEX0_STN5_RX_DP<84>")
	)
	(segment
		(start 93.20784 -390.164828)
		(end 94.180914 -389.76173)
		(width 0.1651)
		(layer "In9.Cu")
		(net "P5E_PEX0_STN5_RX_DP<84>")
	)
	(segment
		(start 72.750426 -366.205262)
		(end 72.726804 -365.723424)
		(width 0.1651)
		(layer "In5.Cu")
		(net "P5E_PEX0_STN5_RX_DP<88>")
	)
	(segment
		(start 65.683892 -321.812158)
		(end 65.683892 -320.068448)
		(width 0.1651)
		(layer "In5.Cu")
		(net "P5E_PEX0_STN5_RX_DP<88>")
	)
	(segment
		(start 66.299842 -316.115192)
		(end 66.299842 -315.849762)
		(width 0.1143)
		(layer "In5.Cu")
		(net "P5E_PEX0_STN5_RX_DP<88>")
	)
	(segment
		(start 72.785224 -366.910874)
		(end 72.667876 -366.804702)
		(width 0.1651)
		(layer "In5.Cu")
		(net "P5E_PEX0_STN5_RX_DP<88>")
	)
	(segment
		(start 72.644254 -366.322356)
		(end 72.750426 -366.205262)
		(width 0.1651)
		(layer "In5.Cu")
		(net "P5E_PEX0_STN5_RX_DP<88>")
	)
	(segment
		(start 72.667876 -366.804702)
		(end 72.644254 -366.322356)
		(width 0.1651)
		(layer "In5.Cu")
		(net "P5E_PEX0_STN5_RX_DP<88>")
	)
	(segment
		(start 65.683892 -320.068448)
		(end 65.683892 -320.04)
		(width 0.1143)
		(layer "In5.Cu")
		(net "P5E_PEX0_STN5_RX_DP<88>")
	)
	(segment
		(start 72.633586 -363.830362)
		(end 72.544432 -362.007404)
		(width 0.1651)
		(layer "In5.Cu")
		(net "P5E_PEX0_STN5_RX_DP<88>")
	)
	(segment
		(start 72.692006 -365.017812)
		(end 72.668384 -364.535974)
		(width 0.1651)
		(layer "In5.Cu")
		(net "P5E_PEX0_STN5_RX_DP<88>")
	)
	(segment
		(start 65.729612 -319.99428)
		(end 65.729612 -316.455298)
		(width 0.1143)
		(layer "In5.Cu")
		(net "P5E_PEX0_STN5_RX_DP<88>")
	)
	(segment
		(start 72.03694 -370.999258)
		(end 72.537066 -370.999258)
		(width 0.1651)
		(layer "In5.Cu")
		(net "P5E_PEX0_STN5_RX_DP<88>")
	)
	(segment
		(start 72.527414 -363.947456)
		(end 72.633586 -363.830362)
		(width 0.1651)
		(layer "In5.Cu")
		(net "P5E_PEX0_STN5_RX_DP<88>")
	)
	(segment
		(start 72.544432 -362.007404)
		(end 72.544432 -341.936578)
		(width 0.1651)
		(layer "In5.Cu")
		(net "P5E_PEX0_STN5_RX_DP<88>")
	)
	(segment
		(start 72.78497 -366.910874)
		(end 72.785224 -366.910874)
		(width 0.1651)
		(layer "In5.Cu")
		(net "P5E_PEX0_STN5_RX_DP<88>")
	)
	(segment
		(start 72.585834 -365.134906)
		(end 72.692006 -365.017812)
		(width 0.1651)
		(layer "In5.Cu")
		(net "P5E_PEX0_STN5_RX_DP<88>")
	)
	(segment
		(start 72.808846 -370.727478)
		(end 72.808846 -367.392712)
		(width 0.1651)
		(layer "In5.Cu")
		(net "P5E_PEX0_STN5_RX_DP<88>")
	)
	(segment
		(start 72.609456 -365.617252)
		(end 72.585834 -365.134906)
		(width 0.1651)
		(layer "In5.Cu")
		(net "P5E_PEX0_STN5_RX_DP<88>")
	)
	(segment
		(start 65.955418 -316.229492)
		(end 66.185542 -316.229492)
		(width 0.1143)
		(layer "In5.Cu")
		(net "P5E_PEX0_STN5_RX_DP<88>")
	)
	(segment
		(start 71.14667 -337.328764)
		(end 66.575178 -326.292464)
		(width 0.1651)
		(layer "In5.Cu")
		(net "P5E_PEX0_STN5_RX_DP<88>")
	)
	(segment
		(start 72.668384 -364.535974)
		(end 72.551036 -364.429802)
		(width 0.1651)
		(layer "In5.Cu")
		(net "P5E_PEX0_STN5_RX_DP<88>")
	)
	(segment
		(start 72.544432 -341.936578)
		(end 71.14667 -337.328764)
		(width 0.1651)
		(layer "In5.Cu")
		(net "P5E_PEX0_STN5_RX_DP<88>")
	)
	(segment
		(start 65.683892 -320.04)
		(end 65.729612 -319.99428)
		(width 0.1143)
		(layer "In5.Cu")
		(net "P5E_PEX0_STN5_RX_DP<88>")
	)
	(segment
		(start 72.537066 -370.999258)
		(end 72.808846 -370.727478)
		(width 0.1651)
		(layer "In5.Cu")
		(net "P5E_PEX0_STN5_RX_DP<88>")
	)
	(segment
		(start 71.90994 -370.489988)
		(end 71.90994 -370.872258)
		(width 0.1651)
		(layer "In5.Cu")
		(net "P5E_PEX0_STN5_RX_DP<88>")
	)
	(segment
		(start 72.808846 -367.392712)
		(end 72.78497 -366.910874)
		(width 0.1651)
		(layer "In5.Cu")
		(net "P5E_PEX0_STN5_RX_DP<88>")
	)
	(segment
		(start 65.729612 -316.455298)
		(end 65.955418 -316.229492)
		(width 0.1143)
		(layer "In5.Cu")
		(net "P5E_PEX0_STN5_RX_DP<88>")
	)
	(segment
		(start 72.726804 -365.723424)
		(end 72.609456 -365.617252)
		(width 0.1651)
		(layer "In5.Cu")
		(net "P5E_PEX0_STN5_RX_DP<88>")
	)
	(segment
		(start 71.90994 -370.872258)
		(end 72.03694 -370.999258)
		(width 0.1651)
		(layer "In5.Cu")
		(net "P5E_PEX0_STN5_RX_DP<88>")
	)
	(segment
		(start 66.185542 -316.229492)
		(end 66.299842 -316.115192)
		(width 0.1143)
		(layer "In5.Cu")
		(net "P5E_PEX0_STN5_RX_DP<88>")
	)
	(segment
		(start 72.551036 -364.429802)
		(end 72.527414 -363.947456)
		(width 0.1651)
		(layer "In5.Cu")
		(net "P5E_PEX0_STN5_RX_DP<88>")
	)
	(segment
		(start 66.575178 -326.292464)
		(end 65.683892 -321.812158)
		(width 0.1651)
		(layer "In5.Cu")
		(net "P5E_PEX0_STN5_RX_DP<88>")
	)
	(segment
		(start 418.688266 -32.4104)
		(end 418.359082 -32.739584)
		(width 0.13462)
		(layer "F.Cu")
		(net "P5E_PEX3_STN2_TX_DP<38>")
	)
	(segment
		(start 419.605206 -32.714184)
		(end 419.301422 -32.4104)
		(width 0.13462)
		(layer "F.Cu")
		(net "P5E_PEX3_STN2_TX_DP<38>")
	)
	(segment
		(start 419.301422 -32.4104)
		(end 418.688266 -32.4104)
		(width 0.13462)
		(layer "F.Cu")
		(net "P5E_PEX3_STN2_TX_DP<38>")
	)
	(segment
		(start 425.440094 -34.717736)
		(end 423.697908 -33.028636)
		(width 0.1651)
		(layer "In11.Cu")
		(net "P5E_PEX3_STN2_TX_DP<38>")
	)
	(segment
		(start 401.299934 -280.434288)
		(end 401.185634 -280.319988)
		(width 0.1143)
		(layer "In11.Cu")
		(net "P5E_PEX3_STN2_TX_DP<38>")
	)
	(segment
		(start 436.740808 -62.267338)
		(end 437.261762 -60.311792)
		(width 0.1651)
		(layer "In11.Cu")
		(net "P5E_PEX3_STN2_TX_DP<38>")
	)
	(segment
		(start 400.944842 -280.319988)
		(end 400.729704 -280.10485)
		(width 0.1143)
		(layer "In11.Cu")
		(net "P5E_PEX3_STN2_TX_DP<38>")
	)
	(segment
		(start 437.261762 -60.311792)
		(end 437.261762 -58.512202)
		(width 0.1651)
		(layer "In11.Cu")
		(net "P5E_PEX3_STN2_TX_DP<38>")
	)
	(segment
		(start 400.729704 -280.10485)
		(end 400.729704 -271.473168)
		(width 0.1143)
		(layer "In11.Cu")
		(net "P5E_PEX3_STN2_TX_DP<38>")
	)
	(segment
		(start 408.109928 -121.034048)
		(end 408.80284 -115.413282)
		(width 0.1651)
		(layer "In11.Cu")
		(net "P5E_PEX3_STN2_TX_DP<38>")
	)
	(segment
		(start 436.24246 -48.697642)
		(end 429.585882 -41.469818)
		(width 0.1651)
		(layer "In11.Cu")
		(net "P5E_PEX3_STN2_TX_DP<38>")
	)
	(segment
		(start 408.80284 -115.413282)
		(end 410.32557 -107.62107)
		(width 0.1651)
		(layer "In11.Cu")
		(net "P5E_PEX3_STN2_TX_DP<38>")
	)
	(segment
		(start 423.697908 -33.028636)
		(end 422.015412 -32.423354)
		(width 0.1651)
		(layer "In11.Cu")
		(net "P5E_PEX3_STN2_TX_DP<38>")
	)
	(segment
		(start 413.687514 -93.070426)
		(end 435.849776 -64.07023)
		(width 0.1651)
		(layer "In11.Cu")
		(net "P5E_PEX3_STN2_TX_DP<38>")
	)
	(segment
		(start 420.699692 -32.423354)
		(end 419.896036 -32.423354)
		(width 0.1651)
		(layer "In11.Cu")
		(net "P5E_PEX3_STN2_TX_DP<38>")
	)
	(segment
		(start 429.585882 -41.469818)
		(end 425.440094 -34.717736)
		(width 0.1651)
		(layer "In11.Cu")
		(net "P5E_PEX3_STN2_TX_DP<38>")
	)
	(segment
		(start 421.296592 -32.524954)
		(end 420.801292 -32.524954)
		(width 0.1651)
		(layer "In11.Cu")
		(net "P5E_PEX3_STN2_TX_DP<38>")
	)
	(segment
		(start 421.398192 -32.423354)
		(end 421.296592 -32.524954)
		(width 0.1651)
		(layer "In11.Cu")
		(net "P5E_PEX3_STN2_TX_DP<38>")
	)
	(segment
		(start 400.683984 -271.399)
		(end 400.683984 -263.176004)
		(width 0.1651)
		(layer "In11.Cu")
		(net "P5E_PEX3_STN2_TX_DP<38>")
	)
	(segment
		(start 410.32557 -107.62107)
		(end 413.687514 -93.070426)
		(width 0.1651)
		(layer "In11.Cu")
		(net "P5E_PEX3_STN2_TX_DP<38>")
	)
	(segment
		(start 435.849776 -64.07023)
		(end 436.740808 -62.267338)
		(width 0.1651)
		(layer "In11.Cu")
		(net "P5E_PEX3_STN2_TX_DP<38>")
	)
	(segment
		(start 420.801292 -32.524954)
		(end 420.699692 -32.423354)
		(width 0.1651)
		(layer "In11.Cu")
		(net "P5E_PEX3_STN2_TX_DP<38>")
	)
	(segment
		(start 437.261762 -58.512202)
		(end 436.24246 -48.697642)
		(width 0.1651)
		(layer "In11.Cu")
		(net "P5E_PEX3_STN2_TX_DP<38>")
	)
	(segment
		(start 400.683984 -271.427448)
		(end 400.683984 -271.399)
		(width 0.1143)
		(layer "In11.Cu")
		(net "P5E_PEX3_STN2_TX_DP<38>")
	)
	(segment
		(start 401.299934 -280.699718)
		(end 401.299934 -280.434288)
		(width 0.1143)
		(layer "In11.Cu")
		(net "P5E_PEX3_STN2_TX_DP<38>")
	)
	(segment
		(start 422.015412 -32.423354)
		(end 421.398192 -32.423354)
		(width 0.1651)
		(layer "In11.Cu")
		(net "P5E_PEX3_STN2_TX_DP<38>")
	)
	(segment
		(start 401.185634 -280.319988)
		(end 400.944842 -280.319988)
		(width 0.1143)
		(layer "In11.Cu")
		(net "P5E_PEX3_STN2_TX_DP<38>")
	)
	(segment
		(start 400.729704 -271.473168)
		(end 400.683984 -271.427448)
		(width 0.1143)
		(layer "In11.Cu")
		(net "P5E_PEX3_STN2_TX_DP<38>")
	)
	(segment
		(start 419.896036 -32.423354)
		(end 419.605206 -32.714184)
		(width 0.1651)
		(layer "In11.Cu")
		(net "P5E_PEX3_STN2_TX_DP<38>")
	)
	(segment
		(start 400.683984 -263.176004)
		(end 408.109928 -121.034048)
		(width 0.1651)
		(layer "In11.Cu")
		(net "P5E_PEX3_STN2_TX_DP<38>")
	)
	(segment
		(start 63.618618 -325.282306)
		(end 60.994798 -322.658486)
		(width 0.1651)
		(layer "In9.Cu")
		(net "P5E_PEX0_STN5_RX_DN<82>")
	)
	(segment
		(start 60.599828 -316.508892)
		(end 60.599828 -316.799722)
		(width 0.1143)
		(layer "In9.Cu")
		(net "P5E_PEX0_STN5_RX_DN<82>")
	)
	(segment
		(start 94.609666 -385.440174)
		(end 94.92234 -371.426486)
		(width 0.1651)
		(layer "In9.Cu")
		(net "P5E_PEX0_STN5_RX_DN<82>")
	)
	(segment
		(start 60.265818 -319.916048)
		(end 60.220098 -319.870328)
		(width 0.1143)
		(layer "In9.Cu")
		(net "P5E_PEX0_STN5_RX_DN<82>")
	)
	(segment
		(start 84.805774 -341.091774)
		(end 79.825596 -336.111596)
		(width 0.1651)
		(layer "In9.Cu")
		(net "P5E_PEX0_STN5_RX_DN<82>")
	)
	(segment
		(start 94.92234 -371.426486)
		(end 94.92234 -370.976398)
		(width 0.1651)
		(layer "In9.Cu")
		(net "P5E_PEX0_STN5_RX_DN<82>")
	)
	(segment
		(start 76.309982 -397.790162)
		(end 76.309982 -397.408146)
		(width 0.1651)
		(layer "In9.Cu")
		(net "P5E_PEX0_STN5_RX_DN<82>")
	)
	(segment
		(start 94.609666 -386.37591)
		(end 94.609666 -385.440174)
		(width 0.1651)
		(layer "In9.Cu")
		(net "P5E_PEX0_STN5_RX_DN<82>")
	)
	(segment
		(start 60.265818 -320.898774)
		(end 60.265818 -319.944496)
		(width 0.1651)
		(layer "In9.Cu")
		(net "P5E_PEX0_STN5_RX_DN<82>")
	)
	(segment
		(start 60.510928 -316.419992)
		(end 60.599828 -316.508892)
		(width 0.1143)
		(layer "In9.Cu")
		(net "P5E_PEX0_STN5_RX_DN<82>")
	)
	(segment
		(start 93.258386 -388.380986)
		(end 94.147386 -387.491986)
		(width 0.1651)
		(layer "In9.Cu")
		(net "P5E_PEX0_STN5_RX_DN<82>")
	)
	(segment
		(start 76.436982 -397.281146)
		(end 76.94295 -397.281146)
		(width 0.1651)
		(layer "In9.Cu")
		(net "P5E_PEX0_STN5_RX_DN<82>")
	)
	(segment
		(start 76.309982 -397.408146)
		(end 76.436982 -397.281146)
		(width 0.1651)
		(layer "In9.Cu")
		(net "P5E_PEX0_STN5_RX_DN<82>")
	)
	(segment
		(start 94.92234 -370.976398)
		(end 94.310962 -367.900966)
		(width 0.1651)
		(layer "In9.Cu")
		(net "P5E_PEX0_STN5_RX_DN<82>")
	)
	(segment
		(start 60.220098 -316.585092)
		(end 60.385198 -316.419992)
		(width 0.1143)
		(layer "In9.Cu")
		(net "P5E_PEX0_STN5_RX_DN<82>")
	)
	(segment
		(start 81.21269 -390.88949)
		(end 92.735146 -388.597902)
		(width 0.1651)
		(layer "In9.Cu")
		(net "P5E_PEX0_STN5_RX_DN<82>")
	)
	(segment
		(start 85.262212 -342.19388)
		(end 84.805774 -341.091774)
		(width 0.1651)
		(layer "In9.Cu")
		(net "P5E_PEX0_STN5_RX_DN<82>")
	)
	(segment
		(start 94.310962 -367.900966)
		(end 93.895926 -366.899698)
		(width 0.1651)
		(layer "In9.Cu")
		(net "P5E_PEX0_STN5_RX_DN<82>")
	)
	(segment
		(start 76.94295 -397.281146)
		(end 77.526642 -396.697454)
		(width 0.1651)
		(layer "In9.Cu")
		(net "P5E_PEX0_STN5_RX_DN<82>")
	)
	(segment
		(start 92.735146 -388.597902)
		(end 93.258386 -388.380986)
		(width 0.1651)
		(layer "In9.Cu")
		(net "P5E_PEX0_STN5_RX_DN<82>")
	)
	(segment
		(start 94.147386 -387.491986)
		(end 94.609666 -386.37591)
		(width 0.1651)
		(layer "In9.Cu")
		(net "P5E_PEX0_STN5_RX_DN<82>")
	)
	(segment
		(start 60.994798 -322.658486)
		(end 60.265818 -320.898774)
		(width 0.1651)
		(layer "In9.Cu")
		(net "P5E_PEX0_STN5_RX_DN<82>")
	)
	(segment
		(start 60.220098 -319.870328)
		(end 60.220098 -316.585092)
		(width 0.1143)
		(layer "In9.Cu")
		(net "P5E_PEX0_STN5_RX_DN<82>")
	)
	(segment
		(start 60.265818 -319.944496)
		(end 60.265818 -319.916048)
		(width 0.1143)
		(layer "In9.Cu")
		(net "P5E_PEX0_STN5_RX_DN<82>")
	)
	(segment
		(start 77.526642 -394.575538)
		(end 81.21269 -390.88949)
		(width 0.1651)
		(layer "In9.Cu")
		(net "P5E_PEX0_STN5_RX_DN<82>")
	)
	(segment
		(start 79.825596 -336.111596)
		(end 63.618618 -325.282306)
		(width 0.1651)
		(layer "In9.Cu")
		(net "P5E_PEX0_STN5_RX_DN<82>")
	)
	(segment
		(start 93.895926 -366.899698)
		(end 85.262212 -358.265984)
		(width 0.1651)
		(layer "In9.Cu")
		(net "P5E_PEX0_STN5_RX_DN<82>")
	)
	(segment
		(start 60.385198 -316.419992)
		(end 60.510928 -316.419992)
		(width 0.1143)
		(layer "In9.Cu")
		(net "P5E_PEX0_STN5_RX_DN<82>")
	)
	(segment
		(start 77.526642 -396.697454)
		(end 77.526642 -394.575538)
		(width 0.1651)
		(layer "In9.Cu")
		(net "P5E_PEX0_STN5_RX_DN<82>")
	)
	(segment
		(start 85.262212 -358.265984)
		(end 85.262212 -342.19388)
		(width 0.1651)
		(layer "In9.Cu")
		(net "P5E_PEX0_STN5_RX_DN<82>")
	)
	(segment
		(start 86.812882 -355.026722)
		(end 87.107522 -354.732082)
		(width 0.13462)
		(layer "F.Cu")
		(net "P5E_PEX0_STN6_TX_DN<99>")
	)
	(segment
		(start 86.812882 -355.658166)
		(end 86.812882 -355.026722)
		(width 0.13462)
		(layer "F.Cu")
		(net "P5E_PEX0_STN6_TX_DN<99>")
	)
	(segment
		(start 87.132922 -355.978206)
		(end 86.812882 -355.658166)
		(width 0.13462)
		(layer "F.Cu")
		(net "P5E_PEX0_STN6_TX_DN<99>")
	)
	(segment
		(start 86.816692 -353.752404)
		(end 88.371172 -352.197924)
		(width 0.1651)
		(layer "In13.Cu")
		(net "P5E_PEX0_STN6_TX_DN<99>")
	)
	(segment
		(start 64.017906 -327.068942)
		(end 55.924196 -323.716396)
		(width 0.1651)
		(layer "In13.Cu")
		(net "P5E_PEX0_STN6_TX_DN<99>")
	)
	(segment
		(start 54.647338 -311.670192)
		(end 54.810914 -311.670192)
		(width 0.1143)
		(layer "In13.Cu")
		(net "P5E_PEX0_STN6_TX_DN<99>")
	)
	(segment
		(start 54.520084 -311.797446)
		(end 54.647338 -311.670192)
		(width 0.1143)
		(layer "In13.Cu")
		(net "P5E_PEX0_STN6_TX_DN<99>")
	)
	(segment
		(start 54.565804 -321.564508)
		(end 54.565804 -320.210688)
		(width 0.1651)
		(layer "In13.Cu")
		(net "P5E_PEX0_STN6_TX_DN<99>")
	)
	(segment
		(start 55.924196 -323.716396)
		(end 55.126382 -322.918582)
		(width 0.1651)
		(layer "In13.Cu")
		(net "P5E_PEX0_STN6_TX_DN<99>")
	)
	(segment
		(start 54.520084 -320.14287)
		(end 54.520084 -311.797446)
		(width 0.1143)
		(layer "In13.Cu")
		(net "P5E_PEX0_STN6_TX_DN<99>")
	)
	(segment
		(start 55.126382 -322.918582)
		(end 54.565804 -321.564508)
		(width 0.1651)
		(layer "In13.Cu")
		(net "P5E_PEX0_STN6_TX_DN<99>")
	)
	(segment
		(start 88.371172 -352.197924)
		(end 88.371172 -341.384382)
		(width 0.1651)
		(layer "In13.Cu")
		(net "P5E_PEX0_STN6_TX_DN<99>")
	)
	(segment
		(start 54.899814 -311.759092)
		(end 54.899814 -312.049922)
		(width 0.1143)
		(layer "In13.Cu")
		(net "P5E_PEX0_STN6_TX_DN<99>")
	)
	(segment
		(start 88.371172 -341.384382)
		(end 87.225632 -339.473032)
		(width 0.1651)
		(layer "In13.Cu")
		(net "P5E_PEX0_STN6_TX_DN<99>")
	)
	(segment
		(start 54.565804 -320.18859)
		(end 54.520084 -320.14287)
		(width 0.1143)
		(layer "In13.Cu")
		(net "P5E_PEX0_STN6_TX_DN<99>")
	)
	(segment
		(start 87.225632 -339.473032)
		(end 64.017906 -327.068942)
		(width 0.1651)
		(layer "In13.Cu")
		(net "P5E_PEX0_STN6_TX_DN<99>")
	)
	(segment
		(start 54.810914 -311.670192)
		(end 54.899814 -311.759092)
		(width 0.1143)
		(layer "In13.Cu")
		(net "P5E_PEX0_STN6_TX_DN<99>")
	)
	(segment
		(start 87.107522 -354.732082)
		(end 86.816692 -354.441252)
		(width 0.1651)
		(layer "In13.Cu")
		(net "P5E_PEX0_STN6_TX_DN<99>")
	)
	(segment
		(start 54.565804 -320.210688)
		(end 54.565804 -320.18859)
		(width 0.1143)
		(layer "In13.Cu")
		(net "P5E_PEX0_STN6_TX_DN<99>")
	)
	(segment
		(start 86.816692 -354.441252)
		(end 86.816692 -353.752404)
		(width 0.1651)
		(layer "In13.Cu")
		(net "P5E_PEX0_STN6_TX_DN<99>")
	)
	(segment
		(start 39.434516 -309.199788)
		(end 39.320216 -309.085488)
		(width 0.1143)
		(layer "In5.Cu")
		(net "P5E_PEX0_STN7_RX_DP<120>")
	)
	(segment
		(start 35.429952 -308.583838)
		(end 35.094672 -308.583838)
		(width 0.1651)
		(layer "In5.Cu")
		(net "P5E_PEX0_STN7_RX_DP<120>")
	)
	(segment
		(start 30.504638 -357.78948)
		(end 28.77693 -369.432586)
		(width 0.1651)
		(layer "In5.Cu")
		(net "P5E_PEX0_STN7_RX_DP<120>")
	)
	(segment
		(start 28.40736 -382.69926)
		(end 28.037028 -382.69926)
		(width 0.1651)
		(layer "In5.Cu")
		(net "P5E_PEX0_STN7_RX_DP<120>")
	)
	(segment
		(start 28.037028 -382.69926)
		(end 27.910028 -382.57226)
		(width 0.1651)
		(layer "In5.Cu")
		(net "P5E_PEX0_STN7_RX_DP<120>")
	)
	(segment
		(start 35.50412 -308.629558)
		(end 35.4584 -308.583838)
		(width 0.1143)
		(layer "In5.Cu")
		(net "P5E_PEX0_STN7_RX_DP<120>")
	)
	(segment
		(start 39.09441 -308.629558)
		(end 35.50412 -308.629558)
		(width 0.1143)
		(layer "In5.Cu")
		(net "P5E_PEX0_STN7_RX_DP<120>")
	)
	(segment
		(start 35.094672 -308.583838)
		(end 34.50717 -308.827424)
		(width 0.1651)
		(layer "In5.Cu")
		(net "P5E_PEX0_STN7_RX_DP<120>")
	)
	(segment
		(start 33.274 -312.53303)
		(end 33.274 -317.022226)
		(width 0.1651)
		(layer "In5.Cu")
		(net "P5E_PEX0_STN7_RX_DP<120>")
	)
	(segment
		(start 34.51606 -321.616324)
		(end 30.504638 -341.78494)
		(width 0.1651)
		(layer "In5.Cu")
		(net "P5E_PEX0_STN7_RX_DP<120>")
	)
	(segment
		(start 39.320216 -308.855364)
		(end 39.09441 -308.629558)
		(width 0.1143)
		(layer "In5.Cu")
		(net "P5E_PEX0_STN7_RX_DP<120>")
	)
	(segment
		(start 39.320216 -309.085488)
		(end 39.320216 -308.855364)
		(width 0.1143)
		(layer "In5.Cu")
		(net "P5E_PEX0_STN7_RX_DP<120>")
	)
	(segment
		(start 35.4584 -308.583838)
		(end 35.429952 -308.583838)
		(width 0.1143)
		(layer "In5.Cu")
		(net "P5E_PEX0_STN7_RX_DP<120>")
	)
	(segment
		(start 34.50717 -308.827424)
		(end 33.51276 -309.821834)
		(width 0.1651)
		(layer "In5.Cu")
		(net "P5E_PEX0_STN7_RX_DP<120>")
	)
	(segment
		(start 33.51276 -311.95645)
		(end 33.274 -312.53303)
		(width 0.1651)
		(layer "In5.Cu")
		(net "P5E_PEX0_STN7_RX_DP<120>")
	)
	(segment
		(start 28.77693 -382.32969)
		(end 28.40736 -382.69926)
		(width 0.1651)
		(layer "In5.Cu")
		(net "P5E_PEX0_STN7_RX_DP<120>")
	)
	(segment
		(start 39.699946 -309.199788)
		(end 39.434516 -309.199788)
		(width 0.1143)
		(layer "In5.Cu")
		(net "P5E_PEX0_STN7_RX_DP<120>")
	)
	(segment
		(start 34.51606 -320.02095)
		(end 34.51606 -321.616324)
		(width 0.1651)
		(layer "In5.Cu")
		(net "P5E_PEX0_STN7_RX_DP<120>")
	)
	(segment
		(start 33.274 -317.022226)
		(end 34.51606 -320.02095)
		(width 0.1651)
		(layer "In5.Cu")
		(net "P5E_PEX0_STN7_RX_DP<120>")
	)
	(segment
		(start 30.504638 -341.78494)
		(end 30.504638 -357.78948)
		(width 0.1651)
		(layer "In5.Cu")
		(net "P5E_PEX0_STN7_RX_DP<120>")
	)
	(segment
		(start 33.51276 -309.821834)
		(end 33.51276 -311.95645)
		(width 0.1651)
		(layer "In5.Cu")
		(net "P5E_PEX0_STN7_RX_DP<120>")
	)
	(segment
		(start 27.910028 -382.57226)
		(end 27.910028 -382.18999)
		(width 0.1651)
		(layer "In5.Cu")
		(net "P5E_PEX0_STN7_RX_DP<120>")
	)
	(segment
		(start 28.77693 -369.432586)
		(end 28.77693 -382.32969)
		(width 0.1651)
		(layer "In5.Cu")
		(net "P5E_PEX0_STN7_RX_DP<120>")
	)
	(segment
		(start 74.102722 -350.685354)
		(end 73.782682 -350.365314)
		(width 0.13462)
		(layer "F.Cu")
		(net "P5E_PEX0_STN5_TX_C_DP<86>")
	)
	(segment
		(start 74.102722 -351.316798)
		(end 74.102722 -350.685354)
		(width 0.13462)
		(layer "F.Cu")
		(net "P5E_PEX0_STN5_TX_C_DP<86>")
	)
	(segment
		(start 73.808082 -351.611438)
		(end 74.102722 -351.316798)
		(width 0.13462)
		(layer "F.Cu")
		(net "P5E_PEX0_STN5_TX_C_DP<86>")
	)
	(segment
		(start 81.986882 -391.394442)
		(end 81.938876 -391.278364)
		(width 0.1651)
		(layer "In7.Cu")
		(net "P5E_PEX0_STN5_TX_C_DP<86>")
	)
	(segment
		(start 81.365344 -391.13714)
		(end 80.907382 -390.947148)
		(width 0.1651)
		(layer "In7.Cu")
		(net "P5E_PEX0_STN5_TX_C_DP<86>")
	)
	(segment
		(start 72.544432 -357.918258)
		(end 72.544432 -353.990402)
		(width 0.1651)
		(layer "In7.Cu")
		(net "P5E_PEX0_STN5_TX_C_DP<86>")
	)
	(segment
		(start 70.189344 -385.80187)
		(end 69.647308 -384.493262)
		(width 0.1651)
		(layer "In7.Cu")
		(net "P5E_PEX0_STN5_TX_C_DP<86>")
	)
	(segment
		(start 85.236812 -404.799038)
		(end 85.573108 -404.799038)
		(width 0.1651)
		(layer "In7.Cu")
		(net "P5E_PEX0_STN5_TX_C_DP<86>")
	)
	(segment
		(start 85.433408 -393.476988)
		(end 85.307678 -393.476988)
		(width 0.1651)
		(layer "In7.Cu")
		(net "P5E_PEX0_STN5_TX_C_DP<86>")
	)
	(segment
		(start 69.647308 -384.493262)
		(end 69.647308 -378.981462)
		(width 0.1651)
		(layer "In7.Cu")
		(net "P5E_PEX0_STN5_TX_C_DP<86>")
	)
	(segment
		(start 74.098912 -351.902268)
		(end 73.808082 -351.611438)
		(width 0.1651)
		(layer "In7.Cu")
		(net "P5E_PEX0_STN5_TX_C_DP<86>")
	)
	(segment
		(start 85.307678 -393.476988)
		(end 84.957412 -393.126722)
		(width 0.1651)
		(layer "In7.Cu")
		(net "P5E_PEX0_STN5_TX_C_DP<86>")
	)
	(segment
		(start 81.938876 -391.278364)
		(end 81.938876 -391.278618)
		(width 0.1651)
		(layer "In7.Cu")
		(net "P5E_PEX0_STN5_TX_C_DP<86>")
	)
	(segment
		(start 85.573108 -404.799038)
		(end 86.002114 -404.370032)
		(width 0.1651)
		(layer "In7.Cu")
		(net "P5E_PEX0_STN5_TX_C_DP<86>")
	)
	(segment
		(start 86.002114 -394.045694)
		(end 85.433408 -393.476988)
		(width 0.1651)
		(layer "In7.Cu")
		(net "P5E_PEX0_STN5_TX_C_DP<86>")
	)
	(segment
		(start 81.938876 -391.278618)
		(end 81.481422 -391.089134)
		(width 0.1651)
		(layer "In7.Cu")
		(net "P5E_PEX0_STN5_TX_C_DP<86>")
	)
	(segment
		(start 69.647308 -378.981462)
		(end 69.511926 -368.583464)
		(width 0.1651)
		(layer "In7.Cu")
		(net "P5E_PEX0_STN5_TX_C_DP<86>")
	)
	(segment
		(start 86.002114 -404.370032)
		(end 86.002114 -394.045694)
		(width 0.1651)
		(layer "In7.Cu")
		(net "P5E_PEX0_STN5_TX_C_DP<86>")
	)
	(segment
		(start 72.544432 -353.990402)
		(end 74.098912 -352.435922)
		(width 0.1651)
		(layer "In7.Cu")
		(net "P5E_PEX0_STN5_TX_C_DP<86>")
	)
	(segment
		(start 83.640422 -391.983468)
		(end 83.524344 -392.031474)
		(width 0.1651)
		(layer "In7.Cu")
		(net "P5E_PEX0_STN5_TX_C_DP<86>")
	)
	(segment
		(start 81.481422 -391.08888)
		(end 81.365344 -391.13714)
		(width 0.1651)
		(layer "In7.Cu")
		(net "P5E_PEX0_STN5_TX_C_DP<86>")
	)
	(segment
		(start 74.098912 -352.435922)
		(end 74.098912 -351.902268)
		(width 0.1651)
		(layer "In7.Cu")
		(net "P5E_PEX0_STN5_TX_C_DP<86>")
	)
	(segment
		(start 83.018122 -391.725658)
		(end 82.560922 -391.536174)
		(width 0.1651)
		(layer "In7.Cu")
		(net "P5E_PEX0_STN5_TX_C_DP<86>")
	)
	(segment
		(start 80.859122 -390.831324)
		(end 71.230236 -386.842762)
		(width 0.1651)
		(layer "In7.Cu")
		(net "P5E_PEX0_STN5_TX_C_DP<86>")
	)
	(segment
		(start 69.511926 -368.583464)
		(end 69.511926 -367.915444)
		(width 0.1651)
		(layer "In7.Cu")
		(net "P5E_PEX0_STN5_TX_C_DP<86>")
	)
	(segment
		(start 83.066382 -391.841736)
		(end 83.018376 -391.725658)
		(width 0.1651)
		(layer "In7.Cu")
		(net "P5E_PEX0_STN5_TX_C_DP<86>")
	)
	(segment
		(start 80.907382 -390.947148)
		(end 80.859376 -390.83107)
		(width 0.1651)
		(layer "In7.Cu")
		(net "P5E_PEX0_STN5_TX_C_DP<86>")
	)
	(segment
		(start 71.230236 -386.842762)
		(end 70.189344 -385.80187)
		(width 0.1651)
		(layer "In7.Cu")
		(net "P5E_PEX0_STN5_TX_C_DP<86>")
	)
	(segment
		(start 84.957412 -393.126722)
		(end 84.957412 -393.000992)
		(width 0.1651)
		(layer "In7.Cu")
		(net "P5E_PEX0_STN5_TX_C_DP<86>")
	)
	(segment
		(start 80.859376 -390.83107)
		(end 80.859122 -390.831324)
		(width 0.1651)
		(layer "In7.Cu")
		(net "P5E_PEX0_STN5_TX_C_DP<86>")
	)
	(segment
		(start 85.109812 -404.290022)
		(end 85.109812 -404.672038)
		(width 0.1651)
		(layer "In7.Cu")
		(net "P5E_PEX0_STN5_TX_C_DP<86>")
	)
	(segment
		(start 81.481422 -391.089134)
		(end 81.481422 -391.08888)
		(width 0.1651)
		(layer "In7.Cu")
		(net "P5E_PEX0_STN5_TX_C_DP<86>")
	)
	(segment
		(start 84.15147 -392.19505)
		(end 83.640422 -391.983468)
		(width 0.1651)
		(layer "In7.Cu")
		(net "P5E_PEX0_STN5_TX_C_DP<86>")
	)
	(segment
		(start 69.511926 -367.915444)
		(end 72.544432 -357.918258)
		(width 0.1651)
		(layer "In7.Cu")
		(net "P5E_PEX0_STN5_TX_C_DP<86>")
	)
	(segment
		(start 84.957412 -393.000992)
		(end 84.15147 -392.19505)
		(width 0.1651)
		(layer "In7.Cu")
		(net "P5E_PEX0_STN5_TX_C_DP<86>")
	)
	(segment
		(start 85.109812 -404.672038)
		(end 85.236812 -404.799038)
		(width 0.1651)
		(layer "In7.Cu")
		(net "P5E_PEX0_STN5_TX_C_DP<86>")
	)
	(segment
		(start 83.524344 -392.031474)
		(end 83.066382 -391.841736)
		(width 0.1651)
		(layer "In7.Cu")
		(net "P5E_PEX0_STN5_TX_C_DP<86>")
	)
	(segment
		(start 82.560922 -391.536174)
		(end 82.444844 -391.584434)
		(width 0.1651)
		(layer "In7.Cu")
		(net "P5E_PEX0_STN5_TX_C_DP<86>")
	)
	(segment
		(start 83.018376 -391.725658)
		(end 83.018122 -391.725658)
		(width 0.1651)
		(layer "In7.Cu")
		(net "P5E_PEX0_STN5_TX_C_DP<86>")
	)
	(segment
		(start 82.444844 -391.584434)
		(end 81.986882 -391.394442)
		(width 0.1651)
		(layer "In7.Cu")
		(net "P5E_PEX0_STN5_TX_C_DP<86>")
	)
	(segment
		(start 387.301232 -355.657658)
		(end 387.301232 -355.02723)
		(width 0.13462)
		(layer "F.Cu")
		(net "P5E_PEX3_STN5_TX_DN<80>")
	)
	(segment
		(start 387.301232 -355.02723)
		(end 387.59638 -354.732082)
		(width 0.13462)
		(layer "F.Cu")
		(net "P5E_PEX3_STN5_TX_DN<80>")
	)
	(segment
		(start 387.62178 -355.978206)
		(end 387.301232 -355.657658)
		(width 0.13462)
		(layer "F.Cu")
		(net "P5E_PEX3_STN5_TX_DN<80>")
	)
	(segment
		(start 406.620218 -319.915032)
		(end 406.620218 -311.784492)
		(width 0.1143)
		(layer "In7.Cu")
		(net "P5E_PEX3_STN5_TX_DN<80>")
	)
	(segment
		(start 387.30555 -353.930966)
		(end 388.867142 -352.369374)
		(width 0.1651)
		(layer "In7.Cu")
		(net "P5E_PEX3_STN5_TX_DN<80>")
	)
	(segment
		(start 388.867142 -352.369374)
		(end 388.867142 -341.904066)
		(width 0.1651)
		(layer "In7.Cu")
		(net "P5E_PEX3_STN5_TX_DN<80>")
	)
	(segment
		(start 388.867142 -341.904066)
		(end 405.131778 -325.884032)
		(width 0.1651)
		(layer "In7.Cu")
		(net "P5E_PEX3_STN5_TX_DN<80>")
	)
	(segment
		(start 387.30555 -354.441252)
		(end 387.30555 -353.930966)
		(width 0.1651)
		(layer "In7.Cu")
		(net "P5E_PEX3_STN5_TX_DN<80>")
	)
	(segment
		(start 406.999948 -311.784492)
		(end 406.999948 -312.049922)
		(width 0.1143)
		(layer "In7.Cu")
		(net "P5E_PEX3_STN5_TX_DN<80>")
	)
	(segment
		(start 406.665938 -319.960752)
		(end 406.620218 -319.915032)
		(width 0.1143)
		(layer "In7.Cu")
		(net "P5E_PEX3_STN5_TX_DN<80>")
	)
	(segment
		(start 405.131778 -325.884032)
		(end 405.652732 -325.114158)
		(width 0.1651)
		(layer "In7.Cu")
		(net "P5E_PEX3_STN5_TX_DN<80>")
	)
	(segment
		(start 387.59638 -354.732082)
		(end 387.30555 -354.441252)
		(width 0.1651)
		(layer "In7.Cu")
		(net "P5E_PEX3_STN5_TX_DN<80>")
	)
	(segment
		(start 405.652732 -325.114158)
		(end 406.665938 -322.668138)
		(width 0.1651)
		(layer "In7.Cu")
		(net "P5E_PEX3_STN5_TX_DN<80>")
	)
	(segment
		(start 406.620218 -311.784492)
		(end 406.734518 -311.670192)
		(width 0.1143)
		(layer "In7.Cu")
		(net "P5E_PEX3_STN5_TX_DN<80>")
	)
	(segment
		(start 406.665938 -322.668138)
		(end 406.665938 -319.9892)
		(width 0.1651)
		(layer "In7.Cu")
		(net "P5E_PEX3_STN5_TX_DN<80>")
	)
	(segment
		(start 406.885648 -311.670192)
		(end 406.999948 -311.784492)
		(width 0.1143)
		(layer "In7.Cu")
		(net "P5E_PEX3_STN5_TX_DN<80>")
	)
	(segment
		(start 406.734518 -311.670192)
		(end 406.885648 -311.670192)
		(width 0.1143)
		(layer "In7.Cu")
		(net "P5E_PEX3_STN5_TX_DN<80>")
	)
	(segment
		(start 406.665938 -319.9892)
		(end 406.665938 -319.960752)
		(width 0.1143)
		(layer "In7.Cu")
		(net "P5E_PEX3_STN5_TX_DN<80>")
	)
	(segment
		(start 24.817324 -322.097654)
		(end 24.817324 -319.938654)
		(width 0.1651)
		(layer "In5.Cu")
		(net "P5E_PEX0_STN7_RX_DN<119>")
	)
	(segment
		(start 31.390336 -310.831992)
		(end 31.731966 -310.490362)
		(width 0.1651)
		(layer "In5.Cu")
		(net "P5E_PEX0_STN7_RX_DN<119>")
	)
	(segment
		(start 43.310048 -410.207968)
		(end 43.437048 -410.080968)
		(width 0.1651)
		(layer "In5.Cu")
		(net "P5E_PEX0_STN7_RX_DN<119>")
	)
	(segment
		(start 35.588448 -307.915818)
		(end 35.634168 -307.870098)
		(width 0.1143)
		(layer "In5.Cu")
		(net "P5E_PEX0_STN7_RX_DN<119>")
	)
	(segment
		(start 33.712404 -308.351936)
		(end 34.765488 -307.915818)
		(width 0.1651)
		(layer "In5.Cu")
		(net "P5E_PEX0_STN7_RX_DN<119>")
	)
	(segment
		(start 27.982164 -314.850018)
		(end 27.957526 -314.726828)
		(width 0.1651)
		(layer "In5.Cu")
		(net "P5E_PEX0_STN7_RX_DN<119>")
	)
	(segment
		(start 27.77617 -385.59359)
		(end 27.285696 -385.103116)
		(width 0.1651)
		(layer "In5.Cu")
		(net "P5E_PEX0_STN7_RX_DN<119>")
	)
	(segment
		(start 37.115242 -308.249828)
		(end 36.849812 -308.249828)
		(width 0.1143)
		(layer "In5.Cu")
		(net "P5E_PEX0_STN7_RX_DN<119>")
	)
	(segment
		(start 27.677618 -341.98433)
		(end 26.603452 -331.076808)
		(width 0.1651)
		(layer "In5.Cu")
		(net "P5E_PEX0_STN7_RX_DN<119>")
	)
	(segment
		(start 32.231076 -309.991252)
		(end 32.572452 -309.649876)
		(width 0.1651)
		(layer "In5.Cu")
		(net "P5E_PEX0_STN7_RX_DN<119>")
	)
	(segment
		(start 31.731966 -310.490362)
		(end 31.731966 -310.332374)
		(width 0.1651)
		(layer "In5.Cu")
		(net "P5E_PEX0_STN7_RX_DN<119>")
	)
	(segment
		(start 44.459144 -396.491968)
		(end 43.405552 -393.94765)
		(width 0.1651)
		(layer "In5.Cu")
		(net "P5E_PEX0_STN7_RX_DN<119>")
	)
	(segment
		(start 27.308302 -315.698378)
		(end 27.583384 -315.286644)
		(width 0.1651)
		(layer "In5.Cu")
		(net "P5E_PEX0_STN7_RX_DN<119>")
	)
	(segment
		(start 27.677618 -357.775256)
		(end 27.677618 -341.98433)
		(width 0.1651)
		(layer "In5.Cu")
		(net "P5E_PEX0_STN7_RX_DN<119>")
	)
	(segment
		(start 43.405552 -393.94765)
		(end 27.77617 -385.59359)
		(width 0.1651)
		(layer "In5.Cu")
		(net "P5E_PEX0_STN7_RX_DN<119>")
	)
	(segment
		(start 26.884376 -384.13436)
		(end 26.884376 -369.925346)
		(width 0.1651)
		(layer "In5.Cu")
		(net "P5E_PEX0_STN7_RX_DN<119>")
	)
	(segment
		(start 30.549596 -311.672732)
		(end 30.891226 -311.331102)
		(width 0.1651)
		(layer "In5.Cu")
		(net "P5E_PEX0_STN7_RX_DN<119>")
	)
	(segment
		(start 35.634168 -307.870098)
		(end 37.115242 -307.870098)
		(width 0.1143)
		(layer "In5.Cu")
		(net "P5E_PEX0_STN7_RX_DN<119>")
	)
	(segment
		(start 27.33294 -315.821568)
		(end 27.308302 -315.698378)
		(width 0.1651)
		(layer "In5.Cu")
		(net "P5E_PEX0_STN7_RX_DN<119>")
	)
	(segment
		(start 25.375616 -318.59093)
		(end 26.93416 -316.258194)
		(width 0.1651)
		(layer "In5.Cu")
		(net "P5E_PEX0_STN7_RX_DN<119>")
	)
	(segment
		(start 30.391608 -311.672732)
		(end 30.549596 -311.672732)
		(width 0.1651)
		(layer "In5.Cu")
		(net "P5E_PEX0_STN7_RX_DN<119>")
	)
	(segment
		(start 29.205682 -312.858658)
		(end 30.391608 -311.672732)
		(width 0.1651)
		(layer "In5.Cu")
		(net "P5E_PEX0_STN7_RX_DN<119>")
	)
	(segment
		(start 28.232608 -314.315094)
		(end 28.355798 -314.290456)
		(width 0.1651)
		(layer "In5.Cu")
		(net "P5E_PEX0_STN7_RX_DN<119>")
	)
	(segment
		(start 37.115242 -307.870098)
		(end 37.229542 -307.984398)
		(width 0.1143)
		(layer "In5.Cu")
		(net "P5E_PEX0_STN7_RX_DN<119>")
	)
	(segment
		(start 32.572452 -309.649876)
		(end 32.572452 -309.491888)
		(width 0.1651)
		(layer "In5.Cu")
		(net "P5E_PEX0_STN7_RX_DN<119>")
	)
	(segment
		(start 37.229542 -308.135528)
		(end 37.115242 -308.249828)
		(width 0.1143)
		(layer "In5.Cu")
		(net "P5E_PEX0_STN7_RX_DN<119>")
	)
	(segment
		(start 35.56 -307.915818)
		(end 35.588448 -307.915818)
		(width 0.1143)
		(layer "In5.Cu")
		(net "P5E_PEX0_STN7_RX_DN<119>")
	)
	(segment
		(start 31.731966 -310.332374)
		(end 32.073088 -309.991252)
		(width 0.1651)
		(layer "In5.Cu")
		(net "P5E_PEX0_STN7_RX_DN<119>")
	)
	(segment
		(start 27.706574 -315.26226)
		(end 27.982164 -314.850018)
		(width 0.1651)
		(layer "In5.Cu")
		(net "P5E_PEX0_STN7_RX_DN<119>")
	)
	(segment
		(start 32.572452 -309.491888)
		(end 33.712404 -308.351936)
		(width 0.1651)
		(layer "In5.Cu")
		(net "P5E_PEX0_STN7_RX_DN<119>")
	)
	(segment
		(start 43.935904 -410.080968)
		(end 44.459144 -409.557728)
		(width 0.1651)
		(layer "In5.Cu")
		(net "P5E_PEX0_STN7_RX_DN<119>")
	)
	(segment
		(start 27.583384 -315.286644)
		(end 27.706574 -315.26226)
		(width 0.1651)
		(layer "In5.Cu")
		(net "P5E_PEX0_STN7_RX_DN<119>")
	)
	(segment
		(start 30.891226 -311.173114)
		(end 31.232348 -310.831992)
		(width 0.1651)
		(layer "In5.Cu")
		(net "P5E_PEX0_STN7_RX_DN<119>")
	)
	(segment
		(start 27.282902 -361.810808)
		(end 27.675078 -357.828342)
		(width 0.1651)
		(layer "In5.Cu")
		(net "P5E_PEX0_STN7_RX_DN<119>")
	)
	(segment
		(start 28.60675 -313.755024)
		(end 29.205682 -312.858658)
		(width 0.1651)
		(layer "In5.Cu")
		(net "P5E_PEX0_STN7_RX_DN<119>")
	)
	(segment
		(start 30.891226 -311.331102)
		(end 30.891226 -311.173114)
		(width 0.1651)
		(layer "In5.Cu")
		(net "P5E_PEX0_STN7_RX_DN<119>")
	)
	(segment
		(start 28.631388 -313.878468)
		(end 28.60675 -313.755024)
		(width 0.1651)
		(layer "In5.Cu")
		(net "P5E_PEX0_STN7_RX_DN<119>")
	)
	(segment
		(start 43.437048 -410.080968)
		(end 43.935904 -410.080968)
		(width 0.1651)
		(layer "In5.Cu")
		(net "P5E_PEX0_STN7_RX_DN<119>")
	)
	(segment
		(start 26.603452 -331.076808)
		(end 24.817324 -322.097654)
		(width 0.1651)
		(layer "In5.Cu")
		(net "P5E_PEX0_STN7_RX_DN<119>")
	)
	(segment
		(start 24.817324 -319.938654)
		(end 25.375616 -318.59093)
		(width 0.1651)
		(layer "In5.Cu")
		(net "P5E_PEX0_STN7_RX_DN<119>")
	)
	(segment
		(start 27.05735 -316.23381)
		(end 27.33294 -315.821568)
		(width 0.1651)
		(layer "In5.Cu")
		(net "P5E_PEX0_STN7_RX_DN<119>")
	)
	(segment
		(start 27.957526 -314.726828)
		(end 28.232608 -314.315094)
		(width 0.1651)
		(layer "In5.Cu")
		(net "P5E_PEX0_STN7_RX_DN<119>")
	)
	(segment
		(start 43.310048 -410.589984)
		(end 43.310048 -410.207968)
		(width 0.1651)
		(layer "In5.Cu")
		(net "P5E_PEX0_STN7_RX_DN<119>")
	)
	(segment
		(start 31.232348 -310.831992)
		(end 31.390336 -310.831992)
		(width 0.1651)
		(layer "In5.Cu")
		(net "P5E_PEX0_STN7_RX_DN<119>")
	)
	(segment
		(start 27.675078 -357.828342)
		(end 27.677618 -357.775256)
		(width 0.1651)
		(layer "In5.Cu")
		(net "P5E_PEX0_STN7_RX_DN<119>")
	)
	(segment
		(start 26.884376 -369.925346)
		(end 27.282902 -361.810808)
		(width 0.1651)
		(layer "In5.Cu")
		(net "P5E_PEX0_STN7_RX_DN<119>")
	)
	(segment
		(start 32.073088 -309.991252)
		(end 32.231076 -309.991252)
		(width 0.1651)
		(layer "In5.Cu")
		(net "P5E_PEX0_STN7_RX_DN<119>")
	)
	(segment
		(start 37.229542 -307.984398)
		(end 37.229542 -308.135528)
		(width 0.1143)
		(layer "In5.Cu")
		(net "P5E_PEX0_STN7_RX_DN<119>")
	)
	(segment
		(start 28.355798 -314.290456)
		(end 28.631388 -313.878468)
		(width 0.1651)
		(layer "In5.Cu")
		(net "P5E_PEX0_STN7_RX_DN<119>")
	)
	(segment
		(start 26.93416 -316.258194)
		(end 27.05735 -316.23381)
		(width 0.1651)
		(layer "In5.Cu")
		(net "P5E_PEX0_STN7_RX_DN<119>")
	)
	(segment
		(start 44.459144 -409.557728)
		(end 44.459144 -396.491968)
		(width 0.1651)
		(layer "In5.Cu")
		(net "P5E_PEX0_STN7_RX_DN<119>")
	)
	(segment
		(start 27.285696 -385.103116)
		(end 26.884376 -384.13436)
		(width 0.1651)
		(layer "In5.Cu")
		(net "P5E_PEX0_STN7_RX_DN<119>")
	)
	(segment
		(start 34.765488 -307.915818)
		(end 35.56 -307.915818)
		(width 0.1651)
		(layer "In5.Cu")
		(net "P5E_PEX0_STN7_RX_DN<119>")
	)
	(segment
		(start 331.725524 -350.685354)
		(end 331.725524 -351.316798)
		(width 0.13462)
		(layer "F.Cu")
		(net "P5E_PEX2_STN5_TX_C_DN<89>")
	)
	(segment
		(start 331.725524 -351.316798)
		(end 332.020164 -351.611438)
		(width 0.13462)
		(layer "F.Cu")
		(net "P5E_PEX2_STN5_TX_C_DN<89>")
	)
	(segment
		(start 332.045564 -350.365314)
		(end 331.725524 -350.685354)
		(width 0.13462)
		(layer "F.Cu")
		(net "P5E_PEX2_STN5_TX_C_DN<89>")
	)
	(segment
		(start 331.729334 -352.473006)
		(end 330.174854 -354.027486)
		(width 0.1651)
		(layer "In7.Cu")
		(net "P5E_PEX2_STN5_TX_C_DN<89>")
	)
	(segment
		(start 330.174854 -358.28097)
		(end 334.815942 -368.412776)
		(width 0.1651)
		(layer "In7.Cu")
		(net "P5E_PEX2_STN5_TX_C_DN<89>")
	)
	(segment
		(start 333.81696 -380.181104)
		(end 333.68996 -380.308104)
		(width 0.1651)
		(layer "In7.Cu")
		(net "P5E_PEX2_STN5_TX_C_DN<89>")
	)
	(segment
		(start 331.729334 -351.902268)
		(end 331.729334 -352.473006)
		(width 0.1651)
		(layer "In7.Cu")
		(net "P5E_PEX2_STN5_TX_C_DN<89>")
	)
	(segment
		(start 330.174854 -354.027486)
		(end 330.174854 -358.28097)
		(width 0.1651)
		(layer "In7.Cu")
		(net "P5E_PEX2_STN5_TX_C_DN<89>")
	)
	(segment
		(start 334.364076 -380.181104)
		(end 333.81696 -380.181104)
		(width 0.1651)
		(layer "In7.Cu")
		(net "P5E_PEX2_STN5_TX_C_DN<89>")
	)
	(segment
		(start 333.68996 -380.308104)
		(end 333.68996 -380.69012)
		(width 0.1651)
		(layer "In7.Cu")
		(net "P5E_PEX2_STN5_TX_C_DN<89>")
	)
	(segment
		(start 332.020164 -351.611438)
		(end 331.729334 -351.902268)
		(width 0.1651)
		(layer "In7.Cu")
		(net "P5E_PEX2_STN5_TX_C_DN<89>")
	)
	(segment
		(start 334.815942 -379.729238)
		(end 334.364076 -380.181104)
		(width 0.1651)
		(layer "In7.Cu")
		(net "P5E_PEX2_STN5_TX_C_DN<89>")
	)
	(segment
		(start 334.815942 -368.412776)
		(end 334.815942 -379.729238)
		(width 0.1651)
		(layer "In7.Cu")
		(net "P5E_PEX2_STN5_TX_C_DN<89>")
	)
	(segment
		(start 392.9253 -355.978206)
		(end 393.244832 -355.658674)
		(width 0.13462)
		(layer "F.Cu")
		(net "P5E_PEX3_STN5_TX_DP<83>")
	)
	(segment
		(start 393.244832 -355.658674)
		(end 393.244832 -355.026214)
		(width 0.13462)
		(layer "F.Cu")
		(net "P5E_PEX3_STN5_TX_DP<83>")
	)
	(segment
		(start 393.244832 -355.026214)
		(end 392.9507 -354.732082)
		(width 0.13462)
		(layer "F.Cu")
		(net "P5E_PEX3_STN5_TX_DP<83>")
	)
	(segment
		(start 393.24153 -353.814126)
		(end 394.79601 -352.259646)
		(width 0.1651)
		(layer "In7.Cu")
		(net "P5E_PEX3_STN5_TX_DP<83>")
	)
	(segment
		(start 392.9507 -354.732082)
		(end 393.24153 -354.441252)
		(width 0.1651)
		(layer "In7.Cu")
		(net "P5E_PEX3_STN5_TX_DP<83>")
	)
	(segment
		(start 406.952704 -327.921366)
		(end 408.225752 -326.016366)
		(width 0.1651)
		(layer "In7.Cu")
		(net "P5E_PEX3_STN5_TX_DP<83>")
	)
	(segment
		(start 409.849828 -313.265312)
		(end 409.849828 -312.999882)
		(width 0.1143)
		(layer "In7.Cu")
		(net "P5E_PEX3_STN5_TX_DP<83>")
	)
	(segment
		(start 409.233878 -319.9892)
		(end 409.233878 -319.960752)
		(width 0.1143)
		(layer "In7.Cu")
		(net "P5E_PEX3_STN5_TX_DP<83>")
	)
	(segment
		(start 408.225752 -326.016366)
		(end 409.233878 -323.582538)
		(width 0.1651)
		(layer "In7.Cu")
		(net "P5E_PEX3_STN5_TX_DP<83>")
	)
	(segment
		(start 394.79601 -352.259646)
		(end 394.79601 -341.68334)
		(width 0.1651)
		(layer "In7.Cu")
		(net "P5E_PEX3_STN5_TX_DP<83>")
	)
	(segment
		(start 400.91614 -334.755236)
		(end 406.952704 -327.921366)
		(width 0.1651)
		(layer "In7.Cu")
		(net "P5E_PEX3_STN5_TX_DP<83>")
	)
	(segment
		(start 400.915378 -334.755236)
		(end 400.91614 -334.755236)
		(width 0.1651)
		(layer "In7.Cu")
		(net "P5E_PEX3_STN5_TX_DP<83>")
	)
	(segment
		(start 393.24153 -354.441252)
		(end 393.24153 -353.814126)
		(width 0.1651)
		(layer "In7.Cu")
		(net "P5E_PEX3_STN5_TX_DP<83>")
	)
	(segment
		(start 409.279598 -313.605418)
		(end 409.505404 -313.379612)
		(width 0.1143)
		(layer "In7.Cu")
		(net "P5E_PEX3_STN5_TX_DP<83>")
	)
	(segment
		(start 409.279598 -319.915032)
		(end 409.279598 -313.605418)
		(width 0.1143)
		(layer "In7.Cu")
		(net "P5E_PEX3_STN5_TX_DP<83>")
	)
	(segment
		(start 409.505404 -313.379612)
		(end 409.735528 -313.379612)
		(width 0.1143)
		(layer "In7.Cu")
		(net "P5E_PEX3_STN5_TX_DP<83>")
	)
	(segment
		(start 409.735528 -313.379612)
		(end 409.849828 -313.265312)
		(width 0.1143)
		(layer "In7.Cu")
		(net "P5E_PEX3_STN5_TX_DP<83>")
	)
	(segment
		(start 394.79601 -341.68334)
		(end 400.915378 -334.755236)
		(width 0.1651)
		(layer "In7.Cu")
		(net "P5E_PEX3_STN5_TX_DP<83>")
	)
	(segment
		(start 409.233878 -323.582538)
		(end 409.233878 -319.9892)
		(width 0.1651)
		(layer "In7.Cu")
		(net "P5E_PEX3_STN5_TX_DP<83>")
	)
	(segment
		(start 409.233878 -319.960752)
		(end 409.279598 -319.915032)
		(width 0.1143)
		(layer "In7.Cu")
		(net "P5E_PEX3_STN5_TX_DP<83>")
	)
	(segment
		(start 27.395678 -341.9983)
		(end 26.324052 -331.11821)
		(width 0.1651)
		(layer "In5.Cu")
		(net "P5E_PEX0_STN7_RX_DP<119>")
	)
	(segment
		(start 27.395678 -357.768398)
		(end 27.395678 -341.9983)
		(width 0.1651)
		(layer "In5.Cu")
		(net "P5E_PEX0_STN7_RX_DP<119>")
	)
	(segment
		(start 34.709354 -307.633878)
		(end 35.56 -307.633878)
		(width 0.1651)
		(layer "In5.Cu")
		(net "P5E_PEX0_STN7_RX_DP<119>")
	)
	(segment
		(start 37.194236 -307.679598)
		(end 37.420042 -307.905404)
		(width 0.1143)
		(layer "In5.Cu")
		(net "P5E_PEX0_STN7_RX_DP<119>")
	)
	(segment
		(start 27.606244 -385.822698)
		(end 27.046682 -385.262882)
		(width 0.1651)
		(layer "In5.Cu")
		(net "P5E_PEX0_STN7_RX_DP<119>")
	)
	(segment
		(start 37.420042 -307.905404)
		(end 37.420042 -308.135528)
		(width 0.1143)
		(layer "In5.Cu")
		(net "P5E_PEX0_STN7_RX_DP<119>")
	)
	(segment
		(start 28.986734 -312.678826)
		(end 33.552638 -308.112922)
		(width 0.1651)
		(layer "In5.Cu")
		(net "P5E_PEX0_STN7_RX_DP<119>")
	)
	(segment
		(start 43.310048 -409.290012)
		(end 43.310048 -409.672028)
		(width 0.1651)
		(layer "In5.Cu")
		(net "P5E_PEX0_STN7_RX_DP<119>")
	)
	(segment
		(start 24.535384 -319.88252)
		(end 25.12568 -318.457326)
		(width 0.1651)
		(layer "In5.Cu")
		(net "P5E_PEX0_STN7_RX_DP<119>")
	)
	(segment
		(start 37.534342 -308.249828)
		(end 37.799772 -308.249828)
		(width 0.1143)
		(layer "In5.Cu")
		(net "P5E_PEX0_STN7_RX_DP<119>")
	)
	(segment
		(start 33.552638 -308.112922)
		(end 34.709354 -307.633878)
		(width 0.1651)
		(layer "In5.Cu")
		(net "P5E_PEX0_STN7_RX_DP<119>")
	)
	(segment
		(start 43.183556 -394.148818)
		(end 27.606244 -385.822698)
		(width 0.1651)
		(layer "In5.Cu")
		(net "P5E_PEX0_STN7_RX_DP<119>")
	)
	(segment
		(start 26.324052 -331.11821)
		(end 24.535384 -322.125594)
		(width 0.1651)
		(layer "In5.Cu")
		(net "P5E_PEX0_STN7_RX_DP<119>")
	)
	(segment
		(start 37.420042 -308.135528)
		(end 37.534342 -308.249828)
		(width 0.1143)
		(layer "In5.Cu")
		(net "P5E_PEX0_STN7_RX_DP<119>")
	)
	(segment
		(start 44.177204 -396.548102)
		(end 43.183556 -394.148818)
		(width 0.1651)
		(layer "In5.Cu")
		(net "P5E_PEX0_STN7_RX_DP<119>")
	)
	(segment
		(start 26.602436 -384.190494)
		(end 26.602436 -369.918234)
		(width 0.1651)
		(layer "In5.Cu")
		(net "P5E_PEX0_STN7_RX_DP<119>")
	)
	(segment
		(start 35.588448 -307.633878)
		(end 35.634168 -307.679598)
		(width 0.1143)
		(layer "In5.Cu")
		(net "P5E_PEX0_STN7_RX_DP<119>")
	)
	(segment
		(start 43.310048 -409.672028)
		(end 43.437048 -409.799028)
		(width 0.1651)
		(layer "In5.Cu")
		(net "P5E_PEX0_STN7_RX_DP<119>")
	)
	(segment
		(start 24.535384 -322.125594)
		(end 24.535384 -319.88252)
		(width 0.1651)
		(layer "In5.Cu")
		(net "P5E_PEX0_STN7_RX_DP<119>")
	)
	(segment
		(start 27.393646 -357.807768)
		(end 27.395678 -357.768398)
		(width 0.1651)
		(layer "In5.Cu")
		(net "P5E_PEX0_STN7_RX_DP<119>")
	)
	(segment
		(start 25.12568 -318.457326)
		(end 28.986734 -312.678826)
		(width 0.1651)
		(layer "In5.Cu")
		(net "P5E_PEX0_STN7_RX_DP<119>")
	)
	(segment
		(start 26.602436 -369.918234)
		(end 27.00147 -361.78998)
		(width 0.1651)
		(layer "In5.Cu")
		(net "P5E_PEX0_STN7_RX_DP<119>")
	)
	(segment
		(start 35.634168 -307.679598)
		(end 37.194236 -307.679598)
		(width 0.1143)
		(layer "In5.Cu")
		(net "P5E_PEX0_STN7_RX_DP<119>")
	)
	(segment
		(start 27.046682 -385.262882)
		(end 26.602436 -384.190494)
		(width 0.1651)
		(layer "In5.Cu")
		(net "P5E_PEX0_STN7_RX_DP<119>")
	)
	(segment
		(start 44.177204 -409.440888)
		(end 44.177204 -396.548102)
		(width 0.1651)
		(layer "In5.Cu")
		(net "P5E_PEX0_STN7_RX_DP<119>")
	)
	(segment
		(start 27.00147 -361.78998)
		(end 27.393646 -357.807768)
		(width 0.1651)
		(layer "In5.Cu")
		(net "P5E_PEX0_STN7_RX_DP<119>")
	)
	(segment
		(start 43.437048 -409.799028)
		(end 43.819064 -409.799028)
		(width 0.1651)
		(layer "In5.Cu")
		(net "P5E_PEX0_STN7_RX_DP<119>")
	)
	(segment
		(start 35.56 -307.633878)
		(end 35.588448 -307.633878)
		(width 0.1143)
		(layer "In5.Cu")
		(net "P5E_PEX0_STN7_RX_DP<119>")
	)
	(segment
		(start 43.819064 -409.799028)
		(end 44.177204 -409.440888)
		(width 0.1651)
		(layer "In5.Cu")
		(net "P5E_PEX0_STN7_RX_DP<119>")
	)
	(segment
		(start 284.010862 -357.46309)
		(end 284.305502 -357.75773)
		(width 0.13462)
		(layer "F.Cu")
		(net "P5E_PEX2_STN7_TX_C_DN<120>")
	)
	(segment
		(start 284.330902 -356.511606)
		(end 284.010862 -356.831646)
		(width 0.13462)
		(layer "F.Cu")
		(net "P5E_PEX2_STN7_TX_C_DN<120>")
	)
	(segment
		(start 284.010862 -356.831646)
		(end 284.010862 -357.46309)
		(width 0.13462)
		(layer "F.Cu")
		(net "P5E_PEX2_STN7_TX_C_DN<120>")
	)
	(segment
		(start 284.305502 -357.75773)
		(end 284.014672 -358.04856)
		(width 0.1651)
		(layer "In7.Cu")
		(net "P5E_PEX2_STN7_TX_C_DN<120>")
	)
	(segment
		(start 284.014672 -358.6988)
		(end 288.615882 -368.6302)
		(width 0.1651)
		(layer "In7.Cu")
		(net "P5E_PEX2_STN7_TX_C_DN<120>")
	)
	(segment
		(start 288.164016 -375.181114)
		(end 287.6169 -375.181114)
		(width 0.1651)
		(layer "In7.Cu")
		(net "P5E_PEX2_STN7_TX_C_DN<120>")
	)
	(segment
		(start 284.014672 -358.04856)
		(end 284.014672 -358.6988)
		(width 0.1651)
		(layer "In7.Cu")
		(net "P5E_PEX2_STN7_TX_C_DN<120>")
	)
	(segment
		(start 287.6169 -375.181114)
		(end 287.4899 -375.308114)
		(width 0.1651)
		(layer "In7.Cu")
		(net "P5E_PEX2_STN7_TX_C_DN<120>")
	)
	(segment
		(start 287.4899 -375.308114)
		(end 287.4899 -375.69013)
		(width 0.1651)
		(layer "In7.Cu")
		(net "P5E_PEX2_STN7_TX_C_DN<120>")
	)
	(segment
		(start 288.615882 -368.6302)
		(end 288.615882 -374.729248)
		(width 0.1651)
		(layer "In7.Cu")
		(net "P5E_PEX2_STN7_TX_C_DN<120>")
	)
	(segment
		(start 288.615882 -374.729248)
		(end 288.164016 -375.181114)
		(width 0.1651)
		(layer "In7.Cu")
		(net "P5E_PEX2_STN7_TX_C_DN<120>")
	)
	(segment
		(start 71.562722 -345.465146)
		(end 71.268082 -345.170506)
		(width 0.13462)
		(layer "F.Cu")
		(net "P5E_PEX0_STN5_TX_C_DN<84>")
	)
	(segment
		(start 71.268082 -344.539062)
		(end 71.588122 -344.219022)
		(width 0.13462)
		(layer "F.Cu")
		(net "P5E_PEX0_STN5_TX_C_DN<84>")
	)
	(segment
		(start 71.268082 -345.170506)
		(end 71.268082 -344.539062)
		(width 0.13462)
		(layer "F.Cu")
		(net "P5E_PEX0_STN5_TX_C_DN<84>")
	)
	(segment
		(start 81.884266 -394.311886)
		(end 79.941674 -392.369294)
		(width 0.1651)
		(layer "In7.Cu")
		(net "P5E_PEX0_STN5_TX_C_DN<84>")
	)
	(segment
		(start 79.941674 -392.369294)
		(end 70.415912 -388.423658)
		(width 0.1651)
		(layer "In7.Cu")
		(net "P5E_PEX0_STN5_TX_C_DN<84>")
	)
	(segment
		(start 71.271892 -345.755976)
		(end 71.562722 -345.465146)
		(width 0.1651)
		(layer "In7.Cu")
		(net "P5E_PEX0_STN5_TX_C_DN<84>")
	)
	(segment
		(start 70.415912 -388.423658)
		(end 68.768468 -386.776214)
		(width 0.1651)
		(layer "In7.Cu")
		(net "P5E_PEX0_STN5_TX_C_DN<84>")
	)
	(segment
		(start 71.271892 -346.474542)
		(end 71.271892 -345.755976)
		(width 0.1651)
		(layer "In7.Cu")
		(net "P5E_PEX0_STN5_TX_C_DN<84>")
	)
	(segment
		(start 80.710024 -405.589994)
		(end 80.710024 -405.207978)
		(width 0.1651)
		(layer "In7.Cu")
		(net "P5E_PEX0_STN5_TX_C_DN<84>")
	)
	(segment
		(start 81.884266 -404.486872)
		(end 81.884266 -394.311886)
		(width 0.1651)
		(layer "In7.Cu")
		(net "P5E_PEX0_STN5_TX_C_DN<84>")
	)
	(segment
		(start 69.717412 -348.029022)
		(end 71.271892 -346.474542)
		(width 0.1651)
		(layer "In7.Cu")
		(net "P5E_PEX0_STN5_TX_C_DN<84>")
	)
	(segment
		(start 69.717412 -358.188514)
		(end 69.717412 -348.029022)
		(width 0.1651)
		(layer "In7.Cu")
		(net "P5E_PEX0_STN5_TX_C_DN<84>")
	)
	(segment
		(start 68.014342 -384.955542)
		(end 68.014342 -378.992638)
		(width 0.1651)
		(layer "In7.Cu")
		(net "P5E_PEX0_STN5_TX_C_DN<84>")
	)
	(segment
		(start 68.014342 -378.992638)
		(end 67.854576 -366.709452)
		(width 0.1651)
		(layer "In7.Cu")
		(net "P5E_PEX0_STN5_TX_C_DN<84>")
	)
	(segment
		(start 80.710024 -405.207978)
		(end 80.837024 -405.080978)
		(width 0.1651)
		(layer "In7.Cu")
		(net "P5E_PEX0_STN5_TX_C_DN<84>")
	)
	(segment
		(start 68.768468 -386.776214)
		(end 68.014342 -384.955542)
		(width 0.1651)
		(layer "In7.Cu")
		(net "P5E_PEX0_STN5_TX_C_DN<84>")
	)
	(segment
		(start 80.837024 -405.080978)
		(end 81.29016 -405.080978)
		(width 0.1651)
		(layer "In7.Cu")
		(net "P5E_PEX0_STN5_TX_C_DN<84>")
	)
	(segment
		(start 81.29016 -405.080978)
		(end 81.884266 -404.486872)
		(width 0.1651)
		(layer "In7.Cu")
		(net "P5E_PEX0_STN5_TX_C_DN<84>")
	)
	(segment
		(start 67.854576 -366.709452)
		(end 69.717412 -358.188514)
		(width 0.1651)
		(layer "In7.Cu")
		(net "P5E_PEX0_STN5_TX_C_DN<84>")
	)
	(segment
		(start 393.307316 -28.8163)
		(end 392.682476 -28.8163)
		(width 0.13462)
		(layer "F.Cu")
		(net "P5E_PEX3_STN2_TX_DP<40>")
	)
	(segment
		(start 392.682476 -28.8163)
		(end 392.359134 -29.139642)
		(width 0.13462)
		(layer "F.Cu")
		(net "P5E_PEX3_STN2_TX_DP<40>")
	)
	(segment
		(start 393.605258 -29.114242)
		(end 393.307316 -28.8163)
		(width 0.13462)
		(layer "F.Cu")
		(net "P5E_PEX3_STN2_TX_DP<40>")
	)
	(segment
		(start 398.829784 -271.473168)
		(end 398.829784 -280.10485)
		(width 0.1143)
		(layer "In11.Cu")
		(net "P5E_PEX3_STN2_TX_DP<40>")
	)
	(segment
		(start 412.838138 -69.570346)
		(end 405.7904 -119.281702)
		(width 0.1651)
		(layer "In11.Cu")
		(net "P5E_PEX3_STN2_TX_DP<40>")
	)
	(segment
		(start 405.7904 -119.281702)
		(end 404.448772 -135.243824)
		(width 0.1651)
		(layer "In11.Cu")
		(net "P5E_PEX3_STN2_TX_DP<40>")
	)
	(segment
		(start 399.213578 -31.231332)
		(end 399.339308 -31.231078)
		(width 0.1651)
		(layer "In11.Cu")
		(net "P5E_PEX3_STN2_TX_DP<40>")
	)
	(segment
		(start 398.032478 -29.93263)
		(end 398.032986 -30.05836)
		(width 0.1651)
		(layer "In11.Cu")
		(net "P5E_PEX3_STN2_TX_DP<40>")
	)
	(segment
		(start 398.784064 -271.113758)
		(end 398.784064 -271.399)
		(width 0.1651)
		(layer "In11.Cu")
		(net "P5E_PEX3_STN2_TX_DP<40>")
	)
	(segment
		(start 412.60141 -49.912524)
		(end 413.263842 -60.607194)
		(width 0.1651)
		(layer "In11.Cu")
		(net "P5E_PEX3_STN2_TX_DP<40>")
	)
	(segment
		(start 399.285714 -280.319988)
		(end 399.400014 -280.434288)
		(width 0.1143)
		(layer "In11.Cu")
		(net "P5E_PEX3_STN2_TX_DP<40>")
	)
	(segment
		(start 401.882864 -34.872168)
		(end 411.603444 -47.064676)
		(width 0.1651)
		(layer "In11.Cu")
		(net "P5E_PEX3_STN2_TX_DP<40>")
	)
	(segment
		(start 393.896088 -28.823412)
		(end 396.18285 -28.823412)
		(width 0.1651)
		(layer "In11.Cu")
		(net "P5E_PEX3_STN2_TX_DP<40>")
	)
	(segment
		(start 399.400014 -280.434288)
		(end 399.400014 -280.699718)
		(width 0.1143)
		(layer "In11.Cu")
		(net "P5E_PEX3_STN2_TX_DP<40>")
	)
	(segment
		(start 400.147282 -32.033972)
		(end 401.882864 -34.872168)
		(width 0.1651)
		(layer "In11.Cu")
		(net "P5E_PEX3_STN2_TX_DP<40>")
	)
	(segment
		(start 399.044922 -280.319988)
		(end 399.285714 -280.319988)
		(width 0.1143)
		(layer "In11.Cu")
		(net "P5E_PEX3_STN2_TX_DP<40>")
	)
	(segment
		(start 398.510252 -30.407356)
		(end 398.861534 -30.756352)
		(width 0.1651)
		(layer "In11.Cu")
		(net "P5E_PEX3_STN2_TX_DP<40>")
	)
	(segment
		(start 396.18285 -28.823412)
		(end 397.445484 -29.349192)
		(width 0.1651)
		(layer "In11.Cu")
		(net "P5E_PEX3_STN2_TX_DP<40>")
	)
	(segment
		(start 411.603444 -47.064676)
		(end 412.60141 -49.912524)
		(width 0.1651)
		(layer "In11.Cu")
		(net "P5E_PEX3_STN2_TX_DP<40>")
	)
	(segment
		(start 413.263842 -60.607194)
		(end 412.838138 -69.570346)
		(width 0.1651)
		(layer "In11.Cu")
		(net "P5E_PEX3_STN2_TX_DP<40>")
	)
	(segment
		(start 397.445484 -29.349192)
		(end 398.032478 -29.93263)
		(width 0.1651)
		(layer "In11.Cu")
		(net "P5E_PEX3_STN2_TX_DP<40>")
	)
	(segment
		(start 399.339308 -31.231078)
		(end 400.147282 -32.033972)
		(width 0.1651)
		(layer "In11.Cu")
		(net "P5E_PEX3_STN2_TX_DP<40>")
	)
	(segment
		(start 398.861534 -30.756352)
		(end 398.861788 -30.882082)
		(width 0.1651)
		(layer "In11.Cu")
		(net "P5E_PEX3_STN2_TX_DP<40>")
	)
	(segment
		(start 398.384522 -30.40761)
		(end 398.510252 -30.407356)
		(width 0.1651)
		(layer "In11.Cu")
		(net "P5E_PEX3_STN2_TX_DP<40>")
	)
	(segment
		(start 398.146016 -252.613668)
		(end 398.419828 -266.03325)
		(width 0.1651)
		(layer "In11.Cu")
		(net "P5E_PEX3_STN2_TX_DP<40>")
	)
	(segment
		(start 404.448772 -135.243824)
		(end 398.146016 -252.613668)
		(width 0.1651)
		(layer "In11.Cu")
		(net "P5E_PEX3_STN2_TX_DP<40>")
	)
	(segment
		(start 398.419828 -266.03325)
		(end 398.7927 -269.820898)
		(width 0.1651)
		(layer "In11.Cu")
		(net "P5E_PEX3_STN2_TX_DP<40>")
	)
	(segment
		(start 393.605258 -29.114242)
		(end 393.896088 -28.823412)
		(width 0.1651)
		(layer "In11.Cu")
		(net "P5E_PEX3_STN2_TX_DP<40>")
	)
	(segment
		(start 398.7927 -271.105122)
		(end 398.784064 -271.113758)
		(width 0.1651)
		(layer "In11.Cu")
		(net "P5E_PEX3_STN2_TX_DP<40>")
	)
	(segment
		(start 398.829784 -280.10485)
		(end 399.044922 -280.319988)
		(width 0.1143)
		(layer "In11.Cu")
		(net "P5E_PEX3_STN2_TX_DP<40>")
	)
	(segment
		(start 398.784064 -271.427448)
		(end 398.829784 -271.473168)
		(width 0.1143)
		(layer "In11.Cu")
		(net "P5E_PEX3_STN2_TX_DP<40>")
	)
	(segment
		(start 398.784064 -271.399)
		(end 398.784064 -271.427448)
		(width 0.1143)
		(layer "In11.Cu")
		(net "P5E_PEX3_STN2_TX_DP<40>")
	)
	(segment
		(start 398.032986 -30.05836)
		(end 398.384522 -30.40761)
		(width 0.1651)
		(layer "In11.Cu")
		(net "P5E_PEX3_STN2_TX_DP<40>")
	)
	(segment
		(start 398.861788 -30.882082)
		(end 399.213578 -31.231332)
		(width 0.1651)
		(layer "In11.Cu")
		(net "P5E_PEX3_STN2_TX_DP<40>")
	)
	(segment
		(start 398.7927 -269.820898)
		(end 398.7927 -271.105122)
		(width 0.1651)
		(layer "In11.Cu")
		(net "P5E_PEX3_STN2_TX_DP<40>")
	)
	(segment
		(start 23.281894 -315.376052)
		(end 24.312372 -313.197748)
		(width 0.1651)
		(layer "In5.Cu")
		(net "P5E_PEX0_STN7_RX_DP<116>")
	)
	(segment
		(start 18.05686 -351.582736)
		(end 18.05686 -341.918798)
		(width 0.1651)
		(layer "In5.Cu")
		(net "P5E_PEX0_STN7_RX_DP<116>")
	)
	(segment
		(start 37.577014 -395.550644)
		(end 37.272214 -394.814806)
		(width 0.1651)
		(layer "In5.Cu")
		(net "P5E_PEX0_STN7_RX_DP<116>")
	)
	(segment
		(start 26.63952 -308.843426)
		(end 27.34183 -308.14137)
		(width 0.1651)
		(layer "In5.Cu")
		(net "P5E_PEX0_STN7_RX_DP<116>")
	)
	(segment
		(start 29.450284 -306.032916)
		(end 31.063692 -305.364388)
		(width 0.1651)
		(layer "In5.Cu")
		(net "P5E_PEX0_STN7_RX_DP<116>")
	)
	(segment
		(start 33.518094 -392.260074)
		(end 25.769316 -388.11835)
		(width 0.1651)
		(layer "In5.Cu")
		(net "P5E_PEX0_STN7_RX_DP<116>")
	)
	(segment
		(start 37.577014 -408.28849)
		(end 37.577014 -395.550644)
		(width 0.1651)
		(layer "In5.Cu")
		(net "P5E_PEX0_STN7_RX_DP<116>")
	)
	(segment
		(start 39.320216 -305.055524)
		(end 39.320216 -305.285648)
		(width 0.1143)
		(layer "In5.Cu")
		(net "P5E_PEX0_STN7_RX_DP<116>")
	)
	(segment
		(start 37.132768 -394.67536)
		(end 33.518094 -392.260074)
		(width 0.1651)
		(layer "In5.Cu")
		(net "P5E_PEX0_STN7_RX_DP<116>")
	)
	(segment
		(start 24.312372 -313.197748)
		(end 26.63952 -308.843426)
		(width 0.1651)
		(layer "In5.Cu")
		(net "P5E_PEX0_STN7_RX_DP<116>")
	)
	(segment
		(start 37.272214 -394.814806)
		(end 37.132768 -394.67536)
		(width 0.1651)
		(layer "In5.Cu")
		(net "P5E_PEX0_STN7_RX_DP<116>")
	)
	(segment
		(start 20.848828 -326.095868)
		(end 21.700236 -319.195196)
		(width 0.1651)
		(layer "In5.Cu")
		(net "P5E_PEX0_STN7_RX_DP<116>")
	)
	(segment
		(start 18.05686 -341.918798)
		(end 20.848828 -326.095868)
		(width 0.1651)
		(layer "In5.Cu")
		(net "P5E_PEX0_STN7_RX_DP<116>")
	)
	(segment
		(start 37.166296 -408.699208)
		(end 37.577014 -408.28849)
		(width 0.1651)
		(layer "In5.Cu")
		(net "P5E_PEX0_STN7_RX_DP<116>")
	)
	(segment
		(start 39.320216 -305.285648)
		(end 39.434516 -305.399948)
		(width 0.1143)
		(layer "In5.Cu")
		(net "P5E_PEX0_STN7_RX_DP<116>")
	)
	(segment
		(start 31.063692 -305.364388)
		(end 33.98139 -304.783998)
		(width 0.1651)
		(layer "In5.Cu")
		(net "P5E_PEX0_STN7_RX_DP<116>")
	)
	(segment
		(start 33.98139 -304.783998)
		(end 35.56 -304.783998)
		(width 0.1651)
		(layer "In5.Cu")
		(net "P5E_PEX0_STN7_RX_DP<116>")
	)
	(segment
		(start 21.700236 -319.195196)
		(end 23.281894 -315.376052)
		(width 0.1651)
		(layer "In5.Cu")
		(net "P5E_PEX0_STN7_RX_DP<116>")
	)
	(segment
		(start 25.769316 -388.11835)
		(end 24.58466 -386.93344)
		(width 0.1651)
		(layer "In5.Cu")
		(net "P5E_PEX0_STN7_RX_DP<116>")
	)
	(segment
		(start 20.75688 -369.783868)
		(end 18.05686 -351.582736)
		(width 0.1651)
		(layer "In5.Cu")
		(net "P5E_PEX0_STN7_RX_DP<116>")
	)
	(segment
		(start 39.09441 -304.829718)
		(end 39.320216 -305.055524)
		(width 0.1143)
		(layer "In5.Cu")
		(net "P5E_PEX0_STN7_RX_DP<116>")
	)
	(segment
		(start 35.634168 -304.829718)
		(end 39.09441 -304.829718)
		(width 0.1143)
		(layer "In5.Cu")
		(net "P5E_PEX0_STN7_RX_DP<116>")
	)
	(segment
		(start 36.837112 -408.699208)
		(end 37.166296 -408.699208)
		(width 0.1651)
		(layer "In5.Cu")
		(net "P5E_PEX0_STN7_RX_DP<116>")
	)
	(segment
		(start 35.588448 -304.783998)
		(end 35.634168 -304.829718)
		(width 0.1143)
		(layer "In5.Cu")
		(net "P5E_PEX0_STN7_RX_DP<116>")
	)
	(segment
		(start 27.34183 -308.14137)
		(end 27.34183 -308.141116)
		(width 0.1651)
		(layer "In5.Cu")
		(net "P5E_PEX0_STN7_RX_DP<116>")
	)
	(segment
		(start 36.710112 -408.572208)
		(end 36.837112 -408.699208)
		(width 0.1651)
		(layer "In5.Cu")
		(net "P5E_PEX0_STN7_RX_DP<116>")
	)
	(segment
		(start 27.34183 -308.141116)
		(end 29.450284 -306.032916)
		(width 0.1651)
		(layer "In5.Cu")
		(net "P5E_PEX0_STN7_RX_DP<116>")
	)
	(segment
		(start 23.783544 -385.0005)
		(end 20.75688 -369.783868)
		(width 0.1651)
		(layer "In5.Cu")
		(net "P5E_PEX0_STN7_RX_DP<116>")
	)
	(segment
		(start 36.710112 -408.190192)
		(end 36.710112 -408.572208)
		(width 0.1651)
		(layer "In5.Cu")
		(net "P5E_PEX0_STN7_RX_DP<116>")
	)
	(segment
		(start 24.58466 -386.93344)
		(end 23.783544 -385.0005)
		(width 0.1651)
		(layer "In5.Cu")
		(net "P5E_PEX0_STN7_RX_DP<116>")
	)
	(segment
		(start 39.434516 -305.399948)
		(end 39.699946 -305.399948)
		(width 0.1143)
		(layer "In5.Cu")
		(net "P5E_PEX0_STN7_RX_DP<116>")
	)
	(segment
		(start 35.56 -304.783998)
		(end 35.588448 -304.783998)
		(width 0.1143)
		(layer "In5.Cu")
		(net "P5E_PEX0_STN7_RX_DP<116>")
	)
	(segment
		(start 159.646112 -356.831646)
		(end 159.966152 -356.511606)
		(width 0.13462)
		(layer "F.Cu")
		(net "P5E_PEX1_STN7_TX_C_DN<112>")
	)
	(segment
		(start 159.940752 -357.75773)
		(end 159.646112 -357.46309)
		(width 0.13462)
		(layer "F.Cu")
		(net "P5E_PEX1_STN7_TX_C_DN<112>")
	)
	(segment
		(start 159.646112 -357.46309)
		(end 159.646112 -356.831646)
		(width 0.13462)
		(layer "F.Cu")
		(net "P5E_PEX1_STN7_TX_C_DN<112>")
	)
	(segment
		(start 161.075116 -394.735558)
		(end 160.699196 -394.359638)
		(width 0.1651)
		(layer "In11.Cu")
		(net "P5E_PEX1_STN7_TX_C_DN<112>")
	)
	(segment
		(start 158.317692 -393.250674)
		(end 158.317692 -393.250928)
		(width 0.1651)
		(layer "In11.Cu")
		(net "P5E_PEX1_STN7_TX_C_DN<112>")
	)
	(segment
		(start 156.856176 -360.526838)
		(end 158.900368 -359.668572)
		(width 0.1651)
		(layer "In11.Cu")
		(net "P5E_PEX1_STN7_TX_C_DN<112>")
	)
	(segment
		(start 158.900368 -359.668572)
		(end 159.649922 -358.919018)
		(width 0.1651)
		(layer "In11.Cu")
		(net "P5E_PEX1_STN7_TX_C_DN<112>")
	)
	(segment
		(start 160.699196 -394.359638)
		(end 158.317692 -393.250674)
		(width 0.1651)
		(layer "In11.Cu")
		(net "P5E_PEX1_STN7_TX_C_DN<112>")
	)
	(segment
		(start 151.973534 -382.832356)
		(end 152.16124 -367.46561)
		(width 0.1651)
		(layer "In11.Cu")
		(net "P5E_PEX1_STN7_TX_C_DN<112>")
	)
	(segment
		(start 159.649922 -358.04856)
		(end 159.940752 -357.75773)
		(width 0.1651)
		(layer "In11.Cu")
		(net "P5E_PEX1_STN7_TX_C_DN<112>")
	)
	(segment
		(start 160.769554 -401.181062)
		(end 161.075116 -400.8755)
		(width 0.1651)
		(layer "In11.Cu")
		(net "P5E_PEX1_STN7_TX_C_DN<112>")
	)
	(segment
		(start 152.16124 -367.46561)
		(end 153.471372 -364.000796)
		(width 0.1651)
		(layer "In11.Cu")
		(net "P5E_PEX1_STN7_TX_C_DN<112>")
	)
	(segment
		(start 159.910018 -401.690078)
		(end 159.910018 -401.308062)
		(width 0.1651)
		(layer "In11.Cu")
		(net "P5E_PEX1_STN7_TX_C_DN<112>")
	)
	(segment
		(start 159.910018 -401.308062)
		(end 160.037018 -401.181062)
		(width 0.1651)
		(layer "In11.Cu")
		(net "P5E_PEX1_STN7_TX_C_DN<112>")
	)
	(segment
		(start 153.471372 -364.000796)
		(end 156.856176 -360.526838)
		(width 0.1651)
		(layer "In11.Cu")
		(net "P5E_PEX1_STN7_TX_C_DN<112>")
	)
	(segment
		(start 160.037018 -401.181062)
		(end 160.769554 -401.181062)
		(width 0.1651)
		(layer "In11.Cu")
		(net "P5E_PEX1_STN7_TX_C_DN<112>")
	)
	(segment
		(start 153.830274 -389.921242)
		(end 152.249378 -386.010404)
		(width 0.1651)
		(layer "In11.Cu")
		(net "P5E_PEX1_STN7_TX_C_DN<112>")
	)
	(segment
		(start 152.249378 -386.010404)
		(end 151.973534 -382.832356)
		(width 0.1651)
		(layer "In11.Cu")
		(net "P5E_PEX1_STN7_TX_C_DN<112>")
	)
	(segment
		(start 161.075116 -400.8755)
		(end 161.075116 -394.735558)
		(width 0.1651)
		(layer "In11.Cu")
		(net "P5E_PEX1_STN7_TX_C_DN<112>")
	)
	(segment
		(start 159.649922 -358.919018)
		(end 159.649922 -358.04856)
		(width 0.1651)
		(layer "In11.Cu")
		(net "P5E_PEX1_STN7_TX_C_DN<112>")
	)
	(segment
		(start 158.317692 -393.250928)
		(end 153.830274 -389.921242)
		(width 0.1651)
		(layer "In11.Cu")
		(net "P5E_PEX1_STN7_TX_C_DN<112>")
	)
	(segment
		(start 369.320064 -30.62732)
		(end 369.001294 -30.94609)
		(width 0.13462)
		(layer "F.Cu")
		(net "P5E_PEX3_STN2_TX_DP<45>")
	)
	(segment
		(start 369.954048 -30.62732)
		(end 369.320064 -30.62732)
		(width 0.13462)
		(layer "F.Cu")
		(net "P5E_PEX3_STN2_TX_DP<45>")
	)
	(segment
		(start 370.247418 -30.92069)
		(end 369.954048 -30.62732)
		(width 0.13462)
		(layer "F.Cu")
		(net "P5E_PEX3_STN2_TX_DP<45>")
	)
	(segment
		(start 370.54028 -30.627828)
		(end 370.545614 -30.62986)
		(width 0.1651)
		(layer "In11.Cu")
		(net "P5E_PEX3_STN2_TX_DP<45>")
	)
	(segment
		(start 394.07973 -278.20493)
		(end 394.294868 -278.420068)
		(width 0.1143)
		(layer "In11.Cu")
		(net "P5E_PEX3_STN2_TX_DP<45>")
	)
	(segment
		(start 374.02389 -33.631124)
		(end 383.140712 -45.07484)
		(width 0.1651)
		(layer "In11.Cu")
		(net "P5E_PEX3_STN2_TX_DP<45>")
	)
	(segment
		(start 373.311674 -32.737044)
		(end 373.620284 -33.124394)
		(width 0.1651)
		(layer "In11.Cu")
		(net "P5E_PEX3_STN2_TX_DP<45>")
	)
	(segment
		(start 394.64996 -278.534368)
		(end 394.64996 -278.799798)
		(width 0.1143)
		(layer "In11.Cu")
		(net "P5E_PEX3_STN2_TX_DP<45>")
	)
	(segment
		(start 370.545614 -30.62986)
		(end 370.931694 -30.62986)
		(width 0.1651)
		(layer "In11.Cu")
		(net "P5E_PEX3_STN2_TX_DP<45>")
	)
	(segment
		(start 381.840994 -137.987278)
		(end 393.007342 -264.195306)
		(width 0.1651)
		(layer "In11.Cu")
		(net "P5E_PEX3_STN2_TX_DP<45>")
	)
	(segment
		(start 394.03401 -271.399)
		(end 394.03401 -271.427448)
		(width 0.1143)
		(layer "In11.Cu")
		(net "P5E_PEX3_STN2_TX_DP<45>")
	)
	(segment
		(start 370.931694 -30.62986)
		(end 371.418866 -30.831536)
		(width 0.1651)
		(layer "In11.Cu")
		(net "P5E_PEX3_STN2_TX_DP<45>")
	)
	(segment
		(start 393.007342 -264.195306)
		(end 394.03401 -270.38427)
		(width 0.1651)
		(layer "In11.Cu")
		(net "P5E_PEX3_STN2_TX_DP<45>")
	)
	(segment
		(start 370.247418 -30.92069)
		(end 370.54028 -30.627828)
		(width 0.1651)
		(layer "In11.Cu")
		(net "P5E_PEX3_STN2_TX_DP<45>")
	)
	(segment
		(start 386.44703 -63.150242)
		(end 385.573524 -78.885796)
		(width 0.1651)
		(layer "In11.Cu")
		(net "P5E_PEX3_STN2_TX_DP<45>")
	)
	(segment
		(start 372.895876 -32.337248)
		(end 373.20474 -32.724852)
		(width 0.1651)
		(layer "In11.Cu")
		(net "P5E_PEX3_STN2_TX_DP<45>")
	)
	(segment
		(start 394.294868 -278.420068)
		(end 394.53566 -278.420068)
		(width 0.1143)
		(layer "In11.Cu")
		(net "P5E_PEX3_STN2_TX_DP<45>")
	)
	(segment
		(start 394.07973 -271.473168)
		(end 394.07973 -278.20493)
		(width 0.1143)
		(layer "In11.Cu")
		(net "P5E_PEX3_STN2_TX_DP<45>")
	)
	(segment
		(start 385.573524 -78.885796)
		(end 381.941324 -105.217976)
		(width 0.1651)
		(layer "In11.Cu")
		(net "P5E_PEX3_STN2_TX_DP<45>")
	)
	(segment
		(start 381.438658 -116.205762)
		(end 381.840994 -137.987278)
		(width 0.1651)
		(layer "In11.Cu")
		(net "P5E_PEX3_STN2_TX_DP<45>")
	)
	(segment
		(start 385.066032 -48.578008)
		(end 385.68376 -50.3682)
		(width 0.1651)
		(layer "In11.Cu")
		(net "P5E_PEX3_STN2_TX_DP<45>")
	)
	(segment
		(start 394.03401 -271.427448)
		(end 394.07973 -271.473168)
		(width 0.1143)
		(layer "In11.Cu")
		(net "P5E_PEX3_STN2_TX_DP<45>")
	)
	(segment
		(start 373.608092 -33.231328)
		(end 373.916956 -33.618932)
		(width 0.1651)
		(layer "In11.Cu")
		(net "P5E_PEX3_STN2_TX_DP<45>")
	)
	(segment
		(start 381.941578 -105.23093)
		(end 381.438658 -116.205762)
		(width 0.1651)
		(layer "In11.Cu")
		(net "P5E_PEX3_STN2_TX_DP<45>")
	)
	(segment
		(start 381.941324 -105.217976)
		(end 381.940562 -105.23093)
		(width 0.1651)
		(layer "In11.Cu")
		(net "P5E_PEX3_STN2_TX_DP<45>")
	)
	(segment
		(start 394.53566 -278.420068)
		(end 394.64996 -278.534368)
		(width 0.1143)
		(layer "In11.Cu")
		(net "P5E_PEX3_STN2_TX_DP<45>")
	)
	(segment
		(start 372.599458 -31.842964)
		(end 372.908068 -32.230314)
		(width 0.1651)
		(layer "In11.Cu")
		(net "P5E_PEX3_STN2_TX_DP<45>")
	)
	(segment
		(start 372.908068 -32.230314)
		(end 372.895876 -32.337248)
		(width 0.1651)
		(layer "In11.Cu")
		(net "P5E_PEX3_STN2_TX_DP<45>")
	)
	(segment
		(start 373.620284 -33.124394)
		(end 373.608092 -33.231328)
		(width 0.1651)
		(layer "In11.Cu")
		(net "P5E_PEX3_STN2_TX_DP<45>")
	)
	(segment
		(start 373.916956 -33.618932)
		(end 374.02389 -33.631124)
		(width 0.1651)
		(layer "In11.Cu")
		(net "P5E_PEX3_STN2_TX_DP<45>")
	)
	(segment
		(start 394.03401 -270.38427)
		(end 394.03401 -271.399)
		(width 0.1651)
		(layer "In11.Cu")
		(net "P5E_PEX3_STN2_TX_DP<45>")
	)
	(segment
		(start 381.940562 -105.23093)
		(end 381.941578 -105.23093)
		(width 0.1651)
		(layer "In11.Cu")
		(net "P5E_PEX3_STN2_TX_DP<45>")
	)
	(segment
		(start 383.140712 -45.07484)
		(end 385.066032 -48.578008)
		(width 0.1651)
		(layer "In11.Cu")
		(net "P5E_PEX3_STN2_TX_DP<45>")
	)
	(segment
		(start 373.20474 -32.724852)
		(end 373.311674 -32.737044)
		(width 0.1651)
		(layer "In11.Cu")
		(net "P5E_PEX3_STN2_TX_DP<45>")
	)
	(segment
		(start 385.68376 -50.3682)
		(end 386.44703 -63.150242)
		(width 0.1651)
		(layer "In11.Cu")
		(net "P5E_PEX3_STN2_TX_DP<45>")
	)
	(segment
		(start 371.418866 -30.831536)
		(end 372.599458 -31.842964)
		(width 0.1651)
		(layer "In11.Cu")
		(net "P5E_PEX3_STN2_TX_DP<45>")
	)
	(segment
		(start 344.161364 -351.316798)
		(end 344.456004 -351.611438)
		(width 0.13462)
		(layer "F.Cu")
		(net "P5E_PEX2_STN5_TX_C_DN<95>")
	)
	(segment
		(start 344.161364 -350.685354)
		(end 344.161364 -351.316798)
		(width 0.13462)
		(layer "F.Cu")
		(net "P5E_PEX2_STN5_TX_C_DN<95>")
	)
	(segment
		(start 344.481404 -350.365314)
		(end 344.161364 -350.685354)
		(width 0.13462)
		(layer "F.Cu")
		(net "P5E_PEX2_STN5_TX_C_DN<95>")
	)
	(segment
		(start 344.456004 -351.611438)
		(end 344.165174 -351.902268)
		(width 0.1651)
		(layer "In7.Cu")
		(net "P5E_PEX2_STN5_TX_C_DN<95>")
	)
	(segment
		(start 344.165174 -352.473006)
		(end 342.610694 -354.027486)
		(width 0.1651)
		(layer "In7.Cu")
		(net "P5E_PEX2_STN5_TX_C_DN<95>")
	)
	(segment
		(start 342.610694 -358.902)
		(end 348.016068 -369.014756)
		(width 0.1651)
		(layer "In7.Cu")
		(net "P5E_PEX2_STN5_TX_C_DN<95>")
	)
	(segment
		(start 344.165174 -351.902268)
		(end 344.165174 -352.473006)
		(width 0.1651)
		(layer "In7.Cu")
		(net "P5E_PEX2_STN5_TX_C_DN<95>")
	)
	(segment
		(start 347.017086 -380.181104)
		(end 346.890086 -380.308104)
		(width 0.1651)
		(layer "In7.Cu")
		(net "P5E_PEX2_STN5_TX_C_DN<95>")
	)
	(segment
		(start 348.016068 -379.729238)
		(end 347.564202 -380.181104)
		(width 0.1651)
		(layer "In7.Cu")
		(net "P5E_PEX2_STN5_TX_C_DN<95>")
	)
	(segment
		(start 346.890086 -380.308104)
		(end 346.890086 -380.69012)
		(width 0.1651)
		(layer "In7.Cu")
		(net "P5E_PEX2_STN5_TX_C_DN<95>")
	)
	(segment
		(start 342.610694 -354.027486)
		(end 342.610694 -358.902)
		(width 0.1651)
		(layer "In7.Cu")
		(net "P5E_PEX2_STN5_TX_C_DN<95>")
	)
	(segment
		(start 348.016068 -369.014756)
		(end 348.016068 -379.729238)
		(width 0.1651)
		(layer "In7.Cu")
		(net "P5E_PEX2_STN5_TX_C_DN<95>")
	)
	(segment
		(start 347.564202 -380.181104)
		(end 347.017086 -380.181104)
		(width 0.1651)
		(layer "In7.Cu")
		(net "P5E_PEX2_STN5_TX_C_DN<95>")
	)
	(segment
		(start 80.594962 -343.365582)
		(end 80.594962 -342.734138)
		(width 0.13462)
		(layer "F.Cu")
		(net "P5E_PEX0_STN6_TX_DN<103>")
	)
	(segment
		(start 80.594962 -342.734138)
		(end 80.889602 -342.439498)
		(width 0.13462)
		(layer "F.Cu")
		(net "P5E_PEX0_STN6_TX_DN<103>")
	)
	(segment
		(start 80.915002 -343.685622)
		(end 80.594962 -343.365582)
		(width 0.13462)
		(layer "F.Cu")
		(net "P5E_PEX0_STN6_TX_DN<103>")
	)
	(segment
		(start 80.598772 -342.148668)
		(end 80.598772 -341.578692)
		(width 0.1651)
		(layer "In13.Cu")
		(net "P5E_PEX0_STN6_TX_DN<103>")
	)
	(segment
		(start 51.011074 -311.670192)
		(end 51.099974 -311.759092)
		(width 0.1143)
		(layer "In13.Cu")
		(net "P5E_PEX0_STN6_TX_DN<103>")
	)
	(segment
		(start 80.598772 -341.578692)
		(end 80.052164 -340.667086)
		(width 0.1651)
		(layer "In13.Cu")
		(net "P5E_PEX0_STN6_TX_DN<103>")
	)
	(segment
		(start 53.564536 -326.87514)
		(end 51.922172 -325.232776)
		(width 0.1651)
		(layer "In13.Cu")
		(net "P5E_PEX0_STN6_TX_DN<103>")
	)
	(segment
		(start 50.720244 -320.113152)
		(end 50.720244 -311.797192)
		(width 0.1143)
		(layer "In13.Cu")
		(net "P5E_PEX0_STN6_TX_DN<103>")
	)
	(segment
		(start 50.765964 -320.158872)
		(end 50.720244 -320.113152)
		(width 0.1143)
		(layer "In13.Cu")
		(net "P5E_PEX0_STN6_TX_DN<103>")
	)
	(segment
		(start 50.847244 -311.670192)
		(end 51.011074 -311.670192)
		(width 0.1143)
		(layer "In13.Cu")
		(net "P5E_PEX0_STN6_TX_DN<103>")
	)
	(segment
		(start 51.099974 -311.759092)
		(end 51.099974 -312.049922)
		(width 0.1143)
		(layer "In13.Cu")
		(net "P5E_PEX0_STN6_TX_DN<103>")
	)
	(segment
		(start 51.922172 -325.232776)
		(end 50.765964 -322.441316)
		(width 0.1651)
		(layer "In13.Cu")
		(net "P5E_PEX0_STN6_TX_DN<103>")
	)
	(segment
		(start 50.765964 -320.18097)
		(end 50.765964 -320.158872)
		(width 0.1143)
		(layer "In13.Cu")
		(net "P5E_PEX0_STN6_TX_DN<103>")
	)
	(segment
		(start 50.720244 -311.797192)
		(end 50.847244 -311.670192)
		(width 0.1143)
		(layer "In13.Cu")
		(net "P5E_PEX0_STN6_TX_DN<103>")
	)
	(segment
		(start 50.765964 -322.441316)
		(end 50.765964 -320.18097)
		(width 0.1651)
		(layer "In13.Cu")
		(net "P5E_PEX0_STN6_TX_DN<103>")
	)
	(segment
		(start 80.889602 -342.439498)
		(end 80.598772 -342.148668)
		(width 0.1651)
		(layer "In13.Cu")
		(net "P5E_PEX0_STN6_TX_DN<103>")
	)
	(segment
		(start 56.607456 -328.135488)
		(end 53.564536 -326.87514)
		(width 0.1651)
		(layer "In13.Cu")
		(net "P5E_PEX0_STN6_TX_DN<103>")
	)
	(segment
		(start 80.052164 -340.667086)
		(end 56.607456 -328.135488)
		(width 0.1651)
		(layer "In13.Cu")
		(net "P5E_PEX0_STN6_TX_DN<103>")
	)
	(segment
		(start 393.31392 -28.54198)
		(end 392.675872 -28.54198)
		(width 0.13462)
		(layer "F.Cu")
		(net "P5E_PEX3_STN2_TX_DN<40>")
	)
	(segment
		(start 393.605258 -28.250642)
		(end 393.31392 -28.54198)
		(width 0.13462)
		(layer "F.Cu")
		(net "P5E_PEX3_STN2_TX_DN<40>")
	)
	(segment
		(start 392.675872 -28.54198)
		(end 392.359134 -28.225242)
		(width 0.13462)
		(layer "F.Cu")
		(net "P5E_PEX3_STN2_TX_DN<40>")
	)
	(segment
		(start 413.117284 -69.60997)
		(end 406.070816 -119.313452)
		(width 0.1651)
		(layer "In11.Cu")
		(net "P5E_PEX3_STN2_TX_DN<40>")
	)
	(segment
		(start 399.400014 -280.015188)
		(end 399.400014 -279.749504)
		(width 0.1143)
		(layer "In11.Cu")
		(net "P5E_PEX3_STN2_TX_DN<40>")
	)
	(segment
		(start 404.730204 -135.263128)
		(end 398.42821 -252.61824)
		(width 0.1651)
		(layer "In11.Cu")
		(net "P5E_PEX3_STN2_TX_DN<40>")
	)
	(segment
		(start 411.853888 -46.926246)
		(end 412.880556 -49.856136)
		(width 0.1651)
		(layer "In11.Cu")
		(net "P5E_PEX3_STN2_TX_DN<40>")
	)
	(segment
		(start 399.285714 -280.129488)
		(end 399.400014 -280.015188)
		(width 0.1143)
		(layer "In11.Cu")
		(net "P5E_PEX3_STN2_TX_DN<40>")
	)
	(segment
		(start 413.54629 -60.605162)
		(end 413.119316 -69.597016)
		(width 0.1651)
		(layer "In11.Cu")
		(net "P5E_PEX3_STN2_TX_DN<40>")
	)
	(segment
		(start 398.701514 -266.016486)
		(end 399.07464 -269.806928)
		(width 0.1651)
		(layer "In11.Cu")
		(net "P5E_PEX3_STN2_TX_DN<40>")
	)
	(segment
		(start 399.020284 -271.473168)
		(end 399.020284 -280.025856)
		(width 0.1143)
		(layer "In11.Cu")
		(net "P5E_PEX3_STN2_TX_DN<40>")
	)
	(segment
		(start 398.42821 -252.61824)
		(end 398.701514 -266.016486)
		(width 0.1651)
		(layer "In11.Cu")
		(net "P5E_PEX3_STN2_TX_DN<40>")
	)
	(segment
		(start 413.119316 -69.597016)
		(end 413.117538 -69.60997)
		(width 0.1651)
		(layer "In11.Cu")
		(net "P5E_PEX3_STN2_TX_DN<40>")
	)
	(segment
		(start 399.123916 -280.129488)
		(end 399.285714 -280.129488)
		(width 0.1143)
		(layer "In11.Cu")
		(net "P5E_PEX3_STN2_TX_DN<40>")
	)
	(segment
		(start 397.604996 -29.110178)
		(end 400.370294 -31.857696)
		(width 0.1651)
		(layer "In11.Cu")
		(net "P5E_PEX3_STN2_TX_DN<40>")
	)
	(segment
		(start 402.114258 -34.710116)
		(end 411.853888 -46.926246)
		(width 0.1651)
		(layer "In11.Cu")
		(net "P5E_PEX3_STN2_TX_DN<40>")
	)
	(segment
		(start 399.020284 -280.025856)
		(end 399.123916 -280.129488)
		(width 0.1143)
		(layer "In11.Cu")
		(net "P5E_PEX3_STN2_TX_DN<40>")
	)
	(segment
		(start 412.880556 -49.856136)
		(end 413.54629 -60.605162)
		(width 0.1651)
		(layer "In11.Cu")
		(net "P5E_PEX3_STN2_TX_DN<40>")
	)
	(segment
		(start 399.066004 -271.399)
		(end 399.066004 -271.427448)
		(width 0.1143)
		(layer "In11.Cu")
		(net "P5E_PEX3_STN2_TX_DN<40>")
	)
	(segment
		(start 406.070816 -119.313452)
		(end 404.730204 -135.263128)
		(width 0.1651)
		(layer "In11.Cu")
		(net "P5E_PEX3_STN2_TX_DN<40>")
	)
	(segment
		(start 399.07464 -269.806928)
		(end 399.07464 -271.221962)
		(width 0.1651)
		(layer "In11.Cu")
		(net "P5E_PEX3_STN2_TX_DN<40>")
	)
	(segment
		(start 399.066004 -271.230598)
		(end 399.066004 -271.399)
		(width 0.1651)
		(layer "In11.Cu")
		(net "P5E_PEX3_STN2_TX_DN<40>")
	)
	(segment
		(start 396.239238 -28.541472)
		(end 397.604996 -29.110178)
		(width 0.1651)
		(layer "In11.Cu")
		(net "P5E_PEX3_STN2_TX_DN<40>")
	)
	(segment
		(start 399.066004 -271.427448)
		(end 399.020284 -271.473168)
		(width 0.1143)
		(layer "In11.Cu")
		(net "P5E_PEX3_STN2_TX_DN<40>")
	)
	(segment
		(start 399.07464 -271.221962)
		(end 399.066004 -271.230598)
		(width 0.1651)
		(layer "In11.Cu")
		(net "P5E_PEX3_STN2_TX_DN<40>")
	)
	(segment
		(start 400.370294 -31.857696)
		(end 402.114258 -34.710116)
		(width 0.1651)
		(layer "In11.Cu")
		(net "P5E_PEX3_STN2_TX_DN<40>")
	)
	(segment
		(start 393.605258 -28.250642)
		(end 393.896088 -28.541472)
		(width 0.1651)
		(layer "In11.Cu")
		(net "P5E_PEX3_STN2_TX_DN<40>")
	)
	(segment
		(start 413.117538 -69.60997)
		(end 413.117284 -69.60997)
		(width 0.1651)
		(layer "In11.Cu")
		(net "P5E_PEX3_STN2_TX_DN<40>")
	)
	(segment
		(start 393.896088 -28.541472)
		(end 396.239238 -28.541472)
		(width 0.1651)
		(layer "In11.Cu")
		(net "P5E_PEX3_STN2_TX_DN<40>")
	)
	(segment
		(start 134.193788 -357.46309)
		(end 134.193788 -356.831646)
		(width 0.13462)
		(layer "F.Cu")
		(net "P5E_PEX1_STN5_TX_C_DN<83>")
	)
	(segment
		(start 134.488428 -357.75773)
		(end 134.193788 -357.46309)
		(width 0.13462)
		(layer "F.Cu")
		(net "P5E_PEX1_STN5_TX_C_DN<83>")
	)
	(segment
		(start 134.193788 -356.831646)
		(end 134.513828 -356.511606)
		(width 0.13462)
		(layer "F.Cu")
		(net "P5E_PEX1_STN5_TX_C_DN<83>")
	)
	(segment
		(start 136.645396 -388.807198)
		(end 137.400792 -388.37108)
		(width 0.1651)
		(layer "In7.Cu")
		(net "P5E_PEX1_STN5_TX_C_DN<83>")
	)
	(segment
		(start 138.321034 -387.605524)
		(end 138.64082 -386.996686)
		(width 0.1651)
		(layer "In7.Cu")
		(net "P5E_PEX1_STN5_TX_C_DN<83>")
	)
	(segment
		(start 122.986038 -406.180798)
		(end 123.569476 -405.59736)
		(width 0.1651)
		(layer "In7.Cu")
		(net "P5E_PEX1_STN5_TX_C_DN<83>")
	)
	(segment
		(start 125.31725 -393.36853)
		(end 134.497826 -389.500364)
		(width 0.1651)
		(layer "In7.Cu")
		(net "P5E_PEX1_STN5_TX_C_DN<83>")
	)
	(segment
		(start 137.400792 -388.37108)
		(end 138.321034 -387.605524)
		(width 0.1651)
		(layer "In7.Cu")
		(net "P5E_PEX1_STN5_TX_C_DN<83>")
	)
	(segment
		(start 122.510042 -406.690068)
		(end 122.510042 -406.308052)
		(width 0.1651)
		(layer "In7.Cu")
		(net "P5E_PEX1_STN5_TX_C_DN<83>")
	)
	(segment
		(start 138.816842 -386.415026)
		(end 138.816842 -383.204974)
		(width 0.1651)
		(layer "In7.Cu")
		(net "P5E_PEX1_STN5_TX_C_DN<83>")
	)
	(segment
		(start 134.197598 -358.04856)
		(end 134.488428 -357.75773)
		(width 0.1651)
		(layer "In7.Cu")
		(net "P5E_PEX1_STN5_TX_C_DN<83>")
	)
	(segment
		(start 123.569476 -405.59736)
		(end 123.569476 -395.116304)
		(width 0.1651)
		(layer "In7.Cu")
		(net "P5E_PEX1_STN5_TX_C_DN<83>")
	)
	(segment
		(start 134.197598 -358.643682)
		(end 134.197598 -358.04856)
		(width 0.1651)
		(layer "In7.Cu")
		(net "P5E_PEX1_STN5_TX_C_DN<83>")
	)
	(segment
		(start 139.155424 -369.466622)
		(end 134.197598 -358.643682)
		(width 0.1651)
		(layer "In7.Cu")
		(net "P5E_PEX1_STN5_TX_C_DN<83>")
	)
	(segment
		(start 134.497826 -389.500364)
		(end 136.645396 -388.807198)
		(width 0.1651)
		(layer "In7.Cu")
		(net "P5E_PEX1_STN5_TX_C_DN<83>")
	)
	(segment
		(start 123.569476 -395.116304)
		(end 125.31725 -393.36853)
		(width 0.1651)
		(layer "In7.Cu")
		(net "P5E_PEX1_STN5_TX_C_DN<83>")
	)
	(segment
		(start 138.64082 -386.996686)
		(end 138.816842 -386.415026)
		(width 0.1651)
		(layer "In7.Cu")
		(net "P5E_PEX1_STN5_TX_C_DN<83>")
	)
	(segment
		(start 122.637296 -406.180798)
		(end 122.986038 -406.180798)
		(width 0.1651)
		(layer "In7.Cu")
		(net "P5E_PEX1_STN5_TX_C_DN<83>")
	)
	(segment
		(start 138.816842 -383.204974)
		(end 139.155424 -369.466622)
		(width 0.1651)
		(layer "In7.Cu")
		(net "P5E_PEX1_STN5_TX_C_DN<83>")
	)
	(segment
		(start 122.510042 -406.308052)
		(end 122.637296 -406.180798)
		(width 0.1651)
		(layer "In7.Cu")
		(net "P5E_PEX1_STN5_TX_C_DN<83>")
	)
	(segment
		(start 393.8397 -349.831914)
		(end 393.519152 -349.511366)
		(width 0.13462)
		(layer "F.Cu")
		(net "P5E_PEX3_STN5_TX_DN<90>")
	)
	(segment
		(start 393.519152 -348.880938)
		(end 393.8143 -348.58579)
		(width 0.13462)
		(layer "F.Cu")
		(net "P5E_PEX3_STN5_TX_DN<90>")
	)
	(segment
		(start 393.519152 -349.511366)
		(end 393.519152 -348.880938)
		(width 0.13462)
		(layer "F.Cu")
		(net "P5E_PEX3_STN5_TX_DN<90>")
	)
	(segment
		(start 393.52347 -347.784674)
		(end 395.07795 -346.230194)
		(width 0.1651)
		(layer "In13.Cu")
		(net "P5E_PEX3_STN5_TX_DN<90>")
	)
	(segment
		(start 416.165792 -321.704716)
		(end 416.165792 -320.046096)
		(width 0.1651)
		(layer "In13.Cu")
		(net "P5E_PEX3_STN5_TX_DN<90>")
	)
	(segment
		(start 416.165792 -320.017648)
		(end 416.120072 -319.971928)
		(width 0.1143)
		(layer "In13.Cu")
		(net "P5E_PEX3_STN5_TX_DN<90>")
	)
	(segment
		(start 416.499802 -311.784492)
		(end 416.499802 -312.049922)
		(width 0.1143)
		(layer "In13.Cu")
		(net "P5E_PEX3_STN5_TX_DN<90>")
	)
	(segment
		(start 393.52347 -348.29496)
		(end 393.52347 -347.784674)
		(width 0.1651)
		(layer "In13.Cu")
		(net "P5E_PEX3_STN5_TX_DN<90>")
	)
	(segment
		(start 414.446974 -324.128892)
		(end 416.165792 -321.704716)
		(width 0.1651)
		(layer "In13.Cu")
		(net "P5E_PEX3_STN5_TX_DN<90>")
	)
	(segment
		(start 416.165792 -320.046096)
		(end 416.165792 -320.017648)
		(width 0.1143)
		(layer "In13.Cu")
		(net "P5E_PEX3_STN5_TX_DN<90>")
	)
	(segment
		(start 416.120072 -311.773824)
		(end 416.223704 -311.670192)
		(width 0.1143)
		(layer "In13.Cu")
		(net "P5E_PEX3_STN5_TX_DN<90>")
	)
	(segment
		(start 395.07795 -346.230194)
		(end 395.07795 -342.100916)
		(width 0.1651)
		(layer "In13.Cu")
		(net "P5E_PEX3_STN5_TX_DN<90>")
	)
	(segment
		(start 393.8143 -348.58579)
		(end 393.52347 -348.29496)
		(width 0.1651)
		(layer "In13.Cu")
		(net "P5E_PEX3_STN5_TX_DN<90>")
	)
	(segment
		(start 395.07795 -342.100916)
		(end 395.428724 -341.147146)
		(width 0.1651)
		(layer "In13.Cu")
		(net "P5E_PEX3_STN5_TX_DN<90>")
	)
	(segment
		(start 395.428724 -341.147146)
		(end 414.446974 -324.128892)
		(width 0.1651)
		(layer "In13.Cu")
		(net "P5E_PEX3_STN5_TX_DN<90>")
	)
	(segment
		(start 416.223704 -311.670192)
		(end 416.385502 -311.670192)
		(width 0.1143)
		(layer "In13.Cu")
		(net "P5E_PEX3_STN5_TX_DN<90>")
	)
	(segment
		(start 416.385502 -311.670192)
		(end 416.499802 -311.784492)
		(width 0.1143)
		(layer "In13.Cu")
		(net "P5E_PEX3_STN5_TX_DN<90>")
	)
	(segment
		(start 416.120072 -319.971928)
		(end 416.120072 -311.773824)
		(width 0.1143)
		(layer "In13.Cu")
		(net "P5E_PEX3_STN5_TX_DN<90>")
	)
	(segment
		(start 334.834484 -356.831646)
		(end 334.834484 -357.46309)
		(width 0.13462)
		(layer "F.Cu")
		(net "P5E_PEX2_STN5_TX_C_DN<91>")
	)
	(segment
		(start 334.834484 -357.46309)
		(end 335.129124 -357.75773)
		(width 0.13462)
		(layer "F.Cu")
		(net "P5E_PEX2_STN5_TX_C_DN<91>")
	)
	(segment
		(start 335.154524 -356.511606)
		(end 334.834484 -356.831646)
		(width 0.13462)
		(layer "F.Cu")
		(net "P5E_PEX2_STN5_TX_C_DN<91>")
	)
	(segment
		(start 338.217002 -380.181104)
		(end 338.764118 -380.181104)
		(width 0.1651)
		(layer "In7.Cu")
		(net "P5E_PEX2_STN5_TX_C_DN<91>")
	)
	(segment
		(start 339.215984 -379.729238)
		(end 339.215984 -368.50574)
		(width 0.1651)
		(layer "In7.Cu")
		(net "P5E_PEX2_STN5_TX_C_DN<91>")
	)
	(segment
		(start 338.090002 -380.308104)
		(end 338.217002 -380.181104)
		(width 0.1651)
		(layer "In7.Cu")
		(net "P5E_PEX2_STN5_TX_C_DN<91>")
	)
	(segment
		(start 338.090002 -380.69012)
		(end 338.090002 -380.308104)
		(width 0.1651)
		(layer "In7.Cu")
		(net "P5E_PEX2_STN5_TX_C_DN<91>")
	)
	(segment
		(start 338.764118 -380.181104)
		(end 339.215984 -379.729238)
		(width 0.1651)
		(layer "In7.Cu")
		(net "P5E_PEX2_STN5_TX_C_DN<91>")
	)
	(segment
		(start 334.838294 -358.948482)
		(end 334.838294 -358.04856)
		(width 0.1651)
		(layer "In7.Cu")
		(net "P5E_PEX2_STN5_TX_C_DN<91>")
	)
	(segment
		(start 334.838294 -358.04856)
		(end 335.129124 -357.75773)
		(width 0.1651)
		(layer "In7.Cu")
		(net "P5E_PEX2_STN5_TX_C_DN<91>")
	)
	(segment
		(start 339.215984 -368.50574)
		(end 334.838294 -358.948482)
		(width 0.1651)
		(layer "In7.Cu")
		(net "P5E_PEX2_STN5_TX_C_DN<91>")
	)
	(segment
		(start 93.030802 -342.734138)
		(end 93.325442 -342.439498)
		(width 0.13462)
		(layer "F.Cu")
		(net "P5E_PEX0_STN6_TX_DN<97>")
	)
	(segment
		(start 93.350842 -343.685622)
		(end 93.030802 -343.365582)
		(width 0.13462)
		(layer "F.Cu")
		(net "P5E_PEX0_STN6_TX_DN<97>")
	)
	(segment
		(start 93.030802 -343.365582)
		(end 93.030802 -342.734138)
		(width 0.13462)
		(layer "F.Cu")
		(net "P5E_PEX0_STN6_TX_DN<97>")
	)
	(segment
		(start 93.034612 -342.148668)
		(end 93.034612 -341.192612)
		(width 0.1651)
		(layer "In13.Cu")
		(net "P5E_PEX0_STN6_TX_DN<97>")
	)
	(segment
		(start 56.420258 -311.797192)
		(end 56.547258 -311.670192)
		(width 0.1143)
		(layer "In13.Cu")
		(net "P5E_PEX0_STN6_TX_DN<97>")
	)
	(segment
		(start 93.325442 -342.439498)
		(end 93.034612 -342.148668)
		(width 0.1651)
		(layer "In13.Cu")
		(net "P5E_PEX0_STN6_TX_DN<97>")
	)
	(segment
		(start 90.869516 -339.044534)
		(end 90.869516 -339.044788)
		(width 0.1651)
		(layer "In13.Cu")
		(net "P5E_PEX0_STN6_TX_DN<97>")
	)
	(segment
		(start 57.163716 -322.161916)
		(end 56.742838 -321.741038)
		(width 0.1651)
		(layer "In13.Cu")
		(net "P5E_PEX0_STN6_TX_DN<97>")
	)
	(segment
		(start 66.585338 -326.064372)
		(end 57.163716 -322.161916)
		(width 0.1651)
		(layer "In13.Cu")
		(net "P5E_PEX0_STN6_TX_DN<97>")
	)
	(segment
		(start 56.742838 -321.741038)
		(end 56.465978 -321.07251)
		(width 0.1651)
		(layer "In13.Cu")
		(net "P5E_PEX0_STN6_TX_DN<97>")
	)
	(segment
		(start 56.420258 -320.145664)
		(end 56.420258 -311.797192)
		(width 0.1143)
		(layer "In13.Cu")
		(net "P5E_PEX0_STN6_TX_DN<97>")
	)
	(segment
		(start 56.711088 -311.670192)
		(end 56.799988 -311.759092)
		(width 0.1143)
		(layer "In13.Cu")
		(net "P5E_PEX0_STN6_TX_DN<97>")
	)
	(segment
		(start 93.034612 -341.192612)
		(end 90.906346 -339.064346)
		(width 0.1651)
		(layer "In13.Cu")
		(net "P5E_PEX0_STN6_TX_DN<97>")
	)
	(segment
		(start 90.869516 -339.044788)
		(end 66.585338 -326.064372)
		(width 0.1651)
		(layer "In13.Cu")
		(net "P5E_PEX0_STN6_TX_DN<97>")
	)
	(segment
		(start 56.799988 -311.759092)
		(end 56.799988 -312.049922)
		(width 0.1143)
		(layer "In13.Cu")
		(net "P5E_PEX0_STN6_TX_DN<97>")
	)
	(segment
		(start 90.906346 -339.064346)
		(end 90.869516 -339.044534)
		(width 0.1651)
		(layer "In13.Cu")
		(net "P5E_PEX0_STN6_TX_DN<97>")
	)
	(segment
		(start 56.465978 -320.213482)
		(end 56.465978 -320.191384)
		(width 0.1143)
		(layer "In13.Cu")
		(net "P5E_PEX0_STN6_TX_DN<97>")
	)
	(segment
		(start 56.547258 -311.670192)
		(end 56.711088 -311.670192)
		(width 0.1143)
		(layer "In13.Cu")
		(net "P5E_PEX0_STN6_TX_DN<97>")
	)
	(segment
		(start 56.465978 -321.07251)
		(end 56.465978 -320.213482)
		(width 0.1651)
		(layer "In13.Cu")
		(net "P5E_PEX0_STN6_TX_DN<97>")
	)
	(segment
		(start 56.465978 -320.191384)
		(end 56.420258 -320.145664)
		(width 0.1143)
		(layer "In13.Cu")
		(net "P5E_PEX0_STN6_TX_DN<97>")
	)
	(segment
		(start 163.049712 -357.75773)
		(end 162.755072 -357.46309)
		(width 0.13462)
		(layer "F.Cu")
		(net "P5E_PEX1_STN7_TX_C_DN<113>")
	)
	(segment
		(start 162.755072 -357.46309)
		(end 162.755072 -356.831646)
		(width 0.13462)
		(layer "F.Cu")
		(net "P5E_PEX1_STN7_TX_C_DN<113>")
	)
	(segment
		(start 162.755072 -356.831646)
		(end 163.075112 -356.511606)
		(width 0.13462)
		(layer "F.Cu")
		(net "P5E_PEX1_STN7_TX_C_DN<113>")
	)
	(segment
		(start 162.969448 -402.281136)
		(end 163.27501 -401.975574)
		(width 0.1651)
		(layer "In11.Cu")
		(net "P5E_PEX1_STN7_TX_C_DN<113>")
	)
	(segment
		(start 159.353504 -392.657584)
		(end 154.535124 -389.081518)
		(width 0.1651)
		(layer "In11.Cu")
		(net "P5E_PEX1_STN7_TX_C_DN<113>")
	)
	(segment
		(start 153.188416 -385.75107)
		(end 152.933654 -382.8161)
		(width 0.1651)
		(layer "In11.Cu")
		(net "P5E_PEX1_STN7_TX_C_DN<113>")
	)
	(segment
		(start 154.300428 -364.578646)
		(end 157.376622 -361.421426)
		(width 0.1651)
		(layer "In11.Cu")
		(net "P5E_PEX1_STN7_TX_C_DN<113>")
	)
	(segment
		(start 162.758882 -358.75468)
		(end 162.758882 -358.04856)
		(width 0.1651)
		(layer "In11.Cu")
		(net "P5E_PEX1_STN7_TX_C_DN<113>")
	)
	(segment
		(start 161.62909 -393.71651)
		(end 159.353504 -392.657584)
		(width 0.1651)
		(layer "In11.Cu")
		(net "P5E_PEX1_STN7_TX_C_DN<113>")
	)
	(segment
		(start 162.236912 -402.281136)
		(end 162.969448 -402.281136)
		(width 0.1651)
		(layer "In11.Cu")
		(net "P5E_PEX1_STN7_TX_C_DN<113>")
	)
	(segment
		(start 154.535124 -389.081518)
		(end 153.188416 -385.75107)
		(width 0.1651)
		(layer "In11.Cu")
		(net "P5E_PEX1_STN7_TX_C_DN<113>")
	)
	(segment
		(start 163.27501 -395.36243)
		(end 161.62909 -393.71651)
		(width 0.1651)
		(layer "In11.Cu")
		(net "P5E_PEX1_STN7_TX_C_DN<113>")
	)
	(segment
		(start 152.933654 -382.8161)
		(end 153.118566 -367.70437)
		(width 0.1651)
		(layer "In11.Cu")
		(net "P5E_PEX1_STN7_TX_C_DN<113>")
	)
	(segment
		(start 162.758882 -358.04856)
		(end 163.049712 -357.75773)
		(width 0.1651)
		(layer "In11.Cu")
		(net "P5E_PEX1_STN7_TX_C_DN<113>")
	)
	(segment
		(start 162.056318 -359.457244)
		(end 162.758882 -358.75468)
		(width 0.1651)
		(layer "In11.Cu")
		(net "P5E_PEX1_STN7_TX_C_DN<113>")
	)
	(segment
		(start 157.376622 -361.421426)
		(end 162.056318 -359.457244)
		(width 0.1651)
		(layer "In11.Cu")
		(net "P5E_PEX1_STN7_TX_C_DN<113>")
	)
	(segment
		(start 162.109912 -402.408136)
		(end 162.236912 -402.281136)
		(width 0.1651)
		(layer "In11.Cu")
		(net "P5E_PEX1_STN7_TX_C_DN<113>")
	)
	(segment
		(start 162.109912 -402.790152)
		(end 162.109912 -402.408136)
		(width 0.1651)
		(layer "In11.Cu")
		(net "P5E_PEX1_STN7_TX_C_DN<113>")
	)
	(segment
		(start 153.118566 -367.70437)
		(end 154.300428 -364.578646)
		(width 0.1651)
		(layer "In11.Cu")
		(net "P5E_PEX1_STN7_TX_C_DN<113>")
	)
	(segment
		(start 163.27501 -401.975574)
		(end 163.27501 -395.36243)
		(width 0.1651)
		(layer "In11.Cu")
		(net "P5E_PEX1_STN7_TX_C_DN<113>")
	)
	(segment
		(start 399.462752 -349.512382)
		(end 399.462752 -348.879922)
		(width 0.13462)
		(layer "F.Cu")
		(net "P5E_PEX3_STN5_TX_DP<93>")
	)
	(segment
		(start 399.14322 -349.831914)
		(end 399.462752 -349.512382)
		(width 0.13462)
		(layer "F.Cu")
		(net "P5E_PEX3_STN5_TX_DP<93>")
	)
	(segment
		(start 399.462752 -348.879922)
		(end 399.16862 -348.58579)
		(width 0.13462)
		(layer "F.Cu")
		(net "P5E_PEX3_STN5_TX_DP<93>")
	)
	(segment
		(start 419.235636 -313.379612)
		(end 419.349936 -313.265312)
		(width 0.1143)
		(layer "In13.Cu")
		(net "P5E_PEX3_STN5_TX_DP<93>")
	)
	(segment
		(start 418.779706 -319.971928)
		(end 418.779706 -313.59475)
		(width 0.1143)
		(layer "In13.Cu")
		(net "P5E_PEX3_STN5_TX_DP<93>")
	)
	(segment
		(start 418.733986 -320.017648)
		(end 418.779706 -319.971928)
		(width 0.1143)
		(layer "In13.Cu")
		(net "P5E_PEX3_STN5_TX_DP<93>")
	)
	(segment
		(start 418.994844 -313.379612)
		(end 419.235636 -313.379612)
		(width 0.1143)
		(layer "In13.Cu")
		(net "P5E_PEX3_STN5_TX_DP<93>")
	)
	(segment
		(start 399.45945 -347.667834)
		(end 401.01393 -346.113354)
		(width 0.1651)
		(layer "In13.Cu")
		(net "P5E_PEX3_STN5_TX_DP<93>")
	)
	(segment
		(start 416.178492 -326.365362)
		(end 418.733986 -322.637658)
		(width 0.1651)
		(layer "In13.Cu")
		(net "P5E_PEX3_STN5_TX_DP<93>")
	)
	(segment
		(start 401.01393 -341.295228)
		(end 401.37842 -340.478618)
		(width 0.1651)
		(layer "In13.Cu")
		(net "P5E_PEX3_STN5_TX_DP<93>")
	)
	(segment
		(start 399.45945 -348.29496)
		(end 399.45945 -347.667834)
		(width 0.1651)
		(layer "In13.Cu")
		(net "P5E_PEX3_STN5_TX_DP<93>")
	)
	(segment
		(start 401.01393 -346.113354)
		(end 401.01393 -341.295228)
		(width 0.1651)
		(layer "In13.Cu")
		(net "P5E_PEX3_STN5_TX_DP<93>")
	)
	(segment
		(start 419.349936 -313.265312)
		(end 419.349936 -312.999882)
		(width 0.1143)
		(layer "In13.Cu")
		(net "P5E_PEX3_STN5_TX_DP<93>")
	)
	(segment
		(start 401.37842 -340.478618)
		(end 416.178492 -326.365362)
		(width 0.1651)
		(layer "In13.Cu")
		(net "P5E_PEX3_STN5_TX_DP<93>")
	)
	(segment
		(start 418.733986 -320.046096)
		(end 418.733986 -320.017648)
		(width 0.1143)
		(layer "In13.Cu")
		(net "P5E_PEX3_STN5_TX_DP<93>")
	)
	(segment
		(start 418.779706 -313.59475)
		(end 418.994844 -313.379612)
		(width 0.1143)
		(layer "In13.Cu")
		(net "P5E_PEX3_STN5_TX_DP<93>")
	)
	(segment
		(start 399.16862 -348.58579)
		(end 399.45945 -348.29496)
		(width 0.1651)
		(layer "In13.Cu")
		(net "P5E_PEX3_STN5_TX_DP<93>")
	)
	(segment
		(start 418.733986 -322.637658)
		(end 418.733986 -320.046096)
		(width 0.1651)
		(layer "In13.Cu")
		(net "P5E_PEX3_STN5_TX_DP<93>")
	)
	(segment
		(start 396.353792 -355.658674)
		(end 396.353792 -355.026214)
		(width 0.13462)
		(layer "F.Cu")
		(net "P5E_PEX3_STN5_TX_DP<92>")
	)
	(segment
		(start 396.03426 -355.978206)
		(end 396.353792 -355.658674)
		(width 0.13462)
		(layer "F.Cu")
		(net "P5E_PEX3_STN5_TX_DP<92>")
	)
	(segment
		(start 396.353792 -355.026214)
		(end 396.05966 -354.732082)
		(width 0.13462)
		(layer "F.Cu")
		(net "P5E_PEX3_STN5_TX_DP<92>")
	)
	(segment
		(start 415.421064 -325.656194)
		(end 417.784026 -322.30695)
		(width 0.1651)
		(layer "In13.Cu")
		(net "P5E_PEX3_STN5_TX_DP<92>")
	)
	(segment
		(start 417.784026 -320.046096)
		(end 417.784026 -320.017648)
		(width 0.1143)
		(layer "In13.Cu")
		(net "P5E_PEX3_STN5_TX_DP<92>")
	)
	(segment
		(start 417.829746 -311.69483)
		(end 418.044884 -311.479692)
		(width 0.1143)
		(layer "In13.Cu")
		(net "P5E_PEX3_STN5_TX_DP<92>")
	)
	(segment
		(start 398.12341 -341.283544)
		(end 415.421064 -325.656194)
		(width 0.1651)
		(layer "In13.Cu")
		(net "P5E_PEX3_STN5_TX_DP<92>")
	)
	(segment
		(start 418.044884 -311.479692)
		(end 418.285676 -311.479692)
		(width 0.1143)
		(layer "In13.Cu")
		(net "P5E_PEX3_STN5_TX_DP<92>")
	)
	(segment
		(start 396.35049 -353.814126)
		(end 397.90497 -352.259646)
		(width 0.1651)
		(layer "In13.Cu")
		(net "P5E_PEX3_STN5_TX_DP<92>")
	)
	(segment
		(start 417.784026 -322.30695)
		(end 417.784026 -320.046096)
		(width 0.1651)
		(layer "In13.Cu")
		(net "P5E_PEX3_STN5_TX_DP<92>")
	)
	(segment
		(start 418.285676 -311.479692)
		(end 418.399976 -311.365392)
		(width 0.1143)
		(layer "In13.Cu")
		(net "P5E_PEX3_STN5_TX_DP<92>")
	)
	(segment
		(start 397.90497 -352.259646)
		(end 397.90497 -342.04148)
		(width 0.1651)
		(layer "In13.Cu")
		(net "P5E_PEX3_STN5_TX_DP<92>")
	)
	(segment
		(start 397.90497 -342.04148)
		(end 398.12341 -341.283544)
		(width 0.1651)
		(layer "In13.Cu")
		(net "P5E_PEX3_STN5_TX_DP<92>")
	)
	(segment
		(start 396.05966 -354.732082)
		(end 396.35049 -354.441252)
		(width 0.1651)
		(layer "In13.Cu")
		(net "P5E_PEX3_STN5_TX_DP<92>")
	)
	(segment
		(start 417.829746 -319.971928)
		(end 417.829746 -311.69483)
		(width 0.1143)
		(layer "In13.Cu")
		(net "P5E_PEX3_STN5_TX_DP<92>")
	)
	(segment
		(start 396.35049 -354.441252)
		(end 396.35049 -353.814126)
		(width 0.1651)
		(layer "In13.Cu")
		(net "P5E_PEX3_STN5_TX_DP<92>")
	)
	(segment
		(start 418.399976 -311.365392)
		(end 418.399976 -311.099962)
		(width 0.1143)
		(layer "In13.Cu")
		(net "P5E_PEX3_STN5_TX_DP<92>")
	)
	(segment
		(start 417.784026 -320.017648)
		(end 417.829746 -319.971928)
		(width 0.1143)
		(layer "In13.Cu")
		(net "P5E_PEX3_STN5_TX_DP<92>")
	)
	(segment
		(start 334.240124 -356.511606)
		(end 334.560164 -356.831646)
		(width 0.13462)
		(layer "F.Cu")
		(net "P5E_PEX2_STN5_TX_C_DP<91>")
	)
	(segment
		(start 334.560164 -357.46309)
		(end 334.265524 -357.75773)
		(width 0.13462)
		(layer "F.Cu")
		(net "P5E_PEX2_STN5_TX_C_DP<91>")
	)
	(segment
		(start 334.560164 -356.831646)
		(end 334.560164 -357.46309)
		(width 0.13462)
		(layer "F.Cu")
		(net "P5E_PEX2_STN5_TX_C_DP<91>")
	)
	(segment
		(start 334.556354 -359.010204)
		(end 337.80349 -366.099344)
		(width 0.1651)
		(layer "In7.Cu")
		(net "P5E_PEX2_STN5_TX_C_DP<91>")
	)
	(segment
		(start 337.747102 -366.250982)
		(end 337.95335 -366.701578)
		(width 0.1651)
		(layer "In7.Cu")
		(net "P5E_PEX2_STN5_TX_C_DP<91>")
	)
	(segment
		(start 338.105242 -366.757966)
		(end 338.934044 -368.567462)
		(width 0.1651)
		(layer "In7.Cu")
		(net "P5E_PEX2_STN5_TX_C_DP<91>")
	)
	(segment
		(start 338.217002 -379.899164)
		(end 338.090002 -379.772164)
		(width 0.1651)
		(layer "In7.Cu")
		(net "P5E_PEX2_STN5_TX_C_DP<91>")
	)
	(segment
		(start 334.265524 -357.75773)
		(end 334.556354 -358.04856)
		(width 0.1651)
		(layer "In7.Cu")
		(net "P5E_PEX2_STN5_TX_C_DP<91>")
	)
	(segment
		(start 338.090002 -379.772164)
		(end 338.090002 -379.390148)
		(width 0.1651)
		(layer "In7.Cu")
		(net "P5E_PEX2_STN5_TX_C_DP<91>")
	)
	(segment
		(start 334.556354 -358.04856)
		(end 334.556354 -359.010204)
		(width 0.1651)
		(layer "In7.Cu")
		(net "P5E_PEX2_STN5_TX_C_DP<91>")
	)
	(segment
		(start 337.95335 -366.701578)
		(end 338.105242 -366.757966)
		(width 0.1651)
		(layer "In7.Cu")
		(net "P5E_PEX2_STN5_TX_C_DP<91>")
	)
	(segment
		(start 338.934044 -368.567462)
		(end 338.934044 -379.612398)
		(width 0.1651)
		(layer "In7.Cu")
		(net "P5E_PEX2_STN5_TX_C_DP<91>")
	)
	(segment
		(start 338.647278 -379.899164)
		(end 338.217002 -379.899164)
		(width 0.1651)
		(layer "In7.Cu")
		(net "P5E_PEX2_STN5_TX_C_DP<91>")
	)
	(segment
		(start 337.80349 -366.099344)
		(end 337.747102 -366.250982)
		(width 0.1651)
		(layer "In7.Cu")
		(net "P5E_PEX2_STN5_TX_C_DP<91>")
	)
	(segment
		(start 338.934044 -379.612398)
		(end 338.647278 -379.899164)
		(width 0.1651)
		(layer "In7.Cu")
		(net "P5E_PEX2_STN5_TX_C_DP<91>")
	)
	(segment
		(start 168.972992 -345.170506)
		(end 168.972992 -344.539062)
		(width 0.13462)
		(layer "F.Cu")
		(net "P5E_PEX1_STN7_TX_C_DN<115>")
	)
	(segment
		(start 169.267632 -345.465146)
		(end 168.972992 -345.170506)
		(width 0.13462)
		(layer "F.Cu")
		(net "P5E_PEX1_STN7_TX_C_DN<115>")
	)
	(segment
		(start 168.972992 -344.539062)
		(end 169.293032 -344.219022)
		(width 0.13462)
		(layer "F.Cu")
		(net "P5E_PEX1_STN7_TX_C_DN<115>")
	)
	(segment
		(start 166.636954 -402.281136)
		(end 167.36949 -402.281136)
		(width 0.1651)
		(layer "In11.Cu")
		(net "P5E_PEX1_STN7_TX_C_DN<115>")
	)
	(segment
		(start 167.422322 -358.62387)
		(end 167.422322 -348.072964)
		(width 0.1651)
		(layer "In11.Cu")
		(net "P5E_PEX1_STN7_TX_C_DN<115>")
	)
	(segment
		(start 166.509954 -402.408136)
		(end 166.636954 -402.281136)
		(width 0.1651)
		(layer "In11.Cu")
		(net "P5E_PEX1_STN7_TX_C_DN<115>")
	)
	(segment
		(start 166.509954 -402.790152)
		(end 166.509954 -402.408136)
		(width 0.1651)
		(layer "In11.Cu")
		(net "P5E_PEX1_STN7_TX_C_DN<115>")
	)
	(segment
		(start 167.422322 -348.072964)
		(end 168.976802 -346.518484)
		(width 0.1651)
		(layer "In11.Cu")
		(net "P5E_PEX1_STN7_TX_C_DN<115>")
	)
	(segment
		(start 168.976802 -346.518484)
		(end 168.976802 -345.755976)
		(width 0.1651)
		(layer "In11.Cu")
		(net "P5E_PEX1_STN7_TX_C_DN<115>")
	)
	(segment
		(start 166.031926 -360.014266)
		(end 167.422322 -358.62387)
		(width 0.1651)
		(layer "In11.Cu")
		(net "P5E_PEX1_STN7_TX_C_DN<115>")
	)
	(segment
		(start 165.83787 -393.471146)
		(end 162.202876 -391.231374)
		(width 0.1651)
		(layer "In11.Cu")
		(net "P5E_PEX1_STN7_TX_C_DN<115>")
	)
	(segment
		(start 155.033218 -368.182144)
		(end 155.958794 -365.734092)
		(width 0.1651)
		(layer "In11.Cu")
		(net "P5E_PEX1_STN7_TX_C_DN<115>")
	)
	(segment
		(start 158.417514 -363.210602)
		(end 166.031926 -360.014266)
		(width 0.1651)
		(layer "In11.Cu")
		(net "P5E_PEX1_STN7_TX_C_DN<115>")
	)
	(segment
		(start 168.976802 -345.755976)
		(end 169.267632 -345.465146)
		(width 0.1651)
		(layer "In11.Cu")
		(net "P5E_PEX1_STN7_TX_C_DN<115>")
	)
	(segment
		(start 162.202876 -391.231374)
		(end 159.389064 -390.302242)
		(width 0.1651)
		(layer "In11.Cu")
		(net "P5E_PEX1_STN7_TX_C_DN<115>")
	)
	(segment
		(start 155.090368 -385.25196)
		(end 154.85745 -382.56337)
		(width 0.1651)
		(layer "In11.Cu")
		(net "P5E_PEX1_STN7_TX_C_DN<115>")
	)
	(segment
		(start 159.389064 -390.302242)
		(end 156.164788 -387.909308)
		(width 0.1651)
		(layer "In11.Cu")
		(net "P5E_PEX1_STN7_TX_C_DN<115>")
	)
	(segment
		(start 167.675052 -401.975574)
		(end 167.675052 -395.308328)
		(width 0.1651)
		(layer "In11.Cu")
		(net "P5E_PEX1_STN7_TX_C_DN<115>")
	)
	(segment
		(start 154.85745 -382.56337)
		(end 155.033218 -368.182144)
		(width 0.1651)
		(layer "In11.Cu")
		(net "P5E_PEX1_STN7_TX_C_DN<115>")
	)
	(segment
		(start 167.675052 -395.308328)
		(end 165.83787 -393.471146)
		(width 0.1651)
		(layer "In11.Cu")
		(net "P5E_PEX1_STN7_TX_C_DN<115>")
	)
	(segment
		(start 167.36949 -402.281136)
		(end 167.675052 -401.975574)
		(width 0.1651)
		(layer "In11.Cu")
		(net "P5E_PEX1_STN7_TX_C_DN<115>")
	)
	(segment
		(start 155.958794 -365.734092)
		(end 158.417514 -363.210602)
		(width 0.1651)
		(layer "In11.Cu")
		(net "P5E_PEX1_STN7_TX_C_DN<115>")
	)
	(segment
		(start 156.164788 -387.909308)
		(end 155.090368 -385.25196)
		(width 0.1651)
		(layer "In11.Cu")
		(net "P5E_PEX1_STN7_TX_C_DN<115>")
	)
	(segment
		(start 399.737072 -349.511366)
		(end 399.737072 -348.880938)
		(width 0.13462)
		(layer "F.Cu")
		(net "P5E_PEX3_STN5_TX_DN<93>")
	)
	(segment
		(start 400.05762 -349.831914)
		(end 399.737072 -349.511366)
		(width 0.13462)
		(layer "F.Cu")
		(net "P5E_PEX3_STN5_TX_DN<93>")
	)
	(segment
		(start 399.737072 -348.880938)
		(end 400.03222 -348.58579)
		(width 0.13462)
		(layer "F.Cu")
		(net "P5E_PEX3_STN5_TX_DN<93>")
	)
	(segment
		(start 419.073838 -313.570112)
		(end 419.235636 -313.570112)
		(width 0.1143)
		(layer "In13.Cu")
		(net "P5E_PEX3_STN5_TX_DN<93>")
	)
	(segment
		(start 419.015926 -320.046096)
		(end 419.015926 -320.017648)
		(width 0.1143)
		(layer "In13.Cu")
		(net "P5E_PEX3_STN5_TX_DN<93>")
	)
	(segment
		(start 419.349936 -313.684412)
		(end 419.349936 -313.949842)
		(width 0.1143)
		(layer "In13.Cu")
		(net "P5E_PEX3_STN5_TX_DN<93>")
	)
	(segment
		(start 419.015926 -320.017648)
		(end 418.970206 -319.971928)
		(width 0.1143)
		(layer "In13.Cu")
		(net "P5E_PEX3_STN5_TX_DN<93>")
	)
	(segment
		(start 401.454366 -341.00008)
		(end 401.61337 -340.64448)
		(width 0.1651)
		(layer "In13.Cu")
		(net "P5E_PEX3_STN5_TX_DN<93>")
	)
	(segment
		(start 418.970206 -319.971928)
		(end 418.970206 -313.673744)
		(width 0.1143)
		(layer "In13.Cu")
		(net "P5E_PEX3_STN5_TX_DN<93>")
	)
	(segment
		(start 399.74139 -348.29496)
		(end 399.74139 -347.784674)
		(width 0.1651)
		(layer "In13.Cu")
		(net "P5E_PEX3_STN5_TX_DN<93>")
	)
	(segment
		(start 401.61337 -340.64448)
		(end 416.394646 -326.549258)
		(width 0.1651)
		(layer "In13.Cu")
		(net "P5E_PEX3_STN5_TX_DN<93>")
	)
	(segment
		(start 400.03222 -348.58579)
		(end 399.74139 -348.29496)
		(width 0.1651)
		(layer "In13.Cu")
		(net "P5E_PEX3_STN5_TX_DN<93>")
	)
	(segment
		(start 419.015926 -322.725034)
		(end 419.015926 -320.046096)
		(width 0.1651)
		(layer "In13.Cu")
		(net "P5E_PEX3_STN5_TX_DN<93>")
	)
	(segment
		(start 416.394646 -326.549258)
		(end 419.015926 -322.725034)
		(width 0.1651)
		(layer "In13.Cu")
		(net "P5E_PEX3_STN5_TX_DN<93>")
	)
	(segment
		(start 401.45462 -341.00008)
		(end 401.454366 -341.00008)
		(width 0.1651)
		(layer "In13.Cu")
		(net "P5E_PEX3_STN5_TX_DN<93>")
	)
	(segment
		(start 401.29587 -341.355426)
		(end 401.45462 -341.00008)
		(width 0.1651)
		(layer "In13.Cu")
		(net "P5E_PEX3_STN5_TX_DN<93>")
	)
	(segment
		(start 418.970206 -313.673744)
		(end 419.073838 -313.570112)
		(width 0.1143)
		(layer "In13.Cu")
		(net "P5E_PEX3_STN5_TX_DN<93>")
	)
	(segment
		(start 399.74139 -347.784674)
		(end 401.29587 -346.230194)
		(width 0.1651)
		(layer "In13.Cu")
		(net "P5E_PEX3_STN5_TX_DN<93>")
	)
	(segment
		(start 419.235636 -313.570112)
		(end 419.349936 -313.684412)
		(width 0.1143)
		(layer "In13.Cu")
		(net "P5E_PEX3_STN5_TX_DN<93>")
	)
	(segment
		(start 401.29587 -346.230194)
		(end 401.29587 -341.355426)
		(width 0.1651)
		(layer "In13.Cu")
		(net "P5E_PEX3_STN5_TX_DN<93>")
	)
	(segment
		(start 289.954462 -356.831646)
		(end 289.954462 -357.46309)
		(width 0.13462)
		(layer "F.Cu")
		(net "P5E_PEX2_STN7_TX_C_DP<123>")
	)
	(segment
		(start 289.954462 -357.46309)
		(end 289.659822 -357.75773)
		(width 0.13462)
		(layer "F.Cu")
		(net "P5E_PEX2_STN7_TX_C_DP<123>")
	)
	(segment
		(start 289.634422 -356.511606)
		(end 289.954462 -356.831646)
		(width 0.13462)
		(layer "F.Cu")
		(net "P5E_PEX2_STN7_TX_C_DP<123>")
	)
	(segment
		(start 294.216836 -375.999248)
		(end 294.647112 -375.999248)
		(width 0.1651)
		(layer "In7.Cu")
		(net "P5E_PEX2_STN7_TX_C_DP<123>")
	)
	(segment
		(start 294.089836 -375.872248)
		(end 294.216836 -375.999248)
		(width 0.1651)
		(layer "In7.Cu")
		(net "P5E_PEX2_STN7_TX_C_DP<123>")
	)
	(segment
		(start 294.933878 -368.722402)
		(end 294.311324 -367.481612)
		(width 0.1651)
		(layer "In7.Cu")
		(net "P5E_PEX2_STN7_TX_C_DP<123>")
	)
	(segment
		(start 294.089836 -375.490232)
		(end 294.089836 -375.872248)
		(width 0.1651)
		(layer "In7.Cu")
		(net "P5E_PEX2_STN7_TX_C_DP<123>")
	)
	(segment
		(start 293.967408 -367.006124)
		(end 294.009318 -366.879886)
		(width 0.1651)
		(layer "In7.Cu")
		(net "P5E_PEX2_STN7_TX_C_DP<123>")
	)
	(segment
		(start 294.185086 -367.439702)
		(end 293.967408 -367.006124)
		(width 0.1651)
		(layer "In7.Cu")
		(net "P5E_PEX2_STN7_TX_C_DP<123>")
	)
	(segment
		(start 289.950652 -358.04856)
		(end 289.659822 -357.75773)
		(width 0.1651)
		(layer "In7.Cu")
		(net "P5E_PEX2_STN7_TX_C_DP<123>")
	)
	(segment
		(start 294.009318 -366.879886)
		(end 289.950652 -358.791002)
		(width 0.1651)
		(layer "In7.Cu")
		(net "P5E_PEX2_STN7_TX_C_DP<123>")
	)
	(segment
		(start 294.647112 -375.999248)
		(end 294.933878 -375.712482)
		(width 0.1651)
		(layer "In7.Cu")
		(net "P5E_PEX2_STN7_TX_C_DP<123>")
	)
	(segment
		(start 294.933878 -375.712482)
		(end 294.933878 -368.722402)
		(width 0.1651)
		(layer "In7.Cu")
		(net "P5E_PEX2_STN7_TX_C_DP<123>")
	)
	(segment
		(start 294.311324 -367.481612)
		(end 294.185086 -367.439702)
		(width 0.1651)
		(layer "In7.Cu")
		(net "P5E_PEX2_STN7_TX_C_DP<123>")
	)
	(segment
		(start 289.950652 -358.791002)
		(end 289.950652 -358.04856)
		(width 0.1651)
		(layer "In7.Cu")
		(net "P5E_PEX2_STN7_TX_C_DP<123>")
	)
	(segment
		(start 390.135872 -355.658674)
		(end 390.135872 -355.026214)
		(width 0.13462)
		(layer "F.Cu")
		(net "P5E_PEX3_STN5_TX_DP<89>")
	)
	(segment
		(start 389.81634 -355.978206)
		(end 390.135872 -355.658674)
		(width 0.13462)
		(layer "F.Cu")
		(net "P5E_PEX3_STN5_TX_DP<89>")
	)
	(segment
		(start 390.135872 -355.026214)
		(end 389.84174 -354.732082)
		(width 0.13462)
		(layer "F.Cu")
		(net "P5E_PEX3_STN5_TX_DP<89>")
	)
	(segment
		(start 414.933892 -321.277742)
		(end 414.933892 -320.046096)
		(width 0.1651)
		(layer "In13.Cu")
		(net "P5E_PEX3_STN5_TX_DP<89>")
	)
	(segment
		(start 415.549842 -313.265312)
		(end 415.549842 -312.999882)
		(width 0.1143)
		(layer "In13.Cu")
		(net "P5E_PEX3_STN5_TX_DP<89>")
	)
	(segment
		(start 414.933892 -320.046096)
		(end 414.933892 -320.017648)
		(width 0.1143)
		(layer "In13.Cu")
		(net "P5E_PEX3_STN5_TX_DP<89>")
	)
	(segment
		(start 389.84174 -354.732082)
		(end 390.13257 -354.441252)
		(width 0.1651)
		(layer "In13.Cu")
		(net "P5E_PEX3_STN5_TX_DP<89>")
	)
	(segment
		(start 414.979612 -313.59475)
		(end 415.19475 -313.379612)
		(width 0.1143)
		(layer "In13.Cu")
		(net "P5E_PEX3_STN5_TX_DP<89>")
	)
	(segment
		(start 413.928306 -322.656454)
		(end 414.933892 -321.277742)
		(width 0.1651)
		(layer "In13.Cu")
		(net "P5E_PEX3_STN5_TX_DP<89>")
	)
	(segment
		(start 415.19475 -313.379612)
		(end 415.435542 -313.379612)
		(width 0.1143)
		(layer "In13.Cu")
		(net "P5E_PEX3_STN5_TX_DP<89>")
	)
	(segment
		(start 392.169142 -341.102188)
		(end 413.928306 -322.656454)
		(width 0.1651)
		(layer "In13.Cu")
		(net "P5E_PEX3_STN5_TX_DP<89>")
	)
	(segment
		(start 414.979612 -319.971928)
		(end 414.979612 -313.59475)
		(width 0.1143)
		(layer "In13.Cu")
		(net "P5E_PEX3_STN5_TX_DP<89>")
	)
	(segment
		(start 390.13257 -354.441252)
		(end 390.13257 -353.814126)
		(width 0.1651)
		(layer "In13.Cu")
		(net "P5E_PEX3_STN5_TX_DP<89>")
	)
	(segment
		(start 391.68705 -352.259646)
		(end 391.68705 -342.090248)
		(width 0.1651)
		(layer "In13.Cu")
		(net "P5E_PEX3_STN5_TX_DP<89>")
	)
	(segment
		(start 414.933892 -320.017648)
		(end 414.979612 -319.971928)
		(width 0.1143)
		(layer "In13.Cu")
		(net "P5E_PEX3_STN5_TX_DP<89>")
	)
	(segment
		(start 390.13257 -353.814126)
		(end 391.68705 -352.259646)
		(width 0.1651)
		(layer "In13.Cu")
		(net "P5E_PEX3_STN5_TX_DP<89>")
	)
	(segment
		(start 415.435542 -313.379612)
		(end 415.549842 -313.265312)
		(width 0.1143)
		(layer "In13.Cu")
		(net "P5E_PEX3_STN5_TX_DP<89>")
	)
	(segment
		(start 391.68705 -342.090248)
		(end 392.169142 -341.102188)
		(width 0.1651)
		(layer "In13.Cu")
		(net "P5E_PEX3_STN5_TX_DP<89>")
	)
	(segment
		(start 400.05762 -355.978206)
		(end 399.737072 -355.657658)
		(width 0.13462)
		(layer "F.Cu")
		(net "P5E_PEX3_STN5_TX_DN<86>")
	)
	(segment
		(start 399.737072 -355.02723)
		(end 400.03222 -354.732082)
		(width 0.13462)
		(layer "F.Cu")
		(net "P5E_PEX3_STN5_TX_DN<86>")
	)
	(segment
		(start 399.737072 -355.657658)
		(end 399.737072 -355.02723)
		(width 0.13462)
		(layer "F.Cu")
		(net "P5E_PEX3_STN5_TX_DN<86>")
	)
	(segment
		(start 412.365952 -319.960752)
		(end 412.320232 -319.915032)
		(width 0.1143)
		(layer "In7.Cu")
		(net "P5E_PEX3_STN5_TX_DN<86>")
	)
	(segment
		(start 412.365952 -324.566026)
		(end 412.365952 -319.9892)
		(width 0.1651)
		(layer "In7.Cu")
		(net "P5E_PEX3_STN5_TX_DN<86>")
	)
	(segment
		(start 411.160468 -327.476358)
		(end 412.365952 -324.566026)
		(width 0.1651)
		(layer "In7.Cu")
		(net "P5E_PEX3_STN5_TX_DN<86>")
	)
	(segment
		(start 412.320232 -319.915032)
		(end 412.320232 -311.784492)
		(width 0.1143)
		(layer "In7.Cu")
		(net "P5E_PEX3_STN5_TX_DN<86>")
	)
	(segment
		(start 412.699962 -311.784492)
		(end 412.699962 -312.049922)
		(width 0.1143)
		(layer "In7.Cu")
		(net "P5E_PEX3_STN5_TX_DN<86>")
	)
	(segment
		(start 401.29587 -352.376486)
		(end 401.29587 -341.574882)
		(width 0.1651)
		(layer "In7.Cu")
		(net "P5E_PEX3_STN5_TX_DN<86>")
	)
	(segment
		(start 400.03222 -354.732082)
		(end 399.74139 -354.441252)
		(width 0.1651)
		(layer "In7.Cu")
		(net "P5E_PEX3_STN5_TX_DN<86>")
	)
	(segment
		(start 399.74139 -353.930966)
		(end 401.29587 -352.376486)
		(width 0.1651)
		(layer "In7.Cu")
		(net "P5E_PEX3_STN5_TX_DN<86>")
	)
	(segment
		(start 412.585662 -311.670192)
		(end 412.699962 -311.784492)
		(width 0.1143)
		(layer "In7.Cu")
		(net "P5E_PEX3_STN5_TX_DN<86>")
	)
	(segment
		(start 409.339034 -330.202286)
		(end 411.160468 -327.476358)
		(width 0.1651)
		(layer "In7.Cu")
		(net "P5E_PEX3_STN5_TX_DN<86>")
	)
	(segment
		(start 412.365952 -319.9892)
		(end 412.365952 -319.960752)
		(width 0.1143)
		(layer "In7.Cu")
		(net "P5E_PEX3_STN5_TX_DN<86>")
	)
	(segment
		(start 401.29587 -341.574882)
		(end 409.339034 -330.202286)
		(width 0.1651)
		(layer "In7.Cu")
		(net "P5E_PEX3_STN5_TX_DN<86>")
	)
	(segment
		(start 412.320232 -311.784492)
		(end 412.434532 -311.670192)
		(width 0.1143)
		(layer "In7.Cu")
		(net "P5E_PEX3_STN5_TX_DN<86>")
	)
	(segment
		(start 412.434532 -311.670192)
		(end 412.585662 -311.670192)
		(width 0.1143)
		(layer "In7.Cu")
		(net "P5E_PEX3_STN5_TX_DN<86>")
	)
	(segment
		(start 399.74139 -354.441252)
		(end 399.74139 -353.930966)
		(width 0.1651)
		(layer "In7.Cu")
		(net "P5E_PEX3_STN5_TX_DN<86>")
	)
	(segment
		(start 328.616564 -357.46309)
		(end 328.911204 -357.75773)
		(width 0.13462)
		(layer "F.Cu")
		(net "P5E_PEX2_STN5_TX_C_DN<88>")
	)
	(segment
		(start 328.616564 -356.831646)
		(end 328.616564 -357.46309)
		(width 0.13462)
		(layer "F.Cu")
		(net "P5E_PEX2_STN5_TX_C_DN<88>")
	)
	(segment
		(start 328.936604 -356.511606)
		(end 328.616564 -356.831646)
		(width 0.13462)
		(layer "F.Cu")
		(net "P5E_PEX2_STN5_TX_C_DN<88>")
	)
	(segment
		(start 331.490066 -379.20803)
		(end 331.490066 -379.590046)
		(width 0.1651)
		(layer "In7.Cu")
		(net "P5E_PEX2_STN5_TX_C_DN<88>")
	)
	(segment
		(start 332.616048 -368.460274)
		(end 332.616048 -378.629164)
		(width 0.1651)
		(layer "In7.Cu")
		(net "P5E_PEX2_STN5_TX_C_DN<88>")
	)
	(segment
		(start 328.620374 -358.813862)
		(end 332.616048 -368.460274)
		(width 0.1651)
		(layer "In7.Cu")
		(net "P5E_PEX2_STN5_TX_C_DN<88>")
	)
	(segment
		(start 328.620374 -358.04856)
		(end 328.620374 -358.813862)
		(width 0.1651)
		(layer "In7.Cu")
		(net "P5E_PEX2_STN5_TX_C_DN<88>")
	)
	(segment
		(start 332.616048 -378.629164)
		(end 332.164182 -379.08103)
		(width 0.1651)
		(layer "In7.Cu")
		(net "P5E_PEX2_STN5_TX_C_DN<88>")
	)
	(segment
		(start 331.617066 -379.08103)
		(end 331.490066 -379.20803)
		(width 0.1651)
		(layer "In7.Cu")
		(net "P5E_PEX2_STN5_TX_C_DN<88>")
	)
	(segment
		(start 332.164182 -379.08103)
		(end 331.617066 -379.08103)
		(width 0.1651)
		(layer "In7.Cu")
		(net "P5E_PEX2_STN5_TX_C_DN<88>")
	)
	(segment
		(start 328.911204 -357.75773)
		(end 328.620374 -358.04856)
		(width 0.1651)
		(layer "In7.Cu")
		(net "P5E_PEX2_STN5_TX_C_DN<88>")
	)
	(segment
		(start 83.429602 -349.511874)
		(end 83.429602 -348.88043)
		(width 0.13462)
		(layer "F.Cu")
		(net "P5E_PEX0_STN6_TX_DP<101>")
	)
	(segment
		(start 83.109562 -349.831914)
		(end 83.429602 -349.511874)
		(width 0.13462)
		(layer "F.Cu")
		(net "P5E_PEX0_STN6_TX_DP<101>")
	)
	(segment
		(start 83.429602 -348.88043)
		(end 83.134962 -348.58579)
		(width 0.13462)
		(layer "F.Cu")
		(net "P5E_PEX0_STN6_TX_DP<101>")
	)
	(segment
		(start 59.344306 -327.50633)
		(end 54.486302 -325.494142)
		(width 0.1651)
		(layer "In13.Cu")
		(net "P5E_PEX0_STN6_TX_DP<101>")
	)
	(segment
		(start 52.910994 -311.479692)
		(end 52.999894 -311.390792)
		(width 0.1143)
		(layer "In13.Cu")
		(net "P5E_PEX0_STN6_TX_DP<101>")
	)
	(segment
		(start 83.425792 -348.29496)
		(end 83.425792 -347.599508)
		(width 0.1651)
		(layer "In13.Cu")
		(net "P5E_PEX0_STN6_TX_DP<101>")
	)
	(segment
		(start 84.980272 -342.02116)
		(end 84.264246 -340.826852)
		(width 0.1651)
		(layer "In13.Cu")
		(net "P5E_PEX0_STN6_TX_DP<101>")
	)
	(segment
		(start 84.264246 -340.826852)
		(end 59.344306 -327.50633)
		(width 0.1651)
		(layer "In13.Cu")
		(net "P5E_PEX0_STN6_TX_DP<101>")
	)
	(segment
		(start 52.429664 -311.718198)
		(end 52.66817 -311.479692)
		(width 0.1143)
		(layer "In13.Cu")
		(net "P5E_PEX0_STN6_TX_DP<101>")
	)
	(segment
		(start 83.425792 -347.599508)
		(end 84.980272 -346.045028)
		(width 0.1651)
		(layer "In13.Cu")
		(net "P5E_PEX0_STN6_TX_DP<101>")
	)
	(segment
		(start 52.383944 -321.916552)
		(end 52.383944 -320.294)
		(width 0.1651)
		(layer "In13.Cu")
		(net "P5E_PEX0_STN6_TX_DP<101>")
	)
	(segment
		(start 52.999894 -311.390792)
		(end 52.999894 -311.099962)
		(width 0.1143)
		(layer "In13.Cu")
		(net "P5E_PEX0_STN6_TX_DP<101>")
	)
	(segment
		(start 52.66817 -311.479692)
		(end 52.910994 -311.479692)
		(width 0.1143)
		(layer "In13.Cu")
		(net "P5E_PEX0_STN6_TX_DP<101>")
	)
	(segment
		(start 52.429664 -320.226182)
		(end 52.429664 -311.718198)
		(width 0.1143)
		(layer "In13.Cu")
		(net "P5E_PEX0_STN6_TX_DP<101>")
	)
	(segment
		(start 53.427122 -324.434962)
		(end 52.383944 -321.916552)
		(width 0.1651)
		(layer "In13.Cu")
		(net "P5E_PEX0_STN6_TX_DP<101>")
	)
	(segment
		(start 84.980272 -346.045028)
		(end 84.980272 -342.02116)
		(width 0.1651)
		(layer "In13.Cu")
		(net "P5E_PEX0_STN6_TX_DP<101>")
	)
	(segment
		(start 54.486302 -325.494142)
		(end 53.427122 -324.434962)
		(width 0.1651)
		(layer "In13.Cu")
		(net "P5E_PEX0_STN6_TX_DP<101>")
	)
	(segment
		(start 52.383944 -320.271902)
		(end 52.429664 -320.226182)
		(width 0.1143)
		(layer "In13.Cu")
		(net "P5E_PEX0_STN6_TX_DP<101>")
	)
	(segment
		(start 83.134962 -348.58579)
		(end 83.425792 -348.29496)
		(width 0.1651)
		(layer "In13.Cu")
		(net "P5E_PEX0_STN6_TX_DP<101>")
	)
	(segment
		(start 52.383944 -320.294)
		(end 52.383944 -320.271902)
		(width 0.1143)
		(layer "In13.Cu")
		(net "P5E_PEX0_STN6_TX_DP<101>")
	)
	(segment
		(start 396.628112 -342.734646)
		(end 396.92326 -342.439498)
		(width 0.13462)
		(layer "F.Cu")
		(net "P5E_PEX3_STN5_TX_DN<91>")
	)
	(segment
		(start 396.94866 -343.685622)
		(end 396.628112 -343.365074)
		(width 0.13462)
		(layer "F.Cu")
		(net "P5E_PEX3_STN5_TX_DN<91>")
	)
	(segment
		(start 396.628112 -343.365074)
		(end 396.628112 -342.734646)
		(width 0.13462)
		(layer "F.Cu")
		(net "P5E_PEX3_STN5_TX_DN<91>")
	)
	(segment
		(start 396.92326 -342.439498)
		(end 396.63243 -342.148668)
		(width 0.1651)
		(layer "In13.Cu")
		(net "P5E_PEX3_STN5_TX_DN<91>")
	)
	(segment
		(start 396.63243 -342.148668)
		(end 396.63243 -341.614506)
		(width 0.1651)
		(layer "In13.Cu")
		(net "P5E_PEX3_STN5_TX_DN<91>")
	)
	(segment
		(start 417.116006 -320.017648)
		(end 417.070286 -319.971928)
		(width 0.1143)
		(layer "In13.Cu")
		(net "P5E_PEX3_STN5_TX_DN<91>")
	)
	(segment
		(start 417.450016 -313.684412)
		(end 417.450016 -313.949842)
		(width 0.1143)
		(layer "In13.Cu")
		(net "P5E_PEX3_STN5_TX_DN<91>")
	)
	(segment
		(start 417.116006 -322.061078)
		(end 417.116006 -320.046096)
		(width 0.1651)
		(layer "In13.Cu")
		(net "P5E_PEX3_STN5_TX_DN<91>")
	)
	(segment
		(start 417.173918 -313.570112)
		(end 417.335716 -313.570112)
		(width 0.1143)
		(layer "In13.Cu")
		(net "P5E_PEX3_STN5_TX_DN<91>")
	)
	(segment
		(start 396.63243 -341.614506)
		(end 396.802864 -341.269066)
		(width 0.1651)
		(layer "In13.Cu")
		(net "P5E_PEX3_STN5_TX_DN<91>")
	)
	(segment
		(start 396.802864 -341.269066)
		(end 415.042096 -324.98284)
		(width 0.1651)
		(layer "In13.Cu")
		(net "P5E_PEX3_STN5_TX_DN<91>")
	)
	(segment
		(start 417.116006 -320.046096)
		(end 417.116006 -320.017648)
		(width 0.1143)
		(layer "In13.Cu")
		(net "P5E_PEX3_STN5_TX_DN<91>")
	)
	(segment
		(start 417.070286 -319.971928)
		(end 417.070286 -313.673744)
		(width 0.1143)
		(layer "In13.Cu")
		(net "P5E_PEX3_STN5_TX_DN<91>")
	)
	(segment
		(start 417.070286 -313.673744)
		(end 417.173918 -313.570112)
		(width 0.1143)
		(layer "In13.Cu")
		(net "P5E_PEX3_STN5_TX_DN<91>")
	)
	(segment
		(start 417.335716 -313.570112)
		(end 417.450016 -313.684412)
		(width 0.1143)
		(layer "In13.Cu")
		(net "P5E_PEX3_STN5_TX_DN<91>")
	)
	(segment
		(start 415.042096 -324.98284)
		(end 417.116006 -322.061078)
		(width 0.1651)
		(layer "In13.Cu")
		(net "P5E_PEX3_STN5_TX_DN<91>")
	)
	(segment
		(start 92.756482 -355.026722)
		(end 92.461842 -354.732082)
		(width 0.13462)
		(layer "F.Cu")
		(net "P5E_PEX0_STN6_TX_DP<96>")
	)
	(segment
		(start 92.436442 -355.978206)
		(end 92.756482 -355.658166)
		(width 0.13462)
		(layer "F.Cu")
		(net "P5E_PEX0_STN6_TX_DP<96>")
	)
	(segment
		(start 92.756482 -355.658166)
		(end 92.756482 -355.026722)
		(width 0.13462)
		(layer "F.Cu")
		(net "P5E_PEX0_STN6_TX_DP<96>")
	)
	(segment
		(start 57.133998 -320.19875)
		(end 57.133998 -320.905632)
		(width 0.1651)
		(layer "In13.Cu")
		(net "P5E_PEX0_STN6_TX_DP<96>")
	)
	(segment
		(start 57.418478 -313.379612)
		(end 57.179718 -313.618372)
		(width 0.1143)
		(layer "In13.Cu")
		(net "P5E_PEX0_STN6_TX_DP<96>")
	)
	(segment
		(start 92.423234 -339.507068)
		(end 93.798644 -340.882224)
		(width 0.1651)
		(layer "In13.Cu")
		(net "P5E_PEX0_STN6_TX_DP<96>")
	)
	(segment
		(start 92.752672 -353.635564)
		(end 92.752672 -354.441252)
		(width 0.1651)
		(layer "In13.Cu")
		(net "P5E_PEX0_STN6_TX_DP<96>")
	)
	(segment
		(start 57.133998 -320.905632)
		(end 57.609994 -321.618102)
		(width 0.1651)
		(layer "In13.Cu")
		(net "P5E_PEX0_STN6_TX_DP<96>")
	)
	(segment
		(start 57.133998 -320.176652)
		(end 57.133998 -320.19875)
		(width 0.1143)
		(layer "In13.Cu")
		(net "P5E_PEX0_STN6_TX_DP<96>")
	)
	(segment
		(start 93.798644 -340.882224)
		(end 94.307152 -342.109806)
		(width 0.1651)
		(layer "In13.Cu")
		(net "P5E_PEX0_STN6_TX_DP<96>")
	)
	(segment
		(start 92.752672 -354.441252)
		(end 92.461842 -354.732082)
		(width 0.1651)
		(layer "In13.Cu")
		(net "P5E_PEX0_STN6_TX_DP<96>")
	)
	(segment
		(start 57.609994 -321.618102)
		(end 68.906136 -326.297036)
		(width 0.1651)
		(layer "In13.Cu")
		(net "P5E_PEX0_STN6_TX_DP<96>")
	)
	(segment
		(start 57.661048 -313.379612)
		(end 57.418478 -313.379612)
		(width 0.1143)
		(layer "In13.Cu")
		(net "P5E_PEX0_STN6_TX_DP<96>")
	)
	(segment
		(start 92.423488 -339.507068)
		(end 92.423234 -339.507068)
		(width 0.1651)
		(layer "In13.Cu")
		(net "P5E_PEX0_STN6_TX_DP<96>")
	)
	(segment
		(start 68.906136 -326.297036)
		(end 91.048078 -338.131912)
		(width 0.1651)
		(layer "In13.Cu")
		(net "P5E_PEX0_STN6_TX_DP<96>")
	)
	(segment
		(start 94.307152 -352.081084)
		(end 92.752672 -353.635564)
		(width 0.1651)
		(layer "In13.Cu")
		(net "P5E_PEX0_STN6_TX_DP<96>")
	)
	(segment
		(start 91.048078 -338.131912)
		(end 92.423488 -339.507068)
		(width 0.1651)
		(layer "In13.Cu")
		(net "P5E_PEX0_STN6_TX_DP<96>")
	)
	(segment
		(start 94.307152 -342.109806)
		(end 94.307152 -352.081084)
		(width 0.1651)
		(layer "In13.Cu")
		(net "P5E_PEX0_STN6_TX_DP<96>")
	)
	(segment
		(start 57.749948 -312.999882)
		(end 57.749948 -313.290712)
		(width 0.1143)
		(layer "In13.Cu")
		(net "P5E_PEX0_STN6_TX_DP<96>")
	)
	(segment
		(start 57.749948 -313.290712)
		(end 57.661048 -313.379612)
		(width 0.1143)
		(layer "In13.Cu")
		(net "P5E_PEX0_STN6_TX_DP<96>")
	)
	(segment
		(start 57.179718 -313.618372)
		(end 57.179718 -320.130932)
		(width 0.1143)
		(layer "In13.Cu")
		(net "P5E_PEX0_STN6_TX_DP<96>")
	)
	(segment
		(start 57.179718 -320.130932)
		(end 57.133998 -320.176652)
		(width 0.1143)
		(layer "In13.Cu")
		(net "P5E_PEX0_STN6_TX_DP<96>")
	)
	(segment
		(start 395.327632 -30.35808)
		(end 395.001242 -30.03169)
		(width 0.13462)
		(layer "F.Cu")
		(net "P5E_PEX3_STN2_TX_DN<41>")
	)
	(segment
		(start 395.946376 -30.35808)
		(end 395.327632 -30.35808)
		(width 0.13462)
		(layer "F.Cu")
		(net "P5E_PEX3_STN2_TX_DN<41>")
	)
	(segment
		(start 396.247366 -30.05709)
		(end 395.946376 -30.35808)
		(width 0.13462)
		(layer "F.Cu")
		(net "P5E_PEX3_STN2_TX_DN<41>")
	)
	(segment
		(start 398.11579 -271.399)
		(end 398.11579 -271.427448)
		(width 0.1143)
		(layer "In11.Cu")
		(net "P5E_PEX3_STN2_TX_DN<41>")
	)
	(segment
		(start 397.399764 -252.662436)
		(end 397.751554 -266.126976)
		(width 0.1651)
		(layer "In11.Cu")
		(net "P5E_PEX3_STN2_TX_DN<41>")
	)
	(segment
		(start 405.101044 -119.31269)
		(end 403.771862 -135.163052)
		(width 0.1651)
		(layer "In11.Cu")
		(net "P5E_PEX3_STN2_TX_DN<41>")
	)
	(segment
		(start 398.11579 -271.427448)
		(end 398.07007 -271.473168)
		(width 0.1143)
		(layer "In11.Cu")
		(net "P5E_PEX3_STN2_TX_DN<41>")
	)
	(segment
		(start 411.223206 -48.058832)
		(end 411.91815 -50.066194)
		(width 0.1651)
		(layer "In11.Cu")
		(net "P5E_PEX3_STN2_TX_DN<41>")
	)
	(segment
		(start 398.07007 -278.125936)
		(end 398.173702 -278.229568)
		(width 0.1143)
		(layer "In11.Cu")
		(net "P5E_PEX3_STN2_TX_DN<41>")
	)
	(segment
		(start 398.3355 -278.229568)
		(end 398.4498 -278.115268)
		(width 0.1143)
		(layer "In11.Cu")
		(net "P5E_PEX3_STN2_TX_DN<41>")
	)
	(segment
		(start 398.4498 -278.115268)
		(end 398.4498 -277.849838)
		(width 0.1143)
		(layer "In11.Cu")
		(net "P5E_PEX3_STN2_TX_DN<41>")
	)
	(segment
		(start 396.988792 -30.34792)
		(end 397.419576 -30.525212)
		(width 0.1651)
		(layer "In11.Cu")
		(net "P5E_PEX3_STN2_TX_DN<41>")
	)
	(segment
		(start 399.98904 -33.072578)
		(end 401.32762 -35.26917)
		(width 0.1651)
		(layer "In11.Cu")
		(net "P5E_PEX3_STN2_TX_DN<41>")
	)
	(segment
		(start 412.05912 -69.628766)
		(end 405.101044 -119.31269)
		(width 0.1651)
		(layer "In11.Cu")
		(net "P5E_PEX3_STN2_TX_DN<41>")
	)
	(segment
		(start 396.538196 -30.34792)
		(end 396.988792 -30.34792)
		(width 0.1651)
		(layer "In11.Cu")
		(net "P5E_PEX3_STN2_TX_DN<41>")
	)
	(segment
		(start 403.771862 -135.163052)
		(end 397.399764 -252.662436)
		(width 0.1651)
		(layer "In11.Cu")
		(net "P5E_PEX3_STN2_TX_DN<41>")
	)
	(segment
		(start 398.173702 -278.229568)
		(end 398.3355 -278.229568)
		(width 0.1143)
		(layer "In11.Cu")
		(net "P5E_PEX3_STN2_TX_DN<41>")
	)
	(segment
		(start 397.751554 -266.126976)
		(end 398.11579 -269.827756)
		(width 0.1651)
		(layer "In11.Cu")
		(net "P5E_PEX3_STN2_TX_DN<41>")
	)
	(segment
		(start 398.07007 -271.473168)
		(end 398.07007 -278.125936)
		(width 0.1143)
		(layer "In11.Cu")
		(net "P5E_PEX3_STN2_TX_DN<41>")
	)
	(segment
		(start 411.91815 -50.066194)
		(end 412.5722 -60.550298)
		(width 0.1651)
		(layer "In11.Cu")
		(net "P5E_PEX3_STN2_TX_DN<41>")
	)
	(segment
		(start 397.419576 -30.525212)
		(end 399.98904 -33.072578)
		(width 0.1651)
		(layer "In11.Cu")
		(net "P5E_PEX3_STN2_TX_DN<41>")
	)
	(segment
		(start 396.247366 -30.05709)
		(end 396.538196 -30.34792)
		(width 0.1651)
		(layer "In11.Cu")
		(net "P5E_PEX3_STN2_TX_DN<41>")
	)
	(segment
		(start 398.11579 -269.827756)
		(end 398.11579 -271.399)
		(width 0.1651)
		(layer "In11.Cu")
		(net "P5E_PEX3_STN2_TX_DN<41>")
	)
	(segment
		(start 412.5722 -60.550298)
		(end 412.05912 -69.628766)
		(width 0.1651)
		(layer "In11.Cu")
		(net "P5E_PEX3_STN2_TX_DN<41>")
	)
	(segment
		(start 401.32762 -35.26917)
		(end 411.223206 -48.058832)
		(width 0.1651)
		(layer "In11.Cu")
		(net "P5E_PEX3_STN2_TX_DN<41>")
	)
	(segment
		(start 444.674752 -28.82392)
		(end 444.35903 -29.139642)
		(width 0.13462)
		(layer "F.Cu")
		(net "P5E_PEX3_STN2_TX_DP<32>")
	)
	(segment
		(start 445.314832 -28.82392)
		(end 444.674752 -28.82392)
		(width 0.13462)
		(layer "F.Cu")
		(net "P5E_PEX3_STN2_TX_DP<32>")
	)
	(segment
		(start 445.605154 -29.114242)
		(end 445.314832 -28.82392)
		(width 0.13462)
		(layer "F.Cu")
		(net "P5E_PEX3_STN2_TX_DP<32>")
	)
	(segment
		(start 445.895984 -28.823412)
		(end 447.65976 -28.823412)
		(width 0.1651)
		(layer "In11.Cu")
		(net "P5E_PEX3_STN2_TX_DP<32>")
	)
	(segment
		(start 427.715934 -140.76553)
		(end 427.454822 -141.889734)
		(width 0.1651)
		(layer "In11.Cu")
		(net "P5E_PEX3_STN2_TX_DP<32>")
	)
	(segment
		(start 406.383998 -266.06373)
		(end 406.383998 -271.399)
		(width 0.1651)
		(layer "In11.Cu")
		(net "P5E_PEX3_STN2_TX_DP<32>")
	)
	(segment
		(start 443.531498 -81.8134)
		(end 429.967898 -105.9434)
		(width 0.1651)
		(layer "In11.Cu")
		(net "P5E_PEX3_STN2_TX_DP<32>")
	)
	(segment
		(start 447.65976 -28.823412)
		(end 449.95338 -29.735018)
		(width 0.1651)
		(layer "In11.Cu")
		(net "P5E_PEX3_STN2_TX_DP<32>")
	)
	(segment
		(start 449.95338 -29.735018)
		(end 452.059802 -31.84652)
		(width 0.1651)
		(layer "In11.Cu")
		(net "P5E_PEX3_STN2_TX_DP<32>")
	)
	(segment
		(start 453.502522 -34.486342)
		(end 456.467972 -39.912036)
		(width 0.1651)
		(layer "In11.Cu")
		(net "P5E_PEX3_STN2_TX_DP<32>")
	)
	(segment
		(start 453.1614 -34.021268)
		(end 453.399398 -34.456116)
		(width 0.1651)
		(layer "In11.Cu")
		(net "P5E_PEX3_STN2_TX_DP<32>")
	)
	(segment
		(start 453.502776 -34.486342)
		(end 453.502522 -34.486342)
		(width 0.1651)
		(layer "In11.Cu")
		(net "P5E_PEX3_STN2_TX_DP<32>")
	)
	(segment
		(start 457.440284 -56.946546)
		(end 455.140568 -68.690744)
		(width 0.1651)
		(layer "In11.Cu")
		(net "P5E_PEX3_STN2_TX_DP<32>")
	)
	(segment
		(start 452.851012 -33.45307)
		(end 452.95439 -33.483296)
		(width 0.1651)
		(layer "In11.Cu")
		(net "P5E_PEX3_STN2_TX_DP<32>")
	)
	(segment
		(start 425.691554 -161.014918)
		(end 406.383998 -266.06373)
		(width 0.1651)
		(layer "In11.Cu")
		(net "P5E_PEX3_STN2_TX_DP<32>")
	)
	(segment
		(start 453.19188 -33.91789)
		(end 453.1614 -34.021268)
		(width 0.1651)
		(layer "In11.Cu")
		(net "P5E_PEX3_STN2_TX_DP<32>")
	)
	(segment
		(start 426.644308 -153.837386)
		(end 425.691554 -161.014918)
		(width 0.1651)
		(layer "In11.Cu")
		(net "P5E_PEX3_STN2_TX_DP<32>")
	)
	(segment
		(start 406.999948 -280.434288)
		(end 406.999948 -280.699718)
		(width 0.1143)
		(layer "In11.Cu")
		(net "P5E_PEX3_STN2_TX_DP<32>")
	)
	(segment
		(start 406.429718 -271.473168)
		(end 406.429718 -280.10485)
		(width 0.1143)
		(layer "In11.Cu")
		(net "P5E_PEX3_STN2_TX_DP<32>")
	)
	(segment
		(start 445.2112 -80.133698)
		(end 443.531498 -81.8134)
		(width 0.1651)
		(layer "In11.Cu")
		(net "P5E_PEX3_STN2_TX_DP<32>")
	)
	(segment
		(start 455.140568 -68.690744)
		(end 452.743062 -75.376786)
		(width 0.1651)
		(layer "In11.Cu")
		(net "P5E_PEX3_STN2_TX_DP<32>")
	)
	(segment
		(start 453.399398 -34.456116)
		(end 453.502776 -34.486342)
		(width 0.1651)
		(layer "In11.Cu")
		(net "P5E_PEX3_STN2_TX_DP<32>")
	)
	(segment
		(start 427.268894 -146.24304)
		(end 426.644308 -153.837386)
		(width 0.1651)
		(layer "In11.Cu")
		(net "P5E_PEX3_STN2_TX_DP<32>")
	)
	(segment
		(start 406.644856 -280.319988)
		(end 406.885648 -280.319988)
		(width 0.1143)
		(layer "In11.Cu")
		(net "P5E_PEX3_STN2_TX_DP<32>")
	)
	(segment
		(start 428.474886 -117.958362)
		(end 427.715934 -135.763508)
		(width 0.1651)
		(layer "In11.Cu")
		(net "P5E_PEX3_STN2_TX_DP<32>")
	)
	(segment
		(start 451.844918 -76.534772)
		(end 445.2112 -80.133698)
		(width 0.1651)
		(layer "In11.Cu")
		(net "P5E_PEX3_STN2_TX_DP<32>")
	)
	(segment
		(start 406.429718 -280.10485)
		(end 406.644856 -280.319988)
		(width 0.1143)
		(layer "In11.Cu")
		(net "P5E_PEX3_STN2_TX_DP<32>")
	)
	(segment
		(start 452.743062 -75.376786)
		(end 451.844918 -76.534772)
		(width 0.1651)
		(layer "In11.Cu")
		(net "P5E_PEX3_STN2_TX_DP<32>")
	)
	(segment
		(start 406.383998 -271.427448)
		(end 406.429718 -271.473168)
		(width 0.1143)
		(layer "In11.Cu")
		(net "P5E_PEX3_STN2_TX_DP<32>")
	)
	(segment
		(start 406.383998 -271.399)
		(end 406.383998 -271.427448)
		(width 0.1143)
		(layer "In11.Cu")
		(net "P5E_PEX3_STN2_TX_DP<32>")
	)
	(segment
		(start 445.605154 -29.114242)
		(end 445.895984 -28.823412)
		(width 0.1651)
		(layer "In11.Cu")
		(net "P5E_PEX3_STN2_TX_DP<32>")
	)
	(segment
		(start 429.967898 -105.9434)
		(end 428.474886 -117.958362)
		(width 0.1651)
		(layer "In11.Cu")
		(net "P5E_PEX3_STN2_TX_DP<32>")
	)
	(segment
		(start 452.059802 -31.84652)
		(end 452.643494 -32.914844)
		(width 0.1651)
		(layer "In11.Cu")
		(net "P5E_PEX3_STN2_TX_DP<32>")
	)
	(segment
		(start 427.454822 -141.889734)
		(end 427.268894 -146.24304)
		(width 0.1651)
		(layer "In11.Cu")
		(net "P5E_PEX3_STN2_TX_DP<32>")
	)
	(segment
		(start 452.613268 -33.018222)
		(end 452.851012 -33.45307)
		(width 0.1651)
		(layer "In11.Cu")
		(net "P5E_PEX3_STN2_TX_DP<32>")
	)
	(segment
		(start 452.643494 -32.914844)
		(end 452.613268 -33.018222)
		(width 0.1651)
		(layer "In11.Cu")
		(net "P5E_PEX3_STN2_TX_DP<32>")
	)
	(segment
		(start 406.885648 -280.319988)
		(end 406.999948 -280.434288)
		(width 0.1143)
		(layer "In11.Cu")
		(net "P5E_PEX3_STN2_TX_DP<32>")
	)
	(segment
		(start 427.715934 -135.763508)
		(end 427.715934 -140.76553)
		(width 0.1651)
		(layer "In11.Cu")
		(net "P5E_PEX3_STN2_TX_DP<32>")
	)
	(segment
		(start 452.95439 -33.483296)
		(end 453.19188 -33.91789)
		(width 0.1651)
		(layer "In11.Cu")
		(net "P5E_PEX3_STN2_TX_DP<32>")
	)
	(segment
		(start 457.152248 -42.485818)
		(end 457.440284 -56.946546)
		(width 0.1651)
		(layer "In11.Cu")
		(net "P5E_PEX3_STN2_TX_DP<32>")
	)
	(segment
		(start 456.467972 -39.912036)
		(end 457.152248 -42.485818)
		(width 0.1651)
		(layer "In11.Cu")
		(net "P5E_PEX3_STN2_TX_DP<32>")
	)
	(segment
		(start 299.555662 -351.316798)
		(end 299.850302 -351.611438)
		(width 0.13462)
		(layer "F.Cu")
		(net "P5E_PEX2_STN7_TX_C_DN<127>")
	)
	(segment
		(start 299.875702 -350.365314)
		(end 299.555662 -350.685354)
		(width 0.13462)
		(layer "F.Cu")
		(net "P5E_PEX2_STN7_TX_C_DN<127>")
	)
	(segment
		(start 299.555662 -350.685354)
		(end 299.555662 -351.316798)
		(width 0.13462)
		(layer "F.Cu")
		(net "P5E_PEX2_STN7_TX_C_DN<127>")
	)
	(segment
		(start 298.004992 -354.027486)
		(end 298.004992 -358.6988)
		(width 0.1651)
		(layer "In7.Cu")
		(net "P5E_PEX2_STN7_TX_C_DN<127>")
	)
	(segment
		(start 298.004992 -358.6988)
		(end 304.015902 -368.7318)
		(width 0.1651)
		(layer "In7.Cu")
		(net "P5E_PEX2_STN7_TX_C_DN<127>")
	)
	(segment
		(start 303.564036 -376.281188)
		(end 303.01692 -376.281188)
		(width 0.1651)
		(layer "In7.Cu")
		(net "P5E_PEX2_STN7_TX_C_DN<127>")
	)
	(segment
		(start 299.559472 -351.902268)
		(end 299.559472 -352.473006)
		(width 0.1651)
		(layer "In7.Cu")
		(net "P5E_PEX2_STN7_TX_C_DN<127>")
	)
	(segment
		(start 299.559472 -352.473006)
		(end 298.004992 -354.027486)
		(width 0.1651)
		(layer "In7.Cu")
		(net "P5E_PEX2_STN7_TX_C_DN<127>")
	)
	(segment
		(start 304.015902 -375.829322)
		(end 303.564036 -376.281188)
		(width 0.1651)
		(layer "In7.Cu")
		(net "P5E_PEX2_STN7_TX_C_DN<127>")
	)
	(segment
		(start 303.01692 -376.281188)
		(end 302.88992 -376.408188)
		(width 0.1651)
		(layer "In7.Cu")
		(net "P5E_PEX2_STN7_TX_C_DN<127>")
	)
	(segment
		(start 299.850302 -351.611438)
		(end 299.559472 -351.902268)
		(width 0.1651)
		(layer "In7.Cu")
		(net "P5E_PEX2_STN7_TX_C_DN<127>")
	)
	(segment
		(start 302.88992 -376.408188)
		(end 302.88992 -376.790204)
		(width 0.1651)
		(layer "In7.Cu")
		(net "P5E_PEX2_STN7_TX_C_DN<127>")
	)
	(segment
		(start 304.015902 -368.7318)
		(end 304.015902 -375.829322)
		(width 0.1651)
		(layer "In7.Cu")
		(net "P5E_PEX2_STN7_TX_C_DN<127>")
	)
	(segment
		(start 419.605206 -28.250642)
		(end 419.313868 -28.54198)
		(width 0.13462)
		(layer "F.Cu")
		(net "P5E_PEX3_STN2_TX_DN<36>")
	)
	(segment
		(start 419.313868 -28.54198)
		(end 418.67582 -28.54198)
		(width 0.13462)
		(layer "F.Cu")
		(net "P5E_PEX3_STN2_TX_DN<36>")
	)
	(segment
		(start 418.67582 -28.54198)
		(end 418.359082 -28.225242)
		(width 0.13462)
		(layer "F.Cu")
		(net "P5E_PEX3_STN2_TX_DN<36>")
	)
	(segment
		(start 402.865844 -271.427448)
		(end 402.820124 -271.473168)
		(width 0.1143)
		(layer "In11.Cu")
		(net "P5E_PEX3_STN2_TX_DN<36>")
	)
	(segment
		(start 410.922216 -116.6876)
		(end 410.406596 -120.957594)
		(width 0.1651)
		(layer "In11.Cu")
		(net "P5E_PEX3_STN2_TX_DN<36>")
	)
	(segment
		(start 419.605206 -28.250642)
		(end 419.896036 -28.541472)
		(width 0.1651)
		(layer "In11.Cu")
		(net "P5E_PEX3_STN2_TX_DN<36>")
	)
	(segment
		(start 403.199854 -280.015188)
		(end 403.199854 -279.749504)
		(width 0.1143)
		(layer "In11.Cu")
		(net "P5E_PEX3_STN2_TX_DN<36>")
	)
	(segment
		(start 403.085554 -280.129488)
		(end 403.199854 -280.015188)
		(width 0.1143)
		(layer "In11.Cu")
		(net "P5E_PEX3_STN2_TX_DN<36>")
	)
	(segment
		(start 402.865844 -271.399)
		(end 402.865844 -271.427448)
		(width 0.1143)
		(layer "In11.Cu")
		(net "P5E_PEX3_STN2_TX_DN<36>")
	)
	(segment
		(start 439.574178 -58.438034)
		(end 439.574178 -60.59424)
		(width 0.1651)
		(layer "In11.Cu")
		(net "P5E_PEX3_STN2_TX_DN<36>")
	)
	(segment
		(start 438.44718 -47.60849)
		(end 439.574178 -58.438034)
		(width 0.1651)
		(layer "In11.Cu")
		(net "P5E_PEX3_STN2_TX_DN<36>")
	)
	(segment
		(start 422.271952 -28.541472)
		(end 423.875454 -29.206952)
		(width 0.1651)
		(layer "In11.Cu")
		(net "P5E_PEX3_STN2_TX_DN<36>")
	)
	(segment
		(start 423.875454 -29.206952)
		(end 426.553884 -31.885636)
		(width 0.1651)
		(layer "In11.Cu")
		(net "P5E_PEX3_STN2_TX_DN<36>")
	)
	(segment
		(start 437.932576 -65.005458)
		(end 415.71799 -94.024958)
		(width 0.1651)
		(layer "In11.Cu")
		(net "P5E_PEX3_STN2_TX_DN<36>")
	)
	(segment
		(start 415.71799 -94.024958)
		(end 412.55061 -108.111798)
		(width 0.1651)
		(layer "In11.Cu")
		(net "P5E_PEX3_STN2_TX_DN<36>")
	)
	(segment
		(start 412.55061 -108.111798)
		(end 410.922216 -116.6876)
		(width 0.1651)
		(layer "In11.Cu")
		(net "P5E_PEX3_STN2_TX_DN<36>")
	)
	(segment
		(start 402.923756 -280.129488)
		(end 403.085554 -280.129488)
		(width 0.1143)
		(layer "In11.Cu")
		(net "P5E_PEX3_STN2_TX_DN<36>")
	)
	(segment
		(start 402.820124 -271.473168)
		(end 402.820124 -280.025856)
		(width 0.1143)
		(layer "In11.Cu")
		(net "P5E_PEX3_STN2_TX_DN<36>")
	)
	(segment
		(start 410.406596 -120.957594)
		(end 402.865844 -263.42467)
		(width 0.1651)
		(layer "In11.Cu")
		(net "P5E_PEX3_STN2_TX_DN<36>")
	)
	(segment
		(start 439.574178 -60.59424)
		(end 438.927748 -62.998604)
		(width 0.1651)
		(layer "In11.Cu")
		(net "P5E_PEX3_STN2_TX_DN<36>")
	)
	(segment
		(start 402.865844 -263.42467)
		(end 402.865844 -271.399)
		(width 0.1651)
		(layer "In11.Cu")
		(net "P5E_PEX3_STN2_TX_DN<36>")
	)
	(segment
		(start 431.54727 -39.727886)
		(end 438.44718 -47.60849)
		(width 0.1651)
		(layer "In11.Cu")
		(net "P5E_PEX3_STN2_TX_DN<36>")
	)
	(segment
		(start 419.896036 -28.541472)
		(end 422.271952 -28.541472)
		(width 0.1651)
		(layer "In11.Cu")
		(net "P5E_PEX3_STN2_TX_DN<36>")
	)
	(segment
		(start 438.927748 -62.998604)
		(end 437.932576 -65.005458)
		(width 0.1651)
		(layer "In11.Cu")
		(net "P5E_PEX3_STN2_TX_DN<36>")
	)
	(segment
		(start 426.553884 -31.885636)
		(end 431.54727 -39.727886)
		(width 0.1651)
		(layer "In11.Cu")
		(net "P5E_PEX3_STN2_TX_DN<36>")
	)
	(segment
		(start 402.820124 -280.025856)
		(end 402.923756 -280.129488)
		(width 0.1143)
		(layer "In11.Cu")
		(net "P5E_PEX3_STN2_TX_DN<36>")
	)
	(segment
		(start 65.050162 -348.88043)
		(end 65.344802 -348.58579)
		(width 0.13462)
		(layer "F.Cu")
		(net "P5E_PEX0_STN6_TX_DN<110>")
	)
	(segment
		(start 65.050162 -349.511874)
		(end 65.050162 -348.88043)
		(width 0.13462)
		(layer "F.Cu")
		(net "P5E_PEX0_STN6_TX_DN<110>")
	)
	(segment
		(start 65.370202 -349.831914)
		(end 65.050162 -349.511874)
		(width 0.13462)
		(layer "F.Cu")
		(net "P5E_PEX0_STN6_TX_DN<110>")
	)
	(segment
		(start 44.115736 -324.493128)
		(end 44.115736 -320.177922)
		(width 0.1651)
		(layer "In13.Cu")
		(net "P5E_PEX0_STN6_TX_DN<110>")
	)
	(segment
		(start 51.45659 -333.29753)
		(end 49.877472 -332.64348)
		(width 0.1651)
		(layer "In13.Cu")
		(net "P5E_PEX0_STN6_TX_DN<110>")
	)
	(segment
		(start 65.344802 -348.58579)
		(end 65.053972 -348.29496)
		(width 0.1651)
		(layer "In13.Cu")
		(net "P5E_PEX0_STN6_TX_DN<110>")
	)
	(segment
		(start 65.053972 -348.29496)
		(end 65.053972 -347.716348)
		(width 0.1651)
		(layer "In13.Cu")
		(net "P5E_PEX0_STN6_TX_DN<110>")
	)
	(segment
		(start 49.877472 -332.64348)
		(end 45.804582 -328.57059)
		(width 0.1651)
		(layer "In13.Cu")
		(net "P5E_PEX0_STN6_TX_DN<110>")
	)
	(segment
		(start 45.804582 -328.57059)
		(end 44.115736 -324.493128)
		(width 0.1651)
		(layer "In13.Cu")
		(net "P5E_PEX0_STN6_TX_DN<110>")
	)
	(segment
		(start 44.449746 -313.659012)
		(end 44.449746 -313.949842)
		(width 0.1143)
		(layer "In13.Cu")
		(net "P5E_PEX0_STN6_TX_DN<110>")
	)
	(segment
		(start 44.070016 -320.110104)
		(end 44.070016 -313.697112)
		(width 0.1143)
		(layer "In13.Cu")
		(net "P5E_PEX0_STN6_TX_DN<110>")
	)
	(segment
		(start 44.070016 -313.697112)
		(end 44.197016 -313.570112)
		(width 0.1143)
		(layer "In13.Cu")
		(net "P5E_PEX0_STN6_TX_DN<110>")
	)
	(segment
		(start 65.053972 -347.716348)
		(end 66.608452 -346.161868)
		(width 0.1651)
		(layer "In13.Cu")
		(net "P5E_PEX0_STN6_TX_DN<110>")
	)
	(segment
		(start 44.197016 -313.570112)
		(end 44.360846 -313.570112)
		(width 0.1143)
		(layer "In13.Cu")
		(net "P5E_PEX0_STN6_TX_DN<110>")
	)
	(segment
		(start 66.036952 -341.090758)
		(end 51.45659 -333.29753)
		(width 0.1651)
		(layer "In13.Cu")
		(net "P5E_PEX0_STN6_TX_DN<110>")
	)
	(segment
		(start 66.608452 -346.161868)
		(end 66.608452 -342.044528)
		(width 0.1651)
		(layer "In13.Cu")
		(net "P5E_PEX0_STN6_TX_DN<110>")
	)
	(segment
		(start 44.115736 -320.177922)
		(end 44.115736 -320.155824)
		(width 0.1143)
		(layer "In13.Cu")
		(net "P5E_PEX0_STN6_TX_DN<110>")
	)
	(segment
		(start 44.360846 -313.570112)
		(end 44.449746 -313.659012)
		(width 0.1143)
		(layer "In13.Cu")
		(net "P5E_PEX0_STN6_TX_DN<110>")
	)
	(segment
		(start 66.608452 -342.044528)
		(end 66.036952 -341.090758)
		(width 0.1651)
		(layer "In13.Cu")
		(net "P5E_PEX0_STN6_TX_DN<110>")
	)
	(segment
		(start 44.115736 -320.155824)
		(end 44.070016 -320.110104)
		(width 0.1143)
		(layer "In13.Cu")
		(net "P5E_PEX0_STN6_TX_DN<110>")
	)
	(segment
		(start 389.81634 -343.685622)
		(end 390.135872 -343.36609)
		(width 0.13462)
		(layer "F.Cu")
		(net "P5E_PEX3_STN5_TX_DP<88>")
	)
	(segment
		(start 390.135872 -342.73363)
		(end 389.84174 -342.439498)
		(width 0.13462)
		(layer "F.Cu")
		(net "P5E_PEX3_STN5_TX_DP<88>")
	)
	(segment
		(start 390.135872 -343.36609)
		(end 390.135872 -342.73363)
		(width 0.13462)
		(layer "F.Cu")
		(net "P5E_PEX3_STN5_TX_DP<88>")
	)
	(segment
		(start 414.599882 -311.365392)
		(end 414.485582 -311.479692)
		(width 0.1143)
		(layer "In13.Cu")
		(net "P5E_PEX3_STN5_TX_DP<88>")
	)
	(segment
		(start 414.25876 -311.479692)
		(end 414.029652 -311.7088)
		(width 0.1143)
		(layer "In13.Cu")
		(net "P5E_PEX3_STN5_TX_DP<88>")
	)
	(segment
		(start 413.983932 -320.017648)
		(end 413.983932 -320.046096)
		(width 0.1143)
		(layer "In13.Cu")
		(net "P5E_PEX3_STN5_TX_DP<88>")
	)
	(segment
		(start 413.983932 -320.046096)
		(end 413.983932 -320.94297)
		(width 0.1651)
		(layer "In13.Cu")
		(net "P5E_PEX3_STN5_TX_DP<88>")
	)
	(segment
		(start 390.853676 -340.578948)
		(end 390.627616 -340.874604)
		(width 0.1651)
		(layer "In13.Cu")
		(net "P5E_PEX3_STN5_TX_DP<88>")
	)
	(segment
		(start 414.485582 -311.479692)
		(end 414.25876 -311.479692)
		(width 0.1143)
		(layer "In13.Cu")
		(net "P5E_PEX3_STN5_TX_DP<88>")
	)
	(segment
		(start 390.13257 -342.148668)
		(end 389.84174 -342.439498)
		(width 0.1651)
		(layer "In13.Cu")
		(net "P5E_PEX3_STN5_TX_DP<88>")
	)
	(segment
		(start 390.627616 -340.874604)
		(end 390.13257 -341.692992)
		(width 0.1651)
		(layer "In13.Cu")
		(net "P5E_PEX3_STN5_TX_DP<88>")
	)
	(segment
		(start 414.599882 -311.099962)
		(end 414.599882 -311.365392)
		(width 0.1143)
		(layer "In13.Cu")
		(net "P5E_PEX3_STN5_TX_DP<88>")
	)
	(segment
		(start 390.13257 -341.692992)
		(end 390.13257 -342.148668)
		(width 0.1651)
		(layer "In13.Cu")
		(net "P5E_PEX3_STN5_TX_DP<88>")
	)
	(segment
		(start 413.983932 -320.94297)
		(end 413.729424 -321.29095)
		(width 0.1651)
		(layer "In13.Cu")
		(net "P5E_PEX3_STN5_TX_DP<88>")
	)
	(segment
		(start 413.729424 -321.29095)
		(end 390.853676 -340.578948)
		(width 0.1651)
		(layer "In13.Cu")
		(net "P5E_PEX3_STN5_TX_DP<88>")
	)
	(segment
		(start 414.029652 -319.971928)
		(end 413.983932 -320.017648)
		(width 0.1143)
		(layer "In13.Cu")
		(net "P5E_PEX3_STN5_TX_DP<88>")
	)
	(segment
		(start 414.029652 -311.7088)
		(end 414.029652 -319.971928)
		(width 0.1143)
		(layer "In13.Cu")
		(net "P5E_PEX3_STN5_TX_DP<88>")
	)
	(segment
		(start 340.483444 -357.75773)
		(end 340.778084 -357.46309)
		(width 0.13462)
		(layer "F.Cu")
		(net "P5E_PEX2_STN5_TX_C_DP<94>")
	)
	(segment
		(start 340.778084 -356.831646)
		(end 340.458044 -356.511606)
		(width 0.13462)
		(layer "F.Cu")
		(net "P5E_PEX2_STN5_TX_C_DP<94>")
	)
	(segment
		(start 340.778084 -357.46309)
		(end 340.778084 -356.831646)
		(width 0.13462)
		(layer "F.Cu")
		(net "P5E_PEX2_STN5_TX_C_DP<94>")
	)
	(segment
		(start 343.16543 -364.247176)
		(end 343.219786 -364.094776)
		(width 0.1651)
		(layer "In7.Cu")
		(net "P5E_PEX2_STN5_TX_C_DP<94>")
	)
	(segment
		(start 343.37752 -364.694978)
		(end 343.16543 -364.247176)
		(width 0.1651)
		(layer "In7.Cu")
		(net "P5E_PEX2_STN5_TX_C_DP<94>")
	)
	(segment
		(start 344.198448 -366.37214)
		(end 344.240866 -366.253522)
		(width 0.1651)
		(layer "In7.Cu")
		(net "P5E_PEX2_STN5_TX_C_DP<94>")
	)
	(segment
		(start 342.698324 -362.992416)
		(end 340.774274 -358.923844)
		(width 0.1651)
		(layer "In7.Cu")
		(net "P5E_PEX2_STN5_TX_C_DP<94>")
	)
	(segment
		(start 343.91092 -365.763556)
		(end 343.69883 -365.3155)
		(width 0.1651)
		(layer "In7.Cu")
		(net "P5E_PEX2_STN5_TX_C_DP<94>")
	)
	(segment
		(start 345.491562 -368.897916)
		(end 344.528902 -366.86236)
		(width 0.1651)
		(layer "In7.Cu")
		(net "P5E_PEX2_STN5_TX_C_DP<94>")
	)
	(segment
		(start 345.247214 -378.79909)
		(end 345.53398 -378.512324)
		(width 0.1651)
		(layer "In7.Cu")
		(net "P5E_PEX2_STN5_TX_C_DP<94>")
	)
	(segment
		(start 344.689938 -378.290074)
		(end 344.689938 -378.67209)
		(width 0.1651)
		(layer "In7.Cu")
		(net "P5E_PEX2_STN5_TX_C_DP<94>")
	)
	(segment
		(start 343.008204 -363.647228)
		(end 342.882982 -363.60227)
		(width 0.1651)
		(layer "In7.Cu")
		(net "P5E_PEX2_STN5_TX_C_DP<94>")
	)
	(segment
		(start 343.529666 -364.749588)
		(end 343.37752 -364.694978)
		(width 0.1651)
		(layer "In7.Cu")
		(net "P5E_PEX2_STN5_TX_C_DP<94>")
	)
	(segment
		(start 343.219786 -364.094776)
		(end 343.008204 -363.647228)
		(width 0.1651)
		(layer "In7.Cu")
		(net "P5E_PEX2_STN5_TX_C_DP<94>")
	)
	(segment
		(start 345.53398 -378.512324)
		(end 345.53398 -368.99977)
		(width 0.1651)
		(layer "In7.Cu")
		(net "P5E_PEX2_STN5_TX_C_DP<94>")
	)
	(segment
		(start 344.029284 -365.805974)
		(end 343.91092 -365.763556)
		(width 0.1651)
		(layer "In7.Cu")
		(net "P5E_PEX2_STN5_TX_C_DP<94>")
	)
	(segment
		(start 344.240866 -366.253522)
		(end 344.029284 -365.805974)
		(width 0.1651)
		(layer "In7.Cu")
		(net "P5E_PEX2_STN5_TX_C_DP<94>")
	)
	(segment
		(start 343.741248 -365.197136)
		(end 343.529666 -364.749588)
		(width 0.1651)
		(layer "In7.Cu")
		(net "P5E_PEX2_STN5_TX_C_DP<94>")
	)
	(segment
		(start 340.774274 -358.04856)
		(end 340.483444 -357.75773)
		(width 0.1651)
		(layer "In7.Cu")
		(net "P5E_PEX2_STN5_TX_C_DP<94>")
	)
	(segment
		(start 342.882982 -363.60227)
		(end 342.65362 -363.117638)
		(width 0.1651)
		(layer "In7.Cu")
		(net "P5E_PEX2_STN5_TX_C_DP<94>")
	)
	(segment
		(start 344.816938 -378.79909)
		(end 345.247214 -378.79909)
		(width 0.1651)
		(layer "In7.Cu")
		(net "P5E_PEX2_STN5_TX_C_DP<94>")
	)
	(segment
		(start 342.65362 -363.117638)
		(end 342.698324 -362.992416)
		(width 0.1651)
		(layer "In7.Cu")
		(net "P5E_PEX2_STN5_TX_C_DP<94>")
	)
	(segment
		(start 345.53398 -368.99977)
		(end 345.491562 -368.897916)
		(width 0.1651)
		(layer "In7.Cu")
		(net "P5E_PEX2_STN5_TX_C_DP<94>")
	)
	(segment
		(start 340.774274 -358.923844)
		(end 340.774274 -358.04856)
		(width 0.1651)
		(layer "In7.Cu")
		(net "P5E_PEX2_STN5_TX_C_DP<94>")
	)
	(segment
		(start 344.528902 -366.86236)
		(end 344.410538 -366.819942)
		(width 0.1651)
		(layer "In7.Cu")
		(net "P5E_PEX2_STN5_TX_C_DP<94>")
	)
	(segment
		(start 344.689938 -378.67209)
		(end 344.816938 -378.79909)
		(width 0.1651)
		(layer "In7.Cu")
		(net "P5E_PEX2_STN5_TX_C_DP<94>")
	)
	(segment
		(start 344.410538 -366.819942)
		(end 344.198448 -366.37214)
		(width 0.1651)
		(layer "In7.Cu")
		(net "P5E_PEX2_STN5_TX_C_DP<94>")
	)
	(segment
		(start 343.69883 -365.3155)
		(end 343.741248 -365.197136)
		(width 0.1651)
		(layer "In7.Cu")
		(net "P5E_PEX2_STN5_TX_C_DP<94>")
	)
	(segment
		(start 369.322604 -30.353)
		(end 369.001294 -30.03169)
		(width 0.13462)
		(layer "F.Cu")
		(net "P5E_PEX3_STN2_TX_DN<45>")
	)
	(segment
		(start 370.247418 -30.05709)
		(end 369.951508 -30.353)
		(width 0.13462)
		(layer "F.Cu")
		(net "P5E_PEX3_STN2_TX_DN<45>")
	)
	(segment
		(start 369.951508 -30.353)
		(end 369.322604 -30.353)
		(width 0.13462)
		(layer "F.Cu")
		(net "P5E_PEX3_STN2_TX_DN<45>")
	)
	(segment
		(start 383.37617 -44.917868)
		(end 385.324858 -48.4632)
		(width 0.1651)
		(layer "In11.Cu")
		(net "P5E_PEX3_STN2_TX_DN<45>")
	)
	(segment
		(start 382.223772 -105.234486)
		(end 381.720852 -116.209572)
		(width 0.1651)
		(layer "In11.Cu")
		(net "P5E_PEX3_STN2_TX_DN<45>")
	)
	(segment
		(start 370.987828 -30.34792)
		(end 371.568218 -30.58795)
		(width 0.1651)
		(layer "In11.Cu")
		(net "P5E_PEX3_STN2_TX_DN<45>")
	)
	(segment
		(start 385.854448 -78.912974)
		(end 382.223772 -105.234486)
		(width 0.1651)
		(layer "In11.Cu")
		(net "P5E_PEX3_STN2_TX_DN<45>")
	)
	(segment
		(start 385.96316 -50.312828)
		(end 386.729478 -63.149734)
		(width 0.1651)
		(layer "In11.Cu")
		(net "P5E_PEX3_STN2_TX_DN<45>")
	)
	(segment
		(start 385.324858 -48.4632)
		(end 385.96316 -50.312828)
		(width 0.1651)
		(layer "In11.Cu")
		(net "P5E_PEX3_STN2_TX_DN<45>")
	)
	(segment
		(start 393.28725 -264.159746)
		(end 394.31595 -270.360902)
		(width 0.1651)
		(layer "In11.Cu")
		(net "P5E_PEX3_STN2_TX_DN<45>")
	)
	(segment
		(start 382.122934 -137.972292)
		(end 393.28725 -264.159746)
		(width 0.1651)
		(layer "In11.Cu")
		(net "P5E_PEX3_STN2_TX_DN<45>")
	)
	(segment
		(start 394.373862 -278.229568)
		(end 394.53566 -278.229568)
		(width 0.1143)
		(layer "In11.Cu")
		(net "P5E_PEX3_STN2_TX_DN<45>")
	)
	(segment
		(start 394.31595 -270.360902)
		(end 394.31595 -271.399)
		(width 0.1651)
		(layer "In11.Cu")
		(net "P5E_PEX3_STN2_TX_DN<45>")
	)
	(segment
		(start 394.31595 -271.427448)
		(end 394.27023 -271.473168)
		(width 0.1143)
		(layer "In11.Cu")
		(net "P5E_PEX3_STN2_TX_DN<45>")
	)
	(segment
		(start 372.80342 -31.646114)
		(end 383.37617 -44.917868)
		(width 0.1651)
		(layer "In11.Cu")
		(net "P5E_PEX3_STN2_TX_DN<45>")
	)
	(segment
		(start 394.27023 -278.125936)
		(end 394.373862 -278.229568)
		(width 0.1143)
		(layer "In11.Cu")
		(net "P5E_PEX3_STN2_TX_DN<45>")
	)
	(segment
		(start 370.493036 -30.302708)
		(end 370.602002 -30.34792)
		(width 0.1651)
		(layer "In11.Cu")
		(net "P5E_PEX3_STN2_TX_DN<45>")
	)
	(segment
		(start 370.247418 -30.05709)
		(end 370.493036 -30.302708)
		(width 0.1651)
		(layer "In11.Cu")
		(net "P5E_PEX3_STN2_TX_DN<45>")
	)
	(segment
		(start 370.602002 -30.34792)
		(end 370.987828 -30.34792)
		(width 0.1651)
		(layer "In11.Cu")
		(net "P5E_PEX3_STN2_TX_DN<45>")
	)
	(segment
		(start 381.720852 -116.209572)
		(end 382.122934 -137.972292)
		(width 0.1651)
		(layer "In11.Cu")
		(net "P5E_PEX3_STN2_TX_DN<45>")
	)
	(segment
		(start 371.568218 -30.58795)
		(end 372.80342 -31.646114)
		(width 0.1651)
		(layer "In11.Cu")
		(net "P5E_PEX3_STN2_TX_DN<45>")
	)
	(segment
		(start 394.64996 -278.115268)
		(end 394.64996 -277.849838)
		(width 0.1143)
		(layer "In11.Cu")
		(net "P5E_PEX3_STN2_TX_DN<45>")
	)
	(segment
		(start 394.53566 -278.229568)
		(end 394.64996 -278.115268)
		(width 0.1143)
		(layer "In11.Cu")
		(net "P5E_PEX3_STN2_TX_DN<45>")
	)
	(segment
		(start 394.27023 -271.473168)
		(end 394.27023 -278.125936)
		(width 0.1143)
		(layer "In11.Cu")
		(net "P5E_PEX3_STN2_TX_DN<45>")
	)
	(segment
		(start 386.729478 -63.149734)
		(end 385.854448 -78.912974)
		(width 0.1651)
		(layer "In11.Cu")
		(net "P5E_PEX3_STN2_TX_DN<45>")
	)
	(segment
		(start 394.31595 -271.399)
		(end 394.31595 -271.427448)
		(width 0.1143)
		(layer "In11.Cu")
		(net "P5E_PEX3_STN2_TX_DN<45>")
	)
	(segment
		(start 334.240124 -344.219022)
		(end 334.560164 -344.539062)
		(width 0.13462)
		(layer "F.Cu")
		(net "P5E_PEX2_STN5_TX_C_DP<90>")
	)
	(segment
		(start 334.560164 -344.539062)
		(end 334.560164 -345.170506)
		(width 0.13462)
		(layer "F.Cu")
		(net "P5E_PEX2_STN5_TX_C_DP<90>")
	)
	(segment
		(start 334.560164 -345.170506)
		(end 334.265524 -345.465146)
		(width 0.13462)
		(layer "F.Cu")
		(net "P5E_PEX2_STN5_TX_C_DP<90>")
	)
	(segment
		(start 334.516984 -362.445554)
		(end 334.463136 -362.559346)
		(width 0.1651)
		(layer "In7.Cu")
		(net "P5E_PEX2_STN5_TX_C_DP<90>")
	)
	(segment
		(start 336.73415 -378.512324)
		(end 336.447384 -378.79909)
		(width 0.1651)
		(layer "In7.Cu")
		(net "P5E_PEX2_STN5_TX_C_DP<90>")
	)
	(segment
		(start 336.017108 -378.79909)
		(end 335.890108 -378.67209)
		(width 0.1651)
		(layer "In7.Cu")
		(net "P5E_PEX2_STN5_TX_C_DP<90>")
	)
	(segment
		(start 335.698084 -365.746538)
		(end 335.644236 -365.86033)
		(width 0.1651)
		(layer "In7.Cu")
		(net "P5E_PEX2_STN5_TX_C_DP<90>")
	)
	(segment
		(start 335.250536 -364.760002)
		(end 335.417414 -365.2266)
		(width 0.1651)
		(layer "In7.Cu")
		(net "P5E_PEX2_STN5_TX_C_DP<90>")
	)
	(segment
		(start 334.463136 -362.559346)
		(end 334.630014 -363.025944)
		(width 0.1651)
		(layer "In7.Cu")
		(net "P5E_PEX2_STN5_TX_C_DP<90>")
	)
	(segment
		(start 334.556354 -346.209874)
		(end 333.001874 -347.764354)
		(width 0.1651)
		(layer "In7.Cu")
		(net "P5E_PEX2_STN5_TX_C_DP<90>")
	)
	(segment
		(start 335.417414 -365.2266)
		(end 335.53146 -365.280194)
		(width 0.1651)
		(layer "In7.Cu")
		(net "P5E_PEX2_STN5_TX_C_DP<90>")
	)
	(segment
		(start 335.53146 -365.280194)
		(end 335.531206 -365.280194)
		(width 0.1651)
		(layer "In7.Cu")
		(net "P5E_PEX2_STN5_TX_C_DP<90>")
	)
	(segment
		(start 334.74406 -363.079538)
		(end 334.910684 -363.545882)
		(width 0.1651)
		(layer "In7.Cu")
		(net "P5E_PEX2_STN5_TX_C_DP<90>")
	)
	(segment
		(start 334.856836 -363.659674)
		(end 335.023714 -364.126272)
		(width 0.1651)
		(layer "In7.Cu")
		(net "P5E_PEX2_STN5_TX_C_DP<90>")
	)
	(segment
		(start 334.910684 -363.545882)
		(end 334.856836 -363.659674)
		(width 0.1651)
		(layer "In7.Cu")
		(net "P5E_PEX2_STN5_TX_C_DP<90>")
	)
	(segment
		(start 333.001874 -347.764354)
		(end 333.001874 -358.210866)
		(width 0.1651)
		(layer "In7.Cu")
		(net "P5E_PEX2_STN5_TX_C_DP<90>")
	)
	(segment
		(start 335.023714 -364.126272)
		(end 335.13776 -364.179866)
		(width 0.1651)
		(layer "In7.Cu")
		(net "P5E_PEX2_STN5_TX_C_DP<90>")
	)
	(segment
		(start 334.556354 -345.755976)
		(end 334.556354 -346.209874)
		(width 0.1651)
		(layer "In7.Cu")
		(net "P5E_PEX2_STN5_TX_C_DP<90>")
	)
	(segment
		(start 335.531206 -365.280194)
		(end 335.69783 -365.746538)
		(width 0.1651)
		(layer "In7.Cu")
		(net "P5E_PEX2_STN5_TX_C_DP<90>")
	)
	(segment
		(start 335.137506 -364.179866)
		(end 335.304384 -364.64621)
		(width 0.1651)
		(layer "In7.Cu")
		(net "P5E_PEX2_STN5_TX_C_DP<90>")
	)
	(segment
		(start 336.447384 -378.79909)
		(end 336.017108 -378.79909)
		(width 0.1651)
		(layer "In7.Cu")
		(net "P5E_PEX2_STN5_TX_C_DP<90>")
	)
	(segment
		(start 335.69783 -365.746538)
		(end 335.698084 -365.746538)
		(width 0.1651)
		(layer "In7.Cu")
		(net "P5E_PEX2_STN5_TX_C_DP<90>")
	)
	(segment
		(start 335.811114 -366.326928)
		(end 335.92516 -366.380522)
		(width 0.1651)
		(layer "In7.Cu")
		(net "P5E_PEX2_STN5_TX_C_DP<90>")
	)
	(segment
		(start 335.13776 -364.179866)
		(end 335.137506 -364.179866)
		(width 0.1651)
		(layer "In7.Cu")
		(net "P5E_PEX2_STN5_TX_C_DP<90>")
	)
	(segment
		(start 335.92516 -366.380522)
		(end 335.924906 -366.380522)
		(width 0.1651)
		(layer "In7.Cu")
		(net "P5E_PEX2_STN5_TX_C_DP<90>")
	)
	(segment
		(start 335.644236 -365.86033)
		(end 335.811114 -366.326928)
		(width 0.1651)
		(layer "In7.Cu")
		(net "P5E_PEX2_STN5_TX_C_DP<90>")
	)
	(segment
		(start 335.304384 -364.64621)
		(end 335.250536 -364.760002)
		(width 0.1651)
		(layer "In7.Cu")
		(net "P5E_PEX2_STN5_TX_C_DP<90>")
	)
	(segment
		(start 335.890108 -378.67209)
		(end 335.890108 -378.290074)
		(width 0.1651)
		(layer "In7.Cu")
		(net "P5E_PEX2_STN5_TX_C_DP<90>")
	)
	(segment
		(start 334.265524 -345.465146)
		(end 334.556354 -345.755976)
		(width 0.1651)
		(layer "In7.Cu")
		(net "P5E_PEX2_STN5_TX_C_DP<90>")
	)
	(segment
		(start 335.924906 -366.380522)
		(end 336.73415 -368.642138)
		(width 0.1651)
		(layer "In7.Cu")
		(net "P5E_PEX2_STN5_TX_C_DP<90>")
	)
	(segment
		(start 333.001874 -358.210866)
		(end 334.516984 -362.445554)
		(width 0.1651)
		(layer "In7.Cu")
		(net "P5E_PEX2_STN5_TX_C_DP<90>")
	)
	(segment
		(start 336.73415 -368.642138)
		(end 336.73415 -378.512324)
		(width 0.1651)
		(layer "In7.Cu")
		(net "P5E_PEX2_STN5_TX_C_DP<90>")
	)
	(segment
		(start 334.630014 -363.025944)
		(end 334.74406 -363.079538)
		(width 0.1651)
		(layer "In7.Cu")
		(net "P5E_PEX2_STN5_TX_C_DP<90>")
	)
	(segment
		(start 71.588122 -349.831914)
		(end 71.268082 -349.511874)
		(width 0.13462)
		(layer "F.Cu")
		(net "P5E_PEX0_STN6_TX_DN<107>")
	)
	(segment
		(start 71.268082 -349.511874)
		(end 71.268082 -348.88043)
		(width 0.13462)
		(layer "F.Cu")
		(net "P5E_PEX0_STN6_TX_DN<107>")
	)
	(segment
		(start 71.268082 -348.88043)
		(end 71.562722 -348.58579)
		(width 0.13462)
		(layer "F.Cu")
		(net "P5E_PEX0_STN6_TX_DN<107>")
	)
	(segment
		(start 51.401726 -330.115418)
		(end 48.330866 -327.044558)
		(width 0.1651)
		(layer "In13.Cu")
		(net "P5E_PEX0_STN6_TX_DN<107>")
	)
	(segment
		(start 71.562722 -348.58579)
		(end 71.271892 -348.29496)
		(width 0.1651)
		(layer "In13.Cu")
		(net "P5E_PEX0_STN6_TX_DN<107>")
	)
	(segment
		(start 72.826372 -346.161868)
		(end 72.826372 -341.74811)
		(width 0.1651)
		(layer "In13.Cu")
		(net "P5E_PEX0_STN6_TX_DN<107>")
	)
	(segment
		(start 47.047404 -311.670192)
		(end 47.21098 -311.670192)
		(width 0.1143)
		(layer "In13.Cu")
		(net "P5E_PEX0_STN6_TX_DN<107>")
	)
	(segment
		(start 47.21098 -311.670192)
		(end 47.29988 -311.759092)
		(width 0.1143)
		(layer "In13.Cu")
		(net "P5E_PEX0_STN6_TX_DN<107>")
	)
	(segment
		(start 52.911502 -330.740766)
		(end 51.401726 -330.115418)
		(width 0.1651)
		(layer "In13.Cu")
		(net "P5E_PEX0_STN6_TX_DN<107>")
	)
	(segment
		(start 46.92015 -320.13144)
		(end 46.92015 -311.797446)
		(width 0.1143)
		(layer "In13.Cu")
		(net "P5E_PEX0_STN6_TX_DN<107>")
	)
	(segment
		(start 46.92015 -311.797446)
		(end 47.047404 -311.670192)
		(width 0.1143)
		(layer "In13.Cu")
		(net "P5E_PEX0_STN6_TX_DN<107>")
	)
	(segment
		(start 71.271892 -348.29496)
		(end 71.271892 -347.716348)
		(width 0.1651)
		(layer "In13.Cu")
		(net "P5E_PEX0_STN6_TX_DN<107>")
	)
	(segment
		(start 72.506586 -341.21471)
		(end 52.911502 -330.740766)
		(width 0.1651)
		(layer "In13.Cu")
		(net "P5E_PEX0_STN6_TX_DN<107>")
	)
	(segment
		(start 47.29988 -311.759092)
		(end 47.29988 -312.049922)
		(width 0.1143)
		(layer "In13.Cu")
		(net "P5E_PEX0_STN6_TX_DN<107>")
	)
	(segment
		(start 48.330866 -327.044558)
		(end 46.96587 -323.749162)
		(width 0.1651)
		(layer "In13.Cu")
		(net "P5E_PEX0_STN6_TX_DN<107>")
	)
	(segment
		(start 71.271892 -347.716348)
		(end 72.826372 -346.161868)
		(width 0.1651)
		(layer "In13.Cu")
		(net "P5E_PEX0_STN6_TX_DN<107>")
	)
	(segment
		(start 46.96587 -320.17716)
		(end 46.92015 -320.13144)
		(width 0.1143)
		(layer "In13.Cu")
		(net "P5E_PEX0_STN6_TX_DN<107>")
	)
	(segment
		(start 46.96587 -320.199258)
		(end 46.96587 -320.17716)
		(width 0.1143)
		(layer "In13.Cu")
		(net "P5E_PEX0_STN6_TX_DN<107>")
	)
	(segment
		(start 46.96587 -323.749162)
		(end 46.96587 -320.199258)
		(width 0.1651)
		(layer "In13.Cu")
		(net "P5E_PEX0_STN6_TX_DN<107>")
	)
	(segment
		(start 72.826372 -341.74811)
		(end 72.506586 -341.21471)
		(width 0.1651)
		(layer "In13.Cu")
		(net "P5E_PEX0_STN6_TX_DN<107>")
	)
	(segment
		(start 447.321432 -33.95218)
		(end 447.001138 -33.631886)
		(width 0.13462)
		(layer "F.Cu")
		(net "P5E_PEX3_STN2_TX_DN<35>")
	)
	(segment
		(start 447.952368 -33.95218)
		(end 447.321432 -33.95218)
		(width 0.13462)
		(layer "F.Cu")
		(net "P5E_PEX3_STN2_TX_DN<35>")
	)
	(segment
		(start 448.247262 -33.657286)
		(end 447.952368 -33.95218)
		(width 0.13462)
		(layer "F.Cu")
		(net "P5E_PEX3_STN2_TX_DN<35>")
	)
	(segment
		(start 403.815804 -265.478768)
		(end 403.815804 -271.399)
		(width 0.1651)
		(layer "In11.Cu")
		(net "P5E_PEX3_STN2_TX_DN<35>")
	)
	(segment
		(start 425.132754 -139.897866)
		(end 424.694096 -141.7955)
		(width 0.1651)
		(layer "In11.Cu")
		(net "P5E_PEX3_STN2_TX_DN<35>")
	)
	(segment
		(start 404.035514 -278.229568)
		(end 404.149814 -278.115268)
		(width 0.1143)
		(layer "In11.Cu")
		(net "P5E_PEX3_STN2_TX_DN<35>")
	)
	(segment
		(start 452.63562 -67.91071)
		(end 448.369944 -74.235564)
		(width 0.1651)
		(layer "In11.Cu")
		(net "P5E_PEX3_STN2_TX_DN<35>")
	)
	(segment
		(start 448.369944 -74.235564)
		(end 443.666626 -77.950314)
		(width 0.1651)
		(layer "In11.Cu")
		(net "P5E_PEX3_STN2_TX_DN<35>")
	)
	(segment
		(start 404.149814 -278.115268)
		(end 404.149814 -277.849838)
		(width 0.1143)
		(layer "In11.Cu")
		(net "P5E_PEX3_STN2_TX_DN<35>")
	)
	(segment
		(start 403.873716 -278.229568)
		(end 404.035514 -278.229568)
		(width 0.1143)
		(layer "In11.Cu")
		(net "P5E_PEX3_STN2_TX_DN<35>")
	)
	(segment
		(start 403.815804 -271.427448)
		(end 403.770084 -271.473168)
		(width 0.1143)
		(layer "In11.Cu")
		(net "P5E_PEX3_STN2_TX_DN<35>")
	)
	(segment
		(start 450.244972 -34.57829)
		(end 454.458578 -42.414952)
		(width 0.1651)
		(layer "In11.Cu")
		(net "P5E_PEX3_STN2_TX_DN<35>")
	)
	(segment
		(start 403.770084 -278.125936)
		(end 403.873716 -278.229568)
		(width 0.1143)
		(layer "In11.Cu")
		(net "P5E_PEX3_STN2_TX_DN<35>")
	)
	(segment
		(start 449.221606 -33.948116)
		(end 449.703444 -34.082736)
		(width 0.1651)
		(layer "In11.Cu")
		(net "P5E_PEX3_STN2_TX_DN<35>")
	)
	(segment
		(start 427.36008 -105.014776)
		(end 425.661836 -118.211854)
		(width 0.1651)
		(layer "In11.Cu")
		(net "P5E_PEX3_STN2_TX_DN<35>")
	)
	(segment
		(start 403.770084 -271.473168)
		(end 403.770084 -278.125936)
		(width 0.1143)
		(layer "In11.Cu")
		(net "P5E_PEX3_STN2_TX_DN<35>")
	)
	(segment
		(start 449.703444 -34.082736)
		(end 450.244972 -34.57829)
		(width 0.1651)
		(layer "In11.Cu")
		(net "P5E_PEX3_STN2_TX_DN<35>")
	)
	(segment
		(start 422.924732 -161.53003)
		(end 403.815804 -265.478768)
		(width 0.1651)
		(layer "In11.Cu")
		(net "P5E_PEX3_STN2_TX_DN<35>")
	)
	(segment
		(start 454.555098 -42.785538)
		(end 454.78446 -56.765698)
		(width 0.1651)
		(layer "In11.Cu")
		(net "P5E_PEX3_STN2_TX_DN<35>")
	)
	(segment
		(start 443.666626 -77.950314)
		(end 441.489084 -80.13319)
		(width 0.1651)
		(layer "In11.Cu")
		(net "P5E_PEX3_STN2_TX_DN<35>")
	)
	(segment
		(start 424.387772 -149.256242)
		(end 422.924732 -161.53003)
		(width 0.1651)
		(layer "In11.Cu")
		(net "P5E_PEX3_STN2_TX_DN<35>")
	)
	(segment
		(start 448.442334 -33.852358)
		(end 448.673728 -33.948116)
		(width 0.1651)
		(layer "In11.Cu")
		(net "P5E_PEX3_STN2_TX_DN<35>")
	)
	(segment
		(start 424.694096 -141.7955)
		(end 424.387772 -149.256242)
		(width 0.1651)
		(layer "In11.Cu")
		(net "P5E_PEX3_STN2_TX_DN<35>")
	)
	(segment
		(start 425.661836 -118.211854)
		(end 425.132754 -131.103624)
		(width 0.1651)
		(layer "In11.Cu")
		(net "P5E_PEX3_STN2_TX_DN<35>")
	)
	(segment
		(start 448.247262 -33.657286)
		(end 448.442334 -33.852358)
		(width 0.1651)
		(layer "In11.Cu")
		(net "P5E_PEX3_STN2_TX_DN<35>")
	)
	(segment
		(start 454.458578 -42.414952)
		(end 454.555098 -42.785538)
		(width 0.1651)
		(layer "In11.Cu")
		(net "P5E_PEX3_STN2_TX_DN<35>")
	)
	(segment
		(start 425.132754 -131.103624)
		(end 425.132754 -139.897866)
		(width 0.1651)
		(layer "In11.Cu")
		(net "P5E_PEX3_STN2_TX_DN<35>")
	)
	(segment
		(start 454.78446 -56.765698)
		(end 452.63562 -67.91071)
		(width 0.1651)
		(layer "In11.Cu")
		(net "P5E_PEX3_STN2_TX_DN<35>")
	)
	(segment
		(start 403.815804 -271.399)
		(end 403.815804 -271.427448)
		(width 0.1143)
		(layer "In11.Cu")
		(net "P5E_PEX3_STN2_TX_DN<35>")
	)
	(segment
		(start 441.489084 -80.13319)
		(end 427.36008 -105.014776)
		(width 0.1651)
		(layer "In11.Cu")
		(net "P5E_PEX3_STN2_TX_DN<35>")
	)
	(segment
		(start 448.673728 -33.948116)
		(end 449.221606 -33.948116)
		(width 0.1651)
		(layer "In11.Cu")
		(net "P5E_PEX3_STN2_TX_DN<35>")
	)
	(segment
		(start 296.766742 -344.219022)
		(end 296.446702 -344.539062)
		(width 0.13462)
		(layer "F.Cu")
		(net "P5E_PEX2_STN7_TX_C_DN<125>")
	)
	(segment
		(start 296.446702 -344.539062)
		(end 296.446702 -345.170506)
		(width 0.13462)
		(layer "F.Cu")
		(net "P5E_PEX2_STN7_TX_C_DN<125>")
	)
	(segment
		(start 296.446702 -345.170506)
		(end 296.741342 -345.465146)
		(width 0.13462)
		(layer "F.Cu")
		(net "P5E_PEX2_STN7_TX_C_DN<125>")
	)
	(segment
		(start 294.896032 -358.6734)
		(end 299.61586 -368.7318)
		(width 0.1651)
		(layer "In7.Cu")
		(net "P5E_PEX2_STN7_TX_C_DN<125>")
	)
	(segment
		(start 299.61586 -368.7318)
		(end 299.61586 -375.829322)
		(width 0.1651)
		(layer "In7.Cu")
		(net "P5E_PEX2_STN7_TX_C_DN<125>")
	)
	(segment
		(start 296.450512 -345.755976)
		(end 296.450512 -346.326714)
		(width 0.1651)
		(layer "In7.Cu")
		(net "P5E_PEX2_STN7_TX_C_DN<125>")
	)
	(segment
		(start 296.450512 -346.326714)
		(end 294.896032 -347.881194)
		(width 0.1651)
		(layer "In7.Cu")
		(net "P5E_PEX2_STN7_TX_C_DN<125>")
	)
	(segment
		(start 296.741342 -345.465146)
		(end 296.450512 -345.755976)
		(width 0.1651)
		(layer "In7.Cu")
		(net "P5E_PEX2_STN7_TX_C_DN<125>")
	)
	(segment
		(start 299.61586 -375.829322)
		(end 299.163994 -376.281188)
		(width 0.1651)
		(layer "In7.Cu")
		(net "P5E_PEX2_STN7_TX_C_DN<125>")
	)
	(segment
		(start 298.616878 -376.281188)
		(end 298.489878 -376.408188)
		(width 0.1651)
		(layer "In7.Cu")
		(net "P5E_PEX2_STN7_TX_C_DN<125>")
	)
	(segment
		(start 294.896032 -347.881194)
		(end 294.896032 -358.6734)
		(width 0.1651)
		(layer "In7.Cu")
		(net "P5E_PEX2_STN7_TX_C_DN<125>")
	)
	(segment
		(start 298.489878 -376.408188)
		(end 298.489878 -376.790204)
		(width 0.1651)
		(layer "In7.Cu")
		(net "P5E_PEX2_STN7_TX_C_DN<125>")
	)
	(segment
		(start 299.163994 -376.281188)
		(end 298.616878 -376.281188)
		(width 0.1651)
		(layer "In7.Cu")
		(net "P5E_PEX2_STN7_TX_C_DN<125>")
	)
	(segment
		(start 68.159122 -350.685354)
		(end 68.479162 -350.365314)
		(width 0.13462)
		(layer "F.Cu")
		(net "P5E_PEX0_STN5_TX_C_DN<83>")
	)
	(segment
		(start 68.453762 -351.611438)
		(end 68.159122 -351.316798)
		(width 0.13462)
		(layer "F.Cu")
		(net "P5E_PEX0_STN5_TX_C_DN<83>")
	)
	(segment
		(start 68.159122 -351.316798)
		(end 68.159122 -350.685354)
		(width 0.13462)
		(layer "F.Cu")
		(net "P5E_PEX0_STN5_TX_C_DN<83>")
	)
	(segment
		(start 68.162932 -351.902268)
		(end 68.453762 -351.611438)
		(width 0.1651)
		(layer "In7.Cu")
		(net "P5E_PEX0_STN5_TX_C_DN<83>")
	)
	(segment
		(start 67.00774 -379.000004)
		(end 66.74739 -359.009696)
		(width 0.1651)
		(layer "In7.Cu")
		(net "P5E_PEX0_STN5_TX_C_DN<83>")
	)
	(segment
		(start 77.94371 -392.67511)
		(end 69.922136 -389.35279)
		(width 0.1651)
		(layer "In7.Cu")
		(net "P5E_PEX0_STN5_TX_C_DN<83>")
	)
	(segment
		(start 79.684372 -405.66467)
		(end 79.684372 -394.415772)
		(width 0.1651)
		(layer "In7.Cu")
		(net "P5E_PEX0_STN5_TX_C_DN<83>")
	)
	(segment
		(start 68.005706 -387.43636)
		(end 67.00774 -385.026916)
		(width 0.1651)
		(layer "In7.Cu")
		(net "P5E_PEX0_STN5_TX_C_DN<83>")
	)
	(segment
		(start 66.608452 -358.31145)
		(end 66.608452 -354.107242)
		(width 0.1651)
		(layer "In7.Cu")
		(net "P5E_PEX0_STN5_TX_C_DN<83>")
	)
	(segment
		(start 79.16799 -406.181052)
		(end 79.684372 -405.66467)
		(width 0.1651)
		(layer "In7.Cu")
		(net "P5E_PEX0_STN5_TX_C_DN<83>")
	)
	(segment
		(start 79.684372 -394.415772)
		(end 77.94371 -392.67511)
		(width 0.1651)
		(layer "In7.Cu")
		(net "P5E_PEX0_STN5_TX_C_DN<83>")
	)
	(segment
		(start 78.636876 -406.181052)
		(end 79.16799 -406.181052)
		(width 0.1651)
		(layer "In7.Cu")
		(net "P5E_PEX0_STN5_TX_C_DN<83>")
	)
	(segment
		(start 78.509876 -406.690068)
		(end 78.509876 -406.308052)
		(width 0.1651)
		(layer "In7.Cu")
		(net "P5E_PEX0_STN5_TX_C_DN<83>")
	)
	(segment
		(start 67.00774 -385.026916)
		(end 67.00774 -379.000004)
		(width 0.1651)
		(layer "In7.Cu")
		(net "P5E_PEX0_STN5_TX_C_DN<83>")
	)
	(segment
		(start 68.162932 -352.552762)
		(end 68.162932 -351.902268)
		(width 0.1651)
		(layer "In7.Cu")
		(net "P5E_PEX0_STN5_TX_C_DN<83>")
	)
	(segment
		(start 69.922136 -389.35279)
		(end 68.005706 -387.43636)
		(width 0.1651)
		(layer "In7.Cu")
		(net "P5E_PEX0_STN5_TX_C_DN<83>")
	)
	(segment
		(start 66.608452 -354.107242)
		(end 68.162932 -352.552762)
		(width 0.1651)
		(layer "In7.Cu")
		(net "P5E_PEX0_STN5_TX_C_DN<83>")
	)
	(segment
		(start 66.74739 -359.009696)
		(end 66.608452 -358.31145)
		(width 0.1651)
		(layer "In7.Cu")
		(net "P5E_PEX0_STN5_TX_C_DN<83>")
	)
	(segment
		(start 78.509876 -406.308052)
		(end 78.636876 -406.181052)
		(width 0.1651)
		(layer "In7.Cu")
		(net "P5E_PEX0_STN5_TX_C_DN<83>")
	)
	(segment
		(start 367.309146 -32.41802)
		(end 366.68075 -32.41802)
		(width 0.13462)
		(layer "F.Cu")
		(net "P5E_PEX3_STN2_TX_DP<46>")
	)
	(segment
		(start 366.68075 -32.41802)
		(end 366.359186 -32.739584)
		(width 0.13462)
		(layer "F.Cu")
		(net "P5E_PEX3_STN2_TX_DP<46>")
	)
	(segment
		(start 367.60531 -32.714184)
		(end 367.309146 -32.41802)
		(width 0.13462)
		(layer "F.Cu")
		(net "P5E_PEX3_STN2_TX_DP<46>")
	)
	(segment
		(start 373.301006 -34.595562)
		(end 373.193818 -34.583624)
		(width 0.1651)
		(layer "In11.Cu")
		(net "P5E_PEX3_STN2_TX_DP<46>")
	)
	(segment
		(start 393.08405 -270.220948)
		(end 392.078464 -264.559288)
		(width 0.1651)
		(layer "In11.Cu")
		(net "P5E_PEX3_STN2_TX_DP<46>")
	)
	(segment
		(start 372.521988 -33.620456)
		(end 369.629182 -32.423354)
		(width 0.1651)
		(layer "In11.Cu")
		(net "P5E_PEX3_STN2_TX_DP<46>")
	)
	(segment
		(start 368.568986 -32.423354)
		(end 367.89614 -32.423354)
		(width 0.1651)
		(layer "In11.Cu")
		(net "P5E_PEX3_STN2_TX_DP<46>")
	)
	(segment
		(start 393.7 -280.699718)
		(end 393.7 -280.434288)
		(width 0.1143)
		(layer "In11.Cu")
		(net "P5E_PEX3_STN2_TX_DP<46>")
	)
	(segment
		(start 385.461764 -62.965838)
		(end 384.71983 -50.504344)
		(width 0.1651)
		(layer "In11.Cu")
		(net "P5E_PEX3_STN2_TX_DP<46>")
	)
	(segment
		(start 369.629182 -32.423354)
		(end 369.242086 -32.423354)
		(width 0.1651)
		(layer "In11.Cu")
		(net "P5E_PEX3_STN2_TX_DP<46>")
	)
	(segment
		(start 380.99873 -104.937814)
		(end 384.577082 -78.744572)
		(width 0.1651)
		(layer "In11.Cu")
		(net "P5E_PEX3_STN2_TX_DP<46>")
	)
	(segment
		(start 369.242086 -32.423354)
		(end 369.153186 -32.512254)
		(width 0.1651)
		(layer "In11.Cu")
		(net "P5E_PEX3_STN2_TX_DP<46>")
	)
	(segment
		(start 393.08405 -271.427448)
		(end 393.08405 -271.399)
		(width 0.1143)
		(layer "In11.Cu")
		(net "P5E_PEX3_STN2_TX_DP<46>")
	)
	(segment
		(start 372.884446 -34.196274)
		(end 372.896384 -34.089086)
		(width 0.1651)
		(layer "In11.Cu")
		(net "P5E_PEX3_STN2_TX_DP<46>")
	)
	(segment
		(start 393.7 -280.434288)
		(end 393.5857 -280.319988)
		(width 0.1143)
		(layer "In11.Cu")
		(net "P5E_PEX3_STN2_TX_DP<46>")
	)
	(segment
		(start 384.71983 -50.504344)
		(end 384.167126 -48.925734)
		(width 0.1651)
		(layer "In11.Cu")
		(net "P5E_PEX3_STN2_TX_DP<46>")
	)
	(segment
		(start 393.12977 -280.10485)
		(end 393.12977 -271.473168)
		(width 0.1143)
		(layer "In11.Cu")
		(net "P5E_PEX3_STN2_TX_DP<46>")
	)
	(segment
		(start 384.577082 -78.744572)
		(end 385.461764 -62.965838)
		(width 0.1651)
		(layer "In11.Cu")
		(net "P5E_PEX3_STN2_TX_DP<46>")
	)
	(segment
		(start 393.08405 -271.399)
		(end 393.08405 -270.220948)
		(width 0.1651)
		(layer "In11.Cu")
		(net "P5E_PEX3_STN2_TX_DP<46>")
	)
	(segment
		(start 380.858776 -138.17854)
		(end 380.395734 -116.818664)
		(width 0.1651)
		(layer "In11.Cu")
		(net "P5E_PEX3_STN2_TX_DP<46>")
	)
	(segment
		(start 380.395734 -116.818664)
		(end 380.99873 -104.937814)
		(width 0.1651)
		(layer "In11.Cu")
		(net "P5E_PEX3_STN2_TX_DP<46>")
	)
	(segment
		(start 369.153186 -32.512254)
		(end 368.657886 -32.512254)
		(width 0.1651)
		(layer "In11.Cu")
		(net "P5E_PEX3_STN2_TX_DP<46>")
	)
	(segment
		(start 393.12977 -271.473168)
		(end 393.08405 -271.427448)
		(width 0.1143)
		(layer "In11.Cu")
		(net "P5E_PEX3_STN2_TX_DP<46>")
	)
	(segment
		(start 382.857756 -46.559216)
		(end 373.301006 -34.595562)
		(width 0.1651)
		(layer "In11.Cu")
		(net "P5E_PEX3_STN2_TX_DP<46>")
	)
	(segment
		(start 393.5857 -280.319988)
		(end 393.344908 -280.319988)
		(width 0.1143)
		(layer "In11.Cu")
		(net "P5E_PEX3_STN2_TX_DP<46>")
	)
	(segment
		(start 373.193818 -34.583624)
		(end 372.884446 -34.196274)
		(width 0.1651)
		(layer "In11.Cu")
		(net "P5E_PEX3_STN2_TX_DP<46>")
	)
	(segment
		(start 393.344908 -280.319988)
		(end 393.12977 -280.10485)
		(width 0.1143)
		(layer "In11.Cu")
		(net "P5E_PEX3_STN2_TX_DP<46>")
	)
	(segment
		(start 367.89614 -32.423354)
		(end 367.60531 -32.714184)
		(width 0.1651)
		(layer "In11.Cu")
		(net "P5E_PEX3_STN2_TX_DP<46>")
	)
	(segment
		(start 384.167126 -48.925734)
		(end 382.857756 -46.559216)
		(width 0.1651)
		(layer "In11.Cu")
		(net "P5E_PEX3_STN2_TX_DP<46>")
	)
	(segment
		(start 392.078464 -264.559288)
		(end 380.858776 -138.17854)
		(width 0.1651)
		(layer "In11.Cu")
		(net "P5E_PEX3_STN2_TX_DP<46>")
	)
	(segment
		(start 368.657886 -32.512254)
		(end 368.568986 -32.423354)
		(width 0.1651)
		(layer "In11.Cu")
		(net "P5E_PEX3_STN2_TX_DP<46>")
	)
	(segment
		(start 372.896384 -34.089086)
		(end 372.521988 -33.620456)
		(width 0.1651)
		(layer "In11.Cu")
		(net "P5E_PEX3_STN2_TX_DP<46>")
	)
	(segment
		(start 25.845008 -351.316798)
		(end 25.845008 -350.685354)
		(width 0.13462)
		(layer "F.Cu")
		(net "P5E_PEX0_STN7_TX_C_DP<115>")
	)
	(segment
		(start 25.550368 -351.611438)
		(end 25.845008 -351.316798)
		(width 0.13462)
		(layer "F.Cu")
		(net "P5E_PEX0_STN7_TX_C_DP<115>")
	)
	(segment
		(start 25.845008 -350.685354)
		(end 25.524968 -350.365314)
		(width 0.13462)
		(layer "F.Cu")
		(net "P5E_PEX0_STN7_TX_C_DP<115>")
	)
	(segment
		(start 33.151318 -392.426698)
		(end 25.73528 -389.354822)
		(width 0.1651)
		(layer "In7.Cu")
		(net "P5E_PEX0_STN7_TX_C_DP<115>")
	)
	(segment
		(start 25.73528 -389.354822)
		(end 23.907242 -387.526784)
		(width 0.1651)
		(layer "In7.Cu")
		(net "P5E_PEX0_STN7_TX_C_DP<115>")
	)
	(segment
		(start 22.684486 -384.809238)
		(end 22.16658 -376.207274)
		(width 0.1651)
		(layer "In7.Cu")
		(net "P5E_PEX0_STN7_TX_C_DP<115>")
	)
	(segment
		(start 23.907242 -387.526784)
		(end 22.684486 -384.809238)
		(width 0.1651)
		(layer "In7.Cu")
		(net "P5E_PEX0_STN7_TX_C_DP<115>")
	)
	(segment
		(start 22.16658 -370.67617)
		(end 22.573742 -366.540288)
		(width 0.1651)
		(layer "In7.Cu")
		(net "P5E_PEX0_STN7_TX_C_DP<115>")
	)
	(segment
		(start 25.841198 -352.435922)
		(end 25.841198 -351.902268)
		(width 0.1651)
		(layer "In7.Cu")
		(net "P5E_PEX0_STN7_TX_C_DP<115>")
	)
	(segment
		(start 35.40252 -401.849336)
		(end 35.40252 -394.6779)
		(width 0.1651)
		(layer "In7.Cu")
		(net "P5E_PEX0_STN7_TX_C_DP<115>")
	)
	(segment
		(start 22.573742 -366.540288)
		(end 24.286718 -357.928418)
		(width 0.1651)
		(layer "In7.Cu")
		(net "P5E_PEX0_STN7_TX_C_DP<115>")
	)
	(segment
		(start 34.636964 -401.999196)
		(end 35.25266 -401.999196)
		(width 0.1651)
		(layer "In7.Cu")
		(net "P5E_PEX0_STN7_TX_C_DP<115>")
	)
	(segment
		(start 34.509964 -401.872196)
		(end 34.636964 -401.999196)
		(width 0.1651)
		(layer "In7.Cu")
		(net "P5E_PEX0_STN7_TX_C_DP<115>")
	)
	(segment
		(start 35.40252 -394.6779)
		(end 33.151318 -392.426698)
		(width 0.1651)
		(layer "In7.Cu")
		(net "P5E_PEX0_STN7_TX_C_DP<115>")
	)
	(segment
		(start 35.25266 -401.999196)
		(end 35.40252 -401.849336)
		(width 0.1651)
		(layer "In7.Cu")
		(net "P5E_PEX0_STN7_TX_C_DP<115>")
	)
	(segment
		(start 24.286718 -353.990402)
		(end 25.841198 -352.435922)
		(width 0.1651)
		(layer "In7.Cu")
		(net "P5E_PEX0_STN7_TX_C_DP<115>")
	)
	(segment
		(start 22.16658 -376.207274)
		(end 22.16658 -370.67617)
		(width 0.1651)
		(layer "In7.Cu")
		(net "P5E_PEX0_STN7_TX_C_DP<115>")
	)
	(segment
		(start 24.286718 -357.928418)
		(end 24.286718 -353.990402)
		(width 0.1651)
		(layer "In7.Cu")
		(net "P5E_PEX0_STN7_TX_C_DP<115>")
	)
	(segment
		(start 25.841198 -351.902268)
		(end 25.550368 -351.611438)
		(width 0.1651)
		(layer "In7.Cu")
		(net "P5E_PEX0_STN7_TX_C_DP<115>")
	)
	(segment
		(start 34.509964 -401.49018)
		(end 34.509964 -401.872196)
		(width 0.1651)
		(layer "In7.Cu")
		(net "P5E_PEX0_STN7_TX_C_DP<115>")
	)
	(segment
		(start 166.158672 -351.611438)
		(end 165.864032 -351.316798)
		(width 0.13462)
		(layer "F.Cu")
		(net "P5E_PEX1_STN7_TX_C_DN<114>")
	)
	(segment
		(start 165.864032 -350.685354)
		(end 166.184072 -350.365314)
		(width 0.13462)
		(layer "F.Cu")
		(net "P5E_PEX1_STN7_TX_C_DN<114>")
	)
	(segment
		(start 165.864032 -351.316798)
		(end 165.864032 -350.685354)
		(width 0.13462)
		(layer "F.Cu")
		(net "P5E_PEX1_STN7_TX_C_DN<114>")
	)
	(segment
		(start 165.169596 -401.181062)
		(end 165.475158 -400.8755)
		(width 0.1651)
		(layer "In11.Cu")
		(net "P5E_PEX1_STN7_TX_C_DN<114>")
	)
	(segment
		(start 164.313362 -354.219256)
		(end 165.867842 -352.664776)
		(width 0.1651)
		(layer "In11.Cu")
		(net "P5E_PEX1_STN7_TX_C_DN<114>")
	)
	(segment
		(start 163.300918 -360.047794)
		(end 164.313362 -358.525064)
		(width 0.1651)
		(layer "In11.Cu")
		(net "P5E_PEX1_STN7_TX_C_DN<114>")
	)
	(segment
		(start 164.31006 -401.308062)
		(end 164.43706 -401.181062)
		(width 0.1651)
		(layer "In11.Cu")
		(net "P5E_PEX1_STN7_TX_C_DN<114>")
	)
	(segment
		(start 155.129738 -365.156242)
		(end 157.897068 -362.316014)
		(width 0.1651)
		(layer "In11.Cu")
		(net "P5E_PEX1_STN7_TX_C_DN<114>")
	)
	(segment
		(start 154.141424 -385.496562)
		(end 153.89606 -382.657858)
		(width 0.1651)
		(layer "In11.Cu")
		(net "P5E_PEX1_STN7_TX_C_DN<114>")
	)
	(segment
		(start 154.075892 -367.94313)
		(end 155.129738 -365.156242)
		(width 0.1651)
		(layer "In11.Cu")
		(net "P5E_PEX1_STN7_TX_C_DN<114>")
	)
	(segment
		(start 164.313362 -358.525064)
		(end 164.313362 -354.219256)
		(width 0.1651)
		(layer "In11.Cu")
		(net "P5E_PEX1_STN7_TX_C_DN<114>")
	)
	(segment
		(start 155.35529 -388.49935)
		(end 154.141424 -385.496562)
		(width 0.1651)
		(layer "In11.Cu")
		(net "P5E_PEX1_STN7_TX_C_DN<114>")
	)
	(segment
		(start 165.867842 -351.902268)
		(end 166.158672 -351.611438)
		(width 0.1651)
		(layer "In11.Cu")
		(net "P5E_PEX1_STN7_TX_C_DN<114>")
	)
	(segment
		(start 157.897068 -362.316014)
		(end 163.300918 -360.047794)
		(width 0.1651)
		(layer "In11.Cu")
		(net "P5E_PEX1_STN7_TX_C_DN<114>")
	)
	(segment
		(start 159.179514 -391.337292)
		(end 155.35529 -388.49935)
		(width 0.1651)
		(layer "In11.Cu")
		(net "P5E_PEX1_STN7_TX_C_DN<114>")
	)
	(segment
		(start 165.475158 -400.8755)
		(end 165.475158 -394.88999)
		(width 0.1651)
		(layer "In11.Cu")
		(net "P5E_PEX1_STN7_TX_C_DN<114>")
	)
	(segment
		(start 164.310314 -393.725146)
		(end 159.179514 -391.337292)
		(width 0.1651)
		(layer "In11.Cu")
		(net "P5E_PEX1_STN7_TX_C_DN<114>")
	)
	(segment
		(start 164.43706 -401.181062)
		(end 165.169596 -401.181062)
		(width 0.1651)
		(layer "In11.Cu")
		(net "P5E_PEX1_STN7_TX_C_DN<114>")
	)
	(segment
		(start 153.89606 -382.657858)
		(end 154.075892 -367.94313)
		(width 0.1651)
		(layer "In11.Cu")
		(net "P5E_PEX1_STN7_TX_C_DN<114>")
	)
	(segment
		(start 165.475158 -394.88999)
		(end 164.310314 -393.725146)
		(width 0.1651)
		(layer "In11.Cu")
		(net "P5E_PEX1_STN7_TX_C_DN<114>")
	)
	(segment
		(start 164.31006 -401.690078)
		(end 164.31006 -401.308062)
		(width 0.1651)
		(layer "In11.Cu")
		(net "P5E_PEX1_STN7_TX_C_DN<114>")
	)
	(segment
		(start 165.867842 -352.664776)
		(end 165.867842 -351.902268)
		(width 0.1651)
		(layer "In11.Cu")
		(net "P5E_PEX1_STN7_TX_C_DN<114>")
	)
	(segment
		(start 367.60531 -31.850584)
		(end 367.312194 -32.1437)
		(width 0.13462)
		(layer "F.Cu")
		(net "P5E_PEX3_STN2_TX_DN<46>")
	)
	(segment
		(start 367.312194 -32.1437)
		(end 366.677702 -32.1437)
		(width 0.13462)
		(layer "F.Cu")
		(net "P5E_PEX3_STN2_TX_DN<46>")
	)
	(segment
		(start 366.677702 -32.1437)
		(end 366.359186 -31.825184)
		(width 0.13462)
		(layer "F.Cu")
		(net "P5E_PEX3_STN2_TX_DN<46>")
	)
	(segment
		(start 383.093214 -46.401736)
		(end 384.425444 -48.810164)
		(width 0.1651)
		(layer "In11.Cu")
		(net "P5E_PEX3_STN2_TX_DN<46>")
	)
	(segment
		(start 384.425444 -48.810164)
		(end 384.998976 -50.44821)
		(width 0.1651)
		(layer "In11.Cu")
		(net "P5E_PEX3_STN2_TX_DN<46>")
	)
	(segment
		(start 369.685316 -32.141414)
		(end 372.696994 -33.387538)
		(width 0.1651)
		(layer "In11.Cu")
		(net "P5E_PEX3_STN2_TX_DN<46>")
	)
	(segment
		(start 372.696994 -33.387538)
		(end 383.093214 -46.401736)
		(width 0.1651)
		(layer "In11.Cu")
		(net "P5E_PEX3_STN2_TX_DN<46>")
	)
	(segment
		(start 385.744212 -62.96533)
		(end 384.858006 -78.771496)
		(width 0.1651)
		(layer "In11.Cu")
		(net "P5E_PEX3_STN2_TX_DN<46>")
	)
	(segment
		(start 393.36599 -271.427448)
		(end 393.32027 -271.473168)
		(width 0.1143)
		(layer "In11.Cu")
		(net "P5E_PEX3_STN2_TX_DN<46>")
	)
	(segment
		(start 393.36599 -271.399)
		(end 393.36599 -271.427448)
		(width 0.1143)
		(layer "In11.Cu")
		(net "P5E_PEX3_STN2_TX_DN<46>")
	)
	(segment
		(start 381.279908 -104.96423)
		(end 380.677928 -116.822728)
		(width 0.1651)
		(layer "In11.Cu")
		(net "P5E_PEX3_STN2_TX_DN<46>")
	)
	(segment
		(start 393.7 -280.015188)
		(end 393.7 -279.749504)
		(width 0.1143)
		(layer "In11.Cu")
		(net "P5E_PEX3_STN2_TX_DN<46>")
	)
	(segment
		(start 393.36599 -270.196056)
		(end 393.36599 -271.399)
		(width 0.1651)
		(layer "In11.Cu")
		(net "P5E_PEX3_STN2_TX_DN<46>")
	)
	(segment
		(start 380.677928 -116.822728)
		(end 381.140462 -138.163046)
		(width 0.1651)
		(layer "In11.Cu")
		(net "P5E_PEX3_STN2_TX_DN<46>")
	)
	(segment
		(start 384.858006 -78.771496)
		(end 381.279908 -104.96423)
		(width 0.1651)
		(layer "In11.Cu")
		(net "P5E_PEX3_STN2_TX_DN<46>")
	)
	(segment
		(start 367.89614 -32.141414)
		(end 369.685316 -32.141414)
		(width 0.1651)
		(layer "In11.Cu")
		(net "P5E_PEX3_STN2_TX_DN<46>")
	)
	(segment
		(start 392.358372 -264.52195)
		(end 393.36599 -270.196056)
		(width 0.1651)
		(layer "In11.Cu")
		(net "P5E_PEX3_STN2_TX_DN<46>")
	)
	(segment
		(start 393.32027 -271.473168)
		(end 393.32027 -280.025856)
		(width 0.1143)
		(layer "In11.Cu")
		(net "P5E_PEX3_STN2_TX_DN<46>")
	)
	(segment
		(start 367.60531 -31.850584)
		(end 367.89614 -32.141414)
		(width 0.1651)
		(layer "In11.Cu")
		(net "P5E_PEX3_STN2_TX_DN<46>")
	)
	(segment
		(start 393.32027 -280.025856)
		(end 393.423902 -280.129488)
		(width 0.1143)
		(layer "In11.Cu")
		(net "P5E_PEX3_STN2_TX_DN<46>")
	)
	(segment
		(start 384.998976 -50.44821)
		(end 385.744212 -62.96533)
		(width 0.1651)
		(layer "In11.Cu")
		(net "P5E_PEX3_STN2_TX_DN<46>")
	)
	(segment
		(start 393.5857 -280.129488)
		(end 393.7 -280.015188)
		(width 0.1143)
		(layer "In11.Cu")
		(net "P5E_PEX3_STN2_TX_DN<46>")
	)
	(segment
		(start 381.140462 -138.163046)
		(end 392.358372 -264.52195)
		(width 0.1651)
		(layer "In11.Cu")
		(net "P5E_PEX3_STN2_TX_DN<46>")
	)
	(segment
		(start 393.423902 -280.129488)
		(end 393.5857 -280.129488)
		(width 0.1143)
		(layer "In11.Cu")
		(net "P5E_PEX3_STN2_TX_DN<46>")
	)
	(segment
		(start 70.935596 -318.320166)
		(end 71.049896 -318.434466)
		(width 0.1143)
		(layer "In5.Cu")
		(net "P5E_PEX0_STN5_RX_DN<93>")
	)
	(segment
		(start 86.858602 -339.689186)
		(end 71.60006 -322.854066)
		(width 0.1651)
		(layer "In5.Cu")
		(net "P5E_PEX0_STN5_RX_DN<93>")
	)
	(segment
		(start 84.200746 -369.306348)
		(end 87.727536 -359.449878)
		(width 0.1651)
		(layer "In5.Cu")
		(net "P5E_PEX0_STN5_RX_DN<93>")
	)
	(segment
		(start 84.08416 -371.984524)
		(end 84.08416 -369.892834)
		(width 0.1651)
		(layer "In5.Cu")
		(net "P5E_PEX0_STN5_RX_DN<93>")
	)
	(segment
		(start 87.727536 -359.449878)
		(end 88.371172 -357.89616)
		(width 0.1651)
		(layer "In5.Cu")
		(net "P5E_PEX0_STN5_RX_DN<93>")
	)
	(segment
		(start 70.715886 -320.719704)
		(end 70.715886 -319.995296)
		(width 0.1651)
		(layer "In5.Cu")
		(net "P5E_PEX0_STN5_RX_DN<93>")
	)
	(segment
		(start 70.670166 -318.434466)
		(end 70.784466 -318.320166)
		(width 0.1143)
		(layer "In5.Cu")
		(net "P5E_PEX0_STN5_RX_DN<93>")
	)
	(segment
		(start 83.036918 -372.381018)
		(end 83.687666 -372.381018)
		(width 0.1651)
		(layer "In5.Cu")
		(net "P5E_PEX0_STN5_RX_DN<93>")
	)
	(segment
		(start 70.715886 -319.966848)
		(end 70.670166 -319.921128)
		(width 0.1143)
		(layer "In5.Cu")
		(net "P5E_PEX0_STN5_RX_DN<93>")
	)
	(segment
		(start 70.715886 -319.995296)
		(end 70.715886 -319.966848)
		(width 0.1143)
		(layer "In5.Cu")
		(net "P5E_PEX0_STN5_RX_DN<93>")
	)
	(segment
		(start 84.08416 -369.892834)
		(end 84.200746 -369.306348)
		(width 0.1651)
		(layer "In5.Cu")
		(net "P5E_PEX0_STN5_RX_DN<93>")
	)
	(segment
		(start 88.371172 -357.89616)
		(end 88.371172 -341.953088)
		(width 0.1651)
		(layer "In5.Cu")
		(net "P5E_PEX0_STN5_RX_DN<93>")
	)
	(segment
		(start 70.784466 -318.320166)
		(end 70.935596 -318.320166)
		(width 0.1143)
		(layer "In5.Cu")
		(net "P5E_PEX0_STN5_RX_DN<93>")
	)
	(segment
		(start 82.909918 -372.508018)
		(end 83.036918 -372.381018)
		(width 0.1651)
		(layer "In5.Cu")
		(net "P5E_PEX0_STN5_RX_DN<93>")
	)
	(segment
		(start 83.687666 -372.381018)
		(end 84.08416 -371.984524)
		(width 0.1651)
		(layer "In5.Cu")
		(net "P5E_PEX0_STN5_RX_DN<93>")
	)
	(segment
		(start 82.909918 -372.890034)
		(end 82.909918 -372.508018)
		(width 0.1651)
		(layer "In5.Cu")
		(net "P5E_PEX0_STN5_RX_DN<93>")
	)
	(segment
		(start 70.670166 -319.921128)
		(end 70.670166 -318.434466)
		(width 0.1143)
		(layer "In5.Cu")
		(net "P5E_PEX0_STN5_RX_DN<93>")
	)
	(segment
		(start 71.049896 -318.434466)
		(end 71.049896 -318.699896)
		(width 0.1143)
		(layer "In5.Cu")
		(net "P5E_PEX0_STN5_RX_DN<93>")
	)
	(segment
		(start 88.371172 -341.953088)
		(end 86.858602 -339.689186)
		(width 0.1651)
		(layer "In5.Cu")
		(net "P5E_PEX0_STN5_RX_DN<93>")
	)
	(segment
		(start 71.60006 -322.854066)
		(end 70.715886 -320.719704)
		(width 0.1651)
		(layer "In5.Cu")
		(net "P5E_PEX0_STN5_RX_DN<93>")
	)
	(segment
		(start 328.342244 -356.831646)
		(end 328.342244 -357.46309)
		(width 0.13462)
		(layer "F.Cu")
		(net "P5E_PEX2_STN5_TX_C_DP<88>")
	)
	(segment
		(start 328.022204 -356.511606)
		(end 328.342244 -356.831646)
		(width 0.13462)
		(layer "F.Cu")
		(net "P5E_PEX2_STN5_TX_C_DP<88>")
	)
	(segment
		(start 328.342244 -357.46309)
		(end 328.047604 -357.75773)
		(width 0.13462)
		(layer "F.Cu")
		(net "P5E_PEX2_STN5_TX_C_DP<88>")
	)
	(segment
		(start 331.22235 -366.064546)
		(end 331.412088 -366.522508)
		(width 0.1651)
		(layer "In7.Cu")
		(net "P5E_PEX2_STN5_TX_C_DP<88>")
	)
	(segment
		(start 330.327762 -363.905546)
		(end 330.5175 -364.363254)
		(width 0.1651)
		(layer "In7.Cu")
		(net "P5E_PEX2_STN5_TX_C_DP<88>")
	)
	(segment
		(start 331.080872 -365.491014)
		(end 331.270356 -365.948468)
		(width 0.1651)
		(layer "In7.Cu")
		(net "P5E_PEX2_STN5_TX_C_DP<88>")
	)
	(segment
		(start 330.375768 -363.789468)
		(end 330.327762 -363.905546)
		(width 0.1651)
		(layer "In7.Cu")
		(net "P5E_PEX2_STN5_TX_C_DP<88>")
	)
	(segment
		(start 329.880468 -362.826046)
		(end 330.070206 -363.283754)
		(width 0.1651)
		(layer "In7.Cu")
		(net "P5E_PEX2_STN5_TX_C_DP<88>")
	)
	(segment
		(start 330.964794 -365.443008)
		(end 331.080872 -365.491014)
		(width 0.1651)
		(layer "In7.Cu")
		(net "P5E_PEX2_STN5_TX_C_DP<88>")
	)
	(segment
		(start 328.338434 -358.869996)
		(end 329.928474 -362.709968)
		(width 0.1651)
		(layer "In7.Cu")
		(net "P5E_PEX2_STN5_TX_C_DP<88>")
	)
	(segment
		(start 328.338434 -358.04856)
		(end 328.338434 -358.869996)
		(width 0.1651)
		(layer "In7.Cu")
		(net "P5E_PEX2_STN5_TX_C_DP<88>")
	)
	(segment
		(start 329.928474 -362.709968)
		(end 329.880468 -362.826046)
		(width 0.1651)
		(layer "In7.Cu")
		(net "P5E_PEX2_STN5_TX_C_DP<88>")
	)
	(segment
		(start 330.186284 -363.332014)
		(end 330.375768 -363.789468)
		(width 0.1651)
		(layer "In7.Cu")
		(net "P5E_PEX2_STN5_TX_C_DP<88>")
	)
	(segment
		(start 330.070206 -363.283754)
		(end 330.186284 -363.332014)
		(width 0.1651)
		(layer "In7.Cu")
		(net "P5E_PEX2_STN5_TX_C_DP<88>")
	)
	(segment
		(start 330.633578 -364.411514)
		(end 330.823062 -364.868968)
		(width 0.1651)
		(layer "In7.Cu")
		(net "P5E_PEX2_STN5_TX_C_DP<88>")
	)
	(segment
		(start 331.270356 -365.948468)
		(end 331.22235 -366.064546)
		(width 0.1651)
		(layer "In7.Cu")
		(net "P5E_PEX2_STN5_TX_C_DP<88>")
	)
	(segment
		(start 328.047604 -357.75773)
		(end 328.338434 -358.04856)
		(width 0.1651)
		(layer "In7.Cu")
		(net "P5E_PEX2_STN5_TX_C_DP<88>")
	)
	(segment
		(start 331.617066 -378.79909)
		(end 331.490066 -378.67209)
		(width 0.1651)
		(layer "In7.Cu")
		(net "P5E_PEX2_STN5_TX_C_DP<88>")
	)
	(segment
		(start 330.823062 -364.868968)
		(end 330.775056 -364.985046)
		(width 0.1651)
		(layer "In7.Cu")
		(net "P5E_PEX2_STN5_TX_C_DP<88>")
	)
	(segment
		(start 330.775056 -364.985046)
		(end 330.964794 -365.443008)
		(width 0.1651)
		(layer "In7.Cu")
		(net "P5E_PEX2_STN5_TX_C_DP<88>")
	)
	(segment
		(start 332.334108 -378.512324)
		(end 332.047342 -378.79909)
		(width 0.1651)
		(layer "In7.Cu")
		(net "P5E_PEX2_STN5_TX_C_DP<88>")
	)
	(segment
		(start 331.528166 -366.570514)
		(end 332.334108 -368.516408)
		(width 0.1651)
		(layer "In7.Cu")
		(net "P5E_PEX2_STN5_TX_C_DP<88>")
	)
	(segment
		(start 331.412088 -366.522508)
		(end 331.528166 -366.570514)
		(width 0.1651)
		(layer "In7.Cu")
		(net "P5E_PEX2_STN5_TX_C_DP<88>")
	)
	(segment
		(start 331.490066 -378.67209)
		(end 331.490066 -378.290074)
		(width 0.1651)
		(layer "In7.Cu")
		(net "P5E_PEX2_STN5_TX_C_DP<88>")
	)
	(segment
		(start 332.047342 -378.79909)
		(end 331.617066 -378.79909)
		(width 0.1651)
		(layer "In7.Cu")
		(net "P5E_PEX2_STN5_TX_C_DP<88>")
	)
	(segment
		(start 332.334108 -368.516408)
		(end 332.334108 -378.512324)
		(width 0.1651)
		(layer "In7.Cu")
		(net "P5E_PEX2_STN5_TX_C_DP<88>")
	)
	(segment
		(start 330.5175 -364.363254)
		(end 330.633578 -364.411514)
		(width 0.1651)
		(layer "In7.Cu")
		(net "P5E_PEX2_STN5_TX_C_DP<88>")
	)
	(segment
		(start 447.327528 -30.35808)
		(end 447.001138 -30.03169)
		(width 0.13462)
		(layer "F.Cu")
		(net "P5E_PEX3_STN2_TX_DN<33>")
	)
	(segment
		(start 448.247262 -30.05709)
		(end 447.946272 -30.35808)
		(width 0.13462)
		(layer "F.Cu")
		(net "P5E_PEX3_STN2_TX_DN<33>")
	)
	(segment
		(start 447.946272 -30.35808)
		(end 447.327528 -30.35808)
		(width 0.13462)
		(layer "F.Cu")
		(net "P5E_PEX3_STN2_TX_DN<33>")
	)
	(segment
		(start 448.247262 -30.05709)
		(end 448.43065 -30.240478)
		(width 0.1651)
		(layer "In11.Cu")
		(net "P5E_PEX3_STN2_TX_DN<33>")
	)
	(segment
		(start 448.43065 -30.240478)
		(end 448.689476 -30.34792)
		(width 0.1651)
		(layer "In11.Cu")
		(net "P5E_PEX3_STN2_TX_DN<33>")
	)
	(segment
		(start 427.042834 -140.401802)
		(end 426.69968 -141.878812)
		(width 0.1651)
		(layer "In11.Cu")
		(net "P5E_PEX3_STN2_TX_DN<33>")
	)
	(segment
		(start 456.743562 -56.860948)
		(end 454.476358 -68.499228)
		(width 0.1651)
		(layer "In11.Cu")
		(net "P5E_PEX3_STN2_TX_DN<33>")
	)
	(segment
		(start 449.648072 -30.615128)
		(end 451.494144 -32.441388)
		(width 0.1651)
		(layer "In11.Cu")
		(net "P5E_PEX3_STN2_TX_DN<33>")
	)
	(segment
		(start 439.583068 -87.404956)
		(end 436.158894 -93.454728)
		(width 0.1651)
		(layer "In11.Cu")
		(net "P5E_PEX3_STN2_TX_DN<33>")
	)
	(segment
		(start 455.96048 -40.622982)
		(end 456.470512 -42.544492)
		(width 0.1651)
		(layer "In11.Cu")
		(net "P5E_PEX3_STN2_TX_DN<33>")
	)
	(segment
		(start 405.935688 -278.229568)
		(end 406.049988 -278.115268)
		(width 0.1143)
		(layer "In11.Cu")
		(net "P5E_PEX3_STN2_TX_DN<33>")
	)
	(segment
		(start 436.158894 -93.454474)
		(end 429.310546 -105.554018)
		(width 0.1651)
		(layer "In11.Cu")
		(net "P5E_PEX3_STN2_TX_DN<33>")
	)
	(segment
		(start 426.200316 -150.936706)
		(end 425.972732 -153.6319)
		(width 0.1651)
		(layer "In11.Cu")
		(net "P5E_PEX3_STN2_TX_DN<33>")
	)
	(segment
		(start 452.16953 -74.95667)
		(end 451.392798 -76.002388)
		(width 0.1651)
		(layer "In11.Cu")
		(net "P5E_PEX3_STN2_TX_DN<33>")
	)
	(segment
		(start 405.77389 -278.229568)
		(end 405.935688 -278.229568)
		(width 0.1143)
		(layer "In11.Cu")
		(net "P5E_PEX3_STN2_TX_DN<33>")
	)
	(segment
		(start 427.042834 -133.840982)
		(end 427.042834 -140.401802)
		(width 0.1651)
		(layer "In11.Cu")
		(net "P5E_PEX3_STN2_TX_DN<33>")
	)
	(segment
		(start 443.007496 -81.35493)
		(end 439.583068 -87.404956)
		(width 0.1651)
		(layer "In11.Cu")
		(net "P5E_PEX3_STN2_TX_DN<33>")
	)
	(segment
		(start 444.805562 -79.581502)
		(end 443.007496 -81.35493)
		(width 0.1651)
		(layer "In11.Cu")
		(net "P5E_PEX3_STN2_TX_DN<33>")
	)
	(segment
		(start 405.715978 -271.427448)
		(end 405.670258 -271.473168)
		(width 0.1143)
		(layer "In11.Cu")
		(net "P5E_PEX3_STN2_TX_DN<33>")
	)
	(segment
		(start 451.494144 -32.441388)
		(end 455.96048 -40.622982)
		(width 0.1651)
		(layer "In11.Cu")
		(net "P5E_PEX3_STN2_TX_DN<33>")
	)
	(segment
		(start 426.20057 -150.936706)
		(end 426.200316 -150.936706)
		(width 0.1651)
		(layer "In11.Cu")
		(net "P5E_PEX3_STN2_TX_DN<33>")
	)
	(segment
		(start 405.715978 -265.859514)
		(end 405.715978 -271.399)
		(width 0.1651)
		(layer "In11.Cu")
		(net "P5E_PEX3_STN2_TX_DN<33>")
	)
	(segment
		(start 456.470512 -42.544492)
		(end 456.743562 -56.860948)
		(width 0.1651)
		(layer "In11.Cu")
		(net "P5E_PEX3_STN2_TX_DN<33>")
	)
	(segment
		(start 436.158894 -93.454728)
		(end 436.158894 -93.454474)
		(width 0.1651)
		(layer "In11.Cu")
		(net "P5E_PEX3_STN2_TX_DN<33>")
	)
	(segment
		(start 424.97883 -161.060384)
		(end 405.715978 -265.859514)
		(width 0.1651)
		(layer "In11.Cu")
		(net "P5E_PEX3_STN2_TX_DN<33>")
	)
	(segment
		(start 429.310546 -105.554018)
		(end 427.69536 -118.553992)
		(width 0.1651)
		(layer "In11.Cu")
		(net "P5E_PEX3_STN2_TX_DN<33>")
	)
	(segment
		(start 449.039234 -30.34792)
		(end 449.648072 -30.615128)
		(width 0.1651)
		(layer "In11.Cu")
		(net "P5E_PEX3_STN2_TX_DN<33>")
	)
	(segment
		(start 405.715978 -271.399)
		(end 405.715978 -271.427448)
		(width 0.1143)
		(layer "In11.Cu")
		(net "P5E_PEX3_STN2_TX_DN<33>")
	)
	(segment
		(start 405.670258 -278.125936)
		(end 405.77389 -278.229568)
		(width 0.1143)
		(layer "In11.Cu")
		(net "P5E_PEX3_STN2_TX_DN<33>")
	)
	(segment
		(start 448.689476 -30.34792)
		(end 449.039234 -30.34792)
		(width 0.1651)
		(layer "In11.Cu")
		(net "P5E_PEX3_STN2_TX_DN<33>")
	)
	(segment
		(start 427.69536 -118.553992)
		(end 427.042834 -133.840982)
		(width 0.1651)
		(layer "In11.Cu")
		(net "P5E_PEX3_STN2_TX_DN<33>")
	)
	(segment
		(start 425.972732 -153.6319)
		(end 424.97883 -161.060384)
		(width 0.1651)
		(layer "In11.Cu")
		(net "P5E_PEX3_STN2_TX_DN<33>")
	)
	(segment
		(start 454.476358 -68.499228)
		(end 452.16953 -74.95667)
		(width 0.1651)
		(layer "In11.Cu")
		(net "P5E_PEX3_STN2_TX_DN<33>")
	)
	(segment
		(start 451.392798 -76.002388)
		(end 444.805562 -79.581502)
		(width 0.1651)
		(layer "In11.Cu")
		(net "P5E_PEX3_STN2_TX_DN<33>")
	)
	(segment
		(start 426.69968 -141.878812)
		(end 426.427646 -148.24456)
		(width 0.1651)
		(layer "In11.Cu")
		(net "P5E_PEX3_STN2_TX_DN<33>")
	)
	(segment
		(start 426.427646 -148.24456)
		(end 426.20057 -150.936706)
		(width 0.1651)
		(layer "In11.Cu")
		(net "P5E_PEX3_STN2_TX_DN<33>")
	)
	(segment
		(start 405.670258 -271.473168)
		(end 405.670258 -278.125936)
		(width 0.1143)
		(layer "In11.Cu")
		(net "P5E_PEX3_STN2_TX_DN<33>")
	)
	(segment
		(start 406.049988 -278.115268)
		(end 406.049988 -277.849838)
		(width 0.1143)
		(layer "In11.Cu")
		(net "P5E_PEX3_STN2_TX_DN<33>")
	)
	(segment
		(start 41.933876 -319.995296)
		(end 41.933876 -319.966848)
		(width 0.1143)
		(layer "In5.Cu")
		(net "P5E_PEX0_STN7_RX_DP<127>")
	)
	(segment
		(start 44.177204 -369.32362)
		(end 45.29709 -366.620044)
		(width 0.1651)
		(layer "In5.Cu")
		(net "P5E_PEX0_STN7_RX_DP<127>")
	)
	(segment
		(start 41.933876 -319.966848)
		(end 41.979596 -319.921128)
		(width 0.1143)
		(layer "In5.Cu")
		(net "P5E_PEX0_STN7_RX_DP<127>")
	)
	(segment
		(start 44.177204 -383.44094)
		(end 44.177204 -369.32362)
		(width 0.1651)
		(layer "In5.Cu")
		(net "P5E_PEX0_STN7_RX_DP<127>")
	)
	(segment
		(start 51.837844 -358.65054)
		(end 52.085494 -358.2797)
		(width 0.1651)
		(layer "In5.Cu")
		(net "P5E_PEX0_STN7_RX_DP<127>")
	)
	(segment
		(start 45.29709 -366.620044)
		(end 51.837844 -358.65054)
		(width 0.1651)
		(layer "In5.Cu")
		(net "P5E_PEX0_STN7_RX_DP<127>")
	)
	(segment
		(start 52.267358 -341.713312)
		(end 51.602386 -340.107778)
		(width 0.1651)
		(layer "In5.Cu")
		(net "P5E_PEX0_STN7_RX_DP<127>")
	)
	(segment
		(start 47.33036 -333.920338)
		(end 47.05477 -333.508096)
		(width 0.1651)
		(layer "In5.Cu")
		(net "P5E_PEX0_STN7_RX_DP<127>")
	)
	(segment
		(start 52.267358 -357.840534)
		(end 52.267358 -341.713312)
		(width 0.1651)
		(layer "In5.Cu")
		(net "P5E_PEX0_STN7_RX_DP<127>")
	)
	(segment
		(start 47.086266 -333.3496)
		(end 43.002708 -327.23836)
		(width 0.1651)
		(layer "In5.Cu")
		(net "P5E_PEX0_STN7_RX_DP<127>")
	)
	(segment
		(start 47.05477 -333.508096)
		(end 47.086266 -333.3496)
		(width 0.1651)
		(layer "In5.Cu")
		(net "P5E_PEX0_STN7_RX_DP<127>")
	)
	(segment
		(start 43.819064 -383.79908)
		(end 44.177204 -383.44094)
		(width 0.1651)
		(layer "In5.Cu")
		(net "P5E_PEX0_STN7_RX_DP<127>")
	)
	(segment
		(start 43.437048 -383.79908)
		(end 43.819064 -383.79908)
		(width 0.1651)
		(layer "In5.Cu")
		(net "P5E_PEX0_STN7_RX_DP<127>")
	)
	(segment
		(start 42.205402 -318.129666)
		(end 42.435526 -318.129666)
		(width 0.1143)
		(layer "In5.Cu")
		(net "P5E_PEX0_STN7_RX_DP<127>")
	)
	(segment
		(start 42.435526 -318.129666)
		(end 42.549826 -318.015366)
		(width 0.1143)
		(layer "In5.Cu")
		(net "P5E_PEX0_STN7_RX_DP<127>")
	)
	(segment
		(start 43.310048 -383.67208)
		(end 43.437048 -383.79908)
		(width 0.1651)
		(layer "In5.Cu")
		(net "P5E_PEX0_STN7_RX_DP<127>")
	)
	(segment
		(start 43.002708 -327.23836)
		(end 41.933876 -324.657466)
		(width 0.1651)
		(layer "In5.Cu")
		(net "P5E_PEX0_STN7_RX_DP<127>")
	)
	(segment
		(start 41.933876 -324.657466)
		(end 41.933876 -319.995296)
		(width 0.1651)
		(layer "In5.Cu")
		(net "P5E_PEX0_STN7_RX_DP<127>")
	)
	(segment
		(start 41.979596 -318.355472)
		(end 42.205402 -318.129666)
		(width 0.1143)
		(layer "In5.Cu")
		(net "P5E_PEX0_STN7_RX_DP<127>")
	)
	(segment
		(start 47.488856 -333.951834)
		(end 47.33036 -333.920338)
		(width 0.1651)
		(layer "In5.Cu")
		(net "P5E_PEX0_STN7_RX_DP<127>")
	)
	(segment
		(start 43.310048 -383.290064)
		(end 43.310048 -383.67208)
		(width 0.1651)
		(layer "In5.Cu")
		(net "P5E_PEX0_STN7_RX_DP<127>")
	)
	(segment
		(start 42.549826 -318.015366)
		(end 42.549826 -317.749936)
		(width 0.1143)
		(layer "In5.Cu")
		(net "P5E_PEX0_STN7_RX_DP<127>")
	)
	(segment
		(start 52.085494 -358.2797)
		(end 52.267358 -357.840534)
		(width 0.1651)
		(layer "In5.Cu")
		(net "P5E_PEX0_STN7_RX_DP<127>")
	)
	(segment
		(start 41.979596 -319.921128)
		(end 41.979596 -318.355472)
		(width 0.1143)
		(layer "In5.Cu")
		(net "P5E_PEX0_STN7_RX_DP<127>")
	)
	(segment
		(start 51.602386 -340.107778)
		(end 47.488856 -333.951834)
		(width 0.1651)
		(layer "In5.Cu")
		(net "P5E_PEX0_STN7_RX_DP<127>")
	)
	(segment
		(start 340.778084 -345.170506)
		(end 340.483444 -345.465146)
		(width 0.13462)
		(layer "F.Cu")
		(net "P5E_PEX2_STN5_TX_C_DP<93>")
	)
	(segment
		(start 340.778084 -344.539062)
		(end 340.778084 -345.170506)
		(width 0.13462)
		(layer "F.Cu")
		(net "P5E_PEX2_STN5_TX_C_DP<93>")
	)
	(segment
		(start 340.458044 -344.219022)
		(end 340.778084 -344.539062)
		(width 0.13462)
		(layer "F.Cu")
		(net "P5E_PEX2_STN5_TX_C_DP<93>")
	)
	(segment
		(start 342.053164 -366.045496)
		(end 342.094566 -365.945928)
		(width 0.1651)
		(layer "In7.Cu")
		(net "P5E_PEX2_STN5_TX_C_DP<93>")
	)
	(segment
		(start 341.615776 -364.989364)
		(end 341.657178 -364.889796)
		(width 0.1651)
		(layer "In7.Cu")
		(net "P5E_PEX2_STN5_TX_C_DP<93>")
	)
	(segment
		(start 342.094566 -365.945928)
		(end 341.905082 -365.488474)
		(width 0.1651)
		(layer "In7.Cu")
		(net "P5E_PEX2_STN5_TX_C_DP<93>")
	)
	(segment
		(start 343.334086 -379.612398)
		(end 343.334086 -368.938556)
		(width 0.1651)
		(layer "In7.Cu")
		(net "P5E_PEX2_STN5_TX_C_DP<93>")
	)
	(segment
		(start 342.490044 -379.772164)
		(end 342.617044 -379.899164)
		(width 0.1651)
		(layer "In7.Cu")
		(net "P5E_PEX2_STN5_TX_C_DP<93>")
	)
	(segment
		(start 340.774274 -345.755976)
		(end 340.483444 -345.465146)
		(width 0.1651)
		(layer "In7.Cu")
		(net "P5E_PEX2_STN5_TX_C_DP<93>")
	)
	(segment
		(start 343.04732 -379.899164)
		(end 343.334086 -379.612398)
		(width 0.1651)
		(layer "In7.Cu")
		(net "P5E_PEX2_STN5_TX_C_DP<93>")
	)
	(segment
		(start 343.334086 -368.938556)
		(end 342.34247 -366.544606)
		(width 0.1651)
		(layer "In7.Cu")
		(net "P5E_PEX2_STN5_TX_C_DP<93>")
	)
	(segment
		(start 342.617044 -379.899164)
		(end 343.04732 -379.899164)
		(width 0.1651)
		(layer "In7.Cu")
		(net "P5E_PEX2_STN5_TX_C_DP<93>")
	)
	(segment
		(start 340.774274 -346.209874)
		(end 340.774274 -345.755976)
		(width 0.1651)
		(layer "In7.Cu")
		(net "P5E_PEX2_STN5_TX_C_DP<93>")
	)
	(segment
		(start 342.490044 -379.390148)
		(end 342.490044 -379.772164)
		(width 0.1651)
		(layer "In7.Cu")
		(net "P5E_PEX2_STN5_TX_C_DP<93>")
	)
	(segment
		(start 339.219794 -347.764354)
		(end 340.774274 -346.209874)
		(width 0.1651)
		(layer "In7.Cu")
		(net "P5E_PEX2_STN5_TX_C_DP<93>")
	)
	(segment
		(start 341.657178 -364.889796)
		(end 339.219794 -359.00487)
		(width 0.1651)
		(layer "In7.Cu")
		(net "P5E_PEX2_STN5_TX_C_DP<93>")
	)
	(segment
		(start 339.219794 -359.00487)
		(end 339.219794 -347.764354)
		(width 0.1651)
		(layer "In7.Cu")
		(net "P5E_PEX2_STN5_TX_C_DP<93>")
	)
	(segment
		(start 341.905082 -365.488474)
		(end 341.805514 -365.447326)
		(width 0.1651)
		(layer "In7.Cu")
		(net "P5E_PEX2_STN5_TX_C_DP<93>")
	)
	(segment
		(start 342.243156 -366.503204)
		(end 342.053164 -366.045496)
		(width 0.1651)
		(layer "In7.Cu")
		(net "P5E_PEX2_STN5_TX_C_DP<93>")
	)
	(segment
		(start 342.34247 -366.544606)
		(end 342.243156 -366.503204)
		(width 0.1651)
		(layer "In7.Cu")
		(net "P5E_PEX2_STN5_TX_C_DP<93>")
	)
	(segment
		(start 341.805514 -365.447326)
		(end 341.615776 -364.989364)
		(width 0.1651)
		(layer "In7.Cu")
		(net "P5E_PEX2_STN5_TX_C_DP<93>")
	)
	(segment
		(start 418.669978 -32.13608)
		(end 418.359082 -31.825184)
		(width 0.13462)
		(layer "F.Cu")
		(net "P5E_PEX3_STN2_TX_DN<38>")
	)
	(segment
		(start 419.31971 -32.13608)
		(end 418.669978 -32.13608)
		(width 0.13462)
		(layer "F.Cu")
		(net "P5E_PEX3_STN2_TX_DN<38>")
	)
	(segment
		(start 419.605206 -31.850584)
		(end 419.31971 -32.13608)
		(width 0.13462)
		(layer "F.Cu")
		(net "P5E_PEX3_STN2_TX_DN<38>")
	)
	(segment
		(start 400.965924 -271.427448)
		(end 400.920204 -271.473168)
		(width 0.1143)
		(layer "In11.Cu")
		(net "P5E_PEX3_STN2_TX_DN<38>")
	)
	(segment
		(start 437.006238 -62.36716)
		(end 436.090568 -64.219836)
		(width 0.1651)
		(layer "In11.Cu")
		(net "P5E_PEX3_STN2_TX_DN<38>")
	)
	(segment
		(start 425.661836 -34.539936)
		(end 429.811942 -41.298876)
		(width 0.1651)
		(layer "In11.Cu")
		(net "P5E_PEX3_STN2_TX_DN<38>")
	)
	(segment
		(start 410.601414 -107.679744)
		(end 409.081478 -115.457732)
		(width 0.1651)
		(layer "In11.Cu")
		(net "P5E_PEX3_STN2_TX_DN<38>")
	)
	(segment
		(start 401.299934 -280.015188)
		(end 401.299934 -279.749504)
		(width 0.1143)
		(layer "In11.Cu")
		(net "P5E_PEX3_STN2_TX_DN<38>")
	)
	(segment
		(start 400.920204 -271.473168)
		(end 400.920204 -280.025856)
		(width 0.1143)
		(layer "In11.Cu")
		(net "P5E_PEX3_STN2_TX_DN<38>")
	)
	(segment
		(start 400.920204 -280.025856)
		(end 401.023836 -280.129488)
		(width 0.1143)
		(layer "In11.Cu")
		(net "P5E_PEX3_STN2_TX_DN<38>")
	)
	(segment
		(start 400.965924 -271.399)
		(end 400.965924 -271.427448)
		(width 0.1143)
		(layer "In11.Cu")
		(net "P5E_PEX3_STN2_TX_DN<38>")
	)
	(segment
		(start 436.090568 -64.219836)
		(end 413.948626 -93.193108)
		(width 0.1651)
		(layer "In11.Cu")
		(net "P5E_PEX3_STN2_TX_DN<38>")
	)
	(segment
		(start 437.543702 -58.49747)
		(end 437.543702 -60.348876)
		(width 0.1651)
		(layer "In11.Cu")
		(net "P5E_PEX3_STN2_TX_DN<38>")
	)
	(segment
		(start 408.391106 -121.058686)
		(end 400.965924 -263.18337)
		(width 0.1651)
		(layer "In11.Cu")
		(net "P5E_PEX3_STN2_TX_DN<38>")
	)
	(segment
		(start 409.081478 -115.457732)
		(end 408.391106 -121.058686)
		(width 0.1651)
		(layer "In11.Cu")
		(net "P5E_PEX3_STN2_TX_DN<38>")
	)
	(segment
		(start 429.811942 -41.298876)
		(end 436.513478 -48.575468)
		(width 0.1651)
		(layer "In11.Cu")
		(net "P5E_PEX3_STN2_TX_DN<38>")
	)
	(segment
		(start 419.896036 -32.141414)
		(end 422.064688 -32.141414)
		(width 0.1651)
		(layer "In11.Cu")
		(net "P5E_PEX3_STN2_TX_DN<38>")
	)
	(segment
		(start 423.850562 -32.78378)
		(end 425.661836 -34.539936)
		(width 0.1651)
		(layer "In11.Cu")
		(net "P5E_PEX3_STN2_TX_DN<38>")
	)
	(segment
		(start 401.185634 -280.129488)
		(end 401.299934 -280.015188)
		(width 0.1143)
		(layer "In11.Cu")
		(net "P5E_PEX3_STN2_TX_DN<38>")
	)
	(segment
		(start 436.513478 -48.575468)
		(end 437.543702 -58.49747)
		(width 0.1651)
		(layer "In11.Cu")
		(net "P5E_PEX3_STN2_TX_DN<38>")
	)
	(segment
		(start 400.965924 -263.18337)
		(end 400.965924 -271.399)
		(width 0.1651)
		(layer "In11.Cu")
		(net "P5E_PEX3_STN2_TX_DN<38>")
	)
	(segment
		(start 422.064688 -32.141414)
		(end 423.850562 -32.78378)
		(width 0.1651)
		(layer "In11.Cu")
		(net "P5E_PEX3_STN2_TX_DN<38>")
	)
	(segment
		(start 401.023836 -280.129488)
		(end 401.185634 -280.129488)
		(width 0.1143)
		(layer "In11.Cu")
		(net "P5E_PEX3_STN2_TX_DN<38>")
	)
	(segment
		(start 419.605206 -31.850584)
		(end 419.896036 -32.141414)
		(width 0.1651)
		(layer "In11.Cu")
		(net "P5E_PEX3_STN2_TX_DN<38>")
	)
	(segment
		(start 437.543702 -60.348876)
		(end 437.006238 -62.36716)
		(width 0.1651)
		(layer "In11.Cu")
		(net "P5E_PEX3_STN2_TX_DN<38>")
	)
	(segment
		(start 413.948626 -93.193108)
		(end 410.601414 -107.679744)
		(width 0.1651)
		(layer "In11.Cu")
		(net "P5E_PEX3_STN2_TX_DN<38>")
	)
	(segment
		(start 41.599866 -316.534292)
		(end 41.599866 -316.799722)
		(width 0.1143)
		(layer "In5.Cu")
		(net "P5E_PEX0_STN7_RX_DN<126>")
	)
	(segment
		(start 42.404284 -369.225576)
		(end 48.572166 -359.994962)
		(width 0.1651)
		(layer "In5.Cu")
		(net "P5E_PEX0_STN7_RX_DN<126>")
	)
	(segment
		(start 41.724072 -382.9812)
		(end 42.258742 -382.44653)
		(width 0.1651)
		(layer "In5.Cu")
		(net "P5E_PEX0_STN7_RX_DN<126>")
	)
	(segment
		(start 41.334436 -316.419992)
		(end 41.485566 -316.419992)
		(width 0.1143)
		(layer "In5.Cu")
		(net "P5E_PEX0_STN7_RX_DN<126>")
	)
	(segment
		(start 41.485566 -316.419992)
		(end 41.599866 -316.534292)
		(width 0.1143)
		(layer "In5.Cu")
		(net "P5E_PEX0_STN7_RX_DN<126>")
	)
	(segment
		(start 41.2369 -382.9812)
		(end 41.724072 -382.9812)
		(width 0.1651)
		(layer "In5.Cu")
		(net "P5E_PEX0_STN7_RX_DN<126>")
	)
	(segment
		(start 42.258742 -369.705128)
		(end 42.404284 -369.225576)
		(width 0.1651)
		(layer "In5.Cu")
		(net "P5E_PEX0_STN7_RX_DN<126>")
	)
	(segment
		(start 41.265856 -319.966848)
		(end 41.220136 -319.921128)
		(width 0.1143)
		(layer "In5.Cu")
		(net "P5E_PEX0_STN7_RX_DN<126>")
	)
	(segment
		(start 41.265856 -325.097394)
		(end 41.265856 -319.995296)
		(width 0.1651)
		(layer "In5.Cu")
		(net "P5E_PEX0_STN7_RX_DN<126>")
	)
	(segment
		(start 41.220136 -319.921128)
		(end 41.220136 -316.534292)
		(width 0.1143)
		(layer "In5.Cu")
		(net "P5E_PEX0_STN7_RX_DN<126>")
	)
	(segment
		(start 41.1099 -383.1082)
		(end 41.2369 -382.9812)
		(width 0.1651)
		(layer "In5.Cu")
		(net "P5E_PEX0_STN7_RX_DN<126>")
	)
	(segment
		(start 49.009554 -340.914736)
		(end 44.567348 -331.518768)
		(width 0.1651)
		(layer "In5.Cu")
		(net "P5E_PEX0_STN7_RX_DN<126>")
	)
	(segment
		(start 41.1099 -383.490216)
		(end 41.1099 -383.1082)
		(width 0.1651)
		(layer "In5.Cu")
		(net "P5E_PEX0_STN7_RX_DN<126>")
	)
	(segment
		(start 41.265856 -319.995296)
		(end 41.265856 -319.966848)
		(width 0.1143)
		(layer "In5.Cu")
		(net "P5E_PEX0_STN7_RX_DN<126>")
	)
	(segment
		(start 49.440338 -357.896668)
		(end 49.440338 -342.33612)
		(width 0.1651)
		(layer "In5.Cu")
		(net "P5E_PEX0_STN7_RX_DN<126>")
	)
	(segment
		(start 49.440338 -342.33612)
		(end 49.009554 -340.914736)
		(width 0.1651)
		(layer "In5.Cu")
		(net "P5E_PEX0_STN7_RX_DN<126>")
	)
	(segment
		(start 48.572166 -359.994962)
		(end 49.440338 -357.896668)
		(width 0.1651)
		(layer "In5.Cu")
		(net "P5E_PEX0_STN7_RX_DN<126>")
	)
	(segment
		(start 44.567348 -331.518768)
		(end 41.652952 -326.372982)
		(width 0.1651)
		(layer "In5.Cu")
		(net "P5E_PEX0_STN7_RX_DN<126>")
	)
	(segment
		(start 41.652952 -326.372982)
		(end 41.265856 -325.097394)
		(width 0.1651)
		(layer "In5.Cu")
		(net "P5E_PEX0_STN7_RX_DN<126>")
	)
	(segment
		(start 42.258742 -382.44653)
		(end 42.258742 -369.705128)
		(width 0.1651)
		(layer "In5.Cu")
		(net "P5E_PEX0_STN7_RX_DN<126>")
	)
	(segment
		(start 41.220136 -316.534292)
		(end 41.334436 -316.419992)
		(width 0.1143)
		(layer "In5.Cu")
		(net "P5E_PEX0_STN7_RX_DN<126>")
	)
	(segment
		(start 92.756482 -342.734138)
		(end 92.461842 -342.439498)
		(width 0.13462)
		(layer "F.Cu")
		(net "P5E_PEX0_STN6_TX_DP<97>")
	)
	(segment
		(start 92.436442 -343.685622)
		(end 92.756482 -343.365582)
		(width 0.13462)
		(layer "F.Cu")
		(net "P5E_PEX0_STN6_TX_DP<97>")
	)
	(segment
		(start 92.756482 -343.365582)
		(end 92.756482 -342.734138)
		(width 0.13462)
		(layer "F.Cu")
		(net "P5E_PEX0_STN6_TX_DP<97>")
	)
	(segment
		(start 56.503824 -321.900804)
		(end 56.184038 -321.128644)
		(width 0.1651)
		(layer "In13.Cu")
		(net "P5E_PEX0_STN6_TX_DP<97>")
	)
	(segment
		(start 56.184038 -320.191384)
		(end 56.229758 -320.145664)
		(width 0.1143)
		(layer "In13.Cu")
		(net "P5E_PEX0_STN6_TX_DP<97>")
	)
	(segment
		(start 56.711088 -311.479692)
		(end 56.799988 -311.390792)
		(width 0.1143)
		(layer "In13.Cu")
		(net "P5E_PEX0_STN6_TX_DP<97>")
	)
	(segment
		(start 56.184038 -320.213482)
		(end 56.184038 -320.191384)
		(width 0.1143)
		(layer "In13.Cu")
		(net "P5E_PEX0_STN6_TX_DP<97>")
	)
	(segment
		(start 56.229758 -311.718198)
		(end 56.468264 -311.479692)
		(width 0.1143)
		(layer "In13.Cu")
		(net "P5E_PEX0_STN6_TX_DP<97>")
	)
	(segment
		(start 92.461842 -342.439498)
		(end 92.752672 -342.148668)
		(width 0.1651)
		(layer "In13.Cu")
		(net "P5E_PEX0_STN6_TX_DP<97>")
	)
	(segment
		(start 57.00395 -322.40093)
		(end 56.503824 -321.900804)
		(width 0.1651)
		(layer "In13.Cu")
		(net "P5E_PEX0_STN6_TX_DP<97>")
	)
	(segment
		(start 92.752672 -342.148668)
		(end 92.752672 -341.309706)
		(width 0.1651)
		(layer "In13.Cu")
		(net "P5E_PEX0_STN6_TX_DP<97>")
	)
	(segment
		(start 90.73642 -339.293454)
		(end 66.464688 -326.319642)
		(width 0.1651)
		(layer "In13.Cu")
		(net "P5E_PEX0_STN6_TX_DP<97>")
	)
	(segment
		(start 56.799988 -311.390792)
		(end 56.799988 -311.099962)
		(width 0.1143)
		(layer "In13.Cu")
		(net "P5E_PEX0_STN6_TX_DP<97>")
	)
	(segment
		(start 56.468264 -311.479692)
		(end 56.711088 -311.479692)
		(width 0.1143)
		(layer "In13.Cu")
		(net "P5E_PEX0_STN6_TX_DP<97>")
	)
	(segment
		(start 56.229758 -320.145664)
		(end 56.229758 -311.718198)
		(width 0.1143)
		(layer "In13.Cu")
		(net "P5E_PEX0_STN6_TX_DP<97>")
	)
	(segment
		(start 66.464688 -326.319642)
		(end 57.00395 -322.40093)
		(width 0.1651)
		(layer "In13.Cu")
		(net "P5E_PEX0_STN6_TX_DP<97>")
	)
	(segment
		(start 92.752672 -341.309706)
		(end 90.73642 -339.293454)
		(width 0.1651)
		(layer "In13.Cu")
		(net "P5E_PEX0_STN6_TX_DP<97>")
	)
	(segment
		(start 56.184038 -321.128644)
		(end 56.184038 -320.213482)
		(width 0.1651)
		(layer "In13.Cu")
		(net "P5E_PEX0_STN6_TX_DP<97>")
	)
	(segment
		(start 402.846032 -355.657658)
		(end 402.846032 -355.02723)
		(width 0.13462)
		(layer "F.Cu")
		(net "P5E_PEX3_STN5_TX_DN<95>")
	)
	(segment
		(start 402.846032 -355.02723)
		(end 403.14118 -354.732082)
		(width 0.13462)
		(layer "F.Cu")
		(net "P5E_PEX3_STN5_TX_DN<95>")
	)
	(segment
		(start 403.16658 -355.978206)
		(end 402.846032 -355.657658)
		(width 0.13462)
		(layer "F.Cu")
		(net "P5E_PEX3_STN5_TX_DN<95>")
	)
	(segment
		(start 403.82063 -352.871024)
		(end 404.08352 -352.434398)
		(width 0.1651)
		(layer "In13.Cu")
		(net "P5E_PEX3_STN5_TX_DN<95>")
	)
	(segment
		(start 402.85035 -353.841304)
		(end 403.82063 -352.871024)
		(width 0.1651)
		(layer "In13.Cu")
		(net "P5E_PEX3_STN5_TX_DN<95>")
	)
	(segment
		(start 421.249856 -313.684412)
		(end 421.249856 -313.949842)
		(width 0.1143)
		(layer "In13.Cu")
		(net "P5E_PEX3_STN5_TX_DN<95>")
	)
	(segment
		(start 420.915846 -320.017648)
		(end 420.870126 -319.971928)
		(width 0.1143)
		(layer "In13.Cu")
		(net "P5E_PEX3_STN5_TX_DN<95>")
	)
	(segment
		(start 404.08352 -352.434398)
		(end 404.08352 -352.434652)
		(width 0.1651)
		(layer "In13.Cu")
		(net "P5E_PEX3_STN5_TX_DN<95>")
	)
	(segment
		(start 408.504644 -341.389208)
		(end 418.25037 -328.163428)
		(width 0.1651)
		(layer "In13.Cu")
		(net "P5E_PEX3_STN5_TX_DN<95>")
	)
	(segment
		(start 420.870126 -313.673744)
		(end 420.973758 -313.570112)
		(width 0.1143)
		(layer "In13.Cu")
		(net "P5E_PEX3_STN5_TX_DN<95>")
	)
	(segment
		(start 420.915846 -320.046096)
		(end 420.915846 -320.017648)
		(width 0.1143)
		(layer "In13.Cu")
		(net "P5E_PEX3_STN5_TX_DN<95>")
	)
	(segment
		(start 421.135556 -313.570112)
		(end 421.249856 -313.684412)
		(width 0.1143)
		(layer "In13.Cu")
		(net "P5E_PEX3_STN5_TX_DN<95>")
	)
	(segment
		(start 420.973758 -313.570112)
		(end 421.135556 -313.570112)
		(width 0.1143)
		(layer "In13.Cu")
		(net "P5E_PEX3_STN5_TX_DN<95>")
	)
	(segment
		(start 404.340568 -352.007424)
		(end 408.504644 -341.389208)
		(width 0.1651)
		(layer "In13.Cu")
		(net "P5E_PEX3_STN5_TX_DN<95>")
	)
	(segment
		(start 418.25037 -328.163428)
		(end 420.915846 -323.441822)
		(width 0.1651)
		(layer "In13.Cu")
		(net "P5E_PEX3_STN5_TX_DN<95>")
	)
	(segment
		(start 403.14118 -354.732082)
		(end 402.85035 -354.441252)
		(width 0.1651)
		(layer "In13.Cu")
		(net "P5E_PEX3_STN5_TX_DN<95>")
	)
	(segment
		(start 420.915846 -323.441822)
		(end 420.915846 -320.046096)
		(width 0.1651)
		(layer "In13.Cu")
		(net "P5E_PEX3_STN5_TX_DN<95>")
	)
	(segment
		(start 402.85035 -354.441252)
		(end 402.85035 -353.841304)
		(width 0.1651)
		(layer "In13.Cu")
		(net "P5E_PEX3_STN5_TX_DN<95>")
	)
	(segment
		(start 420.870126 -319.971928)
		(end 420.870126 -313.673744)
		(width 0.1143)
		(layer "In13.Cu")
		(net "P5E_PEX3_STN5_TX_DN<95>")
	)
	(segment
		(start 404.08352 -352.434652)
		(end 404.340568 -352.007424)
		(width 0.1651)
		(layer "In13.Cu")
		(net "P5E_PEX3_STN5_TX_DN<95>")
	)
	(segment
		(start 40.649906 -318.015366)
		(end 40.649906 -317.749936)
		(width 0.1143)
		(layer "In5.Cu")
		(net "P5E_PEX0_STN7_RX_DP<125>")
	)
	(segment
		(start 42.413682 -331.5081)
		(end 42.413428 -331.5081)
		(width 0.1651)
		(layer "In5.Cu")
		(net "P5E_PEX0_STN7_RX_DP<125>")
	)
	(segment
		(start 40.305482 -318.129666)
		(end 40.535606 -318.129666)
		(width 0.1143)
		(layer "In5.Cu")
		(net "P5E_PEX0_STN7_RX_DP<125>")
	)
	(segment
		(start 40.535606 -318.129666)
		(end 40.649906 -318.015366)
		(width 0.1143)
		(layer "In5.Cu")
		(net "P5E_PEX0_STN7_RX_DP<125>")
	)
	(segment
		(start 40.732456 -366.760506)
		(end 45.001434 -360.371644)
		(width 0.1651)
		(layer "In5.Cu")
		(net "P5E_PEX0_STN7_RX_DP<125>")
	)
	(segment
		(start 46.049438 -342.397588)
		(end 45.24121 -338.334604)
		(width 0.1651)
		(layer "In5.Cu")
		(net "P5E_PEX0_STN7_RX_DP<125>")
	)
	(segment
		(start 38.910006 -383.67208)
		(end 39.037006 -383.79908)
		(width 0.1651)
		(layer "In5.Cu")
		(net "P5E_PEX0_STN7_RX_DP<125>")
	)
	(segment
		(start 38.910006 -383.290064)
		(end 38.910006 -383.67208)
		(width 0.1651)
		(layer "In5.Cu")
		(net "P5E_PEX0_STN7_RX_DP<125>")
	)
	(segment
		(start 40.033956 -319.995296)
		(end 40.033956 -319.966848)
		(width 0.1143)
		(layer "In5.Cu")
		(net "P5E_PEX0_STN7_RX_DP<125>")
	)
	(segment
		(start 40.03421 -325.763128)
		(end 40.033956 -325.763128)
		(width 0.1651)
		(layer "In5.Cu")
		(net "P5E_PEX0_STN7_RX_DP<125>")
	)
	(segment
		(start 45.001434 -360.371644)
		(end 46.049438 -357.840026)
		(width 0.1651)
		(layer "In5.Cu")
		(net "P5E_PEX0_STN7_RX_DP<125>")
	)
	(segment
		(start 39.419022 -383.79908)
		(end 39.777162 -383.44094)
		(width 0.1651)
		(layer "In5.Cu")
		(net "P5E_PEX0_STN7_RX_DP<125>")
	)
	(segment
		(start 46.049438 -357.840026)
		(end 46.049438 -342.397588)
		(width 0.1651)
		(layer "In5.Cu")
		(net "P5E_PEX0_STN7_RX_DP<125>")
	)
	(segment
		(start 45.24121 -338.334604)
		(end 43.696128 -334.60436)
		(width 0.1651)
		(layer "In5.Cu")
		(net "P5E_PEX0_STN7_RX_DP<125>")
	)
	(segment
		(start 39.037006 -383.79908)
		(end 39.419022 -383.79908)
		(width 0.1651)
		(layer "In5.Cu")
		(net "P5E_PEX0_STN7_RX_DP<125>")
	)
	(segment
		(start 40.079676 -318.355472)
		(end 40.305482 -318.129666)
		(width 0.1143)
		(layer "In5.Cu")
		(net "P5E_PEX0_STN7_RX_DP<125>")
	)
	(segment
		(start 39.777162 -383.44094)
		(end 39.777162 -369.910106)
		(width 0.1651)
		(layer "In5.Cu")
		(net "P5E_PEX0_STN7_RX_DP<125>")
	)
	(segment
		(start 40.033956 -325.763128)
		(end 40.033956 -319.995296)
		(width 0.1651)
		(layer "In5.Cu")
		(net "P5E_PEX0_STN7_RX_DP<125>")
	)
	(segment
		(start 39.777162 -369.910106)
		(end 40.732456 -366.760506)
		(width 0.1651)
		(layer "In5.Cu")
		(net "P5E_PEX0_STN7_RX_DP<125>")
	)
	(segment
		(start 42.413428 -331.5081)
		(end 40.03421 -325.763128)
		(width 0.1651)
		(layer "In5.Cu")
		(net "P5E_PEX0_STN7_RX_DP<125>")
	)
	(segment
		(start 40.079676 -319.921128)
		(end 40.079676 -318.355472)
		(width 0.1143)
		(layer "In5.Cu")
		(net "P5E_PEX0_STN7_RX_DP<125>")
	)
	(segment
		(start 43.546522 -334.542384)
		(end 43.357038 -334.084676)
		(width 0.1651)
		(layer "In5.Cu")
		(net "P5E_PEX0_STN7_RX_DP<125>")
	)
	(segment
		(start 43.696128 -334.60436)
		(end 43.546522 -334.542384)
		(width 0.1651)
		(layer "In5.Cu")
		(net "P5E_PEX0_STN7_RX_DP<125>")
	)
	(segment
		(start 43.357038 -334.084676)
		(end 43.419014 -333.935324)
		(width 0.1651)
		(layer "In5.Cu")
		(net "P5E_PEX0_STN7_RX_DP<125>")
	)
	(segment
		(start 43.419014 -333.935324)
		(end 42.413682 -331.5081)
		(width 0.1651)
		(layer "In5.Cu")
		(net "P5E_PEX0_STN7_RX_DP<125>")
	)
	(segment
		(start 40.033956 -319.966848)
		(end 40.079676 -319.921128)
		(width 0.1143)
		(layer "In5.Cu")
		(net "P5E_PEX0_STN7_RX_DP<125>")
	)
	(segment
		(start 86.538562 -355.026722)
		(end 86.243922 -354.732082)
		(width 0.13462)
		(layer "F.Cu")
		(net "P5E_PEX0_STN6_TX_DP<99>")
	)
	(segment
		(start 86.538562 -355.658166)
		(end 86.538562 -355.026722)
		(width 0.13462)
		(layer "F.Cu")
		(net "P5E_PEX0_STN6_TX_DP<99>")
	)
	(segment
		(start 86.218522 -355.978206)
		(end 86.538562 -355.658166)
		(width 0.13462)
		(layer "F.Cu")
		(net "P5E_PEX0_STN6_TX_DP<99>")
	)
	(segment
		(start 88.089232 -341.462614)
		(end 87.023702 -339.685122)
		(width 0.1651)
		(layer "In13.Cu")
		(net "P5E_PEX0_STN6_TX_DP<99>")
	)
	(segment
		(start 54.887368 -323.078348)
		(end 54.283864 -321.620642)
		(width 0.1651)
		(layer "In13.Cu")
		(net "P5E_PEX0_STN6_TX_DP<99>")
	)
	(segment
		(start 54.283864 -321.620642)
		(end 54.283864 -320.210688)
		(width 0.1651)
		(layer "In13.Cu")
		(net "P5E_PEX0_STN6_TX_DP<99>")
	)
	(segment
		(start 54.329584 -320.14287)
		(end 54.329584 -311.718452)
		(width 0.1143)
		(layer "In13.Cu")
		(net "P5E_PEX0_STN6_TX_DP<99>")
	)
	(segment
		(start 55.76443 -323.95541)
		(end 54.887368 -323.078348)
		(width 0.1651)
		(layer "In13.Cu")
		(net "P5E_PEX0_STN6_TX_DP<99>")
	)
	(segment
		(start 54.283864 -320.210688)
		(end 54.283864 -320.18859)
		(width 0.1143)
		(layer "In13.Cu")
		(net "P5E_PEX0_STN6_TX_DP<99>")
	)
	(segment
		(start 87.023702 -339.685122)
		(end 63.897256 -327.324212)
		(width 0.1651)
		(layer "In13.Cu")
		(net "P5E_PEX0_STN6_TX_DP<99>")
	)
	(segment
		(start 54.810914 -311.479692)
		(end 54.899814 -311.390792)
		(width 0.1143)
		(layer "In13.Cu")
		(net "P5E_PEX0_STN6_TX_DP<99>")
	)
	(segment
		(start 54.329584 -311.718452)
		(end 54.568344 -311.479692)
		(width 0.1143)
		(layer "In13.Cu")
		(net "P5E_PEX0_STN6_TX_DP<99>")
	)
	(segment
		(start 88.089232 -352.081084)
		(end 88.089232 -341.462614)
		(width 0.1651)
		(layer "In13.Cu")
		(net "P5E_PEX0_STN6_TX_DP<99>")
	)
	(segment
		(start 86.534752 -353.635564)
		(end 88.089232 -352.081084)
		(width 0.1651)
		(layer "In13.Cu")
		(net "P5E_PEX0_STN6_TX_DP<99>")
	)
	(segment
		(start 54.899814 -311.390792)
		(end 54.899814 -311.099962)
		(width 0.1143)
		(layer "In13.Cu")
		(net "P5E_PEX0_STN6_TX_DP<99>")
	)
	(segment
		(start 54.283864 -320.18859)
		(end 54.329584 -320.14287)
		(width 0.1143)
		(layer "In13.Cu")
		(net "P5E_PEX0_STN6_TX_DP<99>")
	)
	(segment
		(start 86.534752 -354.441252)
		(end 86.534752 -353.635564)
		(width 0.1651)
		(layer "In13.Cu")
		(net "P5E_PEX0_STN6_TX_DP<99>")
	)
	(segment
		(start 63.897256 -327.324212)
		(end 55.76443 -323.95541)
		(width 0.1651)
		(layer "In13.Cu")
		(net "P5E_PEX0_STN6_TX_DP<99>")
	)
	(segment
		(start 54.568344 -311.479692)
		(end 54.810914 -311.479692)
		(width 0.1143)
		(layer "In13.Cu")
		(net "P5E_PEX0_STN6_TX_DP<99>")
	)
	(segment
		(start 86.243922 -354.732082)
		(end 86.534752 -354.441252)
		(width 0.1651)
		(layer "In13.Cu")
		(net "P5E_PEX0_STN6_TX_DP<99>")
	)
	(segment
		(start 67.884802 -350.685354)
		(end 67.564762 -350.365314)
		(width 0.13462)
		(layer "F.Cu")
		(net "P5E_PEX0_STN5_TX_C_DP<83>")
	)
	(segment
		(start 67.884802 -351.316798)
		(end 67.884802 -350.685354)
		(width 0.13462)
		(layer "F.Cu")
		(net "P5E_PEX0_STN5_TX_C_DP<83>")
	)
	(segment
		(start 67.590162 -351.611438)
		(end 67.884802 -351.316798)
		(width 0.13462)
		(layer "F.Cu")
		(net "P5E_PEX0_STN5_TX_C_DP<83>")
	)
	(segment
		(start 66.326512 -358.33939)
		(end 66.465704 -359.039414)
		(width 0.1651)
		(layer "In7.Cu")
		(net "P5E_PEX0_STN5_TX_C_DP<83>")
	)
	(segment
		(start 66.326512 -353.990402)
		(end 66.326512 -358.33939)
		(width 0.1651)
		(layer "In7.Cu")
		(net "P5E_PEX0_STN5_TX_C_DP<83>")
	)
	(segment
		(start 67.880992 -352.435922)
		(end 66.326512 -353.990402)
		(width 0.1651)
		(layer "In7.Cu")
		(net "P5E_PEX0_STN5_TX_C_DP<83>")
	)
	(segment
		(start 67.766692 -387.596126)
		(end 69.76237 -389.591804)
		(width 0.1651)
		(layer "In7.Cu")
		(net "P5E_PEX0_STN5_TX_C_DP<83>")
	)
	(segment
		(start 67.590162 -351.611438)
		(end 67.880992 -351.902268)
		(width 0.1651)
		(layer "In7.Cu")
		(net "P5E_PEX0_STN5_TX_C_DP<83>")
	)
	(segment
		(start 78.302612 -393.432792)
		(end 78.302612 -393.558522)
		(width 0.1651)
		(layer "In7.Cu")
		(net "P5E_PEX0_STN5_TX_C_DP<83>")
	)
	(segment
		(start 78.636876 -405.899112)
		(end 78.509876 -405.772112)
		(width 0.1651)
		(layer "In7.Cu")
		(net "P5E_PEX0_STN5_TX_C_DP<83>")
	)
	(segment
		(start 66.7258 -379.002036)
		(end 66.7258 -385.08305)
		(width 0.1651)
		(layer "In7.Cu")
		(net "P5E_PEX0_STN5_TX_C_DP<83>")
	)
	(segment
		(start 66.465704 -359.039414)
		(end 66.7258 -379.002036)
		(width 0.1651)
		(layer "In7.Cu")
		(net "P5E_PEX0_STN5_TX_C_DP<83>")
	)
	(segment
		(start 66.7258 -385.08305)
		(end 67.766692 -387.596126)
		(width 0.1651)
		(layer "In7.Cu")
		(net "P5E_PEX0_STN5_TX_C_DP<83>")
	)
	(segment
		(start 79.402432 -405.54783)
		(end 79.05115 -405.899112)
		(width 0.1651)
		(layer "In7.Cu")
		(net "P5E_PEX0_STN5_TX_C_DP<83>")
	)
	(segment
		(start 67.880992 -351.902268)
		(end 67.880992 -352.435922)
		(width 0.1651)
		(layer "In7.Cu")
		(net "P5E_PEX0_STN5_TX_C_DP<83>")
	)
	(segment
		(start 79.402432 -394.532612)
		(end 79.402432 -405.54783)
		(width 0.1651)
		(layer "In7.Cu")
		(net "P5E_PEX0_STN5_TX_C_DP<83>")
	)
	(segment
		(start 79.05115 -405.899112)
		(end 78.636876 -405.899112)
		(width 0.1651)
		(layer "In7.Cu")
		(net "P5E_PEX0_STN5_TX_C_DP<83>")
	)
	(segment
		(start 78.302612 -393.558522)
		(end 78.652878 -393.908788)
		(width 0.1651)
		(layer "In7.Cu")
		(net "P5E_PEX0_STN5_TX_C_DP<83>")
	)
	(segment
		(start 78.652878 -393.908788)
		(end 78.778608 -393.908788)
		(width 0.1651)
		(layer "In7.Cu")
		(net "P5E_PEX0_STN5_TX_C_DP<83>")
	)
	(segment
		(start 78.509876 -405.772112)
		(end 78.509876 -405.390096)
		(width 0.1651)
		(layer "In7.Cu")
		(net "P5E_PEX0_STN5_TX_C_DP<83>")
	)
	(segment
		(start 69.76237 -389.591804)
		(end 77.783944 -392.914124)
		(width 0.1651)
		(layer "In7.Cu")
		(net "P5E_PEX0_STN5_TX_C_DP<83>")
	)
	(segment
		(start 78.778608 -393.908788)
		(end 79.402432 -394.532612)
		(width 0.1651)
		(layer "In7.Cu")
		(net "P5E_PEX0_STN5_TX_C_DP<83>")
	)
	(segment
		(start 77.783944 -392.914124)
		(end 78.302612 -393.432792)
		(width 0.1651)
		(layer "In7.Cu")
		(net "P5E_PEX0_STN5_TX_C_DP<83>")
	)
	(segment
		(start 127.975868 -357.46309)
		(end 127.975868 -356.831646)
		(width 0.13462)
		(layer "F.Cu")
		(net "P5E_PEX1_STN5_TX_C_DN<80>")
	)
	(segment
		(start 128.270508 -357.75773)
		(end 127.975868 -357.46309)
		(width 0.13462)
		(layer "F.Cu")
		(net "P5E_PEX1_STN5_TX_C_DN<80>")
	)
	(segment
		(start 127.975868 -356.831646)
		(end 128.295908 -356.511606)
		(width 0.13462)
		(layer "F.Cu")
		(net "P5E_PEX1_STN5_TX_C_DN<80>")
	)
	(segment
		(start 122.665998 -391.154666)
		(end 117.628162 -394.671296)
		(width 0.1651)
		(layer "In7.Cu")
		(net "P5E_PEX1_STN5_TX_C_DN<80>")
	)
	(segment
		(start 127.29972 -389.225282)
		(end 127.29972 -389.225028)
		(width 0.1651)
		(layer "In7.Cu")
		(net "P5E_PEX1_STN5_TX_C_DN<80>")
	)
	(segment
		(start 116.96954 -396.27048)
		(end 116.96954 -404.497286)
		(width 0.1651)
		(layer "In7.Cu")
		(net "P5E_PEX1_STN5_TX_C_DN<80>")
	)
	(segment
		(start 128.229614 -359.542842)
		(end 134.751064 -369.302284)
		(width 0.1651)
		(layer "In7.Cu")
		(net "P5E_PEX1_STN5_TX_C_DN<80>")
	)
	(segment
		(start 134.642352 -385.421378)
		(end 134.545832 -385.571492)
		(width 0.1651)
		(layer "In7.Cu")
		(net "P5E_PEX1_STN5_TX_C_DN<80>")
	)
	(segment
		(start 134.545832 -385.571492)
		(end 131.933696 -387.29539)
		(width 0.1651)
		(layer "In7.Cu")
		(net "P5E_PEX1_STN5_TX_C_DN<80>")
	)
	(segment
		(start 134.751064 -369.302284)
		(end 134.751064 -385.252214)
		(width 0.1651)
		(layer "In7.Cu")
		(net "P5E_PEX1_STN5_TX_C_DN<80>")
	)
	(segment
		(start 134.751064 -385.252214)
		(end 134.642352 -385.421378)
		(width 0.1651)
		(layer "In7.Cu")
		(net "P5E_PEX1_STN5_TX_C_DN<80>")
	)
	(segment
		(start 127.979678 -358.719882)
		(end 128.229614 -359.542842)
		(width 0.1651)
		(layer "In7.Cu")
		(net "P5E_PEX1_STN5_TX_C_DN<80>")
	)
	(segment
		(start 127.979678 -358.04856)
		(end 127.979678 -358.719882)
		(width 0.1651)
		(layer "In7.Cu")
		(net "P5E_PEX1_STN5_TX_C_DN<80>")
	)
	(segment
		(start 127.29972 -389.225028)
		(end 122.665998 -391.154666)
		(width 0.1651)
		(layer "In7.Cu")
		(net "P5E_PEX1_STN5_TX_C_DN<80>")
	)
	(segment
		(start 116.386102 -405.080724)
		(end 116.03736 -405.080724)
		(width 0.1651)
		(layer "In7.Cu")
		(net "P5E_PEX1_STN5_TX_C_DN<80>")
	)
	(segment
		(start 117.628162 -394.671296)
		(end 116.96954 -396.27048)
		(width 0.1651)
		(layer "In7.Cu")
		(net "P5E_PEX1_STN5_TX_C_DN<80>")
	)
	(segment
		(start 128.270508 -357.75773)
		(end 127.979678 -358.04856)
		(width 0.1651)
		(layer "In7.Cu")
		(net "P5E_PEX1_STN5_TX_C_DN<80>")
	)
	(segment
		(start 116.03736 -405.080724)
		(end 115.910106 -405.207978)
		(width 0.1651)
		(layer "In7.Cu")
		(net "P5E_PEX1_STN5_TX_C_DN<80>")
	)
	(segment
		(start 116.96954 -404.497286)
		(end 116.386102 -405.080724)
		(width 0.1651)
		(layer "In7.Cu")
		(net "P5E_PEX1_STN5_TX_C_DN<80>")
	)
	(segment
		(start 115.910106 -405.207978)
		(end 115.910106 -405.589994)
		(width 0.1651)
		(layer "In7.Cu")
		(net "P5E_PEX1_STN5_TX_C_DN<80>")
	)
	(segment
		(start 131.933696 -387.29539)
		(end 127.29972 -389.225282)
		(width 0.1651)
		(layer "In7.Cu")
		(net "P5E_PEX1_STN5_TX_C_DN<80>")
	)
	(segment
		(start 418.682424 -28.8163)
		(end 418.359082 -29.139642)
		(width 0.13462)
		(layer "F.Cu")
		(net "P5E_PEX3_STN2_TX_DP<36>")
	)
	(segment
		(start 419.605206 -29.114242)
		(end 419.307264 -28.8163)
		(width 0.13462)
		(layer "F.Cu")
		(net "P5E_PEX3_STN2_TX_DP<36>")
	)
	(segment
		(start 419.307264 -28.8163)
		(end 418.682424 -28.8163)
		(width 0.13462)
		(layer "F.Cu")
		(net "P5E_PEX3_STN2_TX_DP<36>")
	)
	(segment
		(start 431.320956 -39.897558)
		(end 426.33265 -32.063182)
		(width 0.1651)
		(layer "In11.Cu")
		(net "P5E_PEX3_STN2_TX_DP<36>")
	)
	(segment
		(start 410.643324 -116.64442)
		(end 412.274258 -108.054394)
		(width 0.1651)
		(layer "In11.Cu")
		(net "P5E_PEX3_STN2_TX_DP<36>")
	)
	(segment
		(start 439.292238 -60.556902)
		(end 439.292238 -58.452766)
		(width 0.1651)
		(layer "In11.Cu")
		(net "P5E_PEX3_STN2_TX_DP<36>")
	)
	(segment
		(start 438.662572 -62.898274)
		(end 439.292238 -60.556902)
		(width 0.1651)
		(layer "In11.Cu")
		(net "P5E_PEX3_STN2_TX_DP<36>")
	)
	(segment
		(start 402.583904 -263.41705)
		(end 410.125418 -120.93321)
		(width 0.1651)
		(layer "In11.Cu")
		(net "P5E_PEX3_STN2_TX_DP<36>")
	)
	(segment
		(start 420.78275 -28.937712)
		(end 420.66845 -28.823412)
		(width 0.1651)
		(layer "In11.Cu")
		(net "P5E_PEX3_STN2_TX_DP<36>")
	)
	(segment
		(start 422.215564 -28.823412)
		(end 421.39235 -28.823412)
		(width 0.1651)
		(layer "In11.Cu")
		(net "P5E_PEX3_STN2_TX_DP<36>")
	)
	(segment
		(start 419.896036 -28.823412)
		(end 419.605206 -29.114242)
		(width 0.1651)
		(layer "In11.Cu")
		(net "P5E_PEX3_STN2_TX_DP<36>")
	)
	(segment
		(start 403.085554 -280.319988)
		(end 402.844762 -280.319988)
		(width 0.1143)
		(layer "In11.Cu")
		(net "P5E_PEX3_STN2_TX_DP<36>")
	)
	(segment
		(start 403.199854 -280.699718)
		(end 403.199854 -280.434288)
		(width 0.1143)
		(layer "In11.Cu")
		(net "P5E_PEX3_STN2_TX_DP<36>")
	)
	(segment
		(start 439.292238 -58.452766)
		(end 438.175908 -47.726854)
		(width 0.1651)
		(layer "In11.Cu")
		(net "P5E_PEX3_STN2_TX_DP<36>")
	)
	(segment
		(start 437.691784 -64.855598)
		(end 438.662572 -62.898274)
		(width 0.1651)
		(layer "In11.Cu")
		(net "P5E_PEX3_STN2_TX_DP<36>")
	)
	(segment
		(start 420.66845 -28.823412)
		(end 419.896036 -28.823412)
		(width 0.1651)
		(layer "In11.Cu")
		(net "P5E_PEX3_STN2_TX_DP<36>")
	)
	(segment
		(start 412.274258 -108.054394)
		(end 415.45637 -93.902784)
		(width 0.1651)
		(layer "In11.Cu")
		(net "P5E_PEX3_STN2_TX_DP<36>")
	)
	(segment
		(start 402.583904 -271.399)
		(end 402.583904 -263.41705)
		(width 0.1651)
		(layer "In11.Cu")
		(net "P5E_PEX3_STN2_TX_DP<36>")
	)
	(segment
		(start 410.125418 -120.93321)
		(end 410.643324 -116.64442)
		(width 0.1651)
		(layer "In11.Cu")
		(net "P5E_PEX3_STN2_TX_DP<36>")
	)
	(segment
		(start 423.715688 -29.445966)
		(end 422.215564 -28.823412)
		(width 0.1651)
		(layer "In11.Cu")
		(net "P5E_PEX3_STN2_TX_DP<36>")
	)
	(segment
		(start 415.45637 -93.902784)
		(end 437.691784 -64.855598)
		(width 0.1651)
		(layer "In11.Cu")
		(net "P5E_PEX3_STN2_TX_DP<36>")
	)
	(segment
		(start 426.33265 -32.063182)
		(end 423.715688 -29.445966)
		(width 0.1651)
		(layer "In11.Cu")
		(net "P5E_PEX3_STN2_TX_DP<36>")
	)
	(segment
		(start 421.27805 -28.937712)
		(end 420.78275 -28.937712)
		(width 0.1651)
		(layer "In11.Cu")
		(net "P5E_PEX3_STN2_TX_DP<36>")
	)
	(segment
		(start 438.175908 -47.726854)
		(end 431.320956 -39.897558)
		(width 0.1651)
		(layer "In11.Cu")
		(net "P5E_PEX3_STN2_TX_DP<36>")
	)
	(segment
		(start 402.583904 -271.427448)
		(end 402.583904 -271.399)
		(width 0.1143)
		(layer "In11.Cu")
		(net "P5E_PEX3_STN2_TX_DP<36>")
	)
	(segment
		(start 402.629624 -271.473168)
		(end 402.583904 -271.427448)
		(width 0.1143)
		(layer "In11.Cu")
		(net "P5E_PEX3_STN2_TX_DP<36>")
	)
	(segment
		(start 402.629624 -280.10485)
		(end 402.629624 -271.473168)
		(width 0.1143)
		(layer "In11.Cu")
		(net "P5E_PEX3_STN2_TX_DP<36>")
	)
	(segment
		(start 402.844762 -280.319988)
		(end 402.629624 -280.10485)
		(width 0.1143)
		(layer "In11.Cu")
		(net "P5E_PEX3_STN2_TX_DP<36>")
	)
	(segment
		(start 421.39235 -28.823412)
		(end 421.27805 -28.937712)
		(width 0.1651)
		(layer "In11.Cu")
		(net "P5E_PEX3_STN2_TX_DP<36>")
	)
	(segment
		(start 403.199854 -280.434288)
		(end 403.085554 -280.319988)
		(width 0.1143)
		(layer "In11.Cu")
		(net "P5E_PEX3_STN2_TX_DP<36>")
	)
	(segment
		(start 89.642442 -366.700308)
		(end 89.84869 -366.26419)
		(width 0.1651)
		(layer "In5.Cu")
		(net "P5E_PEX0_STN5_RX_DP<95>")
	)
	(segment
		(start 93.811598 -341.352378)
		(end 84.008214 -332.895194)
		(width 0.1651)
		(layer "In5.Cu")
		(net "P5E_PEX0_STN5_RX_DP<95>")
	)
	(segment
		(start 87.970868 -372.099078)
		(end 88.202516 -371.86743)
		(width 0.1651)
		(layer "In5.Cu")
		(net "P5E_PEX0_STN5_RX_DP<95>")
	)
	(segment
		(start 89.00668 -367.820448)
		(end 89.133934 -367.774982)
		(width 0.1651)
		(layer "In5.Cu")
		(net "P5E_PEX0_STN5_RX_DP<95>")
	)
	(segment
		(start 89.133934 -367.774982)
		(end 89.340436 -367.338864)
		(width 0.1651)
		(layer "In5.Cu")
		(net "P5E_PEX0_STN5_RX_DP<95>")
	)
	(segment
		(start 72.605392 -318.129666)
		(end 72.835516 -318.129666)
		(width 0.1143)
		(layer "In5.Cu")
		(net "P5E_PEX0_STN5_RX_DP<95>")
	)
	(segment
		(start 92.080334 -361.545632)
		(end 93.900498 -358.821736)
		(width 0.1651)
		(layer "In5.Cu")
		(net "P5E_PEX0_STN5_RX_DP<95>")
	)
	(segment
		(start 87.43696 -372.099078)
		(end 87.970868 -372.099078)
		(width 0.1651)
		(layer "In5.Cu")
		(net "P5E_PEX0_STN5_RX_DP<95>")
	)
	(segment
		(start 88.786208 -368.28603)
		(end 89.00668 -367.820448)
		(width 0.1651)
		(layer "In5.Cu")
		(net "P5E_PEX0_STN5_RX_DP<95>")
	)
	(segment
		(start 72.333866 -319.9638)
		(end 72.379586 -319.91808)
		(width 0.1143)
		(layer "In5.Cu")
		(net "P5E_PEX0_STN5_RX_DP<95>")
	)
	(segment
		(start 89.295986 -367.215166)
		(end 89.518998 -366.744504)
		(width 0.1651)
		(layer "In5.Cu")
		(net "P5E_PEX0_STN5_RX_DP<95>")
	)
	(segment
		(start 72.379586 -319.91808)
		(end 72.379586 -318.355472)
		(width 0.1143)
		(layer "In5.Cu")
		(net "P5E_PEX0_STN5_RX_DP<95>")
	)
	(segment
		(start 87.30996 -371.590062)
		(end 87.30996 -371.972078)
		(width 0.1651)
		(layer "In5.Cu")
		(net "P5E_PEX0_STN5_RX_DP<95>")
	)
	(segment
		(start 89.800176 -366.128808)
		(end 90.015568 -365.673894)
		(width 0.1651)
		(layer "In5.Cu")
		(net "P5E_PEX0_STN5_RX_DP<95>")
	)
	(segment
		(start 93.900498 -358.821736)
		(end 94.307152 -357.840026)
		(width 0.1651)
		(layer "In5.Cu")
		(net "P5E_PEX0_STN5_RX_DP<95>")
	)
	(segment
		(start 94.307152 -342.279224)
		(end 93.811598 -341.352378)
		(width 0.1651)
		(layer "In5.Cu")
		(net "P5E_PEX0_STN5_RX_DP<95>")
	)
	(segment
		(start 73.038462 -321.925442)
		(end 72.333866 -320.224658)
		(width 0.1651)
		(layer "In5.Cu")
		(net "P5E_PEX0_STN5_RX_DP<95>")
	)
	(segment
		(start 72.379586 -318.355472)
		(end 72.605392 -318.129666)
		(width 0.1143)
		(layer "In5.Cu")
		(net "P5E_PEX0_STN5_RX_DP<95>")
	)
	(segment
		(start 88.202516 -371.86743)
		(end 88.202516 -370.245386)
		(width 0.1651)
		(layer "In5.Cu")
		(net "P5E_PEX0_STN5_RX_DP<95>")
	)
	(segment
		(start 89.340436 -367.338864)
		(end 89.295986 -367.215166)
		(width 0.1651)
		(layer "In5.Cu")
		(net "P5E_PEX0_STN5_RX_DP<95>")
	)
	(segment
		(start 88.831928 -368.413538)
		(end 88.786208 -368.28603)
		(width 0.1651)
		(layer "In5.Cu")
		(net "P5E_PEX0_STN5_RX_DP<95>")
	)
	(segment
		(start 94.307152 -357.840026)
		(end 94.307152 -342.279224)
		(width 0.1651)
		(layer "In5.Cu")
		(net "P5E_PEX0_STN5_RX_DP<95>")
	)
	(segment
		(start 88.62568 -368.849656)
		(end 88.831928 -368.413538)
		(width 0.1651)
		(layer "In5.Cu")
		(net "P5E_PEX0_STN5_RX_DP<95>")
	)
	(segment
		(start 87.30996 -371.972078)
		(end 87.43696 -372.099078)
		(width 0.1651)
		(layer "In5.Cu")
		(net "P5E_PEX0_STN5_RX_DP<95>")
	)
	(segment
		(start 72.949816 -318.015366)
		(end 72.949816 -317.749936)
		(width 0.1143)
		(layer "In5.Cu")
		(net "P5E_PEX0_STN5_RX_DP<95>")
	)
	(segment
		(start 84.008214 -332.895194)
		(end 73.038462 -321.925442)
		(width 0.1651)
		(layer "In5.Cu")
		(net "P5E_PEX0_STN5_RX_DP<95>")
	)
	(segment
		(start 89.518998 -366.744504)
		(end 89.642442 -366.700308)
		(width 0.1651)
		(layer "In5.Cu")
		(net "P5E_PEX0_STN5_RX_DP<95>")
	)
	(segment
		(start 72.333866 -319.992248)
		(end 72.333866 -319.9638)
		(width 0.1143)
		(layer "In5.Cu")
		(net "P5E_PEX0_STN5_RX_DP<95>")
	)
	(segment
		(start 72.333866 -320.224658)
		(end 72.333866 -319.992248)
		(width 0.1651)
		(layer "In5.Cu")
		(net "P5E_PEX0_STN5_RX_DP<95>")
	)
	(segment
		(start 88.202516 -370.245386)
		(end 88.62568 -368.849656)
		(width 0.1651)
		(layer "In5.Cu")
		(net "P5E_PEX0_STN5_RX_DP<95>")
	)
	(segment
		(start 72.835516 -318.129666)
		(end 72.949816 -318.015366)
		(width 0.1143)
		(layer "In5.Cu")
		(net "P5E_PEX0_STN5_RX_DP<95>")
	)
	(segment
		(start 90.015568 -365.673894)
		(end 90.150696 -365.625634)
		(width 0.1651)
		(layer "In5.Cu")
		(net "P5E_PEX0_STN5_RX_DP<95>")
	)
	(segment
		(start 89.84869 -366.26419)
		(end 89.800176 -366.128808)
		(width 0.1651)
		(layer "In5.Cu")
		(net "P5E_PEX0_STN5_RX_DP<95>")
	)
	(segment
		(start 90.150696 -365.625634)
		(end 92.080334 -361.545632)
		(width 0.1651)
		(layer "In5.Cu")
		(net "P5E_PEX0_STN5_RX_DP<95>")
	)
	(segment
		(start 87.132922 -343.685622)
		(end 86.812882 -343.365582)
		(width 0.13462)
		(layer "F.Cu")
		(net "P5E_PEX0_STN6_TX_DN<100>")
	)
	(segment
		(start 86.812882 -342.734138)
		(end 87.107522 -342.439498)
		(width 0.13462)
		(layer "F.Cu")
		(net "P5E_PEX0_STN6_TX_DN<100>")
	)
	(segment
		(start 86.812882 -343.365582)
		(end 86.812882 -342.734138)
		(width 0.13462)
		(layer "F.Cu")
		(net "P5E_PEX0_STN6_TX_DN<100>")
	)
	(segment
		(start 54.499256 -323.757544)
		(end 55.18658 -324.444868)
		(width 0.1651)
		(layer "In13.Cu")
		(net "P5E_PEX0_STN6_TX_DN<100>")
	)
	(segment
		(start 53.860954 -313.570112)
		(end 53.697378 -313.570112)
		(width 0.1143)
		(layer "In13.Cu")
		(net "P5E_PEX0_STN6_TX_DN<100>")
	)
	(segment
		(start 53.570124 -313.697366)
		(end 53.570124 -320.181478)
		(width 0.1143)
		(layer "In13.Cu")
		(net "P5E_PEX0_STN6_TX_DN<100>")
	)
	(segment
		(start 53.615844 -321.624706)
		(end 54.499256 -323.757544)
		(width 0.1651)
		(layer "In13.Cu")
		(net "P5E_PEX0_STN6_TX_DN<100>")
	)
	(segment
		(start 53.949854 -313.949842)
		(end 53.949854 -313.659012)
		(width 0.1143)
		(layer "In13.Cu")
		(net "P5E_PEX0_STN6_TX_DN<100>")
	)
	(segment
		(start 62.593982 -327.512934)
		(end 85.341206 -339.67166)
		(width 0.1651)
		(layer "In13.Cu")
		(net "P5E_PEX0_STN6_TX_DN<100>")
	)
	(segment
		(start 86.816692 -341.147146)
		(end 86.816692 -342.148668)
		(width 0.1651)
		(layer "In13.Cu")
		(net "P5E_PEX0_STN6_TX_DN<100>")
	)
	(segment
		(start 53.949854 -313.659012)
		(end 53.860954 -313.570112)
		(width 0.1143)
		(layer "In13.Cu")
		(net "P5E_PEX0_STN6_TX_DN<100>")
	)
	(segment
		(start 53.697378 -313.570112)
		(end 53.570124 -313.697366)
		(width 0.1143)
		(layer "In13.Cu")
		(net "P5E_PEX0_STN6_TX_DN<100>")
	)
	(segment
		(start 86.816692 -342.148668)
		(end 87.107522 -342.439498)
		(width 0.1651)
		(layer "In13.Cu")
		(net "P5E_PEX0_STN6_TX_DN<100>")
	)
	(segment
		(start 53.615844 -320.227198)
		(end 53.615844 -320.249296)
		(width 0.1143)
		(layer "In13.Cu")
		(net "P5E_PEX0_STN6_TX_DN<100>")
	)
	(segment
		(start 55.18658 -324.444868)
		(end 62.593982 -327.512934)
		(width 0.1651)
		(layer "In13.Cu")
		(net "P5E_PEX0_STN6_TX_DN<100>")
	)
	(segment
		(start 53.615844 -320.249296)
		(end 53.615844 -321.624706)
		(width 0.1651)
		(layer "In13.Cu")
		(net "P5E_PEX0_STN6_TX_DN<100>")
	)
	(segment
		(start 85.341206 -339.67166)
		(end 86.816692 -341.147146)
		(width 0.1651)
		(layer "In13.Cu")
		(net "P5E_PEX0_STN6_TX_DN<100>")
	)
	(segment
		(start 53.570124 -320.181478)
		(end 53.615844 -320.227198)
		(width 0.1143)
		(layer "In13.Cu")
		(net "P5E_PEX0_STN6_TX_DN<100>")
	)
	(segment
		(start 422.247314 -33.657286)
		(end 421.95242 -33.95218)
		(width 0.13462)
		(layer "F.Cu")
		(net "P5E_PEX3_STN2_TX_DN<39>")
	)
	(segment
		(start 421.321484 -33.95218)
		(end 421.00119 -33.631886)
		(width 0.13462)
		(layer "F.Cu")
		(net "P5E_PEX3_STN2_TX_DN<39>")
	)
	(segment
		(start 421.95242 -33.95218)
		(end 421.321484 -33.95218)
		(width 0.13462)
		(layer "F.Cu")
		(net "P5E_PEX3_STN2_TX_DN<39>")
	)
	(segment
		(start 407.365962 -121.457974)
		(end 400.015964 -262.799068)
		(width 0.1651)
		(layer "In11.Cu")
		(net "P5E_PEX3_STN2_TX_DN<39>")
	)
	(segment
		(start 400.015964 -271.427448)
		(end 399.970244 -271.473168)
		(width 0.1143)
		(layer "In11.Cu")
		(net "P5E_PEX3_STN2_TX_DN<39>")
	)
	(segment
		(start 435.582314 -49.033938)
		(end 436.576978 -58.541412)
		(width 0.1651)
		(layer "In11.Cu")
		(net "P5E_PEX3_STN2_TX_DN<39>")
	)
	(segment
		(start 436.576978 -58.541412)
		(end 436.576978 -60.165234)
		(width 0.1651)
		(layer "In11.Cu")
		(net "P5E_PEX3_STN2_TX_DN<39>")
	)
	(segment
		(start 436.576978 -60.165234)
		(end 436.076344 -62.053724)
		(width 0.1651)
		(layer "In11.Cu")
		(net "P5E_PEX3_STN2_TX_DN<39>")
	)
	(segment
		(start 436.076344 -62.053724)
		(end 435.182518 -63.834518)
		(width 0.1651)
		(layer "In11.Cu")
		(net "P5E_PEX3_STN2_TX_DN<39>")
	)
	(segment
		(start 399.970244 -271.473168)
		(end 399.970244 -278.125936)
		(width 0.1143)
		(layer "In11.Cu")
		(net "P5E_PEX3_STN2_TX_DN<39>")
	)
	(segment
		(start 425.326048 -35.848798)
		(end 428.995078 -41.84396)
		(width 0.1651)
		(layer "In11.Cu")
		(net "P5E_PEX3_STN2_TX_DN<39>")
	)
	(segment
		(start 407.478738 -120.544336)
		(end 407.47823 -120.544336)
		(width 0.1651)
		(layer "In11.Cu")
		(net "P5E_PEX3_STN2_TX_DN<39>")
	)
	(segment
		(start 400.235674 -278.229568)
		(end 400.349974 -278.115268)
		(width 0.1143)
		(layer "In11.Cu")
		(net "P5E_PEX3_STN2_TX_DN<39>")
	)
	(segment
		(start 407.47823 -120.544336)
		(end 407.365962 -121.457974)
		(width 0.1651)
		(layer "In11.Cu")
		(net "P5E_PEX3_STN2_TX_DN<39>")
	)
	(segment
		(start 435.182518 -63.834518)
		(end 412.930848 -92.81541)
		(width 0.1651)
		(layer "In11.Cu")
		(net "P5E_PEX3_STN2_TX_DN<39>")
	)
	(segment
		(start 423.11193 -33.948116)
		(end 423.671238 -34.181034)
		(width 0.1651)
		(layer "In11.Cu")
		(net "P5E_PEX3_STN2_TX_DN<39>")
	)
	(segment
		(start 422.247314 -33.657286)
		(end 422.538144 -33.948116)
		(width 0.1651)
		(layer "In11.Cu")
		(net "P5E_PEX3_STN2_TX_DN<39>")
	)
	(segment
		(start 408.225498 -114.480086)
		(end 407.478738 -120.544336)
		(width 0.1651)
		(layer "In11.Cu")
		(net "P5E_PEX3_STN2_TX_DN<39>")
	)
	(segment
		(start 409.64612 -107.220512)
		(end 408.225498 -114.480086)
		(width 0.1651)
		(layer "In11.Cu")
		(net "P5E_PEX3_STN2_TX_DN<39>")
	)
	(segment
		(start 412.930848 -92.81541)
		(end 409.64612 -107.220512)
		(width 0.1651)
		(layer "In11.Cu")
		(net "P5E_PEX3_STN2_TX_DN<39>")
	)
	(segment
		(start 400.015964 -262.799068)
		(end 400.015964 -271.399)
		(width 0.1651)
		(layer "In11.Cu")
		(net "P5E_PEX3_STN2_TX_DN<39>")
	)
	(segment
		(start 399.970244 -278.125936)
		(end 400.073876 -278.229568)
		(width 0.1143)
		(layer "In11.Cu")
		(net "P5E_PEX3_STN2_TX_DN<39>")
	)
	(segment
		(start 400.349974 -278.115268)
		(end 400.349974 -277.849838)
		(width 0.1143)
		(layer "In11.Cu")
		(net "P5E_PEX3_STN2_TX_DN<39>")
	)
	(segment
		(start 400.073876 -278.229568)
		(end 400.235674 -278.229568)
		(width 0.1143)
		(layer "In11.Cu")
		(net "P5E_PEX3_STN2_TX_DN<39>")
	)
	(segment
		(start 428.995078 -41.84396)
		(end 435.582314 -49.033938)
		(width 0.1651)
		(layer "In11.Cu")
		(net "P5E_PEX3_STN2_TX_DN<39>")
	)
	(segment
		(start 400.015964 -271.399)
		(end 400.015964 -271.427448)
		(width 0.1143)
		(layer "In11.Cu")
		(net "P5E_PEX3_STN2_TX_DN<39>")
	)
	(segment
		(start 423.671238 -34.181034)
		(end 425.326048 -35.848798)
		(width 0.1651)
		(layer "In11.Cu")
		(net "P5E_PEX3_STN2_TX_DN<39>")
	)
	(segment
		(start 422.538144 -33.948116)
		(end 423.11193 -33.948116)
		(width 0.1651)
		(layer "In11.Cu")
		(net "P5E_PEX3_STN2_TX_DN<39>")
	)
	(segment
		(start 49.158398 -357.840534)
		(end 49.158398 -342.37803)
		(width 0.1651)
		(layer "In5.Cu")
		(net "P5E_PEX0_STN7_RX_DP<126>")
	)
	(segment
		(start 41.485566 -316.229492)
		(end 41.599866 -316.115192)
		(width 0.1143)
		(layer "In5.Cu")
		(net "P5E_PEX0_STN7_RX_DP<126>")
	)
	(segment
		(start 41.976802 -369.663218)
		(end 42.146474 -369.103656)
		(width 0.1651)
		(layer "In5.Cu")
		(net "P5E_PEX0_STN7_RX_DP<126>")
	)
	(segment
		(start 41.255442 -316.229492)
		(end 41.485566 -316.229492)
		(width 0.1143)
		(layer "In5.Cu")
		(net "P5E_PEX0_STN7_RX_DP<126>")
	)
	(segment
		(start 41.976802 -382.32969)
		(end 41.976802 -369.663218)
		(width 0.1651)
		(layer "In5.Cu")
		(net "P5E_PEX0_STN7_RX_DP<126>")
	)
	(segment
		(start 40.983916 -319.995296)
		(end 40.983916 -319.966848)
		(width 0.1143)
		(layer "In5.Cu")
		(net "P5E_PEX0_STN7_RX_DP<126>")
	)
	(segment
		(start 40.983916 -325.139304)
		(end 40.983916 -319.995296)
		(width 0.1651)
		(layer "In5.Cu")
		(net "P5E_PEX0_STN7_RX_DP<126>")
	)
	(segment
		(start 41.607232 -382.69926)
		(end 41.976802 -382.32969)
		(width 0.1651)
		(layer "In5.Cu")
		(net "P5E_PEX0_STN7_RX_DP<126>")
	)
	(segment
		(start 48.745648 -341.01659)
		(end 48.745648 -341.016336)
		(width 0.1651)
		(layer "In5.Cu")
		(net "P5E_PEX0_STN7_RX_DP<126>")
	)
	(segment
		(start 40.983916 -319.966848)
		(end 41.029636 -319.921128)
		(width 0.1143)
		(layer "In5.Cu")
		(net "P5E_PEX0_STN7_RX_DP<126>")
	)
	(segment
		(start 41.2369 -382.69926)
		(end 41.607232 -382.69926)
		(width 0.1651)
		(layer "In5.Cu")
		(net "P5E_PEX0_STN7_RX_DP<126>")
	)
	(segment
		(start 44.31665 -331.648816)
		(end 41.392094 -326.484742)
		(width 0.1651)
		(layer "In5.Cu")
		(net "P5E_PEX0_STN7_RX_DP<126>")
	)
	(segment
		(start 41.392094 -326.484742)
		(end 40.983916 -325.139304)
		(width 0.1651)
		(layer "In5.Cu")
		(net "P5E_PEX0_STN7_RX_DP<126>")
	)
	(segment
		(start 41.599866 -316.115192)
		(end 41.599866 -315.849762)
		(width 0.1143)
		(layer "In5.Cu")
		(net "P5E_PEX0_STN7_RX_DP<126>")
	)
	(segment
		(start 42.146474 -369.103656)
		(end 48.32223 -359.861358)
		(width 0.1651)
		(layer "In5.Cu")
		(net "P5E_PEX0_STN7_RX_DP<126>")
	)
	(segment
		(start 46.4312 -336.328512)
		(end 46.21911 -335.880456)
		(width 0.1651)
		(layer "In5.Cu")
		(net "P5E_PEX0_STN7_RX_DP<126>")
	)
	(segment
		(start 46.549564 -336.37093)
		(end 46.4312 -336.328512)
		(width 0.1651)
		(layer "In5.Cu")
		(net "P5E_PEX0_STN7_RX_DP<126>")
	)
	(segment
		(start 45.931582 -335.272126)
		(end 45.719492 -334.82407)
		(width 0.1651)
		(layer "In5.Cu")
		(net "P5E_PEX0_STN7_RX_DP<126>")
	)
	(segment
		(start 46.718474 -336.937096)
		(end 46.760892 -336.818732)
		(width 0.1651)
		(layer "In5.Cu")
		(net "P5E_PEX0_STN7_RX_DP<126>")
	)
	(segment
		(start 46.21911 -335.880456)
		(end 46.261528 -335.762092)
		(width 0.1651)
		(layer "In5.Cu")
		(net "P5E_PEX0_STN7_RX_DP<126>")
	)
	(segment
		(start 46.049946 -335.314544)
		(end 45.931582 -335.272126)
		(width 0.1651)
		(layer "In5.Cu")
		(net "P5E_PEX0_STN7_RX_DP<126>")
	)
	(segment
		(start 46.760892 -336.818732)
		(end 46.54931 -336.371184)
		(width 0.1651)
		(layer "In5.Cu")
		(net "P5E_PEX0_STN7_RX_DP<126>")
	)
	(segment
		(start 46.261528 -335.762092)
		(end 46.049946 -335.314544)
		(width 0.1651)
		(layer "In5.Cu")
		(net "P5E_PEX0_STN7_RX_DP<126>")
	)
	(segment
		(start 47.048928 -337.42757)
		(end 46.930564 -337.385152)
		(width 0.1651)
		(layer "In5.Cu")
		(net "P5E_PEX0_STN7_RX_DP<126>")
	)
	(segment
		(start 46.54931 -336.371184)
		(end 46.549564 -336.37093)
		(width 0.1651)
		(layer "In5.Cu")
		(net "P5E_PEX0_STN7_RX_DP<126>")
	)
	(segment
		(start 45.76191 -334.705706)
		(end 44.31665 -331.648816)
		(width 0.1651)
		(layer "In5.Cu")
		(net "P5E_PEX0_STN7_RX_DP<126>")
	)
	(segment
		(start 48.745648 -341.016336)
		(end 47.048928 -337.42757)
		(width 0.1651)
		(layer "In5.Cu")
		(net "P5E_PEX0_STN7_RX_DP<126>")
	)
	(segment
		(start 49.158398 -342.37803)
		(end 48.745648 -341.01659)
		(width 0.1651)
		(layer "In5.Cu")
		(net "P5E_PEX0_STN7_RX_DP<126>")
	)
	(segment
		(start 41.1099 -382.57226)
		(end 41.2369 -382.69926)
		(width 0.1651)
		(layer "In5.Cu")
		(net "P5E_PEX0_STN7_RX_DP<126>")
	)
	(segment
		(start 45.719492 -334.82407)
		(end 45.76191 -334.705706)
		(width 0.1651)
		(layer "In5.Cu")
		(net "P5E_PEX0_STN7_RX_DP<126>")
	)
	(segment
		(start 41.1099 -382.18999)
		(end 41.1099 -382.57226)
		(width 0.1651)
		(layer "In5.Cu")
		(net "P5E_PEX0_STN7_RX_DP<126>")
	)
	(segment
		(start 46.930564 -337.385152)
		(end 46.718474 -336.937096)
		(width 0.1651)
		(layer "In5.Cu")
		(net "P5E_PEX0_STN7_RX_DP<126>")
	)
	(segment
		(start 41.029636 -319.921128)
		(end 41.029636 -316.455298)
		(width 0.1143)
		(layer "In5.Cu")
		(net "P5E_PEX0_STN7_RX_DP<126>")
	)
	(segment
		(start 48.32223 -359.861358)
		(end 49.158398 -357.840534)
		(width 0.1651)
		(layer "In5.Cu")
		(net "P5E_PEX0_STN7_RX_DP<126>")
	)
	(segment
		(start 41.029636 -316.455298)
		(end 41.255442 -316.229492)
		(width 0.1143)
		(layer "In5.Cu")
		(net "P5E_PEX0_STN7_RX_DP<126>")
	)
	(segment
		(start 74.377042 -342.734138)
		(end 74.671682 -342.439498)
		(width 0.13462)
		(layer "F.Cu")
		(net "P5E_PEX0_STN6_TX_DN<106>")
	)
	(segment
		(start 74.377042 -343.365582)
		(end 74.377042 -342.734138)
		(width 0.13462)
		(layer "F.Cu")
		(net "P5E_PEX0_STN6_TX_DN<106>")
	)
	(segment
		(start 74.697082 -343.685622)
		(end 74.377042 -343.365582)
		(width 0.13462)
		(layer "F.Cu")
		(net "P5E_PEX0_STN6_TX_DN<106>")
	)
	(segment
		(start 74.671682 -342.439498)
		(end 74.380852 -342.148668)
		(width 0.1651)
		(layer "In13.Cu")
		(net "P5E_PEX0_STN6_TX_DN<106>")
	)
	(segment
		(start 48.16094 -313.570112)
		(end 48.24984 -313.659012)
		(width 0.1143)
		(layer "In13.Cu")
		(net "P5E_PEX0_STN6_TX_DN<106>")
	)
	(segment
		(start 47.87011 -313.697112)
		(end 47.99711 -313.570112)
		(width 0.1143)
		(layer "In13.Cu")
		(net "P5E_PEX0_STN6_TX_DN<106>")
	)
	(segment
		(start 74.2188 -341.046054)
		(end 53.327808 -329.879198)
		(width 0.1651)
		(layer "In13.Cu")
		(net "P5E_PEX0_STN6_TX_DN<106>")
	)
	(segment
		(start 47.99711 -313.570112)
		(end 48.16094 -313.570112)
		(width 0.1143)
		(layer "In13.Cu")
		(net "P5E_PEX0_STN6_TX_DN<106>")
	)
	(segment
		(start 48.24984 -313.659012)
		(end 48.24984 -313.949842)
		(width 0.1143)
		(layer "In13.Cu")
		(net "P5E_PEX0_STN6_TX_DN<106>")
	)
	(segment
		(start 53.327808 -329.879198)
		(end 51.942492 -329.305412)
		(width 0.1651)
		(layer "In13.Cu")
		(net "P5E_PEX0_STN6_TX_DN<106>")
	)
	(segment
		(start 74.380852 -341.316564)
		(end 74.2188 -341.046054)
		(width 0.1651)
		(layer "In13.Cu")
		(net "P5E_PEX0_STN6_TX_DN<106>")
	)
	(segment
		(start 47.91583 -320.105024)
		(end 47.87011 -320.059304)
		(width 0.1143)
		(layer "In13.Cu")
		(net "P5E_PEX0_STN6_TX_DN<106>")
	)
	(segment
		(start 47.87011 -320.059304)
		(end 47.87011 -313.697112)
		(width 0.1143)
		(layer "In13.Cu")
		(net "P5E_PEX0_STN6_TX_DN<106>")
	)
	(segment
		(start 47.91583 -320.127122)
		(end 47.91583 -320.105024)
		(width 0.1143)
		(layer "In13.Cu")
		(net "P5E_PEX0_STN6_TX_DN<106>")
	)
	(segment
		(start 47.91583 -323.384164)
		(end 47.91583 -320.127122)
		(width 0.1651)
		(layer "In13.Cu")
		(net "P5E_PEX0_STN6_TX_DN<106>")
	)
	(segment
		(start 51.942492 -329.305412)
		(end 49.255426 -326.618346)
		(width 0.1651)
		(layer "In13.Cu")
		(net "P5E_PEX0_STN6_TX_DN<106>")
	)
	(segment
		(start 49.255426 -326.618346)
		(end 47.91583 -323.384164)
		(width 0.1651)
		(layer "In13.Cu")
		(net "P5E_PEX0_STN6_TX_DN<106>")
	)
	(segment
		(start 74.380852 -342.148668)
		(end 74.380852 -341.316564)
		(width 0.1651)
		(layer "In13.Cu")
		(net "P5E_PEX0_STN6_TX_DN<106>")
	)
	(segment
		(start 402.571712 -343.36609)
		(end 402.571712 -342.73363)
		(width 0.13462)
		(layer "F.Cu")
		(net "P5E_PEX3_STN5_TX_DP<94>")
	)
	(segment
		(start 402.571712 -342.73363)
		(end 402.27758 -342.439498)
		(width 0.13462)
		(layer "F.Cu")
		(net "P5E_PEX3_STN5_TX_DP<94>")
	)
	(segment
		(start 402.25218 -343.685622)
		(end 402.571712 -343.36609)
		(width 0.13462)
		(layer "F.Cu")
		(net "P5E_PEX3_STN5_TX_DP<94>")
	)
	(segment
		(start 419.944804 -311.479692)
		(end 420.185596 -311.479692)
		(width 0.1143)
		(layer "In13.Cu")
		(net "P5E_PEX3_STN5_TX_DP<94>")
	)
	(segment
		(start 419.683946 -320.046096)
		(end 419.683946 -320.017648)
		(width 0.1143)
		(layer "In13.Cu")
		(net "P5E_PEX3_STN5_TX_DP<94>")
	)
	(segment
		(start 419.683946 -323.015356)
		(end 419.683946 -320.046096)
		(width 0.1651)
		(layer "In13.Cu")
		(net "P5E_PEX3_STN5_TX_DP<94>")
	)
	(segment
		(start 420.185596 -311.479692)
		(end 420.299896 -311.365392)
		(width 0.1143)
		(layer "In13.Cu")
		(net "P5E_PEX3_STN5_TX_DP<94>")
	)
	(segment
		(start 402.27758 -342.439498)
		(end 402.56841 -342.148668)
		(width 0.1651)
		(layer "In13.Cu")
		(net "P5E_PEX3_STN5_TX_DP<94>")
	)
	(segment
		(start 420.299896 -311.365392)
		(end 420.299896 -311.099962)
		(width 0.1143)
		(layer "In13.Cu")
		(net "P5E_PEX3_STN5_TX_DP<94>")
	)
	(segment
		(start 419.729666 -319.971928)
		(end 419.729666 -311.69483)
		(width 0.1143)
		(layer "In13.Cu")
		(net "P5E_PEX3_STN5_TX_DP<94>")
	)
	(segment
		(start 419.729666 -311.69483)
		(end 419.944804 -311.479692)
		(width 0.1143)
		(layer "In13.Cu")
		(net "P5E_PEX3_STN5_TX_DP<94>")
	)
	(segment
		(start 402.56841 -342.148668)
		(end 402.56841 -341.500714)
		(width 0.1651)
		(layer "In13.Cu")
		(net "P5E_PEX3_STN5_TX_DP<94>")
	)
	(segment
		(start 416.996626 -326.97928)
		(end 419.683946 -323.015356)
		(width 0.1651)
		(layer "In13.Cu")
		(net "P5E_PEX3_STN5_TX_DP<94>")
	)
	(segment
		(start 402.56841 -341.500714)
		(end 402.826982 -340.769702)
		(width 0.1651)
		(layer "In13.Cu")
		(net "P5E_PEX3_STN5_TX_DP<94>")
	)
	(segment
		(start 419.683946 -320.017648)
		(end 419.729666 -319.971928)
		(width 0.1143)
		(layer "In13.Cu")
		(net "P5E_PEX3_STN5_TX_DP<94>")
	)
	(segment
		(start 402.826982 -340.769702)
		(end 416.996626 -326.97928)
		(width 0.1651)
		(layer "In13.Cu")
		(net "P5E_PEX3_STN5_TX_DP<94>")
	)
	(segment
		(start 42.321734 -336.045556)
		(end 40.964866 -331.573632)
		(width 0.1651)
		(layer "In5.Cu")
		(net "P5E_PEX0_STN7_RX_DN<124>")
	)
	(segment
		(start 39.320216 -319.921128)
		(end 39.320216 -316.534292)
		(width 0.1143)
		(layer "In5.Cu")
		(net "P5E_PEX0_STN7_RX_DN<124>")
	)
	(segment
		(start 43.222418 -342.147906)
		(end 42.321734 -336.045556)
		(width 0.1651)
		(layer "In5.Cu")
		(net "P5E_PEX0_STN7_RX_DN<124>")
	)
	(segment
		(start 39.434516 -316.419992)
		(end 39.585646 -316.419992)
		(width 0.1143)
		(layer "In5.Cu")
		(net "P5E_PEX0_STN7_RX_DN<124>")
	)
	(segment
		(start 40.769286 -330.929234)
		(end 40.769032 -330.928472)
		(width 0.1651)
		(layer "In5.Cu")
		(net "P5E_PEX0_STN7_RX_DN<124>")
	)
	(segment
		(start 37.324284 -382.9812)
		(end 37.858954 -382.44653)
		(width 0.1651)
		(layer "In5.Cu")
		(net "P5E_PEX0_STN7_RX_DN<124>")
	)
	(segment
		(start 36.710112 -383.1082)
		(end 36.837112 -382.9812)
		(width 0.1651)
		(layer "In5.Cu")
		(net "P5E_PEX0_STN7_RX_DN<124>")
	)
	(segment
		(start 40.964866 -331.573632)
		(end 40.964612 -331.57287)
		(width 0.1651)
		(layer "In5.Cu")
		(net "P5E_PEX0_STN7_RX_DN<124>")
	)
	(segment
		(start 43.222418 -357.827326)
		(end 43.222418 -342.147906)
		(width 0.1651)
		(layer "In5.Cu")
		(net "P5E_PEX0_STN7_RX_DN<124>")
	)
	(segment
		(start 39.585646 -316.419992)
		(end 39.699946 -316.534292)
		(width 0.1143)
		(layer "In5.Cu")
		(net "P5E_PEX0_STN7_RX_DN<124>")
	)
	(segment
		(start 38.187122 -368.357404)
		(end 42.871136 -359.593388)
		(width 0.1651)
		(layer "In5.Cu")
		(net "P5E_PEX0_STN7_RX_DN<124>")
	)
	(segment
		(start 40.769032 -330.928472)
		(end 39.365936 -326.304402)
		(width 0.1651)
		(layer "In5.Cu")
		(net "P5E_PEX0_STN7_RX_DN<124>")
	)
	(segment
		(start 36.710112 -383.490216)
		(end 36.710112 -383.1082)
		(width 0.1651)
		(layer "In5.Cu")
		(net "P5E_PEX0_STN7_RX_DN<124>")
	)
	(segment
		(start 39.699946 -316.534292)
		(end 39.699946 -316.799722)
		(width 0.1143)
		(layer "In5.Cu")
		(net "P5E_PEX0_STN7_RX_DN<124>")
	)
	(segment
		(start 39.365936 -326.304402)
		(end 39.365936 -319.995296)
		(width 0.1651)
		(layer "In5.Cu")
		(net "P5E_PEX0_STN7_RX_DN<124>")
	)
	(segment
		(start 37.858954 -369.667282)
		(end 38.187122 -368.357404)
		(width 0.1651)
		(layer "In5.Cu")
		(net "P5E_PEX0_STN7_RX_DN<124>")
	)
	(segment
		(start 39.320216 -316.534292)
		(end 39.434516 -316.419992)
		(width 0.1143)
		(layer "In5.Cu")
		(net "P5E_PEX0_STN7_RX_DN<124>")
	)
	(segment
		(start 40.964612 -331.57287)
		(end 40.769286 -330.929234)
		(width 0.1651)
		(layer "In5.Cu")
		(net "P5E_PEX0_STN7_RX_DN<124>")
	)
	(segment
		(start 37.858954 -382.44653)
		(end 37.858954 -369.667282)
		(width 0.1651)
		(layer "In5.Cu")
		(net "P5E_PEX0_STN7_RX_DN<124>")
	)
	(segment
		(start 42.871136 -359.593388)
		(end 43.222418 -357.827326)
		(width 0.1651)
		(layer "In5.Cu")
		(net "P5E_PEX0_STN7_RX_DN<124>")
	)
	(segment
		(start 39.365936 -319.995296)
		(end 39.365936 -319.966848)
		(width 0.1143)
		(layer "In5.Cu")
		(net "P5E_PEX0_STN7_RX_DN<124>")
	)
	(segment
		(start 36.837112 -382.9812)
		(end 37.324284 -382.9812)
		(width 0.1651)
		(layer "In5.Cu")
		(net "P5E_PEX0_STN7_RX_DN<124>")
	)
	(segment
		(start 39.365936 -319.966848)
		(end 39.320216 -319.921128)
		(width 0.1143)
		(layer "In5.Cu")
		(net "P5E_PEX0_STN7_RX_DN<124>")
	)
	(segment
		(start 341.052404 -357.46309)
		(end 341.347044 -357.75773)
		(width 0.13462)
		(layer "F.Cu")
		(net "P5E_PEX2_STN5_TX_C_DN<94>")
	)
	(segment
		(start 341.052404 -356.831646)
		(end 341.052404 -357.46309)
		(width 0.13462)
		(layer "F.Cu")
		(net "P5E_PEX2_STN5_TX_C_DN<94>")
	)
	(segment
		(start 341.372444 -356.511606)
		(end 341.052404 -356.831646)
		(width 0.13462)
		(layer "F.Cu")
		(net "P5E_PEX2_STN5_TX_C_DN<94>")
	)
	(segment
		(start 345.81592 -368.943636)
		(end 345.749626 -368.783616)
		(width 0.1651)
		(layer "In7.Cu")
		(net "P5E_PEX2_STN5_TX_C_DN<94>")
	)
	(segment
		(start 345.749626 -368.783616)
		(end 345.749372 -368.783362)
		(width 0.1651)
		(layer "In7.Cu")
		(net "P5E_PEX2_STN5_TX_C_DN<94>")
	)
	(segment
		(start 345.364054 -379.08103)
		(end 345.81592 -378.629164)
		(width 0.1651)
		(layer "In7.Cu")
		(net "P5E_PEX2_STN5_TX_C_DN<94>")
	)
	(segment
		(start 344.816938 -379.08103)
		(end 345.364054 -379.08103)
		(width 0.1651)
		(layer "In7.Cu")
		(net "P5E_PEX2_STN5_TX_C_DN<94>")
	)
	(segment
		(start 345.749372 -368.779806)
		(end 345.74607 -368.776504)
		(width 0.1651)
		(layer "In7.Cu")
		(net "P5E_PEX2_STN5_TX_C_DN<94>")
	)
	(segment
		(start 345.74607 -368.776504)
		(end 341.056214 -358.860344)
		(width 0.1651)
		(layer "In7.Cu")
		(net "P5E_PEX2_STN5_TX_C_DN<94>")
	)
	(segment
		(start 345.749372 -368.783362)
		(end 345.749372 -368.779806)
		(width 0.1651)
		(layer "In7.Cu")
		(net "P5E_PEX2_STN5_TX_C_DN<94>")
	)
	(segment
		(start 341.056214 -358.860344)
		(end 341.056214 -358.04856)
		(width 0.1651)
		(layer "In7.Cu")
		(net "P5E_PEX2_STN5_TX_C_DN<94>")
	)
	(segment
		(start 341.056214 -358.04856)
		(end 341.347044 -357.75773)
		(width 0.1651)
		(layer "In7.Cu")
		(net "P5E_PEX2_STN5_TX_C_DN<94>")
	)
	(segment
		(start 344.689938 -379.20803)
		(end 344.816938 -379.08103)
		(width 0.1651)
		(layer "In7.Cu")
		(net "P5E_PEX2_STN5_TX_C_DN<94>")
	)
	(segment
		(start 344.689938 -379.590046)
		(end 344.689938 -379.20803)
		(width 0.1651)
		(layer "In7.Cu")
		(net "P5E_PEX2_STN5_TX_C_DN<94>")
	)
	(segment
		(start 345.81592 -378.629164)
		(end 345.81592 -368.943636)
		(width 0.1651)
		(layer "In7.Cu")
		(net "P5E_PEX2_STN5_TX_C_DN<94>")
	)
	(segment
		(start 396.353792 -343.36609)
		(end 396.353792 -342.73363)
		(width 0.13462)
		(layer "F.Cu")
		(net "P5E_PEX3_STN5_TX_DP<91>")
	)
	(segment
		(start 396.353792 -342.73363)
		(end 396.05966 -342.439498)
		(width 0.13462)
		(layer "F.Cu")
		(net "P5E_PEX3_STN5_TX_DP<91>")
	)
	(segment
		(start 396.03426 -343.685622)
		(end 396.353792 -343.36609)
		(width 0.13462)
		(layer "F.Cu")
		(net "P5E_PEX3_STN5_TX_DP<91>")
	)
	(segment
		(start 417.335716 -313.379612)
		(end 417.450016 -313.265312)
		(width 0.1143)
		(layer "In13.Cu")
		(net "P5E_PEX3_STN5_TX_DP<91>")
	)
	(segment
		(start 396.05966 -342.439498)
		(end 396.35049 -342.148668)
		(width 0.1651)
		(layer "In13.Cu")
		(net "P5E_PEX3_STN5_TX_DP<91>")
	)
	(segment
		(start 416.879786 -313.59475)
		(end 417.094924 -313.379612)
		(width 0.1143)
		(layer "In13.Cu")
		(net "P5E_PEX3_STN5_TX_DP<91>")
	)
	(segment
		(start 414.830514 -324.79361)
		(end 416.834066 -321.971162)
		(width 0.1651)
		(layer "In13.Cu")
		(net "P5E_PEX3_STN5_TX_DP<91>")
	)
	(segment
		(start 417.450016 -313.265312)
		(end 417.450016 -312.999882)
		(width 0.1143)
		(layer "In13.Cu")
		(net "P5E_PEX3_STN5_TX_DP<91>")
	)
	(segment
		(start 396.35049 -341.54872)
		(end 396.573756 -341.09533)
		(width 0.1651)
		(layer "In13.Cu")
		(net "P5E_PEX3_STN5_TX_DP<91>")
	)
	(segment
		(start 416.834066 -320.017648)
		(end 416.879786 -319.971928)
		(width 0.1143)
		(layer "In13.Cu")
		(net "P5E_PEX3_STN5_TX_DP<91>")
	)
	(segment
		(start 396.573756 -341.09533)
		(end 414.830514 -324.79361)
		(width 0.1651)
		(layer "In13.Cu")
		(net "P5E_PEX3_STN5_TX_DP<91>")
	)
	(segment
		(start 396.35049 -342.148668)
		(end 396.35049 -341.54872)
		(width 0.1651)
		(layer "In13.Cu")
		(net "P5E_PEX3_STN5_TX_DP<91>")
	)
	(segment
		(start 416.834066 -321.971162)
		(end 416.834066 -320.046096)
		(width 0.1651)
		(layer "In13.Cu")
		(net "P5E_PEX3_STN5_TX_DP<91>")
	)
	(segment
		(start 416.834066 -320.046096)
		(end 416.834066 -320.017648)
		(width 0.1143)
		(layer "In13.Cu")
		(net "P5E_PEX3_STN5_TX_DP<91>")
	)
	(segment
		(start 417.094924 -313.379612)
		(end 417.335716 -313.379612)
		(width 0.1143)
		(layer "In13.Cu")
		(net "P5E_PEX3_STN5_TX_DP<91>")
	)
	(segment
		(start 416.879786 -319.971928)
		(end 416.879786 -313.59475)
		(width 0.1143)
		(layer "In13.Cu")
		(net "P5E_PEX3_STN5_TX_DP<91>")
	)
	(segment
		(start 72.443086 -322.302886)
		(end 71.665846 -320.426334)
		(width 0.1651)
		(layer "In5.Cu")
		(net "P5E_PEX0_STN5_RX_DN<94>")
	)
	(segment
		(start 91.480132 -341.76462)
		(end 91.179904 -341.039704)
		(width 0.1651)
		(layer "In5.Cu")
		(net "P5E_PEX0_STN5_RX_DN<94>")
	)
	(segment
		(start 85.109812 -371.790214)
		(end 85.109812 -371.408198)
		(width 0.1651)
		(layer "In5.Cu")
		(net "P5E_PEX0_STN5_RX_DN<94>")
	)
	(segment
		(start 85.853778 -371.281198)
		(end 86.290658 -370.844318)
		(width 0.1651)
		(layer "In5.Cu")
		(net "P5E_PEX0_STN5_RX_DN<94>")
	)
	(segment
		(start 71.620126 -316.534292)
		(end 71.734426 -316.419992)
		(width 0.1143)
		(layer "In5.Cu")
		(net "P5E_PEX0_STN5_RX_DN<94>")
	)
	(segment
		(start 71.734426 -316.419992)
		(end 71.885556 -316.419992)
		(width 0.1143)
		(layer "In5.Cu")
		(net "P5E_PEX0_STN5_RX_DN<94>")
	)
	(segment
		(start 71.665846 -320.426334)
		(end 71.665846 -319.995296)
		(width 0.1651)
		(layer "In5.Cu")
		(net "P5E_PEX0_STN5_RX_DN<94>")
	)
	(segment
		(start 88.399112 -365.359696)
		(end 91.480132 -357.89616)
		(width 0.1651)
		(layer "In5.Cu")
		(net "P5E_PEX0_STN5_RX_DN<94>")
	)
	(segment
		(start 86.290658 -369.817142)
		(end 88.399112 -365.359696)
		(width 0.1651)
		(layer "In5.Cu")
		(net "P5E_PEX0_STN5_RX_DN<94>")
	)
	(segment
		(start 85.109812 -371.408198)
		(end 85.236812 -371.281198)
		(width 0.1651)
		(layer "In5.Cu")
		(net "P5E_PEX0_STN5_RX_DN<94>")
	)
	(segment
		(start 71.885556 -316.419992)
		(end 71.999856 -316.534292)
		(width 0.1143)
		(layer "In5.Cu")
		(net "P5E_PEX0_STN5_RX_DN<94>")
	)
	(segment
		(start 71.999856 -316.534292)
		(end 71.999856 -316.799722)
		(width 0.1143)
		(layer "In5.Cu")
		(net "P5E_PEX0_STN5_RX_DN<94>")
	)
	(segment
		(start 91.179904 -341.039704)
		(end 72.443086 -322.302886)
		(width 0.1651)
		(layer "In5.Cu")
		(net "P5E_PEX0_STN5_RX_DN<94>")
	)
	(segment
		(start 71.620126 -319.921128)
		(end 71.620126 -316.534292)
		(width 0.1143)
		(layer "In5.Cu")
		(net "P5E_PEX0_STN5_RX_DN<94>")
	)
	(segment
		(start 91.480132 -357.89616)
		(end 91.480132 -341.76462)
		(width 0.1651)
		(layer "In5.Cu")
		(net "P5E_PEX0_STN5_RX_DN<94>")
	)
	(segment
		(start 85.236812 -371.281198)
		(end 85.853778 -371.281198)
		(width 0.1651)
		(layer "In5.Cu")
		(net "P5E_PEX0_STN5_RX_DN<94>")
	)
	(segment
		(start 86.290658 -370.844318)
		(end 86.290658 -369.817142)
		(width 0.1651)
		(layer "In5.Cu")
		(net "P5E_PEX0_STN5_RX_DN<94>")
	)
	(segment
		(start 71.665846 -319.995296)
		(end 71.665846 -319.966848)
		(width 0.1143)
		(layer "In5.Cu")
		(net "P5E_PEX0_STN5_RX_DN<94>")
	)
	(segment
		(start 71.665846 -319.966848)
		(end 71.620126 -319.921128)
		(width 0.1143)
		(layer "In5.Cu")
		(net "P5E_PEX0_STN5_RX_DN<94>")
	)
	(segment
		(start 296.172382 -356.831646)
		(end 296.172382 -357.46309)
		(width 0.13462)
		(layer "F.Cu")
		(net "P5E_PEX2_STN7_TX_C_DP<126>")
	)
	(segment
		(start 295.852342 -356.511606)
		(end 296.172382 -356.831646)
		(width 0.13462)
		(layer "F.Cu")
		(net "P5E_PEX2_STN7_TX_C_DP<126>")
	)
	(segment
		(start 296.172382 -357.46309)
		(end 295.877742 -357.75773)
		(width 0.13462)
		(layer "F.Cu")
		(net "P5E_PEX2_STN7_TX_C_DP<126>")
	)
	(segment
		(start 298.978066 -364.049056)
		(end 299.211492 -364.485682)
		(width 0.1651)
		(layer "In7.Cu")
		(net "P5E_PEX2_STN7_TX_C_DP<126>")
	)
	(segment
		(start 301.533814 -374.612408)
		(end 301.247048 -374.899174)
		(width 0.1651)
		(layer "In7.Cu")
		(net "P5E_PEX2_STN7_TX_C_DP<126>")
	)
	(segment
		(start 300.277276 -366.667034)
		(end 300.51121 -367.104168)
		(width 0.1651)
		(layer "In7.Cu")
		(net "P5E_PEX2_STN7_TX_C_DP<126>")
	)
	(segment
		(start 300.080426 -366.110012)
		(end 300.313852 -366.546638)
		(width 0.1651)
		(layer "In7.Cu")
		(net "P5E_PEX2_STN7_TX_C_DP<126>")
	)
	(segment
		(start 298.85767 -364.01248)
		(end 298.978066 -364.049056)
		(width 0.1651)
		(layer "In7.Cu")
		(net "P5E_PEX2_STN7_TX_C_DP<126>")
	)
	(segment
		(start 300.51121 -367.104168)
		(end 300.631352 -367.14049)
		(width 0.1651)
		(layer "In7.Cu")
		(net "P5E_PEX2_STN7_TX_C_DP<126>")
	)
	(segment
		(start 296.168572 -358.795066)
		(end 298.660312 -363.455204)
		(width 0.1651)
		(layer "In7.Cu")
		(net "P5E_PEX2_STN7_TX_C_DP<126>")
	)
	(segment
		(start 299.96003 -366.073436)
		(end 300.080426 -366.110012)
		(width 0.1651)
		(layer "In7.Cu")
		(net "P5E_PEX2_STN7_TX_C_DP<126>")
	)
	(segment
		(start 300.313852 -366.546638)
		(end 300.277276 -366.667034)
		(width 0.1651)
		(layer "In7.Cu")
		(net "P5E_PEX2_STN7_TX_C_DP<126>")
	)
	(segment
		(start 299.529246 -365.079534)
		(end 299.762672 -365.51616)
		(width 0.1651)
		(layer "In7.Cu")
		(net "P5E_PEX2_STN7_TX_C_DP<126>")
	)
	(segment
		(start 300.816772 -374.899174)
		(end 300.689772 -374.772174)
		(width 0.1651)
		(layer "In7.Cu")
		(net "P5E_PEX2_STN7_TX_C_DP<126>")
	)
	(segment
		(start 299.211492 -364.485682)
		(end 299.17517 -364.606078)
		(width 0.1651)
		(layer "In7.Cu")
		(net "P5E_PEX2_STN7_TX_C_DP<126>")
	)
	(segment
		(start 295.877742 -357.75773)
		(end 296.168572 -358.04856)
		(width 0.1651)
		(layer "In7.Cu")
		(net "P5E_PEX2_STN7_TX_C_DP<126>")
	)
	(segment
		(start 301.247048 -374.899174)
		(end 300.816772 -374.899174)
		(width 0.1651)
		(layer "In7.Cu")
		(net "P5E_PEX2_STN7_TX_C_DP<126>")
	)
	(segment
		(start 300.689772 -374.772174)
		(end 300.689772 -374.390158)
		(width 0.1651)
		(layer "In7.Cu")
		(net "P5E_PEX2_STN7_TX_C_DP<126>")
	)
	(segment
		(start 300.631352 -367.14049)
		(end 301.533814 -368.828066)
		(width 0.1651)
		(layer "In7.Cu")
		(net "P5E_PEX2_STN7_TX_C_DP<126>")
	)
	(segment
		(start 299.17517 -364.606078)
		(end 299.40885 -365.042958)
		(width 0.1651)
		(layer "In7.Cu")
		(net "P5E_PEX2_STN7_TX_C_DP<126>")
	)
	(segment
		(start 299.40885 -365.042958)
		(end 299.529246 -365.079534)
		(width 0.1651)
		(layer "In7.Cu")
		(net "P5E_PEX2_STN7_TX_C_DP<126>")
	)
	(segment
		(start 296.168572 -358.04856)
		(end 296.168572 -358.795066)
		(width 0.1651)
		(layer "In7.Cu")
		(net "P5E_PEX2_STN7_TX_C_DP<126>")
	)
	(segment
		(start 301.533814 -368.828066)
		(end 301.533814 -374.612408)
		(width 0.1651)
		(layer "In7.Cu")
		(net "P5E_PEX2_STN7_TX_C_DP<126>")
	)
	(segment
		(start 299.762672 -365.51616)
		(end 299.72635 -365.636556)
		(width 0.1651)
		(layer "In7.Cu")
		(net "P5E_PEX2_STN7_TX_C_DP<126>")
	)
	(segment
		(start 298.62399 -363.5756)
		(end 298.85767 -364.01248)
		(width 0.1651)
		(layer "In7.Cu")
		(net "P5E_PEX2_STN7_TX_C_DP<126>")
	)
	(segment
		(start 298.660312 -363.455204)
		(end 298.62399 -363.5756)
		(width 0.1651)
		(layer "In7.Cu")
		(net "P5E_PEX2_STN7_TX_C_DP<126>")
	)
	(segment
		(start 299.72635 -365.636556)
		(end 299.96003 -366.073436)
		(width 0.1651)
		(layer "In7.Cu")
		(net "P5E_PEX2_STN7_TX_C_DP<126>")
	)
	(segment
		(start 64.399922 -293.99992)
		(end 64.874902 -293.52494)
		(width 0.249936)
		(layer "F.Cu")
		(net "GND")
	)
	(segment
		(start 194.274948 -297.32478)
		(end 194.749928 -296.8498)
		(width 0.249936)
		(layer "F.Cu")
		(net "GND")
	)
	(segment
		(start 426.94987 -290.199826)
		(end 427.42485 -290.674806)
		(width 0.249936)
		(layer "F.Cu")
		(net "GND")
	)
	(segment
		(start 231.149144 -178.642772)
		(end 230.460296 -179.33162)
		(width 0.4572)
		(layer "F.Cu")
		(net "GND")
	)
	(segment
		(start 416.974782 -305.874928)
		(end 417.450016 -306.349908)
		(width 0.249936)
		(layer "F.Cu")
		(net "GND")
	)
	(segment
		(start 296.254678 -34.990024)
		(end 294.86479 -34.990024)
		(width 0.3556)
		(layer "F.Cu")
		(net "GND")
	)
	(segment
		(start 17.185386 -274.232624)
		(end 17.794986 -274.232624)
		(width 0.381)
		(layer "F.Cu")
		(net "GND")
	)
	(segment
		(start 70.574916 -302.074834)
		(end 70.099936 -301.599854)
		(width 0.249936)
		(layer "F.Cu")
		(net "GND")
	)
	(segment
		(start 419.349936 -285.449772)
		(end 418.874956 -284.974792)
		(width 0.249936)
		(layer "F.Cu")
		(net "GND")
	)
	(segment
		(start 60.599828 -305.399948)
		(end 61.074808 -305.874928)
		(width 0.249936)
		(layer "F.Cu")
		(net "GND")
	)
	(segment
		(start 211.400136 -186.702954)
		(end 211.400136 -185.728864)
		(width 0.254)
		(layer "F.Cu")
		(net "GND")
	)
	(segment
		(start 292.32479 -297.32478)
		(end 292.79977 -297.79976)
		(width 0.249936)
		(layer "F.Cu")
		(net "GND")
	)
	(segment
		(start 243.577872 -347.400118)
		(end 241.82578 -347.400118)
		(width 0.4572)
		(layer "F.Cu")
		(net "GND")
	)
	(segment
		(start 168.625012 -305.874928)
		(end 169.099992 -305.399948)
		(width 0.249936)
		(layer "F.Cu")
		(net "GND")
	)
	(segment
		(start 192.375028 -297.32478)
		(end 192.850008 -296.8498)
		(width 0.249936)
		(layer "F.Cu")
		(net "GND")
	)
	(segment
		(start 166.249858 -303.499774)
		(end 166.725092 -303.974754)
		(width 0.249936)
		(layer "F.Cu")
		(net "GND")
	)
	(segment
		(start 193.324988 -291.624766)
		(end 192.850008 -291.149786)
		(width 0.249936)
		(layer "F.Cu")
		(net "GND")
	)
	(segment
		(start 67.249802 -306.349908)
		(end 66.774822 -305.874928)
		(width 0.249936)
		(layer "F.Cu")
		(net "GND")
	)
	(segment
		(start 176.624996 -288.299906)
		(end 176.699926 -288.299906)
		(width 0.249936)
		(layer "F.Cu")
		(net "GND")
	)
	(segment
		(start 47.06112 -38.701218)
		(end 47.819564 -38.701218)
		(width 0.4572)
		(layer "F.Cu")
		(net "GND")
	)
	(segment
		(start 173.375066 -285.924752)
		(end 172.900086 -286.399732)
		(width 0.249936)
		(layer "F.Cu")
		(net "GND")
	)
	(segment
		(start 277.251668 -133.565138)
		(end 278.242268 -133.565138)
		(width 0.3556)
		(layer "F.Cu")
		(net "GND")
	)
	(segment
		(start 420.558468 -116.69522)
		(end 420.818564 -116.435124)
		(width 0.3556)
		(layer "F.Cu")
		(net "GND")
	)
	(segment
		(start 237.819438 -225.427032)
		(end 237.819438 -224.483168)
		(width 0.4572)
		(layer "F.Cu")
		(net "GND")
	)
	(segment
		(start 163.018724 -46.693836)
		(end 162.819334 -46.893226)
		(width 0.254)
		(layer "F.Cu")
		(net "GND")
	)
	(segment
		(start 409.374848 -289.724846)
		(end 409.849828 -290.199826)
		(width 0.249936)
		(layer "F.Cu")
		(net "GND")
	)
	(segment
		(start 301.349918 -286.399732)
		(end 301.824898 -285.924752)
		(width 0.249936)
		(layer "F.Cu")
		(net "GND")
	)
	(segment
		(start 37.799772 -293.04996)
		(end 37.324792 -292.57498)
		(width 0.249936)
		(layer "F.Cu")
		(net "GND")
	)
	(segment
		(start 229.067614 -221.504256)
		(end 228.667818 -221.904052)
		(width 0.381)
		(layer "F.Cu")
		(net "GND")
	)
	(segment
		(start 110.438946 -393.740132)
		(end 111.16945 -393.740132)
		(width 0.4572)
		(layer "F.Cu")
		(net "GND")
	)
	(segment
		(start 146.473926 -26.606246)
		(end 146.473926 -25.971246)
		(width 0.4572)
		(layer "F.Cu")
		(net "GND")
	)
	(segment
		(start 242.91671 -162.404044)
		(end 242.91671 -163.021518)
		(width 0.4572)
		(layer "F.Cu")
		(net "GND")
	)
	(segment
		(start 77.22489 -289.724846)
		(end 76.74991 -289.249866)
		(width 0.249936)
		(layer "F.Cu")
		(net "GND")
	)
	(segment
		(start 71.524876 -294.4749)
		(end 71.049896 -294.94988)
		(width 0.249936)
		(layer "F.Cu")
		(net "GND")
	)
	(segment
		(start 396.0749 -301.124874)
		(end 395.59992 -301.599854)
		(width 0.249936)
		(layer "F.Cu")
		(net "GND")
	)
	(segment
		(start 419.349936 -296.8498)
		(end 419.824916 -296.37482)
		(width 0.249936)
		(layer "F.Cu")
		(net "GND")
	)
	(segment
		(start 52.999894 -284.499812)
		(end 53.474874 -284.974792)
		(width 0.249936)
		(layer "F.Cu")
		(net "GND")
	)
	(segment
		(start 421.44696 -53.144166)
		(end 421.44696 -52.592224)
		(width 0.254)
		(layer "F.Cu")
		(net "GND")
	)
	(segment
		(start 417.450016 -293.04996)
		(end 417.924996 -293.52494)
		(width 0.249936)
		(layer "F.Cu")
		(net "GND")
	)
	(segment
		(start 182.39994 -285.449772)
		(end 181.92496 -285.924752)
		(width 0.249936)
		(layer "F.Cu")
		(net "GND")
	)
	(segment
		(start 343.361264 -38.701218)
		(end 344.119708 -38.701218)
		(width 0.4572)
		(layer "F.Cu")
		(net "GND")
	)
	(segment
		(start 411.750002 -292.099746)
		(end 411.275022 -291.624766)
		(width 0.249936)
		(layer "F.Cu")
		(net "GND")
	)
	(segment
		(start 232.517442 -59.399932)
		(end 233.572558 -59.399932)
		(width 0.3556)
		(layer "F.Cu")
		(net "GND")
	)
	(segment
		(start 37.799772 -298.74972)
		(end 37.324538 -298.27474)
		(width 0.249936)
		(layer "F.Cu")
		(net "GND")
	)
	(segment
		(start 262.415782 -337.90255)
		(end 262.197088 -337.90255)
		(width 0.4572)
		(layer "F.Cu")
		(net "GND")
	)
	(segment
		(start 285.674816 -305.874928)
		(end 286.149796 -306.349908)
		(width 0.249936)
		(layer "F.Cu")
		(net "GND")
	)
	(segment
		(start 365.90605 -213.995)
		(end 366.522 -213.995)
		(width 0.4572)
		(layer "F.Cu")
		(net "GND")
	)
	(segment
		(start 386.044948 -27.79014)
		(end 384.96494 -27.79014)
		(width 0.3556)
		(layer "F.Cu")
		(net "GND")
	)
	(segment
		(start 279.974802 -306.824888)
		(end 280.449782 -307.299868)
		(width 0.249936)
		(layer "F.Cu")
		(net "GND")
	)
	(segment
		(start 66.774822 -306.824888)
		(end 67.249802 -306.349908)
		(width 0.249936)
		(layer "F.Cu")
		(net "GND")
	)
	(segment
		(start 410.324808 -285.924752)
		(end 409.849828 -285.449772)
		(width 0.249936)
		(layer "F.Cu")
		(net "GND")
	)
	(segment
		(start 344.49385 -219.187014)
		(end 344.893646 -218.787218)
		(width 0.381)
		(layer "F.Cu")
		(net "GND")
	)
	(segment
		(start 415.564828 -27.79014)
		(end 416.580828 -27.79014)
		(width 0.3556)
		(layer "F.Cu")
		(net "GND")
	)
	(segment
		(start 63.408814 -384.598926)
		(end 63.408814 -383.576068)
		(width 0.4572)
		(layer "F.Cu")
		(net "GND")
	)
	(segment
		(start 67.724782 -291.624766)
		(end 68.199762 -292.099746)
		(width 0.249936)
		(layer "F.Cu")
		(net "GND")
	)
	(segment
		(start 297.074844 -303.974754)
		(end 297.549824 -303.499774)
		(width 0.249936)
		(layer "F.Cu")
		(net "GND")
	)
	(segment
		(start 246.39905 -236.275118)
		(end 245.553484 -236.275118)
		(width 0.4572)
		(layer "F.Cu")
		(net "GND")
	)
	(segment
		(start 180.50002 -301.599854)
		(end 180.02504 -302.074834)
		(width 0.249936)
		(layer "F.Cu")
		(net "GND")
	)
	(segment
		(start 188.366908 -118.234968)
		(end 189.357508 -118.234968)
		(width 0.3556)
		(layer "F.Cu")
		(net "GND")
	)
	(segment
		(start 395.12494 -306.824888)
		(end 394.64996 -306.349908)
		(width 0.249936)
		(layer "F.Cu")
		(net "GND")
	)
	(segment
		(start 161.15157 -98.845116)
		(end 162.14217 -98.845116)
		(width 0.3556)
		(layer "F.Cu")
		(net "GND")
	)
	(segment
		(start 401.299934 -307.299868)
		(end 401.774914 -306.824888)
		(width 0.249936)
		(layer "F.Cu")
		(net "GND")
	)
	(segment
		(start 51.63312 -111.44504)
		(end 50.64252 -111.44504)
		(width 0.3556)
		(layer "F.Cu")
		(net "GND")
	)
	(segment
		(start 311.324752 -296.37482)
		(end 310.849772 -295.89984)
		(width 0.249936)
		(layer "F.Cu")
		(net "GND")
	)
	(segment
		(start 280.449782 -296.8498)
		(end 279.974802 -297.32478)
		(width 0.249936)
		(layer "F.Cu")
		(net "GND")
	)
	(segment
		(start 313.699906 -290.199826)
		(end 314.174886 -289.724846)
		(width 0.249936)
		(layer "F.Cu")
		(net "GND")
	)
	(segment
		(start 174.325026 -306.824888)
		(end 174.800006 -307.299868)
		(width 0.249936)
		(layer "F.Cu")
		(net "GND")
	)
	(segment
		(start 55.415434 -374.51284)
		(end 56.155336 -375.252742)
		(width 0.4572)
		(layer "F.Cu")
		(net "GND")
	)
	(segment
		(start 48.72482 -293.52494)
		(end 49.1998 -293.99992)
		(width 0.249936)
		(layer "F.Cu")
		(net "GND")
	)
	(segment
		(start 194.749928 -293.04996)
		(end 195.224908 -292.574726)
		(width 0.249936)
		(layer "F.Cu")
		(net "GND")
	)
	(segment
		(start 167.732964 -152.96007)
		(end 166.742364 -152.96007)
		(width 0.3556)
		(layer "F.Cu")
		(net "GND")
	)
	(segment
		(start 53.949854 -284.499812)
		(end 53.474874 -284.974792)
		(width 0.249936)
		(layer "F.Cu")
		(net "GND")
	)
	(segment
		(start 134.366 -285.488634)
		(end 134.054596 -285.488634)
		(width 0.2286)
		(layer "F.Cu")
		(net "GND")
	)
	(segment
		(start 142.768066 -55.083456)
		(end 143.423386 -55.083456)
		(width 0.254)
		(layer "F.Cu")
		(net "GND")
	)
	(segment
		(start 397.97482 -288.774886)
		(end 398.4498 -288.299906)
		(width 0.249936)
		(layer "F.Cu")
		(net "GND")
	)
	(segment
		(start 48.72482 -296.37482)
		(end 49.1998 -295.89984)
		(width 0.249936)
		(layer "F.Cu")
		(net "GND")
	)
	(segment
		(start 423.15003 -290.199826)
		(end 423.62501 -290.674806)
		(width 0.249936)
		(layer "F.Cu")
		(net "GND")
	)
	(segment
		(start 125.894084 -285.488634)
		(end 125.605286 -285.199836)
		(width 0.2286)
		(layer "F.Cu")
		(net "GND")
	)
	(segment
		(start 47.29988 -284.499812)
		(end 46.8249 -284.024832)
		(width 0.249936)
		(layer "F.Cu")
		(net "GND")
	)
	(segment
		(start 238.886238 -235.161328)
		(end 238.886238 -235.737654)
		(width 0.4572)
		(layer "F.Cu")
		(net "GND")
	)
	(segment
		(start 237.894114 -35.499548)
		(end 238.266478 -35.871912)
		(width 0.4572)
		(layer "F.Cu")
		(net "GND")
	)
	(segment
		(start 287.574736 -294.4749)
		(end 287.099756 -293.99992)
		(width 0.249936)
		(layer "F.Cu")
		(net "GND")
	)
	(segment
		(start 282.349702 -300.649894)
		(end 282.824936 -300.174914)
		(width 0.249936)
		(layer "F.Cu")
		(net "GND")
	)
	(segment
		(start 414.124902 -303.974754)
		(end 413.649922 -303.499774)
		(width 0.249936)
		(layer "F.Cu")
		(net "GND")
	)
	(segment
		(start 92.997782 -295.965118)
		(end 92.997782 -295.355518)
		(width 0.4572)
		(layer "F.Cu")
		(net "GND")
	)
	(segment
		(start 154.805888 -161.276284)
		(end 155.107894 -160.974278)
		(width 0.4572)
		(layer "F.Cu")
		(net "GND")
	)
	(segment
		(start 205.422246 -215.485218)
		(end 206.548228 -216.6112)
		(width 0.4572)
		(layer "F.Cu")
		(net "GND")
	)
	(segment
		(start 178.599846 -292.099746)
		(end 178.124866 -291.624766)
		(width 0.249936)
		(layer "F.Cu")
		(net "GND")
	)
	(segment
		(start 78.17485 -299.224954)
		(end 78.64983 -299.699934)
		(width 0.249936)
		(layer "F.Cu")
		(net "GND")
	)
	(segment
		(start 76.27493 -296.37482)
		(end 76.74991 -296.8498)
		(width 0.249936)
		(layer "F.Cu")
		(net "GND")
	)
	(segment
		(start 417.924996 -296.37482)
		(end 417.450016 -296.8498)
		(width 0.249936)
		(layer "F.Cu")
		(net "GND")
	)
	(segment
		(start 61.549788 -299.699934)
		(end 61.074808 -300.174914)
		(width 0.249936)
		(layer "F.Cu")
		(net "GND")
	)
	(segment
		(start 284.249876 -284.499812)
		(end 283.774896 -284.024832)
		(width 0.249936)
		(layer "F.Cu")
		(net "GND")
	)
	(segment
		(start 161.975038 -303.024794)
		(end 162.450018 -303.499774)
		(width 0.249936)
		(layer "F.Cu")
		(net "GND")
	)
	(segment
		(start 112.007142 -160.276794)
		(end 112.169448 -160.276794)
		(width 0.1778)
		(layer "F.Cu")
		(net "GND")
	)
	(segment
		(start 417.450016 -297.79976)
		(end 416.974782 -298.27474)
		(width 0.249936)
		(layer "F.Cu")
		(net "GND")
	)
	(segment
		(start 380.85395 -195.326)
		(end 380.104142 -195.326)
		(width 0.4572)
		(layer "F.Cu")
		(net "GND")
	)
	(segment
		(start 177.174906 -284.974792)
		(end 176.699926 -285.449772)
		(width 0.249936)
		(layer "F.Cu")
		(net "GND")
	)
	(segment
		(start 183.766968 -147.55495)
		(end 183.766714 -147.555204)
		(width 0.4572)
		(layer "F.Cu")
		(net "GND")
	)
	(segment
		(start 303.724818 -293.52494)
		(end 303.249838 -293.99992)
		(width 0.249936)
		(layer "F.Cu")
		(net "GND")
	)
	(segment
		(start 190.474854 -300.174914)
		(end 190.950088 -299.699934)
		(width 0.249936)
		(layer "F.Cu")
		(net "GND")
	)
	(segment
		(start 420.277798 -135.320024)
		(end 420.752778 -134.845044)
		(width 0.3556)
		(layer "F.Cu")
		(net "GND")
	)
	(segment
		(start 301.824898 -285.924752)
		(end 301.349918 -285.449772)
		(width 0.249936)
		(layer "F.Cu")
		(net "GND")
	)
	(segment
		(start 275.699728 -288.299906)
		(end 275.224748 -288.774886)
		(width 0.249936)
		(layer "F.Cu")
		(net "GND")
	)
	(segment
		(start 225.7171 -304.703988)
		(end 225.7171 -305.375564)
		(width 0.4572)
		(layer "F.Cu")
		(net "GND")
	)
	(segment
		(start 377.56084 -311.442608)
		(end 377.560332 -311.442608)
		(width 0.4572)
		(layer "F.Cu")
		(net "GND")
	)
	(segment
		(start 118.36273 -34.29762)
		(end 117.927882 -34.732468)
		(width 0.4572)
		(layer "F.Cu")
		(net "GND")
	)
	(segment
		(start 62.024768 -305.874928)
		(end 62.499748 -305.399948)
		(width 0.249936)
		(layer "F.Cu")
		(net "GND")
	)
	(segment
		(start 173.794166 -35.499548)
		(end 174.16653 -35.871912)
		(width 0.4572)
		(layer "F.Cu")
		(net "GND")
	)
	(segment
		(start 298.974764 -307.774848)
		(end 298.499784 -307.299868)
		(width 0.249936)
		(layer "F.Cu")
		(net "GND")
	)
	(segment
		(start 274.749768 -274.999958)
		(end 274.274788 -274.524978)
		(width 0.249936)
		(layer "F.Cu")
		(net "GND")
	)
	(segment
		(start 152.94991 -282.599892)
		(end 152.47493 -282.124912)
		(width 0.249936)
		(layer "F.Cu")
		(net "GND")
	)
	(segment
		(start 176.224946 -297.32478)
		(end 176.699926 -297.79976)
		(width 0.249936)
		(layer "F.Cu")
		(net "GND")
	)
	(segment
		(start 411.541976 -162.781488)
		(end 411.541976 -162.08375)
		(width 0.4572)
		(layer "F.Cu")
		(net "GND")
	)
	(segment
		(start 312.482484 -28.875736)
		(end 312.482484 -28.47848)
		(width 0.254)
		(layer "F.Cu")
		(net "GND")
	)
	(segment
		(start 36.6649 -31.390082)
		(end 37.536374 -31.390082)
		(width 0.3556)
		(layer "F.Cu")
		(net "GND")
	)
	(segment
		(start 62.664848 -34.990024)
		(end 61.648848 -34.990024)
		(width 0.3556)
		(layer "F.Cu")
		(net "GND")
	)
	(segment
		(start 270.949928 -290.199826)
		(end 270.474948 -289.724846)
		(width 0.249936)
		(layer "F.Cu")
		(net "GND")
	)
	(segment
		(start 297.549824 -285.449772)
		(end 297.074844 -285.924752)
		(width 0.249936)
		(layer "F.Cu")
		(net "GND")
	)
	(segment
		(start 113.608866 -161.005774)
		(end 112.973866 -161.005774)
		(width 0.4572)
		(layer "F.Cu")
		(net "GND")
	)
	(segment
		(start 338.893912 -227.186998)
		(end 339.293708 -227.586794)
		(width 0.381)
		(layer "F.Cu")
		(net "GND")
	)
	(segment
		(start 277.599902 -300.649894)
		(end 278.074882 -300.174914)
		(width 0.254)
		(layer "F.Cu")
		(net "GND")
	)
	(segment
		(start 62.024768 -306.824888)
		(end 61.549788 -306.349908)
		(width 0.249936)
		(layer "F.Cu")
		(net "GND")
	)
	(segment
		(start 133.765798 -284.631384)
		(end 133.558534 -284.42412)
		(width 0.2286)
		(layer "F.Cu")
		(net "GND")
	)
	(segment
		(start 262.07212 -33.248092)
		(end 262.07212 -33.857692)
		(width 0.4572)
		(layer "F.Cu")
		(net "GND")
	)
	(segment
		(start 243.296948 -278.041862)
		(end 243.040662 -278.041862)
		(width 0.254)
		(layer "F.Cu")
		(net "GND")
	)
	(segment
		(start 58.224928 -283.074872)
		(end 58.699908 -282.599892)
		(width 0.249936)
		(layer "F.Cu")
		(net "GND")
	)
	(segment
		(start 47.29988 -301.599854)
		(end 47.77486 -301.124874)
		(width 0.249936)
		(layer "F.Cu")
		(net "GND")
	)
	(segment
		(start 258.642612 -211.749386)
		(end 259.258562 -211.749386)
		(width 0.3048)
		(layer "F.Cu")
		(net "GND")
	)
	(segment
		(start 102.353364 -224.650046)
		(end 103.20274 -224.650046)
		(width 0.254)
		(layer "F.Cu")
		(net "GND")
	)
	(segment
		(start 419.824916 -301.124874)
		(end 420.299896 -300.649894)
		(width 0.249936)
		(layer "F.Cu")
		(net "GND")
	)
	(segment
		(start 180.50002 -307.299868)
		(end 180.02504 -306.824888)
		(width 0.249936)
		(layer "F.Cu")
		(net "GND")
	)
	(segment
		(start 170.524932 -284.974792)
		(end 170.999912 -285.449772)
		(width 0.249936)
		(layer "F.Cu")
		(net "GND")
	)
	(segment
		(start 350.647 -150.76805)
		(end 351.38995 -150.76805)
		(width 0.4572)
		(layer "F.Cu")
		(net "GND")
	)
	(segment
		(start 180.50002 -307.299868)
		(end 180.975 -306.824888)
		(width 0.249936)
		(layer "F.Cu")
		(net "GND")
	)
	(segment
		(start 391.799826 -276.899878)
		(end 391.324846 -277.374858)
		(width 0.249936)
		(layer "F.Cu")
		(net "GND")
	)
	(segment
		(start 7.213346 -140.392404)
		(end 6.558026 -140.392404)
		(width 0.4064)
		(layer "F.Cu")
		(net "GND")
	)
	(segment
		(start 208.866486 -212.380576)
		(end 208.999074 -212.513164)
		(width 0.4572)
		(layer "F.Cu")
		(net "GND")
	)
	(segment
		(start 89.680796 -25.990042)
		(end 88.664796 -25.990042)
		(width 0.3556)
		(layer "F.Cu")
		(net "GND")
	)
	(segment
		(start 187.624974 -299.224954)
		(end 188.099954 -298.74972)
		(width 0.249936)
		(layer "F.Cu")
		(net "GND")
	)
	(segment
		(start 172.424852 -300.174914)
		(end 171.949872 -299.699934)
		(width 0.249936)
		(layer "F.Cu")
		(net "GND")
	)
	(segment
		(start 409.849828 -306.349908)
		(end 409.374848 -305.874928)
		(width 0.249936)
		(layer "F.Cu")
		(net "GND")
	)
	(segment
		(start 68.280788 -27.79014)
		(end 67.264788 -27.79014)
		(width 0.3556)
		(layer "F.Cu")
		(net "GND")
	)
	(segment
		(start 72.267064 -123.635008)
		(end 73.257664 -123.635008)
		(width 0.3556)
		(layer "F.Cu")
		(net "GND")
	)
	(segment
		(start 173.375066 -306.824888)
		(end 172.900086 -307.299868)
		(width 0.249936)
		(layer "F.Cu")
		(net "GND")
	)
	(segment
		(start 138.961114 -37.201094)
		(end 138.198606 -37.201094)
		(width 0.4572)
		(layer "F.Cu")
		(net "GND")
	)
	(segment
		(start 13.625322 -119.505476)
		(end 13.625322 -120.11787)
		(width 0.4572)
		(layer "F.Cu")
		(net "GND")
	)
	(segment
		(start 162.974274 -122.355102)
		(end 162.14217 -122.355102)
		(width 0.3556)
		(layer "F.Cu")
		(net "GND")
	)
	(segment
		(start 128.834134 -138.267694)
		(end 128.834134 -138.819636)
		(width 0.254)
		(layer "F.Cu")
		(net "GND")
	)
	(segment
		(start 71.524876 -299.224954)
		(end 71.999856 -299.699934)
		(width 0.249936)
		(layer "F.Cu")
		(net "GND")
	)
	(segment
		(start 312.749692 -291.149786)
		(end 313.224926 -290.674806)
		(width 0.249936)
		(layer "F.Cu")
		(net "GND")
	)
	(segment
		(start 429.325024 -294.4749)
		(end 428.84979 -294.94988)
		(width 0.249936)
		(layer "F.Cu")
		(net "GND")
	)
	(segment
		(start 172.900086 -285.449772)
		(end 172.424852 -284.974792)
		(width 0.249936)
		(layer "F.Cu")
		(net "GND")
	)
	(segment
		(start 221.308676 -196.039486)
		(end 221.5769 -196.30771)
		(width 0.3048)
		(layer "F.Cu")
		(net "GND")
	)
	(segment
		(start 163.13277 -133.565138)
		(end 162.14217 -133.565138)
		(width 0.3556)
		(layer "F.Cu")
		(net "GND")
	)
	(segment
		(start 208.254346 -229.061518)
		(end 206.642716 -230.673148)
		(width 0.4572)
		(layer "F.Cu")
		(net "GND")
	)
	(segment
		(start 361.745784 -113.985802)
		(end 361.745784 -113.373408)
		(width 0.4572)
		(layer "F.Cu")
		(net "GND")
	)
	(segment
		(start 161.15157 -111.44504)
		(end 162.14217 -111.44504)
		(width 0.3556)
		(layer "F.Cu")
		(net "GND")
	)
	(segment
		(start 279.024842 -302.074834)
		(end 279.499822 -301.599854)
		(width 0.249936)
		(layer "F.Cu")
		(net "GND")
	)
	(segment
		(start 394.64996 -282.599892)
		(end 394.17498 -282.124912)
		(width 0.249936)
		(layer "F.Cu")
		(net "GND")
	)
	(segment
		(start 422.199816 -293.99992)
		(end 422.674796 -294.4749)
		(width 0.249936)
		(layer "F.Cu")
		(net "GND")
	)
	(segment
		(start 305.624738 -297.32478)
		(end 305.149758 -297.79976)
		(width 0.249936)
		(layer "F.Cu")
		(net "GND")
	)
	(segment
		(start 282.824936 -305.874928)
		(end 282.349702 -305.399948)
		(width 0.249936)
		(layer "F.Cu")
		(net "GND")
	)
	(segment
		(start 320.864738 -29.589984)
		(end 319.848738 -29.589984)
		(width 0.3556)
		(layer "F.Cu")
		(net "GND")
	)
	(segment
		(start 402.249894 -284.499812)
		(end 401.774914 -284.024832)
		(width 0.249936)
		(layer "F.Cu")
		(net "GND")
	)
	(segment
		(start 349.595694 -285.488634)
		(end 349.306896 -285.199836)
		(width 0.2286)
		(layer "F.Cu")
		(net "GND")
	)
	(segment
		(start 378.880624 -241.311176)
		(end 380.002288 -241.311176)
		(width 0.2794)
		(layer "F.Cu")
		(net "GND")
	)
	(segment
		(start 214.587582 -25.742392)
		(end 214.587582 -26.360882)
		(width 0.4572)
		(layer "F.Cu")
		(net "GND")
	)
	(segment
		(start 219.520262 -231.911906)
		(end 219.520262 -232.471468)
		(width 0.4572)
		(layer "F.Cu")
		(net "GND")
	)
	(segment
		(start 76.27493 -290.674806)
		(end 75.79995 -290.199826)
		(width 0.249936)
		(layer "F.Cu")
		(net "GND")
	)
	(segment
		(start 387.999986 -289.249866)
		(end 388.474966 -289.724846)
		(width 0.254)
		(layer "F.Cu")
		(net "GND")
	)
	(segment
		(start 220.851222 -143.942562)
		(end 220.241622 -143.942562)
		(width 0.4572)
		(layer "F.Cu")
		(net "GND")
	)
	(segment
		(start 63.283084 -381.838454)
		(end 62.927992 -381.483362)
		(width 0.4572)
		(layer "F.Cu")
		(net "GND")
	)
	(segment
		(start 212.522054 -201.716894)
		(end 213.741 -201.716894)
		(width 0.3556)
		(layer "F.Cu")
		(net "GND")
	)
	(segment
		(start 173.764194 -140.6398)
		(end 173.433994 -140.97)
		(width 0.4572)
		(layer "F.Cu")
		(net "GND")
	)
	(segment
		(start 304.467006 -125.435106)
		(end 305.457606 -125.435106)
		(width 0.3556)
		(layer "F.Cu")
		(net "GND")
	)
	(segment
		(start 78.667102 -57.332626)
		(end 78.667102 -56.354218)
		(width 0.4572)
		(layer "F.Cu")
		(net "GND")
	)
	(segment
		(start 178.124866 -285.924752)
		(end 177.649886 -285.449772)
		(width 0.249936)
		(layer "F.Cu")
		(net "GND")
	)
	(segment
		(start 47.29988 -295.89984)
		(end 46.34992 -295.89984)
		(width 0.254)
		(layer "F.Cu")
		(net "GND")
	)
	(segment
		(start 279.232106 -391.198608)
		(end 279.232106 -390.210294)
		(width 0.4318)
		(layer "F.Cu")
		(net "GND")
	)
	(segment
		(start 21.541232 -26.315162)
		(end 22.37232 -26.315162)
		(width 0.4572)
		(layer "F.Cu")
		(net "GND")
	)
	(segment
		(start 73.899776 -296.8498)
		(end 73.424796 -296.37482)
		(width 0.249936)
		(layer "F.Cu")
		(net "GND")
	)
	(segment
		(start 187.624974 -298.27474)
		(end 187.149994 -297.79976)
		(width 0.249936)
		(layer "F.Cu")
		(net "GND")
	)
	(segment
		(start 299.46473 -31.390082)
		(end 300.48073 -31.390082)
		(width 0.3556)
		(layer "F.Cu")
		(net "GND")
	)
	(segment
		(start 273.799808 -287.349946)
		(end 273.324828 -286.874966)
		(width 0.249936)
		(layer "F.Cu")
		(net "GND")
	)
	(segment
		(start 279.261062 -38.701218)
		(end 280.019506 -38.701218)
		(width 0.4572)
		(layer "F.Cu")
		(net "GND")
	)
	(segment
		(start 279.232868 -131.76504)
		(end 278.242268 -131.76504)
		(width 0.3556)
		(layer "F.Cu")
		(net "GND")
	)
	(segment
		(start 161.15157 -138.964924)
		(end 162.14217 -138.964924)
		(width 0.3556)
		(layer "F.Cu")
		(net "GND")
	)
	(segment
		(start 212.522054 -206.288894)
		(end 213.741 -206.288894)
		(width 0.3556)
		(layer "F.Cu")
		(net "GND")
	)
	(segment
		(start 393.351766 -129.964942)
		(end 394.342366 -129.964942)
		(width 0.3556)
		(layer "F.Cu")
		(net "GND")
	)
	(segment
		(start 246.988838 -119.520716)
		(end 246.988838 -120.130316)
		(width 0.4572)
		(layer "F.Cu")
		(net "GND")
	)
	(segment
		(start 180.02504 -302.074834)
		(end 179.55006 -301.599854)
		(width 0.249936)
		(layer "F.Cu")
		(net "GND")
	)
	(segment
		(start 307.524912 -296.37482)
		(end 307.999892 -295.89984)
		(width 0.249936)
		(layer "F.Cu")
		(net "GND")
	)
	(segment
		(start 172.900086 -306.349908)
		(end 173.375066 -305.874928)
		(width 0.249936)
		(layer "F.Cu")
		(net "GND")
	)
	(segment
		(start 325.464678 -33.19018)
		(end 326.480678 -33.19018)
		(width 0.3556)
		(layer "F.Cu")
		(net "GND")
	)
	(segment
		(start 112.495584 -161.172144)
		(end 112.661954 -161.005774)
		(width 0.254)
		(layer "F.Cu")
		(net "GND")
	)
	(segment
		(start 389.56488 -29.589984)
		(end 388.54888 -29.589984)
		(width 0.3556)
		(layer "F.Cu")
		(net "GND")
	)
	(segment
		(start 137.018776 -46.693836)
		(end 136.819386 -46.893226)
		(width 0.254)
		(layer "F.Cu")
		(net "GND")
	)
	(segment
		(start 400.349974 -307.299868)
		(end 399.874994 -306.824888)
		(width 0.249936)
		(layer "F.Cu")
		(net "GND")
	)
	(segment
		(start 71.977758 -135.320024)
		(end 72.452738 -134.845044)
		(width 0.3556)
		(layer "F.Cu")
		(net "GND")
	)
	(segment
		(start 284.249876 -296.8498)
		(end 283.774896 -297.32478)
		(width 0.249936)
		(layer "F.Cu")
		(net "GND")
	)
	(segment
		(start 442.071252 -120.041924)
		(end 441.48248 -120.041924)
		(width 0.254)
		(layer "F.Cu")
		(net "GND")
	)
	(segment
		(start 64.874902 -300.174914)
		(end 64.399922 -299.699934)
		(width 0.249936)
		(layer "F.Cu")
		(net "GND")
	)
	(segment
		(start 303.249838 -292.099746)
		(end 303.249838 -292.1)
		(width 0.249936)
		(layer "F.Cu")
		(net "GND")
	)
	(segment
		(start 271.424908 -296.37482)
		(end 271.899888 -295.89984)
		(width 0.249936)
		(layer "F.Cu")
		(net "GND")
	)
	(segment
		(start 406.834594 -38.937184)
		(end 407.100024 -38.671754)
		(width 0.4572)
		(layer "F.Cu")
		(net "GND")
	)
	(segment
		(start 82.449924 -293.99992)
		(end 81.974944 -293.52494)
		(width 0.249936)
		(layer "F.Cu")
		(net "GND")
	)
	(segment
		(start 269.999714 -275.949918)
		(end 269.524734 -275.474938)
		(width 0.249936)
		(layer "F.Cu")
		(net "GND")
	)
	(segment
		(start 410.799788 -301.599854)
		(end 411.275022 -302.074834)
		(width 0.249936)
		(layer "F.Cu")
		(net "GND")
	)
	(segment
		(start 47.146972 -52.592224)
		(end 47.222156 -52.51704)
		(width 0.254)
		(layer "F.Cu")
		(net "GND")
	)
	(segment
		(start 280.449782 -296.8498)
		(end 280.924762 -296.37482)
		(width 0.249936)
		(layer "F.Cu")
		(net "GND")
	)
	(segment
		(start 293.27475 -300.174914)
		(end 292.79977 -299.699934)
		(width 0.249936)
		(layer "F.Cu")
		(net "GND")
	)
	(segment
		(start 398.4498 -286.399732)
		(end 397.97482 -285.924752)
		(width 0.249936)
		(layer "F.Cu")
		(net "GND")
	)
	(segment
		(start 50.14976 -288.299906)
		(end 49.67478 -287.824926)
		(width 0.249936)
		(layer "F.Cu")
		(net "GND")
	)
	(segment
		(start 215.630506 -65.92189)
		(end 215.630506 -65.15989)
		(width 0.4572)
		(layer "F.Cu")
		(net "GND")
	)
	(segment
		(start 15.541244 -114.436652)
		(end 15.118588 -114.013996)
		(width 0.254)
		(layer "F.Cu")
		(net "GND")
	)
	(segment
		(start 52.524914 -291.624766)
		(end 52.049934 -292.099746)
		(width 0.249936)
		(layer "F.Cu")
		(net "GND")
	)
	(segment
		(start 49.346612 -110.857538)
		(end 49.934114 -111.44504)
		(width 0.3556)
		(layer "F.Cu")
		(net "GND")
	)
	(segment
		(start 409.374848 -285.924752)
		(end 409.849828 -285.449772)
		(width 0.249936)
		(layer "F.Cu")
		(net "GND")
	)
	(segment
		(start 172.900086 -288.299906)
		(end 173.375066 -287.824926)
		(width 0.249936)
		(layer "F.Cu")
		(net "GND")
	)
	(segment
		(start 56.799988 -285.449772)
		(end 57.274968 -285.924752)
		(width 0.249936)
		(layer "F.Cu")
		(net "GND")
	)
	(segment
		(start 99.903534 -242.987322)
		(end 100.430838 -242.987322)
		(width 0.254)
		(layer "F.Cu")
		(net "GND")
	)
	(segment
		(start 155.800044 -277.849838)
		(end 155.325064 -277.374858)
		(width 0.249936)
		(layer "F.Cu")
		(net "GND")
	)
	(segment
		(start 400.349974 -285.449772)
		(end 399.874994 -284.974792)
		(width 0.249936)
		(layer "F.Cu")
		(net "GND")
	)
	(segment
		(start 305.624738 -290.674806)
		(end 306.099718 -291.149786)
		(width 0.249936)
		(layer "F.Cu")
		(net "GND")
	)
	(segment
		(start 155.325064 -296.37482)
		(end 155.800044 -295.89984)
		(width 0.249936)
		(layer "F.Cu")
		(net "GND")
	)
	(segment
		(start 301.349918 -295.89984)
		(end 301.824898 -296.37482)
		(width 0.249936)
		(layer "F.Cu")
		(net "GND")
	)
	(segment
		(start 274.749768 -289.249866)
		(end 275.224748 -289.724846)
		(width 0.254)
		(layer "F.Cu")
		(net "GND")
	)
	(segment
		(start 258.86791 -56.353456)
		(end 259.52323 -56.353456)
		(width 0.254)
		(layer "F.Cu")
		(net "GND")
	)
	(segment
		(start 62.664848 -29.589984)
		(end 61.648848 -29.589984)
		(width 0.3556)
		(layer "F.Cu")
		(net "GND")
	)
	(segment
		(start 427.42485 -300.174914)
		(end 426.94987 -300.649894)
		(width 0.249936)
		(layer "F.Cu")
		(net "GND")
	)
	(segment
		(start 376.40895 -174.15002)
		(end 375.59234 -174.15002)
		(width 0.4572)
		(layer "F.Cu")
		(net "GND")
	)
	(segment
		(start 165.446456 -110.857538)
		(end 166.033958 -111.44504)
		(width 0.3556)
		(layer "F.Cu")
		(net "GND")
	)
	(segment
		(start 62.632082 -167.922702)
		(end 62.632082 -168.94556)
		(width 0.4572)
		(layer "F.Cu")
		(net "GND")
	)
	(segment
		(start 1.69926 -380.182628)
		(end 1.506982 -379.99035)
		(width 0.381)
		(layer "F.Cu")
		(net "GND")
	)
	(segment
		(start 4.781804 -59.957208)
		(end 4.715256 -60.601606)
		(width 0.4572)
		(layer "F.Cu")
		(net "GND")
	)
	(segment
		(start 58.224928 -284.974792)
		(end 57.749948 -284.499812)
		(width 0.249936)
		(layer "F.Cu")
		(net "GND")
	)
	(segment
		(start 164.349938 -306.349908)
		(end 163.874958 -305.874928)
		(width 0.249936)
		(layer "F.Cu")
		(net "GND")
	)
	(segment
		(start 69.680328 -156.554932)
		(end 68.65747 -156.554932)
		(width 0.3556)
		(layer "F.Cu")
		(net "GND")
	)
	(segment
		(start 48.391572 -100.64496)
		(end 50.64252 -100.64496)
		(width 0.3556)
		(layer "F.Cu")
		(net "GND")
	)
	(segment
		(start 436.55234 -113.661444)
		(end 436.55234 -114.384836)
		(width 0.4572)
		(layer "F.Cu")
		(net "GND")
	)
	(segment
		(start 185.783982 -122.200416)
		(end 185.418476 -121.83491)
		(width 0.3556)
		(layer "F.Cu")
		(net "GND")
	)
	(segment
		(start 303.724818 -297.32478)
		(end 303.249838 -297.79976)
		(width 0.249936)
		(layer "F.Cu")
		(net "GND")
	)
	(segment
		(start 279.499822 -288.299906)
		(end 279.024842 -287.824926)
		(width 0.249936)
		(layer "F.Cu")
		(net "GND")
	)
	(segment
		(start 170.524932 -305.874928)
		(end 170.049952 -305.399948)
		(width 0.249936)
		(layer "F.Cu")
		(net "GND")
	)
	(segment
		(start 183.766714 -143.955008)
		(end 184.757314 -143.955008)
		(width 0.3556)
		(layer "F.Cu")
		(net "GND")
	)
	(segment
		(start 294.69969 -290.199826)
		(end 295.174924 -289.724846)
		(width 0.249936)
		(layer "F.Cu")
		(net "GND")
	)
	(segment
		(start 300.399704 -292.099746)
		(end 300.874684 -292.574726)
		(width 0.249936)
		(layer "F.Cu")
		(net "GND")
	)
	(segment
		(start 428.84979 -294.94988)
		(end 428.37481 -294.4749)
		(width 0.249936)
		(layer "F.Cu")
		(net "GND")
	)
	(segment
		(start 287.574736 -300.174914)
		(end 287.099756 -299.699934)
		(width 0.249936)
		(layer "F.Cu")
		(net "GND")
	)
	(segment
		(start 350.77527 -64.102234)
		(end 350.069658 -64.102234)
		(width 0.4572)
		(layer "F.Cu")
		(net "GND")
	)
	(segment
		(start 38.274752 -296.37482)
		(end 38.749986 -295.89984)
		(width 0.249936)
		(layer "F.Cu")
		(net "GND")
	)
	(segment
		(start 335.145634 -88.564466)
		(end 334.575658 -88.564466)
		(width 0.1778)
		(layer "F.Cu")
		(net "GND")
	)
	(segment
		(start 173.375066 -284.974792)
		(end 173.850046 -285.449772)
		(width 0.249936)
		(layer "F.Cu")
		(net "GND")
	)
	(segment
		(start 414.548828 -29.589984)
		(end 415.564828 -29.589984)
		(width 0.3556)
		(layer "F.Cu")
		(net "GND")
	)
	(segment
		(start 158.649924 -285.449772)
		(end 159.124904 -284.974792)
		(width 0.249936)
		(layer "F.Cu")
		(net "GND")
	)
	(segment
		(start 398.925034 -303.974754)
		(end 399.400014 -303.499774)
		(width 0.249936)
		(layer "F.Cu")
		(net "GND")
	)
	(segment
		(start 16.702786 -111.739426)
		(end 16.702786 -111.127032)
		(width 0.4572)
		(layer "F.Cu")
		(net "GND")
	)
	(segment
		(start 300.399704 -293.04996)
		(end 300.874684 -292.574726)
		(width 0.249936)
		(layer "F.Cu")
		(net "GND")
	)
	(segment
		(start 281.874722 -306.824888)
		(end 281.399742 -307.299868)
		(width 0.249936)
		(layer "F.Cu")
		(net "GND")
	)
	(segment
		(start 417.930584 -118.370858)
		(end 417.794694 -118.234968)
		(width 0.3556)
		(layer "F.Cu")
		(net "GND")
	)
	(segment
		(start 66.396108 -25.990042)
		(end 66.214752 -26.171398)
		(width 0.3556)
		(layer "F.Cu")
		(net "GND")
	)
	(segment
		(start 66.774822 -285.924752)
		(end 67.249802 -285.449772)
		(width 0.249936)
		(layer "F.Cu")
		(net "GND")
	)
	(segment
		(start 184.77484 -293.52494)
		(end 184.29986 -293.04996)
		(width 0.249936)
		(layer "F.Cu")
		(net "GND")
	)
	(segment
		(start 303.249838 -301.599854)
		(end 302.774858 -301.124874)
		(width 0.249936)
		(layer "F.Cu")
		(net "GND")
	)
	(segment
		(start 347.442536 -258.78155)
		(end 347.442536 -258.14655)
		(width 0.381)
		(layer "F.Cu")
		(net "GND")
	)
	(segment
		(start 429.800004 -293.99992)
		(end 430.274984 -293.52494)
		(width 0.249936)
		(layer "F.Cu")
		(net "GND")
	)
	(segment
		(start 396.54988 -288.299906)
		(end 396.0749 -287.824926)
		(width 0.249936)
		(layer "F.Cu")
		(net "GND")
	)
	(segment
		(start 292.79977 -292.099746)
		(end 293.27475 -291.624766)
		(width 0.249936)
		(layer "F.Cu")
		(net "GND")
	)
	(segment
		(start 79.12481 -296.37482)
		(end 78.64983 -295.89984)
		(width 0.249936)
		(layer "F.Cu")
		(net "GND")
	)
	(segment
		(start 320.337942 -291.102034)
		(end 320.863976 -291.102034)
		(width 0.4572)
		(layer "F.Cu")
		(net "GND")
	)
	(segment
		(start 324.249542 -303.636426)
		(end 324.249542 -303.026826)
		(width 0.4572)
		(layer "F.Cu")
		(net "GND")
	)
	(segment
		(start 358.964992 -25.990042)
		(end 357.948992 -25.990042)
		(width 0.3556)
		(layer "F.Cu")
		(net "GND")
	)
	(segment
		(start 361.58805 -192.278)
		(end 362.204 -192.278)
		(width 0.4572)
		(layer "F.Cu")
		(net "GND")
	)
	(segment
		(start 283.774896 -289.724846)
		(end 284.249876 -290.199826)
		(width 0.249936)
		(layer "F.Cu")
		(net "GND")
	)
	(segment
		(start 185.725054 -305.874928)
		(end 185.250074 -305.399948)
		(width 0.249936)
		(layer "F.Cu")
		(net "GND")
	)
	(segment
		(start 69.149976 -306.349908)
		(end 69.624956 -305.874928)
		(width 0.249936)
		(layer "F.Cu")
		(net "GND")
	)
	(segment
		(start 310.849772 -302.549814)
		(end 311.324752 -302.074834)
		(width 0.249936)
		(layer "F.Cu")
		(net "GND")
	)
	(segment
		(start 310.843676 -45.88891)
		(end 311.514998 -45.88891)
		(width 0.254)
		(layer "F.Cu")
		(net "GND")
	)
	(segment
		(start 389.56488 -34.990024)
		(end 387.682994 -34.990024)
		(width 0.3556)
		(layer "F.Cu")
		(net "GND")
	)
	(segment
		(start 163.13277 -100.64496)
		(end 162.14217 -100.64496)
		(width 0.3556)
		(layer "F.Cu")
		(net "GND")
	)
	(segment
		(start 77.69987 -293.04996)
		(end 78.17485 -293.52494)
		(width 0.249936)
		(layer "F.Cu")
		(net "GND")
	)
	(segment
		(start 196.174868 -292.574726)
		(end 195.699888 -293.04996)
		(width 0.249936)
		(layer "F.Cu")
		(net "GND")
	)
	(segment
		(start 320.10604 -392.063732)
		(end 320.10604 -392.811)
		(width 0.4572)
		(layer "F.Cu")
		(net "GND")
	)
	(segment
		(start 387.050026 -293.99992)
		(end 386.575046 -293.52494)
		(width 0.249936)
		(layer "F.Cu")
		(net "GND")
	)
	(segment
		(start 173.850046 -290.199826)
		(end 173.375066 -289.724846)
		(width 0.249936)
		(layer "F.Cu")
		(net "GND")
	)
	(segment
		(start 399.93316 -140.765022)
		(end 398.94256 -140.765022)
		(width 0.3556)
		(layer "F.Cu")
		(net "GND")
	)
	(segment
		(start 168.150032 -299.699934)
		(end 167.675052 -300.174914)
		(width 0.249936)
		(layer "F.Cu")
		(net "GND")
	)
	(segment
		(start 162.924998 -302.074834)
		(end 162.450018 -302.549814)
		(width 0.249936)
		(layer "F.Cu")
		(net "GND")
	)
	(segment
		(start 78.17485 -299.224954)
		(end 78.64983 -298.74972)
		(width 0.249936)
		(layer "F.Cu")
		(net "GND")
	)
	(segment
		(start 49.803304 -120.555004)
		(end 50.64252 -120.555004)
		(width 0.3556)
		(layer "F.Cu")
		(net "GND")
	)
	(segment
		(start 457.94422 -110.28553)
		(end 458.0001 -110.22965)
		(width 0.254)
		(layer "F.Cu")
		(net "GND")
	)
	(segment
		(start 54.475126 -64.102234)
		(end 53.769514 -64.102234)
		(width 0.4572)
		(layer "F.Cu")
		(net "GND")
	)
	(segment
		(start 55.78856 -386.725668)
		(end 55.78856 -385.049268)
		(width 0.4572)
		(layer "F.Cu")
		(net "GND")
	)
	(segment
		(start 79.660496 -16.439388)
		(end 79.660496 -15.474188)
		(width 0.4572)
		(layer "F.Cu")
		(net "GND")
	)
	(segment
		(start 402.724874 -285.924752)
		(end 402.249894 -286.399732)
		(width 0.249936)
		(layer "F.Cu")
		(net "GND")
	)
	(segment
		(start 401.774914 -305.874928)
		(end 402.249894 -306.349908)
		(width 0.249936)
		(layer "F.Cu")
		(net "GND")
	)
	(segment
		(start 260.470904 -34.29762)
		(end 260.462522 -34.29762)
		(width 0.4572)
		(layer "F.Cu")
		(net "GND")
	)
	(segment
		(start 280.924762 -309.674768)
		(end 281.399742 -309.199788)
		(width 0.249936)
		(layer "F.Cu")
		(net "GND")
	)
	(segment
		(start 161.118042 -151.157432)
		(end 161.120582 -151.159972)
		(width 0.3556)
		(layer "F.Cu")
		(net "GND")
	)
	(segment
		(start 163.874958 -305.874928)
		(end 163.399978 -306.349908)
		(width 0.249936)
		(layer "F.Cu")
		(net "GND")
	)
	(segment
		(start 60.599828 -306.349908)
		(end 60.124848 -305.874928)
		(width 0.249936)
		(layer "F.Cu")
		(net "GND")
	)
	(segment
		(start 350.093788 -218.387168)
		(end 350.493584 -217.987372)
		(width 0.3556)
		(layer "F.Cu")
		(net "GND")
	)
	(segment
		(start 183.766714 -151.155146)
		(end 184.757314 -151.155146)
		(width 0.3556)
		(layer "F.Cu")
		(net "GND")
	)
	(segment
		(start 70.574916 -299.224954)
		(end 70.099936 -299.699934)
		(width 0.249936)
		(layer "F.Cu")
		(net "GND")
	)
	(segment
		(start 281.496262 -129.68351)
		(end 281.777694 -129.964942)
		(width 0.3556)
		(layer "F.Cu")
		(net "GND")
	)
	(segment
		(start 130.922776 -228.67493)
		(end 129.456942 -228.67493)
		(width 0.4572)
		(layer "F.Cu")
		(net "GND")
	)
	(segment
		(start 403.199854 -306.349908)
		(end 402.724874 -305.874928)
		(width 0.249936)
		(layer "F.Cu")
		(net "GND")
	)
	(segment
		(start 4.675886 -394.767308)
		(end 4.675886 -394.152628)
		(width 0.4572)
		(layer "F.Cu")
		(net "GND")
	)
	(segment
		(start 387.999986 -285.449772)
		(end 387.525006 -284.974792)
		(width 0.249936)
		(layer "F.Cu")
		(net "GND")
	)
	(segment
		(start 246.448834 -31.390082)
		(end 247.464834 -31.390082)
		(width 0.3556)
		(layer "F.Cu")
		(net "GND")
	)
	(segment
		(start 290.42487 -305.874928)
		(end 290.89985 -305.399948)
		(width 0.249936)
		(layer "F.Cu")
		(net "GND")
	)
	(segment
		(start 186.200034 -299.699934)
		(end 186.675014 -299.224954)
		(width 0.249936)
		(layer "F.Cu")
		(net "GND")
	)
	(segment
		(start 341.212932 -110.28553)
		(end 341.844122 -110.28553)
		(width 0.254)
		(layer "F.Cu")
		(net "GND")
	)
	(segment
		(start 189.999874 -297.79976)
		(end 190.474854 -298.27474)
		(width 0.249936)
		(layer "F.Cu")
		(net "GND")
	)
	(segment
		(start 413.649922 -285.449772)
		(end 414.124902 -285.924752)
		(width 0.249936)
		(layer "F.Cu")
		(net "GND")
	)
	(segment
		(start 196.38264 -28.875736)
		(end 196.38264 -28.47848)
		(width 0.254)
		(layer "F.Cu")
		(net "GND")
	)
	(segment
		(start 56.799988 -290.199826)
		(end 56.324754 -289.724846)
		(width 0.249936)
		(layer "F.Cu")
		(net "GND")
	)
	(segment
		(start 298.499784 -292.099746)
		(end 298.974764 -291.624766)
		(width 0.249936)
		(layer "F.Cu")
		(net "GND")
	)
	(segment
		(start 58.534554 -38.937184)
		(end 58.799984 -38.671754)
		(width 0.4572)
		(layer "F.Cu")
		(net "GND")
	)
	(segment
		(start 172.900086 -295.89984)
		(end 172.425106 -296.37482)
		(width 0.249936)
		(layer "F.Cu")
		(net "GND")
	)
	(segment
		(start 118.358412 -124.883926)
		(end 119.013732 -124.883926)
		(width 0.381)
		(layer "F.Cu")
		(net "GND")
	)
	(segment
		(start 47.032926 -129.964942)
		(end 46.042326 -129.964942)
		(width 0.3556)
		(layer "F.Cu")
		(net "GND")
	)
	(segment
		(start 42.549826 -274.999958)
		(end 42.074846 -274.524978)
		(width 0.249936)
		(layer "F.Cu")
		(net "GND")
	)
	(segment
		(start 52.999894 -306.349908)
		(end 53.474874 -306.824888)
		(width 0.249936)
		(layer "F.Cu")
		(net "GND")
	)
	(segment
		(start 273.799808 -299.699934)
		(end 273.324828 -300.174914)
		(width 0.249936)
		(layer "F.Cu")
		(net "GND")
	)
	(segment
		(start 58.224928 -300.174914)
		(end 58.699908 -299.699934)
		(width 0.249936)
		(layer "F.Cu")
		(net "GND")
	)
	(segment
		(start 446.131188 -416.021266)
		(end 446.131188 -416.636962)
		(width 0.4572)
		(layer "F.Cu")
		(net "GND")
	)
	(segment
		(start 404.861268 -365.001556)
		(end 405.69515 -365.001556)
		(width 0.3048)
		(layer "F.Cu")
		(net "GND")
	)
	(segment
		(start 287.574736 -285.924752)
		(end 287.099756 -286.399732)
		(width 0.249936)
		(layer "F.Cu")
		(net "GND")
	)
	(segment
		(start 399.362422 -23.355554)
		(end 400.012154 -23.355554)
		(width 0.4572)
		(layer "F.Cu")
		(net "GND")
	)
	(segment
		(start 303.724818 -292.574726)
		(end 303.249838 -292.099746)
		(width 0.249936)
		(layer "F.Cu")
		(net "GND")
	)
	(segment
		(start 37.325046 -296.37482)
		(end 36.849812 -296.8498)
		(width 0.249936)
		(layer "F.Cu")
		(net "GND")
	)
	(segment
		(start 45.051726 -135.364982)
		(end 46.042326 -135.364982)
		(width 0.3556)
		(layer "F.Cu")
		(net "GND")
	)
	(segment
		(start 270.949928 -289.249866)
		(end 270.474948 -288.774886)
		(width 0.249936)
		(layer "F.Cu")
		(net "GND")
	)
	(segment
		(start 90.039444 -96.411542)
		(end 90.039444 -95.801942)
		(width 0.381)
		(layer "F.Cu")
		(net "GND")
	)
	(segment
		(start 117.644926 -282.021534)
		(end 117.260116 -282.406344)
		(width 0.254)
		(layer "F.Cu")
		(net "GND")
	)
	(segment
		(start 51.63312 -152.96007)
		(end 50.64252 -152.96007)
		(width 0.3556)
		(layer "F.Cu")
		(net "GND")
	)
	(segment
		(start 53.840126 -33.248092)
		(end 53.840126 -33.857692)
		(width 0.4572)
		(layer "F.Cu")
		(net "GND")
	)
	(segment
		(start 190.950088 -292.099746)
		(end 191.425068 -292.574726)
		(width 0.249936)
		(layer "F.Cu")
		(net "GND")
	)
	(segment
		(start 178.124866 -305.874928)
		(end 177.649886 -305.399948)
		(width 0.249936)
		(layer "F.Cu")
		(net "GND")
	)
	(segment
		(start 231.46766 -219.904056)
		(end 231.867456 -220.303852)
		(width 0.381)
		(layer "F.Cu")
		(net "GND")
	)
	(segment
		(start 169.574972 -285.924752)
		(end 170.049952 -286.399732)
		(width 0.249936)
		(layer "F.Cu")
		(net "GND")
	)
	(segment
		(start 188.366908 -145.755106)
		(end 189.357508 -145.755106)
		(width 0.3556)
		(layer "F.Cu")
		(net "GND")
	)
	(segment
		(start 32.31769 -113.158524)
		(end 22.925278 -113.158524)
		(width 0.4572)
		(layer "F.Cu")
		(net "GND")
	)
	(segment
		(start 352.719894 -146.606768)
		(end 353.335844 -146.606768)
		(width 0.4572)
		(layer "F.Cu")
		(net "GND")
	)
	(segment
		(start 161.500058 -293.99992)
		(end 161.975038 -294.4749)
		(width 0.249936)
		(layer "F.Cu")
		(net "GND")
	)
	(segment
		(start 17.599914 -265.719052)
		(end 17.599914 -266.892024)
		(width 0.254)
		(layer "F.Cu")
		(net "GND")
	)
	(segment
		(start 415.549842 -290.199826)
		(end 416.024822 -289.724846)
		(width 0.249936)
		(layer "F.Cu")
		(net "GND")
	)
	(segment
		(start 37.799772 -298.74972)
		(end 38.274752 -298.27474)
		(width 0.249936)
		(layer "F.Cu")
		(net "GND")
	)
	(segment
		(start 306.099718 -294.94988)
		(end 306.574698 -294.4749)
		(width 0.249936)
		(layer "F.Cu")
		(net "GND")
	)
	(segment
		(start 169.574972 -289.724846)
		(end 169.099992 -290.199826)
		(width 0.249936)
		(layer "F.Cu")
		(net "GND")
	)
	(segment
		(start 125.398022 -284.42412)
		(end 125.030738 -284.42412)
		(width 0.2286)
		(layer "F.Cu")
		(net "GND")
	)
	(segment
		(start 419.824916 -302.074834)
		(end 420.299896 -302.549814)
		(width 0.249936)
		(layer "F.Cu")
		(net "GND")
	)
	(segment
		(start 172.900086 -306.349908)
		(end 173.375066 -306.824888)
		(width 0.249936)
		(layer "F.Cu")
		(net "GND")
	)
	(segment
		(start 304.776632 -154.755088)
		(end 305.457606 -154.755088)
		(width 0.3556)
		(layer "F.Cu")
		(net "GND")
	)
	(segment
		(start 301.824898 -292.574726)
		(end 301.349918 -292.099746)
		(width 0.249936)
		(layer "F.Cu")
		(net "GND")
	)
	(segment
		(start 143.9164 -392.4808)
		(end 144.46504 -393.02944)
		(width 0.4572)
		(layer "F.Cu")
		(net "GND")
	)
	(segment
		(start 280.591514 -100.64496)
		(end 282.842462 -100.64496)
		(width 0.3556)
		(layer "F.Cu")
		(net "GND")
	)
	(segment
		(start 156.750004 -274.999958)
		(end 156.275024 -274.524978)
		(width 0.249936)
		(layer "F.Cu")
		(net "GND")
	)
	(segment
		(start 402.685504 -34.183066)
		(end 402.57095 -34.29762)
		(width 0.4572)
		(layer "F.Cu")
		(net "GND")
	)
	(segment
		(start 386.855462 -232.836212)
		(end 386.855462 -231.714548)
		(width 0.2794)
		(layer "F.Cu")
		(net "GND")
	)
	(segment
		(start 395.759178 -165.902894)
		(end 396.62989 -165.902894)
		(width 0.381)
		(layer "F.Cu")
		(net "GND")
	)
	(segment
		(start 67.724782 -303.974754)
		(end 68.199762 -304.449734)
		(width 0.249936)
		(layer "F.Cu")
		(net "GND")
	)
	(segment
		(start 376.582686 -28.47848)
		(end 376.243342 -28.139136)
		(width 0.254)
		(layer "F.Cu")
		(net "GND")
	)
	(segment
		(start 55.357776 -26.606246)
		(end 55.357776 -25.971246)
		(width 0.4572)
		(layer "F.Cu")
		(net "GND")
	)
	(segment
		(start 412.224982 -284.974792)
		(end 412.699962 -284.499812)
		(width 0.249936)
		(layer "F.Cu")
		(net "GND")
	)
	(segment
		(start 402.249894 -288.299906)
		(end 402.724874 -287.824926)
		(width 0.249936)
		(layer "F.Cu")
		(net "GND")
	)
	(segment
		(start 279.974802 -307.774848)
		(end 279.499822 -308.249828)
		(width 0.249936)
		(layer "F.Cu")
		(net "GND")
	)
	(segment
		(start 55.849774 -303.499774)
		(end 55.374794 -303.974754)
		(width 0.249936)
		(layer "F.Cu")
		(net "GND")
	)
	(segment
		(start 67.66687 -116.435124)
		(end 68.65747 -116.435124)
		(width 0.3556)
		(layer "F.Cu")
		(net "GND")
	)
	(segment
		(start 314.02655 -82.022696)
		(end 313.4614 -82.022696)
		(width 0.4064)
		(layer "F.Cu")
		(net "GND")
	)
	(segment
		(start 157.699964 -293.99992)
		(end 157.224984 -293.52494)
		(width 0.249936)
		(layer "F.Cu")
		(net "GND")
	)
	(segment
		(start 402.249894 -299.699934)
		(end 401.774914 -300.174914)
		(width 0.249936)
		(layer "F.Cu")
		(net "GND")
	)
	(segment
		(start 420.58336 -154.461718)
		(end 420.87673 -154.755088)
		(width 0.3556)
		(layer "F.Cu")
		(net "GND")
	)
	(segment
		(start 358.01046 -123.947428)
		(end 357.35514 -123.947428)
		(width 0.4064)
		(layer "F.Cu")
		(net "GND")
	)
	(segment
		(start 46.042326 -137.16508)
		(end 45.051726 -137.16508)
		(width 0.3556)
		(layer "F.Cu")
		(net "GND")
	)
	(segment
		(start 213.598506 -65.92189)
		(end 213.598506 -65.15989)
		(width 0.4572)
		(layer "F.Cu")
		(net "GND")
	)
	(segment
		(start 46.8249 -303.024794)
		(end 46.34992 -303.499774)
		(width 0.249936)
		(layer "F.Cu")
		(net "GND")
	)
	(segment
		(start 208.348834 -33.19018)
		(end 209.364834 -33.19018)
		(width 0.3556)
		(layer "F.Cu")
		(net "GND")
	)
	(segment
		(start 266.275312 -205.274164)
		(end 266.394184 -205.274164)
		(width 0.4572)
		(layer "F.Cu")
		(net "GND")
	)
	(segment
		(start 425.04995 -294.94988)
		(end 424.57497 -294.4749)
		(width 0.249936)
		(layer "F.Cu")
		(net "GND")
	)
	(segment
		(start 57.749948 -284.499812)
		(end 58.224928 -284.024832)
		(width 0.249936)
		(layer "F.Cu")
		(net "GND")
	)
	(segment
		(start 49.67478 -305.874928)
		(end 50.14976 -306.349908)
		(width 0.249936)
		(layer "F.Cu")
		(net "GND")
	)
	(segment
		(start 416.024822 -289.724846)
		(end 416.499802 -290.199826)
		(width 0.249936)
		(layer "F.Cu")
		(net "GND")
	)
	(segment
		(start 281.874722 -307.774848)
		(end 282.349702 -307.299868)
		(width 0.249936)
		(layer "F.Cu")
		(net "GND")
	)
	(segment
		(start 283.833062 -109.644942)
		(end 282.842462 -109.644942)
		(width 0.3556)
		(layer "F.Cu")
		(net "GND")
	)
	(segment
		(start 173.850046 -299.699934)
		(end 173.375066 -300.174914)
		(width 0.249936)
		(layer "F.Cu")
		(net "GND")
	)
	(segment
		(start 178.599846 -305.399948)
		(end 178.124866 -305.874928)
		(width 0.249936)
		(layer "F.Cu")
		(net "GND")
	)
	(segment
		(start 385.149852 -298.74972)
		(end 385.149852 -298.749466)
		(width 0.249936)
		(layer "F.Cu")
		(net "GND")
	)
	(segment
		(start 376.136154 -34.732468)
		(end 375.895362 -34.732468)
		(width 0.4572)
		(layer "F.Cu")
		(net "GND")
	)
	(segment
		(start 181.92496 -306.824888)
		(end 182.39994 -307.299868)
		(width 0.249936)
		(layer "F.Cu")
		(net "GND")
	)
	(segment
		(start 51.35753 -29.784294)
		(end 51.464464 -29.67736)
		(width 0.4572)
		(layer "F.Cu")
		(net "GND")
	)
	(segment
		(start 406.524968 -296.37482)
		(end 406.049988 -296.8498)
		(width 0.249936)
		(layer "F.Cu")
		(net "GND")
	)
	(segment
		(start 363.07395 -207.899)
		(end 362.458 -207.899)
		(width 0.4572)
		(layer "F.Cu")
		(net "GND")
	)
	(segment
		(start 268.9352 -79.892906)
		(end 273.589242 -79.892906)
		(width 0.4572)
		(layer "F.Cu")
		(net "GND")
	)
	(segment
		(start 399.93316 -138.964924)
		(end 398.94256 -138.964924)
		(width 0.3556)
		(layer "F.Cu")
		(net "GND")
	)
	(segment
		(start 109.70006 -110.22965)
		(end 110.165896 -110.22965)
		(width 0.254)
		(layer "F.Cu")
		(net "GND")
	)
	(segment
		(start 168.150032 -301.599854)
		(end 167.675052 -302.074834)
		(width 0.249936)
		(layer "F.Cu")
		(net "GND")
	)
	(segment
		(start 395.12494 -303.024794)
		(end 395.59992 -302.549814)
		(width 0.249936)
		(layer "F.Cu")
		(net "GND")
	)
	(segment
		(start 424.57497 -303.024794)
		(end 424.09999 -303.499774)
		(width 0.249936)
		(layer "F.Cu")
		(net "GND")
	)
	(segment
		(start 301.349918 -307.299868)
		(end 301.824898 -306.824888)
		(width 0.249936)
		(layer "F.Cu")
		(net "GND")
	)
	(segment
		(start 422.674796 -296.37482)
		(end 423.15003 -295.89984)
		(width 0.249936)
		(layer "F.Cu")
		(net "GND")
	)
	(segment
		(start 325.612506 -197.250304)
		(end 325.002906 -197.250304)
		(width 0.4572)
		(layer "F.Cu")
		(net "GND")
	)
	(segment
		(start 417.618672 -120.035066)
		(end 416.95751 -120.035066)
		(width 0.3556)
		(layer "F.Cu")
		(net "GND")
	)
	(segment
		(start 41.599866 -285.449772)
		(end 41.124886 -285.924752)
		(width 0.249936)
		(layer "F.Cu")
		(net "GND")
	)
	(segment
		(start 410.324808 -289.724846)
		(end 409.849828 -290.199826)
		(width 0.249936)
		(layer "F.Cu")
		(net "GND")
	)
	(segment
		(start 181.44998 -306.349908)
		(end 181.92496 -305.874928)
		(width 0.249936)
		(layer "F.Cu")
		(net "GND")
	)
	(segment
		(start 341.68461 -282.021534)
		(end 341.2998 -282.406344)
		(width 0.254)
		(layer "F.Cu")
		(net "GND")
	)
	(segment
		(start 277.251668 -125.955044)
		(end 278.242268 -125.955044)
		(width 0.3556)
		(layer "F.Cu")
		(net "GND")
	)
	(segment
		(start 54.899814 -283.549852)
		(end 55.374794 -284.024832)
		(width 0.249936)
		(layer "F.Cu")
		(net "GND")
	)
	(segment
		(start 40.649906 -282.599892)
		(end 40.174926 -282.124912)
		(width 0.249936)
		(layer "F.Cu")
		(net "GND")
	)
	(segment
		(start 404.149814 -307.299868)
		(end 403.674834 -306.824888)
		(width 0.249936)
		(layer "F.Cu")
		(net "GND")
	)
	(segment
		(start 229.437438 -62.399926)
		(end 228.308154 -62.399926)
		(width 0.3556)
		(layer "F.Cu")
		(net "GND")
	)
	(segment
		(start 391.799826 -284.499812)
		(end 391.324846 -284.024832)
		(width 0.249936)
		(layer "F.Cu")
		(net "GND")
	)
	(segment
		(start 296.599864 -306.349908)
		(end 296.124884 -306.824888)
		(width 0.249936)
		(layer "F.Cu")
		(net "GND")
	)
	(segment
		(start 420.567104 -120.035066)
		(end 421.557704 -120.035066)
		(width 0.3556)
		(layer "F.Cu")
		(net "GND")
	)
	(segment
		(start 314.573666 -26.606246)
		(end 314.573666 -25.971246)
		(width 0.4572)
		(layer "F.Cu")
		(net "GND")
	)
	(segment
		(start 68.674742 -298.27474)
		(end 68.199762 -298.74972)
		(width 0.249936)
		(layer "F.Cu")
		(net "GND")
	)
	(segment
		(start 330.05014 -94.863666)
		(end 330.05014 -94.227904)
		(width 0.4064)
		(layer "F.Cu")
		(net "GND")
	)
	(segment
		(start 168.52519 -14.735302)
		(end 169.035222 -14.735302)
		(width 0.381)
		(layer "F.Cu")
		(net "GND")
	)
	(segment
		(start 271.899888 -287.349946)
		(end 271.424908 -286.874966)
		(width 0.249936)
		(layer "F.Cu")
		(net "GND")
	)
	(segment
		(start 185.250074 -306.349908)
		(end 185.725054 -305.874928)
		(width 0.249936)
		(layer "F.Cu")
		(net "GND")
	)
	(segment
		(start 292.79977 -307.299868)
		(end 293.27475 -306.824888)
		(width 0.249936)
		(layer "F.Cu")
		(net "GND")
	)
	(segment
		(start 281.060906 -37.201094)
		(end 280.298398 -37.201094)
		(width 0.4572)
		(layer "F.Cu")
		(net "GND")
	)
	(segment
		(start 425.52493 -297.32478)
		(end 425.99991 -296.8498)
		(width 0.249936)
		(layer "F.Cu")
		(net "GND")
	)
	(segment
		(start 60.467748 -232.2068)
		(end 68.5546 -232.2068)
		(width 0.4572)
		(layer "F.Cu")
		(net "GND")
	)
	(segment
		(start 386.574792 -298.27474)
		(end 387.050026 -297.79976)
		(width 0.249936)
		(layer "F.Cu")
		(net "GND")
	)
	(segment
		(start 36.6649 -29.589984)
		(end 35.6489 -29.589984)
		(width 0.3556)
		(layer "F.Cu")
		(net "GND")
	)
	(segment
		(start 328.031094 -100.468176)
		(end 327.95591 -100.392992)
		(width 0.254)
		(layer "F.Cu")
		(net "GND")
	)
	(segment
		(start 163.399978 -303.499774)
		(end 162.924998 -303.974754)
		(width 0.249936)
		(layer "F.Cu")
		(net "GND")
	)
	(segment
		(start 5.963666 -74.322432)
		(end 5.963666 -75.087226)
		(width 0.4572)
		(layer "F.Cu")
		(net "GND")
	)
	(segment
		(start 304.674778 -300.174914)
		(end 304.199798 -300.649894)
		(width 0.249936)
		(layer "F.Cu")
		(net "GND")
	)
	(segment
		(start 48.72482 -305.874928)
		(end 48.24984 -305.399948)
		(width 0.249936)
		(layer "F.Cu")
		(net "GND")
	)
	(segment
		(start 329.69835 -65.92189)
		(end 329.69835 -65.15989)
		(width 0.4572)
		(layer "F.Cu")
		(net "GND")
	)
	(segment
		(start 253.708408 -257.852164)
		(end 253.9238 -258.067556)
		(width 0.4572)
		(layer "F.Cu")
		(net "GND")
	)
	(segment
		(start 47.4726 -113.245138)
		(end 46.042326 -113.245138)
		(width 0.3556)
		(layer "F.Cu")
		(net "GND")
	)
	(segment
		(start 38.749986 -283.549852)
		(end 38.275006 -283.074872)
		(width 0.249936)
		(layer "F.Cu")
		(net "GND")
	)
	(segment
		(start 177.174906 -303.974754)
		(end 177.649886 -303.499774)
		(width 0.249936)
		(layer "F.Cu")
		(net "GND")
	)
	(segment
		(start 187.149994 -296.8498)
		(end 187.624974 -297.32478)
		(width 0.249936)
		(layer "F.Cu")
		(net "GND")
	)
	(segment
		(start 418.124132 -130.710432)
		(end 417.589462 -131.245102)
		(width 0.3556)
		(layer "F.Cu")
		(net "GND")
	)
	(segment
		(start 279.024842 -305.874928)
		(end 279.499822 -306.349908)
		(width 0.249936)
		(layer "F.Cu")
		(net "GND")
	)
	(segment
		(start 201.06894 -405.495252)
		(end 201.06894 -404.801832)
		(width 0.4572)
		(layer "F.Cu")
		(net "GND")
	)
	(segment
		(start 82.266028 -77.889608)
		(end 82.266028 -77.175106)
		(width 0.4572)
		(layer "F.Cu")
		(net "GND")
	)
	(segment
		(start 330.016358 -238.976408)
		(end 329.71486 -238.976408)
		(width 0.4572)
		(layer "F.Cu")
		(net "GND")
	)
	(segment
		(start 37.799772 -275.949918)
		(end 37.324792 -275.474938)
		(width 0.249936)
		(layer "F.Cu")
		(net "GND")
	)
	(segment
		(start 393.351766 -138.964924)
		(end 394.342366 -138.964924)
		(width 0.3556)
		(layer "F.Cu")
		(net "GND")
	)
	(segment
		(start 385.149852 -298.749466)
		(end 385.624578 -298.27474)
		(width 0.249936)
		(layer "F.Cu")
		(net "GND")
	)
	(segment
		(start 174.325026 -289.724846)
		(end 174.800006 -290.199826)
		(width 0.249936)
		(layer "F.Cu")
		(net "GND")
	)
	(segment
		(start 222.195898 -103.85679)
		(end 221.643956 -103.85679)
		(width 0.254)
		(layer "F.Cu")
		(net "GND")
	)
	(segment
		(start 53.949854 -301.599854)
		(end 54.424834 -302.074834)
		(width 0.249936)
		(layer "F.Cu")
		(net "GND")
	)
	(segment
		(start 46.918626 -46.693836)
		(end 46.719236 -46.893226)
		(width 0.254)
		(layer "F.Cu")
		(net "GND")
	)
	(segment
		(start 208.999074 -212.513164)
		(end 209.733134 -212.513164)
		(width 0.4572)
		(layer "F.Cu")
		(net "GND")
	)
	(segment
		(start 210.03895 -203.835)
		(end 210.03895 -204.47)
		(width 0.4572)
		(layer "F.Cu")
		(net "GND")
	)
	(segment
		(start 37.799772 -298.74972)
		(end 38.274752 -299.224954)
		(width 0.249936)
		(layer "F.Cu")
		(net "GND")
	)
	(segment
		(start 244.256052 -33.19018)
		(end 242.864894 -33.19018)
		(width 0.3556)
		(layer "F.Cu")
		(net "GND")
	)
	(segment
		(start 287.099756 -299.699934)
		(end 286.624776 -300.174914)
		(width 0.249936)
		(layer "F.Cu")
		(net "GND")
	)
	(segment
		(start 184.380886 -25.990042)
		(end 183.364886 -25.990042)
		(width 0.3556)
		(layer "F.Cu")
		(net "GND")
	)
	(segment
		(start 52.999894 -297.79976)
		(end 52.524914 -298.27474)
		(width 0.249936)
		(layer "F.Cu")
		(net "GND")
	)
	(segment
		(start 167.675052 -306.824888)
		(end 167.200072 -307.299868)
		(width 0.249936)
		(layer "F.Cu")
		(net "GND")
	)
	(segment
		(start 77.353922 -84.332318)
		(end 76.693522 -84.332318)
		(width 0.4064)
		(layer "F.Cu")
		(net "GND")
	)
	(segment
		(start 422.199816 -303.499774)
		(end 421.724836 -303.024794)
		(width 0.249936)
		(layer "F.Cu")
		(net "GND")
	)
	(segment
		(start 399.874994 -297.32478)
		(end 399.400014 -297.79976)
		(width 0.249936)
		(layer "F.Cu")
		(net "GND")
	)
	(segment
		(start 167.732964 -98.845116)
		(end 166.742364 -98.845116)
		(width 0.3556)
		(layer "F.Cu")
		(net "GND")
	)
	(segment
		(start 396.0749 -303.024794)
		(end 395.59992 -303.499774)
		(width 0.249936)
		(layer "F.Cu")
		(net "GND")
	)
	(segment
		(start 399.400014 -306.349908)
		(end 398.925034 -305.874928)
		(width 0.249936)
		(layer "F.Cu")
		(net "GND")
	)
	(segment
		(start 55.849774 -303.499774)
		(end 56.324754 -303.974754)
		(width 0.249936)
		(layer "F.Cu")
		(net "GND")
	)
	(segment
		(start 415.96691 -134.845044)
		(end 416.95751 -134.845044)
		(width 0.3556)
		(layer "F.Cu")
		(net "GND")
	)
	(segment
		(start 153.89987 -290.199826)
		(end 153.42489 -289.724846)
		(width 0.249936)
		(layer "F.Cu")
		(net "GND")
	)
	(segment
		(start 14.248892 -31.390082)
		(end 15.264892 -31.390082)
		(width 0.3556)
		(layer "F.Cu")
		(net "GND")
	)
	(segment
		(start 416.024822 -302.074834)
		(end 416.499802 -302.549814)
		(width 0.249936)
		(layer "F.Cu")
		(net "GND")
	)
	(segment
		(start 72.267064 -121.83491)
		(end 73.257664 -121.83491)
		(width 0.3556)
		(layer "F.Cu")
		(net "GND")
	)
	(segment
		(start 163.572444 -113.245138)
		(end 162.14217 -113.245138)
		(width 0.3556)
		(layer "F.Cu")
		(net "GND")
	)
	(segment
		(start 314.174886 -296.37482)
		(end 313.699906 -295.89984)
		(width 0.249936)
		(layer "F.Cu")
		(net "GND")
	)
	(segment
		(start 281.874722 -303.974754)
		(end 282.349702 -304.449734)
		(width 0.249936)
		(layer "F.Cu")
		(net "GND")
	)
	(segment
		(start 74.84999 -292.099746)
		(end 75.32497 -292.574726)
		(width 0.249936)
		(layer "F.Cu")
		(net "GND")
	)
	(segment
		(start 67.724782 -302.074834)
		(end 68.199762 -302.549814)
		(width 0.249936)
		(layer "F.Cu")
		(net "GND")
	)
	(segment
		(start 46.8249 -303.974754)
		(end 46.34992 -303.499774)
		(width 0.249936)
		(layer "F.Cu")
		(net "GND")
	)
	(segment
		(start 72.267064 -118.234968)
		(end 73.257664 -118.234968)
		(width 0.3556)
		(layer "F.Cu")
		(net "GND")
	)
	(segment
		(start 353.29495 -171.45)
		(end 352.657156 -171.45)
		(width 0.4572)
		(layer "F.Cu")
		(net "GND")
	)
	(segment
		(start 171.474892 -306.824888)
		(end 170.999912 -306.349908)
		(width 0.249936)
		(layer "F.Cu")
		(net "GND")
	)
	(segment
		(start 415.564828 -31.390082)
		(end 416.580828 -31.390082)
		(width 0.3556)
		(layer "F.Cu")
		(net "GND")
	)
	(segment
		(start 58.699908 -297.79976)
		(end 58.224928 -298.27474)
		(width 0.249936)
		(layer "F.Cu")
		(net "GND")
	)
	(segment
		(start 394.17498 -296.37482)
		(end 394.64996 -296.8498)
		(width 0.249936)
		(layer "F.Cu")
		(net "GND")
	)
	(segment
		(start 290.999926 -38.671754)
		(end 290.999926 -38.315138)
		(width 0.4572)
		(layer "F.Cu")
		(net "GND")
	)
	(segment
		(start 70.574916 -307.774848)
		(end 70.099936 -307.299868)
		(width 0.249936)
		(layer "F.Cu")
		(net "GND")
	)
	(segment
		(start 282.349702 -303.499774)
		(end 281.874722 -303.974754)
		(width 0.249936)
		(layer "F.Cu")
		(net "GND")
	)
	(segment
		(start 294.69969 -301.599854)
		(end 295.174924 -302.074834)
		(width 0.249936)
		(layer "F.Cu")
		(net "GND")
	)
	(segment
		(start 51.574954 -300.174914)
		(end 51.099974 -299.699934)
		(width 0.249936)
		(layer "F.Cu")
		(net "GND")
	)
	(segment
		(start 2.781808 -375.757694)
		(end 3.455924 -375.083578)
		(width 0.381)
		(layer "F.Cu")
		(net "GND")
	)
	(segment
		(start 449.623942 -27.411934)
		(end 449.623942 -26.319734)
		(width 0.4572)
		(layer "F.Cu")
		(net "GND")
	)
	(segment
		(start 285.98495 -83.566)
		(end 285.369 -83.566)
		(width 0.4572)
		(layer "F.Cu")
		(net "GND")
	)
	(segment
		(start 376.775218 -64.102234)
		(end 376.069606 -64.102234)
		(width 0.4572)
		(layer "F.Cu")
		(net "GND")
	)
	(segment
		(start 17.604486 -269.429992)
		(end 17.620742 -269.446248)
		(width 0.254)
		(layer "F.Cu")
		(net "GND")
	)
	(segment
		(start 147.515834 -309.287672)
		(end 146.887692 -308.65953)
		(width 0.4572)
		(layer "F.Cu")
		(net "GND")
	)
	(segment
		(start 400.349974 -303.499774)
		(end 400.824954 -303.974754)
		(width 0.249936)
		(layer "F.Cu")
		(net "GND")
	)
	(segment
		(start 183.82488 -285.924752)
		(end 184.29986 -286.399732)
		(width 0.249936)
		(layer "F.Cu")
		(net "GND")
	)
	(segment
		(start 349.845122 -282.021534)
		(end 349.460312 -282.406344)
		(width 0.254)
		(layer "F.Cu")
		(net "GND")
	)
	(segment
		(start 408.899868 -301.599854)
		(end 408.424888 -302.074834)
		(width 0.249936)
		(layer "F.Cu")
		(net "GND")
	)
	(segment
		(start 13.805154 -376.125232)
		(end 14.52499 -376.125232)
		(width 0.4572)
		(layer "F.Cu")
		(net "GND")
	)
	(segment
		(start 287.099756 -292.099746)
		(end 286.624776 -291.624766)
		(width 0.249936)
		(layer "F.Cu")
		(net "GND")
	)
	(segment
		(start 192.900808 -410.696918)
		(end 192.114932 -410.696918)
		(width 0.4572)
		(layer "F.Cu")
		(net "GND")
	)
	(segment
		(start 305.624738 -293.52494)
		(end 305.149758 -293.99992)
		(width 0.249936)
		(layer "F.Cu")
		(net "GND")
	)
	(segment
		(start 197.125082 -292.574726)
		(end 196.649848 -293.04996)
		(width 0.249936)
		(layer "F.Cu")
		(net "GND")
	)
	(segment
		(start 77.22489 -303.024794)
		(end 77.69987 -302.549814)
		(width 0.249936)
		(layer "F.Cu")
		(net "GND")
	)
	(segment
		(start 81.974944 -299.224954)
		(end 81.499964 -299.699934)
		(width 0.249936)
		(layer "F.Cu")
		(net "GND")
	)
	(segment
		(start 306.099718 -293.99992)
		(end 305.624738 -293.52494)
		(width 0.249936)
		(layer "F.Cu")
		(net "GND")
	)
	(segment
		(start 409.849828 -305.399948)
		(end 410.324808 -305.874928)
		(width 0.249936)
		(layer "F.Cu")
		(net "GND")
	)
	(segment
		(start 163.399978 -285.449772)
		(end 162.924998 -284.974792)
		(width 0.249936)
		(layer "F.Cu")
		(net "GND")
	)
	(segment
		(start 289.94989 -288.19983)
		(end 290.449762 -287.699958)
		(width 0.249936)
		(layer "F.Cu")
		(net "GND")
	)
	(segment
		(start 279.974802 -307.774848)
		(end 279.499822 -307.299868)
		(width 0.249936)
		(layer "F.Cu")
		(net "GND")
	)
	(segment
		(start 283.833062 -120.555004)
		(end 282.842462 -120.555004)
		(width 0.3556)
		(layer "F.Cu")
		(net "GND")
	)
	(segment
		(start 412.699962 -290.199826)
		(end 412.224982 -289.724846)
		(width 0.249936)
		(layer "F.Cu")
		(net "GND")
	)
	(segment
		(start 49.67478 -288.774886)
		(end 50.14976 -288.299906)
		(width 0.249936)
		(layer "F.Cu")
		(net "GND")
	)
	(segment
		(start 67.249802 -284.499812)
		(end 66.774822 -284.974792)
		(width 0.249936)
		(layer "F.Cu")
		(net "GND")
	)
	(segment
		(start 279.499822 -305.399948)
		(end 279.974802 -304.924714)
		(width 0.249936)
		(layer "F.Cu")
		(net "GND")
	)
	(segment
		(start 162.924998 -302.074834)
		(end 163.399978 -301.599854)
		(width 0.249936)
		(layer "F.Cu")
		(net "GND")
	)
	(segment
		(start 314.649866 -293.99992)
		(end 315.124846 -293.52494)
		(width 0.249936)
		(layer "F.Cu")
		(net "GND")
	)
	(segment
		(start 422.199816 -296.8498)
		(end 421.724836 -297.32478)
		(width 0.249936)
		(layer "F.Cu")
		(net "GND")
	)
	(segment
		(start 455.996802 -280.224484)
		(end 455.387202 -280.224484)
		(width 0.4572)
		(layer "F.Cu")
		(net "GND")
	)
	(segment
		(start 69.624956 -291.624766)
		(end 70.099936 -291.149786)
		(width 0.249936)
		(layer "F.Cu")
		(net "GND")
	)
	(segment
		(start 161.15157 -131.76504)
		(end 162.14217 -131.76504)
		(width 0.3556)
		(layer "F.Cu")
		(net "GND")
	)
	(segment
		(start 310.374792 -299.224954)
		(end 310.849772 -299.699934)
		(width 0.249936)
		(layer "F.Cu")
		(net "GND")
	)
	(segment
		(start 191.0461 -414.187386)
		(end 191.0461 -413.479234)
		(width 0.4572)
		(layer "F.Cu")
		(net "GND")
	)
	(segment
		(start 169.099992 -307.299868)
		(end 169.574972 -306.824888)
		(width 0.249936)
		(layer "F.Cu")
		(net "GND")
	)
	(segment
		(start 269.999714 -290.199826)
		(end 269.524734 -289.724846)
		(width 0.249936)
		(layer "F.Cu")
		(net "GND")
	)
	(segment
		(start 298.024804 -305.874928)
		(end 298.499784 -306.349908)
		(width 0.249936)
		(layer "F.Cu")
		(net "GND")
	)
	(segment
		(start 212.405214 -213.348062)
		(end 212.27161 -213.481666)
		(width 0.4572)
		(layer "F.Cu")
		(net "GND")
	)
	(segment
		(start 341.146384 -284.631384)
		(end 340.93912 -284.42412)
		(width 0.2286)
		(layer "F.Cu")
		(net "GND")
	)
	(segment
		(start 288.99993 -301.599854)
		(end 289.47491 -302.074834)
		(width 0.249936)
		(layer "F.Cu")
		(net "GND")
	)
	(segment
		(start 400.824954 -284.974792)
		(end 400.349974 -285.449772)
		(width 0.249936)
		(layer "F.Cu")
		(net "GND")
	)
	(segment
		(start 287.574736 -303.974754)
		(end 287.099756 -303.499774)
		(width 0.249936)
		(layer "F.Cu")
		(net "GND")
	)
	(segment
		(start 395.59992 -302.549814)
		(end 396.0749 -303.024794)
		(width 0.249936)
		(layer "F.Cu")
		(net "GND")
	)
	(segment
		(start 10.664952 -31.390082)
		(end 12.016994 -31.390082)
		(width 0.3556)
		(layer "F.Cu")
		(net "GND")
	)
	(segment
		(start 44.449746 -293.04996)
		(end 43.974766 -292.57498)
		(width 0.249936)
		(layer "F.Cu")
		(net "GND")
	)
	(segment
		(start 345.29395 -216.786968)
		(end 345.693746 -216.387172)
		(width 0.381)
		(layer "F.Cu")
		(net "GND")
	)
	(segment
		(start 65.824862 -303.974754)
		(end 66.299842 -303.499774)
		(width 0.249936)
		(layer "F.Cu")
		(net "GND")
	)
	(segment
		(start 258.996434 -341.610696)
		(end 257.882644 -341.610696)
		(width 0.4572)
		(layer "F.Cu")
		(net "GND")
	)
	(segment
		(start 211.400136 -181.213506)
		(end 210.892136 -181.213506)
		(width 0.4572)
		(layer "F.Cu")
		(net "GND")
	)
	(segment
		(start 407.949908 -285.449772)
		(end 408.424888 -284.974792)
		(width 0.249936)
		(layer "F.Cu")
		(net "GND")
	)
	(segment
		(start 159.599884 -277.849838)
		(end 159.124904 -277.374858)
		(width 0.249936)
		(layer "F.Cu")
		(net "GND")
	)
	(segment
		(start 186.675014 -301.124874)
		(end 187.149994 -301.599854)
		(width 0.249936)
		(layer "F.Cu")
		(net "GND")
	)
	(segment
		(start 132.00126 -200.502012)
		(end 132.019802 -200.48347)
		(width 0.4572)
		(layer "F.Cu")
		(net "GND")
	)
	(segment
		(start 406.999948 -306.349908)
		(end 406.524968 -305.874928)
		(width 0.249936)
		(layer "F.Cu")
		(net "GND")
	)
	(segment
		(start 126.816612 -162.404044)
		(end 126.816612 -163.021518)
		(width 0.4572)
		(layer "F.Cu")
		(net "GND")
	)
	(segment
		(start 52.999894 -299.699934)
		(end 53.474874 -300.174914)
		(width 0.249936)
		(layer "F.Cu")
		(net "GND")
	)
	(segment
		(start 180.975 -296.37482)
		(end 180.50002 -295.89984)
		(width 0.249936)
		(layer "F.Cu")
		(net "GND")
	)
	(segment
		(start 335.64195 -159.766)
		(end 335.026 -159.766)
		(width 0.4572)
		(layer "F.Cu")
		(net "GND")
	)
	(segment
		(start 280.670508 -131.277614)
		(end 281.157934 -131.76504)
		(width 0.3556)
		(layer "F.Cu")
		(net "GND")
	)
	(segment
		(start 284.843728 -45.88891)
		(end 285.51505 -45.88891)
		(width 0.254)
		(layer "F.Cu")
		(net "GND")
	)
	(segment
		(start 402.724874 -289.724846)
		(end 403.199854 -290.199826)
		(width 0.249936)
		(layer "F.Cu")
		(net "GND")
	)
	(segment
		(start 220.812868 -105.312718)
		(end 220.812868 -106.019346)
		(width 0.4064)
		(layer "F.Cu")
		(net "GND")
	)
	(segment
		(start 60.599828 -303.499774)
		(end 61.074808 -303.974754)
		(width 0.249936)
		(layer "F.Cu")
		(net "GND")
	)
	(segment
		(start 320.181732 -292.923468)
		(end 320.181732 -291.258244)
		(width 0.4572)
		(layer "F.Cu")
		(net "GND")
	)
	(segment
		(start 301.349918 -306.349908)
		(end 301.824898 -305.874928)
		(width 0.249936)
		(layer "F.Cu")
		(net "GND")
	)
	(segment
		(start 378.172218 -33.248092)
		(end 378.172218 -33.857692)
		(width 0.4572)
		(layer "F.Cu")
		(net "GND")
	)
	(segment
		(start 176.224946 -302.074834)
		(end 175.749966 -301.599854)
		(width 0.249936)
		(layer "F.Cu")
		(net "GND")
	)
	(segment
		(start 179.55006 -301.599854)
		(end 179.07508 -302.074834)
		(width 0.249936)
		(layer "F.Cu")
		(net "GND")
	)
	(segment
		(start 80.54975 -300.649894)
		(end 81.024984 -301.124874)
		(width 0.249936)
		(layer "F.Cu")
		(net "GND")
	)
	(segment
		(start 2.47523 -63.086234)
		(end 2.47523 -62.429136)
		(width 0.4572)
		(layer "F.Cu")
		(net "GND")
	)
	(segment
		(start 76.74991 -293.04996)
		(end 76.27493 -293.52494)
		(width 0.249936)
		(layer "F.Cu")
		(net "GND")
	)
	(segment
		(start 104.609138 -109.032548)
		(end 104.609138 -108.39196)
		(width 0.4572)
		(layer "F.Cu")
		(net "GND")
	)
	(segment
		(start 309.899812 -294.94988)
		(end 310.374792 -294.4749)
		(width 0.249936)
		(layer "F.Cu")
		(net "GND")
	)
	(segment
		(start 72.918574 -46.693836)
		(end 72.719184 -46.893226)
		(width 0.254)
		(layer "F.Cu")
		(net "GND")
	)
	(segment
		(start 61.549788 -290.199826)
		(end 62.024768 -289.724846)
		(width 0.249936)
		(layer "F.Cu")
		(net "GND")
	)
	(segment
		(start 164.349938 -287.349946)
		(end 163.874958 -286.874966)
		(width 0.249936)
		(layer "F.Cu")
		(net "GND")
	)
	(segment
		(start 178.124866 -306.824888)
		(end 178.599846 -306.349908)
		(width 0.249936)
		(layer "F.Cu")
		(net "GND")
	)
	(segment
		(start 199.009762 -303.040034)
		(end 199.009762 -303.024794)
		(width 0.249936)
		(layer "F.Cu")
		(net "GND")
	)
	(segment
		(start 336.867754 -55.083456)
		(end 337.523074 -55.083456)
		(width 0.254)
		(layer "F.Cu")
		(net "GND")
	)
	(segment
		(start 189.049914 -293.99992)
		(end 189.524894 -294.4749)
		(width 0.249936)
		(layer "F.Cu")
		(net "GND")
	)
	(segment
		(start 400.967956 -54.067456)
		(end 401.623276 -54.067456)
		(width 0.254)
		(layer "F.Cu")
		(net "GND")
	)
	(segment
		(start 68.199762 -289.249866)
		(end 68.674742 -288.774886)
		(width 0.249936)
		(layer "F.Cu")
		(net "GND")
	)
	(segment
		(start 421.724836 -297.32478)
		(end 422.199816 -297.79976)
		(width 0.249936)
		(layer "F.Cu")
		(net "GND")
	)
	(segment
		(start 14.670786 -111.739426)
		(end 14.670786 -111.127032)
		(width 0.4572)
		(layer "F.Cu")
		(net "GND")
	)
	(segment
		(start 238.919512 -235.128054)
		(end 238.886238 -235.161328)
		(width 0.4572)
		(layer "F.Cu")
		(net "GND")
	)
	(segment
		(start 272.374868 -300.174914)
		(end 272.849848 -299.699934)
		(width 0.249936)
		(layer "F.Cu")
		(net "GND")
	)
	(segment
		(start 403.199854 -301.599854)
		(end 402.724874 -302.074834)
		(width 0.249936)
		(layer "F.Cu")
		(net "GND")
	)
	(segment
		(start 414.514792 -26.171398)
		(end 414.696148 -25.990042)
		(width 0.3556)
		(layer "F.Cu")
		(net "GND")
	)
	(segment
		(start 292.79977 -285.449772)
		(end 293.27475 -284.974792)
		(width 0.249936)
		(layer "F.Cu")
		(net "GND")
	)
	(segment
		(start 421.249856 -293.99992)
		(end 421.724836 -293.52494)
		(width 0.249936)
		(layer "F.Cu")
		(net "GND")
	)
	(segment
		(start 238.524796 -119.111268)
		(end 239.14227 -119.111268)
		(width 0.4572)
		(layer "F.Cu")
		(net "GND")
	)
	(segment
		(start 159.124904 -277.374858)
		(end 159.599884 -276.899878)
		(width 0.249936)
		(layer "F.Cu")
		(net "GND")
	)
	(segment
		(start 246.194834 -159.336232)
		(end 246.250714 -159.392112)
		(width 0.254)
		(layer "F.Cu")
		(net "GND")
	)
	(segment
		(start 283.299916 -285.449772)
		(end 282.824936 -284.974792)
		(width 0.249936)
		(layer "F.Cu")
		(net "GND")
	)
	(segment
		(start 295.174924 -306.824888)
		(end 294.69969 -307.299868)
		(width 0.249936)
		(layer "F.Cu")
		(net "GND")
	)
	(segment
		(start 63.449962 -284.499812)
		(end 63.924942 -284.974792)
		(width 0.249936)
		(layer "F.Cu")
		(net "GND")
	)
	(segment
		(start 157.699964 -281.649932)
		(end 157.224984 -281.174952)
		(width 0.249936)
		(layer "F.Cu")
		(net "GND")
	)
	(segment
		(start 208.314798 -26.171398)
		(end 208.496154 -25.990042)
		(width 0.3556)
		(layer "F.Cu")
		(net "GND")
	)
	(segment
		(start 126.435104 -114.649504)
		(end 126.435104 -113.910364)
		(width 0.4572)
		(layer "F.Cu")
		(net "GND")
	)
	(segment
		(start 112.247934 -161.172144)
		(end 112.495584 -161.172144)
		(width 0.254)
		(layer "F.Cu")
		(net "GND")
	)
	(segment
		(start 415.18332 -244.37848)
		(end 417.916868 -244.37848)
		(width 0.4572)
		(layer "F.Cu")
		(net "GND")
	)
	(segment
		(start 186.200034 -299.699934)
		(end 186.675014 -300.174914)
		(width 0.249936)
		(layer "F.Cu")
		(net "GND")
	)
	(segment
		(start 169.574972 -284.974792)
		(end 170.049952 -284.499812)
		(width 0.249936)
		(layer "F.Cu")
		(net "GND")
	)
	(segment
		(start 278.242268 -137.16508)
		(end 277.251668 -137.16508)
		(width 0.3556)
		(layer "F.Cu")
		(net "GND")
	)
	(segment
		(start 300.874684 -291.624766)
		(end 300.399704 -292.099746)
		(width 0.249936)
		(layer "F.Cu")
		(net "GND")
	)
	(segment
		(start 425.04995 -296.8498)
		(end 425.52493 -297.32478)
		(width 0.249936)
		(layer "F.Cu")
		(net "GND")
	)
	(segment
		(start 166.725092 -291.624766)
		(end 167.200072 -292.099746)
		(width 0.249936)
		(layer "F.Cu")
		(net "GND")
	)
	(segment
		(start 290.42487 -284.974792)
		(end 289.94989 -285.449772)
		(width 0.249936)
		(layer "F.Cu")
		(net "GND")
	)
	(segment
		(start 397.49984 -307.299868)
		(end 397.02486 -307.774848)
		(width 0.249936)
		(layer "F.Cu")
		(net "GND")
	)
	(segment
		(start 157.224984 -298.27474)
		(end 157.699964 -298.74972)
		(width 0.249936)
		(layer "F.Cu")
		(net "GND")
	)
	(segment
		(start 180.02504 -303.974754)
		(end 179.55006 -303.499774)
		(width 0.249936)
		(layer "F.Cu")
		(net "GND")
	)
	(segment
		(start 401.299934 -292.099746)
		(end 401.774914 -291.624766)
		(width 0.249936)
		(layer "F.Cu")
		(net "GND")
	)
	(segment
		(start 61.074808 -305.874928)
		(end 60.599828 -306.349908)
		(width 0.249936)
		(layer "F.Cu")
		(net "GND")
	)
	(segment
		(start 164.349938 -288.299906)
		(end 163.874958 -287.824926)
		(width 0.249936)
		(layer "F.Cu")
		(net "GND")
	)
	(segment
		(start 298.974764 -303.974754)
		(end 298.499784 -303.499774)
		(width 0.249936)
		(layer "F.Cu")
		(net "GND")
	)
	(segment
		(start 399.400014 -295.89984)
		(end 398.925034 -296.37482)
		(width 0.249936)
		(layer "F.Cu")
		(net "GND")
	)
	(segment
		(start 49.547526 -121.692416)
		(end 49.547526 -122.044206)
		(width 0.3556)
		(layer "F.Cu")
		(net "GND")
	)
	(segment
		(start 226.904296 -181.66842)
		(end 226.104704 -181.66842)
		(width 0.4572)
		(layer "F.Cu")
		(net "GND")
	)
	(segment
		(start 237.903512 -235.128054)
		(end 237.903512 -235.737654)
		(width 0.4572)
		(layer "F.Cu")
		(net "GND")
	)
	(segment
		(start 144.506442 -252.756924)
		(end 144.506442 -253.45644)
		(width 0.4572)
		(layer "F.Cu")
		(net "GND")
	)
	(segment
		(start 278.549862 -297.79976)
		(end 279.024842 -298.27474)
		(width 0.249936)
		(layer "F.Cu")
		(net "GND")
	)
	(segment
		(start 50.14976 -302.549814)
		(end 49.67478 -302.074834)
		(width 0.249936)
		(layer "F.Cu")
		(net "GND")
	)
	(segment
		(start 186.200034 -298.74972)
		(end 186.675014 -299.224954)
		(width 0.249936)
		(layer "F.Cu")
		(net "GND")
	)
	(segment
		(start 66.299842 -297.79976)
		(end 65.824862 -297.32478)
		(width 0.249936)
		(layer "F.Cu")
		(net "GND")
	)
	(segment
		(start 182.39994 -295.89984)
		(end 182.87492 -296.37482)
		(width 0.249936)
		(layer "F.Cu")
		(net "GND")
	)
	(segment
		(start 288.99993 -286.399732)
		(end 289.47491 -285.924752)
		(width 0.249936)
		(layer "F.Cu")
		(net "GND")
	)
	(segment
		(start 417.955222 -145.881852)
		(end 417.828476 -145.755106)
		(width 0.3556)
		(layer "F.Cu")
		(net "GND")
	)
	(segment
		(start 8.85063 -72.459088)
		(end 9.470136 -72.459088)
		(width 0.4572)
		(layer "F.Cu")
		(net "GND")
	)
	(segment
		(start 278.074882 -282.124912)
		(end 278.549862 -282.599892)
		(width 0.249936)
		(layer "F.Cu")
		(net "GND")
	)
	(segment
		(start 122.739404 -136.328404)
		(end 122.615198 -136.45261)
		(width 0.4064)
		(layer "F.Cu")
		(net "GND")
	)
	(segment
		(start 426.967904 -56.353456)
		(end 427.623224 -56.353456)
		(width 0.254)
		(layer "F.Cu")
		(net "GND")
	)
	(segment
		(start 178.599846 -299.699934)
		(end 178.124866 -300.174914)
		(width 0.249936)
		(layer "F.Cu")
		(net "GND")
	)
	(segment
		(start 66.774822 -284.974792)
		(end 66.299842 -285.449772)
		(width 0.249936)
		(layer "F.Cu")
		(net "GND")
	)
	(segment
		(start 76.27493 -301.124874)
		(end 76.74991 -300.649894)
		(width 0.249936)
		(layer "F.Cu")
		(net "GND")
	)
	(segment
		(start 388.949946 -287.349946)
		(end 388.474966 -286.874966)
		(width 0.249936)
		(layer "F.Cu")
		(net "GND")
	)
	(segment
		(start 292.32479 -300.174914)
		(end 292.79977 -299.699934)
		(width 0.249936)
		(layer "F.Cu")
		(net "GND")
	)
	(segment
		(start 441.564776 -31.390082)
		(end 442.580776 -31.390082)
		(width 0.3556)
		(layer "F.Cu")
		(net "GND")
	)
	(segment
		(start 410.767784 -198.306944)
		(end 411.381448 -198.920608)
		(width 0.4572)
		(layer "F.Cu")
		(net "GND")
	)
	(segment
		(start 291.84981 -299.699934)
		(end 292.32479 -300.174914)
		(width 0.249936)
		(layer "F.Cu")
		(net "GND")
	)
	(segment
		(start 279.024842 -307.774848)
		(end 279.499822 -308.249828)
		(width 0.249936)
		(layer "F.Cu")
		(net "GND")
	)
	(segment
		(start 306.099718 -298.74972)
		(end 306.574698 -298.27474)
		(width 0.249936)
		(layer "F.Cu")
		(net "GND")
	)
	(segment
		(start 187.122308 -367.857786)
		(end 187.763912 -367.216182)
		(width 0.4572)
		(layer "F.Cu")
		(net "GND")
	)
	(segment
		(start 215.389968 -73.166732)
		(end 215.389968 -73.85177)
		(width 0.4572)
		(layer "F.Cu")
		(net "GND")
	)
	(segment
		(start 55.374794 -306.824888)
		(end 54.899814 -307.299868)
		(width 0.249936)
		(layer "F.Cu")
		(net "GND")
	)
	(segment
		(start 185.418476 -121.83491)
		(end 184.757314 -121.83491)
		(width 0.3556)
		(layer "F.Cu")
		(net "GND")
	)
	(segment
		(start 123.27509 -98.320606)
		(end 122.357896 -98.320606)
		(width 0.4572)
		(layer "F.Cu")
		(net "GND")
	)
	(segment
		(start 46.34992 -294.94988)
		(end 45.87494 -294.4749)
		(width 0.249936)
		(layer "F.Cu")
		(net "GND")
	)
	(segment
		(start 417.450016 -305.399948)
		(end 417.924996 -305.874928)
		(width 0.249936)
		(layer "F.Cu")
		(net "GND")
	)
	(segment
		(start 269.999714 -277.849838)
		(end 269.524734 -277.374858)
		(width 0.249936)
		(layer "F.Cu")
		(net "GND")
	)
	(segment
		(start 388.057644 -142.892018)
		(end 388.2009 -142.748762)
		(width 0.4572)
		(layer "F.Cu")
		(net "GND")
	)
	(segment
		(start 270.949928 -298.74972)
		(end 270.474694 -298.27474)
		(width 0.249936)
		(layer "F.Cu")
		(net "GND")
	)
	(segment
		(start 180.975 -305.874928)
		(end 181.44998 -306.349908)
		(width 0.249936)
		(layer "F.Cu")
		(net "GND")
	)
	(segment
		(start 305.624738 -303.024794)
		(end 306.099718 -302.549814)
		(width 0.249936)
		(layer "F.Cu")
		(net "GND")
	)
	(segment
		(start 306.099718 -290.199826)
		(end 305.624738 -290.674806)
		(width 0.249936)
		(layer "F.Cu")
		(net "GND")
	)
	(segment
		(start 279.232868 -100.64496)
		(end 278.242268 -100.64496)
		(width 0.3556)
		(layer "F.Cu")
		(net "GND")
	)
	(segment
		(start 271.925288 -141.029436)
		(end 272.173192 -141.029436)
		(width 0.4572)
		(layer "F.Cu")
		(net "GND")
	)
	(segment
		(start 169.574972 -284.974792)
		(end 169.099992 -284.499812)
		(width 0.249936)
		(layer "F.Cu")
		(net "GND")
	)
	(segment
		(start 69.343524 -136.645142)
		(end 68.65747 -136.645142)
		(width 0.3556)
		(layer "F.Cu")
		(net "GND")
	)
	(segment
		(start 394.64996 -296.8498)
		(end 394.17498 -297.32478)
		(width 0.249936)
		(layer "F.Cu")
		(net "GND")
	)
	(segment
		(start 406.524968 -302.074834)
		(end 406.049988 -301.599854)
		(width 0.249936)
		(layer "F.Cu")
		(net "GND")
	)
	(segment
		(start 64.399922 -295.89984)
		(end 64.874902 -296.37482)
		(width 0.249936)
		(layer "F.Cu")
		(net "GND")
	)
	(segment
		(start 68.280788 -25.990042)
		(end 67.264788 -25.990042)
		(width 0.3556)
		(layer "F.Cu")
		(net "GND")
	)
	(segment
		(start 183.3499 -285.449772)
		(end 183.82488 -284.974792)
		(width 0.249936)
		(layer "F.Cu")
		(net "GND")
	)
	(segment
		(start 56.799988 -288.299906)
		(end 56.324754 -287.824926)
		(width 0.249936)
		(layer "F.Cu")
		(net "GND")
	)
	(segment
		(start 360.25836 -255.210564)
		(end 360.86796 -255.210564)
		(width 0.381)
		(layer "F.Cu")
		(net "GND")
	)
	(segment
		(start 233.867706 -216.704164)
		(end 234.267502 -216.304368)
		(width 0.381)
		(layer "F.Cu")
		(net "GND")
	)
	(segment
		(start 171.457874 -26.606246)
		(end 171.457874 -25.971246)
		(width 0.4572)
		(layer "F.Cu")
		(net "GND")
	)
	(segment
		(start 299.449744 -288.299906)
		(end 299.924724 -287.824926)
		(width 0.249936)
		(layer "F.Cu")
		(net "GND")
	)
	(segment
		(start 164.961062 -37.201094)
		(end 164.198554 -37.201094)
		(width 0.4572)
		(layer "F.Cu")
		(net "GND")
	)
	(segment
		(start 162.450018 -291.149786)
		(end 161.975038 -290.674806)
		(width 0.249936)
		(layer "F.Cu")
		(net "GND")
	)
	(segment
		(start 68.674742 -290.674806)
		(end 68.199762 -291.149786)
		(width 0.249936)
		(layer "F.Cu")
		(net "GND")
	)
	(segment
		(start 281.399742 -306.349908)
		(end 281.874722 -305.874928)
		(width 0.249936)
		(layer "F.Cu")
		(net "GND")
	)
	(segment
		(start 71.524876 -303.024794)
		(end 71.049896 -303.499774)
		(width 0.249936)
		(layer "F.Cu")
		(net "GND")
	)
	(segment
		(start 412.224982 -297.32478)
		(end 412.699962 -297.79976)
		(width 0.249936)
		(layer "F.Cu")
		(net "GND")
	)
	(segment
		(start 64.874902 -306.824888)
		(end 65.349882 -306.349908)
		(width 0.249936)
		(layer "F.Cu")
		(net "GND")
	)
	(segment
		(start 312.274712 -294.4749)
		(end 311.799732 -294.94988)
		(width 0.249936)
		(layer "F.Cu")
		(net "GND")
	)
	(segment
		(start 282.824936 -302.074834)
		(end 282.349702 -301.599854)
		(width 0.249936)
		(layer "F.Cu")
		(net "GND")
	)
	(segment
		(start 33.57118 -307.132482)
		(end 33.28289 -306.844192)
		(width 0.4572)
		(layer "F.Cu")
		(net "GND")
	)
	(segment
		(start 380.938024 -306.844192)
		(end 380.542038 -307.240178)
		(width 0.4572)
		(layer "F.Cu")
		(net "GND")
	)
	(segment
		(start 155.800044 -295.89984)
		(end 156.275024 -296.37482)
		(width 0.249936)
		(layer "F.Cu")
		(net "GND")
	)
	(segment
		(start 185.783982 -124.000514)
		(end 185.418476 -123.635008)
		(width 0.3556)
		(layer "F.Cu")
		(net "GND")
	)
	(segment
		(start 2.992374 -389.86968)
		(end 3.04673 -389.924036)
		(width 0.4572)
		(layer "F.Cu")
		(net "GND")
	)
	(segment
		(start 240.521998 -83.951318)
		(end 241.193066 -83.951318)
		(width 0.4572)
		(layer "F.Cu")
		(net "GND")
	)
	(segment
		(start 52.999894 -284.499812)
		(end 53.474874 -284.024832)
		(width 0.249936)
		(layer "F.Cu")
		(net "GND")
	)
	(segment
		(start 148.570442 -252.756924)
		(end 148.570442 -253.45644)
		(width 0.4572)
		(layer "F.Cu")
		(net "GND")
	)
	(segment
		(start 300.399704 -307.299868)
		(end 299.924724 -307.774848)
		(width 0.249936)
		(layer "F.Cu")
		(net "GND")
	)
	(segment
		(start 179.55006 -305.399948)
		(end 180.02504 -305.874928)
		(width 0.249936)
		(layer "F.Cu")
		(net "GND")
	)
	(segment
		(start 404.149814 -303.499774)
		(end 404.624794 -303.974754)
		(width 0.249936)
		(layer "F.Cu")
		(net "GND")
	)
	(segment
		(start 316.321948 -59.971686)
		(end 316.3189 -59.974734)
		(width 0.4572)
		(layer "F.Cu")
		(net "GND")
	)
	(segment
		(start 410.799788 -285.449772)
		(end 410.324808 -285.924752)
		(width 0.249936)
		(layer "F.Cu")
		(net "GND")
	)
	(segment
		(start 56.799988 -285.449772)
		(end 56.324754 -285.924752)
		(width 0.249936)
		(layer "F.Cu")
		(net "GND")
	)
	(segment
		(start 302.774858 -284.024832)
		(end 303.249838 -284.499812)
		(width 0.249936)
		(layer "F.Cu")
		(net "GND")
	)
	(segment
		(start 293.74973 -286.399732)
		(end 294.22471 -285.924752)
		(width 0.249936)
		(layer "F.Cu")
		(net "GND")
	)
	(segment
		(start 208.254346 -228.833426)
		(end 208.254346 -229.061518)
		(width 0.4572)
		(layer "F.Cu")
		(net "GND")
	)
	(segment
		(start 47.29988 -285.449772)
		(end 46.8249 -284.974792)
		(width 0.249936)
		(layer "F.Cu")
		(net "GND")
	)
	(segment
		(start 288.049716 -308.249828)
		(end 287.574736 -307.774848)
		(width 0.127)
		(layer "F.Cu")
		(net "GND")
	)
	(segment
		(start 221.164658 -183.40324)
		(end 220.275658 -183.40324)
		(width 0.3556)
		(layer "F.Cu")
		(net "GND")
	)
	(segment
		(start 156.750004 -284.499812)
		(end 156.275024 -284.024832)
		(width 0.249936)
		(layer "F.Cu")
		(net "GND")
	)
	(segment
		(start 78.17485 -293.52494)
		(end 78.64983 -293.04996)
		(width 0.249936)
		(layer "F.Cu")
		(net "GND")
	)
	(segment
		(start 392.749786 -296.8498)
		(end 393.22502 -297.32478)
		(width 0.249936)
		(layer "F.Cu")
		(net "GND")
	)
	(segment
		(start 389.899906 -276.899878)
		(end 389.424926 -276.424898)
		(width 0.249936)
		(layer "F.Cu")
		(net "GND")
	)
	(segment
		(start 47.77486 -297.32478)
		(end 47.29988 -297.79976)
		(width 0.249936)
		(layer "F.Cu")
		(net "GND")
	)
	(segment
		(start 416.974782 -289.724846)
		(end 416.499802 -290.199826)
		(width 0.249936)
		(layer "F.Cu")
		(net "GND")
	)
	(segment
		(start 331.976476 -6.541516)
		(end 331.650086 -6.541516)
		(width 0.4572)
		(layer "F.Cu")
		(net "GND")
	)
	(segment
		(start 279.346914 -52.592224)
		(end 279.422098 -52.51704)
		(width 0.254)
		(layer "F.Cu")
		(net "GND")
	)
	(segment
		(start 169.099992 -299.699934)
		(end 168.625012 -300.174914)
		(width 0.249936)
		(layer "F.Cu")
		(net "GND")
	)
	(segment
		(start 26.667968 -51.019456)
		(end 27.323288 -51.019456)
		(width 0.254)
		(layer "F.Cu")
		(net "GND")
	)
	(segment
		(start 102.968298 -222.20936)
		(end 102.713536 -222.464122)
		(width 0.4572)
		(layer "F.Cu")
		(net "GND")
	)
	(segment
		(start 395.12494 -304.924714)
		(end 395.59992 -304.449734)
		(width 0.249936)
		(layer "F.Cu")
		(net "GND")
	)
	(segment
		(start 288.049716 -292.099746)
		(end 288.524696 -291.624766)
		(width 0.249936)
		(layer "F.Cu")
		(net "GND")
	)
	(segment
		(start 386.099812 -282.599892)
		(end 385.624832 -282.124912)
		(width 0.249936)
		(layer "F.Cu")
		(net "GND")
	)
	(segment
		(start 139.637262 -213.8426)
		(end 139.507214 -213.712552)
		(width 0.4572)
		(layer "F.Cu")
		(net "GND")
	)
	(segment
		(start 47.77486 -303.974754)
		(end 47.29988 -303.499774)
		(width 0.249936)
		(layer "F.Cu")
		(net "GND")
	)
	(segment
		(start 233.357928 -60.000134)
		(end 233.535728 -60.177934)
		(width 0.3556)
		(layer "F.Cu")
		(net "GND")
	)
	(segment
		(start 173.850046 -305.399948)
		(end 174.325026 -305.874928)
		(width 0.249936)
		(layer "F.Cu")
		(net "GND")
	)
	(segment
		(start 177.174906 -296.37482)
		(end 176.699926 -295.89984)
		(width 0.249936)
		(layer "F.Cu")
		(net "GND")
	)
	(segment
		(start 29.2608 -311.442608)
		(end 29.260292 -311.442608)
		(width 0.4572)
		(layer "F.Cu")
		(net "GND")
	)
	(segment
		(start 46.34992 -296.8498)
		(end 45.87494 -297.32478)
		(width 0.249936)
		(layer "F.Cu")
		(net "GND")
	)
	(segment
		(start 422.548304 -125.435106)
		(end 421.557704 -125.435106)
		(width 0.3556)
		(layer "F.Cu")
		(net "GND")
	)
	(segment
		(start 429.800004 -299.699934)
		(end 430.274984 -299.224954)
		(width 0.249936)
		(layer "F.Cu")
		(net "GND")
	)
	(segment
		(start 180.177694 -114.267742)
		(end 180.788056 -114.267742)
		(width 0.4572)
		(layer "F.Cu")
		(net "GND")
	)
	(segment
		(start 93.264736 -34.990024)
		(end 91.31935 -34.990024)
		(width 0.3556)
		(layer "F.Cu")
		(net "GND")
	)
	(segment
		(start 65.824862 -294.4749)
		(end 65.349882 -294.94988)
		(width 0.249936)
		(layer "F.Cu")
		(net "GND")
	)
	(segment
		(start 164.349938 -304.449734)
		(end 164.824918 -303.974754)
		(width 0.249936)
		(layer "F.Cu")
		(net "GND")
	)
	(segment
		(start 398.4498 -306.349908)
		(end 397.97482 -305.874928)
		(width 0.249936)
		(layer "F.Cu")
		(net "GND")
	)
	(segment
		(start 269.049754 -291.149786)
		(end 268.574774 -290.674806)
		(width 0.249936)
		(layer "F.Cu")
		(net "GND")
	)
	(segment
		(start 239.413288 -137.344404)
		(end 238.757968 -137.344404)
		(width 0.4064)
		(layer "F.Cu")
		(net "GND")
	)
	(segment
		(start 70.099936 -291.149786)
		(end 70.574916 -291.624766)
		(width 0.249936)
		(layer "F.Cu")
		(net "GND")
	)
	(segment
		(start 188.552582 -134.845044)
		(end 189.357508 -134.845044)
		(width 0.3556)
		(layer "F.Cu")
		(net "GND")
	)
	(segment
		(start 288.049716 -305.399948)
		(end 287.574736 -305.874928)
		(width 0.249936)
		(layer "F.Cu")
		(net "GND")
	)
	(segment
		(start 101.323902 -27.411934)
		(end 101.323902 -26.319734)
		(width 0.4572)
		(layer "F.Cu")
		(net "GND")
	)
	(segment
		(start 300.874684 -304.924714)
		(end 301.349918 -305.399948)
		(width 0.249936)
		(layer "F.Cu")
		(net "GND")
	)
	(segment
		(start 298.499784 -306.349908)
		(end 298.024804 -306.824888)
		(width 0.249936)
		(layer "F.Cu")
		(net "GND")
	)
	(segment
		(start 56.324754 -303.974754)
		(end 56.799988 -303.499774)
		(width 0.249936)
		(layer "F.Cu")
		(net "GND")
	)
	(segment
		(start 57.274968 -297.32478)
		(end 57.749948 -296.8498)
		(width 0.249936)
		(layer "F.Cu")
		(net "GND")
	)
	(segment
		(start 389.56488 -33.19018)
		(end 388.54888 -33.19018)
		(width 0.3556)
		(layer "F.Cu")
		(net "GND")
	)
	(segment
		(start 82.449924 -303.499774)
		(end 82.909664 -303.040034)
		(width 0.249936)
		(layer "F.Cu")
		(net "GND")
	)
	(segment
		(start 356.676706 -392.551412)
		(end 356.676706 -393.12977)
		(width 0.3048)
		(layer "F.Cu")
		(net "GND")
	)
	(segment
		(start 159.599884 -282.599892)
		(end 159.124904 -282.124912)
		(width 0.249936)
		(layer "F.Cu")
		(net "GND")
	)
	(segment
		(start 288.99993 -295.89984)
		(end 288.52495 -296.37482)
		(width 0.249936)
		(layer "F.Cu")
		(net "GND")
	)
	(segment
		(start 167.732964 -118.754906)
		(end 166.742364 -118.754906)
		(width 0.3556)
		(layer "F.Cu")
		(net "GND")
	)
	(segment
		(start 239.413288 -140.392404)
		(end 238.757968 -140.392404)
		(width 0.4064)
		(layer "F.Cu")
		(net "GND")
	)
	(segment
		(start 425.04995 -298.74972)
		(end 425.52493 -299.224954)
		(width 0.249936)
		(layer "F.Cu")
		(net "GND")
	)
	(segment
		(start 215.746584 -209.707734)
		(end 216.229438 -209.22488)
		(width 0.254)
		(layer "F.Cu")
		(net "GND")
	)
	(segment
		(start 205.844902 -27.79014)
		(end 204.764894 -27.79014)
		(width 0.3556)
		(layer "F.Cu")
		(net "GND")
	)
	(segment
		(start 288.524696 -284.974792)
		(end 288.049716 -285.449772)
		(width 0.249936)
		(layer "F.Cu")
		(net "GND")
	)
	(segment
		(start 431.505106 -142.597886)
		(end 431.505106 -143.470122)
		(width 0.4064)
		(layer "F.Cu")
		(net "GND")
	)
	(segment
		(start 227.693474 -136.269222)
		(end 227.693474 -135.659622)
		(width 0.4572)
		(layer "F.Cu")
		(net "GND")
	)
	(segment
		(start 342.893904 -217.587068)
		(end 343.2937 -217.187272)
		(width 0.381)
		(layer "F.Cu")
		(net "GND")
	)
	(segment
		(start 219.660724 -105.71734)
		(end 219.996512 -106.053128)
		(width 0.4064)
		(layer "F.Cu")
		(net "GND")
	)
	(segment
		(start 409.374848 -296.37482)
		(end 409.849828 -296.8498)
		(width 0.249936)
		(layer "F.Cu")
		(net "GND")
	)
	(segment
		(start 221.674944 -97.96907)
		(end 221.674944 -97.31375)
		(width 0.4064)
		(layer "F.Cu")
		(net "GND")
	)
	(segment
		(start 42.549826 -275.949918)
		(end 42.074846 -275.474938)
		(width 0.249936)
		(layer "F.Cu")
		(net "GND")
	)
	(segment
		(start 177.295048 -59.978036)
		(end 177.295048 -60.633356)
		(width 0.4572)
		(layer "F.Cu")
		(net "GND")
	)
	(segment
		(start 174.325026 -283.074872)
		(end 174.800006 -282.599892)
		(width 0.249936)
		(layer "F.Cu")
		(net "GND")
	)
	(segment
		(start 303.724818 -299.224954)
		(end 304.199798 -298.74972)
		(width 0.249936)
		(layer "F.Cu")
		(net "GND")
	)
	(segment
		(start 185.783982 -120.400572)
		(end 185.418476 -120.035066)
		(width 0.3556)
		(layer "F.Cu")
		(net "GND")
	)
	(segment
		(start 419.824916 -299.224954)
		(end 420.299896 -298.74972)
		(width 0.249936)
		(layer "F.Cu")
		(net "GND")
	)
	(segment
		(start 422.674796 -296.37482)
		(end 422.199816 -296.8498)
		(width 0.249936)
		(layer "F.Cu")
		(net "GND")
	)
	(segment
		(start 361.58805 -181.102)
		(end 362.204 -181.102)
		(width 0.4572)
		(layer "F.Cu")
		(net "GND")
	)
	(segment
		(start 412.224982 -287.824926)
		(end 412.699962 -288.299906)
		(width 0.249936)
		(layer "F.Cu")
		(net "GND")
	)
	(segment
		(start 240.359184 -209.164428)
		(end 240.72469 -209.529934)
		(width 0.4572)
		(layer "F.Cu")
		(net "GND")
	)
	(segment
		(start 92.0496 -303.636426)
		(end 93.0656 -303.636426)
		(width 0.4572)
		(layer "F.Cu")
		(net "GND")
	)
	(segment
		(start 321.944746 -27.79014)
		(end 320.864738 -27.79014)
		(width 0.3556)
		(layer "F.Cu")
		(net "GND")
	)
	(segment
		(start 421.724836 -305.874928)
		(end 422.199816 -305.399948)
		(width 0.249936)
		(layer "F.Cu")
		(net "GND")
	)
	(segment
		(start 281.399742 -299.699934)
		(end 280.924762 -300.174914)
		(width 0.249936)
		(layer "F.Cu")
		(net "GND")
	)
	(segment
		(start 288.049716 -284.499812)
		(end 288.524696 -284.974792)
		(width 0.249936)
		(layer "F.Cu")
		(net "GND")
	)
	(segment
		(start 52.667154 -56.354218)
		(end 52.667916 -56.353456)
		(width 0.4572)
		(layer "F.Cu")
		(net "GND")
	)
	(segment
		(start 64.399922 -285.449772)
		(end 64.874902 -284.974792)
		(width 0.249936)
		(layer "F.Cu")
		(net "GND")
	)
	(segment
		(start 45.051726 -113.245138)
		(end 46.042326 -113.245138)
		(width 0.3556)
		(layer "F.Cu")
		(net "GND")
	)
	(segment
		(start 185.904124 -132.622036)
		(end 185.481214 -133.044946)
		(width 0.3556)
		(layer "F.Cu")
		(net "GND")
	)
	(segment
		(start 276.174708 -299.224954)
		(end 275.699728 -299.699934)
		(width 0.249936)
		(layer "F.Cu")
		(net "GND")
	)
	(segment
		(start 192.850008 -298.74972)
		(end 193.324988 -299.224954)
		(width 0.249936)
		(layer "F.Cu")
		(net "GND")
	)
	(segment
		(start 115.720368 -322.078604)
		(end 115.34648 -322.452492)
		(width 0.4572)
		(layer "F.Cu")
		(net "GND")
	)
	(segment
		(start 60.524898 -288.299906)
		(end 60.599828 -288.299906)
		(width 0.249936)
		(layer "F.Cu")
		(net "GND")
	)
	(segment
		(start 324.59295 -232.561892)
		(end 324.367906 -232.786936)
		(width 0.4572)
		(layer "F.Cu")
		(net "GND")
	)
	(segment
		(start 290.734496 -38.937184)
		(end 290.999926 -38.671754)
		(width 0.4572)
		(layer "F.Cu")
		(net "GND")
	)
	(segment
		(start 389.899906 -283.549852)
		(end 389.424926 -283.074872)
		(width 0.249936)
		(layer "F.Cu")
		(net "GND")
	)
	(segment
		(start 38.20795 -155.3464)
		(end 38.20795 -156.3624)
		(width 0.4064)
		(layer "F.Cu")
		(net "GND")
	)
	(segment
		(start 394.64996 -302.549814)
		(end 394.17498 -303.024794)
		(width 0.249936)
		(layer "F.Cu")
		(net "GND")
	)
	(segment
		(start 350.582738 -28.875736)
		(end 350.582738 -28.47848)
		(width 0.254)
		(layer "F.Cu")
		(net "GND")
	)
	(segment
		(start 415.564828 -29.589984)
		(end 416.580828 -29.589984)
		(width 0.3556)
		(layer "F.Cu")
		(net "GND")
	)
	(segment
		(start 417.450016 -303.499774)
		(end 416.979862 -303.969928)
		(width 0.249936)
		(layer "F.Cu")
		(net "GND")
	)
	(segment
		(start 61.074808 -284.974792)
		(end 60.599828 -285.449772)
		(width 0.249936)
		(layer "F.Cu")
		(net "GND")
	)
	(segment
		(start 50.14976 -306.349908)
		(end 49.67478 -306.824888)
		(width 0.249936)
		(layer "F.Cu")
		(net "GND")
	)
	(segment
		(start 54.424834 -282.124912)
		(end 54.899814 -282.599892)
		(width 0.249936)
		(layer "F.Cu")
		(net "GND")
	)
	(segment
		(start 56.799988 -305.399948)
		(end 56.324754 -305.874928)
		(width 0.249936)
		(layer "F.Cu")
		(net "GND")
	)
	(segment
		(start 197.600062 -295.89984)
		(end 198.075042 -296.37482)
		(width 0.249936)
		(layer "F.Cu")
		(net "GND")
	)
	(segment
		(start 314.174886 -299.224954)
		(end 313.699906 -299.699934)
		(width 0.249936)
		(layer "F.Cu")
		(net "GND")
	)
	(segment
		(start 64.399922 -288.299906)
		(end 64.874902 -287.824926)
		(width 0.249936)
		(layer "F.Cu")
		(net "GND")
	)
	(segment
		(start 411.275022 -303.974754)
		(end 411.750002 -303.499774)
		(width 0.249936)
		(layer "F.Cu")
		(net "GND")
	)
	(segment
		(start 172.424852 -287.824926)
		(end 172.900086 -288.299906)
		(width 0.249936)
		(layer "F.Cu")
		(net "GND")
	)
	(segment
		(start 414.124902 -305.874928)
		(end 413.649922 -305.399948)
		(width 0.249936)
		(layer "F.Cu")
		(net "GND")
	)
	(segment
		(start 239.720882 -89.225374)
		(end 239.952276 -89.456768)
		(width 0.4572)
		(layer "F.Cu")
		(net "GND")
	)
	(segment
		(start 82.449924 -301.599854)
		(end 81.974944 -301.124874)
		(width 0.249936)
		(layer "F.Cu")
		(net "GND")
	)
	(segment
		(start 393.351766 -124.154946)
		(end 394.342366 -124.154946)
		(width 0.3556)
		(layer "F.Cu")
		(net "GND")
	)
	(segment
		(start 87.98179 -292.923468)
		(end 87.98179 -291.258244)
		(width 0.4572)
		(layer "F.Cu")
		(net "GND")
	)
	(segment
		(start 226.104704 -181.66842)
		(end 225.916744 -181.85638)
		(width 0.4572)
		(layer "F.Cu")
		(net "GND")
	)
	(segment
		(start 165.677596 -129.964942)
		(end 166.742364 -129.964942)
		(width 0.3556)
		(layer "F.Cu")
		(net "GND")
	)
	(segment
		(start 428.84979 -291.149786)
		(end 429.325024 -290.674806)
		(width 0.249936)
		(layer "F.Cu")
		(net "GND")
	)
	(segment
		(start 61.549788 -285.449772)
		(end 61.074808 -285.924752)
		(width 0.249936)
		(layer "F.Cu")
		(net "GND")
	)
	(segment
		(start 49.934114 -111.44504)
		(end 50.64252 -111.44504)
		(width 0.3556)
		(layer "F.Cu")
		(net "GND")
	)
	(segment
		(start 413.174942 -305.874928)
		(end 412.699962 -306.349908)
		(width 0.249936)
		(layer "F.Cu")
		(net "GND")
	)
	(segment
		(start 156.750004 -287.349946)
		(end 156.275024 -286.874966)
		(width 0.249936)
		(layer "F.Cu")
		(net "GND")
	)
	(segment
		(start 412.224982 -289.724846)
		(end 411.750002 -290.199826)
		(width 0.249936)
		(layer "F.Cu")
		(net "GND")
	)
	(segment
		(start 65.349882 -290.199826)
		(end 64.874902 -289.724846)
		(width 0.249936)
		(layer "F.Cu")
		(net "GND")
	)
	(segment
		(start 384.834384 -252.756924)
		(end 384.834384 -253.45644)
		(width 0.4572)
		(layer "F.Cu")
		(net "GND")
	)
	(segment
		(start 414.124902 -300.174914)
		(end 413.649922 -299.699934)
		(width 0.249936)
		(layer "F.Cu")
		(net "GND")
	)
	(segment
		(start 255.346454 -255.66624)
		(end 255.346454 -255.669542)
		(width 0.4572)
		(layer "F.Cu")
		(net "GND")
	)
	(segment
		(start 416.974782 -284.974792)
		(end 416.499802 -284.499812)
		(width 0.249936)
		(layer "F.Cu")
		(net "GND")
	)
	(segment
		(start 300.874684 -290.674806)
		(end 300.399704 -290.199826)
		(width 0.249936)
		(layer "F.Cu")
		(net "GND")
	)
	(segment
		(start 92.396056 -25.990042)
		(end 93.264736 -25.990042)
		(width 0.3556)
		(layer "F.Cu")
		(net "GND")
	)
	(segment
		(start 173.850046 -294.94988)
		(end 173.375066 -294.4749)
		(width 0.249936)
		(layer "F.Cu")
		(net "GND")
	)
	(segment
		(start 412.37789 -114.267742)
		(end 412.988252 -114.267742)
		(width 0.4572)
		(layer "F.Cu")
		(net "GND")
	)
	(segment
		(start 75.79995 -299.699934)
		(end 76.27493 -300.174914)
		(width 0.249936)
		(layer "F.Cu")
		(net "GND")
	)
	(segment
		(start 395.59992 -292.1)
		(end 396.0749 -292.57498)
		(width 0.254)
		(layer "F.Cu")
		(net "GND")
	)
	(segment
		(start 140.705332 -189.778132)
		(end 139.298934 -189.778132)
		(width 0.3048)
		(layer "F.Cu")
		(net "GND")
	)
	(segment
		(start 305.624738 -299.224954)
		(end 306.099718 -298.74972)
		(width 0.249936)
		(layer "F.Cu")
		(net "GND")
	)
	(segment
		(start 187.624974 -292.574726)
		(end 187.149994 -292.099746)
		(width 0.249936)
		(layer "F.Cu")
		(net "GND")
	)
	(segment
		(start 170.049952 -285.449772)
		(end 169.574972 -285.924752)
		(width 0.249936)
		(layer "F.Cu")
		(net "GND")
	)
	(segment
		(start 290.42487 -285.924752)
		(end 290.89985 -285.449772)
		(width 0.249936)
		(layer "F.Cu")
		(net "GND")
	)
	(segment
		(start 279.024842 -302.074834)
		(end 278.549862 -301.599854)
		(width 0.249936)
		(layer "F.Cu")
		(net "GND")
	)
	(segment
		(start 67.249802 -290.199826)
		(end 67.724782 -289.724846)
		(width 0.249936)
		(layer "F.Cu")
		(net "GND")
	)
	(segment
		(start 65.824862 -307.774848)
		(end 65.349882 -307.299868)
		(width 0.249936)
		(layer "F.Cu")
		(net "GND")
	)
	(segment
		(start 275.224748 -278.324818)
		(end 275.699728 -278.799798)
		(width 0.249936)
		(layer "F.Cu")
		(net "GND")
	)
	(segment
		(start 49.67478 -306.824888)
		(end 49.1998 -306.349908)
		(width 0.249936)
		(layer "F.Cu")
		(net "GND")
	)
	(segment
		(start 390.849866 -279.749758)
		(end 390.374886 -279.274778)
		(width 0.249936)
		(layer "F.Cu")
		(net "GND")
	)
	(segment
		(start 163.24707 -52.592224)
		(end 163.322254 -52.51704)
		(width 0.254)
		(layer "F.Cu")
		(net "GND")
	)
	(segment
		(start 182.39994 -299.699934)
		(end 181.92496 -300.174914)
		(width 0.249936)
		(layer "F.Cu")
		(net "GND")
	)
	(segment
		(start 388.949946 -289.249866)
		(end 389.424926 -289.724846)
		(width 0.254)
		(layer "F.Cu")
		(net "GND")
	)
	(segment
		(start 288.524696 -289.724846)
		(end 288.049716 -290.199826)
		(width 0.249936)
		(layer "F.Cu")
		(net "GND")
	)
	(segment
		(start 394.64996 -307.299868)
		(end 395.12494 -307.774848)
		(width 0.249936)
		(layer "F.Cu")
		(net "GND")
	)
	(segment
		(start 140.806678 -199.361806)
		(end 140.806678 -200.489058)
		(width 0.2794)
		(layer "F.Cu")
		(net "GND")
	)
	(segment
		(start 441.321952 -115.335304)
		(end 441.661296 -114.99596)
		(width 0.254)
		(layer "F.Cu")
		(net "GND")
	)
	(segment
		(start 436.964836 -31.390082)
		(end 437.83631 -31.390082)
		(width 0.3556)
		(layer "F.Cu")
		(net "GND")
	)
	(segment
		(start 51.63312 -120.555004)
		(end 50.64252 -120.555004)
		(width 0.3556)
		(layer "F.Cu")
		(net "GND")
	)
	(segment
		(start 44.846748 -38.49116)
		(end 44.141136 -38.49116)
		(width 0.4572)
		(layer "F.Cu")
		(net "GND")
	)
	(segment
		(start 403.199854 -299.699934)
		(end 402.724874 -300.174914)
		(width 0.249936)
		(layer "F.Cu")
		(net "GND")
	)
	(segment
		(start 279.024842 -303.024794)
		(end 278.549862 -302.549814)
		(width 0.249936)
		(layer "F.Cu")
		(net "GND")
	)
	(segment
		(start 301.723044 -134.845044)
		(end 300.857412 -134.845044)
		(width 0.3556)
		(layer "F.Cu")
		(net "GND")
	)
	(segment
		(start 308.474872 -301.124874)
		(end 308.949852 -300.649894)
		(width 0.249936)
		(layer "F.Cu")
		(net "GND")
	)
	(segment
		(start 152.411938 -136.81456)
		(end 151.838406 -136.241028)
		(width 0.4572)
		(layer "F.Cu")
		(net "GND")
	)
	(segment
		(start 61.549788 -285.449772)
		(end 61.074808 -284.974792)
		(width 0.249936)
		(layer "F.Cu")
		(net "GND")
	)
	(segment
		(start 305.624738 -296.37482)
		(end 305.149758 -296.8498)
		(width 0.249936)
		(layer "F.Cu")
		(net "GND")
	)
	(segment
		(start 273.799808 -277.849838)
		(end 273.324828 -277.374858)
		(width 0.249936)
		(layer "F.Cu")
		(net "GND")
	)
	(segment
		(start 404.149814 -305.399948)
		(end 404.624794 -305.874928)
		(width 0.249936)
		(layer "F.Cu")
		(net "GND")
	)
	(segment
		(start 396.54988 -284.499812)
		(end 396.0749 -284.024832)
		(width 0.249936)
		(layer "F.Cu")
		(net "GND")
	)
	(segment
		(start 340.493858 -217.587068)
		(end 340.093808 -217.187018)
		(width 0.254)
		(layer "F.Cu")
		(net "GND")
	)
	(segment
		(start 305.624738 -298.27474)
		(end 305.149758 -298.74972)
		(width 0.249936)
		(layer "F.Cu")
		(net "GND")
	)
	(segment
		(start 424.09999 -301.599854)
		(end 424.57497 -301.124874)
		(width 0.249936)
		(layer "F.Cu")
		(net "GND")
	)
	(segment
		(start 47.29988 -292.1)
		(end 47.77486 -292.57498)
		(width 0.254)
		(layer "F.Cu")
		(net "GND")
	)
	(segment
		(start 36.6649 -25.990042)
		(end 35.6489 -25.990042)
		(width 0.3556)
		(layer "F.Cu")
		(net "GND")
	)
	(segment
		(start 395.693646 -108.279946)
		(end 395.258798 -107.845098)
		(width 0.3556)
		(layer "F.Cu")
		(net "GND")
	)
	(segment
		(start 278.473916 -73.166732)
		(end 278.473916 -73.85177)
		(width 0.4572)
		(layer "F.Cu")
		(net "GND")
	)
	(segment
		(start 124.241052 -54.163722)
		(end 124.792994 -54.163722)
		(width 0.254)
		(layer "F.Cu")
		(net "GND")
	)
	(segment
		(start 301.581312 -133.044946)
		(end 300.857412 -133.044946)
		(width 0.3556)
		(layer "F.Cu")
		(net "GND")
	)
	(segment
		(start 79.12481 -296.37482)
		(end 78.64983 -296.8498)
		(width 0.249936)
		(layer "F.Cu")
		(net "GND")
	)
	(segment
		(start 391.799826 -291.149786)
		(end 391.324846 -290.674806)
		(width 0.249936)
		(layer "F.Cu")
		(net "GND")
	)
	(segment
		(start 57.274968 -284.974792)
		(end 56.799988 -285.449772)
		(width 0.249936)
		(layer "F.Cu")
		(net "GND")
	)
	(segment
		(start 186.675014 -287.824926)
		(end 187.149994 -287.349946)
		(width 0.249936)
		(layer "F.Cu")
		(net "GND")
	)
	(segment
		(start 289.94989 -284.499812)
		(end 289.47491 -284.024832)
		(width 0.249936)
		(layer "F.Cu")
		(net "GND")
	)
	(segment
		(start 186.200034 -300.649894)
		(end 186.675014 -300.174914)
		(width 0.249936)
		(layer "F.Cu")
		(net "GND")
	)
	(segment
		(start 415.327846 -226.403662)
		(end 417.653216 -226.403662)
		(width 0.4572)
		(layer "F.Cu")
		(net "GND")
	)
	(segment
		(start 62.974982 -285.924752)
		(end 62.499748 -285.449772)
		(width 0.249936)
		(layer "F.Cu")
		(net "GND")
	)
	(segment
		(start 275.699728 -299.699934)
		(end 276.174708 -300.174914)
		(width 0.249936)
		(layer "F.Cu")
		(net "GND")
	)
	(segment
		(start 79.12481 -292.574726)
		(end 78.64983 -292.099746)
		(width 0.249936)
		(layer "F.Cu")
		(net "GND")
	)
	(segment
		(start 6.489446 -62.812168)
		(end 7.29996 -62.812168)
		(width 0.4572)
		(layer "F.Cu")
		(net "GND")
	)
	(segment
		(start 283.833062 -102.445058)
		(end 282.842462 -102.445058)
		(width 0.3556)
		(layer "F.Cu")
		(net "GND")
	)
	(segment
		(start 326.30237 -226.825302)
		(end 326.30237 -227.31095)
		(width 0.4572)
		(layer "F.Cu")
		(net "GND")
	)
	(segment
		(start 192.375028 -292.574726)
		(end 192.850008 -293.04996)
		(width 0.249936)
		(layer "F.Cu")
		(net "GND")
	)
	(segment
		(start 406.524968 -284.974792)
		(end 406.049988 -285.449772)
		(width 0.249936)
		(layer "F.Cu")
		(net "GND")
	)
	(segment
		(start 405.575008 -291.624766)
		(end 406.049988 -292.099746)
		(width 0.249936)
		(layer "F.Cu")
		(net "GND")
	)
	(segment
		(start 397.49984 -301.599854)
		(end 397.97482 -302.074834)
		(width 0.249936)
		(layer "F.Cu")
		(net "GND")
	)
	(segment
		(start 45.87494 -296.37482)
		(end 46.34992 -295.89984)
		(width 0.249936)
		(layer "F.Cu")
		(net "GND")
	)
	(segment
		(start 419.349936 -306.349908)
		(end 419.824916 -305.874928)
		(width 0.249936)
		(layer "F.Cu")
		(net "GND")
	)
	(segment
		(start 271.899888 -276.899878)
		(end 271.424908 -276.424898)
		(width 0.249936)
		(layer "F.Cu")
		(net "GND")
	)
	(segment
		(start 301.349918 -307.299868)
		(end 300.874684 -307.774848)
		(width 0.249936)
		(layer "F.Cu")
		(net "GND")
	)
	(segment
		(start 104.66705 -56.354218)
		(end 104.667812 -56.353456)
		(width 0.4572)
		(layer "F.Cu")
		(net "GND")
	)
	(segment
		(start 189.524894 -297.32478)
		(end 189.049914 -297.79976)
		(width 0.249936)
		(layer "F.Cu")
		(net "GND")
	)
	(segment
		(start 294.22471 -294.4749)
		(end 294.69969 -293.99992)
		(width 0.249936)
		(layer "F.Cu")
		(net "GND")
	)
	(segment
		(start 331.575664 -118.467886)
		(end 332.23454 -118.467886)
		(width 0.4572)
		(layer "F.Cu")
		(net "GND")
	)
	(segment
		(start 189.524894 -299.224954)
		(end 189.049914 -298.74972)
		(width 0.249936)
		(layer "F.Cu")
		(net "GND")
	)
	(segment
		(start 301.824898 -291.624766)
		(end 301.349918 -292.099746)
		(width 0.249936)
		(layer "F.Cu")
		(net "GND")
	)
	(segment
		(start 259.69468 -305.613816)
		(end 260.271006 -305.613816)
		(width 0.4572)
		(layer "F.Cu")
		(net "GND")
	)
	(segment
		(start 413.37357 -192.160144)
		(end 413.37357 -192.910206)
		(width 0.4572)
		(layer "F.Cu")
		(net "GND")
	)
	(segment
		(start 161.975038 -302.074834)
		(end 162.450018 -302.549814)
		(width 0.249936)
		(layer "F.Cu")
		(net "GND")
	)
	(segment
		(start 300.874684 -284.974792)
		(end 301.349918 -284.499812)
		(width 0.249936)
		(layer "F.Cu")
		(net "GND")
	)
	(segment
		(start 239.989106 -228.57206)
		(end 239.989106 -229.2096)
		(width 0.4572)
		(layer "F.Cu")
		(net "GND")
	)
	(segment
		(start 192.850008 -294.94988)
		(end 192.375028 -294.4749)
		(width 0.249936)
		(layer "F.Cu")
		(net "GND")
	)
	(segment
		(start 289.94989 -290.199826)
		(end 290.42487 -289.724846)
		(width 0.249936)
		(layer "F.Cu")
		(net "GND")
	)
	(segment
		(start 396.54988 -290.199826)
		(end 396.0749 -289.724846)
		(width 0.249936)
		(layer "F.Cu")
		(net "GND")
	)
	(segment
		(start 243.688362 -306.281582)
		(end 244.196616 -306.281582)
		(width 0.4572)
		(layer "F.Cu")
		(net "GND")
	)
	(segment
		(start 378.673868 -26.606246)
		(end 378.673868 -25.971246)
		(width 0.4572)
		(layer "F.Cu")
		(net "GND")
	)
	(segment
		(start 183.847994 -188.501274)
		(end 183.189372 -188.501274)
		(width 0.4572)
		(layer "F.Cu")
		(net "GND")
	)
	(segment
		(start 363.07395 -200.787)
		(end 362.458 -200.787)
		(width 0.4572)
		(layer "F.Cu")
		(net "GND")
	)
	(segment
		(start 418.874956 -291.624766)
		(end 419.349936 -291.149786)
		(width 0.249936)
		(layer "F.Cu")
		(net "GND")
	)
	(segment
		(start 298.499784 -295.89984)
		(end 298.974764 -296.37482)
		(width 0.249936)
		(layer "F.Cu")
		(net "GND")
	)
	(segment
		(start 288.049716 -288.299906)
		(end 288.524696 -287.824926)
		(width 0.249936)
		(layer "F.Cu")
		(net "GND")
	)
	(segment
		(start 286.624776 -303.974754)
		(end 286.149796 -303.499774)
		(width 0.249936)
		(layer "F.Cu")
		(net "GND")
	)
	(segment
		(start 331.575664 -122.525028)
		(end 332.18755 -122.525028)
		(width 0.4064)
		(layer "F.Cu")
		(net "GND")
	)
	(segment
		(start 76.27493 -289.724846)
		(end 75.79995 -290.199826)
		(width 0.249936)
		(layer "F.Cu")
		(net "GND")
	)
	(segment
		(start 261.454392 -337.90255)
		(end 262.197088 -337.90255)
		(width 0.4572)
		(layer "F.Cu")
		(net "GND")
	)
	(segment
		(start 180.50002 -303.499774)
		(end 180.975 -303.974754)
		(width 0.249936)
		(layer "F.Cu")
		(net "GND")
	)
	(segment
		(start 112.961166 -37.201094)
		(end 112.198658 -37.201094)
		(width 0.4572)
		(layer "F.Cu")
		(net "GND")
	)
	(segment
		(start 55.849774 -305.399948)
		(end 55.374794 -305.874928)
		(width 0.249936)
		(layer "F.Cu")
		(net "GND")
	)
	(segment
		(start 45.39996 -285.449772)
		(end 44.92498 -284.974792)
		(width 0.249936)
		(layer "F.Cu")
		(net "GND")
	)
	(segment
		(start 231.46766 -216.704164)
		(end 231.867456 -216.304368)
		(width 0.381)
		(layer "F.Cu")
		(net "GND")
	)
	(segment
		(start 132.019802 -200.48347)
		(end 132.019802 -200.919334)
		(width 0.4572)
		(layer "F.Cu")
		(net "GND")
	)
	(segment
		(start 260.451346 -335.425034)
		(end 260.460236 -335.433924)
		(width 0.4572)
		(layer "F.Cu")
		(net "GND")
	)
	(segment
		(start 164.349938 -303.499774)
		(end 163.874958 -303.024794)
		(width 0.249936)
		(layer "F.Cu")
		(net "GND")
	)
	(segment
		(start 182.39994 -305.399948)
		(end 182.87492 -305.874928)
		(width 0.249936)
		(layer "F.Cu")
		(net "GND")
	)
	(segment
		(start 185.780172 -156.554932)
		(end 184.757314 -156.554932)
		(width 0.3556)
		(layer "F.Cu")
		(net "GND")
	)
	(segment
		(start 39.699946 -297.79976)
		(end 40.174926 -298.27474)
		(width 0.249936)
		(layer "F.Cu")
		(net "GND")
	)
	(segment
		(start 162.924998 -302.074834)
		(end 162.450018 -301.599854)
		(width 0.249936)
		(layer "F.Cu")
		(net "GND")
	)
	(segment
		(start 131.36499 -29.589984)
		(end 132.38099 -29.589984)
		(width 0.3556)
		(layer "F.Cu")
		(net "GND")
	)
	(segment
		(start 125.419612 -162.404044)
		(end 125.419612 -163.021518)
		(width 0.4572)
		(layer "F.Cu")
		(net "GND")
	)
	(segment
		(start 277.156672 -410.930344)
		(end 277.049738 -410.82341)
		(width 0.4572)
		(layer "F.Cu")
		(net "GND")
	)
	(segment
		(start 173.375066 -306.824888)
		(end 173.850046 -307.299868)
		(width 0.249936)
		(layer "F.Cu")
		(net "GND")
	)
	(segment
		(start 281.874722 -294.4749)
		(end 282.349702 -294.94988)
		(width 0.249936)
		(layer "F.Cu")
		(net "GND")
	)
	(segment
		(start 56.689498 -64.312292)
		(end 57.447942 -64.312292)
		(width 0.4572)
		(layer "F.Cu")
		(net "GND")
	)
	(segment
		(start 233.496104 -276.534118)
		(end 232.868978 -276.534118)
		(width 0.254)
		(layer "F.Cu")
		(net "GND")
	)
	(segment
		(start 63.408814 -382.584706)
		(end 63.408814 -383.576068)
		(width 0.4572)
		(layer "F.Cu")
		(net "GND")
	)
	(segment
		(start 225.867722 -222.304102)
		(end 225.467926 -222.703898)
		(width 0.381)
		(layer "F.Cu")
		(net "GND")
	)
	(segment
		(start 37.799772 -277.849838)
		(end 37.324792 -277.374858)
		(width 0.249936)
		(layer "F.Cu")
		(net "GND")
	)
	(segment
		(start 93.003878 -291.321998)
		(end 93.638878 -291.321998)
		(width 0.4572)
		(layer "F.Cu")
		(net "GND")
	)
	(segment
		(start 81.024984 -296.37482)
		(end 80.54975 -296.8498)
		(width 0.249936)
		(layer "F.Cu")
		(net "GND")
	)
	(segment
		(start 315.405008 -142.597886)
		(end 315.405008 -143.470122)
		(width 0.4064)
		(layer "F.Cu")
		(net "GND")
	)
	(segment
		(start 37.799772 -273.099784)
		(end 38.274752 -273.574764)
		(width 0.249936)
		(layer "F.Cu")
		(net "GND")
	)
	(segment
		(start 416.974782 -293.52494)
		(end 416.499802 -293.99992)
		(width 0.249936)
		(layer "F.Cu")
		(net "GND")
	)
	(segment
		(start 258.86791 -51.019456)
		(end 259.52323 -51.019456)
		(width 0.254)
		(layer "F.Cu")
		(net "GND")
	)
	(segment
		(start 99.146868 -53.144166)
		(end 99.146868 -52.592224)
		(width 0.254)
		(layer "F.Cu")
		(net "GND")
	)
	(segment
		(start 273.799808 -285.449772)
		(end 273.324828 -285.924752)
		(width 0.249936)
		(layer "F.Cu")
		(net "GND")
	)
	(segment
		(start 244.254782 -34.990024)
		(end 242.864894 -34.990024)
		(width 0.3556)
		(layer "F.Cu")
		(net "GND")
	)
	(segment
		(start 45.051726 -106.045)
		(end 46.042326 -106.045)
		(width 0.3556)
		(layer "F.Cu")
		(net "GND")
	)
	(segment
		(start 264.3124 -307.369718)
		(end 264.837926 -306.844192)
		(width 0.4572)
		(layer "F.Cu")
		(net "GND")
	)
	(segment
		(start 67.66687 -114.635026)
		(end 68.65747 -114.635026)
		(width 0.3556)
		(layer "F.Cu")
		(net "GND")
	)
	(segment
		(start 182.39994 -306.349908)
		(end 182.87492 -305.874928)
		(width 0.249936)
		(layer "F.Cu")
		(net "GND")
	)
	(segment
		(start 278.549862 -307.299868)
		(end 279.024842 -306.824888)
		(width 0.249936)
		(layer "F.Cu")
		(net "GND")
	)
	(segment
		(start 404.624794 -302.074834)
		(end 404.149814 -301.599854)
		(width 0.249936)
		(layer "F.Cu")
		(net "GND")
	)
	(segment
		(start 409.374848 -307.774848)
		(end 409.849828 -307.299868)
		(width 0.249936)
		(layer "F.Cu")
		(net "GND")
	)
	(segment
		(start 411.750002 -290.199826)
		(end 411.275022 -289.724846)
		(width 0.249936)
		(layer "F.Cu")
		(net "GND")
	)
	(segment
		(start 238.509048 -27.04973)
		(end 237.849918 -27.04973)
		(width 0.4572)
		(layer "F.Cu")
		(net "GND")
	)
	(segment
		(start 154.850084 -296.8498)
		(end 155.325064 -297.32478)
		(width 0.249936)
		(layer "F.Cu")
		(net "GND")
	)
	(segment
		(start 418.399976 -290.199826)
		(end 418.874956 -290.674806)
		(width 0.249936)
		(layer "F.Cu")
		(net "GND")
	)
	(segment
		(start 251.423678 -153.1112)
		(end 251.423678 -153.782522)
		(width 0.4064)
		(layer "F.Cu")
		(net "GND")
	)
	(segment
		(start 387.050026 -291.149786)
		(end 386.575046 -290.674806)
		(width 0.249936)
		(layer "F.Cu")
		(net "GND")
	)
	(segment
		(start 273.464782 -27.79014)
		(end 272.448782 -27.79014)
		(width 0.3556)
		(layer "F.Cu")
		(net "GND")
	)
	(segment
		(start 396.0749 -307.774848)
		(end 396.54988 -307.299868)
		(width 0.249936)
		(layer "F.Cu")
		(net "GND")
	)
	(segment
		(start 165.963346 -113.780062)
		(end 165.963346 -113.485676)
		(width 0.3556)
		(layer "F.Cu")
		(net "GND")
	)
	(segment
		(start 307.999892 -303.499774)
		(end 308.474872 -303.024794)
		(width 0.249936)
		(layer "F.Cu")
		(net "GND")
	)
	(segment
		(start 181.44998 -288.299906)
		(end 181.92496 -287.824926)
		(width 0.249936)
		(layer "F.Cu")
		(net "GND")
	)
	(segment
		(start 55.374794 -284.974792)
		(end 54.899814 -285.449772)
		(width 0.249936)
		(layer "F.Cu")
		(net "GND")
	)
	(segment
		(start 55.850028 -296.8498)
		(end 55.849774 -296.8498)
		(width 0.249936)
		(layer "F.Cu")
		(net "GND")
	)
	(segment
		(start 284.724856 -291.624766)
		(end 285.199836 -292.099746)
		(width 0.249936)
		(layer "F.Cu")
		(net "GND")
	)
	(segment
		(start 249.94743 -92.496386)
		(end 249.94743 -93.105986)
		(width 0.4572)
		(layer "F.Cu")
		(net "GND")
	)
	(segment
		(start 205.422246 -213.593426)
		(end 205.422246 -215.485218)
		(width 0.4572)
		(layer "F.Cu")
		(net "GND")
	)
	(segment
		(start 78.17485 -291.624766)
		(end 78.64983 -292.099746)
		(width 0.249936)
		(layer "F.Cu")
		(net "GND")
	)
	(segment
		(start 294.69969 -288.299906)
		(end 295.174924 -287.824926)
		(width 0.249936)
		(layer "F.Cu")
		(net "GND")
	)
	(segment
		(start 71.524876 -292.574726)
		(end 71.049896 -293.04996)
		(width 0.249936)
		(layer "F.Cu")
		(net "GND")
	)
	(segment
		(start 286.149796 -290.199826)
		(end 286.624776 -289.724846)
		(width 0.249936)
		(layer "F.Cu")
		(net "GND")
	)
	(segment
		(start 324.59295 -232.156)
		(end 324.59295 -232.561892)
		(width 0.4572)
		(layer "F.Cu")
		(net "GND")
	)
	(segment
		(start 389.899906 -277.849838)
		(end 389.424926 -277.374858)
		(width 0.249936)
		(layer "F.Cu")
		(net "GND")
	)
	(segment
		(start 71.049896 -307.299868)
		(end 70.574916 -307.774848)
		(width 0.249936)
		(layer "F.Cu")
		(net "GND")
	)
	(segment
		(start 75.323954 -27.411934)
		(end 75.323954 -26.319734)
		(width 0.4572)
		(layer "F.Cu")
		(net "GND")
	)
	(segment
		(start 335.64195 -155.702)
		(end 335.026 -155.702)
		(width 0.4572)
		(layer "F.Cu")
		(net "GND")
	)
	(segment
		(start 230.354886 -240.946178)
		(end 230.354886 -241.679476)
		(width 0.4572)
		(layer "F.Cu")
		(net "GND")
	)
	(segment
		(start 167.200072 -284.499812)
		(end 166.725092 -284.024832)
		(width 0.249936)
		(layer "F.Cu")
		(net "GND")
	)
	(segment
		(start 387.525006 -296.37482)
		(end 387.999986 -295.89984)
		(width 0.249936)
		(layer "F.Cu")
		(net "GND")
	)
	(segment
		(start 184.29986 -288.299906)
		(end 183.82488 -287.824926)
		(width 0.249936)
		(layer "F.Cu")
		(net "GND")
	)
	(segment
		(start 45.051726 -98.845116)
		(end 46.042326 -98.845116)
		(width 0.3556)
		(layer "F.Cu")
		(net "GND")
	)
	(segment
		(start 118.485666 -34.183066)
		(end 118.371112 -34.29762)
		(width 0.4572)
		(layer "F.Cu")
		(net "GND")
	)
	(segment
		(start 193.799968 -302.549814)
		(end 194.274948 -302.074834)
		(width 0.249936)
		(layer "F.Cu")
		(net "GND")
	)
	(segment
		(start 210.684618 -78.4606)
		(end 209.751168 -77.52715)
		(width 0.4572)
		(layer "F.Cu")
		(net "GND")
	)
	(segment
		(start 181.44998 -285.449772)
		(end 180.975 -285.924752)
		(width 0.249936)
		(layer "F.Cu")
		(net "GND")
	)
	(segment
		(start 69.624956 -298.27474)
		(end 70.099936 -298.74972)
		(width 0.249936)
		(layer "F.Cu")
		(net "GND")
	)
	(segment
		(start 249.020838 -119.541036)
		(end 249.020838 -120.15343)
		(width 0.4572)
		(layer "F.Cu")
		(net "GND")
	)
	(segment
		(start 151.90724 -379.389132)
		(end 151.90724 -380.379732)
		(width 0.4572)
		(layer "F.Cu")
		(net "GND")
	)
	(segment
		(start 176.699926 -307.299868)
		(end 177.174906 -306.824888)
		(width 0.249936)
		(layer "F.Cu")
		(net "GND")
	)
	(segment
		(start 8.692896 -54.163722)
		(end 8.76808 -54.238906)
		(width 0.254)
		(layer "F.Cu")
		(net "GND")
	)
	(segment
		(start 34.692844 -54.163722)
		(end 34.768028 -54.238906)
		(width 0.254)
		(layer "F.Cu")
		(net "GND")
	)
	(segment
		(start 5.296408 -375.083578)
		(end 5.472176 -375.259346)
		(width 0.381)
		(layer "F.Cu")
		(net "GND")
	)
	(segment
		(start 13.994892 -159.336232)
		(end 14.050772 -159.392112)
		(width 0.254)
		(layer "F.Cu")
		(net "GND")
	)
	(segment
		(start 40.649906 -288.299906)
		(end 40.174926 -287.824926)
		(width 0.381)
		(layer "F.Cu")
		(net "GND")
	)
	(segment
		(start 293.74973 -305.399948)
		(end 294.22471 -305.874928)
		(width 0.249936)
		(layer "F.Cu")
		(net "GND")
	)
	(segment
		(start 187.470288 -47.60087)
		(end 187.896246 -47.60087)
		(width 0.254)
		(layer "F.Cu")
		(net "GND")
	)
	(segment
		(start 67.249802 -290.199826)
		(end 66.774822 -289.724846)
		(width 0.249936)
		(layer "F.Cu")
		(net "GND")
	)
	(segment
		(start 92.248736 -27.79014)
		(end 93.264736 -27.79014)
		(width 0.3556)
		(layer "F.Cu")
		(net "GND")
	)
	(segment
		(start 161.15157 -118.754906)
		(end 162.14217 -118.754906)
		(width 0.3556)
		(layer "F.Cu")
		(net "GND")
	)
	(segment
		(start 313.224926 -294.4749)
		(end 312.749692 -294.94988)
		(width 0.249936)
		(layer "F.Cu")
		(net "GND")
	)
	(segment
		(start 411.275022 -306.824888)
		(end 411.750002 -306.349908)
		(width 0.249936)
		(layer "F.Cu")
		(net "GND")
	)
	(segment
		(start 98.96348 -220.544644)
		(end 98.199956 -220.544644)
		(width 0.381)
		(layer "F.Cu")
		(net "GND")
	)
	(segment
		(start 405.575008 -302.074834)
		(end 406.049988 -301.599854)
		(width 0.249936)
		(layer "F.Cu")
		(net "GND")
	)
	(segment
		(start 264.837926 -306.844192)
		(end 265.482832 -306.844192)
		(width 0.4572)
		(layer "F.Cu")
		(net "GND")
	)
	(segment
		(start 425.52493 -289.724846)
		(end 425.04995 -289.249866)
		(width 0.249936)
		(layer "F.Cu")
		(net "GND")
	)
	(segment
		(start 274.749768 -283.549852)
		(end 274.274788 -283.074872)
		(width 0.249936)
		(layer "F.Cu")
		(net "GND")
	)
	(segment
		(start 357.857298 -242.436142)
		(end 356.62362 -242.436142)
		(width 0.4572)
		(layer "F.Cu")
		(net "GND")
	)
	(segment
		(start 310.867044 -56.354218)
		(end 310.867806 -56.353456)
		(width 0.4572)
		(layer "F.Cu")
		(net "GND")
	)
	(segment
		(start 281.399742 -307.299868)
		(end 280.924762 -306.824888)
		(width 0.249936)
		(layer "F.Cu")
		(net "GND")
	)
	(segment
		(start 401.774914 -284.974792)
		(end 401.299934 -284.499812)
		(width 0.249936)
		(layer "F.Cu")
		(net "GND")
	)
	(segment
		(start 416.499802 -286.399732)
		(end 416.974782 -285.924752)
		(width 0.249936)
		(layer "F.Cu")
		(net "GND")
	)
	(segment
		(start 198.550022 -290.199826)
		(end 199.025002 -289.724846)
		(width 0.249936)
		(layer "F.Cu")
		(net "GND")
	)
	(segment
		(start 243.880894 -25.990042)
		(end 242.864894 -25.990042)
		(width 0.3556)
		(layer "F.Cu")
		(net "GND")
	)
	(segment
		(start 183.82488 -305.874928)
		(end 183.3499 -306.349908)
		(width 0.249936)
		(layer "F.Cu")
		(net "GND")
	)
	(segment
		(start 56.799988 -306.349908)
		(end 56.324754 -305.874928)
		(width 0.249936)
		(layer "F.Cu")
		(net "GND")
	)
	(segment
		(start 218.0336 -97.837244)
		(end 218.080844 -97.79)
		(width 0.381)
		(layer "F.Cu")
		(net "GND")
	)
	(segment
		(start 118.382796 -28.875736)
		(end 118.382796 -28.47848)
		(width 0.254)
		(layer "F.Cu")
		(net "GND")
	)
	(segment
		(start 294.86479 -29.589984)
		(end 293.84879 -29.589984)
		(width 0.3556)
		(layer "F.Cu")
		(net "GND")
	)
	(segment
		(start 214.884 -227.528882)
		(end 214.796116 -227.440998)
		(width 0.4572)
		(layer "F.Cu")
		(net "GND")
	)
	(segment
		(start 139.523216 -214.982806)
		(end 138.679174 -214.982806)
		(width 0.4572)
		(layer "F.Cu")
		(net "GND")
	)
	(segment
		(start 310.849772 -299.699934)
		(end 311.324752 -300.174914)
		(width 0.249936)
		(layer "F.Cu")
		(net "GND")
	)
	(segment
		(start 83.694016 -35.264852)
		(end 83.694016 -35.499548)
		(width 0.4572)
		(layer "F.Cu")
		(net "GND")
	)
	(segment
		(start 170.049952 -284.499812)
		(end 170.524932 -284.024832)
		(width 0.249936)
		(layer "F.Cu")
		(net "GND")
	)
	(segment
		(start 234.040172 -33.248092)
		(end 234.040172 -33.857692)
		(width 0.4572)
		(layer "F.Cu")
		(net "GND")
	)
	(segment
		(start 279.499822 -299.699934)
		(end 279.974802 -299.224954)
		(width 0.249936)
		(layer "F.Cu")
		(net "GND")
	)
	(segment
		(start 184.77484 -298.27474)
		(end 184.29986 -298.74972)
		(width 0.249936)
		(layer "F.Cu")
		(net "GND")
	)
	(segment
		(start 396.54988 -286.399732)
		(end 396.0749 -285.924752)
		(width 0.249936)
		(layer "F.Cu")
		(net "GND")
	)
	(segment
		(start 293.74973 -285.449772)
		(end 294.22471 -285.924752)
		(width 0.249936)
		(layer "F.Cu")
		(net "GND")
	)
	(segment
		(start 57.749948 -299.699934)
		(end 57.274968 -300.174914)
		(width 0.249936)
		(layer "F.Cu")
		(net "GND")
	)
	(segment
		(start 104.667812 -56.353456)
		(end 105.323132 -56.353456)
		(width 0.254)
		(layer "F.Cu")
		(net "GND")
	)
	(segment
		(start 273.589242 -79.892906)
		(end 273.710908 -79.77124)
		(width 0.4572)
		(layer "F.Cu")
		(net "GND")
	)
	(segment
		(start 175.749966 -299.699934)
		(end 176.224946 -300.174914)
		(width 0.249936)
		(layer "F.Cu")
		(net "GND")
	)
	(segment
		(start 314.649866 -290.199826)
		(end 315.124846 -289.724846)
		(width 0.249936)
		(layer "F.Cu")
		(net "GND")
	)
	(segment
		(start 58.699908 -288.149792)
		(end 58.24982 -287.699958)
		(width 0.249936)
		(layer "F.Cu")
		(net "GND")
	)
	(segment
		(start 409.849828 -292.099746)
		(end 410.324808 -291.624766)
		(width 0.249936)
		(layer "F.Cu")
		(net "GND")
	)
	(segment
		(start 157.699964 -290.199826)
		(end 157.224984 -289.724846)
		(width 0.249936)
		(layer "F.Cu")
		(net "GND")
	)
	(segment
		(start 176.240948 -54.163722)
		(end 176.79289 -54.163722)
		(width 0.254)
		(layer "F.Cu")
		(net "GND")
	)
	(segment
		(start 298.024804 -306.824888)
		(end 297.549824 -306.349908)
		(width 0.249936)
		(layer "F.Cu")
		(net "GND")
	)
	(segment
		(start 72.258428 -116.69522)
		(end 72.518524 -116.435124)
		(width 0.3556)
		(layer "F.Cu")
		(net "GND")
	)
	(segment
		(start 428.582582 -28.875736)
		(end 428.582582 -28.47848)
		(width 0.254)
		(layer "F.Cu")
		(net "GND")
	)
	(segment
		(start 167.675052 -306.824888)
		(end 167.200072 -306.349908)
		(width 0.249936)
		(layer "F.Cu")
		(net "GND")
	)
	(segment
		(start 160.074864 -300.174914)
		(end 160.549844 -300.649894)
		(width 0.249936)
		(layer "F.Cu")
		(net "GND")
	)
	(segment
		(start 182.39994 -292.099746)
		(end 181.92496 -291.624766)
		(width 0.249936)
		(layer "F.Cu")
		(net "GND")
	)
	(segment
		(start 69.149976 -303.499774)
		(end 68.674742 -303.024794)
		(width 0.249936)
		(layer "F.Cu")
		(net "GND")
	)
	(segment
		(start 397.49984 -301.599854)
		(end 397.97482 -301.124874)
		(width 0.249936)
		(layer "F.Cu")
		(net "GND")
	)
	(segment
		(start 13.360146 -174.872142)
		(end 14.047978 -174.872142)
		(width 0.4572)
		(layer "F.Cu")
		(net "GND")
	)
	(segment
		(start 147.794218 -35.264852)
		(end 147.794218 -35.499548)
		(width 0.4572)
		(layer "F.Cu")
		(net "GND")
	)
	(segment
		(start 198.075042 -297.32478)
		(end 198.550022 -297.79976)
		(width 0.249936)
		(layer "F.Cu")
		(net "GND")
	)
	(segment
		(start 413.174942 -289.724846)
		(end 412.699962 -290.199826)
		(width 0.249936)
		(layer "F.Cu")
		(net "GND")
	)
	(segment
		(start 447.58991 -73.166732)
		(end 447.58991 -73.85177)
		(width 0.4572)
		(layer "F.Cu")
		(net "GND")
	)
	(segment
		(start 47.092108 -104.404922)
		(end 46.932088 -104.244902)
		(width 0.3556)
		(layer "F.Cu")
		(net "GND")
	)
	(segment
		(start 184.29986 -305.399948)
		(end 184.77484 -305.874928)
		(width 0.249936)
		(layer "F.Cu")
		(net "GND")
	)
	(segment
		(start 397.97482 -286.874966)
		(end 398.4498 -287.349946)
		(width 0.249936)
		(layer "F.Cu")
		(net "GND")
	)
	(segment
		(start 184.77484 -303.024794)
		(end 184.29986 -302.549814)
		(width 0.249936)
		(layer "F.Cu")
		(net "GND")
	)
	(segment
		(start 367.334546 -47.936658)
		(end 367.670334 -47.60087)
		(width 0.254)
		(layer "F.Cu")
		(net "GND")
	)
	(segment
		(start 264.508996 -27.04973)
		(end 263.849866 -27.04973)
		(width 0.4572)
		(layer "F.Cu")
		(net "GND")
	)
	(segment
		(start 66.774822 -302.074834)
		(end 66.299842 -301.599854)
		(width 0.249936)
		(layer "F.Cu")
		(net "GND")
	)
	(segment
		(start 430.172114 -33.248092)
		(end 430.172114 -33.857692)
		(width 0.4572)
		(layer "F.Cu")
		(net "GND")
	)
	(segment
		(start 183.82488 -303.974754)
		(end 183.3499 -303.499774)
		(width 0.249936)
		(layer "F.Cu")
		(net "GND")
	)
	(segment
		(start 36.312094 -136.81456)
		(end 35.738562 -136.241028)
		(width 0.4572)
		(layer "F.Cu")
		(net "GND")
	)
	(segment
		(start 39.699946 -285.449772)
		(end 39.224966 -284.974792)
		(width 0.249936)
		(layer "F.Cu")
		(net "GND")
	)
	(segment
		(start 363.564932 -25.990042)
		(end 364.580932 -25.990042)
		(width 0.3556)
		(layer "F.Cu")
		(net "GND")
	)
	(segment
		(start 422.674796 -300.174914)
		(end 422.199816 -300.649894)
		(width 0.249936)
		(layer "F.Cu")
		(net "GND")
	)
	(segment
		(start 241.910362 -121.661428)
		(end 241.394488 -121.661428)
		(width 0.4064)
		(layer "F.Cu")
		(net "GND")
	)
	(segment
		(start 47.530512 -65.92189)
		(end 47.530512 -65.15989)
		(width 0.4572)
		(layer "F.Cu")
		(net "GND")
	)
	(segment
		(start 54.424834 -291.624766)
		(end 53.949854 -292.099746)
		(width 0.249936)
		(layer "F.Cu")
		(net "GND")
	)
	(segment
		(start 145.457926 -26.606246)
		(end 145.457926 -25.971246)
		(width 0.4572)
		(layer "F.Cu")
		(net "GND")
	)
	(segment
		(start 433.184046 -143.582898)
		(end 431.85207 -142.250922)
		(width 0.4572)
		(layer "F.Cu")
		(net "GND")
	)
	(segment
		(start 278.68753 -25.742392)
		(end 278.68753 -26.360882)
		(width 0.4572)
		(layer "F.Cu")
		(net "GND")
	)
	(segment
		(start 197.44944 -85.426296)
		(end 196.33946 -85.426296)
		(width 0.4572)
		(layer "F.Cu")
		(net "GND")
	)
	(segment
		(start 307.999892 -299.699934)
		(end 308.474872 -299.224954)
		(width 0.249936)
		(layer "F.Cu")
		(net "GND")
	)
	(segment
		(start 286.585406 -34.183066)
		(end 286.470852 -34.29762)
		(width 0.4572)
		(layer "F.Cu")
		(net "GND")
	)
	(segment
		(start 193.83883 -402.263102)
		(end 194.673982 -402.263102)
		(width 0.4572)
		(layer "F.Cu")
		(net "GND")
	)
	(segment
		(start 396.54988 -305.399948)
		(end 396.0749 -304.924714)
		(width 0.249936)
		(layer "F.Cu")
		(net "GND")
	)
	(segment
		(start 151.90724 -380.379732)
		(end 151.90724 -381.344932)
		(width 0.4572)
		(layer "F.Cu")
		(net "GND")
	)
	(segment
		(start 221.780862 -201.733658)
		(end 221.780862 -202.857862)
		(width 0.4572)
		(layer "F.Cu")
		(net "GND")
	)
	(segment
		(start 327.13168 -226.000818)
		(end 326.813926 -226.000818)
		(width 0.4572)
		(layer "F.Cu")
		(net "GND")
	)
	(segment
		(start 404.149814 -306.349908)
		(end 403.674834 -305.874928)
		(width 0.249936)
		(layer "F.Cu")
		(net "GND")
	)
	(segment
		(start 239.413288 -135.058404)
		(end 238.874046 -135.058404)
		(width 0.4064)
		(layer "F.Cu")
		(net "GND")
	)
	(segment
		(start 177.649886 -285.449772)
		(end 177.174906 -284.974792)
		(width 0.249936)
		(layer "F.Cu")
		(net "GND")
	)
	(segment
		(start 344.49385 -221.58706)
		(end 344.8939 -221.98711)
		(width 0.381)
		(layer "F.Cu")
		(net "GND")
	)
	(segment
		(start 52.049934 -303.499774)
		(end 52.524914 -303.974754)
		(width 0.249936)
		(layer "F.Cu")
		(net "GND")
	)
	(segment
		(start 173.375066 -287.824926)
		(end 173.850046 -288.299906)
		(width 0.249936)
		(layer "F.Cu")
		(net "GND")
	)
	(segment
		(start 294.69969 -307.299868)
		(end 294.22471 -306.824888)
		(width 0.249936)
		(layer "F.Cu")
		(net "GND")
	)
	(segment
		(start 416.974782 -307.774848)
		(end 417.450016 -307.299868)
		(width 0.249936)
		(layer "F.Cu")
		(net "GND")
	)
	(segment
		(start 179.55006 -296.8498)
		(end 179.07508 -296.37482)
		(width 0.249936)
		(layer "F.Cu")
		(net "GND")
	)
	(segment
		(start 300.874684 -292.574726)
		(end 301.349918 -292.099746)
		(width 0.249936)
		(layer "F.Cu")
		(net "GND")
	)
	(segment
		(start 142.262352 -262.912352)
		(end 141.650974 -262.912352)
		(width 0.3048)
		(layer "F.Cu")
		(net "GND")
	)
	(segment
		(start 366.566196 -285.488634)
		(end 366.254792 -285.488634)
		(width 0.2286)
		(layer "F.Cu")
		(net "GND")
	)
	(segment
		(start 285.199836 -285.449772)
		(end 284.724856 -284.974792)
		(width 0.249936)
		(layer "F.Cu")
		(net "GND")
	)
	(segment
		(start 392.749786 -299.699934)
		(end 392.274806 -299.224954)
		(width 0.249936)
		(layer "F.Cu")
		(net "GND")
	)
	(segment
		(start 399.874994 -305.874928)
		(end 399.400014 -305.399948)
		(width 0.249936)
		(layer "F.Cu")
		(net "GND")
	)
	(segment
		(start 394.17498 -294.4749)
		(end 393.7 -293.99992)
		(width 0.249936)
		(layer "F.Cu")
		(net "GND")
	)
	(segment
		(start 398.4498 -291.149786)
		(end 398.925034 -291.624766)
		(width 0.249936)
		(layer "F.Cu")
		(net "GND")
	)
	(segment
		(start 415.074862 -287.824926)
		(end 415.549842 -288.299906)
		(width 0.249936)
		(layer "F.Cu")
		(net "GND")
	)
	(segment
		(start 300.459394 -86.132162)
		(end 300.459394 -85.475064)
		(width 0.4572)
		(layer "F.Cu")
		(net "GND")
	)
	(segment
		(start 163.874958 -299.224954)
		(end 163.399978 -299.699934)
		(width 0.249936)
		(layer "F.Cu")
		(net "GND")
	)
	(segment
		(start 161.15157 -125.955044)
		(end 162.14217 -125.955044)
		(width 0.3556)
		(layer "F.Cu")
		(net "GND")
	)
	(segment
		(start 283.774896 -302.074834)
		(end 284.249876 -301.599854)
		(width 0.249936)
		(layer "F.Cu")
		(net "GND")
	)
	(segment
		(start 242.64493 -223.51873)
		(end 242.774724 -223.388936)
		(width 0.4572)
		(layer "F.Cu")
		(net "GND")
	)
	(segment
		(start 52.667916 -56.353456)
		(end 53.323236 -56.353456)
		(width 0.254)
		(layer "F.Cu")
		(net "GND")
	)
	(segment
		(start 306.099718 -293.04996)
		(end 306.574698 -292.574726)
		(width 0.249936)
		(layer "F.Cu")
		(net "GND")
	)
	(segment
		(start 71.524876 -301.124874)
		(end 71.049896 -300.649894)
		(width 0.249936)
		(layer "F.Cu")
		(net "GND")
	)
	(segment
		(start 295.88079 -25.990042)
		(end 294.86479 -25.990042)
		(width 0.3556)
		(layer "F.Cu")
		(net "GND")
	)
	(segment
		(start 203.040234 -143.582898)
		(end 200.98385 -143.582898)
		(width 0.4572)
		(layer "F.Cu")
		(net "GND")
	)
	(segment
		(start 186.675014 -299.224954)
		(end 187.149994 -298.74972)
		(width 0.249936)
		(layer "F.Cu")
		(net "GND")
	)
	(segment
		(start 177.174906 -291.624766)
		(end 176.699926 -292.099746)
		(width 0.249936)
		(layer "F.Cu")
		(net "GND")
	)
	(segment
		(start 425.52493 -293.52494)
		(end 425.99991 -293.04996)
		(width 0.249936)
		(layer "F.Cu")
		(net "GND")
	)
	(segment
		(start 405.247348 -37.087048)
		(end 405.882348 -37.087048)
		(width 0.4572)
		(layer "F.Cu")
		(net "GND")
	)
	(segment
		(start 436.964836 -29.589984)
		(end 435.948836 -29.589984)
		(width 0.3556)
		(layer "F.Cu")
		(net "GND")
	)
	(segment
		(start 297.549824 -299.699934)
		(end 297.074844 -300.174914)
		(width 0.249936)
		(layer "F.Cu")
		(net "GND")
	)
	(segment
		(start 445.798448 -65.92189)
		(end 445.798448 -65.15989)
		(width 0.4572)
		(layer "F.Cu")
		(net "GND")
	)
	(segment
		(start 267.718286 -252.756924)
		(end 267.718286 -253.45644)
		(width 0.4572)
		(layer "F.Cu")
		(net "GND")
	)
	(segment
		(start 309.899812 -300.649894)
		(end 309.424832 -301.124874)
		(width 0.249936)
		(layer "F.Cu")
		(net "GND")
	)
	(segment
		(start 68.65747 -147.55495)
		(end 67.667124 -147.55495)
		(width 0.4572)
		(layer "F.Cu")
		(net "GND")
	)
	(segment
		(start 183.766714 -145.755106)
		(end 184.757314 -145.755106)
		(width 0.3556)
		(layer "F.Cu")
		(net "GND")
	)
	(segment
		(start 190.348108 -116.435124)
		(end 189.357508 -116.435124)
		(width 0.3556)
		(layer "F.Cu")
		(net "GND")
	)
	(segment
		(start 168.743884 -45.88891)
		(end 169.415206 -45.88891)
		(width 0.254)
		(layer "F.Cu")
		(net "GND")
	)
	(segment
		(start 270.498316 -161.683954)
		(end 270.905986 -161.276284)
		(width 0.4572)
		(layer "F.Cu")
		(net "GND")
	)
	(segment
		(start 57.274968 -284.024832)
		(end 56.799988 -284.499812)
		(width 0.249936)
		(layer "F.Cu")
		(net "GND")
	)
	(segment
		(start 177.174906 -306.824888)
		(end 177.649886 -307.299868)
		(width 0.249936)
		(layer "F.Cu")
		(net "GND")
	)
	(segment
		(start 293.74973 -284.499812)
		(end 293.27475 -284.974792)
		(width 0.249936)
		(layer "F.Cu")
		(net "GND")
	)
	(segment
		(start 66.299842 -306.349908)
		(end 66.774822 -306.824888)
		(width 0.249936)
		(layer "F.Cu")
		(net "GND")
	)
	(segment
		(start 196.174868 -290.674806)
		(end 195.699888 -291.149786)
		(width 0.249936)
		(layer "F.Cu")
		(net "GND")
	)
	(segment
		(start 188.077602 -135.320024)
		(end 188.552582 -134.845044)
		(width 0.3556)
		(layer "F.Cu")
		(net "GND")
	)
	(segment
		(start 131.422648 -192.743328)
		(end 132.120386 -192.743328)
		(width 0.4572)
		(layer "F.Cu")
		(net "GND")
	)
	(segment
		(start 416.499802 -288.299906)
		(end 416.974782 -287.824926)
		(width 0.249936)
		(layer "F.Cu")
		(net "GND")
	)
	(segment
		(start 158.649924 -279.749758)
		(end 158.174944 -279.274778)
		(width 0.249936)
		(layer "F.Cu")
		(net "GND")
	)
	(segment
		(start 205.780894 -25.990042)
		(end 204.764894 -25.990042)
		(width 0.3556)
		(layer "F.Cu")
		(net "GND")
	)
	(segment
		(start 426.94987 -299.699934)
		(end 427.42485 -300.174914)
		(width 0.249936)
		(layer "F.Cu")
		(net "GND")
	)
	(segment
		(start 303.249838 -300.649894)
		(end 302.774858 -300.174914)
		(width 0.249936)
		(layer "F.Cu")
		(net "GND")
	)
	(segment
		(start 241.5794 -212.98535)
		(end 240.5888 -212.98535)
		(width 0.4572)
		(layer "F.Cu")
		(net "GND")
	)
	(segment
		(start 154.850084 -275.949918)
		(end 154.375104 -275.474938)
		(width 0.249936)
		(layer "F.Cu")
		(net "GND")
	)
	(segment
		(start 27.827732 -34.732468)
		(end 27.595322 -34.732468)
		(width 0.4572)
		(layer "F.Cu")
		(net "GND")
	)
	(segment
		(start 135.134604 -47.936658)
		(end 135.470392 -47.60087)
		(width 0.254)
		(layer "F.Cu")
		(net "GND")
	)
	(segment
		(start 29.872178 -33.248092)
		(end 29.872178 -33.857692)
		(width 0.4572)
		(layer "F.Cu")
		(net "GND")
	)
	(segment
		(start 292.79977 -295.89984)
		(end 293.27475 -296.37482)
		(width 0.249936)
		(layer "F.Cu")
		(net "GND")
	)
	(segment
		(start 343.69375 -222.386652)
		(end 343.69375 -222.386906)
		(width 0.381)
		(layer "F.Cu")
		(net "GND")
	)
	(segment
		(start 73.899776 -297.79976)
		(end 73.424796 -298.27474)
		(width 0.249936)
		(layer "F.Cu")
		(net "GND")
	)
	(segment
		(start 45.051726 -104.244902)
		(end 46.042326 -104.244902)
		(width 0.3556)
		(layer "F.Cu")
		(net "GND")
	)
	(segment
		(start 271.899888 -299.699934)
		(end 271.424908 -300.174914)
		(width 0.249936)
		(layer "F.Cu")
		(net "GND")
	)
	(segment
		(start 300.874684 -306.824888)
		(end 300.399704 -307.299868)
		(width 0.249936)
		(layer "F.Cu")
		(net "GND")
	)
	(segment
		(start 400.824954 -306.824888)
		(end 401.299934 -307.299868)
		(width 0.249936)
		(layer "F.Cu")
		(net "GND")
	)
	(segment
		(start 314.649866 -303.499774)
		(end 314.649866 -303.484534)
		(width 0.254)
		(layer "F.Cu")
		(net "GND")
	)
	(segment
		(start 407.590498 -373.881142)
		(end 408.11323 -374.403874)
		(width 0.4572)
		(layer "F.Cu")
		(net "GND")
	)
	(segment
		(start 184.29986 -301.599854)
		(end 184.77484 -302.074834)
		(width 0.249936)
		(layer "F.Cu")
		(net "GND")
	)
	(segment
		(start 162.924998 -306.824888)
		(end 162.450018 -307.299868)
		(width 0.249936)
		(layer "F.Cu")
		(net "GND")
	)
	(segment
		(start 101.359208 -224.624392)
		(end 102.32771 -224.624392)
		(width 0.254)
		(layer "F.Cu")
		(net "GND")
	)
	(segment
		(start 52.049934 -285.449772)
		(end 52.524914 -285.924752)
		(width 0.249936)
		(layer "F.Cu")
		(net "GND")
	)
	(segment
		(start 416.499802 -292.099746)
		(end 416.024822 -291.624766)
		(width 0.249936)
		(layer "F.Cu")
		(net "GND")
	)
	(segment
		(start 186.675014 -288.774886)
		(end 186.200034 -289.249866)
		(width 0.249936)
		(layer "F.Cu")
		(net "GND")
	)
	(segment
		(start 417.450016 -297.79976)
		(end 417.924996 -298.27474)
		(width 0.249936)
		(layer "F.Cu")
		(net "GND")
	)
	(segment
		(start 162.924998 -306.824888)
		(end 163.399978 -307.299868)
		(width 0.249936)
		(layer "F.Cu")
		(net "GND")
	)
	(segment
		(start 209.165698 -303.636426)
		(end 209.165698 -303.026826)
		(width 0.4572)
		(layer "F.Cu")
		(net "GND")
	)
	(segment
		(start 188.097668 -133.472682)
		(end 188.525404 -133.044946)
		(width 0.3556)
		(layer "F.Cu")
		(net "GND")
	)
	(segment
		(start 405.994108 -35.499548)
		(end 406.366472 -35.871912)
		(width 0.4572)
		(layer "F.Cu")
		(net "GND")
	)
	(segment
		(start 284.724856 -305.874928)
		(end 284.249876 -305.399948)
		(width 0.249936)
		(layer "F.Cu")
		(net "GND")
	)
	(segment
		(start 241.02949 -211.666328)
		(end 240.03889 -211.666328)
		(width 0.4572)
		(layer "F.Cu")
		(net "GND")
	)
	(segment
		(start 54.424834 -285.924752)
		(end 53.949854 -286.399732)
		(width 0.249936)
		(layer "F.Cu")
		(net "GND")
	)
	(segment
		(start 241.062002 -50.397156)
		(end 241.137186 -50.47234)
		(width 0.254)
		(layer "F.Cu")
		(net "GND")
	)
	(segment
		(start 293.27475 -285.924752)
		(end 292.79977 -285.449772)
		(width 0.249936)
		(layer "F.Cu")
		(net "GND")
	)
	(segment
		(start 287.099756 -285.449772)
		(end 286.624776 -284.974792)
		(width 0.249936)
		(layer "F.Cu")
		(net "GND")
	)
	(segment
		(start 287.099756 -295.89984)
		(end 286.624776 -296.37482)
		(width 0.249936)
		(layer "F.Cu")
		(net "GND")
	)
	(segment
		(start 174.325026 -284.974792)
		(end 174.800006 -285.449772)
		(width 0.249936)
		(layer "F.Cu")
		(net "GND")
	)
	(segment
		(start 294.69969 -306.349908)
		(end 295.174924 -305.874928)
		(width 0.249936)
		(layer "F.Cu")
		(net "GND")
	)
	(segment
		(start 75.79995 -301.599854)
		(end 76.27493 -301.124874)
		(width 0.249936)
		(layer "F.Cu")
		(net "GND")
	)
	(segment
		(start 400.943826 -43.85691)
		(end 401.615148 -43.85691)
		(width 0.254)
		(layer "F.Cu")
		(net "GND")
	)
	(segment
		(start 422.199816 -290.199826)
		(end 422.674796 -290.674806)
		(width 0.249936)
		(layer "F.Cu")
		(net "GND")
	)
	(segment
		(start 283.299916 -292.099746)
		(end 282.824936 -291.624766)
		(width 0.249936)
		(layer "F.Cu")
		(net "GND")
	)
	(segment
		(start 67.264788 -33.19018)
		(end 66.248788 -33.19018)
		(width 0.3556)
		(layer "F.Cu")
		(net "GND")
	)
	(segment
		(start 72.57669 -154.755088)
		(end 73.257664 -154.755088)
		(width 0.3556)
		(layer "F.Cu")
		(net "GND")
	)
	(segment
		(start 108.919264 -282.8417)
		(end 108.686854 -283.07411)
		(width 0.2286)
		(layer "F.Cu")
		(net "GND")
	)
	(segment
		(start 153.89987 -291.149786)
		(end 153.42489 -290.674806)
		(width 0.249936)
		(layer "F.Cu")
		(net "GND")
	)
	(segment
		(start 186.675014 -289.724846)
		(end 186.200034 -290.199826)
		(width 0.249936)
		(layer "F.Cu")
		(net "GND")
	)
	(segment
		(start 15.231364 -126.530862)
		(end 15.17396 -126.588266)
		(width 0.2032)
		(layer "F.Cu")
		(net "GND")
	)
	(segment
		(start 288.524696 -300.174914)
		(end 288.049716 -299.699934)
		(width 0.249936)
		(layer "F.Cu")
		(net "GND")
	)
	(segment
		(start 382.802384 -252.756924)
		(end 382.802384 -253.45644)
		(width 0.4572)
		(layer "F.Cu")
		(net "GND")
	)
	(segment
		(start 54.899814 -292.099746)
		(end 54.424834 -291.624766)
		(width 0.249936)
		(layer "F.Cu")
		(net "GND")
	)
	(segment
		(start 38.749986 -293.04996)
		(end 38.275006 -292.57498)
		(width 0.249936)
		(layer "F.Cu")
		(net "GND")
	)
	(segment
		(start 170.575224 -64.102234)
		(end 169.869612 -64.102234)
		(width 0.4572)
		(layer "F.Cu")
		(net "GND")
	)
	(segment
		(start 279.794462 -126.703836)
		(end 279.04567 -125.955044)
		(width 0.3556)
		(layer "F.Cu")
		(net "GND")
	)
	(segment
		(start 387.050026 -292.099746)
		(end 386.575046 -291.624766)
		(width 0.249936)
		(layer "F.Cu")
		(net "GND")
	)
	(segment
		(start 168.625012 -306.824888)
		(end 169.099992 -306.349908)
		(width 0.249936)
		(layer "F.Cu")
		(net "GND")
	)
	(segment
		(start 33.486344 -252.756924)
		(end 33.486344 -253.45644)
		(width 0.4572)
		(layer "F.Cu")
		(net "GND")
	)
	(segment
		(start 178.124866 -284.974792)
		(end 178.599846 -285.449772)
		(width 0.249936)
		(layer "F.Cu")
		(net "GND")
	)
	(segment
		(start 143.317468 -388.478268)
		(end 143.6624 -388.8232)
		(width 0.4572)
		(layer "F.Cu")
		(net "GND")
	)
	(segment
		(start 285.674816 -284.974792)
		(end 285.199836 -285.449772)
		(width 0.249936)
		(layer "F.Cu")
		(net "GND")
	)
	(segment
		(start 314.46597 -77.889608)
		(end 314.46597 -77.175106)
		(width 0.4572)
		(layer "F.Cu")
		(net "GND")
	)
	(segment
		(start 350.893888 -211.18703)
		(end 351.293684 -210.787234)
		(width 0.381)
		(layer "F.Cu")
		(net "GND")
	)
	(segment
		(start 282.303982 -113.245138)
		(end 282.842462 -113.245138)
		(width 0.3556)
		(layer "F.Cu")
		(net "GND")
	)
	(segment
		(start 313.699906 -293.99992)
		(end 314.174886 -293.52494)
		(width 0.249936)
		(layer "F.Cu")
		(net "GND")
	)
	(segment
		(start 301.824898 -298.27474)
		(end 302.299878 -298.74972)
		(width 0.249936)
		(layer "F.Cu")
		(net "GND")
	)
	(segment
		(start 302.774858 -284.974792)
		(end 303.249838 -284.499812)
		(width 0.249936)
		(layer "F.Cu")
		(net "GND")
	)
	(segment
		(start 48.764952 -98.845116)
		(end 50.64252 -98.845116)
		(width 0.3556)
		(layer "F.Cu")
		(net "GND")
	)
	(segment
		(start 429.800004 -292.099746)
		(end 430.274984 -291.624766)
		(width 0.249936)
		(layer "F.Cu")
		(net "GND")
	)
	(segment
		(start 351.38995 -173.83125)
		(end 351.33915 -173.88205)
		(width 0.4572)
		(layer "F.Cu")
		(net "GND")
	)
	(segment
		(start 408.899868 -292.099746)
		(end 408.424888 -291.624766)
		(width 0.249936)
		(layer "F.Cu")
		(net "GND")
	)
	(segment
		(start 411.750002 -299.699934)
		(end 412.224982 -300.174914)
		(width 0.249936)
		(layer "F.Cu")
		(net "GND")
	)
	(segment
		(start 277.234396 -47.936658)
		(end 277.570184 -47.60087)
		(width 0.254)
		(layer "F.Cu")
		(net "GND")
	)
	(segment
		(start 185.923936 -130.710432)
		(end 185.389266 -131.245102)
		(width 0.3556)
		(layer "F.Cu")
		(net "GND")
	)
	(segment
		(start 422.548304 -147.55495)
		(end 421.557704 -147.55495)
		(width 0.3556)
		(layer "F.Cu")
		(net "GND")
	)
	(segment
		(start 222.482664 -207.42021)
		(end 221.6658 -207.42021)
		(width 0.4572)
		(layer "F.Cu")
		(net "GND")
	)
	(segment
		(start 174.800006 -293.99992)
		(end 174.325026 -293.52494)
		(width 0.249936)
		(layer "F.Cu")
		(net "GND")
	)
	(segment
		(start 408.424888 -284.974792)
		(end 408.899868 -284.499812)
		(width 0.249936)
		(layer "F.Cu")
		(net "GND")
	)
	(segment
		(start 392.749786 -297.79976)
		(end 392.274806 -297.32478)
		(width 0.249936)
		(layer "F.Cu")
		(net "GND")
	)
	(segment
		(start 128.058164 -259.11175)
		(end 128.058164 -258.131564)
		(width 0.4572)
		(layer "F.Cu")
		(net "GND")
	)
	(segment
		(start 53.59527 -34.732468)
		(end 53.82768 -34.732468)
		(width 0.4572)
		(layer "F.Cu")
		(net "GND")
	)
	(segment
		(start 296.599864 -293.99992)
		(end 296.124884 -294.4749)
		(width 0.249936)
		(layer "F.Cu")
		(net "GND")
	)
	(segment
		(start 428.37481 -292.574726)
		(end 428.84979 -293.04996)
		(width 0.249936)
		(layer "F.Cu")
		(net "GND")
	)
	(segment
		(start 436.55234 -116.416836)
		(end 435.94274 -116.416836)
		(width 0.4572)
		(layer "F.Cu")
		(net "GND")
	)
	(segment
		(start 306.448206 -133.044946)
		(end 305.457606 -133.044946)
		(width 0.3556)
		(layer "F.Cu")
		(net "GND")
	)
	(segment
		(start 376.667014 -306.083462)
		(end 376.84075 -306.083462)
		(width 0.4572)
		(layer "F.Cu")
		(net "GND")
	)
	(segment
		(start 355.513386 -135.058404)
		(end 354.858066 -135.058404)
		(width 0.4064)
		(layer "F.Cu")
		(net "GND")
	)
	(segment
		(start 360.93273 -397.250412)
		(end 361.620054 -397.250412)
		(width 0.4572)
		(layer "F.Cu")
		(net "GND")
	)
	(segment
		(start 269.94485 -27.79014)
		(end 268.864842 -27.79014)
		(width 0.3556)
		(layer "F.Cu")
		(net "GND")
	)
	(segment
		(start 281.399742 -297.79976)
		(end 281.874722 -297.32478)
		(width 0.249936)
		(layer "F.Cu")
		(net "GND")
	)
	(segment
		(start 53.949854 -284.499812)
		(end 54.424834 -284.024832)
		(width 0.249936)
		(layer "F.Cu")
		(net "GND")
	)
	(segment
		(start 71.524876 -303.024794)
		(end 71.049896 -302.549814)
		(width 0.249936)
		(layer "F.Cu")
		(net "GND")
	)
	(segment
		(start 50.624994 -303.974754)
		(end 51.099974 -303.499774)
		(width 0.249936)
		(layer "F.Cu")
		(net "GND")
	)
	(segment
		(start 306.099718 -301.599854)
		(end 306.574698 -302.074834)
		(width 0.249936)
		(layer "F.Cu")
		(net "GND")
	)
	(segment
		(start 74.374756 -294.4749)
		(end 74.84999 -293.99992)
		(width 0.249936)
		(layer "F.Cu")
		(net "GND")
	)
	(segment
		(start 84.799932 -38.671754)
		(end 84.799932 -38.315138)
		(width 0.4572)
		(layer "F.Cu")
		(net "GND")
	)
	(segment
		(start 374.967246 -57.332626)
		(end 374.967246 -56.354218)
		(width 0.4572)
		(layer "F.Cu")
		(net "GND")
	)
	(segment
		(start 39.00805 -160.974278)
		(end 39.00805 -160.380934)
		(width 0.4572)
		(layer "F.Cu")
		(net "GND")
	)
	(segment
		(start 269.049754 -288.299906)
		(end 268.574774 -287.824926)
		(width 0.249936)
		(layer "F.Cu")
		(net "GND")
	)
	(segment
		(start 48.24984 -293.04996)
		(end 48.72482 -293.52494)
		(width 0.249936)
		(layer "F.Cu")
		(net "GND")
	)
	(segment
		(start 183.82488 -307.774848)
		(end 184.29986 -307.299868)
		(width 0.249936)
		(layer "F.Cu")
		(net "GND")
	)
	(segment
		(start 153.89987 -298.74972)
		(end 154.37485 -298.27474)
		(width 0.249936)
		(layer "F.Cu")
		(net "GND")
	)
	(segment
		(start 270.949928 -294.94988)
		(end 270.474948 -294.4749)
		(width 0.249936)
		(layer "F.Cu")
		(net "GND")
	)
	(segment
		(start 62.024768 -284.974792)
		(end 61.549788 -285.449772)
		(width 0.249936)
		(layer "F.Cu")
		(net "GND")
	)
	(segment
		(start 68.674742 -305.874928)
		(end 68.199762 -305.399948)
		(width 0.249936)
		(layer "F.Cu")
		(net "GND")
	)
	(segment
		(start 426.47489 -289.724846)
		(end 426.94987 -290.199826)
		(width 0.249936)
		(layer "F.Cu")
		(net "GND")
	)
	(segment
		(start 388.949946 -297.79976)
		(end 388.474966 -298.27474)
		(width 0.249936)
		(layer "F.Cu")
		(net "GND")
	)
	(segment
		(start 266.702286 -252.756924)
		(end 266.702286 -253.45644)
		(width 0.4572)
		(layer "F.Cu")
		(net "GND")
	)
	(segment
		(start 251.974858 -48.753014)
		(end 251.26823 -48.753014)
		(width 0.254)
		(layer "F.Cu")
		(net "GND")
	)
	(segment
		(start 234.541822 -26.606246)
		(end 234.541822 -25.971246)
		(width 0.4572)
		(layer "F.Cu")
		(net "GND")
	)
	(segment
		(start 426.47489 -291.624766)
		(end 426.94987 -291.149786)
		(width 0.249936)
		(layer "F.Cu")
		(net "GND")
	)
	(segment
		(start 421.724836 -290.674806)
		(end 422.199816 -290.199826)
		(width 0.249936)
		(layer "F.Cu")
		(net "GND")
	)
	(segment
		(start 242.169188 -307.368702)
		(end 242.601242 -307.368702)
		(width 0.1778)
		(layer "F.Cu")
		(net "GND")
	)
	(segment
		(start 163.694364 -126.703836)
		(end 162.945572 -125.955044)
		(width 0.3556)
		(layer "F.Cu")
		(net "GND")
	)
	(segment
		(start 196.649848 -291.149786)
		(end 197.125082 -290.674806)
		(width 0.249936)
		(layer "F.Cu")
		(net "GND")
	)
	(segment
		(start 66.299842 -307.299868)
		(end 65.824862 -307.774848)
		(width 0.249936)
		(layer "F.Cu")
		(net "GND")
	)
	(segment
		(start 74.849736 -284.499812)
		(end 74.84999 -284.499812)
		(width 0.249936)
		(layer "F.Cu")
		(net "GND")
	)
	(segment
		(start 70.099936 -307.299868)
		(end 69.624956 -306.824888)
		(width 0.249936)
		(layer "F.Cu")
		(net "GND")
	)
	(segment
		(start 398.4498 -287.349946)
		(end 397.97482 -287.824926)
		(width 0.249936)
		(layer "F.Cu")
		(net "GND")
	)
	(segment
		(start 451.301612 -207.948784)
		(end 450.283072 -207.948784)
		(width 0.4572)
		(layer "F.Cu")
		(net "GND")
	)
	(segment
		(start 276.649688 -284.499812)
		(end 276.174708 -284.024832)
		(width 0.249936)
		(layer "F.Cu")
		(net "GND")
	)
	(segment
		(start 401.774914 -306.824888)
		(end 401.299934 -306.349908)
		(width 0.249936)
		(layer "F.Cu")
		(net "GND")
	)
	(segment
		(start 306.099718 -292.099746)
		(end 306.574698 -292.574726)
		(width 0.249936)
		(layer "F.Cu")
		(net "GND")
	)
	(segment
		(start 177.649886 -296.8498)
		(end 177.174906 -296.37482)
		(width 0.249936)
		(layer "F.Cu")
		(net "GND")
	)
	(segment
		(start 163.399978 -292.099746)
		(end 163.399978 -292.1)
		(width 0.254)
		(layer "F.Cu")
		(net "GND")
	)
	(segment
		(start 1.668018 -393.876022)
		(end 1.668018 -394.77061)
		(width 0.4572)
		(layer "F.Cu")
		(net "GND")
	)
	(segment
		(start 405.100028 -299.699934)
		(end 404.624794 -300.174914)
		(width 0.249936)
		(layer "F.Cu")
		(net "GND")
	)
	(segment
		(start 45.39996 -288.299906)
		(end 44.92498 -287.824926)
		(width 0.249936)
		(layer "F.Cu")
		(net "GND")
	)
	(segment
		(start 389.899906 -273.099784)
		(end 389.424926 -272.624804)
		(width 0.249936)
		(layer "F.Cu")
		(net "GND")
	)
	(segment
		(start 134.304024 -282.021534)
		(end 133.919214 -282.406344)
		(width 0.254)
		(layer "F.Cu")
		(net "GND")
	)
	(segment
		(start 191.900048 -299.699934)
		(end 192.375028 -299.224954)
		(width 0.249936)
		(layer "F.Cu")
		(net "GND")
	)
	(segment
		(start 39.182802 -140.85697)
		(end 39.55288 -140.85697)
		(width 0.4572)
		(layer "F.Cu")
		(net "GND")
	)
	(segment
		(start 326.515222 -226.299522)
		(end 326.515222 -226.61245)
		(width 0.4572)
		(layer "F.Cu")
		(net "GND")
	)
	(segment
		(start 308.949852 -296.8498)
		(end 308.474872 -297.32478)
		(width 0.249936)
		(layer "F.Cu")
		(net "GND")
	)
	(segment
		(start 398.095216 -124.154946)
		(end 398.94256 -124.154946)
		(width 0.3556)
		(layer "F.Cu")
		(net "GND")
	)
	(segment
		(start 364.552992 -159.573468)
		(end 365.19358 -159.573468)
		(width 0.4572)
		(layer "F.Cu")
		(net "GND")
	)
	(segment
		(start 296.124884 -294.4749)
		(end 295.649904 -294.94988)
		(width 0.249936)
		(layer "F.Cu")
		(net "GND")
	)
	(segment
		(start 285.199836 -306.349908)
		(end 285.674816 -306.824888)
		(width 0.249936)
		(layer "F.Cu")
		(net "GND")
	)
	(segment
		(start 336.866992 -56.354218)
		(end 336.867754 -56.353456)
		(width 0.4572)
		(layer "F.Cu")
		(net "GND")
	)
	(segment
		(start 56.799988 -301.599854)
		(end 57.274968 -302.074834)
		(width 0.249936)
		(layer "F.Cu")
		(net "GND")
	)
	(segment
		(start 174.4091 -27.04973)
		(end 173.74997 -27.04973)
		(width 0.4572)
		(layer "F.Cu")
		(net "GND")
	)
	(segment
		(start 164.57041 -131.277614)
		(end 165.057836 -131.76504)
		(width 0.3556)
		(layer "F.Cu")
		(net "GND")
	)
	(segment
		(start 78.17485 -297.32478)
		(end 78.64983 -296.8498)
		(width 0.249936)
		(layer "F.Cu")
		(net "GND")
	)
	(segment
		(start 135.32358 -153.1112)
		(end 135.32358 -153.782522)
		(width 0.4064)
		(layer "F.Cu")
		(net "GND")
	)
	(segment
		(start 58.224928 -285.924752)
		(end 57.749948 -285.449772)
		(width 0.249936)
		(layer "F.Cu")
		(net "GND")
	)
	(segment
		(start 161.975038 -299.224954)
		(end 162.450018 -298.74972)
		(width 0.249936)
		(layer "F.Cu")
		(net "GND")
	)
	(segment
		(start 421.249856 -298.74972)
		(end 421.724836 -299.224954)
		(width 0.249936)
		(layer "F.Cu")
		(net "GND")
	)
	(segment
		(start 160.549844 -300.649894)
		(end 161.025078 -301.124874)
		(width 0.249936)
		(layer "F.Cu")
		(net "GND")
	)
	(segment
		(start 277.251668 -100.64496)
		(end 278.242268 -100.64496)
		(width 0.3556)
		(layer "F.Cu")
		(net "GND")
	)
	(segment
		(start 307.999892 -282.599892)
		(end 307.049932 -282.599892)
		(width 0.254)
		(layer "F.Cu")
		(net "GND")
	)
	(segment
		(start 413.379666 -187.537344)
		(end 414.012126 -188.169804)
		(width 0.4572)
		(layer "F.Cu")
		(net "GND")
	)
	(segment
		(start 79.972916 -33.248092)
		(end 79.332074 -33.248092)
		(width 0.4572)
		(layer "F.Cu")
		(net "GND")
	)
	(segment
		(start 438.355994 -33.19018)
		(end 436.964836 -33.19018)
		(width 0.3556)
		(layer "F.Cu")
		(net "GND")
	)
	(segment
		(start 304.199798 -299.699934)
		(end 304.674778 -300.174914)
		(width 0.249936)
		(layer "F.Cu")
		(net "GND")
	)
	(segment
		(start 309.424832 -297.32478)
		(end 308.949852 -296.8498)
		(width 0.249936)
		(layer "F.Cu")
		(net "GND")
	)
	(segment
		(start 354.419154 -59.974734)
		(end 353.76866 -59.974734)
		(width 0.4572)
		(layer "F.Cu")
		(net "GND")
	)
	(segment
		(start 359.980992 -25.990042)
		(end 358.964992 -25.990042)
		(width 0.3556)
		(layer "F.Cu")
		(net "GND")
	)
	(segment
		(start 165.903148 -120.555004)
		(end 166.742364 -120.555004)
		(width 0.3556)
		(layer "F.Cu")
		(net "GND")
	)
	(segment
		(start 192.375028 -291.624766)
		(end 192.850008 -291.149786)
		(width 0.249936)
		(layer "F.Cu")
		(net "GND")
	)
	(segment
		(start 426.967904 -54.067456)
		(end 427.623224 -54.067456)
		(width 0.254)
		(layer "F.Cu")
		(net "GND")
	)
	(segment
		(start 166.742364 -107.845098)
		(end 167.73271 -107.845098)
		(width 0.4572)
		(layer "F.Cu")
		(net "GND")
	)
	(segment
		(start 298.59605 -25.990042)
		(end 299.46473 -25.990042)
		(width 0.3556)
		(layer "F.Cu")
		(net "GND")
	)
	(segment
		(start 183.364886 -25.990042)
		(end 182.496206 -25.990042)
		(width 0.3556)
		(layer "F.Cu")
		(net "GND")
	)
	(segment
		(start 67.312794 -104.240076)
		(end 68.65747 -104.240076)
		(width 0.3556)
		(layer "F.Cu")
		(net "GND")
	)
	(segment
		(start 152.461468 -392.419332)
		(end 152.0952 -392.7856)
		(width 0.4572)
		(layer "F.Cu")
		(net "GND")
	)
	(segment
		(start 447.675762 -122.525028)
		(end 448.287648 -122.525028)
		(width 0.4064)
		(layer "F.Cu")
		(net "GND")
	)
	(segment
		(start 45.051726 -129.964942)
		(end 46.042326 -129.964942)
		(width 0.3556)
		(layer "F.Cu")
		(net "GND")
	)
	(segment
		(start 302.299878 -292.099746)
		(end 301.824898 -292.574726)
		(width 0.249936)
		(layer "F.Cu")
		(net "GND")
	)
	(segment
		(start 42.549826 -283.549852)
		(end 42.074846 -283.074872)
		(width 0.249936)
		(layer "F.Cu")
		(net "GND")
	)
	(segment
		(start 126.345696 -90.195654)
		(end 126.740412 -90.59037)
		(width 0.254)
		(layer "F.Cu")
		(net "GND")
	)
	(segment
		(start 161.500058 -290.199826)
		(end 161.025078 -289.724846)
		(width 0.249936)
		(layer "F.Cu")
		(net "GND")
	)
	(segment
		(start 414.124902 -305.874928)
		(end 414.599882 -306.349908)
		(width 0.249936)
		(layer "F.Cu")
		(net "GND")
	)
	(segment
		(start 400.349974 -307.299868)
		(end 400.824954 -306.824888)
		(width 0.249936)
		(layer "F.Cu")
		(net "GND")
	)
	(segment
		(start 386.099812 -278.799798)
		(end 385.624832 -278.324818)
		(width 0.249936)
		(layer "F.Cu")
		(net "GND")
	)
	(segment
		(start 49.324006 -27.411934)
		(end 49.324006 -26.319734)
		(width 0.4572)
		(layer "F.Cu")
		(net "GND")
	)
	(segment
		(start 416.024822 -285.924752)
		(end 415.549842 -285.449772)
		(width 0.249936)
		(layer "F.Cu")
		(net "GND")
	)
	(segment
		(start 341.293958 -219.987114)
		(end 340.894162 -220.38691)
		(width 0.381)
		(layer "F.Cu")
		(net "GND")
	)
	(segment
		(start 39.699946 -293.99992)
		(end 39.224966 -293.52494)
		(width 0.249936)
		(layer "F.Cu")
		(net "GND")
	)
	(segment
		(start 279.730454 -65.92189)
		(end 279.730454 -65.15989)
		(width 0.4572)
		(layer "F.Cu")
		(net "GND")
	)
	(segment
		(start 425.99991 -294.94988)
		(end 426.47489 -294.4749)
		(width 0.249936)
		(layer "F.Cu")
		(net "GND")
	)
	(segment
		(start 181.92496 -291.624766)
		(end 181.44998 -292.099746)
		(width 0.249936)
		(layer "F.Cu")
		(net "GND")
	)
	(segment
		(start 409.374848 -300.174914)
		(end 409.849828 -299.699934)
		(width 0.249936)
		(layer "F.Cu")
		(net "GND")
	)
	(segment
		(start 295.649904 -288.299906)
		(end 296.124884 -287.824926)
		(width 0.249936)
		(layer "F.Cu")
		(net "GND")
	)
	(segment
		(start 277.599902 -290.199826)
		(end 277.124922 -289.724846)
		(width 0.249936)
		(layer "F.Cu")
		(net "GND")
	)
	(segment
		(start 371.446552 -255.669542)
		(end 371.60835 -255.83134)
		(width 0.4572)
		(layer "F.Cu")
		(net "GND")
	)
	(segment
		(start 161.500058 -289.249866)
		(end 161.025078 -288.774886)
		(width 0.249936)
		(layer "F.Cu")
		(net "GND")
	)
	(segment
		(start 350.127824 -34.732468)
		(end 349.895414 -34.732468)
		(width 0.4572)
		(layer "F.Cu")
		(net "GND")
	)
	(segment
		(start 166.249858 -307.299868)
		(end 166.725092 -306.824888)
		(width 0.249936)
		(layer "F.Cu")
		(net "GND")
	)
	(segment
		(start 187.624974 -302.074834)
		(end 187.149994 -302.549814)
		(width 0.249936)
		(layer "F.Cu")
		(net "GND")
	)
	(segment
		(start 67.724782 -284.974792)
		(end 68.199762 -284.499812)
		(width 0.249936)
		(layer "F.Cu")
		(net "GND")
	)
	(segment
		(start 50.14976 -300.649894)
		(end 50.624994 -300.174914)
		(width 0.249936)
		(layer "F.Cu")
		(net "GND")
	)
	(segment
		(start 53.474874 -302.074834)
		(end 53.949854 -301.599854)
		(width 0.249936)
		(layer "F.Cu")
		(net "GND")
	)
	(segment
		(start 312.274712 -302.074834)
		(end 311.799732 -302.549814)
		(width 0.249936)
		(layer "F.Cu")
		(net "GND")
	)
	(segment
		(start 4.84505 -71.406766)
		(end 4.84505 -70.720966)
		(width 0.4572)
		(layer "F.Cu")
		(net "GND")
	)
	(segment
		(start 426.943774 -43.85691)
		(end 427.615096 -43.85691)
		(width 0.254)
		(layer "F.Cu")
		(net "GND")
	)
	(segment
		(start 314.649866 -297.79976)
		(end 314.174886 -297.32478)
		(width 0.249936)
		(layer "F.Cu")
		(net "GND")
	)
	(segment
		(start 302.774858 -285.924752)
		(end 303.249838 -285.449772)
		(width 0.249936)
		(layer "F.Cu")
		(net "GND")
	)
	(segment
		(start 392.274806 -299.224954)
		(end 391.799826 -299.699934)
		(width 0.249936)
		(layer "F.Cu")
		(net "GND")
	)
	(segment
		(start 420.87673 -154.755088)
		(end 421.557704 -154.755088)
		(width 0.3556)
		(layer "F.Cu")
		(net "GND")
	)
	(segment
		(start 298.974764 -289.724846)
		(end 299.449744 -290.199826)
		(width 0.249936)
		(layer "F.Cu")
		(net "GND")
	)
	(segment
		(start 399.93316 -133.565138)
		(end 398.94256 -133.565138)
		(width 0.3556)
		(layer "F.Cu")
		(net "GND")
	)
	(segment
		(start 413.174942 -285.924752)
		(end 412.699962 -285.449772)
		(width 0.249936)
		(layer "F.Cu")
		(net "GND")
	)
	(segment
		(start 155.107894 -160.974278)
		(end 155.107894 -160.380934)
		(width 0.4572)
		(layer "F.Cu")
		(net "GND")
	)
	(segment
		(start 77.69987 -302.549814)
		(end 78.17485 -303.024794)
		(width 0.249936)
		(layer "F.Cu")
		(net "GND")
	)
	(segment
		(start 66.299842 -303.499774)
		(end 66.774822 -303.974754)
		(width 0.249936)
		(layer "F.Cu")
		(net "GND")
	)
	(segment
		(start 404.673816 -26.606246)
		(end 404.673816 -25.971246)
		(width 0.4572)
		(layer "F.Cu")
		(net "GND")
	)
	(segment
		(start 320.864738 -33.19018)
		(end 319.848738 -33.19018)
		(width 0.3556)
		(layer "F.Cu")
		(net "GND")
	)
	(segment
		(start 1.506982 -375.55424)
		(end 1.977644 -375.083578)
		(width 0.381)
		(layer "F.Cu")
		(net "GND")
	)
	(segment
		(start 45.87494 -287.824926)
		(end 46.34992 -288.299906)
		(width 0.249936)
		(layer "F.Cu")
		(net "GND")
	)
	(segment
		(start 206.793592 -349.912432)
		(end 207.428592 -349.912432)
		(width 0.4572)
		(layer "F.Cu")
		(net "GND")
	)
	(segment
		(start 410.799788 -306.349908)
		(end 410.324808 -306.824888)
		(width 0.249936)
		(layer "F.Cu")
		(net "GND")
	)
	(segment
		(start 400.349974 -306.349908)
		(end 400.824954 -305.874928)
		(width 0.249936)
		(layer "F.Cu")
		(net "GND")
	)
	(segment
		(start 285.674816 -294.4749)
		(end 286.149796 -294.94988)
		(width 0.249936)
		(layer "F.Cu")
		(net "GND")
	)
	(segment
		(start 54.424834 -303.974754)
		(end 54.899814 -303.499774)
		(width 0.249936)
		(layer "F.Cu")
		(net "GND")
	)
	(segment
		(start 169.574972 -294.4749)
		(end 169.099992 -293.99992)
		(width 0.249936)
		(layer "F.Cu")
		(net "GND")
	)
	(segment
		(start 54.899814 -286.399732)
		(end 54.424834 -285.924752)
		(width 0.249936)
		(layer "F.Cu")
		(net "GND")
	)
	(segment
		(start 187.1345 -47.936658)
		(end 187.470288 -47.60087)
		(width 0.254)
		(layer "F.Cu")
		(net "GND")
	)
	(segment
		(start 294.86479 -34.990024)
		(end 293.84879 -34.990024)
		(width 0.3556)
		(layer "F.Cu")
		(net "GND")
	)
	(segment
		(start 197.600062 -292.099746)
		(end 197.125082 -292.574726)
		(width 0.249936)
		(layer "F.Cu")
		(net "GND")
	)
	(segment
		(start 66.774822 -291.624766)
		(end 66.299842 -292.099746)
		(width 0.249936)
		(layer "F.Cu")
		(net "GND")
	)
	(segment
		(start 270.25473 -34.990024)
		(end 268.864842 -34.990024)
		(width 0.3556)
		(layer "F.Cu")
		(net "GND")
	)
	(segment
		(start 61.549788 -294.94988)
		(end 62.024768 -294.4749)
		(width 0.249936)
		(layer "F.Cu")
		(net "GND")
	)
	(segment
		(start 406.999948 -283.549852)
		(end 406.524968 -283.074872)
		(width 0.249936)
		(layer "F.Cu")
		(net "GND")
	)
	(segment
		(start 418.226748 -136.061958)
		(end 417.643564 -136.645142)
		(width 0.3556)
		(layer "F.Cu")
		(net "GND")
	)
	(segment
		(start 187.624974 -299.224954)
		(end 188.099954 -299.699934)
		(width 0.249936)
		(layer "F.Cu")
		(net "GND")
	)
	(segment
		(start 297.074844 -284.974792)
		(end 296.599864 -284.499812)
		(width 0.249936)
		(layer "F.Cu")
		(net "GND")
	)
	(segment
		(start 278.549862 -297.79976)
		(end 278.074882 -298.27474)
		(width 0.249936)
		(layer "F.Cu")
		(net "GND")
	)
	(segment
		(start 46.34992 -284.499812)
		(end 45.87494 -284.024832)
		(width 0.249936)
		(layer "F.Cu")
		(net "GND")
	)
	(segment
		(start 155.800044 -287.349946)
		(end 155.325064 -286.874966)
		(width 0.249936)
		(layer "F.Cu")
		(net "GND")
	)
	(segment
		(start 283.833062 -138.964924)
		(end 282.842462 -138.964924)
		(width 0.3556)
		(layer "F.Cu")
		(net "GND")
	)
	(segment
		(start 209.364834 -33.19018)
		(end 210.380834 -33.19018)
		(width 0.3556)
		(layer "F.Cu")
		(net "GND")
	)
	(segment
		(start 213.470236 -47.60087)
		(end 213.896194 -47.60087)
		(width 0.254)
		(layer "F.Cu")
		(net "GND")
	)
	(segment
		(start 293.74973 -303.499774)
		(end 293.27475 -303.974754)
		(width 0.249936)
		(layer "F.Cu")
		(net "GND")
	)
	(segment
		(start 281.399742 -293.99992)
		(end 280.924762 -293.52494)
		(width 0.249936)
		(layer "F.Cu")
		(net "GND")
	)
	(segment
		(start 402.562568 -34.29762)
		(end 402.12772 -34.732468)
		(width 0.4572)
		(layer "F.Cu")
		(net "GND")
	)
	(segment
		(start 341.146384 -285.199836)
		(end 341.146384 -284.631384)
		(width 0.2286)
		(layer "F.Cu")
		(net "GND")
	)
	(segment
		(start 38.749986 -294.94988)
		(end 38.275006 -294.4749)
		(width 0.249936)
		(layer "F.Cu")
		(net "GND")
	)
	(segment
		(start 54.424834 -284.974792)
		(end 53.949854 -285.449772)
		(width 0.249936)
		(layer "F.Cu")
		(net "GND")
	)
	(segment
		(start 53.474874 -291.624766)
		(end 53.949854 -292.099746)
		(width 0.249936)
		(layer "F.Cu")
		(net "GND")
	)
	(segment
		(start 407.949908 -290.199826)
		(end 408.424888 -289.724846)
		(width 0.249936)
		(layer "F.Cu")
		(net "GND")
	)
	(segment
		(start 394.64996 -302.549814)
		(end 395.12494 -303.024794)
		(width 0.249936)
		(layer "F.Cu")
		(net "GND")
	)
	(segment
		(start 56.947308 -37.087048)
		(end 57.582308 -37.087048)
		(width 0.4572)
		(layer "F.Cu")
		(net "GND")
	)
	(segment
		(start 53.949854 -284.499812)
		(end 54.424834 -284.974792)
		(width 0.249936)
		(layer "F.Cu")
		(net "GND")
	)
	(segment
		(start 418.874956 -284.974792)
		(end 419.349936 -284.499812)
		(width 0.249936)
		(layer "F.Cu")
		(net "GND")
	)
	(segment
		(start 409.374848 -287.824926)
		(end 409.849828 -288.299906)
		(width 0.249936)
		(layer "F.Cu")
		(net "GND")
	)
	(segment
		(start 437.83631 -31.390082)
		(end 438.088532 -31.642304)
		(width 0.3556)
		(layer "F.Cu")
		(net "GND")
	)
	(segment
		(start 251.234448 -47.936658)
		(end 251.570236 -47.60087)
		(width 0.254)
		(layer "F.Cu")
		(net "GND")
	)
	(segment
		(start 299.449744 -305.399948)
		(end 298.974764 -305.874928)
		(width 0.249936)
		(layer "F.Cu")
		(net "GND")
	)
	(segment
		(start 242.117118 -218.80576)
		(end 241.475514 -218.80576)
		(width 0.3048)
		(layer "F.Cu")
		(net "GND")
	)
	(segment
		(start 414.124902 -287.824926)
		(end 414.599882 -288.299906)
		(width 0.249936)
		(layer "F.Cu")
		(net "GND")
	)
	(segment
		(start 151.618442 -252.756924)
		(end 151.618442 -253.45644)
		(width 0.4572)
		(layer "F.Cu")
		(net "GND")
	)
	(segment
		(start 155.325064 -298.27474)
		(end 155.800044 -297.79976)
		(width 0.249936)
		(layer "F.Cu")
		(net "GND")
	)
	(segment
		(start 231.607614 -259.827014)
		(end 231.620822 -259.813806)
		(width 0.254)
		(layer "F.Cu")
		(net "GND")
	)
	(segment
		(start 235.456984 -114.436144)
		(end 235.512864 -114.380264)
		(width 0.254)
		(layer "F.Cu")
		(net "GND")
	)
	(segment
		(start 311.799732 -296.8498)
		(end 312.274712 -296.37482)
		(width 0.249936)
		(layer "F.Cu")
		(net "GND")
	)
	(segment
		(start 425.99991 -300.649894)
		(end 426.47489 -301.124874)
		(width 0.249936)
		(layer "F.Cu")
		(net "GND")
	)
	(segment
		(start 421.724836 -293.52494)
		(end 422.199816 -293.99992)
		(width 0.249936)
		(layer "F.Cu")
		(net "GND")
	)
	(segment
		(start 394.64996 -298.74972)
		(end 394.17498 -299.224954)
		(width 0.249936)
		(layer "F.Cu")
		(net "GND")
	)
	(segment
		(start 288.99993 -307.299868)
		(end 288.524696 -306.824888)
		(width 0.249936)
		(layer "F.Cu")
		(net "GND")
	)
	(segment
		(start 292.32479 -284.974792)
		(end 292.79977 -284.499812)
		(width 0.249936)
		(layer "F.Cu")
		(net "GND")
	)
	(segment
		(start 71.999856 -293.04996)
		(end 71.524876 -292.574726)
		(width 0.249936)
		(layer "F.Cu")
		(net "GND")
	)
	(segment
		(start 278.074882 -294.4749)
		(end 277.599902 -293.99992)
		(width 0.249936)
		(layer "F.Cu")
		(net "GND")
	)
	(segment
		(start 320.452242 -116.416836)
		(end 319.842642 -116.416836)
		(width 0.4572)
		(layer "F.Cu")
		(net "GND")
	)
	(segment
		(start 74.374756 -298.27474)
		(end 73.899776 -298.74972)
		(width 0.249936)
		(layer "F.Cu")
		(net "GND")
	)
	(segment
		(start 64.874902 -296.37482)
		(end 65.349882 -296.8498)
		(width 0.249936)
		(layer "F.Cu")
		(net "GND")
	)
	(segment
		(start 420.573962 -73.166732)
		(end 420.573962 -73.85177)
		(width 0.4572)
		(layer "F.Cu")
		(net "GND")
	)
	(segment
		(start 302.126396 -25.832054)
		(end 302.769778 -25.832054)
		(width 0.4572)
		(layer "F.Cu")
		(net "GND")
	)
	(segment
		(start 178.731926 -167.922702)
		(end 178.731926 -168.94556)
		(width 0.4572)
		(layer "F.Cu")
		(net "GND")
	)
	(segment
		(start 73.899776 -294.94988)
		(end 74.374756 -294.4749)
		(width 0.249936)
		(layer "F.Cu")
		(net "GND")
	)
	(segment
		(start 298.024804 -284.974792)
		(end 298.499784 -285.449772)
		(width 0.249936)
		(layer "F.Cu")
		(net "GND")
	)
	(segment
		(start 54.424834 -287.824926)
		(end 53.949854 -288.299906)
		(width 0.249936)
		(layer "F.Cu")
		(net "GND")
	)
	(segment
		(start 79.12481 -290.674806)
		(end 78.64983 -291.149786)
		(width 0.249936)
		(layer "F.Cu")
		(net "GND")
	)
	(segment
		(start 308.474872 -298.27474)
		(end 307.999892 -297.79976)
		(width 0.249936)
		(layer "F.Cu")
		(net "GND")
	)
	(segment
		(start 325.82104 -103.280464)
		(end 325.82104 -103.890064)
		(width 0.4572)
		(layer "F.Cu")
		(net "GND")
	)
	(segment
		(start 135.348472 -246.13743)
		(end 134.283196 -245.072154)
		(width 0.4572)
		(layer "F.Cu")
		(net "GND")
	)
	(segment
		(start 170.049952 -306.349908)
		(end 169.574972 -306.824888)
		(width 0.249936)
		(layer "F.Cu")
		(net "GND")
	)
	(segment
		(start 331.73035 -65.92189)
		(end 331.73035 -65.15989)
		(width 0.4572)
		(layer "F.Cu")
		(net "GND")
	)
	(segment
		(start 223.679512 -231.816656)
		(end 223.679512 -232.471468)
		(width 0.4572)
		(layer "F.Cu")
		(net "GND")
	)
	(segment
		(start 289.94989 -306.349908)
		(end 289.47491 -305.874928)
		(width 0.249936)
		(layer "F.Cu")
		(net "GND")
	)
	(segment
		(start 67.724782 -284.974792)
		(end 67.249802 -284.499812)
		(width 0.249936)
		(layer "F.Cu")
		(net "GND")
	)
	(segment
		(start 81.974944 -291.624766)
		(end 81.499964 -292.099746)
		(width 0.249936)
		(layer "F.Cu")
		(net "GND")
	)
	(segment
		(start 46.932088 -104.244902)
		(end 46.042326 -104.244902)
		(width 0.3556)
		(layer "F.Cu")
		(net "GND")
	)
	(segment
		(start 63.449962 -299.699934)
		(end 63.924942 -300.174914)
		(width 0.249936)
		(layer "F.Cu")
		(net "GND")
	)
	(segment
		(start 47.77486 -305.874928)
		(end 48.24984 -305.399948)
		(width 0.249936)
		(layer "F.Cu")
		(net "GND")
	)
	(segment
		(start 166.725092 -300.174914)
		(end 166.249858 -300.649894)
		(width 0.249936)
		(layer "F.Cu")
		(net "GND")
	)
	(segment
		(start 300.874684 -293.52494)
		(end 300.399704 -293.04996)
		(width 0.249936)
		(layer "F.Cu")
		(net "GND")
	)
	(segment
		(start 47.77486 -303.024794)
		(end 47.29988 -302.549814)
		(width 0.249936)
		(layer "F.Cu")
		(net "GND")
	)
	(segment
		(start 191.900048 -295.89984)
		(end 192.375028 -296.37482)
		(width 0.249936)
		(layer "F.Cu")
		(net "GND")
	)
	(segment
		(start 67.724782 -302.074834)
		(end 68.199762 -301.599854)
		(width 0.249936)
		(layer "F.Cu")
		(net "GND")
	)
	(segment
		(start 288.524696 -306.824888)
		(end 288.99993 -306.349908)
		(width 0.249936)
		(layer "F.Cu")
		(net "GND")
	)
	(segment
		(start 50.624994 -302.074834)
		(end 51.099974 -301.599854)
		(width 0.249936)
		(layer "F.Cu")
		(net "GND")
	)
	(segment
		(start 417.450016 -307.299868)
		(end 416.974782 -306.824888)
		(width 0.249936)
		(layer "F.Cu")
		(net "GND")
	)
	(segment
		(start 406.049988 -290.199826)
		(end 406.524968 -289.724846)
		(width 0.249936)
		(layer "F.Cu")
		(net "GND")
	)
	(segment
		(start 58.224928 -302.074834)
		(end 58.699908 -301.599854)
		(width 0.249936)
		(layer "F.Cu")
		(net "GND")
	)
	(segment
		(start 161.500058 -288.299906)
		(end 161.975038 -287.824926)
		(width 0.249936)
		(layer "F.Cu")
		(net "GND")
	)
	(segment
		(start 182.87492 -302.074834)
		(end 183.3499 -301.599854)
		(width 0.249936)
		(layer "F.Cu")
		(net "GND")
	)
	(segment
		(start 68.199762 -286.399732)
		(end 68.674742 -285.924752)
		(width 0.249936)
		(layer "F.Cu")
		(net "GND")
	)
	(segment
		(start 269.049754 -282.599892)
		(end 268.574774 -282.124912)
		(width 0.249936)
		(layer "F.Cu")
		(net "GND")
	)
	(segment
		(start 160.074864 -299.224954)
		(end 160.549844 -299.699934)
		(width 0.249936)
		(layer "F.Cu")
		(net "GND")
	)
	(segment
		(start 396.54988 -291.149786)
		(end 396.0749 -290.674806)
		(width 0.249936)
		(layer "F.Cu")
		(net "GND")
	)
	(segment
		(start 66.774822 -287.824926)
		(end 67.249802 -288.299906)
		(width 0.249936)
		(layer "F.Cu")
		(net "GND")
	)
	(segment
		(start 173.850046 -285.449772)
		(end 174.325026 -284.974792)
		(width 0.249936)
		(layer "F.Cu")
		(net "GND")
	)
	(segment
		(start 384.038602 -136.241028)
		(end 383.598674 -136.680956)
		(width 0.4572)
		(layer "F.Cu")
		(net "GND")
	)
	(segment
		(start 291.84981 -285.449772)
		(end 292.32479 -284.974792)
		(width 0.249936)
		(layer "F.Cu")
		(net "GND")
	)
	(segment
		(start 176.224946 -305.874928)
		(end 175.749966 -305.399948)
		(width 0.249936)
		(layer "F.Cu")
		(net "GND")
	)
	(segment
		(start 41.26484 -31.390082)
		(end 42.28084 -31.390082)
		(width 0.3556)
		(layer "F.Cu")
		(net "GND")
	)
	(segment
		(start 340.493858 -221.58706)
		(end 340.093808 -221.98711)
		(width 0.381)
		(layer "F.Cu")
		(net "GND")
	)
	(segment
		(start 57.749948 -290.199826)
		(end 57.274968 -289.724846)
		(width 0.249936)
		(layer "F.Cu")
		(net "GND")
	)
	(segment
		(start 99.375722 -118.467886)
		(end 100.034598 -118.467886)
		(width 0.4572)
		(layer "F.Cu")
		(net "GND")
	)
	(segment
		(start 181.92496 -305.874928)
		(end 181.44998 -305.399948)
		(width 0.249936)
		(layer "F.Cu")
		(net "GND")
	)
	(segment
		(start 398.4498 -303.499774)
		(end 397.97482 -303.024794)
		(width 0.249936)
		(layer "F.Cu")
		(net "GND")
	)
	(segment
		(start 288.049716 -303.499774)
		(end 288.524696 -303.974754)
		(width 0.249936)
		(layer "F.Cu")
		(net "GND")
	)
	(segment
		(start 406.999948 -297.79976)
		(end 406.524968 -298.27474)
		(width 0.249936)
		(layer "F.Cu")
		(net "GND")
	)
	(segment
		(start 268.864842 -29.589984)
		(end 267.848842 -29.589984)
		(width 0.3556)
		(layer "F.Cu")
		(net "GND")
	)
	(segment
		(start 129.545588 -113.985802)
		(end 129.545588 -113.373408)
		(width 0.4572)
		(layer "F.Cu")
		(net "GND")
	)
	(segment
		(start 411.31744 -390.996932)
		(end 411.31744 -391.344404)
		(width 0.4572)
		(layer "F.Cu")
		(net "GND")
	)
	(segment
		(start 258.574286 -252.756924)
		(end 258.574286 -253.45644)
		(width 0.4572)
		(layer "F.Cu")
		(net "GND")
	)
	(segment
		(start 74.374756 -292.574726)
		(end 73.899776 -292.099746)
		(width 0.249936)
		(layer "F.Cu")
		(net "GND")
	)
	(segment
		(start 81.974944 -297.32478)
		(end 82.449924 -297.79976)
		(width 0.249936)
		(layer "F.Cu")
		(net "GND")
	)
	(segment
		(start 177.746406 -177.711862)
		(end 178.715416 -177.711862)
		(width 0.3556)
		(layer "F.Cu")
		(net "GND")
	)
	(segment
		(start 281.874722 -299.224954)
		(end 282.349702 -298.74972)
		(width 0.249936)
		(layer "F.Cu")
		(net "GND")
	)
	(segment
		(start 387.050026 -283.549852)
		(end 386.575046 -283.074872)
		(width 0.249936)
		(layer "F.Cu")
		(net "GND")
	)
	(segment
		(start 416.974782 -287.824926)
		(end 417.450016 -288.299906)
		(width 0.249936)
		(layer "F.Cu")
		(net "GND")
	)
	(segment
		(start 192.471548 -81.749646)
		(end 192.257426 -81.749646)
		(width 0.4064)
		(layer "F.Cu")
		(net "GND")
	)
	(segment
		(start 360.35615 -33.19018)
		(end 358.964992 -33.19018)
		(width 0.3556)
		(layer "F.Cu")
		(net "GND")
	)
	(segment
		(start 80.270858 -34.29762)
		(end 80.262476 -34.29762)
		(width 0.4572)
		(layer "F.Cu")
		(net "GND")
	)
	(segment
		(start 197.125082 -294.4749)
		(end 196.649848 -294.94988)
		(width 0.249936)
		(layer "F.Cu")
		(net "GND")
	)
	(segment
		(start 187.624974 -305.874928)
		(end 187.149994 -305.399948)
		(width 0.249936)
		(layer "F.Cu")
		(net "GND")
	)
	(segment
		(start 426.47489 -289.724846)
		(end 426.94987 -289.249866)
		(width 0.249936)
		(layer "F.Cu")
		(net "GND")
	)
	(segment
		(start 23.30831 -256.35204)
		(end 23.30831 -255.809496)
		(width 0.4572)
		(layer "F.Cu")
		(net "GND")
	)
	(segment
		(start 174.800006 -283.549852)
		(end 174.325026 -284.024832)
		(width 0.249936)
		(layer "F.Cu")
		(net "GND")
	)
	(segment
		(start 428.37481 -302.074834)
		(end 428.84979 -302.549814)
		(width 0.249936)
		(layer "F.Cu")
		(net "GND")
	)
	(segment
		(start 184.77484 -305.874928)
		(end 184.29986 -306.349908)
		(width 0.249936)
		(layer "F.Cu")
		(net "GND")
	)
	(segment
		(start 247.464834 -25.990042)
		(end 246.596154 -25.990042)
		(width 0.3556)
		(layer "F.Cu")
		(net "GND")
	)
	(segment
		(start 190.950088 -295.89984)
		(end 190.474854 -296.37482)
		(width 0.249936)
		(layer "F.Cu")
		(net "GND")
	)
	(segment
		(start 301.88408 -122.200416)
		(end 301.518574 -121.83491)
		(width 0.3556)
		(layer "F.Cu")
		(net "GND")
	)
	(segment
		(start 393.22502 -297.32478)
		(end 393.7 -296.8498)
		(width 0.249936)
		(layer "F.Cu")
		(net "GND")
	)
	(segment
		(start 429.800004 -303.499774)
		(end 430.274984 -303.024794)
		(width 0.249936)
		(layer "F.Cu")
		(net "GND")
	)
	(segment
		(start 165.774878 -297.32478)
		(end 165.299898 -297.79976)
		(width 0.249936)
		(layer "F.Cu")
		(net "GND")
	)
	(segment
		(start 41.599866 -290.199826)
		(end 41.124886 -289.724846)
		(width 0.249936)
		(layer "F.Cu")
		(net "GND")
	)
	(segment
		(start 405.100028 -301.599854)
		(end 405.575008 -302.074834)
		(width 0.249936)
		(layer "F.Cu")
		(net "GND")
	)
	(segment
		(start 394.64996 -292.099746)
		(end 394.17498 -291.624766)
		(width 0.249936)
		(layer "F.Cu")
		(net "GND")
	)
	(segment
		(start 314.649866 -295.89984)
		(end 314.174886 -296.37482)
		(width 0.249936)
		(layer "F.Cu")
		(net "GND")
	)
	(segment
		(start 408.899868 -306.349908)
		(end 409.374848 -306.824888)
		(width 0.249936)
		(layer "F.Cu")
		(net "GND")
	)
	(segment
		(start 53.474874 -284.974792)
		(end 53.949854 -285.449772)
		(width 0.249936)
		(layer "F.Cu")
		(net "GND")
	)
	(segment
		(start 302.774858 -301.124874)
		(end 302.299878 -301.599854)
		(width 0.249936)
		(layer "F.Cu")
		(net "GND")
	)
	(segment
		(start 204.764894 -25.990042)
		(end 203.748894 -25.990042)
		(width 0.3556)
		(layer "F.Cu")
		(net "GND")
	)
	(segment
		(start 409.849828 -307.299868)
		(end 410.324808 -307.774848)
		(width 0.249936)
		(layer "F.Cu")
		(net "GND")
	)
	(segment
		(start 387.050026 -285.449772)
		(end 386.575046 -284.974792)
		(width 0.249936)
		(layer "F.Cu")
		(net "GND")
	)
	(segment
		(start 179.55006 -306.349908)
		(end 180.02504 -305.874928)
		(width 0.249936)
		(layer "F.Cu")
		(net "GND")
	)
	(segment
		(start 415.96691 -114.635026)
		(end 416.95751 -114.635026)
		(width 0.3556)
		(layer "F.Cu")
		(net "GND")
	)
	(segment
		(start 395.59992 -285.449772)
		(end 395.12494 -284.974792)
		(width 0.249936)
		(layer "F.Cu")
		(net "GND")
	)
	(segment
		(start 168.150032 -284.499812)
		(end 167.675052 -284.024832)
		(width 0.249936)
		(layer "F.Cu")
		(net "GND")
	)
	(segment
		(start 107.817666 -92.768928)
		(end 107.817666 -93.436186)
		(width 0.4572)
		(layer "F.Cu")
		(net "GND")
	)
	(segment
		(start 65.824862 -284.974792)
		(end 65.349882 -285.449772)
		(width 0.249936)
		(layer "F.Cu")
		(net "GND")
	)
	(segment
		(start 223.45396 -239.046004)
		(end 222.626174 -239.046004)
		(width 0.4572)
		(layer "F.Cu")
		(net "GND")
	)
	(segment
		(start 274.749768 -279.749758)
		(end 274.274788 -279.274778)
		(width 0.249936)
		(layer "F.Cu")
		(net "GND")
	)
	(segment
		(start 194.767962 -54.067456)
		(end 195.423282 -54.067456)
		(width 0.254)
		(layer "F.Cu")
		(net "GND")
	)
	(segment
		(start 14.050772 -159.392112)
		(end 14.050772 -159.857948)
		(width 0.254)
		(layer "F.Cu")
		(net "GND")
	)
	(segment
		(start 59.649868 -288.299906)
		(end 60.049918 -287.899856)
		(width 0.249936)
		(layer "F.Cu")
		(net "GND")
	)
	(segment
		(start 71.524876 -301.124874)
		(end 71.049896 -301.599854)
		(width 0.249936)
		(layer "F.Cu")
		(net "GND")
	)
	(segment
		(start 63.449962 -301.599854)
		(end 63.924942 -302.074834)
		(width 0.249936)
		(layer "F.Cu")
		(net "GND")
	)
	(segment
		(start 154.850084 -291.149786)
		(end 154.375104 -290.674806)
		(width 0.249936)
		(layer "F.Cu")
		(net "GND")
	)
	(segment
		(start 89.744804 -29.589984)
		(end 88.664796 -29.589984)
		(width 0.3556)
		(layer "F.Cu")
		(net "GND")
	)
	(segment
		(start 349.907098 -282.021534)
		(end 349.845122 -282.021534)
		(width 0.254)
		(layer "F.Cu")
		(net "GND")
	)
	(segment
		(start 170.999912 -282.599892)
		(end 170.524932 -283.074872)
		(width 0.254)
		(layer "F.Cu")
		(net "GND")
	)
	(segment
		(start 197.125082 -301.124874)
		(end 196.649848 -300.649894)
		(width 0.249936)
		(layer "F.Cu")
		(net "GND")
	)
	(segment
		(start 234.470956 -34.29762)
		(end 234.462574 -34.29762)
		(width 0.4572)
		(layer "F.Cu")
		(net "GND")
	)
	(segment
		(start 69.684138 -122.200416)
		(end 69.318632 -121.83491)
		(width 0.3556)
		(layer "F.Cu")
		(net "GND")
	)
	(segment
		(start 49.577752 -129.964942)
		(end 50.64252 -129.964942)
		(width 0.3556)
		(layer "F.Cu")
		(net "GND")
	)
	(segment
		(start 12.053824 -305.08194)
		(end 12.573 -304.562764)
		(width 0.1778)
		(layer "F.Cu")
		(net "GND")
	)
	(segment
		(start 343.21496 -114.22634)
		(end 341.774272 -112.785652)
		(width 0.254)
		(layer "F.Cu")
		(net "GND")
	)
	(segment
		(start 229.867714 -219.904056)
		(end 230.26751 -220.303852)
		(width 0.381)
		(layer "F.Cu")
		(net "GND")
	)
	(segment
		(start 284.249876 -301.599854)
		(end 284.724856 -302.074834)
		(width 0.249936)
		(layer "F.Cu")
		(net "GND")
	)
	(segment
		(start 304.467006 -120.035066)
		(end 305.457606 -120.035066)
		(width 0.3556)
		(layer "F.Cu")
		(net "GND")
	)
	(segment
		(start 52.999894 -301.599854)
		(end 52.524914 -302.074834)
		(width 0.249936)
		(layer "F.Cu")
		(net "GND")
	)
	(segment
		(start 312.4708 -34.29762)
		(end 312.462418 -34.29762)
		(width 0.4572)
		(layer "F.Cu")
		(net "GND")
	)
	(segment
		(start 28.385516 -34.183066)
		(end 28.270962 -34.29762)
		(width 0.4572)
		(layer "F.Cu")
		(net "GND")
	)
	(segment
		(start 416.024822 -287.824926)
		(end 416.499802 -288.299906)
		(width 0.249936)
		(layer "F.Cu")
		(net "GND")
	)
	(segment
		(start 285.674816 -302.074834)
		(end 286.149796 -301.599854)
		(width 0.249936)
		(layer "F.Cu")
		(net "GND")
	)
	(segment
		(start 411.750002 -285.449772)
		(end 412.224982 -285.924752)
		(width 0.249936)
		(layer "F.Cu")
		(net "GND")
	)
	(segment
		(start 181.44998 -284.499812)
		(end 180.975 -284.974792)
		(width 0.249936)
		(layer "F.Cu")
		(net "GND")
	)
	(segment
		(start 171.949872 -303.499774)
		(end 172.424852 -303.974754)
		(width 0.249936)
		(layer "F.Cu")
		(net "GND")
	)
	(segment
		(start 156.348938 -31.390082)
		(end 157.364938 -31.390082)
		(width 0.3556)
		(layer "F.Cu")
		(net "GND")
	)
	(segment
		(start 275.224748 -300.174914)
		(end 275.699728 -299.699934)
		(width 0.249936)
		(layer "F.Cu")
		(net "GND")
	)
	(segment
		(start 402.57095 -34.29762)
		(end 402.562568 -34.29762)
		(width 0.4572)
		(layer "F.Cu")
		(net "GND")
	)
	(segment
		(start 72.949816 -295.89984)
		(end 73.424796 -296.37482)
		(width 0.249936)
		(layer "F.Cu")
		(net "GND")
	)
	(segment
		(start 410.799788 -288.299906)
		(end 411.275022 -287.824926)
		(width 0.249936)
		(layer "F.Cu")
		(net "GND")
	)
	(segment
		(start 197.972172 -33.248092)
		(end 197.972172 -33.857692)
		(width 0.4572)
		(layer "F.Cu")
		(net "GND")
	)
	(segment
		(start 298.974764 -305.874928)
		(end 298.499784 -305.399948)
		(width 0.249936)
		(layer "F.Cu")
		(net "GND")
	)
	(segment
		(start 211.1375 -213.481666)
		(end 210.766914 -213.11108)
		(width 0.4572)
		(layer "F.Cu")
		(net "GND")
	)
	(segment
		(start 182.39994 -301.599854)
		(end 181.92496 -302.074834)
		(width 0.249936)
		(layer "F.Cu")
		(net "GND")
	)
	(segment
		(start 219.60205 -208.788)
		(end 219.60205 -209.423)
		(width 0.4572)
		(layer "F.Cu")
		(net "GND")
	)
	(segment
		(start 350.093788 -214.387176)
		(end 350.493584 -213.98738)
		(width 0.381)
		(layer "F.Cu")
		(net "GND")
	)
	(segment
		(start 399.400014 -286.399732)
		(end 398.925034 -285.924752)
		(width 0.249936)
		(layer "F.Cu")
		(net "GND")
	)
	(segment
		(start 427.42485 -292.574726)
		(end 426.94987 -292.099746)
		(width 0.249936)
		(layer "F.Cu")
		(net "GND")
	)
	(segment
		(start 388.949946 -283.549852)
		(end 388.474966 -283.074872)
		(width 0.249936)
		(layer "F.Cu")
		(net "GND")
	)
	(segment
		(start 307.049932 -293.99992)
		(end 307.524912 -294.4749)
		(width 0.249936)
		(layer "F.Cu")
		(net "GND")
	)
	(segment
		(start 130.094736 -159.336232)
		(end 130.150616 -159.392112)
		(width 0.254)
		(layer "F.Cu")
		(net "GND")
	)
	(segment
		(start 51.062382 -23.355554)
		(end 51.712114 -23.355554)
		(width 0.4572)
		(layer "F.Cu")
		(net "GND")
	)
	(segment
		(start 192.850008 -293.04996)
		(end 192.375028 -293.52494)
		(width 0.249936)
		(layer "F.Cu")
		(net "GND")
	)
	(segment
		(start 303.249838 -292.099746)
		(end 302.774858 -291.624766)
		(width 0.249936)
		(layer "F.Cu")
		(net "GND")
	)
	(segment
		(start 388.949946 -292.099746)
		(end 388.474966 -292.574726)
		(width 0.249936)
		(layer "F.Cu")
		(net "GND")
	)
	(segment
		(start 168.150032 -307.299868)
		(end 167.675052 -306.824888)
		(width 0.249936)
		(layer "F.Cu")
		(net "GND")
	)
	(segment
		(start 158.649924 -274.999958)
		(end 158.174944 -274.524978)
		(width 0.249936)
		(layer "F.Cu")
		(net "GND")
	)
	(segment
		(start 406.049988 -306.349908)
		(end 406.524968 -306.824888)
		(width 0.249936)
		(layer "F.Cu")
		(net "GND")
	)
	(segment
		(start 389.56488 -27.79014)
		(end 388.54888 -27.79014)
		(width 0.3556)
		(layer "F.Cu")
		(net "GND")
	)
	(segment
		(start 128.058164 -261.814564)
		(end 128.667764 -261.814564)
		(width 0.381)
		(layer "F.Cu")
		(net "GND")
	)
	(segment
		(start 170.441874 -26.606246)
		(end 170.441874 -25.971246)
		(width 0.4572)
		(layer "F.Cu")
		(net "GND")
	)
	(segment
		(start 416.974782 -303.024794)
		(end 416.499802 -303.499774)
		(width 0.249936)
		(layer "F.Cu")
		(net "GND")
	)
	(segment
		(start 37.799772 -288.299906)
		(end 37.324792 -287.824926)
		(width 0.249936)
		(layer "F.Cu")
		(net "GND")
	)
	(segment
		(start 323.48297 -34.990024)
		(end 325.464678 -34.990024)
		(width 0.3556)
		(layer "F.Cu")
		(net "GND")
	)
	(segment
		(start 44.449746 -292.099746)
		(end 43.974766 -291.624766)
		(width 0.249936)
		(layer "F.Cu")
		(net "GND")
	)
	(segment
		(start 181.44998 -306.349908)
		(end 181.92496 -306.824888)
		(width 0.249936)
		(layer "F.Cu")
		(net "GND")
	)
	(segment
		(start 82.373724 -26.606246)
		(end 82.373724 -25.971246)
		(width 0.4572)
		(layer "F.Cu")
		(net "GND")
	)
	(segment
		(start 174.325026 -285.924752)
		(end 173.850046 -285.449772)
		(width 0.249936)
		(layer "F.Cu")
		(net "GND")
	)
	(segment
		(start 405.100028 -301.599854)
		(end 404.624794 -302.074834)
		(width 0.249936)
		(layer "F.Cu")
		(net "GND")
	)
	(segment
		(start 280.449782 -286.399732)
		(end 279.974802 -285.924752)
		(width 0.249936)
		(layer "F.Cu")
		(net "GND")
	)
	(segment
		(start 388.949946 -293.99992)
		(end 388.474966 -293.52494)
		(width 0.249936)
		(layer "F.Cu")
		(net "GND")
	)
	(segment
		(start 295.174924 -305.874928)
		(end 295.649904 -306.349908)
		(width 0.249936)
		(layer "F.Cu")
		(net "GND")
	)
	(segment
		(start 105.889044 -87.779098)
		(end 105.319068 -87.779098)
		(width 0.1778)
		(layer "F.Cu")
		(net "GND")
	)
	(segment
		(start 363.07395 -196.723)
		(end 362.458 -196.723)
		(width 0.4572)
		(layer "F.Cu")
		(net "GND")
	)
	(segment
		(start 273.799808 -293.99992)
		(end 273.324828 -293.52494)
		(width 0.249936)
		(layer "F.Cu")
		(net "GND")
	)
	(segment
		(start 289.47491 -294.4749)
		(end 288.99993 -293.99992)
		(width 0.249936)
		(layer "F.Cu")
		(net "GND")
	)
	(segment
		(start 36.849812 -278.799798)
		(end 36.374832 -278.324818)
		(width 0.249936)
		(layer "F.Cu")
		(net "GND")
	)
	(segment
		(start 419.824916 -289.724846)
		(end 419.349936 -289.249866)
		(width 0.249936)
		(layer "F.Cu")
		(net "GND")
	)
	(segment
		(start 10.316464 -277.814278)
		(end 9.706864 -277.814278)
		(width 0.4572)
		(layer "F.Cu")
		(net "GND")
	)
	(segment
		(start 56.324754 -300.174914)
		(end 55.849774 -299.699934)
		(width 0.249936)
		(layer "F.Cu")
		(net "GND")
	)
	(segment
		(start 11.62177 -305.08194)
		(end 12.053824 -305.08194)
		(width 0.1778)
		(layer "F.Cu")
		(net "GND")
	)
	(segment
		(start 418.874956 -299.224954)
		(end 418.399976 -298.74972)
		(width 0.249936)
		(layer "F.Cu")
		(net "GND")
	)
	(segment
		(start 394.64996 -305.399948)
		(end 395.12494 -305.874928)
		(width 0.249936)
		(layer "F.Cu")
		(net "GND")
	)
	(segment
		(start 103.46436 -29.079952)
		(end 103.46436 -29.571696)
		(width 0.4572)
		(layer "F.Cu")
		(net "GND")
	)
	(segment
		(start 354.097844 -38.937184)
		(end 354.834698 -38.937184)
		(width 0.4572)
		(layer "F.Cu")
		(net "GND")
	)
	(segment
		(start 64.056006 -33.19018)
		(end 62.664848 -33.19018)
		(width 0.3556)
		(layer "F.Cu")
		(net "GND")
	)
	(segment
		(start 232.517442 -67.799966)
		(end 231.388158 -67.799966)
		(width 0.3556)
		(layer "F.Cu")
		(net "GND")
	)
	(segment
		(start 49.67478 -301.124874)
		(end 50.14976 -300.649894)
		(width 0.249936)
		(layer "F.Cu")
		(net "GND")
	)
	(segment
		(start 289.94989 -299.699934)
		(end 290.42487 -300.174914)
		(width 0.249936)
		(layer "F.Cu")
		(net "GND")
	)
	(segment
		(start 408.424888 -285.924752)
		(end 408.899868 -285.449772)
		(width 0.249936)
		(layer "F.Cu")
		(net "GND")
	)
	(segment
		(start 288.524696 -285.924752)
		(end 288.049716 -286.399732)
		(width 0.249936)
		(layer "F.Cu")
		(net "GND")
	)
	(segment
		(start 346.093796 -227.186998)
		(end 346.493592 -227.586794)
		(width 0.381)
		(layer "F.Cu")
		(net "GND")
	)
	(segment
		(start 183.82488 -287.824926)
		(end 183.3499 -288.299906)
		(width 0.249936)
		(layer "F.Cu")
		(net "GND")
	)
	(segment
		(start 79.12481 -298.27474)
		(end 78.64983 -297.79976)
		(width 0.249936)
		(layer "F.Cu")
		(net "GND")
	)
	(segment
		(start 277.251668 -113.245138)
		(end 278.242268 -113.245138)
		(width 0.3556)
		(layer "F.Cu")
		(net "GND")
	)
	(segment
		(start 313.224926 -299.224954)
		(end 312.749692 -298.74972)
		(width 0.249936)
		(layer "F.Cu")
		(net "GND")
	)
	(segment
		(start 71.524876 -298.27474)
		(end 71.049896 -298.74972)
		(width 0.249936)
		(layer "F.Cu")
		(net "GND")
	)
	(segment
		(start 237.997746 -38.937184)
		(end 238.7346 -38.937184)
		(width 0.4572)
		(layer "F.Cu")
		(net "GND")
	)
	(segment
		(start 412.379414 -200.03262)
		(end 411.67177 -200.03262)
		(width 0.4572)
		(layer "F.Cu")
		(net "GND")
	)
	(segment
		(start 408.11323 -374.403874)
		(end 408.11323 -374.457468)
		(width 0.4572)
		(layer "F.Cu")
		(net "GND")
	)
	(segment
		(start 409.157932 -386.14096)
		(end 409.81884 -386.14096)
		(width 0.4572)
		(layer "F.Cu")
		(net "GND")
	)
	(segment
		(start 419.824916 -293.52494)
		(end 419.349936 -293.99992)
		(width 0.249936)
		(layer "F.Cu")
		(net "GND")
	)
	(segment
		(start 143.92783 -34.732468)
		(end 143.69542 -34.732468)
		(width 0.4572)
		(layer "F.Cu")
		(net "GND")
	)
	(segment
		(start 174.325026 -284.024832)
		(end 174.800006 -284.499812)
		(width 0.249936)
		(layer "F.Cu")
		(net "GND")
	)
	(segment
		(start 387.999986 -287.349946)
		(end 387.525006 -286.874966)
		(width 0.249936)
		(layer "F.Cu")
		(net "GND")
	)
	(segment
		(start 302.299878 -307.299868)
		(end 301.824898 -306.824888)
		(width 0.249936)
		(layer "F.Cu")
		(net "GND")
	)
	(segment
		(start 297.549824 -296.8498)
		(end 297.074844 -296.37482)
		(width 0.249936)
		(layer "F.Cu")
		(net "GND")
	)
	(segment
		(start 185.250074 -292.099746)
		(end 185.725054 -292.574726)
		(width 0.249936)
		(layer "F.Cu")
		(net "GND")
	)
	(segment
		(start 144.09166 -33.248092)
		(end 143.432276 -33.248092)
		(width 0.4572)
		(layer "F.Cu")
		(net "GND")
	)
	(segment
		(start 301.728378 -145.755106)
		(end 300.857412 -145.755106)
		(width 0.3556)
		(layer "F.Cu")
		(net "GND")
	)
	(segment
		(start 398.4498 -306.349908)
		(end 397.97482 -306.824888)
		(width 0.249936)
		(layer "F.Cu")
		(net "GND")
	)
	(segment
		(start 102.32771 -224.624392)
		(end 102.353364 -224.650046)
		(width 0.254)
		(layer "F.Cu")
		(net "GND")
	)
	(segment
		(start 174.69485 -103.814372)
		(end 174.079662 -103.814372)
		(width 0.4064)
		(layer "F.Cu")
		(net "GND")
	)
	(segment
		(start 38.749986 -293.99992)
		(end 38.275006 -293.52494)
		(width 0.249936)
		(layer "F.Cu")
		(net "GND")
	)
	(segment
		(start 17.406366 -305.19751)
		(end 18.020538 -305.19751)
		(width 0.254)
		(layer "F.Cu")
		(net "GND")
	)
	(segment
		(start 173.850046 -288.299906)
		(end 173.850046 -288.19983)
		(width 0.249936)
		(layer "F.Cu")
		(net "GND")
	)
	(segment
		(start 272.374868 -275.474938)
		(end 272.849848 -275.949918)
		(width 0.249936)
		(layer "F.Cu")
		(net "GND")
	)
	(segment
		(start 69.318632 -123.635008)
		(end 68.65747 -123.635008)
		(width 0.3556)
		(layer "F.Cu")
		(net "GND")
	)
	(segment
		(start 131.36499 -33.19018)
		(end 132.38099 -33.19018)
		(width 0.3556)
		(layer "F.Cu")
		(net "GND")
	)
	(segment
		(start 64.874902 -305.874928)
		(end 64.399922 -306.349908)
		(width 0.249936)
		(layer "F.Cu")
		(net "GND")
	)
	(segment
		(start 344.911934 -113.563654)
		(end 345.529408 -113.563654)
		(width 0.4572)
		(layer "F.Cu")
		(net "GND")
	)
	(segment
		(start 399.93316 -106.045)
		(end 398.94256 -106.045)
		(width 0.3556)
		(layer "F.Cu")
		(net "GND")
	)
	(segment
		(start 306.574698 -296.37482)
		(end 307.049932 -295.89984)
		(width 0.249936)
		(layer "F.Cu")
		(net "GND")
	)
	(segment
		(start 243.944902 -29.589984)
		(end 242.864894 -29.589984)
		(width 0.3556)
		(layer "F.Cu")
		(net "GND")
	)
	(segment
		(start 393.7 -290.199826)
		(end 393.22502 -289.724846)
		(width 0.249936)
		(layer "F.Cu")
		(net "GND")
	)
	(segment
		(start 94.809056 -94.641416)
		(end 94.809056 -93.98254)
		(width 0.4572)
		(layer "F.Cu")
		(net "GND")
	)
	(segment
		(start 172.900086 -284.499812)
		(end 173.375066 -284.974792)
		(width 0.249936)
		(layer "F.Cu")
		(net "GND")
	)
	(segment
		(start 361.811062 -378.764292)
		(end 361.232704 -378.764292)
		(width 0.3048)
		(layer "F.Cu")
		(net "GND")
	)
	(segment
		(start 198.550022 -293.99992)
		(end 199.025002 -293.52494)
		(width 0.249936)
		(layer "F.Cu")
		(net "GND")
	)
	(segment
		(start 395.12494 -302.074834)
		(end 394.64996 -301.599854)
		(width 0.249936)
		(layer "F.Cu")
		(net "GND")
	)
	(segment
		(start 44.449746 -300.649894)
		(end 44.45 -300.649894)
		(width 0.254)
		(layer "F.Cu")
		(net "GND")
	)
	(segment
		(start 296.599864 -303.499774)
		(end 296.124884 -303.974754)
		(width 0.249936)
		(layer "F.Cu")
		(net "GND")
	)
	(segment
		(start 43.974766 -299.224954)
		(end 44.449746 -299.699934)
		(width 0.249936)
		(layer "F.Cu")
		(net "GND")
	)
	(segment
		(start 302.774858 -300.174914)
		(end 302.299878 -299.699934)
		(width 0.249936)
		(layer "F.Cu")
		(net "GND")
	)
	(segment
		(start 189.999874 -296.8498)
		(end 189.524894 -297.32478)
		(width 0.249936)
		(layer "F.Cu")
		(net "GND")
	)
	(segment
		(start 10.664952 -27.79014)
		(end 9.648952 -27.79014)
		(width 0.3556)
		(layer "F.Cu")
		(net "GND")
	)
	(segment
		(start 187.149994 -302.549814)
		(end 186.675014 -303.024794)
		(width 0.249936)
		(layer "F.Cu")
		(net "GND")
	)
	(segment
		(start 128.024382 -259.145532)
		(end 128.058164 -259.11175)
		(width 0.4572)
		(layer "F.Cu")
		(net "GND")
	)
	(segment
		(start 170.524932 -306.824888)
		(end 170.049952 -307.299868)
		(width 0.249936)
		(layer "F.Cu")
		(net "GND")
	)
	(segment
		(start 69.318632 -120.035066)
		(end 68.65747 -120.035066)
		(width 0.3556)
		(layer "F.Cu")
		(net "GND")
	)
	(segment
		(start 181.593998 -188.445648)
		(end 183.133746 -188.445648)
		(width 0.4572)
		(layer "F.Cu")
		(net "GND")
	)
	(segment
		(start 445.670178 -47.60087)
		(end 446.096136 -47.60087)
		(width 0.254)
		(layer "F.Cu")
		(net "GND")
	)
	(segment
		(start 416.974782 -306.824888)
		(end 416.499802 -307.299868)
		(width 0.249936)
		(layer "F.Cu")
		(net "GND")
	)
	(segment
		(start 38.749986 -290.199826)
		(end 38.275006 -289.724846)
		(width 0.249936)
		(layer "F.Cu")
		(net "GND")
	)
	(segment
		(start 404.624794 -284.024832)
		(end 404.149814 -284.499812)
		(width 0.249936)
		(layer "F.Cu")
		(net "GND")
	)
	(segment
		(start 65.349882 -292.099746)
		(end 64.874902 -291.624766)
		(width 0.249936)
		(layer "F.Cu")
		(net "GND")
	)
	(segment
		(start 161.025078 -301.124874)
		(end 161.500058 -300.649894)
		(width 0.249936)
		(layer "F.Cu")
		(net "GND")
	)
	(segment
		(start 168.768014 -55.083456)
		(end 169.423334 -55.083456)
		(width 0.254)
		(layer "F.Cu")
		(net "GND")
	)
	(segment
		(start 303.046638 -38.49116)
		(end 302.341026 -38.49116)
		(width 0.4572)
		(layer "F.Cu")
		(net "GND")
	)
	(segment
		(start 335.664302 -29.67736)
		(end 335.664302 -29.079952)
		(width 0.4572)
		(layer "F.Cu")
		(net "GND")
	)
	(segment
		(start 167.675052 -305.874928)
		(end 168.150032 -306.349908)
		(width 0.249936)
		(layer "F.Cu")
		(net "GND")
	)
	(segment
		(start 108.506514 -390.420352)
		(end 108.506514 -389.910828)
		(width 0.4572)
		(layer "F.Cu")
		(net "GND")
	)
	(segment
		(start 61.549788 -306.349908)
		(end 61.074808 -305.874928)
		(width 0.249936)
		(layer "F.Cu")
		(net "GND")
	)
	(segment
		(start 299.866812 -134.845044)
		(end 300.857412 -134.845044)
		(width 0.3556)
		(layer "F.Cu")
		(net "GND")
	)
	(segment
		(start 180.02504 -287.824926)
		(end 179.55006 -288.299906)
		(width 0.249936)
		(layer "F.Cu")
		(net "GND")
	)
	(segment
		(start 311.324752 -300.174914)
		(end 310.849772 -300.649894)
		(width 0.249936)
		(layer "F.Cu")
		(net "GND")
	)
	(segment
		(start 229.437438 -60.600082)
		(end 228.308154 -60.600082)
		(width 0.3556)
		(layer "F.Cu")
		(net "GND")
	)
	(segment
		(start 183.82488 -291.624766)
		(end 184.29986 -292.099746)
		(width 0.249936)
		(layer "F.Cu")
		(net "GND")
	)
	(segment
		(start 420.769542 -147.55495)
		(end 421.557704 -147.55495)
		(width 0.3556)
		(layer "F.Cu")
		(net "GND")
	)
	(segment
		(start 101.5746 -240.928144)
		(end 102.281228 -240.928144)
		(width 0.254)
		(layer "F.Cu")
		(net "GND")
	)
	(segment
		(start 440.51474 -26.171398)
		(end 440.696096 -25.990042)
		(width 0.3556)
		(layer "F.Cu")
		(net "GND")
	)
	(segment
		(start 160.968944 -152.958038)
		(end 160.994344 -152.958038)
		(width 0.3556)
		(layer "F.Cu")
		(net "GND")
	)
	(segment
		(start 309.424832 -293.52494)
		(end 308.949852 -293.04996)
		(width 0.249936)
		(layer "F.Cu")
		(net "GND")
	)
	(segment
		(start 15.17396 -126.588266)
		(end 15.17396 -127.004064)
		(width 0.2032)
		(layer "F.Cu")
		(net "GND")
	)
	(segment
		(start 347.159072 -264.95756)
		(end 346.516198 -264.95756)
		(width 0.4572)
		(layer "F.Cu")
		(net "GND")
	)
	(segment
		(start 387.999986 -276.899878)
		(end 387.525006 -276.424898)
		(width 0.249936)
		(layer "F.Cu")
		(net "GND")
	)
	(segment
		(start 288.049716 -303.499774)
		(end 287.574736 -303.974754)
		(width 0.249936)
		(layer "F.Cu")
		(net "GND")
	)
	(segment
		(start 171.949872 -294.94988)
		(end 171.474892 -294.4749)
		(width 0.249936)
		(layer "F.Cu")
		(net "GND")
	)
	(segment
		(start 47.09922 -122.130312)
		(end 46.87443 -122.355102)
		(width 0.3556)
		(layer "F.Cu")
		(net "GND")
	)
	(segment
		(start 397.02486 -298.27474)
		(end 397.49984 -297.79976)
		(width 0.249936)
		(layer "F.Cu")
		(net "GND")
	)
	(segment
		(start 118.358412 -127.931926)
		(end 119.013732 -127.931926)
		(width 0.381)
		(layer "F.Cu")
		(net "GND")
	)
	(segment
		(start 66.299842 -299.699934)
		(end 65.824862 -300.174914)
		(width 0.249936)
		(layer "F.Cu")
		(net "GND")
	)
	(segment
		(start 62.024768 -287.824926)
		(end 62.499748 -288.299906)
		(width 0.249936)
		(layer "F.Cu")
		(net "GND")
	)
	(segment
		(start 418.874956 -286.874966)
		(end 419.349936 -286.399732)
		(width 0.249936)
		(layer "F.Cu")
		(net "GND")
	)
	(segment
		(start 154.37485 -299.224954)
		(end 154.850084 -298.74972)
		(width 0.249936)
		(layer "F.Cu")
		(net "GND")
	)
	(segment
		(start 52.524914 -306.824888)
		(end 52.049934 -307.299868)
		(width 0.249936)
		(layer "F.Cu")
		(net "GND")
	)
	(segment
		(start 279.499822 -307.299868)
		(end 279.024842 -306.824888)
		(width 0.249936)
		(layer "F.Cu")
		(net "GND")
	)
	(segment
		(start 48.24984 -306.349908)
		(end 47.77486 -305.874928)
		(width 0.249936)
		(layer "F.Cu")
		(net "GND")
	)
	(segment
		(start 397.49984 -286.399732)
		(end 397.02486 -285.924752)
		(width 0.249936)
		(layer "F.Cu")
		(net "GND")
	)
	(segment
		(start 384.96494 -34.990024)
		(end 383.94894 -34.990024)
		(width 0.3556)
		(layer "F.Cu")
		(net "GND")
	)
	(segment
		(start 297.549824 -286.399732)
		(end 297.074844 -285.924752)
		(width 0.249936)
		(layer "F.Cu")
		(net "GND")
	)
	(segment
		(start 221.643956 -103.85679)
		(end 221.568772 -103.781606)
		(width 0.254)
		(layer "F.Cu")
		(net "GND")
	)
	(segment
		(start 251.698506 -65.92189)
		(end 251.698506 -65.15989)
		(width 0.4572)
		(layer "F.Cu")
		(net "GND")
	)
	(segment
		(start 167.675052 -305.874928)
		(end 167.200072 -305.399948)
		(width 0.249936)
		(layer "F.Cu")
		(net "GND")
	)
	(segment
		(start 53.949854 -290.199826)
		(end 54.424834 -289.724846)
		(width 0.249936)
		(layer "F.Cu")
		(net "GND")
	)
	(segment
		(start 301.349918 -307.299868)
		(end 300.874684 -306.824888)
		(width 0.249936)
		(layer "F.Cu")
		(net "GND")
	)
	(segment
		(start 284.724856 -284.974792)
		(end 284.249876 -284.499812)
		(width 0.249936)
		(layer "F.Cu")
		(net "GND")
	)
	(segment
		(start 297.074844 -306.824888)
		(end 297.549824 -306.349908)
		(width 0.249936)
		(layer "F.Cu")
		(net "GND")
	)
	(segment
		(start 43.499786 -288.299906)
		(end 43.024806 -287.824926)
		(width 0.249936)
		(layer "F.Cu")
		(net "GND")
	)
	(segment
		(start 196.810376 -412.12643)
		(end 197.62343 -412.12643)
		(width 0.4572)
		(layer "F.Cu")
		(net "GND")
	)
	(segment
		(start 417.924996 -305.874928)
		(end 417.450016 -306.349908)
		(width 0.249936)
		(layer "F.Cu")
		(net "GND")
	)
	(segment
		(start 68.199762 -297.79976)
		(end 68.674742 -298.27474)
		(width 0.249936)
		(layer "F.Cu")
		(net "GND")
	)
	(segment
		(start 69.630544 -118.370858)
		(end 69.494654 -118.234968)
		(width 0.3556)
		(layer "F.Cu")
		(net "GND")
	)
	(segment
		(start 287.099756 -293.99992)
		(end 286.624776 -293.52494)
		(width 0.249936)
		(layer "F.Cu")
		(net "GND")
	)
	(segment
		(start 282.114498 -109.644942)
		(end 282.842462 -109.644942)
		(width 0.3556)
		(layer "F.Cu")
		(net "GND")
	)
	(segment
		(start 197.457822 -26.606246)
		(end 197.457822 -25.971246)
		(width 0.4572)
		(layer "F.Cu")
		(net "GND")
	)
	(segment
		(start 171.474892 -306.824888)
		(end 170.999912 -307.299868)
		(width 0.249936)
		(layer "F.Cu")
		(net "GND")
	)
	(segment
		(start 270.905986 -161.276284)
		(end 271.207992 -160.974278)
		(width 0.4572)
		(layer "F.Cu")
		(net "GND")
	)
	(segment
		(start 429.657764 -26.606246)
		(end 429.657764 -25.971246)
		(width 0.4572)
		(layer "F.Cu")
		(net "GND")
	)
	(segment
		(start 316.999874 -38.671754)
		(end 316.999874 -38.315138)
		(width 0.4572)
		(layer "F.Cu")
		(net "GND")
	)
	(segment
		(start 218.75369 -103.641652)
		(end 218.75369 -104.168956)
		(width 0.254)
		(layer "F.Cu")
		(net "GND")
	)
	(segment
		(start 131.367276 -197.391782)
		(end 131.367276 -196.400928)
		(width 0.3556)
		(layer "F.Cu")
		(net "GND")
	)
	(segment
		(start 194.767962 -56.353456)
		(end 195.423282 -56.353456)
		(width 0.254)
		(layer "F.Cu")
		(net "GND")
	)
	(segment
		(start 269.049754 -290.199826)
		(end 268.574774 -289.724846)
		(width 0.249936)
		(layer "F.Cu")
		(net "GND")
	)
	(segment
		(start 259.590286 -252.756924)
		(end 259.590286 -253.45644)
		(width 0.4572)
		(layer "F.Cu")
		(net "GND")
	)
	(segment
		(start 370.581936 -195.334128)
		(end 369.070128 -195.334128)
		(width 0.4572)
		(layer "F.Cu")
		(net "GND")
	)
	(segment
		(start 297.074844 -289.724846)
		(end 296.599864 -290.199826)
		(width 0.249936)
		(layer "F.Cu")
		(net "GND")
	)
	(segment
		(start 265.303254 -59.971686)
		(end 265.303254 -60.627006)
		(width 0.381)
		(layer "F.Cu")
		(net "GND")
	)
	(segment
		(start 149.382988 -306.844192)
		(end 148.738082 -306.844192)
		(width 0.4572)
		(layer "F.Cu")
		(net "GND")
	)
	(segment
		(start 179.844954 -29.589984)
		(end 178.764946 -29.589984)
		(width 0.3556)
		(layer "F.Cu")
		(net "GND")
	)
	(segment
		(start 419.349936 -290.199826)
		(end 419.824916 -289.724846)
		(width 0.249936)
		(layer "F.Cu")
		(net "GND")
	)
	(segment
		(start 281.44343 -173.229524)
		(end 281.44343 -172.172122)
		(width 0.4572)
		(layer "F.Cu")
		(net "GND")
	)
	(segment
		(start 307.524912 -294.4749)
		(end 307.999892 -293.99992)
		(width 0.249936)
		(layer "F.Cu")
		(net "GND")
	)
	(segment
		(start 398.925034 -291.624766)
		(end 399.400014 -292.099746)
		(width 0.249936)
		(layer "F.Cu")
		(net "GND")
	)
	(segment
		(start 193.799968 -293.04996)
		(end 194.274948 -293.52494)
		(width 0.249936)
		(layer "F.Cu")
		(net "GND")
	)
	(segment
		(start 299.866812 -156.554932)
		(end 300.857412 -156.554932)
		(width 0.3556)
		(layer "F.Cu")
		(net "GND")
	)
	(segment
		(start 441.303918 -291.321998)
		(end 441.938918 -291.321998)
		(width 0.4572)
		(layer "F.Cu")
		(net "GND")
	)
	(segment
		(start 369.808506 -257.852164)
		(end 369.808506 -258.665472)
		(width 0.4572)
		(layer "F.Cu")
		(net "GND")
	)
	(segment
		(start 403.199854 -303.499774)
		(end 403.674834 -303.974754)
		(width 0.249936)
		(layer "F.Cu")
		(net "GND")
	)
	(segment
		(start 166.249858 -284.499812)
		(end 165.774878 -284.024832)
		(width 0.249936)
		(layer "F.Cu")
		(net "GND")
	)
	(segment
		(start 167.732964 -113.245138)
		(end 166.742364 -113.245138)
		(width 0.3556)
		(layer "F.Cu")
		(net "GND")
	)
	(segment
		(start 19.223736 -153.1112)
		(end 19.223736 -153.782522)
		(width 0.4064)
		(layer "F.Cu")
		(net "GND")
	)
	(segment
		(start 185.725054 -294.4749)
		(end 185.250074 -294.94988)
		(width 0.249936)
		(layer "F.Cu")
		(net "GND")
	)
	(segment
		(start 176.699926 -286.399732)
		(end 177.174906 -285.924752)
		(width 0.249936)
		(layer "F.Cu")
		(net "GND")
	)
	(segment
		(start 294.22471 -284.974792)
		(end 294.69969 -284.499812)
		(width 0.249936)
		(layer "F.Cu")
		(net "GND")
	)
	(segment
		(start 334.772 -240.808002)
		(end 334.772 -240.00714)
		(width 0.3556)
		(layer "F.Cu")
		(net "GND")
	)
	(segment
		(start 399.93316 -135.364982)
		(end 398.94256 -135.364982)
		(width 0.3556)
		(layer "F.Cu")
		(net "GND")
	)
	(segment
		(start 10.664952 -34.990024)
		(end 9.648952 -34.990024)
		(width 0.3556)
		(layer "F.Cu")
		(net "GND")
	)
	(segment
		(start 60.467748 -215.1126)
		(end 62.484 -215.1126)
		(width 0.4572)
		(layer "F.Cu")
		(net "GND")
	)
	(segment
		(start 295.736264 -31.390082)
		(end 295.988486 -31.642304)
		(width 0.3556)
		(layer "F.Cu")
		(net "GND")
	)
	(segment
		(start 12.73429 -138.819636)
		(end 12.659106 -138.89482)
		(width 0.254)
		(layer "F.Cu")
		(net "GND")
	)
	(segment
		(start 298.974764 -285.924752)
		(end 298.499784 -286.399732)
		(width 0.249936)
		(layer "F.Cu")
		(net "GND")
	)
	(segment
		(start 229.437438 -66.000122)
		(end 228.308154 -66.000122)
		(width 0.3556)
		(layer "F.Cu")
		(net "GND")
	)
	(segment
		(start 57.274968 -305.874928)
		(end 57.749948 -306.349908)
		(width 0.249936)
		(layer "F.Cu")
		(net "GND")
	)
	(segment
		(start 394.17498 -300.174914)
		(end 394.64996 -299.699934)
		(width 0.249936)
		(layer "F.Cu")
		(net "GND")
	)
	(segment
		(start 419.824916 -292.574726)
		(end 419.349936 -292.099746)
		(width 0.249936)
		(layer "F.Cu")
		(net "GND")
	)
	(segment
		(start 270.407892 -155.3464)
		(end 270.407892 -156.3624)
		(width 0.4064)
		(layer "F.Cu")
		(net "GND")
	)
	(segment
		(start 37.799772 -286.399732)
		(end 37.324792 -285.924752)
		(width 0.249936)
		(layer "F.Cu")
		(net "GND")
	)
	(segment
		(start 255.911858 -346.137992)
		(end 255.911858 -344.583004)
		(width 0.4572)
		(layer "F.Cu")
		(net "GND")
	)
	(segment
		(start 317.30315 -59.971686)
		(end 316.321948 -59.971686)
		(width 0.4572)
		(layer "F.Cu")
		(net "GND")
	)
	(segment
		(start 399.93316 -124.154946)
		(end 398.94256 -124.154946)
		(width 0.3556)
		(layer "F.Cu")
		(net "GND")
	)
	(segment
		(start 17.620742 -269.446248)
		(end 17.620742 -270.100806)
		(width 0.254)
		(layer "F.Cu")
		(net "GND")
	)
	(segment
		(start 347.693742 -224.786952)
		(end 348.093538 -225.186748)
		(width 0.381)
		(layer "F.Cu")
		(net "GND")
	)
	(segment
		(start 399.93316 -152.96007)
		(end 398.94256 -152.96007)
		(width 0.3556)
		(layer "F.Cu")
		(net "GND")
	)
	(segment
		(start 293.74973 -307.299868)
		(end 294.22471 -306.824888)
		(width 0.249936)
		(layer "F.Cu")
		(net "GND")
	)
	(segment
		(start 72.474836 -300.174914)
		(end 71.999856 -299.699934)
		(width 0.249936)
		(layer "F.Cu")
		(net "GND")
	)
	(segment
		(start 37.799772 -278.799798)
		(end 37.324792 -278.324818)
		(width 0.249936)
		(layer "F.Cu")
		(net "GND")
	)
	(segment
		(start 66.299842 -286.399732)
		(end 65.824862 -285.924752)
		(width 0.249936)
		(layer "F.Cu")
		(net "GND")
	)
	(segment
		(start 280.924762 -307.774848)
		(end 280.449782 -307.299868)
		(width 0.249936)
		(layer "F.Cu")
		(net "GND")
	)
	(segment
		(start 413.649922 -301.599854)
		(end 414.124902 -302.074834)
		(width 0.249936)
		(layer "F.Cu")
		(net "GND")
	)
	(segment
		(start 406.524968 -300.174914)
		(end 406.049988 -299.699934)
		(width 0.249936)
		(layer "F.Cu")
		(net "GND")
	)
	(segment
		(start 447.675762 -121.509028)
		(end 448.311524 -121.509028)
		(width 0.4064)
		(layer "F.Cu")
		(net "GND")
	)
	(segment
		(start 176.699926 -305.399948)
		(end 177.174906 -305.874928)
		(width 0.249936)
		(layer "F.Cu")
		(net "GND")
	)
	(segment
		(start 165.774878 -294.4749)
		(end 165.299898 -293.99992)
		(width 0.249936)
		(layer "F.Cu")
		(net "GND")
	)
	(segment
		(start 44.449746 -301.599854)
		(end 44.45 -301.599854)
		(width 0.254)
		(layer "F.Cu")
		(net "GND")
	)
	(segment
		(start 397.49984 -285.449772)
		(end 397.02486 -284.974792)
		(width 0.249936)
		(layer "F.Cu")
		(net "GND")
	)
	(segment
		(start 181.92496 -287.824926)
		(end 182.39994 -288.299906)
		(width 0.249936)
		(layer "F.Cu")
		(net "GND")
	)
	(segment
		(start 399.874994 -303.974754)
		(end 400.349974 -303.499774)
		(width 0.249936)
		(layer "F.Cu")
		(net "GND")
	)
	(segment
		(start 188.525404 -133.044946)
		(end 189.357508 -133.044946)
		(width 0.3556)
		(layer "F.Cu")
		(net "GND")
	)
	(segment
		(start 66.299842 -293.99992)
		(end 65.824862 -294.4749)
		(width 0.249936)
		(layer "F.Cu")
		(net "GND")
	)
	(segment
		(start 358.964992 -33.19018)
		(end 357.948992 -33.19018)
		(width 0.3556)
		(layer "F.Cu")
		(net "GND")
	)
	(segment
		(start 292.24986 -287.899856)
		(end 292.32479 -287.899856)
		(width 0.249936)
		(layer "F.Cu")
		(net "GND")
	)
	(segment
		(start 304.45837 -116.69522)
		(end 304.718466 -116.435124)
		(width 0.3556)
		(layer "F.Cu")
		(net "GND")
	)
	(segment
		(start 313.602624 -89.1159)
		(end 313.602624 -89.790524)
		(width 0.4572)
		(layer "F.Cu")
		(net "GND")
	)
	(segment
		(start 401.299934 -284.499812)
		(end 400.824954 -284.024832)
		(width 0.249936)
		(layer "F.Cu")
		(net "GND")
	)
	(segment
		(start 294.22471 -307.774848)
		(end 294.69969 -307.299868)
		(width 0.249936)
		(layer "F.Cu")
		(net "GND")
	)
	(segment
		(start 243.217954 -178.119278)
		(end 243.217954 -177.355754)
		(width 0.4572)
		(layer "F.Cu")
		(net "GND")
	)
	(segment
		(start 365.70666 -283.07411)
		(end 365.391446 -283.07411)
		(width 0.2286)
		(layer "F.Cu")
		(net "GND")
	)
	(segment
		(start 193.134234 -86.949026)
		(end 194.030092 -86.949026)
		(width 0.381)
		(layer "F.Cu")
		(net "GND")
	)
	(segment
		(start 79.12481 -292.574726)
		(end 78.64983 -293.04996)
		(width 0.249936)
		(layer "F.Cu")
		(net "GND")
	)
	(segment
		(start 278.074882 -296.37482)
		(end 278.549862 -295.89984)
		(width 0.249936)
		(layer "F.Cu")
		(net "GND")
	)
	(segment
		(start 423.62501 -300.174914)
		(end 424.09999 -299.699934)
		(width 0.249936)
		(layer "F.Cu")
		(net "GND")
	)
	(segment
		(start 292.79977 -307.299868)
		(end 293.27475 -307.774848)
		(width 0.249936)
		(layer "F.Cu")
		(net "GND")
	)
	(segment
		(start 386.499862 -154.327352)
		(end 385.864862 -154.327352)
		(width 0.4064)
		(layer "F.Cu")
		(net "GND")
	)
	(segment
		(start 194.749928 -302.549814)
		(end 194.749928 -303.499774)
		(width 0.249936)
		(layer "F.Cu")
		(net "GND")
	)
	(segment
		(start 166.249858 -286.399732)
		(end 165.774878 -285.924752)
		(width 0.249936)
		(layer "F.Cu")
		(net "GND")
	)
	(segment
		(start 395.590014 -73.166732)
		(end 395.590014 -73.85177)
		(width 0.4572)
		(layer "F.Cu")
		(net "GND")
	)
	(segment
		(start 234.671108 -82.118708)
		(end 235.407454 -82.118708)
		(width 0.4572)
		(layer "F.Cu")
		(net "GND")
	)
	(segment
		(start 229.067614 -219.10421)
		(end 228.667818 -219.504006)
		(width 0.381)
		(layer "F.Cu")
		(net "GND")
	)
	(segment
		(start 80.54975 -302.549814)
		(end 81.024984 -302.074834)
		(width 0.249936)
		(layer "F.Cu")
		(net "GND")
	)
	(segment
		(start 336.867754 -54.067456)
		(end 337.523074 -54.067456)
		(width 0.254)
		(layer "F.Cu")
		(net "GND")
	)
	(segment
		(start 306.448206 -156.554932)
		(end 305.457606 -156.554932)
		(width 0.3556)
		(layer "F.Cu")
		(net "GND")
	)
	(segment
		(start 167.675052 -305.874928)
		(end 167.200072 -306.349908)
		(width 0.249936)
		(layer "F.Cu")
		(net "GND")
	)
	(segment
		(start 389.899906 -292.099746)
		(end 389.424926 -291.624766)
		(width 0.249936)
		(layer "F.Cu")
		(net "GND")
	)
	(segment
		(start 301.489364 -131.245102)
		(end 300.857412 -131.245102)
		(width 0.3556)
		(layer "F.Cu")
		(net "GND")
	)
	(segment
		(start 429.800004 -299.699934)
		(end 429.325024 -300.174914)
		(width 0.249936)
		(layer "F.Cu")
		(net "GND")
	)
	(segment
		(start 284.249876 -305.399948)
		(end 283.774896 -305.874928)
		(width 0.249936)
		(layer "F.Cu")
		(net "GND")
	)
	(segment
		(start 183.82488 -306.824888)
		(end 183.3499 -306.349908)
		(width 0.249936)
		(layer "F.Cu")
		(net "GND")
	)
	(segment
		(start 385.149852 -290.199826)
		(end 384.674872 -289.724846)
		(width 0.249936)
		(layer "F.Cu")
		(net "GND")
	)
	(segment
		(start 97.25787 -73.166732)
		(end 97.25787 -73.85177)
		(width 0.4572)
		(layer "F.Cu")
		(net "GND")
	)
	(segment
		(start 428.84979 -300.649894)
		(end 429.325024 -301.124874)
		(width 0.249936)
		(layer "F.Cu")
		(net "GND")
	)
	(segment
		(start 126.76505 -34.990024)
		(end 125.74905 -34.990024)
		(width 0.3556)
		(layer "F.Cu")
		(net "GND")
	)
	(segment
		(start 399.874994 -294.4749)
		(end 400.349974 -294.94988)
		(width 0.249936)
		(layer "F.Cu")
		(net "GND")
	)
	(segment
		(start 62.499748 -295.89984)
		(end 62.974982 -296.37482)
		(width 0.249936)
		(layer "F.Cu")
		(net "GND")
	)
	(segment
		(start 174.325026 -306.824888)
		(end 173.850046 -306.349908)
		(width 0.249936)
		(layer "F.Cu")
		(net "GND")
	)
	(segment
		(start 71.367904 -136.645142)
		(end 73.257664 -136.645142)
		(width 0.3556)
		(layer "F.Cu")
		(net "GND")
	)
	(segment
		(start 148.21916 -59.974734)
		(end 147.568666 -59.974734)
		(width 0.4572)
		(layer "F.Cu")
		(net "GND")
	)
	(segment
		(start 269.049754 -286.399732)
		(end 268.574774 -285.924752)
		(width 0.249936)
		(layer "F.Cu")
		(net "GND")
	)
	(segment
		(start 419.349936 -302.549814)
		(end 418.874956 -302.074834)
		(width 0.249936)
		(layer "F.Cu")
		(net "GND")
	)
	(segment
		(start 358.983788 -243.562632)
		(end 357.857298 -242.436142)
		(width 0.4572)
		(layer "F.Cu")
		(net "GND")
	)
	(segment
		(start 58.11901 -59.974734)
		(end 57.468516 -59.974734)
		(width 0.4572)
		(layer "F.Cu")
		(net "GND")
	)
	(segment
		(start 429.325024 -292.574726)
		(end 429.800004 -292.099746)
		(width 0.249936)
		(layer "F.Cu")
		(net "GND")
	)
	(segment
		(start 369.361212 -38.701218)
		(end 370.119656 -38.701218)
		(width 0.4572)
		(layer "F.Cu")
		(net "GND")
	)
	(segment
		(start 262.766302 -338.25307)
		(end 262.415782 -337.90255)
		(width 0.4572)
		(layer "F.Cu")
		(net "GND")
	)
	(segment
		(start 314.174886 -301.124874)
		(end 313.699906 -301.599854)
		(width 0.249936)
		(layer "F.Cu")
		(net "GND")
	)
	(segment
		(start 305.149758 -296.8498)
		(end 305.624738 -297.32478)
		(width 0.249936)
		(layer "F.Cu")
		(net "GND")
	)
	(segment
		(start 320.207386 -96.411542)
		(end 320.207386 -95.56115)
		(width 0.4572)
		(layer "F.Cu")
		(net "GND")
	)
	(segment
		(start 428.37481 -300.174914)
		(end 428.84979 -300.649894)
		(width 0.249936)
		(layer "F.Cu")
		(net "GND")
	)
	(segment
		(start 140.306806 -199.581516)
		(end 140.306806 -200.489058)
		(width 0.2794)
		(layer "F.Cu")
		(net "GND")
	)
	(segment
		(start 133.765798 -285.199836)
		(end 133.765798 -284.631384)
		(width 0.2286)
		(layer "F.Cu")
		(net "GND")
	)
	(segment
		(start 432.78933 -62.812168)
		(end 433.599844 -62.812168)
		(width 0.4572)
		(layer "F.Cu")
		(net "GND")
	)
	(segment
		(start 277.094442 -152.958038)
		(end 277.096474 -152.96007)
		(width 0.3556)
		(layer "F.Cu")
		(net "GND")
	)
	(segment
		(start 198.075042 -289.724846)
		(end 197.600062 -290.199826)
		(width 0.249936)
		(layer "F.Cu")
		(net "GND")
	)
	(segment
		(start 387.050026 -287.349946)
		(end 386.575046 -286.874966)
		(width 0.249936)
		(layer "F.Cu")
		(net "GND")
	)
	(segment
		(start 198.550022 -303.499774)
		(end 199.009762 -303.040034)
		(width 0.249936)
		(layer "F.Cu")
		(net "GND")
	)
	(segment
		(start 324.414642 -26.171398)
		(end 324.595998 -25.990042)
		(width 0.3556)
		(layer "F.Cu")
		(net "GND")
	)
	(segment
		(start 228.267768 -219.904056)
		(end 227.867972 -220.303852)
		(width 0.381)
		(layer "F.Cu")
		(net "GND")
	)
	(segment
		(start 49.1998 -292.099746)
		(end 48.72482 -291.624766)
		(width 0.249936)
		(layer "F.Cu")
		(net "GND")
	)
	(segment
		(start 358.09428 -285.488634)
		(end 357.805482 -285.199836)
		(width 0.2286)
		(layer "F.Cu")
		(net "GND")
	)
	(segment
		(start 400.967956 -51.019456)
		(end 401.623276 -51.019456)
		(width 0.254)
		(layer "F.Cu")
		(net "GND")
	)
	(segment
		(start 33.103312 -59.971686)
		(end 33.103312 -60.627006)
		(width 0.381)
		(layer "F.Cu")
		(net "GND")
	)
	(segment
		(start 268.802866 -91.478354)
		(end 269.412466 -91.478354)
		(width 0.4572)
		(layer "F.Cu")
		(net "GND")
	)
	(segment
		(start 198.550022 -295.89984)
		(end 199.025002 -296.37482)
		(width 0.249936)
		(layer "F.Cu")
		(net "GND")
	)
	(segment
		(start 462.324958 -307.607716)
		(end 462.938876 -307.607716)
		(width 0.254)
		(layer "F.Cu")
		(net "GND")
	)
	(segment
		(start 148.738082 -306.844192)
		(end 148.342096 -307.240178)
		(width 0.4572)
		(layer "F.Cu")
		(net "GND")
	)
	(segment
		(start 444.131192 -100.468176)
		(end 444.056008 -100.392992)
		(width 0.254)
		(layer "F.Cu")
		(net "GND")
	)
	(segment
		(start 409.374848 -305.874928)
		(end 409.849828 -305.399948)
		(width 0.249936)
		(layer "F.Cu")
		(net "GND")
	)
	(segment
		(start 393.351766 -125.955044)
		(end 394.342366 -125.955044)
		(width 0.3556)
		(layer "F.Cu")
		(net "GND")
	)
	(segment
		(start 124.14123 -172.844968)
		(end 123.609608 -172.844968)
		(width 0.4572)
		(layer "F.Cu")
		(net "GND")
	)
	(segment
		(start 320.864738 -25.990042)
		(end 319.848738 -25.990042)
		(width 0.3556)
		(layer "F.Cu")
		(net "GND")
	)
	(segment
		(start 304.199798 -302.549814)
		(end 303.724818 -303.024794)
		(width 0.249936)
		(layer "F.Cu")
		(net "GND")
	)
	(segment
		(start 296.599864 -285.449772)
		(end 296.124884 -285.924752)
		(width 0.249936)
		(layer "F.Cu")
		(net "GND")
	)
	(segment
		(start 15.264892 -29.589984)
		(end 14.248892 -29.589984)
		(width 0.3556)
		(layer "F.Cu")
		(net "GND")
	)
	(segment
		(start 395.59992 -307.299868)
		(end 396.0749 -307.774848)
		(width 0.249936)
		(layer "F.Cu")
		(net "GND")
	)
	(segment
		(start 154.154886 -34.990024)
		(end 152.764998 -34.990024)
		(width 0.3556)
		(layer "F.Cu")
		(net "GND")
	)
	(segment
		(start 251.96546 -195.973446)
		(end 251.96546 -196.589396)
		(width 0.4572)
		(layer "F.Cu")
		(net "GND")
	)
	(segment
		(start 152.94991 -278.799798)
		(end 152.47493 -278.324818)
		(width 0.249936)
		(layer "F.Cu")
		(net "GND")
	)
	(segment
		(start 268.574774 -280.224738)
		(end 269.049754 -280.699718)
		(width 0.249936)
		(layer "F.Cu")
		(net "GND")
	)
	(segment
		(start 161.358072 -73.166732)
		(end 161.358072 -73.85177)
		(width 0.4572)
		(layer "F.Cu")
		(net "GND")
	)
	(segment
		(start 28.475178 -64.102234)
		(end 27.769566 -64.102234)
		(width 0.4572)
		(layer "F.Cu")
		(net "GND")
	)
	(segment
		(start 176.699926 -303.499774)
		(end 177.174906 -303.974754)
		(width 0.249936)
		(layer "F.Cu")
		(net "GND")
	)
	(segment
		(start 441.564776 -25.990042)
		(end 442.580776 -25.990042)
		(width 0.3556)
		(layer "F.Cu")
		(net "GND")
	)
	(segment
		(start 422.548304 -129.445004)
		(end 421.557704 -129.445004)
		(width 0.3556)
		(layer "F.Cu")
		(net "GND")
	)
	(segment
		(start 429.800004 -290.199826)
		(end 429.325024 -289.724846)
		(width 0.249936)
		(layer "F.Cu")
		(net "GND")
	)
	(segment
		(start 288.072068 -33.248092)
		(end 288.072068 -33.857692)
		(width 0.4572)
		(layer "F.Cu")
		(net "GND")
	)
	(segment
		(start 147.86356 -385.15036)
		(end 148.2852 -385.572)
		(width 0.4572)
		(layer "F.Cu")
		(net "GND")
	)
	(segment
		(start 70.574916 -286.874966)
		(end 71.049896 -286.399732)
		(width 0.249936)
		(layer "F.Cu")
		(net "GND")
	)
	(segment
		(start 414.124902 -297.32478)
		(end 414.599882 -297.79976)
		(width 0.249936)
		(layer "F.Cu")
		(net "GND")
	)
	(segment
		(start 64.054736 -34.990024)
		(end 62.664848 -34.990024)
		(width 0.3556)
		(layer "F.Cu")
		(net "GND")
	)
	(segment
		(start 260.451346 -334.410304)
		(end 260.451346 -335.425034)
		(width 0.4572)
		(layer "F.Cu")
		(net "GND")
	)
	(segment
		(start 410.964888 -29.589984)
		(end 409.948888 -29.589984)
		(width 0.3556)
		(layer "F.Cu")
		(net "GND")
	)
	(segment
		(start 276.126448 -25.832054)
		(end 276.76983 -25.832054)
		(width 0.4572)
		(layer "F.Cu")
		(net "GND")
	)
	(segment
		(start 153.89987 -286.399732)
		(end 153.42489 -285.924752)
		(width 0.249936)
		(layer "F.Cu")
		(net "GND")
	)
	(segment
		(start 69.624956 -303.974754)
		(end 69.149976 -303.499774)
		(width 0.249936)
		(layer "F.Cu")
		(net "GND")
	)
	(segment
		(start 400.943826 -45.88891)
		(end 401.615148 -45.88891)
		(width 0.4572)
		(layer "F.Cu")
		(net "GND")
	)
	(segment
		(start 125.605286 -285.199836)
		(end 125.605286 -284.631384)
		(width 0.2286)
		(layer "F.Cu")
		(net "GND")
	)
	(segment
		(start 165.299898 -299.699934)
		(end 165.774878 -299.224954)
		(width 0.249936)
		(layer "F.Cu")
		(net "GND")
	)
	(segment
		(start 152.634442 -252.756924)
		(end 152.634442 -253.45644)
		(width 0.4572)
		(layer "F.Cu")
		(net "GND")
	)
	(segment
		(start 55.374794 -294.4749)
		(end 54.899814 -293.99992)
		(width 0.249936)
		(layer "F.Cu")
		(net "GND")
	)
	(segment
		(start 277.22068 -151.159972)
		(end 278.242268 -151.159972)
		(width 0.3556)
		(layer "F.Cu")
		(net "GND")
	)
	(segment
		(start 52.667154 -57.332626)
		(end 52.667154 -56.354218)
		(width 0.4572)
		(layer "F.Cu")
		(net "GND")
	)
	(segment
		(start 295.649904 -292.099746)
		(end 296.124884 -291.624766)
		(width 0.249936)
		(layer "F.Cu")
		(net "GND")
	)
	(segment
		(start 394.069316 -89.500202)
		(end 394.818362 -89.500202)
		(width 0.4572)
		(layer "F.Cu")
		(net "GND")
	)
	(segment
		(start 394.17498 -301.124874)
		(end 393.7 -300.649894)
		(width 0.254)
		(layer "F.Cu")
		(net "GND")
	)
	(segment
		(start 303.249838 -288.299906)
		(end 302.774858 -288.774886)
		(width 0.249936)
		(layer "F.Cu")
		(net "GND")
	)
	(segment
		(start 284.625034 -14.735302)
		(end 285.1277 -14.735302)
		(width 0.381)
		(layer "F.Cu")
		(net "GND")
	)
	(segment
		(start 277.251668 -122.355102)
		(end 278.242268 -122.355102)
		(width 0.3556)
		(layer "F.Cu")
		(net "GND")
	)
	(segment
		(start 420.787576 -25.742392)
		(end 420.787576 -26.360882)
		(width 0.4572)
		(layer "F.Cu")
		(net "GND")
	)
	(segment
		(start 226.87026 -306.849526)
		(end 227.438204 -306.281582)
		(width 0.4572)
		(layer "F.Cu")
		(net "GND")
	)
	(segment
		(start 70.099936 -300.649894)
		(end 70.574916 -301.124874)
		(width 0.249936)
		(layer "F.Cu")
		(net "GND")
	)
	(segment
		(start 118.358412 -130.217926)
		(end 119.013732 -130.217926)
		(width 0.381)
		(layer "F.Cu")
		(net "GND")
	)
	(segment
		(start 369.746022 -46.693836)
		(end 369.218718 -46.693836)
		(width 0.254)
		(layer "F.Cu")
		(net "GND")
	)
	(segment
		(start 143.891508 -305.334162)
		(end 143.891508 -305.507898)
		(width 0.4572)
		(layer "F.Cu")
		(net "GND")
	)
	(segment
		(start 395.657832 -102.847394)
		(end 395.255496 -102.445058)
		(width 0.3556)
		(layer "F.Cu")
		(net "GND")
	)
	(segment
		(start 251.570236 -47.60087)
		(end 251.996194 -47.60087)
		(width 0.254)
		(layer "F.Cu")
		(net "GND")
	)
	(segment
		(start 45.87494 -298.27474)
		(end 46.34992 -298.74972)
		(width 0.249936)
		(layer "F.Cu")
		(net "GND")
	)
	(segment
		(start 400.967956 -56.353456)
		(end 401.623276 -56.353456)
		(width 0.254)
		(layer "F.Cu")
		(net "GND")
	)
	(segment
		(start 387.759194 -234.046268)
		(end 387.85546 -233.950002)
		(width 0.254)
		(layer "F.Cu")
		(net "GND")
	)
	(segment
		(start 429.800004 -303.499774)
		(end 429.325024 -303.024794)
		(width 0.249936)
		(layer "F.Cu")
		(net "GND")
	)
	(segment
		(start 283.833062 -118.754906)
		(end 282.842462 -118.754906)
		(width 0.3556)
		(layer "F.Cu")
		(net "GND")
	)
	(segment
		(start 405.754078 -369.894104)
		(end 405.754078 -368.949224)
		(width 0.4572)
		(layer "F.Cu")
		(net "GND")
	)
	(segment
		(start 276.174708 -296.37482)
		(end 276.649688 -296.8498)
		(width 0.249936)
		(layer "F.Cu")
		(net "GND")
	)
	(segment
		(start 281.874722 -292.574726)
		(end 282.349702 -293.04996)
		(width 0.249936)
		(layer "F.Cu")
		(net "GND")
	)
	(segment
		(start 404.149814 -309.199788)
		(end 404.624794 -309.674768)
		(width 0.249936)
		(layer "F.Cu")
		(net "GND")
	)
	(segment
		(start 166.725092 -293.52494)
		(end 167.200072 -293.99992)
		(width 0.249936)
		(layer "F.Cu")
		(net "GND")
	)
	(segment
		(start 277.04669 -38.49116)
		(end 276.341078 -38.49116)
		(width 0.4572)
		(layer "F.Cu")
		(net "GND")
	)
	(segment
		(start 405.100028 -290.199826)
		(end 404.624794 -289.724846)
		(width 0.249936)
		(layer "F.Cu")
		(net "GND")
	)
	(segment
		(start 13.953744 -114.747802)
		(end 13.953744 -114.135408)
		(width 0.4572)
		(layer "F.Cu")
		(net "GND")
	)
	(segment
		(start 79.59979 -296.8498)
		(end 80.07477 -296.37482)
		(width 0.249936)
		(layer "F.Cu")
		(net "GND")
	)
	(segment
		(start 31.797752 -38.937184)
		(end 32.534606 -38.937184)
		(width 0.4572)
		(layer "F.Cu")
		(net "GND")
	)
	(segment
		(start 160.549844 -293.04996)
		(end 160.074864 -292.57498)
		(width 0.249936)
		(layer "F.Cu")
		(net "GND")
	)
	(segment
		(start 303.249838 -291.149786)
		(end 303.724818 -291.624766)
		(width 0.249936)
		(layer "F.Cu")
		(net "GND")
	)
	(segment
		(start 204.764894 -33.19018)
		(end 203.748894 -33.19018)
		(width 0.3556)
		(layer "F.Cu")
		(net "GND")
	)
	(segment
		(start 306.099718 -299.699934)
		(end 305.624738 -299.224954)
		(width 0.249936)
		(layer "F.Cu")
		(net "GND")
	)
	(segment
		(start 308.474872 -290.674806)
		(end 307.999892 -290.199826)
		(width 0.249936)
		(layer "F.Cu")
		(net "GND")
	)
	(segment
		(start 343.69375 -222.386906)
		(end 343.2937 -221.986856)
		(width 0.381)
		(layer "F.Cu")
		(net "GND")
	)
	(segment
		(start 410.799788 -285.449772)
		(end 411.275022 -285.924752)
		(width 0.249936)
		(layer "F.Cu")
		(net "GND")
	)
	(segment
		(start 126.205488 -282.021534)
		(end 126.143512 -282.021534)
		(width 0.254)
		(layer "F.Cu")
		(net "GND")
	)
	(segment
		(start 306.448206 -149.355048)
		(end 305.457606 -149.355048)
		(width 0.3556)
		(layer "F.Cu")
		(net "GND")
	)
	(segment
		(start 430.566068 -77.889608)
		(end 430.566068 -77.175106)
		(width 0.4572)
		(layer "F.Cu")
		(net "GND")
	)
	(segment
		(start 291.84981 -303.499774)
		(end 292.32479 -303.974754)
		(width 0.249936)
		(layer "F.Cu")
		(net "GND")
	)
	(segment
		(start 167.200072 -295.89984)
		(end 166.725092 -296.37482)
		(width 0.249936)
		(layer "F.Cu")
		(net "GND")
	)
	(segment
		(start 189.161166 -38.701218)
		(end 189.91961 -38.701218)
		(width 0.4572)
		(layer "F.Cu")
		(net "GND")
	)
	(segment
		(start 427.42485 -290.674806)
		(end 426.94987 -291.149786)
		(width 0.249936)
		(layer "F.Cu")
		(net "GND")
	)
	(segment
		(start 312.749692 -298.74972)
		(end 312.274712 -298.27474)
		(width 0.249936)
		(layer "F.Cu")
		(net "GND")
	)
	(segment
		(start 266.394184 -205.274164)
		(end 267.281406 -206.161386)
		(width 0.4572)
		(layer "F.Cu")
		(net "GND")
	)
	(segment
		(start 62.024768 -305.874928)
		(end 61.549788 -305.399948)
		(width 0.249936)
		(layer "F.Cu")
		(net "GND")
	)
	(segment
		(start 306.099718 -296.8498)
		(end 305.624738 -297.32478)
		(width 0.249936)
		(layer "F.Cu")
		(net "GND")
	)
	(segment
		(start 416.024822 -302.074834)
		(end 416.499802 -301.599854)
		(width 0.249936)
		(layer "F.Cu")
		(net "GND")
	)
	(segment
		(start 38.274752 -299.224954)
		(end 38.749986 -299.699934)
		(width 0.249936)
		(layer "F.Cu")
		(net "GND")
	)
	(segment
		(start 395.258798 -107.845098)
		(end 394.342366 -107.845098)
		(width 0.3556)
		(layer "F.Cu")
		(net "GND")
	)
	(segment
		(start 281.874722 -287.824926)
		(end 282.349702 -288.299906)
		(width 0.249936)
		(layer "F.Cu")
		(net "GND")
	)
	(segment
		(start 183.364886 -29.589984)
		(end 182.348886 -29.589984)
		(width 0.3556)
		(layer "F.Cu")
		(net "GND")
	)
	(segment
		(start 156.496258 -25.990042)
		(end 157.364938 -25.990042)
		(width 0.3556)
		(layer "F.Cu")
		(net "GND")
	)
	(segment
		(start 109.54639 -285.488634)
		(end 109.234986 -285.488634)
		(width 0.2286)
		(layer "F.Cu")
		(net "GND")
	)
	(segment
		(start 165.618668 -123.878594)
		(end 165.89502 -124.154946)
		(width 0.3556)
		(layer "F.Cu")
		(net "GND")
	)
	(segment
		(start 185.725054 -303.974754)
		(end 185.250074 -303.499774)
		(width 0.249936)
		(layer "F.Cu")
		(net "GND")
	)
	(segment
		(start 282.349702 -286.399732)
		(end 281.874722 -286.874966)
		(width 0.249936)
		(layer "F.Cu")
		(net "GND")
	)
	(segment
		(start 269.999714 -274.049744)
		(end 269.524734 -273.574764)
		(width 0.249936)
		(layer "F.Cu")
		(net "GND")
	)
	(segment
		(start 73.424796 -294.4749)
		(end 73.899776 -293.99992)
		(width 0.249936)
		(layer "F.Cu")
		(net "GND")
	)
	(segment
		(start 279.974802 -301.124874)
		(end 279.499822 -301.599854)
		(width 0.249936)
		(layer "F.Cu")
		(net "GND")
	)
	(segment
		(start 2.47523 -68.166234)
		(end 1.787144 -68.166234)
		(width 0.4572)
		(layer "F.Cu")
		(net "GND")
	)
	(segment
		(start 430.274984 -297.32478)
		(end 430.749964 -297.79976)
		(width 0.249936)
		(layer "F.Cu")
		(net "GND")
	)
	(segment
		(start 166.249858 -304.449734)
		(end 165.774878 -304.924714)
		(width 0.249936)
		(layer "F.Cu")
		(net "GND")
	)
	(segment
		(start 206.117698 -303.636426)
		(end 206.117698 -303.026826)
		(width 0.4572)
		(layer "F.Cu")
		(net "GND")
	)
	(segment
		(start 50.14976 -296.8498)
		(end 50.624994 -296.37482)
		(width 0.249936)
		(layer "F.Cu")
		(net "GND")
	)
	(segment
		(start 75.32497 -294.4749)
		(end 75.79995 -293.99992)
		(width 0.249936)
		(layer "F.Cu")
		(net "GND")
	)
	(segment
		(start 394.17498 -302.074834)
		(end 394.64996 -301.599854)
		(width 0.249936)
		(layer "F.Cu")
		(net "GND")
	)
	(segment
		(start 299.867066 -147.55495)
		(end 299.866812 -147.555204)
		(width 0.4572)
		(layer "F.Cu")
		(net "GND")
	)
	(segment
		(start 422.199816 -307.299868)
		(end 421.724836 -306.824888)
		(width 0.249936)
		(layer "F.Cu")
		(net "GND")
	)
	(segment
		(start 403.674834 -302.074834)
		(end 403.199854 -301.599854)
		(width 0.249936)
		(layer "F.Cu")
		(net "GND")
	)
	(segment
		(start 397.90497 -105.365042)
		(end 397.90497 -105.673652)
		(width 0.3556)
		(layer "F.Cu")
		(net "GND")
	)
	(segment
		(start 74.248264 -131.245102)
		(end 73.257664 -131.245102)
		(width 0.3556)
		(layer "F.Cu")
		(net "GND")
	)
	(segment
		(start 71.049896 -301.599854)
		(end 70.574916 -302.074834)
		(width 0.249936)
		(layer "F.Cu")
		(net "GND")
	)
	(segment
		(start 167.200072 -290.199826)
		(end 166.725092 -289.724846)
		(width 0.249936)
		(layer "F.Cu")
		(net "GND")
	)
	(segment
		(start 291.84981 -288.299906)
		(end 292.24986 -287.899856)
		(width 0.249936)
		(layer "F.Cu")
		(net "GND")
	)
	(segment
		(start 171.474892 -284.024832)
		(end 171.949872 -284.499812)
		(width 0.249936)
		(layer "F.Cu")
		(net "GND")
	)
	(segment
		(start 306.448206 -125.435106)
		(end 305.457606 -125.435106)
		(width 0.3556)
		(layer "F.Cu")
		(net "GND")
	)
	(segment
		(start 300.399704 -300.649894)
		(end 299.924724 -300.174914)
		(width 0.249936)
		(layer "F.Cu")
		(net "GND")
	)
	(segment
		(start 436.28183 -291.258244)
		(end 436.43804 -291.102034)
		(width 0.4572)
		(layer "F.Cu")
		(net "GND")
	)
	(segment
		(start 63.449962 -294.94988)
		(end 63.924942 -294.4749)
		(width 0.249936)
		(layer "F.Cu")
		(net "GND")
	)
	(segment
		(start 154.37485 -299.224954)
		(end 154.850084 -299.699934)
		(width 0.249936)
		(layer "F.Cu")
		(net "GND")
	)
	(segment
		(start 134.518654 -147.38604)
		(end 134.319264 -147.18665)
		(width 0.254)
		(layer "F.Cu")
		(net "GND")
	)
	(segment
		(start 279.232868 -98.845116)
		(end 278.242268 -98.845116)
		(width 0.3556)
		(layer "F.Cu")
		(net "GND")
	)
	(segment
		(start 309.55742 -29.784294)
		(end 309.664354 -29.67736)
		(width 0.4572)
		(layer "F.Cu")
		(net "GND")
	)
	(segment
		(start 165.529006 -107.407456)
		(end 165.966648 -107.845098)
		(width 0.3556)
		(layer "F.Cu")
		(net "GND")
	)
	(segment
		(start 159.599884 -273.099784)
		(end 159.124904 -272.624804)
		(width 0.249936)
		(layer "F.Cu")
		(net "GND")
	)
	(segment
		(start 396.0749 -306.824888)
		(end 395.59992 -307.299868)
		(width 0.249936)
		(layer "F.Cu")
		(net "GND")
	)
	(segment
		(start 165.966648 -107.845098)
		(end 166.742364 -107.845098)
		(width 0.3556)
		(layer "F.Cu")
		(net "GND")
	)
	(segment
		(start 211.308188 -223.140016)
		(end 211.485988 -223.317816)
		(width 0.4572)
		(layer "F.Cu")
		(net "GND")
	)
	(segment
		(start 53.474874 -306.824888)
		(end 52.999894 -307.299868)
		(width 0.249936)
		(layer "F.Cu")
		(net "GND")
	)
	(segment
		(start 347.442536 -258.14655)
		(end 347.442536 -257.13055)
		(width 0.381)
		(layer "F.Cu")
		(net "GND")
	)
	(segment
		(start 422.199816 -300.649894)
		(end 421.724836 -301.124874)
		(width 0.249936)
		(layer "F.Cu")
		(net "GND")
	)
	(segment
		(start 397.49984 -307.299868)
		(end 397.97482 -306.824888)
		(width 0.249936)
		(layer "F.Cu")
		(net "GND")
	)
	(segment
		(start 291.84981 -306.349908)
		(end 292.32479 -305.874928)
		(width 0.249936)
		(layer "F.Cu")
		(net "GND")
	)
	(segment
		(start 196.07784 -33.248092)
		(end 195.432172 -33.248092)
		(width 0.4572)
		(layer "F.Cu")
		(net "GND")
	)
	(segment
		(start 163.874958 -301.124874)
		(end 164.349938 -300.649894)
		(width 0.249936)
		(layer "F.Cu")
		(net "GND")
	)
	(segment
		(start 154.850084 -280.699718)
		(end 154.375104 -280.224738)
		(width 0.249936)
		(layer "F.Cu")
		(net "GND")
	)
	(segment
		(start 428.37481 -298.27474)
		(end 427.89983 -298.74972)
		(width 0.249936)
		(layer "F.Cu")
		(net "GND")
	)
	(segment
		(start 176.699926 -293.99992)
		(end 177.174906 -293.52494)
		(width 0.249936)
		(layer "F.Cu")
		(net "GND")
	)
	(segment
		(start 81.357724 -26.606246)
		(end 81.357724 -25.971246)
		(width 0.4572)
		(layer "F.Cu")
		(net "GND")
	)
	(segment
		(start 415.96691 -152.95499)
		(end 416.95751 -152.95499)
		(width 0.3556)
		(layer "F.Cu")
		(net "GND")
	)
	(segment
		(start 184.380886 -34.990024)
		(end 183.364886 -34.990024)
		(width 0.3556)
		(layer "F.Cu")
		(net "GND")
	)
	(segment
		(start 415.549842 -306.349908)
		(end 416.024822 -305.874928)
		(width 0.249936)
		(layer "F.Cu")
		(net "GND")
	)
	(segment
		(start 269.999714 -293.04996)
		(end 269.524734 -292.57498)
		(width 0.249936)
		(layer "F.Cu")
		(net "GND")
	)
	(segment
		(start 424.57497 -301.124874)
		(end 425.04995 -300.649894)
		(width 0.249936)
		(layer "F.Cu")
		(net "GND")
	)
	(segment
		(start 78.17485 -301.124874)
		(end 78.64983 -301.599854)
		(width 0.249936)
		(layer "F.Cu")
		(net "GND")
	)
	(segment
		(start 420.567104 -143.955008)
		(end 421.557704 -143.955008)
		(width 0.3556)
		(layer "F.Cu")
		(net "GND")
	)
	(segment
		(start 288.99993 -288.299906)
		(end 289.47491 -287.824926)
		(width 0.249936)
		(layer "F.Cu")
		(net "GND")
	)
	(segment
		(start 292.32479 -285.924752)
		(end 291.84981 -286.399732)
		(width 0.249936)
		(layer "F.Cu")
		(net "GND")
	)
	(segment
		(start 173.375066 -305.874928)
		(end 173.850046 -305.399948)
		(width 0.249936)
		(layer "F.Cu")
		(net "GND")
	)
	(segment
		(start 273.799808 -283.549852)
		(end 273.324828 -283.074872)
		(width 0.249936)
		(layer "F.Cu")
		(net "GND")
	)
	(segment
		(start 329.57008 -47.60087)
		(end 329.996038 -47.60087)
		(width 0.254)
		(layer "F.Cu")
		(net "GND")
	)
	(segment
		(start 163.399978 -304.449734)
		(end 163.874958 -304.924714)
		(width 0.249936)
		(layer "F.Cu")
		(net "GND")
	)
	(segment
		(start 301.349918 -306.349908)
		(end 300.874684 -305.874928)
		(width 0.249936)
		(layer "F.Cu")
		(net "GND")
	)
	(segment
		(start 300.874684 -307.774848)
		(end 300.399704 -307.299868)
		(width 0.249936)
		(layer "F.Cu")
		(net "GND")
	)
	(segment
		(start 273.464782 -31.390082)
		(end 272.448782 -31.390082)
		(width 0.3556)
		(layer "F.Cu")
		(net "GND")
	)
	(segment
		(start 387.050026 -297.79976)
		(end 387.525006 -298.27474)
		(width 0.249936)
		(layer "F.Cu")
		(net "GND")
	)
	(segment
		(start 73.424796 -298.27474)
		(end 73.899776 -298.74972)
		(width 0.249936)
		(layer "F.Cu")
		(net "GND")
	)
	(segment
		(start 164.824918 -307.774848)
		(end 164.349938 -307.299868)
		(width 0.249936)
		(layer "F.Cu")
		(net "GND")
	)
	(segment
		(start 53.660548 -16.439388)
		(end 53.660548 -15.474188)
		(width 0.4572)
		(layer "F.Cu")
		(net "GND")
	)
	(segment
		(start 209.282284 -118.771924)
		(end 209.176366 -118.666006)
		(width 0.254)
		(layer "F.Cu")
		(net "GND")
	)
	(segment
		(start 427.42485 -296.37482)
		(end 426.94987 -296.8498)
		(width 0.249936)
		(layer "F.Cu")
		(net "GND")
	)
	(segment
		(start 177.649886 -307.299868)
		(end 177.174906 -307.774848)
		(width 0.249936)
		(layer "F.Cu")
		(net "GND")
	)
	(segment
		(start 55.849774 -299.699934)
		(end 55.374794 -300.174914)
		(width 0.249936)
		(layer "F.Cu")
		(net "GND")
	)
	(segment
		(start 281.777694 -129.964942)
		(end 282.842462 -129.964942)
		(width 0.3556)
		(layer "F.Cu")
		(net "GND")
	)
	(segment
		(start 277.599902 -289.249866)
		(end 277.124922 -288.774886)
		(width 0.249936)
		(layer "F.Cu")
		(net "GND")
	)
	(segment
		(start 277.124668 -301.124874)
		(end 276.649688 -300.649894)
		(width 0.254)
		(layer "F.Cu")
		(net "GND")
	)
	(segment
		(start 247.464834 -34.990024)
		(end 248.480834 -34.990024)
		(width 0.3556)
		(layer "F.Cu")
		(net "GND")
	)
	(segment
		(start 355.513386 -136.328404)
		(end 354.858066 -136.328404)
		(width 0.4064)
		(layer "F.Cu")
		(net "GND")
	)
	(segment
		(start 169.099992 -285.449772)
		(end 168.625012 -285.924752)
		(width 0.249936)
		(layer "F.Cu")
		(net "GND")
	)
	(segment
		(start 40.649906 -276.899878)
		(end 40.174926 -276.424898)
		(width 0.249936)
		(layer "F.Cu")
		(net "GND")
	)
	(segment
		(start 285.199836 -301.599854)
		(end 285.674816 -302.074834)
		(width 0.249936)
		(layer "F.Cu")
		(net "GND")
	)
	(segment
		(start 54.899814 -305.399948)
		(end 54.424834 -305.874928)
		(width 0.249936)
		(layer "F.Cu")
		(net "GND")
	)
	(segment
		(start 221.42323 -55.083456)
		(end 220.76791 -55.083456)
		(width 0.254)
		(layer "F.Cu")
		(net "GND")
	)
	(segment
		(start 151.90724 -381.344932)
		(end 151.93264 -381.370332)
		(width 0.4572)
		(layer "F.Cu")
		(net "GND")
	)
	(segment
		(start 81.974944 -289.724846)
		(end 81.499964 -290.199826)
		(width 0.249936)
		(layer "F.Cu")
		(net "GND")
	)
	(segment
		(start 196.174868 -296.37482)
		(end 195.699888 -296.8498)
		(width 0.249936)
		(layer "F.Cu")
		(net "GND")
	)
	(segment
		(start 285.199836 -307.299868)
		(end 284.724856 -306.824888)
		(width 0.249936)
		(layer "F.Cu")
		(net "GND")
	)
	(segment
		(start 180.975 -303.974754)
		(end 181.44998 -303.499774)
		(width 0.249936)
		(layer "F.Cu")
		(net "GND")
	)
	(segment
		(start 144.575276 -64.102234)
		(end 143.869664 -64.102234)
		(width 0.4572)
		(layer "F.Cu")
		(net "GND")
	)
	(segment
		(start 36.6649 -27.79014)
		(end 35.6489 -27.79014)
		(width 0.3556)
		(layer "F.Cu")
		(net "GND")
	)
	(segment
		(start 171.474892 -287.824926)
		(end 170.999912 -288.299906)
		(width 0.249936)
		(layer "F.Cu")
		(net "GND")
	)
	(segment
		(start 81.499964 -297.79976)
		(end 81.974944 -297.32478)
		(width 0.249936)
		(layer "F.Cu")
		(net "GND")
	)
	(segment
		(start 81.024984 -297.32478)
		(end 80.54975 -296.8498)
		(width 0.249936)
		(layer "F.Cu")
		(net "GND")
	)
	(segment
		(start 395.447012 -52.592224)
		(end 395.522196 -52.51704)
		(width 0.254)
		(layer "F.Cu")
		(net "GND")
	)
	(segment
		(start 53.474874 -289.724846)
		(end 53.949854 -290.199826)
		(width 0.249936)
		(layer "F.Cu")
		(net "GND")
	)
	(segment
		(start 128.058164 -258.131564)
		(end 128.667764 -258.131564)
		(width 0.381)
		(layer "F.Cu")
		(net "GND")
	)
	(segment
		(start 363.531404 -126.94666)
		(end 363.45622 -127.021844)
		(width 0.2032)
		(layer "F.Cu")
		(net "GND")
	)
	(segment
		(start 414.599882 -288.299906)
		(end 415.074862 -287.824926)
		(width 0.249936)
		(layer "F.Cu")
		(net "GND")
	)
	(segment
		(start 419.349936 -291.149786)
		(end 418.874956 -290.674806)
		(width 0.249936)
		(layer "F.Cu")
		(net "GND")
	)
	(segment
		(start 419.349936 -300.649894)
		(end 418.874956 -300.174914)
		(width 0.249936)
		(layer "F.Cu")
		(net "GND")
	)
	(segment
		(start 170.382692 -28.47848)
		(end 170.043348 -28.139136)
		(width 0.254)
		(layer "F.Cu")
		(net "GND")
	)
	(segment
		(start 189.88786 -414.181036)
		(end 189.88786 -413.479234)
		(width 0.4572)
		(layer "F.Cu")
		(net "GND")
	)
	(segment
		(start 180.50002 -285.449772)
		(end 180.975 -285.924752)
		(width 0.249936)
		(layer "F.Cu")
		(net "GND")
	)
	(segment
		(start 63.466726 -384.598926)
		(end 63.408814 -384.598926)
		(width 0.4572)
		(layer "F.Cu")
		(net "GND")
	)
	(segment
		(start 296.124884 -284.974792)
		(end 296.599864 -284.499812)
		(width 0.249936)
		(layer "F.Cu")
		(net "GND")
	)
	(segment
		(start 40.649906 -292.099746)
		(end 40.174926 -292.574726)
		(width 0.249936)
		(layer "F.Cu")
		(net "GND")
	)
	(segment
		(start 209.101436 -220.39072)
		(end 208.286858 -220.39072)
		(width 0.4572)
		(layer "F.Cu")
		(net "GND")
	)
	(segment
		(start 366.630712 -258.762246)
		(end 365.91494 -259.478018)
		(width 0.3556)
		(layer "F.Cu")
		(net "GND")
	)
	(segment
		(start 320.092832 -385.942586)
		(end 320.79819 -385.942586)
		(width 0.4572)
		(layer "F.Cu")
		(net "GND")
	)
	(segment
		(start 327.544938 -236.463078)
		(end 327.544938 -235.723938)
		(width 0.4572)
		(layer "F.Cu")
		(net "GND")
	)
	(segment
		(start 191.425068 -296.37482)
		(end 191.900048 -295.89984)
		(width 0.249936)
		(layer "F.Cu")
		(net "GND")
	)
	(segment
		(start 162.450018 -292.099746)
		(end 161.975038 -291.624766)
		(width 0.249936)
		(layer "F.Cu")
		(net "GND")
	)
	(segment
		(start 42.549826 -287.349946)
		(end 42.074846 -286.874966)
		(width 0.249936)
		(layer "F.Cu")
		(net "GND")
	)
	(segment
		(start 103.946198 -223.906588)
		(end 103.427022 -224.425764)
		(width 0.1778)
		(layer "F.Cu")
		(net "GND")
	)
	(segment
		(start 36.849812 -274.049744)
		(end 37.324792 -274.524724)
		(width 0.249936)
		(layer "F.Cu")
		(net "GND")
	)
	(segment
		(start 289.94989 -306.349908)
		(end 290.42487 -306.824888)
		(width 0.249936)
		(layer "F.Cu")
		(net "GND")
	)
	(segment
		(start 388.6962 -25.990042)
		(end 388.514844 -26.171398)
		(width 0.3556)
		(layer "F.Cu")
		(net "GND")
	)
	(segment
		(start 61.549788 -284.499812)
		(end 62.024768 -284.974792)
		(width 0.249936)
		(layer "F.Cu")
		(net "GND")
	)
	(segment
		(start 245.29796 -359.120186)
		(end 248.651776 -359.120186)
		(width 0.4572)
		(layer "F.Cu")
		(net "GND")
	)
	(segment
		(start 180.02504 -285.924752)
		(end 179.55006 -286.399732)
		(width 0.249936)
		(layer "F.Cu")
		(net "GND")
	)
	(segment
		(start 251.97943 -92.496386)
		(end 251.97943 -93.105986)
		(width 0.4572)
		(layer "F.Cu")
		(net "GND")
	)
	(segment
		(start 164.349938 -284.499812)
		(end 163.874958 -284.024832)
		(width 0.249936)
		(layer "F.Cu")
		(net "GND")
	)
	(segment
		(start 58.699908 -306.349908)
		(end 58.224928 -305.874928)
		(width 0.249936)
		(layer "F.Cu")
		(net "GND")
	)
	(segment
		(start 121.79427 -35.264852)
		(end 121.79427 -35.499548)
		(width 0.4572)
		(layer "F.Cu")
		(net "GND")
	)
	(segment
		(start 11.920474 -33.19018)
		(end 10.664952 -33.19018)
		(width 0.3556)
		(layer "F.Cu")
		(net "GND")
	)
	(segment
		(start 397.95196 -118.754906)
		(end 398.94256 -118.754906)
		(width 0.3556)
		(layer "F.Cu")
		(net "GND")
	)
	(segment
		(start 390.374886 -297.32478)
		(end 389.899906 -296.8498)
		(width 0.249936)
		(layer "F.Cu")
		(net "GND")
	)
	(segment
		(start 189.524894 -293.52494)
		(end 189.049914 -293.99992)
		(width 0.249936)
		(layer "F.Cu")
		(net "GND")
	)
	(segment
		(start 358.964992 -31.390082)
		(end 357.948992 -31.390082)
		(width 0.3556)
		(layer "F.Cu")
		(net "GND")
	)
	(segment
		(start 63.924942 -294.4749)
		(end 64.399922 -293.99992)
		(width 0.249936)
		(layer "F.Cu")
		(net "GND")
	)
	(segment
		(start 251.457968 -73.166732)
		(end 251.457968 -73.85177)
		(width 0.4572)
		(layer "F.Cu")
		(net "GND")
	)
	(segment
		(start 178.124866 -305.874928)
		(end 178.599846 -306.349908)
		(width 0.249936)
		(layer "F.Cu")
		(net "GND")
	)
	(segment
		(start 410.324808 -297.32478)
		(end 409.849828 -296.8498)
		(width 0.249936)
		(layer "F.Cu")
		(net "GND")
	)
	(segment
		(start 152.94991 -275.949918)
		(end 152.47493 -275.474938)
		(width 0.249936)
		(layer "F.Cu")
		(net "GND")
	)
	(segment
		(start 44.896532 -152.96007)
		(end 44.896532 -152.958038)
		(width 0.3556)
		(layer "F.Cu")
		(net "GND")
	)
	(segment
		(start 171.972224 -33.248092)
		(end 171.972224 -33.857692)
		(width 0.4572)
		(layer "F.Cu")
		(net "GND")
	)
	(segment
		(start 187.149994 -292.099746)
		(end 187.624974 -291.624766)
		(width 0.249936)
		(layer "F.Cu")
		(net "GND")
	)
	(segment
		(start 323.233542 -303.636426)
		(end 323.233542 -303.026826)
		(width 0.4572)
		(layer "F.Cu")
		(net "GND")
	)
	(segment
		(start 418.874956 -288.774886)
		(end 419.349936 -288.299906)
		(width 0.249936)
		(layer "F.Cu")
		(net "GND")
	)
	(segment
		(start 49.67478 -294.4749)
		(end 49.1998 -293.99992)
		(width 0.249936)
		(layer "F.Cu")
		(net "GND")
	)
	(segment
		(start 399.874994 -306.824888)
		(end 399.400014 -307.299868)
		(width 0.249936)
		(layer "F.Cu")
		(net "GND")
	)
	(segment
		(start 133.919214 -282.406344)
		(end 133.738874 -282.8417)
		(width 0.2286)
		(layer "F.Cu")
		(net "GND")
	)
	(segment
		(start 298.024804 -300.174914)
		(end 298.499784 -299.699934)
		(width 0.249936)
		(layer "F.Cu")
		(net "GND")
	)
	(segment
		(start 147.4978 -392.2014)
		(end 147.4978 -392.7602)
		(width 0.4572)
		(layer "F.Cu")
		(net "GND")
	)
	(segment
		(start 68.280788 -33.19018)
		(end 67.264788 -33.19018)
		(width 0.3556)
		(layer "F.Cu")
		(net "GND")
	)
	(segment
		(start 232.517442 -64.799972)
		(end 233.572558 -64.799972)
		(width 0.3556)
		(layer "F.Cu")
		(net "GND")
	)
	(segment
		(start 294.255952 -200.822306)
		(end 294.12819 -200.950068)
		(width 0.381)
		(layer "F.Cu")
		(net "GND")
	)
	(segment
		(start 395.218666 -46.693836)
		(end 395.019276 -46.893226)
		(width 0.254)
		(layer "F.Cu")
		(net "GND")
	)
	(segment
		(start 393.7 -300.649894)
		(end 393.22502 -301.124874)
		(width 0.249936)
		(layer "F.Cu")
		(net "GND")
	)
	(segment
		(start 240.75263 -222.064072)
		(end 241.363754 -222.064072)
		(width 0.3048)
		(layer "F.Cu")
		(net "GND")
	)
	(segment
		(start 185.747914 -118.370858)
		(end 185.730388 -118.370858)
		(width 0.3556)
		(layer "F.Cu")
		(net "GND")
	)
	(segment
		(start 249.35434 -228.67493)
		(end 247.099582 -228.67493)
		(width 0.4572)
		(layer "F.Cu")
		(net "GND")
	)
	(segment
		(start 432.834542 -38.937184)
		(end 433.099972 -38.671754)
		(width 0.4572)
		(layer "F.Cu")
		(net "GND")
	)
	(segment
		(start 303.249838 -302.549814)
		(end 302.774858 -303.024794)
		(width 0.249936)
		(layer "F.Cu")
		(net "GND")
	)
	(segment
		(start 298.974764 -291.624766)
		(end 299.449744 -292.099746)
		(width 0.249936)
		(layer "F.Cu")
		(net "GND")
	)
	(segment
		(start 404.624794 -285.924752)
		(end 405.100028 -285.449772)
		(width 0.249936)
		(layer "F.Cu")
		(net "GND")
	)
	(segment
		(start 281.399742 -292.099746)
		(end 281.874722 -292.574726)
		(width 0.249936)
		(layer "F.Cu")
		(net "GND")
	)
	(segment
		(start 379.754384 -252.756924)
		(end 379.754384 -253.45644)
		(width 0.4572)
		(layer "F.Cu")
		(net "GND")
	)
	(segment
		(start 273.799808 -289.249866)
		(end 274.274788 -289.724846)
		(width 0.254)
		(layer "F.Cu")
		(net "GND")
	)
	(segment
		(start 285.674816 -306.824888)
		(end 286.149796 -306.349908)
		(width 0.249936)
		(layer "F.Cu")
		(net "GND")
	)
	(segment
		(start 187.598558 -65.92189)
		(end 187.598558 -65.15989)
		(width 0.4572)
		(layer "F.Cu")
		(net "GND")
	)
	(segment
		(start 422.674796 -292.574726)
		(end 422.199816 -293.04996)
		(width 0.249936)
		(layer "F.Cu")
		(net "GND")
	)
	(segment
		(start 358.354122 -160.70707)
		(end 358.354122 -162.672014)
		(width 0.254)
		(layer "F.Cu")
		(net "GND")
	)
	(segment
		(start 280.964894 -98.845116)
		(end 282.842462 -98.845116)
		(width 0.3556)
		(layer "F.Cu")
		(net "GND")
	)
	(segment
		(start 55.374794 -302.074834)
		(end 54.899814 -301.599854)
		(width 0.249936)
		(layer "F.Cu")
		(net "GND")
	)
	(segment
		(start 71.524876 -302.074834)
		(end 71.999856 -302.549814)
		(width 0.249936)
		(layer "F.Cu")
		(net "GND")
	)
	(segment
		(start 299.46473 -27.79014)
		(end 300.48073 -27.79014)
		(width 0.3556)
		(layer "F.Cu")
		(net "GND")
	)
	(segment
		(start 171.949872 -306.349908)
		(end 171.474892 -306.824888)
		(width 0.249936)
		(layer "F.Cu")
		(net "GND")
	)
	(segment
		(start 250.96343 -92.496386)
		(end 250.96343 -93.105986)
		(width 0.4572)
		(layer "F.Cu")
		(net "GND")
	)
	(segment
		(start 57.33415 -140.97)
		(end 57.023 -140.97)
		(width 0.4572)
		(layer "F.Cu")
		(net "GND")
	)
	(segment
		(start 167.675052 -297.32478)
		(end 167.200072 -297.79976)
		(width 0.249936)
		(layer "F.Cu")
		(net "GND")
	)
	(segment
		(start 157.364938 -33.19018)
		(end 158.380938 -33.19018)
		(width 0.3556)
		(layer "F.Cu")
		(net "GND")
	)
	(segment
		(start 285.674816 -287.824926)
		(end 286.149796 -288.299906)
		(width 0.249936)
		(layer "F.Cu")
		(net "GND")
	)
	(segment
		(start 293.74973 -306.349908)
		(end 293.27475 -306.824888)
		(width 0.249936)
		(layer "F.Cu")
		(net "GND")
	)
	(segment
		(start 403.674834 -306.824888)
		(end 403.199854 -307.299868)
		(width 0.249936)
		(layer "F.Cu")
		(net "GND")
	)
	(segment
		(start 142.525242 -14.735302)
		(end 142.525242 -14.100302)
		(width 0.381)
		(layer "F.Cu")
		(net "GND")
	)
	(segment
		(start 301.645574 -143.955008)
		(end 300.857412 -143.955008)
		(width 0.3556)
		(layer "F.Cu")
		(net "GND")
	)
	(segment
		(start 401.299934 -288.299906)
		(end 401.774914 -287.824926)
		(width 0.249936)
		(layer "F.Cu")
		(net "GND")
	)
	(segment
		(start 39.699946 -277.849838)
		(end 39.224966 -277.374858)
		(width 0.249936)
		(layer "F.Cu")
		(net "GND")
	)
	(segment
		(start 71.049896 -289.249866)
		(end 71.524876 -288.774886)
		(width 0.249936)
		(layer "F.Cu")
		(net "GND")
	)
	(segment
		(start 52.667916 -54.067456)
		(end 53.323236 -54.067456)
		(width 0.254)
		(layer "F.Cu")
		(net "GND")
	)
	(segment
		(start 423.15003 -299.699934)
		(end 422.674796 -300.174914)
		(width 0.249936)
		(layer "F.Cu")
		(net "GND")
	)
	(segment
		(start 408.424888 -306.824888)
		(end 408.899868 -306.349908)
		(width 0.249936)
		(layer "F.Cu")
		(net "GND")
	)
	(segment
		(start 173.850046 -303.499774)
		(end 174.325026 -303.974754)
		(width 0.249936)
		(layer "F.Cu")
		(net "GND")
	)
	(segment
		(start 182.87492 -305.874928)
		(end 183.3499 -305.399948)
		(width 0.249936)
		(layer "F.Cu")
		(net "GND")
	)
	(segment
		(start 167.675052 -291.624766)
		(end 167.200072 -292.099746)
		(width 0.249936)
		(layer "F.Cu")
		(net "GND")
	)
	(segment
		(start 286.149796 -286.399732)
		(end 286.624776 -285.924752)
		(width 0.249936)
		(layer "F.Cu")
		(net "GND")
	)
	(segment
		(start 299.449744 -284.499812)
		(end 299.924724 -284.974792)
		(width 0.249936)
		(layer "F.Cu")
		(net "GND")
	)
	(segment
		(start 410.799788 -284.499812)
		(end 411.275022 -284.974792)
		(width 0.249936)
		(layer "F.Cu")
		(net "GND")
	)
	(segment
		(start 313.699906 -295.89984)
		(end 313.224926 -296.37482)
		(width 0.249936)
		(layer "F.Cu")
		(net "GND")
	)
	(segment
		(start 59.649868 -296.8498)
		(end 60.124848 -297.32478)
		(width 0.249936)
		(layer "F.Cu")
		(net "GND")
	)
	(segment
		(start 39.224966 -296.37482)
		(end 39.699946 -295.89984)
		(width 0.249936)
		(layer "F.Cu")
		(net "GND")
	)
	(segment
		(start 50.624994 -305.874928)
		(end 50.14976 -305.399948)
		(width 0.249936)
		(layer "F.Cu")
		(net "GND")
	)
	(segment
		(start 165.774878 -301.124874)
		(end 166.249858 -300.649894)
		(width 0.249936)
		(layer "F.Cu")
		(net "GND")
	)
	(segment
		(start 147.794218 -35.499548)
		(end 148.166582 -35.871912)
		(width 0.4572)
		(layer "F.Cu")
		(net "GND")
	)
	(segment
		(start 406.999948 -285.449772)
		(end 406.524968 -284.974792)
		(width 0.249936)
		(layer "F.Cu")
		(net "GND")
	)
	(segment
		(start 344.49385 -217.587068)
		(end 344.8939 -217.187018)
		(width 0.381)
		(layer "F.Cu")
		(net "GND")
	)
	(segment
		(start 204.081888 -292.923468)
		(end 204.081888 -291.258244)
		(width 0.4572)
		(layer "F.Cu")
		(net "GND")
	)
	(segment
		(start 338.47405 -148.971)
		(end 339.09 -148.971)
		(width 0.4572)
		(layer "F.Cu")
		(net "GND")
	)
	(segment
		(start 298.414694 -26.171398)
		(end 298.59605 -25.990042)
		(width 0.3556)
		(layer "F.Cu")
		(net "GND")
	)
	(segment
		(start 165.963346 -113.485676)
		(end 166.203884 -113.245138)
		(width 0.3556)
		(layer "F.Cu")
		(net "GND")
	)
	(segment
		(start 160.549844 -296.8498)
		(end 160.074864 -296.37482)
		(width 0.249936)
		(layer "F.Cu")
		(net "GND")
	)
	(segment
		(start 155.800044 -292.099746)
		(end 155.325064 -292.574726)
		(width 0.249936)
		(layer "F.Cu")
		(net "GND")
	)
	(segment
		(start 176.224946 -294.4749)
		(end 176.699926 -293.99992)
		(width 0.249936)
		(layer "F.Cu")
		(net "GND")
	)
	(segment
		(start 161.15157 -129.964942)
		(end 162.14217 -129.964942)
		(width 0.3556)
		(layer "F.Cu")
		(net "GND")
	)
	(segment
		(start 19.034506 -47.936658)
		(end 19.370294 -47.60087)
		(width 0.254)
		(layer "F.Cu")
		(net "GND")
	)
	(segment
		(start 37.799772 -282.599892)
		(end 37.324792 -282.124912)
		(width 0.249936)
		(layer "F.Cu")
		(net "GND")
	)
	(segment
		(start 304.473864 -73.166732)
		(end 304.473864 -73.85177)
		(width 0.4572)
		(layer "F.Cu")
		(net "GND")
	)
	(segment
		(start 279.974802 -303.024794)
		(end 279.499822 -302.549814)
		(width 0.249936)
		(layer "F.Cu")
		(net "GND")
	)
	(segment
		(start 421.724836 -296.37482)
		(end 421.249856 -295.89984)
		(width 0.249936)
		(layer "F.Cu")
		(net "GND")
	)
	(segment
		(start 285.199836 -306.349908)
		(end 284.724856 -305.874928)
		(width 0.249936)
		(layer "F.Cu")
		(net "GND")
	)
	(segment
		(start 391.485882 -90.056462)
		(end 391.485882 -89.421462)
		(width 0.4572)
		(layer "F.Cu")
		(net "GND")
	)
	(segment
		(start 410.32684 -389.955532)
		(end 410.32684 -389.92556)
		(width 0.4572)
		(layer "F.Cu")
		(net "GND")
	)
	(segment
		(start 197.600062 -303.499774)
		(end 197.125082 -303.024794)
		(width 0.249936)
		(layer "F.Cu")
		(net "GND")
	)
	(segment
		(start 286.149796 -286.399732)
		(end 285.674816 -285.924752)
		(width 0.249936)
		(layer "F.Cu")
		(net "GND")
	)
	(segment
		(start 194.743832 -43.85691)
		(end 195.415154 -43.85691)
		(width 0.254)
		(layer "F.Cu")
		(net "GND")
	)
	(segment
		(start 397.95196 -125.955044)
		(end 398.94256 -125.955044)
		(width 0.3556)
		(layer "F.Cu")
		(net "GND")
	)
	(segment
		(start 176.699926 -301.599854)
		(end 177.174906 -302.074834)
		(width 0.249936)
		(layer "F.Cu")
		(net "GND")
	)
	(segment
		(start 306.099718 -303.499774)
		(end 305.624738 -303.024794)
		(width 0.249936)
		(layer "F.Cu")
		(net "GND")
	)
	(segment
		(start 401.299934 -285.449772)
		(end 400.824954 -284.974792)
		(width 0.249936)
		(layer "F.Cu")
		(net "GND")
	)
	(segment
		(start 312.749692 -291.149786)
		(end 312.274712 -290.674806)
		(width 0.249936)
		(layer "F.Cu")
		(net "GND")
	)
	(segment
		(start 401.774914 -287.824926)
		(end 402.249894 -288.299906)
		(width 0.249936)
		(layer "F.Cu")
		(net "GND")
	)
	(segment
		(start 54.424834 -285.924752)
		(end 54.899814 -285.449772)
		(width 0.249936)
		(layer "F.Cu")
		(net "GND")
	)
	(segment
		(start 81.974944 -303.024794)
		(end 81.499964 -303.499774)
		(width 0.249936)
		(layer "F.Cu")
		(net "GND")
	)
	(segment
		(start 297.549824 -307.299868)
		(end 298.024804 -307.774848)
		(width 0.249936)
		(layer "F.Cu")
		(net "GND")
	)
	(segment
		(start 168.767252 -57.332626)
		(end 168.767252 -56.354218)
		(width 0.4572)
		(layer "F.Cu")
		(net "GND")
	)
	(segment
		(start 279.499822 -306.349908)
		(end 279.974802 -305.874928)
		(width 0.249936)
		(layer "F.Cu")
		(net "GND")
	)
	(segment
		(start 305.346862 -53.144166)
		(end 305.346862 -52.592224)
		(width 0.254)
		(layer "F.Cu")
		(net "GND")
	)
	(segment
		(start 289.94989 -290.199826)
		(end 289.47491 -289.724846)
		(width 0.249936)
		(layer "F.Cu")
		(net "GND")
	)
	(segment
		(start 392.749786 -292.099746)
		(end 392.274806 -291.624766)
		(width 0.249936)
		(layer "F.Cu")
		(net "GND")
	)
	(segment
		(start 293.74973 -306.349908)
		(end 294.22471 -305.874928)
		(width 0.249936)
		(layer "F.Cu")
		(net "GND")
	)
	(segment
		(start 296.599864 -285.449772)
		(end 297.074844 -284.974792)
		(width 0.249936)
		(layer "F.Cu")
		(net "GND")
	)
	(segment
		(start 243.039138 -308.073298)
		(end 243.15547 -308.073298)
		(width 0.1778)
		(layer "F.Cu")
		(net "GND")
	)
	(segment
		(start 283.833062 -106.045)
		(end 282.842462 -106.045)
		(width 0.3556)
		(layer "F.Cu")
		(net "GND")
	)
	(segment
		(start 71.999856 -301.599854)
		(end 72.474836 -301.124874)
		(width 0.249936)
		(layer "F.Cu")
		(net "GND")
	)
	(segment
		(start 157.364938 -27.79014)
		(end 158.380938 -27.79014)
		(width 0.3556)
		(layer "F.Cu")
		(net "GND")
	)
	(segment
		(start 198.250302 -81.698846)
		(end 197.343522 -81.698846)
		(width 0.4064)
		(layer "F.Cu")
		(net "GND")
	)
	(segment
		(start 412.699962 -285.449772)
		(end 412.224982 -284.974792)
		(width 0.249936)
		(layer "F.Cu")
		(net "GND")
	)
	(segment
		(start 166.249858 -287.349946)
		(end 165.774878 -286.874966)
		(width 0.249936)
		(layer "F.Cu")
		(net "GND")
	)
	(segment
		(start 146.134328 -387.660896)
		(end 146.134328 -387.02996)
		(width 0.4572)
		(layer "F.Cu")
		(net "GND")
	)
	(segment
		(start 410.799788 -297.79976)
		(end 410.324808 -297.32478)
		(width 0.249936)
		(layer "F.Cu")
		(net "GND")
	)
	(segment
		(start 306.099718 -300.649894)
		(end 305.624738 -301.124874)
		(width 0.249936)
		(layer "F.Cu")
		(net "GND")
	)
	(segment
		(start 125.605286 -284.631384)
		(end 125.398022 -284.42412)
		(width 0.2286)
		(layer "F.Cu")
		(net "GND")
	)
	(segment
		(start 341.146892 -38.49116)
		(end 340.44128 -38.49116)
		(width 0.4572)
		(layer "F.Cu")
		(net "GND")
	)
	(segment
		(start 367.670334 -47.60087)
		(end 368.096292 -47.60087)
		(width 0.254)
		(layer "F.Cu")
		(net "GND")
	)
	(segment
		(start 97.648268 -393.1158)
		(end 97.032318 -393.1158)
		(width 0.4572)
		(layer "F.Cu")
		(net "GND")
	)
	(segment
		(start 279.13203 -104.244902)
		(end 278.242268 -104.244902)
		(width 0.3556)
		(layer "F.Cu")
		(net "GND")
	)
	(segment
		(start 385.149852 -284.499812)
		(end 384.674872 -284.024832)
		(width 0.249936)
		(layer "F.Cu")
		(net "GND")
	)
	(segment
		(start 62.974982 -289.724846)
		(end 63.449962 -290.199826)
		(width 0.249936)
		(layer "F.Cu")
		(net "GND")
	)
	(segment
		(start 51.099974 -305.399948)
		(end 51.574954 -305.874928)
		(width 0.249936)
		(layer "F.Cu")
		(net "GND")
	)
	(segment
		(start 184.29986 -303.499774)
		(end 184.770014 -303.969928)
		(width 0.249936)
		(layer "F.Cu")
		(net "GND")
	)
	(segment
		(start 199.794114 -35.264852)
		(end 199.794114 -35.499548)
		(width 0.4572)
		(layer "F.Cu")
		(net "GND")
	)
	(segment
		(start 88.664796 -33.19018)
		(end 87.648796 -33.19018)
		(width 0.3556)
		(layer "F.Cu")
		(net "GND")
	)
	(segment
		(start 415.564828 -25.990042)
		(end 416.580828 -25.990042)
		(width 0.3556)
		(layer "F.Cu")
		(net "GND")
	)
	(segment
		(start 187.149994 -286.399732)
		(end 186.675014 -286.874966)
		(width 0.249936)
		(layer "F.Cu")
		(net "GND")
	)
	(segment
		(start 309.899812 -289.249866)
		(end 309.424832 -289.724846)
		(width 0.249936)
		(layer "F.Cu")
		(net "GND")
	)
	(segment
		(start 4.481576 -378.370592)
		(end 5.472176 -378.370592)
		(width 0.381)
		(layer "F.Cu")
		(net "GND")
	)
	(segment
		(start 50.14976 -284.499812)
		(end 49.67478 -284.024832)
		(width 0.249936)
		(layer "F.Cu")
		(net "GND")
	)
	(segment
		(start 161.15157 -133.565138)
		(end 162.14217 -133.565138)
		(width 0.3556)
		(layer "F.Cu")
		(net "GND")
	)
	(segment
		(start 59.649868 -290.199826)
		(end 60.124848 -289.724846)
		(width 0.249936)
		(layer "F.Cu")
		(net "GND")
	)
	(segment
		(start 279.232868 -118.754906)
		(end 278.242268 -118.754906)
		(width 0.3556)
		(layer "F.Cu")
		(net "GND")
	)
	(segment
		(start 44.45 -301.599854)
		(end 44.92498 -301.124874)
		(width 0.254)
		(layer "F.Cu")
		(net "GND")
	)
	(segment
		(start 172.424852 -284.024832)
		(end 172.900086 -284.499812)
		(width 0.249936)
		(layer "F.Cu")
		(net "GND")
	)
	(segment
		(start 60.070492 -374.79351)
		(end 60.070492 -373.538496)
		(width 0.4572)
		(layer "F.Cu")
		(net "GND")
	)
	(segment
		(start 153.89987 -273.099784)
		(end 154.37485 -273.574764)
		(width 0.249936)
		(layer "F.Cu")
		(net "GND")
	)
	(segment
		(start 67.249802 -286.399732)
		(end 66.774822 -285.924752)
		(width 0.249936)
		(layer "F.Cu")
		(net "GND")
	)
	(segment
		(start 288.88944 -64.312292)
		(end 289.647884 -64.312292)
		(width 0.4572)
		(layer "F.Cu")
		(net "GND")
	)
	(segment
		(start 306.099718 -282.599892)
		(end 307.049678 -282.599892)
		(width 0.254)
		(layer "F.Cu")
		(net "GND")
	)
	(segment
		(start 281.874722 -288.774886)
		(end 282.349702 -289.249866)
		(width 0.249936)
		(layer "F.Cu")
		(net "GND")
	)
	(segment
		(start 313.699906 -303.499774)
		(end 314.174886 -303.024794)
		(width 0.254)
		(layer "F.Cu")
		(net "GND")
	)
	(segment
		(start 406.999948 -288.149792)
		(end 406.999948 -288.299906)
		(width 0.249936)
		(layer "F.Cu")
		(net "GND")
	)
	(segment
		(start 170.485562 -34.183066)
		(end 170.371008 -34.29762)
		(width 0.4572)
		(layer "F.Cu")
		(net "GND")
	)
	(segment
		(start 137.16127 -38.701218)
		(end 137.919714 -38.701218)
		(width 0.4572)
		(layer "F.Cu")
		(net "GND")
	)
	(segment
		(start 337.824318 -119.026178)
		(end 338.563458 -119.026178)
		(width 0.4572)
		(layer "F.Cu")
		(net "GND")
	)
	(segment
		(start 209.103976 -291.321998)
		(end 209.738976 -291.321998)
		(width 0.4572)
		(layer "F.Cu")
		(net "GND")
	)
	(segment
		(start 410.50337 -205.114144)
		(end 409.99791 -205.114144)
		(width 0.4572)
		(layer "F.Cu")
		(net "GND")
	)
	(segment
		(start 189.999874 -295.89984)
		(end 190.474854 -296.37482)
		(width 0.249936)
		(layer "F.Cu")
		(net "GND")
	)
	(segment
		(start 49.863502 -113.780062)
		(end 49.863502 -113.485676)
		(width 0.3556)
		(layer "F.Cu")
		(net "GND")
	)
	(segment
		(start 85.103208 -59.971686)
		(end 85.103208 -60.627006)
		(width 0.381)
		(layer "F.Cu")
		(net "GND")
	)
	(segment
		(start 194.749928 -298.74972)
		(end 194.274948 -299.224954)
		(width 0.249936)
		(layer "F.Cu")
		(net "GND")
	)
	(segment
		(start 126.76505 -25.990042)
		(end 125.74905 -25.990042)
		(width 0.3556)
		(layer "F.Cu")
		(net "GND")
	)
	(segment
		(start 290.89985 -283.549852)
		(end 290.42487 -283.074872)
		(width 0.249936)
		(layer "F.Cu")
		(net "GND")
	)
	(segment
		(start 52.999894 -306.349908)
		(end 52.524914 -306.824888)
		(width 0.249936)
		(layer "F.Cu")
		(net "GND")
	)
	(segment
		(start 313.224926 -288.774886)
		(end 312.749692 -289.249866)
		(width 0.249936)
		(layer "F.Cu")
		(net "GND")
	)
	(segment
		(start 141.517878 -189.778132)
		(end 141.684502 -189.944756)
		(width 0.3556)
		(layer "F.Cu")
		(net "GND")
	)
	(segment
		(start 231.46766 -215.904064)
		(end 231.867456 -215.504268)
		(width 0.381)
		(layer "F.Cu")
		(net "GND")
	)
	(segment
		(start 39.757604 -142.892018)
		(end 39.90086 -142.748762)
		(width 0.4572)
		(layer "F.Cu")
		(net "GND")
	)
	(segment
		(start 153.89987 -277.849838)
		(end 153.42489 -277.374858)
		(width 0.249936)
		(layer "F.Cu")
		(net "GND")
	)
	(segment
		(start 258.94538 -196.081396)
		(end 259.56133 -196.081396)
		(width 0.4572)
		(layer "F.Cu")
		(net "GND")
	)
	(segment
		(start 145.360898 -311.442608)
		(end 145.36039 -311.442608)
		(width 0.4572)
		(layer "F.Cu")
		(net "GND")
	)
	(segment
		(start 103.22941 -222.20936)
		(end 102.968298 -222.20936)
		(width 0.4572)
		(layer "F.Cu")
		(net "GND")
	)
	(segment
		(start 66.774822 -285.924752)
		(end 66.299842 -285.449772)
		(width 0.249936)
		(layer "F.Cu")
		(net "GND")
	)
	(segment
		(start 306.448206 -147.55495)
		(end 305.457606 -147.55495)
		(width 0.3556)
		(layer "F.Cu")
		(net "GND")
	)
	(segment
		(start 416.499802 -292.099746)
		(end 416.974782 -292.574726)
		(width 0.249936)
		(layer "F.Cu")
		(net "GND")
	)
	(segment
		(start 60.124848 -284.974792)
		(end 60.599828 -284.499812)
		(width 0.249936)
		(layer "F.Cu")
		(net "GND")
	)
	(segment
		(start 203.748894 -31.390082)
		(end 204.764894 -31.390082)
		(width 0.3556)
		(layer "F.Cu")
		(net "GND")
	)
	(segment
		(start 287.574736 -289.724846)
		(end 288.049716 -290.199826)
		(width 0.249936)
		(layer "F.Cu")
		(net "GND")
	)
	(segment
		(start 384.674872 -298.274486)
		(end 385.149852 -298.74972)
		(width 0.249936)
		(layer "F.Cu")
		(net "GND")
	)
	(segment
		(start 249.047254 -347.89999)
		(end 249.809254 -347.89999)
		(width 0.4572)
		(layer "F.Cu")
		(net "GND")
	)
	(segment
		(start 117.260116 -282.406344)
		(end 117.079776 -282.8417)
		(width 0.2286)
		(layer "F.Cu")
		(net "GND")
	)
	(segment
		(start 282.349702 -307.299868)
		(end 282.824936 -306.824888)
		(width 0.249936)
		(layer "F.Cu")
		(net "GND")
	)
	(segment
		(start 54.424834 -289.724846)
		(end 54.899814 -290.199826)
		(width 0.249936)
		(layer "F.Cu")
		(net "GND")
	)
	(segment
		(start 394.074904 -48.753014)
		(end 393.368276 -48.753014)
		(width 0.254)
		(layer "F.Cu")
		(net "GND")
	)
	(segment
		(start 241.910362 -122.931428)
		(end 241.255042 -122.931428)
		(width 0.4064)
		(layer "F.Cu")
		(net "GND")
	)
	(segment
		(start 41.599866 -294.94988)
		(end 41.124886 -294.4749)
		(width 0.249936)
		(layer "F.Cu")
		(net "GND")
	)
	(segment
		(start 431.994056 -35.499548)
		(end 432.36642 -35.871912)
		(width 0.4572)
		(layer "F.Cu")
		(net "GND")
	)
	(segment
		(start 26.667968 -56.353456)
		(end 27.323288 -56.353456)
		(width 0.254)
		(layer "F.Cu")
		(net "GND")
	)
	(segment
		(start 216.937844 -98.40595)
		(end 216.937844 -97.79)
		(width 0.4572)
		(layer "F.Cu")
		(net "GND")
	)
	(segment
		(start 281.629104 -107.407456)
		(end 282.066746 -107.845098)
		(width 0.3556)
		(layer "F.Cu")
		(net "GND")
	)
	(segment
		(start 334.89392 -223.987106)
		(end 334.494124 -224.386902)
		(width 0.381)
		(layer "F.Cu")
		(net "GND")
	)
	(segment
		(start 293.629842 -172.329348)
		(end 293.629842 -171.661328)
		(width 0.4572)
		(layer "F.Cu")
		(net "GND")
	)
	(segment
		(start 180.50002 -286.399732)
		(end 180.02504 -285.924752)
		(width 0.249936)
		(layer "F.Cu")
		(net "GND")
	)
	(segment
		(start 270.949928 -279.749758)
		(end 270.474948 -279.274778)
		(width 0.249936)
		(layer "F.Cu")
		(net "GND")
	)
	(segment
		(start 410.40304 -388.253732)
		(end 411.1752 -388.253732)
		(width 0.4572)
		(layer "F.Cu")
		(net "GND")
	)
	(segment
		(start 459.42631 -273.224752)
		(end 460.323184 -273.224752)
		(width 0.4572)
		(layer "F.Cu")
		(net "GND")
	)
	(segment
		(start 61.173868 -388.73684)
		(end 61.173868 -388.787132)
		(width 0.4572)
		(layer "F.Cu")
		(net "GND")
	)
	(segment
		(start 167.732964 -106.045)
		(end 166.742364 -106.045)
		(width 0.3556)
		(layer "F.Cu")
		(net "GND")
	)
	(segment
		(start 278.549862 -305.399948)
		(end 279.024842 -304.924714)
		(width 0.249936)
		(layer "F.Cu")
		(net "GND")
	)
	(segment
		(start 425.52493 -291.624766)
		(end 425.99991 -291.149786)
		(width 0.249936)
		(layer "F.Cu")
		(net "GND")
	)
	(segment
		(start 152.461468 -391.58164)
		(end 152.461468 -392.419332)
		(width 0.4572)
		(layer "F.Cu")
		(net "GND")
	)
	(segment
		(start 173.375066 -291.624766)
		(end 172.900086 -292.099746)
		(width 0.249936)
		(layer "F.Cu")
		(net "GND")
	)
	(segment
		(start 68.674742 -286.874966)
		(end 68.199762 -287.349946)
		(width 0.249936)
		(layer "F.Cu")
		(net "GND")
	)
	(segment
		(start 170.049952 -303.499774)
		(end 169.574972 -303.974754)
		(width 0.249936)
		(layer "F.Cu")
		(net "GND")
	)
	(segment
		(start 68.674742 -291.624766)
		(end 68.199762 -291.149786)
		(width 0.249936)
		(layer "F.Cu")
		(net "GND")
	)
	(segment
		(start 406.999948 -303.499774)
		(end 406.524968 -303.974754)
		(width 0.249936)
		(layer "F.Cu")
		(net "GND")
	)
	(segment
		(start 61.19495 -59.978036)
		(end 61.19495 -60.633356)
		(width 0.4572)
		(layer "F.Cu")
		(net "GND")
	)
	(segment
		(start 405.100028 -306.349908)
		(end 404.624794 -305.874928)
		(width 0.249936)
		(layer "F.Cu")
		(net "GND")
	)
	(segment
		(start 294.22471 -289.724846)
		(end 294.69969 -290.199826)
		(width 0.249936)
		(layer "F.Cu")
		(net "GND")
	)
	(segment
		(start 177.649886 -306.349908)
		(end 178.124866 -306.824888)
		(width 0.249936)
		(layer "F.Cu")
		(net "GND")
	)
	(segment
		(start 215.01862 -46.693836)
		(end 214.81923 -46.893226)
		(width 0.254)
		(layer "F.Cu")
		(net "GND")
	)
	(segment
		(start 179.55006 -299.699934)
		(end 179.07508 -300.174914)
		(width 0.249936)
		(layer "F.Cu")
		(net "GND")
	)
	(segment
		(start 316.734444 -38.937184)
		(end 316.999874 -38.671754)
		(width 0.4572)
		(layer "F.Cu")
		(net "GND")
	)
	(segment
		(start 181.44998 -296.8498)
		(end 180.975 -296.37482)
		(width 0.249936)
		(layer "F.Cu")
		(net "GND")
	)
	(segment
		(start 168.625012 -287.824926)
		(end 168.150032 -288.299906)
		(width 0.249936)
		(layer "F.Cu")
		(net "GND")
	)
	(segment
		(start 190.348108 -149.355048)
		(end 189.357508 -149.355048)
		(width 0.3556)
		(layer "F.Cu")
		(net "GND")
	)
	(segment
		(start 288.049716 -292.099746)
		(end 287.574736 -291.624766)
		(width 0.249936)
		(layer "F.Cu")
		(net "GND")
	)
	(segment
		(start 16.820896 -119.541036)
		(end 16.820896 -120.15343)
		(width 0.4572)
		(layer "F.Cu")
		(net "GND")
	)
	(segment
		(start 191.900048 -290.199826)
		(end 192.375028 -289.724846)
		(width 0.249936)
		(layer "F.Cu")
		(net "GND")
	)
	(segment
		(start 358.75595 -186.182)
		(end 358.14 -186.182)
		(width 0.4572)
		(layer "F.Cu")
		(net "GND")
	)
	(segment
		(start 276.649688 -298.74972)
		(end 276.174708 -298.27474)
		(width 0.249936)
		(layer "F.Cu")
		(net "GND")
	)
	(segment
		(start 170.049952 -306.349908)
		(end 169.574972 -305.874928)
		(width 0.249936)
		(layer "F.Cu")
		(net "GND")
	)
	(segment
		(start 231.149144 -176.72558)
		(end 231.765348 -176.72558)
		(width 0.4572)
		(layer "F.Cu")
		(net "GND")
	)
	(segment
		(start 166.249858 -306.349908)
		(end 166.725092 -306.824888)
		(width 0.249936)
		(layer "F.Cu")
		(net "GND")
	)
	(segment
		(start 187.149994 -300.649894)
		(end 186.675014 -301.124874)
		(width 0.249936)
		(layer "F.Cu")
		(net "GND")
	)
	(segment
		(start 340.961472 -195.49745)
		(end 341.571072 -195.49745)
		(width 0.4572)
		(layer "F.Cu")
		(net "GND")
	)
	(segment
		(start 210.03895 -199.263)
		(end 210.03895 -199.898)
		(width 0.4572)
		(layer "F.Cu")
		(net "GND")
	)
	(segment
		(start 80.07477 -298.27474)
		(end 80.54975 -298.74972)
		(width 0.249936)
		(layer "F.Cu")
		(net "GND")
	)
	(segment
		(start 163.199064 -122.130312)
		(end 162.974274 -122.355102)
		(width 0.3556)
		(layer "F.Cu")
		(net "GND")
	)
	(segment
		(start 190.348108 -121.83491)
		(end 189.357508 -121.83491)
		(width 0.3556)
		(layer "F.Cu")
		(net "GND")
	)
	(segment
		(start 284.249876 -294.94988)
		(end 283.774896 -294.4749)
		(width 0.249936)
		(layer "F.Cu")
		(net "GND")
	)
	(segment
		(start 170.524932 -284.024832)
		(end 170.999912 -284.499812)
		(width 0.249936)
		(layer "F.Cu")
		(net "GND")
	)
	(segment
		(start 136.374124 -73.166732)
		(end 136.374124 -73.85177)
		(width 0.4572)
		(layer "F.Cu")
		(net "GND")
	)
	(segment
		(start 278.549862 -292.099746)
		(end 278.074882 -291.624766)
		(width 0.249936)
		(layer "F.Cu")
		(net "GND")
	)
	(segment
		(start 16.280892 -29.589984)
		(end 15.264892 -29.589984)
		(width 0.3556)
		(layer "F.Cu")
		(net "GND")
	)
	(segment
		(start 89.589356 -295.647872)
		(end 89.589356 -294.727884)
		(width 0.4572)
		(layer "F.Cu")
		(net "GND")
	)
	(segment
		(start 183.3499 -285.449772)
		(end 182.87492 -284.974792)
		(width 0.249936)
		(layer "F.Cu")
		(net "GND")
	)
	(segment
		(start 450.55028 -407.506678)
		(end 451.391274 -407.506678)
		(width 0.4572)
		(layer "F.Cu")
		(net "GND")
	)
	(segment
		(start 182.87492 -300.174914)
		(end 183.3499 -299.699934)
		(width 0.249936)
		(layer "F.Cu")
		(net "GND")
	)
	(segment
		(start 79.59979 -298.74972)
		(end 80.07477 -298.27474)
		(width 0.249936)
		(layer "F.Cu")
		(net "GND")
	)
	(segment
		(start 276.649688 -296.8498)
		(end 277.124922 -297.32478)
		(width 0.249936)
		(layer "F.Cu")
		(net "GND")
	)
	(segment
		(start 167.732964 -133.565138)
		(end 166.742364 -133.565138)
		(width 0.3556)
		(layer "F.Cu")
		(net "GND")
	)
	(segment
		(start 140.442442 -252.756924)
		(end 140.442442 -253.45644)
		(width 0.4572)
		(layer "F.Cu")
		(net "GND")
	)
	(segment
		(start 402.140166 -33.248092)
		(end 402.140166 -33.857692)
		(width 0.4572)
		(layer "F.Cu")
		(net "GND")
	)
	(segment
		(start 395.39926 -122.130312)
		(end 395.17447 -122.355102)
		(width 0.3556)
		(layer "F.Cu")
		(net "GND")
	)
	(segment
		(start 232.244646 -276.519386)
		(end 232.854246 -276.519386)
		(width 0.381)
		(layer "F.Cu")
		(net "GND")
	)
	(segment
		(start 89.53627 -31.390082)
		(end 89.788492 -31.642304)
		(width 0.3556)
		(layer "F.Cu")
		(net "GND")
	)
	(segment
		(start 264.3124 -307.4924)
		(end 264.3124 -307.369718)
		(width 0.4572)
		(layer "F.Cu")
		(net "GND")
	)
	(segment
		(start 280.924762 -296.37482)
		(end 281.399742 -295.89984)
		(width 0.249936)
		(layer "F.Cu")
		(net "GND")
	)
	(segment
		(start 412.224982 -306.824888)
		(end 412.699962 -307.299868)
		(width 0.249936)
		(layer "F.Cu")
		(net "GND")
	)
	(segment
		(start 149.586442 -252.756924)
		(end 149.586442 -253.45644)
		(width 0.4572)
		(layer "F.Cu")
		(net "GND")
	)
	(segment
		(start 421.249856 -298.74972)
		(end 421.724836 -298.27474)
		(width 0.249936)
		(layer "F.Cu")
		(net "GND")
	)
	(segment
		(start 411.750002 -292.099746)
		(end 412.224982 -291.624766)
		(width 0.249936)
		(layer "F.Cu")
		(net "GND")
	)
	(segment
		(start 176.79289 -54.163722)
		(end 176.868074 -54.238906)
		(width 0.254)
		(layer "F.Cu")
		(net "GND")
	)
	(segment
		(start 61.074808 -306.824888)
		(end 60.599828 -306.349908)
		(width 0.249936)
		(layer "F.Cu")
		(net "GND")
	)
	(segment
		(start 362.548932 -31.390082)
		(end 363.564932 -31.390082)
		(width 0.3556)
		(layer "F.Cu")
		(net "GND")
	)
	(segment
		(start 410.799788 -306.349908)
		(end 410.324808 -305.874928)
		(width 0.249936)
		(layer "F.Cu")
		(net "GND")
	)
	(segment
		(start 3.797554 -39.665402)
		(end 3.797554 -39.268146)
		(width 0.254)
		(layer "F.Cu")
		(net "GND")
	)
	(segment
		(start 21.917914 -414.369758)
		(end 21.917914 -414.985454)
		(width 0.4572)
		(layer "F.Cu")
		(net "GND")
	)
	(segment
		(start 287.099756 -306.349908)
		(end 286.624776 -305.874928)
		(width 0.249936)
		(layer "F.Cu")
		(net "GND")
	)
	(segment
		(start 312.02757 -34.732468)
		(end 311.79516 -34.732468)
		(width 0.4572)
		(layer "F.Cu")
		(net "GND")
	)
	(segment
		(start 152.764998 -33.19018)
		(end 151.748998 -33.19018)
		(width 0.3556)
		(layer "F.Cu")
		(net "GND")
	)
	(segment
		(start 188.618368 -116.435124)
		(end 189.357508 -116.435124)
		(width 0.3556)
		(layer "F.Cu")
		(net "GND")
	)
	(segment
		(start 178.599846 -306.349908)
		(end 179.07508 -305.874928)
		(width 0.249936)
		(layer "F.Cu")
		(net "GND")
	)
	(segment
		(start 424.09999 -295.89984)
		(end 424.57497 -296.37482)
		(width 0.249936)
		(layer "F.Cu")
		(net "GND")
	)
	(segment
		(start 103.529638 -222.20936)
		(end 103.22941 -222.20936)
		(width 0.1778)
		(layer "F.Cu")
		(net "GND")
	)
	(segment
		(start 185.250074 -286.399732)
		(end 185.725054 -285.924752)
		(width 0.249936)
		(layer "F.Cu")
		(net "GND")
	)
	(segment
		(start 100.136198 -94.864174)
		(end 100.136198 -94.208346)
		(width 0.4572)
		(layer "F.Cu")
		(net "GND")
	)
	(segment
		(start 95.926402 -25.832054)
		(end 96.569784 -25.832054)
		(width 0.4572)
		(layer "F.Cu")
		(net "GND")
	)
	(segment
		(start 124.808742 -166.273988)
		(end 125.636528 -166.273988)
		(width 0.4572)
		(layer "F.Cu")
		(net "GND")
	)
	(segment
		(start 183.3499 -286.399732)
		(end 182.87492 -285.924752)
		(width 0.249936)
		(layer "F.Cu")
		(net "GND")
	)
	(segment
		(start 423.62501 -290.674806)
		(end 424.09999 -290.199826)
		(width 0.249936)
		(layer "F.Cu")
		(net "GND")
	)
	(segment
		(start 184.29986 -307.299868)
		(end 184.77484 -306.824888)
		(width 0.249936)
		(layer "F.Cu")
		(net "GND")
	)
	(segment
		(start 299.866812 -142.15491)
		(end 300.857412 -142.15491)
		(width 0.3556)
		(layer "F.Cu")
		(net "GND")
	)
	(segment
		(start 311.936638 -16.363188)
		(end 311.936638 -15.474188)
		(width 0.4572)
		(layer "F.Cu")
		(net "GND")
	)
	(segment
		(start 67.249802 -306.349908)
		(end 67.724782 -305.874928)
		(width 0.249936)
		(layer "F.Cu")
		(net "GND")
	)
	(segment
		(start 78.17485 -297.32478)
		(end 78.64983 -297.79976)
		(width 0.249936)
		(layer "F.Cu")
		(net "GND")
	)
	(segment
		(start 69.149976 -307.299868)
		(end 68.674742 -306.824888)
		(width 0.249936)
		(layer "F.Cu")
		(net "GND")
	)
	(segment
		(start 448.163188 -416.021266)
		(end 448.163188 -416.636962)
		(width 0.4572)
		(layer "F.Cu")
		(net "GND")
	)
	(segment
		(start 73.899776 -301.599854)
		(end 73.424796 -301.124874)
		(width 0.249936)
		(layer "F.Cu")
		(net "GND")
	)
	(segment
		(start 219.60205 -200.279)
		(end 219.60205 -199.644)
		(width 0.4572)
		(layer "F.Cu")
		(net "GND")
	)
	(segment
		(start 70.574916 -285.924752)
		(end 71.049896 -285.449772)
		(width 0.249936)
		(layer "F.Cu")
		(net "GND")
	)
	(segment
		(start 302.299878 -302.549814)
		(end 302.774858 -302.074834)
		(width 0.249936)
		(layer "F.Cu")
		(net "GND")
	)
	(segment
		(start 178.599846 -292.099746)
		(end 179.07508 -291.624766)
		(width 0.249936)
		(layer "F.Cu")
		(net "GND")
	)
	(segment
		(start 381.3556 -244.286024)
		(end 381.3556 -245.364)
		(width 0.2794)
		(layer "F.Cu")
		(net "GND")
	)
	(segment
		(start 186.946794 -38.49116)
		(end 186.241182 -38.49116)
		(width 0.4572)
		(layer "F.Cu")
		(net "GND")
	)
	(segment
		(start 385.149852 -288.299906)
		(end 384.674872 -287.824926)
		(width 0.249936)
		(layer "F.Cu")
		(net "GND")
	)
	(segment
		(start 159.599884 -278.799798)
		(end 159.124904 -279.274778)
		(width 0.249936)
		(layer "F.Cu")
		(net "GND")
	)
	(segment
		(start 16.359632 -146.242278)
		(end 16.359632 -145.53565)
		(width 0.4064)
		(layer "F.Cu")
		(net "GND")
	)
	(segment
		(start 227.261166 -38.701218)
		(end 228.01961 -38.701218)
		(width 0.4572)
		(layer "F.Cu")
		(net "GND")
	)
	(segment
		(start 67.66687 -152.95499)
		(end 68.65747 -152.95499)
		(width 0.3556)
		(layer "F.Cu")
		(net "GND")
	)
	(segment
		(start 43.974766 -298.27474)
		(end 44.449746 -298.74972)
		(width 0.249936)
		(layer "F.Cu")
		(net "GND")
	)
	(segment
		(start 258.86791 -54.067456)
		(end 259.52323 -54.067456)
		(width 0.254)
		(layer "F.Cu")
		(net "GND")
	)
	(segment
		(start 300.879764 -303.969928)
		(end 300.399704 -304.449734)
		(width 0.249936)
		(layer "F.Cu")
		(net "GND")
	)
	(segment
		(start 285.199836 -303.499774)
		(end 285.674816 -303.974754)
		(width 0.249936)
		(layer "F.Cu")
		(net "GND")
	)
	(segment
		(start 153.89987 -293.04996)
		(end 153.42489 -292.57498)
		(width 0.249936)
		(layer "F.Cu")
		(net "GND")
	)
	(segment
		(start 378.079 -214.77605)
		(end 378.82195 -214.77605)
		(width 0.4572)
		(layer "F.Cu")
		(net "GND")
	)
	(segment
		(start 289.94989 -299.699934)
		(end 289.47491 -300.174914)
		(width 0.249936)
		(layer "F.Cu")
		(net "GND")
	)
	(segment
		(start 137.247122 -52.592224)
		(end 137.322306 -52.51704)
		(width 0.254)
		(layer "F.Cu")
		(net "GND")
	)
	(segment
		(start 283.833062 -140.765022)
		(end 282.842462 -140.765022)
		(width 0.3556)
		(layer "F.Cu")
		(net "GND")
	)
	(segment
		(start 51.099974 -307.299868)
		(end 50.624994 -306.824888)
		(width 0.249936)
		(layer "F.Cu")
		(net "GND")
	)
	(segment
		(start 194.749928 -297.79976)
		(end 195.224908 -298.27474)
		(width 0.249936)
		(layer "F.Cu")
		(net "GND")
	)
	(segment
		(start 406.999948 -301.599854)
		(end 406.524968 -302.074834)
		(width 0.249936)
		(layer "F.Cu")
		(net "GND")
	)
	(segment
		(start 304.467006 -118.234968)
		(end 305.457606 -118.234968)
		(width 0.3556)
		(layer "F.Cu")
		(net "GND")
	)
	(segment
		(start 52.524914 -306.824888)
		(end 52.049934 -306.349908)
		(width 0.249936)
		(layer "F.Cu")
		(net "GND")
	)
	(segment
		(start 397.729202 -107.407456)
		(end 398.166844 -107.845098)
		(width 0.3556)
		(layer "F.Cu")
		(net "GND")
	)
	(segment
		(start 185.725054 -297.32478)
		(end 185.250074 -296.8498)
		(width 0.249936)
		(layer "F.Cu")
		(net "GND")
	)
	(segment
		(start 425.04995 -291.149786)
		(end 425.52493 -291.624766)
		(width 0.249936)
		(layer "F.Cu")
		(net "GND")
	)
	(segment
		(start 132.38099 -34.990024)
		(end 131.36499 -34.990024)
		(width 0.3556)
		(layer "F.Cu")
		(net "GND")
	)
	(segment
		(start 393.351766 -118.754906)
		(end 394.342366 -118.754906)
		(width 0.3556)
		(layer "F.Cu")
		(net "GND")
	)
	(segment
		(start 150.331932 -387.81736)
		(end 150.331932 -386.979668)
		(width 0.4572)
		(layer "F.Cu")
		(net "GND")
	)
	(segment
		(start 174.936912 -177.891186)
		(end 176.028858 -177.891186)
		(width 0.3048)
		(layer "F.Cu")
		(net "GND")
	)
	(segment
		(start 396.0749 -304.924714)
		(end 396.54988 -304.449734)
		(width 0.249936)
		(layer "F.Cu")
		(net "GND")
	)
	(segment
		(start 416.024822 -291.624766)
		(end 415.549842 -292.099746)
		(width 0.249936)
		(layer "F.Cu")
		(net "GND")
	)
	(segment
		(start 52.524914 -285.924752)
		(end 52.999894 -285.449772)
		(width 0.249936)
		(layer "F.Cu")
		(net "GND")
	)
	(segment
		(start 434.99278 -54.163722)
		(end 435.067964 -54.238906)
		(width 0.254)
		(layer "F.Cu")
		(net "GND")
	)
	(segment
		(start 16.280892 -25.990042)
		(end 15.264892 -25.990042)
		(width 0.3556)
		(layer "F.Cu")
		(net "GND")
	)
	(segment
		(start 396.0749 -303.974754)
		(end 395.59992 -304.449734)
		(width 0.249936)
		(layer "F.Cu")
		(net "GND")
	)
	(segment
		(start 294.22471 -284.974792)
		(end 293.74973 -284.499812)
		(width 0.249936)
		(layer "F.Cu")
		(net "GND")
	)
	(segment
		(start 165.057836 -131.76504)
		(end 166.742364 -131.76504)
		(width 0.3556)
		(layer "F.Cu")
		(net "GND")
	)
	(segment
		(start 70.574916 -284.974792)
		(end 71.049896 -284.499812)
		(width 0.249936)
		(layer "F.Cu")
		(net "GND")
	)
	(segment
		(start 397.97482 -290.674806)
		(end 398.4498 -291.149786)
		(width 0.249936)
		(layer "F.Cu")
		(net "GND")
	)
	(segment
		(start 63.449962 -305.399948)
		(end 62.974982 -305.874928)
		(width 0.249936)
		(layer "F.Cu")
		(net "GND")
	)
	(segment
		(start 167.200072 -285.449772)
		(end 166.725092 -284.974792)
		(width 0.249936)
		(layer "F.Cu")
		(net "GND")
	)
	(segment
		(start 417.450016 -286.399732)
		(end 417.924996 -285.924752)
		(width 0.249936)
		(layer "F.Cu")
		(net "GND")
	)
	(segment
		(start 321.880738 -25.990042)
		(end 320.864738 -25.990042)
		(width 0.3556)
		(layer "F.Cu")
		(net "GND")
	)
	(segment
		(start 419.349936 -289.249866)
		(end 418.874956 -288.774886)
		(width 0.249936)
		(layer "F.Cu")
		(net "GND")
	)
	(segment
		(start 387.482842 -140.85697)
		(end 387.85292 -140.85697)
		(width 0.4572)
		(layer "F.Cu")
		(net "GND")
	)
	(segment
		(start 190.950088 -295.89984)
		(end 191.425068 -296.37482)
		(width 0.249936)
		(layer "F.Cu")
		(net "GND")
	)
	(segment
		(start 130.26263 -110.977426)
		(end 130.26263 -110.365032)
		(width 0.4572)
		(layer "F.Cu")
		(net "GND")
	)
	(segment
		(start 58.595006 -104.830372)
		(end 57.979818 -104.830372)
		(width 0.4064)
		(layer "F.Cu")
		(net "GND")
	)
	(segment
		(start 164.824918 -306.824888)
		(end 164.349938 -306.349908)
		(width 0.249936)
		(layer "F.Cu")
		(net "GND")
	)
	(segment
		(start 397.02486 -291.624766)
		(end 397.49984 -292.099746)
		(width 0.249936)
		(layer "F.Cu")
		(net "GND")
	)
	(segment
		(start 299.924724 -307.774848)
		(end 299.449744 -307.299868)
		(width 0.249936)
		(layer "F.Cu")
		(net "GND")
	)
	(segment
		(start 417.450016 -284.499812)
		(end 417.924996 -284.024832)
		(width 0.249936)
		(layer "F.Cu")
		(net "GND")
	)
	(segment
		(start 127.78105 -25.990042)
		(end 126.76505 -25.990042)
		(width 0.3556)
		(layer "F.Cu")
		(net "GND")
	)
	(segment
		(start 400.349974 -299.699934)
		(end 400.824954 -300.174914)
		(width 0.249936)
		(layer "F.Cu")
		(net "GND")
	)
	(segment
		(start 171.949872 -307.299868)
		(end 171.474892 -306.824888)
		(width 0.249936)
		(layer "F.Cu")
		(net "GND")
	)
	(segment
		(start 28.341828 -26.606246)
		(end 28.341828 -25.971246)
		(width 0.4572)
		(layer "F.Cu")
		(net "GND")
	)
	(segment
		(start 386.099812 -298.74972)
		(end 386.574792 -299.224954)
		(width 0.249936)
		(layer "F.Cu")
		(net "GND")
	)
	(segment
		(start 65.824862 -284.974792)
		(end 66.299842 -285.449772)
		(width 0.249936)
		(layer "F.Cu")
		(net "GND")
	)
	(segment
		(start 139.298934 -189.778132)
		(end 139.135358 -189.614556)
		(width 0.3048)
		(layer "F.Cu")
		(net "GND")
	)
	(segment
		(start 316.508892 -27.04973)
		(end 315.849762 -27.04973)
		(width 0.4572)
		(layer "F.Cu")
		(net "GND")
	)
	(segment
		(start 218.0336 -98.358706)
		(end 218.0336 -97.837244)
		(width 0.381)
		(layer "F.Cu")
		(net "GND")
	)
	(segment
		(start 401.774914 -305.874928)
		(end 401.299934 -305.399948)
		(width 0.249936)
		(layer "F.Cu")
		(net "GND")
	)
	(segment
		(start 3.856736 -37.395912)
		(end 3.856736 -36.760912)
		(width 0.4572)
		(layer "F.Cu")
		(net "GND")
	)
	(segment
		(start 153.780998 -25.990042)
		(end 152.764998 -25.990042)
		(width 0.3556)
		(layer "F.Cu")
		(net "GND")
	)
	(segment
		(start 51.099974 -305.399948)
		(end 50.624994 -305.874928)
		(width 0.249936)
		(layer "F.Cu")
		(net "GND")
	)
	(segment
		(start 412.224982 -300.174914)
		(end 412.699962 -299.699934)
		(width 0.249936)
		(layer "F.Cu")
		(net "GND")
	)
	(segment
		(start 173.850046 -284.499812)
		(end 173.375066 -284.024832)
		(width 0.249936)
		(layer "F.Cu")
		(net "GND")
	)
	(segment
		(start 269.999714 -288.299906)
		(end 269.524734 -287.824926)
		(width 0.249936)
		(layer "F.Cu")
		(net "GND")
	)
	(segment
		(start 74.84999 -299.699934)
		(end 75.79995 -299.699934)
		(width 0.249936)
		(layer "F.Cu")
		(net "GND")
	)
	(segment
		(start 409.374848 -303.974754)
		(end 409.849828 -303.499774)
		(width 0.249936)
		(layer "F.Cu")
		(net "GND")
	)
	(segment
		(start 182.39994 -290.199826)
		(end 182.87492 -289.724846)
		(width 0.249936)
		(layer "F.Cu")
		(net "GND")
	)
	(segment
		(start 260.271006 -305.613816)
		(end 260.740652 -306.083462)
		(width 0.4572)
		(layer "F.Cu")
		(net "GND")
	)
	(segment
		(start 422.548304 -136.645142)
		(end 421.557704 -136.645142)
		(width 0.3556)
		(layer "F.Cu")
		(net "GND")
	)
	(segment
		(start 394.342366 -137.16508)
		(end 393.351766 -137.16508)
		(width 0.3556)
		(layer "F.Cu")
		(net "GND")
	)
	(segment
		(start 69.64807 -142.15491)
		(end 68.65747 -142.15491)
		(width 0.3556)
		(layer "F.Cu")
		(net "GND")
	)
	(segment
		(start 65.824862 -302.074834)
		(end 66.299842 -301.599854)
		(width 0.249936)
		(layer "F.Cu")
		(net "GND")
	)
	(segment
		(start 283.299916 -305.399948)
		(end 282.824936 -305.874928)
		(width 0.249936)
		(layer "F.Cu")
		(net "GND")
	)
	(segment
		(start 397.543528 -173.229524)
		(end 397.543528 -172.172122)
		(width 0.4572)
		(layer "F.Cu")
		(net "GND")
	)
	(segment
		(start 38.274752 -298.27474)
		(end 38.749986 -297.79976)
		(width 0.249936)
		(layer "F.Cu")
		(net "GND")
	)
	(segment
		(start 149.315932 -386.26796)
		(end 149.315932 -385.557268)
		(width 0.4572)
		(layer "F.Cu")
		(net "GND")
	)
	(segment
		(start 158.649924 -283.549852)
		(end 158.174944 -283.074872)
		(width 0.249936)
		(layer "F.Cu")
		(net "GND")
	)
	(segment
		(start 391.799826 -277.849838)
		(end 391.324846 -278.324818)
		(width 0.249936)
		(layer "F.Cu")
		(net "GND")
	)
	(segment
		(start 50.624994 -296.37482)
		(end 51.099974 -295.89984)
		(width 0.249936)
		(layer "F.Cu")
		(net "GND")
	)
	(segment
		(start 253.489968 -73.166732)
		(end 253.489968 -73.85177)
		(width 0.4572)
		(layer "F.Cu")
		(net "GND")
	)
	(segment
		(start 164.349938 -304.449734)
		(end 163.874958 -303.974754)
		(width 0.249936)
		(layer "F.Cu")
		(net "GND")
	)
	(segment
		(start 417.450016 -307.299868)
		(end 417.924996 -306.824888)
		(width 0.249936)
		(layer "F.Cu")
		(net "GND")
	)
	(segment
		(start 412.224982 -284.974792)
		(end 411.750002 -284.499812)
		(width 0.249936)
		(layer "F.Cu")
		(net "GND")
	)
	(segment
		(start 178.599846 -307.299868)
		(end 178.124866 -307.774848)
		(width 0.249936)
		(layer "F.Cu")
		(net "GND")
	)
	(segment
		(start 264.539984 -76.879704)
		(end 264.539984 -76.270104)
		(width 0.4572)
		(layer "F.Cu")
		(net "GND")
	)
	(segment
		(start 302.774858 -291.624766)
		(end 303.249838 -291.149786)
		(width 0.249936)
		(layer "F.Cu")
		(net "GND")
	)
	(segment
		(start 279.974802 -303.024794)
		(end 280.449782 -303.499774)
		(width 0.249936)
		(layer "F.Cu")
		(net "GND")
	)
	(segment
		(start 189.545976 -46.693836)
		(end 189.018672 -46.693836)
		(width 0.254)
		(layer "F.Cu")
		(net "GND")
	)
	(segment
		(start 406.049988 -306.349908)
		(end 405.575008 -306.824888)
		(width 0.249936)
		(layer "F.Cu")
		(net "GND")
	)
	(segment
		(start 61.074808 -285.924752)
		(end 61.549788 -286.399732)
		(width 0.249936)
		(layer "F.Cu")
		(net "GND")
	)
	(segment
		(start 367.523776 -153.1112)
		(end 367.523776 -153.782522)
		(width 0.4064)
		(layer "F.Cu")
		(net "GND")
	)
	(segment
		(start 384.674872 -296.374566)
		(end 385.149852 -296.8498)
		(width 0.249936)
		(layer "F.Cu")
		(net "GND")
	)
	(segment
		(start 72.42556 -133.044946)
		(end 73.257664 -133.044946)
		(width 0.3556)
		(layer "F.Cu")
		(net "GND")
	)
	(segment
		(start 424.09999 -292.099746)
		(end 424.57497 -291.624766)
		(width 0.249936)
		(layer "F.Cu")
		(net "GND")
	)
	(segment
		(start 188.358272 -116.9035)
		(end 188.358272 -116.69522)
		(width 0.3556)
		(layer "F.Cu")
		(net "GND")
	)
	(segment
		(start 57.749948 -288.19983)
		(end 57.749948 -288.299906)
		(width 0.249936)
		(layer "F.Cu")
		(net "GND")
	)
	(segment
		(start 72.258428 -116.9035)
		(end 72.258428 -116.69522)
		(width 0.3556)
		(layer "F.Cu")
		(net "GND")
	)
	(segment
		(start 99.445826 -46.693836)
		(end 98.918522 -46.693836)
		(width 0.254)
		(layer "F.Cu")
		(net "GND")
	)
	(segment
		(start 189.524894 -293.52494)
		(end 189.049914 -293.04996)
		(width 0.249936)
		(layer "F.Cu")
		(net "GND")
	)
	(segment
		(start 329.974702 -48.753014)
		(end 329.268074 -48.753014)
		(width 0.254)
		(layer "F.Cu")
		(net "GND")
	)
	(segment
		(start 39.699946 -281.649932)
		(end 39.224966 -281.174952)
		(width 0.249936)
		(layer "F.Cu")
		(net "GND")
	)
	(segment
		(start 186.200034 -300.649894)
		(end 185.725054 -300.174914)
		(width 0.249936)
		(layer "F.Cu")
		(net "GND")
	)
	(segment
		(start 341.293958 -219.187014)
		(end 340.894162 -218.787218)
		(width 0.381)
		(layer "F.Cu")
		(net "GND")
	)
	(segment
		(start 279.024842 -291.624766)
		(end 278.549862 -291.149786)
		(width 0.254)
		(layer "F.Cu")
		(net "GND")
	)
	(segment
		(start 292.32479 -305.874928)
		(end 292.79977 -305.399948)
		(width 0.249936)
		(layer "F.Cu")
		(net "GND")
	)
	(segment
		(start 397.97482 -297.32478)
		(end 397.49984 -297.79976)
		(width 0.249936)
		(layer "F.Cu")
		(net "GND")
	)
	(segment
		(start 289.47491 -287.824926)
		(end 289.94989 -288.299906)
		(width 0.249936)
		(layer "F.Cu")
		(net "GND")
	)
	(segment
		(start 176.224946 -303.974754)
		(end 176.699926 -303.499774)
		(width 0.249936)
		(layer "F.Cu")
		(net "GND")
	)
	(segment
		(start 161.15157 -102.445058)
		(end 162.14217 -102.445058)
		(width 0.3556)
		(layer "F.Cu")
		(net "GND")
	)
	(segment
		(start 194.743832 -45.88891)
		(end 195.415154 -45.88891)
		(width 0.254)
		(layer "F.Cu")
		(net "GND")
	)
	(segment
		(start 343.149936 -165.616128)
		(end 344.23477 -165.616128)
		(width 0.4572)
		(layer "F.Cu")
		(net "GND")
	)
	(segment
		(start 302.774858 -290.674806)
		(end 302.299878 -291.149786)
		(width 0.249936)
		(layer "F.Cu")
		(net "GND")
	)
	(segment
		(start 283.557472 -29.784294)
		(end 283.664406 -29.67736)
		(width 0.4572)
		(layer "F.Cu")
		(net "GND")
	)
	(segment
		(start 174.325026 -285.924752)
		(end 174.800006 -285.449772)
		(width 0.249936)
		(layer "F.Cu")
		(net "GND")
	)
	(segment
		(start 363.122718 -228.67493)
		(end 361.728004 -228.67493)
		(width 0.4572)
		(layer "F.Cu")
		(net "GND")
	)
	(segment
		(start 272.798286 -252.756924)
		(end 272.798286 -253.45644)
		(width 0.4572)
		(layer "F.Cu")
		(net "GND")
	)
	(segment
		(start 309.262272 -23.355554)
		(end 309.912004 -23.355554)
		(width 0.4572)
		(layer "F.Cu")
		(net "GND")
	)
	(segment
		(start 245.694708 -158.705042)
		(end 245.694708 -159.498792)
		(width 0.254)
		(layer "F.Cu")
		(net "GND")
	)
	(segment
		(start 401.299934 -306.349908)
		(end 400.824954 -306.824888)
		(width 0.249936)
		(layer "F.Cu")
		(net "GND")
	)
	(segment
		(start 103.764588 -222.306642)
		(end 103.529638 -222.20936)
		(width 0.1778)
		(layer "F.Cu")
		(net "GND")
	)
	(segment
		(start 290.42487 -285.924752)
		(end 290.89985 -286.399732)
		(width 0.249936)
		(layer "F.Cu")
		(net "GND")
	)
	(segment
		(start 303.249838 -301.599854)
		(end 303.724818 -302.074834)
		(width 0.249936)
		(layer "F.Cu")
		(net "GND")
	)
	(segment
		(start 178.124866 -285.924752)
		(end 178.599846 -285.449772)
		(width 0.249936)
		(layer "F.Cu")
		(net "GND")
	)
	(segment
		(start 363.854746 -384.914902)
		(end 363.854746 -384.09245)
		(width 0.4572)
		(layer "F.Cu")
		(net "GND")
	)
	(segment
		(start 116.86032 -284.42412)
		(end 116.532152 -284.42412)
		(width 0.2286)
		(layer "F.Cu")
		(net "GND")
	)
	(segment
		(start 190.474854 -290.674806)
		(end 189.999874 -290.199826)
		(width 0.249936)
		(layer "F.Cu")
		(net "GND")
	)
	(segment
		(start 63.449962 -306.349908)
		(end 63.924942 -306.824888)
		(width 0.249936)
		(layer "F.Cu")
		(net "GND")
	)
	(segment
		(start 320.696336 -95.0722)
		(end 321.619626 -95.0722)
		(width 0.4572)
		(layer "F.Cu")
		(net "GND")
	)
	(segment
		(start 414.599882 -284.499812)
		(end 415.074862 -284.974792)
		(width 0.249936)
		(layer "F.Cu")
		(net "GND")
	)
	(segment
		(start 68.199762 -290.199826)
		(end 68.674742 -290.674806)
		(width 0.249936)
		(layer "F.Cu")
		(net "GND")
	)
	(segment
		(start 45.051726 -118.754906)
		(end 46.042326 -118.754906)
		(width 0.3556)
		(layer "F.Cu")
		(net "GND")
	)
	(segment
		(start 40.24884 -29.589984)
		(end 41.26484 -29.589984)
		(width 0.3556)
		(layer "F.Cu")
		(net "GND")
	)
	(segment
		(start 238.738664 -205.98511)
		(end 239.246664 -205.47711)
		(width 0.4572)
		(layer "F.Cu")
		(net "GND")
	)
	(segment
		(start 188.75756 -403.06879)
		(end 188.75756 -403.267926)
		(width 0.381)
		(layer "F.Cu")
		(net "GND")
	)
	(segment
		(start 67.249802 -288.299906)
		(end 67.724782 -287.824926)
		(width 0.249936)
		(layer "F.Cu")
		(net "GND")
	)
	(segment
		(start 65.824862 -300.174914)
		(end 65.349882 -299.699934)
		(width 0.249936)
		(layer "F.Cu")
		(net "GND")
	)
	(segment
		(start 45.87494 -294.4749)
		(end 45.39996 -293.99992)
		(width 0.249936)
		(layer "F.Cu")
		(net "GND")
	)
	(segment
		(start 422.59504 -104.240076)
		(end 421.557704 -104.240076)
		(width 0.3556)
		(layer "F.Cu")
		(net "GND")
	)
	(segment
		(start 402.724874 -306.824888)
		(end 403.199854 -306.349908)
		(width 0.249936)
		(layer "F.Cu")
		(net "GND")
	)
	(segment
		(start 48.24984 -302.549814)
		(end 47.77486 -303.024794)
		(width 0.249936)
		(layer "F.Cu")
		(net "GND")
	)
	(segment
		(start 190.348108 -152.95499)
		(end 189.357508 -152.95499)
		(width 0.3556)
		(layer "F.Cu")
		(net "GND")
	)
	(segment
		(start 365.90605 -202.819)
		(end 366.522 -202.819)
		(width 0.4572)
		(layer "F.Cu")
		(net "GND")
	)
	(segment
		(start 164.349938 -286.399732)
		(end 163.874958 -285.924752)
		(width 0.249936)
		(layer "F.Cu")
		(net "GND")
	)
	(segment
		(start 210.892136 -181.213506)
		(end 210.765136 -181.340506)
		(width 0.4572)
		(layer "F.Cu")
		(net "GND")
	)
	(segment
		(start 400.824954 -289.724846)
		(end 401.299934 -290.199826)
		(width 0.249936)
		(layer "F.Cu")
		(net "GND")
	)
	(segment
		(start 402.249894 -305.399948)
		(end 402.724874 -305.874928)
		(width 0.249936)
		(layer "F.Cu")
		(net "GND")
	)
	(segment
		(start 40.649906 -297.79976)
		(end 41.124886 -298.27474)
		(width 0.249936)
		(layer "F.Cu")
		(net "GND")
	)
	(segment
		(start 199.897746 -38.937184)
		(end 200.6346 -38.937184)
		(width 0.4572)
		(layer "F.Cu")
		(net "GND")
	)
	(segment
		(start 337.293966 -224.786952)
		(end 336.89417 -225.186748)
		(width 0.381)
		(layer "F.Cu")
		(net "GND")
	)
	(segment
		(start 64.399922 -306.349908)
		(end 63.924942 -305.874928)
		(width 0.249936)
		(layer "F.Cu")
		(net "GND")
	)
	(segment
		(start 169.099992 -303.499774)
		(end 168.625012 -303.974754)
		(width 0.249936)
		(layer "F.Cu")
		(net "GND")
	)
	(segment
		(start 80.341724 -26.606246)
		(end 80.341724 -25.971246)
		(width 0.4572)
		(layer "F.Cu")
		(net "GND")
	)
	(segment
		(start 61.4299 -171.661328)
		(end 61.4299 -172.329348)
		(width 0.4572)
		(layer "F.Cu")
		(net "GND")
	)
	(segment
		(start 52.999894 -285.449772)
		(end 52.524914 -284.974792)
		(width 0.249936)
		(layer "F.Cu")
		(net "GND")
	)
	(segment
		(start 174.325026 -284.024832)
		(end 173.850046 -284.499812)
		(width 0.249936)
		(layer "F.Cu")
		(net "GND")
	)
	(segment
		(start 73.899776 -295.89984)
		(end 74.374756 -296.37482)
		(width 0.249936)
		(layer "F.Cu")
		(net "GND")
	)
	(segment
		(start 311.324752 -290.674806)
		(end 310.849772 -291.149786)
		(width 0.249936)
		(layer "F.Cu")
		(net "GND")
	)
	(segment
		(start 279.024842 -304.924714)
		(end 279.499822 -305.399948)
		(width 0.249936)
		(layer "F.Cu")
		(net "GND")
	)
	(segment
		(start 403.199854 -286.399732)
		(end 402.724874 -285.924752)
		(width 0.249936)
		(layer "F.Cu")
		(net "GND")
	)
	(segment
		(start 52.049934 -294.94988)
		(end 51.574954 -294.4749)
		(width 0.249936)
		(layer "F.Cu")
		(net "GND")
	)
	(segment
		(start 62.499748 -307.299868)
		(end 62.974982 -306.824888)
		(width 0.249936)
		(layer "F.Cu")
		(net "GND")
	)
	(segment
		(start 30.715204 -59.946286)
		(end 30.715204 -60.601606)
		(width 0.4572)
		(layer "F.Cu")
		(net "GND")
	)
	(segment
		(start 303.724818 -302.074834)
		(end 304.199798 -302.549814)
		(width 0.249936)
		(layer "F.Cu")
		(net "GND")
	)
	(segment
		(start 402.533104 -235.358432)
		(end 410.770832 -235.358432)
		(width 0.4572)
		(layer "F.Cu")
		(net "GND")
	)
	(segment
		(start 300.399704 -286.399732)
		(end 299.924724 -285.924752)
		(width 0.249936)
		(layer "F.Cu")
		(net "GND")
	)
	(segment
		(start 298.499784 -284.499812)
		(end 298.024804 -284.974792)
		(width 0.249936)
		(layer "F.Cu")
		(net "GND")
	)
	(segment
		(start 236.573822 -26.606246)
		(end 236.573822 -25.971246)
		(width 0.4572)
		(layer "F.Cu")
		(net "GND")
	)
	(segment
		(start 232.517442 -69.600064)
		(end 233.40441 -69.600064)
		(width 0.3556)
		(layer "F.Cu")
		(net "GND")
	)
	(segment
		(start 396.54988 -293.04996)
		(end 397.02486 -293.52494)
		(width 0.249936)
		(layer "F.Cu")
		(net "GND")
	)
	(segment
		(start 128.058164 -254.194564)
		(end 128.667764 -254.194564)
		(width 0.381)
		(layer "F.Cu")
		(net "GND")
	)
	(segment
		(start 283.833062 -135.364982)
		(end 282.842462 -135.364982)
		(width 0.3556)
		(layer "F.Cu")
		(net "GND")
	)
	(segment
		(start 361.58805 -180.086)
		(end 362.204 -180.086)
		(width 0.4572)
		(layer "F.Cu")
		(net "GND")
	)
	(segment
		(start 400.824954 -287.824926)
		(end 400.349974 -288.299906)
		(width 0.249936)
		(layer "F.Cu")
		(net "GND")
	)
	(segment
		(start 227.467668 -219.904056)
		(end 227.067872 -220.303852)
		(width 0.381)
		(layer "F.Cu")
		(net "GND")
	)
	(segment
		(start 272.374868 -286.874966)
		(end 272.849848 -287.349946)
		(width 0.249936)
		(layer "F.Cu")
		(net "GND")
	)
	(segment
		(start 57.274968 -305.874928)
		(end 57.749948 -305.399948)
		(width 0.249936)
		(layer "F.Cu")
		(net "GND")
	)
	(segment
		(start 376.03684 -16.363188)
		(end 376.03684 -15.474188)
		(width 0.4572)
		(layer "F.Cu")
		(net "GND")
	)
	(segment
		(start 152.764998 -29.589984)
		(end 151.748998 -29.589984)
		(width 0.3556)
		(layer "F.Cu")
		(net "GND")
	)
	(segment
		(start 55.86476 -384.973068)
		(end 54.950868 -384.973068)
		(width 0.4572)
		(layer "F.Cu")
		(net "GND")
	)
	(segment
		(start 429.800004 -301.599854)
		(end 430.274984 -301.124874)
		(width 0.249936)
		(layer "F.Cu")
		(net "GND")
	)
	(segment
		(start 58.224928 -284.024832)
		(end 58.699908 -283.549852)
		(width 0.249936)
		(layer "F.Cu")
		(net "GND")
	)
	(segment
		(start 411.836362 -31.390082)
		(end 412.088584 -31.642304)
		(width 0.3556)
		(layer "F.Cu")
		(net "GND")
	)
	(segment
		(start 417.745672 -143.955008)
		(end 416.95751 -143.955008)
		(width 0.3556)
		(layer "F.Cu")
		(net "GND")
	)
	(segment
		(start 457.31303 -110.28553)
		(end 457.94422 -110.28553)
		(width 0.254)
		(layer "F.Cu")
		(net "GND")
	)
	(segment
		(start 313.699906 -292.099746)
		(end 313.224926 -291.624766)
		(width 0.249936)
		(layer "F.Cu")
		(net "GND")
	)
	(segment
		(start 255.17729 -76.879704)
		(end 255.17729 -76.270104)
		(width 0.4572)
		(layer "F.Cu")
		(net "GND")
	)
	(segment
		(start 270.498316 -161.953702)
		(end 270.498316 -161.683954)
		(width 0.4572)
		(layer "F.Cu")
		(net "GND")
	)
	(segment
		(start 397.97482 -292.574726)
		(end 398.4498 -293.04996)
		(width 0.249936)
		(layer "F.Cu")
		(net "GND")
	)
	(segment
		(start 65.349882 -301.599854)
		(end 64.874902 -302.074834)
		(width 0.249936)
		(layer "F.Cu")
		(net "GND")
	)
	(segment
		(start 400.349974 -284.499812)
		(end 400.824954 -284.974792)
		(width 0.249936)
		(layer "F.Cu")
		(net "GND")
	)
	(segment
		(start 294.22471 -297.32478)
		(end 294.69969 -297.79976)
		(width 0.249936)
		(layer "F.Cu")
		(net "GND")
	)
	(segment
		(start 52.049934 -299.699934)
		(end 51.574954 -300.174914)
		(width 0.249936)
		(layer "F.Cu")
		(net "GND")
	)
	(segment
		(start 76.27493 -294.4749)
		(end 76.74991 -294.94988)
		(width 0.249936)
		(layer "F.Cu")
		(net "GND")
	)
	(segment
		(start 313.557666 -26.606246)
		(end 313.557666 -25.971246)
		(width 0.4572)
		(layer "F.Cu")
		(net "GND")
	)
	(segment
		(start 419.824916 -301.124874)
		(end 419.349936 -300.649894)
		(width 0.249936)
		(layer "F.Cu")
		(net "GND")
	)
	(segment
		(start 162.450018 -290.199826)
		(end 161.975038 -289.724846)
		(width 0.249936)
		(layer "F.Cu")
		(net "GND")
	)
	(segment
		(start 71.524876 -292.574726)
		(end 71.049896 -292.099746)
		(width 0.249936)
		(layer "F.Cu")
		(net "GND")
	)
	(segment
		(start 165.64737 -122.044206)
		(end 165.958266 -122.355102)
		(width 0.3556)
		(layer "F.Cu")
		(net "GND")
	)
	(segment
		(start 194.889628 -405.133556)
		(end 194.889628 -406.180544)
		(width 0.4572)
		(layer "F.Cu")
		(net "GND")
	)
	(segment
		(start 67.249802 -306.349908)
		(end 67.724782 -306.824888)
		(width 0.249936)
		(layer "F.Cu")
		(net "GND")
	)
	(segment
		(start 187.149994 -290.199826)
		(end 186.675014 -289.724846)
		(width 0.249936)
		(layer "F.Cu")
		(net "GND")
	)
	(segment
		(start 398.158462 -122.355102)
		(end 398.94256 -122.355102)
		(width 0.3556)
		(layer "F.Cu")
		(net "GND")
	)
	(segment
		(start 289.14725 -37.087048)
		(end 289.78225 -37.087048)
		(width 0.4572)
		(layer "F.Cu")
		(net "GND")
	)
	(segment
		(start 417.620196 -125.435106)
		(end 416.95751 -125.435106)
		(width 0.3556)
		(layer "F.Cu")
		(net "GND")
	)
	(segment
		(start 244.934232 -138.267694)
		(end 244.934232 -138.819636)
		(width 0.254)
		(layer "F.Cu")
		(net "GND")
	)
	(segment
		(start 308.474872 -291.624766)
		(end 308.949852 -291.149786)
		(width 0.249936)
		(layer "F.Cu")
		(net "GND")
	)
	(segment
		(start 188.099954 -302.549814)
		(end 187.624974 -302.074834)
		(width 0.249936)
		(layer "F.Cu")
		(net "GND")
	)
	(segment
		(start 288.049716 -285.449772)
		(end 287.574736 -284.974792)
		(width 0.249936)
		(layer "F.Cu")
		(net "GND")
	)
	(segment
		(start 421.724836 -293.52494)
		(end 421.249856 -293.04996)
		(width 0.249936)
		(layer "F.Cu")
		(net "GND")
	)
	(segment
		(start 426.967904 -55.083456)
		(end 427.623224 -55.083456)
		(width 0.254)
		(layer "F.Cu")
		(net "GND")
	)
	(segment
		(start 228.267768 -221.504256)
		(end 227.867972 -221.904052)
		(width 0.381)
		(layer "F.Cu")
		(net "GND")
	)
	(segment
		(start 350.562672 -34.29762)
		(end 350.127824 -34.732468)
		(width 0.4572)
		(layer "F.Cu")
		(net "GND")
	)
	(segment
		(start 413.174942 -302.074834)
		(end 413.649922 -301.599854)
		(width 0.249936)
		(layer "F.Cu")
		(net "GND")
	)
	(segment
		(start 97.850198 -94.863666)
		(end 97.850198 -94.227904)
		(width 0.4064)
		(layer "F.Cu")
		(net "GND")
	)
	(segment
		(start 345.29395 -222.38716)
		(end 345.693746 -222.786956)
		(width 0.381)
		(layer "F.Cu")
		(net "GND")
	)
	(segment
		(start 2.31521 -380.182628)
		(end 1.69926 -380.182628)
		(width 0.381)
		(layer "F.Cu")
		(net "GND")
	)
	(segment
		(start 67.66687 -154.755088)
		(end 68.65747 -154.755088)
		(width 0.3556)
		(layer "F.Cu")
		(net "GND")
	)
	(segment
		(start 279.672542 -113.245138)
		(end 278.242268 -113.245138)
		(width 0.3556)
		(layer "F.Cu")
		(net "GND")
	)
	(segment
		(start 306.448206 -118.234968)
		(end 305.457606 -118.234968)
		(width 0.3556)
		(layer "F.Cu")
		(net "GND")
	)
	(segment
		(start 309.424832 -291.624766)
		(end 308.949852 -291.149786)
		(width 0.249936)
		(layer "F.Cu")
		(net "GND")
	)
	(segment
		(start 145.972276 -33.248092)
		(end 145.972276 -33.857692)
		(width 0.4572)
		(layer "F.Cu")
		(net "GND")
	)
	(segment
		(start 282.842462 -107.845098)
		(end 283.832808 -107.845098)
		(width 0.4572)
		(layer "F.Cu")
		(net "GND")
	)
	(segment
		(start 230.66756 -213.504272)
		(end 231.067356 -213.104476)
		(width 0.381)
		(layer "F.Cu")
		(net "GND")
	)
	(segment
		(start 427.42485 -300.174914)
		(end 427.89983 -300.649894)
		(width 0.249936)
		(layer "F.Cu")
		(net "GND")
	)
	(segment
		(start 41.124886 -300.174914)
		(end 41.599866 -299.699934)
		(width 0.249936)
		(layer "F.Cu")
		(net "GND")
	)
	(segment
		(start 100.076 -383.0574)
		(end 99.733862 -383.0574)
		(width 0.4572)
		(layer "F.Cu")
		(net "GND")
	)
	(segment
		(start 185.725054 -284.974792)
		(end 186.200034 -284.499812)
		(width 0.249936)
		(layer "F.Cu")
		(net "GND")
	)
	(segment
		(start 69.624956 -293.52494)
		(end 69.149976 -293.99992)
		(width 0.249936)
		(layer "F.Cu")
		(net "GND")
	)
	(segment
		(start 439.86196 -101.865684)
		(end 439.86196 -101.609398)
		(width 0.254)
		(layer "F.Cu")
		(net "GND")
	)
	(segment
		(start 81.024984 -294.4749)
		(end 81.499964 -293.99992)
		(width 0.249936)
		(layer "F.Cu")
		(net "GND")
	)
	(segment
		(start 3.746754 -16.936974)
		(end 3.746754 -15.844774)
		(width 0.4572)
		(layer "F.Cu")
		(net "GND")
	)
	(segment
		(start 162.450018 -287.349946)
		(end 161.975038 -286.874966)
		(width 0.249936)
		(layer "F.Cu")
		(net "GND")
	)
	(segment
		(start 59.649868 -303.499774)
		(end 60.124848 -303.974754)
		(width 0.249936)
		(layer "F.Cu")
		(net "GND")
	)
	(segment
		(start 168.150032 -292.099746)
		(end 167.675052 -291.624766)
		(width 0.249936)
		(layer "F.Cu")
		(net "GND")
	)
	(segment
		(start 293.941754 -160.981644)
		(end 293.941754 -161.757868)
		(width 0.4572)
		(layer "F.Cu")
		(net "GND")
	)
	(segment
		(start 62.974982 -284.974792)
		(end 63.449962 -285.449772)
		(width 0.249936)
		(layer "F.Cu")
		(net "GND")
	)
	(segment
		(start 134.366 -282.021534)
		(end 134.304024 -282.021534)
		(width 0.254)
		(layer "F.Cu")
		(net "GND")
	)
	(segment
		(start 416.95751 -147.55495)
		(end 415.967164 -147.55495)
		(width 0.4572)
		(layer "F.Cu")
		(net "GND")
	)
	(segment
		(start 26.667206 -56.354218)
		(end 26.667968 -56.353456)
		(width 0.4572)
		(layer "F.Cu")
		(net "GND")
	)
	(segment
		(start 55.374794 -284.024832)
		(end 55.849774 -284.499812)
		(width 0.249936)
		(layer "F.Cu")
		(net "GND")
	)
	(segment
		(start 424.09999 -301.599854)
		(end 423.62501 -302.074834)
		(width 0.249936)
		(layer "F.Cu")
		(net "GND")
	)
	(segment
		(start 404.149814 -308.249828)
		(end 403.674834 -307.774848)
		(width 0.127)
		(layer "F.Cu")
		(net "GND")
	)
	(segment
		(start 404.943056 -373.36476)
		(end 404.26894 -373.36476)
		(width 0.4572)
		(layer "F.Cu")
		(net "GND")
	)
	(segment
		(start 188.37402 -73.166732)
		(end 188.37402 -73.85177)
		(width 0.4572)
		(layer "F.Cu")
		(net "GND")
	)
	(segment
		(start 424.57497 -294.4749)
		(end 424.09999 -293.99992)
		(width 0.249936)
		(layer "F.Cu")
		(net "GND")
	)
	(segment
		(start 77.464412 -29.67736)
		(end 77.464412 -29.079952)
		(width 0.4572)
		(layer "F.Cu")
		(net "GND")
	)
	(segment
		(start 120.473978 -26.606246)
		(end 120.473978 -25.971246)
		(width 0.4572)
		(layer "F.Cu")
		(net "GND")
	)
	(segment
		(start 284.724856 -287.824926)
		(end 285.199836 -288.299906)
		(width 0.249936)
		(layer "F.Cu")
		(net "GND")
	)
	(segment
		(start 46.8249 -302.074834)
		(end 46.34992 -301.599854)
		(width 0.249936)
		(layer "F.Cu")
		(net "GND")
	)
	(segment
		(start 164.349938 -300.649894)
		(end 164.824918 -300.174914)
		(width 0.249936)
		(layer "F.Cu")
		(net "GND")
	)
	(segment
		(start 70.099936 -292.099746)
		(end 69.624956 -291.624766)
		(width 0.249936)
		(layer "F.Cu")
		(net "GND")
	)
	(segment
		(start 45.051726 -109.644942)
		(end 46.042326 -109.644942)
		(width 0.3556)
		(layer "F.Cu")
		(net "GND")
	)
	(segment
		(start 194.749928 -300.649894)
		(end 195.224908 -300.174914)
		(width 0.249936)
		(layer "F.Cu")
		(net "GND")
	)
	(segment
		(start 161.500058 -300.649894)
		(end 161.975038 -300.174914)
		(width 0.249936)
		(layer "F.Cu")
		(net "GND")
	)
	(segment
		(start 371.60835 -255.83134)
		(end 371.60835 -256.35204)
		(width 0.4572)
		(layer "F.Cu")
		(net "GND")
	)
	(segment
		(start 21.530564 -65.92189)
		(end 21.530564 -65.15989)
		(width 0.4572)
		(layer "F.Cu")
		(net "GND")
	)
	(segment
		(start 90.055954 -33.19018)
		(end 88.664796 -33.19018)
		(width 0.3556)
		(layer "F.Cu")
		(net "GND")
	)
	(segment
		(start 360.135424 -116.449348)
		(end 360.135424 -115.688364)
		(width 0.4572)
		(layer "F.Cu")
		(net "GND")
	)
	(segment
		(start 309.664354 -29.67736)
		(end 309.664354 -29.079952)
		(width 0.4572)
		(layer "F.Cu")
		(net "GND")
	)
	(segment
		(start 62.974982 -296.37482)
		(end 63.449962 -296.8498)
		(width 0.249936)
		(layer "F.Cu")
		(net "GND")
	)
	(segment
		(start 427.89983 -298.74972)
		(end 427.42485 -298.27474)
		(width 0.249936)
		(layer "F.Cu")
		(net "GND")
	)
	(segment
		(start 81.024984 -298.27474)
		(end 81.499964 -297.79976)
		(width 0.249936)
		(layer "F.Cu")
		(net "GND")
	)
	(segment
		(start 307.999892 -301.599854)
		(end 308.474872 -301.124874)
		(width 0.249936)
		(layer "F.Cu")
		(net "GND")
	)
	(segment
		(start 422.548304 -149.355048)
		(end 421.557704 -149.355048)
		(width 0.3556)
		(layer "F.Cu")
		(net "GND")
	)
	(segment
		(start 287.099756 -307.299868)
		(end 286.624776 -306.824888)
		(width 0.249936)
		(layer "F.Cu")
		(net "GND")
	)
	(segment
		(start 438.354724 -34.990024)
		(end 436.964836 -34.990024)
		(width 0.3556)
		(layer "F.Cu")
		(net "GND")
	)
	(segment
		(start 176.224946 -287.899856)
		(end 176.624996 -288.299906)
		(width 0.249936)
		(layer "F.Cu")
		(net "GND")
	)
	(segment
		(start 277.251668 -106.045)
		(end 278.242268 -106.045)
		(width 0.3556)
		(layer "F.Cu")
		(net "GND")
	)
	(segment
		(start 269.999714 -284.499812)
		(end 269.524734 -284.024832)
		(width 0.249936)
		(layer "F.Cu")
		(net "GND")
	)
	(segment
		(start 49.446942 -109.177328)
		(end 49.914556 -109.644942)
		(width 0.3556)
		(layer "F.Cu")
		(net "GND")
	)
	(segment
		(start 152.94991 -288.299906)
		(end 152.47493 -287.824926)
		(width 0.249936)
		(layer "F.Cu")
		(net "GND")
	)
	(segment
		(start 152.764998 -34.990024)
		(end 151.748998 -34.990024)
		(width 0.3556)
		(layer "F.Cu")
		(net "GND")
	)
	(segment
		(start 255.346454 -255.669542)
		(end 255.508252 -255.83134)
		(width 0.4572)
		(layer "F.Cu")
		(net "GND")
	)
	(segment
		(start 398.925034 -306.824888)
		(end 399.400014 -306.349908)
		(width 0.249936)
		(layer "F.Cu")
		(net "GND")
	)
	(segment
		(start 377.722384 -252.756924)
		(end 377.722384 -253.45644)
		(width 0.4572)
		(layer "F.Cu")
		(net "GND")
	)
	(segment
		(start 177.174906 -300.174914)
		(end 176.699926 -299.699934)
		(width 0.249936)
		(layer "F.Cu")
		(net "GND")
	)
	(segment
		(start 50.14976 -304.449734)
		(end 49.67478 -304.924714)
		(width 0.249936)
		(layer "F.Cu")
		(net "GND")
	)
	(segment
		(start 44.449746 -298.74972)
		(end 43.974766 -299.224954)
		(width 0.249936)
		(layer "F.Cu")
		(net "GND")
	)
	(segment
		(start 415.074862 -291.624766)
		(end 414.599882 -292.099746)
		(width 0.249936)
		(layer "F.Cu")
		(net "GND")
	)
	(segment
		(start 428.84979 -296.8498)
		(end 429.325024 -296.37482)
		(width 0.249936)
		(layer "F.Cu")
		(net "GND")
	)
	(segment
		(start 167.200072 -299.699934)
		(end 166.725092 -300.174914)
		(width 0.249936)
		(layer "F.Cu")
		(net "GND")
	)
	(segment
		(start 126.205488 -285.488634)
		(end 125.894084 -285.488634)
		(width 0.2286)
		(layer "F.Cu")
		(net "GND")
	)
	(segment
		(start 66.299842 -297.79976)
		(end 66.774822 -298.27474)
		(width 0.249936)
		(layer "F.Cu")
		(net "GND")
	)
	(segment
		(start 130.49631 -25.990042)
		(end 131.36499 -25.990042)
		(width 0.3556)
		(layer "F.Cu")
		(net "GND")
	)
	(segment
		(start 124.063252 -108.82884)
		(end 124.063252 -108.067856)
		(width 0.4572)
		(layer "F.Cu")
		(net "GND")
	)
	(segment
		(start 387.355588 -244.286024)
		(end 387.355588 -243.16436)
		(width 0.2794)
		(layer "F.Cu")
		(net "GND")
	)
	(segment
		(start 397.97482 -301.124874)
		(end 398.4498 -300.649894)
		(width 0.249936)
		(layer "F.Cu")
		(net "GND")
	)
	(segment
		(start 14.656308 -303.70018)
		(end 13.943838 -303.70018)
		(width 0.254)
		(layer "F.Cu")
		(net "GND")
	)
	(segment
		(start 176.699926 -285.449772)
		(end 177.174906 -285.924752)
		(width 0.249936)
		(layer "F.Cu")
		(net "GND")
	)
	(segment
		(start 185.747914 -129.445004)
		(end 184.757314 -129.445004)
		(width 0.3556)
		(layer "F.Cu")
		(net "GND")
	)
	(segment
		(start 193.799968 -300.649894)
		(end 194.274948 -301.124874)
		(width 0.249936)
		(layer "F.Cu")
		(net "GND")
	)
	(segment
		(start 65.824862 -306.824888)
		(end 66.299842 -306.349908)
		(width 0.249936)
		(layer "F.Cu")
		(net "GND")
	)
	(segment
		(start 302.299878 -300.649894)
		(end 301.824898 -300.174914)
		(width 0.249936)
		(layer "F.Cu")
		(net "GND")
	)
	(segment
		(start 81.024984 -291.624766)
		(end 80.54975 -291.149786)
		(width 0.249936)
		(layer "F.Cu")
		(net "GND")
	)
	(segment
		(start 408.424888 -300.174914)
		(end 407.949908 -299.699934)
		(width 0.249936)
		(layer "F.Cu")
		(net "GND")
	)
	(segment
		(start 63.449962 -286.399732)
		(end 62.974982 -285.924752)
		(width 0.249936)
		(layer "F.Cu")
		(net "GND")
	)
	(segment
		(start 84.30895 -27.04973)
		(end 83.64982 -27.04973)
		(width 0.4572)
		(layer "F.Cu")
		(net "GND")
	)
	(segment
		(start 62.499748 -297.79976)
		(end 62.024768 -297.32478)
		(width 0.249936)
		(layer "F.Cu")
		(net "GND")
	)
	(segment
		(start 425.99991 -302.549814)
		(end 425.52493 -303.024794)
		(width 0.249936)
		(layer "F.Cu")
		(net "GND")
	)
	(segment
		(start 306.448206 -129.445004)
		(end 305.457606 -129.445004)
		(width 0.3556)
		(layer "F.Cu")
		(net "GND")
	)
	(segment
		(start 76.27493 -293.52494)
		(end 75.79995 -293.99992)
		(width 0.249936)
		(layer "F.Cu")
		(net "GND")
	)
	(segment
		(start 80.54975 -291.149786)
		(end 80.07477 -290.674806)
		(width 0.249936)
		(layer "F.Cu")
		(net "GND")
	)
	(segment
		(start 133.831838 -208.964022)
		(end 134.953502 -208.964022)
		(width 0.2794)
		(layer "F.Cu")
		(net "GND")
	)
	(segment
		(start 407.05532 -375.71426)
		(end 407.05532 -376.709432)
		(width 0.4572)
		(layer "F.Cu")
		(net "GND")
	)
	(segment
		(start 281.399742 -306.349908)
		(end 281.874722 -306.824888)
		(width 0.249936)
		(layer "F.Cu")
		(net "GND")
	)
	(segment
		(start 417.589462 -131.245102)
		(end 416.95751 -131.245102)
		(width 0.3556)
		(layer "F.Cu")
		(net "GND")
	)
	(segment
		(start 63.449962 -285.449772)
		(end 63.924942 -284.974792)
		(width 0.249936)
		(layer "F.Cu")
		(net "GND")
	)
	(segment
		(start 58.595006 -103.814372)
		(end 57.979818 -103.814372)
		(width 0.4064)
		(layer "F.Cu")
		(net "GND")
	)
	(segment
		(start 325.464678 -31.390082)
		(end 326.480678 -31.390082)
		(width 0.3556)
		(layer "F.Cu")
		(net "GND")
	)
	(segment
		(start 52.999894 -292.099746)
		(end 53.474874 -291.624766)
		(width 0.249936)
		(layer "F.Cu")
		(net "GND")
	)
	(segment
		(start 73.899776 -290.199826)
		(end 74.374756 -290.674806)
		(width 0.249936)
		(layer "F.Cu")
		(net "GND")
	)
	(segment
		(start 165.64737 -121.692416)
		(end 165.64737 -122.044206)
		(width 0.3556)
		(layer "F.Cu")
		(net "GND")
	)
	(segment
		(start 11.62177 -305.881786)
		(end 12.261596 -305.881786)
		(width 0.1778)
		(layer "F.Cu")
		(net "GND")
	)
	(segment
		(start 443.194186 -116.410486)
		(end 443.829186 -116.410486)
		(width 0.4572)
		(layer "F.Cu")
		(net "GND")
	)
	(segment
		(start 179.55006 -305.399948)
		(end 179.07508 -305.874928)
		(width 0.249936)
		(layer "F.Cu")
		(net "GND")
	)
	(segment
		(start 70.099936 -290.199826)
		(end 70.574916 -289.724846)
		(width 0.249936)
		(layer "F.Cu")
		(net "GND")
	)
	(segment
		(start 287.574736 -291.624766)
		(end 287.099756 -292.099746)
		(width 0.249936)
		(layer "F.Cu")
		(net "GND")
	)
	(segment
		(start 436.307484 -96.411542)
		(end 436.307484 -95.796862)
		(width 0.4572)
		(layer "F.Cu")
		(net "GND")
	)
	(segment
		(start 65.349882 -303.499774)
		(end 65.824862 -303.974754)
		(width 0.249936)
		(layer "F.Cu")
		(net "GND")
	)
	(segment
		(start 166.249858 -285.449772)
		(end 165.774878 -284.974792)
		(width 0.249936)
		(layer "F.Cu")
		(net "GND")
	)
	(segment
		(start 274.480782 -27.79014)
		(end 273.464782 -27.79014)
		(width 0.3556)
		(layer "F.Cu")
		(net "GND")
	)
	(segment
		(start 60.14085 -54.163722)
		(end 60.692792 -54.163722)
		(width 0.254)
		(layer "F.Cu")
		(net "GND")
	)
	(segment
		(start 153.89987 -280.699718)
		(end 153.42489 -280.224738)
		(width 0.249936)
		(layer "F.Cu")
		(net "GND")
	)
	(segment
		(start 306.494942 -102.439978)
		(end 305.457606 -102.439978)
		(width 0.3556)
		(layer "F.Cu")
		(net "GND")
	)
	(segment
		(start 425.99991 -302.549814)
		(end 426.47489 -303.024794)
		(width 0.249936)
		(layer "F.Cu")
		(net "GND")
	)
	(segment
		(start 433.403248 -59.971686)
		(end 433.403248 -60.627006)
		(width 0.381)
		(layer "F.Cu")
		(net "GND")
	)
	(segment
		(start 114.958876 -264.95756)
		(end 114.316002 -264.95756)
		(width 0.4572)
		(layer "F.Cu")
		(net "GND")
	)
	(segment
		(start 445.33439 -47.936658)
		(end 445.670178 -47.60087)
		(width 0.254)
		(layer "F.Cu")
		(net "GND")
	)
	(segment
		(start 227.008944 -97.96907)
		(end 227.008944 -97.31375)
		(width 0.4064)
		(layer "F.Cu")
		(net "GND")
	)
	(segment
		(start 64.07785 -114.267742)
		(end 64.688212 -114.267742)
		(width 0.4572)
		(layer "F.Cu")
		(net "GND")
	)
	(segment
		(start 308.474872 -296.37482)
		(end 308.949852 -296.8498)
		(width 0.249936)
		(layer "F.Cu")
		(net "GND")
	)
	(segment
		(start 294.86479 -27.79014)
		(end 293.84879 -27.79014)
		(width 0.3556)
		(layer "F.Cu")
		(net "GND")
	)
	(segment
		(start 190.348108 -133.044946)
		(end 189.357508 -133.044946)
		(width 0.3556)
		(layer "F.Cu")
		(net "GND")
	)
	(segment
		(start 304.199798 -300.649894)
		(end 303.724818 -301.124874)
		(width 0.249936)
		(layer "F.Cu")
		(net "GND")
	)
	(segment
		(start 288.99993 -297.79976)
		(end 288.524696 -298.27474)
		(width 0.249936)
		(layer "F.Cu")
		(net "GND")
	)
	(segment
		(start 290.42487 -284.024832)
		(end 289.94989 -284.499812)
		(width 0.249936)
		(layer "F.Cu")
		(net "GND")
	)
	(segment
		(start 264.689336 -62.812168)
		(end 265.49985 -62.812168)
		(width 0.4572)
		(layer "F.Cu")
		(net "GND")
	)
	(segment
		(start 410.799788 -293.99992)
		(end 410.324808 -294.4749)
		(width 0.249936)
		(layer "F.Cu")
		(net "GND")
	)
	(segment
		(start 290.89985 -293.99992)
		(end 290.42487 -293.52494)
		(width 0.249936)
		(layer "F.Cu")
		(net "GND")
	)
	(segment
		(start 258.867148 -56.354218)
		(end 258.86791 -56.353456)
		(width 0.4572)
		(layer "F.Cu")
		(net "GND")
	)
	(segment
		(start 41.26484 -27.79014)
		(end 42.28084 -27.79014)
		(width 0.3556)
		(layer "F.Cu")
		(net "GND")
	)
	(segment
		(start 415.549842 -307.299868)
		(end 416.024822 -307.774848)
		(width 0.249936)
		(layer "F.Cu")
		(net "GND")
	)
	(segment
		(start 309.424832 -299.224954)
		(end 308.949852 -298.74972)
		(width 0.249936)
		(layer "F.Cu")
		(net "GND")
	)
	(segment
		(start 306.099718 -295.89984)
		(end 306.574698 -296.37482)
		(width 0.249936)
		(layer "F.Cu")
		(net "GND")
	)
	(segment
		(start 55.849774 -286.399732)
		(end 55.374794 -285.924752)
		(width 0.249936)
		(layer "F.Cu")
		(net "GND")
	)
	(segment
		(start 416.974782 -293.52494)
		(end 416.499802 -293.04996)
		(width 0.249936)
		(layer "F.Cu")
		(net "GND")
	)
	(segment
		(start 343.149936 -154.313128)
		(end 344.23477 -154.313128)
		(width 0.4572)
		(layer "F.Cu")
		(net "GND")
	)
	(segment
		(start 291.84981 -290.199826)
		(end 292.32479 -289.724846)
		(width 0.249936)
		(layer "F.Cu")
		(net "GND")
	)
	(segment
		(start 414.696148 -25.990042)
		(end 415.564828 -25.990042)
		(width 0.3556)
		(layer "F.Cu")
		(net "GND")
	)
	(segment
		(start 362.696252 -25.990042)
		(end 363.564932 -25.990042)
		(width 0.3556)
		(layer "F.Cu")
		(net "GND")
	)
	(segment
		(start 414.124902 -294.4749)
		(end 414.599882 -293.99992)
		(width 0.249936)
		(layer "F.Cu")
		(net "GND")
	)
	(segment
		(start 405.575008 -297.32478)
		(end 406.049988 -296.8498)
		(width 0.249936)
		(layer "F.Cu")
		(net "GND")
	)
	(segment
		(start 183.766714 -123.635008)
		(end 184.757314 -123.635008)
		(width 0.3556)
		(layer "F.Cu")
		(net "GND")
	)
	(segment
		(start 155.800044 -274.049744)
		(end 155.325064 -273.574764)
		(width 0.249936)
		(layer "F.Cu")
		(net "GND")
	)
	(segment
		(start 47.77486 -303.024794)
		(end 48.24984 -303.499774)
		(width 0.249936)
		(layer "F.Cu")
		(net "GND")
	)
	(segment
		(start 174.634652 -38.937184)
		(end 174.900082 -38.671754)
		(width 0.4572)
		(layer "F.Cu")
		(net "GND")
	)
	(segment
		(start 82.7151 -59.946286)
		(end 82.7151 -60.601606)
		(width 0.4572)
		(layer "F.Cu")
		(net "GND")
	)
	(segment
		(start 168.743884 -43.85691)
		(end 169.415206 -43.85691)
		(width 0.254)
		(layer "F.Cu")
		(net "GND")
	)
	(segment
		(start 161.0868 -151.157432)
		(end 161.118042 -151.157432)
		(width 0.3556)
		(layer "F.Cu")
		(net "GND")
	)
	(segment
		(start 289.47491 -284.974792)
		(end 288.99993 -285.449772)
		(width 0.249936)
		(layer "F.Cu")
		(net "GND")
	)
	(segment
		(start 68.199762 -288.299906)
		(end 68.674742 -287.824926)
		(width 0.249936)
		(layer "F.Cu")
		(net "GND")
	)
	(segment
		(start 452.967852 -56.353456)
		(end 453.623172 -56.353456)
		(width 0.254)
		(layer "F.Cu")
		(net "GND")
	)
	(segment
		(start 152.94991 -286.399732)
		(end 152.47493 -285.924752)
		(width 0.249936)
		(layer "F.Cu")
		(net "GND")
	)
	(segment
		(start 156.750004 -297.79976)
		(end 157.224984 -298.27474)
		(width 0.249936)
		(layer "F.Cu")
		(net "GND")
	)
	(segment
		(start 294.69969 -306.349908)
		(end 295.174924 -306.824888)
		(width 0.249936)
		(layer "F.Cu")
		(net "GND")
	)
	(segment
		(start 325.464678 -29.589984)
		(end 326.480678 -29.589984)
		(width 0.3556)
		(layer "F.Cu")
		(net "GND")
	)
	(segment
		(start 306.448206 -134.845044)
		(end 305.457606 -134.845044)
		(width 0.3556)
		(layer "F.Cu")
		(net "GND")
	)
	(segment
		(start 157.699964 -299.699934)
		(end 157.224984 -299.224954)
		(width 0.249936)
		(layer "F.Cu")
		(net "GND")
	)
	(segment
		(start 70.574916 -290.674806)
		(end 70.099936 -291.149786)
		(width 0.249936)
		(layer "F.Cu")
		(net "GND")
	)
	(segment
		(start 54.282594 -28.875736)
		(end 54.282594 -28.47848)
		(width 0.254)
		(layer "F.Cu")
		(net "GND")
	)
	(segment
		(start 196.649848 -296.8498)
		(end 196.174868 -296.37482)
		(width 0.249936)
		(layer "F.Cu")
		(net "GND")
	)
	(segment
		(start 386.099812 -291.149786)
		(end 385.624832 -290.674806)
		(width 0.249936)
		(layer "F.Cu")
		(net "GND")
	)
	(segment
		(start 363.478826 -110.977426)
		(end 363.478826 -110.365032)
		(width 0.4572)
		(layer "F.Cu")
		(net "GND")
	)
	(segment
		(start 428.84979 -289.249866)
		(end 428.37481 -288.774886)
		(width 0.249936)
		(layer "F.Cu")
		(net "GND")
	)
	(segment
		(start 296.124884 -287.824926)
		(end 296.599864 -288.299906)
		(width 0.249936)
		(layer "F.Cu")
		(net "GND")
	)
	(segment
		(start 255.508252 -255.83134)
		(end 255.508252 -256.35204)
		(width 0.4572)
		(layer "F.Cu")
		(net "GND")
	)
	(segment
		(start 285.199836 -297.79976)
		(end 285.674816 -297.32478)
		(width 0.249936)
		(layer "F.Cu")
		(net "GND")
	)
	(segment
		(start 208.114138 -238.40694)
		(end 208.114138 -237.395004)
		(width 0.4572)
		(layer "F.Cu")
		(net "GND")
	)
	(segment
		(start 362.462826 -110.977426)
		(end 362.462826 -110.365032)
		(width 0.4572)
		(layer "F.Cu")
		(net "GND")
	)
	(segment
		(start 397.97482 -305.874928)
		(end 397.49984 -306.349908)
		(width 0.249936)
		(layer "F.Cu")
		(net "GND")
	)
	(segment
		(start 54.899814 -306.349908)
		(end 54.424834 -306.824888)
		(width 0.249936)
		(layer "F.Cu")
		(net "GND")
	)
	(segment
		(start 307.999892 -293.99992)
		(end 308.474872 -294.4749)
		(width 0.249936)
		(layer "F.Cu")
		(net "GND")
	)
	(segment
		(start 282.058364 -122.355102)
		(end 282.842462 -122.355102)
		(width 0.3556)
		(layer "F.Cu")
		(net "GND")
	)
	(segment
		(start 194.749928 -290.199826)
		(end 195.224908 -290.674806)
		(width 0.249936)
		(layer "F.Cu")
		(net "GND")
	)
	(segment
		(start 413.174942 -303.974754)
		(end 413.649922 -303.499774)
		(width 0.249936)
		(layer "F.Cu")
		(net "GND")
	)
	(segment
		(start 209.364834 -29.589984)
		(end 210.380834 -29.589984)
		(width 0.3556)
		(layer "F.Cu")
		(net "GND")
	)
	(segment
		(start 182.39994 -301.599854)
		(end 182.87492 -302.074834)
		(width 0.249936)
		(layer "F.Cu")
		(net "GND")
	)
	(segment
		(start 68.199762 -300.649894)
		(end 67.724782 -300.174914)
		(width 0.249936)
		(layer "F.Cu")
		(net "GND")
	)
	(segment
		(start 200.409048 -27.04973)
		(end 199.749918 -27.04973)
		(width 0.4572)
		(layer "F.Cu")
		(net "GND")
	)
	(segment
		(start 389.424926 -298.27474)
		(end 389.899906 -297.79976)
		(width 0.249936)
		(layer "F.Cu")
		(net "GND")
	)
	(segment
		(start 74.248264 -149.355048)
		(end 73.257664 -149.355048)
		(width 0.3556)
		(layer "F.Cu")
		(net "GND")
	)
	(segment
		(start 154.850084 -287.349946)
		(end 154.375104 -286.874966)
		(width 0.249936)
		(layer "F.Cu")
		(net "GND")
	)
	(segment
		(start 277.251668 -102.445058)
		(end 278.242268 -102.445058)
		(width 0.3556)
		(layer "F.Cu")
		(net "GND")
	)
	(segment
		(start 257.557524 -29.784294)
		(end 257.664458 -29.67736)
		(width 0.4572)
		(layer "F.Cu")
		(net "GND")
	)
	(segment
		(start 279.024842 -302.074834)
		(end 279.499822 -302.549814)
		(width 0.249936)
		(layer "F.Cu")
		(net "GND")
	)
	(segment
		(start 165.704774 -105.365042)
		(end 165.704774 -105.673652)
		(width 0.3556)
		(layer "F.Cu")
		(net "GND")
	)
	(segment
		(start 239.413288 -136.328404)
		(end 238.757968 -136.328404)
		(width 0.4064)
		(layer "F.Cu")
		(net "GND")
	)
	(segment
		(start 183.82488 -305.874928)
		(end 184.29986 -305.399948)
		(width 0.249936)
		(layer "F.Cu")
		(net "GND")
	)
	(segment
		(start 97.648268 -394.1318)
		(end 97.032318 -394.1318)
		(width 0.4572)
		(layer "F.Cu")
		(net "GND")
	)
	(segment
		(start 307.999892 -293.99992)
		(end 308.474872 -293.52494)
		(width 0.249936)
		(layer "F.Cu")
		(net "GND")
	)
	(segment
		(start 335.509362 -94.23273)
		(end 335.509362 -93.552264)
		(width 0.4572)
		(layer "F.Cu")
		(net "GND")
	)
	(segment
		(start 52.049934 -307.299868)
		(end 51.574954 -306.824888)
		(width 0.249936)
		(layer "F.Cu")
		(net "GND")
	)
	(segment
		(start 292.32479 -285.924752)
		(end 291.84981 -285.449772)
		(width 0.249936)
		(layer "F.Cu")
		(net "GND")
	)
	(segment
		(start 185.725054 -291.624766)
		(end 186.200034 -291.149786)
		(width 0.249936)
		(layer "F.Cu")
		(net "GND")
	)
	(segment
		(start 60.124848 -285.924752)
		(end 59.649868 -285.449772)
		(width 0.249936)
		(layer "F.Cu")
		(net "GND")
	)
	(segment
		(start 284.249876 -303.499774)
		(end 284.724856 -303.974754)
		(width 0.249936)
		(layer "F.Cu")
		(net "GND")
	)
	(segment
		(start 193.826892 -402.27504)
		(end 193.83883 -402.263102)
		(width 0.4572)
		(layer "F.Cu")
		(net "GND")
	)
	(segment
		(start 91.0336 -303.228248)
		(end 90.753438 -302.948086)
		(width 0.4572)
		(layer "F.Cu")
		(net "GND")
	)
	(segment
		(start 81.402682 -89.1159)
		(end 81.402682 -89.790524)
		(width 0.4572)
		(layer "F.Cu")
		(net "GND")
	)
	(segment
		(start 65.349882 -299.699934)
		(end 64.874902 -300.174914)
		(width 0.249936)
		(layer "F.Cu")
		(net "GND")
	)
	(segment
		(start 277.251668 -135.364982)
		(end 278.242268 -135.364982)
		(width 0.3556)
		(layer "F.Cu")
		(net "GND")
	)
	(segment
		(start 385.135882 -231.70896)
		(end 385.355592 -231.92867)
		(width 0.2794)
		(layer "F.Cu")
		(net "GND")
	)
	(segment
		(start 356.551738 -398.311624)
		(end 356.551738 -398.889982)
		(width 0.3048)
		(layer "F.Cu")
		(net "GND")
	)
	(segment
		(start 334.89392 -219.987114)
		(end 334.494124 -220.38691)
		(width 0.381)
		(layer "F.Cu")
		(net "GND")
	)
	(segment
		(start 180.50002 -293.99992)
		(end 180.975 -293.52494)
		(width 0.249936)
		(layer "F.Cu")
		(net "GND")
	)
	(segment
		(start 231.620822 -259.796534)
		(end 230.961184 -259.136896)
		(width 0.254)
		(layer "F.Cu")
		(net "GND")
	)
	(segment
		(start 361.417362 -118.743476)
		(end 361.417362 -119.35587)
		(width 0.4572)
		(layer "F.Cu")
		(net "GND")
	)
	(segment
		(start 125.810264 -121.661428)
		(end 125.154944 -121.661428)
		(width 0.4064)
		(layer "F.Cu")
		(net "GND")
	)
	(segment
		(start 156.750004 -288.299906)
		(end 157.224984 -287.824926)
		(width 0.249936)
		(layer "F.Cu")
		(net "GND")
	)
	(segment
		(start 405.994108 -35.264852)
		(end 405.994108 -35.499548)
		(width 0.4572)
		(layer "F.Cu")
		(net "GND")
	)
	(segment
		(start 41.599866 -277.849838)
		(end 41.124886 -277.374858)
		(width 0.249936)
		(layer "F.Cu")
		(net "GND")
	)
	(segment
		(start 294.22471 -291.624766)
		(end 294.69969 -292.099746)
		(width 0.249936)
		(layer "F.Cu")
		(net "GND")
	)
	(segment
		(start 71.049896 -292.099746)
		(end 71.049896 -292.1)
		(width 0.249936)
		(layer "F.Cu")
		(net "GND")
	)
	(segment
		(start 301.824898 -284.974792)
		(end 301.349918 -284.499812)
		(width 0.249936)
		(layer "F.Cu")
		(net "GND")
	)
	(segment
		(start 273.799808 -298.74972)
		(end 273.324828 -299.224954)
		(width 0.249936)
		(layer "F.Cu")
		(net "GND")
	)
	(segment
		(start 152.94991 -277.849838)
		(end 152.47493 -277.374858)
		(width 0.249936)
		(layer "F.Cu")
		(net "GND")
	)
	(segment
		(start 154.850084 -276.899878)
		(end 154.375104 -276.424898)
		(width 0.249936)
		(layer "F.Cu")
		(net "GND")
	)
	(segment
		(start 456.540108 -307.492146)
		(end 456.972162 -307.492146)
		(width 0.1778)
		(layer "F.Cu")
		(net "GND")
	)
	(segment
		(start 172.473874 -26.606246)
		(end 172.473874 -25.971246)
		(width 0.4572)
		(layer "F.Cu")
		(net "GND")
	)
	(segment
		(start 229.437438 -58.799984)
		(end 228.308154 -58.799984)
		(width 0.3556)
		(layer "F.Cu")
		(net "GND")
	)
	(segment
		(start 299.924724 -289.724846)
		(end 299.449744 -290.199826)
		(width 0.249936)
		(layer "F.Cu")
		(net "GND")
	)
	(segment
		(start 102.75316 -366.507268)
		(end 102.75316 -367.450878)
		(width 0.4572)
		(layer "F.Cu")
		(net "GND")
	)
	(segment
		(start 161.15157 -120.555004)
		(end 162.14217 -120.555004)
		(width 0.3556)
		(layer "F.Cu")
		(net "GND")
	)
	(segment
		(start 180.975 -300.174914)
		(end 181.44998 -299.699934)
		(width 0.249936)
		(layer "F.Cu")
		(net "GND")
	)
	(segment
		(start 293.84879 -31.390082)
		(end 294.86479 -31.390082)
		(width 0.3556)
		(layer "F.Cu")
		(net "GND")
	)
	(segment
		(start 371.624098 -27.411934)
		(end 371.624098 -26.319734)
		(width 0.4572)
		(layer "F.Cu")
		(net "GND")
	)
	(segment
		(start 336.493866 -219.187014)
		(end 336.09407 -218.787218)
		(width 0.381)
		(layer "F.Cu")
		(net "GND")
	)
	(segment
		(start 386.50799 -162.044126)
		(end 386.50799 -161.828226)
		(width 0.4572)
		(layer "F.Cu")
		(net "GND")
	)
	(segment
		(start 186.200034 -301.599854)
		(end 186.675014 -301.124874)
		(width 0.249936)
		(layer "F.Cu")
		(net "GND")
	)
	(segment
		(start 141.458442 -252.756924)
		(end 141.458442 -253.45644)
		(width 0.4572)
		(layer "F.Cu")
		(net "GND")
	)
	(segment
		(start 313.224926 -296.37482)
		(end 312.749692 -296.8498)
		(width 0.249936)
		(layer "F.Cu")
		(net "GND")
	)
	(segment
		(start 111.706152 -159.572198)
		(end 112.225328 -159.053022)
		(width 0.1778)
		(layer "F.Cu")
		(net "GND")
	)
	(segment
		(start 68.674742 -303.024794)
		(end 68.199762 -302.549814)
		(width 0.249936)
		(layer "F.Cu")
		(net "GND")
	)
	(segment
		(start 425.04995 -300.649894)
		(end 425.52493 -301.124874)
		(width 0.249936)
		(layer "F.Cu")
		(net "GND")
	)
	(segment
		(start 282.824936 -305.874928)
		(end 283.299916 -306.349908)
		(width 0.249936)
		(layer "F.Cu")
		(net "GND")
	)
	(segment
		(start 68.199762 -292.099746)
		(end 68.674742 -292.574726)
		(width 0.249936)
		(layer "F.Cu")
		(net "GND")
	)
	(segment
		(start 397.97482 -306.824888)
		(end 398.4498 -307.299868)
		(width 0.249936)
		(layer "F.Cu")
		(net "GND")
	)
	(segment
		(start 232.517442 -60.000134)
		(end 233.357928 -60.000134)
		(width 0.3556)
		(layer "F.Cu")
		(net "GND")
	)
	(segment
		(start 288.04997 -296.8498)
		(end 288.049716 -296.8498)
		(width 0.249936)
		(layer "F.Cu")
		(net "GND")
	)
	(segment
		(start 41.599866 -287.349946)
		(end 41.124886 -286.874966)
		(width 0.249936)
		(layer "F.Cu")
		(net "GND")
	)
	(segment
		(start 38.749986 -289.249866)
		(end 38.275006 -288.774886)
		(width 0.249936)
		(layer "F.Cu")
		(net "GND")
	)
	(segment
		(start 407.949908 -288.299906)
		(end 408.349958 -287.899856)
		(width 0.249936)
		(layer "F.Cu")
		(net "GND")
	)
	(segment
		(start 381.87122 -307.132482)
		(end 381.58293 -306.844192)
		(width 0.4572)
		(layer "F.Cu")
		(net "GND")
	)
	(segment
		(start 140.087096 -199.361806)
		(end 140.306806 -199.581516)
		(width 0.2794)
		(layer "F.Cu")
		(net "GND")
	)
	(segment
		(start 186.675014 -288.774886)
		(end 187.149994 -289.249866)
		(width 0.249936)
		(layer "F.Cu")
		(net "GND")
	)
	(segment
		(start 414.599882 -295.89984)
		(end 415.074862 -296.37482)
		(width 0.249936)
		(layer "F.Cu")
		(net "GND")
	)
	(segment
		(start 277.251668 -129.964942)
		(end 278.242268 -129.964942)
		(width 0.3556)
		(layer "F.Cu")
		(net "GND")
	)
	(segment
		(start 302.774858 -292.57498)
		(end 302.299878 -293.04996)
		(width 0.249936)
		(layer "F.Cu")
		(net "GND")
	)
	(segment
		(start 384.96494 -27.79014)
		(end 383.94894 -27.79014)
		(width 0.3556)
		(layer "F.Cu")
		(net "GND")
	)
	(segment
		(start 183.766714 -142.15491)
		(end 184.757314 -142.15491)
		(width 0.3556)
		(layer "F.Cu")
		(net "GND")
	)
	(segment
		(start 423.15003 -303.499774)
		(end 423.149776 -303.499774)
		(width 0.249936)
		(layer "F.Cu")
		(net "GND")
	)
	(segment
		(start 187.149994 -291.149786)
		(end 186.675014 -290.674806)
		(width 0.249936)
		(layer "F.Cu")
		(net "GND")
	)
	(segment
		(start 365.811816 -145.837656)
		(end 365.476028 -145.501868)
		(width 0.4064)
		(layer "F.Cu")
		(net "GND")
	)
	(segment
		(start 67.249802 -301.599854)
		(end 67.724782 -302.074834)
		(width 0.249936)
		(layer "F.Cu")
		(net "GND")
	)
	(segment
		(start 285.674816 -306.824888)
		(end 285.199836 -307.299868)
		(width 0.249936)
		(layer "F.Cu")
		(net "GND")
	)
	(segment
		(start 325.221854 -115.335304)
		(end 325.561198 -114.99596)
		(width 0.254)
		(layer "F.Cu")
		(net "GND")
	)
	(segment
		(start 228.39299 -94.073726)
		(end 227.734368 -94.073726)
		(width 0.254)
		(layer "F.Cu")
		(net "GND")
	)
	(segment
		(start 282.824936 -296.37482)
		(end 283.299916 -295.89984)
		(width 0.249936)
		(layer "F.Cu")
		(net "GND")
	)
	(segment
		(start 56.324754 -393.56284)
		(end 58.405268 -393.56284)
		(width 0.4572)
		(layer "F.Cu")
		(net "GND")
	)
	(segment
		(start 68.199762 -306.349908)
		(end 68.674742 -306.824888)
		(width 0.249936)
		(layer "F.Cu")
		(net "GND")
	)
	(segment
		(start 408.424888 -284.974792)
		(end 407.949908 -284.499812)
		(width 0.254)
		(layer "F.Cu")
		(net "GND")
	)
	(segment
		(start 334.575658 -88.564466)
		(end 334.268318 -88.871806)
		(width 0.1778)
		(layer "F.Cu")
		(net "GND")
	)
	(segment
		(start 169.099992 -306.349908)
		(end 169.574972 -305.874928)
		(width 0.249936)
		(layer "F.Cu")
		(net "GND")
	)
	(segment
		(start 158.649924 -280.699718)
		(end 158.174944 -280.224738)
		(width 0.249936)
		(layer "F.Cu")
		(net "GND")
	)
	(segment
		(start 281.718766 -123.878594)
		(end 281.995118 -124.154946)
		(width 0.3556)
		(layer "F.Cu")
		(net "GND")
	)
	(segment
		(start 404.624794 -305.874928)
		(end 404.149814 -306.349908)
		(width 0.249936)
		(layer "F.Cu")
		(net "GND")
	)
	(segment
		(start 271.957546 -142.892018)
		(end 272.100802 -142.748762)
		(width 0.4572)
		(layer "F.Cu")
		(net "GND")
	)
	(segment
		(start 7.213346 -137.344404)
		(end 6.558026 -137.344404)
		(width 0.4064)
		(layer "F.Cu")
		(net "GND")
	)
	(segment
		(start 410.041852 -160.981644)
		(end 410.041852 -161.757868)
		(width 0.4572)
		(layer "F.Cu")
		(net "GND")
	)
	(segment
		(start 299.866812 -131.245102)
		(end 300.857412 -131.245102)
		(width 0.3556)
		(layer "F.Cu")
		(net "GND")
	)
	(segment
		(start 405.575008 -285.924752)
		(end 406.049988 -285.449772)
		(width 0.249936)
		(layer "F.Cu")
		(net "GND")
	)
	(segment
		(start 70.574916 -289.724846)
		(end 71.049896 -289.249866)
		(width 0.249936)
		(layer "F.Cu")
		(net "GND")
	)
	(segment
		(start 359.79481 -158.705042)
		(end 359.79481 -159.266382)
		(width 0.254)
		(layer "F.Cu")
		(net "GND")
	)
	(segment
		(start 167.732964 -135.364982)
		(end 166.742364 -135.364982)
		(width 0.3556)
		(layer "F.Cu")
		(net "GND")
	)
	(segment
		(start 101.784912 -87.487506)
		(end 100.932996 -87.487506)
		(width 0.381)
		(layer "F.Cu")
		(net "GND")
	)
	(segment
		(start 72.267064 -131.245102)
		(end 73.257664 -131.245102)
		(width 0.3556)
		(layer "F.Cu")
		(net "GND")
	)
	(segment
		(start 259.860542 -16.439388)
		(end 259.936742 -16.363188)
		(width 0.4572)
		(layer "F.Cu")
		(net "GND")
	)
	(segment
		(start 52.999894 -293.99992)
		(end 52.524914 -293.52494)
		(width 0.249936)
		(layer "F.Cu")
		(net "GND")
	)
	(segment
		(start 50.14976 -298.74972)
		(end 50.624994 -298.27474)
		(width 0.249936)
		(layer "F.Cu")
		(net "GND")
	)
	(segment
		(start 61.074808 -296.37482)
		(end 61.549788 -296.8498)
		(width 0.249936)
		(layer "F.Cu")
		(net "GND")
	)
	(segment
		(start 185.250074 -296.8498)
		(end 185.725054 -296.37482)
		(width 0.249936)
		(layer "F.Cu")
		(net "GND")
	)
	(segment
		(start 80.282542 -28.875736)
		(end 80.282542 -28.47848)
		(width 0.254)
		(layer "F.Cu")
		(net "GND")
	)
	(segment
		(start 78.64983 -289.249866)
		(end 79.12481 -288.774886)
		(width 0.249936)
		(layer "F.Cu")
		(net "GND")
	)
	(segment
		(start 273.464782 -34.990024)
		(end 271.582896 -34.990024)
		(width 0.3556)
		(layer "F.Cu")
		(net "GND")
	)
	(segment
		(start 419.349936 -301.599854)
		(end 419.824916 -302.074834)
		(width 0.249936)
		(layer "F.Cu")
		(net "GND")
	)
	(segment
		(start 414.599882 -303.499774)
		(end 414.124902 -303.974754)
		(width 0.249936)
		(layer "F.Cu")
		(net "GND")
	)
	(segment
		(start 354.834698 -38.937184)
		(end 355.100128 -38.671754)
		(width 0.4572)
		(layer "F.Cu")
		(net "GND")
	)
	(segment
		(start 271.382744 -141.87297)
		(end 271.382744 -140.85697)
		(width 0.4572)
		(layer "F.Cu")
		(net "GND")
	)
	(segment
		(start 451.7644 -29.67736)
		(end 451.7644 -29.079952)
		(width 0.4572)
		(layer "F.Cu")
		(net "GND")
	)
	(segment
		(start 160.074864 -296.37482)
		(end 160.549844 -295.89984)
		(width 0.249936)
		(layer "F.Cu")
		(net "GND")
	)
	(segment
		(start 39.725346 -141.029436)
		(end 39.97325 -141.029436)
		(width 0.4572)
		(layer "F.Cu")
		(net "GND")
	)
	(segment
		(start 417.450016 -294.94988)
		(end 417.924996 -294.4749)
		(width 0.249936)
		(layer "F.Cu")
		(net "GND")
	)
	(segment
		(start 417.924996 -291.624766)
		(end 418.399976 -291.149786)
		(width 0.249936)
		(layer "F.Cu")
		(net "GND")
	)
	(segment
		(start 230.421942 -113.183162)
		(end 230.421942 -112.542574)
		(width 0.4572)
		(layer "F.Cu")
		(net "GND")
	)
	(segment
		(start 193.324988 -297.32478)
		(end 193.799968 -296.8498)
		(width 0.249936)
		(layer "F.Cu")
		(net "GND")
	)
	(segment
		(start 283.833062 -137.16508)
		(end 282.842462 -137.16508)
		(width 0.3556)
		(layer "F.Cu")
		(net "GND")
	)
	(segment
		(start 397.02486 -307.774848)
		(end 397.49984 -308.249828)
		(width 0.249936)
		(layer "F.Cu")
		(net "GND")
	)
	(segment
		(start 194.274948 -289.724846)
		(end 194.749928 -290.199826)
		(width 0.249936)
		(layer "F.Cu")
		(net "GND")
	)
	(segment
		(start 249.862848 -182.794656)
		(end 249.862848 -183.404256)
		(width 0.4572)
		(layer "F.Cu")
		(net "GND")
	)
	(segment
		(start 416.024822 -303.974754)
		(end 416.499802 -304.449734)
		(width 0.249936)
		(layer "F.Cu")
		(net "GND")
	)
	(segment
		(start 306.099718 -299.699934)
		(end 306.574698 -300.174914)
		(width 0.249936)
		(layer "F.Cu")
		(net "GND")
	)
	(segment
		(start 415.097214 -177.78222)
		(end 415.931604 -177.78222)
		(width 0.4572)
		(layer "F.Cu")
		(net "GND")
	)
	(segment
		(start 307.049932 -292.099746)
		(end 307.524912 -292.574726)
		(width 0.249936)
		(layer "F.Cu")
		(net "GND")
	)
	(segment
		(start 290.794948 -101.782372)
		(end 290.17976 -101.782372)
		(width 0.4064)
		(layer "F.Cu")
		(net "GND")
	)
	(segment
		(start 393.334494 -47.936658)
		(end 393.670282 -47.60087)
		(width 0.254)
		(layer "F.Cu")
		(net "GND")
	)
	(segment
		(start 39.699946 -283.549852)
		(end 39.224966 -283.074872)
		(width 0.249936)
		(layer "F.Cu")
		(net "GND")
	)
	(segment
		(start 60.124848 -303.974754)
		(end 60.599828 -303.499774)
		(width 0.249936)
		(layer "F.Cu")
		(net "GND")
	)
	(segment
		(start 229.067614 -217.504264)
		(end 228.667818 -217.104468)
		(width 0.381)
		(layer "F.Cu")
		(net "GND")
	)
	(segment
		(start 373.658384 -252.756924)
		(end 373.658384 -253.45644)
		(width 0.4572)
		(layer "F.Cu")
		(net "GND")
	)
	(segment
		(start 295.174924 -285.924752)
		(end 294.69969 -285.449772)
		(width 0.249936)
		(layer "F.Cu")
		(net "GND")
	)
	(segment
		(start 82.449924 -299.699934)
		(end 81.974944 -299.224954)
		(width 0.249936)
		(layer "F.Cu")
		(net "GND")
	)
	(segment
		(start 186.200034 -292.099746)
		(end 186.675014 -291.624766)
		(width 0.249936)
		(layer "F.Cu")
		(net "GND")
	)
	(segment
		(start 272.374868 -282.124912)
		(end 272.849848 -282.599892)
		(width 0.249936)
		(layer "F.Cu")
		(net "GND")
	)
	(segment
		(start 57.749948 -292.099746)
		(end 58.224928 -291.624766)
		(width 0.249936)
		(layer "F.Cu")
		(net "GND")
	)
	(segment
		(start 229.067614 -220.704156)
		(end 228.667818 -221.103952)
		(width 0.381)
		(layer "F.Cu")
		(net "GND")
	)
	(segment
		(start 428.84979 -293.04996)
		(end 429.325024 -292.574726)
		(width 0.249936)
		(layer "F.Cu")
		(net "GND")
	)
	(segment
		(start 400.349974 -290.199826)
		(end 400.824954 -289.724846)
		(width 0.249936)
		(layer "F.Cu")
		(net "GND")
	)
	(segment
		(start 421.724836 -303.024794)
		(end 422.199816 -302.549814)
		(width 0.249936)
		(layer "F.Cu")
		(net "GND")
	)
	(segment
		(start 363.531404 -126.394718)
		(end 363.531404 -126.94666)
		(width 0.2032)
		(layer "F.Cu")
		(net "GND")
	)
	(segment
		(start 78.667864 -55.083456)
		(end 79.323184 -55.083456)
		(width 0.254)
		(layer "F.Cu")
		(net "GND")
	)
	(segment
		(start 73.899776 -293.99992)
		(end 73.424796 -293.52494)
		(width 0.249936)
		(layer "F.Cu")
		(net "GND")
	)
	(segment
		(start 247.954038 -307.484272)
		(end 248.567956 -307.484272)
		(width 0.254)
		(layer "F.Cu")
		(net "GND")
	)
	(segment
		(start 47.29988 -293.99992)
		(end 47.77486 -294.4749)
		(width 0.254)
		(layer "F.Cu")
		(net "GND")
	)
	(segment
		(start 384.96494 -29.589984)
		(end 383.94894 -29.589984)
		(width 0.3556)
		(layer "F.Cu")
		(net "GND")
	)
	(segment
		(start 462.865724 -274.61083)
		(end 463.475324 -274.61083)
		(width 0.4572)
		(layer "F.Cu")
		(net "GND")
	)
	(segment
		(start 260.446012 -334.415638)
		(end 260.451346 -334.410304)
		(width 0.4572)
		(layer "F.Cu")
		(net "GND")
	)
	(segment
		(start 403.199854 -286.399732)
		(end 403.674834 -285.924752)
		(width 0.249936)
		(layer "F.Cu")
		(net "GND")
	)
	(segment
		(start 48.72482 -300.174914)
		(end 49.1998 -299.699934)
		(width 0.249936)
		(layer "F.Cu")
		(net "GND")
	)
	(segment
		(start 417.823142 -134.845044)
		(end 416.95751 -134.845044)
		(width 0.3556)
		(layer "F.Cu")
		(net "GND")
	)
	(segment
		(start 288.99993 -301.599854)
		(end 288.524696 -302.074834)
		(width 0.249936)
		(layer "F.Cu")
		(net "GND")
	)
	(segment
		(start 262.889492 -64.312292)
		(end 263.647936 -64.312292)
		(width 0.4572)
		(layer "F.Cu")
		(net "GND")
	)
	(segment
		(start 422.199816 -282.599892)
		(end 423.149776 -282.599892)
		(width 0.254)
		(layer "F.Cu")
		(net "GND")
	)
	(segment
		(start 412.044896 -27.79014)
		(end 410.964888 -27.79014)
		(width 0.3556)
		(layer "F.Cu")
		(net "GND")
	)
	(segment
		(start 292.32479 -287.899856)
		(end 292.72484 -288.299906)
		(width 0.249936)
		(layer "F.Cu")
		(net "GND")
	)
	(segment
		(start 401.299934 -301.599854)
		(end 400.824954 -302.074834)
		(width 0.249936)
		(layer "F.Cu")
		(net "GND")
	)
	(segment
		(start 69.289422 -131.245102)
		(end 68.65747 -131.245102)
		(width 0.3556)
		(layer "F.Cu")
		(net "GND")
	)
	(segment
		(start 76.27493 -297.32478)
		(end 75.79995 -297.79976)
		(width 0.249936)
		(layer "F.Cu")
		(net "GND")
	)
	(segment
		(start 279.155398 -102.445058)
		(end 278.242268 -102.445058)
		(width 0.3556)
		(layer "F.Cu")
		(net "GND")
	)
	(segment
		(start 283.299916 -306.349908)
		(end 283.774896 -305.874928)
		(width 0.249936)
		(layer "F.Cu")
		(net "GND")
	)
	(segment
		(start 402.249894 -303.499774)
		(end 402.724874 -303.974754)
		(width 0.249936)
		(layer "F.Cu")
		(net "GND")
	)
	(segment
		(start 269.999714 -298.74972)
		(end 269.52448 -298.27474)
		(width 0.249936)
		(layer "F.Cu")
		(net "GND")
	)
	(segment
		(start 167.732964 -124.154946)
		(end 166.742364 -124.154946)
		(width 0.3556)
		(layer "F.Cu")
		(net "GND")
	)
	(segment
		(start 301.349918 -293.99992)
		(end 300.874684 -293.52494)
		(width 0.249936)
		(layer "F.Cu")
		(net "GND")
	)
	(segment
		(start 274.749768 -299.699934)
		(end 275.224748 -300.174914)
		(width 0.249936)
		(layer "F.Cu")
		(net "GND")
	)
	(segment
		(start 388.949946 -286.399732)
		(end 388.474966 -285.924752)
		(width 0.249936)
		(layer "F.Cu")
		(net "GND")
	)
	(segment
		(start 283.299916 -307.299868)
		(end 283.774896 -306.824888)
		(width 0.249936)
		(layer "F.Cu")
		(net "GND")
	)
	(segment
		(start 386.099812 -273.099784)
		(end 386.574792 -273.574764)
		(width 0.249936)
		(layer "F.Cu")
		(net "GND")
	)
	(segment
		(start 251.351542 -207.51165)
		(end 250.927362 -207.93583)
		(width 0.4572)
		(layer "F.Cu")
		(net "GND")
	)
	(segment
		(start 154.850084 -279.749758)
		(end 154.375104 -279.274778)
		(width 0.249936)
		(layer "F.Cu")
		(net "GND")
	)
	(segment
		(start 128.199388 -31.390082)
		(end 128.689862 -30.899608)
		(width 0.3556)
		(layer "F.Cu")
		(net "GND")
	)
	(segment
		(start 183.364886 -27.79014)
		(end 182.348886 -27.79014)
		(width 0.3556)
		(layer "F.Cu")
		(net "GND")
	)
	(segment
		(start 49.863502 -113.485676)
		(end 50.10404 -113.245138)
		(width 0.3556)
		(layer "F.Cu")
		(net "GND")
	)
	(segment
		(start 169.099992 -285.449772)
		(end 168.625012 -284.974792)
		(width 0.249936)
		(layer "F.Cu")
		(net "GND")
	)
	(segment
		(start 117.395498 -285.488634)
		(end 117.706902 -285.488634)
		(width 0.2286)
		(layer "F.Cu")
		(net "GND")
	)
	(segment
		(start 57.274968 -302.074834)
		(end 57.749948 -301.599854)
		(width 0.249936)
		(layer "F.Cu")
		(net "GND")
	)
	(segment
		(start 68.674742 -284.974792)
		(end 69.149976 -285.449772)
		(width 0.249936)
		(layer "F.Cu")
		(net "GND")
	)
	(segment
		(start 410.324808 -302.074834)
		(end 410.799788 -301.599854)
		(width 0.249936)
		(layer "F.Cu")
		(net "GND")
	)
	(segment
		(start 312.749692 -302.549814)
		(end 313.224926 -302.074834)
		(width 0.249936)
		(layer "F.Cu")
		(net "GND")
	)
	(segment
		(start 314.649866 -295.89984)
		(end 315.124846 -296.37482)
		(width 0.249936)
		(layer "F.Cu")
		(net "GND")
	)
	(segment
		(start 54.899814 -290.199826)
		(end 55.374794 -289.724846)
		(width 0.249936)
		(layer "F.Cu")
		(net "GND")
	)
	(segment
		(start 101.553264 -242.080288)
		(end 101.979222 -242.080288)
		(width 0.254)
		(layer "F.Cu")
		(net "GND")
	)
	(segment
		(start 180.975 -285.924752)
		(end 181.44998 -286.399732)
		(width 0.249936)
		(layer "F.Cu")
		(net "GND")
	)
	(segment
		(start 401.774914 -300.174914)
		(end 401.299934 -299.699934)
		(width 0.249936)
		(layer "F.Cu")
		(net "GND")
	)
	(segment
		(start 409.374848 -284.974792)
		(end 409.849828 -285.449772)
		(width 0.249936)
		(layer "F.Cu")
		(net "GND")
	)
	(segment
		(start 240.51006 -50.397156)
		(end 241.062002 -50.397156)
		(width 0.254)
		(layer "F.Cu")
		(net "GND")
	)
	(segment
		(start 313.699906 -297.79976)
		(end 313.224926 -297.32478)
		(width 0.249936)
		(layer "F.Cu")
		(net "GND")
	)
	(segment
		(start 186.675014 -284.024832)
		(end 187.149994 -284.499812)
		(width 0.249936)
		(layer "F.Cu")
		(net "GND")
	)
	(segment
		(start 226.78898 -308.073298)
		(end 226.905312 -308.073298)
		(width 0.1778)
		(layer "F.Cu")
		(net "GND")
	)
	(segment
		(start 65.824862 -305.874928)
		(end 66.299842 -306.349908)
		(width 0.249936)
		(layer "F.Cu")
		(net "GND")
	)
	(segment
		(start 416.974782 -304.924714)
		(end 416.499802 -304.449734)
		(width 0.249936)
		(layer "F.Cu")
		(net "GND")
	)
	(segment
		(start 45.051726 -120.555004)
		(end 46.042326 -120.555004)
		(width 0.3556)
		(layer "F.Cu")
		(net "GND")
	)
	(segment
		(start 281.874722 -297.32478)
		(end 282.349702 -296.8498)
		(width 0.249936)
		(layer "F.Cu")
		(net "GND")
	)
	(segment
		(start 55.249826 -392.487912)
		(end 56.324754 -393.56284)
		(width 0.4572)
		(layer "F.Cu")
		(net "GND")
	)
	(segment
		(start 37.799772 -296.8498)
		(end 38.274752 -297.32478)
		(width 0.249936)
		(layer "F.Cu")
		(net "GND")
	)
	(segment
		(start 180.02504 -305.874928)
		(end 180.50002 -306.349908)
		(width 0.249936)
		(layer "F.Cu")
		(net "GND")
	)
	(segment
		(start 117.706902 -282.021534)
		(end 117.644926 -282.021534)
		(width 0.254)
		(layer "F.Cu")
		(net "GND")
	)
	(segment
		(start 185.725054 -293.52494)
		(end 186.200034 -293.04996)
		(width 0.249936)
		(layer "F.Cu")
		(net "GND")
	)
	(segment
		(start 76.74991 -293.04996)
		(end 76.27493 -292.574726)
		(width 0.249936)
		(layer "F.Cu")
		(net "GND")
	)
	(segment
		(start 414.599882 -290.199826)
		(end 415.074862 -289.724846)
		(width 0.249936)
		(layer "F.Cu")
		(net "GND")
	)
	(segment
		(start 160.549844 -297.79976)
		(end 160.074864 -297.32478)
		(width 0.249936)
		(layer "F.Cu")
		(net "GND")
	)
	(segment
		(start 362.548932 -33.19018)
		(end 363.564932 -33.19018)
		(width 0.3556)
		(layer "F.Cu")
		(net "GND")
	)
	(segment
		(start 36.6649 -34.990024)
		(end 35.6489 -34.990024)
		(width 0.3556)
		(layer "F.Cu")
		(net "GND")
	)
	(segment
		(start 181.92496 -289.724846)
		(end 181.44998 -290.199826)
		(width 0.249936)
		(layer "F.Cu")
		(net "GND")
	)
	(segment
		(start 300.399704 -307.299868)
		(end 299.924724 -306.824888)
		(width 0.249936)
		(layer "F.Cu")
		(net "GND")
	)
	(segment
		(start 413.649922 -290.199826)
		(end 414.124902 -289.724846)
		(width 0.249936)
		(layer "F.Cu")
		(net "GND")
	)
	(segment
		(start 417.984178 -122.200416)
		(end 417.618672 -121.83491)
		(width 0.3556)
		(layer "F.Cu")
		(net "GND")
	)
	(segment
		(start 63.36284 -382.538732)
		(end 63.408814 -382.584706)
		(width 0.4572)
		(layer "F.Cu")
		(net "GND")
	)
	(segment
		(start 303.249838 -290.199826)
		(end 302.774858 -290.674806)
		(width 0.249936)
		(layer "F.Cu")
		(net "GND")
	)
	(segment
		(start 418.874956 -288.774886)
		(end 418.399976 -289.249866)
		(width 0.249936)
		(layer "F.Cu")
		(net "GND")
	)
	(segment
		(start 147.89785 -38.937184)
		(end 148.634704 -38.937184)
		(width 0.4572)
		(layer "F.Cu")
		(net "GND")
	)
	(segment
		(start 40.649906 -286.399732)
		(end 40.174926 -285.924752)
		(width 0.249936)
		(layer "F.Cu")
		(net "GND")
	)
	(segment
		(start 155.800044 -289.249866)
		(end 155.325064 -289.724846)
		(width 0.254)
		(layer "F.Cu")
		(net "GND")
	)
	(segment
		(start 88.2523 -116.416836)
		(end 87.6427 -116.416836)
		(width 0.4572)
		(layer "F.Cu")
		(net "GND")
	)
	(segment
		(start 247.018048 -347.89999)
		(end 249.047254 -347.89999)
		(width 0.4572)
		(layer "F.Cu")
		(net "GND")
	)
	(segment
		(start 412.699962 -306.349908)
		(end 413.174942 -306.824888)
		(width 0.249936)
		(layer "F.Cu")
		(net "GND")
	)
	(segment
		(start 366.71885 -147.38604)
		(end 366.51946 -147.18665)
		(width 0.254)
		(layer "F.Cu")
		(net "GND")
	)
	(segment
		(start 179.07508 -289.724846)
		(end 178.599846 -290.199826)
		(width 0.249936)
		(layer "F.Cu")
		(net "GND")
	)
	(segment
		(start 308.474872 -302.074834)
		(end 307.999892 -301.599854)
		(width 0.249936)
		(layer "F.Cu")
		(net "GND")
	)
	(segment
		(start 88.664796 -34.990024)
		(end 87.648796 -34.990024)
		(width 0.3556)
		(layer "F.Cu")
		(net "GND")
	)
	(segment
		(start 239.246664 -205.47711)
		(end 239.246664 -205.16723)
		(width 0.4572)
		(layer "F.Cu")
		(net "GND")
	)
	(segment
		(start 175.203358 -59.971686)
		(end 175.203358 -60.627006)
		(width 0.381)
		(layer "F.Cu")
		(net "GND")
	)
	(segment
		(start 419.824916 -296.37482)
		(end 419.349936 -295.89984)
		(width 0.249936)
		(layer "F.Cu")
		(net "GND")
	)
	(segment
		(start 392.749786 -293.04996)
		(end 392.274806 -292.57498)
		(width 0.249936)
		(layer "F.Cu")
		(net "GND")
	)
	(segment
		(start 351.33915 -173.88205)
		(end 350.647 -173.88205)
		(width 0.4572)
		(layer "F.Cu")
		(net "GND")
	)
	(segment
		(start 15.264892 -25.990042)
		(end 14.396212 -25.990042)
		(width 0.3556)
		(layer "F.Cu")
		(net "GND")
	)
	(segment
		(start 301.837344 -125.752352)
		(end 301.520098 -125.435106)
		(width 0.3556)
		(layer "F.Cu")
		(net "GND")
	)
	(segment
		(start 190.950088 -301.599854)
		(end 191.425068 -302.074834)
		(width 0.249936)
		(layer "F.Cu")
		(net "GND")
	)
	(segment
		(start 363.333284 -113.933478)
		(end 363.333284 -113.674652)
		(width 0.254)
		(layer "F.Cu")
		(net "GND")
	)
	(segment
		(start 410.324808 -307.774848)
		(end 410.799788 -307.299868)
		(width 0.249936)
		(layer "F.Cu")
		(net "GND")
	)
	(segment
		(start 278.549862 -294.94988)
		(end 278.074882 -294.4749)
		(width 0.249936)
		(layer "F.Cu")
		(net "GND")
	)
	(segment
		(start 184.757314 -147.55495)
		(end 183.766968 -147.55495)
		(width 0.4572)
		(layer "F.Cu")
		(net "GND")
	)
	(segment
		(start 306.448206 -136.645142)
		(end 305.457606 -136.645142)
		(width 0.3556)
		(layer "F.Cu")
		(net "GND")
	)
	(segment
		(start 40.24884 -31.390082)
		(end 41.26484 -31.390082)
		(width 0.3556)
		(layer "F.Cu")
		(net "GND")
	)
	(segment
		(start 186.026552 -25.832054)
		(end 186.669934 -25.832054)
		(width 0.4572)
		(layer "F.Cu")
		(net "GND")
	)
	(segment
		(start 421.724836 -298.27474)
		(end 422.199816 -297.79976)
		(width 0.249936)
		(layer "F.Cu")
		(net "GND")
	)
	(segment
		(start 299.512736 -102.439978)
		(end 300.857412 -102.439978)
		(width 0.3556)
		(layer "F.Cu")
		(net "GND")
	)
	(segment
		(start 271.424908 -300.174914)
		(end 270.949928 -299.699934)
		(width 0.249936)
		(layer "F.Cu")
		(net "GND")
	)
	(segment
		(start 399.93316 -111.44504)
		(end 398.94256 -111.44504)
		(width 0.3556)
		(layer "F.Cu")
		(net "GND")
	)
	(segment
		(start 181.92496 -285.924752)
		(end 181.44998 -286.399732)
		(width 0.249936)
		(layer "F.Cu")
		(net "GND")
	)
	(segment
		(start 242.864894 -33.19018)
		(end 241.848894 -33.19018)
		(width 0.3556)
		(layer "F.Cu")
		(net "GND")
	)
	(segment
		(start 424.09999 -303.499774)
		(end 423.15003 -303.499774)
		(width 0.249936)
		(layer "F.Cu")
		(net "GND")
	)
	(segment
		(start 341.212932 -110.785656)
		(end 342.006682 -110.785656)
		(width 0.254)
		(layer "F.Cu")
		(net "GND")
	)
	(segment
		(start 56.799988 -286.399732)
		(end 56.324754 -285.924752)
		(width 0.249936)
		(layer "F.Cu")
		(net "GND")
	)
	(segment
		(start 156.275024 -298.27474)
		(end 156.750004 -297.79976)
		(width 0.249936)
		(layer "F.Cu")
		(net "GND")
	)
	(segment
		(start 415.074862 -302.074834)
		(end 415.549842 -301.599854)
		(width 0.249936)
		(layer "F.Cu")
		(net "GND")
	)
	(segment
		(start 419.349936 -298.74972)
		(end 419.824916 -298.27474)
		(width 0.249936)
		(layer "F.Cu")
		(net "GND")
	)
	(segment
		(start 67.724782 -305.874928)
		(end 68.199762 -306.349908)
		(width 0.249936)
		(layer "F.Cu")
		(net "GND")
	)
	(segment
		(start 169.574972 -291.624766)
		(end 169.099992 -292.099746)
		(width 0.249936)
		(layer "F.Cu")
		(net "GND")
	)
	(segment
		(start 315.893958 -35.264852)
		(end 315.893958 -35.499548)
		(width 0.4572)
		(layer "F.Cu")
		(net "GND")
	)
	(segment
		(start 66.774822 -305.874928)
		(end 66.299842 -306.349908)
		(width 0.249936)
		(layer "F.Cu")
		(net "GND")
	)
	(segment
		(start 410.799788 -303.499774)
		(end 411.275022 -303.974754)
		(width 0.249936)
		(layer "F.Cu")
		(net "GND")
	)
	(segment
		(start 67.249802 -285.449772)
		(end 67.724782 -285.924752)
		(width 0.249936)
		(layer "F.Cu")
		(net "GND")
	)
	(segment
		(start 369.218718 -46.693836)
		(end 369.019328 -46.893226)
		(width 0.254)
		(layer "F.Cu")
		(net "GND")
	)
	(segment
		(start 173.850046 -306.349908)
		(end 174.325026 -305.874928)
		(width 0.249936)
		(layer "F.Cu")
		(net "GND")
	)
	(segment
		(start 391.324846 -276.424898)
		(end 390.849866 -275.949918)
		(width 0.249936)
		(layer "F.Cu")
		(net "GND")
	)
	(segment
		(start 45.370242 -47.60087)
		(end 45.7962 -47.60087)
		(width 0.254)
		(layer "F.Cu")
		(net "GND")
	)
	(segment
		(start 301.349918 -294.94988)
		(end 301.824898 -294.4749)
		(width 0.249936)
		(layer "F.Cu")
		(net "GND")
	)
	(segment
		(start 130.34899 -31.390082)
		(end 131.36499 -31.390082)
		(width 0.3556)
		(layer "F.Cu")
		(net "GND")
	)
	(segment
		(start 258.84378 -45.88891)
		(end 259.515102 -45.88891)
		(width 0.254)
		(layer "F.Cu")
		(net "GND")
	)
	(segment
		(start 38.349428 -161.6329)
		(end 38.706044 -161.276284)
		(width 0.4572)
		(layer "F.Cu")
		(net "GND")
	)
	(segment
		(start 52.999894 -290.199826)
		(end 52.524914 -289.724846)
		(width 0.249936)
		(layer "F.Cu")
		(net "GND")
	)
	(segment
		(start 385.39674 -246.059706)
		(end 384.556 -246.059706)
		(width 0.4572)
		(layer "F.Cu")
		(net "GND")
	)
	(segment
		(start 206.941674 -225.89871)
		(end 206.9592 -225.881184)
		(width 0.4572)
		(layer "F.Cu")
		(net "GND")
	)
	(segment
		(start 168.768014 -54.067456)
		(end 169.423334 -54.067456)
		(width 0.254)
		(layer "F.Cu")
		(net "GND")
	)
	(segment
		(start 299.924724 -291.624766)
		(end 300.399704 -292.099746)
		(width 0.249936)
		(layer "F.Cu")
		(net "GND")
	)
	(segment
		(start 194.749928 -293.99992)
		(end 195.224908 -294.4749)
		(width 0.249936)
		(layer "F.Cu")
		(net "GND")
	)
	(segment
		(start 77.69987 -296.8498)
		(end 77.22489 -297.32478)
		(width 0.249936)
		(layer "F.Cu")
		(net "GND")
	)
	(segment
		(start 168.150032 -285.449772)
		(end 167.675052 -284.974792)
		(width 0.249936)
		(layer "F.Cu")
		(net "GND")
	)
	(segment
		(start 361.03433 -138.267694)
		(end 361.03433 -138.819636)
		(width 0.254)
		(layer "F.Cu")
		(net "GND")
	)
	(segment
		(start 21.147024 -52.592224)
		(end 21.222208 -52.51704)
		(width 0.254)
		(layer "F.Cu")
		(net "GND")
	)
	(segment
		(start 362.580936 -118.779036)
		(end 362.580936 -119.39143)
		(width 0.4572)
		(layer "F.Cu")
		(net "GND")
	)
	(segment
		(start 185.730388 -118.370858)
		(end 185.594498 -118.234968)
		(width 0.3556)
		(layer "F.Cu")
		(net "GND")
	)
	(segment
		(start 193.745104 -414.80486)
		(end 193.745104 -413.87141)
		(width 0.4572)
		(layer "F.Cu")
		(net "GND")
	)
	(segment
		(start 390.849866 -299.699934)
		(end 391.324846 -300.174914)
		(width 0.249936)
		(layer "F.Cu")
		(net "GND")
	)
	(segment
		(start 160.074864 -299.224954)
		(end 159.599884 -299.699934)
		(width 0.249936)
		(layer "F.Cu")
		(net "GND")
	)
	(segment
		(start 73.899776 -293.04996)
		(end 73.424796 -292.574726)
		(width 0.249936)
		(layer "F.Cu")
		(net "GND")
	)
	(segment
		(start 76.27493 -302.074834)
		(end 75.79995 -301.599854)
		(width 0.249936)
		(layer "F.Cu")
		(net "GND")
	)
	(segment
		(start 175.749966 -306.349908)
		(end 176.224946 -306.824888)
		(width 0.249936)
		(layer "F.Cu")
		(net "GND")
	)
	(segment
		(start 405.928068 -389.240268)
		(end 405.928068 -388.73684)
		(width 0.4572)
		(layer "F.Cu")
		(net "GND")
	)
	(segment
		(start 303.249838 -289.249866)
		(end 303.724818 -289.724846)
		(width 0.249936)
		(layer "F.Cu")
		(net "GND")
	)
	(segment
		(start 36.849812 -282.599892)
		(end 36.374832 -282.124912)
		(width 0.249936)
		(layer "F.Cu")
		(net "GND")
	)
	(segment
		(start 297.614848 -84.873592)
		(end 298.967144 -84.873592)
		(width 0.4572)
		(layer "F.Cu")
		(net "GND")
	)
	(segment
		(start 48.24984 -306.349908)
		(end 48.72482 -305.874928)
		(width 0.249936)
		(layer "F.Cu")
		(net "GND")
	)
	(segment
		(start 426.47489 -293.52494)
		(end 425.99991 -293.04996)
		(width 0.249936)
		(layer "F.Cu")
		(net "GND")
	)
	(segment
		(start 416.024822 -300.174914)
		(end 415.549842 -299.699934)
		(width 0.249936)
		(layer "F.Cu")
		(net "GND")
	)
	(segment
		(start 302.299878 -284.499812)
		(end 301.824898 -284.974792)
		(width 0.249936)
		(layer "F.Cu")
		(net "GND")
	)
	(segment
		(start 229.067614 -218.30411)
		(end 228.667818 -217.904314)
		(width 0.381)
		(layer "F.Cu")
		(net "GND")
	)
	(segment
		(start 297.549824 -307.299868)
		(end 298.024804 -306.824888)
		(width 0.249936)
		(layer "F.Cu")
		(net "GND")
	)
	(segment
		(start 47.29988 -303.499774)
		(end 46.8249 -303.024794)
		(width 0.249936)
		(layer "F.Cu")
		(net "GND")
	)
	(segment
		(start 307.524912 -300.174914)
		(end 307.049932 -299.699934)
		(width 0.249936)
		(layer "F.Cu")
		(net "GND")
	)
	(segment
		(start 273.324828 -298.27474)
		(end 273.799808 -298.74972)
		(width 0.249936)
		(layer "F.Cu")
		(net "GND")
	)
	(segment
		(start 135.875014 -48.753014)
		(end 135.168386 -48.753014)
		(width 0.254)
		(layer "F.Cu")
		(net "GND")
	)
	(segment
		(start 153.650442 -252.756924)
		(end 153.650442 -253.45644)
		(width 0.4572)
		(layer "F.Cu")
		(net "GND")
	)
	(segment
		(start 357.778558 -282.8417)
		(end 357.546148 -283.07411)
		(width 0.2286)
		(layer "F.Cu")
		(net "GND")
	)
	(segment
		(start 220.851222 -146.990562)
		(end 220.241622 -146.990562)
		(width 0.4572)
		(layer "F.Cu")
		(net "GND")
	)
	(segment
		(start 281.874722 -302.074834)
		(end 282.349702 -301.599854)
		(width 0.249936)
		(layer "F.Cu")
		(net "GND")
	)
	(segment
		(start 274.749768 -285.449772)
		(end 275.224748 -284.974792)
		(width 0.249936)
		(layer "F.Cu")
		(net "GND")
	)
	(segment
		(start 279.974802 -303.974754)
		(end 279.499822 -304.449734)
		(width 0.249936)
		(layer "F.Cu")
		(net "GND")
	)
	(segment
		(start 197.600062 -303.499774)
		(end 198.075042 -303.024794)
		(width 0.249936)
		(layer "F.Cu")
		(net "GND")
	)
	(segment
		(start 195.224908 -296.37482)
		(end 194.749928 -296.8498)
		(width 0.249936)
		(layer "F.Cu")
		(net "GND")
	)
	(segment
		(start 437.889396 -295.647872)
		(end 437.889396 -294.727884)
		(width 0.4572)
		(layer "F.Cu")
		(net "GND")
	)
	(segment
		(start 345.161108 -37.201094)
		(end 344.3986 -37.201094)
		(width 0.4572)
		(layer "F.Cu")
		(net "GND")
	)
	(segment
		(start 165.546786 -109.177328)
		(end 166.0144 -109.644942)
		(width 0.3556)
		(layer "F.Cu")
		(net "GND")
	)
	(segment
		(start 163.399978 -305.399948)
		(end 163.874958 -305.874928)
		(width 0.249936)
		(layer "F.Cu")
		(net "GND")
	)
	(segment
		(start 280.924762 -305.874928)
		(end 280.449782 -306.349908)
		(width 0.249936)
		(layer "F.Cu")
		(net "GND")
	)
	(segment
		(start 135.2423 -194.938396)
		(end 136.637776 -194.938396)
		(width 0.4572)
		(layer "F.Cu")
		(net "GND")
	)
	(segment
		(start 282.824936 -293.52494)
		(end 282.349702 -293.04996)
		(width 0.249936)
		(layer "F.Cu")
		(net "GND")
	)
	(segment
		(start 82.721958 -141.42085)
		(end 82.369914 -141.42085)
		(width 0.4064)
		(layer "F.Cu")
		(net "GND")
	)
	(segment
		(start 302.299878 -292.099746)
		(end 301.824898 -291.624766)
		(width 0.249936)
		(layer "F.Cu")
		(net "GND")
	)
	(segment
		(start 77.69987 -289.249866)
		(end 77.22489 -289.724846)
		(width 0.249936)
		(layer "F.Cu")
		(net "GND")
	)
	(segment
		(start 98.85045 -6.113526)
		(end 98.675698 -6.113526)
		(width 0.4572)
		(layer "F.Cu")
		(net "GND")
	)
	(segment
		(start 50.14976 -305.399948)
		(end 49.67478 -305.874928)
		(width 0.249936)
		(layer "F.Cu")
		(net "GND")
	)
	(segment
		(start 376.641868 -26.606246)
		(end 376.641868 -25.971246)
		(width 0.4572)
		(layer "F.Cu")
		(net "GND")
	)
	(segment
		(start 169.035222 -14.735302)
		(end 169.217086 -14.553438)
		(width 0.381)
		(layer "F.Cu")
		(net "GND")
	)
	(segment
		(start 184.77484 -285.924752)
		(end 185.250074 -285.449772)
		(width 0.249936)
		(layer "F.Cu")
		(net "GND")
	)
	(segment
		(start 351.65792 -26.606246)
		(end 351.65792 -25.971246)
		(width 0.4572)
		(layer "F.Cu")
		(net "GND")
	)
	(segment
		(start 79.59979 -298.74972)
		(end 79.12481 -298.27474)
		(width 0.249936)
		(layer "F.Cu")
		(net "GND")
	)
	(segment
		(start 53.949854 -294.94988)
		(end 53.474874 -294.4749)
		(width 0.249936)
		(layer "F.Cu")
		(net "GND")
	)
	(segment
		(start 403.199854 -307.299868)
		(end 402.724874 -306.824888)
		(width 0.249936)
		(layer "F.Cu")
		(net "GND")
	)
	(segment
		(start 50.14976 -288.299906)
		(end 50.624994 -287.824926)
		(width 0.249936)
		(layer "F.Cu")
		(net "GND")
	)
	(segment
		(start 242.316 -216.80805)
		(end 241.3254 -216.80805)
		(width 0.4572)
		(layer "F.Cu")
		(net "GND")
	)
	(segment
		(start 137.630662 -65.92189)
		(end 137.630662 -65.15989)
		(width 0.4572)
		(layer "F.Cu")
		(net "GND")
	)
	(segment
		(start 205.844902 -29.589984)
		(end 204.764894 -29.589984)
		(width 0.3556)
		(layer "F.Cu")
		(net "GND")
	)
	(segment
		(start 183.3499 -307.299868)
		(end 183.82488 -307.774848)
		(width 0.249936)
		(layer "F.Cu")
		(net "GND")
	)
	(segment
		(start 285.199836 -284.499812)
		(end 284.724856 -284.974792)
		(width 0.249936)
		(layer "F.Cu")
		(net "GND")
	)
	(segment
		(start 278.549862 -299.699934)
		(end 279.024842 -300.174914)
		(width 0.249936)
		(layer "F.Cu")
		(net "GND")
	)
	(segment
		(start 411.275022 -302.074834)
		(end 411.750002 -301.599854)
		(width 0.249936)
		(layer "F.Cu")
		(net "GND")
	)
	(segment
		(start 258.625086 -14.735302)
		(end 258.625086 -14.100302)
		(width 0.381)
		(layer "F.Cu")
		(net "GND")
	)
	(segment
		(start 45.051726 -100.64496)
		(end 46.042326 -100.64496)
		(width 0.3556)
		(layer "F.Cu")
		(net "GND")
	)
	(segment
		(start 178.599846 -284.499812)
		(end 179.07508 -284.974792)
		(width 0.249936)
		(layer "F.Cu")
		(net "GND")
	)
	(segment
		(start 55.374794 -305.874928)
		(end 54.899814 -306.349908)
		(width 0.249936)
		(layer "F.Cu")
		(net "GND")
	)
	(segment
		(start 414.124902 -302.074834)
		(end 414.599882 -301.599854)
		(width 0.249936)
		(layer "F.Cu")
		(net "GND")
	)
	(segment
		(start 409.374848 -285.924752)
		(end 408.899868 -285.449772)
		(width 0.249936)
		(layer "F.Cu")
		(net "GND")
	)
	(segment
		(start 231.149144 -177.74158)
		(end 231.149144 -178.38039)
		(width 0.4572)
		(layer "F.Cu")
		(net "GND")
	)
	(segment
		(start 130.34899 -29.589984)
		(end 131.36499 -29.589984)
		(width 0.3556)
		(layer "F.Cu")
		(net "GND")
	)
	(segment
		(start 154.850084 -274.999958)
		(end 154.375104 -274.524978)
		(width 0.249936)
		(layer "F.Cu")
		(net "GND")
	)
	(segment
		(start 310.849772 -293.99992)
		(end 310.374792 -293.52494)
		(width 0.249936)
		(layer "F.Cu")
		(net "GND")
	)
	(segment
		(start 117.940328 -33.248092)
		(end 117.940328 -33.857692)
		(width 0.4572)
		(layer "F.Cu")
		(net "GND")
	)
	(segment
		(start 194.749928 -295.89984)
		(end 195.224908 -296.37482)
		(width 0.249936)
		(layer "F.Cu")
		(net "GND")
	)
	(segment
		(start 301.520098 -125.435106)
		(end 300.857412 -125.435106)
		(width 0.3556)
		(layer "F.Cu")
		(net "GND")
	)
	(segment
		(start 56.324754 -285.924752)
		(end 55.849774 -286.399732)
		(width 0.249936)
		(layer "F.Cu")
		(net "GND")
	)
	(segment
		(start 385.98094 -25.990042)
		(end 384.96494 -25.990042)
		(width 0.3556)
		(layer "F.Cu")
		(net "GND")
	)
	(segment
		(start 12.73429 -138.267694)
		(end 12.73429 -138.819636)
		(width 0.254)
		(layer "F.Cu")
		(net "GND")
	)
	(segment
		(start 417.924996 -292.574726)
		(end 418.399976 -292.099746)
		(width 0.249936)
		(layer "F.Cu")
		(net "GND")
	)
	(segment
		(start 353.247452 -37.087048)
		(end 353.882452 -37.087048)
		(width 0.4572)
		(layer "F.Cu")
		(net "GND")
	)
	(segment
		(start 57.274968 -303.974754)
		(end 56.799988 -303.499774)
		(width 0.249936)
		(layer "F.Cu")
		(net "GND")
	)
	(segment
		(start 174.69485 -104.830372)
		(end 174.079662 -104.830372)
		(width 0.4064)
		(layer "F.Cu")
		(net "GND")
	)
	(segment
		(start 50.624994 -293.52494)
		(end 51.099974 -293.99992)
		(width 0.249936)
		(layer "F.Cu")
		(net "GND")
	)
	(segment
		(start 420.774876 -300.174914)
		(end 420.299896 -299.699934)
		(width 0.249936)
		(layer "F.Cu")
		(net "GND")
	)
	(segment
		(start 206.773526 -218.636088)
		(end 206.773526 -218.236546)
		(width 0.254)
		(layer "F.Cu")
		(net "GND")
	)
	(segment
		(start 315.99759 -38.937184)
		(end 316.734444 -38.937184)
		(width 0.4572)
		(layer "F.Cu")
		(net "GND")
	)
	(segment
		(start 56.799988 -295.89984)
		(end 56.325008 -296.37482)
		(width 0.249936)
		(layer "F.Cu")
		(net "GND")
	)
	(segment
		(start 144.362678 -34.29762)
		(end 143.92783 -34.732468)
		(width 0.4572)
		(layer "F.Cu")
		(net "GND")
	)
	(segment
		(start 168.150032 -288.299906)
		(end 167.675052 -287.824926)
		(width 0.249936)
		(layer "F.Cu")
		(net "GND")
	)
	(segment
		(start 52.049934 -292.099746)
		(end 51.574954 -291.624766)
		(width 0.249936)
		(layer "F.Cu")
		(net "GND")
	)
	(segment
		(start 170.049952 -303.499774)
		(end 170.524932 -303.974754)
		(width 0.249936)
		(layer "F.Cu")
		(net "GND")
	)
	(segment
		(start 393.7 -282.599892)
		(end 393.22502 -282.124912)
		(width 0.249936)
		(layer "F.Cu")
		(net "GND")
	)
	(segment
		(start 62.974982 -305.874928)
		(end 63.449962 -306.349908)
		(width 0.249936)
		(layer "F.Cu")
		(net "GND")
	)
	(segment
		(start 402.249894 -306.349908)
		(end 402.724874 -306.824888)
		(width 0.249936)
		(layer "F.Cu")
		(net "GND")
	)
	(segment
		(start 290.89985 -295.89984)
		(end 290.42487 -296.37482)
		(width 0.249936)
		(layer "F.Cu")
		(net "GND")
	)
	(segment
		(start 62.024768 -307.774848)
		(end 62.499748 -307.299868)
		(width 0.249936)
		(layer "F.Cu")
		(net "GND")
	)
	(segment
		(start 205.689454 -294.727884)
		(end 205.644242 -294.682672)
		(width 0.4572)
		(layer "F.Cu")
		(net "GND")
	)
	(segment
		(start 178.124866 -284.974792)
		(end 177.649886 -284.499812)
		(width 0.249936)
		(layer "F.Cu")
		(net "GND")
	)
	(segment
		(start 65.349882 -305.399948)
		(end 65.824862 -305.874928)
		(width 0.249936)
		(layer "F.Cu")
		(net "GND")
	)
	(segment
		(start 288.524696 -291.624766)
		(end 288.99993 -292.099746)
		(width 0.249936)
		(layer "F.Cu")
		(net "GND")
	)
	(segment
		(start 247.464834 -27.79014)
		(end 248.480834 -27.79014)
		(width 0.3556)
		(layer "F.Cu")
		(net "GND")
	)
	(segment
		(start 167.923718 -168.229788)
		(end 168.091104 -168.397174)
		(width 0.4572)
		(layer "F.Cu")
		(net "GND")
	)
	(segment
		(start 279.974802 -297.32478)
		(end 279.499822 -297.79976)
		(width 0.249936)
		(layer "F.Cu")
		(net "GND")
	)
	(segment
		(start 47.032926 -118.754906)
		(end 46.042326 -118.754906)
		(width 0.3556)
		(layer "F.Cu")
		(net "GND")
	)
	(segment
		(start 56.799988 -299.699934)
		(end 56.324754 -300.174914)
		(width 0.249936)
		(layer "F.Cu")
		(net "GND")
	)
	(segment
		(start 406.999948 -299.699934)
		(end 406.524968 -300.174914)
		(width 0.249936)
		(layer "F.Cu")
		(net "GND")
	)
	(segment
		(start 189.39002 -73.166732)
		(end 189.39002 -73.85177)
		(width 0.4572)
		(layer "F.Cu")
		(net "GND")
	)
	(segment
		(start 436.964836 -33.19018)
		(end 435.948836 -33.19018)
		(width 0.3556)
		(layer "F.Cu")
		(net "GND")
	)
	(segment
		(start 184.77992 -303.969928)
		(end 184.29986 -304.449734)
		(width 0.249936)
		(layer "F.Cu")
		(net "GND")
	)
	(segment
		(start 31.69412 -35.499548)
		(end 32.066484 -35.871912)
		(width 0.4572)
		(layer "F.Cu")
		(net "GND")
	)
	(segment
		(start 112.470692 -125.40488)
		(end 112.470692 -124.852938)
		(width 0.254)
		(layer "F.Cu")
		(net "GND")
	)
	(segment
		(start 17.511776 -145.837656)
		(end 17.175988 -145.501868)
		(width 0.4064)
		(layer "F.Cu")
		(net "GND")
	)
	(segment
		(start 248.480834 -29.589984)
		(end 247.464834 -29.589984)
		(width 0.3556)
		(layer "F.Cu")
		(net "GND")
	)
	(segment
		(start 209.90179 -227.625656)
		(end 210.475322 -227.625656)
		(width 0.4572)
		(layer "F.Cu")
		(net "GND")
	)
	(segment
		(start 109.54639 -282.021534)
		(end 109.484414 -282.021534)
		(width 0.254)
		(layer "F.Cu")
		(net "GND")
	)
	(segment
		(start 422.548304 -133.044946)
		(end 421.557704 -133.044946)
		(width 0.3556)
		(layer "F.Cu")
		(net "GND")
	)
	(segment
		(start 232.868978 -276.534118)
		(end 232.854246 -276.519386)
		(width 0.254)
		(layer "F.Cu")
		(net "GND")
	)
	(segment
		(start 302.299878 -293.04996)
		(end 301.824898 -292.574726)
		(width 0.249936)
		(layer "F.Cu")
		(net "GND")
	)
	(segment
		(start 288.99993 -305.399948)
		(end 288.524696 -305.874928)
		(width 0.249936)
		(layer "F.Cu")
		(net "GND")
	)
	(segment
		(start 307.049932 -290.199826)
		(end 307.524912 -290.674806)
		(width 0.249936)
		(layer "F.Cu")
		(net "GND")
	)
	(segment
		(start 153.89987 -275.949918)
		(end 153.42489 -275.474938)
		(width 0.249936)
		(layer "F.Cu")
		(net "GND")
	)
	(segment
		(start 171.949872 -299.699934)
		(end 171.474892 -300.174914)
		(width 0.249936)
		(layer "F.Cu")
		(net "GND")
	)
	(segment
		(start 169.099992 -284.499812)
		(end 169.574972 -284.024832)
		(width 0.249936)
		(layer "F.Cu")
		(net "GND")
	)
	(segment
		(start 411.750002 -301.599854)
		(end 412.224982 -302.074834)
		(width 0.249936)
		(layer "F.Cu")
		(net "GND")
	)
	(segment
		(start 65.824862 -306.824888)
		(end 66.299842 -307.299868)
		(width 0.249936)
		(layer "F.Cu")
		(net "GND")
	)
	(segment
		(start 192.828926 -402.27504)
		(end 193.826892 -402.27504)
		(width 0.4572)
		(layer "F.Cu")
		(net "GND")
	)
	(segment
		(start 272.374868 -289.724846)
		(end 272.849848 -290.199826)
		(width 0.249936)
		(layer "F.Cu")
		(net "GND")
	)
	(segment
		(start 38.749986 -280.699718)
		(end 38.275006 -280.224738)
		(width 0.249936)
		(layer "F.Cu")
		(net "GND")
	)
	(segment
		(start 442.580776 -27.79014)
		(end 441.564776 -27.79014)
		(width 0.3556)
		(layer "F.Cu")
		(net "GND")
	)
	(segment
		(start 102.713536 -222.464122)
		(end 102.483412 -222.464122)
		(width 0.4572)
		(layer "F.Cu")
		(net "GND")
	)
	(segment
		(start 233.503216 -274.531328)
		(end 232.898188 -274.531328)
		(width 0.254)
		(layer "F.Cu")
		(net "GND")
	)
	(segment
		(start 280.924762 -304.924714)
		(end 280.449782 -304.449734)
		(width 0.249936)
		(layer "F.Cu")
		(net "GND")
	)
	(segment
		(start 48.470566 -131.277614)
		(end 48.957992 -131.76504)
		(width 0.3556)
		(layer "F.Cu")
		(net "GND")
	)
	(segment
		(start 401.299934 -286.399732)
		(end 401.774914 -285.924752)
		(width 0.249936)
		(layer "F.Cu")
		(net "GND")
	)
	(segment
		(start 74.374756 -296.37482)
		(end 73.899776 -296.8498)
		(width 0.249936)
		(layer "F.Cu")
		(net "GND")
	)
	(segment
		(start 159.599884 -290.199826)
		(end 159.124904 -289.724846)
		(width 0.249936)
		(layer "F.Cu")
		(net "GND")
	)
	(segment
		(start 450.650864 -374.07215)
		(end 450.650864 -373.42191)
		(width 0.4572)
		(layer "F.Cu")
		(net "GND")
	)
	(segment
		(start 196.649848 -298.74972)
		(end 197.125082 -298.27474)
		(width 0.249936)
		(layer "F.Cu")
		(net "GND")
	)
	(segment
		(start 376.40895 -179.451)
		(end 375.793 -179.451)
		(width 0.4572)
		(layer "F.Cu")
		(net "GND")
	)
	(segment
		(start 301.88408 -120.716548)
		(end 301.88408 -120.400572)
		(width 0.3556)
		(layer "F.Cu")
		(net "GND")
	)
	(segment
		(start 185.844688 -143.655796)
		(end 185.545476 -143.955008)
		(width 0.3556)
		(layer "F.Cu")
		(net "GND")
	)
	(segment
		(start 389.56488 -25.990042)
		(end 388.6962 -25.990042)
		(width 0.3556)
		(layer "F.Cu")
		(net "GND")
	)
	(segment
		(start 360.045 -27.79014)
		(end 358.964992 -27.79014)
		(width 0.3556)
		(layer "F.Cu")
		(net "GND")
	)
	(segment
		(start 387.006084 -161.330132)
		(end 387.006084 -161.276284)
		(width 0.4572)
		(layer "F.Cu")
		(net "GND")
	)
	(segment
		(start 294.255952 -199.718676)
		(end 294.255952 -200.822306)
		(width 0.381)
		(layer "F.Cu")
		(net "GND")
	)
	(segment
		(start 77.69987 -298.74972)
		(end 78.17485 -299.224954)
		(width 0.249936)
		(layer "F.Cu")
		(net "GND")
	)
	(segment
		(start 74.248264 -134.845044)
		(end 73.257664 -134.845044)
		(width 0.3556)
		(layer "F.Cu")
		(net "GND")
	)
	(segment
		(start 182.39994 -292.099746)
		(end 182.87492 -291.624766)
		(width 0.249936)
		(layer "F.Cu")
		(net "GND")
	)
	(segment
		(start 47.29988 -303.499774)
		(end 46.8249 -303.974754)
		(width 0.249936)
		(layer "F.Cu")
		(net "GND")
	)
	(segment
		(start 282.824936 -303.974754)
		(end 282.349702 -303.499774)
		(width 0.249936)
		(layer "F.Cu")
		(net "GND")
	)
	(segment
		(start 375.112788 -9.713976)
		(end 375.112788 -10.35812)
		(width 0.4572)
		(layer "F.Cu")
		(net "GND")
	)
	(segment
		(start 416.974782 -292.574726)
		(end 417.450016 -293.04996)
		(width 0.249936)
		(layer "F.Cu")
		(net "GND")
	)
	(segment
		(start 428.582582 -28.47848)
		(end 428.243238 -28.139136)
		(width 0.254)
		(layer "F.Cu")
		(net "GND")
	)
	(segment
		(start 403.674834 -297.32478)
		(end 403.199854 -297.79976)
		(width 0.249936)
		(layer "F.Cu")
		(net "GND")
	)
	(segment
		(start 85.757766 -299.4406)
		(end 85.757766 -301.262034)
		(width 0.4572)
		(layer "F.Cu")
		(net "GND")
	)
	(segment
		(start 39.699946 -274.049744)
		(end 39.224966 -273.574764)
		(width 0.249936)
		(layer "F.Cu")
		(net "GND")
	)
	(segment
		(start 78.057502 -80.449674)
		(end 78.743302 -80.449674)
		(width 0.254)
		(layer "F.Cu")
		(net "GND")
	)
	(segment
		(start 303.249838 -305.399948)
		(end 303.724818 -305.874928)
		(width 0.249936)
		(layer "F.Cu")
		(net "GND")
	)
	(segment
		(start 163.0553 -102.445058)
		(end 162.14217 -102.445058)
		(width 0.3556)
		(layer "F.Cu")
		(net "GND")
	)
	(segment
		(start 161.15157 -104.244902)
		(end 162.14217 -104.244902)
		(width 0.3556)
		(layer "F.Cu")
		(net "GND")
	)
	(segment
		(start 198.513446 -114.42954)
		(end 197.873366 -114.42954)
		(width 0.4064)
		(layer "F.Cu")
		(net "GND")
	)
	(segment
		(start 313.699906 -299.699934)
		(end 313.224926 -300.174914)
		(width 0.249936)
		(layer "F.Cu")
		(net "GND")
	)
	(segment
		(start 219.162376 -23.355554)
		(end 219.812108 -23.355554)
		(width 0.4572)
		(layer "F.Cu")
		(net "GND")
	)
	(segment
		(start 42.074846 -299.2247)
		(end 41.599866 -298.74972)
		(width 0.249936)
		(layer "F.Cu")
		(net "GND")
	)
	(segment
		(start 119.572532 -119.011954)
		(end 119.969788 -119.011954)
		(width 0.254)
		(layer "F.Cu")
		(net "GND")
	)
	(segment
		(start 410.324808 -300.174914)
		(end 409.849828 -299.699934)
		(width 0.249936)
		(layer "F.Cu")
		(net "GND")
	)
	(segment
		(start 69.684138 -124.31649)
		(end 69.684138 -124.000514)
		(width 0.3556)
		(layer "F.Cu")
		(net "GND")
	)
	(segment
		(start 173.897798 -38.937184)
		(end 174.634652 -38.937184)
		(width 0.4572)
		(layer "F.Cu")
		(net "GND")
	)
	(segment
		(start 391.799826 -286.399732)
		(end 391.324846 -286.874712)
		(width 0.249936)
		(layer "F.Cu")
		(net "GND")
	)
	(segment
		(start 176.224946 -291.624766)
		(end 176.699926 -292.099746)
		(width 0.249936)
		(layer "F.Cu")
		(net "GND")
	)
	(segment
		(start 39.382954 -34.990024)
		(end 41.26484 -34.990024)
		(width 0.3556)
		(layer "F.Cu")
		(net "GND")
	)
	(segment
		(start 172.424852 -289.724846)
		(end 171.949872 -290.199826)
		(width 0.249936)
		(layer "F.Cu")
		(net "GND")
	)
	(segment
		(start 54.899814 -295.89984)
		(end 54.424834 -296.37482)
		(width 0.249936)
		(layer "F.Cu")
		(net "GND")
	)
	(segment
		(start 277.251668 -138.964924)
		(end 278.242268 -138.964924)
		(width 0.3556)
		(layer "F.Cu")
		(net "GND")
	)
	(segment
		(start 367.798604 -65.92189)
		(end 367.798604 -65.15989)
		(width 0.4572)
		(layer "F.Cu")
		(net "GND")
	)
	(segment
		(start 200.011538 -405.501094)
		(end 200.011538 -404.770844)
		(width 0.4572)
		(layer "F.Cu")
		(net "GND")
	)
	(segment
		(start 231.70388 -307.484272)
		(end 232.317798 -307.484272)
		(width 0.254)
		(layer "F.Cu")
		(net "GND")
	)
	(segment
		(start 67.66687 -151.155146)
		(end 68.65747 -151.155146)
		(width 0.3556)
		(layer "F.Cu")
		(net "GND")
	)
	(segment
		(start 322.254626 -34.990024)
		(end 320.864738 -34.990024)
		(width 0.3556)
		(layer "F.Cu")
		(net "GND")
	)
	(segment
		(start 170.999912 -284.499812)
		(end 171.474892 -284.974792)
		(width 0.249936)
		(layer "F.Cu")
		(net "GND")
	)
	(segment
		(start 194.749928 -291.149786)
		(end 195.224908 -290.674806)
		(width 0.249936)
		(layer "F.Cu")
		(net "GND")
	)
	(segment
		(start 418.044884 -143.655796)
		(end 417.745672 -143.955008)
		(width 0.3556)
		(layer "F.Cu")
		(net "GND")
	)
	(segment
		(start 65.349882 -285.449772)
		(end 65.824862 -285.924752)
		(width 0.249936)
		(layer "F.Cu")
		(net "GND")
	)
	(segment
		(start 62.974982 -287.824926)
		(end 63.449962 -288.299906)
		(width 0.249936)
		(layer "F.Cu")
		(net "GND")
	)
	(segment
		(start 303.249838 -296.8498)
		(end 303.724818 -296.37482)
		(width 0.249936)
		(layer "F.Cu")
		(net "GND")
	)
	(segment
		(start 389.899906 -291.149786)
		(end 389.424926 -290.674806)
		(width 0.249936)
		(layer "F.Cu")
		(net "GND")
	)
	(segment
		(start 283.833062 -124.154946)
		(end 282.842462 -124.154946)
		(width 0.3556)
		(layer "F.Cu")
		(net "GND")
	)
	(segment
		(start 302.774858 -286.874966)
		(end 303.249838 -287.349946)
		(width 0.249936)
		(layer "F.Cu")
		(net "GND")
	)
	(segment
		(start 400.824954 -293.52494)
		(end 401.299934 -293.99992)
		(width 0.249936)
		(layer "F.Cu")
		(net "GND")
	)
	(segment
		(start 198.075042 -303.024794)
		(end 198.550022 -303.499774)
		(width 0.249936)
		(layer "F.Cu")
		(net "GND")
	)
	(segment
		(start 156.750004 -286.399732)
		(end 156.275024 -285.924752)
		(width 0.249936)
		(layer "F.Cu")
		(net "GND")
	)
	(segment
		(start 279.593548 -108.279946)
		(end 279.1587 -107.845098)
		(width 0.3556)
		(layer "F.Cu")
		(net "GND")
	)
	(segment
		(start 170.049952 -292.099746)
		(end 170.524932 -291.624766)
		(width 0.249936)
		(layer "F.Cu")
		(net "GND")
	)
	(segment
		(start 198.388986 -407.243534)
		(end 198.51243 -407.12009)
		(width 0.4572)
		(layer "F.Cu")
		(net "GND")
	)
	(segment
		(start 162.450018 -302.549814)
		(end 161.975038 -303.024794)
		(width 0.249936)
		(layer "F.Cu")
		(net "GND")
	)
	(segment
		(start 49.1998 -306.349908)
		(end 49.67478 -305.874928)
		(width 0.249936)
		(layer "F.Cu")
		(net "GND")
	)
	(segment
		(start 39.699946 -287.349946)
		(end 39.224966 -286.874966)
		(width 0.249936)
		(layer "F.Cu")
		(net "GND")
	)
	(segment
		(start 51.632866 -107.845098)
		(end 51.63312 -107.844844)
		(width 0.4572)
		(layer "F.Cu")
		(net "GND")
	)
	(segment
		(start 169.574972 -303.974754)
		(end 169.099992 -303.499774)
		(width 0.249936)
		(layer "F.Cu")
		(net "GND")
	)
	(segment
		(start 155.800044 -278.799798)
		(end 155.325064 -278.324818)
		(width 0.249936)
		(layer "F.Cu")
		(net "GND")
	)
	(segment
		(start 260.027674 -34.732468)
		(end 259.795264 -34.732468)
		(width 0.4572)
		(layer "F.Cu")
		(net "GND")
	)
	(segment
		(start 94.894146 -117.426486)
		(end 95.529146 -117.426486)
		(width 0.4572)
		(layer "F.Cu")
		(net "GND")
	)
	(segment
		(start 195.699888 -302.549814)
		(end 196.649848 -302.549814)
		(width 0.249936)
		(layer "F.Cu")
		(net "GND")
	)
	(segment
		(start 345.36126 -259.782564)
		(end 344.74531 -259.782564)
		(width 0.381)
		(layer "F.Cu")
		(net "GND")
	)
	(segment
		(start 350.571054 -34.29762)
		(end 350.562672 -34.29762)
		(width 0.4572)
		(layer "F.Cu")
		(net "GND")
	)
	(segment
		(start 246.958612 -237.344966)
		(end 246.958612 -236.83468)
		(width 0.4572)
		(layer "F.Cu")
		(net "GND")
	)
	(segment
		(start 349.306896 -285.199836)
		(end 349.306896 -284.631384)
		(width 0.2286)
		(layer "F.Cu")
		(net "GND")
	)
	(segment
		(start 239.64265 -204.771244)
		(end 239.64265 -204.441044)
		(width 0.4572)
		(layer "F.Cu")
		(net "GND")
	)
	(segment
		(start 286.624776 -284.024832)
		(end 287.099756 -284.499812)
		(width 0.249936)
		(layer "F.Cu")
		(net "GND")
	)
	(segment
		(start 37.799772 -290.199826)
		(end 37.324792 -289.724846)
		(width 0.249936)
		(layer "F.Cu")
		(net "GND")
	)
	(segment
		(start 411.750002 -296.8498)
		(end 412.224982 -297.32478)
		(width 0.249936)
		(layer "F.Cu")
		(net "GND")
	)
	(segment
		(start 74.248264 -129.445004)
		(end 73.257664 -129.445004)
		(width 0.3556)
		(layer "F.Cu")
		(net "GND")
	)
	(segment
		(start 278.074882 -299.224954)
		(end 278.549862 -299.699934)
		(width 0.249936)
		(layer "F.Cu")
		(net "GND")
	)
	(segment
		(start 393.7 -286.399732)
		(end 393.22502 -285.924752)
		(width 0.249936)
		(layer "F.Cu")
		(net "GND")
	)
	(segment
		(start 173.850046 -299.699934)
		(end 174.325026 -300.174914)
		(width 0.249936)
		(layer "F.Cu")
		(net "GND")
	)
	(segment
		(start 128.156208 -33.19018)
		(end 126.76505 -33.19018)
		(width 0.3556)
		(layer "F.Cu")
		(net "GND")
	)
	(segment
		(start 166.249858 -291.149786)
		(end 165.774878 -290.674806)
		(width 0.249936)
		(layer "F.Cu")
		(net "GND")
	)
	(segment
		(start 406.895046 -102.798372)
		(end 406.279858 -102.798372)
		(width 0.4064)
		(layer "F.Cu")
		(net "GND")
	)
	(segment
		(start 17.599914 -266.892024)
		(end 17.592802 -266.899136)
		(width 0.254)
		(layer "F.Cu")
		(net "GND")
	)
	(segment
		(start 153.89987 -274.049744)
		(end 153.42489 -273.574764)
		(width 0.249936)
		(layer "F.Cu")
		(net "GND")
	)
	(segment
		(start 210.56219 -371.465094)
		(end 210.99653 -371.465094)
		(width 0.4572)
		(layer "F.Cu")
		(net "GND")
	)
	(segment
		(start 68.674742 -307.774848)
		(end 68.199762 -307.299868)
		(width 0.249936)
		(layer "F.Cu")
		(net "GND")
	)
	(segment
		(start 196.649848 -298.74972)
		(end 197.125082 -299.224954)
		(width 0.249936)
		(layer "F.Cu")
		(net "GND")
	)
	(segment
		(start 330.994258 -189.99454)
		(end 329.754484 -189.99454)
		(width 0.4572)
		(layer "F.Cu")
		(net "GND")
	)
	(segment
		(start 160.549844 -299.699934)
		(end 160.074864 -300.174914)
		(width 0.249936)
		(layer "F.Cu")
		(net "GND")
	)
	(segment
		(start 45.39996 -288.299906)
		(end 45.87494 -287.824926)
		(width 0.249936)
		(layer "F.Cu")
		(net "GND")
	)
	(segment
		(start 423.62501 -294.4749)
		(end 424.09999 -293.99992)
		(width 0.249936)
		(layer "F.Cu")
		(net "GND")
	)
	(segment
		(start 351.169986 -238.09833)
		(end 351.17024 -238.098584)
		(width 0.4572)
		(layer "F.Cu")
		(net "GND")
	)
	(segment
		(start 115.24234 -257.13055)
		(end 115.24234 -258.14655)
		(width 0.381)
		(layer "F.Cu")
		(net "GND")
	)
	(segment
		(start 381.58293 -306.844192)
		(end 380.938024 -306.844192)
		(width 0.4572)
		(layer "F.Cu")
		(net "GND")
	)
	(segment
		(start 131.36499 -34.990024)
		(end 129.349754 -34.990024)
		(width 0.3556)
		(layer "F.Cu")
		(net "GND")
	)
	(segment
		(start 224.324926 -189.637416)
		(end 224.46615 -189.77864)
		(width 0.3048)
		(layer "F.Cu")
		(net "GND")
	)
	(segment
		(start 294.86479 -25.990042)
		(end 293.84879 -25.990042)
		(width 0.3556)
		(layer "F.Cu")
		(net "GND")
	)
	(segment
		(start 426.94987 -302.549814)
		(end 427.42485 -302.074834)
		(width 0.249936)
		(layer "F.Cu")
		(net "GND")
	)
	(segment
		(start 408.899868 -285.449772)
		(end 408.424888 -284.974792)
		(width 0.254)
		(layer "F.Cu")
		(net "GND")
	)
	(segment
		(start 392.749786 -290.199826)
		(end 392.274806 -289.724846)
		(width 0.249936)
		(layer "F.Cu")
		(net "GND")
	)
	(segment
		(start 253.346966 -52.592224)
		(end 253.42215 -52.51704)
		(width 0.254)
		(layer "F.Cu")
		(net "GND")
	)
	(segment
		(start 288.049716 -299.699934)
		(end 287.574736 -300.174914)
		(width 0.249936)
		(layer "F.Cu")
		(net "GND")
	)
	(segment
		(start 34.502344 -252.756924)
		(end 34.502344 -253.45644)
		(width 0.4572)
		(layer "F.Cu")
		(net "GND")
	)
	(segment
		(start 56.799988 -293.99992)
		(end 56.324754 -293.52494)
		(width 0.249936)
		(layer "F.Cu")
		(net "GND")
	)
	(segment
		(start 404.624794 -306.824888)
		(end 404.149814 -307.299868)
		(width 0.249936)
		(layer "F.Cu")
		(net "GND")
	)
	(segment
		(start 295.441878 -162.781488)
		(end 295.441878 -162.08375)
		(width 0.4572)
		(layer "F.Cu")
		(net "GND")
	)
	(segment
		(start 314.649866 -299.699934)
		(end 315.124846 -299.224954)
		(width 0.249936)
		(layer "F.Cu")
		(net "GND")
	)
	(segment
		(start 374.462294 -262.912352)
		(end 373.850916 -262.912352)
		(width 0.3048)
		(layer "F.Cu")
		(net "GND")
	)
	(segment
		(start 311.324752 -294.4749)
		(end 310.849772 -293.99992)
		(width 0.249936)
		(layer "F.Cu")
		(net "GND")
	)
	(segment
		(start 156.348938 -29.589984)
		(end 157.364938 -29.589984)
		(width 0.3556)
		(layer "F.Cu")
		(net "GND")
	)
	(segment
		(start 49.67478 -302.074834)
		(end 49.1998 -301.599854)
		(width 0.249936)
		(layer "F.Cu")
		(net "GND")
	)
	(segment
		(start 295.649904 -292.099746)
		(end 295.174924 -291.624766)
		(width 0.249936)
		(layer "F.Cu")
		(net "GND")
	)
	(segment
		(start 275.699728 -286.399732)
		(end 275.224748 -286.874712)
		(width 0.249936)
		(layer "F.Cu")
		(net "GND")
	)
	(segment
		(start 413.649922 -294.94988)
		(end 414.124902 -294.4749)
		(width 0.249936)
		(layer "F.Cu")
		(net "GND")
	)
	(segment
		(start 169.099992 -288.299906)
		(end 168.625012 -287.824926)
		(width 0.249936)
		(layer "F.Cu")
		(net "GND")
	)
	(segment
		(start 236.909864 -228.137466)
		(end 237.900464 -228.137466)
		(width 0.4572)
		(layer "F.Cu")
		(net "GND")
	)
	(segment
		(start 306.448206 -142.15491)
		(end 305.457606 -142.15491)
		(width 0.3556)
		(layer "F.Cu")
		(net "GND")
	)
	(segment
		(start 303.249838 -298.74972)
		(end 302.774858 -299.224954)
		(width 0.249936)
		(layer "F.Cu")
		(net "GND")
	)
	(segment
		(start 394.787628 -25.742392)
		(end 394.787628 -26.360882)
		(width 0.4572)
		(layer "F.Cu")
		(net "GND")
	)
	(segment
		(start 417.924996 -298.27474)
		(end 418.399976 -298.74972)
		(width 0.249936)
		(layer "F.Cu")
		(net "GND")
	)
	(segment
		(start 191.425068 -302.074834)
		(end 191.900048 -301.599854)
		(width 0.249936)
		(layer "F.Cu")
		(net "GND")
	)
	(segment
		(start 408.899868 -295.89984)
		(end 409.374848 -296.37482)
		(width 0.249936)
		(layer "F.Cu")
		(net "GND")
	)
	(segment
		(start 400.349974 -305.399948)
		(end 400.824954 -305.874928)
		(width 0.249936)
		(layer "F.Cu")
		(net "GND")
	)
	(segment
		(start 51.63312 -109.644942)
		(end 50.64252 -109.644942)
		(width 0.3556)
		(layer "F.Cu")
		(net "GND")
	)
	(segment
		(start 410.324808 -305.874928)
		(end 409.849828 -306.349908)
		(width 0.249936)
		(layer "F.Cu")
		(net "GND")
	)
	(segment
		(start 451.362318 -23.355554)
		(end 452.01205 -23.355554)
		(width 0.4572)
		(layer "F.Cu")
		(net "GND")
	)
	(segment
		(start 56.324754 -305.874928)
		(end 55.849774 -305.399948)
		(width 0.249936)
		(layer "F.Cu")
		(net "GND")
	)
	(segment
		(start 392.274806 -297.32478)
		(end 392.749786 -296.8498)
		(width 0.249936)
		(layer "F.Cu")
		(net "GND")
	)
	(segment
		(start 61.173868 -388.787132)
		(end 60.9346 -389.0264)
		(width 0.4572)
		(layer "F.Cu")
		(net "GND")
	)
	(segment
		(start 240.081562 -215.6968)
		(end 240.4618 -215.6968)
		(width 0.4572)
		(layer "F.Cu")
		(net "GND")
	)
	(segment
		(start 299.449744 -285.449772)
		(end 299.924724 -284.974792)
		(width 0.249936)
		(layer "F.Cu")
		(net "GND")
	)
	(segment
		(start 225.375724 -280.10104)
		(end 224.766124 -280.10104)
		(width 0.4572)
		(layer "F.Cu")
		(net "GND")
	)
	(segment
		(start 38.274752 -298.27474)
		(end 38.749986 -298.74972)
		(width 0.249936)
		(layer "F.Cu")
		(net "GND")
	)
	(segment
		(start 300.399704 -285.449772)
		(end 300.874684 -284.974792)
		(width 0.249936)
		(layer "F.Cu")
		(net "GND")
	)
	(segment
		(start 158.174944 -297.32478)
		(end 157.699964 -296.8498)
		(width 0.249936)
		(layer "F.Cu")
		(net "GND")
	)
	(segment
		(start 294.69969 -295.89984)
		(end 295.174924 -296.37482)
		(width 0.249936)
		(layer "F.Cu")
		(net "GND")
	)
	(segment
		(start 278.549862 -283.549852)
		(end 278.074882 -283.074872)
		(width 0.249936)
		(layer "F.Cu")
		(net "GND")
	)
	(segment
		(start 419.349936 -298.74972)
		(end 419.824916 -299.224954)
		(width 0.249936)
		(layer "F.Cu")
		(net "GND")
	)
	(segment
		(start 260.022086 -306.802028)
		(end 259.437124 -306.217066)
		(width 0.4572)
		(layer "F.Cu")
		(net "GND")
	)
	(segment
		(start 399.400014 -306.349908)
		(end 399.874994 -305.874928)
		(width 0.249936)
		(layer "F.Cu")
		(net "GND")
	)
	(segment
		(start 165.774878 -302.074834)
		(end 165.299898 -301.599854)
		(width 0.249936)
		(layer "F.Cu")
		(net "GND")
	)
	(segment
		(start 188.328808 -147.314412)
		(end 188.569346 -147.55495)
		(width 0.3556)
		(layer "F.Cu")
		(net "GND")
	)
	(segment
		(start 163.874958 -305.874928)
		(end 164.349938 -305.399948)
		(width 0.249936)
		(layer "F.Cu")
		(net "GND")
	)
	(segment
		(start 277.251668 -109.644942)
		(end 278.242268 -109.644942)
		(width 0.3556)
		(layer "F.Cu")
		(net "GND")
	)
	(segment
		(start 44.449746 -300.649894)
		(end 43.974766 -300.174914)
		(width 0.254)
		(layer "F.Cu")
		(net "GND")
	)
	(segment
		(start 188.574934 -300.174914)
		(end 188.099954 -299.699934)
		(width 0.249936)
		(layer "F.Cu")
		(net "GND")
	)
	(segment
		(start 267.848842 -31.390082)
		(end 268.864842 -31.390082)
		(width 0.3556)
		(layer "F.Cu")
		(net "GND")
	)
	(segment
		(start 424.57497 -292.574726)
		(end 425.04995 -293.04996)
		(width 0.249936)
		(layer "F.Cu")
		(net "GND")
	)
	(segment
		(start 185.250074 -306.349908)
		(end 184.77484 -305.874928)
		(width 0.249936)
		(layer "F.Cu")
		(net "GND")
	)
	(segment
		(start 169.099992 -301.599854)
		(end 169.574972 -302.074834)
		(width 0.249936)
		(layer "F.Cu")
		(net "GND")
	)
	(segment
		(start 179.07508 -305.874928)
		(end 178.599846 -305.399948)
		(width 0.249936)
		(layer "F.Cu")
		(net "GND")
	)
	(segment
		(start 173.375066 -284.024832)
		(end 172.900086 -284.499812)
		(width 0.249936)
		(layer "F.Cu")
		(net "GND")
	)
	(segment
		(start 343.69375 -219.187014)
		(end 344.093546 -218.787218)
		(width 0.381)
		(layer "F.Cu")
		(net "GND")
	)
	(segment
		(start 62.215268 -393.56284)
		(end 60.437268 -393.56284)
		(width 0.4572)
		(layer "F.Cu")
		(net "GND")
	)
	(segment
		(start 281.646884 -109.177328)
		(end 282.114498 -109.644942)
		(width 0.3556)
		(layer "F.Cu")
		(net "GND")
	)
	(segment
		(start 320.864738 -31.390082)
		(end 321.736212 -31.390082)
		(width 0.3556)
		(layer "F.Cu")
		(net "GND")
	)
	(segment
		(start 386.099812 -288.299906)
		(end 385.624832 -287.824926)
		(width 0.249936)
		(layer "F.Cu")
		(net "GND")
	)
	(segment
		(start 406.049988 -288.19983)
		(end 406.54986 -287.699958)
		(width 0.249936)
		(layer "F.Cu")
		(net "GND")
	)
	(segment
		(start 215.246966 -53.144166)
		(end 215.246966 -52.592224)
		(width 0.254)
		(layer "F.Cu")
		(net "GND")
	)
	(segment
		(start 248.494804 -274.487386)
		(end 249.104404 -274.487386)
		(width 0.4572)
		(layer "F.Cu")
		(net "GND")
	)
	(segment
		(start 157.699964 -287.349946)
		(end 157.224984 -286.874966)
		(width 0.249936)
		(layer "F.Cu")
		(net "GND")
	)
	(segment
		(start 303.249838 -296.8498)
		(end 303.724818 -297.32478)
		(width 0.249936)
		(layer "F.Cu")
		(net "GND")
	)
	(segment
		(start 390.58088 -27.79014)
		(end 389.56488 -27.79014)
		(width 0.3556)
		(layer "F.Cu")
		(net "GND")
	)
	(segment
		(start 192.850008 -300.649894)
		(end 193.324988 -301.124874)
		(width 0.249936)
		(layer "F.Cu")
		(net "GND")
	)
	(segment
		(start 65.824862 -289.724846)
		(end 66.299842 -290.199826)
		(width 0.249936)
		(layer "F.Cu")
		(net "GND")
	)
	(segment
		(start 233.547666 -69.74332)
		(end 233.611166 -69.74332)
		(width 0.3556)
		(layer "F.Cu")
		(net "GND")
	)
	(segment
		(start 43.024806 -284.974792)
		(end 43.499786 -284.499812)
		(width 0.3048)
		(layer "F.Cu")
		(net "GND")
	)
	(segment
		(start 411.750002 -305.399948)
		(end 411.275022 -305.874928)
		(width 0.249936)
		(layer "F.Cu")
		(net "GND")
	)
	(segment
		(start 386.50799 -155.3464)
		(end 386.50799 -156.3624)
		(width 0.4064)
		(layer "F.Cu")
		(net "GND")
	)
	(segment
		(start 66.774822 -285.924752)
		(end 66.299842 -286.399732)
		(width 0.249936)
		(layer "F.Cu")
		(net "GND")
	)
	(segment
		(start 301.824898 -306.824888)
		(end 301.349918 -306.349908)
		(width 0.249936)
		(layer "F.Cu")
		(net "GND")
	)
	(segment
		(start 13.494766 -158.705042)
		(end 13.494766 -159.498792)
		(width 0.254)
		(layer "F.Cu")
		(net "GND")
	)
	(segment
		(start 402.249894 -301.599854)
		(end 401.774914 -302.074834)
		(width 0.249936)
		(layer "F.Cu")
		(net "GND")
	)
	(segment
		(start 173.794166 -35.264852)
		(end 173.794166 -35.499548)
		(width 0.4572)
		(layer "F.Cu")
		(net "GND")
	)
	(segment
		(start 81.974944 -293.52494)
		(end 81.499964 -293.99992)
		(width 0.249936)
		(layer "F.Cu")
		(net "GND")
	)
	(segment
		(start 412.699962 -301.599854)
		(end 413.174942 -302.074834)
		(width 0.249936)
		(layer "F.Cu")
		(net "GND")
	)
	(segment
		(start 156.750004 -281.649932)
		(end 156.275024 -281.174952)
		(width 0.249936)
		(layer "F.Cu")
		(net "GND")
	)
	(segment
		(start 241.444018 -236.281976)
		(end 241.444018 -235.624116)
		(width 0.4572)
		(layer "F.Cu")
		(net "GND")
	)
	(segment
		(start 352.17227 -33.248092)
		(end 352.17227 -33.857692)
		(width 0.4572)
		(layer "F.Cu")
		(net "GND")
	)
	(segment
		(start 74.84999 -297.79976)
		(end 75.32497 -298.27474)
		(width 0.249936)
		(layer "F.Cu")
		(net "GND")
	)
	(segment
		(start 161.15157 -100.64496)
		(end 162.14217 -100.64496)
		(width 0.3556)
		(layer "F.Cu")
		(net "GND")
	)
	(segment
		(start 173.375066 -289.724846)
		(end 172.900086 -290.199826)
		(width 0.249936)
		(layer "F.Cu")
		(net "GND")
	)
	(segment
		(start 48.957992 -131.76504)
		(end 50.64252 -131.76504)
		(width 0.3556)
		(layer "F.Cu")
		(net "GND")
	)
	(segment
		(start 109.484414 -282.021534)
		(end 109.099604 -282.406344)
		(width 0.254)
		(layer "F.Cu")
		(net "GND")
	)
	(segment
		(start 165.774878 -305.874928)
		(end 166.249858 -305.399948)
		(width 0.249936)
		(layer "F.Cu")
		(net "GND")
	)
	(segment
		(start 413.174942 -293.52494)
		(end 412.699962 -293.99992)
		(width 0.249936)
		(layer "F.Cu")
		(net "GND")
	)
	(segment
		(start 5.472176 -375.259346)
		(end 5.472176 -375.834148)
		(width 0.381)
		(layer "F.Cu")
		(net "GND")
	)
	(segment
		(start 422.199816 -305.399948)
		(end 422.199816 -305.399694)
		(width 0.249936)
		(layer "F.Cu")
		(net "GND")
	)
	(segment
		(start 164.349938 -290.199826)
		(end 163.874958 -289.724846)
		(width 0.249936)
		(layer "F.Cu")
		(net "GND")
	)
	(segment
		(start 246.194834 -158.705042)
		(end 246.194834 -159.336232)
		(width 0.254)
		(layer "F.Cu")
		(net "GND")
	)
	(segment
		(start 334.899 -245.12905)
		(end 335.388458 -245.12905)
		(width 0.4572)
		(layer "F.Cu")
		(net "GND")
	)
	(segment
		(start 3.65125 -393.864592)
		(end 3.65125 -394.492734)
		(width 0.4572)
		(layer "F.Cu")
		(net "GND")
	)
	(segment
		(start 378.079 -203.60005)
		(end 378.82195 -203.60005)
		(width 0.4572)
		(layer "F.Cu")
		(net "GND")
	)
	(segment
		(start 294.22471 -303.974754)
		(end 294.69969 -303.499774)
		(width 0.249936)
		(layer "F.Cu")
		(net "GND")
	)
	(segment
		(start 182.39994 -306.349908)
		(end 181.92496 -305.874928)
		(width 0.249936)
		(layer "F.Cu")
		(net "GND")
	)
	(segment
		(start 198.388986 -407.85796)
		(end 198.388986 -407.243534)
		(width 0.4572)
		(layer "F.Cu")
		(net "GND")
	)
	(segment
		(start 280.449782 -300.649894)
		(end 279.974802 -301.124874)
		(width 0.249936)
		(layer "F.Cu")
		(net "GND")
	)
	(segment
		(start 380.85395 -206.502)
		(end 380.19863 -206.502)
		(width 0.4572)
		(layer "F.Cu")
		(net "GND")
	)
	(segment
		(start 310.849772 -298.74972)
		(end 310.374792 -299.224954)
		(width 0.249936)
		(layer "F.Cu")
		(net "GND")
	)
	(segment
		(start 412.356046 -33.19018)
		(end 410.964888 -33.19018)
		(width 0.3556)
		(layer "F.Cu")
		(net "GND")
	)
	(segment
		(start 441.564776 -29.589984)
		(end 442.580776 -29.589984)
		(width 0.3556)
		(layer "F.Cu")
		(net "GND")
	)
	(segment
		(start 298.024804 -294.4749)
		(end 298.499784 -293.99992)
		(width 0.249936)
		(layer "F.Cu")
		(net "GND")
	)
	(segment
		(start 67.724782 -300.174914)
		(end 67.249802 -299.699934)
		(width 0.249936)
		(layer "F.Cu")
		(net "GND")
	)
	(segment
		(start 182.87492 -291.624766)
		(end 183.3499 -292.099746)
		(width 0.249936)
		(layer "F.Cu")
		(net "GND")
	)
	(segment
		(start 235.387134 -116.936266)
		(end 236.827822 -118.376954)
		(width 0.254)
		(layer "F.Cu")
		(net "GND")
	)
	(segment
		(start 209.364834 -31.390082)
		(end 210.380834 -31.390082)
		(width 0.3556)
		(layer "F.Cu")
		(net "GND")
	)
	(segment
		(start 173.850046 -288.19983)
		(end 174.349918 -287.699958)
		(width 0.249936)
		(layer "F.Cu")
		(net "GND")
	)
	(segment
		(start 329.457812 -73.166732)
		(end 329.457812 -73.85177)
		(width 0.4572)
		(layer "F.Cu")
		(net "GND")
	)
	(segment
		(start 324.824598 -115.335304)
		(end 325.221854 -115.335304)
		(width 0.254)
		(layer "F.Cu")
		(net "GND")
	)
	(segment
		(start 300.874684 -303.024794)
		(end 300.399704 -302.549814)
		(width 0.249936)
		(layer "F.Cu")
		(net "GND")
	)
	(segment
		(start 76.157582 -81.749646)
		(end 76.371704 -81.749646)
		(width 0.4064)
		(layer "F.Cu")
		(net "GND")
	)
	(segment
		(start 261.55777 -26.606246)
		(end 261.55777 -25.971246)
		(width 0.4572)
		(layer "F.Cu")
		(net "GND")
	)
	(segment
		(start 161.500058 -285.449772)
		(end 161.025078 -284.974792)
		(width 0.249936)
		(layer "F.Cu")
		(net "GND")
	)
	(segment
		(start 178.764946 -31.390082)
		(end 179.63642 -31.390082)
		(width 0.3556)
		(layer "F.Cu")
		(net "GND")
	)
	(segment
		(start 301.824898 -297.32478)
		(end 301.349918 -297.79976)
		(width 0.249936)
		(layer "F.Cu")
		(net "GND")
	)
	(segment
		(start 254.521208 -355.006148)
		(end 255.577594 -355.006148)
		(width 0.4572)
		(layer "F.Cu")
		(net "GND")
	)
	(segment
		(start 420.299896 -301.599854)
		(end 420.774876 -301.124874)
		(width 0.249936)
		(layer "F.Cu")
		(net "GND")
	)
	(segment
		(start 48.24984 -305.399948)
		(end 47.77486 -304.924714)
		(width 0.249936)
		(layer "F.Cu")
		(net "GND")
	)
	(segment
		(start 286.624776 -283.074872)
		(end 287.099756 -283.549852)
		(width 0.249936)
		(layer "F.Cu")
		(net "GND")
	)
	(segment
		(start 132.459476 -146.242278)
		(end 132.459476 -145.53565)
		(width 0.4064)
		(layer "F.Cu")
		(net "GND")
	)
	(segment
		(start 395.12494 -306.824888)
		(end 394.64996 -307.299868)
		(width 0.249936)
		(layer "F.Cu")
		(net "GND")
	)
	(segment
		(start 170.999912 -297.79976)
		(end 170.524932 -298.27474)
		(width 0.249936)
		(layer "F.Cu")
		(net "GND")
	)
	(segment
		(start 164.824918 -304.924714)
		(end 164.349938 -304.449734)
		(width 0.249936)
		(layer "F.Cu")
		(net "GND")
	)
	(segment
		(start 11.26871 -275.946616)
		(end 11.731244 -275.7551)
		(width 0.254)
		(layer "F.Cu")
		(net "GND")
	)
	(segment
		(start 216.229438 -209.22488)
		(end 216.352628 -209.22488)
		(width 0.254)
		(layer "F.Cu")
		(net "GND")
	)
	(segment
		(start 415.96691 -143.955008)
		(end 416.95751 -143.955008)
		(width 0.3556)
		(layer "F.Cu")
		(net "GND")
	)
	(segment
		(start 54.424834 -296.37482)
		(end 53.949854 -296.8498)
		(width 0.249936)
		(layer "F.Cu")
		(net "GND")
	)
	(segment
		(start 194.749928 -302.549814)
		(end 195.699888 -302.549814)
		(width 0.249936)
		(layer "F.Cu")
		(net "GND")
	)
	(segment
		(start 162.374072 -73.166732)
		(end 162.374072 -73.85177)
		(width 0.4572)
		(layer "F.Cu")
		(net "GND")
	)
	(segment
		(start 310.849772 -303.499774)
		(end 310.374792 -303.024794)
		(width 0.249936)
		(layer "F.Cu")
		(net "GND")
	)
	(segment
		(start 81.024984 -288.774886)
		(end 80.54975 -289.249866)
		(width 0.249936)
		(layer "F.Cu")
		(net "GND")
	)
	(segment
		(start 299.449744 -307.299868)
		(end 298.974764 -306.824888)
		(width 0.249936)
		(layer "F.Cu")
		(net "GND")
	)
	(segment
		(start 67.724782 -285.924752)
		(end 67.249802 -286.399732)
		(width 0.249936)
		(layer "F.Cu")
		(net "GND")
	)
	(segment
		(start 412.224982 -294.4749)
		(end 411.750002 -294.94988)
		(width 0.249936)
		(layer "F.Cu")
		(net "GND")
	)
	(segment
		(start 306.448206 -154.755088)
		(end 305.457606 -154.755088)
		(width 0.3556)
		(layer "F.Cu")
		(net "GND")
	)
	(segment
		(start 169.574972 -300.174914)
		(end 170.049952 -299.699934)
		(width 0.249936)
		(layer "F.Cu")
		(net "GND")
	)
	(segment
		(start 62.974982 -300.174914)
		(end 63.449962 -299.699934)
		(width 0.249936)
		(layer "F.Cu")
		(net "GND")
	)
	(segment
		(start 151.805894 -114.4905)
		(end 150.79726 -114.4905)
		(width 0.4572)
		(layer "F.Cu")
		(net "GND")
	)
	(segment
		(start 210.03895 -208.407)
		(end 210.03895 -209.042)
		(width 0.4572)
		(layer "F.Cu")
		(net "GND")
	)
	(segment
		(start 422.199816 -293.04996)
		(end 421.724836 -293.52494)
		(width 0.249936)
		(layer "F.Cu")
		(net "GND")
	)
	(segment
		(start 225.91903 -307.368702)
		(end 226.351084 -307.368702)
		(width 0.1778)
		(layer "F.Cu")
		(net "GND")
	)
	(segment
		(start 58.489342 -62.812168)
		(end 59.299856 -62.812168)
		(width 0.4572)
		(layer "F.Cu")
		(net "GND")
	)
	(segment
		(start 68.674742 -284.024832)
		(end 68.199762 -284.499812)
		(width 0.249936)
		(layer "F.Cu")
		(net "GND")
	)
	(segment
		(start 416.024822 -307.774848)
		(end 416.499802 -307.299868)
		(width 0.249936)
		(layer "F.Cu")
		(net "GND")
	)
	(segment
		(start 415.96691 -118.234968)
		(end 416.95751 -118.234968)
		(width 0.3556)
		(layer "F.Cu")
		(net "GND")
	)
	(segment
		(start 232.517442 -65.39992)
		(end 231.388158 -65.39992)
		(width 0.3556)
		(layer "F.Cu")
		(net "GND")
	)
	(segment
		(start 77.06233 -23.355554)
		(end 77.712062 -23.355554)
		(width 0.4572)
		(layer "F.Cu")
		(net "GND")
	)
	(segment
		(start 233.535728 -60.177934)
		(end 233.599228 -60.177934)
		(width 0.3556)
		(layer "F.Cu")
		(net "GND")
	)
	(segment
		(start 103.824532 -120.526302)
		(end 104.585516 -120.526302)
		(width 0.4572)
		(layer "F.Cu")
		(net "GND")
	)
	(segment
		(start 399.93316 -122.355102)
		(end 398.94256 -122.355102)
		(width 0.3556)
		(layer "F.Cu")
		(net "GND")
	)
	(segment
		(start 155.483052 -34.990024)
		(end 157.364938 -34.990024)
		(width 0.3556)
		(layer "F.Cu")
		(net "GND")
	)
	(segment
		(start 340.88705 -283.07411)
		(end 340.571836 -283.07411)
		(width 0.2286)
		(layer "F.Cu")
		(net "GND")
	)
	(segment
		(start 50.624994 -305.874928)
		(end 50.14976 -306.349908)
		(width 0.249936)
		(layer "F.Cu")
		(net "GND")
	)
	(segment
		(start 327.094088 -115.394486)
		(end 327.729088 -115.394486)
		(width 0.4572)
		(layer "F.Cu")
		(net "GND")
	)
	(segment
		(start 281.399742 -306.349908)
		(end 280.924762 -306.824888)
		(width 0.249936)
		(layer "F.Cu")
		(net "GND")
	)
	(segment
		(start 389.899906 -293.99992)
		(end 389.424926 -293.52494)
		(width 0.249936)
		(layer "F.Cu")
		(net "GND")
	)
	(segment
		(start 52.524914 -289.724846)
		(end 52.049934 -290.199826)
		(width 0.249936)
		(layer "F.Cu")
		(net "GND")
	)
	(segment
		(start 302.774858 -300.174914)
		(end 302.299878 -300.649894)
		(width 0.249936)
		(layer "F.Cu")
		(net "GND")
	)
	(segment
		(start 9.1059 -394.53947)
		(end 9.1059 -395.248384)
		(width 0.4572)
		(layer "F.Cu")
		(net "GND")
	)
	(segment
		(start 279.499822 -287.349946)
		(end 279.024842 -286.874966)
		(width 0.249936)
		(layer "F.Cu")
		(net "GND")
	)
	(segment
		(start 304.467006 -142.15491)
		(end 305.457606 -142.15491)
		(width 0.3556)
		(layer "F.Cu")
		(net "GND")
	)
	(segment
		(start 152.94991 -293.04996)
		(end 152.47493 -292.57498)
		(width 0.249936)
		(layer "F.Cu")
		(net "GND")
	)
	(segment
		(start 435.494938 -59.978036)
		(end 435.494938 -60.633356)
		(width 0.4572)
		(layer "F.Cu")
		(net "GND")
	)
	(segment
		(start 171.474892 -285.924752)
		(end 171.949872 -286.399732)
		(width 0.249936)
		(layer "F.Cu")
		(net "GND")
	)
	(segment
		(start 168.625012 -284.024832)
		(end 169.099992 -284.499812)
		(width 0.249936)
		(layer "F.Cu")
		(net "GND")
	)
	(segment
		(start 303.724818 -294.4749)
		(end 303.249838 -294.94988)
		(width 0.249936)
		(layer "F.Cu")
		(net "GND")
	)
	(segment
		(start 143.836898 -16.363188)
		(end 143.836898 -15.474188)
		(width 0.4572)
		(layer "F.Cu")
		(net "GND")
	)
	(segment
		(start 420.752778 -134.845044)
		(end 421.557704 -134.845044)
		(width 0.3556)
		(layer "F.Cu")
		(net "GND")
	)
	(segment
		(start 416.974782 -298.27474)
		(end 416.499802 -297.79976)
		(width 0.249936)
		(layer "F.Cu")
		(net "GND")
	)
	(segment
		(start 430.274984 -293.52494)
		(end 430.749964 -293.99992)
		(width 0.249936)
		(layer "F.Cu")
		(net "GND")
	)
	(segment
		(start 403.199854 -295.89984)
		(end 402.724874 -296.37482)
		(width 0.249936)
		(layer "F.Cu")
		(net "GND")
	)
	(segment
		(start 318.892682 -54.163722)
		(end 318.967866 -54.238906)
		(width 0.254)
		(layer "F.Cu")
		(net "GND")
	)
	(segment
		(start 69.624956 -292.574726)
		(end 69.149976 -293.04996)
		(width 0.249936)
		(layer "F.Cu")
		(net "GND")
	)
	(segment
		(start 298.024804 -285.924752)
		(end 298.499784 -285.449772)
		(width 0.249936)
		(layer "F.Cu")
		(net "GND")
	)
	(segment
		(start 181.92496 -306.824888)
		(end 181.44998 -307.299868)
		(width 0.249936)
		(layer "F.Cu")
		(net "GND")
	)
	(segment
		(start 48.24984 -296.8498)
		(end 48.72482 -296.37482)
		(width 0.249936)
		(layer "F.Cu")
		(net "GND")
	)
	(segment
		(start 409.374848 -284.974792)
		(end 408.899868 -285.449772)
		(width 0.249936)
		(layer "F.Cu")
		(net "GND")
	)
	(segment
		(start 52.049934 -296.8498)
		(end 51.574954 -297.32478)
		(width 0.249936)
		(layer "F.Cu")
		(net "GND")
	)
	(segment
		(start 221.415102 -43.85691)
		(end 220.74378 -43.85691)
		(width 0.254)
		(layer "F.Cu")
		(net "GND")
	)
	(segment
		(start 56.799988 -307.299868)
		(end 56.324754 -306.824888)
		(width 0.249936)
		(layer "F.Cu")
		(net "GND")
	)
	(segment
		(start 29.260292 -311.442608)
		(end 28.64993 -310.832246)
		(width 0.4572)
		(layer "F.Cu")
		(net "GND")
	)
	(segment
		(start 77.22489 -301.124874)
		(end 76.74991 -300.649894)
		(width 0.249936)
		(layer "F.Cu")
		(net "GND")
	)
	(segment
		(start 302.774858 -307.774848)
		(end 302.299878 -307.299868)
		(width 0.249936)
		(layer "F.Cu")
		(net "GND")
	)
	(segment
		(start 3.797554 -39.268146)
		(end 3.45821 -38.928802)
		(width 0.254)
		(layer "F.Cu")
		(net "GND")
	)
	(segment
		(start 293.27475 -291.624766)
		(end 293.74973 -292.099746)
		(width 0.249936)
		(layer "F.Cu")
		(net "GND")
	)
	(segment
		(start 421.724836 -308.724808)
		(end 422.199816 -309.199788)
		(width 0.249936)
		(layer "F.Cu")
		(net "GND")
	)
	(segment
		(start 70.099936 -284.499812)
		(end 69.624956 -284.024832)
		(width 0.249936)
		(layer "F.Cu")
		(net "GND")
	)
	(segment
		(start 398.103344 -120.555004)
		(end 398.94256 -120.555004)
		(width 0.3556)
		(layer "F.Cu")
		(net "GND")
	)
	(segment
		(start 164.349938 -291.149786)
		(end 163.874958 -290.674806)
		(width 0.249936)
		(layer "F.Cu")
		(net "GND")
	)
	(segment
		(start 417.924996 -285.924752)
		(end 417.450016 -285.449772)
		(width 0.249936)
		(layer "F.Cu")
		(net "GND")
	)
	(segment
		(start 170.049952 -290.199826)
		(end 170.524932 -289.724846)
		(width 0.249936)
		(layer "F.Cu")
		(net "GND")
	)
	(segment
		(start 164.824918 -305.874928)
		(end 165.299898 -305.399948)
		(width 0.249936)
		(layer "F.Cu")
		(net "GND")
	)
	(segment
		(start 314.3504 -81.698846)
		(end 314.02655 -82.022696)
		(width 0.4064)
		(layer "F.Cu")
		(net "GND")
	)
	(segment
		(start 411.750002 -307.299868)
		(end 411.275022 -306.824888)
		(width 0.249936)
		(layer "F.Cu")
		(net "GND")
	)
	(segment
		(start 228.241098 -305.986942)
		(end 227.946458 -306.281582)
		(width 0.4572)
		(layer "F.Cu")
		(net "GND")
	)
	(segment
		(start 408.899868 -299.699934)
		(end 408.424888 -300.174914)
		(width 0.249936)
		(layer "F.Cu")
		(net "GND")
	)
	(segment
		(start 61.074808 -300.174914)
		(end 60.599828 -299.699934)
		(width 0.249936)
		(layer "F.Cu")
		(net "GND")
	)
	(segment
		(start 270.949928 -299.699934)
		(end 270.474694 -300.174914)
		(width 0.249936)
		(layer "F.Cu")
		(net "GND")
	)
	(segment
		(start 187.149994 -306.349908)
		(end 187.624974 -305.874928)
		(width 0.249936)
		(layer "F.Cu")
		(net "GND")
	)
	(segment
		(start 406.999948 -283.549852)
		(end 406.524968 -284.024832)
		(width 0.249936)
		(layer "F.Cu")
		(net "GND")
	)
	(segment
		(start 185.443368 -136.645142)
		(end 184.757314 -136.645142)
		(width 0.3556)
		(layer "F.Cu")
		(net "GND")
	)
	(segment
		(start 280.449782 -306.349908)
		(end 279.974802 -306.824888)
		(width 0.249936)
		(layer "F.Cu")
		(net "GND")
	)
	(segment
		(start 204.764894 -29.589984)
		(end 203.748894 -29.589984)
		(width 0.3556)
		(layer "F.Cu")
		(net "GND")
	)
	(segment
		(start 65.824862 -285.924752)
		(end 65.349882 -286.399732)
		(width 0.249936)
		(layer "F.Cu")
		(net "GND")
	)
	(segment
		(start 399.400014 -284.499812)
		(end 398.925034 -284.024832)
		(width 0.249936)
		(layer "F.Cu")
		(net "GND")
	)
	(segment
		(start 45.87494 -297.32478)
		(end 46.34992 -297.79976)
		(width 0.249936)
		(layer "F.Cu")
		(net "GND")
	)
	(segment
		(start 161.975038 -301.124874)
		(end 161.500058 -300.649894)
		(width 0.249936)
		(layer "F.Cu")
		(net "GND")
	)
	(segment
		(start 397.97482 -307.774848)
		(end 397.49984 -308.249828)
		(width 0.249936)
		(layer "F.Cu")
		(net "GND")
	)
	(segment
		(start 150.792942 -54.163722)
		(end 150.868126 -54.238906)
		(width 0.254)
		(layer "F.Cu")
		(net "GND")
	)
	(segment
		(start 192.850008 -302.549814)
		(end 193.799968 -302.549814)
		(width 0.249936)
		(layer "F.Cu")
		(net "GND")
	)
	(segment
		(start 229.09911 -79.405734)
		(end 229.069392 -79.435452)
		(width 0.2032)
		(layer "F.Cu")
		(net "GND")
	)
	(segment
		(start 278.549862 -307.299868)
		(end 279.024842 -307.774848)
		(width 0.249936)
		(layer "F.Cu")
		(net "GND")
	)
	(segment
		(start 390.58088 -25.990042)
		(end 389.56488 -25.990042)
		(width 0.3556)
		(layer "F.Cu")
		(net "GND")
	)
	(segment
		(start 183.412638 -104.240076)
		(end 184.757314 -104.240076)
		(width 0.3556)
		(layer "F.Cu")
		(net "GND")
	)
	(segment
		(start 81.499964 -295.89984)
		(end 81.974944 -296.37482)
		(width 0.249936)
		(layer "F.Cu")
		(net "GND")
	)
	(segment
		(start 396.0749 -303.024794)
		(end 396.54988 -302.549814)
		(width 0.249936)
		(layer "F.Cu")
		(net "GND")
	)
	(segment
		(start 307.524912 -292.574726)
		(end 307.999892 -292.099746)
		(width 0.249936)
		(layer "F.Cu")
		(net "GND")
	)
	(segment
		(start 237.819438 -224.483168)
		(end 237.81893 -224.48266)
		(width 0.4572)
		(layer "F.Cu")
		(net "GND")
	)
	(segment
		(start 289.47491 -284.024832)
		(end 288.99993 -284.499812)
		(width 0.249936)
		(layer "F.Cu")
		(net "GND")
	)
	(segment
		(start 183.82488 -284.974792)
		(end 183.3499 -284.499812)
		(width 0.249936)
		(layer "F.Cu")
		(net "GND")
	)
	(segment
		(start 400.824954 -298.27474)
		(end 401.299934 -297.79976)
		(width 0.249936)
		(layer "F.Cu")
		(net "GND")
	)
	(segment
		(start 395.12494 -303.974754)
		(end 394.64996 -303.499774)
		(width 0.249936)
		(layer "F.Cu")
		(net "GND")
	)
	(segment
		(start 306.494942 -104.240076)
		(end 305.457606 -104.240076)
		(width 0.3556)
		(layer "F.Cu")
		(net "GND")
	)
	(segment
		(start 380.097792 -38.937184)
		(end 380.834646 -38.937184)
		(width 0.4572)
		(layer "F.Cu")
		(net "GND")
	)
	(segment
		(start 337.582256 -94.221554)
		(end 337.582256 -93.554296)
		(width 0.4572)
		(layer "F.Cu")
		(net "GND")
	)
	(segment
		(start 174.325026 -296.37482)
		(end 174.800006 -295.89984)
		(width 0.249936)
		(layer "F.Cu")
		(net "GND")
	)
	(segment
		(start 428.84979 -296.8498)
		(end 428.37481 -296.37482)
		(width 0.249936)
		(layer "F.Cu")
		(net "GND")
	)
	(segment
		(start 214.956136 -181.213506)
		(end 214.829136 -181.340506)
		(width 0.4572)
		(layer "F.Cu")
		(net "GND")
	)
	(segment
		(start 63.002668 -388.73684)
		(end 63.002668 -389.3566)
		(width 0.4572)
		(layer "F.Cu")
		(net "GND")
	)
	(segment
		(start 278.549862 -302.549814)
		(end 279.024842 -302.074834)
		(width 0.249936)
		(layer "F.Cu")
		(net "GND")
	)
	(segment
		(start 64.399922 -297.79976)
		(end 63.924942 -297.32478)
		(width 0.249936)
		(layer "F.Cu")
		(net "GND")
	)
	(segment
		(start 427.960536 -16.439388)
		(end 428.036736 -16.363188)
		(width 0.4572)
		(layer "F.Cu")
		(net "GND")
	)
	(segment
		(start 169.099992 -295.89984)
		(end 168.625012 -296.37482)
		(width 0.249936)
		(layer "F.Cu")
		(net "GND")
	)
	(segment
		(start 185.725054 -306.824888)
		(end 186.200034 -307.299868)
		(width 0.249936)
		(layer "F.Cu")
		(net "GND")
	)
	(segment
		(start 275.224748 -277.374858)
		(end 275.699728 -276.899878)
		(width 0.249936)
		(layer "F.Cu")
		(net "GND")
	)
	(segment
		(start 320.181732 -291.258244)
		(end 320.337942 -291.102034)
		(width 0.4572)
		(layer "F.Cu")
		(net "GND")
	)
	(segment
		(start 231.66959 -82.118708)
		(end 230.991918 -82.118708)
		(width 0.4572)
		(layer "F.Cu")
		(net "GND")
	)
	(segment
		(start 111.274098 -159.572198)
		(end 111.706152 -159.572198)
		(width 0.1778)
		(layer "F.Cu")
		(net "GND")
	)
	(segment
		(start 325.464678 -27.79014)
		(end 326.480678 -27.79014)
		(width 0.3556)
		(layer "F.Cu")
		(net "GND")
	)
	(segment
		(start 163.13277 -129.964942)
		(end 162.14217 -129.964942)
		(width 0.3556)
		(layer "F.Cu")
		(net "GND")
	)
	(segment
		(start 221.760542 -16.439388)
		(end 221.836742 -16.363188)
		(width 0.4572)
		(layer "F.Cu")
		(net "GND")
	)
	(segment
		(start 184.380886 -29.589984)
		(end 183.364886 -29.589984)
		(width 0.3556)
		(layer "F.Cu")
		(net "GND")
	)
	(segment
		(start 395.12494 -298.27474)
		(end 394.64996 -298.74972)
		(width 0.249936)
		(layer "F.Cu")
		(net "GND")
	)
	(segment
		(start 37.799772 -284.499812)
		(end 37.324792 -284.024832)
		(width 0.249936)
		(layer "F.Cu")
		(net "GND")
	)
	(segment
		(start 304.687478 -25.742392)
		(end 304.687478 -26.360882)
		(width 0.4572)
		(layer "F.Cu")
		(net "GND")
	)
	(segment
		(start 164.349938 -294.94988)
		(end 163.874958 -294.4749)
		(width 0.249936)
		(layer "F.Cu")
		(net "GND")
	)
	(segment
		(start 399.874994 -291.624766)
		(end 399.400014 -292.099746)
		(width 0.249936)
		(layer "F.Cu")
		(net "GND")
	)
	(segment
		(start 275.699728 -273.099784)
		(end 275.224748 -272.624804)
		(width 0.249936)
		(layer "F.Cu")
		(net "GND")
	)
	(segment
		(start 395.255496 -102.445058)
		(end 394.342366 -102.445058)
		(width 0.3556)
		(layer "F.Cu")
		(net "GND")
	)
	(segment
		(start 61.074808 -307.774848)
		(end 60.599828 -307.299868)
		(width 0.249936)
		(layer "F.Cu")
		(net "GND")
	)
	(segment
		(start 446.150238 -94.863666)
		(end 446.150238 -94.227904)
		(width 0.4064)
		(layer "F.Cu")
		(net "GND")
	)
	(segment
		(start 387.85292 -140.85697)
		(end 388.025386 -141.029436)
		(width 0.4572)
		(layer "F.Cu")
		(net "GND")
	)
	(segment
		(start 189.999874 -298.74972)
		(end 190.474854 -298.27474)
		(width 0.249936)
		(layer "F.Cu")
		(net "GND")
	)
	(segment
		(start 117.408706 -316.238128)
		(end 117.656864 -315.98997)
		(width 0.254)
		(layer "F.Cu")
		(net "GND")
	)
	(segment
		(start 162.450018 -304.449734)
		(end 162.924998 -304.924714)
		(width 0.249936)
		(layer "F.Cu")
		(net "GND")
	)
	(segment
		(start 313.699906 -290.199826)
		(end 313.224926 -289.724846)
		(width 0.249936)
		(layer "F.Cu")
		(net "GND")
	)
	(segment
		(start 40.649906 -279.749758)
		(end 40.174926 -279.274778)
		(width 0.249936)
		(layer "F.Cu")
		(net "GND")
	)
	(segment
		(start 279.974802 -306.824888)
		(end 279.499822 -307.299868)
		(width 0.249936)
		(layer "F.Cu")
		(net "GND")
	)
	(segment
		(start 177.174906 -289.724846)
		(end 176.699926 -290.199826)
		(width 0.249936)
		(layer "F.Cu")
		(net "GND")
	)
	(segment
		(start 286.624776 -305.874928)
		(end 286.149796 -305.399948)
		(width 0.249936)
		(layer "F.Cu")
		(net "GND")
	)
	(segment
		(start 398.925034 -296.37482)
		(end 398.4498 -296.8498)
		(width 0.249936)
		(layer "F.Cu")
		(net "GND")
	)
	(segment
		(start 362.548932 -29.589984)
		(end 363.564932 -29.589984)
		(width 0.3556)
		(layer "F.Cu")
		(net "GND")
	)
	(segment
		(start 174.900082 -38.671754)
		(end 174.900082 -38.315138)
		(width 0.4572)
		(layer "F.Cu")
		(net "GND")
	)
	(segment
		(start 187.624974 -297.32478)
		(end 187.149994 -297.79976)
		(width 0.249936)
		(layer "F.Cu")
		(net "GND")
	)
	(segment
		(start 189.524894 -292.574726)
		(end 189.999874 -293.04996)
		(width 0.249936)
		(layer "F.Cu")
		(net "GND")
	)
	(segment
		(start 378.738384 -252.756924)
		(end 378.738384 -253.45644)
		(width 0.4572)
		(layer "F.Cu")
		(net "GND")
	)
	(segment
		(start 47.032926 -131.76504)
		(end 46.042326 -131.76504)
		(width 0.3556)
		(layer "F.Cu")
		(net "GND")
	)
	(segment
		(start 137.54608 -46.693836)
		(end 137.018776 -46.693836)
		(width 0.254)
		(layer "F.Cu")
		(net "GND")
	)
	(segment
		(start 186.675014 -290.674806)
		(end 186.200034 -291.149786)
		(width 0.249936)
		(layer "F.Cu")
		(net "GND")
	)
	(segment
		(start 441.564776 -33.19018)
		(end 442.580776 -33.19018)
		(width 0.3556)
		(layer "F.Cu")
		(net "GND")
	)
	(segment
		(start 46.8249 -303.024794)
		(end 47.29988 -302.549814)
		(width 0.249936)
		(layer "F.Cu")
		(net "GND")
	)
	(segment
		(start 331.34681 -53.144166)
		(end 331.34681 -52.592224)
		(width 0.254)
		(layer "F.Cu")
		(net "GND")
	)
	(segment
		(start 151.838406 -136.241028)
		(end 151.398478 -136.680956)
		(width 0.4572)
		(layer "F.Cu")
		(net "GND")
	)
	(segment
		(start 299.449744 -303.499774)
		(end 298.974764 -303.974754)
		(width 0.249936)
		(layer "F.Cu")
		(net "GND")
	)
	(segment
		(start 189.999874 -294.94988)
		(end 190.474854 -294.4749)
		(width 0.249936)
		(layer "F.Cu")
		(net "GND")
	)
	(segment
		(start 387.050026 -280.699718)
		(end 386.575046 -280.224738)
		(width 0.249936)
		(layer "F.Cu")
		(net "GND")
	)
	(segment
		(start 154.307794 -156.3624)
		(end 153.672794 -156.3624)
		(width 0.4064)
		(layer "F.Cu")
		(net "GND")
	)
	(segment
		(start 270.474694 -298.27474)
		(end 269.999714 -298.74972)
		(width 0.249936)
		(layer "F.Cu")
		(net "GND")
	)
	(segment
		(start 156.275024 -296.37482)
		(end 156.750004 -295.89984)
		(width 0.249936)
		(layer "F.Cu")
		(net "GND")
	)
	(segment
		(start 16.02486 -409.448508)
		(end 15.380716 -409.448508)
		(width 0.4572)
		(layer "F.Cu")
		(net "GND")
	)
	(segment
		(start 130.702304 -200.502012)
		(end 132.00126 -200.502012)
		(width 0.4572)
		(layer "F.Cu")
		(net "GND")
	)
	(segment
		(start 395.332966 -118.754906)
		(end 394.342366 -118.754906)
		(width 0.3556)
		(layer "F.Cu")
		(net "GND")
	)
	(segment
		(start 256.542286 -252.756924)
		(end 256.542286 -253.5174)
		(width 0.4572)
		(layer "F.Cu")
		(net "GND")
	)
	(segment
		(start 299.449744 -306.349908)
		(end 298.974764 -305.874928)
		(width 0.249936)
		(layer "F.Cu")
		(net "GND")
	)
	(segment
		(start 416.974782 -305.874928)
		(end 416.499802 -305.399948)
		(width 0.249936)
		(layer "F.Cu")
		(net "GND")
	)
	(segment
		(start 400.824954 -285.924752)
		(end 401.299934 -285.449772)
		(width 0.249936)
		(layer "F.Cu")
		(net "GND")
	)
	(segment
		(start 71.999856 -298.74972)
		(end 71.524876 -298.27474)
		(width 0.249936)
		(layer "F.Cu")
		(net "GND")
	)
	(segment
		(start 296.599864 -293.99992)
		(end 297.074844 -293.52494)
		(width 0.249936)
		(layer "F.Cu")
		(net "GND")
	)
	(segment
		(start 206.712058 -87.303102)
		(end 203.495656 -87.303102)
		(width 0.4572)
		(layer "F.Cu")
		(net "GND")
	)
	(segment
		(start 70.574916 -287.824926)
		(end 71.049896 -288.299906)
		(width 0.249936)
		(layer "F.Cu")
		(net "GND")
	)
	(segment
		(start 388.949946 -288.299906)
		(end 389.424926 -287.824926)
		(width 0.249936)
		(layer "F.Cu")
		(net "GND")
	)
	(segment
		(start 284.867858 -54.067456)
		(end 285.523178 -54.067456)
		(width 0.254)
		(layer "F.Cu")
		(net "GND")
	)
	(segment
		(start 403.674834 -294.4749)
		(end 404.149814 -294.94988)
		(width 0.249936)
		(layer "F.Cu")
		(net "GND")
	)
	(segment
		(start 71.049896 -301.599854)
		(end 71.524876 -302.074834)
		(width 0.249936)
		(layer "F.Cu")
		(net "GND")
	)
	(segment
		(start 155.800044 -293.99992)
		(end 155.325064 -293.52494)
		(width 0.249936)
		(layer "F.Cu")
		(net "GND")
	)
	(segment
		(start 57.274968 -306.824888)
		(end 57.749948 -307.299868)
		(width 0.249936)
		(layer "F.Cu")
		(net "GND")
	)
	(segment
		(start 148.900134 -38.671754)
		(end 148.900134 -38.315138)
		(width 0.4572)
		(layer "F.Cu")
		(net "GND")
	)
	(segment
		(start 181.92496 -284.974792)
		(end 181.44998 -284.499812)
		(width 0.249936)
		(layer "F.Cu")
		(net "GND")
	)
	(segment
		(start 365.90605 -212.979)
		(end 366.522 -212.979)
		(width 0.4572)
		(layer "F.Cu")
		(net "GND")
	)
	(segment
		(start 183.3499 -285.449772)
		(end 183.82488 -285.924752)
		(width 0.249936)
		(layer "F.Cu")
		(net "GND")
	)
	(segment
		(start 80.889348 -223.2406)
		(end 69.9516 -223.2406)
		(width 0.4572)
		(layer "F.Cu")
		(net "GND")
	)
	(segment
		(start 408.899868 -286.399732)
		(end 408.424888 -285.924752)
		(width 0.249936)
		(layer "F.Cu")
		(net "GND")
	)
	(segment
		(start 282.889198 -176.478438)
		(end 282.889198 -175.855376)
		(width 0.381)
		(layer "F.Cu")
		(net "GND")
	)
	(segment
		(start 418.874956 -291.624766)
		(end 418.399976 -292.099746)
		(width 0.249936)
		(layer "F.Cu")
		(net "GND")
	)
	(segment
		(start 105.624376 -119.026178)
		(end 106.363516 -119.026178)
		(width 0.4572)
		(layer "F.Cu")
		(net "GND")
	)
	(segment
		(start 418.874956 -292.57498)
		(end 419.349936 -292.1)
		(width 0.249936)
		(layer "F.Cu")
		(net "GND")
	)
	(segment
		(start 50.14976 -301.599854)
		(end 49.67478 -302.074834)
		(width 0.249936)
		(layer "F.Cu")
		(net "GND")
	)
	(segment
		(start 154.37485 -296.37482)
		(end 154.850084 -295.89984)
		(width 0.249936)
		(layer "F.Cu")
		(net "GND")
	)
	(segment
		(start 288.99993 -285.449772)
		(end 288.524696 -285.924752)
		(width 0.249936)
		(layer "F.Cu")
		(net "GND")
	)
	(segment
		(start 278.549862 -291.149786)
		(end 278.074882 -290.674806)
		(width 0.249936)
		(layer "F.Cu")
		(net "GND")
	)
	(segment
		(start 220.851222 -142.926562)
		(end 220.241622 -142.926562)
		(width 0.4572)
		(layer "F.Cu")
		(net "GND")
	)
	(segment
		(start 395.145768 -125.955044)
		(end 394.342366 -125.955044)
		(width 0.3556)
		(layer "F.Cu")
		(net "GND")
	)
	(segment
		(start 74.374756 -292.574726)
		(end 73.899776 -293.04996)
		(width 0.249936)
		(layer "F.Cu")
		(net "GND")
	)
	(segment
		(start 452.927212 -367.453672)
		(end 452.086472 -367.453672)
		(width 0.4572)
		(layer "F.Cu")
		(net "GND")
	)
	(segment
		(start 281.399742 -307.299868)
		(end 281.874722 -307.774848)
		(width 0.249936)
		(layer "F.Cu")
		(net "GND")
	)
	(segment
		(start 186.675014 -284.974792)
		(end 187.149994 -285.449772)
		(width 0.249936)
		(layer "F.Cu")
		(net "GND")
	)
	(segment
		(start 182.87492 -303.974754)
		(end 183.3499 -303.499774)
		(width 0.249936)
		(layer "F.Cu")
		(net "GND")
	)
	(segment
		(start 57.749948 -303.499774)
		(end 57.274968 -303.974754)
		(width 0.249936)
		(layer "F.Cu")
		(net "GND")
	)
	(segment
		(start 76.74991 -291.149786)
		(end 77.22489 -291.624766)
		(width 0.249936)
		(layer "F.Cu")
		(net "GND")
	)
	(segment
		(start 185.250074 -292.099746)
		(end 185.725054 -291.624766)
		(width 0.249936)
		(layer "F.Cu")
		(net "GND")
	)
	(segment
		(start 371.446552 -255.66624)
		(end 371.446552 -255.669542)
		(width 0.4572)
		(layer "F.Cu")
		(net "GND")
	)
	(segment
		(start 72.267064 -143.955008)
		(end 73.257664 -143.955008)
		(width 0.3556)
		(layer "F.Cu")
		(net "GND")
	)
	(segment
		(start 76.27493 -298.27474)
		(end 75.79995 -297.79976)
		(width 0.249936)
		(layer "F.Cu")
		(net "GND")
	)
	(segment
		(start 304.1777 -135.320024)
		(end 304.65268 -134.845044)
		(width 0.3556)
		(layer "F.Cu")
		(net "GND")
	)
	(segment
		(start 190.950088 -299.699934)
		(end 191.425068 -300.174914)
		(width 0.249936)
		(layer "F.Cu")
		(net "GND")
	)
	(segment
		(start 292.72484 -288.299906)
		(end 292.79977 -288.299906)
		(width 0.249936)
		(layer "F.Cu")
		(net "GND")
	)
	(segment
		(start 55.374794 -285.924752)
		(end 54.899814 -285.449772)
		(width 0.249936)
		(layer "F.Cu")
		(net "GND")
	)
	(segment
		(start 306.448206 -151.155146)
		(end 305.457606 -151.155146)
		(width 0.3556)
		(layer "F.Cu")
		(net "GND")
	)
	(segment
		(start 165.299898 -308.249828)
		(end 165.774878 -307.774848)
		(width 0.249936)
		(layer "F.Cu")
		(net "GND")
	)
	(segment
		(start 272.374868 -283.074872)
		(end 272.849848 -283.549852)
		(width 0.249936)
		(layer "F.Cu")
		(net "GND")
	)
	(segment
		(start 63.924942 -285.924752)
		(end 63.449962 -285.449772)
		(width 0.249936)
		(layer "F.Cu")
		(net "GND")
	)
	(segment
		(start 282.349702 -304.449734)
		(end 281.874722 -304.924714)
		(width 0.249936)
		(layer "F.Cu")
		(net "GND")
	)
	(segment
		(start 71.049896 -305.399948)
		(end 71.524876 -305.874928)
		(width 0.249936)
		(layer "F.Cu")
		(net "GND")
	)
	(segment
		(start 310.843676 -43.85691)
		(end 311.514998 -43.85691)
		(width 0.254)
		(layer "F.Cu")
		(net "GND")
	)
	(segment
		(start 292.32479 -303.974754)
		(end 292.79977 -303.499774)
		(width 0.249936)
		(layer "F.Cu")
		(net "GND")
	)
	(segment
		(start 181.92496 -305.874928)
		(end 182.39994 -305.399948)
		(width 0.249936)
		(layer "F.Cu")
		(net "GND")
	)
	(segment
		(start 404.149814 -285.449772)
		(end 404.624794 -285.924752)
		(width 0.249936)
		(layer "F.Cu")
		(net "GND")
	)
	(segment
		(start 419.557962 -73.166732)
		(end 419.557962 -73.85177)
		(width 0.4572)
		(layer "F.Cu")
		(net "GND")
	)
	(segment
		(start 306.099718 -290.199826)
		(end 306.574698 -290.674806)
		(width 0.249936)
		(layer "F.Cu")
		(net "GND")
	)
	(segment
		(start 312.274712 -298.27474)
		(end 311.799732 -298.74972)
		(width 0.249936)
		(layer "F.Cu")
		(net "GND")
	)
	(segment
		(start 412.699962 -303.499774)
		(end 413.174942 -303.974754)
		(width 0.249936)
		(layer "F.Cu")
		(net "GND")
	)
	(segment
		(start 183.82488 -302.074834)
		(end 184.29986 -301.599854)
		(width 0.249936)
		(layer "F.Cu")
		(net "GND")
	)
	(segment
		(start 286.624776 -305.874928)
		(end 286.149796 -306.349908)
		(width 0.249936)
		(layer "F.Cu")
		(net "GND")
	)
	(segment
		(start 68.674742 -287.824926)
		(end 69.149976 -288.299906)
		(width 0.249936)
		(layer "F.Cu")
		(net "GND")
	)
	(segment
		(start 166.249858 -291.149786)
		(end 166.725092 -291.624766)
		(width 0.249936)
		(layer "F.Cu")
		(net "GND")
	)
	(segment
		(start 52.524914 -284.974792)
		(end 52.999894 -284.499812)
		(width 0.249936)
		(layer "F.Cu")
		(net "GND")
	)
	(segment
		(start 312.749692 -300.649894)
		(end 313.224926 -301.124874)
		(width 0.249936)
		(layer "F.Cu")
		(net "GND")
	)
	(segment
		(start 56.32323 -390.464802)
		(end 55.27294 -390.464802)
		(width 0.3048)
		(layer "F.Cu")
		(net "GND")
	)
	(segment
		(start 280.449782 -304.449734)
		(end 279.974802 -303.974754)
		(width 0.249936)
		(layer "F.Cu")
		(net "GND")
	)
	(segment
		(start 79.12481 -288.774886)
		(end 79.59979 -289.249866)
		(width 0.249936)
		(layer "F.Cu")
		(net "GND")
	)
	(segment
		(start 165.751764 -118.754906)
		(end 166.742364 -118.754906)
		(width 0.3556)
		(layer "F.Cu")
		(net "GND")
	)
	(segment
		(start 398.925034 -298.27474)
		(end 398.4498 -298.74972)
		(width 0.249936)
		(layer "F.Cu")
		(net "GND")
	)
	(segment
		(start 425.99991 -289.249866)
		(end 426.47489 -289.724846)
		(width 0.249936)
		(layer "F.Cu")
		(net "GND")
	)
	(segment
		(start 171.474892 -285.924752)
		(end 170.999912 -285.449772)
		(width 0.249936)
		(layer "F.Cu")
		(net "GND")
	)
	(segment
		(start 413.174942 -291.624766)
		(end 413.649922 -292.099746)
		(width 0.249936)
		(layer "F.Cu")
		(net "GND")
	)
	(segment
		(start 276.649688 -299.699934)
		(end 276.174708 -299.224954)
		(width 0.249936)
		(layer "F.Cu")
		(net "GND")
	)
	(segment
		(start 242.4938 -214.0458)
		(end 242.4938 -213.7156)
		(width 0.4572)
		(layer "F.Cu")
		(net "GND")
	)
	(segment
		(start 59.649868 -294.94988)
		(end 60.124848 -294.4749)
		(width 0.249936)
		(layer "F.Cu")
		(net "GND")
	)
	(segment
		(start 176.224946 -284.974792)
		(end 176.699926 -284.499812)
		(width 0.249936)
		(layer "F.Cu")
		(net "GND")
	)
	(segment
		(start 400.349974 -292.099746)
		(end 399.874994 -291.624766)
		(width 0.249936)
		(layer "F.Cu")
		(net "GND")
	)
	(segment
		(start 406.5778 -389.7122)
		(end 406.4 -389.7122)
		(width 0.4572)
		(layer "F.Cu")
		(net "GND")
	)
	(segment
		(start 293.74973 -305.399948)
		(end 293.27475 -305.874928)
		(width 0.249936)
		(layer "F.Cu")
		(net "GND")
	)
	(segment
		(start 196.174868 -302.074834)
		(end 196.649848 -302.549814)
		(width 0.249936)
		(layer "F.Cu")
		(net "GND")
	)
	(segment
		(start 361.794806 -158.705042)
		(end 361.794806 -159.498792)
		(width 0.254)
		(layer "F.Cu")
		(net "GND")
	)
	(segment
		(start 414.124902 -285.924752)
		(end 414.599882 -285.449772)
		(width 0.249936)
		(layer "F.Cu")
		(net "GND")
	)
	(segment
		(start 422.548304 -143.955008)
		(end 421.557704 -143.955008)
		(width 0.3556)
		(layer "F.Cu")
		(net "GND")
	)
	(segment
		(start 50.14976 -291.149786)
		(end 50.624994 -291.624766)
		(width 0.249936)
		(layer "F.Cu")
		(net "GND")
	)
	(segment
		(start 390.849866 -287.349946)
		(end 390.374886 -286.874966)
		(width 0.249936)
		(layer "F.Cu")
		(net "GND")
	)
	(segment
		(start 343.69375 -217.587068)
		(end 344.093546 -217.187272)
		(width 0.381)
		(layer "F.Cu")
		(net "GND")
	)
	(segment
		(start 298.499784 -290.199826)
		(end 298.974764 -289.724846)
		(width 0.249936)
		(layer "F.Cu")
		(net "GND")
	)
	(segment
		(start 75.79995 -299.699934)
		(end 76.27493 -299.224954)
		(width 0.249936)
		(layer "F.Cu")
		(net "GND")
	)
	(segment
		(start 59.649868 -286.399732)
		(end 60.124848 -285.924752)
		(width 0.249936)
		(layer "F.Cu")
		(net "GND")
	)
	(segment
		(start 411.275022 -284.974792)
		(end 411.750002 -284.499812)
		(width 0.249936)
		(layer "F.Cu")
		(net "GND")
	)
	(segment
		(start 234.825794 -116.936266)
		(end 235.387134 -116.936266)
		(width 0.254)
		(layer "F.Cu")
		(net "GND")
	)
	(segment
		(start 274.480782 -33.19018)
		(end 273.464782 -33.19018)
		(width 0.3556)
		(layer "F.Cu")
		(net "GND")
	)
	(segment
		(start 295.174924 -300.174914)
		(end 295.649904 -299.699934)
		(width 0.249936)
		(layer "F.Cu")
		(net "GND")
	)
	(segment
		(start 316.689232 -62.812168)
		(end 317.499746 -62.812168)
		(width 0.4572)
		(layer "F.Cu")
		(net "GND")
	)
	(segment
		(start 387.999986 -277.849838)
		(end 387.525006 -277.374858)
		(width 0.249936)
		(layer "F.Cu")
		(net "GND")
	)
	(segment
		(start 374.943878 -45.88891)
		(end 375.6152 -45.88891)
		(width 0.254)
		(layer "F.Cu")
		(net "GND")
	)
	(segment
		(start 413.649922 -307.299868)
		(end 413.174942 -306.824888)
		(width 0.249936)
		(layer "F.Cu")
		(net "GND")
	)
	(segment
		(start 386.099812 -290.199826)
		(end 385.624832 -289.724846)
		(width 0.249936)
		(layer "F.Cu")
		(net "GND")
	)
	(segment
		(start 365.24692 -262.006588)
		(end 364.557564 -262.006588)
		(width 0.4572)
		(layer "F.Cu")
		(net "GND")
	)
	(segment
		(start 415.074862 -298.27474)
		(end 414.599882 -297.79976)
		(width 0.249936)
		(layer "F.Cu")
		(net "GND")
	)
	(segment
		(start 133.738874 -282.8417)
		(end 133.506464 -283.07411)
		(width 0.2286)
		(layer "F.Cu")
		(net "GND")
	)
	(segment
		(start 173.375066 -285.924752)
		(end 173.850046 -285.449772)
		(width 0.249936)
		(layer "F.Cu")
		(net "GND")
	)
	(segment
		(start 273.799808 -294.94988)
		(end 273.324828 -294.4749)
		(width 0.249936)
		(layer "F.Cu")
		(net "GND")
	)
	(segment
		(start 49.1998 -284.499812)
		(end 48.72482 -284.024832)
		(width 0.249936)
		(layer "F.Cu")
		(net "GND")
	)
	(segment
		(start 415.96691 -123.635008)
		(end 416.95751 -123.635008)
		(width 0.3556)
		(layer "F.Cu")
		(net "GND")
	)
	(segment
		(start 289.47491 -306.824888)
		(end 289.94989 -307.299868)
		(width 0.249936)
		(layer "F.Cu")
		(net "GND")
	)
	(segment
		(start 394.64996 -294.94988)
		(end 394.17498 -294.4749)
		(width 0.249936)
		(layer "F.Cu")
		(net "GND")
	)
	(segment
		(start 298.974764 -306.824888)
		(end 298.499784 -307.299868)
		(width 0.249936)
		(layer "F.Cu")
		(net "GND")
	)
	(segment
		(start 290.89985 -306.349908)
		(end 290.42487 -305.874928)
		(width 0.249936)
		(layer "F.Cu")
		(net "GND")
	)
	(segment
		(start 302.299878 -298.74972)
		(end 302.774858 -299.224954)
		(width 0.249936)
		(layer "F.Cu")
		(net "GND")
	)
	(segment
		(start 426.357542 -80.449674)
		(end 427.043342 -80.449674)
		(width 0.254)
		(layer "F.Cu")
		(net "GND")
	)
	(segment
		(start 299.924724 -285.924752)
		(end 299.449744 -285.449772)
		(width 0.249936)
		(layer "F.Cu")
		(net "GND")
	)
	(segment
		(start 400.824954 -296.37482)
		(end 400.349974 -296.8498)
		(width 0.249936)
		(layer "F.Cu")
		(net "GND")
	)
	(segment
		(start 415.549842 -285.449772)
		(end 416.024822 -284.974792)
		(width 0.249936)
		(layer "F.Cu")
		(net "GND")
	)
	(segment
		(start 12.49172 -305.786536)
		(end 12.608052 -305.786536)
		(width 0.1778)
		(layer "F.Cu")
		(net "GND")
	)
	(segment
		(start 93.771212 -120.041924)
		(end 93.18244 -120.041924)
		(width 0.254)
		(layer "F.Cu")
		(net "GND")
	)
	(segment
		(start 406.049988 -284.499812)
		(end 406.524968 -284.974792)
		(width 0.249936)
		(layer "F.Cu")
		(net "GND")
	)
	(segment
		(start 117.079776 -282.8417)
		(end 116.847366 -283.07411)
		(width 0.2286)
		(layer "F.Cu")
		(net "GND")
	)
	(segment
		(start 177.174906 -285.924752)
		(end 177.649886 -285.449772)
		(width 0.249936)
		(layer "F.Cu")
		(net "GND")
	)
	(segment
		(start 253.730506 -65.92189)
		(end 253.730506 -65.15989)
		(width 0.4572)
		(layer "F.Cu")
		(net "GND")
	)
	(segment
		(start 279.299162 -122.130312)
		(end 279.074372 -122.355102)
		(width 0.3556)
		(layer "F.Cu")
		(net "GND")
	)
	(segment
		(start 396.54988 -300.649894)
		(end 396.0749 -301.124874)
		(width 0.249936)
		(layer "F.Cu")
		(net "GND")
	)
	(segment
		(start 193.799968 -293.04996)
		(end 193.324988 -293.52494)
		(width 0.249936)
		(layer "F.Cu")
		(net "GND")
	)
	(segment
		(start 306.099718 -293.99992)
		(end 305.624738 -294.4749)
		(width 0.249936)
		(layer "F.Cu")
		(net "GND")
	)
	(segment
		(start 115.24234 -258.14655)
		(end 115.24234 -258.78155)
		(width 0.381)
		(layer "F.Cu")
		(net "GND")
	)
	(segment
		(start 398.925034 -305.874928)
		(end 399.400014 -305.399948)
		(width 0.249936)
		(layer "F.Cu")
		(net "GND")
	)
	(segment
		(start 283.833062 -152.96007)
		(end 282.842462 -152.96007)
		(width 0.3556)
		(layer "F.Cu")
		(net "GND")
	)
	(segment
		(start 241.56416 -56.21147)
		(end 241.56416 -56.86679)
		(width 0.4572)
		(layer "F.Cu")
		(net "GND")
	)
	(segment
		(start 287.574736 -302.074834)
		(end 287.099756 -301.599854)
		(width 0.249936)
		(layer "F.Cu")
		(net "GND")
	)
	(segment
		(start 56.324754 -285.924752)
		(end 55.849774 -285.449772)
		(width 0.249936)
		(layer "F.Cu")
		(net "GND")
	)
	(segment
		(start 386.099812 -296.8498)
		(end 386.574792 -297.32478)
		(width 0.249936)
		(layer "F.Cu")
		(net "GND")
	)
	(segment
		(start 429.325024 -290.674806)
		(end 429.800004 -290.199826)
		(width 0.249936)
		(layer "F.Cu")
		(net "GND")
	)
	(segment
		(start 164.491416 -100.64496)
		(end 166.742364 -100.64496)
		(width 0.3556)
		(layer "F.Cu")
		(net "GND")
	)
	(segment
		(start 71.37019 -47.60087)
		(end 71.796148 -47.60087)
		(width 0.254)
		(layer "F.Cu")
		(net "GND")
	)
	(segment
		(start 390.849866 -280.699718)
		(end 390.374886 -280.224738)
		(width 0.249936)
		(layer "F.Cu")
		(net "GND")
	)
	(segment
		(start 304.467006 -129.445004)
		(end 305.457606 -129.445004)
		(width 0.3556)
		(layer "F.Cu")
		(net "GND")
	)
	(segment
		(start 306.574698 -290.674806)
		(end 307.049932 -290.199826)
		(width 0.249936)
		(layer "F.Cu")
		(net "GND")
	)
	(segment
		(start 388.898384 -252.756924)
		(end 388.898384 -253.45644)
		(width 0.4572)
		(layer "F.Cu")
		(net "GND")
	)
	(segment
		(start 13.140944 -303.99482)
		(end 12.573 -304.562764)
		(width 0.254)
		(layer "F.Cu")
		(net "GND")
	)
	(segment
		(start 242.08359 -221.04096)
		(end 241.373914 -221.04096)
		(width 0.4572)
		(layer "F.Cu")
		(net "GND")
	)
	(segment
		(start 88.664796 -27.79014)
		(end 87.648796 -27.79014)
		(width 0.3556)
		(layer "F.Cu")
		(net "GND")
	)
	(segment
		(start 285.199836 -285.449772)
		(end 285.674816 -285.924752)
		(width 0.249936)
		(layer "F.Cu")
		(net "GND")
	)
	(segment
		(start 146.538442 -252.756924)
		(end 146.538442 -253.45644)
		(width 0.4572)
		(layer "F.Cu")
		(net "GND")
	)
	(segment
		(start 297.549824 -307.299868)
		(end 297.074844 -306.824888)
		(width 0.249936)
		(layer "F.Cu")
		(net "GND")
	)
	(segment
		(start 47.77486 -301.124874)
		(end 48.24984 -300.649894)
		(width 0.249936)
		(layer "F.Cu")
		(net "GND")
	)
	(segment
		(start 414.548828 -33.19018)
		(end 415.564828 -33.19018)
		(width 0.3556)
		(layer "F.Cu")
		(net "GND")
	)
	(segment
		(start 316.3189 -59.974734)
		(end 315.668406 -59.974734)
		(width 0.4572)
		(layer "F.Cu")
		(net "GND")
	)
	(segment
		(start 62.664848 -27.79014)
		(end 61.648848 -27.79014)
		(width 0.3556)
		(layer "F.Cu")
		(net "GND")
	)
	(segment
		(start 398.166844 -107.845098)
		(end 398.94256 -107.845098)
		(width 0.3556)
		(layer "F.Cu")
		(net "GND")
	)
	(segment
		(start 456.018138 -279.19934)
		(end 455.383138 -279.19934)
		(width 0.4572)
		(layer "F.Cu")
		(net "GND")
	)
	(segment
		(start 389.899906 -299.699934)
		(end 390.849866 -299.699934)
		(width 0.249936)
		(layer "F.Cu")
		(net "GND")
	)
	(segment
		(start 41.124886 -299.224954)
		(end 41.599866 -298.74972)
		(width 0.249936)
		(layer "F.Cu")
		(net "GND")
	)
	(segment
		(start 52.049934 -286.399732)
		(end 51.574954 -285.924752)
		(width 0.249936)
		(layer "F.Cu")
		(net "GND")
	)
	(segment
		(start 67.264788 -29.589984)
		(end 66.248788 -29.589984)
		(width 0.3556)
		(layer "F.Cu")
		(net "GND")
	)
	(segment
		(start 161.975038 -296.37482)
		(end 161.500058 -296.8498)
		(width 0.249936)
		(layer "F.Cu")
		(net "GND")
	)
	(segment
		(start 221.505526 -177.390552)
		(end 221.505526 -178.027076)
		(width 0.4572)
		(layer "F.Cu")
		(net "GND")
	)
	(segment
		(start 286.624776 -285.924752)
		(end 287.099756 -286.399732)
		(width 0.249936)
		(layer "F.Cu")
		(net "GND")
	)
	(segment
		(start 437.12384 -291.592)
		(end 437.12384 -291.2618)
		(width 0.4572)
		(layer "F.Cu")
		(net "GND")
	)
	(segment
		(start 164.824918 -293.52494)
		(end 165.299898 -293.99992)
		(width 0.249936)
		(layer "F.Cu")
		(net "GND")
	)
	(segment
		(start 94.894146 -116.410486)
		(end 95.529146 -116.410486)
		(width 0.4572)
		(layer "F.Cu")
		(net "GND")
	)
	(segment
		(start 62.499748 -290.199826)
		(end 62.974982 -289.724846)
		(width 0.249936)
		(layer "F.Cu")
		(net "GND")
	)
	(segment
		(start 340.493858 -219.187014)
		(end 340.094062 -218.787218)
		(width 0.381)
		(layer "F.Cu")
		(net "GND")
	)
	(segment
		(start 234.48264 -28.47848)
		(end 234.143296 -28.139136)
		(width 0.254)
		(layer "F.Cu")
		(net "GND")
	)
	(segment
		(start 276.649688 -288.299906)
		(end 276.174708 -288.774886)
		(width 0.249936)
		(layer "F.Cu")
		(net "GND")
	)
	(segment
		(start 415.96691 -156.554932)
		(end 416.95751 -156.554932)
		(width 0.3556)
		(layer "F.Cu")
		(net "GND")
	)
	(segment
		(start 36.849812 -277.849838)
		(end 36.374832 -277.374858)
		(width 0.249936)
		(layer "F.Cu")
		(net "GND")
	)
	(segment
		(start 405.100028 -290.199826)
		(end 405.575008 -289.724846)
		(width 0.249936)
		(layer "F.Cu")
		(net "GND")
	)
	(segment
		(start 257.664458 -29.67736)
		(end 257.664458 -29.079952)
		(width 0.4572)
		(layer "F.Cu")
		(net "GND")
	)
	(segment
		(start 211.572094 -78.4606)
		(end 210.684618 -78.4606)
		(width 0.4572)
		(layer "F.Cu")
		(net "GND")
	)
	(segment
		(start 274.480782 -25.990042)
		(end 273.464782 -25.990042)
		(width 0.3556)
		(layer "F.Cu")
		(net "GND")
	)
	(segment
		(start 408.424888 -306.824888)
		(end 407.949908 -307.299868)
		(width 0.249936)
		(layer "F.Cu")
		(net "GND")
	)
	(segment
		(start 283.299916 -290.199826)
		(end 282.824936 -289.724846)
		(width 0.249936)
		(layer "F.Cu")
		(net "GND")
	)
	(segment
		(start 180.975 -287.824926)
		(end 181.44998 -288.299906)
		(width 0.249936)
		(layer "F.Cu")
		(net "GND")
	)
	(segment
		(start 80.07477 -296.37482)
		(end 80.54975 -296.8498)
		(width 0.249936)
		(layer "F.Cu")
		(net "GND")
	)
	(segment
		(start 447.446908 -52.592224)
		(end 447.522092 -52.51704)
		(width 0.254)
		(layer "F.Cu")
		(net "GND")
	)
	(segment
		(start 202.792838 -54.163722)
		(end 202.868022 -54.238906)
		(width 0.254)
		(layer "F.Cu")
		(net "GND")
	)
	(segment
		(start 413.174942 -306.824888)
		(end 412.699962 -307.299868)
		(width 0.249936)
		(layer "F.Cu")
		(net "GND")
	)
	(segment
		(start 397.02486 -305.874928)
		(end 397.49984 -306.349908)
		(width 0.249936)
		(layer "F.Cu")
		(net "GND")
	)
	(segment
		(start 299.14723 -196.706236)
		(end 299.14723 -196.022976)
		(width 0.4572)
		(layer "F.Cu")
		(net "GND")
	)
	(segment
		(start 268.864842 -31.390082)
		(end 269.736316 -31.390082)
		(width 0.3556)
		(layer "F.Cu")
		(net "GND")
	)
	(segment
		(start 302.774858 -301.124874)
		(end 303.249838 -300.649894)
		(width 0.249936)
		(layer "F.Cu")
		(net "GND")
	)
	(segment
		(start 104.667812 -55.083456)
		(end 105.323132 -55.083456)
		(width 0.254)
		(layer "F.Cu")
		(net "GND")
	)
	(segment
		(start 283.664406 -29.67736)
		(end 283.664406 -29.079952)
		(width 0.4572)
		(layer "F.Cu")
		(net "GND")
	)
	(segment
		(start 21.508466 -257.852164)
		(end 21.508466 -258.665472)
		(width 0.4572)
		(layer "F.Cu")
		(net "GND")
	)
	(segment
		(start 184.29986 -305.399948)
		(end 184.77484 -304.924714)
		(width 0.249936)
		(layer "F.Cu")
		(net "GND")
	)
	(segment
		(start 180.02504 -285.924752)
		(end 179.55006 -285.449772)
		(width 0.249936)
		(layer "F.Cu")
		(net "GND")
	)
	(segment
		(start 126.76505 -29.589984)
		(end 125.74905 -29.589984)
		(width 0.3556)
		(layer "F.Cu")
		(net "GND")
	)
	(segment
		(start 268.864842 -33.19018)
		(end 267.848842 -33.19018)
		(width 0.3556)
		(layer "F.Cu")
		(net "GND")
	)
	(segment
		(start 53.949854 -303.499774)
		(end 54.424834 -303.974754)
		(width 0.249936)
		(layer "F.Cu")
		(net "GND")
	)
	(segment
		(start 429.649636 -85.426296)
		(end 428.539656 -85.426296)
		(width 0.4572)
		(layer "F.Cu")
		(net "GND")
	)
	(segment
		(start 279.118568 -46.693836)
		(end 278.919178 -46.893226)
		(width 0.254)
		(layer "F.Cu")
		(net "GND")
	)
	(segment
		(start 361.939332 -239.21593)
		(end 362.598462 -238.5568)
		(width 0.4572)
		(layer "F.Cu")
		(net "GND")
	)
	(segment
		(start 296.124884 -305.874928)
		(end 295.649904 -306.349908)
		(width 0.249936)
		(layer "F.Cu")
		(net "GND")
	)
	(segment
		(start 287.099756 -290.199826)
		(end 287.574736 -289.724846)
		(width 0.249936)
		(layer "F.Cu")
		(net "GND")
	)
	(segment
		(start 286.541718 -26.606246)
		(end 286.541718 -25.971246)
		(width 0.4572)
		(layer "F.Cu")
		(net "GND")
	)
	(segment
		(start 303.974754 -48.753014)
		(end 303.268126 -48.753014)
		(width 0.254)
		(layer "F.Cu")
		(net "GND")
	)
	(segment
		(start 281.874722 -305.874928)
		(end 282.349702 -306.349908)
		(width 0.249936)
		(layer "F.Cu")
		(net "GND")
	)
	(segment
		(start 183.3499 -292.099746)
		(end 183.82488 -291.624766)
		(width 0.249936)
		(layer "F.Cu")
		(net "GND")
	)
	(segment
		(start 57.274968 -300.174914)
		(end 56.799988 -299.699934)
		(width 0.249936)
		(layer "F.Cu")
		(net "GND")
	)
	(segment
		(start 69.684138 -124.000514)
		(end 69.318632 -123.635008)
		(width 0.3556)
		(layer "F.Cu")
		(net "GND")
	)
	(segment
		(start 387.050026 -290.199826)
		(end 386.575046 -289.724846)
		(width 0.249936)
		(layer "F.Cu")
		(net "GND")
	)
	(segment
		(start 38.706044 -161.276284)
		(end 39.00805 -160.974278)
		(width 0.4572)
		(layer "F.Cu")
		(net "GND")
	)
	(segment
		(start 405.63419 -140.97)
		(end 405.32304 -140.97)
		(width 0.4572)
		(layer "F.Cu")
		(net "GND")
	)
	(segment
		(start 349.099632 -284.42412)
		(end 348.732348 -284.42412)
		(width 0.2286)
		(layer "F.Cu")
		(net "GND")
	)
	(segment
		(start 402.249894 -296.8498)
		(end 401.774914 -297.32478)
		(width 0.249936)
		(layer "F.Cu")
		(net "GND")
	)
	(segment
		(start 295.174924 -291.624766)
		(end 294.69969 -292.099746)
		(width 0.249936)
		(layer "F.Cu")
		(net "GND")
	)
	(segment
		(start 175.749966 -290.199826)
		(end 176.224946 -289.724846)
		(width 0.249936)
		(layer "F.Cu")
		(net "GND")
	)
	(segment
		(start 282.824936 -291.624766)
		(end 282.349702 -291.149786)
		(width 0.249936)
		(layer "F.Cu")
		(net "GND")
	)
	(segment
		(start 315.893958 -35.499548)
		(end 316.266322 -35.871912)
		(width 0.4572)
		(layer "F.Cu")
		(net "GND")
	)
	(segment
		(start 387.999986 -283.549852)
		(end 387.525006 -283.074872)
		(width 0.249936)
		(layer "F.Cu")
		(net "GND")
	)
	(segment
		(start 279.024842 -304.924714)
		(end 278.549862 -304.449734)
		(width 0.249936)
		(layer "F.Cu")
		(net "GND")
	)
	(segment
		(start 394.64996 -302.549814)
		(end 395.12494 -302.074834)
		(width 0.249936)
		(layer "F.Cu")
		(net "GND")
	)
	(segment
		(start 187.149994 -298.74972)
		(end 187.624974 -298.27474)
		(width 0.249936)
		(layer "F.Cu")
		(net "GND")
	)
	(segment
		(start 188.099954 -302.549814)
		(end 188.574934 -303.024794)
		(width 0.249936)
		(layer "F.Cu")
		(net "GND")
	)
	(segment
		(start 80.07477 -300.174914)
		(end 80.54975 -300.649894)
		(width 0.249936)
		(layer "F.Cu")
		(net "GND")
	)
	(segment
		(start 115.200176 -120.093486)
		(end 114.590576 -120.093486)
		(width 0.4572)
		(layer "F.Cu")
		(net "GND")
	)
	(segment
		(start 421.724836 -297.32478)
		(end 421.249856 -296.8498)
		(width 0.249936)
		(layer "F.Cu")
		(net "GND")
	)
	(segment
		(start 185.250074 -297.79976)
		(end 184.77484 -298.27474)
		(width 0.249936)
		(layer "F.Cu")
		(net "GND")
	)
	(segment
		(start 9.71042 -121.661428)
		(end 9.0551 -121.661428)
		(width 0.4064)
		(layer "F.Cu")
		(net "GND")
	)
	(segment
		(start 61.549788 -285.449772)
		(end 62.024768 -285.924752)
		(width 0.249936)
		(layer "F.Cu")
		(net "GND")
	)
	(segment
		(start 58.699908 -283.549852)
		(end 58.224928 -283.074872)
		(width 0.249936)
		(layer "F.Cu")
		(net "GND")
	)
	(segment
		(start 416.499802 -286.399732)
		(end 416.974782 -286.874966)
		(width 0.249936)
		(layer "F.Cu")
		(net "GND")
	)
	(segment
		(start 285.674816 -305.874928)
		(end 285.199836 -305.399948)
		(width 0.249936)
		(layer "F.Cu")
		(net "GND")
	)
	(segment
		(start 392.749786 -295.89984)
		(end 392.274806 -296.37482)
		(width 0.249936)
		(layer "F.Cu")
		(net "GND")
	)
	(segment
		(start 301.824898 -296.37482)
		(end 301.349918 -296.8498)
		(width 0.249936)
		(layer "F.Cu")
		(net "GND")
	)
	(segment
		(start 399.93316 -131.76504)
		(end 398.94256 -131.76504)
		(width 0.3556)
		(layer "F.Cu")
		(net "GND")
	)
	(segment
		(start 314.649866 -303.484534)
		(end 315.109606 -303.024794)
		(width 0.254)
		(layer "F.Cu")
		(net "GND")
	)
	(segment
		(start 357.495094 -59.978036)
		(end 357.495094 -60.633356)
		(width 0.4572)
		(layer "F.Cu")
		(net "GND")
	)
	(segment
		(start 298.974764 -285.924752)
		(end 299.449744 -285.449772)
		(width 0.249936)
		(layer "F.Cu")
		(net "GND")
	)
	(segment
		(start 424.09999 -290.199826)
		(end 424.57497 -289.724846)
		(width 0.249936)
		(layer "F.Cu")
		(net "GND")
	)
	(segment
		(start 199.651874 -142.250922)
		(end 199.30491 -142.597886)
		(width 0.4064)
		(layer "F.Cu")
		(net "GND")
	)
	(segment
		(start 281.157934 -131.76504)
		(end 282.842462 -131.76504)
		(width 0.3556)
		(layer "F.Cu")
		(net "GND")
	)
	(segment
		(start 452.7804 -222.377)
		(end 452.623936 -222.533464)
		(width 0.2794)
		(layer "F.Cu")
		(net "GND")
	)
	(segment
		(start 248.07164 -212.088222)
		(end 248.06529 -212.094572)
		(width 0.4572)
		(layer "F.Cu")
		(net "GND")
	)
	(segment
		(start 58.224928 -284.974792)
		(end 57.749948 -285.449772)
		(width 0.249936)
		(layer "F.Cu")
		(net "GND")
	)
	(segment
		(start 63.924942 -303.974754)
		(end 64.399922 -303.499774)
		(width 0.249936)
		(layer "F.Cu")
		(net "GND")
	)
	(segment
		(start 286.624776 -287.824926)
		(end 286.149796 -288.299906)
		(width 0.249936)
		(layer "F.Cu")
		(net "GND")
	)
	(segment
		(start 28.26258 -34.29762)
		(end 27.827732 -34.732468)
		(width 0.4572)
		(layer "F.Cu")
		(net "GND")
	)
	(segment
		(start 342.093804 -217.587068)
		(end 341.694008 -217.187272)
		(width 0.381)
		(layer "F.Cu")
		(net "GND")
	)
	(segment
		(start 71.049896 -296.8498)
		(end 71.524876 -296.37482)
		(width 0.249936)
		(layer "F.Cu")
		(net "GND")
	)
	(segment
		(start 270.949928 -281.649932)
		(end 270.474948 -281.174952)
		(width 0.249936)
		(layer "F.Cu")
		(net "GND")
	)
	(segment
		(start 416.024822 -285.924752)
		(end 416.499802 -286.399732)
		(width 0.249936)
		(layer "F.Cu")
		(net "GND")
	)
	(segment
		(start 187.149994 -288.299906)
		(end 186.675014 -287.824926)
		(width 0.249936)
		(layer "F.Cu")
		(net "GND")
	)
	(segment
		(start 406.999948 -293.99992)
		(end 406.524968 -293.52494)
		(width 0.249936)
		(layer "F.Cu")
		(net "GND")
	)
	(segment
		(start 166.725092 -298.27474)
		(end 166.249858 -298.74972)
		(width 0.249936)
		(layer "F.Cu")
		(net "GND")
	)
	(segment
		(start 172.900086 -306.349908)
		(end 172.424852 -305.874928)
		(width 0.249936)
		(layer "F.Cu")
		(net "GND")
	)
	(segment
		(start 73.424796 -299.224954)
		(end 73.899776 -299.699934)
		(width 0.249936)
		(layer "F.Cu")
		(net "GND")
	)
	(segment
		(start 286.624776 -289.724846)
		(end 287.099756 -290.199826)
		(width 0.249936)
		(layer "F.Cu")
		(net "GND")
	)
	(segment
		(start 30.438344 -252.756924)
		(end 30.438344 -253.45644)
		(width 0.4572)
		(layer "F.Cu")
		(net "GND")
	)
	(segment
		(start 122.589544 -62.812168)
		(end 123.400058 -62.812168)
		(width 0.4572)
		(layer "F.Cu")
		(net "GND")
	)
	(segment
		(start 230.66756 -219.904056)
		(end 231.067356 -220.303852)
		(width 0.381)
		(layer "F.Cu")
		(net "GND")
	)
	(segment
		(start 403.674834 -291.624766)
		(end 404.149814 -292.099746)
		(width 0.249936)
		(layer "F.Cu")
		(net "GND")
	)
	(segment
		(start 422.199816 -305.399694)
		(end 421.724836 -304.924714)
		(width 0.249936)
		(layer "F.Cu")
		(net "GND")
	)
	(segment
		(start 425.99991 -291.149786)
		(end 426.47489 -291.624766)
		(width 0.249936)
		(layer "F.Cu")
		(net "GND")
	)
	(segment
		(start 60.124848 -305.874928)
		(end 59.649868 -306.349908)
		(width 0.249936)
		(layer "F.Cu")
		(net "GND")
	)
	(segment
		(start 282.066746 -107.845098)
		(end 282.842462 -107.845098)
		(width 0.3556)
		(layer "F.Cu")
		(net "GND")
	)
	(segment
		(start 153.89987 -294.94988)
		(end 153.42489 -294.4749)
		(width 0.249936)
		(layer "F.Cu")
		(net "GND")
	)
	(segment
		(start 162.450018 -289.249866)
		(end 161.975038 -288.774886)
		(width 0.249936)
		(layer "F.Cu")
		(net "GND")
	)
	(segment
		(start 188.383164 -154.461718)
		(end 188.676534 -154.755088)
		(width 0.3556)
		(layer "F.Cu")
		(net "GND")
	)
	(segment
		(start 285.199836 -290.199826)
		(end 285.674816 -289.724846)
		(width 0.249936)
		(layer "F.Cu")
		(net "GND")
	)
	(segment
		(start 414.599882 -305.399948)
		(end 414.124902 -305.874928)
		(width 0.249936)
		(layer "F.Cu")
		(net "GND")
	)
	(segment
		(start 320.452242 -113.661444)
		(end 320.452242 -114.384836)
		(width 0.4572)
		(layer "F.Cu")
		(net "GND")
	)
	(segment
		(start 179.63642 -31.390082)
		(end 179.888642 -31.642304)
		(width 0.3556)
		(layer "F.Cu")
		(net "GND")
	)
	(segment
		(start 172.900086 -299.699934)
		(end 172.424852 -300.174914)
		(width 0.249936)
		(layer "F.Cu")
		(net "GND")
	)
	(segment
		(start 23.737824 -165.6715)
		(end 23.737824 -165.058852)
		(width 0.4572)
		(layer "F.Cu")
		(net "GND")
	)
	(segment
		(start 184.77484 -305.874928)
		(end 185.250074 -305.399948)
		(width 0.249936)
		(layer "F.Cu")
		(net "GND")
	)
	(segment
		(start 184.77484 -293.52494)
		(end 184.29986 -293.99992)
		(width 0.249936)
		(layer "F.Cu")
		(net "GND")
	)
	(segment
		(start 175.749966 -286.399732)
		(end 176.224946 -285.924752)
		(width 0.249936)
		(layer "F.Cu")
		(net "GND")
	)
	(segment
		(start 297.549824 -299.699934)
		(end 298.024804 -300.174914)
		(width 0.249936)
		(layer "F.Cu")
		(net "GND")
	)
	(segment
		(start 40.24884 -33.19018)
		(end 41.26484 -33.19018)
		(width 0.3556)
		(layer "F.Cu")
		(net "GND")
	)
	(segment
		(start 399.93316 -125.955044)
		(end 398.94256 -125.955044)
		(width 0.3556)
		(layer "F.Cu")
		(net "GND")
	)
	(segment
		(start 412.699962 -284.499812)
		(end 413.174942 -284.974792)
		(width 0.249936)
		(layer "F.Cu")
		(net "GND")
	)
	(segment
		(start 408.899868 -305.399948)
		(end 408.424888 -305.874928)
		(width 0.249936)
		(layer "F.Cu")
		(net "GND")
	)
	(segment
		(start 275.699728 -278.799798)
		(end 275.224748 -279.274778)
		(width 0.249936)
		(layer "F.Cu")
		(net "GND")
	)
	(segment
		(start 163.399978 -305.399948)
		(end 162.924998 -304.924714)
		(width 0.249936)
		(layer "F.Cu")
		(net "GND")
	)
	(segment
		(start 312.274712 -296.37482)
		(end 312.749692 -296.8498)
		(width 0.249936)
		(layer "F.Cu")
		(net "GND")
	)
	(segment
		(start 392.749786 -291.149786)
		(end 392.274806 -290.674806)
		(width 0.249936)
		(layer "F.Cu")
		(net "GND")
	)
	(segment
		(start 16.252952 -159.573468)
		(end 16.89354 -159.573468)
		(width 0.4572)
		(layer "F.Cu")
		(net "GND")
	)
	(segment
		(start 298.974764 -302.074834)
		(end 299.449744 -301.599854)
		(width 0.249936)
		(layer "F.Cu")
		(net "GND")
	)
	(segment
		(start 417.450016 -296.8498)
		(end 417.924996 -297.32478)
		(width 0.249936)
		(layer "F.Cu")
		(net "GND")
	)
	(segment
		(start 144.441926 -26.606246)
		(end 144.441926 -25.971246)
		(width 0.4572)
		(layer "F.Cu")
		(net "GND")
	)
	(segment
		(start 274.480782 -34.990024)
		(end 273.464782 -34.990024)
		(width 0.3556)
		(layer "F.Cu")
		(net "GND")
	)
	(segment
		(start 215.246966 -52.592224)
		(end 215.32215 -52.51704)
		(width 0.254)
		(layer "F.Cu")
		(net "GND")
	)
	(segment
		(start 41.599866 -297.79976)
		(end 41.124886 -298.27474)
		(width 0.249936)
		(layer "F.Cu")
		(net "GND")
	)
	(segment
		(start 185.250074 -288.299906)
		(end 184.77484 -287.824926)
		(width 0.249936)
		(layer "F.Cu")
		(net "GND")
	)
	(segment
		(start 171.474892 -300.174914)
		(end 170.999912 -299.699934)
		(width 0.249936)
		(layer "F.Cu")
		(net "GND")
	)
	(segment
		(start 342.893904 -213.587076)
		(end 343.2937 -213.18728)
		(width 0.381)
		(layer "F.Cu")
		(net "GND")
	)
	(segment
		(start 293.27475 -296.37482)
		(end 293.74973 -296.8498)
		(width 0.249936)
		(layer "F.Cu")
		(net "GND")
	)
	(segment
		(start 405.100028 -306.349908)
		(end 405.575008 -306.824888)
		(width 0.249936)
		(layer "F.Cu")
		(net "GND")
	)
	(segment
		(start 374.3706 -110.428024)
		(end 377.1011 -113.158524)
		(width 0.4572)
		(layer "F.Cu")
		(net "GND")
	)
	(segment
		(start 397.97482 -303.974754)
		(end 398.4498 -303.499774)
		(width 0.249936)
		(layer "F.Cu")
		(net "GND")
	)
	(segment
		(start 176.150016 -287.899856)
		(end 176.224946 -287.899856)
		(width 0.249936)
		(layer "F.Cu")
		(net "GND")
	)
	(segment
		(start 171.949872 -305.399948)
		(end 171.474892 -305.874928)
		(width 0.249936)
		(layer "F.Cu")
		(net "GND")
	)
	(segment
		(start 54.424834 -306.824888)
		(end 53.949854 -307.299868)
		(width 0.249936)
		(layer "F.Cu")
		(net "GND")
	)
	(segment
		(start 189.524894 -294.4749)
		(end 189.999874 -293.99992)
		(width 0.249936)
		(layer "F.Cu")
		(net "GND")
	)
	(segment
		(start 403.674834 -284.974792)
		(end 403.199854 -285.449772)
		(width 0.249936)
		(layer "F.Cu")
		(net "GND")
	)
	(segment
		(start 410.799788 -285.449772)
		(end 410.324808 -284.974792)
		(width 0.249936)
		(layer "F.Cu")
		(net "GND")
	)
	(segment
		(start 288.524696 -303.974754)
		(end 288.99993 -303.499774)
		(width 0.249936)
		(layer "F.Cu")
		(net "GND")
	)
	(segment
		(start 339.693758 -222.38716)
		(end 339.293962 -222.786956)
		(width 0.381)
		(layer "F.Cu")
		(net "GND")
	)
	(segment
		(start 93.264736 -29.589984)
		(end 94.280736 -29.589984)
		(width 0.3556)
		(layer "F.Cu")
		(net "GND")
	)
	(segment
		(start 68.199762 -292.099746)
		(end 68.674742 -291.624766)
		(width 0.249936)
		(layer "F.Cu")
		(net "GND")
	)
	(segment
		(start 117.1702 -285.263336)
		(end 117.395498 -285.488634)
		(width 0.2286)
		(layer "F.Cu")
		(net "GND")
	)
	(segment
		(start 395.12494 -298.27474)
		(end 394.64996 -297.79976)
		(width 0.249936)
		(layer "F.Cu")
		(net "GND")
	)
	(segment
		(start 170.524932 -302.074834)
		(end 170.999912 -301.599854)
		(width 0.249936)
		(layer "F.Cu")
		(net "GND")
	)
	(segment
		(start 400.349974 -305.399948)
		(end 399.874994 -305.874928)
		(width 0.249936)
		(layer "F.Cu")
		(net "GND")
	)
	(segment
		(start 187.624974 -301.124874)
		(end 187.149994 -301.599854)
		(width 0.249936)
		(layer "F.Cu")
		(net "GND")
	)
	(segment
		(start 150.85949 -384.762248)
		(end 151.93264 -383.689098)
		(width 0.4572)
		(layer "F.Cu")
		(net "GND")
	)
	(segment
		(start 382.440942 -54.163722)
		(end 382.992884 -54.163722)
		(width 0.254)
		(layer "F.Cu")
		(net "GND")
	)
	(segment
		(start 163.161218 -38.701218)
		(end 163.919662 -38.701218)
		(width 0.4572)
		(layer "F.Cu")
		(net "GND")
	)
	(segment
		(start 185.725054 -285.924752)
		(end 185.250074 -285.449772)
		(width 0.249936)
		(layer "F.Cu")
		(net "GND")
	)
	(segment
		(start 419.67023 -47.60087)
		(end 420.096188 -47.60087)
		(width 0.254)
		(layer "F.Cu")
		(net "GND")
	)
	(segment
		(start 134.054596 -285.488634)
		(end 133.765798 -285.199836)
		(width 0.2286)
		(layer "F.Cu")
		(net "GND")
	)
	(segment
		(start 300.874684 -293.52494)
		(end 300.399704 -293.99992)
		(width 0.249936)
		(layer "F.Cu")
		(net "GND")
	)
	(segment
		(start 176.699926 -285.449772)
		(end 176.224946 -284.974792)
		(width 0.254)
		(layer "F.Cu")
		(net "GND")
	)
	(segment
		(start 393.351766 -106.045)
		(end 394.342366 -106.045)
		(width 0.3556)
		(layer "F.Cu")
		(net "GND")
	)
	(segment
		(start 377.1011 -113.158524)
		(end 380.61773 -113.158524)
		(width 0.4572)
		(layer "F.Cu")
		(net "GND")
	)
	(segment
		(start 279.024842 -298.27474)
		(end 278.549862 -298.74972)
		(width 0.249936)
		(layer "F.Cu")
		(net "GND")
	)
	(segment
		(start 387.999986 -281.649932)
		(end 387.525006 -281.174952)
		(width 0.249936)
		(layer "F.Cu")
		(net "GND")
	)
	(segment
		(start 298.44873 -27.79014)
		(end 299.46473 -27.79014)
		(width 0.3556)
		(layer "F.Cu")
		(net "GND")
	)
	(segment
		(start 161.975038 -296.37482)
		(end 162.450018 -295.89984)
		(width 0.249936)
		(layer "F.Cu")
		(net "GND")
	)
	(segment
		(start 303.724818 -302.074834)
		(end 303.249838 -302.549814)
		(width 0.249936)
		(layer "F.Cu")
		(net "GND")
	)
	(segment
		(start 289.47491 -302.074834)
		(end 289.94989 -301.599854)
		(width 0.249936)
		(layer "F.Cu")
		(net "GND")
	)
	(segment
		(start 182.39994 -297.79976)
		(end 182.87492 -298.27474)
		(width 0.249936)
		(layer "F.Cu")
		(net "GND")
	)
	(segment
		(start 400.824954 -284.974792)
		(end 401.299934 -284.499812)
		(width 0.249936)
		(layer "F.Cu")
		(net "GND")
	)
	(segment
		(start 59.649868 -292.099746)
		(end 60.124848 -291.624766)
		(width 0.249936)
		(layer "F.Cu")
		(net "GND")
	)
	(segment
		(start 415.074862 -293.52494)
		(end 414.599882 -293.99992)
		(width 0.249936)
		(layer "F.Cu")
		(net "GND")
	)
	(segment
		(start 398.276318 -106.045)
		(end 398.94256 -106.045)
		(width 0.3556)
		(layer "F.Cu")
		(net "GND")
	)
	(segment
		(start 409.72994 -171.661328)
		(end 409.72994 -172.329348)
		(width 0.4572)
		(layer "F.Cu")
		(net "GND")
	)
	(segment
		(start 394.64996 -287.349946)
		(end 394.17498 -286.874966)
		(width 0.249936)
		(layer "F.Cu")
		(net "GND")
	)
	(segment
		(start 394.64996 -302.549814)
		(end 394.17498 -302.074834)
		(width 0.249936)
		(layer "F.Cu")
		(net "GND")
	)
	(segment
		(start 192.375028 -294.4749)
		(end 191.900048 -293.99992)
		(width 0.249936)
		(layer "F.Cu")
		(net "GND")
	)
	(segment
		(start 186.675014 -307.774848)
		(end 187.149994 -307.299868)
		(width 0.249936)
		(layer "F.Cu")
		(net "GND")
	)
	(segment
		(start 54.262528 -34.29762)
		(end 54.27091 -34.29762)
		(width 0.4572)
		(layer "F.Cu")
		(net "GND")
	)
	(segment
		(start 247.741186 -114.436652)
		(end 247.31853 -114.013996)
		(width 0.254)
		(layer "F.Cu")
		(net "GND")
	)
	(segment
		(start 171.474892 -284.974792)
		(end 171.949872 -284.499812)
		(width 0.249936)
		(layer "F.Cu")
		(net "GND")
	)
	(segment
		(start 410.52877 -208.695544)
		(end 410.52877 -209.39887)
		(width 0.4572)
		(layer "F.Cu")
		(net "GND")
	)
	(segment
		(start 301.518574 -121.83491)
		(end 300.857412 -121.83491)
		(width 0.3556)
		(layer "F.Cu")
		(net "GND")
	)
	(segment
		(start 64.874902 -303.974754)
		(end 64.399922 -303.499774)
		(width 0.249936)
		(layer "F.Cu")
		(net "GND")
	)
	(segment
		(start 390.849866 -285.449772)
		(end 391.324846 -284.974792)
		(width 0.249936)
		(layer "F.Cu")
		(net "GND")
	)
	(segment
		(start 191.900048 -297.79976)
		(end 192.375028 -297.32478)
		(width 0.249936)
		(layer "F.Cu")
		(net "GND")
	)
	(segment
		(start 260.468364 -348.796864)
		(end 259.492242 -348.796864)
		(width 0.4572)
		(layer "F.Cu")
		(net "GND")
	)
	(segment
		(start 279.024842 -293.52494)
		(end 278.549862 -293.04996)
		(width 0.254)
		(layer "F.Cu")
		(net "GND")
	)
	(segment
		(start 58.224928 -296.37482)
		(end 57.749948 -296.8498)
		(width 0.249936)
		(layer "F.Cu")
		(net "GND")
	)
	(segment
		(start 454.727056 -365.953548)
		(end 455.669904 -365.953548)
		(width 0.4572)
		(layer "F.Cu")
		(net "GND")
	)
	(segment
		(start 248.452894 -159.573468)
		(end 249.093482 -159.573468)
		(width 0.4572)
		(layer "F.Cu")
		(net "GND")
	)
	(segment
		(start 350.647 -162.57905)
		(end 351.38995 -162.57905)
		(width 0.4572)
		(layer "F.Cu")
		(net "GND")
	)
	(segment
		(start 297.549824 -285.449772)
		(end 298.024804 -284.974792)
		(width 0.249936)
		(layer "F.Cu")
		(net "GND")
	)
	(segment
		(start 394.64996 -301.599854)
		(end 394.17498 -301.124874)
		(width 0.249936)
		(layer "F.Cu")
		(net "GND")
	)
	(segment
		(start 311.860438 -16.439388)
		(end 311.936638 -16.363188)
		(width 0.4572)
		(layer "F.Cu")
		(net "GND")
	)
	(segment
		(start 234.027726 -34.732468)
		(end 233.795316 -34.732468)
		(width 0.4572)
		(layer "F.Cu")
		(net "GND")
	)
	(segment
		(start 298.024804 -307.774848)
		(end 298.499784 -307.299868)
		(width 0.249936)
		(layer "F.Cu")
		(net "GND")
	)
	(segment
		(start 387.525006 -298.27474)
		(end 387.050026 -298.74972)
		(width 0.249936)
		(layer "F.Cu")
		(net "GND")
	)
	(segment
		(start 283.833062 -131.76504)
		(end 282.842462 -131.76504)
		(width 0.3556)
		(layer "F.Cu")
		(net "GND")
	)
	(segment
		(start 298.974764 -306.824888)
		(end 299.449744 -306.349908)
		(width 0.249936)
		(layer "F.Cu")
		(net "GND")
	)
	(segment
		(start 8.140954 -54.163722)
		(end 8.692896 -54.163722)
		(width 0.254)
		(layer "F.Cu")
		(net "GND")
	)
	(segment
		(start 163.874958 -297.32478)
		(end 163.399978 -297.79976)
		(width 0.249936)
		(layer "F.Cu")
		(net "GND")
	)
	(segment
		(start 297.074844 -296.37482)
		(end 296.599864 -295.89984)
		(width 0.249936)
		(layer "F.Cu")
		(net "GND")
	)
	(segment
		(start 111.274098 -161.172144)
		(end 112.247934 -161.172144)
		(width 0.1778)
		(layer "F.Cu")
		(net "GND")
	)
	(segment
		(start 189.999874 -291.149786)
		(end 189.524894 -290.674806)
		(width 0.249936)
		(layer "F.Cu")
		(net "GND")
	)
	(segment
		(start 241.02949 -211.666328)
		(end 241.02949 -212.2932)
		(width 0.4572)
		(layer "F.Cu")
		(net "GND")
	)
	(segment
		(start 196.649848 -291.149786)
		(end 197.125082 -291.624766)
		(width 0.249936)
		(layer "F.Cu")
		(net "GND")
	)
	(segment
		(start 41.26484 -25.990042)
		(end 42.28084 -25.990042)
		(width 0.3556)
		(layer "F.Cu")
		(net "GND")
	)
	(segment
		(start 289.94989 -285.449772)
		(end 289.47491 -285.924752)
		(width 0.249936)
		(layer "F.Cu")
		(net "GND")
	)
	(segment
		(start 71.524876 -297.32478)
		(end 71.049896 -296.8498)
		(width 0.249936)
		(layer "F.Cu")
		(net "GND")
	)
	(segment
		(start 235.056172 -172.15993)
		(end 235.722922 -172.15993)
		(width 0.4572)
		(layer "F.Cu")
		(net "GND")
	)
	(segment
		(start 290.89985 -297.79976)
		(end 290.42487 -298.27474)
		(width 0.249936)
		(layer "F.Cu")
		(net "GND")
	)
	(segment
		(start 57.749948 -306.349908)
		(end 58.224928 -306.824888)
		(width 0.249936)
		(layer "F.Cu")
		(net "GND")
	)
	(segment
		(start 387.050026 -276.899878)
		(end 386.575046 -276.424898)
		(width 0.249936)
		(layer "F.Cu")
		(net "GND")
	)
	(segment
		(start 292.79977 -285.449772)
		(end 292.32479 -285.924752)
		(width 0.249936)
		(layer "F.Cu")
		(net "GND")
	)
	(segment
		(start 73.424796 -293.52494)
		(end 72.949816 -293.99992)
		(width 0.249936)
		(layer "F.Cu")
		(net "GND")
	)
	(segment
		(start 322.255896 -33.19018)
		(end 320.864738 -33.19018)
		(width 0.3556)
		(layer "F.Cu")
		(net "GND")
	)
	(segment
		(start 56.325008 -296.37482)
		(end 55.850028 -296.8498)
		(width 0.249936)
		(layer "F.Cu")
		(net "GND")
	)
	(segment
		(start 237.524798 -83.951318)
		(end 236.826552 -83.951318)
		(width 0.4572)
		(layer "F.Cu")
		(net "GND")
	)
	(segment
		(start 414.548828 -27.79014)
		(end 415.564828 -27.79014)
		(width 0.3556)
		(layer "F.Cu")
		(net "GND")
	)
	(segment
		(start 185.250074 -292.099746)
		(end 184.77484 -292.574726)
		(width 0.249936)
		(layer "F.Cu")
		(net "GND")
	)
	(segment
		(start 415.549842 -285.449772)
		(end 415.074862 -284.974792)
		(width 0.249936)
		(layer "F.Cu")
		(net "GND")
	)
	(segment
		(start 71.524876 -296.37482)
		(end 71.049896 -295.89984)
		(width 0.249936)
		(layer "F.Cu")
		(net "GND")
	)
	(segment
		(start 48.72482 -298.27474)
		(end 48.24984 -298.74972)
		(width 0.249936)
		(layer "F.Cu")
		(net "GND")
	)
	(segment
		(start 171.949872 -284.499812)
		(end 172.424852 -284.974792)
		(width 0.249936)
		(layer "F.Cu")
		(net "GND")
	)
	(segment
		(start 165.299898 -306.349908)
		(end 164.824918 -305.874928)
		(width 0.249936)
		(layer "F.Cu")
		(net "GND")
	)
	(segment
		(start 288.049716 -306.349908)
		(end 287.574736 -305.874928)
		(width 0.249936)
		(layer "F.Cu")
		(net "GND")
	)
	(segment
		(start 298.024804 -284.974792)
		(end 297.549824 -284.499812)
		(width 0.249936)
		(layer "F.Cu")
		(net "GND")
	)
	(segment
		(start 407.949908 -303.499774)
		(end 408.424888 -303.974754)
		(width 0.249936)
		(layer "F.Cu")
		(net "GND")
	)
	(segment
		(start 171.949872 -285.449772)
		(end 172.424852 -285.924752)
		(width 0.249936)
		(layer "F.Cu")
		(net "GND")
	)
	(segment
		(start 173.850046 -307.299868)
		(end 174.325026 -306.824888)
		(width 0.249936)
		(layer "F.Cu")
		(net "GND")
	)
	(segment
		(start 38.749986 -274.999958)
		(end 38.275006 -274.524978)
		(width 0.249936)
		(layer "F.Cu")
		(net "GND")
	)
	(segment
		(start 410.932122 -167.922702)
		(end 410.932122 -168.94556)
		(width 0.4572)
		(layer "F.Cu")
		(net "GND")
	)
	(segment
		(start 422.674796 -292.574726)
		(end 422.199816 -292.099746)
		(width 0.249936)
		(layer "F.Cu")
		(net "GND")
	)
	(segment
		(start 270.949928 -283.549852)
		(end 270.474948 -283.074872)
		(width 0.249936)
		(layer "F.Cu")
		(net "GND")
	)
	(segment
		(start 214.90051 -209.983832)
		(end 215.176608 -209.707734)
		(width 0.254)
		(layer "F.Cu")
		(net "GND")
	)
	(segment
		(start 396.0749 -307.774848)
		(end 395.59992 -308.249828)
		(width 0.249936)
		(layer "F.Cu")
		(net "GND")
	)
	(segment
		(start 109.01299 -110.785656)
		(end 109.80674 -110.785656)
		(width 0.254)
		(layer "F.Cu")
		(net "GND")
	)
	(segment
		(start 405.100028 -292.099746)
		(end 405.575008 -291.624766)
		(width 0.249936)
		(layer "F.Cu")
		(net "GND")
	)
	(segment
		(start 249.711718 -146.263614)
		(end 249.711718 -145.837656)
		(width 0.4064)
		(layer "F.Cu")
		(net "GND")
	)
	(segment
		(start 44.449746 -299.699934)
		(end 43.974766 -300.174914)
		(width 0.249936)
		(layer "F.Cu")
		(net "GND")
	)
	(segment
		(start 242.569492 -222.05696)
		(end 242.09883 -222.05696)
		(width 0.4572)
		(layer "F.Cu")
		(net "GND")
	)
	(segment
		(start 61.074808 -287.824926)
		(end 60.599828 -288.299906)
		(width 0.249936)
		(layer "F.Cu")
		(net "GND")
	)
	(segment
		(start 295.649904 -285.449772)
		(end 295.174924 -285.924752)
		(width 0.249936)
		(layer "F.Cu")
		(net "GND")
	)
	(segment
		(start 408.899868 -307.299868)
		(end 408.424888 -306.824888)
		(width 0.249936)
		(layer "F.Cu")
		(net "GND")
	)
	(segment
		(start 397.49984 -284.499812)
		(end 397.02486 -284.024832)
		(width 0.249936)
		(layer "F.Cu")
		(net "GND")
	)
	(segment
		(start 417.980368 -156.554932)
		(end 416.95751 -156.554932)
		(width 0.3556)
		(layer "F.Cu")
		(net "GND")
	)
	(segment
		(start 180.02504 -297.32478)
		(end 179.55006 -296.8498)
		(width 0.249936)
		(layer "F.Cu")
		(net "GND")
	)
	(segment
		(start 141.877796 -187.593732)
		(end 142.14475 -187.860686)
		(width 0.4572)
		(layer "F.Cu")
		(net "GND")
	)
	(segment
		(start 417.450016 -303.499774)
		(end 417.924996 -303.974754)
		(width 0.249936)
		(layer "F.Cu")
		(net "GND")
	)
	(segment
		(start 64.399922 -285.449772)
		(end 63.924942 -285.924752)
		(width 0.249936)
		(layer "F.Cu")
		(net "GND")
	)
	(segment
		(start 300.399704 -303.499774)
		(end 300.869858 -303.969928)
		(width 0.249936)
		(layer "F.Cu")
		(net "GND")
	)
	(segment
		(start 427.42485 -294.4749)
		(end 426.94987 -294.94988)
		(width 0.249936)
		(layer "F.Cu")
		(net "GND")
	)
	(segment
		(start 280.924762 -293.52494)
		(end 280.449782 -293.04996)
		(width 0.249936)
		(layer "F.Cu")
		(net "GND")
	)
	(segment
		(start 412.224982 -305.874928)
		(end 411.750002 -306.349908)
		(width 0.249936)
		(layer "F.Cu")
		(net "GND")
	)
	(segment
		(start 179.07508 -285.924752)
		(end 178.599846 -285.449772)
		(width 0.249936)
		(layer "F.Cu")
		(net "GND")
	)
	(segment
		(start 192.850008 -302.549814)
		(end 191.900048 -301.599854)
		(width 0.249936)
		(layer "F.Cu")
		(net "GND")
	)
	(segment
		(start 284.867096 -56.354218)
		(end 284.867858 -56.353456)
		(width 0.4572)
		(layer "F.Cu")
		(net "GND")
	)
	(segment
		(start 198.075042 -291.624766)
		(end 198.550022 -292.099746)
		(width 0.249936)
		(layer "F.Cu")
		(net "GND")
	)
	(segment
		(start 278.549862 -287.349946)
		(end 278.074882 -286.874966)
		(width 0.249936)
		(layer "F.Cu")
		(net "GND")
	)
	(segment
		(start 303.249838 -286.399732)
		(end 302.774858 -286.874966)
		(width 0.249936)
		(layer "F.Cu")
		(net "GND")
	)
	(segment
		(start 165.774878 -299.224954)
		(end 166.249858 -298.74972)
		(width 0.249936)
		(layer "F.Cu")
		(net "GND")
	)
	(segment
		(start 389.899906 -294.94988)
		(end 389.424926 -294.4749)
		(width 0.249936)
		(layer "F.Cu")
		(net "GND")
	)
	(segment
		(start 247.431306 -126.94666)
		(end 247.356122 -127.021844)
		(width 0.254)
		(layer "F.Cu")
		(net "GND")
	)
	(segment
		(start 263.615678 -309.287672)
		(end 262.987536 -308.65953)
		(width 0.4572)
		(layer "F.Cu")
		(net "GND")
	)
	(segment
		(start 301.824898 -293.52494)
		(end 301.349918 -293.99992)
		(width 0.249936)
		(layer "F.Cu")
		(net "GND")
	)
	(segment
		(start 404.624794 -305.874928)
		(end 405.100028 -305.399948)
		(width 0.249936)
		(layer "F.Cu")
		(net "GND")
	)
	(segment
		(start 350.14027 -33.248092)
		(end 350.14027 -33.857692)
		(width 0.4572)
		(layer "F.Cu")
		(net "GND")
	)
	(segment
		(start 140.347954 -213.712552)
		(end 140.217906 -213.8426)
		(width 0.4572)
		(layer "F.Cu")
		(net "GND")
	)
	(segment
		(start 410.775404 -391.88644)
		(end 410.04744 -391.88644)
		(width 0.4572)
		(layer "F.Cu")
		(net "GND")
	)
	(segment
		(start 50.624994 -287.824926)
		(end 51.099974 -288.299906)
		(width 0.249936)
		(layer "F.Cu")
		(net "GND")
	)
	(segment
		(start 331.645768 -46.693836)
		(end 331.118464 -46.693836)
		(width 0.254)
		(layer "F.Cu")
		(net "GND")
	)
	(segment
		(start 197.868794 -366.33658)
		(end 198.167244 -366.63503)
		(width 0.254)
		(layer "F.Cu")
		(net "GND")
	)
	(segment
		(start 61.074808 -289.724846)
		(end 60.599828 -290.199826)
		(width 0.249936)
		(layer "F.Cu")
		(net "GND")
	)
	(segment
		(start 166.7891 -175.855376)
		(end 166.663878 -175.730154)
		(width 0.381)
		(layer "F.Cu")
		(net "GND")
	)
	(segment
		(start 167.675052 -303.974754)
		(end 167.200072 -303.499774)
		(width 0.249936)
		(layer "F.Cu")
		(net "GND")
	)
	(segment
		(start 196.649848 -294.94988)
		(end 196.174868 -294.4749)
		(width 0.249936)
		(layer "F.Cu")
		(net "GND")
	)
	(segment
		(start 322.239386 -96.411542)
		(end 322.239386 -95.801942)
		(width 0.381)
		(layer "F.Cu")
		(net "GND")
	)
	(segment
		(start 78.64983 -293.99992)
		(end 79.12481 -294.4749)
		(width 0.249936)
		(layer "F.Cu")
		(net "GND")
	)
	(segment
		(start 54.424834 -283.074872)
		(end 54.899814 -283.549852)
		(width 0.249936)
		(layer "F.Cu")
		(net "GND")
	)
	(segment
		(start 174.69485 -102.798372)
		(end 174.079662 -102.798372)
		(width 0.4064)
		(layer "F.Cu")
		(net "GND")
	)
	(segment
		(start 400.123914 -168.229788)
		(end 400.2913 -168.397174)
		(width 0.4572)
		(layer "F.Cu")
		(net "GND")
	)
	(segment
		(start 57.749948 -306.349908)
		(end 58.224928 -305.874928)
		(width 0.249936)
		(layer "F.Cu")
		(net "GND")
	)
	(segment
		(start 303.249838 -292.1)
		(end 302.774858 -292.57498)
		(width 0.249936)
		(layer "F.Cu")
		(net "GND")
	)
	(segment
		(start 161.15157 -135.364982)
		(end 162.14217 -135.364982)
		(width 0.3556)
		(layer "F.Cu")
		(net "GND")
	)
	(segment
		(start 81.024984 -299.224954)
		(end 80.54975 -298.74972)
		(width 0.249936)
		(layer "F.Cu")
		(net "GND")
	)
	(segment
		(start 161.15157 -107.845098)
		(end 162.14217 -107.845098)
		(width 0.3556)
		(layer "F.Cu")
		(net "GND")
	)
	(segment
		(start 396.54988 -298.74972)
		(end 396.0749 -299.224954)
		(width 0.249936)
		(layer "F.Cu")
		(net "GND")
	)
	(segment
		(start 54.899814 -286.399732)
		(end 55.374794 -285.924752)
		(width 0.249936)
		(layer "F.Cu")
		(net "GND")
	)
	(segment
		(start 176.699926 -288.299906)
		(end 177.174906 -287.824926)
		(width 0.249936)
		(layer "F.Cu")
		(net "GND")
	)
	(segment
		(start 158.649924 -299.699934)
		(end 158.649924 -299.69968)
		(width 0.254)
		(layer "F.Cu")
		(net "GND")
	)
	(segment
		(start 290.508944 -27.04973)
		(end 289.849814 -27.04973)
		(width 0.4572)
		(layer "F.Cu")
		(net "GND")
	)
	(segment
		(start 144.467072 -306.083462)
		(end 144.640808 -306.083462)
		(width 0.4572)
		(layer "F.Cu")
		(net "GND")
	)
	(segment
		(start 131.331208 -126.394718)
		(end 131.331208 -126.94666)
		(width 0.2032)
		(layer "F.Cu")
		(net "GND")
	)
	(segment
		(start 197.125082 -300.174914)
		(end 197.600062 -299.699934)
		(width 0.249936)
		(layer "F.Cu")
		(net "GND")
	)
	(segment
		(start 98.918522 -46.693836)
		(end 98.719132 -46.893226)
		(width 0.254)
		(layer "F.Cu")
		(net "GND")
	)
	(segment
		(start 47.393606 -108.279946)
		(end 46.958758 -107.845098)
		(width 0.3556)
		(layer "F.Cu")
		(net "GND")
	)
	(segment
		(start 220.851222 -144.958562)
		(end 220.241622 -144.958562)
		(width 0.4572)
		(layer "F.Cu")
		(net "GND")
	)
	(segment
		(start 401.299934 -306.349908)
		(end 401.774914 -305.874928)
		(width 0.249936)
		(layer "F.Cu")
		(net "GND")
	)
	(segment
		(start 357.546148 -283.07411)
		(end 357.230934 -283.07411)
		(width 0.2286)
		(layer "F.Cu")
		(net "GND")
	)
	(segment
		(start 47.77486 -292.57498)
		(end 48.24984 -293.04996)
		(width 0.249936)
		(layer "F.Cu")
		(net "GND")
	)
	(segment
		(start 57.749948 -307.299868)
		(end 58.224928 -306.824888)
		(width 0.249936)
		(layer "F.Cu")
		(net "GND")
	)
	(segment
		(start 241.06632 -220.02496)
		(end 241.373914 -220.02496)
		(width 0.4572)
		(layer "F.Cu")
		(net "GND")
	)
	(segment
		(start 394.17498 -303.024794)
		(end 394.64996 -303.499774)
		(width 0.249936)
		(layer "F.Cu")
		(net "GND")
	)
	(segment
		(start 279.024842 -306.824888)
		(end 279.499822 -306.349908)
		(width 0.249936)
		(layer "F.Cu")
		(net "GND")
	)
	(segment
		(start 305.624738 -294.4749)
		(end 306.099718 -294.94988)
		(width 0.249936)
		(layer "F.Cu")
		(net "GND")
	)
	(segment
		(start 286.624776 -300.174914)
		(end 286.149796 -299.699934)
		(width 0.249936)
		(layer "F.Cu")
		(net "GND")
	)
	(segment
		(start 411.275022 -296.37482)
		(end 411.750002 -296.8498)
		(width 0.249936)
		(layer "F.Cu")
		(net "GND")
	)
	(segment
		(start 185.62828 -145.755106)
		(end 184.757314 -145.755106)
		(width 0.3556)
		(layer "F.Cu")
		(net "GND")
	)
	(segment
		(start 403.674834 -287.824926)
		(end 404.149814 -288.299906)
		(width 0.249936)
		(layer "F.Cu")
		(net "GND")
	)
	(segment
		(start 273.324828 -299.224954)
		(end 273.799808 -299.699934)
		(width 0.249936)
		(layer "F.Cu")
		(net "GND")
	)
	(segment
		(start 285.98495 -84.836)
		(end 285.369 -84.836)
		(width 0.4572)
		(layer "F.Cu")
		(net "GND")
	)
	(segment
		(start 166.249858 -302.549814)
		(end 165.774878 -302.074834)
		(width 0.249936)
		(layer "F.Cu")
		(net "GND")
	)
	(segment
		(start 285.199836 -286.399732)
		(end 284.724856 -285.924752)
		(width 0.249936)
		(layer "F.Cu")
		(net "GND")
	)
	(segment
		(start 214.884 -228.19995)
		(end 214.884 -227.528882)
		(width 0.4572)
		(layer "F.Cu")
		(net "GND")
	)
	(segment
		(start 194.749928 -298.74972)
		(end 195.224908 -298.27474)
		(width 0.249936)
		(layer "F.Cu")
		(net "GND")
	)
	(segment
		(start 253.11862 -46.693836)
		(end 252.91923 -46.893226)
		(width 0.254)
		(layer "F.Cu")
		(net "GND")
	)
	(segment
		(start 46.042326 -151.159972)
		(end 45.020738 -151.159972)
		(width 0.3556)
		(layer "F.Cu")
		(net "GND")
	)
	(segment
		(start 57.749948 -305.399948)
		(end 58.224928 -305.874928)
		(width 0.249936)
		(layer "F.Cu")
		(net "GND")
	)
	(segment
		(start 43.499786 -286.399732)
		(end 43.024806 -286.874712)
		(width 0.249936)
		(layer "F.Cu")
		(net "GND")
	)
	(segment
		(start 279.974802 -304.924714)
		(end 280.449782 -305.399948)
		(width 0.249936)
		(layer "F.Cu")
		(net "GND")
	)
	(segment
		(start 265.686286 -252.756924)
		(end 265.686286 -253.45644)
		(width 0.4572)
		(layer "F.Cu")
		(net "GND")
	)
	(segment
		(start 62.499748 -285.449772)
		(end 62.024768 -284.974792)
		(width 0.249936)
		(layer "F.Cu")
		(net "GND")
	)
	(segment
		(start 307.049932 -295.89984)
		(end 307.524912 -296.37482)
		(width 0.249936)
		(layer "F.Cu")
		(net "GND")
	)
	(segment
		(start 365.072422 -392.06551)
		(end 365.072422 -392.71575)
		(width 0.4572)
		(layer "F.Cu")
		(net "GND")
	)
	(segment
		(start 194.525138 -14.735302)
		(end 194.525138 -14.100302)
		(width 0.381)
		(layer "F.Cu")
		(net "GND")
	)
	(segment
		(start 185.725054 -291.624766)
		(end 186.200034 -292.099746)
		(width 0.249936)
		(layer "F.Cu")
		(net "GND")
	)
	(segment
		(start 65.824862 -285.924752)
		(end 66.299842 -285.449772)
		(width 0.249936)
		(layer "F.Cu")
		(net "GND")
	)
	(segment
		(start 422.548304 -120.035066)
		(end 421.557704 -120.035066)
		(width 0.3556)
		(layer "F.Cu")
		(net "GND")
	)
	(segment
		(start 208.866486 -210.829652)
		(end 208.866486 -212.380576)
		(width 0.4572)
		(layer "F.Cu")
		(net "GND")
	)
	(segment
		(start 58.224928 -284.024832)
		(end 58.699908 -284.499812)
		(width 0.249936)
		(layer "F.Cu")
		(net "GND")
	)
	(segment
		(start 301.349918 -285.449772)
		(end 300.874684 -284.974792)
		(width 0.249936)
		(layer "F.Cu")
		(net "GND")
	)
	(segment
		(start 426.94987 -303.499774)
		(end 426.94987 -304.449734)
		(width 0.249936)
		(layer "F.Cu")
		(net "GND")
	)
	(segment
		(start 403.674834 -289.724846)
		(end 404.149814 -290.199826)
		(width 0.249936)
		(layer "F.Cu")
		(net "GND")
	)
	(segment
		(start 63.924942 -287.824926)
		(end 64.399922 -288.299906)
		(width 0.249936)
		(layer "F.Cu")
		(net "GND")
	)
	(segment
		(start 294.69969 -293.99992)
		(end 295.174924 -293.52494)
		(width 0.249936)
		(layer "F.Cu")
		(net "GND")
	)
	(segment
		(start 143.0528 -262.915908)
		(end 143.624554 -262.915908)
		(width 0.3048)
		(layer "F.Cu")
		(net "GND")
	)
	(segment
		(start 172.424852 -284.974792)
		(end 171.949872 -285.449772)
		(width 0.249936)
		(layer "F.Cu")
		(net "GND")
	)
	(segment
		(start 269.999714 -294.94988)
		(end 269.524734 -294.4749)
		(width 0.249936)
		(layer "F.Cu")
		(net "GND")
	)
	(segment
		(start 39.699946 -276.899878)
		(end 39.224966 -276.424898)
		(width 0.249936)
		(layer "F.Cu")
		(net "GND")
	)
	(segment
		(start 432.60899 -27.04973)
		(end 431.94986 -27.04973)
		(width 0.4572)
		(layer "F.Cu")
		(net "GND")
	)
	(segment
		(start 427.89983 -294.94988)
		(end 427.42485 -294.4749)
		(width 0.249936)
		(layer "F.Cu")
		(net "GND")
	)
	(segment
		(start 171.474892 -297.32478)
		(end 170.999912 -297.79976)
		(width 0.249936)
		(layer "F.Cu")
		(net "GND")
	)
	(segment
		(start 74.248264 -154.755088)
		(end 73.257664 -154.755088)
		(width 0.3556)
		(layer "F.Cu")
		(net "GND")
	)
	(segment
		(start 406.524968 -303.974754)
		(end 406.049988 -303.499774)
		(width 0.249936)
		(layer "F.Cu")
		(net "GND")
	)
	(segment
		(start 303.249838 -285.449772)
		(end 302.774858 -284.974792)
		(width 0.249936)
		(layer "F.Cu")
		(net "GND")
	)
	(segment
		(start 336.80908 -109.032548)
		(end 336.80908 -108.39196)
		(width 0.4572)
		(layer "F.Cu")
		(net "GND")
	)
	(segment
		(start 154.156156 -33.19018)
		(end 152.764998 -33.19018)
		(width 0.3556)
		(layer "F.Cu")
		(net "GND")
	)
	(segment
		(start 156.348938 -33.19018)
		(end 157.364938 -33.19018)
		(width 0.3556)
		(layer "F.Cu")
		(net "GND")
	)
	(segment
		(start 73.061068 -38.701218)
		(end 73.819512 -38.701218)
		(width 0.4572)
		(layer "F.Cu")
		(net "GND")
	)
	(segment
		(start 326.007476 -86.23173)
		(end 326.007476 -85.85073)
		(width 0.4572)
		(layer "F.Cu")
		(net "GND")
	)
	(segment
		(start 139.24661 -255.669542)
		(end 139.408408 -255.83134)
		(width 0.4572)
		(layer "F.Cu")
		(net "GND")
	)
	(segment
		(start 175.749966 -292.099746)
		(end 176.224946 -291.624766)
		(width 0.249936)
		(layer "F.Cu")
		(net "GND")
	)
	(segment
		(start 406.789382 -62.812168)
		(end 407.599896 -62.812168)
		(width 0.4572)
		(layer "F.Cu")
		(net "GND")
	)
	(segment
		(start 288.524696 -302.074834)
		(end 288.049716 -301.599854)
		(width 0.249936)
		(layer "F.Cu")
		(net "GND")
	)
	(segment
		(start 318.34074 -54.163722)
		(end 318.892682 -54.163722)
		(width 0.254)
		(layer "F.Cu")
		(net "GND")
	)
	(segment
		(start 387.482842 -141.87297)
		(end 387.482842 -140.85697)
		(width 0.4572)
		(layer "F.Cu")
		(net "GND")
	)
	(segment
		(start 42.549826 -290.199826)
		(end 42.074846 -289.724846)
		(width 0.249936)
		(layer "F.Cu")
		(net "GND")
	)
	(segment
		(start 4.941316 -372.011448)
		(end 5.660136 -372.011448)
		(width 0.508)
		(layer "F.Cu")
		(net "GND")
	)
	(segment
		(start 270.949928 -275.949918)
		(end 270.474948 -275.474938)
		(width 0.249936)
		(layer "F.Cu")
		(net "GND")
	)
	(segment
		(start 293.27475 -306.824888)
		(end 292.79977 -306.349908)
		(width 0.249936)
		(layer "F.Cu")
		(net "GND")
	)
	(segment
		(start 98.866198 -94.863666)
		(end 98.866198 -94.25178)
		(width 0.4064)
		(layer "F.Cu")
		(net "GND")
	)
	(segment
		(start 70.099936 -289.249866)
		(end 70.574916 -289.724846)
		(width 0.249936)
		(layer "F.Cu")
		(net "GND")
	)
	(segment
		(start 134.518654 -147.913344)
		(end 134.518654 -147.38604)
		(width 0.254)
		(layer "F.Cu")
		(net "GND")
	)
	(segment
		(start 417.984178 -124.31649)
		(end 417.984178 -124.000514)
		(width 0.3556)
		(layer "F.Cu")
		(net "GND")
	)
	(segment
		(start 52.524914 -284.024832)
		(end 52.999894 -284.499812)
		(width 0.249936)
		(layer "F.Cu")
		(net "GND")
	)
	(segment
		(start 231.46766 -220.704156)
		(end 231.867456 -221.103952)
		(width 0.381)
		(layer "F.Cu")
		(net "GND")
	)
	(segment
		(start 389.899906 -298.74972)
		(end 390.374886 -298.27474)
		(width 0.249936)
		(layer "F.Cu")
		(net "GND")
	)
	(segment
		(start 408.424888 -305.874928)
		(end 408.899868 -306.349908)
		(width 0.249936)
		(layer "F.Cu")
		(net "GND")
	)
	(segment
		(start 400.123914 -167.742108)
		(end 400.123914 -168.229788)
		(width 0.4572)
		(layer "F.Cu")
		(net "GND")
	)
	(segment
		(start 277.069042 -152.958038)
		(end 277.094442 -152.958038)
		(width 0.3556)
		(layer "F.Cu")
		(net "GND")
	)
	(segment
		(start 304.625502 -133.044946)
		(end 305.457606 -133.044946)
		(width 0.3556)
		(layer "F.Cu")
		(net "GND")
	)
	(segment
		(start 81.974944 -296.37482)
		(end 82.449924 -295.89984)
		(width 0.249936)
		(layer "F.Cu")
		(net "GND")
	)
	(segment
		(start 69.149976 -284.499812)
		(end 68.674742 -284.974792)
		(width 0.249936)
		(layer "F.Cu")
		(net "GND")
	)
	(segment
		(start 219.660724 -105.291382)
		(end 219.660724 -105.71734)
		(width 0.4064)
		(layer "F.Cu")
		(net "GND")
	)
	(segment
		(start 165.299898 -307.299868)
		(end 164.824918 -307.774848)
		(width 0.249936)
		(layer "F.Cu")
		(net "GND")
	)
	(segment
		(start 355.403404 -59.971686)
		(end 355.403404 -60.627006)
		(width 0.381)
		(layer "F.Cu")
		(net "GND")
	)
	(segment
		(start 306.099718 -296.8498)
		(end 306.574698 -296.37482)
		(width 0.249936)
		(layer "F.Cu")
		(net "GND")
	)
	(segment
		(start 61.549788 -306.349908)
		(end 61.074808 -306.824888)
		(width 0.249936)
		(layer "F.Cu")
		(net "GND")
	)
	(segment
		(start 41.599866 -283.549852)
		(end 41.124886 -283.074872)
		(width 0.249936)
		(layer "F.Cu")
		(net "GND")
	)
	(segment
		(start 388.949946 -274.999958)
		(end 388.474966 -274.524978)
		(width 0.249936)
		(layer "F.Cu")
		(net "GND")
	)
	(segment
		(start 327.094088 -116.410486)
		(end 327.729088 -116.410486)
		(width 0.4572)
		(layer "F.Cu")
		(net "GND")
	)
	(segment
		(start 357.598218 -284.42412)
		(end 357.230934 -284.42412)
		(width 0.2286)
		(layer "F.Cu")
		(net "GND")
	)
	(segment
		(start 413.37357 -187.537344)
		(end 413.379666 -187.537344)
		(width 0.4572)
		(layer "F.Cu")
		(net "GND")
	)
	(segment
		(start 55.374794 -300.174914)
		(end 54.899814 -299.699934)
		(width 0.249936)
		(layer "F.Cu")
		(net "GND")
	)
	(segment
		(start 293.74973 -290.199826)
		(end 294.22471 -289.724846)
		(width 0.249936)
		(layer "F.Cu")
		(net "GND")
	)
	(segment
		(start 189.049914 -297.79976)
		(end 189.524894 -298.27474)
		(width 0.249936)
		(layer "F.Cu")
		(net "GND")
	)
	(segment
		(start 167.200072 -305.399948)
		(end 166.725092 -305.874928)
		(width 0.249936)
		(layer "F.Cu")
		(net "GND")
	)
	(segment
		(start 278.074882 -297.32478)
		(end 277.599902 -296.8498)
		(width 0.249936)
		(layer "F.Cu")
		(net "GND")
	)
	(segment
		(start 381.100076 -38.671754)
		(end 381.100076 -38.315138)
		(width 0.4572)
		(layer "F.Cu")
		(net "GND")
	)
	(segment
		(start 115.720368 -321.556634)
		(end 115.720368 -322.078604)
		(width 0.4572)
		(layer "F.Cu")
		(net "GND")
	)
	(segment
		(start 406.895046 -101.782372)
		(end 406.279858 -101.782372)
		(width 0.4064)
		(layer "F.Cu")
		(net "GND")
	)
	(segment
		(start 271.899888 -285.449772)
		(end 271.424908 -284.974792)
		(width 0.249936)
		(layer "F.Cu")
		(net "GND")
	)
	(segment
		(start 352.520504 -90.645234)
		(end 351.649538 -90.645234)
		(width 0.4572)
		(layer "F.Cu")
		(net "GND")
	)
	(segment
		(start 196.370956 -34.29762)
		(end 196.362574 -34.29762)
		(width 0.4572)
		(layer "F.Cu")
		(net "GND")
	)
	(segment
		(start 74.84999 -290.199826)
		(end 75.32497 -290.674806)
		(width 0.249936)
		(layer "F.Cu")
		(net "GND")
	)
	(segment
		(start 162.450018 -296.8498)
		(end 161.975038 -296.37482)
		(width 0.249936)
		(layer "F.Cu")
		(net "GND")
	)
	(segment
		(start 289.94989 -301.599854)
		(end 290.42487 -302.074834)
		(width 0.249936)
		(layer "F.Cu")
		(net "GND")
	)
	(segment
		(start 285.199836 -292.099746)
		(end 285.674816 -291.624766)
		(width 0.249936)
		(layer "F.Cu")
		(net "GND")
	)
	(segment
		(start 297.074844 -306.824888)
		(end 296.599864 -307.299868)
		(width 0.249936)
		(layer "F.Cu")
		(net "GND")
	)
	(segment
		(start 183.766714 -136.645142)
		(end 184.757314 -136.645142)
		(width 0.3556)
		(layer "F.Cu")
		(net "GND")
	)
	(segment
		(start 49.65192 -125.955044)
		(end 50.64252 -125.955044)
		(width 0.3556)
		(layer "F.Cu")
		(net "GND")
	)
	(segment
		(start 351.17024 -238.098584)
		(end 352.326448 -238.098584)
		(width 0.4572)
		(layer "F.Cu")
		(net "GND")
	)
	(segment
		(start 152.764998 -31.390082)
		(end 153.636472 -31.390082)
		(width 0.3556)
		(layer "F.Cu")
		(net "GND")
	)
	(segment
		(start 220.851222 -141.910562)
		(end 220.241622 -141.910562)
		(width 0.4572)
		(layer "F.Cu")
		(net "GND")
	)
	(segment
		(start 190.474854 -290.674806)
		(end 190.950088 -290.199826)
		(width 0.249936)
		(layer "F.Cu")
		(net "GND")
	)
	(segment
		(start 162.450018 -285.449772)
		(end 161.975038 -284.974792)
		(width 0.249936)
		(layer "F.Cu")
		(net "GND")
	)
	(segment
		(start 82.449924 -301.599854)
		(end 82.924904 -301.124874)
		(width 0.249936)
		(layer "F.Cu")
		(net "GND")
	)
	(segment
		(start 176.699926 -306.349908)
		(end 176.224946 -305.874928)
		(width 0.249936)
		(layer "F.Cu")
		(net "GND")
	)
	(segment
		(start 284.18917 -178.378358)
		(end 284.18917 -179.080922)
		(width 0.381)
		(layer "F.Cu")
		(net "GND")
	)
	(segment
		(start 341.694008 -221.986856)
		(end 341.293958 -222.386906)
		(width 0.381)
		(layer "F.Cu")
		(net "GND")
	)
	(segment
		(start 73.899776 -296.8498)
		(end 73.424796 -297.32478)
		(width 0.249936)
		(layer "F.Cu")
		(net "GND")
	)
	(segment
		(start 179.55006 -306.349908)
		(end 179.07508 -306.824888)
		(width 0.249936)
		(layer "F.Cu")
		(net "GND")
	)
	(segment
		(start 297.549824 -290.199826)
		(end 297.074844 -289.724846)
		(width 0.249936)
		(layer "F.Cu")
		(net "GND")
	)
	(segment
		(start 167.675052 -289.724846)
		(end 167.200072 -290.199826)
		(width 0.249936)
		(layer "F.Cu")
		(net "GND")
	)
	(segment
		(start 166.725092 -305.874928)
		(end 166.249858 -306.349908)
		(width 0.249936)
		(layer "F.Cu")
		(net "GND")
	)
	(segment
		(start 409.374848 -302.074834)
		(end 409.849828 -301.599854)
		(width 0.249936)
		(layer "F.Cu")
		(net "GND")
	)
	(segment
		(start 402.724874 -287.824926)
		(end 403.199854 -288.299906)
		(width 0.249936)
		(layer "F.Cu")
		(net "GND")
	)
	(segment
		(start 301.694596 -118.234968)
		(end 300.857412 -118.234968)
		(width 0.3556)
		(layer "F.Cu")
		(net "GND")
	)
	(segment
		(start 345.36126 -261.687564)
		(end 344.74531 -261.687564)
		(width 0.381)
		(layer "F.Cu")
		(net "GND")
	)
	(segment
		(start 292.79977 -288.299906)
		(end 293.27475 -287.824926)
		(width 0.249936)
		(layer "F.Cu")
		(net "GND")
	)
	(segment
		(start 178.764946 -29.589984)
		(end 177.748946 -29.589984)
		(width 0.3556)
		(layer "F.Cu")
		(net "GND")
	)
	(segment
		(start 406.54986 -287.699958)
		(end 406.999948 -288.149792)
		(width 0.249936)
		(layer "F.Cu")
		(net "GND")
	)
	(segment
		(start 119.972328 -33.248092)
		(end 119.972328 -33.857692)
		(width 0.4572)
		(layer "F.Cu")
		(net "GND")
	)
	(segment
		(start 80.282542 -28.47848)
		(end 79.943198 -28.139136)
		(width 0.254)
		(layer "F.Cu")
		(net "GND")
	)
	(segment
		(start 194.749928 -297.79976)
		(end 194.274948 -297.32478)
		(width 0.249936)
		(layer "F.Cu")
		(net "GND")
	)
	(segment
		(start 55.374794 -303.974754)
		(end 54.899814 -303.499774)
		(width 0.249936)
		(layer "F.Cu")
		(net "GND")
	)
	(segment
		(start 190.348108 -143.955008)
		(end 189.357508 -143.955008)
		(width 0.3556)
		(layer "F.Cu")
		(net "GND")
	)
	(segment
		(start 313.224926 -297.32478)
		(end 312.749692 -296.8498)
		(width 0.249936)
		(layer "F.Cu")
		(net "GND")
	)
	(segment
		(start 53.949854 -296.8498)
		(end 53.474874 -297.32478)
		(width 0.249936)
		(layer "F.Cu")
		(net "GND")
	)
	(segment
		(start 279.232868 -129.964942)
		(end 278.242268 -129.964942)
		(width 0.3556)
		(layer "F.Cu")
		(net "GND")
	)
	(segment
		(start 187.149994 -292.1)
		(end 187.149994 -292.099746)
		(width 0.249936)
		(layer "F.Cu")
		(net "GND")
	)
	(segment
		(start 401.299934 -295.89984)
		(end 400.824954 -296.37482)
		(width 0.249936)
		(layer "F.Cu")
		(net "GND")
	)
	(segment
		(start 386.50799 -161.828226)
		(end 387.006084 -161.330132)
		(width 0.4572)
		(layer "F.Cu")
		(net "GND")
	)
	(segment
		(start 74.248264 -145.755106)
		(end 73.257664 -145.755106)
		(width 0.3556)
		(layer "F.Cu")
		(net "GND")
	)
	(segment
		(start 188.665866 -121.83491)
		(end 189.357508 -121.83491)
		(width 0.3556)
		(layer "F.Cu")
		(net "GND")
	)
	(segment
		(start 270.474694 -299.224954)
		(end 270.949928 -299.699934)
		(width 0.249936)
		(layer "F.Cu")
		(net "GND")
	)
	(segment
		(start 414.124902 -307.774848)
		(end 413.649922 -307.299868)
		(width 0.249936)
		(layer "F.Cu")
		(net "GND")
	)
	(segment
		(start 280.449782 -285.449772)
		(end 279.974802 -284.974792)
		(width 0.249936)
		(layer "F.Cu")
		(net "GND")
	)
	(segment
		(start 310.374792 -291.624766)
		(end 310.849772 -291.149786)
		(width 0.249936)
		(layer "F.Cu")
		(net "GND")
	)
	(segment
		(start 360.938318 -31.390082)
		(end 358.964992 -31.390082)
		(width 0.3556)
		(layer "F.Cu")
		(net "GND")
	)
	(segment
		(start 66.299842 -288.299906)
		(end 65.824862 -287.824926)
		(width 0.249936)
		(layer "F.Cu")
		(net "GND")
	)
	(segment
		(start 169.760646 -16.439388)
		(end 169.836846 -16.363188)
		(width 0.4572)
		(layer "F.Cu")
		(net "GND")
	)
	(segment
		(start 190.348108 -156.554932)
		(end 189.357508 -156.554932)
		(width 0.3556)
		(layer "F.Cu")
		(net "GND")
	)
	(segment
		(start 168.150032 -306.349908)
		(end 167.675052 -306.824888)
		(width 0.249936)
		(layer "F.Cu")
		(net "GND")
	)
	(segment
		(start 406.524968 -306.824888)
		(end 406.999948 -306.349908)
		(width 0.249936)
		(layer "F.Cu")
		(net "GND")
	)
	(segment
		(start 294.69969 -285.449772)
		(end 294.22471 -284.974792)
		(width 0.249936)
		(layer "F.Cu")
		(net "GND")
	)
	(segment
		(start 156.698442 -252.756924)
		(end 156.698442 -253.45644)
		(width 0.4572)
		(layer "F.Cu")
		(net "GND")
	)
	(segment
		(start 255.537462 -198.95693)
		(end 255.537462 -200.08723)
		(width 0.3556)
		(layer "F.Cu")
		(net "GND")
	)
	(segment
		(start 404.149814 -306.349908)
		(end 404.624794 -306.824888)
		(width 0.249936)
		(layer "F.Cu")
		(net "GND")
	)
	(segment
		(start 395.59992 -286.399732)
		(end 395.12494 -285.924752)
		(width 0.249936)
		(layer "F.Cu")
		(net "GND")
	)
	(segment
		(start 69.149976 -296.8498)
		(end 69.624956 -296.37482)
		(width 0.249936)
		(layer "F.Cu")
		(net "GND")
	)
	(segment
		(start 283.299916 -284.499812)
		(end 282.824936 -284.024832)
		(width 0.249936)
		(layer "F.Cu")
		(net "GND")
	)
	(segment
		(start 420.567104 -118.234968)
		(end 421.557704 -118.234968)
		(width 0.3556)
		(layer "F.Cu")
		(net "GND")
	)
	(segment
		(start 290.42487 -296.37482)
		(end 289.94989 -296.8498)
		(width 0.249936)
		(layer "F.Cu")
		(net "GND")
	)
	(segment
		(start 172.900086 -290.199826)
		(end 172.424852 -289.724846)
		(width 0.249936)
		(layer "F.Cu")
		(net "GND")
	)
	(segment
		(start 419.824916 -294.4749)
		(end 419.349936 -294.94988)
		(width 0.249936)
		(layer "F.Cu")
		(net "GND")
	)
	(segment
		(start 244.934232 -138.819636)
		(end 244.859048 -138.89482)
		(width 0.254)
		(layer "F.Cu")
		(net "GND")
	)
	(segment
		(start 81.024984 -292.574726)
		(end 81.499964 -292.099746)
		(width 0.249936)
		(layer "F.Cu")
		(net "GND")
	)
	(segment
		(start 215.176608 -209.707734)
		(end 215.746584 -209.707734)
		(width 0.254)
		(layer "F.Cu")
		(net "GND")
	)
	(segment
		(start 281.399742 -297.79976)
		(end 280.924762 -298.27474)
		(width 0.249936)
		(layer "F.Cu")
		(net "GND")
	)
	(segment
		(start 130.150616 -159.392112)
		(end 130.150616 -159.857948)
		(width 0.254)
		(layer "F.Cu")
		(net "GND")
	)
	(segment
		(start 52.999894 -306.349908)
		(end 53.474874 -305.874928)
		(width 0.249936)
		(layer "F.Cu")
		(net "GND")
	)
	(segment
		(start 64.399922 -286.399732)
		(end 63.924942 -285.924752)
		(width 0.249936)
		(layer "F.Cu")
		(net "GND")
	)
	(segment
		(start 416.974782 -304.924714)
		(end 417.450016 -305.399948)
		(width 0.249936)
		(layer "F.Cu")
		(net "GND")
	)
	(segment
		(start 394.64996 -298.74972)
		(end 394.17498 -298.27474)
		(width 0.249936)
		(layer "F.Cu")
		(net "GND")
	)
	(segment
		(start 397.97482 -303.024794)
		(end 398.4498 -302.549814)
		(width 0.249936)
		(layer "F.Cu")
		(net "GND")
	)
	(segment
		(start 376.122184 -306.802028)
		(end 375.372884 -306.052728)
		(width 0.4572)
		(layer "F.Cu")
		(net "GND")
	)
	(segment
		(start 70.099936 -293.04996)
		(end 69.624956 -293.52494)
		(width 0.249936)
		(layer "F.Cu")
		(net "GND")
	)
	(segment
		(start 415.074862 -306.824888)
		(end 414.599882 -307.299868)
		(width 0.249936)
		(layer "F.Cu")
		(net "GND")
	)
	(segment
		(start 389.899906 -287.349946)
		(end 389.424926 -286.874966)
		(width 0.249936)
		(layer "F.Cu")
		(net "GND")
	)
	(segment
		(start 409.849828 -306.349908)
		(end 409.374848 -306.824888)
		(width 0.249936)
		(layer "F.Cu")
		(net "GND")
	)
	(segment
		(start 416.499802 -292.099746)
		(end 416.974782 -291.624766)
		(width 0.249936)
		(layer "F.Cu")
		(net "GND")
	)
	(segment
		(start 416.974782 -303.024794)
		(end 416.499802 -302.549814)
		(width 0.249936)
		(layer "F.Cu")
		(net "GND")
	)
	(segment
		(start 311.324752 -292.574726)
		(end 310.849772 -292.099746)
		(width 0.249936)
		(layer "F.Cu")
		(net "GND")
	)
	(segment
		(start 148.473414 -382.453896)
		(end 149.273006 -382.453896)
		(width 0.4572)
		(layer "F.Cu")
		(net "GND")
	)
	(segment
		(start 72.28332 -154.461718)
		(end 72.57669 -154.755088)
		(width 0.3556)
		(layer "F.Cu")
		(net "GND")
	)
	(segment
		(start 399.93316 -113.245138)
		(end 398.94256 -113.245138)
		(width 0.3556)
		(layer "F.Cu")
		(net "GND")
	)
	(segment
		(start 188.366908 -131.245102)
		(end 189.357508 -131.245102)
		(width 0.3556)
		(layer "F.Cu")
		(net "GND")
	)
	(segment
		(start 198.075042 -296.37482)
		(end 198.550022 -295.89984)
		(width 0.249936)
		(layer "F.Cu")
		(net "GND")
	)
	(segment
		(start 366.254792 -285.488634)
		(end 365.965994 -285.199836)
		(width 0.2286)
		(layer "F.Cu")
		(net "GND")
	)
	(segment
		(start 157.699964 -289.249866)
		(end 157.224984 -289.724846)
		(width 0.254)
		(layer "F.Cu")
		(net "GND")
	)
	(segment
		(start 396.54988 -285.449772)
		(end 396.0749 -284.974792)
		(width 0.249936)
		(layer "F.Cu")
		(net "GND")
	)
	(segment
		(start 298.024804 -303.974754)
		(end 298.499784 -303.499774)
		(width 0.249936)
		(layer "F.Cu")
		(net "GND")
	)
	(segment
		(start 53.474874 -300.174914)
		(end 53.949854 -299.699934)
		(width 0.249936)
		(layer "F.Cu")
		(net "GND")
	)
	(segment
		(start 285.674816 -284.024832)
		(end 286.149796 -284.499812)
		(width 0.249936)
		(layer "F.Cu")
		(net "GND")
	)
	(segment
		(start 67.264788 -34.990024)
		(end 65.382902 -34.990024)
		(width 0.3556)
		(layer "F.Cu")
		(net "GND")
	)
	(segment
		(start 338.47405 -160.782)
		(end 339.09 -160.782)
		(width 0.4572)
		(layer "F.Cu")
		(net "GND")
	)
	(segment
		(start 261.460234 -311.442608)
		(end 260.849872 -310.832246)
		(width 0.4572)
		(layer "F.Cu")
		(net "GND")
	)
	(segment
		(start 305.624738 -293.52494)
		(end 306.099718 -293.04996)
		(width 0.249936)
		(layer "F.Cu")
		(net "GND")
	)
	(segment
		(start 286.624776 -284.974792)
		(end 287.099756 -284.499812)
		(width 0.249936)
		(layer "F.Cu")
		(net "GND")
	)
	(segment
		(start 331.118464 -46.693836)
		(end 330.919074 -46.893226)
		(width 0.254)
		(layer "F.Cu")
		(net "GND")
	)
	(segment
		(start 406.999948 -295.89984)
		(end 406.524968 -296.37482)
		(width 0.249936)
		(layer "F.Cu")
		(net "GND")
	)
	(segment
		(start 419.349936 -287.349946)
		(end 418.874956 -287.824926)
		(width 0.249936)
		(layer "F.Cu")
		(net "GND")
	)
	(segment
		(start 67.724782 -285.924752)
		(end 68.199762 -285.449772)
		(width 0.249936)
		(layer "F.Cu")
		(net "GND")
	)
	(segment
		(start 395.332966 -98.845116)
		(end 394.342366 -98.845116)
		(width 0.3556)
		(layer "F.Cu")
		(net "GND")
	)
	(segment
		(start 43.974766 -296.37482)
		(end 44.449746 -296.8498)
		(width 0.249936)
		(layer "F.Cu")
		(net "GND")
	)
	(segment
		(start 270.399764 -154.327352)
		(end 269.764764 -154.327352)
		(width 0.4064)
		(layer "F.Cu")
		(net "GND")
	)
	(segment
		(start 374.968008 -51.019456)
		(end 375.623328 -51.019456)
		(width 0.254)
		(layer "F.Cu")
		(net "GND")
	)
	(segment
		(start 173.433994 -140.97)
		(end 173.122844 -140.97)
		(width 0.4572)
		(layer "F.Cu")
		(net "GND")
	)
	(segment
		(start 411.750002 -285.449772)
		(end 412.224982 -284.974792)
		(width 0.249936)
		(layer "F.Cu")
		(net "GND")
	)
	(segment
		(start 227.566982 -156.398722)
		(end 227.566982 -157.008322)
		(width 0.4572)
		(layer "F.Cu")
		(net "GND")
	)
	(segment
		(start 426.94987 -293.99992)
		(end 426.47489 -293.52494)
		(width 0.249936)
		(layer "F.Cu")
		(net "GND")
	)
	(segment
		(start 48.24984 -289.249866)
		(end 47.77486 -288.774886)
		(width 0.249936)
		(layer "F.Cu")
		(net "GND")
	)
	(segment
		(start 70.574916 -301.124874)
		(end 71.049896 -300.649894)
		(width 0.249936)
		(layer "F.Cu")
		(net "GND")
	)
	(segment
		(start 175.749966 -288.299906)
		(end 176.150016 -287.899856)
		(width 0.249936)
		(layer "F.Cu")
		(net "GND")
	)
	(segment
		(start 335.557368 -29.784294)
		(end 335.664302 -29.67736)
		(width 0.4572)
		(layer "F.Cu")
		(net "GND")
	)
	(segment
		(start 210.99653 -371.465094)
		(end 211.349336 -371.112288)
		(width 0.4572)
		(layer "F.Cu")
		(net "GND")
	)
	(segment
		(start 156.314902 -26.171398)
		(end 156.496258 -25.990042)
		(width 0.3556)
		(layer "F.Cu")
		(net "GND")
	)
	(segment
		(start 63.924942 -284.974792)
		(end 64.399922 -285.449772)
		(width 0.249936)
		(layer "F.Cu")
		(net "GND")
	)
	(segment
		(start 415.074862 -289.724846)
		(end 415.549842 -290.199826)
		(width 0.249936)
		(layer "F.Cu")
		(net "GND")
	)
	(segment
		(start 152.94991 -294.94988)
		(end 152.47493 -294.4749)
		(width 0.249936)
		(layer "F.Cu")
		(net "GND")
	)
	(segment
		(start 78.643734 -43.85691)
		(end 79.315056 -43.85691)
		(width 0.254)
		(layer "F.Cu")
		(net "GND")
	)
	(segment
		(start 51.574954 -291.624766)
		(end 51.099974 -292.099746)
		(width 0.249936)
		(layer "F.Cu")
		(net "GND")
	)
	(segment
		(start 392.75004 -300.649894)
		(end 393.22502 -301.124874)
		(width 0.254)
		(layer "F.Cu")
		(net "GND")
	)
	(segment
		(start 52.524914 -306.824888)
		(end 52.999894 -307.299868)
		(width 0.249936)
		(layer "F.Cu")
		(net "GND")
	)
	(segment
		(start 294.22471 -285.924752)
		(end 294.69969 -285.449772)
		(width 0.249936)
		(layer "F.Cu")
		(net "GND")
	)
	(segment
		(start 215.475566 -120.239028)
		(end 216.111328 -120.239028)
		(width 0.4064)
		(layer "F.Cu")
		(net "GND")
	)
	(segment
		(start 132.019802 -200.919334)
		(end 132.668264 -201.567796)
		(width 0.4572)
		(layer "F.Cu")
		(net "GND")
	)
	(segment
		(start 163.058602 -107.845098)
		(end 162.14217 -107.845098)
		(width 0.3556)
		(layer "F.Cu")
		(net "GND")
	)
	(segment
		(start 46.955456 -102.445058)
		(end 46.042326 -102.445058)
		(width 0.3556)
		(layer "F.Cu")
		(net "GND")
	)
	(segment
		(start 38.749986 -285.449772)
		(end 38.275006 -284.974792)
		(width 0.249936)
		(layer "F.Cu")
		(net "GND")
	)
	(segment
		(start 53.474874 -294.4749)
		(end 52.999894 -293.99992)
		(width 0.249936)
		(layer "F.Cu")
		(net "GND")
	)
	(segment
		(start 269.049754 -284.499812)
		(end 268.574774 -284.024832)
		(width 0.249936)
		(layer "F.Cu")
		(net "GND")
	)
	(segment
		(start 377.560332 -311.442608)
		(end 376.94997 -310.832246)
		(width 0.4572)
		(layer "F.Cu")
		(net "GND")
	)
	(segment
		(start 56.324754 -284.974792)
		(end 55.849774 -285.449772)
		(width 0.249936)
		(layer "F.Cu")
		(net "GND")
	)
	(segment
		(start 143.922242 -306.802028)
		(end 143.172942 -306.052728)
		(width 0.4572)
		(layer "F.Cu")
		(net "GND")
	)
	(segment
		(start 40.174926 -296.37482)
		(end 40.649906 -295.89984)
		(width 0.249936)
		(layer "F.Cu")
		(net "GND")
	)
	(segment
		(start 294.69969 -297.79976)
		(end 295.174924 -298.27474)
		(width 0.249936)
		(layer "F.Cu")
		(net "GND")
	)
	(segment
		(start 283.833062 -129.964942)
		(end 282.842462 -129.964942)
		(width 0.3556)
		(layer "F.Cu")
		(net "GND")
	)
	(segment
		(start 281.804872 -105.365042)
		(end 281.804872 -105.673652)
		(width 0.3556)
		(layer "F.Cu")
		(net "GND")
	)
	(segment
		(start 401.960588 -16.439388)
		(end 402.036788 -16.363188)
		(width 0.4572)
		(layer "F.Cu")
		(net "GND")
	)
	(segment
		(start 173.850046 -290.199826)
		(end 174.325026 -289.724846)
		(width 0.249936)
		(layer "F.Cu")
		(net "GND")
	)
	(segment
		(start 302.774858 -291.624766)
		(end 302.299878 -291.149786)
		(width 0.249936)
		(layer "F.Cu")
		(net "GND")
	)
	(segment
		(start 416.974782 -284.974792)
		(end 417.450016 -284.499812)
		(width 0.249936)
		(layer "F.Cu")
		(net "GND")
	)
	(segment
		(start 405.575008 -305.874928)
		(end 405.100028 -305.399948)
		(width 0.249936)
		(layer "F.Cu")
		(net "GND")
	)
	(segment
		(start 171.949872 -284.499812)
		(end 172.424852 -284.024832)
		(width 0.249936)
		(layer "F.Cu")
		(net "GND")
	)
	(segment
		(start 281.546554 -110.857538)
		(end 282.134056 -111.44504)
		(width 0.3556)
		(layer "F.Cu")
		(net "GND")
	)
	(segment
		(start 210.99399 -115.902486)
		(end 211.62899 -115.902486)
		(width 0.4572)
		(layer "F.Cu")
		(net "GND")
	)
	(segment
		(start 380.834646 -38.937184)
		(end 381.100076 -38.671754)
		(width 0.4572)
		(layer "F.Cu")
		(net "GND")
	)
	(segment
		(start 62.024768 -303.974754)
		(end 61.549788 -303.499774)
		(width 0.249936)
		(layer "F.Cu")
		(net "GND")
	)
	(segment
		(start 204.764894 -34.990024)
		(end 203.748894 -34.990024)
		(width 0.3556)
		(layer "F.Cu")
		(net "GND")
	)
	(segment
		(start 157.699964 -285.449772)
		(end 157.224984 -285.924752)
		(width 0.249936)
		(layer "F.Cu")
		(net "GND")
	)
	(segment
		(start 356.25405 -166.624)
		(end 356.87 -166.624)
		(width 0.4572)
		(layer "F.Cu")
		(net "GND")
	)
	(segment
		(start 338.47405 -149.987)
		(end 339.09 -149.987)
		(width 0.4572)
		(layer "F.Cu")
		(net "GND")
	)
	(segment
		(start 163.399978 -287.349946)
		(end 162.924998 -286.874966)
		(width 0.249936)
		(layer "F.Cu")
		(net "GND")
	)
	(segment
		(start 429.325024 -293.52494)
		(end 428.84979 -293.04996)
		(width 0.249936)
		(layer "F.Cu")
		(net "GND")
	)
	(segment
		(start 269.524988 -296.37482)
		(end 269.049754 -296.8498)
		(width 0.249936)
		(layer "F.Cu")
		(net "GND")
	)
	(segment
		(start 162.924998 -307.774848)
		(end 162.450018 -308.249828)
		(width 0.249936)
		(layer "F.Cu")
		(net "GND")
	)
	(segment
		(start 392.274806 -281.174952)
		(end 392.749786 -281.649932)
		(width 0.249936)
		(layer "F.Cu")
		(net "GND")
	)
	(segment
		(start 287.099756 -306.349908)
		(end 286.624776 -306.824888)
		(width 0.249936)
		(layer "F.Cu")
		(net "GND")
	)
	(segment
		(start 192.375028 -290.674806)
		(end 191.900048 -290.199826)
		(width 0.249936)
		(layer "F.Cu")
		(net "GND")
	)
	(segment
		(start 404.624794 -285.924752)
		(end 405.100028 -286.399732)
		(width 0.249936)
		(layer "F.Cu")
		(net "GND")
	)
	(segment
		(start 73.53046 -65.92189)
		(end 73.53046 -65.15989)
		(width 0.4572)
		(layer "F.Cu")
		(net "GND")
	)
	(segment
		(start 441.921138 -103.280464)
		(end 441.921138 -103.890064)
		(width 0.4572)
		(layer "F.Cu")
		(net "GND")
	)
	(segment
		(start 72.273922 -73.166732)
		(end 72.273922 -73.85177)
		(width 0.4572)
		(layer "F.Cu")
		(net "GND")
	)
	(segment
		(start 430.274984 -301.124874)
		(end 430.749964 -301.599854)
		(width 0.249936)
		(layer "F.Cu")
		(net "GND")
	)
	(segment
		(start 278.549862 -284.499812)
		(end 278.074882 -284.024832)
		(width 0.249936)
		(layer "F.Cu")
		(net "GND")
	)
	(segment
		(start 272.374868 -296.37482)
		(end 272.849848 -295.89984)
		(width 0.249936)
		(layer "F.Cu")
		(net "GND")
	)
	(segment
		(start 288.524696 -284.024832)
		(end 288.99993 -284.499812)
		(width 0.249936)
		(layer "F.Cu")
		(net "GND")
	)
	(segment
		(start 396.0749 -301.124874)
		(end 396.54988 -301.599854)
		(width 0.249936)
		(layer "F.Cu")
		(net "GND")
	)
	(segment
		(start 374.725184 -14.735302)
		(end 374.725184 -14.100302)
		(width 0.381)
		(layer "F.Cu")
		(net "GND")
	)
	(segment
		(start 271.899888 -274.049744)
		(end 271.424908 -273.574764)
		(width 0.249936)
		(layer "F.Cu")
		(net "GND")
	)
	(segment
		(start 361.58805 -191.262)
		(end 362.204 -191.262)
		(width 0.4572)
		(layer "F.Cu")
		(net "GND")
	)
	(segment
		(start 177.841656 -160.981644)
		(end 177.841656 -161.757868)
		(width 0.4572)
		(layer "F.Cu")
		(net "GND")
	)
	(segment
		(start 389.899906 -274.049744)
		(end 389.424926 -273.574764)
		(width 0.249936)
		(layer "F.Cu")
		(net "GND")
	)
	(segment
		(start 399.932906 -107.845098)
		(end 399.93316 -107.844844)
		(width 0.4572)
		(layer "F.Cu")
		(net "GND")
	)
	(segment
		(start 167.675052 -302.074834)
		(end 167.200072 -301.599854)
		(width 0.249936)
		(layer "F.Cu")
		(net "GND")
	)
	(segment
		(start 313.224926 -302.074834)
		(end 313.699906 -301.599854)
		(width 0.249936)
		(layer "F.Cu")
		(net "GND")
	)
	(segment
		(start 271.390872 -142.892018)
		(end 271.957546 -142.892018)
		(width 0.4572)
		(layer "F.Cu")
		(net "GND")
	)
	(segment
		(start 421.745918 -46.693836)
		(end 421.218614 -46.693836)
		(width 0.254)
		(layer "F.Cu")
		(net "GND")
	)
	(segment
		(start 81.024984 -289.724846)
		(end 80.54975 -289.249866)
		(width 0.249936)
		(layer "F.Cu")
		(net "GND")
	)
	(segment
		(start 46.34992 -285.449772)
		(end 45.87494 -284.974792)
		(width 0.249936)
		(layer "F.Cu")
		(net "GND")
	)
	(segment
		(start 307.999892 -297.79976)
		(end 307.524912 -298.27474)
		(width 0.249936)
		(layer "F.Cu")
		(net "GND")
	)
	(segment
		(start 163.13277 -98.845116)
		(end 162.14217 -98.845116)
		(width 0.3556)
		(layer "F.Cu")
		(net "GND")
	)
	(segment
		(start 387.050026 -296.8498)
		(end 387.525006 -297.32478)
		(width 0.249936)
		(layer "F.Cu")
		(net "GND")
	)
	(segment
		(start 281.399742 -305.399948)
		(end 280.924762 -305.874928)
		(width 0.249936)
		(layer "F.Cu")
		(net "GND")
	)
	(segment
		(start 277.698454 -65.92189)
		(end 277.698454 -65.15989)
		(width 0.4572)
		(layer "F.Cu")
		(net "GND")
	)
	(segment
		(start 57.749948 -299.699934)
		(end 58.224928 -300.174914)
		(width 0.249936)
		(layer "F.Cu")
		(net "GND")
	)
	(segment
		(start 209.09788 -295.965118)
		(end 209.09788 -295.355518)
		(width 0.4572)
		(layer "F.Cu")
		(net "GND")
	)
	(segment
		(start 197.600062 -299.699934)
		(end 198.075042 -299.224954)
		(width 0.249936)
		(layer "F.Cu")
		(net "GND")
	)
	(segment
		(start 458.567536 -306.405026)
		(end 458.059282 -306.405026)
		(width 0.4572)
		(layer "F.Cu")
		(net "GND")
	)
	(segment
		(start 115.200176 -117.338094)
		(end 115.200176 -118.061486)
		(width 0.4572)
		(layer "F.Cu")
		(net "GND")
	)
	(segment
		(start 165.774878 -303.974754)
		(end 166.249858 -304.449734)
		(width 0.249936)
		(layer "F.Cu")
		(net "GND")
	)
	(segment
		(start 291.84981 -305.399948)
		(end 292.32479 -305.874928)
		(width 0.249936)
		(layer "F.Cu")
		(net "GND")
	)
	(segment
		(start 171.474892 -284.024832)
		(end 170.999912 -284.499812)
		(width 0.249936)
		(layer "F.Cu")
		(net "GND")
	)
	(segment
		(start 195.224908 -290.674806)
		(end 195.699888 -291.149786)
		(width 0.249936)
		(layer "F.Cu")
		(net "GND")
	)
	(segment
		(start 187.624974 -302.074834)
		(end 187.149994 -301.599854)
		(width 0.249936)
		(layer "F.Cu")
		(net "GND")
	)
	(segment
		(start 176.699926 -297.79976)
		(end 177.174906 -298.27474)
		(width 0.249936)
		(layer "F.Cu")
		(net "GND")
	)
	(segment
		(start 135.806688 -200.489058)
		(end 135.806688 -199.399398)
		(width 0.2794)
		(layer "F.Cu")
		(net "GND")
	)
	(segment
		(start 187.87491 -48.753014)
		(end 187.168282 -48.753014)
		(width 0.254)
		(layer "F.Cu")
		(net "GND")
	)
	(segment
		(start 299.924724 -300.174914)
		(end 299.449744 -299.699934)
		(width 0.249936)
		(layer "F.Cu")
		(net "GND")
	)
	(segment
		(start 92.248736 -29.589984)
		(end 93.264736 -29.589984)
		(width 0.3556)
		(layer "F.Cu")
		(net "GND")
	)
	(segment
		(start 417.450016 -306.349908)
		(end 417.924996 -306.824888)
		(width 0.249936)
		(layer "F.Cu")
		(net "GND")
	)
	(segment
		(start 152.47493 -280.224738)
		(end 152.94991 -280.699718)
		(width 0.249936)
		(layer "F.Cu")
		(net "GND")
	)
	(segment
		(start 60.124848 -306.824888)
		(end 60.599828 -306.349908)
		(width 0.249936)
		(layer "F.Cu")
		(net "GND")
	)
	(segment
		(start 415.074862 -300.174914)
		(end 414.599882 -299.699934)
		(width 0.249936)
		(layer "F.Cu")
		(net "GND")
	)
	(segment
		(start 404.624794 -284.974792)
		(end 405.100028 -284.499812)
		(width 0.249936)
		(layer "F.Cu")
		(net "GND")
	)
	(segment
		(start 293.27475 -305.874928)
		(end 292.79977 -305.399948)
		(width 0.249936)
		(layer "F.Cu")
		(net "GND")
	)
	(segment
		(start 111.161322 -38.701218)
		(end 111.919766 -38.701218)
		(width 0.4572)
		(layer "F.Cu")
		(net "GND")
	)
	(segment
		(start 9.71042 -123.947428)
		(end 9.0551 -123.947428)
		(width 0.4064)
		(layer "F.Cu")
		(net "GND")
	)
	(segment
		(start 183.766714 -152.95499)
		(end 184.757314 -152.95499)
		(width 0.3556)
		(layer "F.Cu")
		(net "GND")
	)
	(segment
		(start 404.624794 -284.974792)
		(end 404.149814 -285.449772)
		(width 0.249936)
		(layer "F.Cu")
		(net "GND")
	)
	(segment
		(start 306.448206 -121.83491)
		(end 305.457606 -121.83491)
		(width 0.3556)
		(layer "F.Cu")
		(net "GND")
	)
	(segment
		(start 188.099954 -301.599854)
		(end 188.574934 -301.124874)
		(width 0.249936)
		(layer "F.Cu")
		(net "GND")
	)
	(segment
		(start 390.849866 -274.999958)
		(end 390.374886 -274.524978)
		(width 0.249936)
		(layer "F.Cu")
		(net "GND")
	)
	(segment
		(start 405.575008 -305.874928)
		(end 406.049988 -305.399948)
		(width 0.249936)
		(layer "F.Cu")
		(net "GND")
	)
	(segment
		(start 215.464136 -181.213506)
		(end 214.956136 -181.213506)
		(width 0.4572)
		(layer "F.Cu")
		(net "GND")
	)
	(segment
		(start 416.499802 -305.399948)
		(end 416.974782 -304.924714)
		(width 0.249936)
		(layer "F.Cu")
		(net "GND")
	)
	(segment
		(start 170.524932 -289.724846)
		(end 170.999912 -290.199826)
		(width 0.249936)
		(layer "F.Cu")
		(net "GND")
	)
	(segment
		(start 369.487704 -235.756958)
		(end 368.55527 -236.689392)
		(width 0.4572)
		(layer "F.Cu")
		(net "GND")
	)
	(segment
		(start 422.199816 -308.249828)
		(end 421.724836 -308.724808)
		(width 0.249936)
		(layer "F.Cu")
		(net "GND")
	)
	(segment
		(start 178.599846 -307.299868)
		(end 179.07508 -306.824888)
		(width 0.249936)
		(layer "F.Cu")
		(net "GND")
	)
	(segment
		(start 14.860016 -228.67493)
		(end 13.442188 -228.67493)
		(width 0.4572)
		(layer "F.Cu")
		(net "GND")
	)
	(segment
		(start 67.724782 -305.874928)
		(end 67.249802 -305.399948)
		(width 0.249936)
		(layer "F.Cu")
		(net "GND")
	)
	(segment
		(start 219.79128 -86.475316)
		(end 219.79128 -87.063072)
		(width 0.4572)
		(layer "F.Cu")
		(net "GND")
	)
	(segment
		(start 194.749928 -299.699934)
		(end 195.224908 -300.174914)
		(width 0.249936)
		(layer "F.Cu")
		(net "GND")
	)
	(segment
		(start 417.94811 -129.445004)
		(end 416.95751 -129.445004)
		(width 0.3556)
		(layer "F.Cu")
		(net "GND")
	)
	(segment
		(start 142.743936 -43.85691)
		(end 143.415258 -43.85691)
		(width 0.254)
		(layer "F.Cu")
		(net "GND")
	)
	(segment
		(start 323.953378 -102.328218)
		(end 323.761862 -101.865684)
		(width 0.254)
		(layer "F.Cu")
		(net "GND")
	)
	(segment
		(start 137.390124 -73.166732)
		(end 137.390124 -73.85177)
		(width 0.4572)
		(layer "F.Cu")
		(net "GND")
	)
	(segment
		(start 161.874962 -48.753014)
		(end 161.168334 -48.753014)
		(width 0.254)
		(layer "F.Cu")
		(net "GND")
	)
	(segment
		(start 54.899814 -306.349908)
		(end 54.424834 -305.874928)
		(width 0.249936)
		(layer "F.Cu")
		(net "GND")
	)
	(segment
		(start 255.801876 -81.05648)
		(end 255.425956 -81.05648)
		(width 0.2032)
		(layer "F.Cu")
		(net "GND")
	)
	(segment
		(start 278.074882 -300.174914)
		(end 278.549862 -299.699934)
		(width 0.249936)
		(layer "F.Cu")
		(net "GND")
	)
	(segment
		(start 312.274712 -290.674806)
		(end 311.799732 -291.149786)
		(width 0.249936)
		(layer "F.Cu")
		(net "GND")
	)
	(segment
		(start 58.699908 -285.449772)
		(end 58.224928 -285.924752)
		(width 0.249936)
		(layer "F.Cu")
		(net "GND")
	)
	(segment
		(start 459.077822 -365.409988)
		(end 459.077822 -364.83163)
		(width 0.3048)
		(layer "F.Cu")
		(net "GND")
	)
	(segment
		(start 419.349936 -301.599854)
		(end 419.824916 -301.124874)
		(width 0.249936)
		(layer "F.Cu")
		(net "GND")
	)
	(segment
		(start 405.96439 -140.6398)
		(end 405.63419 -140.97)
		(width 0.4572)
		(layer "F.Cu")
		(net "GND")
	)
	(segment
		(start 156.750004 -280.699718)
		(end 156.275024 -280.224738)
		(width 0.249936)
		(layer "F.Cu")
		(net "GND")
	)
	(segment
		(start 167.564562 -29.67736)
		(end 167.564562 -29.079952)
		(width 0.4572)
		(layer "F.Cu")
		(net "GND")
	)
	(segment
		(start 416.499802 -285.449772)
		(end 416.974782 -284.974792)
		(width 0.249936)
		(layer "F.Cu")
		(net "GND")
	)
	(segment
		(start 194.274948 -291.624766)
		(end 194.749928 -291.149786)
		(width 0.249936)
		(layer "F.Cu")
		(net "GND")
	)
	(segment
		(start 73.257664 -142.15491)
		(end 72.267064 -142.15491)
		(width 0.3556)
		(layer "F.Cu")
		(net "GND")
	)
	(segment
		(start 168.150032 -284.499812)
		(end 168.625012 -284.974792)
		(width 0.249936)
		(layer "F.Cu")
		(net "GND")
	)
	(segment
		(start 164.349938 -303.499774)
		(end 163.874958 -303.974754)
		(width 0.249936)
		(layer "F.Cu")
		(net "GND")
	)
	(segment
		(start 419.824916 -303.024794)
		(end 420.299896 -302.549814)
		(width 0.249936)
		(layer "F.Cu")
		(net "GND")
	)
	(segment
		(start 283.774896 -291.624766)
		(end 284.249876 -292.099746)
		(width 0.249936)
		(layer "F.Cu")
		(net "GND")
	)
	(segment
		(start 187.624974 -292.574726)
		(end 188.099954 -293.04996)
		(width 0.249936)
		(layer "F.Cu")
		(net "GND")
	)
	(segment
		(start 380.72695 -212.344)
		(end 380.111 -212.344)
		(width 0.4572)
		(layer "F.Cu")
		(net "GND")
	)
	(segment
		(start 293.27475 -284.974792)
		(end 293.74973 -285.449772)
		(width 0.249936)
		(layer "F.Cu")
		(net "GND")
	)
	(segment
		(start 6.521196 -378.133864)
		(end 6.521196 -377.517914)
		(width 0.4572)
		(layer "F.Cu")
		(net "GND")
	)
	(segment
		(start 144.382744 -28.47848)
		(end 144.0434 -28.139136)
		(width 0.254)
		(layer "F.Cu")
		(net "GND")
	)
	(segment
		(start 275.699728 -290.199826)
		(end 275.224748 -289.724846)
		(width 0.249936)
		(layer "F.Cu")
		(net "GND")
	)
	(segment
		(start 41.599866 -300.649894)
		(end 41.124886 -300.174914)
		(width 0.249936)
		(layer "F.Cu")
		(net "GND")
	)
	(segment
		(start 46.273974 -73.166732)
		(end 46.273974 -73.85177)
		(width 0.4572)
		(layer "F.Cu")
		(net "GND")
	)
	(segment
		(start 221.617286 -85.684868)
		(end 221.617286 -86.237064)
		(width 0.4572)
		(layer "F.Cu")
		(net "GND")
	)
	(segment
		(start 260.169406 -33.248092)
		(end 259.53212 -33.248092)
		(width 0.4572)
		(layer "F.Cu")
		(net "GND")
	)
	(segment
		(start 281.399742 -292.099746)
		(end 280.924762 -291.624766)
		(width 0.249936)
		(layer "F.Cu")
		(net "GND")
	)
	(segment
		(start 360.25836 -258.131564)
		(end 360.86796 -258.131564)
		(width 0.381)
		(layer "F.Cu")
		(net "GND")
	)
	(segment
		(start 57.274968 -306.824888)
		(end 56.799988 -307.299868)
		(width 0.249936)
		(layer "F.Cu")
		(net "GND")
	)
	(segment
		(start 281.851862 -125.955044)
		(end 282.842462 -125.955044)
		(width 0.3556)
		(layer "F.Cu")
		(net "GND")
	)
	(segment
		(start 293.27475 -285.924752)
		(end 292.79977 -286.399732)
		(width 0.249936)
		(layer "F.Cu")
		(net "GND")
	)
	(segment
		(start 390.849866 -276.899878)
		(end 390.374886 -276.424898)
		(width 0.249936)
		(layer "F.Cu")
		(net "GND")
	)
	(segment
		(start 392.274806 -299.224954)
		(end 392.749786 -298.74972)
		(width 0.249936)
		(layer "F.Cu")
		(net "GND")
	)
	(segment
		(start 39.699946 -292.099746)
		(end 39.224966 -292.574726)
		(width 0.249936)
		(layer "F.Cu")
		(net "GND")
	)
	(segment
		(start 391.799826 -273.099784)
		(end 391.324846 -272.624804)
		(width 0.249936)
		(layer "F.Cu")
		(net "GND")
	)
	(segment
		(start 54.899814 -284.499812)
		(end 55.374794 -284.974792)
		(width 0.249936)
		(layer "F.Cu")
		(net "GND")
	)
	(segment
		(start 277.599902 -296.8498)
		(end 278.074882 -296.37482)
		(width 0.249936)
		(layer "F.Cu")
		(net "GND")
	)
	(segment
		(start 284.249876 -285.449772)
		(end 283.774896 -284.974792)
		(width 0.249936)
		(layer "F.Cu")
		(net "GND")
	)
	(segment
		(start 89.744804 -27.79014)
		(end 88.664796 -27.79014)
		(width 0.3556)
		(layer "F.Cu")
		(net "GND")
	)
	(segment
		(start 391.799826 -290.199826)
		(end 391.324846 -289.724846)
		(width 0.249936)
		(layer "F.Cu")
		(net "GND")
	)
	(segment
		(start 121.842022 -121.103136)
		(end 122.477022 -121.103136)
		(width 0.4572)
		(layer "F.Cu")
		(net "GND")
	)
	(segment
		(start 187.149994 -288.299906)
		(end 187.624974 -288.774886)
		(width 0.249936)
		(layer "F.Cu")
		(net "GND")
	)
	(segment
		(start 312.541666 -26.606246)
		(end 312.541666 -25.971246)
		(width 0.4572)
		(layer "F.Cu")
		(net "GND")
	)
	(segment
		(start 301.349918 -303.499774)
		(end 300.874684 -303.024794)
		(width 0.249936)
		(layer "F.Cu")
		(net "GND")
	)
	(segment
		(start 297.549824 -294.94988)
		(end 298.024804 -294.4749)
		(width 0.249936)
		(layer "F.Cu")
		(net "GND")
	)
	(segment
		(start 300.874684 -288.774886)
		(end 301.349918 -288.299906)
		(width 0.249936)
		(layer "F.Cu")
		(net "GND")
	)
	(segment
		(start 272.374868 -281.174952)
		(end 272.849848 -281.649932)
		(width 0.249936)
		(layer "F.Cu")
		(net "GND")
	)
	(segment
		(start 166.725092 -306.824888)
		(end 167.200072 -307.299868)
		(width 0.249936)
		(layer "F.Cu")
		(net "GND")
	)
	(segment
		(start 221.42323 -54.067456)
		(end 220.76791 -54.067456)
		(width 0.254)
		(layer "F.Cu")
		(net "GND")
	)
	(segment
		(start 406.049988 -305.399948)
		(end 406.524968 -305.874928)
		(width 0.249936)
		(layer "F.Cu")
		(net "GND")
	)
	(segment
		(start 57.274968 -285.924752)
		(end 57.749948 -286.399732)
		(width 0.249936)
		(layer "F.Cu")
		(net "GND")
	)
	(segment
		(start 442.15939 -309.690516)
		(end 440.935618 -310.914288)
		(width 0.4572)
		(layer "F.Cu")
		(net "GND")
	)
	(segment
		(start 63.449962 -306.349908)
		(end 62.974982 -306.824888)
		(width 0.249936)
		(layer "F.Cu")
		(net "GND")
	)
	(segment
		(start 237.1598 -225.427032)
		(end 237.819438 -225.427032)
		(width 0.4572)
		(layer "F.Cu")
		(net "GND")
	)
	(segment
		(start 287.574736 -285.924752)
		(end 287.099756 -285.449772)
		(width 0.249936)
		(layer "F.Cu")
		(net "GND")
	)
	(segment
		(start 130.314954 -26.171398)
		(end 130.49631 -25.990042)
		(width 0.3556)
		(layer "F.Cu")
		(net "GND")
	)
	(segment
		(start 197.089014 -405.95804)
		(end 197.089014 -406.331166)
		(width 0.4572)
		(layer "F.Cu")
		(net "GND")
	)
	(segment
		(start 429.800004 -293.99992)
		(end 429.325024 -293.52494)
		(width 0.249936)
		(layer "F.Cu")
		(net "GND")
	)
	(segment
		(start 1.506982 -379.99035)
		(end 1.506982 -375.55424)
		(width 0.381)
		(layer "F.Cu")
		(net "GND")
	)
	(segment
		(start 165.774878 -306.824888)
		(end 166.249858 -307.299868)
		(width 0.249936)
		(layer "F.Cu")
		(net "GND")
	)
	(segment
		(start 185.250074 -288.299906)
		(end 184.77484 -288.774886)
		(width 0.249936)
		(layer "F.Cu")
		(net "GND")
	)
	(segment
		(start 70.574916 -303.024794)
		(end 70.099936 -302.549814)
		(width 0.249936)
		(layer "F.Cu")
		(net "GND")
	)
	(segment
		(start 82.689446 -64.312292)
		(end 83.44789 -64.312292)
		(width 0.4572)
		(layer "F.Cu")
		(net "GND")
	)
	(segment
		(start 176.224946 -284.974792)
		(end 175.749966 -284.499812)
		(width 0.254)
		(layer "F.Cu")
		(net "GND")
	)
	(segment
		(start 221.836742 -16.363188)
		(end 221.836742 -15.474188)
		(width 0.4572)
		(layer "F.Cu")
		(net "GND")
	)
	(segment
		(start 421.724836 -306.824888)
		(end 422.199816 -306.349908)
		(width 0.249936)
		(layer "F.Cu")
		(net "GND")
	)
	(segment
		(start 177.174906 -284.974792)
		(end 177.649886 -284.499812)
		(width 0.249936)
		(layer "F.Cu")
		(net "GND")
	)
	(segment
		(start 49.1998 -306.349908)
		(end 48.72482 -306.824888)
		(width 0.249936)
		(layer "F.Cu")
		(net "GND")
	)
	(segment
		(start 423.62501 -302.074834)
		(end 423.15003 -301.599854)
		(width 0.249936)
		(layer "F.Cu")
		(net "GND")
	)
	(segment
		(start 306.099718 -302.549814)
		(end 306.574698 -302.074834)
		(width 0.249936)
		(layer "F.Cu")
		(net "GND")
	)
	(segment
		(start 183.3499 -307.299868)
		(end 183.82488 -306.824888)
		(width 0.249936)
		(layer "F.Cu")
		(net "GND")
	)
	(segment
		(start 452.623936 -222.533464)
		(end 452.623936 -222.98152)
		(width 0.2794)
		(layer "F.Cu")
		(net "GND")
	)
	(segment
		(start 461.012032 -113.563654)
		(end 461.629506 -113.563654)
		(width 0.4572)
		(layer "F.Cu")
		(net "GND")
	)
	(segment
		(start 186.675014 -303.024794)
		(end 186.200034 -302.549814)
		(width 0.249936)
		(layer "F.Cu")
		(net "GND")
	)
	(segment
		(start 403.674834 -305.874928)
		(end 404.149814 -305.399948)
		(width 0.249936)
		(layer "F.Cu")
		(net "GND")
	)
	(segment
		(start 271.899888 -292.099746)
		(end 271.424908 -292.574726)
		(width 0.249936)
		(layer "F.Cu")
		(net "GND")
	)
	(segment
		(start 398.40408 -113.245138)
		(end 398.94256 -113.245138)
		(width 0.3556)
		(layer "F.Cu")
		(net "GND")
	)
	(segment
		(start 165.299898 -305.399948)
		(end 165.774878 -305.874928)
		(width 0.249936)
		(layer "F.Cu")
		(net "GND")
	)
	(segment
		(start 172.424852 -302.074834)
		(end 171.949872 -301.599854)
		(width 0.249936)
		(layer "F.Cu")
		(net "GND")
	)
	(segment
		(start 20.918678 -46.693836)
		(end 20.719288 -46.893226)
		(width 0.254)
		(layer "F.Cu")
		(net "GND")
	)
	(segment
		(start 47.29988 -303.499774)
		(end 47.77486 -303.024794)
		(width 0.249936)
		(layer "F.Cu")
		(net "GND")
	)
	(segment
		(start 54.424834 -305.874928)
		(end 53.949854 -306.349908)
		(width 0.249936)
		(layer "F.Cu")
		(net "GND")
	)
	(segment
		(start 177.649886 -294.94988)
		(end 178.124866 -294.4749)
		(width 0.249936)
		(layer "F.Cu")
		(net "GND")
	)
	(segment
		(start 283.299916 -301.599854)
		(end 282.824936 -302.074834)
		(width 0.249936)
		(layer "F.Cu")
		(net "GND")
	)
	(segment
		(start 289.89401 -35.499548)
		(end 290.266374 -35.871912)
		(width 0.4572)
		(layer "F.Cu")
		(net "GND")
	)
	(segment
		(start 297.549824 -306.349908)
		(end 297.074844 -305.874928)
		(width 0.249936)
		(layer "F.Cu")
		(net "GND")
	)
	(segment
		(start 418.874956 -307.774848)
		(end 419.349936 -307.299868)
		(width 0.249936)
		(layer "F.Cu")
		(net "GND")
	)
	(segment
		(start 45.257974 -73.166732)
		(end 45.257974 -73.85177)
		(width 0.4572)
		(layer "F.Cu")
		(net "GND")
	)
	(segment
		(start 386.356098 -33.19018)
		(end 384.96494 -33.19018)
		(width 0.3556)
		(layer "F.Cu")
		(net "GND")
	)
	(segment
		(start 51.099974 -284.499812)
		(end 50.624994 -284.024832)
		(width 0.249936)
		(layer "F.Cu")
		(net "GND")
	)
	(segment
		(start 77.03439 -86.949026)
		(end 77.930248 -86.949026)
		(width 0.381)
		(layer "F.Cu")
		(net "GND")
	)
	(segment
		(start 422.548304 -142.15491)
		(end 421.557704 -142.15491)
		(width 0.3556)
		(layer "F.Cu")
		(net "GND")
	)
	(segment
		(start 182.87492 -306.824888)
		(end 183.3499 -306.349908)
		(width 0.249936)
		(layer "F.Cu")
		(net "GND")
	)
	(segment
		(start 301.349918 -296.8498)
		(end 301.824898 -297.32478)
		(width 0.249936)
		(layer "F.Cu")
		(net "GND")
	)
	(segment
		(start 431.224944 -301.124874)
		(end 430.749964 -301.599854)
		(width 0.249936)
		(layer "F.Cu")
		(net "GND")
	)
	(segment
		(start 277.251668 -104.244902)
		(end 278.242268 -104.244902)
		(width 0.3556)
		(layer "F.Cu")
		(net "GND")
	)
	(segment
		(start 452.943722 -43.85691)
		(end 453.615044 -43.85691)
		(width 0.254)
		(layer "F.Cu")
		(net "GND")
	)
	(segment
		(start 59.421268 -393.56284)
		(end 58.405268 -393.56284)
		(width 0.4572)
		(layer "F.Cu")
		(net "GND")
	)
	(segment
		(start 420.074852 -48.753014)
		(end 419.368224 -48.753014)
		(width 0.254)
		(layer "F.Cu")
		(net "GND")
	)
	(segment
		(start 288.524696 -305.874928)
		(end 288.049716 -305.399948)
		(width 0.249936)
		(layer "F.Cu")
		(net "GND")
	)
	(segment
		(start 314.649866 -301.599854)
		(end 314.174886 -301.124874)
		(width 0.249936)
		(layer "F.Cu")
		(net "GND")
	)
	(segment
		(start 49.795176 -124.154946)
		(end 50.64252 -124.154946)
		(width 0.3556)
		(layer "F.Cu")
		(net "GND")
	)
	(segment
		(start 163.399978 -303.499774)
		(end 163.874958 -303.974754)
		(width 0.249936)
		(layer "F.Cu")
		(net "GND")
	)
	(segment
		(start 307.999892 -299.699934)
		(end 307.524912 -300.174914)
		(width 0.249936)
		(layer "F.Cu")
		(net "GND")
	)
	(segment
		(start 177.746406 -177.711862)
		(end 176.208182 -177.711862)
		(width 0.3048)
		(layer "F.Cu")
		(net "GND")
	)
	(segment
		(start 194.274948 -301.124874)
		(end 194.749928 -301.599854)
		(width 0.249936)
		(layer "F.Cu")
		(net "GND")
	)
	(segment
		(start 48.24984 -284.499812)
		(end 47.77486 -284.024832)
		(width 0.249936)
		(layer "F.Cu")
		(net "GND")
	)
	(segment
		(start 272.374868 -285.924752)
		(end 272.849848 -286.399732)
		(width 0.249936)
		(layer "F.Cu")
		(net "GND")
	)
	(segment
		(start 51.464464 -29.67736)
		(end 51.464464 -29.079952)
		(width 0.4572)
		(layer "F.Cu")
		(net "GND")
	)
	(segment
		(start 147.047458 -37.087048)
		(end 147.682458 -37.087048)
		(width 0.4572)
		(layer "F.Cu")
		(net "GND")
	)
	(segment
		(start 197.125082 -298.27474)
		(end 197.600062 -297.79976)
		(width 0.249936)
		(layer "F.Cu")
		(net "GND")
	)
	(segment
		(start 391.324846 -277.374858)
		(end 391.799826 -277.849838)
		(width 0.249936)
		(layer "F.Cu")
		(net "GND")
	)
	(segment
		(start 404.624794 -300.174914)
		(end 404.149814 -299.699934)
		(width 0.249936)
		(layer "F.Cu")
		(net "GND")
	)
	(segment
		(start 402.249894 -290.199826)
		(end 402.724874 -289.724846)
		(width 0.249936)
		(layer "F.Cu")
		(net "GND")
	)
	(segment
		(start 74.374756 -302.074834)
		(end 73.899776 -301.599854)
		(width 0.249936)
		(layer "F.Cu")
		(net "GND")
	)
	(segment
		(start 213.134448 -47.936658)
		(end 213.470236 -47.60087)
		(width 0.254)
		(layer "F.Cu")
		(net "GND")
	)
	(segment
		(start 200.98385 -143.582898)
		(end 199.651874 -142.250922)
		(width 0.4572)
		(layer "F.Cu")
		(net "GND")
	)
	(segment
		(start 49.858422 -122.355102)
		(end 50.64252 -122.355102)
		(width 0.3556)
		(layer "F.Cu")
		(net "GND")
	)
	(segment
		(start 231.846882 -142.889478)
		(end 232.118662 -142.617698)
		(width 0.2032)
		(layer "F.Cu")
		(net "GND")
	)
	(segment
		(start 39.699946 -295.89984)
		(end 40.174926 -296.37482)
		(width 0.249936)
		(layer "F.Cu")
		(net "GND")
	)
	(segment
		(start 399.65757 -29.784294)
		(end 399.764504 -29.67736)
		(width 0.4572)
		(layer "F.Cu")
		(net "GND")
	)
	(segment
		(start 289.94989 -307.299868)
		(end 290.42487 -306.824888)
		(width 0.249936)
		(layer "F.Cu")
		(net "GND")
	)
	(segment
		(start 69.149976 -296.8498)
		(end 69.624956 -297.32478)
		(width 0.249936)
		(layer "F.Cu")
		(net "GND")
	)
	(segment
		(start 104.643682 -45.88891)
		(end 105.315004 -45.88891)
		(width 0.254)
		(layer "F.Cu")
		(net "GND")
	)
	(segment
		(start 292.79977 -293.99992)
		(end 293.27475 -293.52494)
		(width 0.249936)
		(layer "F.Cu")
		(net "GND")
	)
	(segment
		(start 411.275022 -287.824926)
		(end 411.750002 -288.299906)
		(width 0.249936)
		(layer "F.Cu")
		(net "GND")
	)
	(segment
		(start 11.920728 -34.990024)
		(end 10.664952 -34.990024)
		(width 0.3556)
		(layer "F.Cu")
		(net "GND")
	)
	(segment
		(start 78.17485 -303.024794)
		(end 78.64983 -303.499774)
		(width 0.249936)
		(layer "F.Cu")
		(net "GND")
	)
	(segment
		(start 169.574972 -306.824888)
		(end 170.049952 -307.299868)
		(width 0.249936)
		(layer "F.Cu")
		(net "GND")
	)
	(segment
		(start 304.467006 -123.635008)
		(end 305.457606 -123.635008)
		(width 0.3556)
		(layer "F.Cu")
		(net "GND")
	)
	(segment
		(start 189.474856 -403.985222)
		(end 189.474856 -404.981918)
		(width 0.381)
		(layer "F.Cu")
		(net "GND")
	)
	(segment
		(start 149.20341 -59.971686)
		(end 149.20341 -60.627006)
		(width 0.381)
		(layer "F.Cu")
		(net "GND")
	)
	(segment
		(start 277.599902 -287.349946)
		(end 277.124922 -286.874966)
		(width 0.249936)
		(layer "F.Cu")
		(net "GND")
	)
	(segment
		(start 419.824916 -291.624766)
		(end 419.349936 -292.099746)
		(width 0.249936)
		(layer "F.Cu")
		(net "GND")
	)
	(segment
		(start 127.845058 -29.589984)
		(end 126.76505 -29.589984)
		(width 0.3556)
		(layer "F.Cu")
		(net "GND")
	)
	(segment
		(start 52.524914 -300.174914)
		(end 52.049934 -299.699934)
		(width 0.249936)
		(layer "F.Cu")
		(net "GND")
	)
	(segment
		(start 421.8305 -65.92189)
		(end 421.8305 -65.15989)
		(width 0.4572)
		(layer "F.Cu")
		(net "GND")
	)
	(segment
		(start 322.217542 -303.636426)
		(end 322.217542 -303.026826)
		(width 0.4572)
		(layer "F.Cu")
		(net "GND")
	)
	(segment
		(start 307.524912 -302.074834)
		(end 307.999892 -301.599854)
		(width 0.249936)
		(layer "F.Cu")
		(net "GND")
	)
	(segment
		(start 168.089072 -178.378358)
		(end 168.089072 -179.080922)
		(width 0.381)
		(layer "F.Cu")
		(net "GND")
	)
	(segment
		(start 296.124884 -302.074834)
		(end 296.599864 -301.599854)
		(width 0.249936)
		(layer "F.Cu")
		(net "GND")
	)
	(segment
		(start 295.649904 -301.599854)
		(end 296.124884 -302.074834)
		(width 0.249936)
		(layer "F.Cu")
		(net "GND")
	)
	(segment
		(start 424.09999 -292.099746)
		(end 424.57497 -292.574726)
		(width 0.249936)
		(layer "F.Cu")
		(net "GND")
	)
	(segment
		(start 371.51945 -4.48183)
		(end 371.51945 -3.640836)
		(width 0.4572)
		(layer "F.Cu")
		(net "GND")
	)
	(segment
		(start 395.74597 -46.693836)
		(end 395.218666 -46.693836)
		(width 0.254)
		(layer "F.Cu")
		(net "GND")
	)
	(segment
		(start 391.799826 -281.649932)
		(end 391.324846 -281.174952)
		(width 0.249936)
		(layer "F.Cu")
		(net "GND")
	)
	(segment
		(start 162.450018 -304.449734)
		(end 162.924998 -303.974754)
		(width 0.249936)
		(layer "F.Cu")
		(net "GND")
	)
	(segment
		(start 424.09999 -299.699934)
		(end 424.57497 -299.224954)
		(width 0.249936)
		(layer "F.Cu")
		(net "GND")
	)
	(segment
		(start 126.143512 -282.021534)
		(end 125.758702 -282.406344)
		(width 0.254)
		(layer "F.Cu")
		(net "GND")
	)
	(segment
		(start 87.98179 -291.258244)
		(end 88.138 -291.102034)
		(width 0.4572)
		(layer "F.Cu")
		(net "GND")
	)
	(segment
		(start 418.226494 -25.832054)
		(end 418.869876 -25.832054)
		(width 0.4572)
		(layer "F.Cu")
		(net "GND")
	)
	(segment
		(start 71.049896 -288.299906)
		(end 70.574916 -288.774886)
		(width 0.249936)
		(layer "F.Cu")
		(net "GND")
	)
	(segment
		(start 302.774858 -287.824926)
		(end 303.249838 -287.349946)
		(width 0.249936)
		(layer "F.Cu")
		(net "GND")
	)
	(segment
		(start 396.691612 -100.64496)
		(end 398.94256 -100.64496)
		(width 0.3556)
		(layer "F.Cu")
		(net "GND")
	)
	(segment
		(start 429.325024 -299.224954)
		(end 429.800004 -299.699934)
		(width 0.249936)
		(layer "F.Cu")
		(net "GND")
	)
	(segment
		(start 124.796296 -170.4848)
		(end 124.796296 -169.492422)
		(width 0.3556)
		(layer "F.Cu")
		(net "GND")
	)
	(segment
		(start 408.424888 -305.874928)
		(end 407.949908 -305.399948)
		(width 0.249936)
		(layer "F.Cu")
		(net "GND")
	)
	(segment
		(start 296.124884 -291.624766)
		(end 296.599864 -292.099746)
		(width 0.249936)
		(layer "F.Cu")
		(net "GND")
	)
	(segment
		(start 406.049988 -306.349908)
		(end 405.575008 -305.874928)
		(width 0.249936)
		(layer "F.Cu")
		(net "GND")
	)
	(segment
		(start 188.12256 -403.06879)
		(end 188.75756 -403.06879)
		(width 0.381)
		(layer "F.Cu")
		(net "GND")
	)
	(segment
		(start 300.874684 -291.624766)
		(end 300.399704 -291.149786)
		(width 0.249936)
		(layer "F.Cu")
		(net "GND")
	)
	(segment
		(start 255.911858 -344.583004)
		(end 256.651506 -343.843356)
		(width 0.4572)
		(layer "F.Cu")
		(net "GND")
	)
	(segment
		(start 385.149852 -291.149786)
		(end 384.674872 -290.674806)
		(width 0.249936)
		(layer "F.Cu")
		(net "GND")
	)
	(segment
		(start 36.849812 -294.94988)
		(end 36.374832 -294.4749)
		(width 0.249936)
		(layer "F.Cu")
		(net "GND")
	)
	(segment
		(start 182.87492 -284.974792)
		(end 183.3499 -284.499812)
		(width 0.249936)
		(layer "F.Cu")
		(net "GND")
	)
	(segment
		(start 401.774914 -289.724846)
		(end 402.249894 -290.199826)
		(width 0.249936)
		(layer "F.Cu")
		(net "GND")
	)
	(segment
		(start 185.725054 -306.824888)
		(end 185.250074 -307.299868)
		(width 0.249936)
		(layer "F.Cu")
		(net "GND")
	)
	(segment
		(start 172.424852 -285.924752)
		(end 171.949872 -286.399732)
		(width 0.249936)
		(layer "F.Cu")
		(net "GND")
	)
	(segment
		(start 406.41905 -59.974734)
		(end 405.768556 -59.974734)
		(width 0.4572)
		(layer "F.Cu")
		(net "GND")
	)
	(segment
		(start 46.34992 -293.99992)
		(end 45.87494 -293.52494)
		(width 0.249936)
		(layer "F.Cu")
		(net "GND")
	)
	(segment
		(start 398.925034 -306.824888)
		(end 398.4498 -307.299868)
		(width 0.249936)
		(layer "F.Cu")
		(net "GND")
	)
	(segment
		(start 334.09382 -211.18703)
		(end 333.694024 -210.787234)
		(width 0.254)
		(layer "F.Cu")
		(net "GND")
	)
	(segment
		(start 355.513386 -140.392404)
		(end 354.858066 -140.392404)
		(width 0.4064)
		(layer "F.Cu")
		(net "GND")
	)
	(segment
		(start 355.100128 -38.671754)
		(end 355.100128 -38.315138)
		(width 0.4572)
		(layer "F.Cu")
		(net "GND")
	)
	(segment
		(start 186.675014 -285.924752)
		(end 187.149994 -285.449772)
		(width 0.249936)
		(layer "F.Cu")
		(net "GND")
	)
	(segment
		(start 314.649866 -297.79976)
		(end 315.124846 -297.32478)
		(width 0.249936)
		(layer "F.Cu")
		(net "GND")
	)
	(segment
		(start 271.424908 -298.27474)
		(end 270.949928 -297.79976)
		(width 0.249936)
		(layer "F.Cu")
		(net "GND")
	)
	(segment
		(start 86.69274 -54.163722)
		(end 86.767924 -54.238906)
		(width 0.254)
		(layer "F.Cu")
		(net "GND")
	)
	(segment
		(start 50.14976 -301.599854)
		(end 50.624994 -302.074834)
		(width 0.249936)
		(layer "F.Cu")
		(net "GND")
	)
	(segment
		(start 75.32497 -298.27474)
		(end 75.79995 -297.79976)
		(width 0.249936)
		(layer "F.Cu")
		(net "GND")
	)
	(segment
		(start 165.774878 -306.824888)
		(end 165.299898 -306.349908)
		(width 0.249936)
		(layer "F.Cu")
		(net "GND")
	)
	(segment
		(start 224.722944 -97.96907)
		(end 224.722944 -97.31375)
		(width 0.4064)
		(layer "F.Cu")
		(net "GND")
	)
	(segment
		(start 155.282646 -140.85697)
		(end 155.652724 -140.85697)
		(width 0.4572)
		(layer "F.Cu")
		(net "GND")
	)
	(segment
		(start 386.099812 -275.949918)
		(end 385.624832 -275.474938)
		(width 0.249936)
		(layer "F.Cu")
		(net "GND")
	)
	(segment
		(start 299.866812 -149.355048)
		(end 300.857412 -149.355048)
		(width 0.3556)
		(layer "F.Cu")
		(net "GND")
	)
	(segment
		(start 307.049932 -303.499774)
		(end 307.999892 -303.499774)
		(width 0.249936)
		(layer "F.Cu")
		(net "GND")
	)
	(segment
		(start 186.200034 -293.04996)
		(end 185.725054 -292.574726)
		(width 0.249936)
		(layer "F.Cu")
		(net "GND")
	)
	(segment
		(start 419.349936 -289.249866)
		(end 419.824916 -288.774886)
		(width 0.249936)
		(layer "F.Cu")
		(net "GND")
	)
	(segment
		(start 184.29986 -303.499774)
		(end 183.82488 -303.974754)
		(width 0.249936)
		(layer "F.Cu")
		(net "GND")
	)
	(segment
		(start 398.925034 -293.52494)
		(end 399.400014 -293.99992)
		(width 0.249936)
		(layer "F.Cu")
		(net "GND")
	)
	(segment
		(start 297.549824 -292.099746)
		(end 297.074844 -291.624766)
		(width 0.249936)
		(layer "F.Cu")
		(net "GND")
	)
	(segment
		(start 422.199816 -298.74972)
		(end 421.724836 -298.27474)
		(width 0.249936)
		(layer "F.Cu")
		(net "GND")
	)
	(segment
		(start 243.694712 -158.705042)
		(end 243.694712 -159.266382)
		(width 0.254)
		(layer "F.Cu")
		(net "GND")
	)
	(segment
		(start 64.874902 -287.824926)
		(end 65.349882 -288.299906)
		(width 0.249936)
		(layer "F.Cu")
		(net "GND")
	)
	(segment
		(start 409.81884 -386.14096)
		(end 410.0068 -385.953)
		(width 0.4572)
		(layer "F.Cu")
		(net "GND")
	)
	(segment
		(start 408.899868 -290.199826)
		(end 409.374848 -289.724846)
		(width 0.249936)
		(layer "F.Cu")
		(net "GND")
	)
	(segment
		(start 281.874722 -286.874966)
		(end 282.349702 -287.349946)
		(width 0.249936)
		(layer "F.Cu")
		(net "GND")
	)
	(segment
		(start 225.91903 -308.168548)
		(end 226.558856 -308.168548)
		(width 0.1778)
		(layer "F.Cu")
		(net "GND")
	)
	(segment
		(start 16.837914 -414.369758)
		(end 16.837914 -414.985454)
		(width 0.4572)
		(layer "F.Cu")
		(net "GND")
	)
	(segment
		(start 330.473812 -73.166732)
		(end 330.473812 -73.85177)
		(width 0.4572)
		(layer "F.Cu")
		(net "GND")
	)
	(segment
		(start 407.949908 -294.94988)
		(end 408.424888 -294.4749)
		(width 0.249936)
		(layer "F.Cu")
		(net "GND")
	)
	(segment
		(start 387.999986 -274.049744)
		(end 387.525006 -273.574764)
		(width 0.249936)
		(layer "F.Cu")
		(net "GND")
	)
	(segment
		(start 422.548304 -145.755106)
		(end 421.557704 -145.755106)
		(width 0.3556)
		(layer "F.Cu")
		(net "GND")
	)
	(segment
		(start 63.36284 -382.538732)
		(end 63.283084 -382.458976)
		(width 0.4572)
		(layer "F.Cu")
		(net "GND")
	)
	(segment
		(start 157.699964 -298.74972)
		(end 158.174944 -298.27474)
		(width 0.249936)
		(layer "F.Cu")
		(net "GND")
	)
	(segment
		(start 297.074844 -285.924752)
		(end 296.599864 -285.449772)
		(width 0.249936)
		(layer "F.Cu")
		(net "GND")
	)
	(segment
		(start 429.325024 -297.32478)
		(end 429.800004 -297.79976)
		(width 0.249936)
		(layer "F.Cu")
		(net "GND")
	)
	(segment
		(start 50.64252 -107.845098)
		(end 51.632866 -107.845098)
		(width 0.4572)
		(layer "F.Cu")
		(net "GND")
	)
	(segment
		(start 452.725028 -14.735302)
		(end 452.725028 -14.100302)
		(width 0.381)
		(layer "F.Cu")
		(net "GND")
	)
	(segment
		(start 191.425068 -292.574726)
		(end 191.900048 -292.099746)
		(width 0.249936)
		(layer "F.Cu")
		(net "GND")
	)
	(segment
		(start 61.074808 -303.974754)
		(end 61.549788 -303.499774)
		(width 0.249936)
		(layer "F.Cu")
		(net "GND")
	)
	(segment
		(start 68.674742 -305.874928)
		(end 69.149976 -306.349908)
		(width 0.249936)
		(layer "F.Cu")
		(net "GND")
	)
	(segment
		(start 165.774878 -286.874966)
		(end 166.249858 -286.399732)
		(width 0.249936)
		(layer "F.Cu")
		(net "GND")
	)
	(segment
		(start 158.649924 -299.69968)
		(end 158.174944 -299.2247)
		(width 0.254)
		(layer "F.Cu")
		(net "GND")
	)
	(segment
		(start 55.374794 -297.32478)
		(end 54.899814 -297.79976)
		(width 0.249936)
		(layer "F.Cu")
		(net "GND")
	)
	(segment
		(start 414.548828 -31.390082)
		(end 415.564828 -31.390082)
		(width 0.3556)
		(layer "F.Cu")
		(net "GND")
	)
	(segment
		(start 342.093804 -226.387152)
		(end 341.694008 -226.786948)
		(width 0.381)
		(layer "F.Cu")
		(net "GND")
	)
	(segment
		(start 36.849812 -290.199826)
		(end 36.374832 -289.724846)
		(width 0.249936)
		(layer "F.Cu")
		(net "GND")
	)
	(segment
		(start 65.349882 -307.299868)
		(end 65.824862 -306.824888)
		(width 0.249936)
		(layer "F.Cu")
		(net "GND")
	)
	(segment
		(start 335.64195 -167.005)
		(end 335.026 -167.005)
		(width 0.4572)
		(layer "F.Cu")
		(net "GND")
	)
	(segment
		(start 292.32479 -306.824888)
		(end 291.84981 -307.299868)
		(width 0.249936)
		(layer "F.Cu")
		(net "GND")
	)
	(segment
		(start 163.63061 -65.92189)
		(end 163.63061 -65.15989)
		(width 0.4572)
		(layer "F.Cu")
		(net "GND")
	)
	(segment
		(start 99.375722 -121.509028)
		(end 100.011484 -121.509028)
		(width 0.4064)
		(layer "F.Cu")
		(net "GND")
	)
	(segment
		(start 185.250074 -303.499774)
		(end 184.77484 -303.024794)
		(width 0.249936)
		(layer "F.Cu")
		(net "GND")
	)
	(segment
		(start 68.199762 -286.399732)
		(end 68.674742 -286.874966)
		(width 0.249936)
		(layer "F.Cu")
		(net "GND")
	)
	(segment
		(start 426.967142 -56.354218)
		(end 426.967904 -56.353456)
		(width 0.4572)
		(layer "F.Cu")
		(net "GND")
	)
	(segment
		(start 331.06614 -94.863666)
		(end 331.002132 -94.799658)
		(width 0.4064)
		(layer "F.Cu")
		(net "GND")
	)
	(segment
		(start 296.124884 -289.724846)
		(end 296.599864 -290.199826)
		(width 0.249936)
		(layer "F.Cu")
		(net "GND")
	)
	(segment
		(start 285.674816 -300.174914)
		(end 286.149796 -299.699934)
		(width 0.249936)
		(layer "F.Cu")
		(net "GND")
	)
	(segment
		(start 255.060958 -37.201094)
		(end 254.29845 -37.201094)
		(width 0.4572)
		(layer "F.Cu")
		(net "GND")
	)
	(segment
		(start 56.799988 -306.349908)
		(end 57.274968 -305.874928)
		(width 0.249936)
		(layer "F.Cu")
		(net "GND")
	)
	(segment
		(start 272.374868 -276.424898)
		(end 272.849848 -276.899878)
		(width 0.249936)
		(layer "F.Cu")
		(net "GND")
	)
	(segment
		(start 67.66687 -129.445004)
		(end 68.65747 -129.445004)
		(width 0.3556)
		(layer "F.Cu")
		(net "GND")
	)
	(segment
		(start 298.974764 -284.974792)
		(end 298.499784 -284.499812)
		(width 0.249936)
		(layer "F.Cu")
		(net "GND")
	)
	(segment
		(start 333.730346 -121.80824)
		(end 333.117952 -121.80824)
		(width 0.4572)
		(layer "F.Cu")
		(net "GND")
	)
	(segment
		(start 297.074844 -291.624766)
		(end 296.599864 -292.099746)
		(width 0.249936)
		(layer "F.Cu")
		(net "GND")
	)
	(segment
		(start 170.049952 -286.399732)
		(end 170.524932 -285.924752)
		(width 0.249936)
		(layer "F.Cu")
		(net "GND")
	)
	(segment
		(start 263.622282 -342.4428)
		(end 264.21334 -342.4428)
		(width 0.4572)
		(layer "F.Cu")
		(net "GND")
	)
	(segment
		(start 419.824916 -298.27474)
		(end 419.349936 -297.79976)
		(width 0.249936)
		(layer "F.Cu")
		(net "GND")
	)
	(segment
		(start 165.774878 -287.824926)
		(end 166.249858 -287.349946)
		(width 0.249936)
		(layer "F.Cu")
		(net "GND")
	)
	(segment
		(start 51.574954 -294.4749)
		(end 51.099974 -293.99992)
		(width 0.249936)
		(layer "F.Cu")
		(net "GND")
	)
	(segment
		(start 186.675014 -289.724846)
		(end 187.149994 -289.249866)
		(width 0.249936)
		(layer "F.Cu")
		(net "GND")
	)
	(segment
		(start 417.924996 -291.624766)
		(end 417.450016 -292.099746)
		(width 0.249936)
		(layer "F.Cu")
		(net "GND")
	)
	(segment
		(start 431.209704 -303.024794)
		(end 431.209704 -303.040034)
		(width 0.249936)
		(layer "F.Cu")
		(net "GND")
	)
	(segment
		(start 334.86725 -239.91189)
		(end 334.86725 -239.763554)
		(width 0.3556)
		(layer "F.Cu")
		(net "GND")
	)
	(segment
		(start 421.44696 -52.592224)
		(end 421.522144 -52.51704)
		(width 0.254)
		(layer "F.Cu")
		(net "GND")
	)
	(segment
		(start 310.867806 -51.019456)
		(end 311.523126 -51.019456)
		(width 0.254)
		(layer "F.Cu")
		(net "GND")
	)
	(segment
		(start 13.220192 -394.530834)
		(end 13.220192 -395.239748)
		(width 0.4572)
		(layer "F.Cu")
		(net "GND")
	)
	(segment
		(start 173.047406 -37.087048)
		(end 173.682406 -37.087048)
		(width 0.4572)
		(layer "F.Cu")
		(net "GND")
	)
	(segment
		(start 312.585354 -34.183066)
		(end 312.4708 -34.29762)
		(width 0.4572)
		(layer "F.Cu")
		(net "GND")
	)
	(segment
		(start 306.574698 -298.27474)
		(end 307.049932 -297.79976)
		(width 0.249936)
		(layer "F.Cu")
		(net "GND")
	)
	(segment
		(start 111.777272 -160.372044)
		(end 112.007142 -160.276794)
		(width 0.1778)
		(layer "F.Cu")
		(net "GND")
	)
	(segment
		(start 271.899888 -283.549852)
		(end 271.424908 -283.074872)
		(width 0.249936)
		(layer "F.Cu")
		(net "GND")
	)
	(segment
		(start 62.499748 -303.499774)
		(end 62.974982 -303.974754)
		(width 0.249936)
		(layer "F.Cu")
		(net "GND")
	)
	(segment
		(start 143.9164 -391.668)
		(end 143.9164 -392.4808)
		(width 0.4572)
		(layer "F.Cu")
		(net "GND")
	)
	(segment
		(start 136.587738 -25.742392)
		(end 136.587738 -26.360882)
		(width 0.4572)
		(layer "F.Cu")
		(net "GND")
	)
	(segment
		(start 78.17485 -303.024794)
		(end 78.64983 -302.549814)
		(width 0.249936)
		(layer "F.Cu")
		(net "GND")
	)
	(segment
		(start 93.264736 -33.19018)
		(end 94.280736 -33.19018)
		(width 0.3556)
		(layer "F.Cu")
		(net "GND")
	)
	(segment
		(start 414.599882 -285.449772)
		(end 415.074862 -285.924752)
		(width 0.249936)
		(layer "F.Cu")
		(net "GND")
	)
	(segment
		(start 191.425068 -300.174914)
		(end 191.900048 -299.699934)
		(width 0.249936)
		(layer "F.Cu")
		(net "GND")
	)
	(segment
		(start 182.87492 -306.824888)
		(end 182.39994 -307.299868)
		(width 0.249936)
		(layer "F.Cu")
		(net "GND")
	)
	(segment
		(start 280.449782 -304.449734)
		(end 280.924762 -303.974754)
		(width 0.249936)
		(layer "F.Cu")
		(net "GND")
	)
	(segment
		(start 402.582634 -28.47848)
		(end 402.24329 -28.139136)
		(width 0.254)
		(layer "F.Cu")
		(net "GND")
	)
	(segment
		(start 60.599828 -295.89984)
		(end 61.074808 -296.37482)
		(width 0.249936)
		(layer "F.Cu")
		(net "GND")
	)
	(segment
		(start 51.574954 -306.824888)
		(end 51.099974 -306.349908)
		(width 0.249936)
		(layer "F.Cu")
		(net "GND")
	)
	(segment
		(start 306.448206 -131.245102)
		(end 305.457606 -131.245102)
		(width 0.3556)
		(layer "F.Cu")
		(net "GND")
	)
	(segment
		(start 197.600062 -292.099746)
		(end 198.075042 -291.624766)
		(width 0.249936)
		(layer "F.Cu")
		(net "GND")
	)
	(segment
		(start 408.899868 -299.699934)
		(end 409.374848 -300.174914)
		(width 0.249936)
		(layer "F.Cu")
		(net "GND")
	)
	(segment
		(start 298.024804 -291.624766)
		(end 298.499784 -292.099746)
		(width 0.249936)
		(layer "F.Cu")
		(net "GND")
	)
	(segment
		(start 71.524876 -289.724846)
		(end 71.049896 -289.249866)
		(width 0.249936)
		(layer "F.Cu")
		(net "GND")
	)
	(segment
		(start 274.274788 -297.32478)
		(end 273.799808 -296.8498)
		(width 0.249936)
		(layer "F.Cu")
		(net "GND")
	)
	(segment
		(start 284.724856 -285.924752)
		(end 284.249876 -285.449772)
		(width 0.249936)
		(layer "F.Cu")
		(net "GND")
	)
	(segment
		(start 397.97482 -302.074834)
		(end 398.4498 -302.549814)
		(width 0.249936)
		(layer "F.Cu")
		(net "GND")
	)
	(segment
		(start 279.232868 -133.565138)
		(end 278.242268 -133.565138)
		(width 0.3556)
		(layer "F.Cu")
		(net "GND")
	)
	(segment
		(start 398.925034 -287.824926)
		(end 398.4498 -288.299906)
		(width 0.249936)
		(layer "F.Cu")
		(net "GND")
	)
	(segment
		(start 173.375066 -302.074834)
		(end 173.850046 -301.599854)
		(width 0.249936)
		(layer "F.Cu")
		(net "GND")
	)
	(segment
		(start 62.499748 -306.349908)
		(end 62.024768 -306.824888)
		(width 0.249936)
		(layer "F.Cu")
		(net "GND")
	)
	(segment
		(start 62.974982 -291.624766)
		(end 63.449962 -292.099746)
		(width 0.249936)
		(layer "F.Cu")
		(net "GND")
	)
	(segment
		(start 293.74973 -290.199826)
		(end 293.27475 -289.724846)
		(width 0.249936)
		(layer "F.Cu")
		(net "GND")
	)
	(segment
		(start 396.54988 -303.499774)
		(end 396.0749 -303.024794)
		(width 0.249936)
		(layer "F.Cu")
		(net "GND")
	)
	(segment
		(start 221.061534 -181.795166)
		(end 221.747334 -181.795166)
		(width 0.3556)
		(layer "F.Cu")
		(net "GND")
	)
	(segment
		(start 184.77484 -292.574726)
		(end 184.29986 -293.04996)
		(width 0.249936)
		(layer "F.Cu")
		(net "GND")
	)
	(segment
		(start 419.334442 -47.936658)
		(end 419.67023 -47.60087)
		(width 0.254)
		(layer "F.Cu")
		(net "GND")
	)
	(segment
		(start 447.166238 -94.863666)
		(end 447.166238 -94.25178)
		(width 0.4064)
		(layer "F.Cu")
		(net "GND")
	)
	(segment
		(start 456.949048 -278.356822)
		(end 457.411582 -278.165306)
		(width 0.254)
		(layer "F.Cu")
		(net "GND")
	)
	(segment
		(start 68.199762 -301.599854)
		(end 68.674742 -302.074834)
		(width 0.249936)
		(layer "F.Cu")
		(net "GND")
	)
	(segment
		(start 176.224946 -306.824888)
		(end 176.699926 -306.349908)
		(width 0.249936)
		(layer "F.Cu")
		(net "GND")
	)
	(segment
		(start 295.649904 -286.399732)
		(end 295.174924 -285.924752)
		(width 0.249936)
		(layer "F.Cu")
		(net "GND")
	)
	(segment
		(start 117.119654 -321.556634)
		(end 115.720368 -321.556634)
		(width 0.4572)
		(layer "F.Cu")
		(net "GND")
	)
	(segment
		(start 52.999894 -301.599854)
		(end 53.474874 -302.074834)
		(width 0.249936)
		(layer "F.Cu")
		(net "GND")
	)
	(segment
		(start 242.347496 -223.51873)
		(end 242.64493 -223.51873)
		(width 0.4572)
		(layer "F.Cu")
		(net "GND")
	)
	(segment
		(start 71.049896 -285.449772)
		(end 70.574916 -284.974792)
		(width 0.249936)
		(layer "F.Cu")
		(net "GND")
	)
	(segment
		(start 311.324752 -300.174914)
		(end 311.799732 -300.649894)
		(width 0.249936)
		(layer "F.Cu")
		(net "GND")
	)
	(segment
		(start 282.824936 -306.824888)
		(end 283.299916 -307.299868)
		(width 0.249936)
		(layer "F.Cu")
		(net "GND")
	)
	(segment
		(start 91.753436 -102.328218)
		(end 91.56192 -101.865684)
		(width 0.254)
		(layer "F.Cu")
		(net "GND")
	)
	(segment
		(start 278.074882 -297.32478)
		(end 278.549862 -296.8498)
		(width 0.249936)
		(layer "F.Cu")
		(net "GND")
	)
	(segment
		(start 168.625012 -289.724846)
		(end 168.150032 -290.199826)
		(width 0.249936)
		(layer "F.Cu")
		(net "GND")
	)
	(segment
		(start 204.352144 -114.892836)
		(end 203.742544 -114.892836)
		(width 0.4572)
		(layer "F.Cu")
		(net "GND")
	)
	(segment
		(start 423.149776 -303.499774)
		(end 422.199816 -304.449734)
		(width 0.249936)
		(layer "F.Cu")
		(net "GND")
	)
	(segment
		(start 45.87494 -300.174914)
		(end 46.34992 -299.699934)
		(width 0.249936)
		(layer "F.Cu")
		(net "GND")
	)
	(segment
		(start 45.498512 -65.92189)
		(end 45.498512 -65.15989)
		(width 0.4572)
		(layer "F.Cu")
		(net "GND")
	)
	(segment
		(start 301.848012 -118.370858)
		(end 301.830486 -118.370858)
		(width 0.3556)
		(layer "F.Cu")
		(net "GND")
	)
	(segment
		(start 56.324754 -287.824926)
		(end 55.849774 -288.299906)
		(width 0.249936)
		(layer "F.Cu")
		(net "GND")
	)
	(segment
		(start 269.999714 -280.699718)
		(end 269.524734 -280.224738)
		(width 0.249936)
		(layer "F.Cu")
		(net "GND")
	)
	(segment
		(start 276.649688 -292.099746)
		(end 276.174708 -291.624766)
		(width 0.249936)
		(layer "F.Cu")
		(net "GND")
	)
	(segment
		(start 52.049934 -290.199826)
		(end 51.574954 -289.724846)
		(width 0.249936)
		(layer "F.Cu")
		(net "GND")
	)
	(segment
		(start 178.124866 -285.924752)
		(end 177.649886 -286.399732)
		(width 0.249936)
		(layer "F.Cu")
		(net "GND")
	)
	(segment
		(start 64.874902 -306.824888)
		(end 65.349882 -307.299868)
		(width 0.249936)
		(layer "F.Cu")
		(net "GND")
	)
	(segment
		(start 400.824954 -303.974754)
		(end 401.299934 -303.499774)
		(width 0.249936)
		(layer "F.Cu")
		(net "GND")
	)
	(segment
		(start 205.636368 -31.390082)
		(end 205.88859 -31.642304)
		(width 0.3556)
		(layer "F.Cu")
		(net "GND")
	)
	(segment
		(start 196.441822 -26.606246)
		(end 196.441822 -25.971246)
		(width 0.4572)
		(layer "F.Cu")
		(net "GND")
	)
	(segment
		(start 418.874956 -302.074834)
		(end 419.349936 -301.599854)
		(width 0.249936)
		(layer "F.Cu")
		(net "GND")
	)
	(segment
		(start 74.374756 -300.174914)
		(end 73.899776 -299.699934)
		(width 0.249936)
		(layer "F.Cu")
		(net "GND")
	)
	(segment
		(start 301.855124 -145.881852)
		(end 301.728378 -145.755106)
		(width 0.3556)
		(layer "F.Cu")
		(net "GND")
	)
	(segment
		(start 410.964888 -33.19018)
		(end 409.948888 -33.19018)
		(width 0.3556)
		(layer "F.Cu")
		(net "GND")
	)
	(segment
		(start 293.27475 -303.974754)
		(end 292.79977 -303.499774)
		(width 0.249936)
		(layer "F.Cu")
		(net "GND")
	)
	(segment
		(start 415.96691 -136.645142)
		(end 416.95751 -136.645142)
		(width 0.3556)
		(layer "F.Cu")
		(net "GND")
	)
	(segment
		(start 279.499822 -293.99992)
		(end 279.024842 -293.52494)
		(width 0.249936)
		(layer "F.Cu")
		(net "GND")
	)
	(segment
		(start 286.482536 -28.47848)
		(end 286.143192 -28.139136)
		(width 0.254)
		(layer "F.Cu")
		(net "GND")
	)
	(segment
		(start 396.0749 -297.32478)
		(end 395.59992 -297.79976)
		(width 0.249936)
		(layer "F.Cu")
		(net "GND")
	)
	(segment
		(start 331.574648 -203.901548)
		(end 331.574648 -202.961494)
		(width 0.4572)
		(layer "F.Cu")
		(net "GND")
	)
	(segment
		(start 292.340792 -54.163722)
		(end 292.892734 -54.163722)
		(width 0.254)
		(layer "F.Cu")
		(net "GND")
	)
	(segment
		(start 60.124848 -291.624766)
		(end 60.599828 -292.099746)
		(width 0.249936)
		(layer "F.Cu")
		(net "GND")
	)
	(segment
		(start 78.17485 -301.124874)
		(end 77.69987 -300.649894)
		(width 0.249936)
		(layer "F.Cu")
		(net "GND")
	)
	(segment
		(start 408.899868 -286.399732)
		(end 409.374848 -285.924752)
		(width 0.249936)
		(layer "F.Cu")
		(net "GND")
	)
	(segment
		(start 60.124848 -294.4749)
		(end 60.599828 -293.99992)
		(width 0.249936)
		(layer "F.Cu")
		(net "GND")
	)
	(segment
		(start 26.643838 -43.85691)
		(end 27.31516 -43.85691)
		(width 0.254)
		(layer "F.Cu")
		(net "GND")
	)
	(segment
		(start 279.499822 -292.099746)
		(end 279.024842 -291.624766)
		(width 0.249936)
		(layer "F.Cu")
		(net "GND")
	)
	(segment
		(start 172.900086 -286.399732)
		(end 172.424852 -285.924752)
		(width 0.249936)
		(layer "F.Cu")
		(net "GND")
	)
	(segment
		(start 240.300256 -63.450978)
		(end 240.300256 -64.261492)
		(width 0.4572)
		(layer "F.Cu")
		(net "GND")
	)
	(segment
		(start 185.250074 -284.499812)
		(end 185.725054 -284.024832)
		(width 0.249936)
		(layer "F.Cu")
		(net "GND")
	)
	(segment
		(start 179.844954 -27.79014)
		(end 178.764946 -27.79014)
		(width 0.3556)
		(layer "F.Cu")
		(net "GND")
	)
	(segment
		(start 197.600062 -301.599854)
		(end 198.075042 -301.124874)
		(width 0.249936)
		(layer "F.Cu")
		(net "GND")
	)
	(segment
		(start 184.29986 -291.149786)
		(end 184.77484 -291.624766)
		(width 0.249936)
		(layer "F.Cu")
		(net "GND")
	)
	(segment
		(start 313.224926 -298.27474)
		(end 313.699906 -297.79976)
		(width 0.249936)
		(layer "F.Cu")
		(net "GND")
	)
	(segment
		(start 36.849812 -286.399732)
		(end 36.374832 -285.924752)
		(width 0.249936)
		(layer "F.Cu")
		(net "GND")
	)
	(segment
		(start 46.34992 -302.549814)
		(end 46.8249 -303.024794)
		(width 0.249936)
		(layer "F.Cu")
		(net "GND")
	)
	(segment
		(start 45.051726 -124.154946)
		(end 46.042326 -124.154946)
		(width 0.3556)
		(layer "F.Cu")
		(net "GND")
	)
	(segment
		(start 277.251668 -124.154946)
		(end 278.242268 -124.154946)
		(width 0.3556)
		(layer "F.Cu")
		(net "GND")
	)
	(segment
		(start 65.824862 -297.32478)
		(end 65.349882 -296.8498)
		(width 0.249936)
		(layer "F.Cu")
		(net "GND")
	)
	(segment
		(start 163.399978 -290.199826)
		(end 162.924998 -289.724846)
		(width 0.249936)
		(layer "F.Cu")
		(net "GND")
	)
	(segment
		(start 335.64195 -143.891)
		(end 335.026 -143.891)
		(width 0.4572)
		(layer "F.Cu")
		(net "GND")
	)
	(segment
		(start 180.156104 -33.19018)
		(end 178.764946 -33.19018)
		(width 0.3556)
		(layer "F.Cu")
		(net "GND")
	)
	(segment
		(start 98.072448 -7.776972)
		(end 97.437448 -7.776972)
		(width 0.381)
		(layer "F.Cu")
		(net "GND")
	)
	(segment
		(start 56.799988 -286.399732)
		(end 57.274968 -285.924752)
		(width 0.249936)
		(layer "F.Cu")
		(net "GND")
	)
	(segment
		(start 453.960484 -15.993872)
		(end 454.376536 -15.57782)
		(width 0.4572)
		(layer "F.Cu")
		(net "GND")
	)
	(segment
		(start 250.1265 -25.832054)
		(end 250.769882 -25.832054)
		(width 0.4572)
		(layer "F.Cu")
		(net "GND")
	)
	(segment
		(start 387.85546 -233.950002)
		(end 387.85546 -232.836212)
		(width 0.254)
		(layer "F.Cu")
		(net "GND")
	)
	(segment
		(start 397.97482 -306.824888)
		(end 397.49984 -306.349908)
		(width 0.249936)
		(layer "F.Cu")
		(net "GND")
	)
	(segment
		(start 420.567104 -121.83491)
		(end 421.557704 -121.83491)
		(width 0.3556)
		(layer "F.Cu")
		(net "GND")
	)
	(segment
		(start 310.374792 -291.624766)
		(end 309.899812 -291.149786)
		(width 0.249936)
		(layer "F.Cu")
		(net "GND")
	)
	(segment
		(start 405.575008 -306.824888)
		(end 406.049988 -307.299868)
		(width 0.249936)
		(layer "F.Cu")
		(net "GND")
	)
	(segment
		(start 54.424834 -284.024832)
		(end 54.899814 -284.499812)
		(width 0.249936)
		(layer "F.Cu")
		(net "GND")
	)
	(segment
		(start 163.49345 -108.279946)
		(end 163.058602 -107.845098)
		(width 0.3556)
		(layer "F.Cu")
		(net "GND")
	)
	(segment
		(start 79.12481 -294.4749)
		(end 79.59979 -294.94988)
		(width 0.249936)
		(layer "F.Cu")
		(net "GND")
	)
	(segment
		(start 191.425068 -290.674806)
		(end 190.950088 -290.199826)
		(width 0.249936)
		(layer "F.Cu")
		(net "GND")
	)
	(segment
		(start 434.057806 -302.062134)
		(end 434.057806 -299.4406)
		(width 0.4572)
		(layer "F.Cu")
		(net "GND")
	)
	(segment
		(start 298.974764 -284.974792)
		(end 298.499784 -285.449772)
		(width 0.249936)
		(layer "F.Cu")
		(net "GND")
	)
	(segment
		(start 233.716068 -78.99019)
		(end 233.716068 -78.359254)
		(width 0.4572)
		(layer "F.Cu")
		(net "GND")
	)
	(segment
		(start 292.79977 -307.299868)
		(end 292.32479 -306.824888)
		(width 0.249936)
		(layer "F.Cu")
		(net "GND")
	)
	(segment
		(start 178.124866 -300.174914)
		(end 177.649886 -299.699934)
		(width 0.249936)
		(layer "F.Cu")
		(net "GND")
	)
	(segment
		(start 194.157346 -80.449674)
		(end 194.843146 -80.449674)
		(width 0.254)
		(layer "F.Cu")
		(net "GND")
	)
	(segment
		(start 63.680848 -25.990042)
		(end 62.664848 -25.990042)
		(width 0.3556)
		(layer "F.Cu")
		(net "GND")
	)
	(segment
		(start 106.683302 -212.0392)
		(end 107.29722 -212.0392)
		(width 0.381)
		(layer "F.Cu")
		(net "GND")
	)
	(segment
		(start 168.767252 -56.354218)
		(end 168.768014 -56.353456)
		(width 0.4572)
		(layer "F.Cu")
		(net "GND")
	)
	(segment
		(start 53.474874 -305.874928)
		(end 53.949854 -306.349908)
		(width 0.249936)
		(layer "F.Cu")
		(net "GND")
	)
	(segment
		(start 128.834134 -138.819636)
		(end 128.75895 -138.89482)
		(width 0.254)
		(layer "F.Cu")
		(net "GND")
	)
	(segment
		(start 381.403352 -59.971686)
		(end 381.403352 -60.627006)
		(width 0.381)
		(layer "F.Cu")
		(net "GND")
	)
	(segment
		(start 43.499786 -282.599892)
		(end 43.024806 -282.124912)
		(width 0.249936)
		(layer "F.Cu")
		(net "GND")
	)
	(segment
		(start 132.29463 -110.977426)
		(end 132.29463 -110.365032)
		(width 0.4572)
		(layer "F.Cu")
		(net "GND")
	)
	(segment
		(start 300.874684 -305.874928)
		(end 301.349918 -305.399948)
		(width 0.249936)
		(layer "F.Cu")
		(net "GND")
	)
	(segment
		(start 63.924942 -302.074834)
		(end 64.399922 -301.599854)
		(width 0.249936)
		(layer "F.Cu")
		(net "GND")
	)
	(segment
		(start 50.624994 -298.27474)
		(end 51.099974 -297.79976)
		(width 0.249936)
		(layer "F.Cu")
		(net "GND")
	)
	(segment
		(start 52.049934 -285.449772)
		(end 51.574954 -284.974792)
		(width 0.249936)
		(layer "F.Cu")
		(net "GND")
	)
	(segment
		(start 264.21334 -342.4428)
		(end 264.816844 -341.839296)
		(width 0.4572)
		(layer "F.Cu")
		(net "GND")
	)
	(segment
		(start 166.249858 -288.299906)
		(end 165.774878 -287.824926)
		(width 0.249936)
		(layer "F.Cu")
		(net "GND")
	)
	(segment
		(start 320.864738 -34.990024)
		(end 319.848738 -34.990024)
		(width 0.3556)
		(layer "F.Cu")
		(net "GND")
	)
	(segment
		(start 2.989072 -386.638292)
		(end 2.989072 -386.019294)
		(width 0.4572)
		(layer "F.Cu")
		(net "GND")
	)
	(segment
		(start 307.524912 -290.674806)
		(end 307.999892 -290.199826)
		(width 0.249936)
		(layer "F.Cu")
		(net "GND")
	)
	(segment
		(start 285.199836 -284.499812)
		(end 285.674816 -284.024832)
		(width 0.249936)
		(layer "F.Cu")
		(net "GND")
	)
	(segment
		(start 393.7 -287.349946)
		(end 393.22502 -286.874966)
		(width 0.249936)
		(layer "F.Cu")
		(net "GND")
	)
	(segment
		(start 312.749692 -289.249866)
		(end 312.274712 -288.774886)
		(width 0.249936)
		(layer "F.Cu")
		(net "GND")
	)
	(segment
		(start 193.799968 -294.94988)
		(end 194.274948 -294.4749)
		(width 0.249936)
		(layer "F.Cu")
		(net "GND")
	)
	(segment
		(start 45.39996 -296.8498)
		(end 44.92498 -297.32478)
		(width 0.249936)
		(layer "F.Cu")
		(net "GND")
	)
	(segment
		(start 297.549824 -290.199826)
		(end 298.024804 -289.724846)
		(width 0.249936)
		(layer "F.Cu")
		(net "GND")
	)
	(segment
		(start 82.449924 -290.199826)
		(end 82.924904 -289.724846)
		(width 0.249936)
		(layer "F.Cu")
		(net "GND")
	)
	(segment
		(start 398.4498 -289.249866)
		(end 397.97482 -288.774886)
		(width 0.249936)
		(layer "F.Cu")
		(net "GND")
	)
	(segment
		(start 9.195054 -59.978036)
		(end 9.195054 -60.633356)
		(width 0.4572)
		(layer "F.Cu")
		(net "GND")
	)
	(segment
		(start 68.199762 -284.499812)
		(end 68.674742 -284.974792)
		(width 0.249936)
		(layer "F.Cu")
		(net "GND")
	)
	(segment
		(start 287.574736 -306.824888)
		(end 287.099756 -307.299868)
		(width 0.249936)
		(layer "F.Cu")
		(net "GND")
	)
	(segment
		(start 44.45 -300.649894)
		(end 44.92498 -301.124874)
		(width 0.254)
		(layer "F.Cu")
		(net "GND")
	)
	(segment
		(start 243.248434 -251.159772)
		(end 243.248434 -251.857256)
		(width 0.4572)
		(layer "F.Cu")
		(net "GND")
	)
	(segment
		(start 397.49984 -305.399948)
		(end 397.97482 -305.874928)
		(width 0.249936)
		(layer "F.Cu")
		(net "GND")
	)
	(segment
		(start 418.399976 -292.099746)
		(end 417.924996 -291.624766)
		(width 0.249936)
		(layer "F.Cu")
		(net "GND")
	)
	(segment
		(start 51.574954 -303.974754)
		(end 52.049934 -303.499774)
		(width 0.249936)
		(layer "F.Cu")
		(net "GND")
	)
	(segment
		(start 74.248264 -156.554932)
		(end 73.257664 -156.554932)
		(width 0.3556)
		(layer "F.Cu")
		(net "GND")
	)
	(segment
		(start 299.46473 -33.19018)
		(end 300.48073 -33.19018)
		(width 0.3556)
		(layer "F.Cu")
		(net "GND")
	)
	(segment
		(start 411.750002 -306.349908)
		(end 412.224982 -306.824888)
		(width 0.249936)
		(layer "F.Cu")
		(net "GND")
	)
	(segment
		(start 299.924724 -287.824926)
		(end 300.399704 -288.299906)
		(width 0.249936)
		(layer "F.Cu")
		(net "GND")
	)
	(segment
		(start 422.674796 -298.27474)
		(end 422.199816 -298.74972)
		(width 0.249936)
		(layer "F.Cu")
		(net "GND")
	)
	(segment
		(start 77.69987 -298.74972)
		(end 77.22489 -299.224954)
		(width 0.249936)
		(layer "F.Cu")
		(net "GND")
	)
	(segment
		(start 362.268262 -357.556308)
		(end 362.915708 -357.556308)
		(width 0.4572)
		(layer "F.Cu")
		(net "GND")
	)
	(segment
		(start 63.283084 -382.458976)
		(end 63.283084 -381.838454)
		(width 0.4572)
		(layer "F.Cu")
		(net "GND")
	)
	(segment
		(start 67.66687 -145.755106)
		(end 68.65747 -145.755106)
		(width 0.3556)
		(layer "F.Cu")
		(net "GND")
	)
	(segment
		(start 426.47489 -303.024794)
		(end 426.94987 -303.499774)
		(width 0.249936)
		(layer "F.Cu")
		(net "GND")
	)
	(segment
		(start 38.749986 -281.649932)
		(end 38.275006 -281.174952)
		(width 0.249936)
		(layer "F.Cu")
		(net "GND")
	)
	(segment
		(start 70.574916 -288.774886)
		(end 70.099936 -289.249866)
		(width 0.249936)
		(layer "F.Cu")
		(net "GND")
	)
	(segment
		(start 162.924998 -304.924714)
		(end 162.450018 -305.399948)
		(width 0.249936)
		(layer "F.Cu")
		(net "GND")
	)
	(segment
		(start 215.7984 -232.063544)
		(end 215.551512 -231.816656)
		(width 0.4572)
		(layer "F.Cu")
		(net "GND")
	)
	(segment
		(start 288.99993 -293.99992)
		(end 288.524696 -293.52494)
		(width 0.249936)
		(layer "F.Cu")
		(net "GND")
	)
	(segment
		(start 430.749964 -295.89984)
		(end 431.224944 -296.37482)
		(width 0.249936)
		(layer "F.Cu")
		(net "GND")
	)
	(segment
		(start 283.833062 -98.845116)
		(end 282.842462 -98.845116)
		(width 0.3556)
		(layer "F.Cu")
		(net "GND")
	)
	(segment
		(start 283.833062 -104.244902)
		(end 282.842462 -104.244902)
		(width 0.3556)
		(layer "F.Cu")
		(net "GND")
	)
	(segment
		(start 67.66687 -125.435106)
		(end 68.65747 -125.435106)
		(width 0.3556)
		(layer "F.Cu")
		(net "GND")
	)
	(segment
		(start 407.100024 -38.671754)
		(end 407.100024 -38.315138)
		(width 0.4572)
		(layer "F.Cu")
		(net "GND")
	)
	(segment
		(start 15.231364 -126.394718)
		(end 15.231364 -126.530862)
		(width 0.2032)
		(layer "F.Cu")
		(net "GND")
	)
	(segment
		(start 135.348472 -247.104916)
		(end 135.348472 -246.13743)
		(width 0.4572)
		(layer "F.Cu")
		(net "GND")
	)
	(segment
		(start 183.766714 -156.554932)
		(end 184.757314 -156.554932)
		(width 0.3556)
		(layer "F.Cu")
		(net "GND")
	)
	(segment
		(start 35.6489 -31.390082)
		(end 36.6649 -31.390082)
		(width 0.3556)
		(layer "F.Cu")
		(net "GND")
	)
	(segment
		(start 278.549862 -288.299906)
		(end 278.074882 -287.824926)
		(width 0.249936)
		(layer "F.Cu")
		(net "GND")
	)
	(segment
		(start 186.200034 -290.199826)
		(end 186.675014 -290.674806)
		(width 0.249936)
		(layer "F.Cu")
		(net "GND")
	)
	(segment
		(start 410.324808 -294.4749)
		(end 409.849828 -294.94988)
		(width 0.249936)
		(layer "F.Cu")
		(net "GND")
	)
	(segment
		(start 283.833062 -111.44504)
		(end 282.842462 -111.44504)
		(width 0.3556)
		(layer "F.Cu")
		(net "GND")
	)
	(segment
		(start 270.949928 -285.449772)
		(end 270.474948 -284.974792)
		(width 0.249936)
		(layer "F.Cu")
		(net "GND")
	)
	(segment
		(start 386.099812 -298.74972)
		(end 386.574792 -298.27474)
		(width 0.249936)
		(layer "F.Cu")
		(net "GND")
	)
	(segment
		(start 306.448206 -152.95499)
		(end 305.457606 -152.95499)
		(width 0.3556)
		(layer "F.Cu")
		(net "GND")
	)
	(segment
		(start 306.099718 -293.99992)
		(end 306.574698 -294.4749)
		(width 0.249936)
		(layer "F.Cu")
		(net "GND")
	)
	(segment
		(start 397.49984 -293.99992)
		(end 397.97482 -294.4749)
		(width 0.249936)
		(layer "F.Cu")
		(net "GND")
	)
	(segment
		(start 177.649886 -285.449772)
		(end 178.124866 -284.974792)
		(width 0.249936)
		(layer "F.Cu")
		(net "GND")
	)
	(segment
		(start 61.074808 -291.624766)
		(end 60.599828 -292.099746)
		(width 0.249936)
		(layer "F.Cu")
		(net "GND")
	)
	(segment
		(start 53.949854 -303.499774)
		(end 53.474874 -303.974754)
		(width 0.249936)
		(layer "F.Cu")
		(net "GND")
	)
	(segment
		(start 187.624974 -288.774886)
		(end 187.149994 -289.249866)
		(width 0.249936)
		(layer "F.Cu")
		(net "GND")
	)
	(segment
		(start 427.89983 -289.249866)
		(end 427.42485 -288.774886)
		(width 0.249936)
		(layer "F.Cu")
		(net "GND")
	)
	(segment
		(start 413.649922 -306.349908)
		(end 414.124902 -305.874928)
		(width 0.249936)
		(layer "F.Cu")
		(net "GND")
	)
	(segment
		(start 24.342344 -252.756924)
		(end 24.342344 -253.45644)
		(width 0.4572)
		(layer "F.Cu")
		(net "GND")
	)
	(segment
		(start 28.366974 -306.083462)
		(end 28.54071 -306.083462)
		(width 0.4572)
		(layer "F.Cu")
		(net "GND")
	)
	(segment
		(start 425.04995 -293.04996)
		(end 425.52493 -293.52494)
		(width 0.249936)
		(layer "F.Cu")
		(net "GND")
	)
	(segment
		(start 389.899906 -290.199826)
		(end 389.424926 -289.724846)
		(width 0.249936)
		(layer "F.Cu")
		(net "GND")
	)
	(segment
		(start 61.074808 -284.974792)
		(end 61.549788 -284.499812)
		(width 0.249936)
		(layer "F.Cu")
		(net "GND")
	)
	(segment
		(start 79.12481 -300.174914)
		(end 78.64983 -300.649894)
		(width 0.249936)
		(layer "F.Cu")
		(net "GND")
	)
	(segment
		(start 165.299898 -292.099746)
		(end 164.824918 -291.624766)
		(width 0.249936)
		(layer "F.Cu")
		(net "GND")
	)
	(segment
		(start 47.289974 -73.166732)
		(end 47.289974 -73.85177)
		(width 0.4572)
		(layer "F.Cu")
		(net "GND")
	)
	(segment
		(start 153.89987 -298.74972)
		(end 153.424636 -298.27474)
		(width 0.249936)
		(layer "F.Cu")
		(net "GND")
	)
	(segment
		(start 401.774914 -294.4749)
		(end 401.299934 -293.99992)
		(width 0.249936)
		(layer "F.Cu")
		(net "GND")
	)
	(segment
		(start 293.74973 -292.099746)
		(end 294.22471 -291.624766)
		(width 0.249936)
		(layer "F.Cu")
		(net "GND")
	)
	(segment
		(start 405.575008 -294.4749)
		(end 406.049988 -294.94988)
		(width 0.249936)
		(layer "F.Cu")
		(net "GND")
	)
	(segment
		(start 183.766714 -134.845044)
		(end 184.757314 -134.845044)
		(width 0.3556)
		(layer "F.Cu")
		(net "GND")
	)
	(segment
		(start 51.099974 -290.199826)
		(end 50.624994 -289.724846)
		(width 0.249936)
		(layer "F.Cu")
		(net "GND")
	)
	(segment
		(start 242.254024 -160.70707)
		(end 242.254024 -162.672014)
		(width 0.254)
		(layer "F.Cu")
		(net "GND")
	)
	(segment
		(start 167.200072 -297.79976)
		(end 166.725092 -298.27474)
		(width 0.249936)
		(layer "F.Cu")
		(net "GND")
	)
	(segment
		(start 404.172166 -33.248092)
		(end 404.172166 -33.857692)
		(width 0.4572)
		(layer "F.Cu")
		(net "GND")
	)
	(segment
		(start 282.349702 -307.299868)
		(end 281.874722 -306.824888)
		(width 0.249936)
		(layer "F.Cu")
		(net "GND")
	)
	(segment
		(start 300.879764 -303.969928)
		(end 301.349918 -303.499774)
		(width 0.249936)
		(layer "F.Cu")
		(net "GND")
	)
	(segment
		(start 396.54988 -304.449734)
		(end 396.0749 -303.974754)
		(width 0.249936)
		(layer "F.Cu")
		(net "GND")
	)
	(segment
		(start 242.864894 -29.589984)
		(end 241.848894 -29.589984)
		(width 0.3556)
		(layer "F.Cu")
		(net "GND")
	)
	(segment
		(start 306.099718 -296.8498)
		(end 305.624738 -296.37482)
		(width 0.249936)
		(layer "F.Cu")
		(net "GND")
	)
	(segment
		(start 380.034038 -8.900922)
		(end 380.649734 -8.900922)
		(width 0.4572)
		(layer "F.Cu")
		(net "GND")
	)
	(segment
		(start 286.624776 -306.824888)
		(end 286.149796 -307.299868)
		(width 0.249936)
		(layer "F.Cu")
		(net "GND")
	)
	(segment
		(start 57.749948 -301.599854)
		(end 58.224928 -302.074834)
		(width 0.249936)
		(layer "F.Cu")
		(net "GND")
	)
	(segment
		(start 179.07508 -284.974792)
		(end 178.599846 -285.449772)
		(width 0.249936)
		(layer "F.Cu")
		(net "GND")
	)
	(segment
		(start 292.892734 -54.163722)
		(end 292.967918 -54.238906)
		(width 0.254)
		(layer "F.Cu")
		(net "GND")
	)
	(segment
		(start 429.325024 -291.624766)
		(end 428.84979 -291.149786)
		(width 0.249936)
		(layer "F.Cu")
		(net "GND")
	)
	(segment
		(start 171.949872 -292.099746)
		(end 172.424852 -291.624766)
		(width 0.249936)
		(layer "F.Cu")
		(net "GND")
	)
	(segment
		(start 450.682106 -365.89589)
		(end 450.682106 -365.24565)
		(width 0.4572)
		(layer "F.Cu")
		(net "GND")
	)
	(segment
		(start 99.733862 -383.0574)
		(end 99.17938 -383.611882)
		(width 0.4572)
		(layer "F.Cu")
		(net "GND")
	)
	(segment
		(start 233.39044 -58.799984)
		(end 233.516424 -58.674)
		(width 0.3556)
		(layer "F.Cu")
		(net "GND")
	)
	(segment
		(start 160.549844 -293.99992)
		(end 160.074864 -293.52494)
		(width 0.249936)
		(layer "F.Cu")
		(net "GND")
	)
	(segment
		(start 158.649924 -289.249866)
		(end 158.174944 -289.724846)
		(width 0.254)
		(layer "F.Cu")
		(net "GND")
	)
	(segment
		(start 112.40516 -158.87319)
		(end 113.21923 -158.87319)
		(width 0.381)
		(layer "F.Cu")
		(net "GND")
	)
	(segment
		(start 404.624794 -303.974754)
		(end 405.100028 -303.499774)
		(width 0.249936)
		(layer "F.Cu")
		(net "GND")
	)
	(segment
		(start 279.974802 -305.874928)
		(end 279.499822 -305.399948)
		(width 0.249936)
		(layer "F.Cu")
		(net "GND")
	)
	(segment
		(start 429.702722 -89.1159)
		(end 429.702722 -89.790524)
		(width 0.4572)
		(layer "F.Cu")
		(net "GND")
	)
	(segment
		(start 242.864894 -25.990042)
		(end 241.848894 -25.990042)
		(width 0.3556)
		(layer "F.Cu")
		(net "GND")
	)
	(segment
		(start 62.024768 -285.924752)
		(end 61.549788 -286.399732)
		(width 0.249936)
		(layer "F.Cu")
		(net "GND")
	)
	(segment
		(start 371.161056 -37.201094)
		(end 370.398548 -37.201094)
		(width 0.4572)
		(layer "F.Cu")
		(net "GND")
	)
	(segment
		(start 381.786384 -252.756924)
		(end 381.786384 -253.45644)
		(width 0.4572)
		(layer "F.Cu")
		(net "GND")
	)
	(segment
		(start 177.748946 -31.390082)
		(end 178.764946 -31.390082)
		(width 0.3556)
		(layer "F.Cu")
		(net "GND")
	)
	(segment
		(start 193.324988 -299.224954)
		(end 193.799968 -298.74972)
		(width 0.249936)
		(layer "F.Cu")
		(net "GND")
	)
	(segment
		(start 398.214596 -109.644942)
		(end 398.94256 -109.644942)
		(width 0.3556)
		(layer "F.Cu")
		(net "GND")
	)
	(segment
		(start 202.888088 -354.229162)
		(end 203.359258 -353.757992)
		(width 0.4572)
		(layer "F.Cu")
		(net "GND")
	)
	(segment
		(start 259.437124 -306.217066)
		(end 259.190236 -306.217066)
		(width 0.4572)
		(layer "F.Cu")
		(net "GND")
	)
	(segment
		(start 84.118958 -59.974734)
		(end 83.468464 -59.974734)
		(width 0.4572)
		(layer "F.Cu")
		(net "GND")
	)
	(segment
		(start 406.524968 -289.724846)
		(end 406.999948 -290.199826)
		(width 0.249936)
		(layer "F.Cu")
		(net "GND")
	)
	(segment
		(start 178.599846 -307.299868)
		(end 178.124866 -306.824888)
		(width 0.249936)
		(layer "F.Cu")
		(net "GND")
	)
	(segment
		(start 183.766714 -149.355048)
		(end 184.757314 -149.355048)
		(width 0.3556)
		(layer "F.Cu")
		(net "GND")
	)
	(segment
		(start 443.194186 -117.426486)
		(end 443.829186 -117.426486)
		(width 0.4572)
		(layer "F.Cu")
		(net "GND")
	)
	(segment
		(start 46.87443 -122.355102)
		(end 46.042326 -122.355102)
		(width 0.3556)
		(layer "F.Cu")
		(net "GND")
	)
	(segment
		(start 411.275022 -285.924752)
		(end 411.750002 -285.449772)
		(width 0.249936)
		(layer "F.Cu")
		(net "GND")
	)
	(segment
		(start 36.849812 -293.04996)
		(end 36.374832 -292.57498)
		(width 0.249936)
		(layer "F.Cu")
		(net "GND")
	)
	(segment
		(start 73.424796 -293.52494)
		(end 73.899776 -293.04996)
		(width 0.249936)
		(layer "F.Cu")
		(net "GND")
	)
	(segment
		(start 180.50002 -301.599854)
		(end 180.975 -302.074834)
		(width 0.249936)
		(layer "F.Cu")
		(net "GND")
	)
	(segment
		(start 52.049934 -306.349908)
		(end 51.574954 -306.824888)
		(width 0.249936)
		(layer "F.Cu")
		(net "GND")
	)
	(segment
		(start 74.84999 -297.79976)
		(end 74.374756 -298.27474)
		(width 0.249936)
		(layer "F.Cu")
		(net "GND")
	)
	(segment
		(start 304.45837 -116.9035)
		(end 304.45837 -116.69522)
		(width 0.3556)
		(layer "F.Cu")
		(net "GND")
	)
	(segment
		(start 415.549842 -301.599854)
		(end 416.024822 -302.074834)
		(width 0.249936)
		(layer "F.Cu")
		(net "GND")
	)
	(segment
		(start 193.799968 -289.249866)
		(end 194.274948 -289.724846)
		(width 0.249936)
		(layer "F.Cu")
		(net "GND")
	)
	(segment
		(start 179.07508 -287.824926)
		(end 178.599846 -288.299906)
		(width 0.249936)
		(layer "F.Cu")
		(net "GND")
	)
	(segment
		(start 422.674796 -305.874928)
		(end 422.199816 -305.399948)
		(width 0.249936)
		(layer "F.Cu")
		(net "GND")
	)
	(segment
		(start 48.24984 -285.449772)
		(end 47.77486 -284.974792)
		(width 0.249936)
		(layer "F.Cu")
		(net "GND")
	)
	(segment
		(start 117.1702 -284.734)
		(end 117.1702 -285.263336)
		(width 0.2286)
		(layer "F.Cu")
		(net "GND")
	)
	(segment
		(start 164.349938 -293.04996)
		(end 164.824918 -293.52494)
		(width 0.249936)
		(layer "F.Cu")
		(net "GND")
	)
	(segment
		(start 409.415488 -84.488528)
		(end 408.49296 -83.566)
		(width 0.4572)
		(layer "F.Cu")
		(net "GND")
	)
	(segment
		(start 187.624974 -291.624766)
		(end 187.149994 -291.149786)
		(width 0.249936)
		(layer "F.Cu")
		(net "GND")
	)
	(segment
		(start 36.849812 -284.499812)
		(end 36.374832 -284.024832)
		(width 0.249936)
		(layer "F.Cu")
		(net "GND")
	)
	(segment
		(start 194.274948 -293.52494)
		(end 194.749928 -293.04996)
		(width 0.249936)
		(layer "F.Cu")
		(net "GND")
	)
	(segment
		(start 405.575008 -284.024832)
		(end 406.049988 -284.499812)
		(width 0.249936)
		(layer "F.Cu")
		(net "GND")
	)
	(segment
		(start 187.624974 -301.124874)
		(end 187.149994 -300.649894)
		(width 0.249936)
		(layer "F.Cu")
		(net "GND")
	)
	(segment
		(start 430.274984 -299.224954)
		(end 430.749964 -299.699934)
		(width 0.249936)
		(layer "F.Cu")
		(net "GND")
	)
	(segment
		(start 194.274948 -297.32478)
		(end 193.799968 -296.8498)
		(width 0.249936)
		(layer "F.Cu")
		(net "GND")
	)
	(segment
		(start 66.774822 -289.724846)
		(end 66.299842 -290.199826)
		(width 0.249936)
		(layer "F.Cu")
		(net "GND")
	)
	(segment
		(start 173.375066 -285.924752)
		(end 173.850046 -286.399732)
		(width 0.249936)
		(layer "F.Cu")
		(net "GND")
	)
	(segment
		(start 70.099936 -302.549814)
		(end 70.574916 -302.074834)
		(width 0.249936)
		(layer "F.Cu")
		(net "GND")
	)
	(segment
		(start 38.566344 -252.756924)
		(end 38.566344 -253.45644)
		(width 0.4572)
		(layer "F.Cu")
		(net "GND")
	)
	(segment
		(start 424.09999 -293.99992)
		(end 424.57497 -293.52494)
		(width 0.249936)
		(layer "F.Cu")
		(net "GND")
	)
	(segment
		(start 163.874958 -303.974754)
		(end 163.399978 -304.449734)
		(width 0.249936)
		(layer "F.Cu")
		(net "GND")
	)
	(segment
		(start 183.364886 -34.990024)
		(end 181.483 -34.990024)
		(width 0.3556)
		(layer "F.Cu")
		(net "GND")
	)
	(segment
		(start 304.199798 -293.04996)
		(end 304.674778 -292.574726)
		(width 0.249936)
		(layer "F.Cu")
		(net "GND")
	)
	(segment
		(start 169.099992 -301.599854)
		(end 168.625012 -302.074834)
		(width 0.249936)
		(layer "F.Cu")
		(net "GND")
	)
	(segment
		(start 176.224946 -305.874928)
		(end 175.749966 -306.349908)
		(width 0.249936)
		(layer "F.Cu")
		(net "GND")
	)
	(segment
		(start 64.874902 -307.774848)
		(end 64.399922 -307.299868)
		(width 0.249936)
		(layer "F.Cu")
		(net "GND")
	)
	(segment
		(start 413.649922 -290.199826)
		(end 413.174942 -289.724846)
		(width 0.249936)
		(layer "F.Cu")
		(net "GND")
	)
	(segment
		(start 189.524894 -298.27474)
		(end 189.999874 -298.74972)
		(width 0.249936)
		(layer "F.Cu")
		(net "GND")
	)
	(segment
		(start 386.099812 -280.699718)
		(end 385.624832 -280.224738)
		(width 0.249936)
		(layer "F.Cu")
		(net "GND")
	)
	(segment
		(start 366.226598 -25.832054)
		(end 366.86998 -25.832054)
		(width 0.4572)
		(layer "F.Cu")
		(net "GND")
	)
	(segment
		(start 287.099756 -301.599854)
		(end 286.624776 -302.074834)
		(width 0.249936)
		(layer "F.Cu")
		(net "GND")
	)
	(segment
		(start 62.024768 -294.4749)
		(end 62.499748 -293.99992)
		(width 0.249936)
		(layer "F.Cu")
		(net "GND")
	)
	(segment
		(start 79.59979 -293.04996)
		(end 79.12481 -292.574726)
		(width 0.249936)
		(layer "F.Cu")
		(net "GND")
	)
	(segment
		(start 203.495656 -87.303102)
		(end 203.183998 -87.61476)
		(width 0.4572)
		(layer "F.Cu")
		(net "GND")
	)
	(segment
		(start 178.599846 -293.99992)
		(end 179.07508 -293.52494)
		(width 0.249936)
		(layer "F.Cu")
		(net "GND")
	)
	(segment
		(start 408.824938 -288.299906)
		(end 408.899868 -288.299906)
		(width 0.249936)
		(layer "F.Cu")
		(net "GND")
	)
	(segment
		(start 165.774878 -307.774848)
		(end 166.249858 -307.299868)
		(width 0.249936)
		(layer "F.Cu")
		(net "GND")
	)
	(segment
		(start 289.47491 -289.724846)
		(end 288.99993 -290.199826)
		(width 0.249936)
		(layer "F.Cu")
		(net "GND")
	)
	(segment
		(start 274.274788 -298.27474)
		(end 273.799808 -298.74972)
		(width 0.249936)
		(layer "F.Cu")
		(net "GND")
	)
	(segment
		(start 72.228964 -147.314412)
		(end 72.469502 -147.55495)
		(width 0.3556)
		(layer "F.Cu")
		(net "GND")
	)
	(segment
		(start 231.807512 -235.128054)
		(end 231.807512 -235.737654)
		(width 0.4572)
		(layer "F.Cu")
		(net "GND")
	)
	(segment
		(start 46.34992 -291.149786)
		(end 45.87494 -290.674806)
		(width 0.249936)
		(layer "F.Cu")
		(net "GND")
	)
	(segment
		(start 163.13277 -131.76504)
		(end 162.14217 -131.76504)
		(width 0.3556)
		(layer "F.Cu")
		(net "GND")
	)
	(segment
		(start 187.149994 -302.549814)
		(end 186.675014 -302.074834)
		(width 0.249936)
		(layer "F.Cu")
		(net "GND")
	)
	(segment
		(start 278.549862 -298.74972)
		(end 278.074882 -299.224954)
		(width 0.249936)
		(layer "F.Cu")
		(net "GND")
	)
	(segment
		(start 167.675052 -300.174914)
		(end 167.200072 -299.699934)
		(width 0.249936)
		(layer "F.Cu")
		(net "GND")
	)
	(segment
		(start 60.124848 -285.924752)
		(end 60.599828 -286.399732)
		(width 0.249936)
		(layer "F.Cu")
		(net "GND")
	)
	(segment
		(start 394.574014 -73.166732)
		(end 394.574014 -73.85177)
		(width 0.4572)
		(layer "F.Cu")
		(net "GND")
	)
	(segment
		(start 185.42 -125.435106)
		(end 184.757314 -125.435106)
		(width 0.3556)
		(layer "F.Cu")
		(net "GND")
	)
	(segment
		(start 288.524696 -284.974792)
		(end 288.99993 -284.499812)
		(width 0.249936)
		(layer "F.Cu")
		(net "GND")
	)
	(segment
		(start 293.74973 -286.399732)
		(end 293.27475 -285.924752)
		(width 0.249936)
		(layer "F.Cu")
		(net "GND")
	)
	(segment
		(start 80.07477 -288.774886)
		(end 79.59979 -289.249866)
		(width 0.249936)
		(layer "F.Cu")
		(net "GND")
	)
	(segment
		(start 226.790504 -278.041862)
		(end 226.32797 -278.233378)
		(width 0.254)
		(layer "F.Cu")
		(net "GND")
	)
	(segment
		(start 56.940704 -379.175264)
		(end 57.333134 -379.567694)
		(width 0.4572)
		(layer "F.Cu")
		(net "GND")
	)
	(segment
		(start 246.958612 -236.83468)
		(end 246.39905 -236.275118)
		(width 0.4572)
		(layer "F.Cu")
		(net "GND")
	)
	(segment
		(start 180.02504 -294.4749)
		(end 179.55006 -294.94988)
		(width 0.249936)
		(layer "F.Cu")
		(net "GND")
	)
	(segment
		(start 458.0001 -110.22965)
		(end 458.465936 -110.22965)
		(width 0.254)
		(layer "F.Cu")
		(net "GND")
	)
	(segment
		(start 181.92496 -294.4749)
		(end 182.39994 -293.99992)
		(width 0.249936)
		(layer "F.Cu")
		(net "GND")
	)
	(segment
		(start 285.199836 -293.99992)
		(end 285.674816 -294.4749)
		(width 0.249936)
		(layer "F.Cu")
		(net "GND")
	)
	(segment
		(start 422.548304 -121.83491)
		(end 421.557704 -121.83491)
		(width 0.3556)
		(layer "F.Cu")
		(net "GND")
	)
	(segment
		(start 416.024822 -303.974754)
		(end 415.549842 -303.499774)
		(width 0.249936)
		(layer "F.Cu")
		(net "GND")
	)
	(segment
		(start 399.400014 -301.599854)
		(end 398.925034 -302.074834)
		(width 0.249936)
		(layer "F.Cu")
		(net "GND")
	)
	(segment
		(start 69.624956 -306.824888)
		(end 69.149976 -306.349908)
		(width 0.249936)
		(layer "F.Cu")
		(net "GND")
	)
	(segment
		(start 344.49385 -220.78696)
		(end 344.893646 -221.186756)
		(width 0.381)
		(layer "F.Cu")
		(net "GND")
	)
	(segment
		(start 409.849828 -307.299868)
		(end 410.324808 -306.824888)
		(width 0.249936)
		(layer "F.Cu")
		(net "GND")
	)
	(segment
		(start 336.351118 -198.27113)
		(end 336.753708 -198.67372)
		(width 0.4572)
		(layer "F.Cu")
		(net "GND")
	)
	(segment
		(start 302.299878 -284.499812)
		(end 302.774858 -284.024832)
		(width 0.249936)
		(layer "F.Cu")
		(net "GND")
	)
	(segment
		(start 298.024804 -285.924752)
		(end 297.549824 -285.449772)
		(width 0.249936)
		(layer "F.Cu")
		(net "GND")
	)
	(segment
		(start 69.624956 -291.624766)
		(end 69.149976 -292.099746)
		(width 0.249936)
		(layer "F.Cu")
		(net "GND")
	)
	(segment
		(start 306.448206 -116.435124)
		(end 305.457606 -116.435124)
		(width 0.3556)
		(layer "F.Cu")
		(net "GND")
	)
	(segment
		(start 36.849812 -298.74972)
		(end 36.849812 -298.749466)
		(width 0.254)
		(layer "F.Cu")
		(net "GND")
	)
	(segment
		(start 172.425106 -296.37482)
		(end 171.950126 -296.8498)
		(width 0.249936)
		(layer "F.Cu")
		(net "GND")
	)
	(segment
		(start 56.799988 -297.79976)
		(end 56.324754 -298.27474)
		(width 0.249936)
		(layer "F.Cu")
		(net "GND")
	)
	(segment
		(start 54.424834 -302.074834)
		(end 54.899814 -301.599854)
		(width 0.249936)
		(layer "F.Cu")
		(net "GND")
	)
	(segment
		(start 179.55006 -303.499774)
		(end 179.07508 -303.974754)
		(width 0.249936)
		(layer "F.Cu")
		(net "GND")
	)
	(segment
		(start 194.274948 -299.224954)
		(end 194.749928 -299.699934)
		(width 0.249936)
		(layer "F.Cu")
		(net "GND")
	)
	(segment
		(start 237.561374 -172.15993)
		(end 236.832648 -172.15993)
		(width 0.4572)
		(layer "F.Cu")
		(net "GND")
	)
	(segment
		(start 337.693 -243.571522)
		(end 337.428078 -243.836444)
		(width 0.3556)
		(layer "F.Cu")
		(net "GND")
	)
	(segment
		(start 78.667864 -54.067456)
		(end 79.323184 -54.067456)
		(width 0.254)
		(layer "F.Cu")
		(net "GND")
	)
	(segment
		(start 301.349918 -285.449772)
		(end 300.874684 -285.924752)
		(width 0.249936)
		(layer "F.Cu")
		(net "GND")
	)
	(segment
		(start 418.874956 -303.024794)
		(end 419.349936 -303.499774)
		(width 0.249936)
		(layer "F.Cu")
		(net "GND")
	)
	(segment
		(start 72.949816 -293.04996)
		(end 73.424796 -293.52494)
		(width 0.249936)
		(layer "F.Cu")
		(net "GND")
	)
	(segment
		(start 51.574954 -297.32478)
		(end 51.099974 -297.79976)
		(width 0.249936)
		(layer "F.Cu")
		(net "GND")
	)
	(segment
		(start 170.049952 -296.8498)
		(end 170.524932 -296.37482)
		(width 0.249936)
		(layer "F.Cu")
		(net "GND")
	)
	(segment
		(start 139.424156 -27.411934)
		(end 139.424156 -26.319734)
		(width 0.4572)
		(layer "F.Cu")
		(net "GND")
	)
	(segment
		(start 407.949908 -296.8498)
		(end 408.424888 -297.32478)
		(width 0.249936)
		(layer "F.Cu")
		(net "GND")
	)
	(segment
		(start 187.796932 -410.72054)
		(end 186.913012 -410.72054)
		(width 0.508)
		(layer "F.Cu")
		(net "GND")
	)
	(segment
		(start 405.100028 -285.449772)
		(end 404.624794 -284.974792)
		(width 0.249936)
		(layer "F.Cu")
		(net "GND")
	)
	(segment
		(start 303.567846 -136.645142)
		(end 305.457606 -136.645142)
		(width 0.3556)
		(layer "F.Cu")
		(net "GND")
	)
	(segment
		(start 90.0176 -303.636426)
		(end 91.0336 -303.636426)
		(width 0.4572)
		(layer "F.Cu")
		(net "GND")
	)
	(segment
		(start 380.770384 -252.756924)
		(end 380.770384 -253.45644)
		(width 0.4572)
		(layer "F.Cu")
		(net "GND")
	)
	(segment
		(start 416.974782 -290.674806)
		(end 416.499802 -291.149786)
		(width 0.249936)
		(layer "F.Cu")
		(net "GND")
	)
	(segment
		(start 388.474966 -298.27474)
		(end 387.999986 -297.79976)
		(width 0.249936)
		(layer "F.Cu")
		(net "GND")
	)
	(segment
		(start 78.512924 -8.891778)
		(end 78.512924 -9.535922)
		(width 0.4572)
		(layer "F.Cu")
		(net "GND")
	)
	(segment
		(start 284.867858 -55.083456)
		(end 285.523178 -55.083456)
		(width 0.254)
		(layer "F.Cu")
		(net "GND")
	)
	(segment
		(start 300.874684 -292.574726)
		(end 301.349918 -293.04996)
		(width 0.249936)
		(layer "F.Cu")
		(net "GND")
	)
	(segment
		(start 400.349974 -286.399732)
		(end 399.874994 -285.924752)
		(width 0.249936)
		(layer "F.Cu")
		(net "GND")
	)
	(segment
		(start 81.499964 -299.699934)
		(end 81.024984 -300.174914)
		(width 0.249936)
		(layer "F.Cu")
		(net "GND")
	)
	(segment
		(start 402.724874 -298.27474)
		(end 403.199854 -297.79976)
		(width 0.249936)
		(layer "F.Cu")
		(net "GND")
	)
	(segment
		(start 125.454156 -172.84954)
		(end 124.145802 -172.84954)
		(width 0.4572)
		(layer "F.Cu")
		(net "GND")
	)
	(segment
		(start 404.149814 -299.699934)
		(end 403.674834 -300.174914)
		(width 0.249936)
		(layer "F.Cu")
		(net "GND")
	)
	(segment
		(start 189.247018 -53.144166)
		(end 189.247018 -52.592224)
		(width 0.254)
		(layer "F.Cu")
		(net "GND")
	)
	(segment
		(start 418.399976 -300.649894)
		(end 418.874956 -300.174914)
		(width 0.249936)
		(layer "F.Cu")
		(net "GND")
	)
	(segment
		(start 167.200072 -288.299906)
		(end 166.725092 -287.824926)
		(width 0.249936)
		(layer "F.Cu")
		(net "GND")
	)
	(segment
		(start 429.325024 -303.024794)
		(end 428.84979 -302.549814)
		(width 0.249936)
		(layer "F.Cu")
		(net "GND")
	)
	(segment
		(start 292.32479 -289.724846)
		(end 292.79977 -290.199826)
		(width 0.249936)
		(layer "F.Cu")
		(net "GND")
	)
	(segment
		(start 18.41881 -147.913344)
		(end 18.41881 -147.38604)
		(width 0.254)
		(layer "F.Cu")
		(net "GND")
	)
	(segment
		(start 153.425144 -296.37482)
		(end 152.94991 -296.8498)
		(width 0.249936)
		(layer "F.Cu")
		(net "GND")
	)
	(segment
		(start 411.31744 -391.344404)
		(end 410.775404 -391.88644)
		(width 0.4572)
		(layer "F.Cu")
		(net "GND")
	)
	(segment
		(start 208.114138 -237.395004)
		(end 208.382108 -237.127034)
		(width 0.4572)
		(layer "F.Cu")
		(net "GND")
	)
	(segment
		(start 283.262324 -23.355554)
		(end 283.912056 -23.355554)
		(width 0.4572)
		(layer "F.Cu")
		(net "GND")
	)
	(segment
		(start 275.699728 -277.849838)
		(end 275.224748 -278.324818)
		(width 0.249936)
		(layer "F.Cu")
		(net "GND")
	)
	(segment
		(start 389.424926 -299.224954)
		(end 388.949946 -299.699934)
		(width 0.249936)
		(layer "F.Cu")
		(net "GND")
	)
	(segment
		(start 68.674742 -303.024794)
		(end 68.199762 -303.499774)
		(width 0.249936)
		(layer "F.Cu")
		(net "GND")
	)
	(segment
		(start 305.489864 -73.166732)
		(end 305.489864 -73.85177)
		(width 0.4572)
		(layer "F.Cu")
		(net "GND")
	)
	(segment
		(start 268.864842 -34.990024)
		(end 267.848842 -34.990024)
		(width 0.3556)
		(layer "F.Cu")
		(net "GND")
	)
	(segment
		(start 132.352796 -159.573468)
		(end 132.993384 -159.573468)
		(width 0.4572)
		(layer "F.Cu")
		(net "GND")
	)
	(segment
		(start 389.424926 -299.224954)
		(end 389.899906 -298.74972)
		(width 0.249936)
		(layer "F.Cu")
		(net "GND")
	)
	(segment
		(start 161.134552 -47.936658)
		(end 161.47034 -47.60087)
		(width 0.254)
		(layer "F.Cu")
		(net "GND")
	)
	(segment
		(start 67.66687 -118.234968)
		(end 68.65747 -118.234968)
		(width 0.3556)
		(layer "F.Cu")
		(net "GND")
	)
	(segment
		(start 289.94989 -305.399948)
		(end 290.42487 -305.874928)
		(width 0.249936)
		(layer "F.Cu")
		(net "GND")
	)
	(segment
		(start 282.349702 -288.299906)
		(end 281.874722 -288.774886)
		(width 0.249936)
		(layer "F.Cu")
		(net "GND")
	)
	(segment
		(start 387.050026 -275.949918)
		(end 386.575046 -275.474938)
		(width 0.249936)
		(layer "F.Cu")
		(net "GND")
	)
	(segment
		(start 406.895046 -103.814372)
		(end 406.279858 -103.814372)
		(width 0.4064)
		(layer "F.Cu")
		(net "GND")
	)
	(segment
		(start 53.474874 -287.824926)
		(end 53.949854 -288.299906)
		(width 0.249936)
		(layer "F.Cu")
		(net "GND")
	)
	(segment
		(start 399.93316 -98.845116)
		(end 398.94256 -98.845116)
		(width 0.3556)
		(layer "F.Cu")
		(net "GND")
	)
	(segment
		(start 163.874958 -292.57498)
		(end 164.349938 -293.04996)
		(width 0.249936)
		(layer "F.Cu")
		(net "GND")
	)
	(segment
		(start 198.550022 -299.699934)
		(end 199.025002 -299.224954)
		(width 0.249936)
		(layer "F.Cu")
		(net "GND")
	)
	(segment
		(start 260.482588 -28.875736)
		(end 260.482588 -28.47848)
		(width 0.254)
		(layer "F.Cu")
		(net "GND")
	)
	(segment
		(start 341.746586 -282.021534)
		(end 341.68461 -282.021534)
		(width 0.254)
		(layer "F.Cu")
		(net "GND")
	)
	(segment
		(start 343.69375 -222.386906)
		(end 343.69375 -222.38716)
		(width 0.381)
		(layer "F.Cu")
		(net "GND")
	)
	(segment
		(start 31.415736 -309.287672)
		(end 30.787594 -308.65953)
		(width 0.4572)
		(layer "F.Cu")
		(net "GND")
	)
	(segment
		(start 164.349938 -285.449772)
		(end 163.874958 -284.974792)
		(width 0.249936)
		(layer "F.Cu")
		(net "GND")
	)
	(segment
		(start 67.66687 -136.645142)
		(end 68.65747 -136.645142)
		(width 0.3556)
		(layer "F.Cu")
		(net "GND")
	)
	(segment
		(start 55.374794 -284.974792)
		(end 55.849774 -284.499812)
		(width 0.249936)
		(layer "F.Cu")
		(net "GND")
	)
	(segment
		(start 356.992936 -54.163722)
		(end 357.06812 -54.238906)
		(width 0.254)
		(layer "F.Cu")
		(net "GND")
	)
	(segment
		(start 364.947454 -397.825722)
		(end 364.947454 -398.475962)
		(width 0.4572)
		(layer "F.Cu")
		(net "GND")
	)
	(segment
		(start 180.02504 -284.974792)
		(end 179.55006 -285.449772)
		(width 0.249936)
		(layer "F.Cu")
		(net "GND")
	)
	(segment
		(start 165.299898 -297.79976)
		(end 164.824918 -298.27474)
		(width 0.249936)
		(layer "F.Cu")
		(net "GND")
	)
	(segment
		(start 289.47491 -285.924752)
		(end 289.94989 -286.399732)
		(width 0.249936)
		(layer "F.Cu")
		(net "GND")
	)
	(segment
		(start 376.09145 -305.507898)
		(end 376.667014 -306.083462)
		(width 0.4572)
		(layer "F.Cu")
		(net "GND")
	)
	(segment
		(start 168.150032 -307.299868)
		(end 168.625012 -306.824888)
		(width 0.249936)
		(layer "F.Cu")
		(net "GND")
	)
	(segment
		(start 52.524914 -285.924752)
		(end 52.999894 -286.399732)
		(width 0.249936)
		(layer "F.Cu")
		(net "GND")
	)
	(segment
		(start 187.149994 -289.249866)
		(end 187.624974 -289.724846)
		(width 0.249936)
		(layer "F.Cu")
		(net "GND")
	)
	(segment
		(start 69.342 -241.1476)
		(end 68.6054 -240.411)
		(width 0.4572)
		(layer "F.Cu")
		(net "GND")
	)
	(segment
		(start 273.799808 -291.149786)
		(end 273.324828 -290.674806)
		(width 0.249936)
		(layer "F.Cu")
		(net "GND")
	)
	(segment
		(start 392.75004 -281.649932)
		(end 393.22502 -282.124912)
		(width 0.249936)
		(layer "F.Cu")
		(net "GND")
	)
	(segment
		(start 412.224982 -285.924752)
		(end 412.699962 -285.449772)
		(width 0.249936)
		(layer "F.Cu")
		(net "GND")
	)
	(segment
		(start 29.422344 -252.756924)
		(end 29.422344 -253.45644)
		(width 0.4572)
		(layer "F.Cu")
		(net "GND")
	)
	(segment
		(start 402.249894 -285.449772)
		(end 401.774914 -285.924752)
		(width 0.249936)
		(layer "F.Cu")
		(net "GND")
	)
	(segment
		(start 78.667102 -56.354218)
		(end 78.667864 -56.353456)
		(width 0.4572)
		(layer "F.Cu")
		(net "GND")
	)
	(segment
		(start 306.099718 -297.79976)
		(end 306.574698 -298.27474)
		(width 0.249936)
		(layer "F.Cu")
		(net "GND")
	)
	(segment
		(start 280.449782 -288.299906)
		(end 279.974802 -287.824926)
		(width 0.249936)
		(layer "F.Cu")
		(net "GND")
	)
	(segment
		(start 404.149814 -296.8498)
		(end 404.150068 -296.8498)
		(width 0.249936)
		(layer "F.Cu")
		(net "GND")
	)
	(segment
		(start 248.629678 -345.68003)
		(end 249.391678 -345.68003)
		(width 0.4572)
		(layer "F.Cu")
		(net "GND")
	)
	(segment
		(start 282.349702 -287.349946)
		(end 281.874722 -287.824926)
		(width 0.249936)
		(layer "F.Cu")
		(net "GND")
	)
	(segment
		(start 131.133088 -113.933478)
		(end 131.133088 -113.674652)
		(width 0.254)
		(layer "F.Cu")
		(net "GND")
	)
	(segment
		(start 38.749986 -297.79976)
		(end 39.224966 -298.27474)
		(width 0.249936)
		(layer "F.Cu")
		(net "GND")
	)
	(segment
		(start 166.249858 -303.499774)
		(end 165.774878 -303.974754)
		(width 0.249936)
		(layer "F.Cu")
		(net "GND")
	)
	(segment
		(start 290.89985 -288.149792)
		(end 290.89985 -288.299906)
		(width 0.249936)
		(layer "F.Cu")
		(net "GND")
	)
	(segment
		(start 357.958898 -282.406344)
		(end 357.778558 -282.8417)
		(width 0.2286)
		(layer "F.Cu")
		(net "GND")
	)
	(segment
		(start 71.524876 -303.974754)
		(end 71.049896 -304.449734)
		(width 0.249936)
		(layer "F.Cu")
		(net "GND")
	)
	(segment
		(start 417.984178 -120.400572)
		(end 417.618672 -120.035066)
		(width 0.3556)
		(layer "F.Cu")
		(net "GND")
	)
	(segment
		(start 71.049896 -286.399732)
		(end 70.574916 -285.924752)
		(width 0.249936)
		(layer "F.Cu")
		(net "GND")
	)
	(segment
		(start 403.674834 -284.024832)
		(end 403.199854 -284.499812)
		(width 0.249936)
		(layer "F.Cu")
		(net "GND")
	)
	(segment
		(start 40.649906 -290.199826)
		(end 40.174926 -289.724846)
		(width 0.249936)
		(layer "F.Cu")
		(net "GND")
	)
	(segment
		(start 416.024822 -306.824888)
		(end 416.499802 -306.349908)
		(width 0.249936)
		(layer "F.Cu")
		(net "GND")
	)
	(segment
		(start 406.524968 -284.024832)
		(end 406.049988 -284.499812)
		(width 0.249936)
		(layer "F.Cu")
		(net "GND")
	)
	(segment
		(start 426.47489 -303.024794)
		(end 426.94987 -302.549814)
		(width 0.249936)
		(layer "F.Cu")
		(net "GND")
	)
	(segment
		(start 416.974782 -292.574726)
		(end 417.450016 -292.099746)
		(width 0.249936)
		(layer "F.Cu")
		(net "GND")
	)
	(segment
		(start 68.280788 -29.589984)
		(end 67.264788 -29.589984)
		(width 0.3556)
		(layer "F.Cu")
		(net "GND")
	)
	(segment
		(start 49.547526 -122.044206)
		(end 49.858422 -122.355102)
		(width 0.3556)
		(layer "F.Cu")
		(net "GND")
	)
	(segment
		(start 288.99993 -306.349908)
		(end 289.47491 -305.874928)
		(width 0.249936)
		(layer "F.Cu")
		(net "GND")
	)
	(segment
		(start 300.869858 -303.969928)
		(end 300.879764 -303.969928)
		(width 0.249936)
		(layer "F.Cu")
		(net "GND")
	)
	(segment
		(start 304.467006 -143.955008)
		(end 305.457606 -143.955008)
		(width 0.3556)
		(layer "F.Cu")
		(net "GND")
	)
	(segment
		(start 49.518824 -123.878594)
		(end 49.795176 -124.154946)
		(width 0.3556)
		(layer "F.Cu")
		(net "GND")
	)
	(segment
		(start 52.524914 -305.874928)
		(end 52.999894 -306.349908)
		(width 0.249936)
		(layer "F.Cu")
		(net "GND")
	)
	(segment
		(start 279.024842 -303.974754)
		(end 278.549862 -304.449734)
		(width 0.249936)
		(layer "F.Cu")
		(net "GND")
	)
	(segment
		(start 190.348108 -142.15491)
		(end 189.357508 -142.15491)
		(width 0.3556)
		(layer "F.Cu")
		(net "GND")
	)
	(segment
		(start 48.72482 -306.824888)
		(end 48.24984 -306.349908)
		(width 0.249936)
		(layer "F.Cu")
		(net "GND")
	)
	(segment
		(start 55.849774 -285.449772)
		(end 55.374794 -284.974792)
		(width 0.249936)
		(layer "F.Cu")
		(net "GND")
	)
	(segment
		(start 395.12494 -304.924714)
		(end 394.64996 -305.399948)
		(width 0.249936)
		(layer "F.Cu")
		(net "GND")
	)
	(segment
		(start 382.640078 -82.236564)
		(end 381.458978 -82.236564)
		(width 0.3048)
		(layer "F.Cu")
		(net "GND")
	)
	(segment
		(start 56.324754 -302.074834)
		(end 55.849774 -301.599854)
		(width 0.249936)
		(layer "F.Cu")
		(net "GND")
	)
	(segment
		(start 427.42485 -294.4749)
		(end 426.94987 -293.99992)
		(width 0.249936)
		(layer "F.Cu")
		(net "GND")
	)
	(segment
		(start 56.373776 -26.606246)
		(end 56.373776 -25.971246)
		(width 0.4572)
		(layer "F.Cu")
		(net "GND")
	)
	(segment
		(start 238.874046 -135.058404)
		(end 238.716058 -134.900416)
		(width 0.4064)
		(layer "F.Cu")
		(net "GND")
	)
	(segment
		(start 299.866812 -123.635008)
		(end 300.857412 -123.635008)
		(width 0.3556)
		(layer "F.Cu")
		(net "GND")
	)
	(segment
		(start 58.595006 -101.782372)
		(end 57.979818 -101.782372)
		(width 0.4064)
		(layer "F.Cu")
		(net "GND")
	)
	(segment
		(start 169.099992 -290.199826)
		(end 168.625012 -289.724846)
		(width 0.249936)
		(layer "F.Cu")
		(net "GND")
	)
	(segment
		(start 68.674742 -306.824888)
		(end 68.199762 -307.299868)
		(width 0.249936)
		(layer "F.Cu")
		(net "GND")
	)
	(segment
		(start 289.47491 -291.624766)
		(end 288.99993 -292.099746)
		(width 0.249936)
		(layer "F.Cu")
		(net "GND")
	)
	(segment
		(start 69.149976 -307.299868)
		(end 69.624956 -306.824888)
		(width 0.249936)
		(layer "F.Cu")
		(net "GND")
	)
	(segment
		(start 331.9526 -251.367036)
		(end 332.12532 -251.539756)
		(width 0.4572)
		(layer "F.Cu")
		(net "GND")
	)
	(segment
		(start 196.174868 -298.27474)
		(end 196.649848 -298.74972)
		(width 0.249936)
		(layer "F.Cu")
		(net "GND")
	)
	(segment
		(start 168.768014 -51.019456)
		(end 169.423334 -51.019456)
		(width 0.254)
		(layer "F.Cu")
		(net "GND")
	)
	(segment
		(start 53.474874 -284.974792)
		(end 52.999894 -285.449772)
		(width 0.249936)
		(layer "F.Cu")
		(net "GND")
	)
	(segment
		(start 427.42485 -290.674806)
		(end 427.89983 -291.149786)
		(width 0.249936)
		(layer "F.Cu")
		(net "GND")
	)
	(segment
		(start 278.549862 -293.04996)
		(end 278.074882 -292.57498)
		(width 0.249936)
		(layer "F.Cu")
		(net "GND")
	)
	(segment
		(start 160.549844 -298.74972)
		(end 160.074864 -299.224954)
		(width 0.249936)
		(layer "F.Cu")
		(net "GND")
	)
	(segment
		(start 389.899906 -293.04996)
		(end 389.424926 -292.57498)
		(width 0.249936)
		(layer "F.Cu")
		(net "GND")
	)
	(segment
		(start 188.232288 -121.655332)
		(end 188.665866 -121.83491)
		(width 0.3556)
		(layer "F.Cu")
		(net "GND")
	)
	(segment
		(start 168.625012 -302.074834)
		(end 168.150032 -301.599854)
		(width 0.249936)
		(layer "F.Cu")
		(net "GND")
	)
	(segment
		(start 194.274948 -293.52494)
		(end 194.749928 -293.99992)
		(width 0.249936)
		(layer "F.Cu")
		(net "GND")
	)
	(segment
		(start 62.484 -215.1126)
		(end 62.8904 -215.519)
		(width 0.4572)
		(layer "F.Cu")
		(net "GND")
	)
	(segment
		(start 105.019094 -397.912336)
		(end 105.019094 -398.66824)
		(width 0.4572)
		(layer "F.Cu")
		(net "GND")
	)
	(segment
		(start 155.325064 -298.27474)
		(end 154.850084 -298.74972)
		(width 0.249936)
		(layer "F.Cu")
		(net "GND")
	)
	(segment
		(start 47.032926 -100.64496)
		(end 46.042326 -100.64496)
		(width 0.3556)
		(layer "F.Cu")
		(net "GND")
	)
	(segment
		(start 416.499802 -301.599854)
		(end 416.974782 -302.074834)
		(width 0.249936)
		(layer "F.Cu")
		(net "GND")
	)
	(segment
		(start 111.167164 -157.595824)
		(end 111.167164 -157.882844)
		(width 0.3048)
		(layer "F.Cu")
		(net "GND")
	)
	(segment
		(start 252.687582 -25.742392)
		(end 252.687582 -26.360882)
		(width 0.4572)
		(layer "F.Cu")
		(net "GND")
	)
	(segment
		(start 419.349936 -292.1)
		(end 419.349936 -292.099746)
		(width 0.249936)
		(layer "F.Cu")
		(net "GND")
	)
	(segment
		(start 156.750004 -275.949918)
		(end 156.275024 -275.474938)
		(width 0.249936)
		(layer "F.Cu")
		(net "GND")
	)
	(segment
		(start 80.07477 -290.674806)
		(end 79.59979 -291.149786)
		(width 0.249936)
		(layer "F.Cu")
		(net "GND")
	)
	(segment
		(start 256.651506 -343.843356)
		(end 256.776982 -343.843356)
		(width 0.4572)
		(layer "F.Cu")
		(net "GND")
	)
	(segment
		(start 423.15003 -292.099746)
		(end 422.674796 -292.574726)
		(width 0.249936)
		(layer "F.Cu")
		(net "GND")
	)
	(segment
		(start 212.522054 -197.144894)
		(end 213.741 -197.144894)
		(width 0.3556)
		(layer "F.Cu")
		(net "GND")
	)
	(segment
		(start 167.732964 -137.16508)
		(end 166.742364 -137.16508)
		(width 0.3556)
		(layer "F.Cu")
		(net "GND")
	)
	(segment
		(start 282.349702 -291.149786)
		(end 281.874722 -290.674806)
		(width 0.249936)
		(layer "F.Cu")
		(net "GND")
	)
	(segment
		(start 170.524932 -296.37482)
		(end 170.999912 -295.89984)
		(width 0.249936)
		(layer "F.Cu")
		(net "GND")
	)
	(segment
		(start 286.149796 -305.399948)
		(end 285.674816 -305.874928)
		(width 0.249936)
		(layer "F.Cu")
		(net "GND")
	)
	(segment
		(start 410.63037 -198.306944)
		(end 410.767784 -198.306944)
		(width 0.4572)
		(layer "F.Cu")
		(net "GND")
	)
	(segment
		(start 277.251668 -118.754906)
		(end 278.242268 -118.754906)
		(width 0.3556)
		(layer "F.Cu")
		(net "GND")
	)
	(segment
		(start 285.199836 -293.99992)
		(end 284.724856 -293.52494)
		(width 0.249936)
		(layer "F.Cu")
		(net "GND")
	)
	(segment
		(start 264.670286 -252.756924)
		(end 264.670286 -253.45644)
		(width 0.4572)
		(layer "F.Cu")
		(net "GND")
	)
	(segment
		(start 68.674742 -293.52494)
		(end 68.199762 -293.99992)
		(width 0.249936)
		(layer "F.Cu")
		(net "GND")
	)
	(segment
		(start 325.971154 -120.041924)
		(end 325.382382 -120.041924)
		(width 0.254)
		(layer "F.Cu")
		(net "GND")
	)
	(segment
		(start 208.7245 -113.811304)
		(end 209.121756 -113.811304)
		(width 0.254)
		(layer "F.Cu")
		(net "GND")
	)
	(segment
		(start 285.199836 -285.449772)
		(end 284.724856 -285.924752)
		(width 0.249936)
		(layer "F.Cu")
		(net "GND")
	)
	(segment
		(start 60.124848 -302.074834)
		(end 60.599828 -301.599854)
		(width 0.249936)
		(layer "F.Cu")
		(net "GND")
	)
	(segment
		(start 51.099974 -303.499774)
		(end 51.574954 -303.974754)
		(width 0.249936)
		(layer "F.Cu")
		(net "GND")
	)
	(segment
		(start 118.358412 -128.947926)
		(end 119.013732 -128.947926)
		(width 0.381)
		(layer "F.Cu")
		(net "GND")
	)
	(segment
		(start 67.264788 -25.990042)
		(end 66.396108 -25.990042)
		(width 0.3556)
		(layer "F.Cu")
		(net "GND")
	)
	(segment
		(start 302.774858 -290.674806)
		(end 302.299878 -290.199826)
		(width 0.249936)
		(layer "F.Cu")
		(net "GND")
	)
	(segment
		(start 427.89983 -302.549814)
		(end 427.42485 -302.074834)
		(width 0.249936)
		(layer "F.Cu")
		(net "GND")
	)
	(segment
		(start 395.12494 -300.174914)
		(end 395.59992 -299.699934)
		(width 0.249936)
		(layer "F.Cu")
		(net "GND")
	)
	(segment
		(start 295.174924 -302.074834)
		(end 295.649904 -301.599854)
		(width 0.249936)
		(layer "F.Cu")
		(net "GND")
	)
	(segment
		(start 386.099812 -286.399732)
		(end 385.624832 -285.924752)
		(width 0.249936)
		(layer "F.Cu")
		(net "GND")
	)
	(segment
		(start 78.42504 -14.735302)
		(end 78.42504 -14.100302)
		(width 0.381)
		(layer "F.Cu")
		(net "GND")
	)
	(segment
		(start 303.457864 -73.166732)
		(end 303.457864 -73.85177)
		(width 0.4572)
		(layer "F.Cu")
		(net "GND")
	)
	(segment
		(start 159.124904 -276.424898)
		(end 158.649924 -275.949918)
		(width 0.249936)
		(layer "F.Cu")
		(net "GND")
	)
	(segment
		(start 55.849774 -292.099746)
		(end 56.324754 -291.624766)
		(width 0.249936)
		(layer "F.Cu")
		(net "GND")
	)
	(segment
		(start 363.333284 -113.674652)
		(end 362.910628 -113.251996)
		(width 0.254)
		(layer "F.Cu")
		(net "GND")
	)
	(segment
		(start 394.64996 -304.449734)
		(end 395.12494 -303.974754)
		(width 0.249936)
		(layer "F.Cu")
		(net "GND")
	)
	(segment
		(start 427.42485 -298.27474)
		(end 426.94987 -298.74972)
		(width 0.249936)
		(layer "F.Cu")
		(net "GND")
	)
	(segment
		(start 180.02504 -306.824888)
		(end 179.55006 -306.349908)
		(width 0.249936)
		(layer "F.Cu")
		(net "GND")
	)
	(segment
		(start 164.429694 -165.902894)
		(end 163.558982 -165.902894)
		(width 0.381)
		(layer "F.Cu")
		(net "GND")
	)
	(segment
		(start 170.049952 -299.699934)
		(end 170.524932 -300.174914)
		(width 0.249936)
		(layer "F.Cu")
		(net "GND")
	)
	(segment
		(start 228.953568 -305.986942)
		(end 228.241098 -305.986942)
		(width 0.4572)
		(layer "F.Cu")
		(net "GND")
	)
	(segment
		(start 154.850084 -293.99992)
		(end 154.375104 -293.52494)
		(width 0.249936)
		(layer "F.Cu")
		(net "GND")
	)
	(segment
		(start 6.489446 -67.892168)
		(end 7.29996 -67.892168)
		(width 0.4572)
		(layer "F.Cu")
		(net "GND")
	)
	(segment
		(start 162.924998 -307.774848)
		(end 162.450018 -307.299868)
		(width 0.249936)
		(layer "F.Cu")
		(net "GND")
	)
	(segment
		(start 238.524796 -117.714268)
		(end 239.14227 -117.714268)
		(width 0.4572)
		(layer "F.Cu")
		(net "GND")
	)
	(segment
		(start 418.399976 -307.299868)
		(end 418.874956 -307.774848)
		(width 0.249936)
		(layer "F.Cu")
		(net "GND")
	)
	(segment
		(start 169.836846 -16.363188)
		(end 169.836846 -15.474188)
		(width 0.4572)
		(layer "F.Cu")
		(net "GND")
	)
	(segment
		(start 38.20795 -162.044126)
		(end 38.349428 -161.902648)
		(width 0.4572)
		(layer "F.Cu")
		(net "GND")
	)
	(segment
		(start 227.467668 -219.10421)
		(end 227.067872 -219.504006)
		(width 0.381)
		(layer "F.Cu")
		(net "GND")
	)
	(segment
		(start 387.999986 -273.099784)
		(end 387.525006 -272.624804)
		(width 0.249936)
		(layer "F.Cu")
		(net "GND")
	)
	(segment
		(start 65.349882 -284.499812)
		(end 65.824862 -284.974792)
		(width 0.249936)
		(layer "F.Cu")
		(net "GND")
	)
	(segment
		(start 299.449744 -306.349908)
		(end 299.924724 -305.874928)
		(width 0.249936)
		(layer "F.Cu")
		(net "GND")
	)
	(segment
		(start 69.149976 -297.79976)
		(end 68.674742 -298.27474)
		(width 0.249936)
		(layer "F.Cu")
		(net "GND")
	)
	(segment
		(start 81.499964 -293.99992)
		(end 81.024984 -293.52494)
		(width 0.249936)
		(layer "F.Cu")
		(net "GND")
	)
	(segment
		(start 181.44998 -285.449772)
		(end 180.975 -284.974792)
		(width 0.249936)
		(layer "F.Cu")
		(net "GND")
	)
	(segment
		(start 194.767962 -55.083456)
		(end 195.423282 -55.083456)
		(width 0.254)
		(layer "F.Cu")
		(net "GND")
	)
	(segment
		(start 162.450018 -299.699934)
		(end 161.975038 -300.174914)
		(width 0.249936)
		(layer "F.Cu")
		(net "GND")
	)
	(segment
		(start 49.1998 -292.099746)
		(end 49.67478 -292.574726)
		(width 0.249936)
		(layer "F.Cu")
		(net "GND")
	)
	(segment
		(start 69.624956 -294.4749)
		(end 69.149976 -294.94988)
		(width 0.249936)
		(layer "F.Cu")
		(net "GND")
	)
	(segment
		(start 126.740412 -90.59037)
		(end 127.462534 -90.59037)
		(width 0.254)
		(layer "F.Cu")
		(net "GND")
	)
	(segment
		(start 272.374868 -296.37482)
		(end 271.899888 -295.89984)
		(width 0.249936)
		(layer "F.Cu")
		(net "GND")
	)
	(segment
		(start 241.07013 -216.80805)
		(end 240.72469 -217.15349)
		(width 0.4572)
		(layer "F.Cu")
		(net "GND")
	)
	(segment
		(start 44.449746 -291.149786)
		(end 43.974766 -290.674806)
		(width 0.249936)
		(layer "F.Cu")
		(net "GND")
	)
	(segment
		(start 184.77484 -306.824888)
		(end 185.250074 -307.299868)
		(width 0.249936)
		(layer "F.Cu")
		(net "GND")
	)
	(segment
		(start 189.524894 -301.124874)
		(end 189.999874 -301.599854)
		(width 0.249936)
		(layer "F.Cu")
		(net "GND")
	)
	(segment
		(start 179.07508 -305.874928)
		(end 179.55006 -306.349908)
		(width 0.249936)
		(layer "F.Cu")
		(net "GND")
	)
	(segment
		(start 77.22489 -297.32478)
		(end 76.74991 -296.8498)
		(width 0.249936)
		(layer "F.Cu")
		(net "GND")
	)
	(segment
		(start 271.752822 -140.85697)
		(end 271.925288 -141.029436)
		(width 0.4572)
		(layer "F.Cu")
		(net "GND")
	)
	(segment
		(start 47.032926 -98.845116)
		(end 46.042326 -98.845116)
		(width 0.3556)
		(layer "F.Cu")
		(net "GND")
	)
	(segment
		(start 370.489734 -235.756958)
		(end 369.487704 -235.756958)
		(width 0.4572)
		(layer "F.Cu")
		(net "GND")
	)
	(segment
		(start 160.074864 -300.174914)
		(end 159.599884 -299.699934)
		(width 0.249936)
		(layer "F.Cu")
		(net "GND")
	)
	(segment
		(start 300.399704 -301.599854)
		(end 300.874684 -302.074834)
		(width 0.249936)
		(layer "F.Cu")
		(net "GND")
	)
	(segment
		(start 293.394892 -59.978036)
		(end 293.394892 -60.633356)
		(width 0.4572)
		(layer "F.Cu")
		(net "GND")
	)
	(segment
		(start 168.625012 -303.974754)
		(end 168.150032 -303.499774)
		(width 0.249936)
		(layer "F.Cu")
		(net "GND")
	)
	(segment
		(start 221.5769 -196.30771)
		(end 221.5769 -197.078092)
		(width 0.3048)
		(layer "F.Cu")
		(net "GND")
	)
	(segment
		(start 394.17498 -300.174914)
		(end 393.7 -300.649894)
		(width 0.254)
		(layer "F.Cu")
		(net "GND")
	)
	(segment
		(start 52.999894 -285.449772)
		(end 53.474874 -285.924752)
		(width 0.249936)
		(layer "F.Cu")
		(net "GND")
	)
	(segment
		(start 26.667968 -55.083456)
		(end 27.323288 -55.083456)
		(width 0.254)
		(layer "F.Cu")
		(net "GND")
	)
	(segment
		(start 227.467668 -217.504264)
		(end 227.067872 -217.104468)
		(width 0.381)
		(layer "F.Cu")
		(net "GND")
	)
	(segment
		(start 65.824862 -287.824926)
		(end 65.349882 -288.299906)
		(width 0.249936)
		(layer "F.Cu")
		(net "GND")
	)
	(segment
		(start 262.57377 -26.606246)
		(end 262.57377 -25.971246)
		(width 0.4572)
		(layer "F.Cu")
		(net "GND")
	)
	(segment
		(start 142.768066 -54.067456)
		(end 143.423386 -54.067456)
		(width 0.254)
		(layer "F.Cu")
		(net "GND")
	)
	(segment
		(start 394.17498 -300.174914)
		(end 394.64996 -300.649894)
		(width 0.249936)
		(layer "F.Cu")
		(net "GND")
	)
	(segment
		(start 10.664952 -29.589984)
		(end 9.648952 -29.589984)
		(width 0.3556)
		(layer "F.Cu")
		(net "GND")
	)
	(segment
		(start 197.125082 -289.724846)
		(end 196.649848 -289.249866)
		(width 0.249936)
		(layer "F.Cu")
		(net "GND")
	)
	(segment
		(start 421.724836 -292.574726)
		(end 422.199816 -293.04996)
		(width 0.249936)
		(layer "F.Cu")
		(net "GND")
	)
	(segment
		(start 367.558066 -73.166732)
		(end 367.558066 -73.85177)
		(width 0.4572)
		(layer "F.Cu")
		(net "GND")
	)
	(segment
		(start 360.35488 -34.990024)
		(end 358.964992 -34.990024)
		(width 0.3556)
		(layer "F.Cu")
		(net "GND")
	)
	(segment
		(start 197.600062 -290.199826)
		(end 197.125082 -289.724846)
		(width 0.249936)
		(layer "F.Cu")
		(net "GND")
	)
	(segment
		(start 73.424796 -290.674806)
		(end 73.899776 -290.199826)
		(width 0.249936)
		(layer "F.Cu")
		(net "GND")
	)
	(segment
		(start 45.87494 -299.224954)
		(end 46.34992 -299.699934)
		(width 0.249936)
		(layer "F.Cu")
		(net "GND")
	)
	(segment
		(start 134.026656 -25.832054)
		(end 134.670038 -25.832054)
		(width 0.4572)
		(layer "F.Cu")
		(net "GND")
	)
	(segment
		(start 47.77486 -299.224954)
		(end 47.29988 -299.699934)
		(width 0.249936)
		(layer "F.Cu")
		(net "GND")
	)
	(segment
		(start 168.150032 -306.349908)
		(end 168.625012 -306.824888)
		(width 0.249936)
		(layer "F.Cu")
		(net "GND")
	)
	(segment
		(start 233.867706 -215.904572)
		(end 234.267502 -216.304368)
		(width 0.381)
		(layer "F.Cu")
		(net "GND")
	)
	(segment
		(start 209.121756 -113.811304)
		(end 209.4611 -113.47196)
		(width 0.254)
		(layer "F.Cu")
		(net "GND")
	)
	(segment
		(start 58.699908 -295.89984)
		(end 58.224928 -296.37482)
		(width 0.249936)
		(layer "F.Cu")
		(net "GND")
	)
	(segment
		(start 63.449962 -288.299906)
		(end 63.924942 -287.824926)
		(width 0.249936)
		(layer "F.Cu")
		(net "GND")
	)
	(segment
		(start 181.44998 -296.8498)
		(end 181.92496 -297.32478)
		(width 0.249936)
		(layer "F.Cu")
		(net "GND")
	)
	(segment
		(start 299.924724 -305.874928)
		(end 299.449744 -305.399948)
		(width 0.249936)
		(layer "F.Cu")
		(net "GND")
	)
	(segment
		(start 69.149976 -292.099746)
		(end 69.624956 -292.574726)
		(width 0.249936)
		(layer "F.Cu")
		(net "GND")
	)
	(segment
		(start 111.167164 -157.882844)
		(end 110.837726 -158.212282)
		(width 0.3048)
		(layer "F.Cu")
		(net "GND")
	)
	(segment
		(start 297.074844 -307.774848)
		(end 296.599864 -307.299868)
		(width 0.249936)
		(layer "F.Cu")
		(net "GND")
	)
	(segment
		(start 313.699906 -288.299906)
		(end 313.224926 -288.774886)
		(width 0.249936)
		(layer "F.Cu")
		(net "GND")
	)
	(segment
		(start 420.567104 -145.755106)
		(end 421.557704 -145.755106)
		(width 0.3556)
		(layer "F.Cu")
		(net "GND")
	)
	(segment
		(start 71.049896 -287.349946)
		(end 70.574916 -287.824926)
		(width 0.249936)
		(layer "F.Cu")
		(net "GND")
	)
	(segment
		(start 68.674742 -293.52494)
		(end 69.149976 -293.04996)
		(width 0.249936)
		(layer "F.Cu")
		(net "GND")
	)
	(segment
		(start 259.155692 -262.918956)
		(end 259.738876 -262.918956)
		(width 0.254)
		(layer "F.Cu")
		(net "GND")
	)
	(segment
		(start 98.27387 -73.166732)
		(end 98.27387 -73.85177)
		(width 0.4572)
		(layer "F.Cu")
		(net "GND")
	)
	(segment
		(start 279.499822 -303.499774)
		(end 279.974802 -303.974754)
		(width 0.249936)
		(layer "F.Cu")
		(net "GND")
	)
	(segment
		(start 162.587686 -25.742392)
		(end 162.587686 -26.360882)
		(width 0.4572)
		(layer "F.Cu")
		(net "GND")
	)
	(segment
		(start 157.364938 -25.990042)
		(end 158.380938 -25.990042)
		(width 0.3556)
		(layer "F.Cu")
		(net "GND")
	)
	(segment
		(start 194.274948 -302.074834)
		(end 194.749928 -302.549814)
		(width 0.249936)
		(layer "F.Cu")
		(net "GND")
	)
	(segment
		(start 170.999912 -286.399732)
		(end 170.524932 -285.924752)
		(width 0.249936)
		(layer "F.Cu")
		(net "GND")
	)
	(segment
		(start 207.133698 -303.636426)
		(end 207.133698 -303.026826)
		(width 0.4572)
		(layer "F.Cu")
		(net "GND")
	)
	(segment
		(start 298.024804 -306.824888)
		(end 298.499784 -307.299868)
		(width 0.249936)
		(layer "F.Cu")
		(net "GND")
	)
	(segment
		(start 287.574736 -305.874928)
		(end 287.099756 -305.399948)
		(width 0.249936)
		(layer "F.Cu")
		(net "GND")
	)
	(segment
		(start 403.199854 -290.199826)
		(end 403.674834 -289.724846)
		(width 0.249936)
		(layer "F.Cu")
		(net "GND")
	)
	(segment
		(start 274.749768 -299.699934)
		(end 273.799808 -299.699934)
		(width 0.249936)
		(layer "F.Cu")
		(net "GND")
	)
	(segment
		(start 44.449746 -288.299906)
		(end 43.974766 -287.824926)
		(width 0.249936)
		(layer "F.Cu")
		(net "GND")
	)
	(segment
		(start 281.995118 -124.154946)
		(end 282.842462 -124.154946)
		(width 0.3556)
		(layer "F.Cu")
		(net "GND")
	)
	(segment
		(start 84.884006 -143.582898)
		(end 83.55203 -142.250922)
		(width 0.4572)
		(layer "F.Cu")
		(net "GND")
	)
	(segment
		(start 319.848738 -31.390082)
		(end 320.864738 -31.390082)
		(width 0.3556)
		(layer "F.Cu")
		(net "GND")
	)
	(segment
		(start 298.024804 -305.874928)
		(end 297.549824 -306.349908)
		(width 0.249936)
		(layer "F.Cu")
		(net "GND")
	)
	(segment
		(start 152.411938 -136.84885)
		(end 152.411938 -136.81456)
		(width 0.4572)
		(layer "F.Cu")
		(net "GND")
	)
	(segment
		(start 420.818564 -116.435124)
		(end 421.557704 -116.435124)
		(width 0.3556)
		(layer "F.Cu")
		(net "GND")
	)
	(segment
		(start 88.007444 -95.919798)
		(end 88.579198 -95.348044)
		(width 0.4572)
		(layer "F.Cu")
		(net "GND")
	)
	(segment
		(start 168.150032 -286.399732)
		(end 167.675052 -285.924752)
		(width 0.249936)
		(layer "F.Cu")
		(net "GND")
	)
	(segment
		(start 181.44998 -294.94988)
		(end 181.92496 -294.4749)
		(width 0.249936)
		(layer "F.Cu")
		(net "GND")
	)
	(segment
		(start 179.780946 -25.990042)
		(end 178.764946 -25.990042)
		(width 0.3556)
		(layer "F.Cu")
		(net "GND")
	)
	(segment
		(start 20.48764 -25.742392)
		(end 20.48764 -26.360882)
		(width 0.4572)
		(layer "F.Cu")
		(net "GND")
	)
	(segment
		(start 189.999874 -299.699934)
		(end 189.524894 -299.224954)
		(width 0.249936)
		(layer "F.Cu")
		(net "GND")
	)
	(segment
		(start 248.07164 -211.276946)
		(end 248.07164 -212.088222)
		(width 0.4572)
		(layer "F.Cu")
		(net "GND")
	)
	(segment
		(start 417.984178 -124.000514)
		(end 417.618672 -123.635008)
		(width 0.3556)
		(layer "F.Cu")
		(net "GND")
	)
	(segment
		(start 119.969788 -119.011954)
		(end 120.309132 -118.67261)
		(width 0.254)
		(layer "F.Cu")
		(net "GND")
	)
	(segment
		(start 386.099812 -277.849838)
		(end 385.624832 -277.374858)
		(width 0.249936)
		(layer "F.Cu")
		(net "GND")
	)
	(segment
		(start 188.099954 -300.649894)
		(end 187.624974 -301.124874)
		(width 0.249936)
		(layer "F.Cu")
		(net "GND")
	)
	(segment
		(start 308.474872 -294.4749)
		(end 308.949852 -294.94988)
		(width 0.249936)
		(layer "F.Cu")
		(net "GND")
	)
	(segment
		(start 438.044844 -27.79014)
		(end 436.964836 -27.79014)
		(width 0.3556)
		(layer "F.Cu")
		(net "GND")
	)
	(segment
		(start 229.437438 -69.600064)
		(end 228.308154 -69.600064)
		(width 0.3556)
		(layer "F.Cu")
		(net "GND")
	)
	(segment
		(start 399.19275 -85.3948)
		(end 399.19275 -84.721446)
		(width 0.4572)
		(layer "F.Cu")
		(net "GND")
	)
	(segment
		(start 180.50002 -286.399732)
		(end 180.975 -285.924752)
		(width 0.249936)
		(layer "F.Cu")
		(net "GND")
	)
	(segment
		(start 170.524932 -283.074872)
		(end 170.999912 -283.549852)
		(width 0.249936)
		(layer "F.Cu")
		(net "GND")
	)
	(segment
		(start 283.299916 -286.399732)
		(end 282.824936 -285.924752)
		(width 0.249936)
		(layer "F.Cu")
		(net "GND")
	)
	(segment
		(start 394.64996 -299.699934)
		(end 395.12494 -300.174914)
		(width 0.249936)
		(layer "F.Cu")
		(net "GND")
	)
	(segment
		(start 178.124866 -291.624766)
		(end 177.649886 -292.099746)
		(width 0.249936)
		(layer "F.Cu")
		(net "GND")
	)
	(segment
		(start 403.657816 -26.606246)
		(end 403.657816 -25.971246)
		(width 0.4572)
		(layer "F.Cu")
		(net "GND")
	)
	(segment
		(start 295.174924 -305.874928)
		(end 295.649904 -305.399948)
		(width 0.249936)
		(layer "F.Cu")
		(net "GND")
	)
	(segment
		(start 291.84981 -296.8498)
		(end 292.32479 -297.32478)
		(width 0.249936)
		(layer "F.Cu")
		(net "GND")
	)
	(segment
		(start 343.69375 -219.987114)
		(end 344.093546 -220.38691)
		(width 0.381)
		(layer "F.Cu")
		(net "GND")
	)
	(segment
		(start 258.14528 -209.799174)
		(end 258.14528 -210.434174)
		(width 0.4572)
		(layer "F.Cu")
		(net "GND")
	)
	(segment
		(start 285.674816 -303.974754)
		(end 286.149796 -303.499774)
		(width 0.249936)
		(layer "F.Cu")
		(net "GND")
	)
	(segment
		(start 400.967194 -57.332626)
		(end 400.967194 -56.354218)
		(width 0.4572)
		(layer "F.Cu")
		(net "GND")
	)
	(segment
		(start 161.500058 -286.399732)
		(end 161.025078 -285.924752)
		(width 0.249936)
		(layer "F.Cu")
		(net "GND")
	)
	(segment
		(start 299.924724 -284.974792)
		(end 300.399704 -284.499812)
		(width 0.249936)
		(layer "F.Cu")
		(net "GND")
	)
	(segment
		(start 247.464834 -33.19018)
		(end 248.480834 -33.19018)
		(width 0.3556)
		(layer "F.Cu")
		(net "GND")
	)
	(segment
		(start 418.874956 -289.724846)
		(end 419.349936 -290.199826)
		(width 0.249936)
		(layer "F.Cu")
		(net "GND")
	)
	(segment
		(start 446.0748 -48.753014)
		(end 445.368172 -48.753014)
		(width 0.254)
		(layer "F.Cu")
		(net "GND")
	)
	(segment
		(start 172.900086 -301.599854)
		(end 173.375066 -302.074834)
		(width 0.249936)
		(layer "F.Cu")
		(net "GND")
	)
	(segment
		(start 226.558856 -308.168548)
		(end 226.78898 -308.073298)
		(width 0.1778)
		(layer "F.Cu")
		(net "GND")
	)
	(segment
		(start 300.399704 -297.79976)
		(end 300.874684 -298.27474)
		(width 0.249936)
		(layer "F.Cu")
		(net "GND")
	)
	(segment
		(start 301.830486 -118.370858)
		(end 301.694596 -118.234968)
		(width 0.3556)
		(layer "F.Cu")
		(net "GND")
	)
	(segment
		(start 165.704774 -105.673652)
		(end 166.076122 -106.045)
		(width 0.3556)
		(layer "F.Cu")
		(net "GND")
	)
	(segment
		(start 305.346862 -52.592224)
		(end 305.422046 -52.51704)
		(width 0.254)
		(layer "F.Cu")
		(net "GND")
	)
	(segment
		(start 414.599882 -307.299868)
		(end 414.124902 -306.824888)
		(width 0.249936)
		(layer "F.Cu")
		(net "GND")
	)
	(segment
		(start 310.374792 -301.124874)
		(end 310.849772 -301.599854)
		(width 0.249936)
		(layer "F.Cu")
		(net "GND")
	)
	(segment
		(start 61.549788 -288.299906)
		(end 61.074808 -287.824926)
		(width 0.249936)
		(layer "F.Cu")
		(net "GND")
	)
	(segment
		(start 182.496206 -25.990042)
		(end 182.31485 -26.171398)
		(width 0.3556)
		(layer "F.Cu")
		(net "GND")
	)
	(segment
		(start 152.94991 -291.149786)
		(end 152.47493 -290.674806)
		(width 0.249936)
		(layer "F.Cu")
		(net "GND")
	)
	(segment
		(start 37.799772 -274.049744)
		(end 37.324792 -273.574764)
		(width 0.249936)
		(layer "F.Cu")
		(net "GND")
	)
	(segment
		(start 49.67478 -292.574726)
		(end 50.14976 -293.04996)
		(width 0.249936)
		(layer "F.Cu")
		(net "GND")
	)
	(segment
		(start 331.34681 -52.592224)
		(end 331.421994 -52.51704)
		(width 0.254)
		(layer "F.Cu")
		(net "GND")
	)
	(segment
		(start 193.453766 -84.332318)
		(end 192.793366 -84.332318)
		(width 0.4064)
		(layer "F.Cu")
		(net "GND")
	)
	(segment
		(start 311.799732 -298.74972)
		(end 311.324752 -298.27474)
		(width 0.249936)
		(layer "F.Cu")
		(net "GND")
	)
	(segment
		(start 82.909664 -303.040034)
		(end 82.909664 -303.024794)
		(width 0.249936)
		(layer "F.Cu")
		(net "GND")
	)
	(segment
		(start 411.980888 -25.990042)
		(end 410.964888 -25.990042)
		(width 0.3556)
		(layer "F.Cu")
		(net "GND")
	)
	(segment
		(start 201.857864 -299.4406)
		(end 201.857864 -301.262034)
		(width 0.4572)
		(layer "F.Cu")
		(net "GND")
	)
	(segment
		(start 49.914556 -109.644942)
		(end 50.64252 -109.644942)
		(width 0.3556)
		(layer "F.Cu")
		(net "GND")
	)
	(segment
		(start 161.15157 -106.045)
		(end 162.14217 -106.045)
		(width 0.3556)
		(layer "F.Cu")
		(net "GND")
	)
	(segment
		(start 373.761 -193.05905)
		(end 374.50395 -193.05905)
		(width 0.4572)
		(layer "F.Cu")
		(net "GND")
	)
	(segment
		(start 6.309106 -27.04973)
		(end 5.699506 -27.04973)
		(width 0.4572)
		(layer "F.Cu")
		(net "GND")
	)
	(segment
		(start 221.42323 -56.353456)
		(end 220.76791 -56.353456)
		(width 0.254)
		(layer "F.Cu")
		(net "GND")
	)
	(segment
		(start 45.051726 -138.964924)
		(end 46.042326 -138.964924)
		(width 0.3556)
		(layer "F.Cu")
		(net "GND")
	)
	(segment
		(start 279.499822 -290.199826)
		(end 279.024842 -289.724846)
		(width 0.249936)
		(layer "F.Cu")
		(net "GND")
	)
	(segment
		(start 301.824898 -293.52494)
		(end 302.299878 -293.04996)
		(width 0.249936)
		(layer "F.Cu")
		(net "GND")
	)
	(segment
		(start 398.4498 -284.499812)
		(end 397.97482 -284.024832)
		(width 0.249936)
		(layer "F.Cu")
		(net "GND")
	)
	(segment
		(start 163.390072 -73.166732)
		(end 163.390072 -73.85177)
		(width 0.4572)
		(layer "F.Cu")
		(net "GND")
	)
	(segment
		(start 70.099936 -292.099746)
		(end 69.624956 -292.574726)
		(width 0.249936)
		(layer "F.Cu")
		(net "GND")
	)
	(segment
		(start 373.61495 -246.888)
		(end 373.552974 -246.888)
		(width 0.4572)
		(layer "F.Cu")
		(net "GND")
	)
	(segment
		(start 185.725054 -298.27474)
		(end 186.200034 -298.74972)
		(width 0.249936)
		(layer "F.Cu")
		(net "GND")
	)
	(segment
		(start 43.499786 -281.649932)
		(end 43.024806 -281.174952)
		(width 0.249936)
		(layer "F.Cu")
		(net "GND")
	)
	(segment
		(start 421.724836 -307.774848)
		(end 422.199816 -308.249828)
		(width 0.249936)
		(layer "F.Cu")
		(net "GND")
	)
	(segment
		(start 238.385604 -185.5724)
		(end 237.750604 -185.5724)
		(width 0.4572)
		(layer "F.Cu")
		(net "GND")
	)
	(segment
		(start 273.464782 -33.19018)
		(end 272.448782 -33.19018)
		(width 0.3556)
		(layer "F.Cu")
		(net "GND")
	)
	(segment
		(start 82.449924 -290.199826)
		(end 81.974944 -289.724846)
		(width 0.249936)
		(layer "F.Cu")
		(net "GND")
	)
	(segment
		(start 161.15157 -124.154946)
		(end 162.14217 -124.154946)
		(width 0.3556)
		(layer "F.Cu")
		(net "GND")
	)
	(segment
		(start 52.049934 -306.349908)
		(end 52.524914 -305.874928)
		(width 0.249936)
		(layer "F.Cu")
		(net "GND")
	)
	(segment
		(start 190.348108 -131.245102)
		(end 189.357508 -131.245102)
		(width 0.3556)
		(layer "F.Cu")
		(net "GND")
	)
	(segment
		(start 302.774858 -303.024794)
		(end 303.249838 -303.499774)
		(width 0.249936)
		(layer "F.Cu")
		(net "GND")
	)
	(segment
		(start 104.003094 -397.912336)
		(end 104.003094 -398.66824)
		(width 0.4572)
		(layer "F.Cu")
		(net "GND")
	)
	(segment
		(start 283.299916 -306.349908)
		(end 283.774896 -306.824888)
		(width 0.249936)
		(layer "F.Cu")
		(net "GND")
	)
	(segment
		(start 300.399704 -286.399732)
		(end 300.874684 -286.874966)
		(width 0.249936)
		(layer "F.Cu")
		(net "GND")
	)
	(segment
		(start 178.124866 -297.32478)
		(end 177.649886 -296.8498)
		(width 0.249936)
		(layer "F.Cu")
		(net "GND")
	)
	(segment
		(start 363.564932 -34.990024)
		(end 364.580932 -34.990024)
		(width 0.3556)
		(layer "F.Cu")
		(net "GND")
	)
	(segment
		(start 28.270962 -34.29762)
		(end 28.26258 -34.29762)
		(width 0.4572)
		(layer "F.Cu")
		(net "GND")
	)
	(segment
		(start 69.149976 -286.399732)
		(end 69.624956 -285.924752)
		(width 0.249936)
		(layer "F.Cu")
		(net "GND")
	)
	(segment
		(start 402.724874 -284.024832)
		(end 402.249894 -284.499812)
		(width 0.249936)
		(layer "F.Cu")
		(net "GND")
	)
	(segment
		(start 299.866812 -143.955008)
		(end 300.857412 -143.955008)
		(width 0.3556)
		(layer "F.Cu")
		(net "GND")
	)
	(segment
		(start 421.218614 -46.693836)
		(end 421.019224 -46.893226)
		(width 0.254)
		(layer "F.Cu")
		(net "GND")
	)
	(segment
		(start 300.399704 -305.399948)
		(end 299.924724 -305.874928)
		(width 0.249936)
		(layer "F.Cu")
		(net "GND")
	)
	(segment
		(start 269.049754 -275.949918)
		(end 268.574774 -275.474938)
		(width 0.249936)
		(layer "F.Cu")
		(net "GND")
	)
	(segment
		(start 286.482536 -28.875736)
		(end 286.482536 -28.47848)
		(width 0.254)
		(layer "F.Cu")
		(net "GND")
	)
	(segment
		(start 411.370526 -202.181714)
		(end 410.721556 -201.532744)
		(width 0.4572)
		(layer "F.Cu")
		(net "GND")
	)
	(segment
		(start 270.474694 -298.27474)
		(end 270.949928 -297.79976)
		(width 0.249936)
		(layer "F.Cu")
		(net "GND")
	)
	(segment
		(start 299.449744 -301.599854)
		(end 299.924724 -302.074834)
		(width 0.249936)
		(layer "F.Cu")
		(net "GND")
	)
	(segment
		(start 56.324754 -306.824888)
		(end 55.849774 -307.299868)
		(width 0.249936)
		(layer "F.Cu")
		(net "GND")
	)
	(segment
		(start 278.549862 -308.249828)
		(end 279.024842 -307.774848)
		(width 0.249936)
		(layer "F.Cu")
		(net "GND")
	)
	(segment
		(start 186.200034 -307.299868)
		(end 186.675014 -307.774848)
		(width 0.249936)
		(layer "F.Cu")
		(net "GND")
	)
	(segment
		(start 12.343384 -117.211348)
		(end 12.343384 -116.450364)
		(width 0.4572)
		(layer "F.Cu")
		(net "GND")
	)
	(segment
		(start 418.399976 -293.04996)
		(end 418.874956 -292.57498)
		(width 0.249936)
		(layer "F.Cu")
		(net "GND")
	)
	(segment
		(start 64.399922 -290.199826)
		(end 63.924942 -289.724846)
		(width 0.249936)
		(layer "F.Cu")
		(net "GND")
	)
	(segment
		(start 44.92498 -284.024832)
		(end 44.45 -284.499812)
		(width 0.3048)
		(layer "F.Cu")
		(net "GND")
	)
	(segment
		(start 54.27091 -34.29762)
		(end 54.385464 -34.183066)
		(width 0.4572)
		(layer "F.Cu")
		(net "GND")
	)
	(segment
		(start 63.744856 -27.79014)
		(end 62.664848 -27.79014)
		(width 0.3556)
		(layer "F.Cu")
		(net "GND")
	)
	(segment
		(start 439.584338 -34.990024)
		(end 441.564776 -34.990024)
		(width 0.3556)
		(layer "F.Cu")
		(net "GND")
	)
	(segment
		(start 277.251668 -107.845098)
		(end 278.242268 -107.845098)
		(width 0.3556)
		(layer "F.Cu")
		(net "GND")
	)
	(segment
		(start 11.74496 -29.589984)
		(end 10.664952 -29.589984)
		(width 0.3556)
		(layer "F.Cu")
		(net "GND")
	)
	(segment
		(start 197.125082 -303.024794)
		(end 196.649848 -302.549814)
		(width 0.249936)
		(layer "F.Cu")
		(net "GND")
	)
	(segment
		(start 280.449782 -294.94988)
		(end 279.974802 -294.4749)
		(width 0.249936)
		(layer "F.Cu")
		(net "GND")
	)
	(segment
		(start 393.7 -283.549852)
		(end 393.22502 -283.074872)
		(width 0.249936)
		(layer "F.Cu")
		(net "GND")
	)
	(segment
		(start 306.099718 -289.249866)
		(end 306.574698 -288.774886)
		(width 0.249936)
		(layer "F.Cu")
		(net "GND")
	)
	(segment
		(start 57.749948 -290.199826)
		(end 58.224928 -289.724846)
		(width 0.249936)
		(layer "F.Cu")
		(net "GND")
	)
	(segment
		(start 166.203884 -113.245138)
		(end 166.742364 -113.245138)
		(width 0.3556)
		(layer "F.Cu")
		(net "GND")
	)
	(segment
		(start 385.149852 -277.849838)
		(end 384.674872 -277.374858)
		(width 0.249936)
		(layer "F.Cu")
		(net "GND")
	)
	(segment
		(start 396.0749 -304.924714)
		(end 395.59992 -305.399948)
		(width 0.249936)
		(layer "F.Cu")
		(net "GND")
	)
	(segment
		(start 362.517182 -159.558482)
		(end 362.294932 -159.336232)
		(width 0.254)
		(layer "F.Cu")
		(net "GND")
	)
	(segment
		(start 67.249802 -301.599854)
		(end 66.774822 -302.074834)
		(width 0.249936)
		(layer "F.Cu")
		(net "GND")
	)
	(segment
		(start 395.12494 -306.824888)
		(end 395.59992 -307.299868)
		(width 0.249936)
		(layer "F.Cu")
		(net "GND")
	)
	(segment
		(start 80.54975 -291.149786)
		(end 81.024984 -290.674806)
		(width 0.249936)
		(layer "F.Cu")
		(net "GND")
	)
	(segment
		(start 255.524 -27.411934)
		(end 255.524 -26.319734)
		(width 0.4572)
		(layer "F.Cu")
		(net "GND")
	)
	(segment
		(start 310.257444 -80.449674)
		(end 310.943244 -80.449674)
		(width 0.254)
		(layer "F.Cu")
		(net "GND")
	)
	(segment
		(start 394.17498 -301.124874)
		(end 394.64996 -300.649894)
		(width 0.249936)
		(layer "F.Cu")
		(net "GND")
	)
	(segment
		(start 81.872074 -33.248092)
		(end 81.872074 -33.857692)
		(width 0.4572)
		(layer "F.Cu")
		(net "GND")
	)
	(segment
		(start 41.599866 -299.699934)
		(end 41.124886 -299.224954)
		(width 0.249936)
		(layer "F.Cu")
		(net "GND")
	)
	(segment
		(start 410.770832 -235.358432)
		(end 411.445202 -236.032802)
		(width 0.4572)
		(layer "F.Cu")
		(net "GND")
	)
	(segment
		(start 284.867858 -56.353456)
		(end 285.523178 -56.353456)
		(width 0.254)
		(layer "F.Cu")
		(net "GND")
	)
	(segment
		(start 56.715152 -59.946286)
		(end 56.715152 -60.601606)
		(width 0.4572)
		(layer "F.Cu")
		(net "GND")
	)
	(segment
		(start 289.47491 -303.974754)
		(end 288.99993 -303.499774)
		(width 0.249936)
		(layer "F.Cu")
		(net "GND")
	)
	(segment
		(start 166.249858 -288.299906)
		(end 165.774878 -288.774886)
		(width 0.249936)
		(layer "F.Cu")
		(net "GND")
	)
	(segment
		(start 58.284872 -383.652268)
		(end 57.647078 -383.652268)
		(width 0.4572)
		(layer "F.Cu")
		(net "GND")
	)
	(segment
		(start 198.550022 -292.099746)
		(end 199.025002 -291.624766)
		(width 0.249936)
		(layer "F.Cu")
		(net "GND")
	)
	(segment
		(start 242.864894 -34.990024)
		(end 241.848894 -34.990024)
		(width 0.3556)
		(layer "F.Cu")
		(net "GND")
	)
	(segment
		(start 192.375028 -293.52494)
		(end 191.900048 -293.99992)
		(width 0.249936)
		(layer "F.Cu")
		(net "GND")
	)
	(segment
		(start 414.124902 -289.724846)
		(end 414.599882 -290.199826)
		(width 0.249936)
		(layer "F.Cu")
		(net "GND")
	)
	(segment
		(start 57.749948 -286.399732)
		(end 58.224928 -285.924752)
		(width 0.249936)
		(layer "F.Cu")
		(net "GND")
	)
	(segment
		(start 287.574736 -284.024832)
		(end 288.049716 -284.499812)
		(width 0.249936)
		(layer "F.Cu")
		(net "GND")
	)
	(segment
		(start 104.378252 -222.306642)
		(end 103.764588 -222.306642)
		(width 0.1778)
		(layer "F.Cu")
		(net "GND")
	)
	(segment
		(start 152.94991 -284.499812)
		(end 152.47493 -284.024832)
		(width 0.249936)
		(layer "F.Cu")
		(net "GND")
	)
	(segment
		(start 452.124572 -120.526302)
		(end 452.885556 -120.526302)
		(width 0.4572)
		(layer "F.Cu")
		(net "GND")
	)
	(segment
		(start 397.97482 -302.074834)
		(end 398.4498 -301.599854)
		(width 0.249936)
		(layer "F.Cu")
		(net "GND")
	)
	(segment
		(start 67.249802 -292.099746)
		(end 66.774822 -291.624766)
		(width 0.249936)
		(layer "F.Cu")
		(net "GND")
	)
	(segment
		(start 309.899812 -291.149786)
		(end 309.424832 -291.624766)
		(width 0.249936)
		(layer "F.Cu")
		(net "GND")
	)
	(segment
		(start 289.864292 -140.6398)
		(end 289.534092 -140.97)
		(width 0.4572)
		(layer "F.Cu")
		(net "GND")
	)
	(segment
		(start 366.11941 -282.406344)
		(end 365.93907 -282.8417)
		(width 0.2286)
		(layer "F.Cu")
		(net "GND")
	)
	(segment
		(start 42.549826 -279.749758)
		(end 42.074846 -279.274778)
		(width 0.249936)
		(layer "F.Cu")
		(net "GND")
	)
	(segment
		(start 185.725054 -292.574726)
		(end 186.200034 -292.099746)
		(width 0.249936)
		(layer "F.Cu")
		(net "GND")
	)
	(segment
		(start 424.671744 -81.749646)
		(end 425.253404 -82.331306)
		(width 0.4064)
		(layer "F.Cu")
		(net "GND")
	)
	(segment
		(start 400.824954 -305.874928)
		(end 401.299934 -305.399948)
		(width 0.249936)
		(layer "F.Cu")
		(net "GND")
	)
	(segment
		(start 279.974802 -301.124874)
		(end 280.449782 -301.599854)
		(width 0.249936)
		(layer "F.Cu")
		(net "GND")
	)
	(segment
		(start 237.18774 -245.73357)
		(end 237.18774 -246.997982)
		(width 0.4572)
		(layer "F.Cu")
		(net "GND")
	)
	(segment
		(start 161.975038 -298.27474)
		(end 162.450018 -298.74972)
		(width 0.249936)
		(layer "F.Cu")
		(net "GND")
	)
	(segment
		(start 422.199816 -295.89984)
		(end 422.674796 -296.37482)
		(width 0.249936)
		(layer "F.Cu")
		(net "GND")
	)
	(segment
		(start 78.17485 -293.52494)
		(end 78.64983 -293.99992)
		(width 0.249936)
		(layer "F.Cu")
		(net "GND")
	)
	(segment
		(start 400.289268 -178.378358)
		(end 400.289268 -179.080922)
		(width 0.381)
		(layer "F.Cu")
		(net "GND")
	)
	(segment
		(start 64.399922 -305.399948)
		(end 63.924942 -305.874928)
		(width 0.249936)
		(layer "F.Cu")
		(net "GND")
	)
	(segment
		(start 170.049952 -285.449772)
		(end 169.574972 -284.974792)
		(width 0.249936)
		(layer "F.Cu")
		(net "GND")
	)
	(segment
		(start 185.250074 -297.79976)
		(end 185.725054 -298.27474)
		(width 0.249936)
		(layer "F.Cu")
		(net "GND")
	)
	(segment
		(start 195.699888 -300.649894)
		(end 196.174868 -300.174914)
		(width 0.249936)
		(layer "F.Cu")
		(net "GND")
	)
	(segment
		(start 288.573718 -26.606246)
		(end 288.573718 -25.971246)
		(width 0.4572)
		(layer "F.Cu")
		(net "GND")
	)
	(segment
		(start 170.524932 -305.874928)
		(end 170.049952 -306.349908)
		(width 0.249936)
		(layer "F.Cu")
		(net "GND")
	)
	(segment
		(start 118.575328 -64.102234)
		(end 117.869716 -64.102234)
		(width 0.4572)
		(layer "F.Cu")
		(net "GND")
	)
	(segment
		(start 229.867714 -221.504256)
		(end 230.26751 -221.904052)
		(width 0.381)
		(layer "F.Cu")
		(net "GND")
	)
	(segment
		(start 286.149796 -285.449772)
		(end 285.674816 -284.974792)
		(width 0.249936)
		(layer "F.Cu")
		(net "GND")
	)
	(segment
		(start 167.732964 -100.64496)
		(end 166.742364 -100.64496)
		(width 0.3556)
		(layer "F.Cu")
		(net "GND")
	)
	(segment
		(start 90.0176 -303.636426)
		(end 89.0016 -303.636426)
		(width 0.4572)
		(layer "F.Cu")
		(net "GND")
	)
	(segment
		(start 142.768066 -51.019456)
		(end 143.423386 -51.019456)
		(width 0.254)
		(layer "F.Cu")
		(net "GND")
	)
	(segment
		(start 181.92496 -307.774848)
		(end 182.39994 -307.299868)
		(width 0.249936)
		(layer "F.Cu")
		(net "GND")
	)
	(segment
		(start 65.349882 -306.349908)
		(end 65.824862 -306.824888)
		(width 0.249936)
		(layer "F.Cu")
		(net "GND")
	)
	(segment
		(start 328.583036 -100.468176)
		(end 328.031094 -100.468176)
		(width 0.254)
		(layer "F.Cu")
		(net "GND")
	)
	(segment
		(start 150.602442 -252.756924)
		(end 150.602442 -253.45644)
		(width 0.4572)
		(layer "F.Cu")
		(net "GND")
	)
	(segment
		(start 190.950088 -293.99992)
		(end 191.425068 -294.4749)
		(width 0.249936)
		(layer "F.Cu")
		(net "GND")
	)
	(segment
		(start 193.799968 -291.149786)
		(end 193.324988 -291.624766)
		(width 0.249936)
		(layer "F.Cu")
		(net "GND")
	)
	(segment
		(start 412.224982 -303.974754)
		(end 412.699962 -303.499774)
		(width 0.249936)
		(layer "F.Cu")
		(net "GND")
	)
	(segment
		(start 416.499802 -284.499812)
		(end 416.974782 -284.024832)
		(width 0.249936)
		(layer "F.Cu")
		(net "GND")
	)
	(segment
		(start 286.624776 -284.974792)
		(end 286.149796 -285.449772)
		(width 0.249936)
		(layer "F.Cu")
		(net "GND")
	)
	(segment
		(start 276.174708 -300.174914)
		(end 276.649688 -299.699934)
		(width 0.249936)
		(layer "F.Cu")
		(net "GND")
	)
	(segment
		(start 189.999874 -300.649894)
		(end 190.474854 -300.174914)
		(width 0.249936)
		(layer "F.Cu")
		(net "GND")
	)
	(segment
		(start 180.02504 -306.824888)
		(end 179.55006 -307.299868)
		(width 0.249936)
		(layer "F.Cu")
		(net "GND")
	)
	(segment
		(start 399.400014 -299.699934)
		(end 399.874994 -300.174914)
		(width 0.249936)
		(layer "F.Cu")
		(net "GND")
	)
	(segment
		(start 314.915042 -59.946286)
		(end 314.915042 -60.601606)
		(width 0.4572)
		(layer "F.Cu")
		(net "GND")
	)
	(segment
		(start 325.464678 -25.990042)
		(end 326.480678 -25.990042)
		(width 0.3556)
		(layer "F.Cu")
		(net "GND")
	)
	(segment
		(start 286.624776 -296.37482)
		(end 286.149796 -296.8498)
		(width 0.249936)
		(layer "F.Cu")
		(net "GND")
	)
	(segment
		(start 66.299842 -293.99992)
		(end 66.774822 -293.52494)
		(width 0.249936)
		(layer "F.Cu")
		(net "GND")
	)
	(segment
		(start 178.764946 -25.990042)
		(end 177.748946 -25.990042)
		(width 0.3556)
		(layer "F.Cu")
		(net "GND")
	)
	(segment
		(start 303.724818 -291.624766)
		(end 303.249838 -292.099746)
		(width 0.249936)
		(layer "F.Cu")
		(net "GND")
	)
	(segment
		(start 416.979862 -303.969928)
		(end 416.969956 -303.969928)
		(width 0.249936)
		(layer "F.Cu")
		(net "GND")
	)
	(segment
		(start 173.850046 -284.499812)
		(end 173.375066 -284.974792)
		(width 0.249936)
		(layer "F.Cu")
		(net "GND")
	)
	(segment
		(start 260.67512 -64.102234)
		(end 259.969508 -64.102234)
		(width 0.4572)
		(layer "F.Cu")
		(net "GND")
	)
	(segment
		(start 409.849828 -303.499774)
		(end 410.324808 -303.974754)
		(width 0.249936)
		(layer "F.Cu")
		(net "GND")
	)
	(segment
		(start 172.424852 -305.874928)
		(end 171.949872 -305.399948)
		(width 0.249936)
		(layer "F.Cu")
		(net "GND")
	)
	(segment
		(start 184.77484 -304.924714)
		(end 185.250074 -305.399948)
		(width 0.249936)
		(layer "F.Cu")
		(net "GND")
	)
	(segment
		(start 266.340844 -54.163722)
		(end 266.892786 -54.163722)
		(width 0.254)
		(layer "F.Cu")
		(net "GND")
	)
	(segment
		(start 184.29986 -300.649894)
		(end 183.82488 -300.174914)
		(width 0.249936)
		(layer "F.Cu")
		(net "GND")
	)
	(segment
		(start 70.574916 -303.024794)
		(end 71.049896 -303.499774)
		(width 0.249936)
		(layer "F.Cu")
		(net "GND")
	)
	(segment
		(start 279.024842 -298.27474)
		(end 279.499822 -297.79976)
		(width 0.249936)
		(layer "F.Cu")
		(net "GND")
	)
	(segment
		(start 415.097214 -182.32882)
		(end 415.917888 -182.32882)
		(width 0.4572)
		(layer "F.Cu")
		(net "GND")
	)
	(segment
		(start 404.989538 -64.312292)
		(end 405.747982 -64.312292)
		(width 0.4572)
		(layer "F.Cu")
		(net "GND")
	)
	(segment
		(start 198.550022 -301.599854)
		(end 199.025002 -301.124874)
		(width 0.249936)
		(layer "F.Cu")
		(net "GND")
	)
	(segment
		(start 293.74973 -288.299906)
		(end 294.22471 -287.824926)
		(width 0.249936)
		(layer "F.Cu")
		(net "GND")
	)
	(segment
		(start 155.282646 -141.87297)
		(end 155.282646 -140.85697)
		(width 0.4572)
		(layer "F.Cu")
		(net "GND")
	)
	(segment
		(start 284.724856 -302.074834)
		(end 285.199836 -301.599854)
		(width 0.249936)
		(layer "F.Cu")
		(net "GND")
	)
	(segment
		(start 48.24984 -287.349946)
		(end 47.77486 -286.874966)
		(width 0.249936)
		(layer "F.Cu")
		(net "GND")
	)
	(segment
		(start 180.50002 -297.79976)
		(end 180.975 -298.27474)
		(width 0.249936)
		(layer "F.Cu")
		(net "GND")
	)
	(segment
		(start 190.348108 -145.755106)
		(end 189.357508 -145.755106)
		(width 0.3556)
		(layer "F.Cu")
		(net "GND")
	)
	(segment
		(start 189.999874 -293.04996)
		(end 189.524894 -293.52494)
		(width 0.249936)
		(layer "F.Cu")
		(net "GND")
	)
	(segment
		(start 62.024768 -300.174914)
		(end 62.499748 -299.699934)
		(width 0.249936)
		(layer "F.Cu")
		(net "GND")
	)
	(segment
		(start 436.28183 -292.923468)
		(end 436.28183 -291.258244)
		(width 0.4572)
		(layer "F.Cu")
		(net "GND")
	)
	(segment
		(start 128.058164 -255.210564)
		(end 128.667764 -255.210564)
		(width 0.381)
		(layer "F.Cu")
		(net "GND")
	)
	(segment
		(start 279.499822 -286.399732)
		(end 279.024842 -285.924752)
		(width 0.249936)
		(layer "F.Cu")
		(net "GND")
	)
	(segment
		(start 427.42485 -288.774886)
		(end 426.94987 -289.249866)
		(width 0.249936)
		(layer "F.Cu")
		(net "GND")
	)
	(segment
		(start 400.725132 -14.735302)
		(end 401.259548 -14.735302)
		(width 0.381)
		(layer "F.Cu")
		(net "GND")
	)
	(segment
		(start 312.749692 -302.549814)
		(end 312.274712 -302.074834)
		(width 0.249936)
		(layer "F.Cu")
		(net "GND")
	)
	(segment
		(start 172.900086 -285.449772)
		(end 173.375066 -284.974792)
		(width 0.249936)
		(layer "F.Cu")
		(net "GND")
	)
	(segment
		(start 41.599866 -274.049744)
		(end 41.124886 -273.574764)
		(width 0.249936)
		(layer "F.Cu")
		(net "GND")
	)
	(segment
		(start 69.824092 -130.710432)
		(end 69.289422 -131.245102)
		(width 0.3556)
		(layer "F.Cu")
		(net "GND")
	)
	(segment
		(start 282.349702 -284.499812)
		(end 281.874722 -284.024832)
		(width 0.249936)
		(layer "F.Cu")
		(net "GND")
	)
	(segment
		(start 180.02504 -289.724846)
		(end 179.55006 -290.199826)
		(width 0.249936)
		(layer "F.Cu")
		(net "GND")
	)
	(segment
		(start 180.975 -284.974792)
		(end 180.50002 -285.449772)
		(width 0.249936)
		(layer "F.Cu")
		(net "GND")
	)
	(segment
		(start 184.380886 -27.79014)
		(end 183.364886 -27.79014)
		(width 0.3556)
		(layer "F.Cu")
		(net "GND")
	)
	(segment
		(start 242.093242 -221.050612)
		(end 242.08359 -221.04096)
		(width 0.4572)
		(layer "F.Cu")
		(net "GND")
	)
	(segment
		(start 396.54988 -304.449734)
		(end 397.02486 -304.924714)
		(width 0.249936)
		(layer "F.Cu")
		(net "GND")
	)
	(segment
		(start 302.004222 -132.622036)
		(end 301.581312 -133.044946)
		(width 0.3556)
		(layer "F.Cu")
		(net "GND")
	)
	(segment
		(start 411.275022 -289.724846)
		(end 410.799788 -290.199826)
		(width 0.249936)
		(layer "F.Cu")
		(net "GND")
	)
	(segment
		(start 7.213346 -135.058404)
		(end 6.558026 -135.058404)
		(width 0.4064)
		(layer "F.Cu")
		(net "GND")
	)
	(segment
		(start 352.520504 -91.788234)
		(end 351.902776 -91.788234)
		(width 0.4572)
		(layer "F.Cu")
		(net "GND")
	)
	(segment
		(start 51.574954 -305.874928)
		(end 51.099974 -306.349908)
		(width 0.249936)
		(layer "F.Cu")
		(net "GND")
	)
	(segment
		(start 72.267064 -145.755106)
		(end 73.257664 -145.755106)
		(width 0.3556)
		(layer "F.Cu")
		(net "GND")
	)
	(segment
		(start 341.746586 -285.488634)
		(end 341.435182 -285.488634)
		(width 0.2286)
		(layer "F.Cu")
		(net "GND")
	)
	(segment
		(start 360.259376 -259.1435)
		(end 360.25836 -259.142484)
		(width 0.4572)
		(layer "F.Cu")
		(net "GND")
	)
	(segment
		(start 331.650086 -6.541516)
		(end 331.020166 -5.911596)
		(width 0.4572)
		(layer "F.Cu")
		(net "GND")
	)
	(segment
		(start 327.928986 -229.156514)
		(end 328.15657 -228.92893)
		(width 0.3556)
		(layer "F.Cu")
		(net "GND")
	)
	(segment
		(start 182.87492 -285.924752)
		(end 183.3499 -285.449772)
		(width 0.249936)
		(layer "F.Cu")
		(net "GND")
	)
	(segment
		(start 69.926454 -25.832054)
		(end 70.569836 -25.832054)
		(width 0.4572)
		(layer "F.Cu")
		(net "GND")
	)
	(segment
		(start 274.480782 -31.390082)
		(end 273.464782 -31.390082)
		(width 0.3556)
		(layer "F.Cu")
		(net "GND")
	)
	(segment
		(start 171.949872 -306.349908)
		(end 171.474892 -305.874928)
		(width 0.249936)
		(layer "F.Cu")
		(net "GND")
	)
	(segment
		(start 82.449924 -292.099746)
		(end 81.974944 -291.624766)
		(width 0.249936)
		(layer "F.Cu")
		(net "GND")
	)
	(segment
		(start 395.12494 -303.974754)
		(end 395.59992 -304.449734)
		(width 0.249936)
		(layer "F.Cu")
		(net "GND")
	)
	(segment
		(start 413.649922 -292.099746)
		(end 414.124902 -291.624766)
		(width 0.249936)
		(layer "F.Cu")
		(net "GND")
	)
	(segment
		(start 412.224982 -306.824888)
		(end 411.750002 -307.299868)
		(width 0.249936)
		(layer "F.Cu")
		(net "GND")
	)
	(segment
		(start 416.499802 -290.199826)
		(end 416.974782 -290.674806)
		(width 0.249936)
		(layer "F.Cu")
		(net "GND")
	)
	(segment
		(start 73.14692 -53.144166)
		(end 73.14692 -52.592224)
		(width 0.254)
		(layer "F.Cu")
		(net "GND")
	)
	(segment
		(start 271.424908 -298.27474)
		(end 270.949928 -298.74972)
		(width 0.249936)
		(layer "F.Cu")
		(net "GND")
	)
	(segment
		(start 280.449782 -305.399948)
		(end 279.974802 -305.874928)
		(width 0.249936)
		(layer "F.Cu")
		(net "GND")
	)
	(segment
		(start 80.54975 -302.549814)
		(end 81.024984 -303.024794)
		(width 0.249936)
		(layer "F.Cu")
		(net "GND")
	)
	(segment
		(start 427.89983 -302.549814)
		(end 428.37481 -302.074834)
		(width 0.249936)
		(layer "F.Cu")
		(net "GND")
	)
	(segment
		(start 142.768066 -56.353456)
		(end 143.423386 -56.353456)
		(width 0.254)
		(layer "F.Cu")
		(net "GND")
	)
	(segment
		(start 46.34992 -290.199826)
		(end 45.87494 -289.724846)
		(width 0.249936)
		(layer "F.Cu")
		(net "GND")
	)
	(segment
		(start 320.207386 -95.56115)
		(end 320.696336 -95.0722)
		(width 0.4572)
		(layer "F.Cu")
		(net "GND")
	)
	(segment
		(start 321.789298 -294.727884)
		(end 321.744086 -294.682672)
		(width 0.4572)
		(layer "F.Cu")
		(net "GND")
	)
	(segment
		(start 64.874902 -302.074834)
		(end 64.399922 -301.599854)
		(width 0.249936)
		(layer "F.Cu")
		(net "GND")
	)
	(segment
		(start 69.684138 -120.716548)
		(end 69.684138 -120.400572)
		(width 0.3556)
		(layer "F.Cu")
		(net "GND")
	)
	(segment
		(start 197.125082 -299.224954)
		(end 197.600062 -299.699934)
		(width 0.249936)
		(layer "F.Cu")
		(net "GND")
	)
	(segment
		(start 280.449782 -287.349946)
		(end 279.974802 -286.874966)
		(width 0.249936)
		(layer "F.Cu")
		(net "GND")
	)
	(segment
		(start 67.249802 -307.299868)
		(end 66.774822 -307.774848)
		(width 0.249936)
		(layer "F.Cu")
		(net "GND")
	)
	(segment
		(start 282.349702 -296.8498)
		(end 282.824936 -296.37482)
		(width 0.249936)
		(layer "F.Cu")
		(net "GND")
	)
	(segment
		(start 269.52448 -298.27474)
		(end 269.049754 -298.749466)
		(width 0.249936)
		(layer "F.Cu")
		(net "GND")
	)
	(segment
		(start 407.949908 -306.349908)
		(end 408.424888 -306.824888)
		(width 0.249936)
		(layer "F.Cu")
		(net "GND")
	)
	(segment
		(start 79.59979 -291.149786)
		(end 79.12481 -290.674806)
		(width 0.249936)
		(layer "F.Cu")
		(net "GND")
	)
	(segment
		(start 431.01514 -59.946286)
		(end 431.01514 -60.601606)
		(width 0.4572)
		(layer "F.Cu")
		(net "GND")
	)
	(segment
		(start 369.895628 -90.642694)
		(end 370.581428 -90.642694)
		(width 0.4572)
		(layer "F.Cu")
		(net "GND")
	)
	(segment
		(start 163.399978 -288.299906)
		(end 162.924998 -287.824926)
		(width 0.249936)
		(layer "F.Cu")
		(net "GND")
	)
	(segment
		(start 177.529744 -171.661328)
		(end 177.529744 -172.329348)
		(width 0.4572)
		(layer "F.Cu")
		(net "GND")
	)
	(segment
		(start 180.50002 -307.299868)
		(end 180.975 -307.774848)
		(width 0.249936)
		(layer "F.Cu")
		(net "GND")
	)
	(segment
		(start 173.850046 -286.399732)
		(end 174.325026 -285.924752)
		(width 0.249936)
		(layer "F.Cu")
		(net "GND")
	)
	(segment
		(start 389.899906 -285.449772)
		(end 389.424926 -285.924752)
		(width 0.249936)
		(layer "F.Cu")
		(net "GND")
	)
	(segment
		(start 80.07477 -292.574726)
		(end 80.54975 -293.04996)
		(width 0.249936)
		(layer "F.Cu")
		(net "GND")
	)
	(segment
		(start 193.799968 -291.149786)
		(end 194.274948 -291.624766)
		(width 0.249936)
		(layer "F.Cu")
		(net "GND")
	)
	(segment
		(start 365.190532 -91.356942)
		(end 365.190532 -92.096336)
		(width 0.4572)
		(layer "F.Cu")
		(net "GND")
	)
	(segment
		(start 284.724856 -305.874928)
		(end 284.249876 -306.349908)
		(width 0.249936)
		(layer "F.Cu")
		(net "GND")
	)
	(segment
		(start 45.051726 -125.955044)
		(end 46.042326 -125.955044)
		(width 0.3556)
		(layer "F.Cu")
		(net "GND")
	)
	(segment
		(start 71.049896 -300.649894)
		(end 70.574916 -300.174914)
		(width 0.249936)
		(layer "F.Cu")
		(net "GND")
	)
	(segment
		(start 75.79995 -292.099746)
		(end 76.27493 -291.624766)
		(width 0.249936)
		(layer "F.Cu")
		(net "GND")
	)
	(segment
		(start 190.348108 -136.645142)
		(end 189.357508 -136.645142)
		(width 0.3556)
		(layer "F.Cu")
		(net "GND")
	)
	(segment
		(start 301.349918 -297.79976)
		(end 301.824898 -298.27474)
		(width 0.249936)
		(layer "F.Cu")
		(net "GND")
	)
	(segment
		(start 397.02486 -307.774848)
		(end 396.54988 -307.299868)
		(width 0.249936)
		(layer "F.Cu")
		(net "GND")
	)
	(segment
		(start 74.84999 -292.099746)
		(end 74.374756 -292.574726)
		(width 0.249936)
		(layer "F.Cu")
		(net "GND")
	)
	(segment
		(start 39.699946 -289.249866)
		(end 39.224966 -289.724846)
		(width 0.254)
		(layer "F.Cu")
		(net "GND")
	)
	(segment
		(start 409.849828 -284.499812)
		(end 410.324808 -284.974792)
		(width 0.249936)
		(layer "F.Cu")
		(net "GND")
	)
	(segment
		(start 150.241 -54.163722)
		(end 150.792942 -54.163722)
		(width 0.254)
		(layer "F.Cu")
		(net "GND")
	)
	(segment
		(start 159.599884 -288.299906)
		(end 159.124904 -288.774886)
		(width 0.249936)
		(layer "F.Cu")
		(net "GND")
	)
	(segment
		(start 190.348108 -151.155146)
		(end 189.357508 -151.155146)
		(width 0.3556)
		(layer "F.Cu")
		(net "GND")
	)
	(segment
		(start 4.689602 -64.312292)
		(end 5.448046 -64.312292)
		(width 0.4572)
		(layer "F.Cu")
		(net "GND")
	)
	(segment
		(start 395.12494 -300.174914)
		(end 394.64996 -300.649894)
		(width 0.249936)
		(layer "F.Cu")
		(net "GND")
	)
	(segment
		(start 429.325024 -288.774886)
		(end 428.84979 -289.249866)
		(width 0.249936)
		(layer "F.Cu")
		(net "GND")
	)
	(segment
		(start 272.374868 -279.274778)
		(end 272.849848 -279.749758)
		(width 0.249936)
		(layer "F.Cu")
		(net "GND")
	)
	(segment
		(start 310.849772 -290.199826)
		(end 310.374792 -289.724846)
		(width 0.249936)
		(layer "F.Cu")
		(net "GND")
	)
	(segment
		(start 418.399976 -290.199826)
		(end 418.874956 -289.724846)
		(width 0.249936)
		(layer "F.Cu")
		(net "GND")
	)
	(segment
		(start 72.518524 -116.435124)
		(end 73.257664 -116.435124)
		(width 0.3556)
		(layer "F.Cu")
		(net "GND")
	)
	(segment
		(start 64.874902 -284.974792)
		(end 65.349882 -284.499812)
		(width 0.249936)
		(layer "F.Cu")
		(net "GND")
	)
	(segment
		(start 69.318632 -121.83491)
		(end 68.65747 -121.83491)
		(width 0.3556)
		(layer "F.Cu")
		(net "GND")
	)
	(segment
		(start 189.999874 -292.099746)
		(end 189.524894 -292.574726)
		(width 0.249936)
		(layer "F.Cu")
		(net "GND")
	)
	(segment
		(start 279.974802 -305.874928)
		(end 280.449782 -306.349908)
		(width 0.249936)
		(layer "F.Cu")
		(net "GND")
	)
	(segment
		(start 404.150068 -296.8498)
		(end 404.625048 -296.37482)
		(width 0.249936)
		(layer "F.Cu")
		(net "GND")
	)
	(segment
		(start 152.94991 -290.199826)
		(end 152.47493 -289.724846)
		(width 0.249936)
		(layer "F.Cu")
		(net "GND")
	)
	(segment
		(start 376.09145 -305.334162)
		(end 376.09145 -305.507898)
		(width 0.4572)
		(layer "F.Cu")
		(net "GND")
	)
	(segment
		(start 290.89985 -285.449772)
		(end 290.42487 -284.974792)
		(width 0.249936)
		(layer "F.Cu")
		(net "GND")
	)
	(segment
		(start 88.8238 -291.2618)
		(end 88.8238 -291.592)
		(width 0.4572)
		(layer "F.Cu")
		(net "GND")
	)
	(segment
		(start 230.66756 -218.30411)
		(end 231.067356 -217.904314)
		(width 0.381)
		(layer "F.Cu")
		(net "GND")
	)
	(segment
		(start 279.557734 -102.847394)
		(end 279.155398 -102.445058)
		(width 0.3556)
		(layer "F.Cu")
		(net "GND")
	)
	(segment
		(start 287.099756 -297.79976)
		(end 286.624776 -298.27474)
		(width 0.249936)
		(layer "F.Cu")
		(net "GND")
	)
	(segment
		(start 293.27475 -284.974792)
		(end 292.79977 -284.499812)
		(width 0.249936)
		(layer "F.Cu")
		(net "GND")
	)
	(segment
		(start 40.649906 -281.649932)
		(end 40.174926 -281.174952)
		(width 0.249936)
		(layer "F.Cu")
		(net "GND")
	)
	(segment
		(start 405.100028 -293.99992)
		(end 405.575008 -294.4749)
		(width 0.249936)
		(layer "F.Cu")
		(net "GND")
	)
	(segment
		(start 384.572002 -247.32996)
		(end 383.72796 -247.32996)
		(width 0.4572)
		(layer "F.Cu")
		(net "GND")
	)
	(segment
		(start 157.364938 -34.990024)
		(end 158.380938 -34.990024)
		(width 0.3556)
		(layer "F.Cu")
		(net "GND")
	)
	(segment
		(start 367.14684 -38.49116)
		(end 366.441228 -38.49116)
		(width 0.4572)
		(layer "F.Cu")
		(net "GND")
	)
	(segment
		(start 169.574972 -284.024832)
		(end 170.049952 -284.499812)
		(width 0.249936)
		(layer "F.Cu")
		(net "GND")
	)
	(segment
		(start 153.89987 -298.74972)
		(end 154.37485 -299.224954)
		(width 0.249936)
		(layer "F.Cu")
		(net "GND")
	)
	(segment
		(start 218.614244 -181.14518)
		(end 217.979244 -181.14518)
		(width 0.4572)
		(layer "F.Cu")
		(net "GND")
	)
	(segment
		(start 183.364886 -33.19018)
		(end 182.348886 -33.19018)
		(width 0.3556)
		(layer "F.Cu")
		(net "GND")
	)
	(segment
		(start 344.093546 -221.986856)
		(end 343.69375 -222.386652)
		(width 0.381)
		(layer "F.Cu")
		(net "GND")
	)
	(segment
		(start 416.499802 -303.499774)
		(end 416.024822 -303.974754)
		(width 0.249936)
		(layer "F.Cu")
		(net "GND")
	)
	(segment
		(start 297.074844 -305.874928)
		(end 296.599864 -306.349908)
		(width 0.249936)
		(layer "F.Cu")
		(net "GND")
	)
	(segment
		(start 305.624738 -298.27474)
		(end 306.099718 -297.79976)
		(width 0.249936)
		(layer "F.Cu")
		(net "GND")
	)
	(segment
		(start 407.949908 -286.399732)
		(end 408.424888 -285.924752)
		(width 0.249936)
		(layer "F.Cu")
		(net "GND")
	)
	(segment
		(start 393.16914 -152.958038)
		(end 393.19454 -152.958038)
		(width 0.3556)
		(layer "F.Cu")
		(net "GND")
	)
	(segment
		(start 292.79977 -306.349908)
		(end 292.32479 -306.824888)
		(width 0.249936)
		(layer "F.Cu")
		(net "GND")
	)
	(segment
		(start 76.27493 -299.224954)
		(end 76.74991 -298.74972)
		(width 0.249936)
		(layer "F.Cu")
		(net "GND")
	)
	(segment
		(start 296.124884 -297.32478)
		(end 295.649904 -296.8498)
		(width 0.249936)
		(layer "F.Cu")
		(net "GND")
	)
	(segment
		(start 182.87492 -289.724846)
		(end 183.3499 -290.199826)
		(width 0.249936)
		(layer "F.Cu")
		(net "GND")
	)
	(segment
		(start 409.849828 -286.399732)
		(end 410.324808 -285.924752)
		(width 0.249936)
		(layer "F.Cu")
		(net "GND")
	)
	(segment
		(start 193.324988 -289.724846)
		(end 193.799968 -289.249866)
		(width 0.249936)
		(layer "F.Cu")
		(net "GND")
	)
	(segment
		(start 123.31319 -136.328404)
		(end 122.739404 -136.328404)
		(width 0.4064)
		(layer "F.Cu")
		(net "GND")
	)
	(segment
		(start 276.174708 -299.224954)
		(end 276.649688 -298.74972)
		(width 0.249936)
		(layer "F.Cu")
		(net "GND")
	)
	(segment
		(start 423.62501 -296.37482)
		(end 424.09999 -295.89984)
		(width 0.249936)
		(layer "F.Cu")
		(net "GND")
	)
	(segment
		(start 271.899888 -281.649932)
		(end 271.424908 -281.174952)
		(width 0.249936)
		(layer "F.Cu")
		(net "GND")
	)
	(segment
		(start 374.968008 -56.353456)
		(end 375.623328 -56.353456)
		(width 0.254)
		(layer "F.Cu")
		(net "GND")
	)
	(segment
		(start 190.226696 -410.195522)
		(end 190.226696 -410.898086)
		(width 0.381)
		(layer "F.Cu")
		(net "GND")
	)
	(segment
		(start 290.42487 -291.624766)
		(end 290.89985 -292.099746)
		(width 0.249936)
		(layer "F.Cu")
		(net "GND")
	)
	(segment
		(start 46.34992 -302.549814)
		(end 46.8249 -302.074834)
		(width 0.249936)
		(layer "F.Cu")
		(net "GND")
	)
	(segment
		(start 183.82488 -306.824888)
		(end 184.29986 -307.299868)
		(width 0.249936)
		(layer "F.Cu")
		(net "GND")
	)
	(segment
		(start 44.449746 -295.89984)
		(end 43.974766 -296.37482)
		(width 0.249936)
		(layer "F.Cu")
		(net "GND")
	)
	(segment
		(start 169.927778 -34.732468)
		(end 169.695368 -34.732468)
		(width 0.4572)
		(layer "F.Cu")
		(net "GND")
	)
	(segment
		(start 393.351766 -122.355102)
		(end 394.342366 -122.355102)
		(width 0.3556)
		(layer "F.Cu")
		(net "GND")
	)
	(segment
		(start 163.399978 -302.549814)
		(end 163.874958 -303.024794)
		(width 0.249936)
		(layer "F.Cu")
		(net "GND")
	)
	(segment
		(start 457.87437 -112.785652)
		(end 457.31303 -112.785652)
		(width 0.254)
		(layer "F.Cu")
		(net "GND")
	)
	(segment
		(start 67.66687 -143.955008)
		(end 68.65747 -143.955008)
		(width 0.3556)
		(layer "F.Cu")
		(net "GND")
	)
	(segment
		(start 30.68955 -64.312292)
		(end 31.447994 -64.312292)
		(width 0.4572)
		(layer "F.Cu")
		(net "GND")
	)
	(segment
		(start 106.750866 -386.917184)
		(end 106.750866 -387.598412)
		(width 0.4572)
		(layer "F.Cu")
		(net "GND")
	)
	(segment
		(start 44.449746 -300.649894)
		(end 43.974766 -301.124874)
		(width 0.254)
		(layer "F.Cu")
		(net "GND")
	)
	(segment
		(start 203.183998 -87.61476)
		(end 203.183998 -88.22436)
		(width 0.4572)
		(layer "F.Cu")
		(net "GND")
	)
	(segment
		(start 301.88027 -156.554932)
		(end 300.857412 -156.554932)
		(width 0.3556)
		(layer "F.Cu")
		(net "GND")
	)
	(segment
		(start 393.146788 -38.49116)
		(end 392.441176 -38.49116)
		(width 0.4572)
		(layer "F.Cu")
		(net "GND")
	)
	(segment
		(start 91.0336 -303.636426)
		(end 91.0336 -303.228248)
		(width 0.4572)
		(layer "F.Cu")
		(net "GND")
	)
	(segment
		(start 57.749948 -285.449772)
		(end 57.274968 -284.974792)
		(width 0.249936)
		(layer "F.Cu")
		(net "GND")
	)
	(segment
		(start 387.999986 -290.199826)
		(end 387.525006 -289.724846)
		(width 0.249936)
		(layer "F.Cu")
		(net "GND")
	)
	(segment
		(start 302.167544 -134.400544)
		(end 301.723044 -134.845044)
		(width 0.3556)
		(layer "F.Cu")
		(net "GND")
	)
	(segment
		(start 379.715776 -309.287672)
		(end 379.087634 -308.65953)
		(width 0.4572)
		(layer "F.Cu")
		(net "GND")
	)
	(segment
		(start 338.47405 -172.085)
		(end 339.09 -172.085)
		(width 0.4572)
		(layer "F.Cu")
		(net "GND")
	)
	(segment
		(start 51.63312 -106.045)
		(end 50.64252 -106.045)
		(width 0.3556)
		(layer "F.Cu")
		(net "GND")
	)
	(segment
		(start 71.997824 -133.472682)
		(end 72.42556 -133.044946)
		(width 0.3556)
		(layer "F.Cu")
		(net "GND")
	)
	(segment
		(start 15.686786 -111.739426)
		(end 15.686786 -111.127032)
		(width 0.4572)
		(layer "F.Cu")
		(net "GND")
	)
	(segment
		(start 405.575008 -284.974792)
		(end 406.049988 -284.499812)
		(width 0.249936)
		(layer "F.Cu")
		(net "GND")
	)
	(segment
		(start 335.64195 -178.943)
		(end 335.026 -178.943)
		(width 0.4572)
		(layer "F.Cu")
		(net "GND")
	)
	(segment
		(start 155.800044 -290.199826)
		(end 155.325064 -289.724846)
		(width 0.249936)
		(layer "F.Cu")
		(net "GND")
	)
	(segment
		(start 410.324808 -306.824888)
		(end 409.849828 -306.349908)
		(width 0.249936)
		(layer "F.Cu")
		(net "GND")
	)
	(segment
		(start 362.548932 -27.79014)
		(end 363.564932 -27.79014)
		(width 0.3556)
		(layer "F.Cu")
		(net "GND")
	)
	(segment
		(start 49.60493 -105.673652)
		(end 49.976278 -106.045)
		(width 0.3556)
		(layer "F.Cu")
		(net "GND")
	)
	(segment
		(start 391.799826 -274.049744)
		(end 391.324846 -273.574764)
		(width 0.249936)
		(layer "F.Cu")
		(net "GND")
	)
	(segment
		(start 253.261114 -38.701218)
		(end 254.019558 -38.701218)
		(width 0.4572)
		(layer "F.Cu")
		(net "GND")
	)
	(segment
		(start 400.824954 -305.874928)
		(end 401.299934 -306.349908)
		(width 0.249936)
		(layer "F.Cu")
		(net "GND")
	)
	(segment
		(start 71.049896 -290.199826)
		(end 71.524876 -289.724846)
		(width 0.249936)
		(layer "F.Cu")
		(net "GND")
	)
	(segment
		(start 260.54177 -26.606246)
		(end 260.54177 -25.971246)
		(width 0.4572)
		(layer "F.Cu")
		(net "GND")
	)
	(segment
		(start 197.089014 -406.331166)
		(end 196.763132 -406.657048)
		(width 0.4572)
		(layer "F.Cu")
		(net "GND")
	)
	(segment
		(start 289.534092 -140.97)
		(end 289.222942 -140.97)
		(width 0.4572)
		(layer "F.Cu")
		(net "GND")
	)
	(segment
		(start 416.499802 -307.299868)
		(end 416.974782 -307.774848)
		(width 0.249936)
		(layer "F.Cu")
		(net "GND")
	)
	(segment
		(start 417.924996 -284.024832)
		(end 418.399976 -284.499812)
		(width 0.249936)
		(layer "F.Cu")
		(net "GND")
	)
	(segment
		(start 277.251668 -98.845116)
		(end 278.242268 -98.845116)
		(width 0.3556)
		(layer "F.Cu")
		(net "GND")
	)
	(segment
		(start 166.725092 -306.824888)
		(end 167.200072 -306.349908)
		(width 0.249936)
		(layer "F.Cu")
		(net "GND")
	)
	(segment
		(start 288.99993 -306.349908)
		(end 288.524696 -305.874928)
		(width 0.249936)
		(layer "F.Cu")
		(net "GND")
	)
	(segment
		(start 166.725092 -296.37482)
		(end 166.249858 -296.8498)
		(width 0.249936)
		(layer "F.Cu")
		(net "GND")
	)
	(segment
		(start 324.448678 -29.589984)
		(end 325.464678 -29.589984)
		(width 0.3556)
		(layer "F.Cu")
		(net "GND")
	)
	(segment
		(start 185.783982 -122.597164)
		(end 185.783982 -122.200416)
		(width 0.3556)
		(layer "F.Cu")
		(net "GND")
	)
	(segment
		(start 286.624776 -285.924752)
		(end 287.099756 -285.449772)
		(width 0.249936)
		(layer "F.Cu")
		(net "GND")
	)
	(segment
		(start 118.382796 -28.47848)
		(end 118.043452 -28.139136)
		(width 0.254)
		(layer "F.Cu")
		(net "GND")
	)
	(segment
		(start 43.974766 -299.224954)
		(end 43.499786 -299.699934)
		(width 0.249936)
		(layer "F.Cu")
		(net "GND")
	)
	(segment
		(start 80.54975 -302.549814)
		(end 80.07477 -302.074834)
		(width 0.249936)
		(layer "F.Cu")
		(net "GND")
	)
	(segment
		(start 404.624794 -291.624766)
		(end 405.100028 -292.099746)
		(width 0.249936)
		(layer "F.Cu")
		(net "GND")
	)
	(segment
		(start 135.358124 -73.166732)
		(end 135.358124 -73.85177)
		(width 0.4572)
		(layer "F.Cu")
		(net "GND")
	)
	(segment
		(start 405.575008 -285.924752)
		(end 405.100028 -285.449772)
		(width 0.249936)
		(layer "F.Cu")
		(net "GND")
	)
	(segment
		(start 340.493858 -220.78696)
		(end 340.094062 -221.186756)
		(width 0.381)
		(layer "F.Cu")
		(net "GND")
	)
	(segment
		(start 67.66687 -120.035066)
		(end 68.65747 -120.035066)
		(width 0.3556)
		(layer "F.Cu")
		(net "GND")
	)
	(segment
		(start 296.124884 -284.974792)
		(end 296.599864 -285.449772)
		(width 0.249936)
		(layer "F.Cu")
		(net "GND")
	)
	(segment
		(start 311.799732 -293.04996)
		(end 311.324752 -292.574726)
		(width 0.249936)
		(layer "F.Cu")
		(net "GND")
	)
	(segment
		(start 60.599828 -307.299868)
		(end 61.074808 -306.824888)
		(width 0.249936)
		(layer "F.Cu")
		(net "GND")
	)
	(segment
		(start 43.974766 -301.124874)
		(end 43.499786 -300.649894)
		(width 0.249936)
		(layer "F.Cu")
		(net "GND")
	)
	(segment
		(start 284.249876 -299.699934)
		(end 284.724856 -300.174914)
		(width 0.249936)
		(layer "F.Cu")
		(net "GND")
	)
	(segment
		(start 21.147024 -53.144166)
		(end 21.147024 -52.592224)
		(width 0.254)
		(layer "F.Cu")
		(net "GND")
	)
	(segment
		(start 430.274984 -303.024794)
		(end 430.749964 -303.499774)
		(width 0.249936)
		(layer "F.Cu")
		(net "GND")
	)
	(segment
		(start 331.041502 -89.269316)
		(end 330.189586 -89.269316)
		(width 0.381)
		(layer "F.Cu")
		(net "GND")
	)
	(segment
		(start 239.70869 -215.323928)
		(end 240.081562 -215.6968)
		(width 0.4572)
		(layer "F.Cu")
		(net "GND")
	)
	(segment
		(start 181.92496 -306.824888)
		(end 182.39994 -306.349908)
		(width 0.249936)
		(layer "F.Cu")
		(net "GND")
	)
	(segment
		(start 392.749786 -284.499812)
		(end 392.274806 -284.024832)
		(width 0.249936)
		(layer "F.Cu")
		(net "GND")
	)
	(segment
		(start 395.12494 -305.874928)
		(end 394.64996 -306.349908)
		(width 0.249936)
		(layer "F.Cu")
		(net "GND")
	)
	(segment
		(start 104.448356 -225.945954)
		(end 104.448356 -226.595686)
		(width 0.4572)
		(layer "F.Cu")
		(net "GND")
	)
	(segment
		(start 422.199816 -307.299868)
		(end 421.724836 -307.774848)
		(width 0.249936)
		(layer "F.Cu")
		(net "GND")
	)
	(segment
		(start 225.882962 -176.306226)
		(end 224.765362 -176.306226)
		(width 0.3048)
		(layer "F.Cu")
		(net "GND")
	)
	(segment
		(start 429.800004 -295.89984)
		(end 430.274984 -296.37482)
		(width 0.249936)
		(layer "F.Cu")
		(net "GND")
	)
	(segment
		(start 52.049934 -286.399732)
		(end 52.524914 -285.924752)
		(width 0.249936)
		(layer "F.Cu")
		(net "GND")
	)
	(segment
		(start 298.499784 -305.399948)
		(end 298.024804 -305.874928)
		(width 0.249936)
		(layer "F.Cu")
		(net "GND")
	)
	(segment
		(start 386.354828 -34.990024)
		(end 384.96494 -34.990024)
		(width 0.3556)
		(layer "F.Cu")
		(net "GND")
	)
	(segment
		(start 74.84999 -299.699934)
		(end 74.374756 -300.174914)
		(width 0.249936)
		(layer "F.Cu")
		(net "GND")
	)
	(segment
		(start 61.549788 -307.299868)
		(end 62.024768 -307.774848)
		(width 0.249936)
		(layer "F.Cu")
		(net "GND")
	)
	(segment
		(start 75.79995 -293.99992)
		(end 76.27493 -294.4749)
		(width 0.249936)
		(layer "F.Cu")
		(net "GND")
	)
	(segment
		(start 393.351766 -133.565138)
		(end 394.342366 -133.565138)
		(width 0.3556)
		(layer "F.Cu")
		(net "GND")
	)
	(segment
		(start 71.049896 -292.099746)
		(end 71.524876 -291.624766)
		(width 0.249936)
		(layer "F.Cu")
		(net "GND")
	)
	(segment
		(start 164.349938 -298.74972)
		(end 163.874958 -299.224954)
		(width 0.249936)
		(layer "F.Cu")
		(net "GND")
	)
	(segment
		(start 41.599866 -281.649932)
		(end 41.124886 -281.174952)
		(width 0.249936)
		(layer "F.Cu")
		(net "GND")
	)
	(segment
		(start 162.924998 -303.974754)
		(end 162.450018 -303.499774)
		(width 0.249936)
		(layer "F.Cu")
		(net "GND")
	)
	(segment
		(start 360.25836 -254.194564)
		(end 360.86796 -254.194564)
		(width 0.381)
		(layer "F.Cu")
		(net "GND")
	)
	(segment
		(start 161.975038 -287.824926)
		(end 162.450018 -288.299906)
		(width 0.249936)
		(layer "F.Cu")
		(net "GND")
	)
	(segment
		(start 46.34992 -287.349946)
		(end 45.87494 -286.874966)
		(width 0.249936)
		(layer "F.Cu")
		(net "GND")
	)
	(segment
		(start 299.866812 -129.445004)
		(end 300.857412 -129.445004)
		(width 0.3556)
		(layer "F.Cu")
		(net "GND")
	)
	(segment
		(start 422.548304 -152.95499)
		(end 421.557704 -152.95499)
		(width 0.3556)
		(layer "F.Cu")
		(net "GND")
	)
	(segment
		(start 69.9516 -223.2406)
		(end 68.5038 -224.6884)
		(width 0.4572)
		(layer "F.Cu")
		(net "GND")
	)
	(segment
		(start 178.599846 -297.79976)
		(end 178.124866 -297.32478)
		(width 0.249936)
		(layer "F.Cu")
		(net "GND")
	)
	(segment
		(start 69.64807 -118.370858)
		(end 69.630544 -118.370858)
		(width 0.3556)
		(layer "F.Cu")
		(net "GND")
	)
	(segment
		(start 196.649848 -296.8498)
		(end 197.125082 -296.37482)
		(width 0.249936)
		(layer "F.Cu")
		(net "GND")
	)
	(segment
		(start 400.824954 -291.624766)
		(end 401.299934 -292.099746)
		(width 0.249936)
		(layer "F.Cu")
		(net "GND")
	)
	(segment
		(start 52.524914 -284.974792)
		(end 52.049934 -285.449772)
		(width 0.249936)
		(layer "F.Cu")
		(net "GND")
	)
	(segment
		(start 57.274968 -291.624766)
		(end 56.799988 -292.099746)
		(width 0.249936)
		(layer "F.Cu")
		(net "GND")
	)
	(segment
		(start 350.893888 -227.987098)
		(end 351.293684 -228.386894)
		(width 0.381)
		(layer "F.Cu")
		(net "GND")
	)
	(segment
		(start 176.699926 -284.499812)
		(end 177.174906 -284.974792)
		(width 0.249936)
		(layer "F.Cu")
		(net "GND")
	)
	(segment
		(start 185.481214 -133.044946)
		(end 184.757314 -133.044946)
		(width 0.3556)
		(layer "F.Cu")
		(net "GND")
	)
	(segment
		(start 227.438204 -306.281582)
		(end 227.946458 -306.281582)
		(width 0.4572)
		(layer "F.Cu")
		(net "GND")
	)
	(segment
		(start 277.803102 -402.738082)
		(end 278.443182 -402.738082)
		(width 0.4572)
		(layer "F.Cu")
		(net "GND")
	)
	(segment
		(start 168.150032 -305.399948)
		(end 168.625012 -305.874928)
		(width 0.249936)
		(layer "F.Cu")
		(net "GND")
	)
	(segment
		(start 74.248264 -118.234968)
		(end 73.257664 -118.234968)
		(width 0.3556)
		(layer "F.Cu")
		(net "GND")
	)
	(segment
		(start 429.325024 -289.724846)
		(end 428.84979 -289.249866)
		(width 0.249936)
		(layer "F.Cu")
		(net "GND")
	)
	(segment
		(start 295.174924 -306.824888)
		(end 295.649904 -306.349908)
		(width 0.249936)
		(layer "F.Cu")
		(net "GND")
	)
	(segment
		(start 388.949946 -290.199826)
		(end 388.474966 -289.724846)
		(width 0.249936)
		(layer "F.Cu")
		(net "GND")
	)
	(segment
		(start 281.399742 -293.99992)
		(end 281.874722 -294.4749)
		(width 0.249936)
		(layer "F.Cu")
		(net "GND")
	)
	(segment
		(start 384.674872 -280.224738)
		(end 385.149852 -280.699718)
		(width 0.249936)
		(layer "F.Cu")
		(net "GND")
	)
	(segment
		(start 423.62501 -292.574726)
		(end 424.09999 -292.099746)
		(width 0.249936)
		(layer "F.Cu")
		(net "GND")
	)
	(segment
		(start 283.833062 -151.159972)
		(end 282.842462 -151.159972)
		(width 0.3556)
		(layer "F.Cu")
		(net "GND")
	)
	(segment
		(start 42.074846 -298.27474)
		(end 41.599866 -297.79976)
		(width 0.249936)
		(layer "F.Cu")
		(net "GND")
	)
	(segment
		(start 160.549844 -290.199826)
		(end 160.074864 -289.724846)
		(width 0.249936)
		(layer "F.Cu")
		(net "GND")
	)
	(segment
		(start 415.549842 -306.349908)
		(end 415.074862 -305.874928)
		(width 0.249936)
		(layer "F.Cu")
		(net "GND")
	)
	(segment
		(start 410.721556 -201.532744)
		(end 410.57957 -201.532744)
		(width 0.4572)
		(layer "F.Cu")
		(net "GND")
	)
	(segment
		(start 142.743936 -45.88891)
		(end 143.415258 -45.88891)
		(width 0.254)
		(layer "F.Cu")
		(net "GND")
	)
	(segment
		(start 67.724782 -289.724846)
		(end 68.199762 -290.199826)
		(width 0.249936)
		(layer "F.Cu")
		(net "GND")
	)
	(segment
		(start 331.489812 -73.166732)
		(end 331.489812 -73.85177)
		(width 0.4572)
		(layer "F.Cu")
		(net "GND")
	)
	(segment
		(start 298.499784 -297.79976)
		(end 298.974764 -298.27474)
		(width 0.249936)
		(layer "F.Cu")
		(net "GND")
	)
	(segment
		(start 159.599884 -276.899878)
		(end 159.124904 -276.424898)
		(width 0.249936)
		(layer "F.Cu")
		(net "GND")
	)
	(segment
		(start 414.599882 -301.599854)
		(end 415.074862 -302.074834)
		(width 0.249936)
		(layer "F.Cu")
		(net "GND")
	)
	(segment
		(start 413.174942 -306.824888)
		(end 413.649922 -306.349908)
		(width 0.249936)
		(layer "F.Cu")
		(net "GND")
	)
	(segment
		(start 17.592802 -266.899136)
		(end 17.592802 -267.500608)
		(width 0.254)
		(layer "F.Cu")
		(net "GND")
	)
	(segment
		(start 263.997694 -38.937184)
		(end 264.734548 -38.937184)
		(width 0.4572)
		(layer "F.Cu")
		(net "GND")
	)
	(segment
		(start 78.17485 -291.624766)
		(end 77.69987 -291.149786)
		(width 0.249936)
		(layer "F.Cu")
		(net "GND")
	)
	(segment
		(start 92.248736 -31.390082)
		(end 93.264736 -31.390082)
		(width 0.3556)
		(layer "F.Cu")
		(net "GND")
	)
	(segment
		(start 414.599882 -307.299868)
		(end 415.074862 -307.774848)
		(width 0.249936)
		(layer "F.Cu")
		(net "GND")
	)
	(segment
		(start 165.299898 -307.299868)
		(end 164.824918 -306.824888)
		(width 0.249936)
		(layer "F.Cu")
		(net "GND")
	)
	(segment
		(start 444.683134 -100.468176)
		(end 444.131192 -100.468176)
		(width 0.254)
		(layer "F.Cu")
		(net "GND")
	)
	(segment
		(start 61.549788 -292.099746)
		(end 61.074808 -291.624766)
		(width 0.249936)
		(layer "F.Cu")
		(net "GND")
	)
	(segment
		(start 238.585756 -180.885338)
		(end 238.585756 -179.793138)
		(width 0.4572)
		(layer "F.Cu")
		(net "GND")
	)
	(segment
		(start 145.36039 -311.442608)
		(end 144.750028 -310.832246)
		(width 0.4572)
		(layer "F.Cu")
		(net "GND")
	)
	(segment
		(start 42.549826 -276.899878)
		(end 42.074846 -276.424898)
		(width 0.249936)
		(layer "F.Cu")
		(net "GND")
	)
	(segment
		(start 156.750004 -285.449772)
		(end 156.275024 -284.974792)
		(width 0.249936)
		(layer "F.Cu")
		(net "GND")
	)
	(segment
		(start 184.29986 -304.449734)
		(end 183.82488 -303.974754)
		(width 0.249936)
		(layer "F.Cu")
		(net "GND")
	)
	(segment
		(start 60.692792 -54.163722)
		(end 60.767976 -54.238906)
		(width 0.254)
		(layer "F.Cu")
		(net "GND")
	)
	(segment
		(start 310.849772 -292.099746)
		(end 310.374792 -291.624766)
		(width 0.249936)
		(layer "F.Cu")
		(net "GND")
	)
	(segment
		(start 172.900086 -293.99992)
		(end 172.424852 -293.52494)
		(width 0.249936)
		(layer "F.Cu")
		(net "GND")
	)
	(segment
		(start 302.774858 -288.774886)
		(end 303.249838 -289.249866)
		(width 0.249936)
		(layer "F.Cu")
		(net "GND")
	)
	(segment
		(start 47.29988 -292.099746)
		(end 47.29988 -292.1)
		(width 0.254)
		(layer "F.Cu")
		(net "GND")
	)
	(segment
		(start 418.267642 -134.400544)
		(end 417.823142 -134.845044)
		(width 0.3556)
		(layer "F.Cu")
		(net "GND")
	)
	(segment
		(start 410.799788 -306.349908)
		(end 411.275022 -305.874928)
		(width 0.249936)
		(layer "F.Cu")
		(net "GND")
	)
	(segment
		(start 298.499784 -285.449772)
		(end 298.974764 -285.924752)
		(width 0.249936)
		(layer "F.Cu")
		(net "GND")
	)
	(segment
		(start 166.249858 -306.349908)
		(end 165.774878 -305.874928)
		(width 0.249936)
		(layer "F.Cu")
		(net "GND")
	)
	(segment
		(start 53.474874 -307.774848)
		(end 52.999894 -307.299868)
		(width 0.249936)
		(layer "F.Cu")
		(net "GND")
	)
	(segment
		(start 406.049988 -286.399732)
		(end 405.575008 -285.924752)
		(width 0.249936)
		(layer "F.Cu")
		(net "GND")
	)
	(segment
		(start 161.47034 -47.60087)
		(end 161.896298 -47.60087)
		(width 0.254)
		(layer "F.Cu")
		(net "GND")
	)
	(segment
		(start 364.659672 -146.242278)
		(end 364.659672 -145.53565)
		(width 0.4064)
		(layer "F.Cu")
		(net "GND")
	)
	(segment
		(start 293.74973 -307.299868)
		(end 294.22471 -307.774848)
		(width 0.249936)
		(layer "F.Cu")
		(net "GND")
	)
	(segment
		(start 394.17498 -298.27474)
		(end 394.64996 -297.79976)
		(width 0.249936)
		(layer "F.Cu")
		(net "GND")
	)
	(segment
		(start 407.949908 -285.449772)
		(end 408.424888 -285.924752)
		(width 0.249936)
		(layer "F.Cu")
		(net "GND")
	)
	(segment
		(start 414.599882 -286.399732)
		(end 414.124902 -285.924752)
		(width 0.249936)
		(layer "F.Cu")
		(net "GND")
	)
	(segment
		(start 284.724856 -306.824888)
		(end 284.249876 -307.299868)
		(width 0.249936)
		(layer "F.Cu")
		(net "GND")
	)
	(segment
		(start 393.196572 -152.96007)
		(end 394.342366 -152.96007)
		(width 0.3556)
		(layer "F.Cu")
		(net "GND")
	)
	(segment
		(start 437.980836 -25.990042)
		(end 436.964836 -25.990042)
		(width 0.3556)
		(layer "F.Cu")
		(net "GND")
	)
	(segment
		(start 304.428906 -147.314412)
		(end 304.669444 -147.55495)
		(width 0.3556)
		(layer "F.Cu")
		(net "GND")
	)
	(segment
		(start 68.674742 -301.124874)
		(end 68.199762 -300.649894)
		(width 0.249936)
		(layer "F.Cu")
		(net "GND")
	)
	(segment
		(start 394.64996 -293.04996)
		(end 394.17498 -292.57498)
		(width 0.249936)
		(layer "F.Cu")
		(net "GND")
	)
	(segment
		(start 290.689284 -62.812168)
		(end 291.499798 -62.812168)
		(width 0.4572)
		(layer "F.Cu")
		(net "GND")
	)
	(segment
		(start 293.74973 -285.449772)
		(end 293.27475 -285.924752)
		(width 0.249936)
		(layer "F.Cu")
		(net "GND")
	)
	(segment
		(start 187.624974 -296.37482)
		(end 187.149994 -296.8498)
		(width 0.249936)
		(layer "F.Cu")
		(net "GND")
	)
	(segment
		(start 279.232868 -120.555004)
		(end 278.242268 -120.555004)
		(width 0.3556)
		(layer "F.Cu")
		(net "GND")
	)
	(segment
		(start 388.949946 -275.949918)
		(end 388.474966 -275.474938)
		(width 0.249936)
		(layer "F.Cu")
		(net "GND")
	)
	(segment
		(start 145.522442 -252.756924)
		(end 145.522442 -253.45644)
		(width 0.4572)
		(layer "F.Cu")
		(net "GND")
	)
	(segment
		(start 415.96691 -149.355048)
		(end 416.95751 -149.355048)
		(width 0.3556)
		(layer "F.Cu")
		(net "GND")
	)
	(segment
		(start 49.866804 -107.845098)
		(end 50.64252 -107.845098)
		(width 0.3556)
		(layer "F.Cu")
		(net "GND")
	)
	(segment
		(start 421.361108 -38.701218)
		(end 422.119552 -38.701218)
		(width 0.4572)
		(layer "F.Cu")
		(net "GND")
	)
	(segment
		(start 180.50002 -284.499812)
		(end 180.02504 -284.974792)
		(width 0.249936)
		(layer "F.Cu")
		(net "GND")
	)
	(segment
		(start 192.850008 -296.8498)
		(end 193.324988 -297.32478)
		(width 0.249936)
		(layer "F.Cu")
		(net "GND")
	)
	(segment
		(start 432.097688 -38.937184)
		(end 432.834542 -38.937184)
		(width 0.4572)
		(layer "F.Cu")
		(net "GND")
	)
	(segment
		(start 194.749928 -300.649894)
		(end 194.274948 -301.124874)
		(width 0.249936)
		(layer "F.Cu")
		(net "GND")
	)
	(segment
		(start 6.119114 -59.974734)
		(end 5.46862 -59.974734)
		(width 0.4572)
		(layer "F.Cu")
		(net "GND")
	)
	(segment
		(start 64.874902 -284.974792)
		(end 65.349882 -285.449772)
		(width 0.249936)
		(layer "F.Cu")
		(net "GND")
	)
	(segment
		(start 410.32684 -389.92556)
		(end 411.1244 -389.128)
		(width 0.4572)
		(layer "F.Cu")
		(net "GND")
	)
	(segment
		(start 62.499748 -285.449772)
		(end 62.974982 -284.974792)
		(width 0.249936)
		(layer "F.Cu")
		(net "GND")
	)
	(segment
		(start 160.074864 -297.32478)
		(end 160.549844 -296.8498)
		(width 0.249936)
		(layer "F.Cu")
		(net "GND")
	)
	(segment
		(start 76.74991 -302.549814)
		(end 76.27493 -302.074834)
		(width 0.249936)
		(layer "F.Cu")
		(net "GND")
	)
	(segment
		(start 401.774914 -297.32478)
		(end 401.299934 -297.79976)
		(width 0.249936)
		(layer "F.Cu")
		(net "GND")
	)
	(segment
		(start 443.194186 -115.394486)
		(end 443.829186 -115.394486)
		(width 0.4572)
		(layer "F.Cu")
		(net "GND")
	)
	(segment
		(start 79.12481 -302.074834)
		(end 78.64983 -301.599854)
		(width 0.249936)
		(layer "F.Cu")
		(net "GND")
	)
	(segment
		(start 425.764452 -29.67736)
		(end 425.764452 -29.079952)
		(width 0.4572)
		(layer "F.Cu")
		(net "GND")
	)
	(segment
		(start 66.299842 -284.499812)
		(end 65.824862 -284.974792)
		(width 0.249936)
		(layer "F.Cu")
		(net "GND")
	)
	(segment
		(start 415.612834 -104.240076)
		(end 416.95751 -104.240076)
		(width 0.3556)
		(layer "F.Cu")
		(net "GND")
	)
	(segment
		(start 180.975 -307.774848)
		(end 181.44998 -307.299868)
		(width 0.249936)
		(layer "F.Cu")
		(net "GND")
	)
	(segment
		(start 69.624956 -292.574726)
		(end 70.099936 -293.04996)
		(width 0.249936)
		(layer "F.Cu")
		(net "GND")
	)
	(segment
		(start 303.724818 -299.224954)
		(end 304.199798 -299.699934)
		(width 0.249936)
		(layer "F.Cu")
		(net "GND")
	)
	(segment
		(start 230.66756 -220.704156)
		(end 231.067356 -221.103952)
		(width 0.381)
		(layer "F.Cu")
		(net "GND")
	)
	(segment
		(start 73.424796 -296.37482)
		(end 72.949816 -296.8498)
		(width 0.249936)
		(layer "F.Cu")
		(net "GND")
	)
	(segment
		(start 410.324808 -285.924752)
		(end 410.799788 -286.399732)
		(width 0.249936)
		(layer "F.Cu")
		(net "GND")
	)
	(segment
		(start 41.599866 -292.099746)
		(end 41.124886 -291.624766)
		(width 0.249936)
		(layer "F.Cu")
		(net "GND")
	)
	(segment
		(start 176.224946 -300.174914)
		(end 176.699926 -299.699934)
		(width 0.249936)
		(layer "F.Cu")
		(net "GND")
	)
	(segment
		(start 363.564932 -33.19018)
		(end 364.580932 -33.19018)
		(width 0.3556)
		(layer "F.Cu")
		(net "GND")
	)
	(segment
		(start 310.374792 -293.52494)
		(end 309.899812 -293.04996)
		(width 0.249936)
		(layer "F.Cu")
		(net "GND")
	)
	(segment
		(start 223.512634 -238.98733)
		(end 223.45396 -239.046004)
		(width 0.4572)
		(layer "F.Cu")
		(net "GND")
	)
	(segment
		(start 163.399978 -306.349908)
		(end 163.874958 -306.824888)
		(width 0.249936)
		(layer "F.Cu")
		(net "GND")
	)
	(segment
		(start 165.774878 -302.074834)
		(end 166.249858 -301.599854)
		(width 0.249936)
		(layer "F.Cu")
		(net "GND")
	)
	(segment
		(start 225.39706 -279.075896)
		(end 224.76206 -279.075896)
		(width 0.4572)
		(layer "F.Cu")
		(net "GND")
	)
	(segment
		(start 284.724856 -285.924752)
		(end 284.249876 -286.399732)
		(width 0.249936)
		(layer "F.Cu")
		(net "GND")
	)
	(segment
		(start 247.50776 -154.510994)
		(end 248.148348 -154.510994)
		(width 0.4572)
		(layer "F.Cu")
		(net "GND")
	)
	(segment
		(start 392.749786 -288.299906)
		(end 392.274806 -288.774886)
		(width 0.249936)
		(layer "F.Cu")
		(net "GND")
	)
	(segment
		(start 279.1587 -107.845098)
		(end 278.242268 -107.845098)
		(width 0.3556)
		(layer "F.Cu")
		(net "GND")
	)
	(segment
		(start 127.594614 -159.266382)
		(end 126.153926 -160.70707)
		(width 0.254)
		(layer "F.Cu")
		(net "GND")
	)
	(segment
		(start 286.624776 -291.624766)
		(end 286.149796 -292.099746)
		(width 0.249936)
		(layer "F.Cu")
		(net "GND")
	)
	(segment
		(start 299.924724 -303.974754)
		(end 300.399704 -303.499774)
		(width 0.249936)
		(layer "F.Cu")
		(net "GND")
	)
	(segment
		(start 358.01046 -122.931428)
		(end 357.35514 -122.931428)
		(width 0.4064)
		(layer "F.Cu")
		(net "GND")
	)
	(segment
		(start 62.499748 -297.79976)
		(end 62.974982 -298.27474)
		(width 0.249936)
		(layer "F.Cu")
		(net "GND")
	)
	(segment
		(start 77.22489 -293.52494)
		(end 77.69987 -293.04996)
		(width 0.249936)
		(layer "F.Cu")
		(net "GND")
	)
	(segment
		(start 415.549842 -292.099746)
		(end 415.074862 -291.624766)
		(width 0.249936)
		(layer "F.Cu")
		(net "GND")
	)
	(segment
		(start 190.96101 -37.201094)
		(end 190.198502 -37.201094)
		(width 0.4572)
		(layer "F.Cu")
		(net "GND")
	)
	(segment
		(start 415.96691 -125.435106)
		(end 416.95751 -125.435106)
		(width 0.3556)
		(layer "F.Cu")
		(net "GND")
	)
	(segment
		(start 279.499822 -295.89984)
		(end 278.549862 -296.8498)
		(width 0.249936)
		(layer "F.Cu")
		(net "GND")
	)
	(segment
		(start 102.629462 -385.205224)
		(end 102.629462 -384.472942)
		(width 0.4572)
		(layer "F.Cu")
		(net "GND")
	)
	(segment
		(start 128.504188 -214.540846)
		(end 127.950214 -215.09482)
		(width 0.4572)
		(layer "F.Cu")
		(net "GND")
	)
	(segment
		(start 306.099718 -298.74972)
		(end 305.624738 -298.27474)
		(width 0.249936)
		(layer "F.Cu")
		(net "GND")
	)
	(segment
		(start 398.925034 -300.174914)
		(end 398.4498 -300.649894)
		(width 0.249936)
		(layer "F.Cu")
		(net "GND")
	)
	(segment
		(start 408.992832 -54.163722)
		(end 409.068016 -54.238906)
		(width 0.254)
		(layer "F.Cu")
		(net "GND")
	)
	(segment
		(start 416.969956 -303.969928)
		(end 416.499802 -303.499774)
		(width 0.249936)
		(layer "F.Cu")
		(net "GND")
	)
	(segment
		(start 39.699946 -290.199826)
		(end 39.224966 -289.724846)
		(width 0.249936)
		(layer "F.Cu")
		(net "GND")
	)
	(segment
		(start 279.499822 -304.449734)
		(end 279.024842 -303.974754)
		(width 0.249936)
		(layer "F.Cu")
		(net "GND")
	)
	(segment
		(start 425.04995 -289.249866)
		(end 424.57497 -288.774886)
		(width 0.249936)
		(layer "F.Cu")
		(net "GND")
	)
	(segment
		(start 415.549842 -286.399732)
		(end 415.074862 -285.924752)
		(width 0.249936)
		(layer "F.Cu")
		(net "GND")
	)
	(segment
		(start 166.725092 -305.874928)
		(end 166.249858 -305.399948)
		(width 0.249936)
		(layer "F.Cu")
		(net "GND")
	)
	(segment
		(start 305.149758 -295.89984)
		(end 305.624738 -296.37482)
		(width 0.249936)
		(layer "F.Cu")
		(net "GND")
	)
	(segment
		(start 166.725092 -303.974754)
		(end 167.200072 -303.499774)
		(width 0.249936)
		(layer "F.Cu")
		(net "GND")
	)
	(segment
		(start 133.558534 -284.42412)
		(end 133.19125 -284.42412)
		(width 0.2286)
		(layer "F.Cu")
		(net "GND")
	)
	(segment
		(start 234.13466 -206.62011)
		(end 234.13466 -205.98511)
		(width 0.4572)
		(layer "F.Cu")
		(net "GND")
	)
	(segment
		(start 223.647254 -180.495194)
		(end 222.961454 -180.495194)
		(width 0.3556)
		(layer "F.Cu")
		(net "GND")
	)
	(segment
		(start 405.100028 -303.499774)
		(end 405.575008 -303.974754)
		(width 0.249936)
		(layer "F.Cu")
		(net "GND")
	)
	(segment
		(start 53.949854 -307.299868)
		(end 53.474874 -306.824888)
		(width 0.249936)
		(layer "F.Cu")
		(net "GND")
	)
	(segment
		(start 179.34178 -162.781488)
		(end 179.34178 -162.08375)
		(width 0.4572)
		(layer "F.Cu")
		(net "GND")
	)
	(segment
		(start 384.998722 -225.585782)
		(end 383.88671 -225.585782)
		(width 0.4572)
		(layer "F.Cu")
		(net "GND")
	)
	(segment
		(start 136.845294 -96.957642)
		(end 137.593324 -96.957642)
		(width 0.4572)
		(layer "F.Cu")
		(net "GND")
	)
	(segment
		(start 297.074844 -287.824926)
		(end 296.599864 -288.299906)
		(width 0.249936)
		(layer "F.Cu")
		(net "GND")
	)
	(segment
		(start 162.924998 -304.924714)
		(end 163.399978 -304.449734)
		(width 0.249936)
		(layer "F.Cu")
		(net "GND")
	)
	(segment
		(start 56.324754 -306.824888)
		(end 56.799988 -306.349908)
		(width 0.249936)
		(layer "F.Cu")
		(net "GND")
	)
	(segment
		(start 286.470852 -34.29762)
		(end 286.46247 -34.29762)
		(width 0.4572)
		(layer "F.Cu")
		(net "GND")
	)
	(segment
		(start 361.03433 -138.819636)
		(end 360.959146 -138.89482)
		(width 0.254)
		(layer "F.Cu")
		(net "GND")
	)
	(segment
		(start 190.348108 -125.435106)
		(end 189.357508 -125.435106)
		(width 0.3556)
		(layer "F.Cu")
		(net "GND")
	)
	(segment
		(start 165.958266 -122.355102)
		(end 166.742364 -122.355102)
		(width 0.3556)
		(layer "F.Cu")
		(net "GND")
	)
	(segment
		(start 165.299898 -308.249828)
		(end 164.824918 -307.774848)
		(width 0.249936)
		(layer "F.Cu")
		(net "GND")
	)
	(segment
		(start 177.174906 -307.774848)
		(end 176.699926 -307.299868)
		(width 0.249936)
		(layer "F.Cu")
		(net "GND")
	)
	(segment
		(start 144.926812 -189.758066)
		(end 144.926812 -190.4492)
		(width 0.4572)
		(layer "F.Cu")
		(net "GND")
	)
	(segment
		(start 157.699964 -276.899878)
		(end 157.224984 -276.424898)
		(width 0.249936)
		(layer "F.Cu")
		(net "GND")
	)
	(segment
		(start 283.299916 -290.199826)
		(end 283.774896 -289.724846)
		(width 0.249936)
		(layer "F.Cu")
		(net "GND")
	)
	(segment
		(start 61.549788 -307.299868)
		(end 62.024768 -306.824888)
		(width 0.249936)
		(layer "F.Cu")
		(net "GND")
	)
	(segment
		(start 188.248544 -188.895736)
		(end 188.993526 -189.640718)
		(width 0.4572)
		(layer "F.Cu")
		(net "GND")
	)
	(segment
		(start 156.750004 -292.099746)
		(end 156.275024 -292.574726)
		(width 0.249936)
		(layer "F.Cu")
		(net "GND")
	)
	(segment
		(start 167.732964 -140.765022)
		(end 166.742364 -140.765022)
		(width 0.3556)
		(layer "F.Cu")
		(net "GND")
	)
	(segment
		(start 180.50002 -305.399948)
		(end 180.975 -305.874928)
		(width 0.249936)
		(layer "F.Cu")
		(net "GND")
	)
	(segment
		(start 401.774914 -284.024832)
		(end 401.299934 -284.499812)
		(width 0.249936)
		(layer "F.Cu")
		(net "GND")
	)
	(segment
		(start 163.191952 -104.404922)
		(end 163.031932 -104.244902)
		(width 0.3556)
		(layer "F.Cu")
		(net "GND")
	)
	(segment
		(start 131.36499 -25.990042)
		(end 132.38099 -25.990042)
		(width 0.3556)
		(layer "F.Cu")
		(net "GND")
	)
	(segment
		(start 194.274948 -291.624766)
		(end 194.749928 -292.099746)
		(width 0.249936)
		(layer "F.Cu")
		(net "GND")
	)
	(segment
		(start 74.919586 -3.659632)
		(end 74.919586 -2.818638)
		(width 0.4572)
		(layer "F.Cu")
		(net "GND")
	)
	(segment
		(start 158.174944 -299.2247)
		(end 157.699964 -298.74972)
		(width 0.249936)
		(layer "F.Cu")
		(net "GND")
	)
	(segment
		(start 204.764894 -31.390082)
		(end 205.636368 -31.390082)
		(width 0.3556)
		(layer "F.Cu")
		(net "GND")
	)
	(segment
		(start 288.99993 -285.449772)
		(end 288.524696 -284.974792)
		(width 0.249936)
		(layer "F.Cu")
		(net "GND")
	)
	(segment
		(start 68.280788 -34.990024)
		(end 67.264788 -34.990024)
		(width 0.3556)
		(layer "F.Cu")
		(net "GND")
	)
	(segment
		(start 169.099992 -288.299906)
		(end 169.574972 -287.824926)
		(width 0.249936)
		(layer "F.Cu")
		(net "GND")
	)
	(segment
		(start 65.349882 -285.449772)
		(end 64.874902 -285.924752)
		(width 0.249936)
		(layer "F.Cu")
		(net "GND")
	)
	(segment
		(start 419.349936 -292.099746)
		(end 418.874956 -291.624766)
		(width 0.249936)
		(layer "F.Cu")
		(net "GND")
	)
	(segment
		(start 388.274052 -238.811054)
		(end 388.080504 -238.617506)
		(width 0.2794)
		(layer "F.Cu")
		(net "GND")
	)
	(segment
		(start 299.924724 -306.824888)
		(end 300.399704 -306.349908)
		(width 0.249936)
		(layer "F.Cu")
		(net "GND")
	)
	(segment
		(start 188.75756 -403.267926)
		(end 189.474856 -403.985222)
		(width 0.381)
		(layer "F.Cu")
		(net "GND")
	)
	(segment
		(start 426.967142 -57.332626)
		(end 426.967142 -56.354218)
		(width 0.4572)
		(layer "F.Cu")
		(net "GND")
	)
	(segment
		(start 159.599884 -281.649932)
		(end 159.124904 -281.174952)
		(width 0.249936)
		(layer "F.Cu")
		(net "GND")
	)
	(segment
		(start 157.699964 -273.099784)
		(end 157.224984 -272.624804)
		(width 0.249936)
		(layer "F.Cu")
		(net "GND")
	)
	(segment
		(start 396.0749 -305.874928)
		(end 395.59992 -305.399948)
		(width 0.249936)
		(layer "F.Cu")
		(net "GND")
	)
	(segment
		(start 457.179934 -308.291992)
		(end 457.410058 -308.196742)
		(width 0.1778)
		(layer "F.Cu")
		(net "GND")
	)
	(segment
		(start 397.49984 -305.399948)
		(end 397.02486 -305.874928)
		(width 0.249936)
		(layer "F.Cu")
		(net "GND")
	)
	(segment
		(start 271.899888 -293.99992)
		(end 271.424908 -293.52494)
		(width 0.249936)
		(layer "F.Cu")
		(net "GND")
	)
	(segment
		(start 81.024984 -302.074834)
		(end 81.499964 -301.599854)
		(width 0.249936)
		(layer "F.Cu")
		(net "GND")
	)
	(segment
		(start 84.48929 -62.812168)
		(end 85.299804 -62.812168)
		(width 0.4572)
		(layer "F.Cu")
		(net "GND")
	)
	(segment
		(start 167.732964 -111.44504)
		(end 166.742364 -111.44504)
		(width 0.3556)
		(layer "F.Cu")
		(net "GND")
	)
	(segment
		(start 305.624738 -301.124874)
		(end 306.099718 -301.599854)
		(width 0.249936)
		(layer "F.Cu")
		(net "GND")
	)
	(segment
		(start 204.764132 -291.102034)
		(end 204.923898 -291.2618)
		(width 0.4572)
		(layer "F.Cu")
		(net "GND")
	)
	(segment
		(start 388.474966 -296.37482)
		(end 387.999986 -295.89984)
		(width 0.249936)
		(layer "F.Cu")
		(net "GND")
	)
	(segment
		(start 184.29986 -286.399732)
		(end 184.77484 -285.924752)
		(width 0.249936)
		(layer "F.Cu")
		(net "GND")
	)
	(segment
		(start 196.174868 -300.174914)
		(end 196.649848 -300.649894)
		(width 0.249936)
		(layer "F.Cu")
		(net "GND")
	)
	(segment
		(start 273.324828 -300.174914)
		(end 272.849848 -299.699934)
		(width 0.249936)
		(layer "F.Cu")
		(net "GND")
	)
	(segment
		(start 300.874684 -284.974792)
		(end 300.399704 -284.499812)
		(width 0.249936)
		(layer "F.Cu")
		(net "GND")
	)
	(segment
		(start 397.632428 -120.084088)
		(end 398.103344 -120.555004)
		(width 0.3556)
		(layer "F.Cu")
		(net "GND")
	)
	(segment
		(start 298.44873 -33.19018)
		(end 299.46473 -33.19018)
		(width 0.3556)
		(layer "F.Cu")
		(net "GND")
	)
	(segment
		(start 297.074844 -285.924752)
		(end 296.599864 -286.399732)
		(width 0.249936)
		(layer "F.Cu")
		(net "GND")
	)
	(segment
		(start 155.290774 -142.892018)
		(end 155.857448 -142.892018)
		(width 0.4572)
		(layer "F.Cu")
		(net "GND")
	)
	(segment
		(start 135.598662 -65.92189)
		(end 135.598662 -65.15989)
		(width 0.4572)
		(layer "F.Cu")
		(net "GND")
	)
	(segment
		(start 189.018672 -46.693836)
		(end 188.819282 -46.893226)
		(width 0.254)
		(layer "F.Cu")
		(net "GND")
	)
	(segment
		(start 46.34992 -293.04996)
		(end 45.87494 -292.57498)
		(width 0.249936)
		(layer "F.Cu")
		(net "GND")
	)
	(segment
		(start 415.967164 -147.55495)
		(end 415.96691 -147.555204)
		(width 0.4572)
		(layer "F.Cu")
		(net "GND")
	)
	(segment
		(start 430.274984 -291.624766)
		(end 430.749964 -292.099746)
		(width 0.249936)
		(layer "F.Cu")
		(net "GND")
	)
	(segment
		(start 284.724856 -284.024832)
		(end 285.199836 -284.499812)
		(width 0.249936)
		(layer "F.Cu")
		(net "GND")
	)
	(segment
		(start 275.699728 -281.649932)
		(end 275.224748 -281.174952)
		(width 0.249936)
		(layer "F.Cu")
		(net "GND")
	)
	(segment
		(start 168.768014 -56.353456)
		(end 169.423334 -56.353456)
		(width 0.254)
		(layer "F.Cu")
		(net "GND")
	)
	(segment
		(start 241.910362 -126.995428)
		(end 241.255042 -126.995428)
		(width 0.4064)
		(layer "F.Cu")
		(net "GND")
	)
	(segment
		(start 417.828476 -145.755106)
		(end 416.95751 -145.755106)
		(width 0.3556)
		(layer "F.Cu")
		(net "GND")
	)
	(segment
		(start 279.074372 -122.355102)
		(end 278.242268 -122.355102)
		(width 0.3556)
		(layer "F.Cu")
		(net "GND")
	)
	(segment
		(start 187.149994 -286.399732)
		(end 186.675014 -285.924752)
		(width 0.249936)
		(layer "F.Cu")
		(net "GND")
	)
	(segment
		(start 461.280002 -114.22634)
		(end 459.315058 -114.22634)
		(width 0.254)
		(layer "F.Cu")
		(net "GND")
	)
	(segment
		(start 136.306814 -211.93887)
		(end 136.306814 -213.016846)
		(width 0.2794)
		(layer "F.Cu")
		(net "GND")
	)
	(segment
		(start 184.77484 -288.774886)
		(end 184.29986 -289.249866)
		(width 0.249936)
		(layer "F.Cu")
		(net "GND")
	)
	(segment
		(start 299.449744 -307.299868)
		(end 298.974764 -307.774848)
		(width 0.249936)
		(layer "F.Cu")
		(net "GND")
	)
	(segment
		(start 422.548304 -131.245102)
		(end 421.557704 -131.245102)
		(width 0.3556)
		(layer "F.Cu")
		(net "GND")
	)
	(segment
		(start 21.290026 -73.166732)
		(end 21.290026 -73.85177)
		(width 0.4572)
		(layer "F.Cu")
		(net "GND")
	)
	(segment
		(start 413.649922 -284.499812)
		(end 414.124902 -284.974792)
		(width 0.249936)
		(layer "F.Cu")
		(net "GND")
	)
	(segment
		(start 71.034402 -47.936658)
		(end 71.37019 -47.60087)
		(width 0.254)
		(layer "F.Cu")
		(net "GND")
	)
	(segment
		(start 55.849774 -308.249828)
		(end 55.374794 -307.774848)
		(width 0.254)
		(layer "F.Cu")
		(net "GND")
	)
	(segment
		(start 168.150032 -306.349908)
		(end 168.625012 -305.874928)
		(width 0.249936)
		(layer "F.Cu")
		(net "GND")
	)
	(segment
		(start 242.321842 -183.083962)
		(end 242.321842 -184.235344)
		(width 0.4572)
		(layer "F.Cu")
		(net "GND")
	)
	(segment
		(start 396.54988 -307.299868)
		(end 397.02486 -306.824888)
		(width 0.249936)
		(layer "F.Cu")
		(net "GND")
	)
	(segment
		(start 77.22489 -291.624766)
		(end 77.69987 -291.149786)
		(width 0.249936)
		(layer "F.Cu")
		(net "GND")
	)
	(segment
		(start 412.328614 -207.19542)
		(end 411.601666 -207.19542)
		(width 0.4572)
		(layer "F.Cu")
		(net "GND")
	)
	(segment
		(start 231.607614 -261.137654)
		(end 231.607614 -259.827014)
		(width 0.254)
		(layer "F.Cu")
		(net "GND")
	)
	(segment
		(start 341.844122 -110.28553)
		(end 341.900002 -110.22965)
		(width 0.254)
		(layer "F.Cu")
		(net "GND")
	)
	(segment
		(start 413.174942 -300.174914)
		(end 413.649922 -299.699934)
		(width 0.249936)
		(layer "F.Cu")
		(net "GND")
	)
	(segment
		(start 76.74991 -302.549814)
		(end 77.22489 -303.024794)
		(width 0.249936)
		(layer "F.Cu")
		(net "GND")
	)
	(segment
		(start 399.400014 -303.499774)
		(end 399.874994 -303.974754)
		(width 0.249936)
		(layer "F.Cu")
		(net "GND")
	)
	(segment
		(start 11.41984 -303.088802)
		(end 11.41984 -302.417226)
		(width 0.4572)
		(layer "F.Cu")
		(net "GND")
	)
	(segment
		(start 396.54988 -300.649894)
		(end 397.02486 -300.174914)
		(width 0.249936)
		(layer "F.Cu")
		(net "GND")
	)
	(segment
		(start 429.800004 -290.199826)
		(end 430.274984 -289.724846)
		(width 0.249936)
		(layer "F.Cu")
		(net "GND")
	)
	(segment
		(start 193.799968 -302.549814)
		(end 194.749928 -302.549814)
		(width 0.249936)
		(layer "F.Cu")
		(net "GND")
	)
	(segment
		(start 17.511776 -146.263614)
		(end 17.511776 -145.837656)
		(width 0.4064)
		(layer "F.Cu")
		(net "GND")
	)
	(segment
		(start 57.274968 -284.974792)
		(end 57.749948 -284.499812)
		(width 0.249936)
		(layer "F.Cu")
		(net "GND")
	)
	(segment
		(start 284.843728 -43.85691)
		(end 285.51505 -43.85691)
		(width 0.254)
		(layer "F.Cu")
		(net "GND")
	)
	(segment
		(start 279.04567 -125.955044)
		(end 278.242268 -125.955044)
		(width 0.3556)
		(layer "F.Cu")
		(net "GND")
	)
	(segment
		(start 187.624974 -293.52494)
		(end 187.149994 -293.99992)
		(width 0.249936)
		(layer "F.Cu")
		(net "GND")
	)
	(segment
		(start 157.699964 -274.049744)
		(end 157.224984 -273.574764)
		(width 0.249936)
		(layer "F.Cu")
		(net "GND")
	)
	(segment
		(start 163.874958 -307.774848)
		(end 163.399978 -307.299868)
		(width 0.249936)
		(layer "F.Cu")
		(net "GND")
	)
	(segment
		(start 129.217166 -118.743476)
		(end 129.217166 -119.35587)
		(width 0.4572)
		(layer "F.Cu")
		(net "GND")
	)
	(segment
		(start 292.32479 -305.874928)
		(end 292.79977 -306.349908)
		(width 0.249936)
		(layer "F.Cu")
		(net "GND")
	)
	(segment
		(start 62.974982 -284.974792)
		(end 62.499748 -284.499812)
		(width 0.249936)
		(layer "F.Cu")
		(net "GND")
	)
	(segment
		(start 74.84999 -301.599854)
		(end 75.79995 -301.599854)
		(width 0.249936)
		(layer "F.Cu")
		(net "GND")
	)
	(segment
		(start 162.924998 -303.024794)
		(end 163.399978 -302.549814)
		(width 0.249936)
		(layer "F.Cu")
		(net "GND")
	)
	(segment
		(start 290.89985 -283.549852)
		(end 290.42487 -284.024832)
		(width 0.249936)
		(layer "F.Cu")
		(net "GND")
	)
	(segment
		(start 281.399742 -301.599854)
		(end 281.874722 -301.124874)
		(width 0.249936)
		(layer "F.Cu")
		(net "GND")
	)
	(segment
		(start 161.025078 -282.124912)
		(end 161.500058 -282.599892)
		(width 0.249936)
		(layer "F.Cu")
		(net "GND")
	)
	(segment
		(start 297.549824 -288.299906)
		(end 298.024804 -287.824926)
		(width 0.249936)
		(layer "F.Cu")
		(net "GND")
	)
	(segment
		(start 368.574066 -73.166732)
		(end 368.574066 -73.85177)
		(width 0.4572)
		(layer "F.Cu")
		(net "GND")
	)
	(segment
		(start 153.424636 -298.27474)
		(end 152.94991 -298.749466)
		(width 0.249936)
		(layer "F.Cu")
		(net "GND")
	)
	(segment
		(start 58.699908 -288.299906)
		(end 58.699908 -288.149792)
		(width 0.249936)
		(layer "F.Cu")
		(net "GND")
	)
	(segment
		(start 186.675014 -290.674806)
		(end 187.149994 -290.199826)
		(width 0.249936)
		(layer "F.Cu")
		(net "GND")
	)
	(segment
		(start 71.49846 -65.92189)
		(end 71.49846 -65.15989)
		(width 0.4572)
		(layer "F.Cu")
		(net "GND")
	)
	(segment
		(start 395.36116 -38.701218)
		(end 396.119604 -38.701218)
		(width 0.4572)
		(layer "F.Cu")
		(net "GND")
	)
	(segment
		(start 75.32497 -290.674806)
		(end 75.79995 -290.199826)
		(width 0.249936)
		(layer "F.Cu")
		(net "GND")
	)
	(segment
		(start 241.475514 -217.78976)
		(end 242.085114 -217.78976)
		(width 0.3048)
		(layer "F.Cu")
		(net "GND")
	)
	(segment
		(start 213.357968 -73.166732)
		(end 213.357968 -73.85177)
		(width 0.4572)
		(layer "F.Cu")
		(net "GND")
	)
	(segment
		(start 417.450016 -293.99992)
		(end 416.974782 -293.52494)
		(width 0.249936)
		(layer "F.Cu")
		(net "GND")
	)
	(segment
		(start 53.474874 -305.874928)
		(end 52.999894 -305.399948)
		(width 0.249936)
		(layer "F.Cu")
		(net "GND")
	)
	(segment
		(start 405.015192 -59.946286)
		(end 405.015192 -60.601606)
		(width 0.4572)
		(layer "F.Cu")
		(net "GND")
	)
	(segment
		(start 227.467668 -218.30411)
		(end 227.067872 -217.904314)
		(width 0.381)
		(layer "F.Cu")
		(net "GND")
	)
	(segment
		(start 168.625012 -291.624766)
		(end 168.150032 -292.099746)
		(width 0.249936)
		(layer "F.Cu")
		(net "GND")
	)
	(segment
		(start 159.124904 -273.574764)
		(end 159.599884 -274.049744)
		(width 0.249936)
		(layer "F.Cu")
		(net "GND")
	)
	(segment
		(start 404.624794 -298.27474)
		(end 405.100028 -297.79976)
		(width 0.249936)
		(layer "F.Cu")
		(net "GND")
	)
	(segment
		(start 282.17622 -106.045)
		(end 282.842462 -106.045)
		(width 0.3556)
		(layer "F.Cu")
		(net "GND")
	)
	(segment
		(start 165.424104 -27.411934)
		(end 165.424104 -26.319734)
		(width 0.4572)
		(layer "F.Cu")
		(net "GND")
	)
	(segment
		(start 406.524968 -285.924752)
		(end 406.999948 -285.449772)
		(width 0.249936)
		(layer "F.Cu")
		(net "GND")
	)
	(segment
		(start 368.78768 -25.742392)
		(end 368.78768 -26.360882)
		(width 0.4572)
		(layer "F.Cu")
		(net "GND")
	)
	(segment
		(start 36.374832 -280.224738)
		(end 36.849812 -280.699718)
		(width 0.249936)
		(layer "F.Cu")
		(net "GND")
	)
	(segment
		(start 74.84999 -293.99992)
		(end 75.32497 -294.4749)
		(width 0.249936)
		(layer "F.Cu")
		(net "GND")
	)
	(segment
		(start 358.6353 -114.649504)
		(end 358.6353 -113.910364)
		(width 0.4572)
		(layer "F.Cu")
		(net "GND")
	)
	(segment
		(start 186.200034 -291.149786)
		(end 186.675014 -291.624766)
		(width 0.249936)
		(layer "F.Cu")
		(net "GND")
	)
	(segment
		(start 410.799788 -299.699934)
		(end 411.275022 -300.174914)
		(width 0.249936)
		(layer "F.Cu")
		(net "GND")
	)
	(segment
		(start 55.849774 -292.099746)
		(end 55.374794 -291.624766)
		(width 0.249936)
		(layer "F.Cu")
		(net "GND")
	)
	(segment
		(start 297.549824 -305.399948)
		(end 298.024804 -305.874928)
		(width 0.249936)
		(layer "F.Cu")
		(net "GND")
	)
	(segment
		(start 193.324988 -293.52494)
		(end 192.850008 -293.04996)
		(width 0.249936)
		(layer "F.Cu")
		(net "GND")
	)
	(segment
		(start 305.149758 -297.79976)
		(end 305.624738 -298.27474)
		(width 0.249936)
		(layer "F.Cu")
		(net "GND")
	)
	(segment
		(start 430.989486 -64.312292)
		(end 431.74793 -64.312292)
		(width 0.4572)
		(layer "F.Cu")
		(net "GND")
	)
	(segment
		(start 46.8249 -302.074834)
		(end 47.29988 -302.549814)
		(width 0.249936)
		(layer "F.Cu")
		(net "GND")
	)
	(segment
		(start 417.618672 -121.83491)
		(end 416.95751 -121.83491)
		(width 0.3556)
		(layer "F.Cu")
		(net "GND")
	)
	(segment
		(start 392.749786 -298.74972)
		(end 392.274806 -298.27474)
		(width 0.249936)
		(layer "F.Cu")
		(net "GND")
	)
	(segment
		(start 197.125082 -290.674806)
		(end 197.600062 -290.199826)
		(width 0.249936)
		(layer "F.Cu")
		(net "GND")
	)
	(segment
		(start 31.454344 -252.756924)
		(end 31.454344 -253.45644)
		(width 0.4572)
		(layer "F.Cu")
		(net "GND")
	)
	(segment
		(start 369.447064 -52.592224)
		(end 369.522248 -52.51704)
		(width 0.254)
		(layer "F.Cu")
		(net "GND")
	)
	(segment
		(start 47.29988 -301.599854)
		(end 46.8249 -302.074834)
		(width 0.249936)
		(layer "F.Cu")
		(net "GND")
	)
	(segment
		(start 277.124922 -301.124874)
		(end 277.124668 -301.124874)
		(width 0.254)
		(layer "F.Cu")
		(net "GND")
	)
	(segment
		(start 416.499802 -289.249866)
		(end 416.974782 -288.774886)
		(width 0.249936)
		(layer "F.Cu")
		(net "GND")
	)
	(segment
		(start 179.55006 -288.299906)
		(end 179.07508 -287.824926)
		(width 0.249936)
		(layer "F.Cu")
		(net "GND")
	)
	(segment
		(start 177.174906 -302.074834)
		(end 177.649886 -301.599854)
		(width 0.249936)
		(layer "F.Cu")
		(net "GND")
	)
	(segment
		(start 174.349918 -287.699958)
		(end 174.800006 -288.149792)
		(width 0.249936)
		(layer "F.Cu")
		(net "GND")
	)
	(segment
		(start 190.348108 -134.845044)
		(end 189.357508 -134.845044)
		(width 0.3556)
		(layer "F.Cu")
		(net "GND")
	)
	(segment
		(start 37.744908 -27.79014)
		(end 36.6649 -27.79014)
		(width 0.3556)
		(layer "F.Cu")
		(net "GND")
	)
	(segment
		(start 183.766714 -116.435124)
		(end 184.757314 -116.435124)
		(width 0.3556)
		(layer "F.Cu")
		(net "GND")
	)
	(segment
		(start 273.324828 -298.27474)
		(end 272.849848 -297.79976)
		(width 0.249936)
		(layer "F.Cu")
		(net "GND")
	)
	(segment
		(start 270.949928 -276.899878)
		(end 270.474948 -276.424898)
		(width 0.249936)
		(layer "F.Cu")
		(net "GND")
	)
	(segment
		(start 272.374868 -280.224738)
		(end 272.849848 -280.699718)
		(width 0.249936)
		(layer "F.Cu")
		(net "GND")
	)
	(segment
		(start 391.799826 -278.799798)
		(end 391.324846 -279.274778)
		(width 0.249936)
		(layer "F.Cu")
		(net "GND")
	)
	(segment
		(start 154.850084 -292.099746)
		(end 154.375104 -291.624766)
		(width 0.249936)
		(layer "F.Cu")
		(net "GND")
	)
	(segment
		(start 52.667916 -51.019456)
		(end 53.323236 -51.019456)
		(width 0.254)
		(layer "F.Cu")
		(net "GND")
	)
	(segment
		(start 232.517442 -66.000122)
		(end 233.572558 -66.000122)
		(width 0.3556)
		(layer "F.Cu")
		(net "GND")
	)
	(segment
		(start 40.214804 -26.171398)
		(end 40.39616 -25.990042)
		(width 0.3556)
		(layer "F.Cu")
		(net "GND")
	)
	(segment
		(start 180.50002 -292.099746)
		(end 180.02504 -291.624766)
		(width 0.249936)
		(layer "F.Cu")
		(net "GND")
	)
	(segment
		(start 68.199762 -293.04996)
		(end 68.674742 -292.574726)
		(width 0.249936)
		(layer "F.Cu")
		(net "GND")
	)
	(segment
		(start 370.581936 -206.510128)
		(end 369.25885 -206.510128)
		(width 0.4572)
		(layer "F.Cu")
		(net "GND")
	)
	(segment
		(start 302.299878 -292.099746)
		(end 302.774858 -291.624766)
		(width 0.249936)
		(layer "F.Cu")
		(net "GND")
	)
	(segment
		(start 116.86032 -284.42412)
		(end 117.1702 -284.734)
		(width 0.2286)
		(layer "F.Cu")
		(net "GND")
	)
	(segment
		(start 161.500058 -287.349946)
		(end 161.025078 -286.874966)
		(width 0.249936)
		(layer "F.Cu")
		(net "GND")
	)
	(segment
		(start 153.89987 -282.599892)
		(end 153.42489 -282.124912)
		(width 0.249936)
		(layer "F.Cu")
		(net "GND")
	)
	(segment
		(start 64.874902 -305.874928)
		(end 64.399922 -305.399948)
		(width 0.249936)
		(layer "F.Cu")
		(net "GND")
	)
	(segment
		(start 89.589356 -294.727884)
		(end 89.544144 -294.682672)
		(width 0.4572)
		(layer "F.Cu")
		(net "GND")
	)
	(segment
		(start 98.487484 -25.742392)
		(end 98.487484 -26.360882)
		(width 0.4572)
		(layer "F.Cu")
		(net "GND")
	)
	(segment
		(start 276.174708 -297.32478)
		(end 276.649688 -297.79976)
		(width 0.249936)
		(layer "F.Cu")
		(net "GND")
	)
	(segment
		(start 183.82488 -289.724846)
		(end 183.3499 -290.199826)
		(width 0.249936)
		(layer "F.Cu")
		(net "GND")
	)
	(segment
		(start 163.874958 -306.824888)
		(end 164.349938 -307.299868)
		(width 0.249936)
		(layer "F.Cu")
		(net "GND")
	)
	(segment
		(start 410.964888 -25.990042)
		(end 409.948888 -25.990042)
		(width 0.3556)
		(layer "F.Cu")
		(net "GND")
	)
	(segment
		(start 296.599864 -297.79976)
		(end 296.124884 -297.32478)
		(width 0.249936)
		(layer "F.Cu")
		(net "GND")
	)
	(segment
		(start 415.96691 -145.755106)
		(end 416.95751 -145.755106)
		(width 0.3556)
		(layer "F.Cu")
		(net "GND")
	)
	(segment
		(start 142.767304 -56.354218)
		(end 142.768066 -56.353456)
		(width 0.4572)
		(layer "F.Cu")
		(net "GND")
	)
	(segment
		(start 242.809014 -308.168548)
		(end 243.039138 -308.073298)
		(width 0.1778)
		(layer "F.Cu")
		(net "GND")
	)
	(segment
		(start 279.232106 -390.210294)
		(end 279.3746 -390.0678)
		(width 0.4318)
		(layer "F.Cu")
		(net "GND")
	)
	(segment
		(start 282.889198 -175.855376)
		(end 282.763976 -175.730154)
		(width 0.381)
		(layer "F.Cu")
		(net "GND")
	)
	(segment
		(start 160.549844 -294.94988)
		(end 160.074864 -294.4749)
		(width 0.249936)
		(layer "F.Cu")
		(net "GND")
	)
	(segment
		(start 393.351766 -98.845116)
		(end 394.342366 -98.845116)
		(width 0.3556)
		(layer "F.Cu")
		(net "GND")
	)
	(segment
		(start 385.149852 -275.949918)
		(end 384.674872 -275.474938)
		(width 0.249936)
		(layer "F.Cu")
		(net "GND")
	)
	(segment
		(start 278.074882 -298.27474)
		(end 278.549862 -298.74972)
		(width 0.249936)
		(layer "F.Cu")
		(net "GND")
	)
	(segment
		(start 219.79128 -87.063072)
		(end 219.68968 -87.164672)
		(width 0.4572)
		(layer "F.Cu")
		(net "GND")
	)
	(segment
		(start 385.355592 -231.92867)
		(end 385.355592 -232.836212)
		(width 0.2794)
		(layer "F.Cu")
		(net "GND")
	)
	(segment
		(start 411.370526 -202.19289)
		(end 411.370526 -202.181714)
		(width 0.4572)
		(layer "F.Cu")
		(net "GND")
	)
	(segment
		(start 366.50422 -282.021534)
		(end 366.11941 -282.406344)
		(width 0.254)
		(layer "F.Cu")
		(net "GND")
	)
	(segment
		(start 416.974782 -293.52494)
		(end 417.450016 -293.04996)
		(width 0.249936)
		(layer "F.Cu")
		(net "GND")
	)
	(segment
		(start 165.396164 -129.68351)
		(end 165.677596 -129.964942)
		(width 0.3556)
		(layer "F.Cu")
		(net "GND")
	)
	(segment
		(start 441.36564 -303.636426)
		(end 441.36564 -303.026826)
		(width 0.4572)
		(layer "F.Cu")
		(net "GND")
	)
	(segment
		(start 280.449782 -307.299868)
		(end 280.924762 -306.824888)
		(width 0.249936)
		(layer "F.Cu")
		(net "GND")
	)
	(segment
		(start 189.999874 -295.89984)
		(end 189.524894 -296.37482)
		(width 0.249936)
		(layer "F.Cu")
		(net "GND")
	)
	(segment
		(start 80.475074 -64.102234)
		(end 79.769462 -64.102234)
		(width 0.4572)
		(layer "F.Cu")
		(net "GND")
	)
	(segment
		(start 48.24984 -304.449734)
		(end 47.77486 -303.974754)
		(width 0.249936)
		(layer "F.Cu")
		(net "GND")
	)
	(segment
		(start 290.42487 -300.174914)
		(end 290.89985 -299.699934)
		(width 0.249936)
		(layer "F.Cu")
		(net "GND")
	)
	(segment
		(start 408.424888 -294.4749)
		(end 408.899868 -293.99992)
		(width 0.249936)
		(layer "F.Cu")
		(net "GND")
	)
	(segment
		(start 49.67478 -287.824926)
		(end 50.14976 -287.349946)
		(width 0.249936)
		(layer "F.Cu")
		(net "GND")
	)
	(segment
		(start 314.072016 -33.248092)
		(end 314.072016 -33.857692)
		(width 0.4572)
		(layer "F.Cu")
		(net "GND")
	)
	(segment
		(start 158.174944 -298.27474)
		(end 157.699964 -297.79976)
		(width 0.249936)
		(layer "F.Cu")
		(net "GND")
	)
	(segment
		(start 82.449924 -297.79976)
		(end 82.924904 -297.32478)
		(width 0.249936)
		(layer "F.Cu")
		(net "GND")
	)
	(segment
		(start 183.412638 -102.439978)
		(end 184.757314 -102.439978)
		(width 0.3556)
		(layer "F.Cu")
		(net "GND")
	)
	(segment
		(start 68.199762 -286.399732)
		(end 67.724782 -285.924752)
		(width 0.249936)
		(layer "F.Cu")
		(net "GND")
	)
	(segment
		(start 300.874684 -284.024832)
		(end 300.399704 -284.499812)
		(width 0.249936)
		(layer "F.Cu")
		(net "GND")
	)
	(segment
		(start 165.299898 -306.349908)
		(end 165.774878 -305.874928)
		(width 0.249936)
		(layer "F.Cu")
		(net "GND")
	)
	(segment
		(start 394.64996 -304.449734)
		(end 395.12494 -304.924714)
		(width 0.249936)
		(layer "F.Cu")
		(net "GND")
	)
	(segment
		(start 182.39994 -293.99992)
		(end 182.87492 -293.52494)
		(width 0.249936)
		(layer "F.Cu")
		(net "GND")
	)
	(segment
		(start 362.915708 -357.556308)
		(end 362.92536 -357.56596)
		(width 0.4572)
		(layer "F.Cu")
		(net "GND")
	)
	(segment
		(start 166.249858 -302.549814)
		(end 165.774878 -303.024794)
		(width 0.249936)
		(layer "F.Cu")
		(net "GND")
	)
	(segment
		(start 164.349938 -305.399948)
		(end 163.874958 -304.924714)
		(width 0.249936)
		(layer "F.Cu")
		(net "GND")
	)
	(segment
		(start 186.675014 -302.074834)
		(end 186.200034 -301.599854)
		(width 0.249936)
		(layer "F.Cu")
		(net "GND")
	)
	(segment
		(start 403.199854 -293.99992)
		(end 403.674834 -294.4749)
		(width 0.249936)
		(layer "F.Cu")
		(net "GND")
	)
	(segment
		(start 70.099936 -284.499812)
		(end 70.574916 -284.024832)
		(width 0.249936)
		(layer "F.Cu")
		(net "GND")
	)
	(segment
		(start 78.667864 -51.019456)
		(end 79.323184 -51.019456)
		(width 0.254)
		(layer "F.Cu")
		(net "GND")
	)
	(segment
		(start 121.842022 -119.071136)
		(end 122.477022 -119.071136)
		(width 0.4572)
		(layer "F.Cu")
		(net "GND")
	)
	(segment
		(start 163.546028 -46.693836)
		(end 163.018724 -46.693836)
		(width 0.254)
		(layer "F.Cu")
		(net "GND")
	)
	(segment
		(start 293.27475 -306.824888)
		(end 293.74973 -307.299868)
		(width 0.249936)
		(layer "F.Cu")
		(net "GND")
	)
	(segment
		(start 158.649924 -287.349946)
		(end 158.174944 -286.874966)
		(width 0.249936)
		(layer "F.Cu")
		(net "GND")
	)
	(segment
		(start 56.799988 -301.599854)
		(end 56.324754 -302.074834)
		(width 0.249936)
		(layer "F.Cu")
		(net "GND")
	)
	(segment
		(start 274.274788 -299.2247)
		(end 273.799808 -298.74972)
		(width 0.249936)
		(layer "F.Cu")
		(net "GND")
	)
	(segment
		(start 283.832808 -107.845098)
		(end 283.833062 -107.844844)
		(width 0.4572)
		(layer "F.Cu")
		(net "GND")
	)
	(segment
		(start 80.54975 -293.04996)
		(end 81.024984 -292.574726)
		(width 0.249936)
		(layer "F.Cu")
		(net "GND")
	)
	(segment
		(start 144.165828 -113.158524)
		(end 140.43787 -109.430566)
		(width 0.4572)
		(layer "F.Cu")
		(net "GND")
	)
	(segment
		(start 57.749948 -284.499812)
		(end 57.274968 -284.024832)
		(width 0.249936)
		(layer "F.Cu")
		(net "GND")
	)
	(segment
		(start 338.892642 -9.139682)
		(end 338.892642 -8.48995)
		(width 0.4572)
		(layer "F.Cu")
		(net "GND")
	)
	(segment
		(start 427.42485 -292.574726)
		(end 426.94987 -293.04996)
		(width 0.249936)
		(layer "F.Cu")
		(net "GND")
	)
	(segment
		(start 391.324846 -300.174914)
		(end 391.799826 -299.699934)
		(width 0.249936)
		(layer "F.Cu")
		(net "GND")
	)
	(segment
		(start 184.29986 -306.349908)
		(end 183.82488 -306.824888)
		(width 0.249936)
		(layer "F.Cu")
		(net "GND")
	)
	(segment
		(start 56.324754 -305.874928)
		(end 55.849774 -306.349908)
		(width 0.249936)
		(layer "F.Cu")
		(net "GND")
	)
	(segment
		(start 393.320778 -151.159972)
		(end 394.342366 -151.159972)
		(width 0.3556)
		(layer "F.Cu")
		(net "GND")
	)
	(segment
		(start 92.248736 -33.19018)
		(end 93.264736 -33.19018)
		(width 0.3556)
		(layer "F.Cu")
		(net "GND")
	)
	(segment
		(start 63.449962 -303.499774)
		(end 63.924942 -303.974754)
		(width 0.249936)
		(layer "F.Cu")
		(net "GND")
	)
	(segment
		(start 310.374792 -297.32478)
		(end 309.899812 -296.8498)
		(width 0.249936)
		(layer "F.Cu")
		(net "GND")
	)
	(segment
		(start 228.39299 -92.041726)
		(end 227.734368 -92.041726)
		(width 0.254)
		(layer "F.Cu")
		(net "GND")
	)
	(segment
		(start 248.8057 -85.209888)
		(end 248.1961 -85.209888)
		(width 0.4572)
		(layer "F.Cu")
		(net "GND")
	)
	(segment
		(start 125.810264 -126.995428)
		(end 125.154944 -126.995428)
		(width 0.4064)
		(layer "F.Cu")
		(net "GND")
	)
	(segment
		(start 386.574792 -298.27474)
		(end 387.050026 -298.74972)
		(width 0.249936)
		(layer "F.Cu")
		(net "GND")
	)
	(segment
		(start 409.948888 -31.390082)
		(end 410.964888 -31.390082)
		(width 0.3556)
		(layer "F.Cu")
		(net "GND")
	)
	(segment
		(start 376.53595 -184.785)
		(end 375.910348 -184.785)
		(width 0.4572)
		(layer "F.Cu")
		(net "GND")
	)
	(segment
		(start 150.616412 -384.762248)
		(end 150.85949 -384.762248)
		(width 0.4572)
		(layer "F.Cu")
		(net "GND")
	)
	(segment
		(start 159.599884 -273.099784)
		(end 159.124904 -273.574764)
		(width 0.249936)
		(layer "F.Cu")
		(net "GND")
	)
	(segment
		(start 290.42487 -289.724846)
		(end 290.89985 -290.199826)
		(width 0.249936)
		(layer "F.Cu")
		(net "GND")
	)
	(segment
		(start 309.234332 -86.949026)
		(end 310.13019 -86.949026)
		(width 0.381)
		(layer "F.Cu")
		(net "GND")
	)
	(segment
		(start 219.60205 -204.216)
		(end 219.60205 -204.851)
		(width 0.4572)
		(layer "F.Cu")
		(net "GND")
	)
	(segment
		(start 49.332388 -120.084088)
		(end 49.803304 -120.555004)
		(width 0.3556)
		(layer "F.Cu")
		(net "GND")
	)
	(segment
		(start 263.894062 -35.264852)
		(end 263.894062 -35.499548)
		(width 0.4572)
		(layer "F.Cu")
		(net "GND")
	)
	(segment
		(start 49.1998 -299.699934)
		(end 49.67478 -299.224954)
		(width 0.249936)
		(layer "F.Cu")
		(net "GND")
	)
	(segment
		(start 73.424796 -299.224954)
		(end 73.899776 -298.74972)
		(width 0.249936)
		(layer "F.Cu")
		(net "GND")
	)
	(segment
		(start 74.248264 -151.155146)
		(end 73.257664 -151.155146)
		(width 0.3556)
		(layer "F.Cu")
		(net "GND")
	)
	(segment
		(start 118.441978 -26.606246)
		(end 118.441978 -25.971246)
		(width 0.4572)
		(layer "F.Cu")
		(net "GND")
	)
	(segment
		(start 392.274806 -296.37482)
		(end 392.749786 -296.8498)
		(width 0.249936)
		(layer "F.Cu")
		(net "GND")
	)
	(segment
		(start 419.349936 -291.149786)
		(end 419.824916 -291.624766)
		(width 0.249936)
		(layer "F.Cu")
		(net "GND")
	)
	(segment
		(start 42.074846 -300.174914)
		(end 42.549826 -299.699934)
		(width 0.249936)
		(layer "F.Cu")
		(net "GND")
	)
	(segment
		(start 415.074862 -284.974792)
		(end 415.549842 -284.499812)
		(width 0.249936)
		(layer "F.Cu")
		(net "GND")
	)
	(segment
		(start 163.399978 -284.499812)
		(end 162.924998 -284.024832)
		(width 0.249936)
		(layer "F.Cu")
		(net "GND")
	)
	(segment
		(start 409.849828 -288.299906)
		(end 410.324808 -287.824926)
		(width 0.249936)
		(layer "F.Cu")
		(net "GND")
	)
	(segment
		(start 398.4498 -286.399732)
		(end 397.97482 -286.874966)
		(width 0.249936)
		(layer "F.Cu")
		(net "GND")
	)
	(segment
		(start 46.34992 -289.249866)
		(end 45.87494 -288.774886)
		(width 0.249936)
		(layer "F.Cu")
		(net "GND")
	)
	(segment
		(start 415.564828 -34.990024)
		(end 413.682942 -34.990024)
		(width 0.3556)
		(layer "F.Cu")
		(net "GND")
	)
	(segment
		(start 270.949928 -292.099746)
		(end 270.474948 -291.624766)
		(width 0.249936)
		(layer "F.Cu")
		(net "GND")
	)
	(segment
		(start 219.425266 -124.790962)
		(end 218.812872 -124.790962)
		(width 0.4572)
		(layer "F.Cu")
		(net "GND")
	)
	(segment
		(start 189.524894 -290.674806)
		(end 189.999874 -290.199826)
		(width 0.249936)
		(layer "F.Cu")
		(net "GND")
	)
	(segment
		(start 412.699962 -286.399732)
		(end 413.174942 -285.924752)
		(width 0.249936)
		(layer "F.Cu")
		(net "GND")
	)
	(segment
		(start 194.274948 -289.724846)
		(end 194.749928 -289.249866)
		(width 0.249936)
		(layer "F.Cu")
		(net "GND")
	)
	(segment
		(start 51.63312 -124.154946)
		(end 50.64252 -124.154946)
		(width 0.3556)
		(layer "F.Cu")
		(net "GND")
	)
	(segment
		(start 55.374794 -306.824888)
		(end 54.899814 -306.349908)
		(width 0.249936)
		(layer "F.Cu")
		(net "GND")
	)
	(segment
		(start 403.674834 -284.974792)
		(end 404.149814 -284.499812)
		(width 0.249936)
		(layer "F.Cu")
		(net "GND")
	)
	(segment
		(start 276.649688 -286.399732)
		(end 276.174708 -286.874712)
		(width 0.249936)
		(layer "F.Cu")
		(net "GND")
	)
	(segment
		(start 361.027472 -392.007852)
		(end 361.75823 -392.007852)
		(width 0.4572)
		(layer "F.Cu")
		(net "GND")
	)
	(segment
		(start 299.866812 -121.83491)
		(end 300.857412 -121.83491)
		(width 0.3556)
		(layer "F.Cu")
		(net "GND")
	)
	(segment
		(start 45.39996 -287.349946)
		(end 44.92498 -286.874966)
		(width 0.249936)
		(layer "F.Cu")
		(net "GND")
	)
	(segment
		(start 177.649886 -301.599854)
		(end 178.124866 -302.074834)
		(width 0.249936)
		(layer "F.Cu")
		(net "GND")
	)
	(segment
		(start 154.850084 -285.449772)
		(end 154.375104 -284.974792)
		(width 0.249936)
		(layer "F.Cu")
		(net "GND")
	)
	(segment
		(start 69.637402 -125.752352)
		(end 69.320156 -125.435106)
		(width 0.3556)
		(layer "F.Cu")
		(net "GND")
	)
	(segment
		(start 412.699962 -299.699934)
		(end 413.174942 -300.174914)
		(width 0.249936)
		(layer "F.Cu")
		(net "GND")
	)
	(segment
		(start 373.764556 -29.67736)
		(end 373.764556 -29.079952)
		(width 0.4572)
		(layer "F.Cu")
		(net "GND")
	)
	(segment
		(start 249.333512 -212.638386)
		(end 248.717562 -212.638386)
		(width 0.381)
		(layer "F.Cu")
		(net "GND")
	)
	(segment
		(start 288.049716 -296.8498)
		(end 287.574736 -297.32478)
		(width 0.249936)
		(layer "F.Cu")
		(net "GND")
	)
	(segment
		(start 212.522054 -192.572894)
		(end 213.741 -192.572894)
		(width 0.3556)
		(layer "F.Cu")
		(net "GND")
	)
	(segment
		(start 167.457628 -29.784294)
		(end 167.564562 -29.67736)
		(width 0.4572)
		(layer "F.Cu")
		(net "GND")
	)
	(segment
		(start 144.382744 -28.875736)
		(end 144.382744 -28.47848)
		(width 0.254)
		(layer "F.Cu")
		(net "GND")
	)
	(segment
		(start 84.534502 -38.937184)
		(end 84.799932 -38.671754)
		(width 0.4572)
		(layer "F.Cu")
		(net "GND")
	)
	(segment
		(start 277.974806 -48.753014)
		(end 277.268178 -48.753014)
		(width 0.254)
		(layer "F.Cu")
		(net "GND")
	)
	(segment
		(start 103.46436 -29.571696)
		(end 103.757222 -29.864558)
		(width 0.4572)
		(layer "F.Cu")
		(net "GND")
	)
	(segment
		(start 77.22489 -299.224954)
		(end 76.74991 -298.74972)
		(width 0.249936)
		(layer "F.Cu")
		(net "GND")
	)
	(segment
		(start 374.968008 -54.067456)
		(end 375.623328 -54.067456)
		(width 0.254)
		(layer "F.Cu")
		(net "GND")
	)
	(segment
		(start 310.374792 -303.024794)
		(end 309.899812 -302.549814)
		(width 0.249936)
		(layer "F.Cu")
		(net "GND")
	)
	(segment
		(start 281.399742 -305.399948)
		(end 281.874722 -305.874928)
		(width 0.249936)
		(layer "F.Cu")
		(net "GND")
	)
	(segment
		(start 398.989296 -175.855376)
		(end 398.864074 -175.730154)
		(width 0.381)
		(layer "F.Cu")
		(net "GND")
	)
	(segment
		(start 292.32479 -302.074834)
		(end 292.79977 -301.599854)
		(width 0.249936)
		(layer "F.Cu")
		(net "GND")
	)
	(segment
		(start 165.89502 -124.154946)
		(end 166.742364 -124.154946)
		(width 0.3556)
		(layer "F.Cu")
		(net "GND")
	)
	(segment
		(start 56.324754 -284.974792)
		(end 56.799988 -284.499812)
		(width 0.249936)
		(layer "F.Cu")
		(net "GND")
	)
	(segment
		(start 246.870728 -111.739426)
		(end 246.870728 -111.127032)
		(width 0.4572)
		(layer "F.Cu")
		(net "GND")
	)
	(segment
		(start 415.549842 -284.499812)
		(end 416.024822 -284.974792)
		(width 0.249936)
		(layer "F.Cu")
		(net "GND")
	)
	(segment
		(start 310.849772 -290.199826)
		(end 311.324752 -290.674806)
		(width 0.249936)
		(layer "F.Cu")
		(net "GND")
	)
	(segment
		(start 179.07508 -300.174914)
		(end 178.599846 -299.699934)
		(width 0.249936)
		(layer "F.Cu")
		(net "GND")
	)
	(segment
		(start 215.475566 -121.255028)
		(end 216.087452 -121.255028)
		(width 0.4064)
		(layer "F.Cu")
		(net "GND")
	)
	(segment
		(start 162.450018 -302.549814)
		(end 162.924998 -303.024794)
		(width 0.249936)
		(layer "F.Cu")
		(net "GND")
	)
	(segment
		(start 66.299842 -299.699934)
		(end 66.774822 -300.174914)
		(width 0.249936)
		(layer "F.Cu")
		(net "GND")
	)
	(segment
		(start 397.847566 -121.692416)
		(end 397.847566 -122.044206)
		(width 0.3556)
		(layer "F.Cu")
		(net "GND")
	)
	(segment
		(start 179.07508 -285.924752)
		(end 178.599846 -286.399732)
		(width 0.249936)
		(layer "F.Cu")
		(net "GND")
	)
	(segment
		(start 277.124922 -301.124874)
		(end 277.599902 -300.649894)
		(width 0.249936)
		(layer "F.Cu")
		(net "GND")
	)
	(segment
		(start 421.724836 -298.27474)
		(end 421.249856 -297.79976)
		(width 0.249936)
		(layer "F.Cu")
		(net "GND")
	)
	(segment
		(start 417.924996 -284.974792)
		(end 418.399976 -284.499812)
		(width 0.249936)
		(layer "F.Cu")
		(net "GND")
	)
	(segment
		(start 390.849866 -290.199826)
		(end 390.374886 -289.724846)
		(width 0.249936)
		(layer "F.Cu")
		(net "GND")
	)
	(segment
		(start 430.673764 -26.606246)
		(end 430.673764 -25.971246)
		(width 0.4572)
		(layer "F.Cu")
		(net "GND")
	)
	(segment
		(start 88.664796 -25.990042)
		(end 87.648796 -25.990042)
		(width 0.3556)
		(layer "F.Cu")
		(net "GND")
	)
	(segment
		(start 364.945168 -395.062964)
		(end 364.123732 -395.062964)
		(width 0.4572)
		(layer "F.Cu")
		(net "GND")
	)
	(segment
		(start 93.264736 -25.990042)
		(end 94.280736 -25.990042)
		(width 0.3556)
		(layer "F.Cu")
		(net "GND")
	)
	(segment
		(start 277.096474 -152.96007)
		(end 278.242268 -152.96007)
		(width 0.3556)
		(layer "F.Cu")
		(net "GND")
	)
	(segment
		(start 187.149994 -291.149786)
		(end 186.675014 -291.624766)
		(width 0.249936)
		(layer "F.Cu")
		(net "GND")
	)
	(segment
		(start 81.143348 -241.1476)
		(end 69.342 -241.1476)
		(width 0.4572)
		(layer "F.Cu")
		(net "GND")
	)
	(segment
		(start 164.824918 -305.874928)
		(end 164.349938 -305.399948)
		(width 0.249936)
		(layer "F.Cu")
		(net "GND")
	)
	(segment
		(start 293.74973 -299.699934)
		(end 294.22471 -300.174914)
		(width 0.249936)
		(layer "F.Cu")
		(net "GND")
	)
	(segment
		(start 271.899888 -297.79976)
		(end 271.424908 -298.27474)
		(width 0.249936)
		(layer "F.Cu")
		(net "GND")
	)
	(segment
		(start 282.349702 -306.349908)
		(end 282.824936 -306.824888)
		(width 0.249936)
		(layer "F.Cu")
		(net "GND")
	)
	(segment
		(start 273.464782 -25.990042)
		(end 272.596102 -25.990042)
		(width 0.3556)
		(layer "F.Cu")
		(net "GND")
	)
	(segment
		(start 198.815198 -59.946286)
		(end 198.815198 -60.601606)
		(width 0.4572)
		(layer "F.Cu")
		(net "GND")
	)
	(segment
		(start 286.149796 -284.499812)
		(end 286.624776 -284.024832)
		(width 0.249936)
		(layer "F.Cu")
		(net "GND")
	)
	(segment
		(start 188.676534 -154.755088)
		(end 189.357508 -154.755088)
		(width 0.3556)
		(layer "F.Cu")
		(net "GND")
	)
	(segment
		(start 170.524932 -285.924752)
		(end 170.999912 -285.449772)
		(width 0.249936)
		(layer "F.Cu")
		(net "GND")
	)
	(segment
		(start 270.949928 -296.8498)
		(end 271.424908 -297.32478)
		(width 0.249936)
		(layer "F.Cu")
		(net "GND")
	)
	(segment
		(start 288.049716 -286.399732)
		(end 287.574736 -285.924752)
		(width 0.249936)
		(layer "F.Cu")
		(net "GND")
	)
	(segment
		(start 173.375066 -303.974754)
		(end 173.850046 -303.499774)
		(width 0.249936)
		(layer "F.Cu")
		(net "GND")
	)
	(segment
		(start 52.049934 -284.499812)
		(end 51.574954 -284.024832)
		(width 0.249936)
		(layer "F.Cu")
		(net "GND")
	)
	(segment
		(start 14.248892 -33.19018)
		(end 15.264892 -33.19018)
		(width 0.3556)
		(layer "F.Cu")
		(net "GND")
	)
	(segment
		(start 284.724856 -284.974792)
		(end 284.249876 -285.449772)
		(width 0.249936)
		(layer "F.Cu")
		(net "GND")
	)
	(segment
		(start 280.449782 -290.199826)
		(end 279.974802 -289.724846)
		(width 0.249936)
		(layer "F.Cu")
		(net "GND")
	)
	(segment
		(start 211.485988 -223.317816)
		(end 211.485988 -223.675448)
		(width 0.4572)
		(layer "F.Cu")
		(net "GND")
	)
	(segment
		(start 80.54975 -298.74972)
		(end 81.024984 -298.27474)
		(width 0.249936)
		(layer "F.Cu")
		(net "GND")
	)
	(segment
		(start 308.474872 -303.024794)
		(end 308.949852 -302.549814)
		(width 0.249936)
		(layer "F.Cu")
		(net "GND")
	)
	(segment
		(start 288.99993 -290.199826)
		(end 288.524696 -289.724846)
		(width 0.249936)
		(layer "F.Cu")
		(net "GND")
	)
	(segment
		(start 9.648952 -31.390082)
		(end 10.664952 -31.390082)
		(width 0.3556)
		(layer "F.Cu")
		(net "GND")
	)
	(segment
		(start 55.374794 -287.824926)
		(end 55.849774 -288.299906)
		(width 0.249936)
		(layer "F.Cu")
		(net "GND")
	)
	(segment
		(start 430.274984 -289.724846)
		(end 430.749964 -290.199826)
		(width 0.249936)
		(layer "F.Cu")
		(net "GND")
	)
	(segment
		(start 88.664796 -29.589984)
		(end 87.648796 -29.589984)
		(width 0.3556)
		(layer "F.Cu")
		(net "GND")
	)
	(segment
		(start 403.674834 -285.924752)
		(end 403.199854 -285.449772)
		(width 0.249936)
		(layer "F.Cu")
		(net "GND")
	)
	(segment
		(start 294.22471 -306.824888)
		(end 294.69969 -306.349908)
		(width 0.249936)
		(layer "F.Cu")
		(net "GND")
	)
	(segment
		(start 51.099974 -286.399732)
		(end 50.624994 -285.924752)
		(width 0.249936)
		(layer "F.Cu")
		(net "GND")
	)
	(segment
		(start 298.024804 -285.924752)
		(end 297.549824 -286.399732)
		(width 0.249936)
		(layer "F.Cu")
		(net "GND")
	)
	(segment
		(start 169.099992 -307.299868)
		(end 168.625012 -306.824888)
		(width 0.249936)
		(layer "F.Cu")
		(net "GND")
	)
	(segment
		(start 52.049934 -284.499812)
		(end 52.524914 -284.974792)
		(width 0.249936)
		(layer "F.Cu")
		(net "GND")
	)
	(segment
		(start 397.5227 -129.964942)
		(end 398.94256 -129.964942)
		(width 0.3556)
		(layer "F.Cu")
		(net "GND")
	)
	(segment
		(start 418.399976 -299.699934)
		(end 418.874956 -299.224954)
		(width 0.249936)
		(layer "F.Cu")
		(net "GND")
	)
	(segment
		(start 398.761204 -169.23385)
		(end 398.761204 -169.89679)
		(width 0.4572)
		(layer "F.Cu")
		(net "GND")
	)
	(segment
		(start 49.29632 -129.68351)
		(end 49.577752 -129.964942)
		(width 0.3556)
		(layer "F.Cu")
		(net "GND")
	)
	(segment
		(start 181.92496 -285.924752)
		(end 182.39994 -286.399732)
		(width 0.249936)
		(layer "F.Cu")
		(net "GND")
	)
	(segment
		(start 140.217906 -213.8426)
		(end 139.637262 -213.8426)
		(width 0.4572)
		(layer "F.Cu")
		(net "GND")
	)
	(segment
		(start 69.744844 -143.655796)
		(end 69.445632 -143.955008)
		(width 0.3556)
		(layer "F.Cu")
		(net "GND")
	)
	(segment
		(start 406.999948 -292.099746)
		(end 406.524968 -291.624766)
		(width 0.249936)
		(layer "F.Cu")
		(net "GND")
	)
	(segment
		(start 188.099954 -302.549814)
		(end 187.624974 -303.024794)
		(width 0.249936)
		(layer "F.Cu")
		(net "GND")
	)
	(segment
		(start 173.850046 -292.099746)
		(end 174.325026 -291.624766)
		(width 0.249936)
		(layer "F.Cu")
		(net "GND")
	)
	(segment
		(start 43.974766 -297.32478)
		(end 44.449746 -297.79976)
		(width 0.249936)
		(layer "F.Cu")
		(net "GND")
	)
	(segment
		(start 289.94989 -285.449772)
		(end 289.47491 -284.974792)
		(width 0.249936)
		(layer "F.Cu")
		(net "GND")
	)
	(segment
		(start 285.93669 -16.363188)
		(end 285.93669 -15.474188)
		(width 0.4572)
		(layer "F.Cu")
		(net "GND")
	)
	(segment
		(start 394.64996 -283.549852)
		(end 394.17498 -283.074872)
		(width 0.249936)
		(layer "F.Cu")
		(net "GND")
	)
	(segment
		(start 122.219212 -59.974734)
		(end 121.568718 -59.974734)
		(width 0.4572)
		(layer "F.Cu")
		(net "GND")
	)
	(segment
		(start 289.94989 -288.299906)
		(end 289.94989 -288.19983)
		(width 0.249936)
		(layer "F.Cu")
		(net "GND")
	)
	(segment
		(start 307.999892 -292.099746)
		(end 308.474872 -292.574726)
		(width 0.249936)
		(layer "F.Cu")
		(net "GND")
	)
	(segment
		(start 51.63312 -125.955044)
		(end 50.64252 -125.955044)
		(width 0.3556)
		(layer "F.Cu")
		(net "GND")
	)
	(segment
		(start 172.900086 -297.79976)
		(end 172.424852 -298.27474)
		(width 0.249936)
		(layer "F.Cu")
		(net "GND")
	)
	(segment
		(start 69.624956 -293.52494)
		(end 69.149976 -293.04996)
		(width 0.249936)
		(layer "F.Cu")
		(net "GND")
	)
	(segment
		(start 233.516424 -58.674)
		(end 233.579924 -58.674)
		(width 0.3556)
		(layer "F.Cu")
		(net "GND")
	)
	(segment
		(start 189.049914 -296.8498)
		(end 189.524894 -297.32478)
		(width 0.249936)
		(layer "F.Cu")
		(net "GND")
	)
	(segment
		(start 182.39994 -303.499774)
		(end 182.87492 -303.974754)
		(width 0.249936)
		(layer "F.Cu")
		(net "GND")
	)
	(segment
		(start 403.199854 -288.299906)
		(end 403.674834 -287.824926)
		(width 0.249936)
		(layer "F.Cu")
		(net "GND")
	)
	(segment
		(start 305.624738 -292.574726)
		(end 306.099718 -292.099746)
		(width 0.249936)
		(layer "F.Cu")
		(net "GND")
	)
	(segment
		(start 378.452634 -91.1098)
		(end 377.53544 -91.1098)
		(width 0.4572)
		(layer "F.Cu")
		(net "GND")
	)
	(segment
		(start 310.624982 -14.735302)
		(end 310.624982 -14.100302)
		(width 0.381)
		(layer "F.Cu")
		(net "GND")
	)
	(segment
		(start 166.249858 -306.349908)
		(end 165.774878 -306.824888)
		(width 0.249936)
		(layer "F.Cu")
		(net "GND")
	)
	(segment
		(start 270.474694 -299.224954)
		(end 270.949928 -298.74972)
		(width 0.249936)
		(layer "F.Cu")
		(net "GND")
	)
	(segment
		(start 232.517442 -64.200024)
		(end 231.388158 -64.200024)
		(width 0.3556)
		(layer "F.Cu")
		(net "GND")
	)
	(segment
		(start 416.499802 -285.449772)
		(end 416.024822 -285.924752)
		(width 0.249936)
		(layer "F.Cu")
		(net "GND")
	)
	(segment
		(start 279.499822 -284.499812)
		(end 279.024842 -284.024832)
		(width 0.249936)
		(layer "F.Cu")
		(net "GND")
	)
	(segment
		(start 32.534606 -38.937184)
		(end 32.800036 -38.671754)
		(width 0.4572)
		(layer "F.Cu")
		(net "GND")
	)
	(segment
		(start 74.374756 -290.674806)
		(end 74.84999 -290.199826)
		(width 0.249936)
		(layer "F.Cu")
		(net "GND")
	)
	(segment
		(start 418.874956 -303.024794)
		(end 418.399976 -302.549814)
		(width 0.249936)
		(layer "F.Cu")
		(net "GND")
	)
	(segment
		(start 336.843624 -43.85691)
		(end 337.514946 -43.85691)
		(width 0.254)
		(layer "F.Cu")
		(net "GND")
	)
	(segment
		(start 61.549788 -301.599854)
		(end 61.074808 -302.074834)
		(width 0.249936)
		(layer "F.Cu")
		(net "GND")
	)
	(segment
		(start 342.093804 -221.58706)
		(end 341.694008 -221.986856)
		(width 0.381)
		(layer "F.Cu")
		(net "GND")
	)
	(segment
		(start 58.24982 -287.699958)
		(end 57.749948 -288.19983)
		(width 0.249936)
		(layer "F.Cu")
		(net "GND")
	)
	(segment
		(start 76.27493 -300.174914)
		(end 76.74991 -300.649894)
		(width 0.249936)
		(layer "F.Cu")
		(net "GND")
	)
	(segment
		(start 270.766286 -252.756924)
		(end 270.766286 -253.45644)
		(width 0.4572)
		(layer "F.Cu")
		(net "GND")
	)
	(segment
		(start 82.947256 -37.087048)
		(end 83.582256 -37.087048)
		(width 0.4572)
		(layer "F.Cu")
		(net "GND")
	)
	(segment
		(start 417.450016 -303.499774)
		(end 416.974782 -303.024794)
		(width 0.249936)
		(layer "F.Cu")
		(net "GND")
	)
	(segment
		(start 397.258032 -131.76504)
		(end 398.94256 -131.76504)
		(width 0.3556)
		(layer "F.Cu")
		(net "GND")
	)
	(segment
		(start 63.924942 -300.174914)
		(end 64.399922 -299.699934)
		(width 0.249936)
		(layer "F.Cu")
		(net "GND")
	)
	(segment
		(start 298.499784 -301.599854)
		(end 298.974764 -302.074834)
		(width 0.249936)
		(layer "F.Cu")
		(net "GND")
	)
	(segment
		(start 192.375028 -299.224954)
		(end 192.850008 -298.74972)
		(width 0.249936)
		(layer "F.Cu")
		(net "GND")
	)
	(segment
		(start 422.674796 -302.074834)
		(end 423.15003 -301.599854)
		(width 0.249936)
		(layer "F.Cu")
		(net "GND")
	)
	(segment
		(start 243.043202 -115.411504)
		(end 243.043202 -114.672364)
		(width 0.4572)
		(layer "F.Cu")
		(net "GND")
	)
	(segment
		(start 290.42487 -305.874928)
		(end 289.94989 -306.349908)
		(width 0.249936)
		(layer "F.Cu")
		(net "GND")
	)
	(segment
		(start 293.74973 -303.499774)
		(end 294.22471 -303.974754)
		(width 0.249936)
		(layer "F.Cu")
		(net "GND")
	)
	(segment
		(start 389.424926 -298.27474)
		(end 389.899906 -298.74972)
		(width 0.249936)
		(layer "F.Cu")
		(net "GND")
	)
	(segment
		(start 435.948836 -31.390082)
		(end 436.964836 -31.390082)
		(width 0.3556)
		(layer "F.Cu")
		(net "GND")
	)
	(segment
		(start 146.789648 -64.312292)
		(end 147.548092 -64.312292)
		(width 0.4572)
		(layer "F.Cu")
		(net "GND")
	)
	(segment
		(start 408.899868 -303.499774)
		(end 409.374848 -303.974754)
		(width 0.249936)
		(layer "F.Cu")
		(net "GND")
	)
	(segment
		(start 360.25836 -261.814564)
		(end 360.86796 -261.814564)
		(width 0.381)
		(layer "F.Cu")
		(net "GND")
	)
	(segment
		(start 69.624956 -296.37482)
		(end 69.149976 -295.89984)
		(width 0.249936)
		(layer "F.Cu")
		(net "GND")
	)
	(segment
		(start 373.301768 -240.6904)
		(end 374.02897 -240.6904)
		(width 0.4572)
		(layer "F.Cu")
		(net "GND")
	)
	(segment
		(start 62.499748 -306.349908)
		(end 62.974982 -305.874928)
		(width 0.249936)
		(layer "F.Cu")
		(net "GND")
	)
	(segment
		(start 45.051726 -102.445058)
		(end 46.042326 -102.445058)
		(width 0.3556)
		(layer "F.Cu")
		(net "GND")
	)
	(segment
		(start 191.424052 -27.411934)
		(end 191.424052 -26.319734)
		(width 0.4572)
		(layer "F.Cu")
		(net "GND")
	)
	(segment
		(start 251.046742 -38.49116)
		(end 250.34113 -38.49116)
		(width 0.4572)
		(layer "F.Cu")
		(net "GND")
	)
	(segment
		(start 235.476288 -97.658428)
		(end 235.476288 -98.295968)
		(width 0.254)
		(layer "F.Cu")
		(net "GND")
	)
	(segment
		(start 81.024984 -301.124874)
		(end 81.499964 -301.599854)
		(width 0.249936)
		(layer "F.Cu")
		(net "GND")
	)
	(segment
		(start 72.267064 -120.035066)
		(end 73.257664 -120.035066)
		(width 0.3556)
		(layer "F.Cu")
		(net "GND")
	)
	(segment
		(start 37.550344 -252.756924)
		(end 37.550344 -253.45644)
		(width 0.4572)
		(layer "F.Cu")
		(net "GND")
	)
	(segment
		(start 402.249894 -284.499812)
		(end 401.774914 -284.974792)
		(width 0.249936)
		(layer "F.Cu")
		(net "GND")
	)
	(segment
		(start 239.246664 -205.16723)
		(end 239.64265 -204.771244)
		(width 0.4572)
		(layer "F.Cu")
		(net "GND")
	)
	(segment
		(start 189.049914 -298.74972)
		(end 189.524894 -298.27474)
		(width 0.249936)
		(layer "F.Cu")
		(net "GND")
	)
	(segment
		(start 415.612834 -102.439978)
		(end 416.95751 -102.439978)
		(width 0.3556)
		(layer "F.Cu")
		(net "GND")
	)
	(segment
		(start 124.145802 -172.84954)
		(end 124.14123 -172.844968)
		(width 0.4572)
		(layer "F.Cu")
		(net "GND")
	)
	(segment
		(start 165.751764 -125.955044)
		(end 166.742364 -125.955044)
		(width 0.3556)
		(layer "F.Cu")
		(net "GND")
	)
	(segment
		(start 75.32497 -296.37482)
		(end 75.79995 -295.89984)
		(width 0.249936)
		(layer "F.Cu")
		(net "GND")
	)
	(segment
		(start 300.399704 -305.399948)
		(end 300.874684 -304.924714)
		(width 0.249936)
		(layer "F.Cu")
		(net "GND")
	)
	(segment
		(start 172.424852 -309.674768)
		(end 171.949872 -309.199788)
		(width 0.249936)
		(layer "F.Cu")
		(net "GND")
	)
	(segment
		(start 408.899868 -307.299868)
		(end 409.374848 -307.774848)
		(width 0.249936)
		(layer "F.Cu")
		(net "GND")
	)
	(segment
		(start 392.274806 -279.274778)
		(end 391.799826 -278.799798)
		(width 0.249936)
		(layer "F.Cu")
		(net "GND")
	)
	(segment
		(start 272.374868 -298.27474)
		(end 271.899888 -297.79976)
		(width 0.249936)
		(layer "F.Cu")
		(net "GND")
	)
	(segment
		(start 68.674742 -304.924714)
		(end 68.199762 -304.449734)
		(width 0.249936)
		(layer "F.Cu")
		(net "GND")
	)
	(segment
		(start 171.474892 -303.974754)
		(end 170.999912 -303.499774)
		(width 0.249936)
		(layer "F.Cu")
		(net "GND")
	)
	(segment
		(start 406.049988 -285.449772)
		(end 406.524968 -285.924752)
		(width 0.249936)
		(layer "F.Cu")
		(net "GND")
	)
	(segment
		(start 180.50002 -290.199826)
		(end 180.975 -289.724846)
		(width 0.249936)
		(layer "F.Cu")
		(net "GND")
	)
	(segment
		(start 55.78856 -385.049268)
		(end 55.86476 -384.973068)
		(width 0.4572)
		(layer "F.Cu")
		(net "GND")
	)
	(segment
		(start 71.999856 -302.549814)
		(end 71.524876 -303.024794)
		(width 0.249936)
		(layer "F.Cu")
		(net "GND")
	)
	(segment
		(start 284.724856 -289.724846)
		(end 285.199836 -290.199826)
		(width 0.249936)
		(layer "F.Cu")
		(net "GND")
	)
	(segment
		(start 160.946846 -38.49116)
		(end 160.241234 -38.49116)
		(width 0.4572)
		(layer "F.Cu")
		(net "GND")
	)
	(segment
		(start 12.261596 -305.881786)
		(end 12.49172 -305.786536)
		(width 0.1778)
		(layer "F.Cu")
		(net "GND")
	)
	(segment
		(start 167.732964 -131.76504)
		(end 166.742364 -131.76504)
		(width 0.3556)
		(layer "F.Cu")
		(net "GND")
	)
	(segment
		(start 44.896532 -152.958038)
		(end 44.8691 -152.958038)
		(width 0.3556)
		(layer "F.Cu")
		(net "GND")
	)
	(segment
		(start 269.049754 -293.04996)
		(end 268.574774 -292.57498)
		(width 0.249936)
		(layer "F.Cu")
		(net "GND")
	)
	(segment
		(start 390.849866 -283.549852)
		(end 390.374886 -283.074872)
		(width 0.249936)
		(layer "F.Cu")
		(net "GND")
	)
	(segment
		(start 399.93316 -102.445058)
		(end 398.94256 -102.445058)
		(width 0.3556)
		(layer "F.Cu")
		(net "GND")
	)
	(segment
		(start 52.524914 -296.37482)
		(end 52.049934 -296.8498)
		(width 0.249936)
		(layer "F.Cu")
		(net "GND")
	)
	(segment
		(start 259.399786 -334.415638)
		(end 260.446012 -334.415638)
		(width 0.4572)
		(layer "F.Cu")
		(net "GND")
	)
	(segment
		(start 46.845728 -125.955044)
		(end 46.042326 -125.955044)
		(width 0.3556)
		(layer "F.Cu")
		(net "GND")
	)
	(segment
		(start 422.674796 -302.074834)
		(end 422.199816 -301.599854)
		(width 0.249936)
		(layer "F.Cu")
		(net "GND")
	)
	(segment
		(start 423.15003 -293.99992)
		(end 423.62501 -294.4749)
		(width 0.249936)
		(layer "F.Cu")
		(net "GND")
	)
	(segment
		(start 341.293958 -222.386652)
		(end 340.894162 -221.986856)
		(width 0.381)
		(layer "F.Cu")
		(net "GND")
	)
	(segment
		(start 190.474854 -292.574726)
		(end 190.950088 -292.099746)
		(width 0.249936)
		(layer "F.Cu")
		(net "GND")
	)
	(segment
		(start 35.195002 -59.978036)
		(end 35.195002 -60.633356)
		(width 0.4572)
		(layer "F.Cu")
		(net "GND")
	)
	(segment
		(start 180.50002 -306.349908)
		(end 180.975 -305.874928)
		(width 0.249936)
		(layer "F.Cu")
		(net "GND")
	)
	(segment
		(start 311.799732 -296.8498)
		(end 311.324752 -296.37482)
		(width 0.249936)
		(layer "F.Cu")
		(net "GND")
	)
	(segment
		(start 125.578362 -282.8417)
		(end 125.345952 -283.07411)
		(width 0.2286)
		(layer "F.Cu")
		(net "GND")
	)
	(segment
		(start 321.736212 -31.390082)
		(end 321.988434 -31.642304)
		(width 0.3556)
		(layer "F.Cu")
		(net "GND")
	)
	(segment
		(start 10.84326 -115.411504)
		(end 10.84326 -114.672364)
		(width 0.4572)
		(layer "F.Cu")
		(net "GND")
	)
	(segment
		(start 428.37481 -290.674806)
		(end 427.89983 -291.149786)
		(width 0.249936)
		(layer "F.Cu")
		(net "GND")
	)
	(segment
		(start 265.482832 -306.844192)
		(end 265.771122 -307.132482)
		(width 0.4572)
		(layer "F.Cu")
		(net "GND")
	)
	(segment
		(start 169.574972 -307.774848)
		(end 169.099992 -307.299868)
		(width 0.249936)
		(layer "F.Cu")
		(net "GND")
	)
	(segment
		(start 260.778752 -335.115408)
		(end 262.20293 -335.115408)
		(width 0.4572)
		(layer "F.Cu")
		(net "GND")
	)
	(segment
		(start 69.38137 -133.044946)
		(end 68.65747 -133.044946)
		(width 0.3556)
		(layer "F.Cu")
		(net "GND")
	)
	(segment
		(start 198.513446 -113.41354)
		(end 197.835774 -113.41354)
		(width 0.4064)
		(layer "F.Cu")
		(net "GND")
	)
	(segment
		(start 320.863976 -291.102034)
		(end 321.023742 -291.2618)
		(width 0.4572)
		(layer "F.Cu")
		(net "GND")
	)
	(segment
		(start 301.349918 -292.099746)
		(end 300.874684 -291.624766)
		(width 0.249936)
		(layer "F.Cu")
		(net "GND")
	)
	(segment
		(start 273.799808 -276.899878)
		(end 273.324828 -276.424898)
		(width 0.249936)
		(layer "F.Cu")
		(net "GND")
	)
	(segment
		(start 97.648268 -395.1478)
		(end 97.032318 -395.1478)
		(width 0.4572)
		(layer "F.Cu")
		(net "GND")
	)
	(segment
		(start 58.224928 -306.824888)
		(end 58.699908 -306.349908)
		(width 0.249936)
		(layer "F.Cu")
		(net "GND")
	)
	(segment
		(start 416.974782 -299.224954)
		(end 416.499802 -298.74972)
		(width 0.249936)
		(layer "F.Cu")
		(net "GND")
	)
	(segment
		(start 393.19454 -152.958038)
		(end 393.196572 -152.96007)
		(width 0.3556)
		(layer "F.Cu")
		(net "GND")
	)
	(segment
		(start 307.049932 -303.499774)
		(end 306.099718 -303.499774)
		(width 0.249936)
		(layer "F.Cu")
		(net "GND")
	)
	(segment
		(start 289.89401 -35.264852)
		(end 289.89401 -35.499548)
		(width 0.4572)
		(layer "F.Cu")
		(net "GND")
	)
	(segment
		(start 391.324846 -273.574764)
		(end 391.799826 -273.099784)
		(width 0.249936)
		(layer "F.Cu")
		(net "GND")
	)
	(segment
		(start 417.450016 -285.449772)
		(end 416.974782 -284.974792)
		(width 0.249936)
		(layer "F.Cu")
		(net "GND")
	)
	(segment
		(start 385.149852 -282.599892)
		(end 384.674872 -282.124912)
		(width 0.249936)
		(layer "F.Cu")
		(net "GND")
	)
	(segment
		(start 47.032926 -120.555004)
		(end 46.042326 -120.555004)
		(width 0.3556)
		(layer "F.Cu")
		(net "GND")
	)
	(segment
		(start 380.034038 -3.820922)
		(end 380.649734 -3.820922)
		(width 0.4572)
		(layer "F.Cu")
		(net "GND")
	)
	(segment
		(start 398.234154 -111.44504)
		(end 398.94256 -111.44504)
		(width 0.3556)
		(layer "F.Cu")
		(net "GND")
	)
	(segment
		(start 335.64195 -171.069)
		(end 335.026 -171.069)
		(width 0.4572)
		(layer "F.Cu")
		(net "GND")
	)
	(segment
		(start 422.199816 -292.099746)
		(end 421.724836 -292.574726)
		(width 0.249936)
		(layer "F.Cu")
		(net "GND")
	)
	(segment
		(start 458.059282 -306.405026)
		(end 457.491338 -306.97297)
		(width 0.4572)
		(layer "F.Cu")
		(net "GND")
	)
	(segment
		(start 75.32497 -292.574726)
		(end 75.79995 -292.099746)
		(width 0.249936)
		(layer "F.Cu")
		(net "GND")
	)
	(segment
		(start 279.024842 -303.024794)
		(end 279.499822 -303.499774)
		(width 0.249936)
		(layer "F.Cu")
		(net "GND")
	)
	(segment
		(start 167.732964 -104.244902)
		(end 166.742364 -104.244902)
		(width 0.3556)
		(layer "F.Cu")
		(net "GND")
	)
	(segment
		(start 65.349882 -306.349908)
		(end 64.874902 -305.874928)
		(width 0.249936)
		(layer "F.Cu")
		(net "GND")
	)
	(segment
		(start 308.949852 -291.149786)
		(end 308.474872 -290.674806)
		(width 0.249936)
		(layer "F.Cu")
		(net "GND")
	)
	(segment
		(start 164.349938 -307.299868)
		(end 163.874958 -307.774848)
		(width 0.249936)
		(layer "F.Cu")
		(net "GND")
	)
	(segment
		(start 154.307794 -162.044126)
		(end 154.307794 -161.510218)
		(width 0.4572)
		(layer "F.Cu")
		(net "GND")
	)
	(segment
		(start 45.87494 -296.37482)
		(end 46.34992 -296.8498)
		(width 0.249936)
		(layer "F.Cu")
		(net "GND")
	)
	(segment
		(start 419.824916 -303.024794)
		(end 419.349936 -303.499774)
		(width 0.249936)
		(layer "F.Cu")
		(net "GND")
	)
	(segment
		(start 163.874958 -306.824888)
		(end 163.399978 -307.299868)
		(width 0.249936)
		(layer "F.Cu")
		(net "GND")
	)
	(segment
		(start 426.967904 -51.019456)
		(end 427.623224 -51.019456)
		(width 0.254)
		(layer "F.Cu")
		(net "GND")
	)
	(segment
		(start 194.767962 -51.019456)
		(end 195.423282 -51.019456)
		(width 0.254)
		(layer "F.Cu")
		(net "GND")
	)
	(segment
		(start 334.89392 -226.387152)
		(end 334.494124 -226.786948)
		(width 0.381)
		(layer "F.Cu")
		(net "GND")
	)
	(segment
		(start 166.725092 -287.824926)
		(end 166.249858 -288.299906)
		(width 0.249936)
		(layer "F.Cu")
		(net "GND")
	)
	(segment
		(start 281.874722 -303.024794)
		(end 282.349702 -303.499774)
		(width 0.249936)
		(layer "F.Cu")
		(net "GND")
	)
	(segment
		(start 13.802106 -378.725938)
		(end 14.514576 -378.725938)
		(width 0.2032)
		(layer "F.Cu")
		(net "GND")
	)
	(segment
		(start 183.3499 -286.399732)
		(end 183.82488 -285.924752)
		(width 0.249936)
		(layer "F.Cu")
		(net "GND")
	)
	(segment
		(start 395.59992 -306.349908)
		(end 396.0749 -306.824888)
		(width 0.249936)
		(layer "F.Cu")
		(net "GND")
	)
	(segment
		(start 198.075042 -301.124874)
		(end 198.550022 -301.599854)
		(width 0.249936)
		(layer "F.Cu")
		(net "GND")
	)
	(segment
		(start 185.250074 -293.99992)
		(end 185.725054 -294.4749)
		(width 0.249936)
		(layer "F.Cu")
		(net "GND")
	)
	(segment
		(start 293.74973 -299.699934)
		(end 293.27475 -300.174914)
		(width 0.249936)
		(layer "F.Cu")
		(net "GND")
	)
	(segment
		(start 131.36499 -27.79014)
		(end 132.38099 -27.79014)
		(width 0.3556)
		(layer "F.Cu")
		(net "GND")
	)
	(segment
		(start 422.674796 -300.174914)
		(end 422.199816 -299.699934)
		(width 0.249936)
		(layer "F.Cu")
		(net "GND")
	)
	(segment
		(start 397.49984 -292.099746)
		(end 397.97482 -292.574726)
		(width 0.249936)
		(layer "F.Cu")
		(net "GND")
	)
	(segment
		(start 395.392148 -104.793034)
		(end 395.392148 -104.404922)
		(width 0.3556)
		(layer "F.Cu")
		(net "GND")
	)
	(segment
		(start 340.493858 -218.387168)
		(end 340.094062 -217.987372)
		(width 0.381)
		(layer "F.Cu")
		(net "GND")
	)
	(segment
		(start 197.125082 -296.37482)
		(end 197.600062 -295.89984)
		(width 0.249936)
		(layer "F.Cu")
		(net "GND")
	)
	(segment
		(start 191.900048 -297.79976)
		(end 191.425068 -298.27474)
		(width 0.249936)
		(layer "F.Cu")
		(net "GND")
	)
	(segment
		(start 420.299896 -293.04996)
		(end 420.774876 -292.574726)
		(width 0.249936)
		(layer "F.Cu")
		(net "GND")
	)
	(segment
		(start 263.147302 -37.087048)
		(end 263.782302 -37.087048)
		(width 0.4572)
		(layer "F.Cu")
		(net "GND")
	)
	(segment
		(start 320.864738 -27.79014)
		(end 319.848738 -27.79014)
		(width 0.3556)
		(layer "F.Cu")
		(net "GND")
	)
	(segment
		(start 58.699908 -285.449772)
		(end 58.224928 -284.974792)
		(width 0.249936)
		(layer "F.Cu")
		(net "GND")
	)
	(segment
		(start 304.199798 -298.74972)
		(end 303.724818 -298.27474)
		(width 0.249936)
		(layer "F.Cu")
		(net "GND")
	)
	(segment
		(start 63.241936 -162.781488)
		(end 63.241936 -162.08375)
		(width 0.4572)
		(layer "F.Cu")
		(net "GND")
	)
	(segment
		(start 310.374792 -289.724846)
		(end 309.899812 -289.249866)
		(width 0.249936)
		(layer "F.Cu")
		(net "GND")
	)
	(segment
		(start 163.399978 -306.349908)
		(end 162.924998 -306.824888)
		(width 0.249936)
		(layer "F.Cu")
		(net "GND")
	)
	(segment
		(start 267.083794 -336.197194)
		(end 267.083794 -339.413596)
		(width 0.4572)
		(layer "F.Cu")
		(net "GND")
	)
	(segment
		(start 27.79141 -305.334162)
		(end 27.79141 -305.507898)
		(width 0.4572)
		(layer "F.Cu")
		(net "GND")
	)
	(segment
		(start 427.89983 -300.649894)
		(end 428.37481 -300.174914)
		(width 0.249936)
		(layer "F.Cu")
		(net "GND")
	)
	(segment
		(start 176.224946 -306.824888)
		(end 176.699926 -307.299868)
		(width 0.249936)
		(layer "F.Cu")
		(net "GND")
	)
	(segment
		(start 53.474874 -305.874928)
		(end 53.949854 -305.399948)
		(width 0.249936)
		(layer "F.Cu")
		(net "GND")
	)
	(segment
		(start 401.774914 -303.974754)
		(end 402.249894 -303.499774)
		(width 0.249936)
		(layer "F.Cu")
		(net "GND")
	)
	(segment
		(start 39.699946 -273.099784)
		(end 39.224966 -272.624804)
		(width 0.249936)
		(layer "F.Cu")
		(net "GND")
	)
	(segment
		(start 51.63312 -118.754906)
		(end 50.64252 -118.754906)
		(width 0.3556)
		(layer "F.Cu")
		(net "GND")
	)
	(segment
		(start 67.66687 -134.845044)
		(end 68.65747 -134.845044)
		(width 0.3556)
		(layer "F.Cu")
		(net "GND")
	)
	(segment
		(start 165.299898 -301.599854)
		(end 165.774878 -301.124874)
		(width 0.249936)
		(layer "F.Cu")
		(net "GND")
	)
	(segment
		(start 363.607858 -154.510994)
		(end 364.248446 -154.510994)
		(width 0.4572)
		(layer "F.Cu")
		(net "GND")
	)
	(segment
		(start 305.149758 -293.99992)
		(end 305.624738 -294.4749)
		(width 0.249936)
		(layer "F.Cu")
		(net "GND")
	)
	(segment
		(start 431.85207 -142.250922)
		(end 431.505106 -142.597886)
		(width 0.4064)
		(layer "F.Cu")
		(net "GND")
	)
	(segment
		(start 74.248264 -121.83491)
		(end 73.257664 -121.83491)
		(width 0.3556)
		(layer "F.Cu")
		(net "GND")
	)
	(segment
		(start 313.699906 -293.99992)
		(end 313.224926 -294.4749)
		(width 0.249936)
		(layer "F.Cu")
		(net "GND")
	)
	(segment
		(start 15.264892 -31.390082)
		(end 16.280892 -31.390082)
		(width 0.3556)
		(layer "F.Cu")
		(net "GND")
	)
	(segment
		(start 170.524932 -303.974754)
		(end 170.999912 -303.499774)
		(width 0.249936)
		(layer "F.Cu")
		(net "GND")
	)
	(segment
		(start 164.824918 -300.174914)
		(end 165.299898 -299.699934)
		(width 0.249936)
		(layer "F.Cu")
		(net "GND")
	)
	(segment
		(start 113.134394 -180.644546)
		(end 113.750344 -180.644546)
		(width 0.381)
		(layer "F.Cu")
		(net "GND")
	)
	(segment
		(start 293.74973 -306.349908)
		(end 294.22471 -306.824888)
		(width 0.249936)
		(layer "F.Cu")
		(net "GND")
	)
	(segment
		(start 411.275022 -305.874928)
		(end 410.799788 -305.399948)
		(width 0.249936)
		(layer "F.Cu")
		(net "GND")
	)
	(segment
		(start 297.549824 -307.299868)
		(end 297.074844 -307.774848)
		(width 0.249936)
		(layer "F.Cu")
		(net "GND")
	)
	(segment
		(start 294.832024 -167.922702)
		(end 294.832024 -168.94556)
		(width 0.4572)
		(layer "F.Cu")
		(net "GND")
	)
	(segment
		(start 393.318238 -151.157432)
		(end 393.320778 -151.159972)
		(width 0.3556)
		(layer "F.Cu")
		(net "GND")
	)
	(segment
		(start 299.924724 -302.074834)
		(end 300.399704 -301.599854)
		(width 0.249936)
		(layer "F.Cu")
		(net "GND")
	)
	(segment
		(start 55.27294 -390.464802)
		(end 55.249826 -390.441688)
		(width 0.3048)
		(layer "F.Cu")
		(net "GND")
	)
	(segment
		(start 351.38995 -173.77156)
		(end 351.38995 -173.83125)
		(width 0.4572)
		(layer "F.Cu")
		(net "GND")
	)
	(segment
		(start 399.93316 -129.964942)
		(end 398.94256 -129.964942)
		(width 0.3556)
		(layer "F.Cu")
		(net "GND")
	)
	(segment
		(start 154.850084 -294.94988)
		(end 154.375104 -294.4749)
		(width 0.249936)
		(layer "F.Cu")
		(net "GND")
	)
	(segment
		(start 393.351766 -107.845098)
		(end 394.342366 -107.845098)
		(width 0.3556)
		(layer "F.Cu")
		(net "GND")
	)
	(segment
		(start 288.524696 -306.824888)
		(end 288.049716 -307.299868)
		(width 0.249936)
		(layer "F.Cu")
		(net "GND")
	)
	(segment
		(start 42.074846 -300.174914)
		(end 41.599866 -300.649894)
		(width 0.249936)
		(layer "F.Cu")
		(net "GND")
	)
	(segment
		(start 93.264736 -31.390082)
		(end 94.280736 -31.390082)
		(width 0.3556)
		(layer "F.Cu")
		(net "GND")
	)
	(segment
		(start 226.351084 -307.368702)
		(end 226.87026 -306.849526)
		(width 0.1778)
		(layer "F.Cu")
		(net "GND")
	)
	(segment
		(start 4.91871 -379.551692)
		(end 4.91871 -380.182628)
		(width 0.381)
		(layer "F.Cu")
		(net "GND")
	)
	(segment
		(start 197.600062 -297.79976)
		(end 198.075042 -297.32478)
		(width 0.249936)
		(layer "F.Cu")
		(net "GND")
	)
	(segment
		(start 385.625086 -296.37482)
		(end 385.149852 -296.8498)
		(width 0.249936)
		(layer "F.Cu")
		(net "GND")
	)
	(segment
		(start 157.364938 -31.390082)
		(end 158.380938 -31.390082)
		(width 0.3556)
		(layer "F.Cu")
		(net "GND")
	)
	(segment
		(start 57.274968 -287.824926)
		(end 56.799988 -288.299906)
		(width 0.249936)
		(layer "F.Cu")
		(net "GND")
	)
	(segment
		(start 177.174906 -305.874928)
		(end 176.699926 -306.349908)
		(width 0.249936)
		(layer "F.Cu")
		(net "GND")
	)
	(segment
		(start 283.774896 -305.874928)
		(end 283.299916 -305.399948)
		(width 0.249936)
		(layer "F.Cu")
		(net "GND")
	)
	(segment
		(start 287.574736 -306.824888)
		(end 287.099756 -306.349908)
		(width 0.249936)
		(layer "F.Cu")
		(net "GND")
	)
	(segment
		(start 304.718466 -116.435124)
		(end 305.457606 -116.435124)
		(width 0.3556)
		(layer "F.Cu")
		(net "GND")
	)
	(segment
		(start 282.824936 -298.27474)
		(end 282.349702 -298.74972)
		(width 0.249936)
		(layer "F.Cu")
		(net "GND")
	)
	(segment
		(start 294.22471 -305.874928)
		(end 294.69969 -305.399948)
		(width 0.249936)
		(layer "F.Cu")
		(net "GND")
	)
	(segment
		(start 419.824916 -292.574726)
		(end 420.299896 -293.04996)
		(width 0.249936)
		(layer "F.Cu")
		(net "GND")
	)
	(segment
		(start 42.549826 -300.649894)
		(end 42.074846 -300.174914)
		(width 0.249936)
		(layer "F.Cu")
		(net "GND")
	)
	(segment
		(start 45.39996 -284.499812)
		(end 44.92498 -284.024832)
		(width 0.249936)
		(layer "F.Cu")
		(net "GND")
	)
	(segment
		(start 364.494826 -110.977426)
		(end 364.494826 -110.365032)
		(width 0.4572)
		(layer "F.Cu")
		(net "GND")
	)
	(segment
		(start 301.543466 -136.645142)
		(end 300.857412 -136.645142)
		(width 0.3556)
		(layer "F.Cu")
		(net "GND")
	)
	(segment
		(start 178.764946 -34.990024)
		(end 177.748946 -34.990024)
		(width 0.3556)
		(layer "F.Cu")
		(net "GND")
	)
	(segment
		(start 70.574916 -300.174914)
		(end 70.099936 -300.649894)
		(width 0.249936)
		(layer "F.Cu")
		(net "GND")
	)
	(segment
		(start 383.495042 -59.978036)
		(end 383.495042 -60.633356)
		(width 0.4572)
		(layer "F.Cu")
		(net "GND")
	)
	(segment
		(start 284.023816 -168.229788)
		(end 284.191202 -168.397174)
		(width 0.4572)
		(layer "F.Cu")
		(net "GND")
	)
	(segment
		(start 10.664952 -33.19018)
		(end 9.648952 -33.19018)
		(width 0.3556)
		(layer "F.Cu")
		(net "GND")
	)
	(segment
		(start 382.992884 -54.163722)
		(end 383.068068 -54.238906)
		(width 0.254)
		(layer "F.Cu")
		(net "GND")
	)
	(segment
		(start 190.394844 -104.240076)
		(end 189.357508 -104.240076)
		(width 0.3556)
		(layer "F.Cu")
		(net "GND")
	)
	(segment
		(start 284.724856 -300.174914)
		(end 285.199836 -299.699934)
		(width 0.249936)
		(layer "F.Cu")
		(net "GND")
	)
	(segment
		(start 340.93912 -284.42412)
		(end 340.571836 -284.42412)
		(width 0.2286)
		(layer "F.Cu")
		(net "GND")
	)
	(segment
		(start 181.9529 -176.966372)
		(end 181.9529 -177.667158)
		(width 0.4572)
		(layer "F.Cu")
		(net "GND")
	)
	(segment
		(start 428.37481 -294.4749)
		(end 427.89983 -294.94988)
		(width 0.249936)
		(layer "F.Cu")
		(net "GND")
	)
	(segment
		(start 402.641816 -26.606246)
		(end 402.641816 -25.971246)
		(width 0.4572)
		(layer "F.Cu")
		(net "GND")
	)
	(segment
		(start 171.949872 -301.599854)
		(end 171.474892 -302.074834)
		(width 0.249936)
		(layer "F.Cu")
		(net "GND")
	)
	(segment
		(start 426.47489 -293.52494)
		(end 426.94987 -293.04996)
		(width 0.249936)
		(layer "F.Cu")
		(net "GND")
	)
	(segment
		(start 413.649922 -296.8498)
		(end 414.124902 -297.32478)
		(width 0.249936)
		(layer "F.Cu")
		(net "GND")
	)
	(segment
		(start 57.333134 -379.567694)
		(end 57.775348 -379.567694)
		(width 0.4572)
		(layer "F.Cu")
		(net "GND")
	)
	(segment
		(start 42.549826 -285.449772)
		(end 43.024806 -284.974792)
		(width 0.249936)
		(layer "F.Cu")
		(net "GND")
	)
	(segment
		(start 311.324752 -294.4749)
		(end 310.849772 -294.94988)
		(width 0.249936)
		(layer "F.Cu")
		(net "GND")
	)
	(segment
		(start 54.899814 -288.299906)
		(end 55.374794 -287.824926)
		(width 0.249936)
		(layer "F.Cu")
		(net "GND")
	)
	(segment
		(start 296.599864 -306.349908)
		(end 297.074844 -306.824888)
		(width 0.249936)
		(layer "F.Cu")
		(net "GND")
	)
	(segment
		(start 385.836414 -31.390082)
		(end 386.088636 -31.642304)
		(width 0.3556)
		(layer "F.Cu")
		(net "GND")
	)
	(segment
		(start 301.349918 -293.04996)
		(end 301.824898 -293.52494)
		(width 0.249936)
		(layer "F.Cu")
		(net "GND")
	)
	(segment
		(start 303.724818 -305.874928)
		(end 303.249838 -306.349908)
		(width 0.249936)
		(layer "F.Cu")
		(net "GND")
	)
	(segment
		(start 241.967258 -305.338988)
		(end 241.967258 -304.703988)
		(width 0.4572)
		(layer "F.Cu")
		(net "GND")
	)
	(segment
		(start 62.499748 -299.699934)
		(end 62.974982 -300.174914)
		(width 0.249936)
		(layer "F.Cu")
		(net "GND")
	)
	(segment
		(start 388.949946 -281.649932)
		(end 388.474966 -281.174952)
		(width 0.249936)
		(layer "F.Cu")
		(net "GND")
	)
	(segment
		(start 423.15003 -295.89984)
		(end 423.62501 -296.37482)
		(width 0.249936)
		(layer "F.Cu")
		(net "GND")
	)
	(segment
		(start 295.174924 -303.974754)
		(end 294.69969 -303.499774)
		(width 0.249936)
		(layer "F.Cu")
		(net "GND")
	)
	(segment
		(start 289.94989 -306.349908)
		(end 289.47491 -306.824888)
		(width 0.249936)
		(layer "F.Cu")
		(net "GND")
	)
	(segment
		(start 15.264892 -33.19018)
		(end 16.280892 -33.19018)
		(width 0.3556)
		(layer "F.Cu")
		(net "GND")
	)
	(segment
		(start 410.964888 -31.390082)
		(end 411.836362 -31.390082)
		(width 0.3556)
		(layer "F.Cu")
		(net "GND")
	)
	(segment
		(start 182.39994 -288.299906)
		(end 182.87492 -287.824926)
		(width 0.249936)
		(layer "F.Cu")
		(net "GND")
	)
	(segment
		(start 416.024822 -305.874928)
		(end 416.499802 -306.349908)
		(width 0.249936)
		(layer "F.Cu")
		(net "GND")
	)
	(segment
		(start 401.299934 -288.299906)
		(end 400.824954 -287.824926)
		(width 0.249936)
		(layer "F.Cu")
		(net "GND")
	)
	(segment
		(start 351.902776 -91.788234)
		(end 351.580196 -92.110814)
		(width 0.4572)
		(layer "F.Cu")
		(net "GND")
	)
	(segment
		(start 45.39996 -286.399732)
		(end 44.92498 -285.924752)
		(width 0.249936)
		(layer "F.Cu")
		(net "GND")
	)
	(segment
		(start 422.548304 -116.435124)
		(end 421.557704 -116.435124)
		(width 0.3556)
		(layer "F.Cu")
		(net "GND")
	)
	(segment
		(start 288.99993 -306.349908)
		(end 289.47491 -306.824888)
		(width 0.249936)
		(layer "F.Cu")
		(net "GND")
	)
	(segment
		(start 310.867806 -55.083456)
		(end 311.523126 -55.083456)
		(width 0.254)
		(layer "F.Cu")
		(net "GND")
	)
	(segment
		(start 163.399978 -306.349908)
		(end 162.924998 -305.874928)
		(width 0.249936)
		(layer "F.Cu")
		(net "GND")
	)
	(segment
		(start 349.047562 -283.07411)
		(end 348.732348 -283.07411)
		(width 0.2286)
		(layer "F.Cu")
		(net "GND")
	)
	(segment
		(start 301.824898 -294.4749)
		(end 301.349918 -293.99992)
		(width 0.249936)
		(layer "F.Cu")
		(net "GND")
	)
	(segment
		(start 67.667124 -147.55495)
		(end 67.66687 -147.555204)
		(width 0.4572)
		(layer "F.Cu")
		(net "GND")
	)
	(segment
		(start 401.774914 -306.824888)
		(end 402.249894 -307.299868)
		(width 0.249936)
		(layer "F.Cu")
		(net "GND")
	)
	(segment
		(start 57.749948 -292.099746)
		(end 57.274968 -291.624766)
		(width 0.249936)
		(layer "F.Cu")
		(net "GND")
	)
	(segment
		(start 286.624776 -284.024832)
		(end 287.099756 -283.549852)
		(width 0.249936)
		(layer "F.Cu")
		(net "GND")
	)
	(segment
		(start 300.399704 -304.449734)
		(end 299.924724 -303.974754)
		(width 0.249936)
		(layer "F.Cu")
		(net "GND")
	)
	(segment
		(start 208.149698 -303.636426)
		(end 208.149698 -303.026826)
		(width 0.4572)
		(layer "F.Cu")
		(net "GND")
	)
	(segment
		(start 362.732574 -395.750288)
		(end 362.01604 -395.750288)
		(width 0.4572)
		(layer "F.Cu")
		(net "GND")
	)
	(segment
		(start 411.275022 -284.974792)
		(end 410.799788 -285.449772)
		(width 0.249936)
		(layer "F.Cu")
		(net "GND")
	)
	(segment
		(start 307.999892 -299.699934)
		(end 308.474872 -300.174914)
		(width 0.249936)
		(layer "F.Cu")
		(net "GND")
	)
	(segment
		(start 180.50002 -288.299906)
		(end 180.975 -287.824926)
		(width 0.249936)
		(layer "F.Cu")
		(net "GND")
	)
	(segment
		(start 397.624046 -27.411934)
		(end 397.624046 -26.319734)
		(width 0.4572)
		(layer "F.Cu")
		(net "GND")
	)
	(segment
		(start 103.958136 -189.30112)
		(end 103.958136 -188.294264)
		(width 0.2794)
		(layer "F.Cu")
		(net "GND")
	)
	(segment
		(start 300.857412 -147.55495)
		(end 299.867066 -147.55495)
		(width 0.4572)
		(layer "F.Cu")
		(net "GND")
	)
	(segment
		(start 185.747914 -142.15491)
		(end 184.757314 -142.15491)
		(width 0.3556)
		(layer "F.Cu")
		(net "GND")
	)
	(segment
		(start 208.496154 -25.990042)
		(end 209.364834 -25.990042)
		(width 0.3556)
		(layer "F.Cu")
		(net "GND")
	)
	(segment
		(start 162.450018 -286.399732)
		(end 161.975038 -285.924752)
		(width 0.249936)
		(layer "F.Cu")
		(net "GND")
	)
	(segment
		(start 404.149814 -292.099746)
		(end 404.624794 -291.624766)
		(width 0.249936)
		(layer "F.Cu")
		(net "GND")
	)
	(segment
		(start 157.224984 -299.224954)
		(end 156.750004 -299.699934)
		(width 0.249936)
		(layer "F.Cu")
		(net "GND")
	)
	(segment
		(start 419.824916 -288.774886)
		(end 419.349936 -288.299906)
		(width 0.249936)
		(layer "F.Cu")
		(net "GND")
	)
	(segment
		(start 431.224944 -297.32478)
		(end 430.749964 -297.79976)
		(width 0.249936)
		(layer "F.Cu")
		(net "GND")
	)
	(segment
		(start 394.64996 -286.399732)
		(end 394.17498 -285.924752)
		(width 0.249936)
		(layer "F.Cu")
		(net "GND")
	)
	(segment
		(start 99.17938 -383.611882)
		(end 99.17938 -385.177792)
		(width 0.4572)
		(layer "F.Cu")
		(net "GND")
	)
	(segment
		(start 172.900086 -303.499774)
		(end 173.375066 -303.974754)
		(width 0.249936)
		(layer "F.Cu")
		(net "GND")
	)
	(segment
		(start 181.44998 -306.349908)
		(end 180.975 -306.824888)
		(width 0.249936)
		(layer "F.Cu")
		(net "GND")
	)
	(segment
		(start 323.761862 -101.865684)
		(end 323.761862 -101.609398)
		(width 0.254)
		(layer "F.Cu")
		(net "GND")
	)
	(segment
		(start 423.160952 -37.201094)
		(end 422.398444 -37.201094)
		(width 0.4572)
		(layer "F.Cu")
		(net "GND")
	)
	(segment
		(start 181.92496 -302.074834)
		(end 181.44998 -301.599854)
		(width 0.249936)
		(layer "F.Cu")
		(net "GND")
	)
	(segment
		(start 390.58088 -31.390082)
		(end 389.56488 -31.390082)
		(width 0.3556)
		(layer "F.Cu")
		(net "GND")
	)
	(segment
		(start 199.047354 -37.087048)
		(end 199.682354 -37.087048)
		(width 0.4572)
		(layer "F.Cu")
		(net "GND")
	)
	(segment
		(start 393.7 -288.299906)
		(end 394.17498 -287.824926)
		(width 0.249936)
		(layer "F.Cu")
		(net "GND")
	)
	(segment
		(start 74.248264 -133.044946)
		(end 73.257664 -133.044946)
		(width 0.3556)
		(layer "F.Cu")
		(net "GND")
	)
	(segment
		(start 402.249894 -294.94988)
		(end 401.774914 -294.4749)
		(width 0.249936)
		(layer "F.Cu")
		(net "GND")
	)
	(segment
		(start 415.549842 -307.299868)
		(end 415.074862 -306.824888)
		(width 0.249936)
		(layer "F.Cu")
		(net "GND")
	)
	(segment
		(start 81.974944 -301.124874)
		(end 81.499964 -301.599854)
		(width 0.249936)
		(layer "F.Cu")
		(net "GND")
	)
	(segment
		(start 237.524798 -85.551518)
		(end 236.885988 -85.551518)
		(width 0.4572)
		(layer "F.Cu")
		(net "GND")
	)
	(segment
		(start 62.499748 -306.349908)
		(end 62.024768 -305.874928)
		(width 0.249936)
		(layer "F.Cu")
		(net "GND")
	)
	(segment
		(start 74.248264 -136.645142)
		(end 73.257664 -136.645142)
		(width 0.3556)
		(layer "F.Cu")
		(net "GND")
	)
	(segment
		(start 417.450016 -293.99992)
		(end 417.924996 -293.52494)
		(width 0.249936)
		(layer "F.Cu")
		(net "GND")
	)
	(segment
		(start 454.695814 -374.129808)
		(end 455.645266 -374.129808)
		(width 0.4572)
		(layer "F.Cu")
		(net "GND")
	)
	(segment
		(start 243.040662 -278.041862)
		(end 242.578128 -278.233378)
		(width 0.254)
		(layer "F.Cu")
		(net "GND")
	)
	(segment
		(start 350.093788 -223.987106)
		(end 350.493584 -224.386902)
		(width 0.381)
		(layer "F.Cu")
		(net "GND")
	)
	(segment
		(start 182.87492 -306.824888)
		(end 182.39994 -306.349908)
		(width 0.249936)
		(layer "F.Cu")
		(net "GND")
	)
	(segment
		(start 290.42487 -284.974792)
		(end 289.94989 -284.499812)
		(width 0.249936)
		(layer "F.Cu")
		(net "GND")
	)
	(segment
		(start 188.366908 -143.955008)
		(end 189.357508 -143.955008)
		(width 0.3556)
		(layer "F.Cu")
		(net "GND")
	)
	(segment
		(start 180.975 -302.074834)
		(end 181.44998 -301.599854)
		(width 0.249936)
		(layer "F.Cu")
		(net "GND")
	)
	(segment
		(start 45.020738 -151.159972)
		(end 45.020738 -151.157432)
		(width 0.3556)
		(layer "F.Cu")
		(net "GND")
	)
	(segment
		(start 234.460288 -97.658428)
		(end 234.460288 -98.295968)
		(width 0.254)
		(layer "F.Cu")
		(net "GND")
	)
	(segment
		(start 62.664848 -25.990042)
		(end 61.648848 -25.990042)
		(width 0.3556)
		(layer "F.Cu")
		(net "GND")
	)
	(segment
		(start 283.299916 -301.599854)
		(end 283.774896 -302.074834)
		(width 0.249936)
		(layer "F.Cu")
		(net "GND")
	)
	(segment
		(start 419.824916 -299.224954)
		(end 420.299896 -299.699934)
		(width 0.249936)
		(layer "F.Cu")
		(net "GND")
	)
	(segment
		(start 169.940224 -33.248092)
		(end 169.940224 -33.857692)
		(width 0.4572)
		(layer "F.Cu")
		(net "GND")
	)
	(segment
		(start 97.370138 -47.60087)
		(end 97.796096 -47.60087)
		(width 0.254)
		(layer "F.Cu")
		(net "GND")
	)
	(segment
		(start 180.02504 -306.824888)
		(end 180.50002 -306.349908)
		(width 0.249936)
		(layer "F.Cu")
		(net "GND")
	)
	(segment
		(start 274.749768 -290.199826)
		(end 274.274788 -289.724846)
		(width 0.249936)
		(layer "F.Cu")
		(net "GND")
	)
	(segment
		(start 413.649922 -306.349908)
		(end 414.124902 -306.824888)
		(width 0.249936)
		(layer "F.Cu")
		(net "GND")
	)
	(segment
		(start 186.026552 -136.061958)
		(end 185.443368 -136.645142)
		(width 0.3556)
		(layer "F.Cu")
		(net "GND")
	)
	(segment
		(start 282.349702 -288.299906)
		(end 282.824936 -287.824926)
		(width 0.249936)
		(layer "F.Cu")
		(net "GND")
	)
	(segment
		(start 209.364834 -34.990024)
		(end 207.425798 -34.990024)
		(width 0.3556)
		(layer "F.Cu")
		(net "GND")
	)
	(segment
		(start 49.976278 -106.045)
		(end 50.64252 -106.045)
		(width 0.3556)
		(layer "F.Cu")
		(net "GND")
	)
	(segment
		(start 276.174708 -298.27474)
		(end 276.649688 -297.79976)
		(width 0.249936)
		(layer "F.Cu")
		(net "GND")
	)
	(segment
		(start 270.256 -33.19018)
		(end 268.864842 -33.19018)
		(width 0.3556)
		(layer "F.Cu")
		(net "GND")
	)
	(segment
		(start 178.124866 -307.774848)
		(end 177.649886 -307.299868)
		(width 0.249936)
		(layer "F.Cu")
		(net "GND")
	)
	(segment
		(start 62.024768 -297.32478)
		(end 61.549788 -296.8498)
		(width 0.249936)
		(layer "F.Cu")
		(net "GND")
	)
	(segment
		(start 299.866812 -136.645142)
		(end 300.857412 -136.645142)
		(width 0.3556)
		(layer "F.Cu")
		(net "GND")
	)
	(segment
		(start 286.624776 -302.074834)
		(end 286.149796 -301.599854)
		(width 0.249936)
		(layer "F.Cu")
		(net "GND")
	)
	(segment
		(start 397.646652 -110.857538)
		(end 398.234154 -111.44504)
		(width 0.3556)
		(layer "F.Cu")
		(net "GND")
	)
	(segment
		(start 164.349938 -296.8498)
		(end 164.824918 -296.37482)
		(width 0.249936)
		(layer "F.Cu")
		(net "GND")
	)
	(segment
		(start 279.499822 -285.449772)
		(end 279.024842 -284.974792)
		(width 0.249936)
		(layer "F.Cu")
		(net "GND")
	)
	(segment
		(start 144.485614 -34.183066)
		(end 144.37106 -34.29762)
		(width 0.4572)
		(layer "F.Cu")
		(net "GND")
	)
	(segment
		(start 411.750002 -288.299906)
		(end 412.224982 -287.824926)
		(width 0.249936)
		(layer "F.Cu")
		(net "GND")
	)
	(segment
		(start 245.29796 -345.68003)
		(end 248.629678 -345.68003)
		(width 0.4572)
		(layer "F.Cu")
		(net "GND")
	)
	(segment
		(start 143.317468 -388.17804)
		(end 143.317468 -388.478268)
		(width 0.4572)
		(layer "F.Cu")
		(net "GND")
	)
	(segment
		(start 267.083794 -339.413596)
		(end 267.264134 -339.593936)
		(width 0.4572)
		(layer "F.Cu")
		(net "GND")
	)
	(segment
		(start 236.827822 -118.376954)
		(end 238.792766 -118.376954)
		(width 0.254)
		(layer "F.Cu")
		(net "GND")
	)
	(segment
		(start 60.599828 -305.399948)
		(end 60.124848 -305.874928)
		(width 0.249936)
		(layer "F.Cu")
		(net "GND")
	)
	(segment
		(start 197.502526 -89.1159)
		(end 197.502526 -89.790524)
		(width 0.4572)
		(layer "F.Cu")
		(net "GND")
	)
	(segment
		(start 71.999856 -300.649894)
		(end 71.524876 -301.124874)
		(width 0.249936)
		(layer "F.Cu")
		(net "GND")
	)
	(segment
		(start 38.749986 -291.149786)
		(end 38.275006 -290.674806)
		(width 0.249936)
		(layer "F.Cu")
		(net "GND")
	)
	(segment
		(start 402.724874 -285.924752)
		(end 403.199854 -285.449772)
		(width 0.249936)
		(layer "F.Cu")
		(net "GND")
	)
	(segment
		(start 36.6649 -33.19018)
		(end 35.6489 -33.19018)
		(width 0.3556)
		(layer "F.Cu")
		(net "GND")
	)
	(segment
		(start 303.570132 -47.60087)
		(end 303.99609 -47.60087)
		(width 0.254)
		(layer "F.Cu")
		(net "GND")
	)
	(segment
		(start 372.642384 -252.756924)
		(end 372.642384 -253.45644)
		(width 0.4572)
		(layer "F.Cu")
		(net "GND")
	)
	(segment
		(start 203.294996 -59.978036)
		(end 203.294996 -60.633356)
		(width 0.4572)
		(layer "F.Cu")
		(net "GND")
	)
	(segment
		(start 416.499802 -300.649894)
		(end 416.974782 -301.124874)
		(width 0.249936)
		(layer "F.Cu")
		(net "GND")
	)
	(segment
		(start 251.472954 -207.497172)
		(end 251.351542 -207.51165)
		(width 0.4572)
		(layer "F.Cu")
		(net "GND")
	)
	(segment
		(start 410.324808 -305.874928)
		(end 410.799788 -305.399948)
		(width 0.249936)
		(layer "F.Cu")
		(net "GND")
	)
	(segment
		(start 319.39484 -59.978036)
		(end 319.39484 -60.633356)
		(width 0.4572)
		(layer "F.Cu")
		(net "GND")
	)
	(segment
		(start 399.93316 -109.644942)
		(end 398.94256 -109.644942)
		(width 0.3556)
		(layer "F.Cu")
		(net "GND")
	)
	(segment
		(start 221.415102 -45.88891)
		(end 220.74378 -45.88891)
		(width 0.254)
		(layer "F.Cu")
		(net "GND")
	)
	(segment
		(start 139.24661 -255.66624)
		(end 139.24661 -255.669542)
		(width 0.4572)
		(layer "F.Cu")
		(net "GND")
	)
	(segment
		(start 377.657868 -26.606246)
		(end 377.657868 -25.971246)
		(width 0.4572)
		(layer "F.Cu")
		(net "GND")
	)
	(segment
		(start 307.524912 -298.27474)
		(end 307.049932 -297.79976)
		(width 0.249936)
		(layer "F.Cu")
		(net "GND")
	)
	(segment
		(start 38.749986 -296.8498)
		(end 39.224966 -297.32478)
		(width 0.249936)
		(layer "F.Cu")
		(net "GND")
	)
	(segment
		(start 192.375028 -298.27474)
		(end 191.900048 -297.79976)
		(width 0.249936)
		(layer "F.Cu")
		(net "GND")
	)
	(segment
		(start 321.023742 -291.2618)
		(end 321.023742 -291.592)
		(width 0.4572)
		(layer "F.Cu")
		(net "GND")
	)
	(segment
		(start 416.499802 -293.04996)
		(end 416.974782 -292.574726)
		(width 0.249936)
		(layer "F.Cu")
		(net "GND")
	)
	(segment
		(start 117.408706 -316.869318)
		(end 117.408706 -316.238128)
		(width 0.254)
		(layer "F.Cu")
		(net "GND")
	)
	(segment
		(start 413.649922 -285.449772)
		(end 413.174942 -284.974792)
		(width 0.249936)
		(layer "F.Cu")
		(net "GND")
	)
	(segment
		(start 64.399922 -297.79976)
		(end 64.874902 -298.27474)
		(width 0.249936)
		(layer "F.Cu")
		(net "GND")
	)
	(segment
		(start 304.467006 -145.755106)
		(end 305.457606 -145.755106)
		(width 0.3556)
		(layer "F.Cu")
		(net "GND")
	)
	(segment
		(start 153.845006 -27.79014)
		(end 152.764998 -27.79014)
		(width 0.3556)
		(layer "F.Cu")
		(net "GND")
	)
	(segment
		(start 44.92498 -297.32478)
		(end 44.449746 -296.8498)
		(width 0.249936)
		(layer "F.Cu")
		(net "GND")
	)
	(segment
		(start 230.66756 -214.304118)
		(end 231.067356 -213.904322)
		(width 0.381)
		(layer "F.Cu")
		(net "GND")
	)
	(segment
		(start 304.199798 -301.599854)
		(end 304.674778 -301.124874)
		(width 0.249936)
		(layer "F.Cu")
		(net "GND")
	)
	(segment
		(start 253.645924 -46.693836)
		(end 253.11862 -46.693836)
		(width 0.254)
		(layer "F.Cu")
		(net "GND")
	)
	(segment
		(start 49.67478 -306.824888)
		(end 50.14976 -307.299868)
		(width 0.249936)
		(layer "F.Cu")
		(net "GND")
	)
	(segment
		(start 179.55006 -285.449772)
		(end 179.07508 -284.974792)
		(width 0.249936)
		(layer "F.Cu")
		(net "GND")
	)
	(segment
		(start 298.44873 -31.390082)
		(end 299.46473 -31.390082)
		(width 0.3556)
		(layer "F.Cu")
		(net "GND")
	)
	(segment
		(start 99.28987 -73.166732)
		(end 99.28987 -73.85177)
		(width 0.4572)
		(layer "F.Cu")
		(net "GND")
	)
	(segment
		(start 201.203306 -59.971686)
		(end 201.203306 -60.627006)
		(width 0.381)
		(layer "F.Cu")
		(net "GND")
	)
	(segment
		(start 289.94989 -292.099746)
		(end 289.47491 -291.624766)
		(width 0.249936)
		(layer "F.Cu")
		(net "GND")
	)
	(segment
		(start 292.79977 -306.349908)
		(end 293.27475 -305.874928)
		(width 0.249936)
		(layer "F.Cu")
		(net "GND")
	)
	(segment
		(start 287.557718 -26.606246)
		(end 287.557718 -25.971246)
		(width 0.4572)
		(layer "F.Cu")
		(net "GND")
	)
	(segment
		(start 275.224748 -276.424898)
		(end 274.749768 -275.949918)
		(width 0.249936)
		(layer "F.Cu")
		(net "GND")
	)
	(segment
		(start 156.750004 -279.749758)
		(end 156.275024 -279.274778)
		(width 0.249936)
		(layer "F.Cu")
		(net "GND")
	)
	(segment
		(start 121.04751 -37.087048)
		(end 121.68251 -37.087048)
		(width 0.4572)
		(layer "F.Cu")
		(net "GND")
	)
	(segment
		(start 10.054082 -160.70707)
		(end 10.054082 -162.672014)
		(width 0.254)
		(layer "F.Cu")
		(net "GND")
	)
	(segment
		(start 418.399976 -284.499812)
		(end 418.874956 -284.024832)
		(width 0.249936)
		(layer "F.Cu")
		(net "GND")
	)
	(segment
		(start 415.074862 -285.924752)
		(end 415.549842 -285.449772)
		(width 0.249936)
		(layer "F.Cu")
		(net "GND")
	)
	(segment
		(start 299.46473 -29.589984)
		(end 300.48073 -29.589984)
		(width 0.3556)
		(layer "F.Cu")
		(net "GND")
	)
	(segment
		(start 172.789596 -64.312292)
		(end 173.54804 -64.312292)
		(width 0.4572)
		(layer "F.Cu")
		(net "GND")
	)
	(segment
		(start 402.724874 -291.624766)
		(end 403.199854 -292.099746)
		(width 0.249936)
		(layer "F.Cu")
		(net "GND")
	)
	(segment
		(start 404.149814 -284.499812)
		(end 404.624794 -284.974792)
		(width 0.249936)
		(layer "F.Cu")
		(net "GND")
	)
	(segment
		(start 68.679822 -303.969928)
		(end 68.199762 -304.449734)
		(width 0.249936)
		(layer "F.Cu")
		(net "GND")
	)
	(segment
		(start 287.574736 -305.874928)
		(end 287.099756 -306.349908)
		(width 0.249936)
		(layer "F.Cu")
		(net "GND")
	)
	(segment
		(start 163.457636 -102.847394)
		(end 163.0553 -102.445058)
		(width 0.3556)
		(layer "F.Cu")
		(net "GND")
	)
	(segment
		(start 395.17447 -122.355102)
		(end 394.342366 -122.355102)
		(width 0.3556)
		(layer "F.Cu")
		(net "GND")
	)
	(segment
		(start 163.399978 -303.499774)
		(end 162.924998 -303.024794)
		(width 0.249936)
		(layer "F.Cu")
		(net "GND")
	)
	(segment
		(start 267.498576 -136.680956)
		(end 267.938504 -136.241028)
		(width 0.4572)
		(layer "F.Cu")
		(net "GND")
	)
	(segment
		(start 445.318134 -411.100016)
		(end 444.67399 -411.100016)
		(width 0.4572)
		(layer "F.Cu")
		(net "GND")
	)
	(segment
		(start 154.850084 -289.249866)
		(end 154.375104 -288.774886)
		(width 0.249936)
		(layer "F.Cu")
		(net "GND")
	)
	(segment
		(start 279.29205 -104.793034)
		(end 279.29205 -104.404922)
		(width 0.3556)
		(layer "F.Cu")
		(net "GND")
	)
	(segment
		(start 329.045062 -238.262922)
		(end 329.045062 -239.002062)
		(width 0.4572)
		(layer "F.Cu")
		(net "GND")
	)
	(segment
		(start 62.499748 -288.299906)
		(end 62.974982 -287.824926)
		(width 0.249936)
		(layer "F.Cu")
		(net "GND")
	)
	(segment
		(start 417.450016 -305.399948)
		(end 416.974782 -305.874928)
		(width 0.249936)
		(layer "F.Cu")
		(net "GND")
	)
	(segment
		(start 345.179904 -114.22634)
		(end 343.21496 -114.22634)
		(width 0.254)
		(layer "F.Cu")
		(net "GND")
	)
	(segment
		(start 299.449744 -285.449772)
		(end 298.974764 -284.974792)
		(width 0.249936)
		(layer "F.Cu")
		(net "GND")
	)
	(segment
		(start 49.1998 -297.79976)
		(end 48.72482 -298.27474)
		(width 0.249936)
		(layer "F.Cu")
		(net "GND")
	)
	(segment
		(start 82.449924 -303.499774)
		(end 81.974944 -303.024794)
		(width 0.249936)
		(layer "F.Cu")
		(net "GND")
	)
	(segment
		(start 60.124848 -287.899856)
		(end 60.524898 -288.299906)
		(width 0.249936)
		(layer "F.Cu")
		(net "GND")
	)
	(segment
		(start 341.293958 -222.38716)
		(end 341.293958 -222.386906)
		(width 0.381)
		(layer "F.Cu")
		(net "GND")
	)
	(segment
		(start 408.424888 -303.974754)
		(end 408.899868 -303.499774)
		(width 0.249936)
		(layer "F.Cu")
		(net "GND")
	)
	(segment
		(start 197.125082 -293.52494)
		(end 196.649848 -293.04996)
		(width 0.249936)
		(layer "F.Cu")
		(net "GND")
	)
	(segment
		(start 69.149976 -293.99992)
		(end 68.674742 -293.52494)
		(width 0.249936)
		(layer "F.Cu")
		(net "GND")
	)
	(segment
		(start 123.27509 -99.463606)
		(end 122.357896 -99.463606)
		(width 0.4572)
		(layer "F.Cu")
		(net "GND")
	)
	(segment
		(start 363.564932 -27.79014)
		(end 364.580932 -27.79014)
		(width 0.3556)
		(layer "F.Cu")
		(net "GND")
	)
	(segment
		(start 311.799732 -293.04996)
		(end 312.274712 -292.574726)
		(width 0.249936)
		(layer "F.Cu")
		(net "GND")
	)
	(segment
		(start 357.801164 -82.482182)
		(end 357.368348 -82.914998)
		(width 0.381)
		(layer "F.Cu")
		(net "GND")
	)
	(segment
		(start 310.867806 -54.067456)
		(end 311.523126 -54.067456)
		(width 0.254)
		(layer "F.Cu")
		(net "GND")
	)
	(segment
		(start 188.099954 -300.649894)
		(end 188.574934 -300.174914)
		(width 0.249936)
		(layer "F.Cu")
		(net "GND")
	)
	(segment
		(start 303.698402 -65.92189)
		(end 303.698402 -65.15989)
		(width 0.4572)
		(layer "F.Cu")
		(net "GND")
	)
	(segment
		(start 76.74991 -291.149786)
		(end 76.27493 -290.674806)
		(width 0.249936)
		(layer "F.Cu")
		(net "GND")
	)
	(segment
		(start 190.348108 -123.635008)
		(end 189.357508 -123.635008)
		(width 0.3556)
		(layer "F.Cu")
		(net "GND")
	)
	(segment
		(start 200.90003 -38.671754)
		(end 200.90003 -38.315138)
		(width 0.4572)
		(layer "F.Cu")
		(net "GND")
	)
	(segment
		(start 298.974764 -305.874928)
		(end 298.499784 -306.349908)
		(width 0.249936)
		(layer "F.Cu")
		(net "GND")
	)
	(segment
		(start 430.450498 -81.698846)
		(end 429.543718 -81.698846)
		(width 0.4064)
		(layer "F.Cu")
		(net "GND")
	)
	(segment
		(start 229.437438 -64.200024)
		(end 228.314504 -64.200024)
		(width 0.3556)
		(layer "F.Cu")
		(net "GND")
	)
	(segment
		(start 187.467748 -136.645142)
		(end 189.357508 -136.645142)
		(width 0.3556)
		(layer "F.Cu")
		(net "GND")
	)
	(segment
		(start 14.396212 -25.990042)
		(end 14.214856 -26.171398)
		(width 0.3556)
		(layer "F.Cu")
		(net "GND")
	)
	(segment
		(start 425.04995 -302.549814)
		(end 424.57497 -302.074834)
		(width 0.249936)
		(layer "F.Cu")
		(net "GND")
	)
	(segment
		(start 137.35558 -153.1112)
		(end 137.35558 -153.782522)
		(width 0.4064)
		(layer "F.Cu")
		(net "GND")
	)
	(segment
		(start 298.499784 -306.349908)
		(end 298.974764 -306.824888)
		(width 0.249936)
		(layer "F.Cu")
		(net "GND")
	)
	(segment
		(start 393.351766 -111.44504)
		(end 394.342366 -111.44504)
		(width 0.3556)
		(layer "F.Cu")
		(net "GND")
	)
	(segment
		(start 439.33364 -303.636426)
		(end 439.33364 -303.026826)
		(width 0.4572)
		(layer "F.Cu")
		(net "GND")
	)
	(segment
		(start 395.332966 -133.565138)
		(end 394.342366 -133.565138)
		(width 0.3556)
		(layer "F.Cu")
		(net "GND")
	)
	(segment
		(start 61.549788 -306.349908)
		(end 62.024768 -305.874928)
		(width 0.249936)
		(layer "F.Cu")
		(net "GND")
	)
	(segment
		(start 38.749986 -275.949918)
		(end 38.275006 -275.474938)
		(width 0.249936)
		(layer "F.Cu")
		(net "GND")
	)
	(segment
		(start 170.524932 -305.874928)
		(end 170.999912 -306.349908)
		(width 0.249936)
		(layer "F.Cu")
		(net "GND")
	)
	(segment
		(start 181.20995 -198.997062)
		(end 181.20995 -199.651366)
		(width 0.4572)
		(layer "F.Cu")
		(net "GND")
	)
	(segment
		(start 141.45768 -29.784294)
		(end 141.564614 -29.67736)
		(width 0.4572)
		(layer "F.Cu")
		(net "GND")
	)
	(segment
		(start 438.044844 -29.589984)
		(end 436.964836 -29.589984)
		(width 0.3556)
		(layer "F.Cu")
		(net "GND")
	)
	(segment
		(start 275.699728 -284.499812)
		(end 275.224748 -284.024832)
		(width 0.249936)
		(layer "F.Cu")
		(net "GND")
	)
	(segment
		(start 50.14976 -294.94988)
		(end 49.67478 -294.4749)
		(width 0.249936)
		(layer "F.Cu")
		(net "GND")
	)
	(segment
		(start 137.608564 -257.852164)
		(end 137.608564 -258.665472)
		(width 0.4572)
		(layer "F.Cu")
		(net "GND")
	)
	(segment
		(start 396.0749 -292.57498)
		(end 396.54988 -293.04996)
		(width 0.249936)
		(layer "F.Cu")
		(net "GND")
	)
	(segment
		(start 68.199762 -306.349908)
		(end 68.674742 -305.874928)
		(width 0.249936)
		(layer "F.Cu")
		(net "GND")
	)
	(segment
		(start 39.55288 -140.85697)
		(end 39.725346 -141.029436)
		(width 0.4572)
		(layer "F.Cu")
		(net "GND")
	)
	(segment
		(start 164.864796 -98.845116)
		(end 166.742364 -98.845116)
		(width 0.3556)
		(layer "F.Cu")
		(net "GND")
	)
	(segment
		(start 283.299916 -303.499774)
		(end 283.774896 -303.974754)
		(width 0.249936)
		(layer "F.Cu")
		(net "GND")
	)
	(segment
		(start 160.549844 -292.099746)
		(end 160.074864 -291.624766)
		(width 0.249936)
		(layer "F.Cu")
		(net "GND")
	)
	(segment
		(start 51.099974 -285.449772)
		(end 50.624994 -284.974792)
		(width 0.249936)
		(layer "F.Cu")
		(net "GND")
	)
	(segment
		(start 164.349938 -306.349908)
		(end 164.824918 -305.874928)
		(width 0.249936)
		(layer "F.Cu")
		(net "GND")
	)
	(segment
		(start 321.944746 -29.589984)
		(end 320.864738 -29.589984)
		(width 0.3556)
		(layer "F.Cu")
		(net "GND")
	)
	(segment
		(start 184.29986 -298.74972)
		(end 184.77484 -299.224954)
		(width 0.249936)
		(layer "F.Cu")
		(net "GND")
	)
	(segment
		(start 69.624956 -305.874928)
		(end 69.149976 -305.399948)
		(width 0.249936)
		(layer "F.Cu")
		(net "GND")
	)
	(segment
		(start 395.59992 -306.349908)
		(end 395.12494 -306.824888)
		(width 0.249936)
		(layer "F.Cu")
		(net "GND")
	)
	(segment
		(start 292.79977 -297.79976)
		(end 293.27475 -298.27474)
		(width 0.249936)
		(layer "F.Cu")
		(net "GND")
	)
	(segment
		(start 434.440838 -54.163722)
		(end 434.99278 -54.163722)
		(width 0.254)
		(layer "F.Cu")
		(net "GND")
	)
	(segment
		(start 135.470392 -47.60087)
		(end 135.89635 -47.60087)
		(width 0.254)
		(layer "F.Cu")
		(net "GND")
	)
	(segment
		(start 234.855512 -235.128054)
		(end 234.855512 -235.737654)
		(width 0.4572)
		(layer "F.Cu")
		(net "GND")
	)
	(segment
		(start 172.424852 -285.924752)
		(end 172.900086 -285.449772)
		(width 0.249936)
		(layer "F.Cu")
		(net "GND")
	)
	(segment
		(start 277.251668 -111.44504)
		(end 278.242268 -111.44504)
		(width 0.3556)
		(layer "F.Cu")
		(net "GND")
	)
	(segment
		(start 413.174942 -305.874928)
		(end 412.699962 -305.399948)
		(width 0.249936)
		(layer "F.Cu")
		(net "GND")
	)
	(segment
		(start 189.999874 -296.8498)
		(end 189.524894 -296.37482)
		(width 0.249936)
		(layer "F.Cu")
		(net "GND")
	)
	(segment
		(start 300.874684 -285.924752)
		(end 300.399704 -286.399732)
		(width 0.249936)
		(layer "F.Cu")
		(net "GND")
	)
	(segment
		(start 269.049754 -277.849838)
		(end 268.574774 -277.374858)
		(width 0.249936)
		(layer "F.Cu")
		(net "GND")
	)
	(segment
		(start 238.738664 -206.11211)
		(end 238.738664 -205.98511)
		(width 0.4572)
		(layer "F.Cu")
		(net "GND")
	)
	(segment
		(start 423.62501 -298.27474)
		(end 423.15003 -297.79976)
		(width 0.249936)
		(layer "F.Cu")
		(net "GND")
	)
	(segment
		(start 60.049918 -287.899856)
		(end 60.124848 -287.899856)
		(width 0.249936)
		(layer "F.Cu")
		(net "GND")
	)
	(segment
		(start 402.724874 -305.874928)
		(end 403.199854 -305.399948)
		(width 0.249936)
		(layer "F.Cu")
		(net "GND")
	)
	(segment
		(start 406.999948 -284.499812)
		(end 406.524968 -284.024832)
		(width 0.249936)
		(layer "F.Cu")
		(net "GND")
	)
	(segment
		(start 449.830444 -121.80824)
		(end 449.21805 -121.80824)
		(width 0.4572)
		(layer "F.Cu")
		(net "GND")
	)
	(segment
		(start 386.866384 -252.756924)
		(end 386.866384 -253.45644)
		(width 0.4572)
		(layer "F.Cu")
		(net "GND")
	)
	(segment
		(start 269.049754 -274.049744)
		(end 269.524734 -274.524724)
		(width 0.249936)
		(layer "F.Cu")
		(net "GND")
	)
	(segment
		(start 47.29988 -290.199826)
		(end 46.8249 -289.724846)
		(width 0.249936)
		(layer "F.Cu")
		(net "GND")
	)
	(segment
		(start 197.386956 -366.33658)
		(end 197.868794 -366.33658)
		(width 0.254)
		(layer "F.Cu")
		(net "GND")
	)
	(segment
		(start 412.224982 -291.624766)
		(end 412.699962 -292.099746)
		(width 0.249936)
		(layer "F.Cu")
		(net "GND")
	)
	(segment
		(start 161.500058 -283.549852)
		(end 161.025078 -283.074872)
		(width 0.249936)
		(layer "F.Cu")
		(net "GND")
	)
	(segment
		(start 402.724874 -306.824888)
		(end 402.249894 -307.299868)
		(width 0.249936)
		(layer "F.Cu")
		(net "GND")
	)
	(segment
		(start 50.624994 -300.174914)
		(end 51.099974 -299.699934)
		(width 0.249936)
		(layer "F.Cu")
		(net "GND")
	)
	(segment
		(start 49.429162 -107.407456)
		(end 49.866804 -107.845098)
		(width 0.3556)
		(layer "F.Cu")
		(net "GND")
	)
	(segment
		(start 76.74991 -296.8498)
		(end 76.27493 -297.32478)
		(width 0.249936)
		(layer "F.Cu")
		(net "GND")
	)
	(segment
		(start 273.799808 -273.099784)
		(end 273.324828 -272.624804)
		(width 0.249936)
		(layer "F.Cu")
		(net "GND")
	)
	(segment
		(start 47.357792 -102.847394)
		(end 46.955456 -102.445058)
		(width 0.3556)
		(layer "F.Cu")
		(net "GND")
	)
	(segment
		(start 13.994892 -158.705042)
		(end 13.994892 -159.336232)
		(width 0.254)
		(layer "F.Cu")
		(net "GND")
	)
	(segment
		(start 289.94989 -294.94988)
		(end 289.47491 -294.4749)
		(width 0.249936)
		(layer "F.Cu")
		(net "GND")
	)
	(segment
		(start 366.71885 -147.913344)
		(end 366.71885 -147.38604)
		(width 0.254)
		(layer "F.Cu")
		(net "GND")
	)
	(segment
		(start 230.66756 -217.504264)
		(end 231.067356 -217.104468)
		(width 0.381)
		(layer "F.Cu")
		(net "GND")
	)
	(segment
		(start 50.14976 -286.399732)
		(end 49.67478 -285.924752)
		(width 0.249936)
		(layer "F.Cu")
		(net "GND")
	)
	(segment
		(start 321.789298 -295.647872)
		(end 321.789298 -294.727884)
		(width 0.4572)
		(layer "F.Cu")
		(net "GND")
	)
	(segment
		(start 81.499964 -297.79976)
		(end 81.024984 -297.32478)
		(width 0.249936)
		(layer "F.Cu")
		(net "GND")
	)
	(segment
		(start 40.649906 -287.349946)
		(end 40.174926 -286.874966)
		(width 0.249936)
		(layer "F.Cu")
		(net "GND")
	)
	(segment
		(start 184.29986 -284.499812)
		(end 184.77484 -284.974792)
		(width 0.249936)
		(layer "F.Cu")
		(net "GND")
	)
	(segment
		(start 411.445202 -236.032802)
		(end 417.862512 -236.032802)
		(width 0.4572)
		(layer "F.Cu")
		(net "GND")
	)
	(segment
		(start 454.376536 -15.57782)
		(end 454.376536 -15.207234)
		(width 0.4572)
		(layer "F.Cu")
		(net "GND")
	)
	(segment
		(start 402.582634 -28.875736)
		(end 402.582634 -28.47848)
		(width 0.254)
		(layer "F.Cu")
		(net "GND")
	)
	(segment
		(start 237.722664 -206.11211)
		(end 238.738664 -206.11211)
		(width 0.4572)
		(layer "F.Cu")
		(net "GND")
	)
	(segment
		(start 204.923898 -291.2618)
		(end 204.923898 -291.592)
		(width 0.4572)
		(layer "F.Cu")
		(net "GND")
	)
	(segment
		(start 192.850008 -300.649894)
		(end 192.375028 -300.174914)
		(width 0.249936)
		(layer "F.Cu")
		(net "GND")
	)
	(segment
		(start 49.60493 -105.365042)
		(end 49.60493 -105.673652)
		(width 0.3556)
		(layer "F.Cu")
		(net "GND")
	)
	(segment
		(start 365.965994 -284.631384)
		(end 365.75873 -284.42412)
		(width 0.2286)
		(layer "F.Cu")
		(net "GND")
	)
	(segment
		(start 425.653962 -84.332318)
		(end 424.993562 -84.332318)
		(width 0.4064)
		(layer "F.Cu")
		(net "GND")
	)
	(segment
		(start 48.24984 -290.199826)
		(end 47.77486 -289.724846)
		(width 0.249936)
		(layer "F.Cu")
		(net "GND")
	)
	(segment
		(start 55.849774 -306.349908)
		(end 55.374794 -306.824888)
		(width 0.249936)
		(layer "F.Cu")
		(net "GND")
	)
	(segment
		(start 197.600062 -293.99992)
		(end 197.125082 -293.52494)
		(width 0.249936)
		(layer "F.Cu")
		(net "GND")
	)
	(segment
		(start 418.874956 -284.024832)
		(end 419.349936 -284.499812)
		(width 0.249936)
		(layer "F.Cu")
		(net "GND")
	)
	(segment
		(start 366.263936 -173.617128)
		(end 365.197136 -173.617128)
		(width 0.4572)
		(layer "F.Cu")
		(net "GND")
	)
	(segment
		(start 162.14217 -137.16508)
		(end 161.15157 -137.16508)
		(width 0.3556)
		(layer "F.Cu")
		(net "GND")
	)
	(segment
		(start 392.274806 -298.27474)
		(end 392.749786 -297.79976)
		(width 0.249936)
		(layer "F.Cu")
		(net "GND")
	)
	(segment
		(start 137.247122 -53.144166)
		(end 137.247122 -52.592224)
		(width 0.254)
		(layer "F.Cu")
		(net "GND")
	)
	(segment
		(start 186.675014 -286.874966)
		(end 187.149994 -287.349946)
		(width 0.249936)
		(layer "F.Cu")
		(net "GND")
	)
	(segment
		(start 312.462418 -34.29762)
		(end 312.02757 -34.732468)
		(width 0.4572)
		(layer "F.Cu")
		(net "GND")
	)
	(segment
		(start 236.072172 -33.248092)
		(end 236.072172 -33.857692)
		(width 0.4572)
		(layer "F.Cu")
		(net "GND")
	)
	(segment
		(start 295.649904 -285.449772)
		(end 295.174924 -284.974792)
		(width 0.249936)
		(layer "F.Cu")
		(net "GND")
	)
	(segment
		(start 40.649906 -283.549852)
		(end 40.174926 -283.074872)
		(width 0.249936)
		(layer "F.Cu")
		(net "GND")
	)
	(segment
		(start 82.449924 -299.699934)
		(end 82.924904 -299.224954)
		(width 0.249936)
		(layer "F.Cu")
		(net "GND")
	)
	(segment
		(start 220.851222 -148.038312)
		(end 220.241622 -148.038312)
		(width 0.4572)
		(layer "F.Cu")
		(net "GND")
	)
	(segment
		(start 406.524968 -283.074872)
		(end 406.999948 -282.599892)
		(width 0.249936)
		(layer "F.Cu")
		(net "GND")
	)
	(segment
		(start 375.96064 -16.439388)
		(end 376.03684 -16.363188)
		(width 0.4572)
		(layer "F.Cu")
		(net "GND")
	)
	(segment
		(start 395.332966 -131.76504)
		(end 394.342366 -131.76504)
		(width 0.3556)
		(layer "F.Cu")
		(net "GND")
	)
	(segment
		(start 329.900026 -251.367036)
		(end 331.9526 -251.367036)
		(width 0.4572)
		(layer "F.Cu")
		(net "GND")
	)
	(segment
		(start 58.224928 -289.724846)
		(end 58.699908 -290.199826)
		(width 0.249936)
		(layer "F.Cu")
		(net "GND")
	)
	(segment
		(start 283.833062 -122.355102)
		(end 282.842462 -122.355102)
		(width 0.3556)
		(layer "F.Cu")
		(net "GND")
	)
	(segment
		(start 189.524894 -294.4749)
		(end 189.049914 -294.94988)
		(width 0.249936)
		(layer "F.Cu")
		(net "GND")
	)
	(segment
		(start 391.324846 -278.324818)
		(end 391.799826 -278.799798)
		(width 0.249936)
		(layer "F.Cu")
		(net "GND")
	)
	(segment
		(start 164.824918 -306.824888)
		(end 165.299898 -306.349908)
		(width 0.249936)
		(layer "F.Cu")
		(net "GND")
	)
	(segment
		(start 225.738944 -97.96907)
		(end 225.738944 -97.31375)
		(width 0.4064)
		(layer "F.Cu")
		(net "GND")
	)
	(segment
		(start 72.949816 -298.74972)
		(end 73.424796 -299.224954)
		(width 0.249936)
		(layer "F.Cu")
		(net "GND")
	)
	(segment
		(start 243.944902 -27.79014)
		(end 242.864894 -27.79014)
		(width 0.3556)
		(layer "F.Cu")
		(net "GND")
	)
	(segment
		(start 269.999714 -298.74972)
		(end 270.474694 -299.224954)
		(width 0.249936)
		(layer "F.Cu")
		(net "GND")
	)
	(segment
		(start 69.684138 -120.400572)
		(end 69.318632 -120.035066)
		(width 0.3556)
		(layer "F.Cu")
		(net "GND")
	)
	(segment
		(start 13.943838 -303.70018)
		(end 13.649198 -303.99482)
		(width 0.254)
		(layer "F.Cu")
		(net "GND")
	)
	(segment
		(start 404.624794 -293.52494)
		(end 405.100028 -293.99992)
		(width 0.249936)
		(layer "F.Cu")
		(net "GND")
	)
	(segment
		(start 289.47491 -284.974792)
		(end 288.99993 -284.499812)
		(width 0.249936)
		(layer "F.Cu")
		(net "GND")
	)
	(segment
		(start 415.96691 -129.445004)
		(end 416.95751 -129.445004)
		(width 0.3556)
		(layer "F.Cu")
		(net "GND")
	)
	(segment
		(start 269.999714 -286.399732)
		(end 269.524734 -285.924752)
		(width 0.249936)
		(layer "F.Cu")
		(net "GND")
	)
	(segment
		(start 376.40895 -190.627)
		(end 375.793 -190.627)
		(width 0.4572)
		(layer "F.Cu")
		(net "GND")
	)
	(segment
		(start 73.424796 -297.32478)
		(end 72.949816 -297.79976)
		(width 0.249936)
		(layer "F.Cu")
		(net "GND")
	)
	(segment
		(start 170.999912 -283.549852)
		(end 170.524932 -284.024832)
		(width 0.249936)
		(layer "F.Cu")
		(net "GND")
	)
	(segment
		(start 397.02486 -305.874928)
		(end 396.54988 -305.399948)
		(width 0.249936)
		(layer "F.Cu")
		(net "GND")
	)
	(segment
		(start 169.574972 -297.32478)
		(end 169.099992 -297.79976)
		(width 0.249936)
		(layer "F.Cu")
		(net "GND")
	)
	(segment
		(start 99.375722 -123.795028)
		(end 100.031042 -123.795028)
		(width 0.4572)
		(layer "F.Cu")
		(net "GND")
	)
	(segment
		(start 299.19168 -197.838822)
		(end 299.90161 -197.838822)
		(width 0.4572)
		(layer "F.Cu")
		(net "GND")
	)
	(segment
		(start 162.450018 -297.79976)
		(end 161.975038 -298.27474)
		(width 0.249936)
		(layer "F.Cu")
		(net "GND")
	)
	(segment
		(start 429.800004 -297.79976)
		(end 430.274984 -297.32478)
		(width 0.249936)
		(layer "F.Cu")
		(net "GND")
	)
	(segment
		(start 204.081888 -291.258244)
		(end 204.238098 -291.102034)
		(width 0.4572)
		(layer "F.Cu")
		(net "GND")
	)
	(segment
		(start 165.774878 -292.574726)
		(end 165.299898 -292.099746)
		(width 0.249936)
		(layer "F.Cu")
		(net "GND")
	)
	(segment
		(start 269.049754 -298.749466)
		(end 269.049754 -298.74972)
		(width 0.249936)
		(layer "F.Cu")
		(net "GND")
	)
	(segment
		(start 393.351766 -102.445058)
		(end 394.342366 -102.445058)
		(width 0.3556)
		(layer "F.Cu")
		(net "GND")
	)
	(segment
		(start 441.564776 -34.990024)
		(end 442.580776 -34.990024)
		(width 0.3556)
		(layer "F.Cu")
		(net "GND")
	)
	(segment
		(start 61.074808 -285.924752)
		(end 60.599828 -285.449772)
		(width 0.249936)
		(layer "F.Cu")
		(net "GND")
	)
	(segment
		(start 184.77484 -292.574726)
		(end 184.29986 -292.099746)
		(width 0.249936)
		(layer "F.Cu")
		(net "GND")
	)
	(segment
		(start 236.887512 -235.128054)
		(end 236.887512 -235.737654)
		(width 0.4572)
		(layer "F.Cu")
		(net "GND")
	)
	(segment
		(start 396.0749 -305.874928)
		(end 395.59992 -306.349908)
		(width 0.249936)
		(layer "F.Cu")
		(net "GND")
	)
	(segment
		(start 88.138 -291.102034)
		(end 88.664034 -291.102034)
		(width 0.4572)
		(layer "F.Cu")
		(net "GND")
	)
	(segment
		(start 47.77486 -301.124874)
		(end 48.24984 -301.599854)
		(width 0.249936)
		(layer "F.Cu")
		(net "GND")
	)
	(segment
		(start 184.770014 -303.969928)
		(end 184.77992 -303.969928)
		(width 0.249936)
		(layer "F.Cu")
		(net "GND")
	)
	(segment
		(start 452.96709 -57.332626)
		(end 452.96709 -56.354218)
		(width 0.4572)
		(layer "F.Cu")
		(net "GND")
	)
	(segment
		(start 395.59992 -304.449734)
		(end 396.0749 -304.924714)
		(width 0.249936)
		(layer "F.Cu")
		(net "GND")
	)
	(segment
		(start 294.69969 -305.399948)
		(end 295.174924 -305.874928)
		(width 0.249936)
		(layer "F.Cu")
		(net "GND")
	)
	(segment
		(start 361.939332 -239.62106)
		(end 361.939332 -239.21593)
		(width 0.4572)
		(layer "F.Cu")
		(net "GND")
	)
	(segment
		(start 409.374848 -306.824888)
		(end 408.899868 -307.299868)
		(width 0.249936)
		(layer "F.Cu")
		(net "GND")
	)
	(segment
		(start 50.14976 -303.499774)
		(end 50.624994 -303.974754)
		(width 0.249936)
		(layer "F.Cu")
		(net "GND")
	)
	(segment
		(start 170.362626 -34.29762)
		(end 169.927778 -34.732468)
		(width 0.4572)
		(layer "F.Cu")
		(net "GND")
	)
	(segment
		(start 425.52493 -299.224954)
		(end 425.99991 -298.74972)
		(width 0.249936)
		(layer "F.Cu")
		(net "GND")
	)
	(segment
		(start 185.250074 -297.79976)
		(end 185.725054 -297.32478)
		(width 0.249936)
		(layer "F.Cu")
		(net "GND")
	)
	(segment
		(start 215.475566 -117.191028)
		(end 216.086182 -117.191028)
		(width 0.4064)
		(layer "F.Cu")
		(net "GND")
	)
	(segment
		(start 279.489916 -73.166732)
		(end 279.489916 -73.85177)
		(width 0.4572)
		(layer "F.Cu")
		(net "GND")
	)
	(segment
		(start 245.203726 -305.986942)
		(end 244.491256 -305.986942)
		(width 0.4572)
		(layer "F.Cu")
		(net "GND")
	)
	(segment
		(start 83.55203 -142.250922)
		(end 82.721958 -141.42085)
		(width 0.4064)
		(layer "F.Cu")
		(net "GND")
	)
	(segment
		(start 380.419102 -59.974734)
		(end 379.768608 -59.974734)
		(width 0.4572)
		(layer "F.Cu")
		(net "GND")
	)
	(segment
		(start 148.417534 -113.158524)
		(end 144.165828 -113.158524)
		(width 0.4572)
		(layer "F.Cu")
		(net "GND")
	)
	(segment
		(start 390.849866 -281.649932)
		(end 390.374886 -281.174952)
		(width 0.249936)
		(layer "F.Cu")
		(net "GND")
	)
	(segment
		(start 283.774896 -305.874928)
		(end 284.249876 -306.349908)
		(width 0.249936)
		(layer "F.Cu")
		(net "GND")
	)
	(segment
		(start 284.867096 -57.332626)
		(end 284.867096 -56.354218)
		(width 0.4572)
		(layer "F.Cu")
		(net "GND")
	)
	(segment
		(start 78.17485 -289.724846)
		(end 78.64983 -290.199826)
		(width 0.249936)
		(layer "F.Cu")
		(net "GND")
	)
	(segment
		(start 334.772 -240.00714)
		(end 334.86725 -239.91189)
		(width 0.3556)
		(layer "F.Cu")
		(net "GND")
	)
	(segment
		(start 426.72508 -14.735302)
		(end 426.72508 -14.100302)
		(width 0.381)
		(layer "F.Cu")
		(net "GND")
	)
	(segment
		(start 400.967956 -55.083456)
		(end 401.623276 -55.083456)
		(width 0.254)
		(layer "F.Cu")
		(net "GND")
	)
	(segment
		(start 384.612134 -136.81456)
		(end 384.038602 -136.241028)
		(width 0.4572)
		(layer "F.Cu")
		(net "GND")
	)
	(segment
		(start 431.994056 -35.264852)
		(end 431.994056 -35.499548)
		(width 0.4572)
		(layer "F.Cu")
		(net "GND")
	)
	(segment
		(start 278.549862 -293.99992)
		(end 278.074882 -293.52494)
		(width 0.249936)
		(layer "F.Cu")
		(net "GND")
	)
	(segment
		(start 52.524914 -305.874928)
		(end 52.999894 -305.399948)
		(width 0.249936)
		(layer "F.Cu")
		(net "GND")
	)
	(segment
		(start 416.499802 -306.349908)
		(end 416.974782 -306.824888)
		(width 0.249936)
		(layer "F.Cu")
		(net "GND")
	)
	(segment
		(start 48.72482 -304.924714)
		(end 48.24984 -304.449734)
		(width 0.249936)
		(layer "F.Cu")
		(net "GND")
	)
	(segment
		(start 152.94991 -274.049744)
		(end 153.42489 -274.524724)
		(width 0.249936)
		(layer "F.Cu")
		(net "GND")
	)
	(segment
		(start 239.205008 -89.225374)
		(end 239.720882 -89.225374)
		(width 0.4572)
		(layer "F.Cu")
		(net "GND")
	)
	(segment
		(start 400.967194 -56.354218)
		(end 400.967956 -56.353456)
		(width 0.4572)
		(layer "F.Cu")
		(net "GND")
	)
	(segment
		(start 229.794816 -79.405734)
		(end 229.09911 -79.405734)
		(width 0.2032)
		(layer "F.Cu")
		(net "GND")
	)
	(segment
		(start 69.149976 -297.79976)
		(end 69.624956 -298.27474)
		(width 0.249936)
		(layer "F.Cu")
		(net "GND")
	)
	(segment
		(start 295.174924 -289.724846)
		(end 295.649904 -290.199826)
		(width 0.249936)
		(layer "F.Cu")
		(net "GND")
	)
	(segment
		(start 223.186244 -174.49038)
		(end 222.576644 -174.49038)
		(width 0.4572)
		(layer "F.Cu")
		(net "GND")
	)
	(segment
		(start 416.499802 -305.399948)
		(end 416.024822 -305.874928)
		(width 0.249936)
		(layer "F.Cu")
		(net "GND")
	)
	(segment
		(start 164.824918 -296.37482)
		(end 165.299898 -295.89984)
		(width 0.249936)
		(layer "F.Cu")
		(net "GND")
	)
	(segment
		(start 240.568226 -319.392554)
		(end 240.568226 -320.02349)
		(width 0.381)
		(layer "F.Cu")
		(net "GND")
	)
	(segment
		(start 86.94039 -143.582898)
		(end 84.884006 -143.582898)
		(width 0.4572)
		(layer "F.Cu")
		(net "GND")
	)
	(segment
		(start 417.94811 -142.15491)
		(end 416.95751 -142.15491)
		(width 0.3556)
		(layer "F.Cu")
		(net "GND")
	)
	(segment
		(start 395.59992 -303.499774)
		(end 395.12494 -303.974754)
		(width 0.249936)
		(layer "F.Cu")
		(net "GND")
	)
	(segment
		(start 166.249858 -294.94988)
		(end 165.774878 -294.4749)
		(width 0.249936)
		(layer "F.Cu")
		(net "GND")
	)
	(segment
		(start 411.275022 -306.824888)
		(end 410.799788 -307.299868)
		(width 0.249936)
		(layer "F.Cu")
		(net "GND")
	)
	(segment
		(start 400.349974 -290.199826)
		(end 399.874994 -289.724846)
		(width 0.249936)
		(layer "F.Cu")
		(net "GND")
	)
	(segment
		(start 171.950126 -296.8498)
		(end 171.949872 -296.8498)
		(width 0.249936)
		(layer "F.Cu")
		(net "GND")
	)
	(segment
		(start 310.374792 -293.52494)
		(end 310.849772 -293.04996)
		(width 0.249936)
		(layer "F.Cu")
		(net "GND")
	)
	(segment
		(start 241.848894 -31.390082)
		(end 242.864894 -31.390082)
		(width 0.3556)
		(layer "F.Cu")
		(net "GND")
	)
	(segment
		(start 383.598674 -136.680956)
		(end 383.598674 -136.859264)
		(width 0.4572)
		(layer "F.Cu")
		(net "GND")
	)
	(segment
		(start 371.30609 -241.54892)
		(end 371.556026 -241.298984)
		(width 0.4572)
		(layer "F.Cu")
		(net "GND")
	)
	(segment
		(start 231.46766 -217.504264)
		(end 231.867456 -217.104468)
		(width 0.381)
		(layer "F.Cu")
		(net "GND")
	)
	(segment
		(start 373.552974 -246.888)
		(end 372.999 -247.441974)
		(width 0.4572)
		(layer "F.Cu")
		(net "GND")
	)
	(segment
		(start 160.994344 -152.958038)
		(end 160.996376 -152.96007)
		(width 0.3556)
		(layer "F.Cu")
		(net "GND")
	)
	(segment
		(start 169.099992 -299.699934)
		(end 169.574972 -300.174914)
		(width 0.249936)
		(layer "F.Cu")
		(net "GND")
	)
	(segment
		(start 324.595998 -25.990042)
		(end 325.464678 -25.990042)
		(width 0.3556)
		(layer "F.Cu")
		(net "GND")
	)
	(segment
		(start 347.693742 -219.987114)
		(end 348.093538 -220.38691)
		(width 0.381)
		(layer "F.Cu")
		(net "GND")
	)
	(segment
		(start 428.84979 -298.74972)
		(end 428.37481 -298.27474)
		(width 0.249936)
		(layer "F.Cu")
		(net "GND")
	)
	(segment
		(start 184.77484 -291.624766)
		(end 184.29986 -292.099746)
		(width 0.249936)
		(layer "F.Cu")
		(net "GND")
	)
	(segment
		(start 181.92496 -300.174914)
		(end 181.44998 -299.699934)
		(width 0.249936)
		(layer "F.Cu")
		(net "GND")
	)
	(segment
		(start 402.249894 -286.399732)
		(end 401.774914 -285.924752)
		(width 0.249936)
		(layer "F.Cu")
		(net "GND")
	)
	(segment
		(start 191.900048 -303.499774)
		(end 192.850008 -302.549814)
		(width 0.249936)
		(layer "F.Cu")
		(net "GND")
	)
	(segment
		(start 58.595006 -99.750372)
		(end 57.979818 -99.750372)
		(width 0.4064)
		(layer "F.Cu")
		(net "GND")
	)
	(segment
		(start 405.100028 -284.499812)
		(end 404.624794 -284.024832)
		(width 0.249936)
		(layer "F.Cu")
		(net "GND")
	)
	(segment
		(start 51.63312 -104.244902)
		(end 50.64252 -104.244902)
		(width 0.3556)
		(layer "F.Cu")
		(net "GND")
	)
	(segment
		(start 373.761 -181.88305)
		(end 374.50395 -181.88305)
		(width 0.4572)
		(layer "F.Cu")
		(net "GND")
	)
	(segment
		(start 63.924942 -305.874928)
		(end 63.449962 -305.399948)
		(width 0.249936)
		(layer "F.Cu")
		(net "GND")
	)
	(segment
		(start 196.550788 -414.0581)
		(end 196.550788 -413.364172)
		(width 0.4572)
		(layer "F.Cu")
		(net "GND")
	)
	(segment
		(start 422.199816 -302.549814)
		(end 422.674796 -302.074834)
		(width 0.249936)
		(layer "F.Cu")
		(net "GND")
	)
	(segment
		(start 176.699926 -301.599854)
		(end 176.224946 -302.074834)
		(width 0.249936)
		(layer "F.Cu")
		(net "GND")
	)
	(segment
		(start 412.224982 -305.874928)
		(end 412.699962 -306.349908)
		(width 0.249936)
		(layer "F.Cu")
		(net "GND")
	)
	(segment
		(start 187.149994 -298.74972)
		(end 187.624974 -299.224954)
		(width 0.249936)
		(layer "F.Cu")
		(net "GND")
	)
	(segment
		(start 227.04679 -278.041862)
		(end 226.790504 -278.041862)
		(width 0.254)
		(layer "F.Cu")
		(net "GND")
	)
	(segment
		(start 58.309002 -27.04973)
		(end 57.649872 -27.04973)
		(width 0.4572)
		(layer "F.Cu")
		(net "GND")
	)
	(segment
		(start 232.244646 -274.487386)
		(end 232.854246 -274.487386)
		(width 0.4572)
		(layer "F.Cu")
		(net "GND")
	)
	(segment
		(start 67.249802 -285.449772)
		(end 66.774822 -284.974792)
		(width 0.249936)
		(layer "F.Cu")
		(net "GND")
	)
	(segment
		(start 427.89983 -293.04996)
		(end 427.42485 -292.574726)
		(width 0.249936)
		(layer "F.Cu")
		(net "GND")
	)
	(segment
		(start 105.319068 -87.779098)
		(end 105.011728 -88.086438)
		(width 0.1778)
		(layer "F.Cu")
		(net "GND")
	)
	(segment
		(start 311.324752 -292.574726)
		(end 310.849772 -293.04996)
		(width 0.249936)
		(layer "F.Cu")
		(net "GND")
	)
	(segment
		(start 46.34992 -283.549852)
		(end 45.87494 -283.074872)
		(width 0.249936)
		(layer "F.Cu")
		(net "GND")
	)
	(segment
		(start 4.872736 -37.395912)
		(end 4.872736 -36.760912)
		(width 0.4572)
		(layer "F.Cu")
		(net "GND")
	)
	(segment
		(start 402.724874 -305.874928)
		(end 402.249894 -306.349908)
		(width 0.249936)
		(layer "F.Cu")
		(net "GND")
	)
	(segment
		(start 242.605306 -228.57206)
		(end 242.605306 -228.920548)
		(width 0.4572)
		(layer "F.Cu")
		(net "GND")
	)
	(segment
		(start 247.886728 -111.739426)
		(end 247.886728 -111.127032)
		(width 0.4572)
		(layer "F.Cu")
		(net "GND")
	)
	(segment
		(start 177.174906 -305.874928)
		(end 177.649886 -305.399948)
		(width 0.249936)
		(layer "F.Cu")
		(net "GND")
	)
	(segment
		(start 183.766714 -131.245102)
		(end 184.757314 -131.245102)
		(width 0.3556)
		(layer "F.Cu")
		(net "GND")
	)
	(segment
		(start 380.789434 -62.812168)
		(end 381.599948 -62.812168)
		(width 0.4572)
		(layer "F.Cu")
		(net "GND")
	)
	(segment
		(start 399.400014 -297.79976)
		(end 398.925034 -298.27474)
		(width 0.249936)
		(layer "F.Cu")
		(net "GND")
	)
	(segment
		(start 311.324752 -298.27474)
		(end 310.849772 -298.74972)
		(width 0.249936)
		(layer "F.Cu")
		(net "GND")
	)
	(segment
		(start 36.849812 -288.299906)
		(end 36.374832 -287.824926)
		(width 0.249936)
		(layer "F.Cu")
		(net "GND")
	)
	(segment
		(start 47.29988 -305.399694)
		(end 47.77486 -304.924714)
		(width 0.254)
		(layer "F.Cu")
		(net "GND")
	)
	(segment
		(start 296.599864 -286.399732)
		(end 296.124884 -285.924752)
		(width 0.249936)
		(layer "F.Cu")
		(net "GND")
	)
	(segment
		(start 394.17498 -297.32478)
		(end 394.64996 -297.79976)
		(width 0.249936)
		(layer "F.Cu")
		(net "GND")
	)
	(segment
		(start 249.711718 -145.837656)
		(end 249.37593 -145.501868)
		(width 0.4064)
		(layer "F.Cu")
		(net "GND")
	)
	(segment
		(start 131.407662 -154.510994)
		(end 132.04825 -154.510994)
		(width 0.4572)
		(layer "F.Cu")
		(net "GND")
	)
	(segment
		(start 193.56451 -29.079952)
		(end 193.56451 -29.72816)
		(width 0.4572)
		(layer "F.Cu")
		(net "GND")
	)
	(segment
		(start 185.594498 -118.234968)
		(end 184.757314 -118.234968)
		(width 0.3556)
		(layer "F.Cu")
		(net "GND")
	)
	(segment
		(start 281.399742 -299.699934)
		(end 281.874722 -299.224954)
		(width 0.249936)
		(layer "F.Cu")
		(net "GND")
	)
	(segment
		(start 48.24984 -298.74972)
		(end 47.77486 -299.224954)
		(width 0.249936)
		(layer "F.Cu")
		(net "GND")
	)
	(segment
		(start 405.575008 -287.824926)
		(end 406.049988 -288.299906)
		(width 0.249936)
		(layer "F.Cu")
		(net "GND")
	)
	(segment
		(start 144.261332 -389.18896)
		(end 144.02816 -389.18896)
		(width 0.4572)
		(layer "F.Cu")
		(net "GND")
	)
	(segment
		(start 99.375722 -122.525028)
		(end 99.987608 -122.525028)
		(width 0.4064)
		(layer "F.Cu")
		(net "GND")
	)
	(segment
		(start 409.849828 -301.599854)
		(end 410.324808 -302.074834)
		(width 0.249936)
		(layer "F.Cu")
		(net "GND")
	)
	(segment
		(start 385.624578 -298.27474)
		(end 386.099812 -298.74972)
		(width 0.249936)
		(layer "F.Cu")
		(net "GND")
	)
	(segment
		(start 292.32479 -291.624766)
		(end 292.79977 -292.099746)
		(width 0.249936)
		(layer "F.Cu")
		(net "GND")
	)
	(segment
		(start 418.874956 -301.124874)
		(end 418.399976 -301.599854)
		(width 0.249936)
		(layer "F.Cu")
		(net "GND")
	)
	(segment
		(start 279.024842 -300.174914)
		(end 278.549862 -300.649894)
		(width 0.249936)
		(layer "F.Cu")
		(net "GND")
	)
	(segment
		(start 306.574698 -292.574726)
		(end 307.049932 -292.099746)
		(width 0.249936)
		(layer "F.Cu")
		(net "GND")
	)
	(segment
		(start 239.47247 -56.20512)
		(end 239.47247 -56.86044)
		(width 0.381)
		(layer "F.Cu")
		(net "GND")
	)
	(segment
		(start 71.049896 -302.549814)
		(end 70.574916 -303.024794)
		(width 0.249936)
		(layer "F.Cu")
		(net "GND")
	)
	(segment
		(start 314.649866 -301.599854)
		(end 315.124846 -301.124874)
		(width 0.249936)
		(layer "F.Cu")
		(net "GND")
	)
	(segment
		(start 284.724856 -306.824888)
		(end 285.199836 -306.349908)
		(width 0.249936)
		(layer "F.Cu")
		(net "GND")
	)
	(segment
		(start 82.150458 -81.698846)
		(end 81.243678 -81.698846)
		(width 0.4064)
		(layer "F.Cu")
		(net "GND")
	)
	(segment
		(start 244.543326 -117.211348)
		(end 244.543326 -116.450364)
		(width 0.4572)
		(layer "F.Cu")
		(net "GND")
	)
	(segment
		(start 170.524932 -284.974792)
		(end 170.049952 -284.499812)
		(width 0.249936)
		(layer "F.Cu")
		(net "GND")
	)
	(segment
		(start 72.949816 -296.8498)
		(end 73.424796 -297.32478)
		(width 0.249936)
		(layer "F.Cu")
		(net "GND")
	)
	(segment
		(start 427.89983 -304.449734)
		(end 426.94987 -303.499774)
		(width 0.249936)
		(layer "F.Cu")
		(net "GND")
	)
	(segment
		(start 180.50002 -290.199826)
		(end 180.02504 -289.724846)
		(width 0.249936)
		(layer "F.Cu")
		(net "GND")
	)
	(segment
		(start 419.349936 -285.449772)
		(end 418.874956 -285.924752)
		(width 0.249936)
		(layer "F.Cu")
		(net "GND")
	)
	(segment
		(start 298.499784 -299.699934)
		(end 298.974764 -300.174914)
		(width 0.249936)
		(layer "F.Cu")
		(net "GND")
	)
	(segment
		(start 200.589388 -62.812168)
		(end 201.399902 -62.812168)
		(width 0.4572)
		(layer "F.Cu")
		(net "GND")
	)
	(segment
		(start 161.15157 -122.355102)
		(end 162.14217 -122.355102)
		(width 0.3556)
		(layer "F.Cu")
		(net "GND")
	)
	(segment
		(start 270.407892 -156.3624)
		(end 269.772892 -156.3624)
		(width 0.4064)
		(layer "F.Cu")
		(net "GND")
	)
	(segment
		(start 267.905992 -114.4905)
		(end 266.897358 -114.4905)
		(width 0.4572)
		(layer "F.Cu")
		(net "GND")
	)
	(segment
		(start 306.574698 -294.4749)
		(end 307.049932 -293.99992)
		(width 0.249936)
		(layer "F.Cu")
		(net "GND")
	)
	(segment
		(start 295.649904 -307.299868)
		(end 296.124884 -306.824888)
		(width 0.249936)
		(layer "F.Cu")
		(net "GND")
	)
	(segment
		(start 238.48822 -56.208168)
		(end 237.837726 -56.208168)
		(width 0.4572)
		(layer "F.Cu")
		(net "GND")
	)
	(segment
		(start 419.667944 -136.645142)
		(end 421.557704 -136.645142)
		(width 0.3556)
		(layer "F.Cu")
		(net "GND")
	)
	(segment
		(start 38.749986 -287.349946)
		(end 38.275006 -286.874966)
		(width 0.249936)
		(layer "F.Cu")
		(net "GND")
	)
	(segment
		(start 152.764998 -27.79014)
		(end 151.748998 -27.79014)
		(width 0.3556)
		(layer "F.Cu")
		(net "GND")
	)
	(segment
		(start 324.448678 -27.79014)
		(end 325.464678 -27.79014)
		(width 0.3556)
		(layer "F.Cu")
		(net "GND")
	)
	(segment
		(start 209.364834 -25.990042)
		(end 210.380834 -25.990042)
		(width 0.3556)
		(layer "F.Cu")
		(net "GND")
	)
	(segment
		(start 300.399704 -291.149786)
		(end 300.874684 -290.674806)
		(width 0.249936)
		(layer "F.Cu")
		(net "GND")
	)
	(segment
		(start 269.999714 -291.149786)
		(end 269.524734 -290.674806)
		(width 0.249936)
		(layer "F.Cu")
		(net "GND")
	)
	(segment
		(start 283.774896 -303.974754)
		(end 284.249876 -303.499774)
		(width 0.249936)
		(layer "F.Cu")
		(net "GND")
	)
	(segment
		(start 416.499802 -307.299868)
		(end 416.024822 -306.824888)
		(width 0.249936)
		(layer "F.Cu")
		(net "GND")
	)
	(segment
		(start 43.499786 -290.199826)
		(end 43.024806 -289.724846)
		(width 0.249936)
		(layer "F.Cu")
		(net "GND")
	)
	(segment
		(start 180.50002 -285.449772)
		(end 180.02504 -285.924752)
		(width 0.249936)
		(layer "F.Cu")
		(net "GND")
	)
	(segment
		(start 70.099936 -298.74972)
		(end 70.574916 -299.224954)
		(width 0.249936)
		(layer "F.Cu")
		(net "GND")
	)
	(segment
		(start 178.764946 -27.79014)
		(end 177.748946 -27.79014)
		(width 0.3556)
		(layer "F.Cu")
		(net "GND")
	)
	(segment
		(start 244.221762 -178.119278)
		(end 243.217954 -178.119278)
		(width 0.4572)
		(layer "F.Cu")
		(net "GND")
	)
	(segment
		(start 109.234986 -285.488634)
		(end 108.946188 -285.199836)
		(width 0.2286)
		(layer "F.Cu")
		(net "GND")
	)
	(segment
		(start 438.339484 -96.411542)
		(end 438.339484 -95.801942)
		(width 0.381)
		(layer "F.Cu")
		(net "GND")
	)
	(segment
		(start 166.249858 -293.04996)
		(end 166.725092 -293.52494)
		(width 0.249936)
		(layer "F.Cu")
		(net "GND")
	)
	(segment
		(start 26.643838 -45.88891)
		(end 27.31516 -45.88891)
		(width 0.254)
		(layer "F.Cu")
		(net "GND")
	)
	(segment
		(start 196.649848 -291.149786)
		(end 196.174868 -290.674806)
		(width 0.249936)
		(layer "F.Cu")
		(net "GND")
	)
	(segment
		(start 162.450018 -299.699934)
		(end 161.975038 -299.224954)
		(width 0.249936)
		(layer "F.Cu")
		(net "GND")
	)
	(segment
		(start 156.750004 -293.99992)
		(end 156.275024 -293.52494)
		(width 0.249936)
		(layer "F.Cu")
		(net "GND")
	)
	(segment
		(start 45.39996 -300.649894)
		(end 44.92498 -301.124874)
		(width 0.249936)
		(layer "F.Cu")
		(net "GND")
	)
	(segment
		(start 275.699728 -282.599892)
		(end 275.224748 -282.124912)
		(width 0.249936)
		(layer "F.Cu")
		(net "GND")
	)
	(segment
		(start 278.549862 -285.449772)
		(end 278.074882 -284.974792)
		(width 0.249936)
		(layer "F.Cu")
		(net "GND")
	)
	(segment
		(start 93.0656 -303.636426)
		(end 93.704918 -303.636426)
		(width 0.4572)
		(layer "F.Cu")
		(net "GND")
	)
	(segment
		(start 185.250074 -306.349908)
		(end 185.725054 -306.824888)
		(width 0.249936)
		(layer "F.Cu")
		(net "GND")
	)
	(segment
		(start 302.774858 -302.074834)
		(end 302.299878 -301.599854)
		(width 0.249936)
		(layer "F.Cu")
		(net "GND")
	)
	(segment
		(start 284.249876 -286.399732)
		(end 283.774896 -285.924752)
		(width 0.249936)
		(layer "F.Cu")
		(net "GND")
	)
	(segment
		(start 178.124866 -306.824888)
		(end 177.649886 -307.299868)
		(width 0.249936)
		(layer "F.Cu")
		(net "GND")
	)
	(segment
		(start 147.554442 -252.756924)
		(end 147.554442 -253.45644)
		(width 0.4572)
		(layer "F.Cu")
		(net "GND")
	)
	(segment
		(start 424.09999 -290.199826)
		(end 424.57497 -290.674806)
		(width 0.249936)
		(layer "F.Cu")
		(net "GND")
	)
	(segment
		(start 408.424888 -287.899856)
		(end 408.824938 -288.299906)
		(width 0.249936)
		(layer "F.Cu")
		(net "GND")
	)
	(segment
		(start 272.374868 -284.974792)
		(end 272.849848 -285.449772)
		(width 0.249936)
		(layer "F.Cu")
		(net "GND")
	)
	(segment
		(start 161.15157 -109.644942)
		(end 162.14217 -109.644942)
		(width 0.3556)
		(layer "F.Cu")
		(net "GND")
	)
	(segment
		(start 184.29986 -290.199826)
		(end 184.77484 -289.724846)
		(width 0.249936)
		(layer "F.Cu")
		(net "GND")
	)
	(segment
		(start 155.800044 -285.449772)
		(end 155.325064 -284.974792)
		(width 0.249936)
		(layer "F.Cu")
		(net "GND")
	)
	(segment
		(start 29.357828 -26.606246)
		(end 29.357828 -25.971246)
		(width 0.4572)
		(layer "F.Cu")
		(net "GND")
	)
	(segment
		(start 17.604486 -268.134084)
		(end 17.604486 -269.429992)
		(width 0.254)
		(layer "F.Cu")
		(net "GND")
	)
	(segment
		(start 75.79995 -295.89984)
		(end 76.27493 -296.37482)
		(width 0.249936)
		(layer "F.Cu")
		(net "GND")
	)
	(segment
		(start 63.924942 -306.824888)
		(end 63.449962 -307.299868)
		(width 0.249936)
		(layer "F.Cu")
		(net "GND")
	)
	(segment
		(start 385.149852 -278.799798)
		(end 384.674872 -278.324818)
		(width 0.249936)
		(layer "F.Cu")
		(net "GND")
	)
	(segment
		(start 400.349974 -301.599854)
		(end 399.874994 -302.074834)
		(width 0.249936)
		(layer "F.Cu")
		(net "GND")
	)
	(segment
		(start 406.289002 -87.305642)
		(end 407.044398 -87.305642)
		(width 0.4572)
		(layer "F.Cu")
		(net "GND")
	)
	(segment
		(start 173.375066 -294.4749)
		(end 172.900086 -293.99992)
		(width 0.249936)
		(layer "F.Cu")
		(net "GND")
	)
	(segment
		(start 128.566164 -214.540846)
		(end 128.504188 -214.540846)
		(width 0.4572)
		(layer "F.Cu")
		(net "GND")
	)
	(segment
		(start 405.100028 -286.399732)
		(end 405.575008 -285.924752)
		(width 0.249936)
		(layer "F.Cu")
		(net "GND")
	)
	(segment
		(start 397.97482 -287.824926)
		(end 398.4498 -288.299906)
		(width 0.249936)
		(layer "F.Cu")
		(net "GND")
	)
	(segment
		(start 241.3254 -216.80805)
		(end 241.07013 -216.80805)
		(width 0.4572)
		(layer "F.Cu")
		(net "GND")
	)
	(segment
		(start 353.994212 -35.264852)
		(end 353.994212 -35.499548)
		(width 0.4572)
		(layer "F.Cu")
		(net "GND")
	)
	(segment
		(start 130.38074 -118.779036)
		(end 130.38074 -119.39143)
		(width 0.4572)
		(layer "F.Cu")
		(net "GND")
	)
	(segment
		(start 58.595006 -102.798372)
		(end 57.979818 -102.798372)
		(width 0.4064)
		(layer "F.Cu")
		(net "GND")
	)
	(segment
		(start 53.949854 -286.399732)
		(end 53.474874 -285.924752)
		(width 0.249936)
		(layer "F.Cu")
		(net "GND")
	)
	(segment
		(start 402.724874 -293.52494)
		(end 403.199854 -293.99992)
		(width 0.249936)
		(layer "F.Cu")
		(net "GND")
	)
	(segment
		(start 19.774916 -48.753014)
		(end 19.068288 -48.753014)
		(width 0.254)
		(layer "F.Cu")
		(net "GND")
	)
	(segment
		(start 186.200034 -284.499812)
		(end 186.675014 -284.024832)
		(width 0.249936)
		(layer "F.Cu")
		(net "GND")
	)
	(segment
		(start 257.558286 -252.756924)
		(end 257.558286 -253.45644)
		(width 0.4572)
		(layer "F.Cu")
		(net "GND")
	)
	(segment
		(start 189.524894 -298.27474)
		(end 189.999874 -297.79976)
		(width 0.249936)
		(layer "F.Cu")
		(net "GND")
	)
	(segment
		(start 360.25836 -259.142484)
		(end 360.25836 -258.131564)
		(width 0.4572)
		(layer "F.Cu")
		(net "GND")
	)
	(segment
		(start 118.371112 -34.29762)
		(end 118.36273 -34.29762)
		(width 0.4572)
		(layer "F.Cu")
		(net "GND")
	)
	(segment
		(start 404.149814 -288.299906)
		(end 404.624794 -287.824926)
		(width 0.249936)
		(layer "F.Cu")
		(net "GND")
	)
	(segment
		(start 164.349938 -306.349908)
		(end 163.874958 -306.824888)
		(width 0.249936)
		(layer "F.Cu")
		(net "GND")
	)
	(segment
		(start 182.87492 -285.924752)
		(end 182.39994 -286.399732)
		(width 0.249936)
		(layer "F.Cu")
		(net "GND")
	)
	(segment
		(start 189.999874 -297.79976)
		(end 189.524894 -297.32478)
		(width 0.249936)
		(layer "F.Cu")
		(net "GND")
	)
	(segment
		(start 240.521998 -85.551518)
		(end 241.252502 -85.551518)
		(width 0.4572)
		(layer "F.Cu")
		(net "GND")
	)
	(segment
		(start 420.774876 -292.574726)
		(end 421.249856 -293.04996)
		(width 0.249936)
		(layer "F.Cu")
		(net "GND")
	)
	(segment
		(start 232.823512 -235.128054)
		(end 232.823512 -235.737654)
		(width 0.4572)
		(layer "F.Cu")
		(net "GND")
	)
	(segment
		(start 73.424796 -294.4749)
		(end 73.899776 -294.94988)
		(width 0.249936)
		(layer "F.Cu")
		(net "GND")
	)
	(segment
		(start 179.55006 -290.199826)
		(end 179.07508 -289.724846)
		(width 0.249936)
		(layer "F.Cu")
		(net "GND")
	)
	(segment
		(start 363.282738 -228.67493)
		(end 363.122718 -228.67493)
		(width 0.4572)
		(layer "F.Cu")
		(net "GND")
	)
	(segment
		(start 131.36499 -31.390082)
		(end 132.38099 -31.390082)
		(width 0.3556)
		(layer "F.Cu")
		(net "GND")
	)
	(segment
		(start 139.408408 -255.83134)
		(end 139.408408 -256.35204)
		(width 0.4572)
		(layer "F.Cu")
		(net "GND")
	)
	(segment
		(start 49.67478 -299.224954)
		(end 50.14976 -298.74972)
		(width 0.249936)
		(layer "F.Cu")
		(net "GND")
	)
	(segment
		(start 284.724856 -303.974754)
		(end 285.199836 -303.499774)
		(width 0.249936)
		(layer "F.Cu")
		(net "GND")
	)
	(segment
		(start 374.968008 -55.083456)
		(end 375.623328 -55.083456)
		(width 0.254)
		(layer "F.Cu")
		(net "GND")
	)
	(segment
		(start 71.999856 -300.649894)
		(end 72.474836 -300.174914)
		(width 0.249936)
		(layer "F.Cu")
		(net "GND")
	)
	(segment
		(start 421.724836 -299.224954)
		(end 422.199816 -298.74972)
		(width 0.249936)
		(layer "F.Cu")
		(net "GND")
	)
	(segment
		(start 410.799788 -306.349908)
		(end 411.275022 -306.824888)
		(width 0.249936)
		(layer "F.Cu")
		(net "GND")
	)
	(segment
		(start 287.574736 -287.824926)
		(end 287.099756 -288.299906)
		(width 0.249936)
		(layer "F.Cu")
		(net "GND")
	)
	(segment
		(start 421.724836 -294.4749)
		(end 421.249856 -294.94988)
		(width 0.249936)
		(layer "F.Cu")
		(net "GND")
	)
	(segment
		(start 293.27475 -307.774848)
		(end 293.74973 -307.299868)
		(width 0.249936)
		(layer "F.Cu")
		(net "GND")
	)
	(segment
		(start 167.200072 -286.399732)
		(end 166.725092 -285.924752)
		(width 0.249936)
		(layer "F.Cu")
		(net "GND")
	)
	(segment
		(start 151.748998 -31.390082)
		(end 152.764998 -31.390082)
		(width 0.3556)
		(layer "F.Cu")
		(net "GND")
	)
	(segment
		(start 295.649904 -307.299868)
		(end 295.174924 -306.824888)
		(width 0.249936)
		(layer "F.Cu")
		(net "GND")
	)
	(segment
		(start 83.434174 -2.998724)
		(end 84.04987 -2.998724)
		(width 0.4572)
		(layer "F.Cu")
		(net "GND")
	)
	(segment
		(start 200.6346 -38.937184)
		(end 200.90003 -38.671754)
		(width 0.4572)
		(layer "F.Cu")
		(net "GND")
	)
	(segment
		(start 73.424796 -294.4749)
		(end 72.949816 -293.99992)
		(width 0.249936)
		(layer "F.Cu")
		(net "GND")
	)
	(segment
		(start 177.649886 -292.099746)
		(end 177.174906 -291.624766)
		(width 0.249936)
		(layer "F.Cu")
		(net "GND")
	)
	(segment
		(start 126.76505 -27.79014)
		(end 125.74905 -27.79014)
		(width 0.3556)
		(layer "F.Cu")
		(net "GND")
	)
	(segment
		(start 165.299898 -285.449772)
		(end 164.824918 -284.974792)
		(width 0.249936)
		(layer "F.Cu")
		(net "GND")
	)
	(segment
		(start 312.749692 -294.94988)
		(end 312.274712 -294.4749)
		(width 0.249936)
		(layer "F.Cu")
		(net "GND")
	)
	(segment
		(start 68.674742 -284.974792)
		(end 68.199762 -285.449772)
		(width 0.249936)
		(layer "F.Cu")
		(net "GND")
	)
	(segment
		(start 59.649868 -301.599854)
		(end 60.124848 -302.074834)
		(width 0.249936)
		(layer "F.Cu")
		(net "GND")
	)
	(segment
		(start 408.424888 -305.874928)
		(end 407.949908 -306.349908)
		(width 0.249936)
		(layer "F.Cu")
		(net "GND")
	)
	(segment
		(start 41.599866 -278.799798)
		(end 41.124886 -278.324818)
		(width 0.249936)
		(layer "F.Cu")
		(net "GND")
	)
	(segment
		(start 349.306896 -284.631384)
		(end 349.099632 -284.42412)
		(width 0.2286)
		(layer "F.Cu")
		(net "GND")
	)
	(segment
		(start 162.924998 -305.874928)
		(end 163.399978 -305.399948)
		(width 0.249936)
		(layer "F.Cu")
		(net "GND")
	)
	(segment
		(start 61.549788 -292.099746)
		(end 62.024768 -291.624766)
		(width 0.249936)
		(layer "F.Cu")
		(net "GND")
	)
	(segment
		(start 71.049896 -297.79976)
		(end 71.524876 -297.32478)
		(width 0.249936)
		(layer "F.Cu")
		(net "GND")
	)
	(segment
		(start 424.57497 -300.174914)
		(end 425.04995 -300.649894)
		(width 0.249936)
		(layer "F.Cu")
		(net "GND")
	)
	(segment
		(start 19.370294 -47.60087)
		(end 19.796252 -47.60087)
		(width 0.254)
		(layer "F.Cu")
		(net "GND")
	)
	(segment
		(start 178.124866 -294.4749)
		(end 178.599846 -293.99992)
		(width 0.249936)
		(layer "F.Cu")
		(net "GND")
	)
	(segment
		(start 173.850046 -296.8498)
		(end 174.325026 -296.37482)
		(width 0.249936)
		(layer "F.Cu")
		(net "GND")
	)
	(segment
		(start 406.999948 -307.299868)
		(end 406.524968 -306.824888)
		(width 0.249936)
		(layer "F.Cu")
		(net "GND")
	)
	(segment
		(start 50.14976 -287.349946)
		(end 49.67478 -286.874966)
		(width 0.249936)
		(layer "F.Cu")
		(net "GND")
	)
	(segment
		(start 227.467668 -221.504256)
		(end 227.067872 -221.904052)
		(width 0.381)
		(layer "F.Cu")
		(net "GND")
	)
	(segment
		(start 302.774858 -289.724846)
		(end 302.299878 -289.249866)
		(width 0.249936)
		(layer "F.Cu")
		(net "GND")
	)
	(segment
		(start 309.899812 -298.74972)
		(end 309.424832 -299.224954)
		(width 0.249936)
		(layer "F.Cu")
		(net "GND")
	)
	(segment
		(start 364.809532 -357.56596)
		(end 363.793532 -357.56596)
		(width 0.4572)
		(layer "F.Cu")
		(net "GND")
	)
	(segment
		(start 231.46766 -219.10421)
		(end 231.867456 -219.504006)
		(width 0.381)
		(layer "F.Cu")
		(net "GND")
	)
	(segment
		(start 248.559574 -146.242278)
		(end 248.559574 -145.53565)
		(width 0.4064)
		(layer "F.Cu")
		(net "GND")
	)
	(segment
		(start 104.66705 -57.332626)
		(end 104.66705 -56.354218)
		(width 0.4572)
		(layer "F.Cu")
		(net "GND")
	)
	(segment
		(start 109.64418 -110.28553)
		(end 109.70006 -110.22965)
		(width 0.254)
		(layer "F.Cu")
		(net "GND")
	)
	(segment
		(start 359.79481 -159.266382)
		(end 358.354122 -160.70707)
		(width 0.254)
		(layer "F.Cu")
		(net "GND")
	)
	(segment
		(start 331.575664 -121.509028)
		(end 332.211426 -121.509028)
		(width 0.4064)
		(layer "F.Cu")
		(net "GND")
	)
	(segment
		(start 390.374886 -296.37482)
		(end 389.899906 -295.89984)
		(width 0.249936)
		(layer "F.Cu")
		(net "GND")
	)
	(segment
		(start 301.848012 -129.445004)
		(end 300.857412 -129.445004)
		(width 0.3556)
		(layer "F.Cu")
		(net "GND")
	)
	(segment
		(start 171.949872 -288.299906)
		(end 172.424852 -287.824926)
		(width 0.249936)
		(layer "F.Cu")
		(net "GND")
	)
	(segment
		(start 34.140902 -54.163722)
		(end 34.692844 -54.163722)
		(width 0.254)
		(layer "F.Cu")
		(net "GND")
	)
	(segment
		(start 171.474892 -289.724846)
		(end 171.949872 -290.199826)
		(width 0.249936)
		(layer "F.Cu")
		(net "GND")
	)
	(segment
		(start 398.4498 -293.04996)
		(end 398.925034 -293.52494)
		(width 0.249936)
		(layer "F.Cu")
		(net "GND")
	)
	(segment
		(start 363.793532 -357.56596)
		(end 362.92536 -357.56596)
		(width 0.4572)
		(layer "F.Cu")
		(net "GND")
	)
	(segment
		(start 393.670282 -47.60087)
		(end 394.09624 -47.60087)
		(width 0.254)
		(layer "F.Cu")
		(net "GND")
	)
	(segment
		(start 398.4498 -285.449772)
		(end 397.97482 -284.974792)
		(width 0.249936)
		(layer "F.Cu")
		(net "GND")
	)
	(segment
		(start 293.74973 -285.449772)
		(end 294.22471 -284.974792)
		(width 0.249936)
		(layer "F.Cu")
		(net "GND")
	)
	(segment
		(start 184.77484 -306.824888)
		(end 184.29986 -306.349908)
		(width 0.249936)
		(layer "F.Cu")
		(net "GND")
	)
	(segment
		(start 310.849772 -301.599854)
		(end 311.324752 -302.074834)
		(width 0.249936)
		(layer "F.Cu")
		(net "GND")
	)
	(segment
		(start 35.738562 -136.241028)
		(end 35.298634 -136.680956)
		(width 0.4572)
		(layer "F.Cu")
		(net "GND")
	)
	(segment
		(start 411.275022 -305.874928)
		(end 411.750002 -306.349908)
		(width 0.249936)
		(layer "F.Cu")
		(net "GND")
	)
	(segment
		(start 81.499964 -299.699934)
		(end 81.024984 -299.224954)
		(width 0.249936)
		(layer "F.Cu")
		(net "GND")
	)
	(segment
		(start 48.24984 -291.149786)
		(end 47.77486 -290.674806)
		(width 0.249936)
		(layer "F.Cu")
		(net "GND")
	)
	(segment
		(start 295.174924 -284.974792)
		(end 294.69969 -285.449772)
		(width 0.249936)
		(layer "F.Cu")
		(net "GND")
	)
	(segment
		(start 68.199762 -298.74972)
		(end 68.674742 -299.224954)
		(width 0.249936)
		(layer "F.Cu")
		(net "GND")
	)
	(segment
		(start 164.824918 -309.674768)
		(end 165.299898 -309.199788)
		(width 0.249936)
		(layer "F.Cu")
		(net "GND")
	)
	(segment
		(start 123.203462 -59.971686)
		(end 123.203462 -60.627006)
		(width 0.381)
		(layer "F.Cu")
		(net "GND")
	)
	(segment
		(start 308.474872 -289.724846)
		(end 308.949852 -289.249866)
		(width 0.249936)
		(layer "F.Cu")
		(net "GND")
	)
	(segment
		(start 153.89987 -288.299906)
		(end 153.42489 -287.824926)
		(width 0.249936)
		(layer "F.Cu")
		(net "GND")
	)
	(segment
		(start 42.074846 -297.32478)
		(end 41.599866 -296.8498)
		(width 0.249936)
		(layer "F.Cu")
		(net "GND")
	)
	(segment
		(start 52.524914 -287.824926)
		(end 52.049934 -288.299906)
		(width 0.249936)
		(layer "F.Cu")
		(net "GND")
	)
	(segment
		(start 295.944798 -27.79014)
		(end 294.86479 -27.79014)
		(width 0.3556)
		(layer "F.Cu")
		(net "GND")
	)
	(segment
		(start 50.14976 -293.04996)
		(end 50.624994 -293.52494)
		(width 0.249936)
		(layer "F.Cu")
		(net "GND")
	)
	(segment
		(start 47.77486 -304.924714)
		(end 48.24984 -304.449734)
		(width 0.249936)
		(layer "F.Cu")
		(net "GND")
	)
	(segment
		(start 7.213346 -136.328404)
		(end 6.558026 -136.328404)
		(width 0.4064)
		(layer "F.Cu")
		(net "GND")
	)
	(segment
		(start 300.874684 -304.924714)
		(end 300.399704 -304.449734)
		(width 0.249936)
		(layer "F.Cu")
		(net "GND")
	)
	(segment
		(start 356.25405 -177.546)
		(end 356.87 -177.546)
		(width 0.4572)
		(layer "F.Cu")
		(net "GND")
	)
	(segment
		(start 457.411582 -278.165306)
		(end 457.667868 -278.165306)
		(width 0.254)
		(layer "F.Cu")
		(net "GND")
	)
	(segment
		(start 452.967852 -54.067456)
		(end 453.623172 -54.067456)
		(width 0.254)
		(layer "F.Cu")
		(net "GND")
	)
	(segment
		(start 269.880842 -25.990042)
		(end 268.864842 -25.990042)
		(width 0.3556)
		(layer "F.Cu")
		(net "GND")
	)
	(segment
		(start 60.599828 -286.399732)
		(end 61.074808 -285.924752)
		(width 0.249936)
		(layer "F.Cu")
		(net "GND")
	)
	(segment
		(start 395.59992 -287.349946)
		(end 395.12494 -286.874966)
		(width 0.249936)
		(layer "F.Cu")
		(net "GND")
	)
	(segment
		(start 62.664848 -33.19018)
		(end 61.648848 -33.19018)
		(width 0.3556)
		(layer "F.Cu")
		(net "GND")
	)
	(segment
		(start 441.297822 -295.965118)
		(end 441.297822 -295.355518)
		(width 0.4572)
		(layer "F.Cu")
		(net "GND")
	)
	(segment
		(start 397.161004 -37.201094)
		(end 396.398496 -37.201094)
		(width 0.4572)
		(layer "F.Cu")
		(net "GND")
	)
	(segment
		(start 422.59504 -102.439978)
		(end 421.557704 -102.439978)
		(width 0.3556)
		(layer "F.Cu")
		(net "GND")
	)
	(segment
		(start 56.155336 -375.252742)
		(end 56.155336 -375.89587)
		(width 0.4572)
		(layer "F.Cu")
		(net "GND")
	)
	(segment
		(start 252.473968 -73.166732)
		(end 252.473968 -73.85177)
		(width 0.4572)
		(layer "F.Cu")
		(net "GND")
	)
	(segment
		(start 424.57497 -289.724846)
		(end 425.04995 -289.249866)
		(width 0.249936)
		(layer "F.Cu")
		(net "GND")
	)
	(segment
		(start 289.997642 -38.937184)
		(end 290.734496 -38.937184)
		(width 0.4572)
		(layer "F.Cu")
		(net "GND")
	)
	(segment
		(start 400.824954 -302.074834)
		(end 400.349974 -301.599854)
		(width 0.249936)
		(layer "F.Cu")
		(net "GND")
	)
	(segment
		(start 399.874994 -305.874928)
		(end 400.349974 -306.349908)
		(width 0.249936)
		(layer "F.Cu")
		(net "GND")
	)
	(segment
		(start 336.867754 -51.019456)
		(end 337.523074 -51.019456)
		(width 0.254)
		(layer "F.Cu")
		(net "GND")
	)
	(segment
		(start 67.249802 -305.399948)
		(end 66.774822 -305.874928)
		(width 0.249936)
		(layer "F.Cu")
		(net "GND")
	)
	(segment
		(start 418.874956 -302.074834)
		(end 418.399976 -302.549814)
		(width 0.249936)
		(layer "F.Cu")
		(net "GND")
	)
	(segment
		(start 395.89456 -126.703836)
		(end 395.145768 -125.955044)
		(width 0.3556)
		(layer "F.Cu")
		(net "GND")
	)
	(segment
		(start 394.17498 -297.32478)
		(end 393.7 -296.8498)
		(width 0.249936)
		(layer "F.Cu")
		(net "GND")
	)
	(segment
		(start 48.24984 -296.8498)
		(end 47.77486 -297.32478)
		(width 0.249936)
		(layer "F.Cu")
		(net "GND")
	)
	(segment
		(start 407.044398 -87.305642)
		(end 407.330656 -87.019384)
		(width 0.4572)
		(layer "F.Cu")
		(net "GND")
	)
	(segment
		(start 170.049952 -288.299906)
		(end 170.524932 -287.824926)
		(width 0.249936)
		(layer "F.Cu")
		(net "GND")
	)
	(segment
		(start 287.574736 -284.974792)
		(end 288.049716 -284.499812)
		(width 0.249936)
		(layer "F.Cu")
		(net "GND")
	)
	(segment
		(start 67.312794 -102.439978)
		(end 68.65747 -102.439978)
		(width 0.3556)
		(layer "F.Cu")
		(net "GND")
	)
	(segment
		(start 295.944798 -29.589984)
		(end 294.86479 -29.589984)
		(width 0.3556)
		(layer "F.Cu")
		(net "GND")
	)
	(segment
		(start 17.185386 -272.200624)
		(end 17.794986 -272.200624)
		(width 0.4572)
		(layer "F.Cu")
		(net "GND")
	)
	(segment
		(start 36.849812 -291.149786)
		(end 36.374832 -290.674806)
		(width 0.249936)
		(layer "F.Cu")
		(net "GND")
	)
	(segment
		(start 426.47489 -299.224954)
		(end 426.94987 -299.699934)
		(width 0.249936)
		(layer "F.Cu")
		(net "GND")
	)
	(segment
		(start 395.59992 -290.199826)
		(end 395.12494 -289.724846)
		(width 0.249936)
		(layer "F.Cu")
		(net "GND")
	)
	(segment
		(start 427.89983 -296.8498)
		(end 427.42485 -296.37482)
		(width 0.249936)
		(layer "F.Cu")
		(net "GND")
	)
	(segment
		(start 395.59992 -288.299906)
		(end 395.12494 -287.824926)
		(width 0.249936)
		(layer "F.Cu")
		(net "GND")
	)
	(segment
		(start 137.806684 -200.489058)
		(end 137.806684 -199.367394)
		(width 0.2794)
		(layer "F.Cu")
		(net "GND")
	)
	(segment
		(start 297.549824 -301.599854)
		(end 298.024804 -302.074834)
		(width 0.249936)
		(layer "F.Cu")
		(net "GND")
	)
	(segment
		(start 416.974782 -306.824888)
		(end 417.450016 -306.349908)
		(width 0.249936)
		(layer "F.Cu")
		(net "GND")
	)
	(segment
		(start 55.849774 -284.499812)
		(end 56.324754 -284.024832)
		(width 0.249936)
		(layer "F.Cu")
		(net "GND")
	)
	(segment
		(start 305.26101 -38.701218)
		(end 306.019454 -38.701218)
		(width 0.4572)
		(layer "F.Cu")
		(net "GND")
	)
	(segment
		(start 2.989072 -386.019294)
		(end 3.131058 -385.877308)
		(width 0.4572)
		(layer "F.Cu")
		(net "GND")
	)
	(segment
		(start 68.679822 -303.969928)
		(end 69.149976 -303.499774)
		(width 0.249936)
		(layer "F.Cu")
		(net "GND")
	)
	(segment
		(start 423.149776 -303.499774)
		(end 422.199816 -303.499774)
		(width 0.249936)
		(layer "F.Cu")
		(net "GND")
	)
	(segment
		(start 288.52495 -296.37482)
		(end 288.04997 -296.8498)
		(width 0.249936)
		(layer "F.Cu")
		(net "GND")
	)
	(segment
		(start 279.974802 -304.924714)
		(end 279.499822 -304.449734)
		(width 0.249936)
		(layer "F.Cu")
		(net "GND")
	)
	(segment
		(start 288.524696 -287.824926)
		(end 288.99993 -288.299906)
		(width 0.249936)
		(layer "F.Cu")
		(net "GND")
	)
	(segment
		(start 172.900086 -301.599854)
		(end 172.424852 -302.074834)
		(width 0.249936)
		(layer "F.Cu")
		(net "GND")
	)
	(segment
		(start 67.724782 -307.774848)
		(end 67.249802 -307.299868)
		(width 0.249936)
		(layer "F.Cu")
		(net "GND")
	)
	(segment
		(start 431.224944 -299.224954)
		(end 430.749964 -299.699934)
		(width 0.249936)
		(layer "F.Cu")
		(net "GND")
	)
	(segment
		(start 393.7 -285.449772)
		(end 393.22502 -284.974792)
		(width 0.249936)
		(layer "F.Cu")
		(net "GND")
	)
	(segment
		(start 289.47491 -306.824888)
		(end 288.99993 -307.299868)
		(width 0.249936)
		(layer "F.Cu")
		(net "GND")
	)
	(segment
		(start 46.487588 -25.742392)
		(end 46.487588 -26.360882)
		(width 0.4572)
		(layer "F.Cu")
		(net "GND")
	)
	(segment
		(start 2.992374 -389.245348)
		(end 2.992374 -389.86968)
		(width 0.4572)
		(layer "F.Cu")
		(net "GND")
	)
	(segment
		(start 189.999874 -293.99992)
		(end 189.524894 -293.52494)
		(width 0.249936)
		(layer "F.Cu")
		(net "GND")
	)
	(segment
		(start 146.815302 -59.946286)
		(end 146.815302 -60.601606)
		(width 0.4572)
		(layer "F.Cu")
		(net "GND")
	)
	(segment
		(start 167.732964 -102.445058)
		(end 166.742364 -102.445058)
		(width 0.3556)
		(layer "F.Cu")
		(net "GND")
	)
	(segment
		(start 38.054788 -34.990024)
		(end 36.6649 -34.990024)
		(width 0.3556)
		(layer "F.Cu")
		(net "GND")
	)
	(segment
		(start 64.399922 -284.499812)
		(end 64.874902 -284.974792)
		(width 0.249936)
		(layer "F.Cu")
		(net "GND")
	)
	(segment
		(start 108.686854 -283.07411)
		(end 108.37164 -283.07411)
		(width 0.2286)
		(layer "F.Cu")
		(net "GND")
	)
	(segment
		(start 113.161064 -261.687564)
		(end 112.545114 -261.687564)
		(width 0.381)
		(layer "F.Cu")
		(net "GND")
	)
	(segment
		(start 403.199854 -283.549852)
		(end 403.674834 -284.024832)
		(width 0.249936)
		(layer "F.Cu")
		(net "GND")
	)
	(segment
		(start 185.250074 -292.099746)
		(end 184.77484 -291.624766)
		(width 0.249936)
		(layer "F.Cu")
		(net "GND")
	)
	(segment
		(start 162.450018 -305.399948)
		(end 162.924998 -305.874928)
		(width 0.249936)
		(layer "F.Cu")
		(net "GND")
	)
	(segment
		(start 74.248264 -120.035066)
		(end 73.257664 -120.035066)
		(width 0.3556)
		(layer "F.Cu")
		(net "GND")
	)
	(segment
		(start 198.550022 -293.99992)
		(end 198.075042 -293.52494)
		(width 0.249936)
		(layer "F.Cu")
		(net "GND")
	)
	(segment
		(start 300.399704 -289.249866)
		(end 300.874684 -288.774886)
		(width 0.249936)
		(layer "F.Cu")
		(net "GND")
	)
	(segment
		(start 52.524914 -302.074834)
		(end 52.049934 -301.599854)
		(width 0.249936)
		(layer "F.Cu")
		(net "GND")
	)
	(segment
		(start 111.015018 -114.22634)
		(end 109.57433 -112.785652)
		(width 0.254)
		(layer "F.Cu")
		(net "GND")
	)
	(segment
		(start 445.55791 -73.166732)
		(end 445.55791 -73.85177)
		(width 0.4572)
		(layer "F.Cu")
		(net "GND")
	)
	(segment
		(start 182.948834 -198.109332)
		(end 182.948834 -198.750174)
		(width 0.4572)
		(layer "F.Cu")
		(net "GND")
	)
	(segment
		(start 302.299878 -300.649894)
		(end 302.774858 -301.124874)
		(width 0.249936)
		(layer "F.Cu")
		(net "GND")
	)
	(segment
		(start 277.21814 -151.157432)
		(end 277.22068 -151.159972)
		(width 0.3556)
		(layer "F.Cu")
		(net "GND")
	)
	(segment
		(start 190.348108 -120.035066)
		(end 189.357508 -120.035066)
		(width 0.3556)
		(layer "F.Cu")
		(net "GND")
	)
	(segment
		(start 394.17498 -299.224954)
		(end 394.64996 -299.699934)
		(width 0.249936)
		(layer "F.Cu")
		(net "GND")
	)
	(segment
		(start 157.699964 -291.149786)
		(end 157.224984 -290.674806)
		(width 0.249936)
		(layer "F.Cu")
		(net "GND")
	)
	(segment
		(start 52.999894 -288.299906)
		(end 52.524914 -287.824926)
		(width 0.249936)
		(layer "F.Cu")
		(net "GND")
	)
	(segment
		(start 180.975 -306.824888)
		(end 180.50002 -306.349908)
		(width 0.249936)
		(layer "F.Cu")
		(net "GND")
	)
	(segment
		(start 361.1118 -31.2166)
		(end 360.938318 -31.390082)
		(width 0.3556)
		(layer "F.Cu")
		(net "GND")
	)
	(segment
		(start 296.599864 -306.349908)
		(end 296.124884 -305.874928)
		(width 0.249936)
		(layer "F.Cu")
		(net "GND")
	)
	(segment
		(start 462.865724 -276.64283)
		(end 463.475324 -276.64283)
		(width 0.381)
		(layer "F.Cu")
		(net "GND")
	)
	(segment
		(start 162.450018 -300.649894)
		(end 161.975038 -301.124874)
		(width 0.249936)
		(layer "F.Cu")
		(net "GND")
	)
	(segment
		(start 138.837924 -193.238628)
		(end 137.73785 -193.238628)
		(width 0.4572)
		(layer "F.Cu")
		(net "GND")
	)
	(segment
		(start 365.90605 -201.803)
		(end 366.522 -201.803)
		(width 0.4572)
		(layer "F.Cu")
		(net "GND")
	)
	(segment
		(start 257.262376 -23.355554)
		(end 257.912108 -23.355554)
		(width 0.4572)
		(layer "F.Cu")
		(net "GND")
	)
	(segment
		(start 145.28165 -206.4639)
		(end 144.159986 -206.4639)
		(width 0.2794)
		(layer "F.Cu")
		(net "GND")
	)
	(segment
		(start 396.54988 -306.349908)
		(end 396.0749 -306.824888)
		(width 0.249936)
		(layer "F.Cu")
		(net "GND")
	)
	(segment
		(start 366.566196 -282.021534)
		(end 366.50422 -282.021534)
		(width 0.254)
		(layer "F.Cu")
		(net "GND")
	)
	(segment
		(start 428.641764 -26.606246)
		(end 428.641764 -25.971246)
		(width 0.4572)
		(layer "F.Cu")
		(net "GND")
	)
	(segment
		(start 422.674796 -298.27474)
		(end 423.15003 -297.79976)
		(width 0.249936)
		(layer "F.Cu")
		(net "GND")
	)
	(segment
		(start 396.54988 -289.249866)
		(end 396.0749 -288.774886)
		(width 0.249936)
		(layer "F.Cu")
		(net "GND")
	)
	(segment
		(start 293.74973 -301.599854)
		(end 294.22471 -302.074834)
		(width 0.249936)
		(layer "F.Cu")
		(net "GND")
	)
	(segment
		(start 155.857448 -142.892018)
		(end 156.000704 -142.748762)
		(width 0.4572)
		(layer "F.Cu")
		(net "GND")
	)
	(segment
		(start 192.375028 -289.724846)
		(end 192.850008 -289.249866)
		(width 0.249936)
		(layer "F.Cu")
		(net "GND")
	)
	(segment
		(start 297.549824 -296.8498)
		(end 298.024804 -297.32478)
		(width 0.249936)
		(layer "F.Cu")
		(net "GND")
	)
	(segment
		(start 198.789544 -64.312292)
		(end 199.547988 -64.312292)
		(width 0.4572)
		(layer "F.Cu")
		(net "GND")
	)
	(segment
		(start 396.54988 -306.349908)
		(end 397.02486 -305.874928)
		(width 0.249936)
		(layer "F.Cu")
		(net "GND")
	)
	(segment
		(start 327.008998 -94.641416)
		(end 327.008998 -93.98254)
		(width 0.4572)
		(layer "F.Cu")
		(net "GND")
	)
	(segment
		(start 399.874994 -302.074834)
		(end 399.400014 -301.599854)
		(width 0.249936)
		(layer "F.Cu")
		(net "GND")
	)
	(segment
		(start 156.750004 -290.199826)
		(end 156.275024 -289.724846)
		(width 0.249936)
		(layer "F.Cu")
		(net "GND")
	)
	(segment
		(start 207.023208 -87.977472)
		(end 207.023208 -87.614252)
		(width 0.4572)
		(layer "F.Cu")
		(net "GND")
	)
	(segment
		(start 154.850084 -283.549852)
		(end 154.375104 -283.074872)
		(width 0.249936)
		(layer "F.Cu")
		(net "GND")
	)
	(segment
		(start 63.94704 -385.561332)
		(end 63.94704 -385.07924)
		(width 0.4572)
		(layer "F.Cu")
		(net "GND")
	)
	(segment
		(start 62.499748 -306.349908)
		(end 62.974982 -306.824888)
		(width 0.249936)
		(layer "F.Cu")
		(net "GND")
	)
	(segment
		(start 363.07395 -211.963)
		(end 362.458 -211.963)
		(width 0.4572)
		(layer "F.Cu")
		(net "GND")
	)
	(segment
		(start 282.134056 -111.44504)
		(end 282.842462 -111.44504)
		(width 0.3556)
		(layer "F.Cu")
		(net "GND")
	)
	(segment
		(start 286.46247 -34.29762)
		(end 286.027622 -34.732468)
		(width 0.4572)
		(layer "F.Cu")
		(net "GND")
	)
	(segment
		(start 70.574916 -300.174914)
		(end 70.099936 -299.699934)
		(width 0.249936)
		(layer "F.Cu")
		(net "GND")
	)
	(segment
		(start 392.749786 -282.599892)
		(end 392.274806 -282.124912)
		(width 0.249936)
		(layer "F.Cu")
		(net "GND")
	)
	(segment
		(start 63.924942 -297.32478)
		(end 63.449962 -296.8498)
		(width 0.249936)
		(layer "F.Cu")
		(net "GND")
	)
	(segment
		(start 208.348834 -31.390082)
		(end 209.364834 -31.390082)
		(width 0.3556)
		(layer "F.Cu")
		(net "GND")
	)
	(segment
		(start 436.964074 -291.102034)
		(end 436.43804 -291.102034)
		(width 0.4572)
		(layer "F.Cu")
		(net "GND")
	)
	(segment
		(start 290.794948 -102.798372)
		(end 290.17976 -102.798372)
		(width 0.4064)
		(layer "F.Cu")
		(net "GND")
	)
	(segment
		(start 45.39996 -283.549852)
		(end 44.92498 -283.074872)
		(width 0.249936)
		(layer "F.Cu")
		(net "GND")
	)
	(segment
		(start 53.474874 -285.924752)
		(end 53.949854 -285.449772)
		(width 0.249936)
		(layer "F.Cu")
		(net "GND")
	)
	(segment
		(start 279.346914 -53.144166)
		(end 279.346914 -52.592224)
		(width 0.254)
		(layer "F.Cu")
		(net "GND")
	)
	(segment
		(start 76.371704 -81.749646)
		(end 76.953364 -82.331306)
		(width 0.4064)
		(layer "F.Cu")
		(net "GND")
	)
	(segment
		(start 307.049932 -301.599854)
		(end 307.524912 -302.074834)
		(width 0.249936)
		(layer "F.Cu")
		(net "GND")
	)
	(segment
		(start 260.585458 -34.183066)
		(end 260.470904 -34.29762)
		(width 0.4572)
		(layer "F.Cu")
		(net "GND")
	)
	(segment
		(start 144.02816 -389.18896)
		(end 143.6624 -388.8232)
		(width 0.4572)
		(layer "F.Cu")
		(net "GND")
	)
	(segment
		(start 431.224944 -293.52494)
		(end 430.749964 -293.99992)
		(width 0.249936)
		(layer "F.Cu")
		(net "GND")
	)
	(segment
		(start 169.574972 -305.874928)
		(end 170.049952 -305.399948)
		(width 0.249936)
		(layer "F.Cu")
		(net "GND")
	)
	(segment
		(start 60.124848 -306.824888)
		(end 60.599828 -307.299868)
		(width 0.249936)
		(layer "F.Cu")
		(net "GND")
	)
	(segment
		(start 192.850008 -300.649894)
		(end 192.375028 -301.124874)
		(width 0.249936)
		(layer "F.Cu")
		(net "GND")
	)
	(segment
		(start 205.101698 -303.636426)
		(end 205.101698 -303.026826)
		(width 0.4572)
		(layer "F.Cu")
		(net "GND")
	)
	(segment
		(start 279.974802 -292.57498)
		(end 280.449782 -293.04996)
		(width 0.249936)
		(layer "F.Cu")
		(net "GND")
	)
	(segment
		(start 268.512036 -136.81456)
		(end 268.512036 -136.84885)
		(width 0.4572)
		(layer "F.Cu")
		(net "GND")
	)
	(segment
		(start 163.399978 -292.1)
		(end 163.874958 -292.57498)
		(width 0.254)
		(layer "F.Cu")
		(net "GND")
	)
	(segment
		(start 395.232128 -104.244902)
		(end 394.342366 -104.244902)
		(width 0.3556)
		(layer "F.Cu")
		(net "GND")
	)
	(segment
		(start 447.830448 -65.92189)
		(end 447.830448 -65.15989)
		(width 0.4572)
		(layer "F.Cu")
		(net "GND")
	)
	(segment
		(start 165.343332 -173.229524)
		(end 165.343332 -172.172122)
		(width 0.4572)
		(layer "F.Cu")
		(net "GND")
	)
	(segment
		(start 302.774858 -303.024794)
		(end 302.299878 -302.549814)
		(width 0.249936)
		(layer "F.Cu")
		(net "GND")
	)
	(segment
		(start 267.394944 -59.978036)
		(end 267.394944 -60.633356)
		(width 0.4572)
		(layer "F.Cu")
		(net "GND")
	)
	(segment
		(start 424.57497 -297.32478)
		(end 424.09999 -297.79976)
		(width 0.249936)
		(layer "F.Cu")
		(net "GND")
	)
	(segment
		(start 235.867448 -212.304376)
		(end 235.467652 -212.704172)
		(width 0.381)
		(layer "F.Cu")
		(net "GND")
	)
	(segment
		(start 51.574954 -302.074834)
		(end 51.099974 -301.599854)
		(width 0.249936)
		(layer "F.Cu")
		(net "GND")
	)
	(segment
		(start 142.767304 -57.332626)
		(end 142.767304 -56.354218)
		(width 0.4572)
		(layer "F.Cu")
		(net "GND")
	)
	(segment
		(start 394.64996 -284.499812)
		(end 394.17498 -284.024832)
		(width 0.249936)
		(layer "F.Cu")
		(net "GND")
	)
	(segment
		(start 298.974764 -287.824926)
		(end 299.449744 -288.299906)
		(width 0.249936)
		(layer "F.Cu")
		(net "GND")
	)
	(segment
		(start 404.624794 -306.824888)
		(end 405.100028 -306.349908)
		(width 0.249936)
		(layer "F.Cu")
		(net "GND")
	)
	(segment
		(start 403.674834 -306.824888)
		(end 404.149814 -306.349908)
		(width 0.249936)
		(layer "F.Cu")
		(net "GND")
	)
	(segment
		(start 431.209704 -303.040034)
		(end 430.749964 -303.499774)
		(width 0.249936)
		(layer "F.Cu")
		(net "GND")
	)
	(segment
		(start 185.250074 -284.499812)
		(end 185.725054 -284.974792)
		(width 0.249936)
		(layer "F.Cu")
		(net "GND")
	)
	(segment
		(start 278.549862 -309.199788)
		(end 279.024842 -309.674768)
		(width 0.249936)
		(layer "F.Cu")
		(net "GND")
	)
	(segment
		(start 258.84378 -43.85691)
		(end 259.515102 -43.85691)
		(width 0.254)
		(layer "F.Cu")
		(net "GND")
	)
	(segment
		(start 283.299916 -303.499774)
		(end 282.824936 -303.974754)
		(width 0.249936)
		(layer "F.Cu")
		(net "GND")
	)
	(segment
		(start 163.874958 -301.124874)
		(end 163.399978 -301.599854)
		(width 0.249936)
		(layer "F.Cu")
		(net "GND")
	)
	(segment
		(start 277.599902 -285.449772)
		(end 277.124922 -284.974792)
		(width 0.249936)
		(layer "F.Cu")
		(net "GND")
	)
	(segment
		(start 389.899906 -299.699934)
		(end 389.424926 -299.224954)
		(width 0.249936)
		(layer "F.Cu")
		(net "GND")
	)
	(segment
		(start 186.675014 -302.074834)
		(end 187.149994 -301.599854)
		(width 0.249936)
		(layer "F.Cu")
		(net "GND")
	)
	(segment
		(start 385.149852 -293.04996)
		(end 384.674872 -292.57498)
		(width 0.249936)
		(layer "F.Cu")
		(net "GND")
	)
	(segment
		(start 10.3378 -276.789134)
		(end 9.7028 -276.789134)
		(width 0.4572)
		(layer "F.Cu")
		(net "GND")
	)
	(segment
		(start 312.749692 -293.04996)
		(end 313.224926 -292.574726)
		(width 0.249936)
		(layer "F.Cu")
		(net "GND")
	)
	(segment
		(start 78.64983 -291.149786)
		(end 78.17485 -291.624766)
		(width 0.249936)
		(layer "F.Cu")
		(net "GND")
	)
	(segment
		(start 45.051726 -111.44504)
		(end 46.042326 -111.44504)
		(width 0.3556)
		(layer "F.Cu")
		(net "GND")
	)
	(segment
		(start 358.964992 -34.990024)
		(end 357.948992 -34.990024)
		(width 0.3556)
		(layer "F.Cu")
		(net "GND")
	)
	(segment
		(start 225.046794 -38.49116)
		(end 225.046794 -39.1414)
		(width 0.4572)
		(layer "F.Cu")
		(net "GND")
	)
	(segment
		(start 274.480782 -29.589984)
		(end 273.464782 -29.589984)
		(width 0.3556)
		(layer "F.Cu")
		(net "GND")
	)
	(segment
		(start 63.924942 -291.624766)
		(end 63.449962 -292.099746)
		(width 0.249936)
		(layer "F.Cu")
		(net "GND")
	)
	(segment
		(start 388.949946 -276.899878)
		(end 388.474966 -276.424898)
		(width 0.249936)
		(layer "F.Cu")
		(net "GND")
	)
	(segment
		(start 32.309054 -27.04973)
		(end 31.649924 -27.04973)
		(width 0.4572)
		(layer "F.Cu")
		(net "GND")
	)
	(segment
		(start 228.267768 -217.504264)
		(end 227.867972 -217.104468)
		(width 0.381)
		(layer "F.Cu")
		(net "GND")
	)
	(segment
		(start 354.789486 -62.812168)
		(end 355.6 -62.812168)
		(width 0.4572)
		(layer "F.Cu")
		(net "GND")
	)
	(segment
		(start 301.824898 -291.624766)
		(end 302.299878 -291.149786)
		(width 0.249936)
		(layer "F.Cu")
		(net "GND")
	)
	(segment
		(start 300.874684 -305.874928)
		(end 300.399704 -305.399948)
		(width 0.249936)
		(layer "F.Cu")
		(net "GND")
	)
	(segment
		(start 229.067614 -219.904056)
		(end 228.667818 -220.303852)
		(width 0.381)
		(layer "F.Cu")
		(net "GND")
	)
	(segment
		(start 50.624994 -291.624766)
		(end 51.099974 -292.099746)
		(width 0.249936)
		(layer "F.Cu")
		(net "GND")
	)
	(segment
		(start 70.574916 -291.624766)
		(end 71.049896 -291.149786)
		(width 0.249936)
		(layer "F.Cu")
		(net "GND")
	)
	(segment
		(start 306.099718 -293.04996)
		(end 305.624738 -292.574726)
		(width 0.249936)
		(layer "F.Cu")
		(net "GND")
	)
	(segment
		(start 74.374756 -296.37482)
		(end 74.84999 -295.89984)
		(width 0.249936)
		(layer "F.Cu")
		(net "GND")
	)
	(segment
		(start 131.133088 -113.674652)
		(end 130.710432 -113.251996)
		(width 0.254)
		(layer "F.Cu")
		(net "GND")
	)
	(segment
		(start 172.424852 -305.874928)
		(end 171.949872 -306.349908)
		(width 0.249936)
		(layer "F.Cu")
		(net "GND")
	)
	(segment
		(start 161.59861 -65.92189)
		(end 161.59861 -65.15989)
		(width 0.4572)
		(layer "F.Cu")
		(net "GND")
	)
	(segment
		(start 436.964836 -27.79014)
		(end 435.948836 -27.79014)
		(width 0.3556)
		(layer "F.Cu")
		(net "GND")
	)
	(segment
		(start 256.769362 -349.695008)
		(end 256.146808 -349.695008)
		(width 0.4572)
		(layer "F.Cu")
		(net "GND")
	)
	(segment
		(start 324.448678 -31.390082)
		(end 325.464678 -31.390082)
		(width 0.3556)
		(layer "F.Cu")
		(net "GND")
	)
	(segment
		(start 62.974982 -302.074834)
		(end 63.449962 -301.599854)
		(width 0.249936)
		(layer "F.Cu")
		(net "GND")
	)
	(segment
		(start 304.467006 -121.83491)
		(end 305.457606 -121.83491)
		(width 0.3556)
		(layer "F.Cu")
		(net "GND")
	)
	(segment
		(start 358.365806 -232.457244)
		(end 359.04805 -232.457244)
		(width 0.4572)
		(layer "F.Cu")
		(net "GND")
	)
	(segment
		(start 295.174924 -287.824926)
		(end 295.649904 -288.299906)
		(width 0.249936)
		(layer "F.Cu")
		(net "GND")
	)
	(segment
		(start 410.324808 -291.624766)
		(end 410.799788 -292.099746)
		(width 0.249936)
		(layer "F.Cu")
		(net "GND")
	)
	(segment
		(start 412.699962 -286.399732)
		(end 412.224982 -285.924752)
		(width 0.249936)
		(layer "F.Cu")
		(net "GND")
	)
	(segment
		(start 412.354776 -34.990024)
		(end 410.964888 -34.990024)
		(width 0.3556)
		(layer "F.Cu")
		(net "GND")
	)
	(segment
		(start 45.774864 -48.753014)
		(end 45.068236 -48.753014)
		(width 0.254)
		(layer "F.Cu")
		(net "GND")
	)
	(segment
		(start 122.563128 -107.028996)
		(end 122.563128 -106.289856)
		(width 0.4572)
		(layer "F.Cu")
		(net "GND")
	)
	(segment
		(start 419.349936 -287.349946)
		(end 418.874956 -286.874966)
		(width 0.249936)
		(layer "F.Cu")
		(net "GND")
	)
	(segment
		(start 58.224928 -303.974754)
		(end 58.699908 -303.499774)
		(width 0.249936)
		(layer "F.Cu")
		(net "GND")
	)
	(segment
		(start 111.274098 -160.372044)
		(end 111.777272 -160.372044)
		(width 0.1778)
		(layer "F.Cu")
		(net "GND")
	)
	(segment
		(start 174.800006 -306.349908)
		(end 174.325026 -306.824888)
		(width 0.249936)
		(layer "F.Cu")
		(net "GND")
	)
	(segment
		(start 338.47405 -184.023)
		(end 339.09 -184.023)
		(width 0.4572)
		(layer "F.Cu")
		(net "GND")
	)
	(segment
		(start 66.774822 -305.874928)
		(end 66.299842 -305.399948)
		(width 0.249936)
		(layer "F.Cu")
		(net "GND")
	)
	(segment
		(start 387.999986 -293.99992)
		(end 387.525006 -293.52494)
		(width 0.249936)
		(layer "F.Cu")
		(net "GND")
	)
	(segment
		(start 281.53233 -120.084088)
		(end 282.003246 -120.555004)
		(width 0.3556)
		(layer "F.Cu")
		(net "GND")
	)
	(segment
		(start 69.624956 -297.32478)
		(end 69.149976 -297.79976)
		(width 0.249936)
		(layer "F.Cu")
		(net "GND")
	)
	(segment
		(start 185.783982 -124.31649)
		(end 185.783982 -124.000514)
		(width 0.3556)
		(layer "F.Cu")
		(net "GND")
	)
	(segment
		(start 300.874684 -301.124874)
		(end 300.399704 -300.649894)
		(width 0.249936)
		(layer "F.Cu")
		(net "GND")
	)
	(segment
		(start 422.674796 -290.674806)
		(end 422.199816 -291.149786)
		(width 0.249936)
		(layer "F.Cu")
		(net "GND")
	)
	(segment
		(start 305.730402 -65.92189)
		(end 305.730402 -65.15989)
		(width 0.4572)
		(layer "F.Cu")
		(net "GND")
	)
	(segment
		(start 406.09774 -38.937184)
		(end 406.834594 -38.937184)
		(width 0.4572)
		(layer "F.Cu")
		(net "GND")
	)
	(segment
		(start 268.802866 -92.526104)
		(end 269.412466 -92.526104)
		(width 0.4572)
		(layer "F.Cu")
		(net "GND")
	)
	(segment
		(start 141.806676 -200.489058)
		(end 141.806676 -199.367394)
		(width 0.2794)
		(layer "F.Cu")
		(net "GND")
	)
	(segment
		(start 311.324752 -302.074834)
		(end 311.799732 -302.549814)
		(width 0.249936)
		(layer "F.Cu")
		(net "GND")
	)
	(segment
		(start 196.362574 -34.29762)
		(end 195.927726 -34.732468)
		(width 0.4572)
		(layer "F.Cu")
		(net "GND")
	)
	(segment
		(start 453.960484 -16.439388)
		(end 453.960484 -15.993872)
		(width 0.4572)
		(layer "F.Cu")
		(net "GND")
	)
	(segment
		(start 147.86356 -384.566668)
		(end 147.86356 -385.15036)
		(width 0.4572)
		(layer "F.Cu")
		(net "GND")
	)
	(segment
		(start 174.800006 -288.149792)
		(end 174.800006 -288.299906)
		(width 0.249936)
		(layer "F.Cu")
		(net "GND")
	)
	(segment
		(start 182.87492 -287.824926)
		(end 183.3499 -288.299906)
		(width 0.249936)
		(layer "F.Cu")
		(net "GND")
	)
	(segment
		(start 352.326448 -238.098584)
		(end 355.154738 -235.270294)
		(width 0.4572)
		(layer "F.Cu")
		(net "GND")
	)
	(segment
		(start 282.349702 -302.549814)
		(end 281.874722 -303.024794)
		(width 0.249936)
		(layer "F.Cu")
		(net "GND")
	)
	(segment
		(start 184.29986 -304.449734)
		(end 184.77484 -304.924714)
		(width 0.249936)
		(layer "F.Cu")
		(net "GND")
	)
	(segment
		(start 406.524968 -291.624766)
		(end 406.049988 -292.099746)
		(width 0.249936)
		(layer "F.Cu")
		(net "GND")
	)
	(segment
		(start 78.64983 -299.699934)
		(end 79.12481 -300.174914)
		(width 0.249936)
		(layer "F.Cu")
		(net "GND")
	)
	(segment
		(start 393.286996 -151.157432)
		(end 393.318238 -151.157432)
		(width 0.3556)
		(layer "F.Cu")
		(net "GND")
	)
	(segment
		(start 411.750002 -305.399948)
		(end 412.224982 -305.874928)
		(width 0.249936)
		(layer "F.Cu")
		(net "GND")
	)
	(segment
		(start 68.674742 -306.824888)
		(end 69.149976 -306.349908)
		(width 0.249936)
		(layer "F.Cu")
		(net "GND")
	)
	(segment
		(start 71.524876 -288.774886)
		(end 71.049896 -288.299906)
		(width 0.249936)
		(layer "F.Cu")
		(net "GND")
	)
	(segment
		(start 385.850384 -252.756924)
		(end 385.850384 -253.45644)
		(width 0.4572)
		(layer "F.Cu")
		(net "GND")
	)
	(segment
		(start 80.385412 -34.183066)
		(end 80.270858 -34.29762)
		(width 0.4572)
		(layer "F.Cu")
		(net "GND")
	)
	(segment
		(start 429.325024 -301.124874)
		(end 429.800004 -301.599854)
		(width 0.249936)
		(layer "F.Cu")
		(net "GND")
	)
	(segment
		(start 303.724818 -288.774886)
		(end 303.249838 -288.299906)
		(width 0.249936)
		(layer "F.Cu")
		(net "GND")
	)
	(segment
		(start 316.87516 -388.960868)
		(end 316.87516 -388.52856)
		(width 0.4572)
		(layer "F.Cu")
		(net "GND")
	)
	(segment
		(start 54.899814 -299.699934)
		(end 54.424834 -300.174914)
		(width 0.249936)
		(layer "F.Cu")
		(net "GND")
	)
	(segment
		(start 189.999874 -292.099746)
		(end 190.474854 -292.574726)
		(width 0.249936)
		(layer "F.Cu")
		(net "GND")
	)
	(segment
		(start 38.274752 -299.224954)
		(end 38.749986 -298.74972)
		(width 0.249936)
		(layer "F.Cu")
		(net "GND")
	)
	(segment
		(start 299.866812 -120.035066)
		(end 300.857412 -120.035066)
		(width 0.3556)
		(layer "F.Cu")
		(net "GND")
	)
	(segment
		(start 420.567104 -131.245102)
		(end 421.557704 -131.245102)
		(width 0.3556)
		(layer "F.Cu")
		(net "GND")
	)
	(segment
		(start 290.794948 -104.830372)
		(end 290.17976 -104.830372)
		(width 0.4064)
		(layer "F.Cu")
		(net "GND")
	)
	(segment
		(start 421.249856 -293.99992)
		(end 421.724836 -294.4749)
		(width 0.249936)
		(layer "F.Cu")
		(net "GND")
	)
	(segment
		(start 387.999986 -278.799798)
		(end 387.525006 -278.324818)
		(width 0.249936)
		(layer "F.Cu")
		(net "GND")
	)
	(segment
		(start 409.415488 -85.408008)
		(end 409.415488 -84.488528)
		(width 0.4572)
		(layer "F.Cu")
		(net "GND")
	)
	(segment
		(start 395.59992 -306.349908)
		(end 395.12494 -305.874928)
		(width 0.249936)
		(layer "F.Cu")
		(net "GND")
	)
	(segment
		(start 299.46473 -34.990024)
		(end 297.582844 -34.990024)
		(width 0.3556)
		(layer "F.Cu")
		(net "GND")
	)
	(segment
		(start 55.849774 -294.94988)
		(end 55.374794 -294.4749)
		(width 0.249936)
		(layer "F.Cu")
		(net "GND")
	)
	(segment
		(start 400.824954 -306.824888)
		(end 400.349974 -306.349908)
		(width 0.249936)
		(layer "F.Cu")
		(net "GND")
	)
	(segment
		(start 313.224926 -290.674806)
		(end 313.699906 -290.199826)
		(width 0.249936)
		(layer "F.Cu")
		(net "GND")
	)
	(segment
		(start 114.939318 -265.949938)
		(end 114.240818 -265.949938)
		(width 0.4572)
		(layer "F.Cu")
		(net "GND")
	)
	(segment
		(start 41.599866 -298.74972)
		(end 42.074846 -298.27474)
		(width 0.249936)
		(layer "F.Cu")
		(net "GND")
	)
	(segment
		(start 283.833062 -113.245138)
		(end 282.842462 -113.245138)
		(width 0.3556)
		(layer "F.Cu")
		(net "GND")
	)
	(segment
		(start 386.044948 -29.589984)
		(end 384.96494 -29.589984)
		(width 0.3556)
		(layer "F.Cu")
		(net "GND")
	)
	(segment
		(start 308.474872 -299.224954)
		(end 308.949852 -298.74972)
		(width 0.249936)
		(layer "F.Cu")
		(net "GND")
	)
	(segment
		(start 42.549826 -281.649932)
		(end 42.074846 -281.174952)
		(width 0.249936)
		(layer "F.Cu")
		(net "GND")
	)
	(segment
		(start 289.47491 -300.174914)
		(end 288.99993 -299.699934)
		(width 0.249936)
		(layer "F.Cu")
		(net "GND")
	)
	(segment
		(start 90.054684 -34.990024)
		(end 88.664796 -34.990024)
		(width 0.3556)
		(layer "F.Cu")
		(net "GND")
	)
	(segment
		(start 51.574954 -289.724846)
		(end 51.099974 -290.199826)
		(width 0.249936)
		(layer "F.Cu")
		(net "GND")
	)
	(segment
		(start 71.049896 -301.599854)
		(end 70.574916 -301.124874)
		(width 0.249936)
		(layer "F.Cu")
		(net "GND")
	)
	(segment
		(start 119.457978 -26.606246)
		(end 119.457978 -25.971246)
		(width 0.4572)
		(layer "F.Cu")
		(net "GND")
	)
	(segment
		(start 275.699728 -277.849838)
		(end 275.224748 -277.374858)
		(width 0.249936)
		(layer "F.Cu")
		(net "GND")
	)
	(segment
		(start 103.868982 -223.106742)
		(end 103.369618 -223.206056)
		(width 0.1778)
		(layer "F.Cu")
		(net "GND")
	)
	(segment
		(start 48.72482 -305.874928)
		(end 49.1998 -305.399948)
		(width 0.249936)
		(layer "F.Cu")
		(net "GND")
	)
	(segment
		(start 407.4033 -59.971686)
		(end 407.4033 -60.627006)
		(width 0.381)
		(layer "F.Cu")
		(net "GND")
	)
	(segment
		(start 56.324754 -284.024832)
		(end 56.799988 -284.499812)
		(width 0.249936)
		(layer "F.Cu")
		(net "GND")
	)
	(segment
		(start 187.624974 -294.4749)
		(end 187.149994 -294.94988)
		(width 0.249936)
		(layer "F.Cu")
		(net "GND")
	)
	(segment
		(start 182.39994 -285.449772)
		(end 182.87492 -284.974792)
		(width 0.249936)
		(layer "F.Cu")
		(net "GND")
	)
	(segment
		(start 363.564932 -31.390082)
		(end 364.580932 -31.390082)
		(width 0.3556)
		(layer "F.Cu")
		(net "GND")
	)
	(segment
		(start 262.766302 -338.75091)
		(end 262.766302 -338.25307)
		(width 0.4572)
		(layer "F.Cu")
		(net "GND")
	)
	(segment
		(start 343.69375 -221.58706)
		(end 344.093546 -221.986856)
		(width 0.381)
		(layer "F.Cu")
		(net "GND")
	)
	(segment
		(start 48.860964 -37.201094)
		(end 48.098456 -37.201094)
		(width 0.4572)
		(layer "F.Cu")
		(net "GND")
	)
	(segment
		(start 196.649848 -293.04996)
		(end 196.174868 -292.574726)
		(width 0.249936)
		(layer "F.Cu")
		(net "GND")
	)
	(segment
		(start 397.49984 -307.299868)
		(end 397.97482 -307.774848)
		(width 0.249936)
		(layer "F.Cu")
		(net "GND")
	)
	(segment
		(start 40.649906 -274.999958)
		(end 40.174926 -274.524978)
		(width 0.249936)
		(layer "F.Cu")
		(net "GND")
	)
	(segment
		(start 10.716768 -162.404044)
		(end 10.716768 -163.021518)
		(width 0.4572)
		(layer "F.Cu")
		(net "GND")
	)
	(segment
		(start 162.945572 -125.955044)
		(end 162.14217 -125.955044)
		(width 0.3556)
		(layer "F.Cu")
		(net "GND")
	)
	(segment
		(start 446.787524 -25.742392)
		(end 446.787524 -26.360882)
		(width 0.4572)
		(layer "F.Cu")
		(net "GND")
	)
	(segment
		(start 206.642716 -230.673148)
		(end 206.453994 -230.673148)
		(width 0.4572)
		(layer "F.Cu")
		(net "GND")
	)
	(segment
		(start 271.899888 -273.099784)
		(end 271.424908 -272.624804)
		(width 0.249936)
		(layer "F.Cu")
		(net "GND")
	)
	(segment
		(start 324.448678 -33.19018)
		(end 325.464678 -33.19018)
		(width 0.3556)
		(layer "F.Cu")
		(net "GND")
	)
	(segment
		(start 2.378456 -26.670254)
		(end 2.378456 -27.305254)
		(width 0.381)
		(layer "F.Cu")
		(net "GND")
	)
	(segment
		(start 171.949872 -308.249828)
		(end 171.474892 -307.774848)
		(width 0.127)
		(layer "F.Cu")
		(net "GND")
	)
	(segment
		(start 395.12494 -305.874928)
		(end 395.59992 -305.399948)
		(width 0.249936)
		(layer "F.Cu")
		(net "GND")
	)
	(segment
		(start 71.049896 -298.74972)
		(end 71.524876 -299.224954)
		(width 0.249936)
		(layer "F.Cu")
		(net "GND")
	)
	(segment
		(start 185.250074 -293.04996)
		(end 184.77484 -293.52494)
		(width 0.249936)
		(layer "F.Cu")
		(net "GND")
	)
	(segment
		(start 56.799988 -284.499812)
		(end 57.274968 -284.974792)
		(width 0.249936)
		(layer "F.Cu")
		(net "GND")
	)
	(segment
		(start 45.051726 -122.355102)
		(end 46.042326 -122.355102)
		(width 0.3556)
		(layer "F.Cu")
		(net "GND")
	)
	(segment
		(start 57.749948 -294.94988)
		(end 57.274968 -294.4749)
		(width 0.249936)
		(layer "F.Cu")
		(net "GND")
	)
	(segment
		(start 210.99399 -113.870486)
		(end 211.62899 -113.870486)
		(width 0.4572)
		(layer "F.Cu")
		(net "GND")
	)
	(segment
		(start 180.154834 -34.990024)
		(end 178.764946 -34.990024)
		(width 0.3556)
		(layer "F.Cu")
		(net "GND")
	)
	(segment
		(start 184.380886 -31.390082)
		(end 183.364886 -31.390082)
		(width 0.3556)
		(layer "F.Cu")
		(net "GND")
	)
	(segment
		(start 258.867148 -57.332626)
		(end 258.867148 -56.354218)
		(width 0.4572)
		(layer "F.Cu")
		(net "GND")
	)
	(segment
		(start 282.003246 -120.555004)
		(end 282.842462 -120.555004)
		(width 0.3556)
		(layer "F.Cu")
		(net "GND")
	)
	(segment
		(start 73.424796 -298.27474)
		(end 72.949816 -297.79976)
		(width 0.249936)
		(layer "F.Cu")
		(net "GND")
	)
	(segment
		(start 195.224908 -294.4749)
		(end 195.699888 -294.94988)
		(width 0.249936)
		(layer "F.Cu")
		(net "GND")
	)
	(segment
		(start 54.899814 -293.99992)
		(end 54.424834 -293.52494)
		(width 0.249936)
		(layer "F.Cu")
		(net "GND")
	)
	(segment
		(start 160.549844 -286.399732)
		(end 160.074864 -286.874712)
		(width 0.249936)
		(layer "F.Cu")
		(net "GND")
	)
	(segment
		(start 14.788896 -119.541036)
		(end 14.788896 -120.15343)
		(width 0.4572)
		(layer "F.Cu")
		(net "GND")
	)
	(segment
		(start 297.074844 -284.974792)
		(end 297.549824 -285.449772)
		(width 0.249936)
		(layer "F.Cu")
		(net "GND")
	)
	(segment
		(start 330.687426 -25.742392)
		(end 330.687426 -26.360882)
		(width 0.4572)
		(layer "F.Cu")
		(net "GND")
	)
	(segment
		(start 384.96494 -31.390082)
		(end 385.836414 -31.390082)
		(width 0.3556)
		(layer "F.Cu")
		(net "GND")
	)
	(segment
		(start 188.366908 -123.635008)
		(end 189.357508 -123.635008)
		(width 0.3556)
		(layer "F.Cu")
		(net "GND")
	)
	(segment
		(start 41.124886 -298.27474)
		(end 41.599866 -298.74972)
		(width 0.249936)
		(layer "F.Cu")
		(net "GND")
	)
	(segment
		(start 398.4498 -304.449734)
		(end 397.97482 -303.974754)
		(width 0.249936)
		(layer "F.Cu")
		(net "GND")
	)
	(segment
		(start 283.833062 -125.955044)
		(end 282.842462 -125.955044)
		(width 0.3556)
		(layer "F.Cu")
		(net "GND")
	)
	(segment
		(start 60.599828 -285.449772)
		(end 60.124848 -284.974792)
		(width 0.254)
		(layer "F.Cu")
		(net "GND")
	)
	(segment
		(start 66.299842 -305.399948)
		(end 65.824862 -305.874928)
		(width 0.249936)
		(layer "F.Cu")
		(net "GND")
	)
	(segment
		(start 183.3499 -301.599854)
		(end 183.82488 -302.074834)
		(width 0.249936)
		(layer "F.Cu")
		(net "GND")
	)
	(segment
		(start 79.12481 -300.174914)
		(end 79.59979 -300.649894)
		(width 0.249936)
		(layer "F.Cu")
		(net "GND")
	)
	(segment
		(start 70.099936 -284.499812)
		(end 69.624956 -284.974792)
		(width 0.249936)
		(layer "F.Cu")
		(net "GND")
	)
	(segment
		(start 271.899888 -277.849838)
		(end 271.424908 -277.374858)
		(width 0.249936)
		(layer "F.Cu")
		(net "GND")
	)
	(segment
		(start 309.553864 -84.332318)
		(end 310.219598 -84.332318)
		(width 0.4064)
		(layer "F.Cu")
		(net "GND")
	)
	(segment
		(start 11.680952 -25.990042)
		(end 10.664952 -25.990042)
		(width 0.3556)
		(layer "F.Cu")
		(net "GND")
	)
	(segment
		(start 67.66687 -133.044946)
		(end 68.65747 -133.044946)
		(width 0.3556)
		(layer "F.Cu")
		(net "GND")
	)
	(segment
		(start 400.824954 -285.924752)
		(end 400.349974 -285.449772)
		(width 0.249936)
		(layer "F.Cu")
		(net "GND")
	)
	(segment
		(start 48.24984 -286.399732)
		(end 47.77486 -285.924752)
		(width 0.249936)
		(layer "F.Cu")
		(net "GND")
	)
	(segment
		(start 303.234344 -47.936658)
		(end 303.570132 -47.60087)
		(width 0.254)
		(layer "F.Cu")
		(net "GND")
	)
	(segment
		(start 183.766714 -129.445004)
		(end 184.757314 -129.445004)
		(width 0.3556)
		(layer "F.Cu")
		(net "GND")
	)
	(segment
		(start 71.049896 -298.74972)
		(end 70.574916 -299.224954)
		(width 0.249936)
		(layer "F.Cu")
		(net "GND")
	)
	(segment
		(start 185.783982 -120.716548)
		(end 185.783982 -120.400572)
		(width 0.3556)
		(layer "F.Cu")
		(net "GND")
	)
	(segment
		(start 395.59992 -301.599854)
		(end 395.12494 -302.074834)
		(width 0.249936)
		(layer "F.Cu")
		(net "GND")
	)
	(segment
		(start 237.147354 -37.087048)
		(end 237.782354 -37.087048)
		(width 0.4572)
		(layer "F.Cu")
		(net "GND")
	)
	(segment
		(start 198.473822 -26.606246)
		(end 198.473822 -25.971246)
		(width 0.4572)
		(layer "F.Cu")
		(net "GND")
	)
	(segment
		(start 195.760594 -16.439388)
		(end 195.836794 -16.363188)
		(width 0.4572)
		(layer "F.Cu")
		(net "GND")
	)
	(segment
		(start 352.989642 -64.312292)
		(end 353.748086 -64.312292)
		(width 0.4572)
		(layer "F.Cu")
		(net "GND")
	)
	(segment
		(start 309.899812 -293.04996)
		(end 309.424832 -293.52494)
		(width 0.249936)
		(layer "F.Cu")
		(net "GND")
	)
	(segment
		(start 232.517442 -58.799984)
		(end 233.39044 -58.799984)
		(width 0.3556)
		(layer "F.Cu")
		(net "GND")
	)
	(segment
		(start 301.944786 -143.655796)
		(end 301.645574 -143.955008)
		(width 0.3556)
		(layer "F.Cu")
		(net "GND")
	)
	(segment
		(start 167.732964 -120.555004)
		(end 166.742364 -120.555004)
		(width 0.3556)
		(layer "F.Cu")
		(net "GND")
	)
	(segment
		(start 232.517442 -62.399926)
		(end 233.572558 -62.399926)
		(width 0.3556)
		(layer "F.Cu")
		(net "GND")
	)
	(segment
		(start 244.491256 -305.986942)
		(end 244.196616 -306.281582)
		(width 0.4572)
		(layer "F.Cu")
		(net "GND")
	)
	(segment
		(start 175.749966 -303.499774)
		(end 176.224946 -303.974754)
		(width 0.249936)
		(layer "F.Cu")
		(net "GND")
	)
	(segment
		(start 314.174886 -289.724846)
		(end 314.649866 -290.199826)
		(width 0.249936)
		(layer "F.Cu")
		(net "GND")
	)
	(segment
		(start 88.664034 -291.102034)
		(end 88.8238 -291.2618)
		(width 0.4572)
		(layer "F.Cu")
		(net "GND")
	)
	(segment
		(start 185.418476 -120.035066)
		(end 184.757314 -120.035066)
		(width 0.3556)
		(layer "F.Cu")
		(net "GND")
	)
	(segment
		(start 231.620822 -259.813806)
		(end 231.620822 -259.796534)
		(width 0.254)
		(layer "F.Cu")
		(net "GND")
	)
	(segment
		(start 277.124922 -297.32478)
		(end 277.599902 -296.8498)
		(width 0.249936)
		(layer "F.Cu")
		(net "GND")
	)
	(segment
		(start 11.74496 -27.79014)
		(end 10.664952 -27.79014)
		(width 0.3556)
		(layer "F.Cu")
		(net "GND")
	)
	(segment
		(start 299.449744 -292.099746)
		(end 299.924724 -291.624766)
		(width 0.249936)
		(layer "F.Cu")
		(net "GND")
	)
	(segment
		(start 186.067446 -134.400544)
		(end 185.622946 -134.845044)
		(width 0.3556)
		(layer "F.Cu")
		(net "GND")
	)
	(segment
		(start 389.899906 -278.799798)
		(end 389.424926 -278.324818)
		(width 0.249936)
		(layer "F.Cu")
		(net "GND")
	)
	(segment
		(start 60.124848 -305.874928)
		(end 59.649868 -305.399948)
		(width 0.249936)
		(layer "F.Cu")
		(net "GND")
	)
	(segment
		(start 116.847366 -283.07411)
		(end 116.532152 -283.07411)
		(width 0.2286)
		(layer "F.Cu")
		(net "GND")
	)
	(segment
		(start 422.199816 -297.79976)
		(end 422.674796 -298.27474)
		(width 0.249936)
		(layer "F.Cu")
		(net "GND")
	)
	(segment
		(start 213.874858 -48.753014)
		(end 213.16823 -48.753014)
		(width 0.254)
		(layer "F.Cu")
		(net "GND")
	)
	(segment
		(start 69.624956 -285.924752)
		(end 69.149976 -285.449772)
		(width 0.249936)
		(layer "F.Cu")
		(net "GND")
	)
	(segment
		(start 82.449924 -292.099746)
		(end 82.924904 -291.624766)
		(width 0.249936)
		(layer "F.Cu")
		(net "GND")
	)
	(segment
		(start 72.469502 -147.55495)
		(end 73.257664 -147.55495)
		(width 0.3556)
		(layer "F.Cu")
		(net "GND")
	)
	(segment
		(start 65.349882 -290.199826)
		(end 65.824862 -289.724846)
		(width 0.249936)
		(layer "F.Cu")
		(net "GND")
	)
	(segment
		(start 71.049896 -287.349946)
		(end 70.574916 -286.874966)
		(width 0.249936)
		(layer "F.Cu")
		(net "GND")
	)
	(segment
		(start 421.724836 -292.574726)
		(end 421.249856 -293.04996)
		(width 0.249936)
		(layer "F.Cu")
		(net "GND")
	)
	(segment
		(start 429.325024 -302.074834)
		(end 428.84979 -302.549814)
		(width 0.249936)
		(layer "F.Cu")
		(net "GND")
	)
	(segment
		(start 9.319768 -162.404044)
		(end 9.319768 -163.021518)
		(width 0.4572)
		(layer "F.Cu")
		(net "GND")
	)
	(segment
		(start 417.984178 -122.597164)
		(end 417.984178 -122.200416)
		(width 0.3556)
		(layer "F.Cu")
		(net "GND")
	)
	(segment
		(start 61.549788 -288.299906)
		(end 62.024768 -287.824926)
		(width 0.249936)
		(layer "F.Cu")
		(net "GND")
	)
	(segment
		(start 421.724836 -294.4749)
		(end 422.199816 -293.99992)
		(width 0.249936)
		(layer "F.Cu")
		(net "GND")
	)
	(segment
		(start 52.999894 -292.099746)
		(end 52.524914 -291.624766)
		(width 0.249936)
		(layer "F.Cu")
		(net "GND")
	)
	(segment
		(start 298.024804 -287.824926)
		(end 298.499784 -288.299906)
		(width 0.249936)
		(layer "F.Cu")
		(net "GND")
	)
	(segment
		(start 306.448206 -145.755106)
		(end 305.457606 -145.755106)
		(width 0.3556)
		(layer "F.Cu")
		(net "GND")
	)
	(segment
		(start 272.374868 -284.024832)
		(end 272.849848 -284.499812)
		(width 0.249936)
		(layer "F.Cu")
		(net "GND")
	)
	(segment
		(start 279.024842 -303.974754)
		(end 279.499822 -303.499774)
		(width 0.249936)
		(layer "F.Cu")
		(net "GND")
	)
	(segment
		(start 67.264788 -27.79014)
		(end 66.248788 -27.79014)
		(width 0.3556)
		(layer "F.Cu")
		(net "GND")
	)
	(segment
		(start 281.804872 -105.673652)
		(end 282.17622 -106.045)
		(width 0.3556)
		(layer "F.Cu")
		(net "GND")
	)
	(segment
		(start 72.267064 -125.435106)
		(end 73.257664 -125.435106)
		(width 0.3556)
		(layer "F.Cu")
		(net "GND")
	)
	(segment
		(start 292.32479 -284.974792)
		(end 291.84981 -284.499812)
		(width 0.254)
		(layer "F.Cu")
		(net "GND")
	)
	(segment
		(start 403.199854 -284.499812)
		(end 403.674834 -284.974792)
		(width 0.249936)
		(layer "F.Cu")
		(net "GND")
	)
	(segment
		(start 233.594656 -204.04201)
		(end 232.591864 -204.04201)
		(width 0.4572)
		(layer "F.Cu")
		(net "GND")
	)
	(segment
		(start 408.899868 -305.399948)
		(end 409.374848 -305.874928)
		(width 0.249936)
		(layer "F.Cu")
		(net "GND")
	)
	(segment
		(start 74.248264 -123.635008)
		(end 73.257664 -123.635008)
		(width 0.3556)
		(layer "F.Cu")
		(net "GND")
	)
	(segment
		(start 387.050026 -279.749758)
		(end 386.575046 -279.274778)
		(width 0.249936)
		(layer "F.Cu")
		(net "GND")
	)
	(segment
		(start 413.649922 -296.8498)
		(end 413.174942 -296.37482)
		(width 0.249936)
		(layer "F.Cu")
		(net "GND")
	)
	(segment
		(start 180.50002 -293.99992)
		(end 180.02504 -294.4749)
		(width 0.249936)
		(layer "F.Cu")
		(net "GND")
	)
	(segment
		(start 52.049934 -306.349908)
		(end 51.574954 -305.874928)
		(width 0.249936)
		(layer "F.Cu")
		(net "GND")
	)
	(segment
		(start 151.93264 -383.689098)
		(end 151.93264 -381.370332)
		(width 0.4572)
		(layer "F.Cu")
		(net "GND")
	)
	(segment
		(start 315.147198 -37.087048)
		(end 315.782198 -37.087048)
		(width 0.4572)
		(layer "F.Cu")
		(net "GND")
	)
	(segment
		(start 69.926708 -136.061958)
		(end 69.343524 -136.645142)
		(width 0.3556)
		(layer "F.Cu")
		(net "GND")
	)
	(segment
		(start 403.199854 -285.449772)
		(end 402.724874 -284.974792)
		(width 0.249936)
		(layer "F.Cu")
		(net "GND")
	)
	(segment
		(start 422.548304 -154.755088)
		(end 421.557704 -154.755088)
		(width 0.3556)
		(layer "F.Cu")
		(net "GND")
	)
	(segment
		(start 388.949946 -282.599892)
		(end 388.474966 -282.124912)
		(width 0.249936)
		(layer "F.Cu")
		(net "GND")
	)
	(segment
		(start 228.314504 -64.200024)
		(end 228.238304 -64.276224)
		(width 0.3556)
		(layer "F.Cu")
		(net "GND")
	)
	(segment
		(start 393.351766 -100.64496)
		(end 394.342366 -100.64496)
		(width 0.3556)
		(layer "F.Cu")
		(net "GND")
	)
	(segment
		(start 127.935228 -116.449348)
		(end 127.935228 -115.688364)
		(width 0.4572)
		(layer "F.Cu")
		(net "GND")
	)
	(segment
		(start 69.445632 -143.955008)
		(end 68.65747 -143.955008)
		(width 0.3556)
		(layer "F.Cu")
		(net "GND")
	)
	(segment
		(start 49.1998 -306.349908)
		(end 48.72482 -305.874928)
		(width 0.249936)
		(layer "F.Cu")
		(net "GND")
	)
	(segment
		(start 188.366908 -120.035066)
		(end 189.357508 -120.035066)
		(width 0.3556)
		(layer "F.Cu")
		(net "GND")
	)
	(segment
		(start 418.399976 -291.149786)
		(end 418.874956 -291.624766)
		(width 0.249936)
		(layer "F.Cu")
		(net "GND")
	)
	(segment
		(start 64.399922 -307.299868)
		(end 64.874902 -306.824888)
		(width 0.249936)
		(layer "F.Cu")
		(net "GND")
	)
	(segment
		(start 74.248264 -143.955008)
		(end 73.257664 -143.955008)
		(width 0.3556)
		(layer "F.Cu")
		(net "GND")
	)
	(segment
		(start 293.27475 -287.824926)
		(end 293.74973 -288.299906)
		(width 0.249936)
		(layer "F.Cu")
		(net "GND")
	)
	(segment
		(start 182.39994 -285.449772)
		(end 181.92496 -284.974792)
		(width 0.249936)
		(layer "F.Cu")
		(net "GND")
	)
	(segment
		(start 303.249838 -298.74972)
		(end 303.724818 -299.224954)
		(width 0.249936)
		(layer "F.Cu")
		(net "GND")
	)
	(segment
		(start 288.99993 -299.699934)
		(end 288.524696 -300.174914)
		(width 0.249936)
		(layer "F.Cu")
		(net "GND")
	)
	(segment
		(start 299.866812 -145.755106)
		(end 300.857412 -145.755106)
		(width 0.3556)
		(layer "F.Cu")
		(net "GND")
	)
	(segment
		(start 167.923718 -167.742108)
		(end 167.923718 -168.229788)
		(width 0.4572)
		(layer "F.Cu")
		(net "GND")
	)
	(segment
		(start 300.48073 -34.990024)
		(end 299.46473 -34.990024)
		(width 0.3556)
		(layer "F.Cu")
		(net "GND")
	)
	(segment
		(start 327.928986 -229.785926)
		(end 327.928986 -229.156514)
		(width 0.3556)
		(layer "F.Cu")
		(net "GND")
	)
	(segment
		(start 280.449782 -305.399948)
		(end 280.924762 -305.874928)
		(width 0.249936)
		(layer "F.Cu")
		(net "GND")
	)
	(segment
		(start 120.7897 -64.312292)
		(end 121.548144 -64.312292)
		(width 0.4572)
		(layer "F.Cu")
		(net "GND")
	)
	(segment
		(start 402.249894 -284.499812)
		(end 402.724874 -284.974792)
		(width 0.249936)
		(layer "F.Cu")
		(net "GND")
	)
	(segment
		(start 102.75316 -367.450878)
		(end 102.71506 -367.488978)
		(width 0.4572)
		(layer "F.Cu")
		(net "GND")
	)
	(segment
		(start 100.430838 -242.987322)
		(end 100.630228 -242.787932)
		(width 0.254)
		(layer "F.Cu")
		(net "GND")
	)
	(segment
		(start 15.541244 -114.695478)
		(end 15.541244 -114.436652)
		(width 0.254)
		(layer "F.Cu")
		(net "GND")
	)
	(segment
		(start 396.54988 -287.349946)
		(end 396.0749 -286.874966)
		(width 0.249936)
		(layer "F.Cu")
		(net "GND")
	)
	(segment
		(start 283.774896 -306.824888)
		(end 284.249876 -306.349908)
		(width 0.249936)
		(layer "F.Cu")
		(net "GND")
	)
	(segment
		(start 366.760252 -238.325914)
		(end 366.891062 -238.456724)
		(width 0.3556)
		(layer "F.Cu")
		(net "GND")
	)
	(segment
		(start 37.6809 -25.990042)
		(end 36.6649 -25.990042)
		(width 0.3556)
		(layer "F.Cu")
		(net "GND")
	)
	(segment
		(start 397.746982 -109.177328)
		(end 398.214596 -109.644942)
		(width 0.3556)
		(layer "F.Cu")
		(net "GND")
	)
	(segment
		(start 221.42323 -51.019456)
		(end 220.76791 -51.019456)
		(width 0.254)
		(layer "F.Cu")
		(net "GND")
	)
	(segment
		(start 400.349974 -286.399732)
		(end 400.824954 -285.924752)
		(width 0.249936)
		(layer "F.Cu")
		(net "GND")
	)
	(segment
		(start 184.29986 -287.349946)
		(end 184.77484 -286.874966)
		(width 0.249936)
		(layer "F.Cu")
		(net "GND")
	)
	(segment
		(start 187.149994 -288.299906)
		(end 186.675014 -288.774886)
		(width 0.249936)
		(layer "F.Cu")
		(net "GND")
	)
	(segment
		(start 276.649688 -291.149786)
		(end 276.174708 -290.674806)
		(width 0.249936)
		(layer "F.Cu")
		(net "GND")
	)
	(segment
		(start 342.893904 -221.58706)
		(end 343.2937 -221.986856)
		(width 0.381)
		(layer "F.Cu")
		(net "GND")
	)
	(segment
		(start 405.575008 -289.724846)
		(end 406.049988 -290.199826)
		(width 0.249936)
		(layer "F.Cu")
		(net "GND")
	)
	(segment
		(start 290.42487 -284.024832)
		(end 290.89985 -284.499812)
		(width 0.249936)
		(layer "F.Cu")
		(net "GND")
	)
	(segment
		(start 91.56192 -101.865684)
		(end 91.56192 -101.609398)
		(width 0.254)
		(layer "F.Cu")
		(net "GND")
	)
	(segment
		(start 58.699908 -286.399732)
		(end 58.224928 -285.924752)
		(width 0.249936)
		(layer "F.Cu")
		(net "GND")
	)
	(segment
		(start 267.938504 -136.241028)
		(end 268.512036 -136.81456)
		(width 0.4572)
		(layer "F.Cu")
		(net "GND")
	)
	(segment
		(start 396.54988 -298.74972)
		(end 397.02486 -298.27474)
		(width 0.249936)
		(layer "F.Cu")
		(net "GND")
	)
	(segment
		(start 211.512404 -213.481666)
		(end 211.1375 -213.481666)
		(width 0.4572)
		(layer "F.Cu")
		(net "GND")
	)
	(segment
		(start 154.37485 -298.27474)
		(end 154.850084 -298.74972)
		(width 0.249936)
		(layer "F.Cu")
		(net "GND")
	)
	(segment
		(start 395.59992 -292.099746)
		(end 395.59992 -292.1)
		(width 0.254)
		(layer "F.Cu")
		(net "GND")
	)
	(segment
		(start 169.099992 -286.399732)
		(end 168.625012 -285.924752)
		(width 0.249936)
		(layer "F.Cu")
		(net "GND")
	)
	(segment
		(start 161.500058 -284.499812)
		(end 161.025078 -284.024832)
		(width 0.249936)
		(layer "F.Cu")
		(net "GND")
	)
	(segment
		(start 157.364938 -29.589984)
		(end 158.380938 -29.589984)
		(width 0.3556)
		(layer "F.Cu")
		(net "GND")
	)
	(segment
		(start 18.41881 -147.38604)
		(end 18.21942 -147.18665)
		(width 0.254)
		(layer "F.Cu")
		(net "GND")
	)
	(segment
		(start 38.20795 -156.3624)
		(end 37.57295 -156.3624)
		(width 0.4064)
		(layer "F.Cu")
		(net "GND")
	)
	(segment
		(start 392.749786 -286.399732)
		(end 392.274806 -286.874712)
		(width 0.249936)
		(layer "F.Cu")
		(net "GND")
	)
	(segment
		(start 189.049914 -293.04996)
		(end 188.574934 -292.574726)
		(width 0.249936)
		(layer "F.Cu")
		(net "GND")
	)
	(segment
		(start 419.824916 -298.27474)
		(end 420.299896 -298.74972)
		(width 0.249936)
		(layer "F.Cu")
		(net "GND")
	)
	(segment
		(start 332.33614 -94.864174)
		(end 332.33614 -94.208346)
		(width 0.4572)
		(layer "F.Cu")
		(net "GND")
	)
	(segment
		(start 112.711992 -114.960654)
		(end 113.329466 -114.960654)
		(width 0.4572)
		(layer "F.Cu")
		(net "GND")
	)
	(segment
		(start 157.699964 -297.79976)
		(end 157.224984 -298.27474)
		(width 0.249936)
		(layer "F.Cu")
		(net "GND")
	)
	(segment
		(start 295.649904 -305.399948)
		(end 296.124884 -305.874928)
		(width 0.249936)
		(layer "F.Cu")
		(net "GND")
	)
	(segment
		(start 196.38264 -28.47848)
		(end 196.043296 -28.139136)
		(width 0.254)
		(layer "F.Cu")
		(net "GND")
	)
	(segment
		(start 53.474874 -303.974754)
		(end 52.999894 -303.499774)
		(width 0.249936)
		(layer "F.Cu")
		(net "GND")
	)
	(segment
		(start 26.667206 -57.332626)
		(end 26.667206 -56.354218)
		(width 0.4572)
		(layer "F.Cu")
		(net "GND")
	)
	(segment
		(start 420.567104 -142.15491)
		(end 421.557704 -142.15491)
		(width 0.3556)
		(layer "F.Cu")
		(net "GND")
	)
	(segment
		(start 242.4938 -213.7156)
		(end 241.76355 -212.98535)
		(width 0.4572)
		(layer "F.Cu")
		(net "GND")
	)
	(segment
		(start 279.024842 -306.824888)
		(end 278.549862 -306.349908)
		(width 0.249936)
		(layer "F.Cu")
		(net "GND")
	)
	(segment
		(start 277.599902 -284.499812)
		(end 277.124922 -284.024832)
		(width 0.249936)
		(layer "F.Cu")
		(net "GND")
	)
	(segment
		(start 259.936742 -16.363188)
		(end 259.936742 -15.474188)
		(width 0.4572)
		(layer "F.Cu")
		(net "GND")
	)
	(segment
		(start 408.44089 -54.163722)
		(end 408.992832 -54.163722)
		(width 0.254)
		(layer "F.Cu")
		(net "GND")
	)
	(segment
		(start 417.984178 -120.716548)
		(end 417.984178 -120.400572)
		(width 0.3556)
		(layer "F.Cu")
		(net "GND")
	)
	(segment
		(start 415.074862 -305.874928)
		(end 414.599882 -306.349908)
		(width 0.249936)
		(layer "F.Cu")
		(net "GND")
	)
	(segment
		(start 388.949946 -297.79976)
		(end 389.424926 -298.27474)
		(width 0.249936)
		(layer "F.Cu")
		(net "GND")
	)
	(segment
		(start 397.02486 -306.824888)
		(end 396.54988 -306.349908)
		(width 0.249936)
		(layer "F.Cu")
		(net "GND")
	)
	(segment
		(start 401.774914 -302.074834)
		(end 401.299934 -301.599854)
		(width 0.249936)
		(layer "F.Cu")
		(net "GND")
	)
	(segment
		(start 310.374792 -303.024794)
		(end 310.849772 -302.549814)
		(width 0.249936)
		(layer "F.Cu")
		(net "GND")
	)
	(segment
		(start 282.824936 -306.824888)
		(end 283.299916 -306.349908)
		(width 0.249936)
		(layer "F.Cu")
		(net "GND")
	)
	(segment
		(start 290.42487 -283.074872)
		(end 290.89985 -282.599892)
		(width 0.249936)
		(layer "F.Cu")
		(net "GND")
	)
	(segment
		(start 170.049952 -290.199826)
		(end 169.574972 -289.724846)
		(width 0.249936)
		(layer "F.Cu")
		(net "GND")
	)
	(segment
		(start 231.149144 -178.38039)
		(end 231.149144 -178.642772)
		(width 0.4572)
		(layer "F.Cu")
		(net "GND")
	)
	(segment
		(start 185.725054 -293.52494)
		(end 185.250074 -293.99992)
		(width 0.249936)
		(layer "F.Cu")
		(net "GND")
	)
	(segment
		(start 281.399742 -284.499812)
		(end 280.924762 -284.024832)
		(width 0.249936)
		(layer "F.Cu")
		(net "GND")
	)
	(segment
		(start 303.724818 -298.27474)
		(end 303.249838 -298.74972)
		(width 0.249936)
		(layer "F.Cu")
		(net "GND")
	)
	(segment
		(start 69.64807 -129.445004)
		(end 68.65747 -129.445004)
		(width 0.3556)
		(layer "F.Cu")
		(net "GND")
	)
	(segment
		(start 99.776534 -6.541516)
		(end 99.27844 -6.541516)
		(width 0.4572)
		(layer "F.Cu")
		(net "GND")
	)
	(segment
		(start 344.49385 -219.987114)
		(end 344.893646 -220.38691)
		(width 0.381)
		(layer "F.Cu")
		(net "GND")
	)
	(segment
		(start 280.571448 -408.115008)
		(end 281.33548 -408.115008)
		(width 0.4572)
		(layer "F.Cu")
		(net "GND")
	)
	(segment
		(start 289.47491 -305.874928)
		(end 289.94989 -305.399948)
		(width 0.249936)
		(layer "F.Cu")
		(net "GND")
	)
	(segment
		(start 416.974782 -298.27474)
		(end 416.499802 -298.74972)
		(width 0.249936)
		(layer "F.Cu")
		(net "GND")
	)
	(segment
		(start 299.866812 -125.435106)
		(end 300.857412 -125.435106)
		(width 0.3556)
		(layer "F.Cu")
		(net "GND")
	)
	(segment
		(start 73.289922 -73.166732)
		(end 73.289922 -73.85177)
		(width 0.4572)
		(layer "F.Cu")
		(net "GND")
	)
	(segment
		(start 52.425092 -14.735302)
		(end 52.425092 -14.100302)
		(width 0.381)
		(layer "F.Cu")
		(net "GND")
	)
	(segment
		(start 362.294932 -159.336232)
		(end 362.294932 -158.705042)
		(width 0.254)
		(layer "F.Cu")
		(net "GND")
	)
	(segment
		(start 399.400014 -307.299868)
		(end 398.925034 -306.824888)
		(width 0.249936)
		(layer "F.Cu")
		(net "GND")
	)
	(segment
		(start 231.846882 -143.265398)
		(end 231.846882 -142.889478)
		(width 0.2032)
		(layer "F.Cu")
		(net "GND")
	)
	(segment
		(start 428.84979 -296.8498)
		(end 429.325024 -297.32478)
		(width 0.249936)
		(layer "F.Cu")
		(net "GND")
	)
	(segment
		(start 61.549788 -307.299868)
		(end 61.074808 -307.774848)
		(width 0.249936)
		(layer "F.Cu")
		(net "GND")
	)
	(segment
		(start 283.774896 -287.824926)
		(end 284.249876 -288.299906)
		(width 0.249936)
		(layer "F.Cu")
		(net "GND")
	)
	(segment
		(start 71.524876 -298.27474)
		(end 71.049896 -297.79976)
		(width 0.249936)
		(layer "F.Cu")
		(net "GND")
	)
	(segment
		(start 319.140332 -143.582898)
		(end 317.083948 -143.582898)
		(width 0.4572)
		(layer "F.Cu")
		(net "GND")
	)
	(segment
		(start 437.12384 -291.2618)
		(end 436.964074 -291.102034)
		(width 0.4572)
		(layer "F.Cu")
		(net "GND")
	)
	(segment
		(start 48.24984 -303.499774)
		(end 47.77486 -303.974754)
		(width 0.249936)
		(layer "F.Cu")
		(net "GND")
	)
	(segment
		(start 63.924942 -284.974792)
		(end 64.399922 -284.499812)
		(width 0.249936)
		(layer "F.Cu")
		(net "GND")
	)
	(segment
		(start 296.599864 -297.79976)
		(end 297.074844 -298.27474)
		(width 0.249936)
		(layer "F.Cu")
		(net "GND")
	)
	(segment
		(start 452.909178 -109.032548)
		(end 452.909178 -108.39196)
		(width 0.4572)
		(layer "F.Cu")
		(net "GND")
	)
	(segment
		(start 286.149796 -284.499812)
		(end 286.624776 -284.974792)
		(width 0.249936)
		(layer "F.Cu")
		(net "GND")
	)
	(segment
		(start 167.73271 -107.845098)
		(end 167.732964 -107.844844)
		(width 0.4572)
		(layer "F.Cu")
		(net "GND")
	)
	(segment
		(start 301.88408 -122.597164)
		(end 301.88408 -122.200416)
		(width 0.3556)
		(layer "F.Cu")
		(net "GND")
	)
	(segment
		(start 392.749786 -294.94988)
		(end 392.274806 -294.4749)
		(width 0.249936)
		(layer "F.Cu")
		(net "GND")
	)
	(segment
		(start 68.674742 -291.624766)
		(end 69.149976 -292.099746)
		(width 0.249936)
		(layer "F.Cu")
		(net "GND")
	)
	(segment
		(start 303.249838 -291.149786)
		(end 302.774858 -290.674806)
		(width 0.249936)
		(layer "F.Cu")
		(net "GND")
	)
	(segment
		(start 62.664848 -31.390082)
		(end 63.536322 -31.390082)
		(width 0.3556)
		(layer "F.Cu")
		(net "GND")
	)
	(segment
		(start 123.31319 -140.392404)
		(end 122.65787 -140.392404)
		(width 0.4064)
		(layer "F.Cu")
		(net "GND")
	)
	(segment
		(start 50.14976 -289.249866)
		(end 49.67478 -288.774886)
		(width 0.249936)
		(layer "F.Cu")
		(net "GND")
	)
	(segment
		(start 182.39994 -299.699934)
		(end 182.87492 -300.174914)
		(width 0.249936)
		(layer "F.Cu")
		(net "GND")
	)
	(segment
		(start 287.574736 -284.024832)
		(end 287.099756 -284.499812)
		(width 0.249936)
		(layer "F.Cu")
		(net "GND")
	)
	(segment
		(start 456.972162 -307.492146)
		(end 457.491338 -306.97297)
		(width 0.1778)
		(layer "F.Cu")
		(net "GND")
	)
	(segment
		(start 285.98495 -86.106)
		(end 285.369 -86.106)
		(width 0.4572)
		(layer "F.Cu")
		(net "GND")
	)
	(segment
		(start 305.624738 -292.574726)
		(end 305.149758 -293.04996)
		(width 0.249936)
		(layer "F.Cu")
		(net "GND")
	)
	(segment
		(start 420.7256 -133.044946)
		(end 421.557704 -133.044946)
		(width 0.3556)
		(layer "F.Cu")
		(net "GND")
	)
	(segment
		(start 133.61162 -146.263614)
		(end 133.61162 -145.837656)
		(width 0.4064)
		(layer "F.Cu")
		(net "GND")
	)
	(segment
		(start 283.299916 -297.79976)
		(end 282.824936 -298.27474)
		(width 0.249936)
		(layer "F.Cu")
		(net "GND")
	)
	(segment
		(start 60.124848 -289.724846)
		(end 60.599828 -290.199826)
		(width 0.249936)
		(layer "F.Cu")
		(net "GND")
	)
	(segment
		(start 231.149144 -175.70958)
		(end 231.149144 -176.72558)
		(width 0.4572)
		(layer "F.Cu")
		(net "GND")
	)
	(segment
		(start 314.649866 -299.699934)
		(end 314.174886 -299.224954)
		(width 0.249936)
		(layer "F.Cu")
		(net "GND")
	)
	(segment
		(start 430.274984 -296.37482)
		(end 430.749964 -295.89984)
		(width 0.249936)
		(layer "F.Cu")
		(net "GND")
	)
	(segment
		(start 198.550022 -297.79976)
		(end 199.025002 -297.32478)
		(width 0.249936)
		(layer "F.Cu")
		(net "GND")
	)
	(segment
		(start 301.88408 -124.000514)
		(end 301.518574 -123.635008)
		(width 0.3556)
		(layer "F.Cu")
		(net "GND")
	)
	(segment
		(start 417.924996 -294.4749)
		(end 417.450016 -293.99992)
		(width 0.249936)
		(layer "F.Cu")
		(net "GND")
	)
	(segment
		(start 54.424834 -284.974792)
		(end 54.899814 -284.499812)
		(width 0.249936)
		(layer "F.Cu")
		(net "GND")
	)
	(segment
		(start 281.399742 -286.399732)
		(end 280.924762 -285.924752)
		(width 0.249936)
		(layer "F.Cu")
		(net "GND")
	)
	(segment
		(start 273.799808 -297.79976)
		(end 274.274788 -298.27474)
		(width 0.249936)
		(layer "F.Cu")
		(net "GND")
	)
	(segment
		(start 58.577226 -373.620284)
		(end 58.23204 -373.275098)
		(width 0.4572)
		(layer "F.Cu")
		(net "GND")
	)
	(segment
		(start 297.074844 -305.874928)
		(end 296.599864 -305.399948)
		(width 0.249936)
		(layer "F.Cu")
		(net "GND")
	)
	(segment
		(start 308.357524 -81.749646)
		(end 308.571646 -81.749646)
		(width 0.4064)
		(layer "F.Cu")
		(net "GND")
	)
	(segment
		(start 303.724818 -303.024794)
		(end 303.249838 -303.499774)
		(width 0.249936)
		(layer "F.Cu")
		(net "GND")
	)
	(segment
		(start 405.575008 -306.824888)
		(end 405.100028 -307.299868)
		(width 0.249936)
		(layer "F.Cu")
		(net "GND")
	)
	(segment
		(start 221.617286 -86.237064)
		(end 221.96679 -86.586568)
		(width 0.4572)
		(layer "F.Cu")
		(net "GND")
	)
	(segment
		(start 3.228086 -44.037758)
		(end 3.228086 -44.647358)
		(width 0.4572)
		(layer "F.Cu")
		(net "GND")
	)
	(segment
		(start 452.7804 -222.123)
		(end 452.7804 -222.377)
		(width 0.2794)
		(layer "F.Cu")
		(net "GND")
	)
	(segment
		(start 395.77264 -113.245138)
		(end 394.342366 -113.245138)
		(width 0.3556)
		(layer "F.Cu")
		(net "GND")
	)
	(segment
		(start 440.895994 -103.259128)
		(end 440.895994 -103.894128)
		(width 0.4572)
		(layer "F.Cu")
		(net "GND")
	)
	(segment
		(start 284.249876 -288.299906)
		(end 284.724856 -287.824926)
		(width 0.249936)
		(layer "F.Cu")
		(net "GND")
	)
	(segment
		(start 246.250714 -159.392112)
		(end 246.250714 -159.857948)
		(width 0.254)
		(layer "F.Cu")
		(net "GND")
	)
	(segment
		(start 369.447064 -53.144166)
		(end 369.447064 -52.592224)
		(width 0.254)
		(layer "F.Cu")
		(net "GND")
	)
	(segment
		(start 426.47489 -299.224954)
		(end 425.99991 -298.74972)
		(width 0.249936)
		(layer "F.Cu")
		(net "GND")
	)
	(segment
		(start 290.42487 -303.974754)
		(end 289.94989 -303.499774)
		(width 0.249936)
		(layer "F.Cu")
		(net "GND")
	)
	(segment
		(start 166.561008 -169.23385)
		(end 166.561008 -169.89679)
		(width 0.4572)
		(layer "F.Cu")
		(net "GND")
	)
	(segment
		(start 142.474442 -252.756924)
		(end 142.474442 -253.45644)
		(width 0.4572)
		(layer "F.Cu")
		(net "GND")
	)
	(segment
		(start 64.874902 -285.924752)
		(end 64.399922 -285.449772)
		(width 0.249936)
		(layer "F.Cu")
		(net "GND")
	)
	(segment
		(start 386.099812 -294.94988)
		(end 385.624832 -294.4749)
		(width 0.249936)
		(layer "F.Cu")
		(net "GND")
	)
	(segment
		(start 289.94989 -286.399732)
		(end 290.42487 -285.924752)
		(width 0.249936)
		(layer "F.Cu")
		(net "GND")
	)
	(segment
		(start 447.745866 -46.693836)
		(end 447.218562 -46.693836)
		(width 0.254)
		(layer "F.Cu")
		(net "GND")
	)
	(segment
		(start 54.899814 -307.299868)
		(end 54.424834 -306.824888)
		(width 0.249936)
		(layer "F.Cu")
		(net "GND")
	)
	(segment
		(start 225.152712 -238.98733)
		(end 223.512634 -238.98733)
		(width 0.4572)
		(layer "F.Cu")
		(net "GND")
	)
	(segment
		(start 285.199836 -295.89984)
		(end 284.724856 -296.37482)
		(width 0.249936)
		(layer "F.Cu")
		(net "GND")
	)
	(segment
		(start 47.29988 -286.399732)
		(end 46.8249 -285.924752)
		(width 0.249936)
		(layer "F.Cu")
		(net "GND")
	)
	(segment
		(start 72.949816 -294.94988)
		(end 73.424796 -294.4749)
		(width 0.249936)
		(layer "F.Cu")
		(net "GND")
	)
	(segment
		(start 50.624994 -306.824888)
		(end 51.099974 -306.349908)
		(width 0.249936)
		(layer "F.Cu")
		(net "GND")
	)
	(segment
		(start 109.01299 -110.28553)
		(end 109.64418 -110.28553)
		(width 0.254)
		(layer "F.Cu")
		(net "GND")
	)
	(segment
		(start 248.8057 -83.431888)
		(end 248.1961 -83.431888)
		(width 0.4572)
		(layer "F.Cu")
		(net "GND")
	)
	(segment
		(start 269.736316 -31.390082)
		(end 269.988538 -31.642304)
		(width 0.3556)
		(layer "F.Cu")
		(net "GND")
	)
	(segment
		(start 171.949872 -285.449772)
		(end 171.474892 -284.974792)
		(width 0.249936)
		(layer "F.Cu")
		(net "GND")
	)
	(segment
		(start 58.699908 -284.499812)
		(end 58.224928 -284.974792)
		(width 0.249936)
		(layer "F.Cu")
		(net "GND")
	)
	(segment
		(start 67.66687 -149.355048)
		(end 68.65747 -149.355048)
		(width 0.3556)
		(layer "F.Cu")
		(net "GND")
	)
	(segment
		(start 294.69969 -286.399732)
		(end 294.22471 -285.924752)
		(width 0.249936)
		(layer "F.Cu")
		(net "GND")
	)
	(segment
		(start 22.861016 -37.201094)
		(end 22.098508 -37.201094)
		(width 0.4572)
		(layer "F.Cu")
		(net "GND")
	)
	(segment
		(start 165.432232 -120.084088)
		(end 165.903148 -120.555004)
		(width 0.3556)
		(layer "F.Cu")
		(net "GND")
	)
	(segment
		(start 104.299004 -386.917184)
		(end 104.299004 -387.601714)
		(width 0.4572)
		(layer "F.Cu")
		(net "GND")
	)
	(segment
		(start 270.949928 -274.999958)
		(end 270.474948 -274.524978)
		(width 0.249936)
		(layer "F.Cu")
		(net "GND")
	)
	(segment
		(start 424.57497 -293.52494)
		(end 425.04995 -293.04996)
		(width 0.249936)
		(layer "F.Cu")
		(net "GND")
	)
	(segment
		(start 378.452634 -89.9668)
		(end 377.53544 -89.9668)
		(width 0.4572)
		(layer "F.Cu")
		(net "GND")
	)
	(segment
		(start 189.524894 -292.574726)
		(end 189.049914 -293.04996)
		(width 0.249936)
		(layer "F.Cu")
		(net "GND")
	)
	(segment
		(start 194.749928 -292.099746)
		(end 195.224908 -292.574726)
		(width 0.249936)
		(layer "F.Cu")
		(net "GND")
	)
	(segment
		(start 235.557822 -26.606246)
		(end 235.557822 -25.971246)
		(width 0.4572)
		(layer "F.Cu")
		(net "GND")
	)
	(segment
		(start 156.750004 -282.599892)
		(end 156.275024 -282.124912)
		(width 0.249936)
		(layer "F.Cu")
		(net "GND")
	)
	(segment
		(start 62.024768 -291.624766)
		(end 62.499748 -292.099746)
		(width 0.249936)
		(layer "F.Cu")
		(net "GND")
	)
	(segment
		(start 387.006084 -161.276284)
		(end 387.30809 -160.974278)
		(width 0.4572)
		(layer "F.Cu")
		(net "GND")
	)
	(segment
		(start 72.267064 -129.445004)
		(end 73.257664 -129.445004)
		(width 0.3556)
		(layer "F.Cu")
		(net "GND")
	)
	(segment
		(start 421.724836 -304.924714)
		(end 422.199816 -304.449734)
		(width 0.249936)
		(layer "F.Cu")
		(net "GND")
	)
	(segment
		(start 161.120582 -151.159972)
		(end 162.14217 -151.159972)
		(width 0.3556)
		(layer "F.Cu")
		(net "GND")
	)
	(segment
		(start 245.452138 -34.990024)
		(end 247.464834 -34.990024)
		(width 0.3556)
		(layer "F.Cu")
		(net "GND")
	)
	(segment
		(start 280.449782 -302.549814)
		(end 279.974802 -303.024794)
		(width 0.249936)
		(layer "F.Cu")
		(net "GND")
	)
	(segment
		(start 282.661106 -169.23385)
		(end 282.661106 -169.89679)
		(width 0.4572)
		(layer "F.Cu")
		(net "GND")
	)
	(segment
		(start 69.80428 -132.622036)
		(end 69.38137 -133.044946)
		(width 0.3556)
		(layer "F.Cu")
		(net "GND")
	)
	(segment
		(start 237.900464 -228.417374)
		(end 238.299752 -228.816662)
		(width 0.4572)
		(layer "F.Cu")
		(net "GND")
	)
	(segment
		(start 394.17498 -287.824926)
		(end 394.64996 -288.299906)
		(width 0.249936)
		(layer "F.Cu")
		(net "GND")
	)
	(segment
		(start 312.675016 -64.102234)
		(end 311.969404 -64.102234)
		(width 0.4572)
		(layer "F.Cu")
		(net "GND")
	)
	(segment
		(start 415.564828 -33.19018)
		(end 416.580828 -33.19018)
		(width 0.3556)
		(layer "F.Cu")
		(net "GND")
	)
	(segment
		(start 321.201542 -303.636426)
		(end 321.201542 -303.026826)
		(width 0.4572)
		(layer "F.Cu")
		(net "GND")
	)
	(segment
		(start 415.96691 -116.435124)
		(end 416.95751 -116.435124)
		(width 0.3556)
		(layer "F.Cu")
		(net "GND")
	)
	(segment
		(start 210.380834 -34.990024)
		(end 209.364834 -34.990024)
		(width 0.3556)
		(layer "F.Cu")
		(net "GND")
	)
	(segment
		(start 189.524894 -296.37482)
		(end 189.049914 -296.8498)
		(width 0.249936)
		(layer "F.Cu")
		(net "GND")
	)
	(segment
		(start 380.72695 -201.168)
		(end 380.111 -201.168)
		(width 0.4572)
		(layer "F.Cu")
		(net "GND")
	)
	(segment
		(start 170.999912 -284.499812)
		(end 170.524932 -284.974792)
		(width 0.249936)
		(layer "F.Cu")
		(net "GND")
	)
	(segment
		(start 425.04995 -298.74972)
		(end 424.57497 -298.27474)
		(width 0.249936)
		(layer "F.Cu")
		(net "GND")
	)
	(segment
		(start 413.174942 -284.974792)
		(end 413.649922 -284.499812)
		(width 0.249936)
		(layer "F.Cu")
		(net "GND")
	)
	(segment
		(start 77.69987 -296.8498)
		(end 78.17485 -297.32478)
		(width 0.249936)
		(layer "F.Cu")
		(net "GND")
	)
	(segment
		(start 301.848012 -142.15491)
		(end 300.857412 -142.15491)
		(width 0.3556)
		(layer "F.Cu")
		(net "GND")
	)
	(segment
		(start 387.050026 -294.94988)
		(end 386.575046 -294.4749)
		(width 0.249936)
		(layer "F.Cu")
		(net "GND")
	)
	(segment
		(start 157.224984 -299.224954)
		(end 157.699964 -298.74972)
		(width 0.249936)
		(layer "F.Cu")
		(net "GND")
	)
	(segment
		(start 196.649848 -300.649894)
		(end 197.125082 -300.174914)
		(width 0.249936)
		(layer "F.Cu")
		(net "GND")
	)
	(segment
		(start 397.02486 -296.37482)
		(end 397.49984 -295.89984)
		(width 0.249936)
		(layer "F.Cu")
		(net "GND")
	)
	(segment
		(start 205.689454 -295.647872)
		(end 205.689454 -294.727884)
		(width 0.4572)
		(layer "F.Cu")
		(net "GND")
	)
	(segment
		(start 4.675886 -394.152628)
		(end 4.682236 -394.146278)
		(width 0.4572)
		(layer "F.Cu")
		(net "GND")
	)
	(segment
		(start 40.649906 -284.499812)
		(end 40.174926 -284.024832)
		(width 0.249936)
		(layer "F.Cu")
		(net "GND")
	)
	(segment
		(start 276.649688 -293.04996)
		(end 276.174708 -292.57498)
		(width 0.249936)
		(layer "F.Cu")
		(net "GND")
	)
	(segment
		(start 387.050026 -293.04996)
		(end 386.575046 -292.57498)
		(width 0.249936)
		(layer "F.Cu")
		(net "GND")
	)
	(segment
		(start 412.430214 -196.80682)
		(end 411.571186 -196.80682)
		(width 0.4572)
		(layer "F.Cu")
		(net "GND")
	)
	(segment
		(start 413.649922 -286.399732)
		(end 414.124902 -285.924752)
		(width 0.249936)
		(layer "F.Cu")
		(net "GND")
	)
	(segment
		(start 187.149994 -295.89984)
		(end 187.624974 -296.37482)
		(width 0.249936)
		(layer "F.Cu")
		(net "GND")
	)
	(segment
		(start 172.900086 -297.79976)
		(end 173.375066 -297.32478)
		(width 0.249936)
		(layer "F.Cu")
		(net "GND")
	)
	(segment
		(start 297.549824 -301.599854)
		(end 297.074844 -302.074834)
		(width 0.249936)
		(layer "F.Cu")
		(net "GND")
	)
	(segment
		(start 285.674816 -307.774848)
		(end 285.199836 -307.299868)
		(width 0.249936)
		(layer "F.Cu")
		(net "GND")
	)
	(segment
		(start 71.524876 -293.52494)
		(end 71.049896 -293.99992)
		(width 0.249936)
		(layer "F.Cu")
		(net "GND")
	)
	(segment
		(start 184.77484 -290.674806)
		(end 184.29986 -290.199826)
		(width 0.249936)
		(layer "F.Cu")
		(net "GND")
	)
	(segment
		(start 74.374756 -290.674806)
		(end 73.899776 -291.149786)
		(width 0.249936)
		(layer "F.Cu")
		(net "GND")
	)
	(segment
		(start 175.749966 -294.94988)
		(end 176.224946 -294.4749)
		(width 0.249936)
		(layer "F.Cu")
		(net "GND")
	)
	(segment
		(start 403.674834 -300.174914)
		(end 403.199854 -299.699934)
		(width 0.249936)
		(layer "F.Cu")
		(net "GND")
	)
	(segment
		(start 151.2951 -59.978036)
		(end 151.2951 -60.633356)
		(width 0.4572)
		(layer "F.Cu")
		(net "GND")
	)
	(segment
		(start 45.051726 -131.76504)
		(end 46.042326 -131.76504)
		(width 0.3556)
		(layer "F.Cu")
		(net "GND")
	)
	(segment
		(start 290.89985 -284.499812)
		(end 290.42487 -284.974792)
		(width 0.249936)
		(layer "F.Cu")
		(net "GND")
	)
	(segment
		(start 72.474836 -292.574726)
		(end 72.949816 -293.04996)
		(width 0.249936)
		(layer "F.Cu")
		(net "GND")
	)
	(segment
		(start 44.449746 -297.79976)
		(end 43.974766 -298.27474)
		(width 0.249936)
		(layer "F.Cu")
		(net "GND")
	)
	(segment
		(start 196.48551 -34.183066)
		(end 196.370956 -34.29762)
		(width 0.4572)
		(layer "F.Cu")
		(net "GND")
	)
	(segment
		(start 326.007476 -85.85073)
		(end 326.49668 -85.361526)
		(width 0.4572)
		(layer "F.Cu")
		(net "GND")
	)
	(segment
		(start 129.59461 -158.705042)
		(end 129.59461 -159.498792)
		(width 0.254)
		(layer "F.Cu")
		(net "GND")
	)
	(segment
		(start 173.850046 -306.349908)
		(end 173.375066 -306.824888)
		(width 0.249936)
		(layer "F.Cu")
		(net "GND")
	)
	(segment
		(start 69.494654 -118.234968)
		(end 68.65747 -118.234968)
		(width 0.3556)
		(layer "F.Cu")
		(net "GND")
	)
	(segment
		(start 161.500058 -288.299906)
		(end 161.025078 -287.824926)
		(width 0.249936)
		(layer "F.Cu")
		(net "GND")
	)
	(segment
		(start 275.871432 -386.951982)
		(end 275.204682 -386.951982)
		(width 0.4572)
		(layer "F.Cu")
		(net "GND")
	)
	(segment
		(start 183.3499 -306.349908)
		(end 182.87492 -305.874928)
		(width 0.249936)
		(layer "F.Cu")
		(net "GND")
	)
	(segment
		(start 185.725054 -284.024832)
		(end 186.200034 -284.499812)
		(width 0.249936)
		(layer "F.Cu")
		(net "GND")
	)
	(segment
		(start 406.524968 -284.974792)
		(end 406.999948 -284.499812)
		(width 0.249936)
		(layer "F.Cu")
		(net "GND")
	)
	(segment
		(start 79.12481 -302.074834)
		(end 79.59979 -302.549814)
		(width 0.249936)
		(layer "F.Cu")
		(net "GND")
	)
	(segment
		(start 415.549842 -306.349908)
		(end 416.024822 -306.824888)
		(width 0.249936)
		(layer "F.Cu")
		(net "GND")
	)
	(segment
		(start 55.374794 -305.874928)
		(end 54.899814 -305.399948)
		(width 0.249936)
		(layer "F.Cu")
		(net "GND")
	)
	(segment
		(start 18.869914 -414.369758)
		(end 18.869914 -414.985454)
		(width 0.4572)
		(layer "F.Cu")
		(net "GND")
	)
	(segment
		(start 286.624776 -306.824888)
		(end 286.149796 -306.349908)
		(width 0.249936)
		(layer "F.Cu")
		(net "GND")
	)
	(segment
		(start 341.774272 -112.785652)
		(end 341.212932 -112.785652)
		(width 0.254)
		(layer "F.Cu")
		(net "GND")
	)
	(segment
		(start 238.15929 -209.164428)
		(end 239.14989 -209.164428)
		(width 0.4572)
		(layer "F.Cu")
		(net "GND")
	)
	(segment
		(start 57.694068 -35.264852)
		(end 57.694068 -35.499548)
		(width 0.4572)
		(layer "F.Cu")
		(net "GND")
	)
	(segment
		(start 55.872126 -33.248092)
		(end 55.872126 -33.857692)
		(width 0.4572)
		(layer "F.Cu")
		(net "GND")
	)
	(segment
		(start 287.099756 -284.499812)
		(end 287.574736 -284.974792)
		(width 0.249936)
		(layer "F.Cu")
		(net "GND")
	)
	(segment
		(start 181.44998 -285.449772)
		(end 181.92496 -284.974792)
		(width 0.249936)
		(layer "F.Cu")
		(net "GND")
	)
	(segment
		(start 193.143378 -82.421476)
		(end 192.471548 -81.749646)
		(width 0.4064)
		(layer "F.Cu")
		(net "GND")
	)
	(segment
		(start 325.612506 -196.234304)
		(end 325.002906 -196.234304)
		(width 0.4572)
		(layer "F.Cu")
		(net "GND")
	)
	(segment
		(start 271.899888 -278.799798)
		(end 271.424908 -278.324818)
		(width 0.249936)
		(layer "F.Cu")
		(net "GND")
	)
	(segment
		(start 178.599846 -284.499812)
		(end 178.124866 -284.974792)
		(width 0.249936)
		(layer "F.Cu")
		(net "GND")
	)
	(segment
		(start 408.899868 -292.099746)
		(end 409.374848 -291.624766)
		(width 0.249936)
		(layer "F.Cu")
		(net "GND")
	)
	(segment
		(start 374.674384 -252.756924)
		(end 374.674384 -253.45644)
		(width 0.4572)
		(layer "F.Cu")
		(net "GND")
	)
	(segment
		(start 419.824916 -297.32478)
		(end 419.349936 -296.8498)
		(width 0.249936)
		(layer "F.Cu")
		(net "GND")
	)
	(segment
		(start 76.74991 -289.249866)
		(end 76.27493 -289.724846)
		(width 0.249936)
		(layer "F.Cu")
		(net "GND")
	)
	(segment
		(start 198.701406 -412.464504)
		(end 198.701406 -411.507686)
		(width 0.4572)
		(layer "F.Cu")
		(net "GND")
	)
	(segment
		(start 398.4498 -303.499774)
		(end 398.925034 -303.974754)
		(width 0.249936)
		(layer "F.Cu")
		(net "GND")
	)
	(segment
		(start 307.999892 -292.099746)
		(end 308.474872 -291.624766)
		(width 0.249936)
		(layer "F.Cu")
		(net "GND")
	)
	(segment
		(start 338.47405 -185.039)
		(end 339.09 -185.039)
		(width 0.4572)
		(layer "F.Cu")
		(net "GND")
	)
	(segment
		(start 93.621098 -103.280464)
		(end 93.621098 -103.890064)
		(width 0.4572)
		(layer "F.Cu")
		(net "GND")
	)
	(segment
		(start 71.257922 -73.166732)
		(end 71.257922 -73.85177)
		(width 0.4572)
		(layer "F.Cu")
		(net "GND")
	)
	(segment
		(start 404.149814 -286.399732)
		(end 404.624794 -285.924752)
		(width 0.249936)
		(layer "F.Cu")
		(net "GND")
	)
	(segment
		(start 112.979962 -114.22634)
		(end 111.015018 -114.22634)
		(width 0.254)
		(layer "F.Cu")
		(net "GND")
	)
	(segment
		(start 76.74991 -293.04996)
		(end 77.22489 -293.52494)
		(width 0.249936)
		(layer "F.Cu")
		(net "GND")
	)
	(segment
		(start 78.643734 -45.88891)
		(end 79.315056 -45.88891)
		(width 0.254)
		(layer "F.Cu")
		(net "GND")
	)
	(segment
		(start 44.449746 -290.199826)
		(end 43.974766 -289.724846)
		(width 0.249936)
		(layer "F.Cu")
		(net "GND")
	)
	(segment
		(start 413.649922 -285.449772)
		(end 413.174942 -285.924752)
		(width 0.249936)
		(layer "F.Cu")
		(net "GND")
	)
	(segment
		(start 302.299878 -284.499812)
		(end 301.824898 -284.024832)
		(width 0.249936)
		(layer "F.Cu")
		(net "GND")
	)
	(segment
		(start 168.625012 -285.924752)
		(end 168.150032 -286.399732)
		(width 0.249936)
		(layer "F.Cu")
		(net "GND")
	)
	(segment
		(start 79.12481 -294.4749)
		(end 78.64983 -294.94988)
		(width 0.249936)
		(layer "F.Cu")
		(net "GND")
	)
	(segment
		(start 61.074808 -302.074834)
		(end 60.599828 -301.599854)
		(width 0.249936)
		(layer "F.Cu")
		(net "GND")
	)
	(segment
		(start 288.049716 -307.299868)
		(end 287.574736 -306.824888)
		(width 0.249936)
		(layer "F.Cu")
		(net "GND")
	)
	(segment
		(start 83.434174 -6.046724)
		(end 84.04987 -6.046724)
		(width 0.4572)
		(layer "F.Cu")
		(net "GND")
	)
	(segment
		(start 271.382744 -140.85697)
		(end 271.752822 -140.85697)
		(width 0.4572)
		(layer "F.Cu")
		(net "GND")
	)
	(segment
		(start 77.69987 -300.649894)
		(end 77.22489 -301.124874)
		(width 0.249936)
		(layer "F.Cu")
		(net "GND")
	)
	(segment
		(start 404.149814 -286.399732)
		(end 403.674834 -285.924752)
		(width 0.249936)
		(layer "F.Cu")
		(net "GND")
	)
	(segment
		(start 399.93316 -120.555004)
		(end 398.94256 -120.555004)
		(width 0.3556)
		(layer "F.Cu")
		(net "GND")
	)
	(segment
		(start 56.373268 -390.51484)
		(end 56.32323 -390.464802)
		(width 0.3048)
		(layer "F.Cu")
		(net "GND")
	)
	(segment
		(start 415.96691 -120.035066)
		(end 416.95751 -120.035066)
		(width 0.3556)
		(layer "F.Cu")
		(net "GND")
	)
	(segment
		(start 178.599846 -297.79976)
		(end 179.07508 -298.27474)
		(width 0.249936)
		(layer "F.Cu")
		(net "GND")
	)
	(segment
		(start 187.763912 -367.216182)
		(end 188.63437 -367.216182)
		(width 0.4572)
		(layer "F.Cu")
		(net "GND")
	)
	(segment
		(start 269.94485 -29.589984)
		(end 268.864842 -29.589984)
		(width 0.3556)
		(layer "F.Cu")
		(net "GND")
	)
	(segment
		(start 52.049934 -301.599854)
		(end 51.574954 -302.074834)
		(width 0.249936)
		(layer "F.Cu")
		(net "GND")
	)
	(segment
		(start 401.299934 -286.399732)
		(end 400.824954 -285.924752)
		(width 0.249936)
		(layer "F.Cu")
		(net "GND")
	)
	(segment
		(start 426.943774 -45.88891)
		(end 427.615096 -45.88891)
		(width 0.254)
		(layer "F.Cu")
		(net "GND")
	)
	(segment
		(start 397.97482 -307.774848)
		(end 398.4498 -307.299868)
		(width 0.249936)
		(layer "F.Cu")
		(net "GND")
	)
	(segment
		(start 227.467668 -220.704156)
		(end 227.067872 -221.103952)
		(width 0.381)
		(layer "F.Cu")
		(net "GND")
	)
	(segment
		(start 51.63312 -129.964942)
		(end 50.64252 -129.964942)
		(width 0.3556)
		(layer "F.Cu")
		(net "GND")
	)
	(segment
		(start 78.64983 -302.549814)
		(end 79.12481 -302.074834)
		(width 0.249936)
		(layer "F.Cu")
		(net "GND")
	)
	(segment
		(start 148.634704 -38.937184)
		(end 148.900134 -38.671754)
		(width 0.4572)
		(layer "F.Cu")
		(net "GND")
	)
	(segment
		(start 176.699926 -285.449772)
		(end 176.224946 -285.924752)
		(width 0.249936)
		(layer "F.Cu")
		(net "GND")
	)
	(segment
		(start 400.349974 -288.299906)
		(end 399.874994 -287.824926)
		(width 0.249936)
		(layer "F.Cu")
		(net "GND")
	)
	(segment
		(start 66.299842 -292.099746)
		(end 65.824862 -291.624766)
		(width 0.249936)
		(layer "F.Cu")
		(net "GND")
	)
	(segment
		(start 68.199762 -305.399948)
		(end 67.724782 -305.874928)
		(width 0.249936)
		(layer "F.Cu")
		(net "GND")
	)
	(segment
		(start 171.949872 -296.8498)
		(end 171.474892 -297.32478)
		(width 0.249936)
		(layer "F.Cu")
		(net "GND")
	)
	(segment
		(start 418.874956 -287.824926)
		(end 419.349936 -288.299906)
		(width 0.249936)
		(layer "F.Cu")
		(net "GND")
	)
	(segment
		(start 397.818864 -123.878594)
		(end 398.095216 -124.154946)
		(width 0.3556)
		(layer "F.Cu")
		(net "GND")
	)
	(segment
		(start 426.47489 -301.124874)
		(end 426.94987 -301.599854)
		(width 0.249936)
		(layer "F.Cu")
		(net "GND")
	)
	(segment
		(start 80.262476 -34.29762)
		(end 79.827628 -34.732468)
		(width 0.4572)
		(layer "F.Cu")
		(net "GND")
	)
	(segment
		(start 399.764504 -29.67736)
		(end 399.764504 -29.079952)
		(width 0.4572)
		(layer "F.Cu")
		(net "GND")
	)
	(segment
		(start 240.682272 -215.476328)
		(end 240.4618 -215.6968)
		(width 0.4572)
		(layer "F.Cu")
		(net "GND")
	)
	(segment
		(start 176.224946 -285.924752)
		(end 176.699926 -286.399732)
		(width 0.249936)
		(layer "F.Cu")
		(net "GND")
	)
	(segment
		(start 32.637984 -306.844192)
		(end 32.241998 -307.240178)
		(width 0.4572)
		(layer "F.Cu")
		(net "GND")
	)
	(segment
		(start 360.045 -29.589984)
		(end 358.964992 -29.589984)
		(width 0.3556)
		(layer "F.Cu")
		(net "GND")
	)
	(segment
		(start 293.27475 -289.724846)
		(end 292.79977 -290.199826)
		(width 0.249936)
		(layer "F.Cu")
		(net "GND")
	)
	(segment
		(start 406.524968 -305.874928)
		(end 406.049988 -306.349908)
		(width 0.249936)
		(layer "F.Cu")
		(net "GND")
	)
	(segment
		(start 376.582686 -28.875736)
		(end 376.582686 -28.47848)
		(width 0.254)
		(layer "F.Cu")
		(net "GND")
	)
	(segment
		(start 313.224926 -291.624766)
		(end 312.749692 -291.149786)
		(width 0.249936)
		(layer "F.Cu")
		(net "GND")
	)
	(segment
		(start 148.409152 -27.04973)
		(end 147.750022 -27.04973)
		(width 0.4572)
		(layer "F.Cu")
		(net "GND")
	)
	(segment
		(start 109.099604 -282.406344)
		(end 108.919264 -282.8417)
		(width 0.2286)
		(layer "F.Cu")
		(net "GND")
	)
	(segment
		(start 395.59992 -284.499812)
		(end 395.12494 -284.024832)
		(width 0.249936)
		(layer "F.Cu")
		(net "GND")
	)
	(segment
		(start 395.59992 -303.499774)
		(end 395.12494 -303.024794)
		(width 0.249936)
		(layer "F.Cu")
		(net "GND")
	)
	(segment
		(start 423.149776 -282.599892)
		(end 423.15003 -282.599892)
		(width 0.254)
		(layer "F.Cu")
		(net "GND")
	)
	(segment
		(start 295.174924 -296.37482)
		(end 295.649904 -296.8498)
		(width 0.249936)
		(layer "F.Cu")
		(net "GND")
	)
	(segment
		(start 341.293958 -222.386906)
		(end 341.293958 -222.386652)
		(width 0.381)
		(layer "F.Cu")
		(net "GND")
	)
	(segment
		(start 295.174924 -285.924752)
		(end 294.69969 -286.399732)
		(width 0.249936)
		(layer "F.Cu")
		(net "GND")
	)
	(segment
		(start 67.66687 -156.554932)
		(end 68.65747 -156.554932)
		(width 0.3556)
		(layer "F.Cu")
		(net "GND")
	)
	(segment
		(start 397.97482 -305.874928)
		(end 398.4498 -305.399948)
		(width 0.249936)
		(layer "F.Cu")
		(net "GND")
	)
	(segment
		(start 299.924724 -303.974754)
		(end 299.449744 -303.499774)
		(width 0.249936)
		(layer "F.Cu")
		(net "GND")
	)
	(segment
		(start 353.994212 -35.499548)
		(end 354.366576 -35.871912)
		(width 0.4572)
		(layer "F.Cu")
		(net "GND")
	)
	(segment
		(start 66.774822 -307.774848)
		(end 66.299842 -307.299868)
		(width 0.249936)
		(layer "F.Cu")
		(net "GND")
	)
	(segment
		(start 165.774878 -288.774886)
		(end 166.249858 -289.249866)
		(width 0.249936)
		(layer "F.Cu")
		(net "GND")
	)
	(segment
		(start 185.250074 -293.04996)
		(end 185.725054 -293.52494)
		(width 0.249936)
		(layer "F.Cu")
		(net "GND")
	)
	(segment
		(start 268.864842 -27.79014)
		(end 267.848842 -27.79014)
		(width 0.3556)
		(layer "F.Cu")
		(net "GND")
	)
	(segment
		(start 425.04995 -302.549814)
		(end 424.57497 -303.024794)
		(width 0.249936)
		(layer "F.Cu")
		(net "GND")
	)
	(segment
		(start 112.711992 -113.563654)
		(end 113.329466 -113.563654)
		(width 0.4572)
		(layer "F.Cu")
		(net "GND")
	)
	(segment
		(start 69.967602 -134.400544)
		(end 69.523102 -134.845044)
		(width 0.3556)
		(layer "F.Cu")
		(net "GND")
	)
	(segment
		(start 206.154782 -34.990024)
		(end 204.764894 -34.990024)
		(width 0.3556)
		(layer "F.Cu")
		(net "GND")
	)
	(segment
		(start 388.949946 -280.699718)
		(end 388.474966 -280.224738)
		(width 0.249936)
		(layer "F.Cu")
		(net "GND")
	)
	(segment
		(start 64.874902 -289.724846)
		(end 64.399922 -290.199826)
		(width 0.249936)
		(layer "F.Cu")
		(net "GND")
	)
	(segment
		(start 376.685556 -34.183066)
		(end 376.136154 -34.732468)
		(width 0.4572)
		(layer "F.Cu")
		(net "GND")
	)
	(segment
		(start 108.946188 -285.199836)
		(end 108.946188 -284.631384)
		(width 0.2286)
		(layer "F.Cu")
		(net "GND")
	)
	(segment
		(start 408.899868 -288.299906)
		(end 409.374848 -287.824926)
		(width 0.249936)
		(layer "F.Cu")
		(net "GND")
	)
	(segment
		(start 51.63312 -135.364982)
		(end 50.64252 -135.364982)
		(width 0.3556)
		(layer "F.Cu")
		(net "GND")
	)
	(segment
		(start 63.924942 -289.724846)
		(end 63.449962 -290.199826)
		(width 0.249936)
		(layer "F.Cu")
		(net "GND")
	)
	(segment
		(start 293.74973 -294.94988)
		(end 294.22471 -294.4749)
		(width 0.249936)
		(layer "F.Cu")
		(net "GND")
	)
	(segment
		(start 336.867754 -56.353456)
		(end 337.523074 -56.353456)
		(width 0.254)
		(layer "F.Cu")
		(net "GND")
	)
	(segment
		(start 44.45 -284.499812)
		(end 44.449746 -284.499812)
		(width 0.3048)
		(layer "F.Cu")
		(net "GND")
	)
	(segment
		(start 54.424834 -300.174914)
		(end 53.949854 -299.699934)
		(width 0.249936)
		(layer "F.Cu")
		(net "GND")
	)
	(segment
		(start 54.424834 -284.024832)
		(end 54.899814 -283.549852)
		(width 0.249936)
		(layer "F.Cu")
		(net "GND")
	)
	(segment
		(start 412.699962 -292.099746)
		(end 413.174942 -291.624766)
		(width 0.249936)
		(layer "F.Cu")
		(net "GND")
	)
	(segment
		(start 294.22471 -302.074834)
		(end 294.69969 -301.599854)
		(width 0.249936)
		(layer "F.Cu")
		(net "GND")
	)
	(segment
		(start 395.12494 -303.024794)
		(end 394.64996 -303.499774)
		(width 0.249936)
		(layer "F.Cu")
		(net "GND")
	)
	(segment
		(start 396.54988 -304.449734)
		(end 397.02486 -303.974754)
		(width 0.249936)
		(layer "F.Cu")
		(net "GND")
	)
	(segment
		(start 281.851862 -118.754906)
		(end 282.842462 -118.754906)
		(width 0.3556)
		(layer "F.Cu")
		(net "GND")
	)
	(segment
		(start 436.307484 -95.796862)
		(end 437.886856 -94.21749)
		(width 0.4572)
		(layer "F.Cu")
		(net "GND")
	)
	(segment
		(start 173.375066 -305.874928)
		(end 172.900086 -305.399948)
		(width 0.249936)
		(layer "F.Cu")
		(net "GND")
	)
	(segment
		(start 299.866812 -152.95499)
		(end 300.857412 -152.95499)
		(width 0.3556)
		(layer "F.Cu")
		(net "GND")
	)
	(segment
		(start 277.599902 -286.399732)
		(end 277.124922 -285.924752)
		(width 0.249936)
		(layer "F.Cu")
		(net "GND")
	)
	(segment
		(start 409.374848 -293.52494)
		(end 408.899868 -293.99992)
		(width 0.249936)
		(layer "F.Cu")
		(net "GND")
	)
	(segment
		(start 234.58551 -34.183066)
		(end 234.470956 -34.29762)
		(width 0.4572)
		(layer "F.Cu")
		(net "GND")
	)
	(segment
		(start 418.874956 -290.674806)
		(end 419.349936 -290.199826)
		(width 0.249936)
		(layer "F.Cu")
		(net "GND")
	)
	(segment
		(start 96.383094 -100.468176)
		(end 95.831152 -100.468176)
		(width 0.254)
		(layer "F.Cu")
		(net "GND")
	)
	(segment
		(start 273.799808 -292.099746)
		(end 273.324828 -291.624766)
		(width 0.249936)
		(layer "F.Cu")
		(net "GND")
	)
	(segment
		(start 299.866812 -154.755088)
		(end 300.857412 -154.755088)
		(width 0.3556)
		(layer "F.Cu")
		(net "GND")
	)
	(segment
		(start 57.749948 -303.499774)
		(end 58.224928 -303.974754)
		(width 0.249936)
		(layer "F.Cu")
		(net "GND")
	)
	(segment
		(start 379.99416 -35.499548)
		(end 380.366524 -35.871912)
		(width 0.4572)
		(layer "F.Cu")
		(net "GND")
	)
	(segment
		(start 392.226546 -25.832054)
		(end 392.869928 -25.832054)
		(width 0.4572)
		(layer "F.Cu")
		(net "GND")
	)
	(segment
		(start 180.975 -289.724846)
		(end 181.44998 -290.199826)
		(width 0.249936)
		(layer "F.Cu")
		(net "GND")
	)
	(segment
		(start 398.4498 -306.349908)
		(end 398.925034 -306.824888)
		(width 0.249936)
		(layer "F.Cu")
		(net "GND")
	)
	(segment
		(start 74.295 -104.240076)
		(end 73.257664 -104.240076)
		(width 0.3556)
		(layer "F.Cu")
		(net "GND")
	)
	(segment
		(start 112.661954 -161.005774)
		(end 112.973866 -161.005774)
		(width 0.254)
		(layer "F.Cu")
		(net "GND")
	)
	(segment
		(start 68.674742 -288.774886)
		(end 69.149976 -288.299906)
		(width 0.249936)
		(layer "F.Cu")
		(net "GND")
	)
	(segment
		(start 70.099936 -292.099746)
		(end 70.574916 -291.624766)
		(width 0.249936)
		(layer "F.Cu")
		(net "GND")
	)
	(segment
		(start 86.140798 -54.163722)
		(end 86.69274 -54.163722)
		(width 0.254)
		(layer "F.Cu")
		(net "GND")
	)
	(segment
		(start 234.671108 -83.718908)
		(end 234.671108 -84.432394)
		(width 0.4572)
		(layer "F.Cu")
		(net "GND")
	)
	(segment
		(start 461.012032 -114.960654)
		(end 461.629506 -114.960654)
		(width 0.4572)
		(layer "F.Cu")
		(net "GND")
	)
	(segment
		(start 45.39996 -296.8498)
		(end 45.87494 -296.37482)
		(width 0.249936)
		(layer "F.Cu")
		(net "GND")
	)
	(segment
		(start 40.649906 -275.949918)
		(end 40.174926 -275.474938)
		(width 0.249936)
		(layer "F.Cu")
		(net "GND")
	)
	(segment
		(start 144.37106 -34.29762)
		(end 144.362678 -34.29762)
		(width 0.4572)
		(layer "F.Cu")
		(net "GND")
	)
	(segment
		(start 162.450018 -301.599854)
		(end 161.975038 -302.074834)
		(width 0.249936)
		(layer "F.Cu")
		(net "GND")
	)
	(segment
		(start 421.589962 -73.166732)
		(end 421.589962 -73.85177)
		(width 0.4572)
		(layer "F.Cu")
		(net "GND")
	)
	(segment
		(start 234.462574 -34.29762)
		(end 234.027726 -34.732468)
		(width 0.4572)
		(layer "F.Cu")
		(net "GND")
	)
	(segment
		(start 276.649688 -300.649894)
		(end 276.174708 -300.174914)
		(width 0.254)
		(layer "F.Cu")
		(net "GND")
	)
	(segment
		(start 396.54988 -305.399948)
		(end 396.0749 -305.874928)
		(width 0.249936)
		(layer "F.Cu")
		(net "GND")
	)
	(segment
		(start 141.564614 -29.67736)
		(end 141.564614 -29.079952)
		(width 0.4572)
		(layer "F.Cu")
		(net "GND")
	)
	(segment
		(start 402.724874 -296.37482)
		(end 402.249894 -296.8498)
		(width 0.249936)
		(layer "F.Cu")
		(net "GND")
	)
	(segment
		(start 51.574954 -287.824926)
		(end 51.099974 -288.299906)
		(width 0.249936)
		(layer "F.Cu")
		(net "GND")
	)
	(segment
		(start 248.902728 -111.739426)
		(end 248.902728 -111.127032)
		(width 0.4572)
		(layer "F.Cu")
		(net "GND")
	)
	(segment
		(start 405.575008 -303.974754)
		(end 406.049988 -303.499774)
		(width 0.249936)
		(layer "F.Cu")
		(net "GND")
	)
	(segment
		(start 81.024984 -293.52494)
		(end 80.54975 -293.04996)
		(width 0.249936)
		(layer "F.Cu")
		(net "GND")
	)
	(segment
		(start 206.156052 -33.19018)
		(end 204.764894 -33.19018)
		(width 0.3556)
		(layer "F.Cu")
		(net "GND")
	)
	(segment
		(start 2.781808 -376.170444)
		(end 2.781808 -375.757694)
		(width 0.381)
		(layer "F.Cu")
		(net "GND")
	)
	(segment
		(start 69.149976 -305.399948)
		(end 68.674742 -305.874928)
		(width 0.249936)
		(layer "F.Cu")
		(net "GND")
	)
	(segment
		(start 9.71042 -122.931428)
		(end 9.0551 -122.931428)
		(width 0.4064)
		(layer "F.Cu")
		(net "GND")
	)
	(segment
		(start 299.866812 -118.234968)
		(end 300.857412 -118.234968)
		(width 0.3556)
		(layer "F.Cu")
		(net "GND")
	)
	(segment
		(start 80.54975 -294.94988)
		(end 80.07477 -294.4749)
		(width 0.249936)
		(layer "F.Cu")
		(net "GND")
	)
	(segment
		(start 299.46473 -25.990042)
		(end 300.48073 -25.990042)
		(width 0.3556)
		(layer "F.Cu")
		(net "GND")
	)
	(segment
		(start 414.599882 -306.349908)
		(end 415.074862 -306.824888)
		(width 0.249936)
		(layer "F.Cu")
		(net "GND")
	)
	(segment
		(start 411.275022 -285.924752)
		(end 410.799788 -286.399732)
		(width 0.249936)
		(layer "F.Cu")
		(net "GND")
	)
	(segment
		(start 306.448206 -120.035066)
		(end 305.457606 -120.035066)
		(width 0.3556)
		(layer "F.Cu")
		(net "GND")
	)
	(segment
		(start 343.149936 -177.554128)
		(end 341.744554 -177.554128)
		(width 0.4572)
		(layer "F.Cu")
		(net "GND")
	)
	(segment
		(start 78.64983 -289.249866)
		(end 78.17485 -289.724846)
		(width 0.249936)
		(layer "F.Cu")
		(net "GND")
	)
	(segment
		(start 390.58088 -29.589984)
		(end 389.56488 -29.589984)
		(width 0.3556)
		(layer "F.Cu")
		(net "GND")
	)
	(segment
		(start 190.78956 -402.26869)
		(end 190.78956 -401.65909)
		(width 0.381)
		(layer "F.Cu")
		(net "GND")
	)
	(segment
		(start 66.774822 -303.974754)
		(end 67.249802 -303.499774)
		(width 0.249936)
		(layer "F.Cu")
		(net "GND")
	)
	(segment
		(start 52.999894 -290.199826)
		(end 53.474874 -289.724846)
		(width 0.249936)
		(layer "F.Cu")
		(net "GND")
	)
	(segment
		(start 452.967852 -51.019456)
		(end 453.623172 -51.019456)
		(width 0.254)
		(layer "F.Cu")
		(net "GND")
	)
	(segment
		(start 399.400014 -306.349908)
		(end 399.874994 -306.824888)
		(width 0.249936)
		(layer "F.Cu")
		(net "GND")
	)
	(segment
		(start 417.924996 -292.574726)
		(end 417.450016 -293.04996)
		(width 0.249936)
		(layer "F.Cu")
		(net "GND")
	)
	(segment
		(start 414.599882 -285.449772)
		(end 414.124902 -284.974792)
		(width 0.249936)
		(layer "F.Cu")
		(net "GND")
	)
	(segment
		(start 280.449782 -284.499812)
		(end 279.974802 -284.024832)
		(width 0.249936)
		(layer "F.Cu")
		(net "GND")
	)
	(segment
		(start 440.34964 -303.636426)
		(end 440.34964 -303.026826)
		(width 0.4572)
		(layer "F.Cu")
		(net "GND")
	)
	(segment
		(start 56.799988 -297.79976)
		(end 57.274968 -297.32478)
		(width 0.249936)
		(layer "F.Cu")
		(net "GND")
	)
	(segment
		(start 121.897902 -38.937184)
		(end 122.634756 -38.937184)
		(width 0.4572)
		(layer "F.Cu")
		(net "GND")
	)
	(segment
		(start 184.29986 -307.299868)
		(end 184.77484 -307.774848)
		(width 0.249936)
		(layer "F.Cu")
		(net "GND")
	)
	(segment
		(start 185.250074 -284.499812)
		(end 184.77484 -284.974792)
		(width 0.249936)
		(layer "F.Cu")
		(net "GND")
	)
	(segment
		(start 219.457524 -29.784294)
		(end 219.564458 -29.67736)
		(width 0.4572)
		(layer "F.Cu")
		(net "GND")
	)
	(segment
		(start 184.77484 -284.974792)
		(end 185.250074 -285.449772)
		(width 0.249936)
		(layer "F.Cu")
		(net "GND")
	)
	(segment
		(start 244.153944 -31.390082)
		(end 242.864894 -31.390082)
		(width 0.3556)
		(layer "F.Cu")
		(net "GND")
	)
	(segment
		(start 62.024768 -302.074834)
		(end 62.499748 -301.599854)
		(width 0.249936)
		(layer "F.Cu")
		(net "GND")
	)
	(segment
		(start 40.174926 -298.27474)
		(end 40.649906 -297.79976)
		(width 0.249936)
		(layer "F.Cu")
		(net "GND")
	)
	(segment
		(start 312.749692 -300.649894)
		(end 312.274712 -300.174914)
		(width 0.249936)
		(layer "F.Cu")
		(net "GND")
	)
	(segment
		(start 60.599828 -293.99992)
		(end 61.074808 -293.52494)
		(width 0.249936)
		(layer "F.Cu")
		(net "GND")
	)
	(segment
		(start 41.599866 -299.699934)
		(end 42.074846 -300.174914)
		(width 0.249936)
		(layer "F.Cu")
		(net "GND")
	)
	(segment
		(start 60.599828 -297.79976)
		(end 61.074808 -298.27474)
		(width 0.249936)
		(layer "F.Cu")
		(net "GND")
	)
	(segment
		(start 401.299934 -290.199826)
		(end 401.774914 -289.724846)
		(width 0.249936)
		(layer "F.Cu")
		(net "GND")
	)
	(segment
		(start 242.601242 -307.368702)
		(end 243.120418 -306.849526)
		(width 0.1778)
		(layer "F.Cu")
		(net "GND")
	)
	(segment
		(start 76.27493 -291.624766)
		(end 76.74991 -291.149786)
		(width 0.249936)
		(layer "F.Cu")
		(net "GND")
	)
	(segment
		(start 66.774822 -284.974792)
		(end 66.299842 -284.499812)
		(width 0.249936)
		(layer "F.Cu")
		(net "GND")
	)
	(segment
		(start 184.77484 -301.124874)
		(end 184.29986 -300.649894)
		(width 0.249936)
		(layer "F.Cu")
		(net "GND")
	)
	(segment
		(start 281.523948 -27.411934)
		(end 281.523948 -26.319734)
		(width 0.4572)
		(layer "F.Cu")
		(net "GND")
	)
	(segment
		(start 106.6927 -9.139682)
		(end 106.6927 -8.48995)
		(width 0.4572)
		(layer "F.Cu")
		(net "GND")
	)
	(segment
		(start 325.83882 -291.321998)
		(end 325.20382 -291.321998)
		(width 0.4572)
		(layer "F.Cu")
		(net "GND")
	)
	(segment
		(start 101.530404 -121.80824)
		(end 100.91801 -121.80824)
		(width 0.4572)
		(layer "F.Cu")
		(net "GND")
	)
	(segment
		(start 49.1998 -286.399732)
		(end 48.72482 -285.924752)
		(width 0.249936)
		(layer "F.Cu")
		(net "GND")
	)
	(segment
		(start 69.655182 -145.881852)
		(end 69.528436 -145.755106)
		(width 0.3556)
		(layer "F.Cu")
		(net "GND")
	)
	(segment
		(start 81.499964 -292.099746)
		(end 81.024984 -291.624766)
		(width 0.249936)
		(layer "F.Cu")
		(net "GND")
	)
	(segment
		(start 142.806674 -200.489058)
		(end 142.806674 -199.367394)
		(width 0.2794)
		(layer "F.Cu")
		(net "GND")
	)
	(segment
		(start 51.63312 -131.76504)
		(end 50.64252 -131.76504)
		(width 0.3556)
		(layer "F.Cu")
		(net "GND")
	)
	(segment
		(start 41.26484 -34.990024)
		(end 42.28084 -34.990024)
		(width 0.3556)
		(layer "F.Cu")
		(net "GND")
	)
	(segment
		(start 313.699906 -293.99992)
		(end 313.224926 -293.52494)
		(width 0.249936)
		(layer "F.Cu")
		(net "GND")
	)
	(segment
		(start 161.025078 -297.32478)
		(end 161.500058 -296.8498)
		(width 0.249936)
		(layer "F.Cu")
		(net "GND")
	)
	(segment
		(start 294.86479 -31.390082)
		(end 295.736264 -31.390082)
		(width 0.3556)
		(layer "F.Cu")
		(net "GND")
	)
	(segment
		(start 400.349974 -284.499812)
		(end 399.874994 -284.024832)
		(width 0.249936)
		(layer "F.Cu")
		(net "GND")
	)
	(segment
		(start 214.90051 -210.232244)
		(end 214.90051 -209.983832)
		(width 0.254)
		(layer "F.Cu")
		(net "GND")
	)
	(segment
		(start 419.349936 -293.04996)
		(end 419.824916 -292.574726)
		(width 0.249936)
		(layer "F.Cu")
		(net "GND")
	)
	(segment
		(start 130.34899 -27.79014)
		(end 131.36499 -27.79014)
		(width 0.3556)
		(layer "F.Cu")
		(net "GND")
	)
	(segment
		(start 419.824916 -303.974754)
		(end 419.349936 -304.449734)
		(width 0.249936)
		(layer "F.Cu")
		(net "GND")
	)
	(segment
		(start 78.17485 -289.724846)
		(end 77.69987 -289.249866)
		(width 0.249936)
		(layer "F.Cu")
		(net "GND")
	)
	(segment
		(start 67.66687 -142.15491)
		(end 68.65747 -142.15491)
		(width 0.3556)
		(layer "F.Cu")
		(net "GND")
	)
	(segment
		(start 413.174942 -284.974792)
		(end 412.699962 -285.449772)
		(width 0.249936)
		(layer "F.Cu")
		(net "GND")
	)
	(segment
		(start 217.583512 -231.816656)
		(end 217.583512 -232.471468)
		(width 0.4572)
		(layer "F.Cu")
		(net "GND")
	)
	(segment
		(start 40.649906 -293.99992)
		(end 40.174926 -293.52494)
		(width 0.249936)
		(layer "F.Cu")
		(net "GND")
	)
	(segment
		(start 195.699888 -298.74972)
		(end 196.174868 -298.27474)
		(width 0.249936)
		(layer "F.Cu")
		(net "GND")
	)
	(segment
		(start 59.649868 -306.349908)
		(end 60.124848 -306.824888)
		(width 0.249936)
		(layer "F.Cu")
		(net "GND")
	)
	(segment
		(start 229.437438 -67.799966)
		(end 228.308154 -67.799966)
		(width 0.3556)
		(layer "F.Cu")
		(net "GND")
	)
	(segment
		(start 422.674796 -290.674806)
		(end 423.15003 -290.199826)
		(width 0.249936)
		(layer "F.Cu")
		(net "GND")
	)
	(segment
		(start 303.249838 -303.499774)
		(end 303.724818 -303.974754)
		(width 0.249936)
		(layer "F.Cu")
		(net "GND")
	)
	(segment
		(start 341.435182 -285.488634)
		(end 341.146384 -285.199836)
		(width 0.2286)
		(layer "F.Cu")
		(net "GND")
	)
	(segment
		(start 158.649924 -281.649932)
		(end 158.174944 -281.174952)
		(width 0.249936)
		(layer "F.Cu")
		(net "GND")
	)
	(segment
		(start 70.574916 -289.724846)
		(end 71.049896 -290.199826)
		(width 0.249936)
		(layer "F.Cu")
		(net "GND")
	)
	(segment
		(start 60.070492 -373.538496)
		(end 59.09945 -372.567454)
		(width 0.4572)
		(layer "F.Cu")
		(net "GND")
	)
	(segment
		(start 426.94987 -296.8498)
		(end 426.47489 -297.32478)
		(width 0.249936)
		(layer "F.Cu")
		(net "GND")
	)
	(segment
		(start 310.374792 -297.32478)
		(end 310.849772 -296.8498)
		(width 0.249936)
		(layer "F.Cu")
		(net "GND")
	)
	(segment
		(start 177.174906 -306.824888)
		(end 177.649886 -306.349908)
		(width 0.249936)
		(layer "F.Cu")
		(net "GND")
	)
	(segment
		(start 51.63312 -113.245138)
		(end 50.64252 -113.245138)
		(width 0.3556)
		(layer "F.Cu")
		(net "GND")
	)
	(segment
		(start 198.075042 -293.52494)
		(end 197.600062 -293.99992)
		(width 0.249936)
		(layer "F.Cu")
		(net "GND")
	)
	(segment
		(start 418.10432 -132.622036)
		(end 417.68141 -133.044946)
		(width 0.3556)
		(layer "F.Cu")
		(net "GND")
	)
	(segment
		(start 376.267472 -33.248092)
		(end 375.632218 -33.248092)
		(width 0.4572)
		(layer "F.Cu")
		(net "GND")
	)
	(segment
		(start 67.724782 -287.824926)
		(end 68.199762 -288.299906)
		(width 0.249936)
		(layer "F.Cu")
		(net "GND")
	)
	(segment
		(start 390.849866 -275.949918)
		(end 390.374886 -275.474938)
		(width 0.249936)
		(layer "F.Cu")
		(net "GND")
	)
	(segment
		(start 69.528436 -145.755106)
		(end 68.65747 -145.755106)
		(width 0.3556)
		(layer "F.Cu")
		(net "GND")
	)
	(segment
		(start 65.349882 -307.299868)
		(end 64.874902 -307.774848)
		(width 0.249936)
		(layer "F.Cu")
		(net "GND")
	)
	(segment
		(start 386.574792 -299.224954)
		(end 387.050026 -298.74972)
		(width 0.249936)
		(layer "F.Cu")
		(net "GND")
	)
	(segment
		(start 390.330436 -238.811054)
		(end 388.274052 -238.811054)
		(width 0.2794)
		(layer "F.Cu")
		(net "GND")
	)
	(segment
		(start 422.674796 -294.4749)
		(end 423.15003 -293.99992)
		(width 0.249936)
		(layer "F.Cu")
		(net "GND")
	)
	(segment
		(start 53.474874 -306.824888)
		(end 53.949854 -306.349908)
		(width 0.249936)
		(layer "F.Cu")
		(net "GND")
	)
	(segment
		(start 397.97482 -294.4749)
		(end 398.4498 -294.94988)
		(width 0.249936)
		(layer "F.Cu")
		(net "GND")
	)
	(segment
		(start 180.02504 -305.874928)
		(end 180.50002 -305.399948)
		(width 0.249936)
		(layer "F.Cu")
		(net "GND")
	)
	(segment
		(start 243.694712 -159.266382)
		(end 242.254024 -160.70707)
		(width 0.254)
		(layer "F.Cu")
		(net "GND")
	)
	(segment
		(start 267.281406 -206.161386)
		(end 267.519658 -206.161386)
		(width 0.4572)
		(layer "F.Cu")
		(net "GND")
	)
	(segment
		(start 172.424852 -306.824888)
		(end 172.900086 -306.349908)
		(width 0.249936)
		(layer "F.Cu")
		(net "GND")
	)
	(segment
		(start 312.274712 -300.174914)
		(end 311.799732 -300.649894)
		(width 0.249936)
		(layer "F.Cu")
		(net "GND")
	)
	(segment
		(start 299.449744 -306.349908)
		(end 299.924724 -306.824888)
		(width 0.249936)
		(layer "F.Cu")
		(net "GND")
	)
	(segment
		(start 420.529004 -147.314412)
		(end 420.769542 -147.55495)
		(width 0.3556)
		(layer "F.Cu")
		(net "GND")
	)
	(segment
		(start 54.424834 -306.824888)
		(end 53.949854 -306.349908)
		(width 0.249936)
		(layer "F.Cu")
		(net "GND")
	)
	(segment
		(start 334.09382 -227.987098)
		(end 333.694024 -228.386894)
		(width 0.381)
		(layer "F.Cu")
		(net "GND")
	)
	(segment
		(start 302.774858 -299.224954)
		(end 302.299878 -299.699934)
		(width 0.249936)
		(layer "F.Cu")
		(net "GND")
	)
	(segment
		(start 189.999874 -291.149786)
		(end 190.474854 -290.674806)
		(width 0.249936)
		(layer "F.Cu")
		(net "GND")
	)
	(segment
		(start 398.4498 -305.399948)
		(end 398.925034 -305.874928)
		(width 0.249936)
		(layer "F.Cu")
		(net "GND")
	)
	(segment
		(start 397.847566 -122.044206)
		(end 398.158462 -122.355102)
		(width 0.3556)
		(layer "F.Cu")
		(net "GND")
	)
	(segment
		(start 282.063444 -113.780062)
		(end 282.063444 -113.485676)
		(width 0.3556)
		(layer "F.Cu")
		(net "GND")
	)
	(segment
		(start 297.549824 -284.499812)
		(end 297.074844 -284.974792)
		(width 0.249936)
		(layer "F.Cu")
		(net "GND")
	)
	(segment
		(start 277.186898 -151.157432)
		(end 277.21814 -151.157432)
		(width 0.3556)
		(layer "F.Cu")
		(net "GND")
	)
	(segment
		(start 186.675014 -300.174914)
		(end 187.149994 -300.649894)
		(width 0.249936)
		(layer "F.Cu")
		(net "GND")
	)
	(segment
		(start 51.63312 -102.445058)
		(end 50.64252 -102.445058)
		(width 0.3556)
		(layer "F.Cu")
		(net "GND")
	)
	(segment
		(start 387.999986 -292.099746)
		(end 387.525006 -292.574726)
		(width 0.249936)
		(layer "F.Cu")
		(net "GND")
	)
	(segment
		(start 388.949946 -279.749758)
		(end 388.474966 -279.274778)
		(width 0.249936)
		(layer "F.Cu")
		(net "GND")
	)
	(segment
		(start 397.90497 -105.673652)
		(end 398.276318 -106.045)
		(width 0.3556)
		(layer "F.Cu")
		(net "GND")
	)
	(segment
		(start 391.799826 -288.299906)
		(end 391.324846 -288.774886)
		(width 0.249936)
		(layer "F.Cu")
		(net "GND")
	)
	(segment
		(start 404.625048 -296.37482)
		(end 405.100028 -295.89984)
		(width 0.249936)
		(layer "F.Cu")
		(net "GND")
	)
	(segment
		(start 452.943722 -45.88891)
		(end 453.615044 -45.88891)
		(width 0.254)
		(layer "F.Cu")
		(net "GND")
	)
	(segment
		(start 427.42485 -302.074834)
		(end 426.94987 -301.599854)
		(width 0.249936)
		(layer "F.Cu")
		(net "GND")
	)
	(segment
		(start 427.42485 -298.27474)
		(end 426.94987 -297.79976)
		(width 0.249936)
		(layer "F.Cu")
		(net "GND")
	)
	(segment
		(start 167.200072 -306.349908)
		(end 166.725092 -305.874928)
		(width 0.249936)
		(layer "F.Cu")
		(net "GND")
	)
	(segment
		(start 283.299916 -288.299906)
		(end 283.774896 -287.824926)
		(width 0.249936)
		(layer "F.Cu")
		(net "GND")
	)
	(segment
		(start 422.674796 -294.4749)
		(end 422.199816 -294.94988)
		(width 0.249936)
		(layer "F.Cu")
		(net "GND")
	)
	(segment
		(start 188.050678 -188.895736)
		(end 188.248544 -188.895736)
		(width 0.4572)
		(layer "F.Cu")
		(net "GND")
	)
	(segment
		(start 284.023816 -167.742108)
		(end 284.023816 -168.229788)
		(width 0.4572)
		(layer "F.Cu")
		(net "GND")
	)
	(segment
		(start 71.999856 -302.549814)
		(end 72.474836 -303.024794)
		(width 0.249936)
		(layer "F.Cu")
		(net "GND")
	)
	(segment
		(start 273.799808 -293.04996)
		(end 273.324828 -292.57498)
		(width 0.249936)
		(layer "F.Cu")
		(net "GND")
	)
	(segment
		(start 27.390344 -252.756924)
		(end 27.390344 -253.45644)
		(width 0.4572)
		(layer "F.Cu")
		(net "GND")
	)
	(segment
		(start 241.51971 -162.404044)
		(end 241.51971 -163.021518)
		(width 0.4572)
		(layer "F.Cu")
		(net "GND")
	)
	(segment
		(start 190.474854 -296.37482)
		(end 189.999874 -296.8498)
		(width 0.249936)
		(layer "F.Cu")
		(net "GND")
	)
	(segment
		(start 275.699728 -274.049744)
		(end 275.224748 -273.574764)
		(width 0.249936)
		(layer "F.Cu")
		(net "GND")
	)
	(segment
		(start 167.16248 -23.355554)
		(end 167.812212 -23.355554)
		(width 0.4572)
		(layer "F.Cu")
		(net "GND")
	)
	(segment
		(start 170.999912 -290.199826)
		(end 171.474892 -289.724846)
		(width 0.249936)
		(layer "F.Cu")
		(net "GND")
	)
	(segment
		(start 47.092108 -104.793034)
		(end 47.092108 -104.404922)
		(width 0.3556)
		(layer "F.Cu")
		(net "GND")
	)
	(segment
		(start 70.574916 -290.674806)
		(end 71.049896 -290.199826)
		(width 0.249936)
		(layer "F.Cu")
		(net "GND")
	)
	(segment
		(start 453.924416 -119.026178)
		(end 454.663556 -119.026178)
		(width 0.4572)
		(layer "F.Cu")
		(net "GND")
	)
	(segment
		(start 179.07508 -284.974792)
		(end 179.55006 -284.499812)
		(width 0.249936)
		(layer "F.Cu")
		(net "GND")
	)
	(segment
		(start 194.889628 -406.180544)
		(end 194.89674 -406.187656)
		(width 0.4572)
		(layer "F.Cu")
		(net "GND")
	)
	(segment
		(start 81.499964 -295.89984)
		(end 81.024984 -296.37482)
		(width 0.249936)
		(layer "F.Cu")
		(net "GND")
	)
	(segment
		(start 303.249838 -293.04996)
		(end 303.724818 -292.574726)
		(width 0.249936)
		(layer "F.Cu")
		(net "GND")
	)
	(segment
		(start 347.139514 -265.949938)
		(end 346.441014 -265.949938)
		(width 0.4572)
		(layer "F.Cu")
		(net "GND")
	)
	(segment
		(start 180.50002 -292.099746)
		(end 180.975 -291.624766)
		(width 0.249936)
		(layer "F.Cu")
		(net "GND")
	)
	(segment
		(start 418.399976 -301.599854)
		(end 418.874956 -302.074834)
		(width 0.249936)
		(layer "F.Cu")
		(net "GND")
	)
	(segment
		(start 277.570184 -47.60087)
		(end 277.996142 -47.60087)
		(width 0.254)
		(layer "F.Cu")
		(net "GND")
	)
	(segment
		(start 262.228584 -113.158524)
		(end 264.517632 -113.158524)
		(width 0.4572)
		(layer "F.Cu")
		(net "GND")
	)
	(segment
		(start 340.493858 -219.987114)
		(end 340.094062 -220.38691)
		(width 0.381)
		(layer "F.Cu")
		(net "GND")
	)
	(segment
		(start 183.3499 -307.299868)
		(end 182.87492 -306.824888)
		(width 0.249936)
		(layer "F.Cu")
		(net "GND")
	)
	(segment
		(start 374.02897 -240.6904)
		(end 374.484646 -241.146076)
		(width 0.4572)
		(layer "F.Cu")
		(net "GND")
	)
	(segment
		(start 401.774914 -285.924752)
		(end 401.299934 -285.449772)
		(width 0.249936)
		(layer "F.Cu")
		(net "GND")
	)
	(segment
		(start 269.750286 -252.756924)
		(end 269.750286 -253.45644)
		(width 0.4572)
		(layer "F.Cu")
		(net "GND")
	)
	(segment
		(start 176.224946 -289.724846)
		(end 176.699926 -290.199826)
		(width 0.249936)
		(layer "F.Cu")
		(net "GND")
	)
	(segment
		(start 349.460312 -282.406344)
		(end 349.279972 -282.8417)
		(width 0.2286)
		(layer "F.Cu")
		(net "GND")
	)
	(segment
		(start 282.349702 -286.399732)
		(end 281.874722 -285.924752)
		(width 0.249936)
		(layer "F.Cu")
		(net "GND")
	)
	(segment
		(start 41.599866 -276.899878)
		(end 41.124886 -276.424898)
		(width 0.249936)
		(layer "F.Cu")
		(net "GND")
	)
	(segment
		(start 126.153926 -160.70707)
		(end 126.153926 -162.672014)
		(width 0.254)
		(layer "F.Cu")
		(net "GND")
	)
	(segment
		(start 55.374794 -289.724846)
		(end 55.849774 -290.199826)
		(width 0.249936)
		(layer "F.Cu")
		(net "GND")
	)
	(segment
		(start 310.374792 -289.724846)
		(end 310.849772 -289.249866)
		(width 0.249936)
		(layer "F.Cu")
		(net "GND")
	)
	(segment
		(start 231.66959 -83.718908)
		(end 231.66959 -84.41309)
		(width 0.4572)
		(layer "F.Cu")
		(net "GND")
	)
	(segment
		(start 60.124848 -297.32478)
		(end 60.599828 -297.79976)
		(width 0.249936)
		(layer "F.Cu")
		(net "GND")
	)
	(segment
		(start 72.452738 -134.845044)
		(end 73.257664 -134.845044)
		(width 0.3556)
		(layer "F.Cu")
		(net "GND")
	)
	(segment
		(start 148.589492 -62.812168)
		(end 149.400006 -62.812168)
		(width 0.4572)
		(layer "F.Cu")
		(net "GND")
	)
	(segment
		(start 419.146736 -38.49116)
		(end 418.441124 -38.49116)
		(width 0.4572)
		(layer "F.Cu")
		(net "GND")
	)
	(segment
		(start 236.023658 -142.640812)
		(end 236.633258 -142.640812)
		(width 0.4572)
		(layer "F.Cu")
		(net "GND")
	)
	(segment
		(start 403.674834 -303.974754)
		(end 404.149814 -303.499774)
		(width 0.249936)
		(layer "F.Cu")
		(net "GND")
	)
	(segment
		(start 398.925034 -305.874928)
		(end 398.4498 -306.349908)
		(width 0.249936)
		(layer "F.Cu")
		(net "GND")
	)
	(segment
		(start 65.349882 -301.599854)
		(end 65.824862 -302.074834)
		(width 0.249936)
		(layer "F.Cu")
		(net "GND")
	)
	(segment
		(start 301.824898 -303.974754)
		(end 301.349918 -303.499774)
		(width 0.249936)
		(layer "F.Cu")
		(net "GND")
	)
	(segment
		(start 71.999856 -293.04996)
		(end 72.474836 -292.574726)
		(width 0.249936)
		(layer "F.Cu")
		(net "GND")
	)
	(segment
		(start 46.34992 -286.399732)
		(end 45.87494 -285.924752)
		(width 0.249936)
		(layer "F.Cu")
		(net "GND")
	)
	(segment
		(start 189.999874 -302.549814)
		(end 189.999874 -301.599854)
		(width 0.249936)
		(layer "F.Cu")
		(net "GND")
	)
	(segment
		(start 185.250074 -306.349908)
		(end 184.77484 -306.824888)
		(width 0.249936)
		(layer "F.Cu")
		(net "GND")
	)
	(segment
		(start 269.999714 -278.799798)
		(end 269.524734 -278.324818)
		(width 0.249936)
		(layer "F.Cu")
		(net "GND")
	)
	(segment
		(start 260.460236 -335.433924)
		(end 260.778752 -335.115408)
		(width 0.4572)
		(layer "F.Cu")
		(net "GND")
	)
	(segment
		(start 73.445878 -46.693836)
		(end 72.918574 -46.693836)
		(width 0.254)
		(layer "F.Cu")
		(net "GND")
	)
	(segment
		(start 172.424852 -284.974792)
		(end 172.900086 -284.499812)
		(width 0.249936)
		(layer "F.Cu")
		(net "GND")
	)
	(segment
		(start 290.794948 -99.750372)
		(end 290.17976 -99.750372)
		(width 0.4064)
		(layer "F.Cu")
		(net "GND")
	)
	(segment
		(start 73.899776 -297.79976)
		(end 74.374756 -298.27474)
		(width 0.249936)
		(layer "F.Cu")
		(net "GND")
	)
	(segment
		(start 391.799826 -282.599892)
		(end 391.324846 -282.124912)
		(width 0.249936)
		(layer "F.Cu")
		(net "GND")
	)
	(segment
		(start 304.483262 -154.461718)
		(end 304.776632 -154.755088)
		(width 0.3556)
		(layer "F.Cu")
		(net "GND")
	)
	(segment
		(start 375.252742 -262.915908)
		(end 375.824496 -262.915908)
		(width 0.3048)
		(layer "F.Cu")
		(net "GND")
	)
	(segment
		(start 67.724782 -306.824888)
		(end 68.199762 -306.349908)
		(width 0.249936)
		(layer "F.Cu")
		(net "GND")
	)
	(segment
		(start 158.649924 -290.199826)
		(end 158.174944 -289.724846)
		(width 0.249936)
		(layer "F.Cu")
		(net "GND")
	)
	(segment
		(start 170.371008 -34.29762)
		(end 170.362626 -34.29762)
		(width 0.4572)
		(layer "F.Cu")
		(net "GND")
	)
	(segment
		(start 440.696096 -25.990042)
		(end 441.564776 -25.990042)
		(width 0.3556)
		(layer "F.Cu")
		(net "GND")
	)
	(segment
		(start 429.325024 -300.174914)
		(end 428.84979 -300.649894)
		(width 0.249936)
		(layer "F.Cu")
		(net "GND")
	)
	(segment
		(start 410.324808 -284.974792)
		(end 410.799788 -284.499812)
		(width 0.249936)
		(layer "F.Cu")
		(net "GND")
	)
	(segment
		(start 420.297864 -133.472682)
		(end 420.7256 -133.044946)
		(width 0.3556)
		(layer "F.Cu")
		(net "GND")
	)
	(segment
		(start 174.800006 -305.399948)
		(end 174.325026 -305.874928)
		(width 0.249936)
		(layer "F.Cu")
		(net "GND")
	)
	(segment
		(start 290.794948 -103.814372)
		(end 290.17976 -103.814372)
		(width 0.4064)
		(layer "F.Cu")
		(net "GND")
	)
	(segment
		(start 399.93316 -100.64496)
		(end 398.94256 -100.64496)
		(width 0.3556)
		(layer "F.Cu")
		(net "GND")
	)
	(segment
		(start 425.04995 -296.8498)
		(end 424.57497 -297.32478)
		(width 0.249936)
		(layer "F.Cu")
		(net "GND")
	)
	(segment
		(start 290.42487 -306.824888)
		(end 290.89985 -307.299868)
		(width 0.249936)
		(layer "F.Cu")
		(net "GND")
	)
	(segment
		(start 249.413776 -359.120186)
		(end 248.651776 -359.120186)
		(width 0.4572)
		(layer "F.Cu")
		(net "GND")
	)
	(segment
		(start 167.732964 -151.159972)
		(end 166.742364 -151.159972)
		(width 0.3556)
		(layer "F.Cu")
		(net "GND")
	)
	(segment
		(start 187.149994 -302.549814)
		(end 187.624974 -303.024794)
		(width 0.249936)
		(layer "F.Cu")
		(net "GND")
	)
	(segment
		(start 57.749948 -288.299906)
		(end 57.274968 -287.824926)
		(width 0.249936)
		(layer "F.Cu")
		(net "GND")
	)
	(segment
		(start 38.349428 -161.902648)
		(end 38.349428 -161.6329)
		(width 0.4572)
		(layer "F.Cu")
		(net "GND")
	)
	(segment
		(start 30.94736 -37.087048)
		(end 31.58236 -37.087048)
		(width 0.4572)
		(layer "F.Cu")
		(net "GND")
	)
	(segment
		(start 79.12481 -303.974754)
		(end 78.64983 -303.499774)
		(width 0.249936)
		(layer "F.Cu")
		(net "GND")
	)
	(segment
		(start 154.850084 -297.79976)
		(end 155.325064 -298.27474)
		(width 0.249936)
		(layer "F.Cu")
		(net "GND")
	)
	(segment
		(start 123.31319 -135.058404)
		(end 122.65787 -135.058404)
		(width 0.4064)
		(layer "F.Cu")
		(net "GND")
	)
	(segment
		(start 174.800006 -283.549852)
		(end 174.325026 -283.074872)
		(width 0.249936)
		(layer "F.Cu")
		(net "GND")
	)
	(segment
		(start 54.282594 -28.47848)
		(end 53.94325 -28.139136)
		(width 0.254)
		(layer "F.Cu")
		(net "GND")
	)
	(segment
		(start 183.82488 -302.074834)
		(end 184.29986 -302.549814)
		(width 0.249936)
		(layer "F.Cu")
		(net "GND")
	)
	(segment
		(start 81.349596 -85.426296)
		(end 80.239616 -85.426296)
		(width 0.4572)
		(layer "F.Cu")
		(net "GND")
	)
	(segment
		(start 153.89987 -296.8498)
		(end 154.37485 -297.32478)
		(width 0.249936)
		(layer "F.Cu")
		(net "GND")
	)
	(segment
		(start 300.874684 -293.52494)
		(end 301.349918 -293.04996)
		(width 0.249936)
		(layer "F.Cu")
		(net "GND")
	)
	(segment
		(start 416.499802 -300.649894)
		(end 416.024822 -300.174914)
		(width 0.249936)
		(layer "F.Cu")
		(net "GND")
	)
	(segment
		(start 285.199836 -305.399948)
		(end 284.724856 -305.874928)
		(width 0.249936)
		(layer "F.Cu")
		(net "GND")
	)
	(segment
		(start 176.224946 -285.924752)
		(end 175.749966 -285.449772)
		(width 0.249936)
		(layer "F.Cu")
		(net "GND")
	)
	(segment
		(start 395.59992 -295.89984)
		(end 394.64996 -296.8498)
		(width 0.249936)
		(layer "F.Cu")
		(net "GND")
	)
	(segment
		(start 92.2147 -26.171398)
		(end 92.396056 -25.990042)
		(width 0.3556)
		(layer "F.Cu")
		(net "GND")
	)
	(segment
		(start 76.27493 -292.574726)
		(end 75.79995 -292.099746)
		(width 0.249936)
		(layer "F.Cu")
		(net "GND")
	)
	(segment
		(start 65.349882 -303.499774)
		(end 64.874902 -303.974754)
		(width 0.249936)
		(layer "F.Cu")
		(net "GND")
	)
	(segment
		(start 188.366908 -129.445004)
		(end 189.357508 -129.445004)
		(width 0.3556)
		(layer "F.Cu")
		(net "GND")
	)
	(segment
		(start 184.29986 -297.79976)
		(end 184.77484 -298.27474)
		(width 0.249936)
		(layer "F.Cu")
		(net "GND")
	)
	(segment
		(start 424.57497 -291.624766)
		(end 425.04995 -291.149786)
		(width 0.249936)
		(layer "F.Cu")
		(net "GND")
	)
	(segment
		(start 410.324808 -306.824888)
		(end 410.799788 -307.299868)
		(width 0.249936)
		(layer "F.Cu")
		(net "GND")
	)
	(segment
		(start 400.349974 -292.099746)
		(end 400.824954 -291.624766)
		(width 0.249936)
		(layer "F.Cu")
		(net "GND")
	)
	(segment
		(start 163.031932 -104.244902)
		(end 162.14217 -104.244902)
		(width 0.3556)
		(layer "F.Cu")
		(net "GND")
	)
	(segment
		(start 51.63312 -133.565138)
		(end 50.64252 -133.565138)
		(width 0.3556)
		(layer "F.Cu")
		(net "GND")
	)
	(segment
		(start 185.737246 -125.752352)
		(end 185.42 -125.435106)
		(width 0.3556)
		(layer "F.Cu")
		(net "GND")
	)
	(segment
		(start 267.498576 -136.859264)
		(end 267.498576 -136.680956)
		(width 0.4572)
		(layer "F.Cu")
		(net "GND")
	)
	(segment
		(start 300.399704 -290.199826)
		(end 300.874684 -289.724846)
		(width 0.249936)
		(layer "F.Cu")
		(net "GND")
	)
	(segment
		(start 303.724818 -289.724846)
		(end 303.249838 -290.199826)
		(width 0.249936)
		(layer "F.Cu")
		(net "GND")
	)
	(segment
		(start 264.734548 -38.937184)
		(end 264.999978 -38.671754)
		(width 0.4572)
		(layer "F.Cu")
		(net "GND")
	)
	(segment
		(start 260.12521 -338.826856)
		(end 260.530086 -338.826856)
		(width 0.4572)
		(layer "F.Cu")
		(net "GND")
	)
	(segment
		(start 15.264892 -34.990024)
		(end 16.280892 -34.990024)
		(width 0.3556)
		(layer "F.Cu")
		(net "GND")
	)
	(segment
		(start 174.325026 -303.974754)
		(end 174.800006 -303.499774)
		(width 0.249936)
		(layer "F.Cu")
		(net "GND")
	)
	(segment
		(start 16.280892 -27.79014)
		(end 15.264892 -27.79014)
		(width 0.3556)
		(layer "F.Cu")
		(net "GND")
	)
	(segment
		(start 272.849848 -288.299906)
		(end 273.324828 -287.824926)
		(width 0.249936)
		(layer "F.Cu")
		(net "GND")
	)
	(segment
		(start 189.524894 -299.224954)
		(end 189.999874 -298.74972)
		(width 0.249936)
		(layer "F.Cu")
		(net "GND")
	)
	(segment
		(start 400.349974 -296.8498)
		(end 399.874994 -297.32478)
		(width 0.249936)
		(layer "F.Cu")
		(net "GND")
	)
	(segment
		(start 415.173414 -190.66002)
		(end 414.321498 -190.66002)
		(width 0.4572)
		(layer "F.Cu")
		(net "GND")
	)
	(segment
		(start 190.950088 -303.499774)
		(end 189.999874 -303.499774)
		(width 0.249936)
		(layer "F.Cu")
		(net "GND")
	)
	(segment
		(start 173.850046 -292.099746)
		(end 173.375066 -291.624766)
		(width 0.249936)
		(layer "F.Cu")
		(net "GND")
	)
	(segment
		(start 120.815354 -59.946286)
		(end 120.815354 -60.601606)
		(width 0.4572)
		(layer "F.Cu")
		(net "GND")
	)
	(segment
		(start 94.280736 -34.990024)
		(end 93.264736 -34.990024)
		(width 0.3556)
		(layer "F.Cu")
		(net "GND")
	)
	(segment
		(start 417.94811 -118.370858)
		(end 417.930584 -118.370858)
		(width 0.3556)
		(layer "F.Cu")
		(net "GND")
	)
	(segment
		(start 303.249838 -297.79976)
		(end 303.724818 -298.27474)
		(width 0.249936)
		(layer "F.Cu")
		(net "GND")
	)
	(segment
		(start 422.199816 -303.499774)
		(end 421.724836 -303.974754)
		(width 0.249936)
		(layer "F.Cu")
		(net "GND")
	)
	(segment
		(start 68.674742 -285.924752)
		(end 69.149976 -285.449772)
		(width 0.249936)
		(layer "F.Cu")
		(net "GND")
	)
	(segment
		(start 180.50002 -297.79976)
		(end 180.02504 -297.32478)
		(width 0.249936)
		(layer "F.Cu")
		(net "GND")
	)
	(segment
		(start 197.600062 -293.99992)
		(end 197.125082 -294.4749)
		(width 0.249936)
		(layer "F.Cu")
		(net "GND")
	)
	(segment
		(start 285.1277 -14.735302)
		(end 285.255208 -14.607794)
		(width 0.381)
		(layer "F.Cu")
		(net "GND")
	)
	(segment
		(start 285.674816 -285.924752)
		(end 286.149796 -285.449772)
		(width 0.249936)
		(layer "F.Cu")
		(net "GND")
	)
	(segment
		(start 416.974782 -286.874966)
		(end 416.499802 -287.349946)
		(width 0.249936)
		(layer "F.Cu")
		(net "GND")
	)
	(segment
		(start 162.450018 -306.349908)
		(end 162.924998 -306.824888)
		(width 0.249936)
		(layer "F.Cu")
		(net "GND")
	)
	(segment
		(start 155.800044 -283.549852)
		(end 155.325064 -283.074872)
		(width 0.249936)
		(layer "F.Cu")
		(net "GND")
	)
	(segment
		(start 233.867706 -215.904064)
		(end 233.867706 -215.904572)
		(width 0.381)
		(layer "F.Cu")
		(net "GND")
	)
	(segment
		(start 428.44466 -34.183066)
		(end 427.895258 -34.732468)
		(width 0.4572)
		(layer "F.Cu")
		(net "GND")
	)
	(segment
		(start 184.77484 -307.774848)
		(end 185.250074 -307.299868)
		(width 0.249936)
		(layer "F.Cu")
		(net "GND")
	)
	(segment
		(start 435.24043 -143.582898)
		(end 433.184046 -143.582898)
		(width 0.4572)
		(layer "F.Cu")
		(net "GND")
	)
	(segment
		(start 219.60205 -195.707)
		(end 219.60205 -195.072)
		(width 0.4572)
		(layer "F.Cu")
		(net "GND")
	)
	(segment
		(start 144.46504 -393.02944)
		(end 145.273268 -393.02944)
		(width 0.4572)
		(layer "F.Cu")
		(net "GND")
	)
	(segment
		(start 163.13277 -120.555004)
		(end 162.14217 -120.555004)
		(width 0.3556)
		(layer "F.Cu")
		(net "GND")
	)
	(segment
		(start 239.14989 -209.164428)
		(end 240.359184 -209.164428)
		(width 0.4572)
		(layer "F.Cu")
		(net "GND")
	)
	(segment
		(start 364.612936 -118.779036)
		(end 364.612936 -119.39143)
		(width 0.4572)
		(layer "F.Cu")
		(net "GND")
	)
	(segment
		(start 405.575008 -300.174914)
		(end 406.049988 -299.699934)
		(width 0.249936)
		(layer "F.Cu")
		(net "GND")
	)
	(segment
		(start 171.474892 -305.874928)
		(end 170.999912 -306.349908)
		(width 0.249936)
		(layer "F.Cu")
		(net "GND")
	)
	(segment
		(start 414.599882 -305.399948)
		(end 415.074862 -305.874928)
		(width 0.249936)
		(layer "F.Cu")
		(net "GND")
	)
	(segment
		(start 233.40441 -69.600064)
		(end 233.547666 -69.74332)
		(width 0.3556)
		(layer "F.Cu")
		(net "GND")
	)
	(segment
		(start 154.850084 -293.04996)
		(end 154.375104 -292.57498)
		(width 0.249936)
		(layer "F.Cu")
		(net "GND")
	)
	(segment
		(start 398.94256 -107.845098)
		(end 399.932906 -107.845098)
		(width 0.4572)
		(layer "F.Cu")
		(net "GND")
	)
	(segment
		(start 50.624994 -306.824888)
		(end 50.14976 -306.349908)
		(width 0.249936)
		(layer "F.Cu")
		(net "GND")
	)
	(segment
		(start 71.524876 -305.874928)
		(end 71.049896 -306.349908)
		(width 0.249936)
		(layer "F.Cu")
		(net "GND")
	)
	(segment
		(start 55.374794 -284.024832)
		(end 54.899814 -284.499812)
		(width 0.249936)
		(layer "F.Cu")
		(net "GND")
	)
	(segment
		(start 4.248912 -28.37434)
		(end 4.248912 -27.40914)
		(width 0.4572)
		(layer "F.Cu")
		(net "GND")
	)
	(segment
		(start 408.424888 -302.074834)
		(end 407.949908 -301.599854)
		(width 0.249936)
		(layer "F.Cu")
		(net "GND")
	)
	(segment
		(start 15.264892 -27.79014)
		(end 14.248892 -27.79014)
		(width 0.3556)
		(layer "F.Cu")
		(net "GND")
	)
	(segment
		(start 283.774896 -297.32478)
		(end 283.299916 -297.79976)
		(width 0.249936)
		(layer "F.Cu")
		(net "GND")
	)
	(segment
		(start 183.766714 -133.044946)
		(end 184.757314 -133.044946)
		(width 0.3556)
		(layer "F.Cu")
		(net "GND")
	)
	(segment
		(start 294.86479 -33.19018)
		(end 293.84879 -33.19018)
		(width 0.3556)
		(layer "F.Cu")
		(net "GND")
	)
	(segment
		(start 350.582738 -28.47848)
		(end 350.243394 -28.139136)
		(width 0.254)
		(layer "F.Cu")
		(net "GND")
	)
	(segment
		(start 294.22471 -287.824926)
		(end 294.69969 -288.299906)
		(width 0.249936)
		(layer "F.Cu")
		(net "GND")
	)
	(segment
		(start 160.549844 -280.699718)
		(end 160.074864 -280.224738)
		(width 0.249936)
		(layer "F.Cu")
		(net "GND")
	)
	(segment
		(start 41.599866 -293.99992)
		(end 41.124886 -293.52494)
		(width 0.249936)
		(layer "F.Cu")
		(net "GND")
	)
	(segment
		(start 412.224982 -285.924752)
		(end 411.750002 -286.399732)
		(width 0.249936)
		(layer "F.Cu")
		(net "GND")
	)
	(segment
		(start 298.499784 -293.99992)
		(end 298.974764 -293.52494)
		(width 0.249936)
		(layer "F.Cu")
		(net "GND")
	)
	(segment
		(start 375.690384 -252.756924)
		(end 375.690384 -253.45644)
		(width 0.4572)
		(layer "F.Cu")
		(net "GND")
	)
	(segment
		(start 299.924724 -285.924752)
		(end 299.449744 -286.399732)
		(width 0.249936)
		(layer "F.Cu")
		(net "GND")
	)
	(segment
		(start 272.374868 -300.174914)
		(end 271.899888 -299.699934)
		(width 0.249936)
		(layer "F.Cu")
		(net "GND")
	)
	(segment
		(start 299.449744 -286.399732)
		(end 298.974764 -285.924752)
		(width 0.249936)
		(layer "F.Cu")
		(net "GND")
	)
	(segment
		(start 157.699964 -278.799798)
		(end 157.224984 -278.324818)
		(width 0.249936)
		(layer "F.Cu")
		(net "GND")
	)
	(segment
		(start 180.50002 -285.449772)
		(end 180.02504 -284.974792)
		(width 0.249936)
		(layer "F.Cu")
		(net "GND")
	)
	(segment
		(start 158.649924 -275.949918)
		(end 158.174944 -275.474938)
		(width 0.249936)
		(layer "F.Cu")
		(net "GND")
	)
	(segment
		(start 417.68141 -133.044946)
		(end 416.95751 -133.044946)
		(width 0.3556)
		(layer "F.Cu")
		(net "GND")
	)
	(segment
		(start 451.211188 -416.021266)
		(end 451.211188 -416.636962)
		(width 0.4572)
		(layer "F.Cu")
		(net "GND")
	)
	(segment
		(start 245.825264 -119.505476)
		(end 245.825264 -120.11787)
		(width 0.4572)
		(layer "F.Cu")
		(net "GND")
	)
	(segment
		(start 159.124904 -278.324818)
		(end 159.599884 -278.799798)
		(width 0.249936)
		(layer "F.Cu")
		(net "GND")
	)
	(segment
		(start 393.558014 -73.166732)
		(end 393.558014 -73.85177)
		(width 0.4572)
		(layer "F.Cu")
		(net "GND")
	)
	(segment
		(start 64.874902 -291.624766)
		(end 64.399922 -292.099746)
		(width 0.249936)
		(layer "F.Cu")
		(net "GND")
	)
	(segment
		(start 276.649688 -282.599892)
		(end 276.174708 -282.124912)
		(width 0.249936)
		(layer "F.Cu")
		(net "GND")
	)
	(segment
		(start 280.449782 -291.149786)
		(end 279.974802 -290.674806)
		(width 0.249936)
		(layer "F.Cu")
		(net "GND")
	)
	(segment
		(start 414.599882 -286.399732)
		(end 415.074862 -285.924752)
		(width 0.249936)
		(layer "F.Cu")
		(net "GND")
	)
	(segment
		(start 346.093796 -212.786976)
		(end 346.493592 -212.38718)
		(width 0.381)
		(layer "F.Cu")
		(net "GND")
	)
	(segment
		(start 56.799988 -285.449772)
		(end 56.324754 -284.974792)
		(width 0.249936)
		(layer "F.Cu")
		(net "GND")
	)
	(segment
		(start 49.1998 -285.449772)
		(end 48.72482 -284.974792)
		(width 0.249936)
		(layer "F.Cu")
		(net "GND")
	)
	(segment
		(start 182.39994 -303.499774)
		(end 181.92496 -303.974754)
		(width 0.249936)
		(layer "F.Cu")
		(net "GND")
	)
	(segment
		(start 163.874958 -304.924714)
		(end 164.349938 -304.449734)
		(width 0.249936)
		(layer "F.Cu")
		(net "GND")
	)
	(segment
		(start 380.609094 -27.04973)
		(end 379.949964 -27.04973)
		(width 0.4572)
		(layer "F.Cu")
		(net "GND")
	)
	(segment
		(start 47.032926 -133.565138)
		(end 46.042326 -133.565138)
		(width 0.3556)
		(layer "F.Cu")
		(net "GND")
	)
	(segment
		(start 446.57391 -73.166732)
		(end 446.57391 -73.85177)
		(width 0.4572)
		(layer "F.Cu")
		(net "GND")
	)
	(segment
		(start 171.949872 -303.499774)
		(end 171.474892 -303.974754)
		(width 0.249936)
		(layer "F.Cu")
		(net "GND")
	)
	(segment
		(start 410.799788 -295.89984)
		(end 411.275022 -296.37482)
		(width 0.249936)
		(layer "F.Cu")
		(net "GND")
	)
	(segment
		(start 422.199816 -291.149786)
		(end 421.724836 -290.674806)
		(width 0.249936)
		(layer "F.Cu")
		(net "GND")
	)
	(segment
		(start 350.093788 -220.78696)
		(end 350.493584 -221.186756)
		(width 0.381)
		(layer "F.Cu")
		(net "GND")
	)
	(segment
		(start 358.75595 -179.07)
		(end 358.14 -179.07)
		(width 0.4572)
		(layer "F.Cu")
		(net "GND")
	)
	(segment
		(start 130.094736 -158.705042)
		(end 130.094736 -159.336232)
		(width 0.254)
		(layer "F.Cu")
		(net "GND")
	)
	(segment
		(start 398.925034 -289.724846)
		(end 399.400014 -290.199826)
		(width 0.249936)
		(layer "F.Cu")
		(net "GND")
	)
	(segment
		(start 399.400014 -299.699934)
		(end 398.925034 -300.174914)
		(width 0.249936)
		(layer "F.Cu")
		(net "GND")
	)
	(segment
		(start 408.899868 -284.499812)
		(end 409.374848 -284.974792)
		(width 0.249936)
		(layer "F.Cu")
		(net "GND")
	)
	(segment
		(start 58.224928 -291.624766)
		(end 58.699908 -292.099746)
		(width 0.249936)
		(layer "F.Cu")
		(net "GND")
	)
	(segment
		(start 440.053476 -102.328218)
		(end 439.86196 -101.865684)
		(width 0.254)
		(layer "F.Cu")
		(net "GND")
	)
	(segment
		(start 189.999874 -299.699934)
		(end 190.474854 -300.174914)
		(width 0.249936)
		(layer "F.Cu")
		(net "GND")
	)
	(segment
		(start 272.849848 -289.249866)
		(end 273.324828 -289.724846)
		(width 0.254)
		(layer "F.Cu")
		(net "GND")
	)
	(segment
		(start 287.099756 -283.549852)
		(end 287.574736 -284.024832)
		(width 0.249936)
		(layer "F.Cu")
		(net "GND")
	)
	(segment
		(start 413.29737 -184.248298)
		(end 413.718502 -184.66943)
		(width 0.4572)
		(layer "F.Cu")
		(net "GND")
	)
	(segment
		(start 168.150032 -303.499774)
		(end 167.675052 -303.974754)
		(width 0.249936)
		(layer "F.Cu")
		(net "GND")
	)
	(segment
		(start 160.549844 -296.8498)
		(end 161.025078 -297.32478)
		(width 0.249936)
		(layer "F.Cu")
		(net "GND")
	)
	(segment
		(start 279.29205 -104.404922)
		(end 279.13203 -104.244902)
		(width 0.3556)
		(layer "F.Cu")
		(net "GND")
	)
	(segment
		(start 284.867858 -51.019456)
		(end 285.523178 -51.019456)
		(width 0.254)
		(layer "F.Cu")
		(net "GND")
	)
	(segment
		(start 64.399922 -292.099746)
		(end 63.924942 -291.624766)
		(width 0.249936)
		(layer "F.Cu")
		(net "GND")
	)
	(segment
		(start 343.149936 -142.502128)
		(end 344.23477 -142.502128)
		(width 0.4572)
		(layer "F.Cu")
		(net "GND")
	)
	(segment
		(start 239.00003 -38.671754)
		(end 239.00003 -38.315138)
		(width 0.4572)
		(layer "F.Cu")
		(net "GND")
	)
	(segment
		(start 132.41274 -118.779036)
		(end 132.41274 -119.39143)
		(width 0.4572)
		(layer "F.Cu")
		(net "GND")
	)
	(segment
		(start 338.47405 -173.101)
		(end 339.09 -173.101)
		(width 0.4572)
		(layer "F.Cu")
		(net "GND")
	)
	(segment
		(start 412.224982 -302.074834)
		(end 412.699962 -301.599854)
		(width 0.249936)
		(layer "F.Cu")
		(net "GND")
	)
	(segment
		(start 393.351766 -104.244902)
		(end 394.342366 -104.244902)
		(width 0.3556)
		(layer "F.Cu")
		(net "GND")
	)
	(segment
		(start 288.99993 -286.399732)
		(end 288.524696 -285.924752)
		(width 0.249936)
		(layer "F.Cu")
		(net "GND")
	)
	(segment
		(start 187.624974 -303.974754)
		(end 187.149994 -303.499774)
		(width 0.249936)
		(layer "F.Cu")
		(net "GND")
	)
	(segment
		(start 370.762022 -241.54892)
		(end 371.30609 -241.54892)
		(width 0.4572)
		(layer "F.Cu")
		(net "GND")
	)
	(segment
		(start 62.499748 -286.399732)
		(end 62.024768 -285.924752)
		(width 0.249936)
		(layer "F.Cu")
		(net "GND")
	)
	(segment
		(start 288.049716 -294.94988)
		(end 287.574736 -294.4749)
		(width 0.249936)
		(layer "F.Cu")
		(net "GND")
	)
	(segment
		(start 83.797648 -38.937184)
		(end 84.534502 -38.937184)
		(width 0.4572)
		(layer "F.Cu")
		(net "GND")
	)
	(segment
		(start 276.649688 -293.99992)
		(end 276.174708 -293.52494)
		(width 0.249936)
		(layer "F.Cu")
		(net "GND")
	)
	(segment
		(start 170.524932 -306.824888)
		(end 170.049952 -306.349908)
		(width 0.249936)
		(layer "F.Cu")
		(net "GND")
	)
	(segment
		(start 426.94987 -300.649894)
		(end 426.47489 -301.124874)
		(width 0.249936)
		(layer "F.Cu")
		(net "GND")
	)
	(segment
		(start 344.911934 -114.960654)
		(end 345.529408 -114.960654)
		(width 0.4572)
		(layer "F.Cu")
		(net "GND")
	)
	(segment
		(start 81.024984 -290.674806)
		(end 81.499964 -290.199826)
		(width 0.249936)
		(layer "F.Cu")
		(net "GND")
	)
	(segment
		(start 193.324988 -301.124874)
		(end 193.799968 -300.649894)
		(width 0.249936)
		(layer "F.Cu")
		(net "GND")
	)
	(segment
		(start 291.84981 -292.099746)
		(end 292.32479 -291.624766)
		(width 0.249936)
		(layer "F.Cu")
		(net "GND")
	)
	(segment
		(start 187.624974 -289.724846)
		(end 187.149994 -290.199826)
		(width 0.249936)
		(layer "F.Cu")
		(net "GND")
	)
	(segment
		(start 177.649886 -306.349908)
		(end 177.174906 -305.874928)
		(width 0.249936)
		(layer "F.Cu")
		(net "GND")
	)
	(segment
		(start 178.599846 -290.199826)
		(end 178.124866 -289.724846)
		(width 0.249936)
		(layer "F.Cu")
		(net "GND")
	)
	(segment
		(start 286.675068 -64.102234)
		(end 285.969456 -64.102234)
		(width 0.4572)
		(layer "F.Cu")
		(net "GND")
	)
	(segment
		(start 108.738924 -284.42412)
		(end 108.37164 -284.42412)
		(width 0.2286)
		(layer "F.Cu")
		(net "GND")
	)
	(segment
		(start 164.824918 -298.27474)
		(end 164.349938 -298.74972)
		(width 0.249936)
		(layer "F.Cu")
		(net "GND")
	)
	(segment
		(start 289.94989 -285.449772)
		(end 290.42487 -285.924752)
		(width 0.249936)
		(layer "F.Cu")
		(net "GND")
	)
	(segment
		(start 426.47489 -297.32478)
		(end 426.94987 -297.79976)
		(width 0.249936)
		(layer "F.Cu")
		(net "GND")
	)
	(segment
		(start 169.099992 -297.79976)
		(end 168.625012 -298.27474)
		(width 0.249936)
		(layer "F.Cu")
		(net "GND")
	)
	(segment
		(start 55.249826 -390.441688)
		(end 55.249826 -392.487912)
		(width 0.4572)
		(layer "F.Cu")
		(net "GND")
	)
	(segment
		(start 187.122308 -368.721386)
		(end 187.122308 -367.857786)
		(width 0.4572)
		(layer "F.Cu")
		(net "GND")
	)
	(segment
		(start 167.675052 -287.824926)
		(end 167.200072 -288.299906)
		(width 0.249936)
		(layer "F.Cu")
		(net "GND")
	)
	(segment
		(start 425.33443 -86.949026)
		(end 426.230288 -86.949026)
		(width 0.381)
		(layer "F.Cu")
		(net "GND")
	)
	(segment
		(start 401.299934 -303.499774)
		(end 401.774914 -303.974754)
		(width 0.249936)
		(layer "F.Cu")
		(net "GND")
	)
	(segment
		(start 217.424 -27.411934)
		(end 217.424 -26.319734)
		(width 0.4572)
		(layer "F.Cu")
		(net "GND")
	)
	(segment
		(start 334.89392 -214.387176)
		(end 334.494124 -213.98738)
		(width 0.254)
		(layer "F.Cu")
		(net "GND")
	)
	(segment
		(start 141.162532 -23.355554)
		(end 141.812264 -23.355554)
		(width 0.4572)
		(layer "F.Cu")
		(net "GND")
	)
	(segment
		(start 191.425068 -294.4749)
		(end 191.900048 -293.99992)
		(width 0.249936)
		(layer "F.Cu")
		(net "GND")
	)
	(segment
		(start 412.699962 -305.399948)
		(end 412.224982 -305.874928)
		(width 0.249936)
		(layer "F.Cu")
		(net "GND")
	)
	(segment
		(start 384.00609 -114.4905)
		(end 382.997456 -114.4905)
		(width 0.4572)
		(layer "F.Cu")
		(net "GND")
	)
	(segment
		(start 394.17498 -296.37482)
		(end 394.64996 -295.89984)
		(width 0.249936)
		(layer "F.Cu")
		(net "GND")
	)
	(segment
		(start 183.766714 -120.035066)
		(end 184.757314 -120.035066)
		(width 0.3556)
		(layer "F.Cu")
		(net "GND")
	)
	(segment
		(start 444.226442 -25.832054)
		(end 444.869824 -25.832054)
		(width 0.4572)
		(layer "F.Cu")
		(net "GND")
	)
	(segment
		(start 374.3706 -110.0074)
		(end 374.3706 -110.428024)
		(width 0.4572)
		(layer "F.Cu")
		(net "GND")
	)
	(segment
		(start 349.907098 -285.488634)
		(end 349.595694 -285.488634)
		(width 0.2286)
		(layer "F.Cu")
		(net "GND")
	)
	(segment
		(start 47.146972 -53.144166)
		(end 47.146972 -52.592224)
		(width 0.254)
		(layer "F.Cu")
		(net "GND")
	)
	(segment
		(start 296.124884 -285.924752)
		(end 295.649904 -286.399732)
		(width 0.249936)
		(layer "F.Cu")
		(net "GND")
	)
	(segment
		(start 356.440994 -54.163722)
		(end 356.992936 -54.163722)
		(width 0.254)
		(layer "F.Cu")
		(net "GND")
	)
	(segment
		(start 160.549844 -282.599892)
		(end 160.074864 -282.124912)
		(width 0.249936)
		(layer "F.Cu")
		(net "GND")
	)
	(segment
		(start 399.400014 -285.449772)
		(end 398.925034 -284.974792)
		(width 0.249936)
		(layer "F.Cu")
		(net "GND")
	)
	(segment
		(start 192.850008 -298.74972)
		(end 192.375028 -298.27474)
		(width 0.249936)
		(layer "F.Cu")
		(net "GND")
	)
	(segment
		(start 177.649886 -306.349908)
		(end 178.124866 -305.874928)
		(width 0.249936)
		(layer "F.Cu")
		(net "GND")
	)
	(segment
		(start 307.060854 -37.201094)
		(end 306.298346 -37.201094)
		(width 0.4572)
		(layer "F.Cu")
		(net "GND")
	)
	(segment
		(start 170.999912 -307.299868)
		(end 170.524932 -306.824888)
		(width 0.249936)
		(layer "F.Cu")
		(net "GND")
	)
	(segment
		(start 70.574916 -288.774886)
		(end 71.049896 -289.249866)
		(width 0.249936)
		(layer "F.Cu")
		(net "GND")
	)
	(segment
		(start 425.52493 -303.024794)
		(end 425.04995 -302.549814)
		(width 0.249936)
		(layer "F.Cu")
		(net "GND")
	)
	(segment
		(start 280.924762 -305.874928)
		(end 281.399742 -306.349908)
		(width 0.249936)
		(layer "F.Cu")
		(net "GND")
	)
	(segment
		(start 438.31764 -303.636426)
		(end 438.31764 -303.026826)
		(width 0.4572)
		(layer "F.Cu")
		(net "GND")
	)
	(segment
		(start 35.70605 -114.4905)
		(end 34.697416 -114.4905)
		(width 0.4572)
		(layer "F.Cu")
		(net "GND")
	)
	(segment
		(start 277.124922 -282.124912)
		(end 277.599902 -282.599892)
		(width 0.249936)
		(layer "F.Cu")
		(net "GND")
	)
	(segment
		(start 159.599884 -284.499812)
		(end 159.124904 -284.024832)
		(width 0.249936)
		(layer "F.Cu")
		(net "GND")
	)
	(segment
		(start 61.648848 -31.390082)
		(end 62.664848 -31.390082)
		(width 0.3556)
		(layer "F.Cu")
		(net "GND")
	)
	(segment
		(start 387.050026 -299.699934)
		(end 387.999986 -299.699934)
		(width 0.249936)
		(layer "F.Cu")
		(net "GND")
	)
	(segment
		(start 5.472176 -378.370592)
		(end 5.472176 -375.834148)
		(width 0.381)
		(layer "F.Cu")
		(net "GND")
	)
	(segment
		(start 387.30809 -160.974278)
		(end 387.30809 -160.380934)
		(width 0.4572)
		(layer "F.Cu")
		(net "GND")
	)
	(segment
		(start 167.675052 -294.4749)
		(end 167.200072 -293.99992)
		(width 0.249936)
		(layer "F.Cu")
		(net "GND")
	)
	(segment
		(start 249.627898 -228.538278)
		(end 249.490992 -228.538278)
		(width 0.4572)
		(layer "F.Cu")
		(net "GND")
	)
	(segment
		(start 311.324752 -290.674806)
		(end 311.799732 -291.149786)
		(width 0.249936)
		(layer "F.Cu")
		(net "GND")
	)
	(segment
		(start 228.39299 -93.057726)
		(end 227.734368 -93.057726)
		(width 0.254)
		(layer "F.Cu")
		(net "GND")
	)
	(segment
		(start 264.319004 -59.974734)
		(end 263.66851 -59.974734)
		(width 0.4572)
		(layer "F.Cu")
		(net "GND")
	)
	(segment
		(start 411.750002 -303.499774)
		(end 412.224982 -303.974754)
		(width 0.249936)
		(layer "F.Cu")
		(net "GND")
	)
	(segment
		(start 61.741812 -160.981644)
		(end 61.741812 -161.667444)
		(width 0.4572)
		(layer "F.Cu")
		(net "GND")
	)
	(segment
		(start 41.26484 -33.19018)
		(end 42.28084 -33.19018)
		(width 0.3556)
		(layer "F.Cu")
		(net "GND")
	)
	(segment
		(start 176.208182 -177.711862)
		(end 176.063402 -177.856642)
		(width 0.3048)
		(layer "F.Cu")
		(net "GND")
	)
	(segment
		(start 73.899776 -293.99992)
		(end 74.374756 -294.4749)
		(width 0.249936)
		(layer "F.Cu")
		(net "GND")
	)
	(segment
		(start 183.82488 -284.974792)
		(end 184.29986 -284.499812)
		(width 0.249936)
		(layer "F.Cu")
		(net "GND")
	)
	(segment
		(start 238.28375 -59.351926)
		(end 238.28375 -58.646314)
		(width 0.4572)
		(layer "F.Cu")
		(net "GND")
	)
	(segment
		(start 43.499786 -291.149786)
		(end 43.024806 -290.674806)
		(width 0.249936)
		(layer "F.Cu")
		(net "GND")
	)
	(segment
		(start 102.987094 -397.912336)
		(end 102.987094 -398.66824)
		(width 0.4572)
		(layer "F.Cu")
		(net "GND")
	)
	(segment
		(start 418.874956 -285.924752)
		(end 419.349936 -286.399732)
		(width 0.249936)
		(layer "F.Cu")
		(net "GND")
	)
	(segment
		(start 183.82488 -300.174914)
		(end 183.3499 -299.699934)
		(width 0.249936)
		(layer "F.Cu")
		(net "GND")
	)
	(segment
		(start 248.480834 -25.990042)
		(end 247.464834 -25.990042)
		(width 0.3556)
		(layer "F.Cu")
		(net "GND")
	)
	(segment
		(start 194.274948 -299.224954)
		(end 193.799968 -298.74972)
		(width 0.249936)
		(layer "F.Cu")
		(net "GND")
	)
	(segment
		(start 415.549842 -299.699934)
		(end 415.074862 -300.174914)
		(width 0.249936)
		(layer "F.Cu")
		(net "GND")
	)
	(segment
		(start 396.54988 -296.8498)
		(end 396.0749 -297.32478)
		(width 0.249936)
		(layer "F.Cu")
		(net "GND")
	)
	(segment
		(start 285.199836 -284.499812)
		(end 285.674816 -284.974792)
		(width 0.249936)
		(layer "F.Cu")
		(net "GND")
	)
	(segment
		(start 92.595954 -103.259128)
		(end 92.595954 -103.894128)
		(width 0.4572)
		(layer "F.Cu")
		(net "GND")
	)
	(segment
		(start 183.766714 -154.755088)
		(end 184.757314 -154.755088)
		(width 0.3556)
		(layer "F.Cu")
		(net "GND")
	)
	(segment
		(start 305.149758 -293.04996)
		(end 305.624738 -293.52494)
		(width 0.249936)
		(layer "F.Cu")
		(net "GND")
	)
	(segment
		(start 429.800004 -301.599854)
		(end 429.325024 -302.074834)
		(width 0.249936)
		(layer "F.Cu")
		(net "GND")
	)
	(segment
		(start 213.130638 -238.66602)
		(end 213.136988 -238.67237)
		(width 0.4572)
		(layer "F.Cu")
		(net "GND")
	)
	(segment
		(start 166.7891 -176.478438)
		(end 166.7891 -175.855376)
		(width 0.381)
		(layer "F.Cu")
		(net "GND")
	)
	(segment
		(start 376.706384 -252.756924)
		(end 376.706384 -253.45644)
		(width 0.4572)
		(layer "F.Cu")
		(net "GND")
	)
	(segment
		(start 135.926068 -100.154486)
		(end 135.926068 -100.978208)
		(width 0.4572)
		(layer "F.Cu")
		(net "GND")
	)
	(segment
		(start 69.149976 -293.99992)
		(end 69.624956 -294.4749)
		(width 0.249936)
		(layer "F.Cu")
		(net "GND")
	)
	(segment
		(start 303.724818 -296.37482)
		(end 303.249838 -295.89984)
		(width 0.249936)
		(layer "F.Cu")
		(net "GND")
	)
	(segment
		(start 163.399978 -295.89984)
		(end 162.450018 -296.8498)
		(width 0.249936)
		(layer "F.Cu")
		(net "GND")
	)
	(segment
		(start 81.499964 -290.199826)
		(end 81.024984 -289.724846)
		(width 0.249936)
		(layer "F.Cu")
		(net "GND")
	)
	(segment
		(start 50.14976 -304.449734)
		(end 49.67478 -303.974754)
		(width 0.249936)
		(layer "F.Cu")
		(net "GND")
	)
	(segment
		(start 336.753708 -198.67372)
		(end 337.206336 -198.67372)
		(width 0.4572)
		(layer "F.Cu")
		(net "GND")
	)
	(segment
		(start 401.259548 -14.735302)
		(end 401.403058 -14.591792)
		(width 0.381)
		(layer "F.Cu")
		(net "GND")
	)
	(segment
		(start 78.667864 -56.353456)
		(end 79.323184 -56.353456)
		(width 0.254)
		(layer "F.Cu")
		(net "GND")
	)
	(segment
		(start 229.867714 -218.30411)
		(end 230.26751 -217.904314)
		(width 0.381)
		(layer "F.Cu")
		(net "GND")
	)
	(segment
		(start 191.900048 -290.199826)
		(end 191.425068 -290.674806)
		(width 0.249936)
		(layer "F.Cu")
		(net "GND")
	)
	(segment
		(start 281.747468 -121.692416)
		(end 281.747468 -122.044206)
		(width 0.3556)
		(layer "F.Cu")
		(net "GND")
	)
	(segment
		(start 167.732964 -129.964942)
		(end 166.742364 -129.964942)
		(width 0.3556)
		(layer "F.Cu")
		(net "GND")
	)
	(segment
		(start 415.173414 -186.03722)
		(end 414.281874 -186.03722)
		(width 0.4572)
		(layer "F.Cu")
		(net "GND")
	)
	(segment
		(start 160.549844 -298.74972)
		(end 160.074864 -298.27474)
		(width 0.249936)
		(layer "F.Cu")
		(net "GND")
	)
	(segment
		(start 279.65908 -165.902894)
		(end 280.529792 -165.902894)
		(width 0.381)
		(layer "F.Cu")
		(net "GND")
	)
	(segment
		(start 289.47491 -305.874928)
		(end 288.99993 -305.399948)
		(width 0.249936)
		(layer "F.Cu")
		(net "GND")
	)
	(segment
		(start 331.002132 -94.799658)
		(end 331.002132 -94.244922)
		(width 0.4064)
		(layer "F.Cu")
		(net "GND")
	)
	(segment
		(start 369.590066 -73.166732)
		(end 369.590066 -73.85177)
		(width 0.4572)
		(layer "F.Cu")
		(net "GND")
	)
	(segment
		(start 294.69969 -284.499812)
		(end 295.174924 -284.974792)
		(width 0.249936)
		(layer "F.Cu")
		(net "GND")
	)
	(segment
		(start 67.724782 -303.974754)
		(end 67.249802 -303.499774)
		(width 0.249936)
		(layer "F.Cu")
		(net "GND")
	)
	(segment
		(start 44.449746 -293.99992)
		(end 43.974766 -293.52494)
		(width 0.249936)
		(layer "F.Cu")
		(net "GND")
	)
	(segment
		(start 404.624794 -287.824926)
		(end 405.100028 -288.299906)
		(width 0.249936)
		(layer "F.Cu")
		(net "GND")
	)
	(segment
		(start 174.69485 -101.782372)
		(end 174.079662 -101.782372)
		(width 0.4064)
		(layer "F.Cu")
		(net "GND")
	)
	(segment
		(start 301.824898 -284.024832)
		(end 301.349918 -284.499812)
		(width 0.249936)
		(layer "F.Cu")
		(net "GND")
	)
	(segment
		(start 324.795896 -103.259128)
		(end 324.795896 -103.894128)
		(width 0.4572)
		(layer "F.Cu")
		(net "GND")
	)
	(segment
		(start 285.674816 -305.874928)
		(end 285.199836 -306.349908)
		(width 0.249936)
		(layer "F.Cu")
		(net "GND")
	)
	(segment
		(start 49.65192 -118.754906)
		(end 50.64252 -118.754906)
		(width 0.3556)
		(layer "F.Cu")
		(net "GND")
	)
	(segment
		(start 278.549862 -290.199826)
		(end 278.074882 -289.724846)
		(width 0.249936)
		(layer "F.Cu")
		(net "GND")
	)
	(segment
		(start 73.14692 -52.592224)
		(end 73.222104 -52.51704)
		(width 0.254)
		(layer "F.Cu")
		(net "GND")
	)
	(segment
		(start 11.731244 -275.7551)
		(end 11.98753 -275.7551)
		(width 0.254)
		(layer "F.Cu")
		(net "GND")
	)
	(segment
		(start 286.040068 -33.248092)
		(end 286.040068 -33.857692)
		(width 0.4572)
		(layer "F.Cu")
		(net "GND")
	)
	(segment
		(start 301.88408 -120.400572)
		(end 301.518574 -120.035066)
		(width 0.3556)
		(layer "F.Cu")
		(net "GND")
	)
	(segment
		(start 399.93316 -118.754906)
		(end 398.94256 -118.754906)
		(width 0.3556)
		(layer "F.Cu")
		(net "GND")
	)
	(segment
		(start 309.424832 -303.024794)
		(end 309.899812 -302.549814)
		(width 0.249936)
		(layer "F.Cu")
		(net "GND")
	)
	(segment
		(start 278.549862 -303.499774)
		(end 279.024842 -303.974754)
		(width 0.249936)
		(layer "F.Cu")
		(net "GND")
	)
	(segment
		(start 447.218562 -46.693836)
		(end 447.019172 -46.893226)
		(width 0.254)
		(layer "F.Cu")
		(net "GND")
	)
	(segment
		(start 185.725054 -296.37482)
		(end 185.250074 -295.89984)
		(width 0.249936)
		(layer "F.Cu")
		(net "GND")
	)
	(segment
		(start 428.37481 -296.37482)
		(end 427.89983 -296.8498)
		(width 0.249936)
		(layer "F.Cu")
		(net "GND")
	)
	(segment
		(start 62.974982 -306.824888)
		(end 63.449962 -307.299868)
		(width 0.249936)
		(layer "F.Cu")
		(net "GND")
	)
	(segment
		(start 276.649688 -295.89984)
		(end 276.174708 -296.37482)
		(width 0.249936)
		(layer "F.Cu")
		(net "GND")
	)
	(segment
		(start 114.23523 -158.87319)
		(end 113.21923 -158.87319)
		(width 0.4572)
		(layer "F.Cu")
		(net "GND")
	)
	(segment
		(start 416.974782 -291.624766)
		(end 416.499802 -291.149786)
		(width 0.249936)
		(layer "F.Cu")
		(net "GND")
	)
	(segment
		(start 97.77476 -48.753014)
		(end 97.068132 -48.753014)
		(width 0.254)
		(layer "F.Cu")
		(net "GND")
	)
	(segment
		(start 39.19093 -142.892018)
		(end 39.757604 -142.892018)
		(width 0.4572)
		(layer "F.Cu")
		(net "GND")
	)
	(segment
		(start 61.549788 -301.599854)
		(end 62.024768 -302.074834)
		(width 0.249936)
		(layer "F.Cu")
		(net "GND")
	)
	(segment
		(start 352.67392 -26.606246)
		(end 352.67392 -25.971246)
		(width 0.4572)
		(layer "F.Cu")
		(net "GND")
	)
	(segment
		(start 422.199816 -306.349908)
		(end 422.674796 -305.874928)
		(width 0.249936)
		(layer "F.Cu")
		(net "GND")
	)
	(segment
		(start 306.099718 -291.149786)
		(end 306.574698 -290.674806)
		(width 0.249936)
		(layer "F.Cu")
		(net "GND")
	)
	(segment
		(start 423.15003 -299.699934)
		(end 423.62501 -300.174914)
		(width 0.249936)
		(layer "F.Cu")
		(net "GND")
	)
	(segment
		(start 290.42487 -306.824888)
		(end 290.89985 -306.349908)
		(width 0.249936)
		(layer "F.Cu")
		(net "GND")
	)
	(segment
		(start 63.449962 -284.499812)
		(end 62.974982 -284.974792)
		(width 0.249936)
		(layer "F.Cu")
		(net "GND")
	)
	(segment
		(start 253.9238 -258.067556)
		(end 253.9238 -258.6736)
		(width 0.4572)
		(layer "F.Cu")
		(net "GND")
	)
	(segment
		(start 415.074862 -303.974754)
		(end 415.549842 -303.499774)
		(width 0.249936)
		(layer "F.Cu")
		(net "GND")
	)
	(segment
		(start 362.296964 -387.160008)
		(end 361.646724 -387.160008)
		(width 0.4572)
		(layer "F.Cu")
		(net "GND")
	)
	(segment
		(start 67.66687 -123.635008)
		(end 68.65747 -123.635008)
		(width 0.3556)
		(layer "F.Cu")
		(net "GND")
	)
	(segment
		(start 387.050026 -274.999958)
		(end 386.575046 -274.524978)
		(width 0.249936)
		(layer "F.Cu")
		(net "GND")
	)
	(segment
		(start 204.764894 -27.79014)
		(end 203.748894 -27.79014)
		(width 0.3556)
		(layer "F.Cu")
		(net "GND")
	)
	(segment
		(start 210.942936 -189.052454)
		(end 210.942936 -189.662054)
		(width 0.4572)
		(layer "F.Cu")
		(net "GND")
	)
	(segment
		(start 409.374848 -305.874928)
		(end 408.899868 -306.349908)
		(width 0.249936)
		(layer "F.Cu")
		(net "GND")
	)
	(segment
		(start 163.399978 -308.249828)
		(end 162.924998 -307.774848)
		(width 0.249936)
		(layer "F.Cu")
		(net "GND")
	)
	(segment
		(start 173.375066 -297.32478)
		(end 173.850046 -296.8498)
		(width 0.249936)
		(layer "F.Cu")
		(net "GND")
	)
	(segment
		(start 411.275022 -293.52494)
		(end 410.799788 -293.99992)
		(width 0.249936)
		(layer "F.Cu")
		(net "GND")
	)
	(segment
		(start 40.649906 -300.649894)
		(end 41.124886 -300.174914)
		(width 0.249936)
		(layer "F.Cu")
		(net "GND")
	)
	(segment
		(start 58.699908 -293.99992)
		(end 58.224928 -293.52494)
		(width 0.249936)
		(layer "F.Cu")
		(net "GND")
	)
	(segment
		(start 162.450018 -293.99992)
		(end 161.975038 -293.52494)
		(width 0.249936)
		(layer "F.Cu")
		(net "GND")
	)
	(segment
		(start 306.574698 -302.074834)
		(end 307.049932 -301.599854)
		(width 0.249936)
		(layer "F.Cu")
		(net "GND")
	)
	(segment
		(start 70.574916 -291.624766)
		(end 71.049896 -292.099746)
		(width 0.249936)
		(layer "F.Cu")
		(net "GND")
	)
	(segment
		(start 281.874722 -302.074834)
		(end 281.399742 -301.599854)
		(width 0.249936)
		(layer "F.Cu")
		(net "GND")
	)
	(segment
		(start 174.800006 -286.399732)
		(end 174.325026 -285.924752)
		(width 0.249936)
		(layer "F.Cu")
		(net "GND")
	)
	(segment
		(start 289.47491 -285.924752)
		(end 288.99993 -285.449772)
		(width 0.249936)
		(layer "F.Cu")
		(net "GND")
	)
	(segment
		(start 408.424888 -297.32478)
		(end 408.899868 -297.79976)
		(width 0.249936)
		(layer "F.Cu")
		(net "GND")
	)
	(segment
		(start 32.800036 -38.671754)
		(end 32.800036 -38.315138)
		(width 0.4572)
		(layer "F.Cu")
		(net "GND")
	)
	(segment
		(start 209.364834 -27.79014)
		(end 210.380834 -27.79014)
		(width 0.3556)
		(layer "F.Cu")
		(net "GND")
	)
	(segment
		(start 396.54988 -306.349908)
		(end 396.0749 -305.874928)
		(width 0.249936)
		(layer "F.Cu")
		(net "GND")
	)
	(segment
		(start 241.910362 -123.947428)
		(end 241.255042 -123.947428)
		(width 0.4064)
		(layer "F.Cu")
		(net "GND")
	)
	(segment
		(start 58.224928 -306.824888)
		(end 58.699908 -307.299868)
		(width 0.249936)
		(layer "F.Cu")
		(net "GND")
	)
	(segment
		(start 164.349938 -301.599854)
		(end 163.874958 -301.124874)
		(width 0.249936)
		(layer "F.Cu")
		(net "GND")
	)
	(segment
		(start 385.149852 -286.399732)
		(end 384.674872 -285.924752)
		(width 0.249936)
		(layer "F.Cu")
		(net "GND")
	)
	(segment
		(start 69.149976 -307.299868)
		(end 68.674742 -307.774848)
		(width 0.249936)
		(layer "F.Cu")
		(net "GND")
	)
	(segment
		(start 188.569346 -147.55495)
		(end 189.357508 -147.55495)
		(width 0.3556)
		(layer "F.Cu")
		(net "GND")
	)
	(segment
		(start 39.224966 -298.27474)
		(end 38.749986 -298.74972)
		(width 0.249936)
		(layer "F.Cu")
		(net "GND")
	)
	(segment
		(start 401.774914 -284.974792)
		(end 402.249894 -285.449772)
		(width 0.249936)
		(layer "F.Cu")
		(net "GND")
	)
	(segment
		(start 336.866992 -57.332626)
		(end 336.866992 -56.354218)
		(width 0.4572)
		(layer "F.Cu")
		(net "GND")
	)
	(segment
		(start 396.54988 -296.8498)
		(end 397.02486 -296.37482)
		(width 0.249936)
		(layer "F.Cu")
		(net "GND")
	)
	(segment
		(start 156.750004 -289.249866)
		(end 156.275024 -289.724846)
		(width 0.254)
		(layer "F.Cu")
		(net "GND")
	)
	(segment
		(start 55.849774 -301.599854)
		(end 55.374794 -302.074834)
		(width 0.249936)
		(layer "F.Cu")
		(net "GND")
	)
	(segment
		(start 160.549844 -284.499812)
		(end 160.074864 -284.024832)
		(width 0.249936)
		(layer "F.Cu")
		(net "GND")
	)
	(segment
		(start 52.667916 -55.083456)
		(end 53.323236 -55.083456)
		(width 0.254)
		(layer "F.Cu")
		(net "GND")
	)
	(segment
		(start 306.574698 -300.174914)
		(end 307.049932 -299.699934)
		(width 0.249936)
		(layer "F.Cu")
		(net "GND")
	)
	(segment
		(start 369.830604 -65.92189)
		(end 369.830604 -65.15989)
		(width 0.4572)
		(layer "F.Cu")
		(net "GND")
	)
	(segment
		(start 315.751972 -142.250922)
		(end 315.405008 -142.597886)
		(width 0.4064)
		(layer "F.Cu")
		(net "GND")
	)
	(segment
		(start 310.374792 -299.224954)
		(end 309.899812 -298.74972)
		(width 0.249936)
		(layer "F.Cu")
		(net "GND")
	)
	(segment
		(start 192.375028 -300.174914)
		(end 191.900048 -299.699934)
		(width 0.249936)
		(layer "F.Cu")
		(net "GND")
	)
	(segment
		(start 185.725054 -292.574726)
		(end 185.250074 -293.04996)
		(width 0.249936)
		(layer "F.Cu")
		(net "GND")
	)
	(segment
		(start 417.794694 -118.234968)
		(end 416.95751 -118.234968)
		(width 0.3556)
		(layer "F.Cu")
		(net "GND")
	)
	(segment
		(start 221.647512 -231.816656)
		(end 221.647512 -232.471468)
		(width 0.4572)
		(layer "F.Cu")
		(net "GND")
	)
	(segment
		(start 229.06101 -37.201094)
		(end 228.298502 -37.201094)
		(width 0.4572)
		(layer "F.Cu")
		(net "GND")
	)
	(segment
		(start 41.599866 -291.149786)
		(end 41.124886 -290.674806)
		(width 0.249936)
		(layer "F.Cu")
		(net "GND")
	)
	(segment
		(start 387.050026 -299.699934)
		(end 386.574792 -299.224954)
		(width 0.249936)
		(layer "F.Cu")
		(net "GND")
	)
	(segment
		(start 228.267768 -220.704156)
		(end 227.867972 -221.103952)
		(width 0.381)
		(layer "F.Cu")
		(net "GND")
	)
	(segment
		(start 69.320156 -125.435106)
		(end 68.65747 -125.435106)
		(width 0.3556)
		(layer "F.Cu")
		(net "GND")
	)
	(segment
		(start 70.099936 -300.649894)
		(end 69.624956 -300.174914)
		(width 0.249936)
		(layer "F.Cu")
		(net "GND")
	)
	(segment
		(start 147.4978 -392.7602)
		(end 147.89404 -393.15644)
		(width 0.4572)
		(layer "F.Cu")
		(net "GND")
	)
	(segment
		(start 149.671278 -307.132482)
		(end 149.382988 -306.844192)
		(width 0.4572)
		(layer "F.Cu")
		(net "GND")
	)
	(segment
		(start 126.345696 -90.057986)
		(end 126.345696 -90.195654)
		(width 0.254)
		(layer "F.Cu")
		(net "GND")
	)
	(segment
		(start 88.2523 -113.661444)
		(end 88.2523 -114.384836)
		(width 0.4572)
		(layer "F.Cu")
		(net "GND")
	)
	(segment
		(start 169.099992 -285.449772)
		(end 169.574972 -284.974792)
		(width 0.249936)
		(layer "F.Cu")
		(net "GND")
	)
	(segment
		(start 183.766714 -125.435106)
		(end 184.757314 -125.435106)
		(width 0.3556)
		(layer "F.Cu")
		(net "GND")
	)
	(segment
		(start 301.518574 -120.035066)
		(end 300.857412 -120.035066)
		(width 0.3556)
		(layer "F.Cu")
		(net "GND")
	)
	(segment
		(start 168.150032 -305.399948)
		(end 167.675052 -305.874928)
		(width 0.249936)
		(layer "F.Cu")
		(net "GND")
	)
	(segment
		(start 387.49097 -142.892018)
		(end 388.057644 -142.892018)
		(width 0.4572)
		(layer "F.Cu")
		(net "GND")
	)
	(segment
		(start 290.42487 -302.074834)
		(end 290.89985 -301.599854)
		(width 0.249936)
		(layer "F.Cu")
		(net "GND")
	)
	(segment
		(start 32.470344 -252.756924)
		(end 32.470344 -253.45644)
		(width 0.4572)
		(layer "F.Cu")
		(net "GND")
	)
	(segment
		(start 181.92496 -284.974792)
		(end 182.39994 -284.499812)
		(width 0.249936)
		(layer "F.Cu")
		(net "GND")
	)
	(segment
		(start 163.874958 -304.924714)
		(end 163.399978 -305.399948)
		(width 0.249936)
		(layer "F.Cu")
		(net "GND")
	)
	(segment
		(start 313.224926 -301.124874)
		(end 313.699906 -301.599854)
		(width 0.249936)
		(layer "F.Cu")
		(net "GND")
	)
	(segment
		(start 52.643786 -45.88891)
		(end 53.315108 -45.88891)
		(width 0.254)
		(layer "F.Cu")
		(net "GND")
	)
	(segment
		(start 303.724818 -292.574726)
		(end 304.199798 -293.04996)
		(width 0.249936)
		(layer "F.Cu")
		(net "GND")
	)
	(segment
		(start 57.274968 -305.874928)
		(end 56.799988 -305.399948)
		(width 0.249936)
		(layer "F.Cu")
		(net "GND")
	)
	(segment
		(start 305.118516 -46.693836)
		(end 304.919126 -46.893226)
		(width 0.254)
		(layer "F.Cu")
		(net "GND")
	)
	(segment
		(start 190.474854 -292.574726)
		(end 189.999874 -293.04996)
		(width 0.249936)
		(layer "F.Cu")
		(net "GND")
	)
	(segment
		(start 412.699962 -293.99992)
		(end 412.224982 -294.4749)
		(width 0.249936)
		(layer "F.Cu")
		(net "GND")
	)
	(segment
		(start 395.59992 -308.249828)
		(end 395.12494 -307.774848)
		(width 0.249936)
		(layer "F.Cu")
		(net "GND")
	)
	(segment
		(start 162.924998 -303.024794)
		(end 162.450018 -303.499774)
		(width 0.249936)
		(layer "F.Cu")
		(net "GND")
	)
	(segment
		(start 243.120418 -306.849526)
		(end 243.688362 -306.281582)
		(width 0.4572)
		(layer "F.Cu")
		(net "GND")
	)
	(segment
		(start 50.14976 -307.299868)
		(end 50.624994 -306.824888)
		(width 0.249936)
		(layer "F.Cu")
		(net "GND")
	)
	(segment
		(start 459.04658 -373.586248)
		(end 459.04658 -373.00789)
		(width 0.3048)
		(layer "F.Cu")
		(net "GND")
	)
	(segment
		(start 187.624974 -303.024794)
		(end 187.149994 -303.499774)
		(width 0.249936)
		(layer "F.Cu")
		(net "GND")
	)
	(segment
		(start 57.274968 -289.724846)
		(end 56.799988 -290.199826)
		(width 0.249936)
		(layer "F.Cu")
		(net "GND")
	)
	(segment
		(start 328.126344 -25.832054)
		(end 328.769726 -25.832054)
		(width 0.4572)
		(layer "F.Cu")
		(net "GND")
	)
	(segment
		(start 172.424852 -291.624766)
		(end 172.900086 -292.099746)
		(width 0.249936)
		(layer "F.Cu")
		(net "GND")
	)
	(segment
		(start 37.536374 -31.390082)
		(end 37.788596 -31.642304)
		(width 0.3556)
		(layer "F.Cu")
		(net "GND")
	)
	(segment
		(start 13.649198 -303.99482)
		(end 13.140944 -303.99482)
		(width 0.254)
		(layer "F.Cu")
		(net "GND")
	)
	(segment
		(start 303.724818 -303.974754)
		(end 303.249838 -304.449734)
		(width 0.249936)
		(layer "F.Cu")
		(net "GND")
	)
	(segment
		(start 70.574916 -302.074834)
		(end 71.049896 -302.549814)
		(width 0.249936)
		(layer "F.Cu")
		(net "GND")
	)
	(segment
		(start 40.649906 -285.449772)
		(end 40.174926 -284.974792)
		(width 0.249936)
		(layer "F.Cu")
		(net "GND")
	)
	(segment
		(start 413.649922 -307.299868)
		(end 413.174942 -307.774848)
		(width 0.249936)
		(layer "F.Cu")
		(net "GND")
	)
	(segment
		(start 241.76355 -212.98535)
		(end 241.5794 -212.98535)
		(width 0.4572)
		(layer "F.Cu")
		(net "GND")
	)
	(segment
		(start 309.899812 -296.8498)
		(end 309.424832 -297.32478)
		(width 0.249936)
		(layer "F.Cu")
		(net "GND")
	)
	(segment
		(start 273.799808 -297.79976)
		(end 273.324828 -298.27474)
		(width 0.249936)
		(layer "F.Cu")
		(net "GND")
	)
	(segment
		(start 452.96709 -56.354218)
		(end 452.967852 -56.353456)
		(width 0.4572)
		(layer "F.Cu")
		(net "GND")
	)
	(segment
		(start 358.964992 -29.589984)
		(end 357.948992 -29.589984)
		(width 0.3556)
		(layer "F.Cu")
		(net "GND")
	)
	(segment
		(start 397.02486 -309.674768)
		(end 397.49984 -309.199788)
		(width 0.249936)
		(layer "F.Cu")
		(net "GND")
	)
	(segment
		(start 76.74991 -298.74972)
		(end 76.27493 -298.27474)
		(width 0.249936)
		(layer "F.Cu")
		(net "GND")
	)
	(segment
		(start 388.949946 -284.499812)
		(end 388.474966 -284.024832)
		(width 0.249936)
		(layer "F.Cu")
		(net "GND")
	)
	(segment
		(start 68.669916 -303.969928)
		(end 68.679822 -303.969928)
		(width 0.249936)
		(layer "F.Cu")
		(net "GND")
	)
	(segment
		(start 403.199854 -283.549852)
		(end 402.724874 -283.074872)
		(width 0.249936)
		(layer "F.Cu")
		(net "GND")
	)
	(segment
		(start 167.732964 -138.964924)
		(end 166.742364 -138.964924)
		(width 0.3556)
		(layer "F.Cu")
		(net "GND")
	)
	(segment
		(start 417.618672 -123.635008)
		(end 416.95751 -123.635008)
		(width 0.3556)
		(layer "F.Cu")
		(net "GND")
	)
	(segment
		(start 5.260086 -44.037758)
		(end 5.260086 -44.647358)
		(width 0.4572)
		(layer "F.Cu")
		(net "GND")
	)
	(segment
		(start 81.024984 -300.174914)
		(end 80.54975 -300.649894)
		(width 0.249936)
		(layer "F.Cu")
		(net "GND")
	)
	(segment
		(start 200.219056 -59.974734)
		(end 199.568562 -59.974734)
		(width 0.4572)
		(layer "F.Cu")
		(net "GND")
	)
	(segment
		(start 448.436238 -94.864174)
		(end 448.436238 -94.208346)
		(width 0.4572)
		(layer "F.Cu")
		(net "GND")
	)
	(segment
		(start 339.773514 -240.936272)
		(end 340.527386 -240.936272)
		(width 0.3556)
		(layer "F.Cu")
		(net "GND")
	)
	(segment
		(start 373.362474 -23.355554)
		(end 374.012206 -23.355554)
		(width 0.4572)
		(layer "F.Cu")
		(net "GND")
	)
	(segment
		(start 52.999894 -288.299906)
		(end 53.474874 -287.824926)
		(width 0.249936)
		(layer "F.Cu")
		(net "GND")
	)
	(segment
		(start 195.224908 -296.37482)
		(end 195.699888 -296.8498)
		(width 0.249936)
		(layer "F.Cu")
		(net "GND")
	)
	(segment
		(start 405.100028 -306.349908)
		(end 405.575008 -305.874928)
		(width 0.249936)
		(layer "F.Cu")
		(net "GND")
	)
	(segment
		(start 189.630558 -65.92189)
		(end 189.630558 -65.15989)
		(width 0.4572)
		(layer "F.Cu")
		(net "GND")
	)
	(segment
		(start 336.024474 -120.526302)
		(end 336.785458 -120.526302)
		(width 0.4572)
		(layer "F.Cu")
		(net "GND")
	)
	(segment
		(start 246.448834 -33.19018)
		(end 247.464834 -33.19018)
		(width 0.3556)
		(layer "F.Cu")
		(net "GND")
	)
	(segment
		(start 413.649922 -288.299906)
		(end 414.124902 -287.824926)
		(width 0.249936)
		(layer "F.Cu")
		(net "GND")
	)
	(segment
		(start 17.926558 -25.832054)
		(end 18.56994 -25.832054)
		(width 0.4572)
		(layer "F.Cu")
		(net "GND")
	)
	(segment
		(start 58.799984 -38.671754)
		(end 58.799984 -38.315138)
		(width 0.4572)
		(layer "F.Cu")
		(net "GND")
	)
	(segment
		(start 78.64983 -300.649894)
		(end 78.17485 -301.124874)
		(width 0.249936)
		(layer "F.Cu")
		(net "GND")
	)
	(segment
		(start 215.7984 -232.477564)
		(end 215.7984 -232.063544)
		(width 0.4572)
		(layer "F.Cu")
		(net "GND")
	)
	(segment
		(start 196.649848 -296.8498)
		(end 197.125082 -297.32478)
		(width 0.249936)
		(layer "F.Cu")
		(net "GND")
	)
	(segment
		(start 410.324808 -284.974792)
		(end 409.849828 -285.449772)
		(width 0.249936)
		(layer "F.Cu")
		(net "GND")
	)
	(segment
		(start 46.34992 -300.649894)
		(end 45.87494 -300.174914)
		(width 0.249936)
		(layer "F.Cu")
		(net "GND")
	)
	(segment
		(start 426.47489 -291.624766)
		(end 426.94987 -292.099746)
		(width 0.249936)
		(layer "F.Cu")
		(net "GND")
	)
	(segment
		(start 395.12494 -307.774848)
		(end 394.64996 -308.249828)
		(width 0.249936)
		(layer "F.Cu")
		(net "GND")
	)
	(segment
		(start 291.303202 -59.971686)
		(end 291.303202 -60.627006)
		(width 0.381)
		(layer "F.Cu")
		(net "GND")
	)
	(segment
		(start 273.799808 -274.049744)
		(end 273.324828 -273.574764)
		(width 0.249936)
		(layer "F.Cu")
		(net "GND")
	)
	(segment
		(start 414.124902 -306.824888)
		(end 413.649922 -307.299868)
		(width 0.249936)
		(layer "F.Cu")
		(net "GND")
	)
	(segment
		(start 418.399976 -300.649894)
		(end 418.874956 -301.124874)
		(width 0.249936)
		(layer "F.Cu")
		(net "GND")
	)
	(segment
		(start 169.574972 -305.874928)
		(end 169.099992 -305.399948)
		(width 0.249936)
		(layer "F.Cu")
		(net "GND")
	)
	(segment
		(start 383.818384 -252.756924)
		(end 383.818384 -253.45644)
		(width 0.4572)
		(layer "F.Cu")
		(net "GND")
	)
	(segment
		(start 94.894146 -115.394486)
		(end 95.529146 -115.394486)
		(width 0.4572)
		(layer "F.Cu")
		(net "GND")
	)
	(segment
		(start 299.101764 -197.748906)
		(end 299.19168 -197.838822)
		(width 0.4572)
		(layer "F.Cu")
		(net "GND")
	)
	(segment
		(start 285.199836 -288.299906)
		(end 285.674816 -287.824926)
		(width 0.249936)
		(layer "F.Cu")
		(net "GND")
	)
	(segment
		(start 418.874956 -290.674806)
		(end 418.399976 -291.149786)
		(width 0.249936)
		(layer "F.Cu")
		(net "GND")
	)
	(segment
		(start 241.647218 -279.075896)
		(end 241.012218 -279.075896)
		(width 0.4572)
		(layer "F.Cu")
		(net "GND")
	)
	(segment
		(start 162.450018 -284.499812)
		(end 161.975038 -284.024832)
		(width 0.249936)
		(layer "F.Cu")
		(net "GND")
	)
	(segment
		(start 253.455678 -153.1112)
		(end 253.455678 -153.782522)
		(width 0.4064)
		(layer "F.Cu")
		(net "GND")
	)
	(segment
		(start 49.67478 -297.32478)
		(end 49.1998 -297.79976)
		(width 0.249936)
		(layer "F.Cu")
		(net "GND")
	)
	(segment
		(start 297.549824 -292.099746)
		(end 298.024804 -291.624766)
		(width 0.249936)
		(layer "F.Cu")
		(net "GND")
	)
	(segment
		(start 14.252956 -394.53058)
		(end 14.252956 -395.239494)
		(width 0.4572)
		(layer "F.Cu")
		(net "GND")
	)
	(segment
		(start 55.849774 -307.299868)
		(end 55.374794 -306.824888)
		(width 0.249936)
		(layer "F.Cu")
		(net "GND")
	)
	(segment
		(start 411.275022 -291.624766)
		(end 410.799788 -292.099746)
		(width 0.249936)
		(layer "F.Cu")
		(net "GND")
	)
	(segment
		(start 224.46615 -189.77864)
		(end 224.54743 -189.77864)
		(width 0.3048)
		(layer "F.Cu")
		(net "GND")
	)
	(segment
		(start 279.499822 -302.549814)
		(end 279.024842 -303.024794)
		(width 0.249936)
		(layer "F.Cu")
		(net "GND")
	)
	(segment
		(start 421.724836 -296.37482)
		(end 422.199816 -296.8498)
		(width 0.249936)
		(layer "F.Cu")
		(net "GND")
	)
	(segment
		(start 180.02504 -284.974792)
		(end 179.55006 -284.499812)
		(width 0.249936)
		(layer "F.Cu")
		(net "GND")
	)
	(segment
		(start 155.800044 -281.649932)
		(end 155.325064 -281.174952)
		(width 0.249936)
		(layer "F.Cu")
		(net "GND")
	)
	(segment
		(start 328.311764 -204.278484)
		(end 327.676764 -204.278484)
		(width 0.4572)
		(layer "F.Cu")
		(net "GND")
	)
	(segment
		(start 417.937442 -125.752352)
		(end 417.620196 -125.435106)
		(width 0.3556)
		(layer "F.Cu")
		(net "GND")
	)
	(segment
		(start 198.550022 -290.199826)
		(end 198.075042 -289.724846)
		(width 0.249936)
		(layer "F.Cu")
		(net "GND")
	)
	(segment
		(start 335.388458 -245.12905)
		(end 335.560416 -244.957092)
		(width 0.4572)
		(layer "F.Cu")
		(net "GND")
	)
	(segment
		(start 15.307818 -154.510994)
		(end 15.948406 -154.510994)
		(width 0.4572)
		(layer "F.Cu")
		(net "GND")
	)
	(segment
		(start 314.174886 -293.52494)
		(end 314.649866 -293.99992)
		(width 0.249936)
		(layer "F.Cu")
		(net "GND")
	)
	(segment
		(start 49.67478 -286.874966)
		(end 50.14976 -286.399732)
		(width 0.249936)
		(layer "F.Cu")
		(net "GND")
	)
	(segment
		(start 180.975 -284.974792)
		(end 180.50002 -284.499812)
		(width 0.249936)
		(layer "F.Cu")
		(net "GND")
	)
	(segment
		(start 406.049988 -288.299906)
		(end 406.049988 -288.19983)
		(width 0.249936)
		(layer "F.Cu")
		(net "GND")
	)
	(segment
		(start 238.800132 -61.651134)
		(end 238.800132 -62.409578)
		(width 0.4572)
		(layer "F.Cu")
		(net "GND")
	)
	(segment
		(start 306.448206 -143.955008)
		(end 305.457606 -143.955008)
		(width 0.3556)
		(layer "F.Cu")
		(net "GND")
	)
	(segment
		(start 185.250074 -293.04996)
		(end 184.77484 -292.574726)
		(width 0.249936)
		(layer "F.Cu")
		(net "GND")
	)
	(segment
		(start 420.299896 -300.649894)
		(end 420.774876 -300.174914)
		(width 0.249936)
		(layer "F.Cu")
		(net "GND")
	)
	(segment
		(start 282.824936 -300.174914)
		(end 283.299916 -299.699934)
		(width 0.249936)
		(layer "F.Cu")
		(net "GND")
	)
	(segment
		(start 182.39994 -290.199826)
		(end 181.92496 -289.724846)
		(width 0.249936)
		(layer "F.Cu")
		(net "GND")
	)
	(segment
		(start 388.025386 -141.029436)
		(end 388.27329 -141.029436)
		(width 0.4572)
		(layer "F.Cu")
		(net "GND")
	)
	(segment
		(start 399.874994 -306.824888)
		(end 400.349974 -306.349908)
		(width 0.249936)
		(layer "F.Cu")
		(net "GND")
	)
	(segment
		(start 365.811816 -146.263614)
		(end 365.811816 -145.837656)
		(width 0.4064)
		(layer "F.Cu")
		(net "GND")
	)
	(segment
		(start 390.374886 -298.27474)
		(end 389.899906 -297.79976)
		(width 0.249936)
		(layer "F.Cu")
		(net "GND")
	)
	(segment
		(start 255.425956 -81.05648)
		(end 255.154176 -80.7847)
		(width 0.2032)
		(layer "F.Cu")
		(net "GND")
	)
	(segment
		(start 74.374756 -302.074834)
		(end 74.84999 -301.599854)
		(width 0.249936)
		(layer "F.Cu")
		(net "GND")
	)
	(segment
		(start 73.424796 -301.124874)
		(end 73.899776 -300.649894)
		(width 0.249936)
		(layer "F.Cu")
		(net "GND")
	)
	(segment
		(start 60.9346 -389.0264)
		(end 60.3758 -389.0264)
		(width 0.4572)
		(layer "F.Cu")
		(net "GND")
	)
	(segment
		(start 299.924724 -302.074834)
		(end 300.399704 -302.549814)
		(width 0.249936)
		(layer "F.Cu")
		(net "GND")
	)
	(segment
		(start 161.975038 -301.124874)
		(end 162.450018 -301.599854)
		(width 0.249936)
		(layer "F.Cu")
		(net "GND")
	)
	(segment
		(start 57.274968 -285.924752)
		(end 57.749948 -285.449772)
		(width 0.249936)
		(layer "F.Cu")
		(net "GND")
	)
	(segment
		(start 406.524968 -306.824888)
		(end 406.049988 -307.299868)
		(width 0.249936)
		(layer "F.Cu")
		(net "GND")
	)
	(segment
		(start 19.258026 -73.166732)
		(end 19.258026 -73.85177)
		(width 0.4572)
		(layer "F.Cu")
		(net "GND")
	)
	(segment
		(start 366.630712 -257.658108)
		(end 366.630712 -258.762246)
		(width 0.3556)
		(layer "F.Cu")
		(net "GND")
	)
	(segment
		(start 33.28289 -306.844192)
		(end 32.637984 -306.844192)
		(width 0.4572)
		(layer "F.Cu")
		(net "GND")
	)
	(segment
		(start 189.247018 -52.592224)
		(end 189.322202 -52.51704)
		(width 0.254)
		(layer "F.Cu")
		(net "GND")
	)
	(segment
		(start 59.10326 -59.971686)
		(end 59.10326 -60.627006)
		(width 0.381)
		(layer "F.Cu")
		(net "GND")
	)
	(segment
		(start 279.499822 -304.449734)
		(end 279.024842 -304.924714)
		(width 0.249936)
		(layer "F.Cu")
		(net "GND")
	)
	(segment
		(start 161.975038 -294.4749)
		(end 162.450018 -294.94988)
		(width 0.249936)
		(layer "F.Cu")
		(net "GND")
	)
	(segment
		(start 278.549862 -303.499774)
		(end 279.024842 -303.024794)
		(width 0.249936)
		(layer "F.Cu")
		(net "GND")
	)
	(segment
		(start 161.975038 -282.124912)
		(end 162.450018 -282.599892)
		(width 0.249936)
		(layer "F.Cu")
		(net "GND")
	)
	(segment
		(start 74.248264 -125.435106)
		(end 73.257664 -125.435106)
		(width 0.3556)
		(layer "F.Cu")
		(net "GND")
	)
	(segment
		(start 186.200034 -293.04996)
		(end 186.675014 -292.57498)
		(width 0.249936)
		(layer "F.Cu")
		(net "GND")
	)
	(segment
		(start 437.30164 -303.636426)
		(end 437.30164 -303.026826)
		(width 0.4572)
		(layer "F.Cu")
		(net "GND")
	)
	(segment
		(start 289.94989 -292.099746)
		(end 290.42487 -291.624766)
		(width 0.249936)
		(layer "F.Cu")
		(net "GND")
	)
	(segment
		(start 264.999978 -38.671754)
		(end 264.999978 -38.315138)
		(width 0.4572)
		(layer "F.Cu")
		(net "GND")
	)
	(segment
		(start 52.999894 -299.699934)
		(end 52.524914 -300.174914)
		(width 0.249936)
		(layer "F.Cu")
		(net "GND")
	)
	(segment
		(start 198.075042 -299.224954)
		(end 198.550022 -299.699934)
		(width 0.249936)
		(layer "F.Cu")
		(net "GND")
	)
	(segment
		(start 422.548304 -151.155146)
		(end 421.557704 -151.155146)
		(width 0.3556)
		(layer "F.Cu")
		(net "GND")
	)
	(segment
		(start 390.58088 -33.19018)
		(end 389.56488 -33.19018)
		(width 0.3556)
		(layer "F.Cu")
		(net "GND")
	)
	(segment
		(start 256.19329 -76.879704)
		(end 256.19329 -76.270104)
		(width 0.4572)
		(layer "F.Cu")
		(net "GND")
	)
	(segment
		(start 428.685452 -34.183066)
		(end 428.44466 -34.183066)
		(width 0.4572)
		(layer "F.Cu")
		(net "GND")
	)
	(segment
		(start 415.96691 -131.245102)
		(end 416.95751 -131.245102)
		(width 0.3556)
		(layer "F.Cu")
		(net "GND")
	)
	(segment
		(start 143.760698 -16.439388)
		(end 143.836898 -16.363188)
		(width 0.4572)
		(layer "F.Cu")
		(net "GND")
	)
	(segment
		(start 459.574646 -306.110386)
		(end 458.862176 -306.110386)
		(width 0.4572)
		(layer "F.Cu")
		(net "GND")
	)
	(segment
		(start 125.810264 -122.931428)
		(end 125.154944 -122.931428)
		(width 0.4064)
		(layer "F.Cu")
		(net "GND")
	)
	(segment
		(start 95.831152 -100.468176)
		(end 95.755968 -100.392992)
		(width 0.254)
		(layer "F.Cu")
		(net "GND")
	)
	(segment
		(start 303.249838 -302.549814)
		(end 303.724818 -303.024794)
		(width 0.249936)
		(layer "F.Cu")
		(net "GND")
	)
	(segment
		(start 52.524914 -303.974754)
		(end 52.999894 -303.499774)
		(width 0.249936)
		(layer "F.Cu")
		(net "GND")
	)
	(segment
		(start 133.61162 -145.837656)
		(end 133.275832 -145.501868)
		(width 0.4064)
		(layer "F.Cu")
		(net "GND")
	)
	(segment
		(start 409.99791 -205.114144)
		(end 409.76169 -205.350364)
		(width 0.4572)
		(layer "F.Cu")
		(net "GND")
	)
	(segment
		(start 283.833062 -133.565138)
		(end 282.842462 -133.565138)
		(width 0.3556)
		(layer "F.Cu")
		(net "GND")
	)
	(segment
		(start 269.049754 -294.94988)
		(end 268.574774 -294.4749)
		(width 0.249936)
		(layer "F.Cu")
		(net "GND")
	)
	(segment
		(start 160.074864 -298.27474)
		(end 160.549844 -297.79976)
		(width 0.249936)
		(layer "F.Cu")
		(net "GND")
	)
	(segment
		(start 183.133746 -188.445648)
		(end 183.189372 -188.501274)
		(width 0.4572)
		(layer "F.Cu")
		(net "GND")
	)
	(segment
		(start 395.332966 -100.64496)
		(end 394.342366 -100.64496)
		(width 0.3556)
		(layer "F.Cu")
		(net "GND")
	)
	(segment
		(start 141.162024 -187.593732)
		(end 141.877796 -187.593732)
		(width 0.4572)
		(layer "F.Cu")
		(net "GND")
	)
	(segment
		(start 278.549862 -297.79976)
		(end 278.074882 -297.32478)
		(width 0.249936)
		(layer "F.Cu")
		(net "GND")
	)
	(segment
		(start 361.57281 -34.990024)
		(end 363.564932 -34.990024)
		(width 0.3556)
		(layer "F.Cu")
		(net "GND")
	)
	(segment
		(start 262.638286 -252.756924)
		(end 262.638286 -253.45644)
		(width 0.4572)
		(layer "F.Cu")
		(net "GND")
	)
	(segment
		(start 177.649886 -299.699934)
		(end 177.174906 -300.174914)
		(width 0.249936)
		(layer "F.Cu")
		(net "GND")
	)
	(segment
		(start 61.074808 -306.824888)
		(end 61.549788 -307.299868)
		(width 0.249936)
		(layer "F.Cu")
		(net "GND")
	)
	(segment
		(start 163.399978 -307.299868)
		(end 162.924998 -307.774848)
		(width 0.249936)
		(layer "F.Cu")
		(net "GND")
	)
	(segment
		(start 414.124902 -291.624766)
		(end 414.599882 -292.099746)
		(width 0.249936)
		(layer "F.Cu")
		(net "GND")
	)
	(segment
		(start 66.299842 -288.299906)
		(end 66.774822 -287.824926)
		(width 0.249936)
		(layer "F.Cu")
		(net "GND")
	)
	(segment
		(start 281.399742 -308.249828)
		(end 281.874722 -307.774848)
		(width 0.249936)
		(layer "F.Cu")
		(net "GND")
	)
	(segment
		(start 38.056058 -33.19018)
		(end 36.6649 -33.19018)
		(width 0.3556)
		(layer "F.Cu")
		(net "GND")
	)
	(segment
		(start 303.249838 -290.199826)
		(end 302.774858 -289.724846)
		(width 0.249936)
		(layer "F.Cu")
		(net "GND")
	)
	(segment
		(start 184.77484 -284.974792)
		(end 184.29986 -285.449772)
		(width 0.249936)
		(layer "F.Cu")
		(net "GND")
	)
	(segment
		(start 174.325026 -291.624766)
		(end 174.800006 -292.099746)
		(width 0.249936)
		(layer "F.Cu")
		(net "GND")
	)
	(segment
		(start 191.900048 -282.599892)
		(end 190.950088 -282.599892)
		(width 0.254)
		(layer "F.Cu")
		(net "GND")
	)
	(segment
		(start 359.016808 -162.404044)
		(end 359.016808 -163.021518)
		(width 0.4572)
		(layer "F.Cu")
		(net "GND")
	)
	(segment
		(start 409.849828 -284.499812)
		(end 409.374848 -284.974792)
		(width 0.249936)
		(layer "F.Cu")
		(net "GND")
	)
	(segment
		(start 184.29986 -290.199826)
		(end 183.82488 -289.724846)
		(width 0.249936)
		(layer "F.Cu")
		(net "GND")
	)
	(segment
		(start 440.548776 -29.589984)
		(end 441.564776 -29.589984)
		(width 0.3556)
		(layer "F.Cu")
		(net "GND")
	)
	(segment
		(start 311.324752 -298.27474)
		(end 310.849772 -297.79976)
		(width 0.249936)
		(layer "F.Cu")
		(net "GND")
	)
	(segment
		(start 45.034454 -47.936658)
		(end 45.370242 -47.60087)
		(width 0.254)
		(layer "F.Cu")
		(net "GND")
	)
	(segment
		(start 393.7 -284.499812)
		(end 393.22502 -284.024832)
		(width 0.249936)
		(layer "F.Cu")
		(net "GND")
	)
	(segment
		(start 21.257006 -405.85517)
		(end 22.098 -405.85517)
		(width 0.4572)
		(layer "F.Cu")
		(net "GND")
	)
	(segment
		(start 45.39996 -296.8498)
		(end 45.87494 -297.32478)
		(width 0.249936)
		(layer "F.Cu")
		(net "GND")
	)
	(segment
		(start 158.649924 -276.899878)
		(end 158.174944 -276.424898)
		(width 0.249936)
		(layer "F.Cu")
		(net "GND")
	)
	(segment
		(start 304.467006 -131.245102)
		(end 305.457606 -131.245102)
		(width 0.3556)
		(layer "F.Cu")
		(net "GND")
	)
	(segment
		(start 416.024822 -306.824888)
		(end 415.549842 -307.299868)
		(width 0.249936)
		(layer "F.Cu")
		(net "GND")
	)
	(segment
		(start 313.224926 -293.52494)
		(end 312.749692 -293.04996)
		(width 0.249936)
		(layer "F.Cu")
		(net "GND")
	)
	(segment
		(start 99.146868 -52.592224)
		(end 99.222052 -52.51704)
		(width 0.254)
		(layer "F.Cu")
		(net "GND")
	)
	(segment
		(start 185.755026 -145.881852)
		(end 185.62828 -145.755106)
		(width 0.3556)
		(layer "F.Cu")
		(net "GND")
	)
	(segment
		(start 199.794114 -35.499548)
		(end 200.166478 -35.871912)
		(width 0.4572)
		(layer "F.Cu")
		(net "GND")
	)
	(segment
		(start 407.254202 -371.693948)
		(end 407.254202 -370.98478)
		(width 0.4572)
		(layer "F.Cu")
		(net "GND")
	)
	(segment
		(start 271.207992 -160.974278)
		(end 271.207992 -160.380934)
		(width 0.4572)
		(layer "F.Cu")
		(net "GND")
	)
	(segment
		(start 183.766714 -121.83491)
		(end 184.757314 -121.83491)
		(width 0.3556)
		(layer "F.Cu")
		(net "GND")
	)
	(segment
		(start 350.139762 -238.09833)
		(end 351.169986 -238.09833)
		(width 0.4572)
		(layer "F.Cu")
		(net "GND")
	)
	(segment
		(start 59.649868 -307.299868)
		(end 60.124848 -306.824888)
		(width 0.249936)
		(layer "F.Cu")
		(net "GND")
	)
	(segment
		(start 170.524932 -306.824888)
		(end 170.999912 -306.349908)
		(width 0.249936)
		(layer "F.Cu")
		(net "GND")
	)
	(segment
		(start 419.349936 -303.499774)
		(end 419.824916 -303.974754)
		(width 0.249936)
		(layer "F.Cu")
		(net "GND")
	)
	(segment
		(start 452.89597 -375.629932)
		(end 453.787256 -375.629932)
		(width 0.4572)
		(layer "F.Cu")
		(net "GND")
	)
	(segment
		(start 221.719394 -123.509024)
		(end 222.480378 -123.509024)
		(width 0.4572)
		(layer "F.Cu")
		(net "GND")
	)
	(segment
		(start 42.549826 -280.699718)
		(end 42.074846 -280.224738)
		(width 0.249936)
		(layer "F.Cu")
		(net "GND")
	)
	(segment
		(start 165.299898 -284.499812)
		(end 164.824918 -284.024832)
		(width 0.249936)
		(layer "F.Cu")
		(net "GND")
	)
	(segment
		(start 234.932728 -177.008282)
		(end 234.932728 -178.066954)
		(width 0.4572)
		(layer "F.Cu")
		(net "GND")
	)
	(segment
		(start 44.449746 -286.399732)
		(end 43.974766 -286.874712)
		(width 0.249936)
		(layer "F.Cu")
		(net "GND")
	)
	(segment
		(start 298.974764 -300.174914)
		(end 299.449744 -299.699934)
		(width 0.249936)
		(layer "F.Cu")
		(net "GND")
	)
	(segment
		(start 56.324754 -289.724846)
		(end 55.849774 -290.199826)
		(width 0.249936)
		(layer "F.Cu")
		(net "GND")
	)
	(segment
		(start 218.080844 -98.40595)
		(end 218.0336 -98.358706)
		(width 0.381)
		(layer "F.Cu")
		(net "GND")
	)
	(segment
		(start 284.249876 -290.199826)
		(end 284.724856 -289.724846)
		(width 0.249936)
		(layer "F.Cu")
		(net "GND")
	)
	(segment
		(start 183.766714 -118.234968)
		(end 184.757314 -118.234968)
		(width 0.3556)
		(layer "F.Cu")
		(net "GND")
	)
	(segment
		(start 397.49984 -306.349908)
		(end 397.02486 -306.824888)
		(width 0.249936)
		(layer "F.Cu")
		(net "GND")
	)
	(segment
		(start 410.324808 -303.974754)
		(end 410.799788 -303.499774)
		(width 0.249936)
		(layer "F.Cu")
		(net "GND")
	)
	(segment
		(start 301.824898 -305.874928)
		(end 301.349918 -305.399948)
		(width 0.249936)
		(layer "F.Cu")
		(net "GND")
	)
	(segment
		(start 416.974782 -285.924752)
		(end 417.450016 -285.449772)
		(width 0.249936)
		(layer "F.Cu")
		(net "GND")
	)
	(segment
		(start 415.074862 -284.974792)
		(end 414.599882 -285.449772)
		(width 0.249936)
		(layer "F.Cu")
		(net "GND")
	)
	(segment
		(start 422.548304 -134.845044)
		(end 421.557704 -134.845044)
		(width 0.3556)
		(layer "F.Cu")
		(net "GND")
	)
	(segment
		(start 159.599884 -277.849838)
		(end 159.124904 -278.324818)
		(width 0.249936)
		(layer "F.Cu")
		(net "GND")
	)
	(segment
		(start 179.07508 -291.624766)
		(end 179.55006 -292.099746)
		(width 0.249936)
		(layer "F.Cu")
		(net "GND")
	)
	(segment
		(start 230.66756 -219.10421)
		(end 231.067356 -219.504006)
		(width 0.381)
		(layer "F.Cu")
		(net "GND")
	)
	(segment
		(start 187.624974 -298.27474)
		(end 188.099954 -298.74972)
		(width 0.249936)
		(layer "F.Cu")
		(net "GND")
	)
	(segment
		(start 214.373968 -73.166732)
		(end 214.373968 -73.85177)
		(width 0.4572)
		(layer "F.Cu")
		(net "GND")
	)
	(segment
		(start 11.49477 -159.266382)
		(end 10.054082 -160.70707)
		(width 0.254)
		(layer "F.Cu")
		(net "GND")
	)
	(segment
		(start 296.124884 -306.824888)
		(end 295.649904 -306.349908)
		(width 0.249936)
		(layer "F.Cu")
		(net "GND")
	)
	(segment
		(start 39.182802 -141.87297)
		(end 39.182802 -140.85697)
		(width 0.4572)
		(layer "F.Cu")
		(net "GND")
	)
	(segment
		(start 422.548304 -118.234968)
		(end 421.557704 -118.234968)
		(width 0.3556)
		(layer "F.Cu")
		(net "GND")
	)
	(segment
		(start 339.693758 -216.786968)
		(end 339.293962 -216.387172)
		(width 0.381)
		(layer "F.Cu")
		(net "GND")
	)
	(segment
		(start 357.805482 -285.199836)
		(end 357.805482 -284.631384)
		(width 0.2286)
		(layer "F.Cu")
		(net "GND")
	)
	(segment
		(start 379.015244 -59.946286)
		(end 379.015244 -60.601606)
		(width 0.4572)
		(layer "F.Cu")
		(net "GND")
	)
	(segment
		(start 447.446908 -53.144166)
		(end 447.446908 -52.592224)
		(width 0.254)
		(layer "F.Cu")
		(net "GND")
	)
	(segment
		(start 288.99993 -297.79976)
		(end 289.47491 -297.32478)
		(width 0.249936)
		(layer "F.Cu")
		(net "GND")
	)
	(segment
		(start 187.149994 -284.499812)
		(end 186.675014 -284.974792)
		(width 0.249936)
		(layer "F.Cu")
		(net "GND")
	)
	(segment
		(start 282.349702 -305.399948)
		(end 281.874722 -305.874928)
		(width 0.249936)
		(layer "F.Cu")
		(net "GND")
	)
	(segment
		(start 280.449782 -304.449734)
		(end 279.974802 -304.924714)
		(width 0.249936)
		(layer "F.Cu")
		(net "GND")
	)
	(segment
		(start 9.71042 -126.995428)
		(end 9.0551 -126.995428)
		(width 0.4064)
		(layer "F.Cu")
		(net "GND")
	)
	(segment
		(start 184.380886 -33.19018)
		(end 183.364886 -33.19018)
		(width 0.3556)
		(layer "F.Cu")
		(net "GND")
	)
	(segment
		(start 393.351766 -131.76504)
		(end 394.342366 -131.76504)
		(width 0.3556)
		(layer "F.Cu")
		(net "GND")
	)
	(segment
		(start 190.950088 -303.499774)
		(end 191.900048 -303.499774)
		(width 0.249936)
		(layer "F.Cu")
		(net "GND")
	)
	(segment
		(start 240.716308 -219.674948)
		(end 241.06632 -220.02496)
		(width 0.4572)
		(layer "F.Cu")
		(net "GND")
	)
	(segment
		(start 74.295 -102.439978)
		(end 73.257664 -102.439978)
		(width 0.3556)
		(layer "F.Cu")
		(net "GND")
	)
	(segment
		(start 291.84981 -301.599854)
		(end 292.32479 -302.074834)
		(width 0.249936)
		(layer "F.Cu")
		(net "GND")
	)
	(segment
		(start 398.163542 -113.780062)
		(end 398.163542 -113.485676)
		(width 0.3556)
		(layer "F.Cu")
		(net "GND")
	)
	(segment
		(start 412.699962 -306.349908)
		(end 412.224982 -306.824888)
		(width 0.249936)
		(layer "F.Cu")
		(net "GND")
	)
	(segment
		(start 174.58944 -62.812168)
		(end 175.399954 -62.812168)
		(width 0.4572)
		(layer "F.Cu")
		(net "GND")
	)
	(segment
		(start 154.307794 -155.3464)
		(end 154.307794 -156.3624)
		(width 0.4064)
		(layer "F.Cu")
		(net "GND")
	)
	(segment
		(start 18.8468 -38.49116)
		(end 18.141188 -38.49116)
		(width 0.4572)
		(layer "F.Cu")
		(net "GND")
	)
	(segment
		(start 308.474872 -293.52494)
		(end 308.949852 -293.04996)
		(width 0.249936)
		(layer "F.Cu")
		(net "GND")
	)
	(segment
		(start 67.249802 -285.449772)
		(end 67.724782 -284.974792)
		(width 0.249936)
		(layer "F.Cu")
		(net "GND")
	)
	(segment
		(start 45.020738 -151.157432)
		(end 44.986956 -151.157432)
		(width 0.3556)
		(layer "F.Cu")
		(net "GND")
	)
	(segment
		(start 62.499748 -293.99992)
		(end 62.974982 -293.52494)
		(width 0.249936)
		(layer "F.Cu")
		(net "GND")
	)
	(segment
		(start 295.174924 -284.974792)
		(end 295.649904 -284.499812)
		(width 0.249936)
		(layer "F.Cu")
		(net "GND")
	)
	(segment
		(start 419.349936 -302.549814)
		(end 419.824916 -303.024794)
		(width 0.249936)
		(layer "F.Cu")
		(net "GND")
	)
	(segment
		(start 127.845058 -27.79014)
		(end 126.76505 -27.79014)
		(width 0.3556)
		(layer "F.Cu")
		(net "GND")
	)
	(segment
		(start 421.249856 -296.8498)
		(end 421.724836 -296.37482)
		(width 0.249936)
		(layer "F.Cu")
		(net "GND")
	)
	(segment
		(start 182.39994 -285.449772)
		(end 182.87492 -285.924752)
		(width 0.249936)
		(layer "F.Cu")
		(net "GND")
	)
	(segment
		(start 303.724818 -301.124874)
		(end 303.249838 -300.649894)
		(width 0.249936)
		(layer "F.Cu")
		(net "GND")
	)
	(segment
		(start 143.891508 -305.507898)
		(end 144.467072 -306.083462)
		(width 0.4572)
		(layer "F.Cu")
		(net "GND")
	)
	(segment
		(start 229.867714 -219.10421)
		(end 230.26751 -219.504006)
		(width 0.381)
		(layer "F.Cu")
		(net "GND")
	)
	(segment
		(start 46.34992 -297.79976)
		(end 45.87494 -298.27474)
		(width 0.249936)
		(layer "F.Cu")
		(net "GND")
	)
	(segment
		(start 270.949928 -280.699718)
		(end 270.474948 -280.224738)
		(width 0.249936)
		(layer "F.Cu")
		(net "GND")
	)
	(segment
		(start 1.66624 -393.874244)
		(end 1.668018 -393.876022)
		(width 0.4572)
		(layer "F.Cu")
		(net "GND")
	)
	(segment
		(start 295.649904 -290.199826)
		(end 296.124884 -289.724846)
		(width 0.249936)
		(layer "F.Cu")
		(net "GND")
	)
	(segment
		(start 341.11946 -282.8417)
		(end 340.88705 -283.07411)
		(width 0.2286)
		(layer "F.Cu")
		(net "GND")
	)
	(segment
		(start 68.674742 -304.924714)
		(end 69.149976 -305.399948)
		(width 0.249936)
		(layer "F.Cu")
		(net "GND")
	)
	(segment
		(start 166.033958 -111.44504)
		(end 166.742364 -111.44504)
		(width 0.3556)
		(layer "F.Cu")
		(net "GND")
	)
	(segment
		(start 431.224944 -289.724846)
		(end 430.749964 -290.199826)
		(width 0.249936)
		(layer "F.Cu")
		(net "GND")
	)
	(segment
		(start 303.724818 -301.124874)
		(end 303.249838 -301.599854)
		(width 0.249936)
		(layer "F.Cu")
		(net "GND")
	)
	(segment
		(start 279.499822 -305.399948)
		(end 279.024842 -305.874928)
		(width 0.249936)
		(layer "F.Cu")
		(net "GND")
	)
	(segment
		(start 410.324808 -287.824926)
		(end 410.799788 -288.299906)
		(width 0.249936)
		(layer "F.Cu")
		(net "GND")
	)
	(segment
		(start 417.924996 -297.32478)
		(end 417.450016 -297.79976)
		(width 0.249936)
		(layer "F.Cu")
		(net "GND")
	)
	(segment
		(start 168.150032 -294.94988)
		(end 167.675052 -294.4749)
		(width 0.249936)
		(layer "F.Cu")
		(net "GND")
	)
	(segment
		(start 358.964992 -27.79014)
		(end 357.948992 -27.79014)
		(width 0.3556)
		(layer "F.Cu")
		(net "GND")
	)
	(segment
		(start 404.953978 -382.30302)
		(end 404.262844 -382.30302)
		(width 0.4572)
		(layer "F.Cu")
		(net "GND")
	)
	(segment
		(start 101.979222 -242.080288)
		(end 102.31501 -241.7445)
		(width 0.254)
		(layer "F.Cu")
		(net "GND")
	)
	(segment
		(start 171.474892 -284.974792)
		(end 170.999912 -285.449772)
		(width 0.249936)
		(layer "F.Cu")
		(net "GND")
	)
	(segment
		(start 125.74905 -31.390082)
		(end 126.76505 -31.390082)
		(width 0.3556)
		(layer "F.Cu")
		(net "GND")
	)
	(segment
		(start 239.935512 -235.128054)
		(end 239.935512 -235.737654)
		(width 0.4572)
		(layer "F.Cu")
		(net "GND")
	)
	(segment
		(start 223.16694 -189.781434)
		(end 223.310958 -189.637416)
		(width 0.3048)
		(layer "F.Cu")
		(net "GND")
	)
	(segment
		(start 293.74973 -296.8498)
		(end 294.22471 -297.32478)
		(width 0.249936)
		(layer "F.Cu")
		(net "GND")
	)
	(segment
		(start 447.675762 -123.795028)
		(end 448.331082 -123.795028)
		(width 0.4572)
		(layer "F.Cu")
		(net "GND")
	)
	(segment
		(start 409.374848 -298.27474)
		(end 408.899868 -297.79976)
		(width 0.249936)
		(layer "F.Cu")
		(net "GND")
	)
	(segment
		(start 310.849772 -297.79976)
		(end 310.374792 -297.32478)
		(width 0.249936)
		(layer "F.Cu")
		(net "GND")
	)
	(segment
		(start 167.200072 -301.599854)
		(end 166.725092 -302.074834)
		(width 0.249936)
		(layer "F.Cu")
		(net "GND")
	)
	(segment
		(start 215.545924 -46.693836)
		(end 215.01862 -46.693836)
		(width 0.254)
		(layer "F.Cu")
		(net "GND")
	)
	(segment
		(start 59.649868 -285.449772)
		(end 60.124848 -284.974792)
		(width 0.249936)
		(layer "F.Cu")
		(net "GND")
	)
	(segment
		(start 215.475566 -122.525028)
		(end 216.130886 -122.525028)
		(width 0.4064)
		(layer "F.Cu")
		(net "GND")
	)
	(segment
		(start 158.174944 -296.37482)
		(end 157.699964 -295.89984)
		(width 0.249936)
		(layer "F.Cu")
		(net "GND")
	)
	(segment
		(start 155.800044 -273.099784)
		(end 155.325064 -272.624804)
		(width 0.249936)
		(layer "F.Cu")
		(net "GND")
	)
	(segment
		(start 299.512736 -104.240076)
		(end 300.857412 -104.240076)
		(width 0.3556)
		(layer "F.Cu")
		(net "GND")
	)
	(segment
		(start 40.598344 -252.756924)
		(end 40.598344 -253.45644)
		(width 0.4572)
		(layer "F.Cu")
		(net "GND")
	)
	(segment
		(start 208.348834 -29.589984)
		(end 209.364834 -29.589984)
		(width 0.3556)
		(layer "F.Cu")
		(net "GND")
	)
	(segment
		(start 50.14976 -291.149786)
		(end 49.67478 -290.674806)
		(width 0.249936)
		(layer "F.Cu")
		(net "GND")
	)
	(segment
		(start 230.66756 -215.104218)
		(end 231.067356 -214.704422)
		(width 0.381)
		(layer "F.Cu")
		(net "GND")
	)
	(segment
		(start 419.349936 -302.549814)
		(end 418.874956 -303.024794)
		(width 0.249936)
		(layer "F.Cu")
		(net "GND")
	)
	(segment
		(start 166.725092 -302.074834)
		(end 166.249858 -301.599854)
		(width 0.249936)
		(layer "F.Cu")
		(net "GND")
	)
	(segment
		(start 185.418476 -123.635008)
		(end 184.757314 -123.635008)
		(width 0.3556)
		(layer "F.Cu")
		(net "GND")
	)
	(segment
		(start 300.874684 -306.824888)
		(end 301.349918 -306.349908)
		(width 0.249936)
		(layer "F.Cu")
		(net "GND")
	)
	(segment
		(start 171.474892 -302.074834)
		(end 170.999912 -301.599854)
		(width 0.249936)
		(layer "F.Cu")
		(net "GND")
	)
	(segment
		(start 387.050026 -281.649932)
		(end 386.575046 -281.174952)
		(width 0.249936)
		(layer "F.Cu")
		(net "GND")
	)
	(segment
		(start 165.299898 -307.299868)
		(end 165.774878 -306.824888)
		(width 0.249936)
		(layer "F.Cu")
		(net "GND")
	)
	(segment
		(start 293.27475 -302.074834)
		(end 292.79977 -301.599854)
		(width 0.249936)
		(layer "F.Cu")
		(net "GND")
	)
	(segment
		(start 283.299916 -292.099746)
		(end 283.774896 -291.624766)
		(width 0.249936)
		(layer "F.Cu")
		(net "GND")
	)
	(segment
		(start 308.571646 -81.749646)
		(end 309.153306 -82.331306)
		(width 0.4064)
		(layer "F.Cu")
		(net "GND")
	)
	(segment
		(start 212.0265 -25.832054)
		(end 212.669882 -25.832054)
		(width 0.4572)
		(layer "F.Cu")
		(net "GND")
	)
	(segment
		(start 270.474694 -296.37482)
		(end 270.949928 -295.89984)
		(width 0.249936)
		(layer "F.Cu")
		(net "GND")
	)
	(segment
		(start 210.419442 -244.416326)
		(end 210.419442 -245.041674)
		(width 0.4572)
		(layer "F.Cu")
		(net "GND")
	)
	(segment
		(start 10.664952 -25.990042)
		(end 9.648952 -25.990042)
		(width 0.3556)
		(layer "F.Cu")
		(net "GND")
	)
	(segment
		(start 402.724874 -284.974792)
		(end 403.199854 -284.499812)
		(width 0.249936)
		(layer "F.Cu")
		(net "GND")
	)
	(segment
		(start 15.17396 -127.004064)
		(end 15.15618 -127.021844)
		(width 0.2032)
		(layer "F.Cu")
		(net "GND")
	)
	(segment
		(start 403.199854 -292.099746)
		(end 403.674834 -291.624766)
		(width 0.249936)
		(layer "F.Cu")
		(net "GND")
	)
	(segment
		(start 373.657622 -29.784294)
		(end 373.764556 -29.67736)
		(width 0.4572)
		(layer "F.Cu")
		(net "GND")
	)
	(segment
		(start 68.199762 -290.199826)
		(end 68.674742 -289.724846)
		(width 0.249936)
		(layer "F.Cu")
		(net "GND")
	)
	(segment
		(start 47.29988 -288.299906)
		(end 46.8249 -287.824926)
		(width 0.249936)
		(layer "F.Cu")
		(net "GND")
	)
	(segment
		(start 399.874994 -289.724846)
		(end 399.400014 -290.199826)
		(width 0.249936)
		(layer "F.Cu")
		(net "GND")
	)
	(segment
		(start 153.636472 -31.390082)
		(end 153.888694 -31.642304)
		(width 0.3556)
		(layer "F.Cu")
		(net "GND")
	)
	(segment
		(start 416.974782 -288.774886)
		(end 417.450016 -288.299906)
		(width 0.249936)
		(layer "F.Cu")
		(net "GND")
	)
	(segment
		(start 309.424832 -289.724846)
		(end 308.949852 -289.249866)
		(width 0.249936)
		(layer "F.Cu")
		(net "GND")
	)
	(segment
		(start 279.024842 -300.174914)
		(end 279.499822 -299.699934)
		(width 0.249936)
		(layer "F.Cu")
		(net "GND")
	)
	(segment
		(start 5.100066 -364.193074)
		(end 5.100066 -363.054138)
		(width 0.508)
		(layer "F.Cu")
		(net "GND")
	)
	(segment
		(start 65.349882 -286.399732)
		(end 64.874902 -285.924752)
		(width 0.249936)
		(layer "F.Cu")
		(net "GND")
	)
	(segment
		(start 179.55006 -286.399732)
		(end 179.07508 -285.924752)
		(width 0.249936)
		(layer "F.Cu")
		(net "GND")
	)
	(segment
		(start 196.575172 -64.102234)
		(end 195.86956 -64.102234)
		(width 0.4572)
		(layer "F.Cu")
		(net "GND")
	)
	(segment
		(start 313.699906 -299.699934)
		(end 313.224926 -299.224954)
		(width 0.249936)
		(layer "F.Cu")
		(net "GND")
	)
	(segment
		(start 198.365872 -77.889608)
		(end 198.365872 -77.175106)
		(width 0.4572)
		(layer "F.Cu")
		(net "GND")
	)
	(segment
		(start 288.049716 -306.349908)
		(end 288.524696 -306.824888)
		(width 0.249936)
		(layer "F.Cu")
		(net "GND")
	)
	(segment
		(start 78.64983 -298.74972)
		(end 79.12481 -298.27474)
		(width 0.249936)
		(layer "F.Cu")
		(net "GND")
	)
	(segment
		(start 41.599866 -289.249866)
		(end 41.124886 -289.724846)
		(width 0.254)
		(layer "F.Cu")
		(net "GND")
	)
	(segment
		(start 312.274712 -288.774886)
		(end 311.799732 -289.249866)
		(width 0.249936)
		(layer "F.Cu")
		(net "GND")
	)
	(segment
		(start 408.424888 -289.724846)
		(end 408.899868 -290.199826)
		(width 0.249936)
		(layer "F.Cu")
		(net "GND")
	)
	(segment
		(start 314.174886 -291.624766)
		(end 314.649866 -292.099746)
		(width 0.249936)
		(layer "F.Cu")
		(net "GND")
	)
	(segment
		(start 308.474872 -292.574726)
		(end 308.949852 -293.04996)
		(width 0.249936)
		(layer "F.Cu")
		(net "GND")
	)
	(segment
		(start 308.949852 -302.549814)
		(end 308.474872 -302.074834)
		(width 0.249936)
		(layer "F.Cu")
		(net "GND")
	)
	(segment
		(start 424.09999 -299.699934)
		(end 424.57497 -300.174914)
		(width 0.249936)
		(layer "F.Cu")
		(net "GND")
	)
	(segment
		(start 279.645872 -46.693836)
		(end 279.118568 -46.693836)
		(width 0.254)
		(layer "F.Cu")
		(net "GND")
	)
	(segment
		(start 310.867044 -57.332626)
		(end 310.867044 -56.354218)
		(width 0.4572)
		(layer "F.Cu")
		(net "GND")
	)
	(segment
		(start 195.224908 -298.27474)
		(end 195.699888 -298.74972)
		(width 0.249936)
		(layer "F.Cu")
		(net "GND")
	)
	(segment
		(start 285.674816 -285.924752)
		(end 285.199836 -286.399732)
		(width 0.249936)
		(layer "F.Cu")
		(net "GND")
	)
	(segment
		(start 186.200034 -302.549814)
		(end 186.675014 -302.074834)
		(width 0.249936)
		(layer "F.Cu")
		(net "GND")
	)
	(segment
		(start 125.295152 -59.978036)
		(end 125.295152 -60.633356)
		(width 0.4572)
		(layer "F.Cu")
		(net "GND")
	)
	(segment
		(start 184.77484 -287.824926)
		(end 184.29986 -288.299906)
		(width 0.249936)
		(layer "F.Cu")
		(net "GND")
	)
	(segment
		(start 417.450016 -284.499812)
		(end 417.924996 -284.974792)
		(width 0.249936)
		(layer "F.Cu")
		(net "GND")
	)
	(segment
		(start 399.93316 -137.16508)
		(end 398.94256 -137.16508)
		(width 0.3556)
		(layer "F.Cu")
		(net "GND")
	)
	(segment
		(start 395.12494 -302.074834)
		(end 395.59992 -302.549814)
		(width 0.249936)
		(layer "F.Cu")
		(net "GND")
	)
	(segment
		(start 115.87734 -255.18872)
		(end 115.87734 -255.82372)
		(width 0.381)
		(layer "F.Cu")
		(net "GND")
	)
	(segment
		(start 20.274026 -73.166732)
		(end 20.274026 -73.85177)
		(width 0.4572)
		(layer "F.Cu")
		(net "GND")
	)
	(segment
		(start 221.780862 -202.857862)
		(end 221.8055 -202.8825)
		(width 0.4572)
		(layer "F.Cu")
		(net "GND")
	)
	(segment
		(start 171.949872 -306.349908)
		(end 172.424852 -306.824888)
		(width 0.249936)
		(layer "F.Cu")
		(net "GND")
	)
	(segment
		(start 176.028858 -177.891186)
		(end 176.063402 -177.856642)
		(width 0.3048)
		(layer "F.Cu")
		(net "GND")
	)
	(segment
		(start 416.024822 -284.974792)
		(end 416.499802 -284.499812)
		(width 0.249936)
		(layer "F.Cu")
		(net "GND")
	)
	(segment
		(start 122.634756 -38.937184)
		(end 122.900186 -38.671754)
		(width 0.4572)
		(layer "F.Cu")
		(net "GND")
	)
	(segment
		(start 230.66756 -221.504256)
		(end 231.067356 -221.904052)
		(width 0.381)
		(layer "F.Cu")
		(net "GND")
	)
	(segment
		(start 180.975 -291.624766)
		(end 181.44998 -292.099746)
		(width 0.249936)
		(layer "F.Cu")
		(net "GND")
	)
	(segment
		(start 316.87516 -388.52856)
		(end 316.4586 -388.112)
		(width 0.4572)
		(layer "F.Cu")
		(net "GND")
	)
	(segment
		(start 391.799826 -276.899878)
		(end 391.324846 -276.424898)
		(width 0.249936)
		(layer "F.Cu")
		(net "GND")
	)
	(segment
		(start 171.474892 -294.4749)
		(end 170.999912 -293.99992)
		(width 0.249936)
		(layer "F.Cu")
		(net "GND")
	)
	(segment
		(start 57.694068 -35.499548)
		(end 58.066432 -35.871912)
		(width 0.4572)
		(layer "F.Cu")
		(net "GND")
	)
	(segment
		(start 369.555776 -153.1112)
		(end 369.555776 -153.782522)
		(width 0.4064)
		(layer "F.Cu")
		(net "GND")
	)
	(segment
		(start 248.07164 -210.289902)
		(end 248.07164 -211.276946)
		(width 0.4572)
		(layer "F.Cu")
		(net "GND")
	)
	(segment
		(start 152.94991 -298.749466)
		(end 152.94991 -298.74972)
		(width 0.249936)
		(layer "F.Cu")
		(net "GND")
	)
	(segment
		(start 177.174906 -285.924752)
		(end 177.649886 -286.399732)
		(width 0.249936)
		(layer "F.Cu")
		(net "GND")
	)
	(segment
		(start 79.59979 -296.8498)
		(end 79.12481 -296.37482)
		(width 0.249936)
		(layer "F.Cu")
		(net "GND")
	)
	(segment
		(start 53.474874 -284.024832)
		(end 53.949854 -284.499812)
		(width 0.249936)
		(layer "F.Cu")
		(net "GND")
	)
	(segment
		(start 406.609042 -27.04973)
		(end 405.949912 -27.04973)
		(width 0.4572)
		(layer "F.Cu")
		(net "GND")
	)
	(segment
		(start 61.074808 -305.874928)
		(end 61.549788 -305.399948)
		(width 0.249936)
		(layer "F.Cu")
		(net "GND")
	)
	(segment
		(start 418.874956 -300.174914)
		(end 418.399976 -299.699934)
		(width 0.249936)
		(layer "F.Cu")
		(net "GND")
	)
	(segment
		(start 378.98959 -64.312292)
		(end 379.748034 -64.312292)
		(width 0.4572)
		(layer "F.Cu")
		(net "GND")
	)
	(segment
		(start 415.074862 -305.874928)
		(end 415.549842 -305.399948)
		(width 0.249936)
		(layer "F.Cu")
		(net "GND")
	)
	(segment
		(start 161.15157 -113.245138)
		(end 162.14217 -113.245138)
		(width 0.3556)
		(layer "F.Cu")
		(net "GND")
	)
	(segment
		(start 425.99991 -289.249866)
		(end 425.52493 -289.724846)
		(width 0.249936)
		(layer "F.Cu")
		(net "GND")
	)
	(segment
		(start 305.624738 -294.4749)
		(end 305.149758 -294.94988)
		(width 0.249936)
		(layer "F.Cu")
		(net "GND")
	)
	(segment
		(start 52.049934 -288.299906)
		(end 51.574954 -287.824926)
		(width 0.249936)
		(layer "F.Cu")
		(net "GND")
	)
	(segment
		(start 195.224908 -300.174914)
		(end 195.699888 -300.649894)
		(width 0.249936)
		(layer "F.Cu")
		(net "GND")
	)
	(segment
		(start 288.524696 -285.924752)
		(end 288.049716 -285.449772)
		(width 0.249936)
		(layer "F.Cu")
		(net "GND")
	)
	(segment
		(start 397.064992 -98.845116)
		(end 398.94256 -98.845116)
		(width 0.3556)
		(layer "F.Cu")
		(net "GND")
	)
	(segment
		(start 62.499748 -301.599854)
		(end 62.974982 -302.074834)
		(width 0.249936)
		(layer "F.Cu")
		(net "GND")
	)
	(segment
		(start 405.100028 -284.499812)
		(end 405.575008 -284.974792)
		(width 0.249936)
		(layer "F.Cu")
		(net "GND")
	)
	(segment
		(start 50.624994 -305.874928)
		(end 51.099974 -306.349908)
		(width 0.249936)
		(layer "F.Cu")
		(net "GND")
	)
	(segment
		(start 3.455924 -375.083578)
		(end 5.296408 -375.083578)
		(width 0.381)
		(layer "F.Cu")
		(net "GND")
	)
	(segment
		(start 131.27863 -110.977426)
		(end 131.27863 -110.365032)
		(width 0.4572)
		(layer "F.Cu")
		(net "GND")
	)
	(segment
		(start 80.07477 -302.074834)
		(end 79.59979 -302.549814)
		(width 0.249936)
		(layer "F.Cu")
		(net "GND")
	)
	(segment
		(start 424.09999 -297.79976)
		(end 423.62501 -298.27474)
		(width 0.249936)
		(layer "F.Cu")
		(net "GND")
	)
	(segment
		(start 262.915146 -59.946286)
		(end 262.915146 -60.601606)
		(width 0.4572)
		(layer "F.Cu")
		(net "GND")
	)
	(segment
		(start 174.800006 -284.499812)
		(end 174.325026 -284.974792)
		(width 0.249936)
		(layer "F.Cu")
		(net "GND")
	)
	(segment
		(start 317.957708 -299.4406)
		(end 317.957708 -301.262034)
		(width 0.4572)
		(layer "F.Cu")
		(net "GND")
	)
	(segment
		(start 142.306802 -211.93887)
		(end 142.306802 -210.817206)
		(width 0.2794)
		(layer "F.Cu")
		(net "GND")
	)
	(segment
		(start 303.249838 -289.249866)
		(end 303.724818 -288.774886)
		(width 0.249936)
		(layer "F.Cu")
		(net "GND")
	)
	(segment
		(start 299.924724 -306.824888)
		(end 299.449744 -307.299868)
		(width 0.249936)
		(layer "F.Cu")
		(net "GND")
	)
	(segment
		(start 67.249802 -307.299868)
		(end 66.774822 -306.824888)
		(width 0.249936)
		(layer "F.Cu")
		(net "GND")
	)
	(segment
		(start 54.899814 -297.79976)
		(end 54.424834 -298.27474)
		(width 0.249936)
		(layer "F.Cu")
		(net "GND")
	)
	(segment
		(start 358.343708 -282.021534)
		(end 357.958898 -282.406344)
		(width 0.254)
		(layer "F.Cu")
		(net "GND")
	)
	(segment
		(start 154.37485 -298.27474)
		(end 154.850084 -297.79976)
		(width 0.249936)
		(layer "F.Cu")
		(net "GND")
	)
	(segment
		(start 429.800004 -292.099746)
		(end 429.325024 -291.624766)
		(width 0.249936)
		(layer "F.Cu")
		(net "GND")
	)
	(segment
		(start 422.199816 -295.89984)
		(end 421.724836 -296.37482)
		(width 0.249936)
		(layer "F.Cu")
		(net "GND")
	)
	(segment
		(start 60.599828 -285.449772)
		(end 60.124848 -285.924752)
		(width 0.249936)
		(layer "F.Cu")
		(net "GND")
	)
	(segment
		(start 421.249856 -297.79976)
		(end 421.724836 -297.32478)
		(width 0.249936)
		(layer "F.Cu")
		(net "GND")
	)
	(segment
		(start 300.874684 -286.874966)
		(end 300.399704 -287.349946)
		(width 0.249936)
		(layer "F.Cu")
		(net "GND")
	)
	(segment
		(start 279.974802 -299.224954)
		(end 280.449782 -298.74972)
		(width 0.249936)
		(layer "F.Cu")
		(net "GND")
	)
	(segment
		(start 392.274806 -300.174914)
		(end 391.799826 -299.699934)
		(width 0.249936)
		(layer "F.Cu")
		(net "GND")
	)
	(segment
		(start 399.400014 -288.299906)
		(end 398.925034 -287.824926)
		(width 0.249936)
		(layer "F.Cu")
		(net "GND")
	)
	(segment
		(start 402.12772 -34.732468)
		(end 401.89531 -34.732468)
		(width 0.4572)
		(layer "F.Cu")
		(net "GND")
	)
	(segment
		(start 162.450018 -283.549852)
		(end 161.975038 -283.074872)
		(width 0.249936)
		(layer "F.Cu")
		(net "GND")
	)
	(segment
		(start 123.31319 -137.344404)
		(end 122.65787 -137.344404)
		(width 0.4064)
		(layer "F.Cu")
		(net "GND")
	)
	(segment
		(start 58.224928 -305.874928)
		(end 58.699908 -305.399948)
		(width 0.249936)
		(layer "F.Cu")
		(net "GND")
	)
	(segment
		(start 192.850008 -291.149786)
		(end 192.375028 -290.674806)
		(width 0.249936)
		(layer "F.Cu")
		(net "GND")
	)
	(segment
		(start 423.623994 -27.411934)
		(end 423.623994 -26.319734)
		(width 0.4572)
		(layer "F.Cu")
		(net "GND")
	)
	(segment
		(start 303.249838 -288.299906)
		(end 302.774858 -287.824926)
		(width 0.249936)
		(layer "F.Cu")
		(net "GND")
	)
	(segment
		(start 62.024768 -306.824888)
		(end 62.499748 -307.299868)
		(width 0.249936)
		(layer "F.Cu")
		(net "GND")
	)
	(segment
		(start 398.925034 -302.074834)
		(end 398.4498 -301.599854)
		(width 0.249936)
		(layer "F.Cu")
		(net "GND")
	)
	(segment
		(start 54.899814 -288.299906)
		(end 54.424834 -287.824926)
		(width 0.249936)
		(layer "F.Cu")
		(net "GND")
	)
	(segment
		(start 365.965994 -285.199836)
		(end 365.965994 -284.631384)
		(width 0.2286)
		(layer "F.Cu")
		(net "GND")
	)
	(segment
		(start 60.124848 -300.174914)
		(end 60.599828 -299.699934)
		(width 0.249936)
		(layer "F.Cu")
		(net "GND")
	)
	(segment
		(start 246.596154 -25.990042)
		(end 246.414798 -26.171398)
		(width 0.3556)
		(layer "F.Cu")
		(net "GND")
	)
	(segment
		(start 40.649906 -280.699718)
		(end 40.174926 -280.224738)
		(width 0.249936)
		(layer "F.Cu")
		(net "GND")
	)
	(segment
		(start 163.399978 -293.99992)
		(end 163.874958 -294.4749)
		(width 0.254)
		(layer "F.Cu")
		(net "GND")
	)
	(segment
		(start 63.924942 -305.874928)
		(end 63.449962 -306.349908)
		(width 0.249936)
		(layer "F.Cu")
		(net "GND")
	)
	(segment
		(start 429.325024 -298.27474)
		(end 428.84979 -298.74972)
		(width 0.249936)
		(layer "F.Cu")
		(net "GND")
	)
	(segment
		(start 441.564776 -27.79014)
		(end 440.548776 -27.79014)
		(width 0.3556)
		(layer "F.Cu")
		(net "GND")
	)
	(segment
		(start 394.64996 -291.149786)
		(end 394.17498 -290.674806)
		(width 0.249936)
		(layer "F.Cu")
		(net "GND")
	)
	(segment
		(start 357.368348 -82.914998)
		(end 356.707948 -82.914998)
		(width 0.381)
		(layer "F.Cu")
		(net "GND")
	)
	(segment
		(start 419.349936 -297.79976)
		(end 419.824916 -297.32478)
		(width 0.249936)
		(layer "F.Cu")
		(net "GND")
	)
	(segment
		(start 191.900048 -292.099746)
		(end 192.375028 -292.574726)
		(width 0.249936)
		(layer "F.Cu")
		(net "GND")
	)
	(segment
		(start 126.76505 -33.19018)
		(end 125.74905 -33.19018)
		(width 0.3556)
		(layer "F.Cu")
		(net "GND")
	)
	(segment
		(start 184.77484 -286.874966)
		(end 184.29986 -286.399732)
		(width 0.249936)
		(layer "F.Cu")
		(net "GND")
	)
	(segment
		(start 260.482588 -28.47848)
		(end 260.143244 -28.139136)
		(width 0.254)
		(layer "F.Cu")
		(net "GND")
	)
	(segment
		(start 66.774822 -300.174914)
		(end 67.249802 -299.699934)
		(width 0.249936)
		(layer "F.Cu")
		(net "GND")
	)
	(segment
		(start 282.349702 -302.549814)
		(end 281.874722 -302.074834)
		(width 0.249936)
		(layer "F.Cu")
		(net "GND")
	)
	(segment
		(start 409.374848 -306.824888)
		(end 409.849828 -307.299868)
		(width 0.249936)
		(layer "F.Cu")
		(net "GND")
	)
	(segment
		(start 274.274788 -296.37482)
		(end 273.799808 -295.89984)
		(width 0.249936)
		(layer "F.Cu")
		(net "GND")
	)
	(segment
		(start 131.331208 -126.94666)
		(end 131.256024 -127.021844)
		(width 0.2032)
		(layer "F.Cu")
		(net "GND")
	)
	(segment
		(start 77.357478 -29.784294)
		(end 77.464412 -29.67736)
		(width 0.4572)
		(layer "F.Cu")
		(net "GND")
	)
	(segment
		(start 236.023658 -143.656812)
		(end 236.633258 -143.656812)
		(width 0.4572)
		(layer "F.Cu")
		(net "GND")
	)
	(segment
		(start 292.32479 -306.824888)
		(end 291.84981 -306.349908)
		(width 0.249936)
		(layer "F.Cu")
		(net "GND")
	)
	(segment
		(start 35.518344 -252.756924)
		(end 35.518344 -253.45644)
		(width 0.4572)
		(layer "F.Cu")
		(net "GND")
	)
	(segment
		(start 165.299898 -307.299868)
		(end 165.774878 -307.774848)
		(width 0.249936)
		(layer "F.Cu")
		(net "GND")
	)
	(segment
		(start 52.999894 -295.89984)
		(end 52.524914 -296.37482)
		(width 0.249936)
		(layer "F.Cu")
		(net "GND")
	)
	(segment
		(start 385.149852 -274.049744)
		(end 385.624832 -274.524724)
		(width 0.249936)
		(layer "F.Cu")
		(net "GND")
	)
	(segment
		(start 296.277792 -114.267742)
		(end 296.888154 -114.267742)
		(width 0.4572)
		(layer "F.Cu")
		(net "GND")
	)
	(segment
		(start 411.750002 -286.399732)
		(end 411.275022 -285.924752)
		(width 0.249936)
		(layer "F.Cu")
		(net "GND")
	)
	(segment
		(start 63.924942 -285.924752)
		(end 63.449962 -286.399732)
		(width 0.249936)
		(layer "F.Cu")
		(net "GND")
	)
	(segment
		(start 237.900464 -228.137466)
		(end 237.900464 -228.417374)
		(width 0.4572)
		(layer "F.Cu")
		(net "GND")
	)
	(segment
		(start 190.348108 -118.234968)
		(end 189.357508 -118.234968)
		(width 0.3556)
		(layer "F.Cu")
		(net "GND")
	)
	(segment
		(start 117.927882 -34.732468)
		(end 117.695472 -34.732468)
		(width 0.4572)
		(layer "F.Cu")
		(net "GND")
	)
	(segment
		(start 285.199836 -297.79976)
		(end 284.724856 -298.27474)
		(width 0.249936)
		(layer "F.Cu")
		(net "GND")
	)
	(segment
		(start 300.399704 -288.299906)
		(end 300.874684 -287.824926)
		(width 0.249936)
		(layer "F.Cu")
		(net "GND")
	)
	(segment
		(start 71.524876 -291.624766)
		(end 71.049896 -291.149786)
		(width 0.249936)
		(layer "F.Cu")
		(net "GND")
	)
	(segment
		(start 45.051726 -107.845098)
		(end 46.042326 -107.845098)
		(width 0.3556)
		(layer "F.Cu")
		(net "GND")
	)
	(segment
		(start 1.650746 -35.290506)
		(end 2.300478 -35.290506)
		(width 0.4572)
		(layer "F.Cu")
		(net "GND")
	)
	(segment
		(start 395.59992 -303.499774)
		(end 396.0749 -303.974754)
		(width 0.249936)
		(layer "F.Cu")
		(net "GND")
	)
	(segment
		(start 307.999892 -295.89984)
		(end 308.474872 -296.37482)
		(width 0.249936)
		(layer "F.Cu")
		(net "GND")
	)
	(segment
		(start 389.899906 -281.649932)
		(end 389.424926 -281.174952)
		(width 0.249936)
		(layer "F.Cu")
		(net "GND")
	)
	(segment
		(start 170.999912 -293.99992)
		(end 170.524932 -293.52494)
		(width 0.249936)
		(layer "F.Cu")
		(net "GND")
	)
	(segment
		(start 393.351766 -109.644942)
		(end 394.342366 -109.644942)
		(width 0.3556)
		(layer "F.Cu")
		(net "GND")
	)
	(segment
		(start 418.874956 -299.224954)
		(end 419.349936 -298.74972)
		(width 0.249936)
		(layer "F.Cu")
		(net "GND")
	)
	(segment
		(start 70.099936 -290.199826)
		(end 70.574916 -290.674806)
		(width 0.249936)
		(layer "F.Cu")
		(net "GND")
	)
	(segment
		(start 242.605306 -228.920548)
		(end 242.211098 -229.314756)
		(width 0.4572)
		(layer "F.Cu")
		(net "GND")
	)
	(segment
		(start 43.974766 -300.174914)
		(end 43.499786 -299.699934)
		(width 0.249936)
		(layer "F.Cu")
		(net "GND")
	)
	(segment
		(start 53.474874 -285.924752)
		(end 52.999894 -286.399732)
		(width 0.249936)
		(layer "F.Cu")
		(net "GND")
	)
	(segment
		(start 325.197724 -295.965118)
		(end 325.197724 -295.355518)
		(width 0.4572)
		(layer "F.Cu")
		(net "GND")
	)
	(segment
		(start 229.471474 -136.269222)
		(end 229.471474 -135.659622)
		(width 0.4572)
		(layer "F.Cu")
		(net "GND")
	)
	(segment
		(start 45.39996 -290.199826)
		(end 44.92498 -289.724846)
		(width 0.249936)
		(layer "F.Cu")
		(net "GND")
	)
	(segment
		(start 155.800044 -276.899878)
		(end 155.325064 -276.424898)
		(width 0.249936)
		(layer "F.Cu")
		(net "GND")
	)
	(segment
		(start 303.249838 -301.599854)
		(end 302.774858 -302.074834)
		(width 0.249936)
		(layer "F.Cu")
		(net "GND")
	)
	(segment
		(start 414.599882 -299.699934)
		(end 414.124902 -300.174914)
		(width 0.249936)
		(layer "F.Cu")
		(net "GND")
	)
	(segment
		(start 163.874958 -307.774848)
		(end 163.399978 -308.249828)
		(width 0.249936)
		(layer "F.Cu")
		(net "GND")
	)
	(segment
		(start 406.524968 -305.874928)
		(end 406.999948 -305.399948)
		(width 0.249936)
		(layer "F.Cu")
		(net "GND")
	)
	(segment
		(start 240.682272 -215.04529)
		(end 240.682272 -215.476328)
		(width 0.4572)
		(layer "F.Cu")
		(net "GND")
	)
	(segment
		(start 70.574916 -292.57498)
		(end 70.099936 -293.04996)
		(width 0.249936)
		(layer "F.Cu")
		(net "GND")
	)
	(segment
		(start 52.643786 -43.85691)
		(end 53.315108 -43.85691)
		(width 0.254)
		(layer "F.Cu")
		(net "GND")
	)
	(segment
		(start 313.224926 -292.574726)
		(end 313.699906 -292.099746)
		(width 0.249936)
		(layer "F.Cu")
		(net "GND")
	)
	(segment
		(start 152.764998 -25.990042)
		(end 151.748998 -25.990042)
		(width 0.3556)
		(layer "F.Cu")
		(net "GND")
	)
	(segment
		(start 68.199762 -303.499774)
		(end 67.724782 -303.974754)
		(width 0.249936)
		(layer "F.Cu")
		(net "GND")
	)
	(segment
		(start 368.074956 -48.753014)
		(end 367.368328 -48.753014)
		(width 0.254)
		(layer "F.Cu")
		(net "GND")
	)
	(segment
		(start 188.587634 -25.742392)
		(end 188.587634 -26.360882)
		(width 0.4572)
		(layer "F.Cu")
		(net "GND")
	)
	(segment
		(start 383.94894 -31.390082)
		(end 384.96494 -31.390082)
		(width 0.3556)
		(layer "F.Cu")
		(net "GND")
	)
	(segment
		(start 385.149852 -294.94988)
		(end 384.674872 -294.4749)
		(width 0.249936)
		(layer "F.Cu")
		(net "GND")
	)
	(segment
		(start 282.063444 -113.485676)
		(end 282.303982 -113.245138)
		(width 0.3556)
		(layer "F.Cu")
		(net "GND")
	)
	(segment
		(start 197.366382 -404.513288)
		(end 197.366382 -405.18461)
		(width 0.4572)
		(layer "F.Cu")
		(net "GND")
	)
	(segment
		(start 283.774896 -294.4749)
		(end 283.299916 -293.99992)
		(width 0.249936)
		(layer "F.Cu")
		(net "GND")
	)
	(segment
		(start 198.505318 -112.394492)
		(end 197.86219 -112.394492)
		(width 0.4064)
		(layer "F.Cu")
		(net "GND")
	)
	(segment
		(start 166.0144 -109.644942)
		(end 166.742364 -109.644942)
		(width 0.3556)
		(layer "F.Cu")
		(net "GND")
	)
	(segment
		(start 415.96691 -142.15491)
		(end 416.95751 -142.15491)
		(width 0.3556)
		(layer "F.Cu")
		(net "GND")
	)
	(segment
		(start 260.606286 -252.756924)
		(end 260.606286 -253.45644)
		(width 0.4572)
		(layer "F.Cu")
		(net "GND")
	)
	(segment
		(start 37.744908 -29.589984)
		(end 36.6649 -29.589984)
		(width 0.3556)
		(layer "F.Cu")
		(net "GND")
	)
	(segment
		(start 216.022936 -189.052454)
		(end 215.006936 -189.052454)
		(width 0.4572)
		(layer "F.Cu")
		(net "GND")
	)
	(segment
		(start 166.249858 -293.04996)
		(end 165.774878 -292.574726)
		(width 0.249936)
		(layer "F.Cu")
		(net "GND")
	)
	(segment
		(start 410.799788 -290.199826)
		(end 410.324808 -289.724846)
		(width 0.249936)
		(layer "F.Cu")
		(net "GND")
	)
	(segment
		(start 397.97482 -299.224954)
		(end 398.4498 -298.74972)
		(width 0.249936)
		(layer "F.Cu")
		(net "GND")
	)
	(segment
		(start 358.405684 -282.021534)
		(end 358.343708 -282.021534)
		(width 0.254)
		(layer "F.Cu")
		(net "GND")
	)
	(segment
		(start 197.600062 -303.499774)
		(end 197.125082 -303.974754)
		(width 0.249936)
		(layer "F.Cu")
		(net "GND")
	)
	(segment
		(start 384.96494 -25.990042)
		(end 383.94894 -25.990042)
		(width 0.3556)
		(layer "F.Cu")
		(net "GND")
	)
	(segment
		(start 163.874958 -303.024794)
		(end 164.349938 -302.549814)
		(width 0.249936)
		(layer "F.Cu")
		(net "GND")
	)
	(segment
		(start 426.94987 -298.74972)
		(end 426.47489 -299.224954)
		(width 0.249936)
		(layer "F.Cu")
		(net "GND")
	)
	(segment
		(start 299.866812 -114.635026)
		(end 300.857412 -114.635026)
		(width 0.3556)
		(layer "F.Cu")
		(net "GND")
	)
	(segment
		(start 408.349958 -287.899856)
		(end 408.424888 -287.899856)
		(width 0.249936)
		(layer "F.Cu")
		(net "GND")
	)
	(segment
		(start 102.71506 -367.488978)
		(end 102.10546 -367.488978)
		(width 0.4572)
		(layer "F.Cu")
		(net "GND")
	)
	(segment
		(start 234.825794 -114.93627)
		(end 235.619544 -114.93627)
		(width 0.254)
		(layer "F.Cu")
		(net "GND")
	)
	(segment
		(start 335.64195 -183.007)
		(end 335.026 -183.007)
		(width 0.4572)
		(layer "F.Cu")
		(net "GND")
	)
	(segment
		(start 395.447012 -53.144166)
		(end 395.447012 -52.592224)
		(width 0.254)
		(layer "F.Cu")
		(net "GND")
	)
	(segment
		(start 259.152644 -262.915908)
		(end 259.155692 -262.918956)
		(width 0.254)
		(layer "F.Cu")
		(net "GND")
	)
	(segment
		(start 36.534344 -252.756924)
		(end 36.534344 -253.45644)
		(width 0.4572)
		(layer "F.Cu")
		(net "GND")
	)
	(segment
		(start 260.462522 -34.29762)
		(end 260.027674 -34.732468)
		(width 0.4572)
		(layer "F.Cu")
		(net "GND")
	)
	(segment
		(start 160.996376 -152.96007)
		(end 162.14217 -152.96007)
		(width 0.3556)
		(layer "F.Cu")
		(net "GND")
	)
	(segment
		(start 163.399978 -286.399732)
		(end 162.924998 -285.924752)
		(width 0.249936)
		(layer "F.Cu")
		(net "GND")
	)
	(segment
		(start 432.418998 -59.974734)
		(end 431.768504 -59.974734)
		(width 0.4572)
		(layer "F.Cu")
		(net "GND")
	)
	(segment
		(start 425.52493 -301.124874)
		(end 425.99991 -300.649894)
		(width 0.249936)
		(layer "F.Cu")
		(net "GND")
	)
	(segment
		(start 68.199762 -307.299868)
		(end 67.724782 -307.774848)
		(width 0.249936)
		(layer "F.Cu")
		(net "GND")
	)
	(segment
		(start 39.699946 -278.799798)
		(end 39.224966 -278.324818)
		(width 0.249936)
		(layer "F.Cu")
		(net "GND")
	)
	(segment
		(start 285.674816 -284.974792)
		(end 286.149796 -284.499812)
		(width 0.249936)
		(layer "F.Cu")
		(net "GND")
	)
	(segment
		(start 270.949928 -291.149786)
		(end 270.474948 -290.674806)
		(width 0.249936)
		(layer "F.Cu")
		(net "GND")
	)
	(segment
		(start 366.263936 -184.793128)
		(end 364.888018 -184.793128)
		(width 0.4572)
		(layer "F.Cu")
		(net "GND")
	)
	(segment
		(start 72.487536 -25.742392)
		(end 72.487536 -26.360882)
		(width 0.4572)
		(layer "F.Cu")
		(net "GND")
	)
	(segment
		(start 36.312094 -136.84885)
		(end 36.312094 -136.81456)
		(width 0.4572)
		(layer "F.Cu")
		(net "GND")
	)
	(segment
		(start 268.734286 -252.756924)
		(end 268.734286 -253.45644)
		(width 0.4572)
		(layer "F.Cu")
		(net "GND")
	)
	(segment
		(start 38.749986 -276.899878)
		(end 38.275006 -276.424898)
		(width 0.249936)
		(layer "F.Cu")
		(net "GND")
	)
	(segment
		(start 298.024804 -297.32478)
		(end 298.499784 -297.79976)
		(width 0.249936)
		(layer "F.Cu")
		(net "GND")
	)
	(segment
		(start 125.810264 -123.947428)
		(end 125.154944 -123.947428)
		(width 0.4064)
		(layer "F.Cu")
		(net "GND")
	)
	(segment
		(start 73.424796 -292.574726)
		(end 73.899776 -292.099746)
		(width 0.249936)
		(layer "F.Cu")
		(net "GND")
	)
	(segment
		(start 272.596102 -25.990042)
		(end 272.414746 -26.171398)
		(width 0.3556)
		(layer "F.Cu")
		(net "GND")
	)
	(segment
		(start 46.042326 -152.96007)
		(end 44.896532 -152.96007)
		(width 0.3556)
		(layer "F.Cu")
		(net "GND")
	)
	(segment
		(start 403.199854 -306.349908)
		(end 403.674834 -306.824888)
		(width 0.249936)
		(layer "F.Cu")
		(net "GND")
	)
	(segment
		(start 195.927726 -34.732468)
		(end 195.695316 -34.732468)
		(width 0.4572)
		(layer "F.Cu")
		(net "GND")
	)
	(segment
		(start 61.078364 -381.979678)
		(end 61.57468 -381.483362)
		(width 0.4572)
		(layer "F.Cu")
		(net "GND")
	)
	(segment
		(start 68.199762 -303.499774)
		(end 68.669916 -303.969928)
		(width 0.249936)
		(layer "F.Cu")
		(net "GND")
	)
	(segment
		(start 358.75595 -190.246)
		(end 358.14 -190.246)
		(width 0.4572)
		(layer "F.Cu")
		(net "GND")
	)
	(segment
		(start 125.34519 -111.122968)
		(end 125.34519 -111.735362)
		(width 0.4572)
		(layer "F.Cu")
		(net "GND")
	)
	(segment
		(start 299.449744 -284.499812)
		(end 298.974764 -284.974792)
		(width 0.249936)
		(layer "F.Cu")
		(net "GND")
	)
	(segment
		(start 160.026604 -25.832054)
		(end 160.669986 -25.832054)
		(width 0.4572)
		(layer "F.Cu")
		(net "GND")
	)
	(segment
		(start 93.939106 -309.61076)
		(end 92.635578 -310.914288)
		(width 0.4572)
		(layer "F.Cu")
		(net "GND")
	)
	(segment
		(start 263.894062 -35.499548)
		(end 264.266426 -35.871912)
		(width 0.4572)
		(layer "F.Cu")
		(net "GND")
	)
	(segment
		(start 307.523896 -27.411934)
		(end 307.523896 -26.319734)
		(width 0.4572)
		(layer "F.Cu")
		(net "GND")
	)
	(segment
		(start 415.549842 -286.399732)
		(end 416.024822 -285.924752)
		(width 0.249936)
		(layer "F.Cu")
		(net "GND")
	)
	(segment
		(start 246.153686 -114.747802)
		(end 246.153686 -114.135408)
		(width 0.4572)
		(layer "F.Cu")
		(net "GND")
	)
	(segment
		(start 374.943878 -43.85691)
		(end 375.6152 -43.85691)
		(width 0.254)
		(layer "F.Cu")
		(net "GND")
	)
	(segment
		(start 396.0749 -303.974754)
		(end 396.54988 -303.499774)
		(width 0.249936)
		(layer "F.Cu")
		(net "GND")
	)
	(segment
		(start 133.506464 -283.07411)
		(end 133.19125 -283.07411)
		(width 0.2286)
		(layer "F.Cu")
		(net "GND")
	)
	(segment
		(start 397.02486 -306.824888)
		(end 397.49984 -307.299868)
		(width 0.249936)
		(layer "F.Cu")
		(net "GND")
	)
	(segment
		(start 44.92498 -301.124874)
		(end 45.39996 -301.599854)
		(width 0.249936)
		(layer "F.Cu")
		(net "GND")
	)
	(segment
		(start 178.599846 -303.499774)
		(end 178.124866 -303.974754)
		(width 0.249936)
		(layer "F.Cu")
		(net "GND")
	)
	(segment
		(start 51.63312 -140.765022)
		(end 50.64252 -140.765022)
		(width 0.3556)
		(layer "F.Cu")
		(net "GND")
	)
	(segment
		(start 287.574736 -284.974792)
		(end 287.099756 -285.449772)
		(width 0.249936)
		(layer "F.Cu")
		(net "GND")
	)
	(segment
		(start 289.47491 -297.32478)
		(end 289.94989 -296.8498)
		(width 0.249936)
		(layer "F.Cu")
		(net "GND")
	)
	(segment
		(start 415.96691 -133.044946)
		(end 416.95751 -133.044946)
		(width 0.3556)
		(layer "F.Cu")
		(net "GND")
	)
	(segment
		(start 308.474872 -300.174914)
		(end 308.949852 -300.649894)
		(width 0.249936)
		(layer "F.Cu")
		(net "GND")
	)
	(segment
		(start 70.574916 -301.124874)
		(end 70.099936 -301.599854)
		(width 0.249936)
		(layer "F.Cu")
		(net "GND")
	)
	(segment
		(start 186.200034 -300.649894)
		(end 186.675014 -301.124874)
		(width 0.249936)
		(layer "F.Cu")
		(net "GND")
	)
	(segment
		(start 416.974782 -291.624766)
		(end 417.450016 -292.099746)
		(width 0.249936)
		(layer "F.Cu")
		(net "GND")
	)
	(segment
		(start 411.750002 -285.449772)
		(end 411.275022 -284.974792)
		(width 0.249936)
		(layer "F.Cu")
		(net "GND")
	)
	(segment
		(start 452.967852 -55.083456)
		(end 453.623172 -55.083456)
		(width 0.254)
		(layer "F.Cu")
		(net "GND")
	)
	(segment
		(start 295.649904 -299.699934)
		(end 296.124884 -300.174914)
		(width 0.249936)
		(layer "F.Cu")
		(net "GND")
	)
	(segment
		(start 399.93316 -104.244902)
		(end 398.94256 -104.244902)
		(width 0.3556)
		(layer "F.Cu")
		(net "GND")
	)
	(segment
		(start 235.871512 -235.128054)
		(end 235.871512 -235.737654)
		(width 0.4572)
		(layer "F.Cu")
		(net "GND")
	)
	(segment
		(start 87.194898 -59.978036)
		(end 87.194898 -60.633356)
		(width 0.4572)
		(layer "F.Cu")
		(net "GND")
	)
	(segment
		(start 178.124866 -303.974754)
		(end 177.649886 -303.499774)
		(width 0.249936)
		(layer "F.Cu")
		(net "GND")
	)
	(segment
		(start 281.747468 -122.044206)
		(end 282.058364 -122.355102)
		(width 0.3556)
		(layer "F.Cu")
		(net "GND")
	)
	(segment
		(start 143.9672 -391.6172)
		(end 143.9164 -391.668)
		(width 0.4572)
		(layer "F.Cu")
		(net "GND")
	)
	(segment
		(start 387.050026 -289.249866)
		(end 386.575046 -288.774886)
		(width 0.249936)
		(layer "F.Cu")
		(net "GND")
	)
	(segment
		(start 121.79427 -35.499548)
		(end 122.166634 -35.871912)
		(width 0.4572)
		(layer "F.Cu")
		(net "GND")
	)
	(segment
		(start 415.074862 -307.774848)
		(end 415.549842 -307.299868)
		(width 0.249936)
		(layer "F.Cu")
		(net "GND")
	)
	(segment
		(start 63.536322 -31.390082)
		(end 63.788544 -31.642304)
		(width 0.3556)
		(layer "F.Cu")
		(net "GND")
	)
	(segment
		(start 398.4498 -296.8498)
		(end 397.97482 -297.32478)
		(width 0.249936)
		(layer "F.Cu")
		(net "GND")
	)
	(segment
		(start 290.318952 -59.974734)
		(end 289.668458 -59.974734)
		(width 0.4572)
		(layer "F.Cu")
		(net "GND")
	)
	(segment
		(start 65.824862 -291.624766)
		(end 65.349882 -292.099746)
		(width 0.249936)
		(layer "F.Cu")
		(net "GND")
	)
	(segment
		(start 414.599882 -307.299868)
		(end 414.124902 -307.774848)
		(width 0.249936)
		(layer "F.Cu")
		(net "GND")
	)
	(segment
		(start 403.199854 -283.549852)
		(end 402.724874 -284.024832)
		(width 0.249936)
		(layer "F.Cu")
		(net "GND")
	)
	(segment
		(start 174.325026 -305.874928)
		(end 174.800006 -306.349908)
		(width 0.249936)
		(layer "F.Cu")
		(net "GND")
	)
	(segment
		(start 302.774858 -289.724846)
		(end 302.299878 -290.199826)
		(width 0.249936)
		(layer "F.Cu")
		(net "GND")
	)
	(segment
		(start 284.249876 -306.349908)
		(end 284.724856 -306.824888)
		(width 0.249936)
		(layer "F.Cu")
		(net "GND")
	)
	(segment
		(start 59.649868 -299.699934)
		(end 60.124848 -300.174914)
		(width 0.249936)
		(layer "F.Cu")
		(net "GND")
	)
	(segment
		(start 358.75595 -175.006)
		(end 358.14 -175.006)
		(width 0.4572)
		(layer "F.Cu")
		(net "GND")
	)
	(segment
		(start 387.999986 -299.699934)
		(end 388.949946 -299.699934)
		(width 0.249936)
		(layer "F.Cu")
		(net "GND")
	)
	(segment
		(start 304.65268 -134.845044)
		(end 305.457606 -134.845044)
		(width 0.3556)
		(layer "F.Cu")
		(net "GND")
	)
	(segment
		(start 159.599884 -286.399732)
		(end 159.124904 -286.874712)
		(width 0.249936)
		(layer "F.Cu")
		(net "GND")
	)
	(segment
		(start 300.399704 -298.74972)
		(end 300.874684 -299.224954)
		(width 0.249936)
		(layer "F.Cu")
		(net "GND")
	)
	(segment
		(start 397.97482 -304.924714)
		(end 398.4498 -304.449734)
		(width 0.249936)
		(layer "F.Cu")
		(net "GND")
	)
	(segment
		(start 209.959448 -309.690516)
		(end 208.735676 -310.914288)
		(width 0.4572)
		(layer "F.Cu")
		(net "GND")
	)
	(segment
		(start 393.351766 -135.364982)
		(end 394.342366 -135.364982)
		(width 0.3556)
		(layer "F.Cu")
		(net "GND")
	)
	(segment
		(start 408.424888 -291.624766)
		(end 407.949908 -292.099746)
		(width 0.249936)
		(layer "F.Cu")
		(net "GND")
	)
	(segment
		(start 19.498564 -65.92189)
		(end 19.498564 -65.15989)
		(width 0.4572)
		(layer "F.Cu")
		(net "GND")
	)
	(segment
		(start 169.099992 -293.99992)
		(end 168.625012 -293.52494)
		(width 0.249936)
		(layer "F.Cu")
		(net "GND")
	)
	(segment
		(start 299.924724 -305.874928)
		(end 300.399704 -306.349908)
		(width 0.249936)
		(layer "F.Cu")
		(net "GND")
	)
	(segment
		(start 289.94989 -303.499774)
		(end 289.47491 -303.974754)
		(width 0.249936)
		(layer "F.Cu")
		(net "GND")
	)
	(segment
		(start 397.49984 -299.699934)
		(end 397.97482 -299.224954)
		(width 0.249936)
		(layer "F.Cu")
		(net "GND")
	)
	(segment
		(start 178.599846 -288.299906)
		(end 178.124866 -287.824926)
		(width 0.249936)
		(layer "F.Cu")
		(net "GND")
	)
	(segment
		(start 62.974982 -303.974754)
		(end 63.449962 -303.499774)
		(width 0.249936)
		(layer "F.Cu")
		(net "GND")
	)
	(segment
		(start 279.974802 -303.974754)
		(end 280.449782 -303.499774)
		(width 0.249936)
		(layer "F.Cu")
		(net "GND")
	)
	(segment
		(start 154.666442 -252.756924)
		(end 154.666442 -253.45644)
		(width 0.4572)
		(layer "F.Cu")
		(net "GND")
	)
	(segment
		(start 269.999714 -282.599892)
		(end 269.524734 -282.124912)
		(width 0.249936)
		(layer "F.Cu")
		(net "GND")
	)
	(segment
		(start 191.900048 -292.099746)
		(end 192.375028 -291.624766)
		(width 0.249936)
		(layer "F.Cu")
		(net "GND")
	)
	(segment
		(start 319.76695 -83.058)
		(end 319.76695 -82.31505)
		(width 0.4572)
		(layer "F.Cu")
		(net "GND")
	)
	(segment
		(start 268.906498 -86.235286)
		(end 269.57655 -86.235286)
		(width 0.4572)
		(layer "F.Cu")
		(net "GND")
	)
	(segment
		(start 276.649688 -290.199826)
		(end 276.174708 -289.724846)
		(width 0.249936)
		(layer "F.Cu")
		(net "GND")
	)
	(segment
		(start 47.29988 -305.399948)
		(end 47.29988 -305.399694)
		(width 0.254)
		(layer "F.Cu")
		(net "GND")
	)
	(segment
		(start 286.149796 -307.299868)
		(end 285.674816 -306.824888)
		(width 0.249936)
		(layer "F.Cu")
		(net "GND")
	)
	(segment
		(start 331.09408 -190.094362)
		(end 330.994258 -189.99454)
		(width 0.4572)
		(layer "F.Cu")
		(net "GND")
	)
	(segment
		(start 208.348834 -27.79014)
		(end 209.364834 -27.79014)
		(width 0.3556)
		(layer "F.Cu")
		(net "GND")
	)
	(segment
		(start 404.149814 -296.8498)
		(end 403.674834 -297.32478)
		(width 0.249936)
		(layer "F.Cu")
		(net "GND")
	)
	(segment
		(start 278.074882 -287.824926)
		(end 277.599902 -288.299906)
		(width 0.249936)
		(layer "F.Cu")
		(net "GND")
	)
	(segment
		(start 272.374868 -274.524978)
		(end 272.849848 -274.999958)
		(width 0.249936)
		(layer "F.Cu")
		(net "GND")
	)
	(segment
		(start 178.124866 -302.074834)
		(end 178.599846 -301.599854)
		(width 0.249936)
		(layer "F.Cu")
		(net "GND")
	)
	(segment
		(start 55.849774 -296.8498)
		(end 55.374794 -297.32478)
		(width 0.249936)
		(layer "F.Cu")
		(net "GND")
	)
	(segment
		(start 429.800004 -293.99992)
		(end 429.325024 -294.4749)
		(width 0.249936)
		(layer "F.Cu")
		(net "GND")
	)
	(segment
		(start 405.100028 -285.449772)
		(end 405.575008 -284.974792)
		(width 0.249936)
		(layer "F.Cu")
		(net "GND")
	)
	(segment
		(start 183.3499 -305.399948)
		(end 183.82488 -305.874928)
		(width 0.249936)
		(layer "F.Cu")
		(net "GND")
	)
	(segment
		(start 31.69412 -35.264852)
		(end 31.69412 -35.499548)
		(width 0.4572)
		(layer "F.Cu")
		(net "GND")
	)
	(segment
		(start 241.06378 -347.400118)
		(end 241.82578 -347.400118)
		(width 0.4572)
		(layer "F.Cu")
		(net "GND")
	)
	(segment
		(start 417.924996 -293.52494)
		(end 418.399976 -293.04996)
		(width 0.249936)
		(layer "F.Cu")
		(net "GND")
	)
	(segment
		(start 250.618752 -147.913344)
		(end 250.618752 -147.38604)
		(width 0.254)
		(layer "F.Cu")
		(net "GND")
	)
	(segment
		(start 401.299934 -307.299868)
		(end 401.774914 -307.774848)
		(width 0.249936)
		(layer "F.Cu")
		(net "GND")
	)
	(segment
		(start 252.99543 -92.496386)
		(end 251.97943 -92.496386)
		(width 0.4572)
		(layer "F.Cu")
		(net "GND")
	)
	(segment
		(start 277.251668 -131.76504)
		(end 278.242268 -131.76504)
		(width 0.3556)
		(layer "F.Cu")
		(net "GND")
	)
	(segment
		(start 80.54975 -294.94988)
		(end 81.024984 -294.4749)
		(width 0.249936)
		(layer "F.Cu")
		(net "GND")
	)
	(segment
		(start 288.049716 -306.349908)
		(end 287.574736 -306.824888)
		(width 0.249936)
		(layer "F.Cu")
		(net "GND")
	)
	(segment
		(start 277.599902 -283.549852)
		(end 277.124922 -283.074872)
		(width 0.249936)
		(layer "F.Cu")
		(net "GND")
	)
	(segment
		(start 338.47405 -161.798)
		(end 339.09 -161.798)
		(width 0.4572)
		(layer "F.Cu")
		(net "GND")
	)
	(segment
		(start 206.9592 -225.881184)
		(end 206.9592 -224.923604)
		(width 0.4572)
		(layer "F.Cu")
		(net "GND")
	)
	(segment
		(start 358.405684 -285.488634)
		(end 358.09428 -285.488634)
		(width 0.2286)
		(layer "F.Cu")
		(net "GND")
	)
	(segment
		(start 188.366908 -142.15491)
		(end 189.357508 -142.15491)
		(width 0.3556)
		(layer "F.Cu")
		(net "GND")
	)
	(segment
		(start 412.699962 -288.299906)
		(end 413.174942 -287.824926)
		(width 0.249936)
		(layer "F.Cu")
		(net "GND")
	)
	(segment
		(start 163.874958 -303.024794)
		(end 163.399978 -303.499774)
		(width 0.249936)
		(layer "F.Cu")
		(net "GND")
	)
	(segment
		(start 35.298634 -136.680956)
		(end 35.298634 -136.859264)
		(width 0.4572)
		(layer "F.Cu")
		(net "GND")
	)
	(segment
		(start 211.958936 -189.052454)
		(end 210.942936 -189.052454)
		(width 0.4572)
		(layer "F.Cu")
		(net "GND")
	)
	(segment
		(start 204.804772 -354.967794)
		(end 204.804772 -356.021894)
		(width 0.4572)
		(layer "F.Cu")
		(net "GND")
	)
	(segment
		(start 179.55006 -285.449772)
		(end 179.07508 -285.924752)
		(width 0.249936)
		(layer "F.Cu")
		(net "GND")
	)
	(segment
		(start 176.699926 -306.349908)
		(end 177.174906 -306.824888)
		(width 0.249936)
		(layer "F.Cu")
		(net "GND")
	)
	(segment
		(start 51.574954 -306.824888)
		(end 51.099974 -307.299868)
		(width 0.249936)
		(layer "F.Cu")
		(net "GND")
	)
	(segment
		(start 409.49499 -59.978036)
		(end 409.49499 -60.633356)
		(width 0.4572)
		(layer "F.Cu")
		(net "GND")
	)
	(segment
		(start 302.774858 -288.774886)
		(end 302.299878 -289.249866)
		(width 0.249936)
		(layer "F.Cu")
		(net "GND")
	)
	(segment
		(start 160.549844 -288.299906)
		(end 160.074864 -288.774886)
		(width 0.249936)
		(layer "F.Cu")
		(net "GND")
	)
	(segment
		(start 37.799772 -280.699718)
		(end 37.324792 -280.224738)
		(width 0.249936)
		(layer "F.Cu")
		(net "GND")
	)
	(segment
		(start 191.425068 -298.27474)
		(end 190.950088 -297.79976)
		(width 0.249936)
		(layer "F.Cu")
		(net "GND")
	)
	(segment
		(start 50.14976 -296.8498)
		(end 49.67478 -297.32478)
		(width 0.249936)
		(layer "F.Cu")
		(net "GND")
	)
	(segment
		(start 413.649922 -286.399732)
		(end 413.174942 -285.924752)
		(width 0.249936)
		(layer "F.Cu")
		(net "GND")
	)
	(segment
		(start 168.150032 -290.199826)
		(end 167.675052 -289.724846)
		(width 0.249936)
		(layer "F.Cu")
		(net "GND")
	)
	(segment
		(start 179.07508 -306.824888)
		(end 179.55006 -307.299868)
		(width 0.249936)
		(layer "F.Cu")
		(net "GND")
	)
	(segment
		(start 334.628998 -293.416736)
		(end 334.628998 -292.781736)
		(width 0.4572)
		(layer "F.Cu")
		(net "GND")
	)
	(segment
		(start 64.399922 -306.349908)
		(end 63.924942 -306.824888)
		(width 0.249936)
		(layer "F.Cu")
		(net "GND")
	)
	(segment
		(start 326.813926 -226.000818)
		(end 326.515222 -226.299522)
		(width 0.4572)
		(layer "F.Cu")
		(net "GND")
	)
	(segment
		(start 330.43495 -239.395)
		(end 330.016358 -238.976408)
		(width 0.4572)
		(layer "F.Cu")
		(net "GND")
	)
	(segment
		(start 64.874902 -306.824888)
		(end 64.399922 -306.349908)
		(width 0.249936)
		(layer "F.Cu")
		(net "GND")
	)
	(segment
		(start 241.394488 -121.661428)
		(end 241.268504 -121.535444)
		(width 0.4064)
		(layer "F.Cu")
		(net "GND")
	)
	(segment
		(start 287.099756 -303.499774)
		(end 286.624776 -303.974754)
		(width 0.249936)
		(layer "F.Cu")
		(net "GND")
	)
	(segment
		(start 348.077536 -255.18872)
		(end 348.077536 -255.82372)
		(width 0.381)
		(layer "F.Cu")
		(net "GND")
	)
	(segment
		(start 174.800006 -297.79976)
		(end 174.325026 -298.27474)
		(width 0.249936)
		(layer "F.Cu")
		(net "GND")
	)
	(segment
		(start 163.13277 -118.754906)
		(end 162.14217 -118.754906)
		(width 0.3556)
		(layer "F.Cu")
		(net "GND")
	)
	(segment
		(start 61.549788 -290.199826)
		(end 61.074808 -289.724846)
		(width 0.249936)
		(layer "F.Cu")
		(net "GND")
	)
	(segment
		(start 54.341776 -26.606246)
		(end 54.341776 -25.971246)
		(width 0.4572)
		(layer "F.Cu")
		(net "GND")
	)
	(segment
		(start 457.31303 -110.785656)
		(end 458.10678 -110.785656)
		(width 0.254)
		(layer "F.Cu")
		(net "GND")
	)
	(segment
		(start 456.338178 -305.500024)
		(end 456.338178 -304.827432)
		(width 0.4572)
		(layer "F.Cu")
		(net "GND")
	)
	(segment
		(start 405.100028 -297.79976)
		(end 405.575008 -297.32478)
		(width 0.249936)
		(layer "F.Cu")
		(net "GND")
	)
	(segment
		(start 406.999948 -286.399732)
		(end 406.524968 -285.924752)
		(width 0.249936)
		(layer "F.Cu")
		(net "GND")
	)
	(segment
		(start 301.518574 -123.635008)
		(end 300.857412 -123.635008)
		(width 0.3556)
		(layer "F.Cu")
		(net "GND")
	)
	(segment
		(start 437.889396 -294.727884)
		(end 437.844184 -294.682672)
		(width 0.4572)
		(layer "F.Cu")
		(net "GND")
	)
	(segment
		(start 282.349702 -306.349908)
		(end 282.824936 -305.874928)
		(width 0.249936)
		(layer "F.Cu")
		(net "GND")
	)
	(segment
		(start 406.895046 -104.830372)
		(end 406.279858 -104.830372)
		(width 0.4064)
		(layer "F.Cu")
		(net "GND")
	)
	(segment
		(start 56.799988 -306.349908)
		(end 57.274968 -306.824888)
		(width 0.249936)
		(layer "F.Cu")
		(net "GND")
	)
	(segment
		(start 287.099756 -288.299906)
		(end 286.624776 -287.824926)
		(width 0.249936)
		(layer "F.Cu")
		(net "GND")
	)
	(segment
		(start 299.866812 -151.155146)
		(end 300.857412 -151.155146)
		(width 0.3556)
		(layer "F.Cu")
		(net "GND")
	)
	(segment
		(start 415.96691 -151.155146)
		(end 416.95751 -151.155146)
		(width 0.3556)
		(layer "F.Cu")
		(net "GND")
	)
	(segment
		(start 49.67478 -303.024794)
		(end 50.14976 -302.549814)
		(width 0.249936)
		(layer "F.Cu")
		(net "GND")
	)
	(segment
		(start 294.69969 -299.699934)
		(end 295.174924 -300.174914)
		(width 0.249936)
		(layer "F.Cu")
		(net "GND")
	)
	(segment
		(start 440.548776 -31.390082)
		(end 441.564776 -31.390082)
		(width 0.3556)
		(layer "F.Cu")
		(net "GND")
	)
	(segment
		(start 51.63312 -138.964924)
		(end 50.64252 -138.964924)
		(width 0.3556)
		(layer "F.Cu")
		(net "GND")
	)
	(segment
		(start 283.774896 -306.824888)
		(end 284.249876 -307.299868)
		(width 0.249936)
		(layer "F.Cu")
		(net "GND")
	)
	(segment
		(start 154.299666 -154.327352)
		(end 153.664666 -154.327352)
		(width 0.4064)
		(layer "F.Cu")
		(net "GND")
	)
	(segment
		(start 49.1998 -301.599854)
		(end 49.67478 -301.124874)
		(width 0.249936)
		(layer "F.Cu")
		(net "GND")
	)
	(segment
		(start 13.318998 -34.990024)
		(end 15.264892 -34.990024)
		(width 0.3556)
		(layer "F.Cu")
		(net "GND")
	)
	(segment
		(start 436.964836 -25.990042)
		(end 435.948836 -25.990042)
		(width 0.3556)
		(layer "F.Cu")
		(net "GND")
	)
	(segment
		(start 280.449782 -307.299868)
		(end 279.974802 -307.774848)
		(width 0.249936)
		(layer "F.Cu")
		(net "GND")
	)
	(segment
		(start 421.724836 -303.974754)
		(end 422.199816 -304.449734)
		(width 0.249936)
		(layer "F.Cu")
		(net "GND")
	)
	(segment
		(start 422.548304 -156.554932)
		(end 421.557704 -156.554932)
		(width 0.3556)
		(layer "F.Cu")
		(net "GND")
	)
	(segment
		(start 358.01046 -126.995428)
		(end 357.35514 -126.995428)
		(width 0.4064)
		(layer "F.Cu")
		(net "GND")
	)
	(segment
		(start 74.248264 -152.95499)
		(end 73.257664 -152.95499)
		(width 0.3556)
		(layer "F.Cu")
		(net "GND")
	)
	(segment
		(start 159.599884 -291.149786)
		(end 159.124904 -290.674806)
		(width 0.249936)
		(layer "F.Cu")
		(net "GND")
	)
	(segment
		(start 208.060036 -219.356178)
		(end 207.493616 -219.356178)
		(width 0.254)
		(layer "F.Cu")
		(net "GND")
	)
	(segment
		(start 270.407892 -162.044126)
		(end 270.498316 -161.953702)
		(width 0.4572)
		(layer "F.Cu")
		(net "GND")
	)
	(segment
		(start 173.850046 -306.349908)
		(end 173.375066 -305.874928)
		(width 0.249936)
		(layer "F.Cu")
		(net "GND")
	)
	(segment
		(start 308.949852 -302.549814)
		(end 309.424832 -303.024794)
		(width 0.249936)
		(layer "F.Cu")
		(net "GND")
	)
	(segment
		(start 418.399976 -300.649894)
		(end 417.924996 -300.174914)
		(width 0.249936)
		(layer "F.Cu")
		(net "GND")
	)
	(segment
		(start 392.749786 -299.699934)
		(end 392.274806 -300.174914)
		(width 0.249936)
		(layer "F.Cu")
		(net "GND")
	)
	(segment
		(start 68.199762 -307.299868)
		(end 67.724782 -306.824888)
		(width 0.249936)
		(layer "F.Cu")
		(net "GND")
	)
	(segment
		(start 40.24884 -27.79014)
		(end 41.26484 -27.79014)
		(width 0.3556)
		(layer "F.Cu")
		(net "GND")
	)
	(segment
		(start 248.073164 -210.288378)
		(end 248.07164 -210.289902)
		(width 0.4572)
		(layer "F.Cu")
		(net "GND")
	)
	(segment
		(start 393.7 -296.8498)
		(end 394.17498 -296.37482)
		(width 0.249936)
		(layer "F.Cu")
		(net "GND")
	)
	(segment
		(start 274.749768 -276.899878)
		(end 274.274788 -276.424898)
		(width 0.249936)
		(layer "F.Cu")
		(net "GND")
	)
	(segment
		(start 176.699926 -305.399948)
		(end 176.224946 -305.874928)
		(width 0.249936)
		(layer "F.Cu")
		(net "GND")
	)
	(segment
		(start 402.775166 -64.102234)
		(end 402.069554 -64.102234)
		(width 0.4572)
		(layer "F.Cu")
		(net "GND")
	)
	(segment
		(start 403.674834 -305.874928)
		(end 403.199854 -306.349908)
		(width 0.249936)
		(layer "F.Cu")
		(net "GND")
	)
	(segment
		(start 304.674778 -292.574726)
		(end 305.149758 -293.04996)
		(width 0.249936)
		(layer "F.Cu")
		(net "GND")
	)
	(segment
		(start 180.975 -306.824888)
		(end 181.44998 -307.299868)
		(width 0.249936)
		(layer "F.Cu")
		(net "GND")
	)
	(segment
		(start 166.076122 -106.045)
		(end 166.742364 -106.045)
		(width 0.3556)
		(layer "F.Cu")
		(net "GND")
	)
	(segment
		(start 395.332966 -129.964942)
		(end 394.342366 -129.964942)
		(width 0.3556)
		(layer "F.Cu")
		(net "GND")
	)
	(segment
		(start 21.445982 -46.693836)
		(end 20.918678 -46.693836)
		(width 0.254)
		(layer "F.Cu")
		(net "GND")
	)
	(segment
		(start 275.224748 -273.574764)
		(end 275.699728 -273.099784)
		(width 0.249936)
		(layer "F.Cu")
		(net "GND")
	)
	(segment
		(start 168.625012 -300.174914)
		(end 168.150032 -299.699934)
		(width 0.249936)
		(layer "F.Cu")
		(net "GND")
	)
	(segment
		(start 297.074844 -300.174914)
		(end 296.599864 -299.699934)
		(width 0.249936)
		(layer "F.Cu")
		(net "GND")
	)
	(segment
		(start 386.099812 -284.499812)
		(end 385.624832 -284.024832)
		(width 0.249936)
		(layer "F.Cu")
		(net "GND")
	)
	(segment
		(start 384.96494 -33.19018)
		(end 383.94894 -33.19018)
		(width 0.3556)
		(layer "F.Cu")
		(net "GND")
	)
	(segment
		(start 430.749964 -292.099746)
		(end 431.224944 -291.624766)
		(width 0.249936)
		(layer "F.Cu")
		(net "GND")
	)
	(segment
		(start 431.247296 -37.087048)
		(end 431.882296 -37.087048)
		(width 0.4572)
		(layer "F.Cu")
		(net "GND")
	)
	(segment
		(start 79.827628 -34.732468)
		(end 79.595218 -34.732468)
		(width 0.4572)
		(layer "F.Cu")
		(net "GND")
	)
	(segment
		(start 312.482484 -28.47848)
		(end 312.14314 -28.139136)
		(width 0.254)
		(layer "F.Cu")
		(net "GND")
	)
	(segment
		(start 49.67478 -303.974754)
		(end 50.14976 -303.499774)
		(width 0.249936)
		(layer "F.Cu")
		(net "GND")
	)
	(segment
		(start 416.979862 -303.969928)
		(end 416.499802 -304.449734)
		(width 0.249936)
		(layer "F.Cu")
		(net "GND")
	)
	(segment
		(start 310.849772 -300.649894)
		(end 310.374792 -301.124874)
		(width 0.249936)
		(layer "F.Cu")
		(net "GND")
	)
	(segment
		(start 113.161064 -259.782564)
		(end 112.545114 -259.782564)
		(width 0.381)
		(layer "F.Cu")
		(net "GND")
	)
	(segment
		(start 210.03895 -194.691)
		(end 210.03895 -195.326)
		(width 0.4572)
		(layer "F.Cu")
		(net "GND")
	)
	(segment
		(start 399.874994 -287.824926)
		(end 399.400014 -288.299906)
		(width 0.249936)
		(layer "F.Cu")
		(net "GND")
	)
	(segment
		(start 219.615512 -231.816656)
		(end 219.520262 -231.911906)
		(width 0.4572)
		(layer "F.Cu")
		(net "GND")
	)
	(segment
		(start 440.924696 -115.335304)
		(end 441.321952 -115.335304)
		(width 0.254)
		(layer "F.Cu")
		(net "GND")
	)
	(segment
		(start 413.174942 -298.27474)
		(end 412.699962 -297.79976)
		(width 0.249936)
		(layer "F.Cu")
		(net "GND")
	)
	(segment
		(start 30.373828 -26.606246)
		(end 30.373828 -25.971246)
		(width 0.4572)
		(layer "F.Cu")
		(net "GND")
	)
	(segment
		(start 46.34992 -298.74972)
		(end 45.87494 -299.224954)
		(width 0.249936)
		(layer "F.Cu")
		(net "GND")
	)
	(segment
		(start 357.805482 -284.631384)
		(end 357.598218 -284.42412)
		(width 0.2286)
		(layer "F.Cu")
		(net "GND")
	)
	(segment
		(start 190.348108 -154.755088)
		(end 189.357508 -154.755088)
		(width 0.3556)
		(layer "F.Cu")
		(net "GND")
	)
	(segment
		(start 180.50002 -303.499774)
		(end 180.02504 -303.974754)
		(width 0.249936)
		(layer "F.Cu")
		(net "GND")
	)
	(segment
		(start 7.103364 -59.971686)
		(end 7.103364 -60.627006)
		(width 0.381)
		(layer "F.Cu")
		(net "GND")
	)
	(segment
		(start 104.378252 -223.906588)
		(end 103.946198 -223.906588)
		(width 0.1778)
		(layer "F.Cu")
		(net "GND")
	)
	(segment
		(start 352.720148 -159.465518)
		(end 353.463098 -159.465518)
		(width 0.4572)
		(layer "F.Cu")
		(net "GND")
	)
	(segment
		(start 42.549826 -289.249866)
		(end 42.074846 -288.774886)
		(width 0.249936)
		(layer "F.Cu")
		(net "GND")
	)
	(segment
		(start 280.449782 -289.249866)
		(end 279.974802 -288.774886)
		(width 0.249936)
		(layer "F.Cu")
		(net "GND")
	)
	(segment
		(start 310.867806 -56.353456)
		(end 311.523126 -56.353456)
		(width 0.254)
		(layer "F.Cu")
		(net "GND")
	)
	(segment
		(start 232.517442 -60.600082)
		(end 231.388158 -60.600082)
		(width 0.3556)
		(layer "F.Cu")
		(net "GND")
	)
	(segment
		(start 170.999912 -286.399732)
		(end 171.474892 -285.924752)
		(width 0.249936)
		(layer "F.Cu")
		(net "GND")
	)
	(segment
		(start 232.898188 -274.531328)
		(end 232.854246 -274.487386)
		(width 0.254)
		(layer "F.Cu")
		(net "GND")
	)
	(segment
		(start 320.10604 -386.958332)
		(end 320.863468 -386.958332)
		(width 0.4572)
		(layer "F.Cu")
		(net "GND")
	)
	(segment
		(start 404.149814 -285.449772)
		(end 403.674834 -284.974792)
		(width 0.249936)
		(layer "F.Cu")
		(net "GND")
	)
	(segment
		(start 362.514896 -26.171398)
		(end 362.696252 -25.990042)
		(width 0.3556)
		(layer "F.Cu")
		(net "GND")
	)
	(segment
		(start 112.225328 -159.053022)
		(end 112.40516 -158.87319)
		(width 0.381)
		(layer "F.Cu")
		(net "GND")
	)
	(segment
		(start 386.50799 -156.3624)
		(end 385.87299 -156.3624)
		(width 0.4064)
		(layer "F.Cu")
		(net "GND")
	)
	(segment
		(start 314.649866 -292.099746)
		(end 315.124846 -291.624766)
		(width 0.249936)
		(layer "F.Cu")
		(net "GND")
	)
	(segment
		(start 422.199816 -299.699934)
		(end 421.724836 -299.224954)
		(width 0.249936)
		(layer "F.Cu")
		(net "GND")
	)
	(segment
		(start 457.410058 -308.196742)
		(end 457.52639 -308.196742)
		(width 0.1778)
		(layer "F.Cu")
		(net "GND")
	)
	(segment
		(start 300.874684 -303.024794)
		(end 300.399704 -303.499774)
		(width 0.249936)
		(layer "F.Cu")
		(net "GND")
	)
	(segment
		(start 399.93316 -151.159972)
		(end 398.94256 -151.159972)
		(width 0.3556)
		(layer "F.Cu")
		(net "GND")
	)
	(segment
		(start 185.389266 -131.245102)
		(end 184.757314 -131.245102)
		(width 0.3556)
		(layer "F.Cu")
		(net "GND")
	)
	(segment
		(start 163.24707 -53.144166)
		(end 163.24707 -52.592224)
		(width 0.254)
		(layer "F.Cu")
		(net "GND")
	)
	(segment
		(start 67.249802 -292.099746)
		(end 67.724782 -291.624766)
		(width 0.249936)
		(layer "F.Cu")
		(net "GND")
	)
	(segment
		(start 48.24984 -300.649894)
		(end 48.72482 -300.174914)
		(width 0.249936)
		(layer "F.Cu")
		(net "GND")
	)
	(segment
		(start 186.675014 -291.624766)
		(end 187.149994 -292.099746)
		(width 0.249936)
		(layer "F.Cu")
		(net "GND")
	)
	(segment
		(start 325.382382 -120.041924)
		(end 325.276464 -119.936006)
		(width 0.254)
		(layer "F.Cu")
		(net "GND")
	)
	(segment
		(start 403.199854 -305.399948)
		(end 403.674834 -305.874928)
		(width 0.249936)
		(layer "F.Cu")
		(net "GND")
	)
	(segment
		(start 278.549862 -300.649894)
		(end 278.074882 -300.174914)
		(width 0.249936)
		(layer "F.Cu")
		(net "GND")
	)
	(segment
		(start 178.764946 -33.19018)
		(end 177.748946 -33.19018)
		(width 0.3556)
		(layer "F.Cu")
		(net "GND")
	)
	(segment
		(start 57.7977 -38.937184)
		(end 58.534554 -38.937184)
		(width 0.4572)
		(layer "F.Cu")
		(net "GND")
	)
	(segment
		(start 71.524876 -299.224954)
		(end 71.999856 -298.74972)
		(width 0.249936)
		(layer "F.Cu")
		(net "GND")
	)
	(segment
		(start 307.999892 -290.199826)
		(end 308.474872 -289.724846)
		(width 0.249936)
		(layer "F.Cu")
		(net "GND")
	)
	(segment
		(start 270.949928 -293.99992)
		(end 270.474948 -293.52494)
		(width 0.249936)
		(layer "F.Cu")
		(net "GND")
	)
	(segment
		(start 277.457916 -73.166732)
		(end 277.457916 -73.85177)
		(width 0.4572)
		(layer "F.Cu")
		(net "GND")
	)
	(segment
		(start 312.749692 -298.74972)
		(end 313.224926 -298.27474)
		(width 0.249936)
		(layer "F.Cu")
		(net "GND")
	)
	(segment
		(start 393.798552 -65.92189)
		(end 393.798552 -65.15989)
		(width 0.4572)
		(layer "F.Cu")
		(net "GND")
	)
	(segment
		(start 219.564458 -29.67736)
		(end 219.564458 -29.079952)
		(width 0.4572)
		(layer "F.Cu")
		(net "GND")
	)
	(segment
		(start 204.352144 -112.137444)
		(end 204.352144 -112.860836)
		(width 0.4572)
		(layer "F.Cu")
		(net "GND")
	)
	(segment
		(start 189.524894 -294.4749)
		(end 189.999874 -294.94988)
		(width 0.249936)
		(layer "F.Cu")
		(net "GND")
	)
	(segment
		(start 174.325026 -300.174914)
		(end 174.800006 -299.699934)
		(width 0.249936)
		(layer "F.Cu")
		(net "GND")
	)
	(segment
		(start 154.541728 -161.276284)
		(end 154.805888 -161.276284)
		(width 0.4572)
		(layer "F.Cu")
		(net "GND")
	)
	(segment
		(start 157.699964 -294.94988)
		(end 157.224984 -294.4749)
		(width 0.249936)
		(layer "F.Cu")
		(net "GND")
	)
	(segment
		(start 183.364886 -31.390082)
		(end 182.348886 -31.390082)
		(width 0.3556)
		(layer "F.Cu")
		(net "GND")
	)
	(segment
		(start 414.124902 -306.824888)
		(end 414.599882 -306.349908)
		(width 0.249936)
		(layer "F.Cu")
		(net "GND")
	)
	(segment
		(start 38.749986 -279.749758)
		(end 38.275006 -279.274778)
		(width 0.249936)
		(layer "F.Cu")
		(net "GND")
	)
	(segment
		(start 295.649904 -284.499812)
		(end 296.124884 -284.974792)
		(width 0.249936)
		(layer "F.Cu")
		(net "GND")
	)
	(segment
		(start 209.871056 -118.771924)
		(end 209.282284 -118.771924)
		(width 0.254)
		(layer "F.Cu")
		(net "GND")
	)
	(segment
		(start 69.624956 -284.974792)
		(end 69.149976 -284.499812)
		(width 0.249936)
		(layer "F.Cu")
		(net "GND")
	)
	(segment
		(start 48.24984 -288.299906)
		(end 47.77486 -287.824926)
		(width 0.249936)
		(layer "F.Cu")
		(net "GND")
	)
	(segment
		(start 277.251668 -120.555004)
		(end 278.242268 -120.555004)
		(width 0.3556)
		(layer "F.Cu")
		(net "GND")
	)
	(segment
		(start 273.799808 -278.799798)
		(end 273.324828 -278.324818)
		(width 0.249936)
		(layer "F.Cu")
		(net "GND")
	)
	(segment
		(start 192.850008 -289.249866)
		(end 193.324988 -289.724846)
		(width 0.249936)
		(layer "F.Cu")
		(net "GND")
	)
	(segment
		(start 274.749768 -287.349946)
		(end 274.274788 -286.874966)
		(width 0.249936)
		(layer "F.Cu")
		(net "GND")
	)
	(segment
		(start 395.392148 -104.404922)
		(end 395.232128 -104.244902)
		(width 0.3556)
		(layer "F.Cu")
		(net "GND")
	)
	(segment
		(start 178.124866 -287.824926)
		(end 177.649886 -288.299906)
		(width 0.249936)
		(layer "F.Cu")
		(net "GND")
	)
	(segment
		(start 83.434174 -8.078724)
		(end 84.04987 -8.078724)
		(width 0.4572)
		(layer "F.Cu")
		(net "GND")
	)
	(segment
		(start 67.724782 -306.824888)
		(end 67.249802 -307.299868)
		(width 0.249936)
		(layer "F.Cu")
		(net "GND")
	)
	(segment
		(start 270.949928 -287.349946)
		(end 270.474948 -286.874966)
		(width 0.249936)
		(layer "F.Cu")
		(net "GND")
	)
	(segment
		(start 170.524932 -300.174914)
		(end 170.999912 -299.699934)
		(width 0.249936)
		(layer "F.Cu")
		(net "GND")
	)
	(segment
		(start 412.303214 -203.61402)
		(end 411.498288 -203.61402)
		(width 0.4572)
		(layer "F.Cu")
		(net "GND")
	)
	(segment
		(start 420.567104 -125.435106)
		(end 421.557704 -125.435106)
		(width 0.3556)
		(layer "F.Cu")
		(net "GND")
	)
	(segment
		(start 79.12481 -290.674806)
		(end 78.64983 -290.199826)
		(width 0.249936)
		(layer "F.Cu")
		(net "GND")
	)
	(segment
		(start 180.50002 -299.699934)
		(end 180.975 -300.174914)
		(width 0.249936)
		(layer "F.Cu")
		(net "GND")
	)
	(segment
		(start 27.978608 -33.248092)
		(end 27.332178 -33.248092)
		(width 0.4572)
		(layer "F.Cu")
		(net "GND")
	)
	(segment
		(start 211.485988 -223.675448)
		(end 211.80298 -223.99244)
		(width 0.4572)
		(layer "F.Cu")
		(net "GND")
	)
	(segment
		(start 317.083948 -143.582898)
		(end 315.751972 -142.250922)
		(width 0.4572)
		(layer "F.Cu")
		(net "GND")
	)
	(segment
		(start 77.69987 -294.94988)
		(end 78.17485 -294.4749)
		(width 0.249936)
		(layer "F.Cu")
		(net "GND")
	)
	(segment
		(start 218.398852 -174.04842)
		(end 217.334084 -174.04842)
		(width 0.4572)
		(layer "F.Cu")
		(net "GND")
	)
	(segment
		(start 153.89987 -278.799798)
		(end 153.42489 -278.324818)
		(width 0.249936)
		(layer "F.Cu")
		(net "GND")
	)
	(segment
		(start 277.156672 -411.86481)
		(end 277.156672 -410.930344)
		(width 0.4572)
		(layer "F.Cu")
		(net "GND")
	)
	(segment
		(start 256.770632 -348.674436)
		(end 256.154682 -348.674436)
		(width 0.4572)
		(layer "F.Cu")
		(net "GND")
	)
	(segment
		(start 424.57497 -302.074834)
		(end 424.09999 -301.599854)
		(width 0.249936)
		(layer "F.Cu")
		(net "GND")
	)
	(segment
		(start 62.499748 -286.399732)
		(end 62.974982 -285.924752)
		(width 0.249936)
		(layer "F.Cu")
		(net "GND")
	)
	(segment
		(start 277.599902 -288.299906)
		(end 277.124922 -287.824926)
		(width 0.249936)
		(layer "F.Cu")
		(net "GND")
	)
	(segment
		(start 36.849812 -298.749466)
		(end 37.324538 -298.27474)
		(width 0.254)
		(layer "F.Cu")
		(net "GND")
	)
	(segment
		(start 121.842022 -120.087136)
		(end 122.477022 -120.087136)
		(width 0.4572)
		(layer "F.Cu")
		(net "GND")
	)
	(segment
		(start 99.27844 -6.541516)
		(end 98.85045 -6.113526)
		(width 0.4572)
		(layer "F.Cu")
		(net "GND")
	)
	(segment
		(start 272.374868 -298.27474)
		(end 272.849848 -297.79976)
		(width 0.249936)
		(layer "F.Cu")
		(net "GND")
	)
	(segment
		(start 425.657518 -29.784294)
		(end 425.764452 -29.67736)
		(width 0.4572)
		(layer "F.Cu")
		(net "GND")
	)
	(segment
		(start 424.57497 -298.27474)
		(end 424.09999 -297.79976)
		(width 0.249936)
		(layer "F.Cu")
		(net "GND")
	)
	(segment
		(start 155.82519 -141.029436)
		(end 156.073094 -141.029436)
		(width 0.4572)
		(layer "F.Cu")
		(net "GND")
	)
	(segment
		(start 330.27239 -7.776972)
		(end 329.63739 -7.776972)
		(width 0.381)
		(layer "F.Cu")
		(net "GND")
	)
	(segment
		(start 189.999874 -300.649894)
		(end 189.524894 -301.124874)
		(width 0.249936)
		(layer "F.Cu")
		(net "GND")
	)
	(segment
		(start 105.744772 -92.766896)
		(end 105.744772 -93.447362)
		(width 0.4572)
		(layer "F.Cu")
		(net "GND")
	)
	(segment
		(start 233.839512 -235.128054)
		(end 233.839512 -235.737654)
		(width 0.4572)
		(layer "F.Cu")
		(net "GND")
	)
	(segment
		(start 197.125082 -297.32478)
		(end 197.600062 -297.79976)
		(width 0.249936)
		(layer "F.Cu")
		(net "GND")
	)
	(segment
		(start 413.649922 -306.349908)
		(end 413.174942 -305.874928)
		(width 0.249936)
		(layer "F.Cu")
		(net "GND")
	)
	(segment
		(start 160.074864 -279.274778)
		(end 159.599884 -278.799798)
		(width 0.249936)
		(layer "F.Cu")
		(net "GND")
	)
	(segment
		(start 393.7 -288.299906)
		(end 393.22502 -287.824926)
		(width 0.249936)
		(layer "F.Cu")
		(net "GND")
	)
	(segment
		(start 247.464834 -31.390082)
		(end 248.480834 -31.390082)
		(width 0.3556)
		(layer "F.Cu")
		(net "GND")
	)
	(segment
		(start 185.545476 -143.955008)
		(end 184.757314 -143.955008)
		(width 0.3556)
		(layer "F.Cu")
		(net "GND")
	)
	(segment
		(start 296.124884 -306.824888)
		(end 296.599864 -307.299868)
		(width 0.249936)
		(layer "F.Cu")
		(net "GND")
	)
	(segment
		(start 66.774822 -306.824888)
		(end 66.299842 -307.299868)
		(width 0.249936)
		(layer "F.Cu")
		(net "GND")
	)
	(segment
		(start 395.830552 -65.92189)
		(end 395.830552 -65.15989)
		(width 0.4572)
		(layer "F.Cu")
		(net "GND")
	)
	(segment
		(start 209.84591 -219.202)
		(end 209.84591 -218.257374)
		(width 0.3048)
		(layer "F.Cu")
		(net "GND")
	)
	(segment
		(start 283.833062 -100.64496)
		(end 282.842462 -100.64496)
		(width 0.3556)
		(layer "F.Cu")
		(net "GND")
	)
	(segment
		(start 420.567104 -129.445004)
		(end 421.557704 -129.445004)
		(width 0.3556)
		(layer "F.Cu")
		(net "GND")
	)
	(segment
		(start 168.625012 -285.924752)
		(end 168.150032 -285.449772)
		(width 0.249936)
		(layer "F.Cu")
		(net "GND")
	)
	(segment
		(start 279.499822 -306.349908)
		(end 279.974802 -306.824888)
		(width 0.249936)
		(layer "F.Cu")
		(net "GND")
	)
	(segment
		(start 303.249838 -289.249866)
		(end 302.774858 -289.724846)
		(width 0.249936)
		(layer "F.Cu")
		(net "GND")
	)
	(segment
		(start 247.431306 -126.394718)
		(end 247.431306 -126.94666)
		(width 0.254)
		(layer "F.Cu")
		(net "GND")
	)
	(segment
		(start 94.705678 -245.824248)
		(end 94.034356 -245.824248)
		(width 0.254)
		(layer "F.Cu")
		(net "GND")
	)
	(segment
		(start 39.224966 -298.27474)
		(end 39.699946 -297.79976)
		(width 0.249936)
		(layer "F.Cu")
		(net "GND")
	)
	(segment
		(start 71.049896 -291.149786)
		(end 70.574916 -290.674806)
		(width 0.249936)
		(layer "F.Cu")
		(net "GND")
	)
	(segment
		(start 308.474872 -297.32478)
		(end 307.999892 -297.79976)
		(width 0.249936)
		(layer "F.Cu")
		(net "GND")
	)
	(segment
		(start 157.699964 -293.04996)
		(end 157.224984 -292.57498)
		(width 0.249936)
		(layer "F.Cu")
		(net "GND")
	)
	(segment
		(start 71.774812 -48.753014)
		(end 71.068184 -48.753014)
		(width 0.254)
		(layer "F.Cu")
		(net "GND")
	)
	(segment
		(start 231.46766 -218.30411)
		(end 231.867456 -217.904314)
		(width 0.381)
		(layer "F.Cu")
		(net "GND")
	)
	(segment
		(start 70.574916 -284.024832)
		(end 71.049896 -284.499812)
		(width 0.249936)
		(layer "F.Cu")
		(net "GND")
	)
	(segment
		(start 234.48264 -28.875736)
		(end 234.48264 -28.47848)
		(width 0.254)
		(layer "F.Cu")
		(net "GND")
	)
	(segment
		(start 195.699888 -302.549814)
		(end 196.174868 -302.074834)
		(width 0.249936)
		(layer "F.Cu")
		(net "GND")
	)
	(segment
		(start 80.54975 -289.249866)
		(end 80.07477 -288.774886)
		(width 0.249936)
		(layer "F.Cu")
		(net "GND")
	)
	(segment
		(start 55.374794 -291.624766)
		(end 54.899814 -292.099746)
		(width 0.249936)
		(layer "F.Cu")
		(net "GND")
	)
	(segment
		(start 389.899906 -289.249866)
		(end 390.374886 -289.724846)
		(width 0.254)
		(layer "F.Cu")
		(net "GND")
	)
	(segment
		(start 380.034038 -6.868922)
		(end 380.649734 -6.868922)
		(width 0.4572)
		(layer "F.Cu")
		(net "GND")
	)
	(segment
		(start 97.03435 -47.936658)
		(end 97.370138 -47.60087)
		(width 0.254)
		(layer "F.Cu")
		(net "GND")
	)
	(segment
		(start 47.77486 -303.974754)
		(end 47.29988 -304.449734)
		(width 0.249936)
		(layer "F.Cu")
		(net "GND")
	)
	(segment
		(start 186.675014 -292.57498)
		(end 187.149994 -292.1)
		(width 0.249936)
		(layer "F.Cu")
		(net "GND")
	)
	(segment
		(start 177.649886 -290.199826)
		(end 177.174906 -289.724846)
		(width 0.249936)
		(layer "F.Cu")
		(net "GND")
	)
	(segment
		(start 172.81525 -59.946286)
		(end 172.81525 -60.601606)
		(width 0.4572)
		(layer "F.Cu")
		(net "GND")
	)
	(segment
		(start 302.024034 -130.710432)
		(end 301.489364 -131.245102)
		(width 0.3556)
		(layer "F.Cu")
		(net "GND")
	)
	(segment
		(start 197.125082 -291.624766)
		(end 197.600062 -292.099746)
		(width 0.249936)
		(layer "F.Cu")
		(net "GND")
	)
	(segment
		(start 278.549862 -286.399732)
		(end 278.074882 -285.924752)
		(width 0.249936)
		(layer "F.Cu")
		(net "GND")
	)
	(segment
		(start 278.549862 -306.349908)
		(end 279.024842 -305.874928)
		(width 0.249936)
		(layer "F.Cu")
		(net "GND")
	)
	(segment
		(start 166.249858 -296.8498)
		(end 165.774878 -297.32478)
		(width 0.249936)
		(layer "F.Cu")
		(net "GND")
	)
	(segment
		(start 220.525086 -14.735302)
		(end 220.525086 -14.100302)
		(width 0.381)
		(layer "F.Cu")
		(net "GND")
	)
	(segment
		(start 295.649904 -285.449772)
		(end 296.124884 -284.974792)
		(width 0.249936)
		(layer "F.Cu")
		(net "GND")
	)
	(segment
		(start 41.124886 -299.224954)
		(end 40.649906 -299.699934)
		(width 0.249936)
		(layer "F.Cu")
		(net "GND")
	)
	(segment
		(start 188.366908 -125.435106)
		(end 189.357508 -125.435106)
		(width 0.3556)
		(layer "F.Cu")
		(net "GND")
	)
	(segment
		(start 188.574934 -292.574726)
		(end 188.099954 -293.04996)
		(width 0.249936)
		(layer "F.Cu")
		(net "GND")
	)
	(segment
		(start 428.775114 -64.102234)
		(end 428.069502 -64.102234)
		(width 0.4572)
		(layer "F.Cu")
		(net "GND")
	)
	(segment
		(start 405.100028 -307.299868)
		(end 404.624794 -306.824888)
		(width 0.249936)
		(layer "F.Cu")
		(net "GND")
	)
	(segment
		(start 302.774858 -302.074834)
		(end 303.249838 -302.549814)
		(width 0.249936)
		(layer "F.Cu")
		(net "GND")
	)
	(segment
		(start 182.39994 -307.299868)
		(end 182.87492 -307.774848)
		(width 0.249936)
		(layer "F.Cu")
		(net "GND")
	)
	(segment
		(start 108.946188 -284.631384)
		(end 108.738924 -284.42412)
		(width 0.2286)
		(layer "F.Cu")
		(net "GND")
	)
	(segment
		(start 273.799808 -290.199826)
		(end 273.324828 -289.724846)
		(width 0.249936)
		(layer "F.Cu")
		(net "GND")
	)
	(segment
		(start 71.049896 -303.499774)
		(end 71.524876 -303.974754)
		(width 0.249936)
		(layer "F.Cu")
		(net "GND")
	)
	(segment
		(start 180.02504 -300.174914)
		(end 179.55006 -299.699934)
		(width 0.249936)
		(layer "F.Cu")
		(net "GND")
	)
	(segment
		(start 170.049952 -301.599854)
		(end 170.524932 -302.074834)
		(width 0.249936)
		(layer "F.Cu")
		(net "GND")
	)
	(segment
		(start 272.374868 -293.52494)
		(end 272.849848 -293.99992)
		(width 0.249936)
		(layer "F.Cu")
		(net "GND")
	)
	(segment
		(start 57.274968 -294.4749)
		(end 56.799988 -293.99992)
		(width 0.249936)
		(layer "F.Cu")
		(net "GND")
	)
	(segment
		(start 218.75369 -104.168956)
		(end 218.95308 -104.368346)
		(width 0.254)
		(layer "F.Cu")
		(net "GND")
	)
	(segment
		(start 82.449924 -295.89984)
		(end 82.924904 -296.37482)
		(width 0.249936)
		(layer "F.Cu")
		(net "GND")
	)
	(segment
		(start 43.499786 -301.599854)
		(end 43.974766 -301.124874)
		(width 0.249936)
		(layer "F.Cu")
		(net "GND")
	)
	(segment
		(start 410.964888 -27.79014)
		(end 409.948888 -27.79014)
		(width 0.3556)
		(layer "F.Cu")
		(net "GND")
	)
	(segment
		(start 310.374792 -301.124874)
		(end 309.899812 -300.649894)
		(width 0.249936)
		(layer "F.Cu")
		(net "GND")
	)
	(segment
		(start 154.307794 -161.510218)
		(end 154.541728 -161.276284)
		(width 0.4572)
		(layer "F.Cu")
		(net "GND")
	)
	(segment
		(start 157.699964 -292.099746)
		(end 157.224984 -291.624766)
		(width 0.249936)
		(layer "F.Cu")
		(net "GND")
	)
	(segment
		(start 305.624738 -297.32478)
		(end 306.099718 -297.79976)
		(width 0.249936)
		(layer "F.Cu")
		(net "GND")
	)
	(segment
		(start 458.862176 -306.110386)
		(end 458.567536 -306.405026)
		(width 0.4572)
		(layer "F.Cu")
		(net "GND")
	)
	(segment
		(start 303.249838 -286.399732)
		(end 302.774858 -285.924752)
		(width 0.249936)
		(layer "F.Cu")
		(net "GND")
	)
	(segment
		(start 422.199816 -306.349908)
		(end 421.724836 -305.874928)
		(width 0.249936)
		(layer "F.Cu")
		(net "GND")
	)
	(segment
		(start 415.96691 -154.755088)
		(end 416.95751 -154.755088)
		(width 0.3556)
		(layer "F.Cu")
		(net "GND")
	)
	(segment
		(start 303.249838 -307.299868)
		(end 302.774858 -307.774848)
		(width 0.249936)
		(layer "F.Cu")
		(net "GND")
	)
	(segment
		(start 394.64996 -293.99992)
		(end 394.17498 -293.52494)
		(width 0.249936)
		(layer "F.Cu")
		(net "GND")
	)
	(segment
		(start 257.85953 -108.78947)
		(end 262.228584 -113.158524)
		(width 0.4572)
		(layer "F.Cu")
		(net "GND")
	)
	(segment
		(start 151.398478 -136.680956)
		(end 151.398478 -136.859264)
		(width 0.4572)
		(layer "F.Cu")
		(net "GND")
	)
	(segment
		(start 38.749986 -292.099746)
		(end 38.275006 -291.624766)
		(width 0.249936)
		(layer "F.Cu")
		(net "GND")
	)
	(segment
		(start 271.899888 -290.199826)
		(end 271.424908 -289.724846)
		(width 0.249936)
		(layer "F.Cu")
		(net "GND")
	)
	(segment
		(start 413.174942 -287.824926)
		(end 413.649922 -288.299906)
		(width 0.249936)
		(layer "F.Cu")
		(net "GND")
	)
	(segment
		(start 422.199816 -294.94988)
		(end 421.724836 -294.4749)
		(width 0.249936)
		(layer "F.Cu")
		(net "GND")
	)
	(segment
		(start 161.975038 -300.174914)
		(end 162.450018 -300.649894)
		(width 0.249936)
		(layer "F.Cu")
		(net "GND")
	)
	(segment
		(start 79.59979 -293.04996)
		(end 80.07477 -292.574726)
		(width 0.249936)
		(layer "F.Cu")
		(net "GND")
	)
	(segment
		(start 417.450016 -295.89984)
		(end 417.924996 -296.37482)
		(width 0.249936)
		(layer "F.Cu")
		(net "GND")
	)
	(segment
		(start 197.600062 -301.599854)
		(end 197.125082 -301.124874)
		(width 0.249936)
		(layer "F.Cu")
		(net "GND")
	)
	(segment
		(start 415.074862 -306.824888)
		(end 415.549842 -306.349908)
		(width 0.249936)
		(layer "F.Cu")
		(net "GND")
	)
	(segment
		(start 274.749768 -280.699718)
		(end 274.274788 -280.224738)
		(width 0.249936)
		(layer "F.Cu")
		(net "GND")
	)
	(segment
		(start 424.57497 -299.224954)
		(end 425.04995 -298.74972)
		(width 0.249936)
		(layer "F.Cu")
		(net "GND")
	)
	(segment
		(start 280.924762 -307.774848)
		(end 281.399742 -308.249828)
		(width 0.249936)
		(layer "F.Cu")
		(net "GND")
	)
	(segment
		(start 365.75873 -284.42412)
		(end 365.391446 -284.42412)
		(width 0.2286)
		(layer "F.Cu")
		(net "GND")
	)
	(segment
		(start 41.26484 -29.589984)
		(end 42.28084 -29.589984)
		(width 0.3556)
		(layer "F.Cu")
		(net "GND")
	)
	(segment
		(start 65.824862 -305.874928)
		(end 65.349882 -306.349908)
		(width 0.249936)
		(layer "F.Cu")
		(net "GND")
	)
	(segment
		(start 279.499822 -303.499774)
		(end 279.974802 -303.024794)
		(width 0.249936)
		(layer "F.Cu")
		(net "GND")
	)
	(segment
		(start 196.174868 -294.4749)
		(end 195.699888 -294.94988)
		(width 0.249936)
		(layer "F.Cu")
		(net "GND")
	)
	(segment
		(start 312.749692 -302.549814)
		(end 313.224926 -303.024794)
		(width 0.249936)
		(layer "F.Cu")
		(net "GND")
	)
	(segment
		(start 202.240896 -54.163722)
		(end 202.792838 -54.163722)
		(width 0.254)
		(layer "F.Cu")
		(net "GND")
	)
	(segment
		(start 153.89987 -284.499812)
		(end 153.42489 -284.024832)
		(width 0.249936)
		(layer "F.Cu")
		(net "GND")
	)
	(segment
		(start 82.449924 -293.99992)
		(end 82.924904 -293.52494)
		(width 0.249936)
		(layer "F.Cu")
		(net "GND")
	)
	(segment
		(start 416.024822 -305.874928)
		(end 415.549842 -305.399948)
		(width 0.249936)
		(layer "F.Cu")
		(net "GND")
	)
	(segment
		(start 38.199822 -154.327352)
		(end 37.564822 -154.327352)
		(width 0.4064)
		(layer "F.Cu")
		(net "GND")
	)
	(segment
		(start 170.524932 -291.624766)
		(end 170.999912 -292.099746)
		(width 0.249936)
		(layer "F.Cu")
		(net "GND")
	)
	(segment
		(start 283.299916 -293.99992)
		(end 282.824936 -293.52494)
		(width 0.249936)
		(layer "F.Cu")
		(net "GND")
	)
	(segment
		(start 311.799732 -294.94988)
		(end 311.324752 -294.4749)
		(width 0.249936)
		(layer "F.Cu")
		(net "GND")
	)
	(segment
		(start 233.444288 -97.658428)
		(end 233.444288 -98.295968)
		(width 0.254)
		(layer "F.Cu")
		(net "GND")
	)
	(segment
		(start 418.874956 -289.724846)
		(end 418.399976 -289.249866)
		(width 0.249936)
		(layer "F.Cu")
		(net "GND")
	)
	(segment
		(start 329.234292 -47.936658)
		(end 329.57008 -47.60087)
		(width 0.254)
		(layer "F.Cu")
		(net "GND")
	)
	(segment
		(start 66.299842 -295.89984)
		(end 66.774822 -296.37482)
		(width 0.249936)
		(layer "F.Cu")
		(net "GND")
	)
	(segment
		(start 365.565436 -238.325914)
		(end 366.760252 -238.325914)
		(width 0.3556)
		(layer "F.Cu")
		(net "GND")
	)
	(segment
		(start 28.406344 -252.756924)
		(end 28.406344 -253.45644)
		(width 0.4572)
		(layer "F.Cu")
		(net "GND")
	)
	(segment
		(start 305.149758 -298.74972)
		(end 305.624738 -299.224954)
		(width 0.249936)
		(layer "F.Cu")
		(net "GND")
	)
	(segment
		(start 239.689894 -201.25182)
		(end 240.189004 -200.75271)
		(width 0.4572)
		(layer "F.Cu")
		(net "GND")
	)
	(segment
		(start 184.29986 -306.349908)
		(end 183.82488 -305.874928)
		(width 0.249936)
		(layer "F.Cu")
		(net "GND")
	)
	(segment
		(start 331.575664 -123.795028)
		(end 332.230984 -123.795028)
		(width 0.4572)
		(layer "F.Cu")
		(net "GND")
	)
	(segment
		(start 403.674834 -284.024832)
		(end 404.149814 -284.499812)
		(width 0.249936)
		(layer "F.Cu")
		(net "GND")
	)
	(segment
		(start 393.351766 -113.245138)
		(end 394.342366 -113.245138)
		(width 0.3556)
		(layer "F.Cu")
		(net "GND")
	)
	(segment
		(start 170.999912 -283.549852)
		(end 171.474892 -284.024832)
		(width 0.249936)
		(layer "F.Cu")
		(net "GND")
	)
	(segment
		(start 355.513386 -137.344404)
		(end 354.858066 -137.344404)
		(width 0.4064)
		(layer "F.Cu")
		(net "GND")
	)
	(segment
		(start 414.124902 -284.974792)
		(end 414.599882 -284.499812)
		(width 0.249936)
		(layer "F.Cu")
		(net "GND")
	)
	(segment
		(start 278.074882 -296.37482)
		(end 278.549862 -296.8498)
		(width 0.249936)
		(layer "F.Cu")
		(net "GND")
	)
	(segment
		(start 293.74973 -301.599854)
		(end 293.27475 -302.074834)
		(width 0.249936)
		(layer "F.Cu")
		(net "GND")
	)
	(segment
		(start 241.625882 -280.10104)
		(end 241.016282 -280.10104)
		(width 0.4572)
		(layer "F.Cu")
		(net "GND")
	)
	(segment
		(start 404.149814 -301.599854)
		(end 403.674834 -302.074834)
		(width 0.249936)
		(layer "F.Cu")
		(net "GND")
	)
	(segment
		(start 298.499784 -288.299906)
		(end 298.974764 -287.824926)
		(width 0.249936)
		(layer "F.Cu")
		(net "GND")
	)
	(segment
		(start 48.72482 -309.674768)
		(end 49.1998 -309.199788)
		(width 0.249936)
		(layer "F.Cu")
		(net "GND")
	)
	(segment
		(start 170.999912 -305.399948)
		(end 170.524932 -305.874928)
		(width 0.249936)
		(layer "F.Cu")
		(net "GND")
	)
	(segment
		(start 418.874956 -301.124874)
		(end 419.349936 -300.649894)
		(width 0.249936)
		(layer "F.Cu")
		(net "GND")
	)
	(segment
		(start 420.558468 -116.9035)
		(end 420.558468 -116.69522)
		(width 0.3556)
		(layer "F.Cu")
		(net "GND")
	)
	(segment
		(start 172.900086 -285.449772)
		(end 173.375066 -285.924752)
		(width 0.249936)
		(layer "F.Cu")
		(net "GND")
	)
	(segment
		(start 341.900002 -110.22965)
		(end 342.365838 -110.22965)
		(width 0.254)
		(layer "F.Cu")
		(net "GND")
	)
	(segment
		(start 73.424796 -296.37482)
		(end 73.899776 -295.89984)
		(width 0.249936)
		(layer "F.Cu")
		(net "GND")
	)
	(segment
		(start 224.318068 -319.392554)
		(end 224.318068 -320.02349)
		(width 0.381)
		(layer "F.Cu")
		(net "GND")
	)
	(segment
		(start 260.530086 -338.826856)
		(end 261.454392 -337.90255)
		(width 0.4572)
		(layer "F.Cu")
		(net "GND")
	)
	(segment
		(start 51.63312 -151.159972)
		(end 50.64252 -151.159972)
		(width 0.3556)
		(layer "F.Cu")
		(net "GND")
	)
	(segment
		(start 68.199762 -305.399948)
		(end 68.674742 -304.924714)
		(width 0.249936)
		(layer "F.Cu")
		(net "GND")
	)
	(segment
		(start 37.799772 -294.94988)
		(end 37.324792 -294.4749)
		(width 0.249936)
		(layer "F.Cu")
		(net "GND")
	)
	(segment
		(start 387.525006 -298.27474)
		(end 387.999986 -297.79976)
		(width 0.249936)
		(layer "F.Cu")
		(net "GND")
	)
	(segment
		(start 156.750004 -283.549852)
		(end 156.275024 -283.074872)
		(width 0.249936)
		(layer "F.Cu")
		(net "GND")
	)
	(segment
		(start 225.256344 -184.703212)
		(end 225.256344 -185.363612)
		(width 0.4572)
		(layer "F.Cu")
		(net "GND")
	)
	(segment
		(start 451.657466 -29.784294)
		(end 451.7644 -29.67736)
		(width 0.4572)
		(layer "F.Cu")
		(net "GND")
	)
	(segment
		(start 428.84979 -291.149786)
		(end 428.37481 -290.674806)
		(width 0.249936)
		(layer "F.Cu")
		(net "GND")
	)
	(segment
		(start 285.199836 -299.699934)
		(end 285.674816 -300.174914)
		(width 0.249936)
		(layer "F.Cu")
		(net "GND")
	)
	(segment
		(start 180.135276 -193.58356)
		(end 179.31765 -193.58356)
		(width 0.381)
		(layer "F.Cu")
		(net "GND")
	)
	(segment
		(start 414.599882 -303.499774)
		(end 415.074862 -303.974754)
		(width 0.249936)
		(layer "F.Cu")
		(net "GND")
	)
	(segment
		(start 127.594614 -158.705042)
		(end 127.594614 -159.266382)
		(width 0.254)
		(layer "F.Cu")
		(net "GND")
	)
	(segment
		(start 51.63312 -137.16508)
		(end 50.64252 -137.16508)
		(width 0.3556)
		(layer "F.Cu")
		(net "GND")
	)
	(segment
		(start 167.732964 -125.955044)
		(end 166.742364 -125.955044)
		(width 0.3556)
		(layer "F.Cu")
		(net "GND")
	)
	(segment
		(start 52.049934 -305.399948)
		(end 52.524914 -305.874928)
		(width 0.249936)
		(layer "F.Cu")
		(net "GND")
	)
	(segment
		(start 418.399976 -293.04996)
		(end 417.924996 -292.574726)
		(width 0.249936)
		(layer "F.Cu")
		(net "GND")
	)
	(segment
		(start 425.36237 -23.355554)
		(end 426.012102 -23.355554)
		(width 0.4572)
		(layer "F.Cu")
		(net "GND")
	)
	(segment
		(start 447.675762 -118.467886)
		(end 448.334638 -118.467886)
		(width 0.4572)
		(layer "F.Cu")
		(net "GND")
	)
	(segment
		(start 125.345952 -283.07411)
		(end 125.030738 -283.07411)
		(width 0.2286)
		(layer "F.Cu")
		(net "GND")
	)
	(segment
		(start 163.191952 -104.793034)
		(end 163.191952 -104.404922)
		(width 0.3556)
		(layer "F.Cu")
		(net "GND")
	)
	(segment
		(start 414.124902 -284.974792)
		(end 413.649922 -285.449772)
		(width 0.249936)
		(layer "F.Cu")
		(net "GND")
	)
	(segment
		(start 386.099812 -274.049744)
		(end 385.624832 -273.574764)
		(width 0.249936)
		(layer "F.Cu")
		(net "GND")
	)
	(segment
		(start 402.724874 -303.974754)
		(end 403.199854 -303.499774)
		(width 0.249936)
		(layer "F.Cu")
		(net "GND")
	)
	(segment
		(start 184.29986 -291.149786)
		(end 184.77484 -290.674806)
		(width 0.249936)
		(layer "F.Cu")
		(net "GND")
	)
	(segment
		(start 290.449762 -287.699958)
		(end 290.89985 -288.149792)
		(width 0.249936)
		(layer "F.Cu")
		(net "GND")
	)
	(segment
		(start 338.893912 -212.786976)
		(end 338.494116 -212.38718)
		(width 0.381)
		(layer "F.Cu")
		(net "GND")
	)
	(segment
		(start 296.124884 -285.924752)
		(end 295.649904 -285.449772)
		(width 0.249936)
		(layer "F.Cu")
		(net "GND")
	)
	(segment
		(start 94.705678 -243.792248)
		(end 94.034356 -243.792248)
		(width 0.254)
		(layer "F.Cu")
		(net "GND")
	)
	(segment
		(start 402.249894 -305.399948)
		(end 401.774914 -305.874928)
		(width 0.249936)
		(layer "F.Cu")
		(net "GND")
	)
	(segment
		(start 209.746596 -227.470462)
		(end 209.90179 -227.625656)
		(width 0.4572)
		(layer "F.Cu")
		(net "GND")
	)
	(segment
		(start 276.649688 -296.8498)
		(end 276.174708 -297.32478)
		(width 0.249936)
		(layer "F.Cu")
		(net "GND")
	)
	(segment
		(start 62.927992 -381.483362)
		(end 61.790072 -381.483362)
		(width 0.4572)
		(layer "F.Cu")
		(net "GND")
	)
	(segment
		(start 61.57468 -381.483362)
		(end 61.790072 -381.483362)
		(width 0.4572)
		(layer "F.Cu")
		(net "GND")
	)
	(segment
		(start 406.4 -389.7122)
		(end 405.928068 -389.240268)
		(width 0.4572)
		(layer "F.Cu")
		(net "GND")
	)
	(segment
		(start 124.792994 -54.163722)
		(end 124.868178 -54.238906)
		(width 0.254)
		(layer "F.Cu")
		(net "GND")
	)
	(segment
		(start 306.448206 -123.635008)
		(end 305.457606 -123.635008)
		(width 0.3556)
		(layer "F.Cu")
		(net "GND")
	)
	(segment
		(start 186.200034 -289.249866)
		(end 186.675014 -289.724846)
		(width 0.249936)
		(layer "F.Cu")
		(net "GND")
	)
	(segment
		(start 192.375028 -301.124874)
		(end 191.900048 -301.599854)
		(width 0.249936)
		(layer "F.Cu")
		(net "GND")
	)
	(segment
		(start 281.399742 -285.449772)
		(end 280.924762 -284.974792)
		(width 0.249936)
		(layer "F.Cu")
		(net "GND")
	)
	(segment
		(start 153.845006 -29.589984)
		(end 152.764998 -29.589984)
		(width 0.3556)
		(layer "F.Cu")
		(net "GND")
	)
	(segment
		(start 87.648796 -31.390082)
		(end 88.664796 -31.390082)
		(width 0.3556)
		(layer "F.Cu")
		(net "GND")
	)
	(segment
		(start 184.77992 -303.969928)
		(end 185.250074 -303.499774)
		(width 0.249936)
		(layer "F.Cu")
		(net "GND")
	)
	(segment
		(start 287.099756 -305.399948)
		(end 286.624776 -305.874928)
		(width 0.249936)
		(layer "F.Cu")
		(net "GND")
	)
	(segment
		(start 288.049716 -284.499812)
		(end 288.524696 -284.024832)
		(width 0.249936)
		(layer "F.Cu")
		(net "GND")
	)
	(segment
		(start 187.149994 -304.449734)
		(end 187.624974 -303.974754)
		(width 0.249936)
		(layer "F.Cu")
		(net "GND")
	)
	(segment
		(start 415.96691 -121.83491)
		(end 416.95751 -121.83491)
		(width 0.3556)
		(layer "F.Cu")
		(net "GND")
	)
	(segment
		(start 26.374344 -252.756924)
		(end 26.374344 -253.45644)
		(width 0.4572)
		(layer "F.Cu")
		(net "GND")
	)
	(segment
		(start 130.34899 -33.19018)
		(end 131.36499 -33.19018)
		(width 0.3556)
		(layer "F.Cu")
		(net "GND")
	)
	(segment
		(start 170.049952 -292.099746)
		(end 169.574972 -291.624766)
		(width 0.249936)
		(layer "F.Cu")
		(net "GND")
	)
	(segment
		(start 169.574972 -287.824926)
		(end 170.049952 -288.299906)
		(width 0.249936)
		(layer "F.Cu")
		(net "GND")
	)
	(segment
		(start 178.599846 -286.399732)
		(end 178.124866 -285.924752)
		(width 0.249936)
		(layer "F.Cu")
		(net "GND")
	)
	(segment
		(start 36.849812 -275.949918)
		(end 36.374832 -275.474938)
		(width 0.249936)
		(layer "F.Cu")
		(net "GND")
	)
	(segment
		(start 172.900086 -305.399948)
		(end 172.424852 -305.874928)
		(width 0.249936)
		(layer "F.Cu")
		(net "GND")
	)
	(segment
		(start 396.0749 -299.224954)
		(end 395.59992 -299.699934)
		(width 0.249936)
		(layer "F.Cu")
		(net "GND")
	)
	(segment
		(start 183.766714 -114.635026)
		(end 184.757314 -114.635026)
		(width 0.3556)
		(layer "F.Cu")
		(net "GND")
	)
	(segment
		(start 396.54988 -294.94988)
		(end 396.0749 -294.4749)
		(width 0.249936)
		(layer "F.Cu")
		(net "GND")
	)
	(segment
		(start 292.32479 -285.924752)
		(end 292.79977 -286.399732)
		(width 0.249936)
		(layer "F.Cu")
		(net "GND")
	)
	(segment
		(start 67.264788 -31.390082)
		(end 66.248788 -31.390082)
		(width 0.3556)
		(layer "F.Cu")
		(net "GND")
	)
	(segment
		(start 298.024804 -289.724846)
		(end 298.499784 -290.199826)
		(width 0.249936)
		(layer "F.Cu")
		(net "GND")
	)
	(segment
		(start 1.977644 -375.083578)
		(end 3.455924 -375.083578)
		(width 0.381)
		(layer "F.Cu")
		(net "GND")
	)
	(segment
		(start 398.163542 -113.485676)
		(end 398.40408 -113.245138)
		(width 0.3556)
		(layer "F.Cu")
		(net "GND")
	)
	(segment
		(start 337.693 -242.807998)
		(end 337.693 -243.571522)
		(width 0.3556)
		(layer "F.Cu")
		(net "GND")
	)
	(segment
		(start 269.049754 -278.799798)
		(end 268.574774 -278.324818)
		(width 0.249936)
		(layer "F.Cu")
		(net "GND")
	)
	(segment
		(start 155.652724 -140.85697)
		(end 155.82519 -141.029436)
		(width 0.4572)
		(layer "F.Cu")
		(net "GND")
	)
	(segment
		(start 70.846696 -38.49116)
		(end 70.141084 -38.49116)
		(width 0.4572)
		(layer "F.Cu")
		(net "GND")
	)
	(segment
		(start 123.609608 -172.844968)
		(end 123.266962 -173.187614)
		(width 0.4572)
		(layer "F.Cu")
		(net "GND")
	)
	(segment
		(start 296.599864 -303.499774)
		(end 297.074844 -303.974754)
		(width 0.249936)
		(layer "F.Cu")
		(net "GND")
	)
	(segment
		(start 213.130638 -237.687866)
		(end 213.130638 -238.66602)
		(width 0.4572)
		(layer "F.Cu")
		(net "GND")
	)
	(segment
		(start 162.924998 -305.874928)
		(end 162.450018 -306.349908)
		(width 0.249936)
		(layer "F.Cu")
		(net "GND")
	)
	(segment
		(start 419.7985 -65.92189)
		(end 419.7985 -65.15989)
		(width 0.4572)
		(layer "F.Cu")
		(net "GND")
	)
	(segment
		(start 50.14976 -285.449772)
		(end 49.67478 -284.974792)
		(width 0.249936)
		(layer "F.Cu")
		(net "GND")
	)
	(segment
		(start 169.099992 -292.099746)
		(end 168.625012 -291.624766)
		(width 0.249936)
		(layer "F.Cu")
		(net "GND")
	)
	(segment
		(start 81.024984 -303.024794)
		(end 81.499964 -303.499774)
		(width 0.249936)
		(layer "F.Cu")
		(net "GND")
	)
	(segment
		(start 416.499802 -306.349908)
		(end 416.974782 -305.874928)
		(width 0.249936)
		(layer "F.Cu")
		(net "GND")
	)
	(segment
		(start 288.049716 -288.299906)
		(end 287.574736 -287.824926)
		(width 0.249936)
		(layer "F.Cu")
		(net "GND")
	)
	(segment
		(start 43.926506 -25.832054)
		(end 44.569888 -25.832054)
		(width 0.4572)
		(layer "F.Cu")
		(net "GND")
	)
	(segment
		(start 398.989296 -176.478438)
		(end 398.989296 -175.855376)
		(width 0.381)
		(layer "F.Cu")
		(net "GND")
	)
	(segment
		(start 67.66687 -121.83491)
		(end 68.65747 -121.83491)
		(width 0.3556)
		(layer "F.Cu")
		(net "GND")
	)
	(segment
		(start 207.023208 -87.614252)
		(end 206.712058 -87.303102)
		(width 0.4572)
		(layer "F.Cu")
		(net "GND")
	)
	(segment
		(start 297.074844 -302.074834)
		(end 296.599864 -301.599854)
		(width 0.249936)
		(layer "F.Cu")
		(net "GND")
	)
	(segment
		(start 11.49477 -158.705042)
		(end 11.49477 -159.266382)
		(width 0.254)
		(layer "F.Cu")
		(net "GND")
	)
	(segment
		(start 280.924762 -298.27474)
		(end 280.449782 -298.74972)
		(width 0.249936)
		(layer "F.Cu")
		(net "GND")
	)
	(segment
		(start 179.07508 -296.37482)
		(end 178.599846 -295.89984)
		(width 0.249936)
		(layer "F.Cu")
		(net "GND")
	)
	(segment
		(start 292.331648 -82.333592)
		(end 291.023294 -82.333592)
		(width 0.4572)
		(layer "F.Cu")
		(net "GND")
	)
	(segment
		(start 229.867714 -217.504264)
		(end 230.26751 -217.104468)
		(width 0.381)
		(layer "F.Cu")
		(net "GND")
	)
	(segment
		(start 47.29988 -287.349946)
		(end 46.8249 -286.874966)
		(width 0.249936)
		(layer "F.Cu")
		(net "GND")
	)
	(segment
		(start 173.850046 -284.499812)
		(end 174.325026 -284.974792)
		(width 0.249936)
		(layer "F.Cu")
		(net "GND")
	)
	(segment
		(start 104.643682 -43.85691)
		(end 105.315004 -43.85691)
		(width 0.254)
		(layer "F.Cu")
		(net "GND")
	)
	(segment
		(start 12.016994 -31.390082)
		(end 12.505944 -30.901132)
		(width 0.3556)
		(layer "F.Cu")
		(net "GND")
	)
	(segment
		(start 326.186292 -309.563516)
		(end 324.83552 -310.914288)
		(width 0.4572)
		(layer "F.Cu")
		(net "GND")
	)
	(segment
		(start 306.099718 -300.649894)
		(end 306.574698 -300.174914)
		(width 0.249936)
		(layer "F.Cu")
		(net "GND")
	)
	(segment
		(start 413.29737 -183.828944)
		(end 413.29737 -184.248298)
		(width 0.4572)
		(layer "F.Cu")
		(net "GND")
	)
	(segment
		(start 313.699906 -292.099746)
		(end 314.174886 -291.624766)
		(width 0.249936)
		(layer "F.Cu")
		(net "GND")
	)
	(segment
		(start 242.169188 -308.168548)
		(end 242.809014 -308.168548)
		(width 0.1778)
		(layer "F.Cu")
		(net "GND")
	)
	(segment
		(start 247.741186 -114.695478)
		(end 247.741186 -114.436652)
		(width 0.254)
		(layer "F.Cu")
		(net "GND")
	)
	(segment
		(start 291.84981 -294.94988)
		(end 292.32479 -294.4749)
		(width 0.249936)
		(layer "F.Cu")
		(net "GND")
	)
	(segment
		(start 190.474854 -294.4749)
		(end 189.999874 -293.99992)
		(width 0.249936)
		(layer "F.Cu")
		(net "GND")
	)
	(segment
		(start 122.900186 -38.671754)
		(end 122.900186 -38.315138)
		(width 0.4572)
		(layer "F.Cu")
		(net "GND")
	)
	(segment
		(start 250.618752 -147.38604)
		(end 250.419362 -147.18665)
		(width 0.254)
		(layer "F.Cu")
		(net "GND")
	)
	(segment
		(start 268.864842 -25.990042)
		(end 267.848842 -25.990042)
		(width 0.3556)
		(layer "F.Cu")
		(net "GND")
	)
	(segment
		(start 301.88408 -124.31649)
		(end 301.88408 -124.000514)
		(width 0.3556)
		(layer "F.Cu")
		(net "GND")
	)
	(segment
		(start 168.625012 -305.874928)
		(end 169.099992 -306.349908)
		(width 0.249936)
		(layer "F.Cu")
		(net "GND")
	)
	(segment
		(start 285.674816 -297.32478)
		(end 286.149796 -296.8498)
		(width 0.249936)
		(layer "F.Cu")
		(net "GND")
	)
	(segment
		(start 240.189004 -200.75271)
		(end 240.189004 -200.599294)
		(width 0.4572)
		(layer "F.Cu")
		(net "GND")
	)
	(segment
		(start 305.64582 -46.693836)
		(end 305.118516 -46.693836)
		(width 0.254)
		(layer "F.Cu")
		(net "GND")
	)
	(segment
		(start 285.674816 -291.624766)
		(end 286.149796 -292.099746)
		(width 0.249936)
		(layer "F.Cu")
		(net "GND")
	)
	(segment
		(start 427.89983 -293.04996)
		(end 428.37481 -292.574726)
		(width 0.249936)
		(layer "F.Cu")
		(net "GND")
	)
	(segment
		(start 297.549824 -303.499774)
		(end 298.024804 -303.974754)
		(width 0.249936)
		(layer "F.Cu")
		(net "GND")
	)
	(segment
		(start 32.489394 -62.812168)
		(end 33.299908 -62.812168)
		(width 0.4572)
		(layer "F.Cu")
		(net "GND")
	)
	(segment
		(start 402.724874 -284.974792)
		(end 402.249894 -285.449772)
		(width 0.249936)
		(layer "F.Cu")
		(net "GND")
	)
	(segment
		(start 50.10404 -113.245138)
		(end 50.64252 -113.245138)
		(width 0.3556)
		(layer "F.Cu")
		(net "GND")
	)
	(segment
		(start 51.63312 -122.355102)
		(end 50.64252 -122.355102)
		(width 0.3556)
		(layer "F.Cu")
		(net "GND")
	)
	(segment
		(start 269.999714 -273.099784)
		(end 270.474694 -273.574764)
		(width 0.249936)
		(layer "F.Cu")
		(net "GND")
	)
	(segment
		(start 164.349938 -307.299868)
		(end 164.824918 -306.824888)
		(width 0.249936)
		(layer "F.Cu")
		(net "GND")
	)
	(segment
		(start 296.124884 -300.174914)
		(end 296.599864 -299.699934)
		(width 0.249936)
		(layer "F.Cu")
		(net "GND")
	)
	(segment
		(start 416.580828 -34.990024)
		(end 415.564828 -34.990024)
		(width 0.3556)
		(layer "F.Cu")
		(net "GND")
	)
	(segment
		(start 273.324828 -299.224954)
		(end 272.849848 -299.699934)
		(width 0.249936)
		(layer "F.Cu")
		(net "GND")
	)
	(segment
		(start 261.460742 -311.442608)
		(end 261.460234 -311.442608)
		(width 0.4572)
		(layer "F.Cu")
		(net "GND")
	)
	(segment
		(start 263.654286 -252.756924)
		(end 263.654286 -253.45644)
		(width 0.4572)
		(layer "F.Cu")
		(net "GND")
	)
	(segment
		(start 256.765044 -346.337382)
		(end 256.111248 -346.337382)
		(width 0.4572)
		(layer "F.Cu")
		(net "GND")
	)
	(segment
		(start 202.430888 -354.229162)
		(end 202.888088 -354.229162)
		(width 0.4572)
		(layer "F.Cu")
		(net "GND")
	)
	(segment
		(start 402.724874 -302.074834)
		(end 402.249894 -301.599854)
		(width 0.249936)
		(layer "F.Cu")
		(net "GND")
	)
	(segment
		(start 183.82488 -285.924752)
		(end 184.29986 -285.449772)
		(width 0.249936)
		(layer "F.Cu")
		(net "GND")
	)
	(segment
		(start 385.855464 -231.70896)
		(end 385.855464 -232.836212)
		(width 0.2794)
		(layer "F.Cu")
		(net "GND")
	)
	(segment
		(start 300.874684 -287.824926)
		(end 301.349918 -288.299906)
		(width 0.249936)
		(layer "F.Cu")
		(net "GND")
	)
	(segment
		(start 420.299896 -302.549814)
		(end 420.774876 -303.024794)
		(width 0.249936)
		(layer "F.Cu")
		(net "GND")
	)
	(segment
		(start 412.044896 -29.589984)
		(end 410.964888 -29.589984)
		(width 0.3556)
		(layer "F.Cu")
		(net "GND")
	)
	(segment
		(start 354.609146 -27.04973)
		(end 353.950016 -27.04973)
		(width 0.4572)
		(layer "F.Cu")
		(net "GND")
	)
	(segment
		(start 298.44873 -29.589984)
		(end 299.46473 -29.589984)
		(width 0.3556)
		(layer "F.Cu")
		(net "GND")
	)
	(segment
		(start 175.749966 -285.449772)
		(end 176.224946 -284.974792)
		(width 0.249936)
		(layer "F.Cu")
		(net "GND")
	)
	(segment
		(start 394.64996 -285.449772)
		(end 394.17498 -284.974792)
		(width 0.249936)
		(layer "F.Cu")
		(net "GND")
	)
	(segment
		(start 168.150032 -296.8498)
		(end 167.675052 -297.32478)
		(width 0.249936)
		(layer "F.Cu")
		(net "GND")
	)
	(segment
		(start 424.457622 -81.749646)
		(end 424.671744 -81.749646)
		(width 0.4064)
		(layer "F.Cu")
		(net "GND")
	)
	(segment
		(start 229.867714 -220.704156)
		(end 230.26751 -221.103952)
		(width 0.381)
		(layer "F.Cu")
		(net "GND")
	)
	(segment
		(start 389.56488 -31.390082)
		(end 388.54888 -31.390082)
		(width 0.3556)
		(layer "F.Cu")
		(net "GND")
	)
	(segment
		(start 274.749768 -281.649932)
		(end 274.274788 -281.174952)
		(width 0.249936)
		(layer "F.Cu")
		(net "GND")
	)
	(segment
		(start 400.824954 -300.174914)
		(end 401.299934 -299.699934)
		(width 0.249936)
		(layer "F.Cu")
		(net "GND")
	)
	(segment
		(start 55.849774 -306.349908)
		(end 55.374794 -305.874928)
		(width 0.249936)
		(layer "F.Cu")
		(net "GND")
	)
	(segment
		(start 179.07508 -306.824888)
		(end 178.599846 -306.349908)
		(width 0.249936)
		(layer "F.Cu")
		(net "GND")
	)
	(segment
		(start 180.50002 -299.699934)
		(end 180.02504 -300.174914)
		(width 0.249936)
		(layer "F.Cu")
		(net "GND")
	)
	(segment
		(start 62.499748 -292.099746)
		(end 62.974982 -291.624766)
		(width 0.249936)
		(layer "F.Cu")
		(net "GND")
	)
	(segment
		(start 394.64996 -289.249866)
		(end 394.17498 -288.774886)
		(width 0.249936)
		(layer "F.Cu")
		(net "GND")
	)
	(segment
		(start 276.649688 -294.94988)
		(end 276.174708 -294.4749)
		(width 0.249936)
		(layer "F.Cu")
		(net "GND")
	)
	(segment
		(start 293.27475 -305.874928)
		(end 293.74973 -306.349908)
		(width 0.249936)
		(layer "F.Cu")
		(net "GND")
	)
	(segment
		(start 108.506514 -389.910828)
		(end 108.253784 -389.658098)
		(width 0.4572)
		(layer "F.Cu")
		(net "GND")
	)
	(segment
		(start 325.265542 -303.636426)
		(end 325.265542 -303.026826)
		(width 0.4572)
		(layer "F.Cu")
		(net "GND")
	)
	(segment
		(start 399.874994 -300.174914)
		(end 400.349974 -299.699934)
		(width 0.249936)
		(layer "F.Cu")
		(net "GND")
	)
	(segment
		(start 171.474892 -291.624766)
		(end 171.949872 -292.099746)
		(width 0.249936)
		(layer "F.Cu")
		(net "GND")
	)
	(segment
		(start 238.7346 -38.937184)
		(end 239.00003 -38.671754)
		(width 0.4572)
		(layer "F.Cu")
		(net "GND")
	)
	(segment
		(start 285.86049 -16.439388)
		(end 285.93669 -16.363188)
		(width 0.4572)
		(layer "F.Cu")
		(net "GND")
	)
	(segment
		(start 167.732964 -109.644942)
		(end 166.742364 -109.644942)
		(width 0.3556)
		(layer "F.Cu")
		(net "GND")
	)
	(segment
		(start 299.866812 -133.044946)
		(end 300.857412 -133.044946)
		(width 0.3556)
		(layer "F.Cu")
		(net "GND")
	)
	(segment
		(start 283.774896 -300.174914)
		(end 284.249876 -299.699934)
		(width 0.249936)
		(layer "F.Cu")
		(net "GND")
	)
	(segment
		(start 184.77484 -303.024794)
		(end 184.29986 -303.499774)
		(width 0.249936)
		(layer "F.Cu")
		(net "GND")
	)
	(segment
		(start 109.57433 -112.785652)
		(end 109.01299 -112.785652)
		(width 0.254)
		(layer "F.Cu")
		(net "GND")
	)
	(segment
		(start 172.900086 -307.299868)
		(end 172.424852 -306.824888)
		(width 0.249936)
		(layer "F.Cu")
		(net "GND")
	)
	(segment
		(start 247.464834 -29.589984)
		(end 246.448834 -29.589984)
		(width 0.3556)
		(layer "F.Cu")
		(net "GND")
	)
	(segment
		(start 266.892786 -54.163722)
		(end 266.96797 -54.238906)
		(width 0.254)
		(layer "F.Cu")
		(net "GND")
	)
	(segment
		(start 169.099992 -286.399732)
		(end 169.574972 -285.924752)
		(width 0.249936)
		(layer "F.Cu")
		(net "GND")
	)
	(segment
		(start 125.758702 -282.406344)
		(end 125.578362 -282.8417)
		(width 0.2286)
		(layer "F.Cu")
		(net "GND")
	)
	(segment
		(start 162.450018 -297.79976)
		(end 161.975038 -297.32478)
		(width 0.249936)
		(layer "F.Cu")
		(net "GND")
	)
	(segment
		(start 258.86791 -55.083456)
		(end 259.52323 -55.083456)
		(width 0.254)
		(layer "F.Cu")
		(net "GND")
	)
	(segment
		(start 344.49385 -218.387168)
		(end 344.893646 -217.987372)
		(width 0.381)
		(layer "F.Cu")
		(net "GND")
	)
	(segment
		(start 300.874684 -298.27474)
		(end 301.349918 -297.79976)
		(width 0.249936)
		(layer "F.Cu")
		(net "GND")
	)
	(segment
		(start 74.374756 -300.174914)
		(end 73.899776 -300.649894)
		(width 0.249936)
		(layer "F.Cu")
		(net "GND")
	)
	(segment
		(start 300.399704 -306.349908)
		(end 300.874684 -306.824888)
		(width 0.249936)
		(layer "F.Cu")
		(net "GND")
	)
	(segment
		(start 181.92496 -297.32478)
		(end 182.39994 -297.79976)
		(width 0.249936)
		(layer "F.Cu")
		(net "GND")
	)
	(segment
		(start 174.69485 -99.750372)
		(end 174.079662 -99.750372)
		(width 0.4064)
		(layer "F.Cu")
		(net "GND")
	)
	(segment
		(start 392.749786 -300.649894)
		(end 392.75004 -300.649894)
		(width 0.254)
		(layer "F.Cu")
		(net "GND")
	)
	(segment
		(start 74.248264 -147.55495)
		(end 73.257664 -147.55495)
		(width 0.3556)
		(layer "F.Cu")
		(net "GND")
	)
	(segment
		(start 193.162428 -23.355554)
		(end 193.81216 -23.355554)
		(width 0.4572)
		(layer "F.Cu")
		(net "GND")
	)
	(segment
		(start 362.827316 -390.507728)
		(end 362.091732 -390.507728)
		(width 0.4572)
		(layer "F.Cu")
		(net "GND")
	)
	(segment
		(start 51.574954 -305.874928)
		(end 52.049934 -305.399948)
		(width 0.249936)
		(layer "F.Cu")
		(net "GND")
	)
	(segment
		(start 333.523844 -27.411934)
		(end 333.523844 -26.319734)
		(width 0.4572)
		(layer "F.Cu")
		(net "GND")
	)
	(segment
		(start 302.12665 -136.061958)
		(end 301.543466 -136.645142)
		(width 0.3556)
		(layer "F.Cu")
		(net "GND")
	)
	(segment
		(start 83.694016 -35.499548)
		(end 84.06638 -35.871912)
		(width 0.4572)
		(layer "F.Cu")
		(net "GND")
	)
	(segment
		(start 103.20274 -224.650046)
		(end 103.427022 -224.425764)
		(width 0.254)
		(layer "F.Cu")
		(net "GND")
	)
	(segment
		(start 292.32479 -294.4749)
		(end 292.79977 -293.99992)
		(width 0.249936)
		(layer "F.Cu")
		(net "GND")
	)
	(segment
		(start 336.843624 -45.88891)
		(end 337.514946 -45.88891)
		(width 0.254)
		(layer "F.Cu")
		(net "GND")
	)
	(segment
		(start 388.949946 -285.449772)
		(end 388.474966 -284.974792)
		(width 0.249936)
		(layer "F.Cu")
		(net "GND")
	)
	(segment
		(start 235.512864 -114.380264)
		(end 235.9787 -114.380264)
		(width 0.254)
		(layer "F.Cu")
		(net "GND")
	)
	(segment
		(start 273.464782 -29.589984)
		(end 272.448782 -29.589984)
		(width 0.3556)
		(layer "F.Cu")
		(net "GND")
	)
	(segment
		(start 406.895046 -99.750372)
		(end 406.279858 -99.750372)
		(width 0.4064)
		(layer "F.Cu")
		(net "GND")
	)
	(segment
		(start 169.099992 -306.349908)
		(end 169.574972 -306.824888)
		(width 0.249936)
		(layer "F.Cu")
		(net "GND")
	)
	(segment
		(start 41.599866 -273.099784)
		(end 41.124886 -272.624804)
		(width 0.249936)
		(layer "F.Cu")
		(net "GND")
	)
	(segment
		(start 443.109096 -94.641416)
		(end 443.109096 -93.98254)
		(width 0.4572)
		(layer "F.Cu")
		(net "GND")
	)
	(segment
		(start 305.624738 -296.37482)
		(end 306.099718 -295.89984)
		(width 0.249936)
		(layer "F.Cu")
		(net "GND")
	)
	(segment
		(start 72.949816 -298.74972)
		(end 73.424796 -298.27474)
		(width 0.249936)
		(layer "F.Cu")
		(net "GND")
	)
	(segment
		(start 147.89404 -393.15644)
		(end 148.270468 -393.15644)
		(width 0.4572)
		(layer "F.Cu")
		(net "GND")
	)
	(segment
		(start 396.770606 -131.277614)
		(end 397.258032 -131.76504)
		(width 0.3556)
		(layer "F.Cu")
		(net "GND")
	)
	(segment
		(start 147.258532 -386.24256)
		(end 148.26996 -386.24256)
		(width 0.4572)
		(layer "F.Cu")
		(net "GND")
	)
	(segment
		(start 415.549842 -288.299906)
		(end 416.024822 -287.824926)
		(width 0.249936)
		(layer "F.Cu")
		(net "GND")
	)
	(segment
		(start 40.39616 -25.990042)
		(end 41.26484 -25.990042)
		(width 0.3556)
		(layer "F.Cu")
		(net "GND")
	)
	(segment
		(start 280.924762 -306.824888)
		(end 280.449782 -306.349908)
		(width 0.249936)
		(layer "F.Cu")
		(net "GND")
	)
	(segment
		(start 162.924998 -303.974754)
		(end 163.399978 -304.449734)
		(width 0.249936)
		(layer "F.Cu")
		(net "GND")
	)
	(segment
		(start 10.020808 -317.105792)
		(end 10.020808 -317.736728)
		(width 0.381)
		(layer "F.Cu")
		(net "GND")
	)
	(segment
		(start 62.974982 -285.924752)
		(end 63.449962 -285.449772)
		(width 0.249936)
		(layer "F.Cu")
		(net "GND")
	)
	(segment
		(start 304.197766 -133.472682)
		(end 304.625502 -133.044946)
		(width 0.3556)
		(layer "F.Cu")
		(net "GND")
	)
	(segment
		(start 62.024768 -289.724846)
		(end 62.499748 -290.199826)
		(width 0.249936)
		(layer "F.Cu")
		(net "GND")
	)
	(segment
		(start 223.519238 -122.0089)
		(end 224.258378 -122.0089)
		(width 0.4572)
		(layer "F.Cu")
		(net "GND")
	)
	(segment
		(start 73.424796 -297.32478)
		(end 73.899776 -297.79976)
		(width 0.249936)
		(layer "F.Cu")
		(net "GND")
	)
	(segment
		(start 180.02504 -291.624766)
		(end 179.55006 -292.099746)
		(width 0.249936)
		(layer "F.Cu")
		(net "GND")
	)
	(segment
		(start 427.42485 -296.37482)
		(end 426.94987 -295.89984)
		(width 0.249936)
		(layer "F.Cu")
		(net "GND")
	)
	(segment
		(start 395.12494 -307.774848)
		(end 395.59992 -307.299868)
		(width 0.249936)
		(layer "F.Cu")
		(net "GND")
	)
	(segment
		(start 175.749966 -307.299868)
		(end 176.224946 -306.824888)
		(width 0.249936)
		(layer "F.Cu")
		(net "GND")
	)
	(segment
		(start 308.949852 -298.74972)
		(end 308.474872 -298.27474)
		(width 0.249936)
		(layer "F.Cu")
		(net "GND")
	)
	(segment
		(start 296.124884 -305.874928)
		(end 296.599864 -305.399948)
		(width 0.249936)
		(layer "F.Cu")
		(net "GND")
	)
	(segment
		(start 192.375028 -296.37482)
		(end 192.850008 -296.8498)
		(width 0.249936)
		(layer "F.Cu")
		(net "GND")
	)
	(segment
		(start 282.824936 -287.824926)
		(end 283.299916 -288.299906)
		(width 0.249936)
		(layer "F.Cu")
		(net "GND")
	)
	(segment
		(start 126.76505 -31.390082)
		(end 128.199388 -31.390082)
		(width 0.3556)
		(layer "F.Cu")
		(net "GND")
	)
	(segment
		(start 406.049988 -285.449772)
		(end 405.575008 -284.974792)
		(width 0.249936)
		(layer "F.Cu")
		(net "GND")
	)
	(segment
		(start 341.293958 -217.587068)
		(end 340.894162 -217.187272)
		(width 0.381)
		(layer "F.Cu")
		(net "GND")
	)
	(segment
		(start 37.799772 -291.149786)
		(end 37.324792 -290.674806)
		(width 0.249936)
		(layer "F.Cu")
		(net "GND")
	)
	(segment
		(start 261.622286 -252.756924)
		(end 261.622286 -253.45644)
		(width 0.4572)
		(layer "F.Cu")
		(net "GND")
	)
	(segment
		(start 190.950088 -293.99992)
		(end 190.474854 -294.4749)
		(width 0.249936)
		(layer "F.Cu")
		(net "GND")
	)
	(segment
		(start 397.02486 -293.52494)
		(end 397.49984 -293.99992)
		(width 0.249936)
		(layer "F.Cu")
		(net "GND")
	)
	(segment
		(start 341.293958 -221.58706)
		(end 340.894162 -221.986856)
		(width 0.381)
		(layer "F.Cu")
		(net "GND")
	)
	(segment
		(start 45.39996 -289.249866)
		(end 44.92498 -288.774886)
		(width 0.249936)
		(layer "F.Cu")
		(net "GND")
	)
	(segment
		(start 405.100028 -284.499812)
		(end 405.575008 -284.024832)
		(width 0.249936)
		(layer "F.Cu")
		(net "GND")
	)
	(segment
		(start 287.574736 -297.32478)
		(end 287.099756 -297.79976)
		(width 0.249936)
		(layer "F.Cu")
		(net "GND")
	)
	(segment
		(start 298.024804 -302.074834)
		(end 298.499784 -301.599854)
		(width 0.249936)
		(layer "F.Cu")
		(net "GND")
	)
	(segment
		(start 164.349938 -296.8498)
		(end 163.874958 -297.32478)
		(width 0.249936)
		(layer "F.Cu")
		(net "GND")
	)
	(segment
		(start 162.924998 -309.674768)
		(end 162.450018 -309.199788)
		(width 0.249936)
		(layer "F.Cu")
		(net "GND")
	)
	(segment
		(start 304.199798 -302.549814)
		(end 304.674778 -303.024794)
		(width 0.249936)
		(layer "F.Cu")
		(net "GND")
	)
	(segment
		(start 402.249894 -292.099746)
		(end 402.724874 -291.624766)
		(width 0.249936)
		(layer "F.Cu")
		(net "GND")
	)
	(segment
		(start 388.949946 -295.89984)
		(end 388.474966 -296.37482)
		(width 0.249936)
		(layer "F.Cu")
		(net "GND")
	)
	(segment
		(start 278.451056 -398.000982)
		(end 278.451056 -396.82039)
		(width 0.4572)
		(layer "F.Cu")
		(net "GND")
	)
	(segment
		(start 406.049988 -286.399732)
		(end 406.524968 -285.924752)
		(width 0.249936)
		(layer "F.Cu")
		(net "GND")
	)
	(segment
		(start 242.774724 -223.388936)
		(end 242.774724 -222.262192)
		(width 0.4572)
		(layer "F.Cu")
		(net "GND")
	)
	(segment
		(start 68.674742 -292.574726)
		(end 69.149976 -292.099746)
		(width 0.249936)
		(layer "F.Cu")
		(net "GND")
	)
	(segment
		(start 194.749928 -294.94988)
		(end 195.224908 -294.4749)
		(width 0.249936)
		(layer "F.Cu")
		(net "GND")
	)
	(segment
		(start 55.849774 -306.349908)
		(end 56.324754 -306.824888)
		(width 0.249936)
		(layer "F.Cu")
		(net "GND")
	)
	(segment
		(start 322.019168 -230.702358)
		(end 322.71081 -230.702358)
		(width 0.4572)
		(layer "F.Cu")
		(net "GND")
	)
	(segment
		(start 112.470692 -124.852938)
		(end 112.545876 -124.777754)
		(width 0.254)
		(layer "F.Cu")
		(net "GND")
	)
	(segment
		(start 195.836794 -16.363188)
		(end 195.836794 -15.474188)
		(width 0.4572)
		(layer "F.Cu")
		(net "GND")
	)
	(segment
		(start 58.577226 -374.528588)
		(end 58.577226 -373.620284)
		(width 0.4572)
		(layer "F.Cu")
		(net "GND")
	)
	(segment
		(start 274.749768 -275.949918)
		(end 274.274788 -275.474938)
		(width 0.249936)
		(layer "F.Cu")
		(net "GND")
	)
	(segment
		(start 256.111248 -346.337382)
		(end 255.911858 -346.137992)
		(width 0.4572)
		(layer "F.Cu")
		(net "GND")
	)
	(segment
		(start 161.975038 -297.32478)
		(end 162.450018 -296.8498)
		(width 0.249936)
		(layer "F.Cu")
		(net "GND")
	)
	(segment
		(start 188.358272 -116.69522)
		(end 188.618368 -116.435124)
		(width 0.3556)
		(layer "F.Cu")
		(net "GND")
	)
	(segment
		(start 410.964888 -34.990024)
		(end 409.948888 -34.990024)
		(width 0.3556)
		(layer "F.Cu")
		(net "GND")
	)
	(segment
		(start 204.238098 -291.102034)
		(end 204.764132 -291.102034)
		(width 0.4572)
		(layer "F.Cu")
		(net "GND")
	)
	(segment
		(start 46.34992 -292.099746)
		(end 45.87494 -291.624766)
		(width 0.249936)
		(layer "F.Cu")
		(net "GND")
	)
	(segment
		(start 285.674816 -289.724846)
		(end 286.149796 -290.199826)
		(width 0.249936)
		(layer "F.Cu")
		(net "GND")
	)
	(segment
		(start 48.24984 -294.94988)
		(end 47.77486 -294.4749)
		(width 0.249936)
		(layer "F.Cu")
		(net "GND")
	)
	(segment
		(start 69.684138 -122.597164)
		(end 69.684138 -122.200416)
		(width 0.3556)
		(layer "F.Cu")
		(net "GND")
	)
	(segment
		(start 234.825794 -114.436144)
		(end 235.456984 -114.436144)
		(width 0.254)
		(layer "F.Cu")
		(net "GND")
	)
	(segment
		(start 45.051726 -133.565138)
		(end 46.042326 -133.565138)
		(width 0.3556)
		(layer "F.Cu")
		(net "GND")
	)
	(segment
		(start 51.63312 -100.64496)
		(end 50.64252 -100.64496)
		(width 0.3556)
		(layer "F.Cu")
		(net "GND")
	)
	(segment
		(start 275.699728 -276.899878)
		(end 275.224748 -276.424898)
		(width 0.249936)
		(layer "F.Cu")
		(net "GND")
	)
	(segment
		(start 386.574792 -296.37482)
		(end 387.050026 -295.89984)
		(width 0.249936)
		(layer "F.Cu")
		(net "GND")
	)
	(segment
		(start 74.84999 -295.89984)
		(end 75.32497 -296.37482)
		(width 0.249936)
		(layer "F.Cu")
		(net "GND")
	)
	(segment
		(start 426.47489 -297.32478)
		(end 425.99991 -296.8498)
		(width 0.249936)
		(layer "F.Cu")
		(net "GND")
	)
	(segment
		(start 279.024842 -307.774848)
		(end 279.499822 -307.299868)
		(width 0.249936)
		(layer "F.Cu")
		(net "GND")
	)
	(segment
		(start 79.59979 -300.649894)
		(end 80.07477 -300.174914)
		(width 0.249936)
		(layer "F.Cu")
		(net "GND")
	)
	(segment
		(start 164.349938 -289.249866)
		(end 163.874958 -288.774886)
		(width 0.249936)
		(layer "F.Cu")
		(net "GND")
	)
	(segment
		(start 27.822144 -306.802028)
		(end 27.072844 -306.052728)
		(width 0.4572)
		(layer "F.Cu")
		(net "GND")
	)
	(segment
		(start 433.099972 -38.671754)
		(end 433.099972 -38.315138)
		(width 0.4572)
		(layer "F.Cu")
		(net "GND")
	)
	(segment
		(start 62.499748 -303.499774)
		(end 62.024768 -303.974754)
		(width 0.249936)
		(layer "F.Cu")
		(net "GND")
	)
	(segment
		(start 242.774724 -222.262192)
		(end 242.569492 -222.05696)
		(width 0.4572)
		(layer "F.Cu")
		(net "GND")
	)
	(segment
		(start 402.724874 -300.174914)
		(end 402.249894 -299.699934)
		(width 0.249936)
		(layer "F.Cu")
		(net "GND")
	)
	(segment
		(start 170.049952 -296.8498)
		(end 169.574972 -297.32478)
		(width 0.249936)
		(layer "F.Cu")
		(net "GND")
	)
	(segment
		(start 307.049678 -282.599892)
		(end 307.049932 -282.599892)
		(width 0.254)
		(layer "F.Cu")
		(net "GND")
	)
	(segment
		(start 74.860912 -37.201094)
		(end 74.098404 -37.201094)
		(width 0.4572)
		(layer "F.Cu")
		(net "GND")
	)
	(segment
		(start 294.69969 -306.349908)
		(end 294.22471 -305.874928)
		(width 0.249936)
		(layer "F.Cu")
		(net "GND")
	)
	(segment
		(start 215.464136 -186.702954)
		(end 215.464136 -185.719974)
		(width 0.254)
		(layer "F.Cu")
		(net "GND")
	)
	(segment
		(start 185.622946 -134.845044)
		(end 184.757314 -134.845044)
		(width 0.3556)
		(layer "F.Cu")
		(net "GND")
	)
	(segment
		(start 228.267768 -219.10421)
		(end 227.867972 -219.504006)
		(width 0.381)
		(layer "F.Cu")
		(net "GND")
	)
	(segment
		(start 295.649904 -303.499774)
		(end 295.174924 -303.974754)
		(width 0.249936)
		(layer "F.Cu")
		(net "GND")
	)
	(segment
		(start 362.354622 -383.115058)
		(end 361.45851 -383.115058)
		(width 0.4572)
		(layer "F.Cu")
		(net "GND")
	)
	(segment
		(start 26.667968 -54.067456)
		(end 27.323288 -54.067456)
		(width 0.254)
		(layer "F.Cu")
		(net "GND")
	)
	(segment
		(start 57.749948 -306.349908)
		(end 57.274968 -306.824888)
		(width 0.249936)
		(layer "F.Cu")
		(net "GND")
	)
	(segment
		(start 393.7 -289.249866)
		(end 393.22502 -288.774886)
		(width 0.249936)
		(layer "F.Cu")
		(net "GND")
	)
	(segment
		(start 300.874684 -298.27474)
		(end 300.399704 -298.74972)
		(width 0.249936)
		(layer "F.Cu")
		(net "GND")
	)
	(segment
		(start 46.958758 -107.845098)
		(end 46.042326 -107.845098)
		(width 0.3556)
		(layer "F.Cu")
		(net "GND")
	)
	(segment
		(start 169.574972 -302.074834)
		(end 170.049952 -301.599854)
		(width 0.249936)
		(layer "F.Cu")
		(net "GND")
	)
	(segment
		(start 56.324754 -291.624766)
		(end 56.799988 -292.099746)
		(width 0.249936)
		(layer "F.Cu")
		(net "GND")
	)
	(segment
		(start 244.69344 -30.850586)
		(end 244.153944 -31.390082)
		(width 0.3556)
		(layer "F.Cu")
		(net "GND")
	)
	(segment
		(start 314.174886 -297.32478)
		(end 313.699906 -297.79976)
		(width 0.249936)
		(layer "F.Cu")
		(net "GND")
	)
	(segment
		(start 365.93907 -282.8417)
		(end 365.70666 -283.07411)
		(width 0.2286)
		(layer "F.Cu")
		(net "GND")
	)
	(segment
		(start 93.18244 -120.041924)
		(end 93.076522 -119.936006)
		(width 0.254)
		(layer "F.Cu")
		(net "GND")
	)
	(segment
		(start 170.524932 -287.824926)
		(end 170.999912 -288.299906)
		(width 0.249936)
		(layer "F.Cu")
		(net "GND")
	)
	(segment
		(start 393.351766 -120.555004)
		(end 394.342366 -120.555004)
		(width 0.3556)
		(layer "F.Cu")
		(net "GND")
	)
	(segment
		(start 99.530408 -65.92189)
		(end 99.530408 -65.15989)
		(width 0.4572)
		(layer "F.Cu")
		(net "GND")
	)
	(segment
		(start 417.924996 -306.824888)
		(end 418.399976 -307.299868)
		(width 0.249936)
		(layer "F.Cu")
		(net "GND")
	)
	(segment
		(start 397.02486 -300.174914)
		(end 397.49984 -299.699934)
		(width 0.249936)
		(layer "F.Cu")
		(net "GND")
	)
	(segment
		(start 379.2474 -37.087048)
		(end 379.8824 -37.087048)
		(width 0.4572)
		(layer "F.Cu")
		(net "GND")
	)
	(segment
		(start 171.949872 -288.299906)
		(end 171.474892 -287.824926)
		(width 0.249936)
		(layer "F.Cu")
		(net "GND")
	)
	(segment
		(start 374.967246 -56.354218)
		(end 374.968008 -56.353456)
		(width 0.4572)
		(layer "F.Cu")
		(net "GND")
	)
	(segment
		(start 69.523102 -134.845044)
		(end 68.65747 -134.845044)
		(width 0.3556)
		(layer "F.Cu")
		(net "GND")
	)
	(segment
		(start 429.800004 -297.79976)
		(end 429.325024 -298.27474)
		(width 0.249936)
		(layer "F.Cu")
		(net "GND")
	)
	(segment
		(start 421.724836 -301.124874)
		(end 422.199816 -301.599854)
		(width 0.249936)
		(layer "F.Cu")
		(net "GND")
	)
	(segment
		(start 168.625012 -284.974792)
		(end 168.150032 -285.449772)
		(width 0.249936)
		(layer "F.Cu")
		(net "GND")
	)
	(segment
		(start 284.724856 -296.37482)
		(end 284.249876 -296.8498)
		(width 0.249936)
		(layer "F.Cu")
		(net "GND")
	)
	(segment
		(start 350.64192 -26.606246)
		(end 350.64192 -25.971246)
		(width 0.4572)
		(layer "F.Cu")
		(net "GND")
	)
	(segment
		(start 187.35802 -73.166732)
		(end 187.35802 -73.85177)
		(width 0.4572)
		(layer "F.Cu")
		(net "GND")
	)
	(segment
		(start 249.490992 -228.538278)
		(end 249.35434 -228.67493)
		(width 0.4572)
		(layer "F.Cu")
		(net "GND")
	)
	(segment
		(start 180.50002 -288.299906)
		(end 180.02504 -287.824926)
		(width 0.249936)
		(layer "F.Cu")
		(net "GND")
	)
	(segment
		(start 413.174942 -296.37482)
		(end 412.699962 -295.89984)
		(width 0.249936)
		(layer "F.Cu")
		(net "GND")
	)
	(segment
		(start 409.849828 -286.399732)
		(end 409.374848 -285.924752)
		(width 0.249936)
		(layer "F.Cu")
		(net "GND")
	)
	(segment
		(start 122.409204 -27.04973)
		(end 121.750074 -27.04973)
		(width 0.4572)
		(layer "F.Cu")
		(net "GND")
	)
	(segment
		(start 231.46766 -214.304118)
		(end 231.867456 -213.904322)
		(width 0.381)
		(layer "F.Cu")
		(net "GND")
	)
	(segment
		(start 223.310958 -189.637416)
		(end 224.324926 -189.637416)
		(width 0.3048)
		(layer "F.Cu")
		(net "GND")
	)
	(segment
		(start 172.424852 -303.974754)
		(end 172.900086 -303.499774)
		(width 0.249936)
		(layer "F.Cu")
		(net "GND")
	)
	(segment
		(start 88.664796 -31.390082)
		(end 89.53627 -31.390082)
		(width 0.3556)
		(layer "F.Cu")
		(net "GND")
	)
	(segment
		(start 394.64996 -290.199826)
		(end 394.17498 -289.724846)
		(width 0.249936)
		(layer "F.Cu")
		(net "GND")
	)
	(segment
		(start 57.66435 -140.6398)
		(end 57.33415 -140.97)
		(width 0.4572)
		(layer "F.Cu")
		(net "GND")
	)
	(segment
		(start 392.749786 -281.649932)
		(end 392.75004 -281.649932)
		(width 0.249936)
		(layer "F.Cu")
		(net "GND")
	)
	(segment
		(start 64.874902 -285.924752)
		(end 64.399922 -286.399732)
		(width 0.249936)
		(layer "F.Cu")
		(net "GND")
	)
	(segment
		(start 331.192378 -242.848892)
		(end 331.192378 -243.863622)
		(width 0.3556)
		(layer "F.Cu")
		(net "GND")
	)
	(segment
		(start 441.48248 -120.041924)
		(end 441.376562 -119.936006)
		(width 0.254)
		(layer "F.Cu")
		(net "GND")
	)
	(segment
		(start 399.400014 -293.99992)
		(end 399.874994 -294.4749)
		(width 0.249936)
		(layer "F.Cu")
		(net "GND")
	)
	(segment
		(start 44.449746 -296.8498)
		(end 43.974766 -297.32478)
		(width 0.249936)
		(layer "F.Cu")
		(net "GND")
	)
	(segment
		(start 165.299898 -286.399732)
		(end 164.824918 -285.924752)
		(width 0.249936)
		(layer "F.Cu")
		(net "GND")
	)
	(segment
		(start 47.59452 -126.703836)
		(end 46.845728 -125.955044)
		(width 0.3556)
		(layer "F.Cu")
		(net "GND")
	)
	(segment
		(start 312.21553 -33.248092)
		(end 311.532016 -33.248092)
		(width 0.4572)
		(layer "F.Cu")
		(net "GND")
	)
	(segment
		(start 44.449746 -294.94988)
		(end 43.974766 -294.4749)
		(width 0.249936)
		(layer "F.Cu")
		(net "GND")
	)
	(segment
		(start 404.624794 -289.724846)
		(end 404.149814 -290.199826)
		(width 0.249936)
		(layer "F.Cu")
		(net "GND")
	)
	(segment
		(start 325.464678 -34.990024)
		(end 326.480678 -34.990024)
		(width 0.3556)
		(layer "F.Cu")
		(net "GND")
	)
	(segment
		(start 413.174942 -307.774848)
		(end 412.699962 -307.299868)
		(width 0.249936)
		(layer "F.Cu")
		(net "GND")
	)
	(segment
		(start 157.699964 -283.549852)
		(end 157.224984 -283.074872)
		(width 0.249936)
		(layer "F.Cu")
		(net "GND")
	)
	(segment
		(start 428.84979 -298.74972)
		(end 429.325024 -299.224954)
		(width 0.249936)
		(layer "F.Cu")
		(net "GND")
	)
	(segment
		(start 170.524932 -284.974792)
		(end 170.049952 -285.449772)
		(width 0.249936)
		(layer "F.Cu")
		(net "GND")
	)
	(segment
		(start 286.027622 -34.732468)
		(end 285.795212 -34.732468)
		(width 0.4572)
		(layer "F.Cu")
		(net "GND")
	)
	(segment
		(start 246.448834 -27.79014)
		(end 247.464834 -27.79014)
		(width 0.3556)
		(layer "F.Cu")
		(net "GND")
	)
	(segment
		(start 353.015296 -59.946286)
		(end 353.015296 -60.601606)
		(width 0.4572)
		(layer "F.Cu")
		(net "GND")
	)
	(segment
		(start 61.549788 -299.699934)
		(end 62.024768 -300.174914)
		(width 0.249936)
		(layer "F.Cu")
		(net "GND")
	)
	(segment
		(start 428.036736 -16.363188)
		(end 428.036736 -15.474188)
		(width 0.4572)
		(layer "F.Cu")
		(net "GND")
	)
	(segment
		(start 423.15003 -292.099746)
		(end 423.62501 -292.574726)
		(width 0.249936)
		(layer "F.Cu")
		(net "GND")
	)
	(segment
		(start 184.77484 -284.024832)
		(end 184.29986 -284.499812)
		(width 0.249936)
		(layer "F.Cu")
		(net "GND")
	)
	(segment
		(start 185.250074 -293.99992)
		(end 184.77484 -293.52494)
		(width 0.249936)
		(layer "F.Cu")
		(net "GND")
	)
	(segment
		(start 428.37481 -288.774886)
		(end 427.89983 -289.249866)
		(width 0.249936)
		(layer "F.Cu")
		(net "GND")
	)
	(segment
		(start 350.685608 -34.183066)
		(end 350.571054 -34.29762)
		(width 0.4572)
		(layer "F.Cu")
		(net "GND")
	)
	(segment
		(start 53.82768 -34.732468)
		(end 54.262528 -34.29762)
		(width 0.4572)
		(layer "F.Cu")
		(net "GND")
	)
	(segment
		(start 49.67478 -305.874928)
		(end 49.1998 -305.399948)
		(width 0.249936)
		(layer "F.Cu")
		(net "GND")
	)
	(segment
		(start 210.99399 -114.886486)
		(end 211.62899 -114.886486)
		(width 0.4572)
		(layer "F.Cu")
		(net "GND")
	)
	(segment
		(start 408.899868 -301.599854)
		(end 409.374848 -302.074834)
		(width 0.249936)
		(layer "F.Cu")
		(net "GND")
	)
	(segment
		(start 181.44998 -307.299868)
		(end 181.92496 -307.774848)
		(width 0.249936)
		(layer "F.Cu")
		(net "GND")
	)
	(segment
		(start 195.224908 -292.574726)
		(end 195.699888 -293.04996)
		(width 0.249936)
		(layer "F.Cu")
		(net "GND")
	)
	(segment
		(start 288.915094 -59.946286)
		(end 288.915094 -60.601606)
		(width 0.4572)
		(layer "F.Cu")
		(net "GND")
	)
	(segment
		(start 280.924762 -300.174914)
		(end 280.449782 -300.649894)
		(width 0.249936)
		(layer "F.Cu")
		(net "GND")
	)
	(segment
		(start 55.849774 -284.499812)
		(end 56.324754 -284.974792)
		(width 0.249936)
		(layer "F.Cu")
		(net "GND")
	)
	(segment
		(start 253.346966 -53.144166)
		(end 253.346966 -52.592224)
		(width 0.254)
		(layer "F.Cu")
		(net "GND")
	)
	(segment
		(start 161.500058 -296.8498)
		(end 161.975038 -297.32478)
		(width 0.249936)
		(layer "F.Cu")
		(net "GND")
	)
	(segment
		(start 182.87492 -284.974792)
		(end 182.39994 -284.499812)
		(width 0.249936)
		(layer "F.Cu")
		(net "GND")
	)
	(segment
		(start 156.750004 -276.899878)
		(end 156.275024 -276.424898)
		(width 0.249936)
		(layer "F.Cu")
		(net "GND")
	)
	(segment
		(start 47.44593 -46.693836)
		(end 46.918626 -46.693836)
		(width 0.254)
		(layer "F.Cu")
		(net "GND")
	)
	(segment
		(start 281.874722 -301.124874)
		(end 282.349702 -300.649894)
		(width 0.249936)
		(layer "F.Cu")
		(net "GND")
	)
	(segment
		(start 32.119062 -59.974734)
		(end 31.468568 -59.974734)
		(width 0.4572)
		(layer "F.Cu")
		(net "GND")
	)
	(segment
		(start 284.249876 -292.099746)
		(end 284.724856 -291.624766)
		(width 0.249936)
		(layer "F.Cu")
		(net "GND")
	)
	(segment
		(start 179.07508 -302.074834)
		(end 178.599846 -301.599854)
		(width 0.249936)
		(layer "F.Cu")
		(net "GND")
	)
	(segment
		(start 454.939146 -319.515998)
		(end 454.939146 -320.146934)
		(width 0.381)
		(layer "F.Cu")
		(net "GND")
	)
	(segment
		(start 190.474854 -298.27474)
		(end 190.950088 -297.79976)
		(width 0.249936)
		(layer "F.Cu")
		(net "GND")
	)
	(segment
		(start 80.07477 -294.4749)
		(end 79.59979 -294.94988)
		(width 0.249936)
		(layer "F.Cu")
		(net "GND")
	)
	(segment
		(start 53.474874 -297.32478)
		(end 52.999894 -297.79976)
		(width 0.249936)
		(layer "F.Cu")
		(net "GND")
	)
	(segment
		(start 292.79977 -285.449772)
		(end 292.32479 -284.974792)
		(width 0.254)
		(layer "F.Cu")
		(net "GND")
	)
	(segment
		(start 5.888736 -37.395912)
		(end 5.888736 -36.760912)
		(width 0.4572)
		(layer "F.Cu")
		(net "GND")
	)
	(segment
		(start 272.374868 -292.574726)
		(end 272.849848 -292.099746)
		(width 0.249936)
		(layer "F.Cu")
		(net "GND")
	)
	(segment
		(start 413.14878 -179.282344)
		(end 412.533592 -179.897532)
		(width 0.4572)
		(layer "F.Cu")
		(net "GND")
	)
	(segment
		(start 340.527386 -240.936272)
		(end 340.82228 -240.641378)
		(width 0.3556)
		(layer "F.Cu")
		(net "GND")
	)
	(segment
		(start 296.124884 -303.974754)
		(end 295.649904 -303.499774)
		(width 0.249936)
		(layer "F.Cu")
		(net "GND")
	)
	(segment
		(start 270.949928 -293.04996)
		(end 270.474948 -292.57498)
		(width 0.249936)
		(layer "F.Cu")
		(net "GND")
	)
	(segment
		(start 108.94695 -38.49116)
		(end 108.241338 -38.49116)
		(width 0.4572)
		(layer "F.Cu")
		(net "GND")
	)
	(segment
		(start 409.374848 -291.624766)
		(end 409.849828 -292.099746)
		(width 0.249936)
		(layer "F.Cu")
		(net "GND")
	)
	(segment
		(start 395.59992 -305.399948)
		(end 395.12494 -304.924714)
		(width 0.249936)
		(layer "F.Cu")
		(net "GND")
	)
	(segment
		(start 299.866812 -116.435124)
		(end 300.857412 -116.435124)
		(width 0.3556)
		(layer "F.Cu")
		(net "GND")
	)
	(segment
		(start 187.149994 -293.04996)
		(end 187.624974 -292.574726)
		(width 0.249936)
		(layer "F.Cu")
		(net "GND")
	)
	(segment
		(start 228.267768 -218.30411)
		(end 227.867972 -217.904314)
		(width 0.381)
		(layer "F.Cu")
		(net "GND")
	)
	(segment
		(start 422.548304 -123.635008)
		(end 421.557704 -123.635008)
		(width 0.3556)
		(layer "F.Cu")
		(net "GND")
	)
	(segment
		(start 396.0749 -306.824888)
		(end 396.54988 -307.299868)
		(width 0.249936)
		(layer "F.Cu")
		(net "GND")
	)
	(segment
		(start 424.57497 -290.674806)
		(end 425.04995 -291.149786)
		(width 0.249936)
		(layer "F.Cu")
		(net "GND")
	)
	(segment
		(start 301.824898 -292.574726)
		(end 301.349918 -293.04996)
		(width 0.249936)
		(layer "F.Cu")
		(net "GND")
	)
	(segment
		(start 173.850046 -301.599854)
		(end 174.325026 -302.074834)
		(width 0.249936)
		(layer "F.Cu")
		(net "GND")
	)
	(segment
		(start 54.899814 -285.449772)
		(end 54.424834 -284.974792)
		(width 0.249936)
		(layer "F.Cu")
		(net "GND")
	)
	(segment
		(start 281.874722 -306.824888)
		(end 282.349702 -306.349908)
		(width 0.249936)
		(layer "F.Cu")
		(net "GND")
	)
	(segment
		(start 41.599866 -293.04996)
		(end 41.124886 -292.57498)
		(width 0.249936)
		(layer "F.Cu")
		(net "GND")
	)
	(segment
		(start 179.31765 -193.58356)
		(end 178.929284 -193.195194)
		(width 0.381)
		(layer "F.Cu")
		(net "GND")
	)
	(segment
		(start 401.774914 -291.624766)
		(end 402.249894 -292.099746)
		(width 0.249936)
		(layer "F.Cu")
		(net "GND")
	)
	(segment
		(start 207.493616 -219.356178)
		(end 206.773526 -218.636088)
		(width 0.254)
		(layer "F.Cu")
		(net "GND")
	)
	(segment
		(start 451.122034 -212.463126)
		(end 451.815454 -212.463126)
		(width 0.4572)
		(layer "F.Cu")
		(net "GND")
	)
	(segment
		(start 69.624956 -284.024832)
		(end 69.149976 -284.499812)
		(width 0.249936)
		(layer "F.Cu")
		(net "GND")
	)
	(segment
		(start 231.46766 -215.104218)
		(end 231.867456 -214.704422)
		(width 0.381)
		(layer "F.Cu")
		(net "GND")
	)
	(segment
		(start 73.899776 -291.149786)
		(end 73.424796 -290.674806)
		(width 0.249936)
		(layer "F.Cu")
		(net "GND")
	)
	(segment
		(start 43.499786 -300.649894)
		(end 43.974766 -300.174914)
		(width 0.249936)
		(layer "F.Cu")
		(net "GND")
	)
	(segment
		(start 288.524696 -305.874928)
		(end 288.049716 -306.349908)
		(width 0.249936)
		(layer "F.Cu")
		(net "GND")
	)
	(segment
		(start 50.14976 -303.499774)
		(end 49.67478 -303.024794)
		(width 0.249936)
		(layer "F.Cu")
		(net "GND")
	)
	(segment
		(start 177.174906 -287.824926)
		(end 177.649886 -288.299906)
		(width 0.249936)
		(layer "F.Cu")
		(net "GND")
	)
	(segment
		(start 390.58088 -34.990024)
		(end 389.56488 -34.990024)
		(width 0.3556)
		(layer "F.Cu")
		(net "GND")
	)
	(segment
		(start 104.378252 -223.106742)
		(end 103.868982 -223.106742)
		(width 0.1778)
		(layer "F.Cu")
		(net "GND")
	)
	(segment
		(start 386.099812 -293.04996)
		(end 385.624832 -292.57498)
		(width 0.249936)
		(layer "F.Cu")
		(net "GND")
	)
	(segment
		(start 156.348938 -27.79014)
		(end 157.364938 -27.79014)
		(width 0.3556)
		(layer "F.Cu")
		(net "GND")
	)
	(segment
		(start 353.29495 -183.388)
		(end 352.613214 -183.388)
		(width 0.4572)
		(layer "F.Cu")
		(net "GND")
	)
	(segment
		(start 349.279972 -282.8417)
		(end 349.047562 -283.07411)
		(width 0.2286)
		(layer "F.Cu")
		(net "GND")
	)
	(segment
		(start 170.049952 -294.94988)
		(end 169.574972 -294.4749)
		(width 0.249936)
		(layer "F.Cu")
		(net "GND")
	)
	(segment
		(start 160.549844 -291.149786)
		(end 160.074864 -290.674806)
		(width 0.249936)
		(layer "F.Cu")
		(net "GND")
	)
	(segment
		(start 186.675014 -303.024794)
		(end 187.149994 -303.499774)
		(width 0.249936)
		(layer "F.Cu")
		(net "GND")
	)
	(segment
		(start 190.394844 -102.439978)
		(end 189.357508 -102.439978)
		(width 0.3556)
		(layer "F.Cu")
		(net "GND")
	)
	(segment
		(start 313.224926 -289.724846)
		(end 312.749692 -289.249866)
		(width 0.249936)
		(layer "F.Cu")
		(net "GND")
	)
	(segment
		(start 174.325026 -302.074834)
		(end 174.800006 -301.599854)
		(width 0.249936)
		(layer "F.Cu")
		(net "GND")
	)
	(segment
		(start 154.850084 -281.649932)
		(end 154.375104 -281.174952)
		(width 0.249936)
		(layer "F.Cu")
		(net "GND")
	)
	(segment
		(start 424.57497 -296.37482)
		(end 425.04995 -296.8498)
		(width 0.249936)
		(layer "F.Cu")
		(net "GND")
	)
	(segment
		(start 428.287434 -33.248092)
		(end 427.632114 -33.248092)
		(width 0.4572)
		(layer "F.Cu")
		(net "GND")
	)
	(segment
		(start 298.499784 -286.399732)
		(end 298.024804 -285.924752)
		(width 0.249936)
		(layer "F.Cu")
		(net "GND")
	)
	(segment
		(start 384.612134 -136.84885)
		(end 384.612134 -136.81456)
		(width 0.4572)
		(layer "F.Cu")
		(net "GND")
	)
	(segment
		(start 215.006936 -189.052454)
		(end 215.006936 -189.662054)
		(width 0.4572)
		(layer "F.Cu")
		(net "GND")
	)
	(segment
		(start 271.899888 -289.249866)
		(end 272.374868 -289.724846)
		(width 0.254)
		(layer "F.Cu")
		(net "GND")
	)
	(segment
		(start 459.315058 -114.22634)
		(end 457.87437 -112.785652)
		(width 0.254)
		(layer "F.Cu")
		(net "GND")
	)
	(segment
		(start 358.01046 -121.661428)
		(end 357.35514 -121.661428)
		(width 0.4064)
		(layer "F.Cu")
		(net "GND")
	)
	(segment
		(start 182.87492 -307.774848)
		(end 183.3499 -307.299868)
		(width 0.249936)
		(layer "F.Cu")
		(net "GND")
	)
	(segment
		(start 395.59992 -297.79976)
		(end 395.12494 -298.27474)
		(width 0.249936)
		(layer "F.Cu")
		(net "GND")
	)
	(segment
		(start 63.744856 -29.589984)
		(end 62.664848 -29.589984)
		(width 0.3556)
		(layer "F.Cu")
		(net "GND")
	)
	(segment
		(start 297.549824 -288.299906)
		(end 297.074844 -287.824926)
		(width 0.249936)
		(layer "F.Cu")
		(net "GND")
	)
	(segment
		(start 165.774878 -303.024794)
		(end 166.249858 -303.499774)
		(width 0.249936)
		(layer "F.Cu")
		(net "GND")
	)
	(segment
		(start 390.849866 -289.249866)
		(end 391.324846 -289.724846)
		(width 0.254)
		(layer "F.Cu")
		(net "GND")
	)
	(segment
		(start 411.275022 -298.27474)
		(end 410.799788 -297.79976)
		(width 0.249936)
		(layer "F.Cu")
		(net "GND")
	)
	(segment
		(start 73.424796 -292.574726)
		(end 72.949816 -293.04996)
		(width 0.249936)
		(layer "F.Cu")
		(net "GND")
	)
	(segment
		(start 178.124866 -289.724846)
		(end 177.649886 -290.199826)
		(width 0.249936)
		(layer "F.Cu")
		(net "GND")
	)
	(segment
		(start 190.348108 -129.445004)
		(end 189.357508 -129.445004)
		(width 0.3556)
		(layer "F.Cu")
		(net "GND")
	)
	(segment
		(start 48.24984 -304.449734)
		(end 48.72482 -303.974754)
		(width 0.249936)
		(layer "F.Cu")
		(net "GND")
	)
	(segment
		(start 420.567104 -123.635008)
		(end 421.557704 -123.635008)
		(width 0.3556)
		(layer "F.Cu")
		(net "GND")
	)
	(segment
		(start 167.732964 -122.355102)
		(end 166.742364 -122.355102)
		(width 0.3556)
		(layer "F.Cu")
		(net "GND")
	)
	(segment
		(start 68.280788 -31.390082)
		(end 67.264788 -31.390082)
		(width 0.3556)
		(layer "F.Cu")
		(net "GND")
	)
	(segment
		(start 74.248264 -142.15491)
		(end 73.257664 -142.15491)
		(width 0.3556)
		(layer "F.Cu")
		(net "GND")
	)
	(segment
		(start 237.894114 -35.264852)
		(end 237.894114 -35.499548)
		(width 0.4572)
		(layer "F.Cu")
		(net "GND")
	)
	(segment
		(start 248.494804 -276.519386)
		(end 249.104404 -276.519386)
		(width 0.381)
		(layer "F.Cu")
		(net "GND")
	)
	(segment
		(start 419.349936 -301.599854)
		(end 418.874956 -301.124874)
		(width 0.249936)
		(layer "F.Cu")
		(net "GND")
	)
	(segment
		(start 25.358344 -252.756924)
		(end 25.358344 -253.45644)
		(width 0.4572)
		(layer "F.Cu")
		(net "GND")
	)
	(segment
		(start 23.30831 -255.809496)
		(end 23.146512 -255.647698)
		(width 0.4572)
		(layer "F.Cu")
		(net "GND")
	)
	(segment
		(start 405.100028 -299.699934)
		(end 405.575008 -300.174914)
		(width 0.249936)
		(layer "F.Cu")
		(net "GND")
	)
	(segment
		(start 172.424852 -306.824888)
		(end 171.949872 -307.299868)
		(width 0.249936)
		(layer "F.Cu")
		(net "GND")
	)
	(segment
		(start 326.515222 -226.61245)
		(end 326.30237 -226.825302)
		(width 0.4572)
		(layer "F.Cu")
		(net "GND")
	)
	(segment
		(start 104.667812 -51.019456)
		(end 105.323132 -51.019456)
		(width 0.254)
		(layer "F.Cu")
		(net "GND")
	)
	(segment
		(start 162.450018 -293.04996)
		(end 161.975038 -292.57498)
		(width 0.249936)
		(layer "F.Cu")
		(net "GND")
	)
	(segment
		(start 294.22471 -300.174914)
		(end 294.69969 -299.699934)
		(width 0.249936)
		(layer "F.Cu")
		(net "GND")
	)
	(segment
		(start 401.299934 -285.449772)
		(end 401.774914 -284.974792)
		(width 0.249936)
		(layer "F.Cu")
		(net "GND")
	)
	(segment
		(start 104.667812 -54.067456)
		(end 105.323132 -54.067456)
		(width 0.254)
		(layer "F.Cu")
		(net "GND")
	)
	(segment
		(start 419.349936 -289.249866)
		(end 418.874956 -289.724846)
		(width 0.249936)
		(layer "F.Cu")
		(net "GND")
	)
	(segment
		(start 163.399978 -302.549814)
		(end 162.924998 -302.074834)
		(width 0.249936)
		(layer "F.Cu")
		(net "GND")
	)
	(segment
		(start 168.625012 -284.974792)
		(end 169.099992 -284.499812)
		(width 0.249936)
		(layer "F.Cu")
		(net "GND")
	)
	(segment
		(start 311.324752 -296.37482)
		(end 310.849772 -296.8498)
		(width 0.249936)
		(layer "F.Cu")
		(net "GND")
	)
	(segment
		(start 68.674742 -292.574726)
		(end 69.149976 -293.04996)
		(width 0.249936)
		(layer "F.Cu")
		(net "GND")
	)
	(segment
		(start 10.013442 -41.469056)
		(end 11.679936 -41.469056)
		(width 0.4572)
		(layer "F.Cu")
		(net "GND")
	)
	(segment
		(start 143.490442 -252.756924)
		(end 143.490442 -253.45644)
		(width 0.4572)
		(layer "F.Cu")
		(net "GND")
	)
	(segment
		(start 4.689602 -69.392292)
		(end 5.432044 -69.392292)
		(width 0.4572)
		(layer "F.Cu")
		(net "GND")
	)
	(segment
		(start 440.548776 -33.19018)
		(end 441.564776 -33.19018)
		(width 0.3556)
		(layer "F.Cu")
		(net "GND")
	)
	(segment
		(start 62.024768 -285.924752)
		(end 62.499748 -285.449772)
		(width 0.249936)
		(layer "F.Cu")
		(net "GND")
	)
	(segment
		(start 363.564932 -29.589984)
		(end 364.580932 -29.589984)
		(width 0.3556)
		(layer "F.Cu")
		(net "GND")
	)
	(segment
		(start 290.89985 -303.499774)
		(end 290.42487 -303.974754)
		(width 0.249936)
		(layer "F.Cu")
		(net "GND")
	)
	(segment
		(start 21.061172 -38.701218)
		(end 21.819616 -38.701218)
		(width 0.4572)
		(layer "F.Cu")
		(net "GND")
	)
	(segment
		(start 357.619808 -162.404044)
		(end 357.619808 -163.021518)
		(width 0.4572)
		(layer "F.Cu")
		(net "GND")
	)
	(segment
		(start 402.036788 -16.363188)
		(end 402.036788 -15.474188)
		(width 0.4572)
		(layer "F.Cu")
		(net "GND")
	)
	(segment
		(start 62.024768 -284.974792)
		(end 62.499748 -284.499812)
		(width 0.249936)
		(layer "F.Cu")
		(net "GND")
	)
	(segment
		(start 300.874684 -305.874928)
		(end 300.399704 -306.349908)
		(width 0.249936)
		(layer "F.Cu")
		(net "GND")
	)
	(segment
		(start 54.424834 -305.874928)
		(end 53.949854 -305.399948)
		(width 0.249936)
		(layer "F.Cu")
		(net "GND")
	)
	(segment
		(start 279.024842 -305.874928)
		(end 278.549862 -305.399948)
		(width 0.249936)
		(layer "F.Cu")
		(net "GND")
	)
	(segment
		(start 67.66687 -131.245102)
		(end 68.65747 -131.245102)
		(width 0.3556)
		(layer "F.Cu")
		(net "GND")
	)
	(segment
		(start 60.599828 -284.499812)
		(end 61.074808 -284.974792)
		(width 0.249936)
		(layer "F.Cu")
		(net "GND")
	)
	(segment
		(start 181.92496 -285.924752)
		(end 181.44998 -285.449772)
		(width 0.249936)
		(layer "F.Cu")
		(net "GND")
	)
	(segment
		(start 71.524876 -302.074834)
		(end 71.049896 -302.549814)
		(width 0.249936)
		(layer "F.Cu")
		(net "GND")
	)
	(segment
		(start 179.07508 -303.974754)
		(end 178.599846 -303.499774)
		(width 0.249936)
		(layer "F.Cu")
		(net "GND")
	)
	(segment
		(start 419.824916 -302.074834)
		(end 419.349936 -302.549814)
		(width 0.249936)
		(layer "F.Cu")
		(net "GND")
	)
	(segment
		(start 97.498408 -65.92189)
		(end 97.498408 -65.15989)
		(width 0.4572)
		(layer "F.Cu")
		(net "GND")
	)
	(segment
		(start 313.224926 -300.174914)
		(end 312.749692 -300.649894)
		(width 0.249936)
		(layer "F.Cu")
		(net "GND")
	)
	(segment
		(start 154.850084 -290.199826)
		(end 154.375104 -289.724846)
		(width 0.249936)
		(layer "F.Cu")
		(net "GND")
	)
	(segment
		(start 314.889388 -64.312292)
		(end 315.647832 -64.312292)
		(width 0.4572)
		(layer "F.Cu")
		(net "GND")
	)
	(segment
		(start 281.399742 -307.299868)
		(end 280.924762 -307.774848)
		(width 0.249936)
		(layer "F.Cu")
		(net "GND")
	)
	(segment
		(start 313.549538 -85.426296)
		(end 312.439558 -85.426296)
		(width 0.4572)
		(layer "F.Cu")
		(net "GND")
	)
	(segment
		(start 379.99416 -35.264852)
		(end 379.99416 -35.499548)
		(width 0.4572)
		(layer "F.Cu")
		(net "GND")
	)
	(segment
		(start 304.669444 -147.55495)
		(end 305.457606 -147.55495)
		(width 0.3556)
		(layer "F.Cu")
		(net "GND")
	)
	(segment
		(start 282.349702 -285.449772)
		(end 281.874722 -284.974792)
		(width 0.249936)
		(layer "F.Cu")
		(net "GND")
	)
	(segment
		(start 312.274712 -292.574726)
		(end 312.749692 -293.04996)
		(width 0.249936)
		(layer "F.Cu")
		(net "GND")
	)
	(segment
		(start 134.946898 -38.49116)
		(end 134.241286 -38.49116)
		(width 0.4572)
		(layer "F.Cu")
		(net "GND")
	)
	(segment
		(start 335.64195 -147.955)
		(end 335.026 -147.955)
		(width 0.4572)
		(layer "F.Cu")
		(net "GND")
	)
	(segment
		(start 395.332966 -120.555004)
		(end 394.342366 -120.555004)
		(width 0.3556)
		(layer "F.Cu")
		(net "GND")
	)
	(segment
		(start 68.674742 -293.52494)
		(end 68.199762 -293.04996)
		(width 0.249936)
		(layer "F.Cu")
		(net "GND")
	)
	(segment
		(start 402.724874 -284.024832)
		(end 403.199854 -284.499812)
		(width 0.249936)
		(layer "F.Cu")
		(net "GND")
	)
	(segment
		(start 341.2998 -282.406344)
		(end 341.11946 -282.8417)
		(width 0.2286)
		(layer "F.Cu")
		(net "GND")
	)
	(segment
		(start 309.424832 -301.124874)
		(end 308.949852 -300.649894)
		(width 0.249936)
		(layer "F.Cu")
		(net "GND")
	)
	(segment
		(start 155.800044 -297.79976)
		(end 156.275024 -298.27474)
		(width 0.249936)
		(layer "F.Cu")
		(net "GND")
	)
	(segment
		(start 174.219108 -59.974734)
		(end 173.568614 -59.974734)
		(width 0.4572)
		(layer "F.Cu")
		(net "GND")
	)
	(segment
		(start 199.30491 -142.597886)
		(end 199.30491 -143.470122)
		(width 0.4064)
		(layer "F.Cu")
		(net "GND")
	)
	(segment
		(start 296.255948 -33.19018)
		(end 294.86479 -33.19018)
		(width 0.3556)
		(layer "F.Cu")
		(net "GND")
	)
	(segment
		(start 171.474892 -305.874928)
		(end 170.999912 -305.399948)
		(width 0.249936)
		(layer "F.Cu")
		(net "GND")
	)
	(segment
		(start 289.94989 -284.499812)
		(end 289.47491 -284.974792)
		(width 0.249936)
		(layer "F.Cu")
		(net "GND")
	)
	(segment
		(start 417.924996 -292.574726)
		(end 417.450016 -292.099746)
		(width 0.249936)
		(layer "F.Cu")
		(net "GND")
	)
	(segment
		(start 93.264736 -27.79014)
		(end 94.280736 -27.79014)
		(width 0.3556)
		(layer "F.Cu")
		(net "GND")
	)
	(segment
		(start 181.92496 -303.974754)
		(end 181.44998 -303.499774)
		(width 0.249936)
		(layer "F.Cu")
		(net "GND")
	)
	(segment
		(start 212.27161 -213.481666)
		(end 211.512404 -213.481666)
		(width 0.4572)
		(layer "F.Cu")
		(net "GND")
	)
	(segment
		(start 21.255736 -153.1112)
		(end 21.255736 -153.782522)
		(width 0.4064)
		(layer "F.Cu")
		(net "GND")
	)
	(segment
		(start 88.007444 -96.411542)
		(end 88.007444 -95.919798)
		(width 0.4572)
		(layer "F.Cu")
		(net "GND")
	)
	(segment
		(start 71.049896 -292.1)
		(end 70.574916 -292.57498)
		(width 0.249936)
		(layer "F.Cu")
		(net "GND")
	)
	(segment
		(start 62.499748 -305.399948)
		(end 62.974982 -305.874928)
		(width 0.249936)
		(layer "F.Cu")
		(net "GND")
	)
	(segment
		(start 419.824916 -305.874928)
		(end 419.349936 -305.399948)
		(width 0.249936)
		(layer "F.Cu")
		(net "GND")
	)
	(segment
		(start 51.63312 -98.845116)
		(end 50.64252 -98.845116)
		(width 0.3556)
		(layer "F.Cu")
		(net "GND")
	)
	(segment
		(start 283.299916 -299.699934)
		(end 283.774896 -300.174914)
		(width 0.249936)
		(layer "F.Cu")
		(net "GND")
	)
	(segment
		(start 170.999912 -292.099746)
		(end 171.474892 -291.624766)
		(width 0.249936)
		(layer "F.Cu")
		(net "GND")
	)
	(segment
		(start 456.540108 -308.291992)
		(end 457.179934 -308.291992)
		(width 0.1778)
		(layer "F.Cu")
		(net "GND")
	)
	(segment
		(start 273.799808 -281.649932)
		(end 273.324828 -281.174952)
		(width 0.249936)
		(layer "F.Cu")
		(net "GND")
	)
	(segment
		(start 417.643564 -136.645142)
		(end 416.95751 -136.645142)
		(width 0.3556)
		(layer "F.Cu")
		(net "GND")
	)
	(segment
		(start 405.100028 -288.299906)
		(end 405.575008 -287.824926)
		(width 0.249936)
		(layer "F.Cu")
		(net "GND")
	)
	(segment
		(start 63.94704 -385.07924)
		(end 63.466726 -384.598926)
		(width 0.4572)
		(layer "F.Cu")
		(net "GND")
	)
	(segment
		(start 207.860138 -238.66094)
		(end 208.114138 -238.40694)
		(width 0.4572)
		(layer "F.Cu")
		(net "GND")
	)
	(segment
		(start 157.699964 -277.849838)
		(end 157.224984 -277.374858)
		(width 0.249936)
		(layer "F.Cu")
		(net "GND")
	)
	(segment
		(start 429.325024 -296.37482)
		(end 429.800004 -295.89984)
		(width 0.249936)
		(layer "F.Cu")
		(net "GND")
	)
	(segment
		(start 269.999714 -296.8498)
		(end 270.474694 -297.32478)
		(width 0.249936)
		(layer "F.Cu")
		(net "GND")
	)
	(segment
		(start 60.124848 -284.974792)
		(end 59.649868 -284.499812)
		(width 0.254)
		(layer "F.Cu")
		(net "GND")
	)
	(segment
		(start 64.399922 -307.299868)
		(end 63.924942 -306.824888)
		(width 0.249936)
		(layer "F.Cu")
		(net "GND")
	)
	(segment
		(start 278.549862 -289.249866)
		(end 278.074882 -288.774886)
		(width 0.249936)
		(layer "F.Cu")
		(net "GND")
	)
	(segment
		(start 350.647 -185.82005)
		(end 351.38995 -185.82005)
		(width 0.4572)
		(layer "F.Cu")
		(net "GND")
	)
	(segment
		(start 411.275022 -300.174914)
		(end 411.750002 -299.699934)
		(width 0.249936)
		(layer "F.Cu")
		(net "GND")
	)
	(segment
		(start 402.249894 -306.349908)
		(end 401.774914 -306.824888)
		(width 0.249936)
		(layer "F.Cu")
		(net "GND")
	)
	(segment
		(start 27.79141 -305.507898)
		(end 28.366974 -306.083462)
		(width 0.4572)
		(layer "F.Cu")
		(net "GND")
	)
	(segment
		(start 175.749966 -296.8498)
		(end 176.224946 -297.32478)
		(width 0.249936)
		(layer "F.Cu")
		(net "GND")
	)
	(segment
		(start 275.699728 -291.149786)
		(end 275.224748 -290.674806)
		(width 0.249936)
		(layer "F.Cu")
		(net "GND")
	)
	(segment
		(start 395.59992 -293.99992)
		(end 396.0749 -294.4749)
		(width 0.254)
		(layer "F.Cu")
		(net "GND")
	)
	(segment
		(start 44.449746 -282.599892)
		(end 43.974766 -282.124912)
		(width 0.249936)
		(layer "F.Cu")
		(net "GND")
	)
	(segment
		(start 288.049716 -301.599854)
		(end 287.574736 -302.074834)
		(width 0.249936)
		(layer "F.Cu")
		(net "GND")
	)
	(segment
		(start 169.574972 -285.924752)
		(end 169.099992 -285.449772)
		(width 0.249936)
		(layer "F.Cu")
		(net "GND")
	)
	(segment
		(start 328.041 -81.64195)
		(end 328.78395 -81.64195)
		(width 0.4572)
		(layer "F.Cu")
		(net "GND")
	)
	(segment
		(start 392.749786 -293.99992)
		(end 392.274806 -293.52494)
		(width 0.249936)
		(layer "F.Cu")
		(net "GND")
	)
	(segment
		(start 60.437268 -393.56284)
		(end 59.421268 -393.56284)
		(width 0.4572)
		(layer "F.Cu")
		(net "GND")
	)
	(segment
		(start 190.348108 -147.55495)
		(end 189.357508 -147.55495)
		(width 0.3556)
		(layer "F.Cu")
		(net "GND")
	)
	(segment
		(start 410.799788 -299.699934)
		(end 410.324808 -300.174914)
		(width 0.249936)
		(layer "F.Cu")
		(net "GND")
	)
	(segment
		(start 168.625012 -296.37482)
		(end 168.150032 -296.8498)
		(width 0.249936)
		(layer "F.Cu")
		(net "GND")
	)
	(segment
		(start 300.399704 -285.449772)
		(end 299.924724 -285.924752)
		(width 0.249936)
		(layer "F.Cu")
		(net "GND")
	)
	(segment
		(start 42.074846 -296.37482)
		(end 41.599866 -295.89984)
		(width 0.249936)
		(layer "F.Cu")
		(net "GND")
	)
	(segment
		(start 170.382692 -28.875736)
		(end 170.382692 -28.47848)
		(width 0.254)
		(layer "F.Cu")
		(net "GND")
	)
	(segment
		(start 242.864894 -27.79014)
		(end 241.848894 -27.79014)
		(width 0.3556)
		(layer "F.Cu")
		(net "GND")
	)
	(segment
		(start 40.649906 -289.249866)
		(end 40.174926 -289.724846)
		(width 0.254)
		(layer "F.Cu")
		(net "GND")
	)
	(segment
		(start 140.705332 -189.778132)
		(end 141.517878 -189.778132)
		(width 0.3556)
		(layer "F.Cu")
		(net "GND")
	)
	(segment
		(start 300.399704 -290.199826)
		(end 299.924724 -289.724846)
		(width 0.249936)
		(layer "F.Cu")
		(net "GND")
	)
	(segment
		(start 173.375066 -300.174914)
		(end 172.900086 -299.699934)
		(width 0.249936)
		(layer "F.Cu")
		(net "GND")
	)
	(segment
		(start 327.094088 -117.426486)
		(end 327.729088 -117.426486)
		(width 0.4572)
		(layer "F.Cu")
		(net "GND")
	)
	(segment
		(start 436.964836 -34.990024)
		(end 435.948836 -34.990024)
		(width 0.3556)
		(layer "F.Cu")
		(net "GND")
	)
	(segment
		(start 128.154938 -34.990024)
		(end 126.76505 -34.990024)
		(width 0.3556)
		(layer "F.Cu")
		(net "GND")
	)
	(segment
		(start 189.049914 -295.89984)
		(end 189.524894 -296.37482)
		(width 0.249936)
		(layer "F.Cu")
		(net "GND")
	)
	(segment
		(start 413.29737 -179.282344)
		(end 413.14878 -179.282344)
		(width 0.4572)
		(layer "F.Cu")
		(net "GND")
	)
	(via
		(at 431.768504 -59.974734)
		(size 0.508)
		(drill 0.254)
		(layers "F.Cu" "B.Cu")
		(net "GND")
	)
	(via
		(at 427.89983 -281.649932)
		(size 0.4064)
		(drill 0.2032)
		(layers "F.Cu" "B.Cu")
		(net "GND")
	)
	(via
		(at 438.044844 -29.589984)
		(size 0.508)
		(drill 0.254)
		(layers "F.Cu" "B.Cu")
		(net "GND")
	)
	(via
		(at 152.47493 -278.324818)
		(size 0.4064)
		(drill 0.2032)
		(layers "F.Cu" "B.Cu")
		(net "GND")
	)
	(via
		(at 226.302824 -149.43455)
		(size 0.508)
		(drill 0.254)
		(layers "F.Cu" "B.Cu")
		(net "GND")
	)
	(via
		(at 170.524932 -291.624766)
		(size 0.4064)
		(drill 0.2032)
		(layers "F.Cu" "B.Cu")
		(net "GND")
	)
	(via
		(at 131.57708 -344.831162)
		(size 0.4572)
		(drill 0.254)
		(layers "F.Cu" "B.Cu")
		(net "GND")
	)
	(via
		(at 366.912144 -131.957572)
		(size 0.508)
		(drill 0.254)
		(layers "F.Cu" "B.Cu")
		(net "GND")
	)
	(via
		(at 173.375066 -291.624766)
		(size 0.4064)
		(drill 0.2032)
		(layers "F.Cu" "B.Cu")
		(net "GND")
	)
	(via
		(at 324.741032 -344.831162)
		(size 0.4572)
		(drill 0.254)
		(layers "F.Cu" "B.Cu")
		(net "GND")
	)
	(via
		(at 59.649868 -310.149748)
		(size 0.4064)
		(drill 0.2032)
		(layers "F.Cu" "B.Cu")
		(net "GND")
	)
	(via
		(at 307.049932 -316.799722)
		(size 0.4064)
		(drill 0.2032)
		(layers "F.Cu" "B.Cu")
		(net "GND")
	)
	(via
		(at 49.1998 -276.899878)
		(size 0.4064)
		(drill 0.2032)
		(layers "F.Cu" "B.Cu")
		(net "GND")
	)
	(via
		(at 231.331262 -181.829456)
		(size 0.508)
		(drill 0.254)
		(layers "F.Cu" "B.Cu")
		(net "GND")
	)
	(via
		(at 276.174708 -289.724846)
		(size 0.4064)
		(drill 0.2032)
		(layers "F.Cu" "B.Cu")
		(net "GND")
	)
	(via
		(at 191.425068 -296.37482)
		(size 0.4064)
		(drill 0.2032)
		(layers "F.Cu" "B.Cu")
		(net "GND")
	)
	(via
		(at 197.600062 -274.049744)
		(size 0.4064)
		(drill 0.2032)
		(layers "F.Cu" "B.Cu")
		(net "GND")
	)
	(via
		(at 448.163188 -416.636962)
		(size 0.508)
		(drill 0.254)
		(layers "F.Cu" "B.Cu")
		(net "GND")
	)
	(via
		(at 295.68013 -354.074222)
		(size 0.4572)
		(drill 0.254)
		(layers "F.Cu" "B.Cu")
		(net "GND")
	)
	(via
		(at 268.099286 -314.899548)
		(size 0.4064)
		(drill 0.2032)
		(layers "F.Cu" "B.Cu")
		(net "GND")
	)
	(via
		(at 421.249856 -314.899802)
		(size 0.4064)
		(drill 0.2032)
		(layers "F.Cu" "B.Cu")
		(net "GND")
	)
	(via
		(at 363.350048 -131.312666)
		(size 0.508)
		(drill 0.254)
		(layers "F.Cu" "B.Cu")
		(net "GND")
	)
	(via
		(at 466.827616 -16.452596)
		(size 0.508)
		(drill 0.254)
		(layers "F.Cu" "B.Cu")
		(net "GND")
	)
	(via
		(at 278.139144 -29.311854)
		(size 0.508)
		(drill 0.254)
		(layers "F.Cu" "B.Cu")
		(net "GND")
	)
	(via
		(at 65.81267 -133.0452)
		(size 0.508)
		(drill 0.254)
		(layers "F.Cu" "B.Cu")
		(net "GND")
	)
	(via
		(at 421.161972 -345.465146)
		(size 0.4064)
		(drill 0.2032)
		(layers "F.Cu" "B.Cu")
		(net "GND")
	)
	(via
		(at 165.440106 -73.87463)
		(size 0.508)
		(drill 0.254)
		(layers "F.Cu" "B.Cu")
		(net "GND")
	)
	(via
		(at 73.239122 -357.75773)
		(size 0.4064)
		(drill 0.2032)
		(layers "F.Cu" "B.Cu")
		(net "GND")
	)
	(via
		(at 417.984178 -124.31649)
		(size 0.508)
		(drill 0.254)
		(layers "F.Cu" "B.Cu")
		(net "GND")
	)
	(via
		(at 153.898346 -21.738336)
		(size 0.508)
		(drill 0.254)
		(layers "F.Cu" "B.Cu")
		(net "GND")
	)
	(via
		(at 51.099974 -273.099784)
		(size 0.4064)
		(drill 0.2032)
		(layers "F.Cu" "B.Cu")
		(net "GND")
	)
	(via
		(at 444.690754 -231.33939)
		(size 0.508)
		(drill 0.254)
		(layers "F.Cu" "B.Cu")
		(net "GND")
	)
	(via
		(at 392.52779 -402.241766)
		(size 0.508)
		(drill 0.254)
		(layers "F.Cu" "B.Cu")
		(net "GND")
	)
	(via
		(at 332.18755 -122.525028)
		(size 0.508)
		(drill 0.254)
		(layers "F.Cu" "B.Cu")
		(net "GND")
	)
	(via
		(at 425.52493 -303.024794)
		(size 0.4064)
		(drill 0.2032)
		(layers "F.Cu" "B.Cu")
		(net "GND")
	)
	(via
		(at 393.22502 -288.774886)
		(size 0.4064)
		(drill 0.2032)
		(layers "F.Cu" "B.Cu")
		(net "GND")
	)
	(via
		(at 133.427216 -355.366066)
		(size 0.4572)
		(drill 0.254)
		(layers "F.Cu" "B.Cu")
		(net "GND")
	)
	(via
		(at 53.474874 -302.074834)
		(size 0.4064)
		(drill 0.2032)
		(layers "F.Cu" "B.Cu")
		(net "GND")
	)
	(via
		(at 45.636688 -357.75773)
		(size 0.4064)
		(drill 0.2032)
		(layers "F.Cu" "B.Cu")
		(net "GND")
	)
	(via
		(at 77.947774 -378.83846)
		(size 0.508)
		(drill 0.254)
		(layers "F.Cu" "B.Cu")
		(net "GND")
	)
	(via
		(at 386.574792 -296.37482)
		(size 0.4064)
		(drill 0.2032)
		(layers "F.Cu" "B.Cu")
		(net "GND")
	)
	(via
		(at 174.42434 -357.123746)
		(size 0.4572)
		(drill 0.254)
		(layers "F.Cu" "B.Cu")
		(net "GND")
	)
	(via
		(at 115.638326 -282.910788)
		(size 0.49022)
		(drill 0.254)
		(layers "F.Cu" "B.Cu")
		(net "GND")
	)
	(via
		(at 307.524912 -298.27474)
		(size 0.4064)
		(drill 0.2032)
		(layers "F.Cu" "B.Cu")
		(net "GND")
	)
	(via
		(at 159.347916 -375.040144)
		(size 0.508)
		(drill 0.254)
		(layers "F.Cu" "B.Cu")
		(net "GND")
	)
	(via
		(at 142.293594 -299.133514)
		(size 0.508)
		(drill 0.254)
		(layers "F.Cu" "B.Cu")
		(net "GND")
	)
	(via
		(at 105.976674 -285.267654)
		(size 0.508)
		(drill 0.254)
		(layers "F.Cu" "B.Cu")
		(net "GND")
	)
	(via
		(at 286.149796 -280.699718)
		(size 0.4064)
		(drill 0.2032)
		(layers "F.Cu" "B.Cu")
		(net "GND")
	)
	(via
		(at 363.73308 -285.953454)
		(size 0.508)
		(drill 0.254)
		(layers "F.Cu" "B.Cu")
		(net "GND")
	)
	(via
		(at 432.12766 -403.738588)
		(size 0.508)
		(drill 0.254)
		(layers "F.Cu" "B.Cu")
		(net "GND")
	)
	(via
		(at 182.272432 -342.439498)
		(size 0.4064)
		(drill 0.2032)
		(layers "F.Cu" "B.Cu")
		(net "GND")
	)
	(via
		(at 392.749786 -303.499774)
		(size 0.4064)
		(drill 0.2032)
		(layers "F.Cu" "B.Cu")
		(net "GND")
	)
	(via
		(at 7.095236 -307.317394)
		(size 0.508)
		(drill 0.254)
		(layers "F.Cu" "B.Cu")
		(net "GND")
	)
	(via
		(at 429.543718 -81.698846)
		(size 0.508)
		(drill 0.254)
		(layers "F.Cu" "B.Cu")
		(net "GND")
	)
	(via
		(at 196.649848 -279.749758)
		(size 0.4064)
		(drill 0.2032)
		(layers "F.Cu" "B.Cu")
		(net "GND")
	)
	(via
		(at 178.792124 -352.245422)
		(size 0.4572)
		(drill 0.254)
		(layers "F.Cu" "B.Cu")
		(net "GND")
	)
	(via
		(at 418.971222 -29.311854)
		(size 0.508)
		(drill 0.254)
		(layers "F.Cu" "B.Cu")
		(net "GND")
	)
	(via
		(at 170.049952 -312.049922)
		(size 0.4064)
		(drill 0.2032)
		(layers "F.Cu" "B.Cu")
		(net "GND")
	)
	(via
		(at 84.54771 -369.938554)
		(size 0.508)
		(drill 0.254)
		(layers "F.Cu" "B.Cu")
		(net "GND")
	)
	(via
		(at 397.02486 -284.024832)
		(size 0.4064)
		(drill 0.2032)
		(layers "F.Cu" "B.Cu")
		(net "GND")
	)
	(via
		(at 198.701406 -411.507686)
		(size 0.508)
		(drill 0.254)
		(layers "F.Cu" "B.Cu")
		(net "GND")
	)
	(via
		(at 190.394844 -104.240076)
		(size 0.508)
		(drill 0.254)
		(layers "F.Cu" "B.Cu")
		(net "GND")
	)
	(via
		(at 158.380938 -31.390082)
		(size 0.508)
		(drill 0.254)
		(layers "F.Cu" "B.Cu")
		(net "GND")
	)
	(via
		(at 378.467112 -352.245422)
		(size 0.4572)
		(drill 0.254)
		(layers "F.Cu" "B.Cu")
		(net "GND")
	)
	(via
		(at 115.34775 -381.638556)
		(size 0.508)
		(drill 0.254)
		(layers "F.Cu" "B.Cu")
		(net "GND")
	)
	(via
		(at 104.905048 -392.200892)
		(size 0.508)
		(drill 0.254)
		(layers "F.Cu" "B.Cu")
		(net "GND")
	)
	(via
		(at 47.77486 -288.774886)
		(size 0.4064)
		(drill 0.2032)
		(layers "F.Cu" "B.Cu")
		(net "GND")
	)
	(via
		(at 82.924904 -301.124874)
		(size 0.4064)
		(drill 0.2032)
		(layers "F.Cu" "B.Cu")
		(net "GND")
	)
	(via
		(at 452.220838 -313.682126)
		(size 0.508)
		(drill 0.254)
		(layers "F.Cu" "B.Cu")
		(net "GND")
	)
	(via
		(at 186.675014 -299.224954)
		(size 0.4064)
		(drill 0.2032)
		(layers "F.Cu" "B.Cu")
		(net "GND")
	)
	(via
		(at 385.433824 -132.04317)
		(size 0.508)
		(drill 0.254)
		(layers "F.Cu" "B.Cu")
		(net "GND")
	)
	(via
		(at 122.743468 -93.086174)
		(size 0.508)
		(drill 0.254)
		(layers "F.Cu" "B.Cu")
		(net "GND")
	)
	(via
		(at 298.647612 -152.95499)
		(size 0.508)
		(drill 0.254)
		(layers "F.Cu" "B.Cu")
		(net "GND")
	)
	(via
		(at 80.147922 -384.041904)
		(size 0.508)
		(drill 0.254)
		(layers "F.Cu" "B.Cu")
		(net "GND")
	)
	(via
		(at 117.882416 -344.831162)
		(size 0.4572)
		(drill 0.254)
		(layers "F.Cu" "B.Cu")
		(net "GND")
	)
	(via
		(at 77.978254 -350.977454)
		(size 0.4572)
		(drill 0.254)
		(layers "F.Cu" "B.Cu")
		(net "GND")
	)
	(via
		(at 433.96916 -354.098098)
		(size 0.4572)
		(drill 0.254)
		(layers "F.Cu" "B.Cu")
		(net "GND")
	)
	(via
		(at 280.924762 -284.024832)
		(size 0.4064)
		(drill 0.2032)
		(layers "F.Cu" "B.Cu")
		(net "GND")
	)
	(via
		(at 89.15527 -355.366066)
		(size 0.4572)
		(drill 0.254)
		(layers "F.Cu" "B.Cu")
		(net "GND")
	)
	(via
		(at 189.999874 -309.199788)
		(size 0.4064)
		(drill 0.2032)
		(layers "F.Cu" "B.Cu")
		(net "GND")
	)
	(via
		(at 324.369684 -348.58579)
		(size 0.4064)
		(drill 0.2032)
		(layers "F.Cu" "B.Cu")
		(net "GND")
	)
	(via
		(at 131.57708 -357.123746)
		(size 0.4572)
		(drill 0.254)
		(layers "F.Cu" "B.Cu")
		(net "GND")
	)
	(via
		(at 371.524276 -222.214186)
		(size 0.508)
		(drill 0.254)
		(layers "F.Cu" "B.Cu")
		(net "GND")
	)
	(via
		(at 375.112788 -10.35812)
		(size 0.508)
		(drill 0.254)
		(layers "F.Cu" "B.Cu")
		(net "GND")
	)
	(via
		(at 68.651374 -346.09913)
		(size 0.4572)
		(drill 0.254)
		(layers "F.Cu" "B.Cu")
		(net "GND")
	)
	(via
		(at 263.647936 -64.312292)
		(size 0.508)
		(drill 0.254)
		(layers "F.Cu" "B.Cu")
		(net "GND")
	)
	(via
		(at 386.16382 -348.58579)
		(size 0.4064)
		(drill 0.2032)
		(layers "F.Cu" "B.Cu")
		(net "GND")
	)
	(via
		(at 71.524876 -303.974754)
		(size 0.4064)
		(drill 0.2032)
		(layers "F.Cu" "B.Cu")
		(net "GND")
	)
	(via
		(at 74.849736 -279.749758)
		(size 0.4064)
		(drill 0.2032)
		(layers "F.Cu" "B.Cu")
		(net "GND")
	)
	(via
		(at 429.198278 -142.418054)
		(size 0.508)
		(drill 0.254)
		(layers "F.Cu" "B.Cu")
		(net "GND")
	)
	(via
		(at 14.514576 -378.725938)
		(size 0.508)
		(drill 0.254)
		(layers "F.Cu" "B.Cu")
		(net "GND")
	)
	(via
		(at 171.474892 -289.724846)
		(size 0.4064)
		(drill 0.2032)
		(layers "F.Cu" "B.Cu")
		(net "GND")
	)
	(via
		(at 38.401752 -100.375466)
		(size 0.508)
		(drill 0.254)
		(layers "F.Cu" "B.Cu")
		(net "GND")
	)
	(via
		(at 272.374868 -286.874966)
		(size 0.4064)
		(drill 0.2032)
		(layers "F.Cu" "B.Cu")
		(net "GND")
	)
	(via
		(at 419.824916 -288.774886)
		(size 0.4064)
		(drill 0.2032)
		(layers "F.Cu" "B.Cu")
		(net "GND")
	)
	(via
		(at 77.947774 -381.241808)
		(size 0.508)
		(drill 0.254)
		(layers "F.Cu" "B.Cu")
		(net "GND")
	)
	(via
		(at 190.949834 -282.599892)
		(size 0.4064)
		(drill 0.2032)
		(layers "F.Cu" "B.Cu")
		(net "GND")
	)
	(via
		(at 128.547622 -395.938502)
		(size 0.508)
		(drill 0.254)
		(layers "F.Cu" "B.Cu")
		(net "GND")
	)
	(via
		(at 409.374848 -293.52494)
		(size 0.4064)
		(drill 0.2032)
		(layers "F.Cu" "B.Cu")
		(net "GND")
	)
	(via
		(at 51.099974 -274.049744)
		(size 0.4064)
		(drill 0.2032)
		(layers "F.Cu" "B.Cu")
		(net "GND")
	)
	(via
		(at 373.72798 -342.439498)
		(size 0.4064)
		(drill 0.2032)
		(layers "F.Cu" "B.Cu")
		(net "GND")
	)
	(via
		(at 430.953164 -49.574704)
		(size 0.508)
		(drill 0.254)
		(layers "F.Cu" "B.Cu")
		(net "GND")
	)
	(via
		(at 412.20644 -347.92793)
		(size 0.4572)
		(drill 0.254)
		(layers "F.Cu" "B.Cu")
		(net "GND")
	)
	(via
		(at 124.100336 -349.219774)
		(size 0.4572)
		(drill 0.254)
		(layers "F.Cu" "B.Cu")
		(net "GND")
	)
	(via
		(at 384.059684 -111.72317)
		(size 0.508)
		(drill 0.254)
		(layers "F.Cu" "B.Cu")
		(net "GND")
	)
	(via
		(at 277.457916 -73.85177)
		(size 0.508)
		(drill 0.254)
		(layers "F.Cu" "B.Cu")
		(net "GND")
	)
	(via
		(at 349.110554 -277.004272)
		(size 0.508)
		(drill 0.254)
		(layers "F.Cu" "B.Cu")
		(net "GND")
	)
	(via
		(at 37.799772 -313.949842)
		(size 0.4064)
		(drill 0.2032)
		(layers "F.Cu" "B.Cu")
		(net "GND")
	)
	(via
		(at 422.548304 -149.355048)
		(size 0.508)
		(drill 0.254)
		(layers "F.Cu" "B.Cu")
		(net "GND")
	)
	(via
		(at 16.359632 -145.53565)
		(size 0.508)
		(drill 0.254)
		(layers "F.Cu" "B.Cu")
		(net "GND")
	)
	(via
		(at 172.900086 -274.049744)
		(size 0.4064)
		(drill 0.2032)
		(layers "F.Cu" "B.Cu")
		(net "GND")
	)
	(via
		(at 177.174906 -291.624766)
		(size 0.4064)
		(drill 0.2032)
		(layers "F.Cu" "B.Cu")
		(net "GND")
	)
	(via
		(at 188.33211 -114.812572)
		(size 0.508)
		(drill 0.254)
		(layers "F.Cu" "B.Cu")
		(net "GND")
	)
	(via
		(at 74.84999 -281.649932)
		(size 0.4064)
		(drill 0.2032)
		(layers "F.Cu" "B.Cu")
		(net "GND")
	)
	(via
		(at 183.75122 -350.977454)
		(size 0.4572)
		(drill 0.254)
		(layers "F.Cu" "B.Cu")
		(net "GND")
	)
	(via
		(at 220.241622 -144.958562)
		(size 0.508)
		(drill 0.254)
		(layers "F.Cu" "B.Cu")
		(net "GND")
	)
	(via
		(at 294.69969 -281.649932)
		(size 0.4064)
		(drill 0.2032)
		(layers "F.Cu" "B.Cu")
		(net "GND")
	)
	(via
		(at 189.322202 -52.51704)
		(size 0.508)
		(drill 0.254)
		(layers "F.Cu" "B.Cu")
		(net "GND")
	)
	(via
		(at 163.874958 -294.4749)
		(size 0.4064)
		(drill 0.2032)
		(layers "F.Cu" "B.Cu")
		(net "GND")
	)
	(via
		(at 310.374792 -297.32478)
		(size 0.4064)
		(drill 0.2032)
		(layers "F.Cu" "B.Cu")
		(net "GND")
	)
	(via
		(at 76.74991 -279.749758)
		(size 0.4064)
		(drill 0.2032)
		(layers "F.Cu" "B.Cu")
		(net "GND")
	)
	(via
		(at 402.24964 -272.14957)
		(size 0.4064)
		(drill 0.2032)
		(layers "F.Cu" "B.Cu")
		(net "GND")
	)
	(via
		(at 384.685032 -358.391714)
		(size 0.4572)
		(drill 0.254)
		(layers "F.Cu" "B.Cu")
		(net "GND")
	)
	(via
		(at 340.094062 -218.787218)
		(size 0.4572)
		(drill 0.254)
		(layers "F.Cu" "B.Cu")
		(net "GND")
	)
	(via
		(at 400.229832 -350.977454)
		(size 0.4572)
		(drill 0.254)
		(layers "F.Cu" "B.Cu")
		(net "GND")
	)
	(via
		(at 198.075042 -291.624766)
		(size 0.4064)
		(drill 0.2032)
		(layers "F.Cu" "B.Cu")
		(net "GND")
	)
	(via
		(at 432.12766 -378.94006)
		(size 0.508)
		(drill 0.254)
		(layers "F.Cu" "B.Cu")
		(net "GND")
	)
	(via
		(at 277.251668 -135.364982)
		(size 0.508)
		(drill 0.254)
		(layers "F.Cu" "B.Cu")
		(net "GND")
	)
	(via
		(at 370.990368 -350.977454)
		(size 0.4572)
		(drill 0.254)
		(layers "F.Cu" "B.Cu")
		(net "GND")
	)
	(via
		(at 302.299878 -281.649932)
		(size 0.4064)
		(drill 0.2032)
		(layers "F.Cu" "B.Cu")
		(net "GND")
	)
	(via
		(at 386.535168 -352.245422)
		(size 0.4572)
		(drill 0.254)
		(layers "F.Cu" "B.Cu")
		(net "GND")
	)
	(via
		(at 153.89987 -309.199788)
		(size 0.4064)
		(drill 0.2032)
		(layers "F.Cu" "B.Cu")
		(net "GND")
	)
	(via
		(at 278.285194 -350.977454)
		(size 0.4572)
		(drill 0.254)
		(layers "F.Cu" "B.Cu")
		(net "GND")
	)
	(via
		(at 397.134588 -71.451978)
		(size 0.508)
		(drill 0.254)
		(layers "F.Cu" "B.Cu")
		(net "GND")
	)
	(via
		(at 378.467112 -350.977454)
		(size 0.4572)
		(drill 0.254)
		(layers "F.Cu" "B.Cu")
		(net "GND")
	)
	(via
		(at 259.868924 -292.732714)
		(size 0.508)
		(drill 0.254)
		(layers "F.Cu" "B.Cu")
		(net "GND")
	)
	(via
		(at 335.026 -171.069)
		(size 0.508)
		(drill 0.254)
		(layers "F.Cu" "B.Cu")
		(net "GND")
	)
	(via
		(at 170.347894 -381.241808)
		(size 0.508)
		(drill 0.254)
		(layers "F.Cu" "B.Cu")
		(net "GND")
	)
	(via
		(at 304.467006 -131.245102)
		(size 0.508)
		(drill 0.254)
		(layers "F.Cu" "B.Cu")
		(net "GND")
	)
	(via
		(at 65.81267 -147.555204)
		(size 0.508)
		(drill 0.254)
		(layers "F.Cu" "B.Cu")
		(net "GND")
	)
	(via
		(at 48.24984 -319.65011)
		(size 0.4064)
		(drill 0.2032)
		(layers "F.Cu" "B.Cu")
		(net "GND")
	)
	(via
		(at 196.649848 -283.549852)
		(size 0.4064)
		(drill 0.2032)
		(layers "F.Cu" "B.Cu")
		(net "GND")
	)
	(via
		(at 317.008256 -152.683464)
		(size 0.508)
		(drill 0.254)
		(layers "F.Cu" "B.Cu")
		(net "GND")
	)
	(via
		(at 289.46221 -344.831162)
		(size 0.4572)
		(drill 0.254)
		(layers "F.Cu" "B.Cu")
		(net "GND")
	)
	(via
		(at 54.424834 -296.37482)
		(size 0.4064)
		(drill 0.2032)
		(layers "F.Cu" "B.Cu")
		(net "GND")
	)
	(via
		(at 203.183998 -88.22436)
		(size 0.508)
		(drill 0.254)
		(layers "F.Cu" "B.Cu")
		(net "GND")
	)
	(via
		(at 76.74991 -275.949918)
		(size 0.4064)
		(drill 0.2032)
		(layers "F.Cu" "B.Cu")
		(net "GND")
	)
	(via
		(at 213.741 -206.288894)
		(size 0.508)
		(drill 0.254)
		(layers "F.Cu" "B.Cu")
		(net "GND")
	)
	(via
		(at 272.849848 -314.899802)
		(size 0.4064)
		(drill 0.2032)
		(layers "F.Cu" "B.Cu")
		(net "GND")
	)
	(via
		(at 20.719288 -46.893226)
		(size 0.508)
		(drill 0.254)
		(layers "F.Cu" "B.Cu")
		(net "GND")
	)
	(via
		(at 395.862048 -355.366066)
		(size 0.4572)
		(drill 0.254)
		(layers "F.Cu" "B.Cu")
		(net "GND")
	)
	(via
		(at 332.217776 -350.977454)
		(size 0.4572)
		(drill 0.254)
		(layers "F.Cu" "B.Cu")
		(net "GND")
	)
	(via
		(at 387.050026 -299.699934)
		(size 0.4064)
		(drill 0.2032)
		(layers "F.Cu" "B.Cu")
		(net "GND")
	)
	(via
		(at 144.01292 -344.831162)
		(size 0.4572)
		(drill 0.254)
		(layers "F.Cu" "B.Cu")
		(net "GND")
	)
	(via
		(at 37.798248 -21.738336)
		(size 0.508)
		(drill 0.254)
		(layers "F.Cu" "B.Cu")
		(net "GND")
	)
	(via
		(at 455.669904 -365.953548)
		(size 0.508)
		(drill 0.254)
		(layers "F.Cu" "B.Cu")
		(net "GND")
	)
	(via
		(at 343.2937 -217.187272)
		(size 0.4572)
		(drill 0.254)
		(layers "F.Cu" "B.Cu")
		(net "GND")
	)
	(via
		(at 168.20642 -347.951806)
		(size 0.4572)
		(drill 0.254)
		(layers "F.Cu" "B.Cu")
		(net "GND")
	)
	(via
		(at 404.149814 -274.999958)
		(size 0.4064)
		(drill 0.2032)
		(layers "F.Cu" "B.Cu")
		(net "GND")
	)
	(via
		(at 289.47491 -306.824888)
		(size 0.4064)
		(drill 0.2032)
		(layers "F.Cu" "B.Cu")
		(net "GND")
	)
	(via
		(at 197.873366 -114.42954)
		(size 0.508)
		(drill 0.254)
		(layers "F.Cu" "B.Cu")
		(net "GND")
	)
	(via
		(at 69.64807 -142.15491)
		(size 0.508)
		(drill 0.254)
		(layers "F.Cu" "B.Cu")
		(net "GND")
	)
	(via
		(at 54.424834 -306.824888)
		(size 0.4064)
		(drill 0.2032)
		(layers "F.Cu" "B.Cu")
		(net "GND")
	)
	(via
		(at 135.920226 -122.195844)
		(size 0.508)
		(drill 0.254)
		(layers "F.Cu" "B.Cu")
		(net "GND")
	)
	(via
		(at 370.881402 -34.718498)
		(size 0.508)
		(drill 0.254)
		(layers "F.Cu" "B.Cu")
		(net "GND")
	)
	(via
		(at 125.35916 -344.831162)
		(size 0.4572)
		(drill 0.254)
		(layers "F.Cu" "B.Cu")
		(net "GND")
	)
	(via
		(at 195.415154 -43.85691)
		(size 0.508)
		(drill 0.254)
		(layers "F.Cu" "B.Cu")
		(net "GND")
	)
	(via
		(at 81.974944 -301.124874)
		(size 0.4064)
		(drill 0.2032)
		(layers "F.Cu" "B.Cu")
		(net "GND")
	)
	(via
		(at 238.378746 -91.999308)
		(size 0.508)
		(drill 0.254)
		(layers "F.Cu" "B.Cu")
		(net "GND")
	)
	(via
		(at 411.835092 -345.465146)
		(size 0.4064)
		(drill 0.2032)
		(layers "F.Cu" "B.Cu")
		(net "GND")
	)
	(via
		(at 44.449746 -274.999958)
		(size 0.4064)
		(drill 0.2032)
		(layers "F.Cu" "B.Cu")
		(net "GND")
	)
	(via
		(at 208.79816 -112.799114)
		(size 0.508)
		(drill 0.254)
		(layers "F.Cu" "B.Cu")
		(net "GND")
	)
	(via
		(at 106.229404 -164.84092)
		(size 0.508)
		(drill 0.254)
		(layers "F.Cu" "B.Cu")
		(net "GND")
	)
	(via
		(at 395.12494 -285.924752)
		(size 0.4064)
		(drill 0.2032)
		(layers "F.Cu" "B.Cu")
		(net "GND")
	)
	(via
		(at 67.66687 -114.635026)
		(size 0.508)
		(drill 0.254)
		(layers "F.Cu" "B.Cu")
		(net "GND")
	)
	(via
		(at 30.091888 -351.611438)
		(size 0.4064)
		(drill 0.2032)
		(layers "F.Cu" "B.Cu")
		(net "GND")
	)
	(via
		(at 396.0749 -303.974754)
		(size 0.4064)
		(drill 0.2032)
		(layers "F.Cu" "B.Cu")
		(net "GND")
	)
	(via
		(at 160.549844 -301.599854)
		(size 0.4064)
		(drill 0.2032)
		(layers "F.Cu" "B.Cu")
		(net "GND")
	)
	(via
		(at 50.224436 -347.951806)
		(size 0.4572)
		(drill 0.254)
		(layers "F.Cu" "B.Cu")
		(net "GND")
	)
	(via
		(at 387.006084 -161.276284)
		(size 0.508)
		(drill 0.254)
		(layers "F.Cu" "B.Cu")
		(net "GND")
	)
	(via
		(at 37.133784 -136.901936)
		(size 0.508)
		(drill 0.254)
		(layers "F.Cu" "B.Cu")
		(net "GND")
	)
	(via
		(at 256.154682 -348.674436)
		(size 0.508)
		(drill 0.254)
		(layers "F.Cu" "B.Cu")
		(net "GND")
	)
	(via
		(at 344.119708 -38.701218)
		(size 0.508)
		(drill 0.254)
		(layers "F.Cu" "B.Cu")
		(net "GND")
	)
	(via
		(at 306.099718 -306.349908)
		(size 0.4064)
		(drill 0.2032)
		(layers "F.Cu" "B.Cu")
		(net "GND")
	)
	(via
		(at 79.12481 -296.37482)
		(size 0.4064)
		(drill 0.2032)
		(layers "F.Cu" "B.Cu")
		(net "GND")
	)
	(via
		(at 66.802762 -74.624184)
		(size 0.508)
		(drill 0.254)
		(layers "F.Cu" "B.Cu")
		(net "GND")
	)
	(via
		(at 80.147922 -407.638504)
		(size 0.508)
		(drill 0.254)
		(layers "F.Cu" "B.Cu")
		(net "GND")
	)
	(via
		(at 282.824936 -306.824888)
		(size 0.4064)
		(drill 0.2032)
		(layers "F.Cu" "B.Cu")
		(net "GND")
	)
	(via
		(at 385.433824 -99.116642)
		(size 0.508)
		(drill 0.254)
		(layers "F.Cu" "B.Cu")
		(net "GND")
	)
	(via
		(at 105.012998 -351.764346)
		(size 0.508)
		(drill 0.254)
		(layers "F.Cu" "B.Cu")
		(net "GND")
	)
	(via
		(at 19.134836 -343.073482)
		(size 0.4572)
		(drill 0.254)
		(layers "F.Cu" "B.Cu")
		(net "GND")
	)
	(via
		(at 44.196254 -60.099194)
		(size 0.508)
		(drill 0.254)
		(layers "F.Cu" "B.Cu")
		(net "GND")
	)
	(via
		(at 420.547038 -115.504976)
		(size 0.508)
		(drill 0.254)
		(layers "F.Cu" "B.Cu")
		(net "GND")
	)
	(via
		(at 40.649906 -310.149748)
		(size 0.4064)
		(drill 0.2032)
		(layers "F.Cu" "B.Cu")
		(net "GND")
	)
	(via
		(at 291.32784 -380.141734)
		(size 0.508)
		(drill 0.254)
		(layers "F.Cu" "B.Cu")
		(net "GND")
	)
	(via
		(at 54.348126 -371.930422)
		(size 0.4064)
		(drill 0.2032)
		(layers "F.Cu" "B.Cu")
		(net "GND")
	)
	(via
		(at 158.174944 -276.424898)
		(size 0.4064)
		(drill 0.2032)
		(layers "F.Cu" "B.Cu")
		(net "GND")
	)
	(via
		(at 24.342344 -253.45644)
		(size 0.508)
		(drill 0.254)
		(layers "F.Cu" "B.Cu")
		(net "GND")
	)
	(via
		(at 51.74996 -145.520156)
		(size 0.508)
		(drill 0.254)
		(layers "F.Cu" "B.Cu")
		(net "GND")
	)
	(via
		(at 186.86018 -344.831162)
		(size 0.4572)
		(drill 0.254)
		(layers "F.Cu" "B.Cu")
		(net "GND")
	)
	(via
		(at 290.42487 -283.074872)
		(size 0.4064)
		(drill 0.2032)
		(layers "F.Cu" "B.Cu")
		(net "GND")
	)
	(via
		(at 289.127692 -398.24025)
		(size 0.508)
		(drill 0.254)
		(layers "F.Cu" "B.Cu")
		(net "GND")
	)
	(via
		(at 420.774876 -301.124874)
		(size 0.4064)
		(drill 0.2032)
		(layers "F.Cu" "B.Cu")
		(net "GND")
	)
	(via
		(at 196.18706 -344.831162)
		(size 0.4572)
		(drill 0.254)
		(layers "F.Cu" "B.Cu")
		(net "GND")
	)
	(via
		(at 292.32479 -305.874928)
		(size 0.4064)
		(drill 0.2032)
		(layers "F.Cu" "B.Cu")
		(net "GND")
	)
	(via
		(at 433.96916 -352.245422)
		(size 0.4572)
		(drill 0.254)
		(layers "F.Cu" "B.Cu")
		(net "GND")
	)
	(via
		(at 39.224966 -289.724846)
		(size 0.4064)
		(drill 0.2032)
		(layers "F.Cu" "B.Cu")
		(net "GND")
	)
	(via
		(at 119.747792 -395.938502)
		(size 0.508)
		(drill 0.254)
		(layers "F.Cu" "B.Cu")
		(net "GND")
	)
	(via
		(at 198.550022 -307.299868)
		(size 0.4064)
		(drill 0.2032)
		(layers "F.Cu" "B.Cu")
		(net "GND")
	)
	(via
		(at 379.14326 -52.536852)
		(size 0.508)
		(drill 0.254)
		(layers "F.Cu" "B.Cu")
		(net "GND")
	)
	(via
		(at 292.32479 -300.174914)
		(size 0.4064)
		(drill 0.2032)
		(layers "F.Cu" "B.Cu")
		(net "GND")
	)
	(via
		(at 184.380886 -34.990024)
		(size 0.508)
		(drill 0.254)
		(layers "F.Cu" "B.Cu")
		(net "GND")
	)
	(via
		(at 136.764268 -168.669208)
		(size 0.508)
		(drill 0.254)
		(layers "F.Cu" "B.Cu")
		(net "GND")
	)
	(via
		(at 274.274788 -283.074872)
		(size 0.4064)
		(drill 0.2032)
		(layers "F.Cu" "B.Cu")
		(net "GND")
	)
	(via
		(at 64.77 -108.462318)
		(size 0.508)
		(drill 0.254)
		(layers "F.Cu" "B.Cu")
		(net "GND")
	)
	(via
		(at 427.623224 -56.353456)
		(size 0.508)
		(drill 0.254)
		(layers "F.Cu" "B.Cu")
		(net "GND")
	)
	(via
		(at 38.401752 -135.643112)
		(size 0.508)
		(drill 0.254)
		(layers "F.Cu" "B.Cu")
		(net "GND")
	)
	(via
		(at 334.067912 -357.123746)
		(size 0.4572)
		(drill 0.254)
		(layers "F.Cu" "B.Cu")
		(net "GND")
	)
	(via
		(at 284.249876 -274.999958)
		(size 0.4064)
		(drill 0.2032)
		(layers "F.Cu" "B.Cu")
		(net "GND")
	)
	(via
		(at 179.55006 -281.649932)
		(size 0.4064)
		(drill 0.2032)
		(layers "F.Cu" "B.Cu")
		(net "GND")
	)
	(via
		(at 199.500236 -274.999958)
		(size 0.4064)
		(drill 0.2032)
		(layers "F.Cu" "B.Cu")
		(net "GND")
	)
	(via
		(at 185.783982 -120.716548)
		(size 0.508)
		(drill 0.254)
		(layers "F.Cu" "B.Cu")
		(net "GND")
	)
	(via
		(at 423.163492 -357.75773)
		(size 0.4064)
		(drill 0.2032)
		(layers "F.Cu" "B.Cu")
		(net "GND")
	)
	(via
		(at 71.999856 -310.149748)
		(size 0.4064)
		(drill 0.2032)
		(layers "F.Cu" "B.Cu")
		(net "GND")
	)
	(via
		(at 250.871228 -29.311854)
		(size 0.508)
		(drill 0.254)
		(layers "F.Cu" "B.Cu")
		(net "GND")
	)
	(via
		(at 161.15157 -106.045)
		(size 0.508)
		(drill 0.254)
		(layers "F.Cu" "B.Cu")
		(net "GND")
	)
	(via
		(at 28.557982 -279.931114)
		(size 0.508)
		(drill 0.254)
		(layers "F.Cu" "B.Cu")
		(net "GND")
	)
	(via
		(at 42.074846 -298.27474)
		(size 0.4064)
		(drill 0.2032)
		(layers "F.Cu" "B.Cu")
		(net "GND")
	)
	(via
		(at 254.781304 -31.118302)
		(size 0.508)
		(drill 0.254)
		(layers "F.Cu" "B.Cu")
		(net "GND")
	)
	(via
		(at 67.249802 -314.899802)
		(size 0.4064)
		(drill 0.2032)
		(layers "F.Cu" "B.Cu")
		(net "GND")
	)
	(via
		(at 165.299898 -278.799798)
		(size 0.4064)
		(drill 0.2032)
		(layers "F.Cu" "B.Cu")
		(net "GND")
	)
	(via
		(at 71.347838 -408.840178)
		(size 0.508)
		(drill 0.254)
		(layers "F.Cu" "B.Cu")
		(net "GND")
	)
	(via
		(at 130.318256 -352.245422)
		(size 0.4572)
		(drill 0.254)
		(layers "F.Cu" "B.Cu")
		(net "GND")
	)
	(via
		(at 82.347816 -397.038576)
		(size 0.508)
		(drill 0.254)
		(layers "F.Cu" "B.Cu")
		(net "GND")
	)
	(via
		(at 48.72482 -304.924714)
		(size 0.4064)
		(drill 0.2032)
		(layers "F.Cu" "B.Cu")
		(net "GND")
	)
	(via
		(at 433.108354 -132.77342)
		(size 0.508)
		(drill 0.254)
		(layers "F.Cu" "B.Cu")
		(net "GND")
	)
	(via
		(at 228.131624 -140.922248)
		(size 0.508)
		(drill 0.254)
		(layers "F.Cu" "B.Cu")
		(net "GND")
	)
	(via
		(at 154.375104 -290.674806)
		(size 0.4064)
		(drill 0.2032)
		(layers "F.Cu" "B.Cu")
		(net "GND")
	)
	(via
		(at 46.34992 -279.749758)
		(size 0.4064)
		(drill 0.2032)
		(layers "F.Cu" "B.Cu")
		(net "GND")
	)
	(via
		(at 81.499964 -273.099784)
		(size 0.4064)
		(drill 0.2032)
		(layers "F.Cu" "B.Cu")
		(net "GND")
	)
	(via
		(at 337.5279 -408.738578)
		(size 0.508)
		(drill 0.254)
		(layers "F.Cu" "B.Cu")
		(net "GND")
	)
	(via
		(at 401.70862 -342.439498)
		(size 0.4064)
		(drill 0.2032)
		(layers "F.Cu" "B.Cu")
		(net "GND")
	)
	(via
		(at 279.763982 -342.439498)
		(size 0.4064)
		(drill 0.2032)
		(layers "F.Cu" "B.Cu")
		(net "GND")
	)
	(via
		(at 103.984044 -106.779822)
		(size 0.508)
		(drill 0.254)
		(layers "F.Cu" "B.Cu")
		(net "GND")
	)
	(via
		(at 191.900048 -286.399732)
		(size 0.4064)
		(drill 0.2032)
		(layers "F.Cu" "B.Cu")
		(net "GND")
	)
	(via
		(at 420.516304 -110.12678)
		(size 0.508)
		(drill 0.254)
		(layers "F.Cu" "B.Cu")
		(net "GND")
	)
	(via
		(at 386.574792 -273.574764)
		(size 0.4064)
		(drill 0.2032)
		(layers "F.Cu" "B.Cu")
		(net "GND")
	)
	(via
		(at 448.287648 -122.525028)
		(size 0.508)
		(drill 0.254)
		(layers "F.Cu" "B.Cu")
		(net "GND")
	)
	(via
		(at 325.708518 -223.569022)
		(size 0.508)
		(drill 0.254)
		(layers "F.Cu" "B.Cu")
		(net "GND")
	)
	(via
		(at 52.999894 -273.099784)
		(size 0.4064)
		(drill 0.2032)
		(layers "F.Cu" "B.Cu")
		(net "GND")
	)
	(via
		(at 39.699946 -299.699934)
		(size 0.4064)
		(drill 0.2032)
		(layers "F.Cu" "B.Cu")
		(net "GND")
	)
	(via
		(at 327.849992 -352.245422)
		(size 0.4572)
		(drill 0.254)
		(layers "F.Cu" "B.Cu")
		(net "GND")
	)
	(via
		(at 180.270912 -348.58579)
		(size 0.4064)
		(drill 0.2032)
		(layers "F.Cu" "B.Cu")
		(net "GND")
	)
	(via
		(at 97.25787 -73.85177)
		(size 0.508)
		(drill 0.254)
		(layers "F.Cu" "B.Cu")
		(net "GND")
	)
	(via
		(at 161.617152 -357.75773)
		(size 0.4064)
		(drill 0.2032)
		(layers "F.Cu" "B.Cu")
		(net "GND")
	)
	(via
		(at 64.59347 -151.155146)
		(size 0.508)
		(drill 0.254)
		(layers "F.Cu" "B.Cu")
		(net "GND")
	)
	(via
		(at 404.624794 -284.024832)
		(size 0.4064)
		(drill 0.2032)
		(layers "F.Cu" "B.Cu")
		(net "GND")
	)
	(via
		(at 199.30491 -143.470122)
		(size 0.508)
		(drill 0.254)
		(layers "F.Cu" "B.Cu")
		(net "GND")
	)
	(via
		(at 193.799968 -317.749936)
		(size 0.4064)
		(drill 0.2032)
		(layers "F.Cu" "B.Cu")
		(net "GND")
	)
	(via
		(at 213.741 -192.572894)
		(size 0.508)
		(drill 0.254)
		(layers "F.Cu" "B.Cu")
		(net "GND")
	)
	(via
		(at 111.664496 -349.219774)
		(size 0.4572)
		(drill 0.254)
		(layers "F.Cu" "B.Cu")
		(net "GND")
	)
	(via
		(at 411.275022 -303.974754)
		(size 0.4064)
		(drill 0.2032)
		(layers "F.Cu" "B.Cu")
		(net "GND")
	)
	(via
		(at 210.765136 -181.340506)
		(size 0.508)
		(drill 0.254)
		(layers "F.Cu" "B.Cu")
		(net "GND")
	)
	(via
		(at 105.586784 -193.666364)
		(size 0.508)
		(drill 0.254)
		(layers "F.Cu" "B.Cu")
		(net "GND")
	)
	(via
		(at 452.909178 -108.39196)
		(size 0.508)
		(drill 0.254)
		(layers "F.Cu" "B.Cu")
		(net "GND")
	)
	(via
		(at 50.224436 -343.073482)
		(size 0.4572)
		(drill 0.254)
		(layers "F.Cu" "B.Cu")
		(net "GND")
	)
	(via
		(at 234.267502 -216.304368)
		(size 0.4572)
		(drill 0.254)
		(layers "F.Cu" "B.Cu")
		(net "GND")
	)
	(via
		(at 161.15157 -131.76504)
		(size 0.508)
		(drill 0.254)
		(layers "F.Cu" "B.Cu")
		(net "GND")
	)
	(via
		(at 406.279858 -103.814372)
		(size 0.508)
		(drill 0.254)
		(layers "F.Cu" "B.Cu")
		(net "GND")
	)
	(via
		(at 246.448834 -33.19018)
		(size 0.508)
		(drill 0.254)
		(layers "F.Cu" "B.Cu")
		(net "GND")
	)
	(via
		(at 403.199854 -276.899878)
		(size 0.4064)
		(drill 0.2032)
		(layers "F.Cu" "B.Cu")
		(net "GND")
	)
	(via
		(at 200.908158 -156.283406)
		(size 0.508)
		(drill 0.254)
		(layers "F.Cu" "B.Cu")
		(net "GND")
	)
	(via
		(at 129.349754 -34.990024)
		(size 0.508)
		(drill 0.254)
		(layers "F.Cu" "B.Cu")
		(net "GND")
	)
	(via
		(at 407.949908 -316.799722)
		(size 0.4064)
		(drill 0.2032)
		(layers "F.Cu" "B.Cu")
		(net "GND")
	)
	(via
		(at 46.34992 -307.299868)
		(size 0.4064)
		(drill 0.2032)
		(layers "F.Cu" "B.Cu")
		(net "GND")
	)
	(via
		(at 93.361256 -114.99596)
		(size 0.508)
		(drill 0.254)
		(layers "F.Cu" "B.Cu")
		(net "GND")
	)
	(via
		(at 81.499964 -284.499812)
		(size 0.4064)
		(drill 0.2032)
		(layers "F.Cu" "B.Cu")
		(net "GND")
	)
	(via
		(at 184.29986 -277.849838)
		(size 0.4064)
		(drill 0.2032)
		(layers "F.Cu" "B.Cu")
		(net "GND")
	)
	(via
		(at 51.574954 -303.974754)
		(size 0.4064)
		(drill 0.2032)
		(layers "F.Cu" "B.Cu")
		(net "GND")
	)
	(via
		(at 38.749986 -308.249828)
		(size 0.4064)
		(drill 0.2032)
		(layers "F.Cu" "B.Cu")
		(net "GND")
	)
	(via
		(at 170.049952 -276.899878)
		(size 0.4064)
		(drill 0.2032)
		(layers "F.Cu" "B.Cu")
		(net "GND")
	)
	(via
		(at 81.499964 -280.699718)
		(size 0.4064)
		(drill 0.2032)
		(layers "F.Cu" "B.Cu")
		(net "GND")
	)
	(via
		(at 45.051726 -125.955044)
		(size 0.508)
		(drill 0.254)
		(layers "F.Cu" "B.Cu")
		(net "GND")
	)
	(via
		(at 176.94783 -402.241766)
		(size 0.508)
		(drill 0.254)
		(layers "F.Cu" "B.Cu")
		(net "GND")
	)
	(via
		(at 349.656654 -261.675372)
		(size 0.508)
		(drill 0.254)
		(layers "F.Cu" "B.Cu")
		(net "GND")
	)
	(via
		(at 353.176586 -258.36372)
		(size 0.6604)
		(drill 0.3302)
		(layers "F.Cu" "B.Cu")
		(net "GND")
	)
	(via
		(at 193.0781 -346.09913)
		(size 0.4572)
		(drill 0.254)
		(layers "F.Cu" "B.Cu")
		(net "GND")
	)
	(via
		(at 161.025078 -285.924752)
		(size 0.4064)
		(drill 0.2032)
		(layers "F.Cu" "B.Cu")
		(net "GND")
	)
	(via
		(at 73.899776 -308.249828)
		(size 0.4064)
		(drill 0.2032)
		(layers "F.Cu" "B.Cu")
		(net "GND")
	)
	(via
		(at 300.399704 -318.699896)
		(size 0.4064)
		(drill 0.2032)
		(layers "F.Cu" "B.Cu")
		(net "GND")
	)
	(via
		(at 393.7 -273.099784)
		(size 0.4064)
		(drill 0.2032)
		(layers "F.Cu" "B.Cu")
		(net "GND")
	)
	(via
		(at 358.21874 -305.008534)
		(size 0.508)
		(drill 0.254)
		(layers "F.Cu" "B.Cu")
		(net "GND")
	)
	(via
		(at 289.090862 -348.58579)
		(size 0.4064)
		(drill 0.2032)
		(layers "F.Cu" "B.Cu")
		(net "GND")
	)
	(via
		(at 249.933206 -120.890284)
		(size 0.508)
		(drill 0.254)
		(layers "F.Cu" "B.Cu")
		(net "GND")
	)
	(via
		(at 337.5279 -400.938492)
		(size 0.508)
		(drill 0.254)
		(layers "F.Cu" "B.Cu")
		(net "GND")
	)
	(via
		(at 241.255042 -123.947428)
		(size 0.508)
		(drill 0.254)
		(layers "F.Cu" "B.Cu")
		(net "GND")
	)
	(via
		(at 229.843838 -290.872926)
		(size 0.508)
		(drill 0.254)
		(layers "F.Cu" "B.Cu")
		(net "GND")
	)
	(via
		(at 171.949872 -281.649932)
		(size 0.4064)
		(drill 0.2032)
		(layers "F.Cu" "B.Cu")
		(net "GND")
	)
	(via
		(at 286.927798 -403.738588)
		(size 0.508)
		(drill 0.254)
		(layers "F.Cu" "B.Cu")
		(net "GND")
	)
	(via
		(at 93.43771 -74.624184)
		(size 0.508)
		(drill 0.254)
		(layers "F.Cu" "B.Cu")
		(net "GND")
	)
	(via
		(at 312.541666 -25.971246)
		(size 0.508)
		(drill 0.254)
		(layers "F.Cu" "B.Cu")
		(net "GND")
	)
	(via
		(at 124.100336 -350.977454)
		(size 0.4572)
		(drill 0.254)
		(layers "F.Cu" "B.Cu")
		(net "GND")
	)
	(via
		(at 134.771384 -31.652972)
		(size 0.508)
		(drill 0.254)
		(layers "F.Cu" "B.Cu")
		(net "GND")
	)
	(via
		(at 403.674834 -291.624766)
		(size 0.4064)
		(drill 0.2032)
		(layers "F.Cu" "B.Cu")
		(net "GND")
	)
	(via
		(at 261.351522 -256.375916)
		(size 0.508)
		(drill 0.254)
		(layers "F.Cu" "B.Cu")
		(net "GND")
	)
	(via
		(at 75.339956 -73.23963)
		(size 0.508)
		(drill 0.254)
		(layers "F.Cu" "B.Cu")
		(net "GND")
	)
	(via
		(at 154.375104 -292.57498)
		(size 0.4064)
		(drill 0.2032)
		(layers "F.Cu" "B.Cu")
		(net "GND")
	)
	(via
		(at 266.691618 -120.28551)
		(size 0.508)
		(drill 0.254)
		(layers "F.Cu" "B.Cu")
		(net "GND")
	)
	(via
		(at 23.50262 -347.92793)
		(size 0.4572)
		(drill 0.254)
		(layers "F.Cu" "B.Cu")
		(net "GND")
	)
	(via
		(at 179.07508 -287.824926)
		(size 0.4064)
		(drill 0.2032)
		(layers "F.Cu" "B.Cu")
		(net "GND")
	)
	(via
		(at 119.747792 -403.738588)
		(size 0.508)
		(drill 0.254)
		(layers "F.Cu" "B.Cu")
		(net "GND")
	)
	(via
		(at 81.499964 -317.749936)
		(size 0.4064)
		(drill 0.2032)
		(layers "F.Cu" "B.Cu")
		(net "GND")
	)
	(via
		(at 432.12766 -369.938554)
		(size 0.508)
		(drill 0.254)
		(layers "F.Cu" "B.Cu")
		(net "GND")
	)
	(via
		(at 453.623172 -56.353456)
		(size 0.508)
		(drill 0.254)
		(layers "F.Cu" "B.Cu")
		(net "GND")
	)
	(via
		(at 119.809768 -289.41649)
		(size 0.508)
		(drill 0.254)
		(layers "F.Cu" "B.Cu")
		(net "GND")
	)
	(via
		(at 313.224926 -303.974754)
		(size 0.4064)
		(drill 0.2032)
		(layers "F.Cu" "B.Cu")
		(net "GND")
	)
	(via
		(at 258.805426 -241.686588)
		(size 0.508)
		(drill 0.254)
		(layers "F.Cu" "B.Cu")
		(net "GND")
	)
	(via
		(at 122.2502 -355.366066)
		(size 0.4572)
		(drill 0.254)
		(layers "F.Cu" "B.Cu")
		(net "GND")
	)
	(via
		(at 313.699906 -278.799798)
		(size 0.4064)
		(drill 0.2032)
		(layers "F.Cu" "B.Cu")
		(net "GND")
	)
	(via
		(at 70.574916 -284.024832)
		(size 0.4064)
		(drill 0.2032)
		(layers "F.Cu" "B.Cu")
		(net "GND")
	)
	(via
		(at 168.952164 -109.644942)
		(size 0.508)
		(drill 0.254)
		(layers "F.Cu" "B.Cu")
		(net "GND")
	)
	(via
		(at 29.54782 -404.838662)
		(size 0.508)
		(drill 0.254)
		(layers "F.Cu" "B.Cu")
		(net "GND")
	)
	(via
		(at 436.527702 -395.938502)
		(size 0.508)
		(drill 0.254)
		(layers "F.Cu" "B.Cu")
		(net "GND")
	)
	(via
		(at 158.380938 -27.79014)
		(size 0.508)
		(drill 0.254)
		(layers "F.Cu" "B.Cu")
		(net "GND")
	)
	(via
		(at 186.2963 -60.099194)
		(size 0.508)
		(drill 0.254)
		(layers "F.Cu" "B.Cu")
		(net "GND")
	)
	(via
		(at 9.358122 -143.051276)
		(size 0.508)
		(drill 0.254)
		(layers "F.Cu" "B.Cu")
		(net "GND")
	)
	(via
		(at 165.09746 -341.805514)
		(size 0.4572)
		(drill 0.254)
		(layers "F.Cu" "B.Cu")
		(net "GND")
	)
	(via
		(at 168.625012 -293.52494)
		(size 0.4064)
		(drill 0.2032)
		(layers "F.Cu" "B.Cu")
		(net "GND")
	)
	(via
		(at 73.547732 -371.038628)
		(size 0.508)
		(drill 0.254)
		(layers "F.Cu" "B.Cu")
		(net "GND")
	)
	(via
		(at 65.824862 -285.924752)
		(size 0.4064)
		(drill 0.2032)
		(layers "F.Cu" "B.Cu")
		(net "GND")
	)
	(via
		(at 142.754096 -341.805514)
		(size 0.4572)
		(drill 0.254)
		(layers "F.Cu" "B.Cu")
		(net "GND")
	)
	(via
		(at 227.207826 -108.445808)
		(size 0.508)
		(drill 0.254)
		(layers "F.Cu" "B.Cu")
		(net "GND")
	)
	(via
		(at 85.674962 -342.439498)
		(size 0.4064)
		(drill 0.2032)
		(layers "F.Cu" "B.Cu")
		(net "GND")
	)
	(via
		(at 415.549842 -319.65011)
		(size 0.4064)
		(drill 0.2032)
		(layers "F.Cu" "B.Cu")
		(net "GND")
	)
	(via
		(at 401.623276 -51.019456)
		(size 0.508)
		(drill 0.254)
		(layers "F.Cu" "B.Cu")
		(net "GND")
	)
	(via
		(at 445.382396 -137.845546)
		(size 0.508)
		(drill 0.254)
		(layers "F.Cu" "B.Cu")
		(net "GND")
	)
	(via
		(at 284.724856 -300.174914)
		(size 0.4064)
		(drill 0.2032)
		(layers "F.Cu" "B.Cu")
		(net "GND")
	)
	(via
		(at 63.957708 -209.328512)
		(size 0.508)
		(drill 0.254)
		(layers "F.Cu" "B.Cu")
		(net "GND")
	)
	(via
		(at 217.46083 -172.183298)
		(size 0.508)
		(drill 0.254)
		(layers "F.Cu" "B.Cu")
		(net "GND")
	)
	(via
		(at 115.34775 -404.940262)
		(size 0.4572)
		(drill 0.254)
		(layers "F.Cu" "B.Cu")
		(net "GND")
	)
	(via
		(at 55.374794 -285.924752)
		(size 0.4064)
		(drill 0.2032)
		(layers "F.Cu" "B.Cu")
		(net "GND")
	)
	(via
		(at 37.00018 -151.78532)
		(size 0.508)
		(drill 0.254)
		(layers "F.Cu" "B.Cu")
		(net "GND")
	)
	(via
		(at 158.380938 -34.990024)
		(size 0.508)
		(drill 0.254)
		(layers "F.Cu" "B.Cu")
		(net "GND")
	)
	(via
		(at 293.527734 -398.24025)
		(size 0.508)
		(drill 0.254)
		(layers "F.Cu" "B.Cu")
		(net "GND")
	)
	(via
		(at 79.59979 -312.999882)
		(size 0.4064)
		(drill 0.2032)
		(layers "F.Cu" "B.Cu")
		(net "GND")
	)
	(via
		(at 167.200072 -318.699896)
		(size 0.4064)
		(drill 0.2032)
		(layers "F.Cu" "B.Cu")
		(net "GND")
	)
	(via
		(at 169.836846 -15.474188)
		(size 0.508)
		(drill 0.254)
		(layers "F.Cu" "B.Cu")
		(net "GND")
	)
	(via
		(at 9.648952 -33.19018)
		(size 0.508)
		(drill 0.254)
		(layers "F.Cu" "B.Cu")
		(net "GND")
	)
	(via
		(at 75.74788 -369.938554)
		(size 0.508)
		(drill 0.254)
		(layers "F.Cu" "B.Cu")
		(net "GND")
	)
	(via
		(at 301.837344 -125.752352)
		(size 0.508)
		(drill 0.254)
		(layers "F.Cu" "B.Cu")
		(net "GND")
	)
	(via
		(at 274.749768 -300.649894)
		(size 0.4064)
		(drill 0.2032)
		(layers "F.Cu" "B.Cu")
		(net "GND")
	)
	(via
		(at 331.421994 -52.51704)
		(size 0.508)
		(drill 0.254)
		(layers "F.Cu" "B.Cu")
		(net "GND")
	)
	(via
		(at 440.35853 -307.889656)
		(size 0.508)
		(drill 0.254)
		(layers "F.Cu" "B.Cu")
		(net "GND")
	)
	(via
		(at 177.529744 -172.329348)
		(size 0.508)
		(drill 0.254)
		(layers "F.Cu" "B.Cu")
		(net "GND")
	)
	(via
		(at 424.64228 -347.951806)
		(size 0.4572)
		(drill 0.254)
		(layers "F.Cu" "B.Cu")
		(net "GND")
	)
	(via
		(at 0.77089 -253.501144)
		(size 0.508)
		(drill 0.254)
		(layers "F.Cu" "B.Cu")
		(net "GND")
	)
	(via
		(at 37.744908 -27.79014)
		(size 0.508)
		(drill 0.254)
		(layers "F.Cu" "B.Cu")
		(net "GND")
	)
	(via
		(at 196.998336 -118.498112)
		(size 0.508)
		(drill 0.254)
		(layers "F.Cu" "B.Cu")
		(net "GND")
	)
	(via
		(at 421.724836 -294.4749)
		(size 0.4064)
		(drill 0.2032)
		(layers "F.Cu" "B.Cu")
		(net "GND")
	)
	(via
		(at 121.210324 -305.008534)
		(size 0.508)
		(drill 0.254)
		(layers "F.Cu" "B.Cu")
		(net "GND")
	)
	(via
		(at 337.5279 -377.341892)
		(size 0.508)
		(drill 0.254)
		(layers "F.Cu" "B.Cu")
		(net "GND")
	)
	(via
		(at 190.950088 -305.399948)
		(size 0.4064)
		(drill 0.2032)
		(layers "F.Cu" "B.Cu")
		(net "GND")
	)
	(via
		(at 392.52779 -372.342156)
		(size 0.508)
		(drill 0.254)
		(layers "F.Cu" "B.Cu")
		(net "GND")
	)
	(via
		(at 228.317552 -111.153956)
		(size 0.508)
		(drill 0.254)
		(layers "F.Cu" "B.Cu")
		(net "GND")
	)
	(via
		(at 74.849736 -282.599892)
		(size 0.4064)
		(drill 0.2032)
		(layers "F.Cu" "B.Cu")
		(net "GND")
	)
	(via
		(at 400.60118 -342.439498)
		(size 0.4064)
		(drill 0.2032)
		(layers "F.Cu" "B.Cu")
		(net "GND")
	)
	(via
		(at 117.547644 -385.141978)
		(size 0.4572)
		(drill 0.254)
		(layers "F.Cu" "B.Cu")
		(net "GND")
	)
	(via
		(at 312.274712 -302.074834)
		(size 0.4064)
		(drill 0.2032)
		(layers "F.Cu" "B.Cu")
		(net "GND")
	)
	(via
		(at 423.15003 -286.399732)
		(size 0.4064)
		(drill 0.2032)
		(layers "F.Cu" "B.Cu")
		(net "GND")
	)
	(via
		(at 186.675014 -303.024794)
		(size 0.4064)
		(drill 0.2032)
		(layers "F.Cu" "B.Cu")
		(net "GND")
	)
	(via
		(at 7.319772 -173.263306)
		(size 0.508)
		(drill 0.254)
		(layers "F.Cu" "B.Cu")
		(net "GND")
	)
	(via
		(at 420.567104 -123.635008)
		(size 0.508)
		(drill 0.254)
		(layers "F.Cu" "B.Cu")
		(net "GND")
	)
	(via
		(at 393.7 -305.399948)
		(size 0.4064)
		(drill 0.2032)
		(layers "F.Cu" "B.Cu")
		(net "GND")
	)
	(via
		(at 308.174898 -73.87463)
		(size 0.508)
		(drill 0.254)
		(layers "F.Cu" "B.Cu")
		(net "GND")
	)
	(via
		(at 141.275308 -354.732082)
		(size 0.4064)
		(drill 0.2032)
		(layers "F.Cu" "B.Cu")
		(net "GND")
	)
	(via
		(at 149.586442 -253.45644)
		(size 0.508)
		(drill 0.254)
		(layers "F.Cu" "B.Cu")
		(net "GND")
	)
	(via
		(at 269.524734 -280.224738)
		(size 0.4064)
		(drill 0.2032)
		(layers "F.Cu" "B.Cu")
		(net "GND")
	)
	(via
		(at 101.527864 -328.980292)
		(size 0.508)
		(drill 0.254)
		(layers "F.Cu" "B.Cu")
		(net "GND")
	)
	(via
		(at 51.574954 -285.924752)
		(size 0.4064)
		(drill 0.2032)
		(layers "F.Cu" "B.Cu")
		(net "GND")
	)
	(via
		(at 203.748894 -31.390082)
		(size 0.508)
		(drill 0.254)
		(layers "F.Cu" "B.Cu")
		(net "GND")
	)
	(via
		(at 6.558026 -140.392404)
		(size 0.508)
		(drill 0.254)
		(layers "F.Cu" "B.Cu")
		(net "GND")
	)
	(via
		(at 69.149976 -276.899878)
		(size 0.4064)
		(drill 0.2032)
		(layers "F.Cu" "B.Cu")
		(net "GND")
	)
	(via
		(at 184.77484 -306.824888)
		(size 0.4064)
		(drill 0.2032)
		(layers "F.Cu" "B.Cu")
		(net "GND")
	)
	(via
		(at 344.23477 -142.502128)
		(size 0.508)
		(drill 0.254)
		(layers "F.Cu" "B.Cu")
		(net "GND")
	)
	(via
		(at 62.974982 -300.174914)
		(size 0.4064)
		(drill 0.2032)
		(layers "F.Cu" "B.Cu")
		(net "GND")
	)
	(via
		(at 47.032926 -98.845116)
		(size 0.508)
		(drill 0.254)
		(layers "F.Cu" "B.Cu")
		(net "GND")
	)
	(via
		(at 150.103078 -290.294314)
		(size 0.508)
		(drill 0.254)
		(layers "F.Cu" "B.Cu")
		(net "GND")
	)
	(via
		(at 261.705852 -353.465638)
		(size 0.508)
		(drill 0.254)
		(layers "F.Cu" "B.Cu")
		(net "GND")
	)
	(via
		(at 285.052262 -111.44504)
		(size 0.508)
		(drill 0.254)
		(layers "F.Cu" "B.Cu")
		(net "GND")
	)
	(via
		(at 176.94783 -407.638504)
		(size 0.508)
		(drill 0.254)
		(layers "F.Cu" "B.Cu")
		(net "GND")
	)
	(via
		(at 420.573962 -73.85177)
		(size 0.508)
		(drill 0.254)
		(layers "F.Cu" "B.Cu")
		(net "GND")
	)
	(via
		(at 76.71943 -352.245422)
		(size 0.4572)
		(drill 0.254)
		(layers "F.Cu" "B.Cu")
		(net "GND")
	)
	(via
		(at 137.795 -358.391714)
		(size 0.4572)
		(drill 0.254)
		(layers "F.Cu" "B.Cu")
		(net "GND")
	)
	(via
		(at 196.174868 -292.574726)
		(size 0.4064)
		(drill 0.2032)
		(layers "F.Cu" "B.Cu")
		(net "GND")
	)
	(via
		(at 285.674816 -284.974792)
		(size 0.4064)
		(drill 0.2032)
		(layers "F.Cu" "B.Cu")
		(net "GND")
	)
	(via
		(at 399.874994 -289.724846)
		(size 0.4064)
		(drill 0.2032)
		(layers "F.Cu" "B.Cu")
		(net "GND")
	)
	(via
		(at 27.390344 -253.45644)
		(size 0.508)
		(drill 0.254)
		(layers "F.Cu" "B.Cu")
		(net "GND")
	)
	(via
		(at 10.069322 -141.019276)
		(size 0.508)
		(drill 0.254)
		(layers "F.Cu" "B.Cu")
		(net "GND")
	)
	(via
		(at 206.49692 -209.338164)
		(size 0.508)
		(drill 0.254)
		(layers "F.Cu" "B.Cu")
		(net "GND")
	)
	(via
		(at 441.094368 -123.84278)
		(size 0.508)
		(drill 0.254)
		(layers "F.Cu" "B.Cu")
		(net "GND")
	)
	(via
		(at 14.320774 -280.6954)
		(size 0.508)
		(drill 0.254)
		(layers "F.Cu" "B.Cu")
		(net "GND")
	)
	(via
		(at 363.478826 -110.365032)
		(size 0.508)
		(drill 0.254)
		(layers "F.Cu" "B.Cu")
		(net "GND")
	)
	(via
		(at 433.597812 -354.732082)
		(size 0.4064)
		(drill 0.2032)
		(layers "F.Cu" "B.Cu")
		(net "GND")
	)
	(via
		(at 5.46862 -59.974734)
		(size 0.508)
		(drill 0.254)
		(layers "F.Cu" "B.Cu")
		(net "GND")
	)
	(via
		(at 433.96916 -347.951806)
		(size 0.4572)
		(drill 0.254)
		(layers "F.Cu" "B.Cu")
		(net "GND")
	)
	(via
		(at 340.926928 -0.762)
		(size 0.508)
		(drill 0.254)
		(layers "F.Cu" "B.Cu")
		(net "GND")
	)
	(via
		(at 1.538986 -277.358856)
		(size 0.508)
		(drill 0.254)
		(layers "F.Cu" "B.Cu")
		(net "GND")
	)
	(via
		(at 283.774896 -294.4749)
		(size 0.4064)
		(drill 0.2032)
		(layers "F.Cu" "B.Cu")
		(net "GND")
	)
	(via
		(at 123.19127 -167.581834)
		(size 0.508)
		(drill 0.254)
		(layers "F.Cu" "B.Cu")
		(net "GND")
	)
	(via
		(at 30.20822 -52.536852)
		(size 0.508)
		(drill 0.254)
		(layers "F.Cu" "B.Cu")
		(net "GND")
	)
	(via
		(at 183.3499 -319.65011)
		(size 0.4064)
		(drill 0.2032)
		(layers "F.Cu" "B.Cu")
		(net "GND")
	)
	(via
		(at 248.581672 -133.972046)
		(size 0.508)
		(drill 0.254)
		(layers "F.Cu" "B.Cu")
		(net "GND")
	)
	(via
		(at 163.747958 -378.94006)
		(size 0.508)
		(drill 0.254)
		(layers "F.Cu" "B.Cu")
		(net "GND")
	)
	(via
		(at 431.840386 -136.373362)
		(size 0.508)
		(drill 0.254)
		(layers "F.Cu" "B.Cu")
		(net "GND")
	)
	(via
		(at 158.174944 -279.274778)
		(size 0.4064)
		(drill 0.2032)
		(layers "F.Cu" "B.Cu")
		(net "GND")
	)
	(via
		(at 292.199822 -345.465146)
		(size 0.4064)
		(drill 0.2032)
		(layers "F.Cu" "B.Cu")
		(net "GND")
	)
	(via
		(at 312.871866 -49.574704)
		(size 0.508)
		(drill 0.254)
		(layers "F.Cu" "B.Cu")
		(net "GND")
	)
	(via
		(at 391.799826 -318.699896)
		(size 0.4064)
		(drill 0.2032)
		(layers "F.Cu" "B.Cu")
		(net "GND")
	)
	(via
		(at 177.649886 -312.049922)
		(size 0.4064)
		(drill 0.2032)
		(layers "F.Cu" "B.Cu")
		(net "GND")
	)
	(via
		(at 299.512736 -102.439978)
		(size 0.508)
		(drill 0.254)
		(layers "F.Cu" "B.Cu")
		(net "GND")
	)
	(via
		(at 294.22471 -289.724846)
		(size 0.4064)
		(drill 0.2032)
		(layers "F.Cu" "B.Cu")
		(net "GND")
	)
	(via
		(at 75.32497 -298.27474)
		(size 0.4064)
		(drill 0.2032)
		(layers "F.Cu" "B.Cu")
		(net "GND")
	)
	(via
		(at 27.347926 -397.140176)
		(size 0.508)
		(drill 0.254)
		(layers "F.Cu" "B.Cu")
		(net "GND")
	)
	(via
		(at 83.400138 -304.449734)
		(size 0.4064)
		(drill 0.2032)
		(layers "F.Cu" "B.Cu")
		(net "GND")
	)
	(via
		(at 418.42436 -352.245422)
		(size 0.4572)
		(drill 0.254)
		(layers "F.Cu" "B.Cu")
		(net "GND")
	)
	(via
		(at 400.2913 -168.397174)
		(size 0.508)
		(drill 0.254)
		(layers "F.Cu" "B.Cu")
		(net "GND")
	)
	(via
		(at 440.34964 -303.026826)
		(size 0.508)
		(drill 0.254)
		(layers "F.Cu" "B.Cu")
		(net "GND")
	)
	(via
		(at 185.783982 -124.31649)
		(size 0.508)
		(drill 0.254)
		(layers "F.Cu" "B.Cu")
		(net "GND")
	)
	(via
		(at 35.93846 -358.391714)
		(size 0.4572)
		(drill 0.254)
		(layers "F.Cu" "B.Cu")
		(net "GND")
	)
	(via
		(at 174.747936 -408.738578)
		(size 0.508)
		(drill 0.254)
		(layers "F.Cu" "B.Cu")
		(net "GND")
	)
	(via
		(at 115.34775 -406.141936)
		(size 0.4572)
		(drill 0.254)
		(layers "F.Cu" "B.Cu")
		(net "GND")
	)
	(via
		(at 337.5279 -380.040134)
		(size 0.508)
		(drill 0.254)
		(layers "F.Cu" "B.Cu")
		(net "GND")
	)
	(via
		(at 231.067356 -213.904322)
		(size 0.4572)
		(drill 0.254)
		(layers "F.Cu" "B.Cu")
		(net "GND")
	)
	(via
		(at 168.952164 -133.564884)
		(size 0.508)
		(drill 0.254)
		(layers "F.Cu" "B.Cu")
		(net "GND")
	)
	(via
		(at 397.640048 -74.58583)
		(size 0.508)
		(drill 0.254)
		(layers "F.Cu" "B.Cu")
		(net "GND")
	)
	(via
		(at 295.68013 -357.123746)
		(size 0.4572)
		(drill 0.254)
		(layers "F.Cu" "B.Cu")
		(net "GND")
	)
	(via
		(at 73.899776 -284.499812)
		(size 0.4064)
		(drill 0.2032)
		(layers "F.Cu" "B.Cu")
		(net "GND")
	)
	(via
		(at 42.074846 -276.424898)
		(size 0.4064)
		(drill 0.2032)
		(layers "F.Cu" "B.Cu")
		(net "GND")
	)
	(via
		(at 153.233628 -133.301994)
		(size 0.508)
		(drill 0.254)
		(layers "F.Cu" "B.Cu")
		(net "GND")
	)
	(via
		(at 420.297864 -133.472682)
		(size 0.508)
		(drill 0.254)
		(layers "F.Cu" "B.Cu")
		(net "GND")
	)
	(via
		(at 310.751474 -98.021648)
		(size 0.508)
		(drill 0.254)
		(layers "F.Cu" "B.Cu")
		(net "GND")
	)
	(via
		(at 392.75004 -319.65011)
		(size 0.4064)
		(drill 0.2032)
		(layers "F.Cu" "B.Cu")
		(net "GND")
	)
	(via
		(at 320.153284 -351.611438)
		(size 0.4064)
		(drill 0.2032)
		(layers "F.Cu" "B.Cu")
		(net "GND")
	)
	(via
		(at 270.474948 -286.874966)
		(size 0.4064)
		(drill 0.2032)
		(layers "F.Cu" "B.Cu")
		(net "GND")
	)
	(via
		(at 181.901084 -358.391714)
		(size 0.4572)
		(drill 0.254)
		(layers "F.Cu" "B.Cu")
		(net "GND")
	)
	(via
		(at 16.280892 -29.589984)
		(size 0.508)
		(drill 0.254)
		(layers "F.Cu" "B.Cu")
		(net "GND")
	)
	(via
		(at 370.385848 -102.456996)
		(size 0.508)
		(drill 0.254)
		(layers "F.Cu" "B.Cu")
		(net "GND")
	)
	(via
		(at 440.18708 -350.977454)
		(size 0.4572)
		(drill 0.254)
		(layers "F.Cu" "B.Cu")
		(net "GND")
	)
	(via
		(at 70.50151 -343.073482)
		(size 0.4572)
		(drill 0.254)
		(layers "F.Cu" "B.Cu")
		(net "GND")
	)
	(via
		(at 104.585516 -120.526302)
		(size 0.508)
		(drill 0.254)
		(layers "F.Cu" "B.Cu")
		(net "GND")
	)
	(via
		(at 445.368172 -48.753014)
		(size 0.508)
		(drill 0.254)
		(layers "F.Cu" "B.Cu")
		(net "GND")
	)
	(via
		(at 263.654286 -253.45644)
		(size 0.508)
		(drill 0.254)
		(layers "F.Cu" "B.Cu")
		(net "GND")
	)
	(via
		(at 194.651376 -102.088696)
		(size 0.508)
		(drill 0.254)
		(layers "F.Cu" "B.Cu")
		(net "GND")
	)
	(via
		(at 333.117952 -121.80824)
		(size 0.508)
		(drill 0.254)
		(layers "F.Cu" "B.Cu")
		(net "GND")
	)
	(via
		(at 105.22585 -129.722118)
		(size 0.508)
		(drill 0.254)
		(layers "F.Cu" "B.Cu")
		(net "GND")
	)
	(via
		(at 416.499802 -310.149748)
		(size 0.4064)
		(drill 0.2032)
		(layers "F.Cu" "B.Cu")
		(net "GND")
	)
	(via
		(at 313.699906 -315.849762)
		(size 0.4064)
		(drill 0.2032)
		(layers "F.Cu" "B.Cu")
		(net "GND")
	)
	(via
		(at 115.24234 -258.78155)
		(size 0.508)
		(drill 0.254)
		(layers "F.Cu" "B.Cu")
		(net "GND")
	)
	(via
		(at 205.898242 -19.096736)
		(size 0.508)
		(drill 0.254)
		(layers "F.Cu" "B.Cu")
		(net "GND")
	)
	(via
		(at 435.227984 -355.366066)
		(size 0.4572)
		(drill 0.254)
		(layers "F.Cu" "B.Cu")
		(net "GND")
	)
	(via
		(at 279.499822 -313.949842)
		(size 0.4064)
		(drill 0.2032)
		(layers "F.Cu" "B.Cu")
		(net "GND")
	)
	(via
		(at 297.074844 -298.27474)
		(size 0.4064)
		(drill 0.2032)
		(layers "F.Cu" "B.Cu")
		(net "GND")
	)
	(via
		(at 397.729202 -107.407456)
		(size 0.508)
		(drill 0.254)
		(layers "F.Cu" "B.Cu")
		(net "GND")
	)
	(via
		(at 66.299842 -281.649932)
		(size 0.4064)
		(drill 0.2032)
		(layers "F.Cu" "B.Cu")
		(net "GND")
	)
	(via
		(at 385.624578 -300.174914)
		(size 0.4064)
		(drill 0.2032)
		(layers "F.Cu" "B.Cu")
		(net "GND")
	)
	(via
		(at 429.927766 -400.938492)
		(size 0.508)
		(drill 0.254)
		(layers "F.Cu" "B.Cu")
		(net "GND")
	)
	(via
		(at 393.368276 -48.753014)
		(size 0.508)
		(drill 0.254)
		(layers "F.Cu" "B.Cu")
		(net "GND")
	)
	(via
		(at 1.551432 -270.590772)
		(size 0.508)
		(drill 0.254)
		(layers "F.Cu" "B.Cu")
		(net "GND")
	)
	(via
		(at 279.024842 -303.974754)
		(size 0.4064)
		(drill 0.2032)
		(layers "F.Cu" "B.Cu")
		(net "GND")
	)
	(via
		(at 77.69987 -278.799798)
		(size 0.4064)
		(drill 0.2032)
		(layers "F.Cu" "B.Cu")
		(net "GND")
	)
	(via
		(at 108.142786 -220.959934)
		(size 0.508)
		(drill 0.254)
		(layers "F.Cu" "B.Cu")
		(net "GND")
	)
	(via
		(at 167.200072 -317.749936)
		(size 0.4064)
		(drill 0.2032)
		(layers "F.Cu" "B.Cu")
		(net "GND")
	)
	(via
		(at 272.067274 -357.123746)
		(size 0.4572)
		(drill 0.254)
		(layers "F.Cu" "B.Cu")
		(net "GND")
	)
	(via
		(at 69.624956 -306.824888)
		(size 0.4064)
		(drill 0.2032)
		(layers "F.Cu" "B.Cu")
		(net "GND")
	)
	(via
		(at 76.749656 -274.999958)
		(size 0.4064)
		(drill 0.2032)
		(layers "F.Cu" "B.Cu")
		(net "GND")
	)
	(via
		(at 416.945572 -348.58579)
		(size 0.4064)
		(drill 0.2032)
		(layers "F.Cu" "B.Cu")
		(net "GND")
	)
	(via
		(at 289.47491 -300.174914)
		(size 0.4064)
		(drill 0.2032)
		(layers "F.Cu" "B.Cu")
		(net "GND")
	)
	(via
		(at 344.127836 -380.141734)
		(size 0.508)
		(drill 0.254)
		(layers "F.Cu" "B.Cu")
		(net "GND")
	)
	(via
		(at 164.681408 -29.859478)
		(size 0.508)
		(drill 0.254)
		(layers "F.Cu" "B.Cu")
		(net "GND")
	)
	(via
		(at 52.524914 -285.924752)
		(size 0.4064)
		(drill 0.2032)
		(layers "F.Cu" "B.Cu")
		(net "GND")
	)
	(via
		(at 337.925156 -78.754732)
		(size 0.508)
		(drill 0.254)
		(layers "F.Cu" "B.Cu")
		(net "GND")
	)
	(via
		(at 289.127692 -381.241808)
		(size 0.508)
		(drill 0.254)
		(layers "F.Cu" "B.Cu")
		(net "GND")
	)
	(via
		(at 401.15236 -135.364982)
		(size 0.508)
		(drill 0.254)
		(layers "F.Cu" "B.Cu")
		(net "GND")
	)
	(via
		(at 183.766714 -121.83491)
		(size 0.508)
		(drill 0.254)
		(layers "F.Cu" "B.Cu")
		(net "GND")
	)
	(via
		(at 346.327984 -397.038576)
		(size 0.508)
		(drill 0.254)
		(layers "F.Cu" "B.Cu")
		(net "GND")
	)
	(via
		(at 345.024964 -345.465146)
		(size 0.4064)
		(drill 0.2032)
		(layers "F.Cu" "B.Cu")
		(net "GND")
	)
	(via
		(at 48.72482 -284.024832)
		(size 0.4064)
		(drill 0.2032)
		(layers "F.Cu" "B.Cu")
		(net "GND")
	)
	(via
		(at 417.937442 -125.752352)
		(size 0.508)
		(drill 0.254)
		(layers "F.Cu" "B.Cu")
		(net "GND")
	)
	(via
		(at 392.274806 -284.024832)
		(size 0.4064)
		(drill 0.2032)
		(layers "F.Cu" "B.Cu")
		(net "GND")
	)
	(via
		(at 29.54782 -378.83846)
		(size 0.508)
		(drill 0.254)
		(layers "F.Cu" "B.Cu")
		(net "GND")
	)
	(via
		(at 93.894402 -348.58579)
		(size 0.4064)
		(drill 0.2032)
		(layers "F.Cu" "B.Cu")
		(net "GND")
	)
	(via
		(at 454.376536 -15.207234)
		(size 0.508)
		(drill 0.254)
		(layers "F.Cu" "B.Cu")
		(net "GND")
	)
	(via
		(at 161.15157 -109.644942)
		(size 0.508)
		(drill 0.254)
		(layers "F.Cu" "B.Cu")
		(net "GND")
	)
	(via
		(at 393.954762 -23.880318)
		(size 0.508)
		(drill 0.254)
		(layers "F.Cu" "B.Cu")
		(net "GND")
	)
	(via
		(at 189.999874 -307.299868)
		(size 0.4064)
		(drill 0.2032)
		(layers "F.Cu" "B.Cu")
		(net "GND")
	)
	(via
		(at 166.249858 -280.699718)
		(size 0.4064)
		(drill 0.2032)
		(layers "F.Cu" "B.Cu")
		(net "GND")
	)
	(via
		(at 341.694008 -221.986856)
		(size 0.4572)
		(drill 0.254)
		(layers "F.Cu" "B.Cu")
		(net "GND")
	)
	(via
		(at 320.79819 -385.942586)
		(size 0.508)
		(drill 0.254)
		(layers "F.Cu" "B.Cu")
		(net "GND")
	)
	(via
		(at 414.599882 -318.699896)
		(size 0.4064)
		(drill 0.2032)
		(layers "F.Cu" "B.Cu")
		(net "GND")
	)
	(via
		(at 53.48732 -106.044746)
		(size 0.508)
		(drill 0.254)
		(layers "F.Cu" "B.Cu")
		(net "GND")
	)
	(via
		(at 311.324752 -290.674806)
		(size 0.4064)
		(drill 0.2032)
		(layers "F.Cu" "B.Cu")
		(net "GND")
	)
	(via
		(at 433.146962 -1.13538)
		(size 0.508)
		(drill 0.254)
		(layers "F.Cu" "B.Cu")
		(net "GND")
	)
	(via
		(at 197.125082 -298.27474)
		(size 0.4064)
		(drill 0.2032)
		(layers "F.Cu" "B.Cu")
		(net "GND")
	)
	(via
		(at 221.674944 -97.31375)
		(size 0.508)
		(drill 0.254)
		(layers "F.Cu" "B.Cu")
		(net "GND")
	)
	(via
		(at 162.924998 -303.024794)
		(size 0.4064)
		(drill 0.2032)
		(layers "F.Cu" "B.Cu")
		(net "GND")
	)
	(via
		(at 230.892096 -149.039072)
		(size 0.508)
		(drill 0.254)
		(layers "F.Cu" "B.Cu")
		(net "GND")
	)
	(via
		(at 443.773306 -73.20026)
		(size 0.508)
		(drill 0.254)
		(layers "F.Cu" "B.Cu")
		(net "GND")
	)
	(via
		(at 287.099756 -314.899802)
		(size 0.4064)
		(drill 0.2032)
		(layers "F.Cu" "B.Cu")
		(net "GND")
	)
	(via
		(at 23.873968 -351.611438)
		(size 0.4064)
		(drill 0.2032)
		(layers "F.Cu" "B.Cu")
		(net "GND")
	)
	(via
		(at 63.798196 -21.738336)
		(size 0.508)
		(drill 0.254)
		(layers "F.Cu" "B.Cu")
		(net "GND")
	)
	(via
		(at 177.174906 -284.974792)
		(size 0.4064)
		(drill 0.2032)
		(layers "F.Cu" "B.Cu")
		(net "GND")
	)
	(via
		(at 412.89351 -134.845044)
		(size 0.508)
		(drill 0.254)
		(layers "F.Cu" "B.Cu")
		(net "GND")
	)
	(via
		(at 264.986008 -229.235254)
		(size 0.508)
		(drill 0.254)
		(layers "F.Cu" "B.Cu")
		(net "GND")
	)
	(via
		(at 418.441124 -38.49116)
		(size 0.508)
		(drill 0.254)
		(layers "F.Cu" "B.Cu")
		(net "GND")
	)
	(via
		(at 252.020324 -122.195844)
		(size 0.508)
		(drill 0.254)
		(layers "F.Cu" "B.Cu")
		(net "GND")
	)
	(via
		(at 304.527712 -375.040398)
		(size 0.508)
		(drill 0.254)
		(layers "F.Cu" "B.Cu")
		(net "GND")
	)
	(via
		(at 188.097668 -133.472682)
		(size 0.508)
		(drill 0.254)
		(layers "F.Cu" "B.Cu")
		(net "GND")
	)
	(via
		(at 196.998082 -153.218134)
		(size 0.508)
		(drill 0.254)
		(layers "F.Cu" "B.Cu")
		(net "GND")
	)
	(via
		(at 392.749786 -305.399948)
		(size 0.4064)
		(drill 0.2032)
		(layers "F.Cu" "B.Cu")
		(net "GND")
	)
	(via
		(at 0.77089 -304.301144)
		(size 0.508)
		(drill 0.254)
		(layers "F.Cu" "B.Cu")
		(net "GND")
	)
	(via
		(at 36.849812 -309.199788)
		(size 0.4064)
		(drill 0.2032)
		(layers "F.Cu" "B.Cu")
		(net "GND")
	)
	(via
		(at 77.712062 -23.355554)
		(size 0.508)
		(drill 0.254)
		(layers "F.Cu" "B.Cu")
		(net "GND")
	)
	(via
		(at 421.53332 -344.831162)
		(size 0.4572)
		(drill 0.254)
		(layers "F.Cu" "B.Cu")
		(net "GND")
	)
	(via
		(at 95.473266 -72.56526)
		(size 0.508)
		(drill 0.254)
		(layers "F.Cu" "B.Cu")
		(net "GND")
	)
	(via
		(at 186.284616 -73.20026)
		(size 0.508)
		(drill 0.254)
		(layers "F.Cu" "B.Cu")
		(net "GND")
	)
	(via
		(at 288.524696 -284.974792)
		(size 0.4064)
		(drill 0.2032)
		(layers "F.Cu" "B.Cu")
		(net "GND")
	)
	(via
		(at 56.324754 -285.924752)
		(size 0.4064)
		(drill 0.2032)
		(layers "F.Cu" "B.Cu")
		(net "GND")
	)
	(via
		(at 408.899868 -281.649932)
		(size 0.4064)
		(drill 0.2032)
		(layers "F.Cu" "B.Cu")
		(net "GND")
	)
	(via
		(at 425.901104 -343.073482)
		(size 0.4572)
		(drill 0.254)
		(layers "F.Cu" "B.Cu")
		(net "GND")
	)
	(via
		(at 405.754078 -368.949224)
		(size 0.508)
		(drill 0.254)
		(layers "F.Cu" "B.Cu")
		(net "GND")
	)
	(via
		(at 393.351766 -102.445058)
		(size 0.508)
		(drill 0.254)
		(layers "F.Cu" "B.Cu")
		(net "GND")
	)
	(via
		(at 84.808314 -155.024582)
		(size 0.508)
		(drill 0.254)
		(layers "F.Cu" "B.Cu")
		(net "GND")
	)
	(via
		(at 9.319768 -163.021518)
		(size 0.508)
		(drill 0.254)
		(layers "F.Cu" "B.Cu")
		(net "GND")
	)
	(via
		(at 45.939202 -28.05303)
		(size 0.508)
		(drill 0.254)
		(layers "F.Cu" "B.Cu")
		(net "GND")
	)
	(via
		(at 176.699926 -278.799798)
		(size 0.4064)
		(drill 0.2032)
		(layers "F.Cu" "B.Cu")
		(net "GND")
	)
	(via
		(at 291.32784 -398.34185)
		(size 0.508)
		(drill 0.254)
		(layers "F.Cu" "B.Cu")
		(net "GND")
	)
	(via
		(at 193.799968 -312.999882)
		(size 0.4064)
		(drill 0.2032)
		(layers "F.Cu" "B.Cu")
		(net "GND")
	)
	(via
		(at 339.037422 -307.877718)
		(size 0.508)
		(drill 0.254)
		(layers "F.Cu" "B.Cu")
		(net "GND")
	)
	(via
		(at 365.799624 -57.439814)
		(size 0.508)
		(drill 0.254)
		(layers "F.Cu" "B.Cu")
		(net "GND")
	)
	(via
		(at 44.006516 -352.245422)
		(size 0.4572)
		(drill 0.254)
		(layers "F.Cu" "B.Cu")
		(net "GND")
	)
	(via
		(at 289.090862 -351.611438)
		(size 0.4064)
		(drill 0.2032)
		(layers "F.Cu" "B.Cu")
		(net "GND")
	)
	(via
		(at 172.547788 -380.141734)
		(size 0.508)
		(drill 0.254)
		(layers "F.Cu" "B.Cu")
		(net "GND")
	)
	(via
		(at 81.458562 -357.75773)
		(size 0.4064)
		(drill 0.2032)
		(layers "F.Cu" "B.Cu")
		(net "GND")
	)
	(via
		(at 418.874956 -291.624766)
		(size 0.4064)
		(drill 0.2032)
		(layers "F.Cu" "B.Cu")
		(net "GND")
	)
	(via
		(at 65.81267 -125.435106)
		(size 0.508)
		(drill 0.254)
		(layers "F.Cu" "B.Cu")
		(net "GND")
	)
	(via
		(at 334.490822 -235.103162)
		(size 0.508)
		(drill 0.254)
		(layers "F.Cu" "B.Cu")
		(net "GND")
	)
	(via
		(at 265.855196 -86.367874)
		(size 0.508)
		(drill 0.254)
		(layers "F.Cu" "B.Cu")
		(net "GND")
	)
	(via
		(at 404.624794 -306.824888)
		(size 0.4064)
		(drill 0.2032)
		(layers "F.Cu" "B.Cu")
		(net "GND")
	)
	(via
		(at 256.707386 -397.705834)
		(size 0.508)
		(drill 0.254)
		(layers "F.Cu" "B.Cu")
		(net "GND")
	)
	(via
		(at 285.199836 -277.849838)
		(size 0.4064)
		(drill 0.2032)
		(layers "F.Cu" "B.Cu")
		(net "GND")
	)
	(via
		(at 11.7983 -21.077936)
		(size 0.508)
		(drill 0.254)
		(layers "F.Cu" "B.Cu")
		(net "GND")
	)
	(via
		(at 104.293162 -172.22724)
		(size 0.508)
		(drill 0.254)
		(layers "F.Cu" "B.Cu")
		(net "GND")
	)
	(via
		(at 322.921884 -99.614482)
		(size 0.508)
		(drill 0.254)
		(layers "F.Cu" "B.Cu")
		(net "GND")
	)
	(via
		(at 80.54975 -287.349946)
		(size 0.4064)
		(drill 0.2032)
		(layers "F.Cu" "B.Cu")
		(net "GND")
	)
	(via
		(at 52.524914 -298.27474)
		(size 0.4064)
		(drill 0.2032)
		(layers "F.Cu" "B.Cu")
		(net "GND")
	)
	(via
		(at 387.999986 -310.149748)
		(size 0.4064)
		(drill 0.2032)
		(layers "F.Cu" "B.Cu")
		(net "GND")
	)
	(via
		(at 429.325024 -290.674806)
		(size 0.4064)
		(drill 0.2032)
		(layers "F.Cu" "B.Cu")
		(net "GND")
	)
	(via
		(at 23.368 -417.82492)
		(size 0.508)
		(drill 0.254)
		(layers "F.Cu" "B.Cu")
		(net "GND")
	)
	(via
		(at 390.374886 -286.874966)
		(size 0.4064)
		(drill 0.2032)
		(layers "F.Cu" "B.Cu")
		(net "GND")
	)
	(via
		(at 65.81267 -156.555186)
		(size 0.508)
		(drill 0.254)
		(layers "F.Cu" "B.Cu")
		(net "GND")
	)
	(via
		(at 174.800006 -274.049744)
		(size 0.4064)
		(drill 0.2032)
		(layers "F.Cu" "B.Cu")
		(net "GND")
	)
	(via
		(at 123.728988 -354.732082)
		(size 0.4064)
		(drill 0.2032)
		(layers "F.Cu" "B.Cu")
		(net "GND")
	)
	(via
		(at 277.02637 -358.391714)
		(size 0.4572)
		(drill 0.254)
		(layers "F.Cu" "B.Cu")
		(net "GND")
	)
	(via
		(at 93.894402 -351.611438)
		(size 0.4064)
		(drill 0.2032)
		(layers "F.Cu" "B.Cu")
		(net "GND")
	)
	(via
		(at 184.77484 -285.924752)
		(size 0.4064)
		(drill 0.2032)
		(layers "F.Cu" "B.Cu")
		(net "GND")
	)
	(via
		(at 432.12766 -404.940262)
		(size 0.508)
		(drill 0.254)
		(layers "F.Cu" "B.Cu")
		(net "GND")
	)
	(via
		(at 246.870728 -111.127032)
		(size 0.508)
		(drill 0.254)
		(layers "F.Cu" "B.Cu")
		(net "GND")
	)
	(via
		(at 392.52779 -371.140482)
		(size 0.508)
		(drill 0.254)
		(layers "F.Cu" "B.Cu")
		(net "GND")
	)
	(via
		(at 227.867972 -221.904052)
		(size 0.4572)
		(drill 0.254)
		(layers "F.Cu" "B.Cu")
		(net "GND")
	)
	(via
		(at 14.248892 -29.589984)
		(size 0.508)
		(drill 0.254)
		(layers "F.Cu" "B.Cu")
		(net "GND")
	)
	(via
		(at 2.248408 -282.354782)
		(size 0.508)
		(drill 0.254)
		(layers "F.Cu" "B.Cu")
		(net "GND")
	)
	(via
		(at 162.924998 -287.824926)
		(size 0.4064)
		(drill 0.2032)
		(layers "F.Cu" "B.Cu")
		(net "GND")
	)
	(via
		(at 287.612074 -347.951806)
		(size 0.4572)
		(drill 0.254)
		(layers "F.Cu" "B.Cu")
		(net "GND")
	)
	(via
		(at 85.674962 -351.611438)
		(size 0.4064)
		(drill 0.2032)
		(layers "F.Cu" "B.Cu")
		(net "GND")
	)
	(via
		(at 122.2502 -341.805514)
		(size 0.4572)
		(drill 0.254)
		(layers "F.Cu" "B.Cu")
		(net "GND")
	)
	(via
		(at 312.274712 -292.574726)
		(size 0.4064)
		(drill 0.2032)
		(layers "F.Cu" "B.Cu")
		(net "GND")
	)
	(via
		(at 360.170476 -288.14649)
		(size 0.508)
		(drill 0.254)
		(layers "F.Cu" "B.Cu")
		(net "GND")
	)
	(via
		(at 4.255008 -287.104582)
		(size 0.508)
		(drill 0.254)
		(layers "F.Cu" "B.Cu")
		(net "GND")
	)
	(via
		(at 365.197136 -173.617128)
		(size 0.508)
		(drill 0.254)
		(layers "F.Cu" "B.Cu")
		(net "GND")
	)
	(via
		(at 7.857236 -308.739794)
		(size 0.508)
		(drill 0.254)
		(layers "F.Cu" "B.Cu")
		(net "GND")
	)
	(via
		(at 317.2968 -257.556)
		(size 0.508)
		(drill 0.254)
		(layers "F.Cu" "B.Cu")
		(net "GND")
	)
	(via
		(at 285.981902 -351.611438)
		(size 0.4064)
		(drill 0.2032)
		(layers "F.Cu" "B.Cu")
		(net "GND")
	)
	(via
		(at 195.699888 -304.449734)
		(size 0.4064)
		(drill 0.2032)
		(layers "F.Cu" "B.Cu")
		(net "GND")
	)
	(via
		(at 28.090368 -357.75773)
		(size 0.4064)
		(drill 0.2032)
		(layers "F.Cu" "B.Cu")
		(net "GND")
	)
	(via
		(at 297.927776 -406.040336)
		(size 0.508)
		(drill 0.254)
		(layers "F.Cu" "B.Cu")
		(net "GND")
	)
	(via
		(at 448.333622 -107.681776)
		(size 0.508)
		(drill 0.254)
		(layers "F.Cu" "B.Cu")
		(net "GND")
	)
	(via
		(at 146.787362 -238.990378)
		(size 0.508)
		(drill 0.254)
		(layers "F.Cu" "B.Cu")
		(net "GND")
	)
	(via
		(at 160.138364 -358.391714)
		(size 0.4572)
		(drill 0.254)
		(layers "F.Cu" "B.Cu")
		(net "GND")
	)
	(via
		(at 390.849866 -316.799722)
		(size 0.4064)
		(drill 0.2032)
		(layers "F.Cu" "B.Cu")
		(net "GND")
	)
	(via
		(at 284.249876 -319.65011)
		(size 0.4064)
		(drill 0.2032)
		(layers "F.Cu" "B.Cu")
		(net "GND")
	)
	(via
		(at 388.949946 -314.899802)
		(size 0.4064)
		(drill 0.2032)
		(layers "F.Cu" "B.Cu")
		(net "GND")
	)
	(via
		(at 115.34775 -408.840178)
		(size 0.4572)
		(drill 0.254)
		(layers "F.Cu" "B.Cu")
		(net "GND")
	)
	(via
		(at 45.39996 -314.899802)
		(size 0.4064)
		(drill 0.2032)
		(layers "F.Cu" "B.Cu")
		(net "GND")
	)
	(via
		(at 132.747512 -178.786536)
		(size 0.508)
		(drill 0.254)
		(layers "F.Cu" "B.Cu")
		(net "GND")
	)
	(via
		(at 250.769882 -25.832054)
		(size 0.508)
		(drill 0.254)
		(layers "F.Cu" "B.Cu")
		(net "GND")
	)
	(via
		(at 81.024984 -300.174914)
		(size 0.4064)
		(drill 0.2032)
		(layers "F.Cu" "B.Cu")
		(net "GND")
	)
	(via
		(at 32.470344 -253.45644)
		(size 0.508)
		(drill 0.254)
		(layers "F.Cu" "B.Cu")
		(net "GND")
	)
	(via
		(at 216.352628 -209.22488)
		(size 0.508)
		(drill 0.254)
		(layers "F.Cu" "B.Cu")
		(net "GND")
	)
	(via
		(at 62.433454 -350.977454)
		(size 0.4572)
		(drill 0.254)
		(layers "F.Cu" "B.Cu")
		(net "GND")
	)
	(via
		(at 14.36116 -134.335012)
		(size 0.508)
		(drill 0.254)
		(layers "F.Cu" "B.Cu")
		(net "GND")
	)
	(via
		(at 13.902182 -56.826404)
		(size 0.508)
		(drill 0.254)
		(layers "F.Cu" "B.Cu")
		(net "GND")
	)
	(via
		(at 366.86998 -25.832054)
		(size 0.508)
		(drill 0.254)
		(layers "F.Cu" "B.Cu")
		(net "GND")
	)
	(via
		(at 45.87494 -289.724846)
		(size 0.4064)
		(drill 0.2032)
		(layers "F.Cu" "B.Cu")
		(net "GND")
	)
	(via
		(at 87.305134 -346.09913)
		(size 0.4572)
		(drill 0.254)
		(layers "F.Cu" "B.Cu")
		(net "GND")
	)
	(via
		(at 277.251668 -109.644942)
		(size 0.508)
		(drill 0.254)
		(layers "F.Cu" "B.Cu")
		(net "GND")
	)
	(via
		(at 192.541652 -96.810322)
		(size 0.508)
		(drill 0.254)
		(layers "F.Cu" "B.Cu")
		(net "GND")
	)
	(via
		(at 28.461716 -358.391714)
		(size 0.4572)
		(drill 0.254)
		(layers "F.Cu" "B.Cu")
		(net "GND")
	)
	(via
		(at 43.499786 -273.099784)
		(size 0.4064)
		(drill 0.2032)
		(layers "F.Cu" "B.Cu")
		(net "GND")
	)
	(via
		(at 103.205026 -307.82387)
		(size 0.508)
		(drill 0.254)
		(layers "F.Cu" "B.Cu")
		(net "GND")
	)
	(via
		(at 135.988298 -181.004718)
		(size 0.508)
		(drill 0.254)
		(layers "F.Cu" "B.Cu")
		(net "GND")
	)
	(via
		(at 192.375028 -300.174914)
		(size 0.4064)
		(drill 0.2032)
		(layers "F.Cu" "B.Cu")
		(net "GND")
	)
	(via
		(at 130.74777 -377.341892)
		(size 0.4572)
		(drill 0.254)
		(layers "F.Cu" "B.Cu")
		(net "GND")
	)
	(via
		(at 428.84979 -310.149748)
		(size 0.4064)
		(drill 0.2032)
		(layers "F.Cu" "B.Cu")
		(net "GND")
	)
	(via
		(at 377.208288 -354.098098)
		(size 0.4572)
		(drill 0.254)
		(layers "F.Cu" "B.Cu")
		(net "GND")
	)
	(via
		(at 285.052262 -109.644942)
		(size 0.508)
		(drill 0.254)
		(layers "F.Cu" "B.Cu")
		(net "GND")
	)
	(via
		(at 378.83846 -354.732082)
		(size 0.4064)
		(drill 0.2032)
		(layers "F.Cu" "B.Cu")
		(net "GND")
	)
	(via
		(at 260.143244 -28.139136)
		(size 0.508)
		(drill 0.254)
		(layers "F.Cu" "B.Cu")
		(net "GND")
	)
	(via
		(at 455.05878 -18.93189)
		(size 0.508)
		(drill 0.254)
		(layers "F.Cu" "B.Cu")
		(net "GND")
	)
	(via
		(at 388.16534 -357.75773)
		(size 0.4064)
		(drill 0.2032)
		(layers "F.Cu" "B.Cu")
		(net "GND")
	)
	(via
		(at 208.158588 -307.889656)
		(size 0.508)
		(drill 0.254)
		(layers "F.Cu" "B.Cu")
		(net "GND")
	)
	(via
		(at 403.674834 -285.924752)
		(size 0.4064)
		(drill 0.2032)
		(layers "F.Cu" "B.Cu")
		(net "GND")
	)
	(via
		(at 169.574972 -307.774848)
		(size 0.4064)
		(drill 0.2032)
		(layers "F.Cu" "B.Cu")
		(net "GND")
	)
	(via
		(at 96.19615 -60.099194)
		(size 0.508)
		(drill 0.254)
		(layers "F.Cu" "B.Cu")
		(net "GND")
	)
	(via
		(at 415.96691 -120.035066)
		(size 0.508)
		(drill 0.254)
		(layers "F.Cu" "B.Cu")
		(net "GND")
	)
	(via
		(at 29.15158 -256.375916)
		(size 0.508)
		(drill 0.254)
		(layers "F.Cu" "B.Cu")
		(net "GND")
	)
	(via
		(at 54.899814 -276.899878)
		(size 0.4064)
		(drill 0.2032)
		(layers "F.Cu" "B.Cu")
		(net "GND")
	)
	(via
		(at 191.80683 -0.762)
		(size 0.508)
		(drill 0.254)
		(layers "F.Cu" "B.Cu")
		(net "GND")
	)
	(via
		(at 463.037682 -179.337462)
		(size 0.508)
		(drill 0.254)
		(layers "F.Cu" "B.Cu")
		(net "GND")
	)
	(via
		(at 387.525006 -297.32478)
		(size 0.4064)
		(drill 0.2032)
		(layers "F.Cu" "B.Cu")
		(net "GND")
	)
	(via
		(at 333.127858 -408.738578)
		(size 0.508)
		(drill 0.254)
		(layers "F.Cu" "B.Cu")
		(net "GND")
	)
	(via
		(at 321.880738 -25.990042)
		(size 0.508)
		(drill 0.254)
		(layers "F.Cu" "B.Cu")
		(net "GND")
	)
	(via
		(at 21.313394 -29.859478)
		(size 0.508)
		(drill 0.254)
		(layers "F.Cu" "B.Cu")
		(net "GND")
	)
	(via
		(at 269.99819 -21.738336)
		(size 0.508)
		(drill 0.254)
		(layers "F.Cu" "B.Cu")
		(net "GND")
	)
	(via
		(at 345.703906 -87.083138)
		(size 0.508)
		(drill 0.254)
		(layers "F.Cu" "B.Cu")
		(net "GND")
	)
	(via
		(at 75.74788 -407.638504)
		(size 0.508)
		(drill 0.254)
		(layers "F.Cu" "B.Cu")
		(net "GND")
	)
	(via
		(at 332.703424 -228.386894)
		(size 0.4572)
		(drill 0.254)
		(layers "F.Cu" "B.Cu")
		(net "GND")
	)
	(via
		(at 179.07508 -284.974792)
		(size 0.4064)
		(drill 0.2032)
		(layers "F.Cu" "B.Cu")
		(net "GND")
	)
	(via
		(at 219.996512 -106.053128)
		(size 0.508)
		(drill 0.254)
		(layers "F.Cu" "B.Cu")
		(net "GND")
	)
	(via
		(at 430.274984 -301.124874)
		(size 0.4064)
		(drill 0.2032)
		(layers "F.Cu" "B.Cu")
		(net "GND")
	)
	(via
		(at 50.224436 -346.09913)
		(size 0.4572)
		(drill 0.254)
		(layers "F.Cu" "B.Cu")
		(net "GND")
	)
	(via
		(at 121.947686 -402.140166)
		(size 0.4572)
		(drill 0.254)
		(layers "F.Cu" "B.Cu")
		(net "GND")
	)
	(via
		(at 418.00399 -99.187)
		(size 0.508)
		(drill 0.254)
		(layers "F.Cu" "B.Cu")
		(net "GND")
	)
	(via
		(at 68.5546 -232.2068)
		(size 0.508)
		(drill 0.254)
		(layers "F.Cu" "B.Cu")
		(net "GND")
	)
	(via
		(at 377.45162 -259.576316)
		(size 0.508)
		(drill 0.254)
		(layers "F.Cu" "B.Cu")
		(net "GND")
	)
	(via
		(at 156.275024 -276.424898)
		(size 0.4064)
		(drill 0.2032)
		(layers "F.Cu" "B.Cu")
		(net "GND")
	)
	(via
		(at 105.011728 -88.086438)
		(size 0.508)
		(drill 0.254)
		(layers "F.Cu" "B.Cu")
		(net "GND")
	)
	(via
		(at 319.781936 -343.073482)
		(size 0.4572)
		(drill 0.254)
		(layers "F.Cu" "B.Cu")
		(net "GND")
	)
	(via
		(at 394.64996 -316.799722)
		(size 0.4064)
		(drill 0.2032)
		(layers "F.Cu" "B.Cu")
		(net "GND")
	)
	(via
		(at 286.927798 -408.840178)
		(size 0.508)
		(drill 0.254)
		(layers "F.Cu" "B.Cu")
		(net "GND")
	)
	(via
		(at 99.792028 -70.918832)
		(size 0.508)
		(drill 0.254)
		(layers "F.Cu" "B.Cu")
		(net "GND")
	)
	(via
		(at 135.128 -417.82492)
		(size 0.508)
		(drill 0.254)
		(layers "F.Cu" "B.Cu")
		(net "GND")
	)
	(via
		(at 385.927854 -398.24025)
		(size 0.508)
		(drill 0.254)
		(layers "F.Cu" "B.Cu")
		(net "GND")
	)
	(via
		(at 309.899812 -278.799798)
		(size 0.4064)
		(drill 0.2032)
		(layers "F.Cu" "B.Cu")
		(net "GND")
	)
	(via
		(at 163.13277 -118.754906)
		(size 0.508)
		(drill 0.254)
		(layers "F.Cu" "B.Cu")
		(net "GND")
	)
	(via
		(at 71.347838 -399.838418)
		(size 0.508)
		(drill 0.254)
		(layers "F.Cu" "B.Cu")
		(net "GND")
	)
	(via
		(at 23.873968 -348.58579)
		(size 0.4064)
		(drill 0.2032)
		(layers "F.Cu" "B.Cu")
		(net "GND")
	)
	(via
		(at 367.178844 -122.09907)
		(size 0.508)
		(drill 0.254)
		(layers "F.Cu" "B.Cu")
		(net "GND")
	)
	(via
		(at 168.20642 -350.977454)
		(size 0.4572)
		(drill 0.254)
		(layers "F.Cu" "B.Cu")
		(net "GND")
	)
	(via
		(at 403.00656 -106.044746)
		(size 0.508)
		(drill 0.254)
		(layers "F.Cu" "B.Cu")
		(net "GND")
	)
	(via
		(at 463.037682 -128.537462)
		(size 0.508)
		(drill 0.254)
		(layers "F.Cu" "B.Cu")
		(net "GND")
	)
	(via
		(at 214.373968 -73.85177)
		(size 0.508)
		(drill 0.254)
		(layers "F.Cu" "B.Cu")
		(net "GND")
	)
	(via
		(at 97.519998 -57.076848)
		(size 0.508)
		(drill 0.254)
		(layers "F.Cu" "B.Cu")
		(net "GND")
	)
	(via
		(at 363.23778 -282.910788)
		(size 0.49022)
		(drill 0.254)
		(layers "F.Cu" "B.Cu")
		(net "GND")
	)
	(via
		(at 3.620008 -287.104582)
		(size 0.508)
		(drill 0.254)
		(layers "F.Cu" "B.Cu")
		(net "GND")
	)
	(via
		(at 20.39366 -346.09913)
		(size 0.4572)
		(drill 0.254)
		(layers "F.Cu" "B.Cu")
		(net "GND")
	)
	(via
		(at 217.424 -26.319734)
		(size 0.508)
		(drill 0.254)
		(layers "F.Cu" "B.Cu")
		(net "GND")
	)
	(via
		(at 228.308154 -69.600064)
		(size 0.508)
		(drill 0.254)
		(layers "F.Cu" "B.Cu")
		(net "GND")
	)
	(via
		(at 288.99993 -278.799798)
		(size 0.4064)
		(drill 0.2032)
		(layers "F.Cu" "B.Cu")
		(net "GND")
	)
	(via
		(at 390.327896 -406.040336)
		(size 0.508)
		(drill 0.254)
		(layers "F.Cu" "B.Cu")
		(net "GND")
	)
	(via
		(at 61.549788 -316.799722)
		(size 0.4064)
		(drill 0.2032)
		(layers "F.Cu" "B.Cu")
		(net "GND")
	)
	(via
		(at 366.971326 -31.652972)
		(size 0.508)
		(drill 0.254)
		(layers "F.Cu" "B.Cu")
		(net "GND")
	)
	(via
		(at 22.098508 -37.201094)
		(size 0.508)
		(drill 0.254)
		(layers "F.Cu" "B.Cu")
		(net "GND")
	)
	(via
		(at 322.890896 -352.245422)
		(size 0.4572)
		(drill 0.254)
		(layers "F.Cu" "B.Cu")
		(net "GND")
	)
	(via
		(at 163.747958 -395.938502)
		(size 0.508)
		(drill 0.254)
		(layers "F.Cu" "B.Cu")
		(net "GND")
	)
	(via
		(at 210.900772 -171.237656)
		(size 0.508)
		(drill 0.254)
		(layers "F.Cu" "B.Cu")
		(net "GND")
	)
	(via
		(at 303.249838 -311.099962)
		(size 0.4064)
		(drill 0.2032)
		(layers "F.Cu" "B.Cu")
		(net "GND")
	)
	(via
		(at 270.601694 -135.643112)
		(size 0.508)
		(drill 0.254)
		(layers "F.Cu" "B.Cu")
		(net "GND")
	)
	(via
		(at 393.798552 -65.15989)
		(size 0.508)
		(drill 0.254)
		(layers "F.Cu" "B.Cu")
		(net "GND")
	)
	(via
		(at 49.518824 -123.878594)
		(size 0.508)
		(drill 0.254)
		(layers "F.Cu" "B.Cu")
		(net "GND")
	)
	(via
		(at 198.26605 -143.676878)
		(size 0.508)
		(drill 0.254)
		(layers "F.Cu" "B.Cu")
		(net "GND")
	)
	(via
		(at 89.15527 -343.073482)
		(size 0.4572)
		(drill 0.254)
		(layers "F.Cu" "B.Cu")
		(net "GND")
	)
	(via
		(at 169.017442 -24.600662)
		(size 0.508)
		(drill 0.254)
		(layers "F.Cu" "B.Cu")
		(net "GND")
	)
	(via
		(at 67.39255 -344.831162)
		(size 0.4572)
		(drill 0.254)
		(layers "F.Cu" "B.Cu")
		(net "GND")
	)
	(via
		(at 270.256 -33.19018)
		(size 0.508)
		(drill 0.254)
		(layers "F.Cu" "B.Cu")
		(net "GND")
	)
	(via
		(at 110.045246 -307.82387)
		(size 0.508)
		(drill 0.254)
		(layers "F.Cu" "B.Cu")
		(net "GND")
	)
	(via
		(at 378.83846 -342.439498)
		(size 0.4064)
		(drill 0.2032)
		(layers "F.Cu" "B.Cu")
		(net "GND")
	)
	(via
		(at 420.299896 -274.049744)
		(size 0.4064)
		(drill 0.2032)
		(layers "F.Cu" "B.Cu")
		(net "GND")
	)
	(via
		(at 401.299934 -273.099784)
		(size 0.4064)
		(drill 0.2032)
		(layers "F.Cu" "B.Cu")
		(net "GND")
	)
	(via
		(at 259.868924 -295.933114)
		(size 0.508)
		(drill 0.254)
		(layers "F.Cu" "B.Cu")
		(net "GND")
	)
	(via
		(at 163.322254 -52.51704)
		(size 0.508)
		(drill 0.254)
		(layers "F.Cu" "B.Cu")
		(net "GND")
	)
	(via
		(at 72.131682 -351.611438)
		(size 0.4064)
		(drill 0.2032)
		(layers "F.Cu" "B.Cu")
		(net "GND")
	)
	(via
		(at 403.674834 -300.174914)
		(size 0.4064)
		(drill 0.2032)
		(layers "F.Cu" "B.Cu")
		(net "GND")
	)
	(via
		(at 121.947686 -406.040336)
		(size 0.4572)
		(drill 0.254)
		(layers "F.Cu" "B.Cu")
		(net "GND")
	)
	(via
		(at 434.120036 -34.990278)
		(size 0.508)
		(drill 0.254)
		(layers "F.Cu" "B.Cu")
		(net "GND")
	)
	(via
		(at 93.451426 -113.364772)
		(size 0.508)
		(drill 0.254)
		(layers "F.Cu" "B.Cu")
		(net "GND")
	)
	(via
		(at 309.899812 -306.349908)
		(size 0.4064)
		(drill 0.2032)
		(layers "F.Cu" "B.Cu")
		(net "GND")
	)
	(via
		(at 379.816106 -259.576316)
		(size 0.508)
		(drill 0.254)
		(layers "F.Cu" "B.Cu")
		(net "GND")
	)
	(via
		(at 154.375104 -288.774886)
		(size 0.4064)
		(drill 0.2032)
		(layers "F.Cu" "B.Cu")
		(net "GND")
	)
	(via
		(at 205.898242 -20.417536)
		(size 0.508)
		(drill 0.254)
		(layers "F.Cu" "B.Cu")
		(net "GND")
	)
	(via
		(at 114.402108 -348.58579)
		(size 0.4064)
		(drill 0.2032)
		(layers "F.Cu" "B.Cu")
		(net "GND")
	)
	(via
		(at 415.3154 -343.073482)
		(size 0.4572)
		(drill 0.254)
		(layers "F.Cu" "B.Cu")
		(net "GND")
	)
	(via
		(at 151.748998 -33.19018)
		(size 0.508)
		(drill 0.254)
		(layers "F.Cu" "B.Cu")
		(net "GND")
	)
	(via
		(at 173.375066 -284.974792)
		(size 0.4064)
		(drill 0.2032)
		(layers "F.Cu" "B.Cu")
		(net "GND")
	)
	(via
		(at 441.938918 -291.321998)
		(size 0.508)
		(drill 0.254)
		(layers "F.Cu" "B.Cu")
		(net "GND")
	)
	(via
		(at 412.20644 -344.831162)
		(size 0.4572)
		(drill 0.254)
		(layers "F.Cu" "B.Cu")
		(net "GND")
	)
	(via
		(at 358.369362 -145.083276)
		(size 0.508)
		(drill 0.254)
		(layers "F.Cu" "B.Cu")
		(net "GND")
	)
	(via
		(at 275.176234 -358.391714)
		(size 0.4572)
		(drill 0.254)
		(layers "F.Cu" "B.Cu")
		(net "GND")
	)
	(via
		(at 124.496322 -251.338334)
		(size 0.508)
		(drill 0.254)
		(layers "F.Cu" "B.Cu")
		(net "GND")
	)
	(via
		(at 423.740834 -45.853858)
		(size 0.508)
		(drill 0.254)
		(layers "F.Cu" "B.Cu")
		(net "GND")
	)
	(via
		(at 377.53544 -91.1098)
		(size 0.508)
		(drill 0.254)
		(layers "F.Cu" "B.Cu")
		(net "GND")
	)
	(via
		(at 151.20112 -100.92309)
		(size 0.508)
		(drill 0.254)
		(layers "F.Cu" "B.Cu")
		(net "GND")
	)
	(via
		(at 107.881674 -131.051808)
		(size 0.508)
		(drill 0.254)
		(layers "F.Cu" "B.Cu")
		(net "GND")
	)
	(via
		(at 3.30708 -49.574704)
		(size 0.508)
		(drill 0.254)
		(layers "F.Cu" "B.Cu")
		(net "GND")
	)
	(via
		(at 36.309808 -354.732082)
		(size 0.4064)
		(drill 0.2032)
		(layers "F.Cu" "B.Cu")
		(net "GND")
	)
	(via
		(at 335.326736 -347.951806)
		(size 0.4572)
		(drill 0.254)
		(layers "F.Cu" "B.Cu")
		(net "GND")
	)
	(via
		(at 213.16823 -48.753014)
		(size 0.508)
		(drill 0.254)
		(layers "F.Cu" "B.Cu")
		(net "GND")
	)
	(via
		(at 392.274806 -299.224954)
		(size 0.4064)
		(drill 0.2032)
		(layers "F.Cu" "B.Cu")
		(net "GND")
	)
	(via
		(at 58.224928 -302.074834)
		(size 0.4064)
		(drill 0.2032)
		(layers "F.Cu" "B.Cu")
		(net "GND")
	)
	(via
		(at 76.71943 -346.09913)
		(size 0.4572)
		(drill 0.254)
		(layers "F.Cu" "B.Cu")
		(net "GND")
	)
	(via
		(at 448.244976 -278.861266)
		(size 0.508)
		(drill 0.254)
		(layers "F.Cu" "B.Cu")
		(net "GND")
	)
	(via
		(at 384.059684 -120.28551)
		(size 0.508)
		(drill 0.254)
		(layers "F.Cu" "B.Cu")
		(net "GND")
	)
	(via
		(at 2.785364 -38.829742)
		(size 0.508)
		(drill 0.254)
		(layers "F.Cu" "B.Cu")
		(net "GND")
	)
	(via
		(at 226.32797 -278.233378)
		(size 0.508)
		(drill 0.254)
		(layers "F.Cu" "B.Cu")
		(net "GND")
	)
	(via
		(at 74.869294 -358.391714)
		(size 0.4572)
		(drill 0.254)
		(layers "F.Cu" "B.Cu")
		(net "GND")
	)
	(via
		(at 343.394792 -347.951806)
		(size 0.4572)
		(drill 0.254)
		(layers "F.Cu" "B.Cu")
		(net "GND")
	)
	(via
		(at 33.200848 -345.465146)
		(size 0.4064)
		(drill 0.2032)
		(layers "F.Cu" "B.Cu")
		(net "GND")
	)
	(via
		(at 221.42323 -54.067456)
		(size 0.508)
		(drill 0.254)
		(layers "F.Cu" "B.Cu")
		(net "GND")
	)
	(via
		(at 189.999874 -314.899802)
		(size 0.4064)
		(drill 0.2032)
		(layers "F.Cu" "B.Cu")
		(net "GND")
	)
	(via
		(at 368.239294 -29.311854)
		(size 0.508)
		(drill 0.254)
		(layers "F.Cu" "B.Cu")
		(net "GND")
	)
	(via
		(at 142.754096 -358.391714)
		(size 0.4572)
		(drill 0.254)
		(layers "F.Cu" "B.Cu")
		(net "GND")
	)
	(via
		(at 209.537808 -74.624184)
		(size 0.508)
		(drill 0.254)
		(layers "F.Cu" "B.Cu")
		(net "GND")
	)
	(via
		(at 119.747792 -377.738386)
		(size 0.508)
		(drill 0.254)
		(layers "F.Cu" "B.Cu")
		(net "GND")
	)
	(via
		(at 291.33419 -206.411068)
		(size 0.508)
		(drill 0.254)
		(layers "F.Cu" "B.Cu")
		(net "GND")
	)
	(via
		(at 388.474966 -276.424898)
		(size 0.4064)
		(drill 0.2032)
		(layers "F.Cu" "B.Cu")
		(net "GND")
	)
	(via
		(at 295.68013 -344.831162)
		(size 0.4572)
		(drill 0.254)
		(layers "F.Cu" "B.Cu")
		(net "GND")
	)
	(via
		(at 421.53332 -355.366066)
		(size 0.4572)
		(drill 0.254)
		(layers "F.Cu" "B.Cu")
		(net "GND")
	)
	(via
		(at 287.574736 -306.824888)
		(size 0.4064)
		(drill 0.2032)
		(layers "F.Cu" "B.Cu")
		(net "GND")
	)
	(via
		(at 84.567522 -357.75773)
		(size 0.4064)
		(drill 0.2032)
		(layers "F.Cu" "B.Cu")
		(net "GND")
	)
	(via
		(at 341.916004 -351.611438)
		(size 0.4064)
		(drill 0.2032)
		(layers "F.Cu" "B.Cu")
		(net "GND")
	)
	(via
		(at 372.68658 -48.874934)
		(size 0.508)
		(drill 0.254)
		(layers "F.Cu" "B.Cu")
		(net "GND")
	)
	(via
		(at 45.051726 -138.964924)
		(size 0.508)
		(drill 0.254)
		(layers "F.Cu" "B.Cu")
		(net "GND")
	)
	(via
		(at 395.862048 -347.951806)
		(size 0.4572)
		(drill 0.254)
		(layers "F.Cu" "B.Cu")
		(net "GND")
	)
	(via
		(at 292.199822 -351.611438)
		(size 0.4064)
		(drill 0.2032)
		(layers "F.Cu" "B.Cu")
		(net "GND")
	)
	(via
		(at 153.42489 -274.524724)
		(size 0.4064)
		(drill 0.2032)
		(layers "F.Cu" "B.Cu")
		(net "GND")
	)
	(via
		(at 378.41047 -220.062044)
		(size 0.508)
		(drill 0.254)
		(layers "F.Cu" "B.Cu")
		(net "GND")
	)
	(via
		(at 197.600062 -288.299906)
		(size 0.4064)
		(drill 0.2032)
		(layers "F.Cu" "B.Cu")
		(net "GND")
	)
	(via
		(at 298.78909 -343.073482)
		(size 0.4572)
		(drill 0.254)
		(layers "F.Cu" "B.Cu")
		(net "GND")
	)
	(via
		(at 254.10668 -88.634316)
		(size 0.508)
		(drill 0.254)
		(layers "F.Cu" "B.Cu")
		(net "GND")
	)
	(via
		(at 25.352756 -341.805514)
		(size 0.4572)
		(drill 0.254)
		(layers "F.Cu" "B.Cu")
		(net "GND")
	)
	(via
		(at 443.213998 -231.779318)
		(size 0.508)
		(drill 0.254)
		(layers "F.Cu" "B.Cu")
		(net "GND")
	)
	(via
		(at 315.414152 -350.977454)
		(size 0.4572)
		(drill 0.254)
		(layers "F.Cu" "B.Cu")
		(net "GND")
	)
	(via
		(at 452.775574 -310.4388)
		(size 0.508)
		(drill 0.254)
		(layers "F.Cu" "B.Cu")
		(net "GND")
	)
	(via
		(at 53.949854 -274.999958)
		(size 0.4064)
		(drill 0.2032)
		(layers "F.Cu" "B.Cu")
		(net "GND")
	)
	(via
		(at 142.293594 -295.933114)
		(size 0.508)
		(drill 0.254)
		(layers "F.Cu" "B.Cu")
		(net "GND")
	)
	(via
		(at 345.877642 -307.242718)
		(size 0.508)
		(drill 0.254)
		(layers "F.Cu" "B.Cu")
		(net "GND")
	)
	(via
		(at 173.568614 -59.974734)
		(size 0.508)
		(drill 0.254)
		(layers "F.Cu" "B.Cu")
		(net "GND")
	)
	(via
		(at 22.581362 -29.859478)
		(size 0.508)
		(drill 0.254)
		(layers "F.Cu" "B.Cu")
		(net "GND")
	)
	(via
		(at 280.781252 -31.118302)
		(size 0.508)
		(drill 0.254)
		(layers "F.Cu" "B.Cu")
		(net "GND")
	)
	(via
		(at 300.419262 -351.611438)
		(size 0.4064)
		(drill 0.2032)
		(layers "F.Cu" "B.Cu")
		(net "GND")
	)
	(via
		(at 280.13533 -354.098098)
		(size 0.4572)
		(drill 0.254)
		(layers "F.Cu" "B.Cu")
		(net "GND")
	)
	(via
		(at 335.326736 -354.098098)
		(size 0.4572)
		(drill 0.254)
		(layers "F.Cu" "B.Cu")
		(net "GND")
	)
	(via
		(at 150.555198 -27.79014)
		(size 0.508)
		(drill 0.254)
		(layers "F.Cu" "B.Cu")
		(net "GND")
	)
	(via
		(at 50.624994 -287.824926)
		(size 0.4064)
		(drill 0.2032)
		(layers "F.Cu" "B.Cu")
		(net "GND")
	)
	(via
		(at 162.450018 -279.749758)
		(size 0.4064)
		(drill 0.2032)
		(layers "F.Cu" "B.Cu")
		(net "GND")
	)
	(via
		(at 437.07812 -357.123746)
		(size 0.4572)
		(drill 0.254)
		(layers "F.Cu" "B.Cu")
		(net "GND")
	)
	(via
		(at 422.548304 -131.245102)
		(size 0.508)
		(drill 0.254)
		(layers "F.Cu" "B.Cu")
		(net "GND")
	)
	(via
		(at 175.683164 -346.09913)
		(size 0.4572)
		(drill 0.254)
		(layers "F.Cu" "B.Cu")
		(net "GND")
	)
	(via
		(at 305.624738 -303.024794)
		(size 0.4064)
		(drill 0.2032)
		(layers "F.Cu" "B.Cu")
		(net "GND")
	)
	(via
		(at 386.701792 -109.916722)
		(size 0.508)
		(drill 0.254)
		(layers "F.Cu" "B.Cu")
		(net "GND")
	)
	(via
		(at 412.89351 -131.245102)
		(size 0.508)
		(drill 0.254)
		(layers "F.Cu" "B.Cu")
		(net "GND")
	)
	(via
		(at 404.14956 -272.14957)
		(size 0.4064)
		(drill 0.2032)
		(layers "F.Cu" "B.Cu")
		(net "GND")
	)
	(via
		(at 189.049914 -319.65011)
		(size 0.4064)
		(drill 0.2032)
		(layers "F.Cu" "B.Cu")
		(net "GND")
	)
	(via
		(at 0.77089 -395.741144)
		(size 0.508)
		(drill 0.254)
		(layers "F.Cu" "B.Cu")
		(net "GND")
	)
	(via
		(at 176.555146 -27.79014)
		(size 0.508)
		(drill 0.254)
		(layers "F.Cu" "B.Cu")
		(net "GND")
	)
	(via
		(at 159.58566 -63.218314)
		(size 0.508)
		(drill 0.254)
		(layers "F.Cu" "B.Cu")
		(net "GND")
	)
	(via
		(at 109.85119 -336.749136)
		(size 0.508)
		(drill 0.254)
		(layers "F.Cu" "B.Cu")
		(net "GND")
	)
	(via
		(at 50.224436 -341.805514)
		(size 0.4572)
		(drill 0.254)
		(layers "F.Cu" "B.Cu")
		(net "GND")
	)
	(via
		(at 372.237762 -261.679182)
		(size 0.508)
		(drill 0.254)
		(layers "F.Cu" "B.Cu")
		(net "GND")
	)
	(via
		(at 430.749964 -313.949842)
		(size 0.4064)
		(drill 0.2032)
		(layers "F.Cu" "B.Cu")
		(net "GND")
	)
	(via
		(at 169.465244 -357.123746)
		(size 0.4572)
		(drill 0.254)
		(layers "F.Cu" "B.Cu")
		(net "GND")
	)
	(via
		(at 279.974802 -304.924714)
		(size 0.4064)
		(drill 0.2032)
		(layers "F.Cu" "B.Cu")
		(net "GND")
	)
	(via
		(at 207.134968 -186.160918)
		(size 0.508)
		(drill 0.254)
		(layers "F.Cu" "B.Cu")
		(net "GND")
	)
	(via
		(at 402.079968 -349.219774)
		(size 0.4572)
		(drill 0.254)
		(layers "F.Cu" "B.Cu")
		(net "GND")
	)
	(via
		(at 448.854068 -403.407626)
		(size 0.508)
		(drill 0.254)
		(layers "F.Cu" "B.Cu")
		(net "GND")
	)
	(via
		(at 386.044948 -27.79014)
		(size 0.508)
		(drill 0.254)
		(layers "F.Cu" "B.Cu")
		(net "GND")
	)
	(via
		(at 84.600796 -34.990278)
		(size 0.508)
		(drill 0.254)
		(layers "F.Cu" "B.Cu")
		(net "GND")
	)
	(via
		(at 130.00228 -56.826404)
		(size 0.508)
		(drill 0.254)
		(layers "F.Cu" "B.Cu")
		(net "GND")
	)
	(via
		(at 397.49222 -357.75773)
		(size 0.4064)
		(drill 0.2032)
		(layers "F.Cu" "B.Cu")
		(net "GND")
	)
	(via
		(at 318.019938 -34.990278)
		(size 0.508)
		(drill 0.254)
		(layers "F.Cu" "B.Cu")
		(net "GND")
	)
	(via
		(at 155.325064 -277.374858)
		(size 0.4064)
		(drill 0.2032)
		(layers "F.Cu" "B.Cu")
		(net "GND")
	)
	(via
		(at 179.07508 -298.27474)
		(size 0.4064)
		(drill 0.2032)
		(layers "F.Cu" "B.Cu")
		(net "GND")
	)
	(via
		(at 239.39246 -11.372342)
		(size 0.508)
		(drill 0.254)
		(layers "F.Cu" "B.Cu")
		(net "GND")
	)
	(via
		(at 116.154962 -279.086818)
		(size 0.508)
		(drill 0.254)
		(layers "F.Cu" "B.Cu")
		(net "GND")
	)
	(via
		(at 448.881246 -34.718498)
		(size 0.508)
		(drill 0.254)
		(layers "F.Cu" "B.Cu")
		(net "GND")
	)
	(via
		(at 39.224966 -298.27474)
		(size 0.4064)
		(drill 0.2032)
		(layers "F.Cu" "B.Cu")
		(net "GND")
	)
	(via
		(at 402.140166 -33.857692)
		(size 0.508)
		(drill 0.254)
		(layers "F.Cu" "B.Cu")
		(net "GND")
	)
	(via
		(at 399.65757 -29.784294)
		(size 0.508)
		(drill 0.254)
		(layers "F.Cu" "B.Cu")
		(net "GND")
	)
	(via
		(at 106.087164 -163.230052)
		(size 0.508)
		(drill 0.254)
		(layers "F.Cu" "B.Cu")
		(net "GND")
	)
	(via
		(at 9.7028 -276.789134)
		(size 0.508)
		(drill 0.254)
		(layers "F.Cu" "B.Cu")
		(net "GND")
	)
	(via
		(at 401.15236 -109.644942)
		(size 0.508)
		(drill 0.254)
		(layers "F.Cu" "B.Cu")
		(net "GND")
	)
	(via
		(at 158.87954 -357.123746)
		(size 0.4572)
		(drill 0.254)
		(layers "F.Cu" "B.Cu")
		(net "GND")
	)
	(via
		(at 394.17498 -294.4749)
		(size 0.4064)
		(drill 0.2032)
		(layers "F.Cu" "B.Cu")
		(net "GND")
	)
	(via
		(at 222.4278 -330.1238)
		(size 0.508)
		(drill 0.254)
		(layers "F.Cu" "B.Cu")
		(net "GND")
	)
	(via
		(at 400.824954 -302.074834)
		(size 0.4064)
		(drill 0.2032)
		(layers "F.Cu" "B.Cu")
		(net "GND")
	)
	(via
		(at 198.26605 -146.017996)
		(size 0.508)
		(drill 0.254)
		(layers "F.Cu" "B.Cu")
		(net "GND")
	)
	(via
		(at 233.579924 -58.674)
		(size 0.508)
		(drill 0.254)
		(layers "F.Cu" "B.Cu")
		(net "GND")
	)
	(via
		(at 337.176872 -343.073482)
		(size 0.4572)
		(drill 0.254)
		(layers "F.Cu" "B.Cu")
		(net "GND")
	)
	(via
		(at 165.704774 -105.365042)
		(size 0.508)
		(drill 0.254)
		(layers "F.Cu" "B.Cu")
		(net "GND")
	)
	(via
		(at 451.211188 -416.636962)
		(size 0.508)
		(drill 0.254)
		(layers "F.Cu" "B.Cu")
		(net "GND")
	)
	(via
		(at 248.757948 -56.809894)
		(size 0.508)
		(drill 0.254)
		(layers "F.Cu" "B.Cu")
		(net "GND")
	)
	(via
		(at 376.267472 -33.248092)
		(size 0.508)
		(drill 0.254)
		(layers "F.Cu" "B.Cu")
		(net "GND")
	)
	(via
		(at 171.474892 -291.624766)
		(size 0.4064)
		(drill 0.2032)
		(layers "F.Cu" "B.Cu")
		(net "GND")
	)
	(via
		(at 343.408 -417.82492)
		(size 0.508)
		(drill 0.254)
		(layers "F.Cu" "B.Cu")
		(net "GND")
	)
	(via
		(at 260.169406 -33.248092)
		(size 0.508)
		(drill 0.254)
		(layers "F.Cu" "B.Cu")
		(net "GND")
	)
	(via
		(at 280.449782 -281.649932)
		(size 0.4064)
		(drill 0.2032)
		(layers "F.Cu" "B.Cu")
		(net "GND")
	)
	(via
		(at 181.912514 -156.555186)
		(size 0.508)
		(drill 0.254)
		(layers "F.Cu" "B.Cu")
		(net "GND")
	)
	(via
		(at 270.474948 -279.274778)
		(size 0.4064)
		(drill 0.2032)
		(layers "F.Cu" "B.Cu")
		(net "GND")
	)
	(via
		(at 337.176872 -349.219774)
		(size 0.4572)
		(drill 0.254)
		(layers "F.Cu" "B.Cu")
		(net "GND")
	)
	(via
		(at 271.899888 -308.249828)
		(size 0.4064)
		(drill 0.2032)
		(layers "F.Cu" "B.Cu")
		(net "GND")
	)
	(via
		(at 235.407454 -82.118708)
		(size 0.508)
		(drill 0.254)
		(layers "F.Cu" "B.Cu")
		(net "GND")
	)
	(via
		(at 350.93656 -51.661822)
		(size 0.508)
		(drill 0.254)
		(layers "F.Cu" "B.Cu")
		(net "GND")
	)
	(via
		(at 142.382748 -357.75773)
		(size 0.4064)
		(drill 0.2032)
		(layers "F.Cu" "B.Cu")
		(net "GND")
	)
	(via
		(at 90.414094 -347.951806)
		(size 0.4572)
		(drill 0.254)
		(layers "F.Cu" "B.Cu")
		(net "GND")
	)
	(via
		(at 52.85232 -104.244902)
		(size 0.508)
		(drill 0.254)
		(layers "F.Cu" "B.Cu")
		(net "GND")
	)
	(via
		(at 395.830552 -65.15989)
		(size 0.508)
		(drill 0.254)
		(layers "F.Cu" "B.Cu")
		(net "GND")
	)
	(via
		(at 310.849772 -306.349908)
		(size 0.4064)
		(drill 0.2032)
		(layers "F.Cu" "B.Cu")
		(net "GND")
	)
	(via
		(at 448.451986 -0.762254)
		(size 0.508)
		(drill 0.254)
		(layers "F.Cu" "B.Cu")
		(net "GND")
	)
	(via
		(at 194.708272 -345.465146)
		(size 0.4064)
		(drill 0.2032)
		(layers "F.Cu" "B.Cu")
		(net "GND")
	)
	(via
		(at 101.8286 -191.8716)
		(size 0.508)
		(drill 0.254)
		(layers "F.Cu" "B.Cu")
		(net "GND")
	)
	(via
		(at 165.947852 -400.938492)
		(size 0.508)
		(drill 0.254)
		(layers "F.Cu" "B.Cu")
		(net "GND")
	)
	(via
		(at 241.848894 -29.589984)
		(size 0.508)
		(drill 0.254)
		(layers "F.Cu" "B.Cu")
		(net "GND")
	)
	(via
		(at 259.419852 -352.703638)
		(size 0.508)
		(drill 0.254)
		(layers "F.Cu" "B.Cu")
		(net "GND")
	)
	(via
		(at 254.093726 -211.922868)
		(size 0.508)
		(drill 0.254)
		(layers "F.Cu" "B.Cu")
		(net "GND")
	)
	(via
		(at 353.950016 -27.04973)
		(size 0.508)
		(drill 0.254)
		(layers "F.Cu" "B.Cu")
		(net "GND")
	)
	(via
		(at 422.881298 -29.859478)
		(size 0.508)
		(drill 0.254)
		(layers "F.Cu" "B.Cu")
		(net "GND")
	)
	(via
		(at 180.693314 -120.035066)
		(size 0.508)
		(drill 0.254)
		(layers "F.Cu" "B.Cu")
		(net "GND")
	)
	(via
		(at 293.829994 -354.098098)
		(size 0.4572)
		(drill 0.254)
		(layers "F.Cu" "B.Cu")
		(net "GND")
	)
	(via
		(at 207.519524 -287.788858)
		(size 0.508)
		(drill 0.254)
		(layers "F.Cu" "B.Cu")
		(net "GND")
	)
	(via
		(at 377.12777 -408.738578)
		(size 0.508)
		(drill 0.254)
		(layers "F.Cu" "B.Cu")
		(net "GND")
	)
	(via
		(at 330.766928 -0.762)
		(size 0.508)
		(drill 0.254)
		(layers "F.Cu" "B.Cu")
		(net "GND")
	)
	(via
		(at 68.199762 -314.899802)
		(size 0.4064)
		(drill 0.2032)
		(layers "F.Cu" "B.Cu")
		(net "GND")
	)
	(via
		(at 47.77486 -297.32478)
		(size 0.4064)
		(drill 0.2032)
		(layers "F.Cu" "B.Cu")
		(net "GND")
	)
	(via
		(at 418.927788 -406.141936)
		(size 0.508)
		(drill 0.254)
		(layers "F.Cu" "B.Cu")
		(net "GND")
	)
	(via
		(at 156.750004 -300.649894)
		(size 0.4064)
		(drill 0.2032)
		(layers "F.Cu" "B.Cu")
		(net "GND")
	)
	(via
		(at 279.387046 -139.731242)
		(size 0.508)
		(drill 0.254)
		(layers "F.Cu" "B.Cu")
		(net "GND")
	)
	(via
		(at 411.541976 -162.08375)
		(size 0.508)
		(drill 0.254)
		(layers "F.Cu" "B.Cu")
		(net "GND")
	)
	(via
		(at 412.224982 -305.874928)
		(size 0.4064)
		(drill 0.2032)
		(layers "F.Cu" "B.Cu")
		(net "GND")
	)
	(via
		(at 221.505526 -178.027076)
		(size 0.508)
		(drill 0.254)
		(layers "F.Cu" "B.Cu")
		(net "GND")
	)
	(via
		(at 412.89351 -120.035066)
		(size 0.508)
		(drill 0.254)
		(layers "F.Cu" "B.Cu")
		(net "GND")
	)
	(via
		(at 401.78736 -106.044746)
		(size 0.508)
		(drill 0.254)
		(layers "F.Cu" "B.Cu")
		(net "GND")
	)
	(via
		(at 413.174942 -293.52494)
		(size 0.4064)
		(drill 0.2032)
		(layers "F.Cu" "B.Cu")
		(net "GND")
	)
	(via
		(at 434.327808 -407.24201)
		(size 0.508)
		(drill 0.254)
		(layers "F.Cu" "B.Cu")
		(net "GND")
	)
	(via
		(at 75.74788 -378.94006)
		(size 0.508)
		(drill 0.254)
		(layers "F.Cu" "B.Cu")
		(net "GND")
	)
	(via
		(at 422.548304 -125.435106)
		(size 0.508)
		(drill 0.254)
		(layers "F.Cu" "B.Cu")
		(net "GND")
	)
	(via
		(at 398.925034 -298.27474)
		(size 0.4064)
		(drill 0.2032)
		(layers "F.Cu" "B.Cu")
		(net "GND")
	)
	(via
		(at 388.949946 -304.449734)
		(size 0.4064)
		(drill 0.2032)
		(layers "F.Cu" "B.Cu")
		(net "GND")
	)
	(via
		(at 364.47095 -307.242718)
		(size 0.508)
		(drill 0.254)
		(layers "F.Cu" "B.Cu")
		(net "GND")
	)
	(via
		(at 120.77573 -256.870962)
		(size 0.508)
		(drill 0.254)
		(layers "F.Cu" "B.Cu")
		(net "GND")
	)
	(via
		(at 133.261862 -163.47313)
		(size 0.508)
		(drill 0.254)
		(layers "F.Cu" "B.Cu")
		(net "GND")
	)
	(via
		(at 406.524968 -293.52494)
		(size 0.4064)
		(drill 0.2032)
		(layers "F.Cu" "B.Cu")
		(net "GND")
	)
	(via
		(at 424.09999 -307.299868)
		(size 0.4064)
		(drill 0.2032)
		(layers "F.Cu" "B.Cu")
		(net "GND")
	)
	(via
		(at 154.375104 -291.624766)
		(size 0.4064)
		(drill 0.2032)
		(layers "F.Cu" "B.Cu")
		(net "GND")
	)
	(via
		(at 299.15485 -227.089462)
		(size 0.508)
		(drill 0.254)
		(layers "F.Cu" "B.Cu")
		(net "GND")
	)
	(via
		(at 154.850084 -306.349908)
		(size 0.4064)
		(drill 0.2032)
		(layers "F.Cu" "B.Cu")
		(net "GND")
	)
	(via
		(at 429.198278 -149.617938)
		(size 0.508)
		(drill 0.254)
		(layers "F.Cu" "B.Cu")
		(net "GND")
	)
	(via
		(at 44.905676 -1.364996)
		(size 0.508)
		(drill 0.254)
		(layers "F.Cu" "B.Cu")
		(net "GND")
	)
	(via
		(at 415.540698 -85.246464)
		(size 0.508)
		(drill 0.254)
		(layers "F.Cu" "B.Cu")
		(net "GND")
	)
	(via
		(at 375.969022 -279.931114)
		(size 0.508)
		(drill 0.254)
		(layers "F.Cu" "B.Cu")
		(net "GND")
	)
	(via
		(at 249.058176 -123.097036)
		(size 0.508)
		(drill 0.254)
		(layers "F.Cu" "B.Cu")
		(net "GND")
	)
	(via
		(at 189.413388 -31.118302)
		(size 0.508)
		(drill 0.254)
		(layers "F.Cu" "B.Cu")
		(net "GND")
	)
	(via
		(at 418.927788 -407.638504)
		(size 0.508)
		(drill 0.254)
		(layers "F.Cu" "B.Cu")
		(net "GND")
	)
	(via
		(at 79.599536 -287.349946)
		(size 0.4064)
		(drill 0.2032)
		(layers "F.Cu" "B.Cu")
		(net "GND")
	)
	(via
		(at 275.224748 -276.424898)
		(size 0.4064)
		(drill 0.2032)
		(layers "F.Cu" "B.Cu")
		(net "GND")
	)
	(via
		(at 133.796024 -161.54527)
		(size 0.508)
		(drill 0.254)
		(layers "F.Cu" "B.Cu")
		(net "GND")
	)
	(via
		(at 180.50002 -314.899802)
		(size 0.4064)
		(drill 0.2032)
		(layers "F.Cu" "B.Cu")
		(net "GND")
	)
	(via
		(at 258.231386 -398.467834)
		(size 0.508)
		(drill 0.254)
		(layers "F.Cu" "B.Cu")
		(net "GND")
	)
	(via
		(at 286.624776 -298.27474)
		(size 0.4064)
		(drill 0.2032)
		(layers "F.Cu" "B.Cu")
		(net "GND")
	)
	(via
		(at 340.58098 -329.564492)
		(size 0.508)
		(drill 0.254)
		(layers "F.Cu" "B.Cu")
		(net "GND")
	)
	(via
		(at 79.323184 -51.019456)
		(size 0.508)
		(drill 0.254)
		(layers "F.Cu" "B.Cu")
		(net "GND")
	)
	(via
		(at 431.700178 -274.999958)
		(size 0.4064)
		(drill 0.2032)
		(layers "F.Cu" "B.Cu")
		(net "GND")
	)
	(via
		(at 444.97117 -31.652972)
		(size 0.508)
		(drill 0.254)
		(layers "F.Cu" "B.Cu")
		(net "GND")
	)
	(via
		(at 434.327808 -380.040134)
		(size 0.508)
		(drill 0.254)
		(layers "F.Cu" "B.Cu")
		(net "GND")
	)
	(via
		(at 193.799968 -287.349946)
		(size 0.4064)
		(drill 0.2032)
		(layers "F.Cu" "B.Cu")
		(net "GND")
	)
	(via
		(at 366.467644 -122.09907)
		(size 0.508)
		(drill 0.254)
		(layers "F.Cu" "B.Cu")
		(net "GND")
	)
	(via
		(at 313.557666 -25.971246)
		(size 0.508)
		(drill 0.254)
		(layers "F.Cu" "B.Cu")
		(net "GND")
	)
	(via
		(at 145.741136 -388.784084)
		(size 0.508)
		(drill 0.254)
		(layers "F.Cu" "B.Cu")
		(net "GND")
	)
	(via
		(at 194.274948 -289.724846)
		(size 0.4064)
		(drill 0.2032)
		(layers "F.Cu" "B.Cu")
		(net "GND")
	)
	(via
		(at 181.912514 -136.645142)
		(size 0.508)
		(drill 0.254)
		(layers "F.Cu" "B.Cu")
		(net "GND")
	)
	(via
		(at 79.457042 -345.465146)
		(size 0.4064)
		(drill 0.2032)
		(layers "F.Cu" "B.Cu")
		(net "GND")
	)
	(via
		(at 372.62054 -345.465146)
		(size 0.4064)
		(drill 0.2032)
		(layers "F.Cu" "B.Cu")
		(net "GND")
	)
	(via
		(at 55.374794 -294.4749)
		(size 0.4064)
		(drill 0.2032)
		(layers "F.Cu" "B.Cu")
		(net "GND")
	)
	(via
		(at 423.15003 -315.849762)
		(size 0.4064)
		(drill 0.2032)
		(layers "F.Cu" "B.Cu")
		(net "GND")
	)
	(via
		(at 191.599312 -345.465146)
		(size 0.4064)
		(drill 0.2032)
		(layers "F.Cu" "B.Cu")
		(net "GND")
	)
	(via
		(at 452.775574 -308.3052)
		(size 0.508)
		(drill 0.254)
		(layers "F.Cu" "B.Cu")
		(net "GND")
	)
	(via
		(at 450.824346 -289.514788)
		(size 0.508)
		(drill 0.254)
		(layers "F.Cu" "B.Cu")
		(net "GND")
	)
	(via
		(at 293.84879 -29.589984)
		(size 0.508)
		(drill 0.254)
		(layers "F.Cu" "B.Cu")
		(net "GND")
	)
	(via
		(at 335.328006 -403.738588)
		(size 0.508)
		(drill 0.254)
		(layers "F.Cu" "B.Cu")
		(net "GND")
	)
	(via
		(at 423.149776 -279.749758)
		(size 0.4064)
		(drill 0.2032)
		(layers "F.Cu" "B.Cu")
		(net "GND")
	)
	(via
		(at 245.452138 -34.990024)
		(size 0.508)
		(drill 0.254)
		(layers "F.Cu" "B.Cu")
		(net "GND")
	)
	(via
		(at 289.127692 -407.24201)
		(size 0.508)
		(drill 0.254)
		(layers "F.Cu" "B.Cu")
		(net "GND")
	)
	(via
		(at 414.124902 -297.32478)
		(size 0.4064)
		(drill 0.2032)
		(layers "F.Cu" "B.Cu")
		(net "GND")
	)
	(via
		(at 167.200072 -277.849838)
		(size 0.4064)
		(drill 0.2032)
		(layers "F.Cu" "B.Cu")
		(net "GND")
	)
	(via
		(at 37.133784 -107.57535)
		(size 0.508)
		(drill 0.254)
		(layers "F.Cu" "B.Cu")
		(net "GND")
	)
	(via
		(at 190.348108 -145.755106)
		(size 0.508)
		(drill 0.254)
		(layers "F.Cu" "B.Cu")
		(net "GND")
	)
	(via
		(at 7.095236 -305.894994)
		(size 0.508)
		(drill 0.254)
		(layers "F.Cu" "B.Cu")
		(net "GND")
	)
	(via
		(at 200.908158 -132.77342)
		(size 0.508)
		(drill 0.254)
		(layers "F.Cu" "B.Cu")
		(net "GND")
	)
	(via
		(at 277.599902 -307.299868)
		(size 0.4064)
		(drill 0.2032)
		(layers "F.Cu" "B.Cu")
		(net "GND")
	)
	(via
		(at 278.656542 -357.75773)
		(size 0.4064)
		(drill 0.2032)
		(layers "F.Cu" "B.Cu")
		(net "GND")
	)
	(via
		(at 413.649922 -274.999958)
		(size 0.4064)
		(drill 0.2032)
		(layers "F.Cu" "B.Cu")
		(net "GND")
	)
	(via
		(at 93.704918 -303.636426)
		(size 0.508)
		(drill 0.254)
		(layers "F.Cu" "B.Cu")
		(net "GND")
	)
	(via
		(at 130.74777 -376.140218)
		(size 0.4572)
		(drill 0.254)
		(layers "F.Cu" "B.Cu")
		(net "GND")
	)
	(via
		(at 235.476288 -98.295968)
		(size 0.508)
		(drill 0.254)
		(layers "F.Cu" "B.Cu")
		(net "GND")
	)
	(via
		(at 393.351766 -120.555004)
		(size 0.508)
		(drill 0.254)
		(layers "F.Cu" "B.Cu")
		(net "GND")
	)
	(via
		(at 51.48326 -344.831162)
		(size 0.4572)
		(drill 0.254)
		(layers "F.Cu" "B.Cu")
		(net "GND")
	)
	(via
		(at 425.04995 -279.749758)
		(size 0.4064)
		(drill 0.2032)
		(layers "F.Cu" "B.Cu")
		(net "GND")
	)
	(via
		(at 74.84999 -315.849762)
		(size 0.4064)
		(drill 0.2032)
		(layers "F.Cu" "B.Cu")
		(net "GND")
	)
	(via
		(at 388.474966 -292.574726)
		(size 0.4064)
		(drill 0.2032)
		(layers "F.Cu" "B.Cu")
		(net "GND")
	)
	(via
		(at 47.29988 -317.749936)
		(size 0.4064)
		(drill 0.2032)
		(layers "F.Cu" "B.Cu")
		(net "GND")
	)
	(via
		(at 441.921138 -103.890064)
		(size 0.508)
		(drill 0.254)
		(layers "F.Cu" "B.Cu")
		(net "GND")
	)
	(via
		(at 55.872126 -33.857692)
		(size 0.508)
		(drill 0.254)
		(layers "F.Cu" "B.Cu")
		(net "GND")
	)
	(via
		(at 313.699906 -288.299906)
		(size 0.4064)
		(drill 0.2032)
		(layers "F.Cu" "B.Cu")
		(net "GND")
	)
	(via
		(at 51.63312 -118.754906)
		(size 0.508)
		(drill 0.254)
		(layers "F.Cu" "B.Cu")
		(net "GND")
	)
	(via
		(at 412.20644 -357.123746)
		(size 0.4572)
		(drill 0.254)
		(layers "F.Cu" "B.Cu")
		(net "GND")
	)
	(via
		(at 429.800004 -309.199788)
		(size 0.4064)
		(drill 0.2032)
		(layers "F.Cu" "B.Cu")
		(net "GND")
	)
	(via
		(at 360.170476 -290.05149)
		(size 0.508)
		(drill 0.254)
		(layers "F.Cu" "B.Cu")
		(net "GND")
	)
	(via
		(at 392.753088 -357.123746)
		(size 0.4572)
		(drill 0.254)
		(layers "F.Cu" "B.Cu")
		(net "GND")
	)
	(via
		(at 397.97482 -287.824926)
		(size 0.4064)
		(drill 0.2032)
		(layers "F.Cu" "B.Cu")
		(net "GND")
	)
	(via
		(at 128.46812 -357.123746)
		(size 0.4572)
		(drill 0.254)
		(layers "F.Cu" "B.Cu")
		(net "GND")
	)
	(via
		(at 191.227964 -346.09913)
		(size 0.4572)
		(drill 0.254)
		(layers "F.Cu" "B.Cu")
		(net "GND")
	)
	(via
		(at 379.816106 -256.375916)
		(size 0.508)
		(drill 0.254)
		(layers "F.Cu" "B.Cu")
		(net "GND")
	)
	(via
		(at 161.500058 -301.599854)
		(size 0.4064)
		(drill 0.2032)
		(layers "F.Cu" "B.Cu")
		(net "GND")
	)
	(via
		(at 349.410782 -290.68649)
		(size 0.508)
		(drill 0.254)
		(layers "F.Cu" "B.Cu")
		(net "GND")
	)
	(via
		(at 415.074862 -284.974792)
		(size 0.4064)
		(drill 0.2032)
		(layers "F.Cu" "B.Cu")
		(net "GND")
	)
	(via
		(at 53.48732 -104.244902)
		(size 0.508)
		(drill 0.254)
		(layers "F.Cu" "B.Cu")
		(net "GND")
	)
	(via
		(at 304.139092 -28.05303)
		(size 0.508)
		(drill 0.254)
		(layers "F.Cu" "B.Cu")
		(net "GND")
	)
	(via
		(at 119.747792 -375.040144)
		(size 0.4572)
		(drill 0.254)
		(layers "F.Cu" "B.Cu")
		(net "GND")
	)
	(via
		(at 123.92025 -34.990278)
		(size 0.508)
		(drill 0.254)
		(layers "F.Cu" "B.Cu")
		(net "GND")
	)
	(via
		(at 239.00003 -38.315138)
		(size 0.508)
		(drill 0.254)
		(layers "F.Cu" "B.Cu")
		(net "GND")
	)
	(via
		(at 418.874956 -292.57498)
		(size 0.4064)
		(drill 0.2032)
		(layers "F.Cu" "B.Cu")
		(net "GND")
	)
	(via
		(at 231.149144 -178.38039)
		(size 0.508)
		(drill 0.254)
		(layers "F.Cu" "B.Cu")
		(net "GND")
	)
	(via
		(at 381.576072 -354.098098)
		(size 0.4572)
		(drill 0.254)
		(layers "F.Cu" "B.Cu")
		(net "GND")
	)
	(via
		(at 47.77486 -290.674806)
		(size 0.4064)
		(drill 0.2032)
		(layers "F.Cu" "B.Cu")
		(net "GND")
	)
	(via
		(at 288.99993 -310.149748)
		(size 0.4064)
		(drill 0.2032)
		(layers "F.Cu" "B.Cu")
		(net "GND")
	)
	(via
		(at 326.141334 -238.762032)
		(size 0.508)
		(drill 0.254)
		(layers "F.Cu" "B.Cu")
		(net "GND")
	)
	(via
		(at 246.561102 -134.335012)
		(size 0.508)
		(drill 0.254)
		(layers "F.Cu" "B.Cu")
		(net "GND")
	)
	(via
		(at 162.587686 -26.360882)
		(size 0.508)
		(drill 0.254)
		(layers "F.Cu" "B.Cu")
		(net "GND")
	)
	(via
		(at 377.086876 -0.762)
		(size 0.508)
		(drill 0.254)
		(layers "F.Cu" "B.Cu")
		(net "GND")
	)
	(via
		(at 388.474966 -283.074872)
		(size 0.4064)
		(drill 0.2032)
		(layers "F.Cu" "B.Cu")
		(net "GND")
	)
	(via
		(at 427.727872 -371.140228)
		(size 0.508)
		(drill 0.254)
		(layers "F.Cu" "B.Cu")
		(net "GND")
	)
	(via
		(at 422.548304 -156.554932)
		(size 0.508)
		(drill 0.254)
		(layers "F.Cu" "B.Cu")
		(net "GND")
	)
	(via
		(at 362.202222 -58.731404)
		(size 0.508)
		(drill 0.254)
		(layers "F.Cu" "B.Cu")
		(net "GND")
	)
	(via
		(at 281.394154 -349.219774)
		(size 0.4572)
		(drill 0.254)
		(layers "F.Cu" "B.Cu")
		(net "GND")
	)
	(via
		(at 150.103078 -296.695114)
		(size 0.508)
		(drill 0.254)
		(layers "F.Cu" "B.Cu")
		(net "GND")
	)
	(via
		(at 372.249192 -346.09913)
		(size 0.4572)
		(drill 0.254)
		(layers "F.Cu" "B.Cu")
		(net "GND")
	)
	(via
		(at 408.11323 -374.457468)
		(size 0.508)
		(drill 0.254)
		(layers "F.Cu" "B.Cu")
		(net "GND")
	)
	(via
		(at 425.527724 -408.738578)
		(size 0.508)
		(drill 0.254)
		(layers "F.Cu" "B.Cu")
		(net "GND")
	)
	(via
		(at 347.073982 -285.953454)
		(size 0.508)
		(drill 0.254)
		(layers "F.Cu" "B.Cu")
		(net "GND")
	)
	(via
		(at 165.963346 -113.780062)
		(size 0.508)
		(drill 0.254)
		(layers "F.Cu" "B.Cu")
		(net "GND")
	)
	(via
		(at 330.927964 -378.94006)
		(size 0.508)
		(drill 0.254)
		(layers "F.Cu" "B.Cu")
		(net "GND")
	)
	(via
		(at 168.148 -395.938502)
		(size 0.508)
		(drill 0.254)
		(layers "F.Cu" "B.Cu")
		(net "GND")
	)
	(via
		(at 286.240474 -115.205256)
		(size 0.508)
		(drill 0.254)
		(layers "F.Cu" "B.Cu")
		(net "GND")
	)
	(via
		(at 122.819414 -96.597724)
		(size 0.508)
		(drill 0.254)
		(layers "F.Cu" "B.Cu")
		(net "GND")
	)
	(via
		(at 427.89983 -306.349908)
		(size 0.4064)
		(drill 0.2032)
		(layers "F.Cu" "B.Cu")
		(net "GND")
	)
	(via
		(at 413.649922 -281.649932)
		(size 0.4064)
		(drill 0.2032)
		(layers "F.Cu" "B.Cu")
		(net "GND")
	)
	(via
		(at 353.776788 -270.001492)
		(size 0.508)
		(drill 0.254)
		(layers "F.Cu" "B.Cu")
		(net "GND")
	)
	(via
		(at 153.89987 -311.099962)
		(size 0.4064)
		(drill 0.2032)
		(layers "F.Cu" "B.Cu")
		(net "GND")
	)
	(via
		(at 291.32784 -395.938502)
		(size 0.508)
		(drill 0.254)
		(layers "F.Cu" "B.Cu")
		(net "GND")
	)
	(via
		(at 352.249486 -105.199942)
		(size 0.508)
		(drill 0.254)
		(layers "F.Cu" "B.Cu")
		(net "GND")
	)
	(via
		(at 87.305134 -355.366066)
		(size 0.4572)
		(drill 0.254)
		(layers "F.Cu" "B.Cu")
		(net "GND")
	)
	(via
		(at 79.12481 -288.774886)
		(size 0.4064)
		(drill 0.2032)
		(layers "F.Cu" "B.Cu")
		(net "GND")
	)
	(via
		(at 78.64983 -282.599892)
		(size 0.4064)
		(drill 0.2032)
		(layers "F.Cu" "B.Cu")
		(net "GND")
	)
	(via
		(at 414.321498 -190.66002)
		(size 0.508)
		(drill 0.254)
		(layers "F.Cu" "B.Cu")
		(net "GND")
	)
	(via
		(at 333.127858 -381.241808)
		(size 0.508)
		(drill 0.254)
		(layers "F.Cu" "B.Cu")
		(net "GND")
	)
	(via
		(at 57.087262 -368.714274)
		(size 0.4572)
		(drill 0.254)
		(layers "F.Cu" "B.Cu")
		(net "GND")
	)
	(via
		(at 383.72796 -372.341902)
		(size 0.508)
		(drill 0.254)
		(layers "F.Cu" "B.Cu")
		(net "GND")
	)
	(via
		(at 419.824916 -291.624766)
		(size 0.4064)
		(drill 0.2032)
		(layers "F.Cu" "B.Cu")
		(net "GND")
	)
	(via
		(at 91.753436 -102.328218)
		(size 0.508)
		(drill 0.254)
		(layers "F.Cu" "B.Cu")
		(net "GND")
	)
	(via
		(at 139.440158 -73.23963)
		(size 0.508)
		(drill 0.254)
		(layers "F.Cu" "B.Cu")
		(net "GND")
	)
	(via
		(at 393.7 -307.299868)
		(size 0.4064)
		(drill 0.2032)
		(layers "F.Cu" "B.Cu")
		(net "GND")
	)
	(via
		(at 269.333726 -100.375466)
		(size 0.508)
		(drill 0.254)
		(layers "F.Cu" "B.Cu")
		(net "GND")
	)
	(via
		(at 395.019276 -46.893226)
		(size 0.508)
		(drill 0.254)
		(layers "F.Cu" "B.Cu")
		(net "GND")
	)
	(via
		(at 224.182686 -252.53823)
		(size 0.508)
		(drill 0.254)
		(layers "F.Cu" "B.Cu")
		(net "GND")
	)
	(via
		(at 441.661296 -114.99596)
		(size 0.508)
		(drill 0.254)
		(layers "F.Cu" "B.Cu")
		(net "GND")
	)
	(via
		(at 384.048 -417.82492)
		(size 0.508)
		(drill 0.254)
		(layers "F.Cu" "B.Cu")
		(net "GND")
	)
	(via
		(at 162.773106 -23.880318)
		(size 0.508)
		(drill 0.254)
		(layers "F.Cu" "B.Cu")
		(net "GND")
	)
	(via
		(at 155.325064 -297.32478)
		(size 0.4064)
		(drill 0.2032)
		(layers "F.Cu" "B.Cu")
		(net "GND")
	)
	(via
		(at 219.314268 -289.391344)
		(size 0.508)
		(drill 0.254)
		(layers "F.Cu" "B.Cu")
		(net "GND")
	)
	(via
		(at 425.04995 -304.449734)
		(size 0.4064)
		(drill 0.2032)
		(layers "F.Cu" "B.Cu")
		(net "GND")
	)
	(via
		(at 176.699926 -281.649932)
		(size 0.4064)
		(drill 0.2032)
		(layers "F.Cu" "B.Cu")
		(net "GND")
	)
	(via
		(at 117.309646 -172.216064)
		(size 0.508)
		(drill 0.254)
		(layers "F.Cu" "B.Cu")
		(net "GND")
	)
	(via
		(at 300.757844 -58.156094)
		(size 0.508)
		(drill 0.254)
		(layers "F.Cu" "B.Cu")
		(net "GND")
	)
	(via
		(at 287.983422 -345.465146)
		(size 0.4064)
		(drill 0.2032)
		(layers "F.Cu" "B.Cu")
		(net "GND")
	)
	(via
		(at 139.273788 -351.611438)
		(size 0.4064)
		(drill 0.2032)
		(layers "F.Cu" "B.Cu")
		(net "GND")
	)
	(via
		(at 0.77089 -370.341144)
		(size 0.508)
		(drill 0.254)
		(layers "F.Cu" "B.Cu")
		(net "GND")
	)
	(via
		(at 391.324846 -273.574764)
		(size 0.4064)
		(drill 0.2032)
		(layers "F.Cu" "B.Cu")
		(net "GND")
	)
	(via
		(at 378.467112 -357.123746)
		(size 0.4572)
		(drill 0.254)
		(layers "F.Cu" "B.Cu")
		(net "GND")
	)
	(via
		(at 173.375066 -302.074834)
		(size 0.4064)
		(drill 0.2032)
		(layers "F.Cu" "B.Cu")
		(net "GND")
	)
	(via
		(at 45.26534 -343.073482)
		(size 0.4572)
		(drill 0.254)
		(layers "F.Cu" "B.Cu")
		(net "GND")
	)
	(via
		(at 189.892178 -70.918832)
		(size 0.508)
		(drill 0.254)
		(layers "F.Cu" "B.Cu")
		(net "GND")
	)
	(via
		(at 403.338792 -352.245422)
		(size 0.4572)
		(drill 0.254)
		(layers "F.Cu" "B.Cu")
		(net "GND")
	)
	(via
		(at 280.13533 -341.805514)
		(size 0.4572)
		(drill 0.254)
		(layers "F.Cu" "B.Cu")
		(net "GND")
	)
	(via
		(at 381.527812 -399.441924)
		(size 0.508)
		(drill 0.254)
		(layers "F.Cu" "B.Cu")
		(net "GND")
	)
	(via
		(at 420.58336 -154.461718)
		(size 0.508)
		(drill 0.254)
		(layers "F.Cu" "B.Cu")
		(net "GND")
	)
	(via
		(at 219.812108 -23.355554)
		(size 0.508)
		(drill 0.254)
		(layers "F.Cu" "B.Cu")
		(net "GND")
	)
	(via
		(at 299.14723 -196.022976)
		(size 0.508)
		(drill 0.254)
		(layers "F.Cu" "B.Cu")
		(net "GND")
	)
	(via
		(at 124.147834 -399.838418)
		(size 0.508)
		(drill 0.254)
		(layers "F.Cu" "B.Cu")
		(net "GND")
	)
	(via
		(at 45.034454 -47.936658)
		(size 0.508)
		(drill 0.254)
		(layers "F.Cu" "B.Cu")
		(net "GND")
	)
	(via
		(at 62.974982 -306.824888)
		(size 0.4064)
		(drill 0.2032)
		(layers "F.Cu" "B.Cu")
		(net "GND")
	)
	(via
		(at 375.793 -179.451)
		(size 0.508)
		(drill 0.254)
		(layers "F.Cu" "B.Cu")
		(net "GND")
	)
	(via
		(at 138.618214 -204.253846)
		(size 0.508)
		(drill 0.254)
		(layers "F.Cu" "B.Cu")
		(net "GND")
	)
	(via
		(at 120.941592 -268.096492)
		(size 0.508)
		(drill 0.254)
		(layers "F.Cu" "B.Cu")
		(net "GND")
	)
	(via
		(at 369.062 -160.8963)
		(size 0.508)
		(drill 0.254)
		(layers "F.Cu" "B.Cu")
		(net "GND")
	)
	(via
		(at 210.380834 -34.990024)
		(size 0.508)
		(drill 0.254)
		(layers "F.Cu" "B.Cu")
		(net "GND")
	)
	(via
		(at 8.128 -417.82492)
		(size 0.508)
		(drill 0.254)
		(layers "F.Cu" "B.Cu")
		(net "GND")
	)
	(via
		(at 70.141084 -38.49116)
		(size 0.508)
		(drill 0.254)
		(layers "F.Cu" "B.Cu")
		(net "GND")
	)
	(via
		(at 289.127692 -404.838662)
		(size 0.508)
		(drill 0.254)
		(layers "F.Cu" "B.Cu")
		(net "GND")
	)
	(via
		(at 163.618672 -351.611438)
		(size 0.4064)
		(drill 0.2032)
		(layers "F.Cu" "B.Cu")
		(net "GND")
	)
	(via
		(at 84.04987 -6.046724)
		(size 0.508)
		(drill 0.254)
		(layers "F.Cu" "B.Cu")
		(net "GND")
	)
	(via
		(at 311.514998 -43.85691)
		(size 0.508)
		(drill 0.254)
		(layers "F.Cu" "B.Cu")
		(net "GND")
	)
	(via
		(at 248.629678 -345.68003)
		(size 0.508)
		(drill 0.254)
		(layers "F.Cu" "B.Cu")
		(net "GND")
	)
	(via
		(at 286.35325 -350.977454)
		(size 0.4572)
		(drill 0.254)
		(layers "F.Cu" "B.Cu")
		(net "GND")
	)
	(via
		(at 286.927798 -377.738386)
		(size 0.508)
		(drill 0.254)
		(layers "F.Cu" "B.Cu")
		(net "GND")
	)
	(via
		(at 34.679636 -357.123746)
		(size 0.4572)
		(drill 0.254)
		(layers "F.Cu" "B.Cu")
		(net "GND")
	)
	(via
		(at 69.624956 -291.624766)
		(size 0.4064)
		(drill 0.2032)
		(layers "F.Cu" "B.Cu")
		(net "GND")
	)
	(via
		(at 418.874956 -299.224954)
		(size 0.4064)
		(drill 0.2032)
		(layers "F.Cu" "B.Cu")
		(net "GND")
	)
	(via
		(at 52.85232 -111.44504)
		(size 0.508)
		(drill 0.254)
		(layers "F.Cu" "B.Cu")
		(net "GND")
	)
	(via
		(at 282.661106 -169.89679)
		(size 0.508)
		(drill 0.254)
		(layers "F.Cu" "B.Cu")
		(net "GND")
	)
	(via
		(at 185.783982 -122.597164)
		(size 0.508)
		(drill 0.254)
		(layers "F.Cu" "B.Cu")
		(net "GND")
	)
	(via
		(at 285.199836 -314.899802)
		(size 0.4064)
		(drill 0.2032)
		(layers "F.Cu" "B.Cu")
		(net "GND")
	)
	(via
		(at 50.14976 -316.799722)
		(size 0.4064)
		(drill 0.2032)
		(layers "F.Cu" "B.Cu")
		(net "GND")
	)
	(via
		(at 383.72796 -247.32996)
		(size 0.508)
		(drill 0.254)
		(layers "F.Cu" "B.Cu")
		(net "GND")
	)
	(via
		(at 195.699888 -283.549852)
		(size 0.4064)
		(drill 0.2032)
		(layers "F.Cu" "B.Cu")
		(net "GND")
	)
	(via
		(at 126.347728 -371.038628)
		(size 0.508)
		(drill 0.254)
		(layers "F.Cu" "B.Cu")
		(net "GND")
	)
	(via
		(at 278.656542 -351.611438)
		(size 0.4064)
		(drill 0.2032)
		(layers "F.Cu" "B.Cu")
		(net "GND")
	)
	(via
		(at 180.693314 -145.755106)
		(size 0.508)
		(drill 0.254)
		(layers "F.Cu" "B.Cu")
		(net "GND")
	)
	(via
		(at 384.059684 -131.495546)
		(size 0.508)
		(drill 0.254)
		(layers "F.Cu" "B.Cu")
		(net "GND")
	)
	(via
		(at 353.99853 -306.55387)
		(size 0.508)
		(drill 0.254)
		(layers "F.Cu" "B.Cu")
		(net "GND")
	)
	(via
		(at 41.124886 -272.624804)
		(size 0.4064)
		(drill 0.2032)
		(layers "F.Cu" "B.Cu")
		(net "GND")
	)
	(via
		(at 64.28359 -355.366066)
		(size 0.4572)
		(drill 0.254)
		(layers "F.Cu" "B.Cu")
		(net "GND")
	)
	(via
		(at 290.42487 -289.724846)
		(size 0.4064)
		(drill 0.2032)
		(layers "F.Cu" "B.Cu")
		(net "GND")
	)
	(via
		(at 58.699908 -274.049744)
		(size 0.4064)
		(drill 0.2032)
		(layers "F.Cu" "B.Cu")
		(net "GND")
	)
	(via
		(at 427.727872 -410.041852)
		(size 0.508)
		(drill 0.254)
		(layers "F.Cu" "B.Cu")
		(net "GND")
	)
	(via
		(at 61.023246 -159.595312)
		(size 0.508)
		(drill 0.254)
		(layers "F.Cu" "B.Cu")
		(net "GND")
	)
	(via
		(at 347.166438 -293.424102)
		(size 0.508)
		(drill 0.254)
		(layers "F.Cu" "B.Cu")
		(net "GND")
	)
	(via
		(at 192.850008 -283.549852)
		(size 0.4064)
		(drill 0.2032)
		(layers "F.Cu" "B.Cu")
		(net "GND")
	)
	(via
		(at 278.549862 -316.799722)
		(size 0.4064)
		(drill 0.2032)
		(layers "F.Cu" "B.Cu")
		(net "GND")
	)
	(via
		(at 307.049932 -311.099962)
		(size 0.4064)
		(drill 0.2032)
		(layers "F.Cu" "B.Cu")
		(net "GND")
	)
	(via
		(at 93.621098 -103.890064)
		(size 0.508)
		(drill 0.254)
		(layers "F.Cu" "B.Cu")
		(net "GND")
	)
	(via
		(at 82.93735 -357.123746)
		(size 0.4572)
		(drill 0.254)
		(layers "F.Cu" "B.Cu")
		(net "GND")
	)
	(via
		(at 82.566002 -357.75773)
		(size 0.4064)
		(drill 0.2032)
		(layers "F.Cu" "B.Cu")
		(net "GND")
	)
	(via
		(at 416.974782 -301.124874)
		(size 0.4064)
		(drill 0.2032)
		(layers "F.Cu" "B.Cu")
		(net "GND")
	)
	(via
		(at 336.805524 -357.75773)
		(size 0.4064)
		(drill 0.2032)
		(layers "F.Cu" "B.Cu")
		(net "GND")
	)
	(via
		(at 372.383304 -248.855484)
		(size 0.508)
		(drill 0.254)
		(layers "F.Cu" "B.Cu")
		(net "GND")
	)
	(via
		(at 186.220608 -63.218314)
		(size 0.508)
		(drill 0.254)
		(layers "F.Cu" "B.Cu")
		(net "GND")
	)
	(via
		(at 141.806676 -199.367394)
		(size 0.508)
		(drill 0.254)
		(layers "F.Cu" "B.Cu")
		(net "GND")
	)
	(via
		(at 392.52779 -369.938808)
		(size 0.508)
		(drill 0.254)
		(layers "F.Cu" "B.Cu")
		(net "GND")
	)
	(via
		(at 450.113146 -284.764988)
		(size 0.508)
		(drill 0.254)
		(layers "F.Cu" "B.Cu")
		(net "GND")
	)
	(via
		(at 171.31538 -343.073482)
		(size 0.4572)
		(drill 0.254)
		(layers "F.Cu" "B.Cu")
		(net "GND")
	)
	(via
		(at 450.497956 -227.39985)
		(size 0.508)
		(drill 0.254)
		(layers "F.Cu" "B.Cu")
		(net "GND")
	)
	(via
		(at 451.657466 -29.784294)
		(size 0.508)
		(drill 0.254)
		(layers "F.Cu" "B.Cu")
		(net "GND")
	)
	(via
		(at 314.141866 -49.574704)
		(size 0.508)
		(drill 0.254)
		(layers "F.Cu" "B.Cu")
		(net "GND")
	)
	(via
		(at 463.037682 -204.737462)
		(size 0.508)
		(drill 0.254)
		(layers "F.Cu" "B.Cu")
		(net "GND")
	)
	(via
		(at 33.947862 -377.341892)
		(size 0.508)
		(drill 0.254)
		(layers "F.Cu" "B.Cu")
		(net "GND")
	)
	(via
		(at 188.254894 -96.901)
		(size 0.508)
		(drill 0.254)
		(layers "F.Cu" "B.Cu")
		(net "GND")
	)
	(via
		(at 435.948836 -34.990024)
		(size 0.508)
		(drill 0.254)
		(layers "F.Cu" "B.Cu")
		(net "GND")
	)
	(via
		(at 68.674742 -306.824888)
		(size 0.4064)
		(drill 0.2032)
		(layers "F.Cu" "B.Cu")
		(net "GND")
	)
	(via
		(at 188.490352 -357.733854)
		(size 0.4064)
		(drill 0.2032)
		(layers "F.Cu" "B.Cu")
		(net "GND")
	)
	(via
		(at 146.815302 -60.601606)
		(size 0.508)
		(drill 0.254)
		(layers "F.Cu" "B.Cu")
		(net "GND")
	)
	(via
		(at 340.285832 -344.831162)
		(size 0.4572)
		(drill 0.254)
		(layers "F.Cu" "B.Cu")
		(net "GND")
	)
	(via
		(at 283.299916 -312.999882)
		(size 0.4064)
		(drill 0.2032)
		(layers "F.Cu" "B.Cu")
		(net "GND")
	)
	(via
		(at 444.882016 -58.238644)
		(size 0.508)
		(drill 0.254)
		(layers "F.Cu" "B.Cu")
		(net "GND")
	)
	(via
		(at 375.7295 -351.611438)
		(size 0.4064)
		(drill 0.2032)
		(layers "F.Cu" "B.Cu")
		(net "GND")
	)
	(via
		(at 398.925034 -287.824926)
		(size 0.4064)
		(drill 0.2032)
		(layers "F.Cu" "B.Cu")
		(net "GND")
	)
	(via
		(at 267.959586 -130.236722)
		(size 0.508)
		(drill 0.254)
		(layers "F.Cu" "B.Cu")
		(net "GND")
	)
	(via
		(at 276.93112 -11.372342)
		(size 0.508)
		(drill 0.254)
		(layers "F.Cu" "B.Cu")
		(net "GND")
	)
	(via
		(at 165.774878 -302.074834)
		(size 0.4064)
		(drill 0.2032)
		(layers "F.Cu" "B.Cu")
		(net "GND")
	)
	(via
		(at 240.655094 -29.590238)
		(size 0.508)
		(drill 0.254)
		(layers "F.Cu" "B.Cu")
		(net "GND")
	)
	(via
		(at 170.806364 -106.044746)
		(size 0.508)
		(drill 0.254)
		(layers "F.Cu" "B.Cu")
		(net "GND")
	)
	(via
		(at 57.274968 -305.874928)
		(size 0.4064)
		(drill 0.2032)
		(layers "F.Cu" "B.Cu")
		(net "GND")
	)
	(via
		(at 128.46812 -343.073482)
		(size 0.4572)
		(drill 0.254)
		(layers "F.Cu" "B.Cu")
		(net "GND")
	)
	(via
		(at 398.864074 -175.730154)
		(size 0.508)
		(drill 0.254)
		(layers "F.Cu" "B.Cu")
		(net "GND")
	)
	(via
		(at 380.317248 -349.219774)
		(size 0.4572)
		(drill 0.254)
		(layers "F.Cu" "B.Cu")
		(net "GND")
	)
	(via
		(at 168.150032 -311.099962)
		(size 0.4064)
		(drill 0.2032)
		(layers "F.Cu" "B.Cu")
		(net "GND")
	)
	(via
		(at 189.049914 -281.649932)
		(size 0.4064)
		(drill 0.2032)
		(layers "F.Cu" "B.Cu")
		(net "GND")
	)
	(via
		(at 423.15003 -305.399948)
		(size 0.4064)
		(drill 0.2032)
		(layers "F.Cu" "B.Cu")
		(net "GND")
	)
	(via
		(at 387.050026 -319.65011)
		(size 0.4064)
		(drill 0.2032)
		(layers "F.Cu" "B.Cu")
		(net "GND")
	)
	(via
		(at 40.547798 -376.241818)
		(size 0.508)
		(drill 0.254)
		(layers "F.Cu" "B.Cu")
		(net "GND")
	)
	(via
		(at 85.741256 -258.646676)
		(size 0.508)
		(drill 0.254)
		(layers "F.Cu" "B.Cu")
		(net "GND")
	)
	(via
		(at 253.471934 -84.748116)
		(size 0.508)
		(drill 0.254)
		(layers "F.Cu" "B.Cu")
		(net "GND")
	)
	(via
		(at 382.802384 -253.45644)
		(size 0.508)
		(drill 0.254)
		(layers "F.Cu" "B.Cu")
		(net "GND")
	)
	(via
		(at 197.600062 -317.749936)
		(size 0.4064)
		(drill 0.2032)
		(layers "F.Cu" "B.Cu")
		(net "GND")
	)
	(via
		(at 36.374832 -287.824926)
		(size 0.4064)
		(drill 0.2032)
		(layers "F.Cu" "B.Cu")
		(net "GND")
	)
	(via
		(at 133.796024 -162.25647)
		(size 0.508)
		(drill 0.254)
		(layers "F.Cu" "B.Cu")
		(net "GND")
	)
	(via
		(at 194.749928 -304.449734)
		(size 0.4064)
		(drill 0.2032)
		(layers "F.Cu" "B.Cu")
		(net "GND")
	)
	(via
		(at 69.149976 -281.649932)
		(size 0.4064)
		(drill 0.2032)
		(layers "F.Cu" "B.Cu")
		(net "GND")
	)
	(via
		(at 281.640788 -45.853858)
		(size 0.508)
		(drill 0.254)
		(layers "F.Cu" "B.Cu")
		(net "GND")
	)
	(via
		(at 79.12481 -292.574726)
		(size 0.4064)
		(drill 0.2032)
		(layers "F.Cu" "B.Cu")
		(net "GND")
	)
	(via
		(at 286.164782 -142.367)
		(size 0.508)
		(drill 0.254)
		(layers "F.Cu" "B.Cu")
		(net "GND")
	)
	(via
		(at 127.97028 -288.14649)
		(size 0.508)
		(drill 0.254)
		(layers "F.Cu" "B.Cu")
		(net "GND")
	)
	(via
		(at 292.57117 -341.805514)
		(size 0.4572)
		(drill 0.254)
		(layers "F.Cu" "B.Cu")
		(net "GND")
	)
	(via
		(at 452.28891 -229.310184)
		(size 0.508)
		(drill 0.254)
		(layers "F.Cu" "B.Cu")
		(net "GND")
	)
	(via
		(at 300.047914 -341.805514)
		(size 0.4572)
		(drill 0.254)
		(layers "F.Cu" "B.Cu")
		(net "GND")
	)
	(via
		(at 279.513284 -34.718498)
		(size 0.508)
		(drill 0.254)
		(layers "F.Cu" "B.Cu")
		(net "GND")
	)
	(via
		(at 44.94784 -373.838724)
		(size 0.508)
		(drill 0.254)
		(layers "F.Cu" "B.Cu")
		(net "GND")
	)
	(via
		(at 454.252584 -227.346764)
		(size 0.508)
		(drill 0.254)
		(layers "F.Cu" "B.Cu")
		(net "GND")
	)
	(via
		(at 300.399704 -277.849838)
		(size 0.4064)
		(drill 0.2032)
		(layers "F.Cu" "B.Cu")
		(net "GND")
	)
	(via
		(at 317.008256 -147.824698)
		(size 0.508)
		(drill 0.254)
		(layers "F.Cu" "B.Cu")
		(net "GND")
	)
	(via
		(at 318.019938 -33.19018)
		(size 0.508)
		(drill 0.254)
		(layers "F.Cu" "B.Cu")
		(net "GND")
	)
	(via
		(at 83.540346 -149.083522)
		(size 0.508)
		(drill 0.254)
		(layers "F.Cu" "B.Cu")
		(net "GND")
	)
	(via
		(at 392.274806 -300.174914)
		(size 0.4064)
		(drill 0.2032)
		(layers "F.Cu" "B.Cu")
		(net "GND")
	)
	(via
		(at 289.127692 -403.34184)
		(size 0.508)
		(drill 0.254)
		(layers "F.Cu" "B.Cu")
		(net "GND")
	)
	(via
		(at 198.550022 -317.749936)
		(size 0.4064)
		(drill 0.2032)
		(layers "F.Cu" "B.Cu")
		(net "GND")
	)
	(via
		(at 328.353674 -84.28228)
		(size 0.508)
		(drill 0.254)
		(layers "F.Cu" "B.Cu")
		(net "GND")
	)
	(via
		(at 188.119004 -355.34219)
		(size 0.4572)
		(drill 0.254)
		(layers "F.Cu" "B.Cu")
		(net "GND")
	)
	(via
		(at 237.34014 -27.729688)
		(size 0.508)
		(drill 0.254)
		(layers "F.Cu" "B.Cu")
		(net "GND")
	)
	(via
		(at 100.476558 -114.310414)
		(size 0.508)
		(drill 0.254)
		(layers "F.Cu" "B.Cu")
		(net "GND")
	)
	(via
		(at 111.056674 -293.345108)
		(size 0.508)
		(drill 0.254)
		(layers "F.Cu" "B.Cu")
		(net "GND")
	)
	(via
		(at 48.3743 -355.366066)
		(size 0.4572)
		(drill 0.254)
		(layers "F.Cu" "B.Cu")
		(net "GND")
	)
	(via
		(at 336.80908 -108.39196)
		(size 0.508)
		(drill 0.254)
		(layers "F.Cu" "B.Cu")
		(net "GND")
	)
	(via
		(at 0.77089 -273.821144)
		(size 0.508)
		(drill 0.254)
		(layers "F.Cu" "B.Cu")
		(net "GND")
	)
	(via
		(at 401.774914 -291.624766)
		(size 0.4064)
		(drill 0.2032)
		(layers "F.Cu" "B.Cu")
		(net "GND")
	)
	(via
		(at 426.272452 -351.611438)
		(size 0.4064)
		(drill 0.2032)
		(layers "F.Cu" "B.Cu")
		(net "GND")
	)
	(via
		(at 170.049952 -319.65011)
		(size 0.4064)
		(drill 0.2032)
		(layers "F.Cu" "B.Cu")
		(net "GND")
	)
	(via
		(at 415.96691 -145.755106)
		(size 0.508)
		(drill 0.254)
		(layers "F.Cu" "B.Cu")
		(net "GND")
	)
	(via
		(at 47.147988 -377.342146)
		(size 0.508)
		(drill 0.254)
		(layers "F.Cu" "B.Cu")
		(net "GND")
	)
	(via
		(at 219.314268 -287.105344)
		(size 0.508)
		(drill 0.254)
		(layers "F.Cu" "B.Cu")
		(net "GND")
	)
	(via
		(at 246.093996 -290.872926)
		(size 0.508)
		(drill 0.254)
		(layers "F.Cu" "B.Cu")
		(net "GND")
	)
	(via
		(at 167.200072 -313.949842)
		(size 0.4064)
		(drill 0.2032)
		(layers "F.Cu" "B.Cu")
		(net "GND")
	)
	(via
		(at 429.927766 -376.140218)
		(size 0.508)
		(drill 0.254)
		(layers "F.Cu" "B.Cu")
		(net "GND")
	)
	(via
		(at 277.599902 -302.549814)
		(size 0.4064)
		(drill 0.2032)
		(layers "F.Cu" "B.Cu")
		(net "GND")
	)
	(via
		(at 80.07477 -300.174914)
		(size 0.4064)
		(drill 0.2032)
		(layers "F.Cu" "B.Cu")
		(net "GND")
	)
	(via
		(at 441.376562 -119.936006)
		(size 0.508)
		(drill 0.254)
		(layers "F.Cu" "B.Cu")
		(net "GND")
	)
	(via
		(at 138.68146 -31.118302)
		(size 0.508)
		(drill 0.254)
		(layers "F.Cu" "B.Cu")
		(net "GND")
	)
	(via
		(at 70.21068 -57.439814)
		(size 0.508)
		(drill 0.254)
		(layers "F.Cu" "B.Cu")
		(net "GND")
	)
	(via
		(at 216.087452 -121.255028)
		(size 0.508)
		(drill 0.254)
		(layers "F.Cu" "B.Cu")
		(net "GND")
	)
	(via
		(at 174.42434 -352.245422)
		(size 0.4572)
		(drill 0.254)
		(layers "F.Cu" "B.Cu")
		(net "GND")
	)
	(via
		(at 352.752152 -108.800392)
		(size 0.508)
		(drill 0.254)
		(layers "F.Cu" "B.Cu")
		(net "GND")
	)
	(via
		(at 423.32783 -410.041852)
		(size 0.508)
		(drill 0.254)
		(layers "F.Cu" "B.Cu")
		(net "GND")
	)
	(via
		(at 88.947752 -377.73864)
		(size 0.508)
		(drill 0.254)
		(layers "F.Cu" "B.Cu")
		(net "GND")
	)
	(via
		(at 339.513926 -292.789102)
		(size 0.508)
		(drill 0.254)
		(layers "F.Cu" "B.Cu")
		(net "GND")
	)
	(via
		(at 178.792124 -358.391714)
		(size 0.4572)
		(drill 0.254)
		(layers "F.Cu" "B.Cu")
		(net "GND")
	)
	(via
		(at 418.484558 -73.20026)
		(size 0.508)
		(drill 0.254)
		(layers "F.Cu" "B.Cu")
		(net "GND")
	)
	(via
		(at 411.275022 -296.37482)
		(size 0.4064)
		(drill 0.2032)
		(layers "F.Cu" "B.Cu")
		(net "GND")
	)
	(via
		(at 399.93316 -111.44504)
		(size 0.508)
		(drill 0.254)
		(layers "F.Cu" "B.Cu")
		(net "GND")
	)
	(via
		(at 346.327984 -377.341892)
		(size 0.508)
		(drill 0.254)
		(layers "F.Cu" "B.Cu")
		(net "GND")
	)
	(via
		(at 63.449962 -274.999958)
		(size 0.4064)
		(drill 0.2032)
		(layers "F.Cu" "B.Cu")
		(net "GND")
	)
	(via
		(at 172.547788 -399.838418)
		(size 0.508)
		(drill 0.254)
		(layers "F.Cu" "B.Cu")
		(net "GND")
	)
	(via
		(at 45.051726 -104.244902)
		(size 0.508)
		(drill 0.254)
		(layers "F.Cu" "B.Cu")
		(net "GND")
	)
	(via
		(at 92.26423 -347.951806)
		(size 0.4572)
		(drill 0.254)
		(layers "F.Cu" "B.Cu")
		(net "GND")
	)
	(via
		(at 277.031196 -60.099194)
		(size 0.508)
		(drill 0.254)
		(layers "F.Cu" "B.Cu")
		(net "GND")
	)
	(via
		(at 172.424852 -289.724846)
		(size 0.4064)
		(drill 0.2032)
		(layers "F.Cu" "B.Cu")
		(net "GND")
	)
	(via
		(at 57.749948 -315.849762)
		(size 0.4064)
		(drill 0.2032)
		(layers "F.Cu" "B.Cu")
		(net "GND")
	)
	(via
		(at 186.675014 -291.624766)
		(size 0.4064)
		(drill 0.2032)
		(layers "F.Cu" "B.Cu")
		(net "GND")
	)
	(via
		(at 356.173024 -293.424102)
		(size 0.508)
		(drill 0.254)
		(layers "F.Cu" "B.Cu")
		(net "GND")
	)
	(via
		(at 284.503114 -357.123746)
		(size 0.4572)
		(drill 0.254)
		(layers "F.Cu" "B.Cu")
		(net "GND")
	)
	(via
		(at 307.999892 -318.699896)
		(size 0.4064)
		(drill 0.2032)
		(layers "F.Cu" "B.Cu")
		(net "GND")
	)
	(via
		(at 427.75124 -346.09913)
		(size 0.4572)
		(drill 0.254)
		(layers "F.Cu" "B.Cu")
		(net "GND")
	)
	(via
		(at 38.401752 -120.833134)
		(size 0.508)
		(drill 0.254)
		(layers "F.Cu" "B.Cu")
		(net "GND")
	)
	(via
		(at 19.520154 -57.076848)
		(size 0.508)
		(drill 0.254)
		(layers "F.Cu" "B.Cu")
		(net "GND")
	)
	(via
		(at 51.854608 -348.58579)
		(size 0.4064)
		(drill 0.2032)
		(layers "F.Cu" "B.Cu")
		(net "GND")
	)
	(via
		(at 119.512588 -342.439498)
		(size 0.4064)
		(drill 0.2032)
		(layers "F.Cu" "B.Cu")
		(net "GND")
	)
	(via
		(at 184.658 -57.521094)
		(size 0.508)
		(drill 0.254)
		(layers "F.Cu" "B.Cu")
		(net "GND")
	)
	(via
		(at 55.849774 -314.899802)
		(size 0.4064)
		(drill 0.2032)
		(layers "F.Cu" "B.Cu")
		(net "GND")
	)
	(via
		(at 137.795 -352.245422)
		(size 0.4572)
		(drill 0.254)
		(layers "F.Cu" "B.Cu")
		(net "GND")
	)
	(via
		(at 256.586482 -48.874934)
		(size 0.508)
		(drill 0.254)
		(layers "F.Cu" "B.Cu")
		(net "GND")
	)
	(via
		(at 383.72796 -404.940262)
		(size 0.508)
		(drill 0.254)
		(layers "F.Cu" "B.Cu")
		(net "GND")
	)
	(via
		(at 181.901084 -341.805514)
		(size 0.4572)
		(drill 0.254)
		(layers "F.Cu" "B.Cu")
		(net "GND")
	)
	(via
		(at 229.030276 -278.36876)
		(size 0.508)
		(drill 0.254)
		(layers "F.Cu" "B.Cu")
		(net "GND")
	)
	(via
		(at 458.473302 -277.336758)
		(size 0.508)
		(drill 0.254)
		(layers "F.Cu" "B.Cu")
		(net "GND")
	)
	(via
		(at 402.724874 -284.974792)
		(size 0.4064)
		(drill 0.2032)
		(layers "F.Cu" "B.Cu")
		(net "GND")
	)
	(via
		(at 262.045196 -51.227482)
		(size 0.508)
		(drill 0.254)
		(layers "F.Cu" "B.Cu")
		(net "GND")
	)
	(via
		(at 402.079968 -344.831162)
		(size 0.4572)
		(drill 0.254)
		(layers "F.Cu" "B.Cu")
		(net "GND")
	)
	(via
		(at 143.869664 -64.102234)
		(size 0.508)
		(drill 0.254)
		(layers "F.Cu" "B.Cu")
		(net "GND")
	)
	(via
		(at 105.323132 -54.067456)
		(size 0.508)
		(drill 0.254)
		(layers "F.Cu" "B.Cu")
		(net "GND")
	)
	(via
		(at 439.033412 -100.803964)
		(size 0.508)
		(drill 0.254)
		(layers "F.Cu" "B.Cu")
		(net "GND")
	)
	(via
		(at 351.451926 -256.870962)
		(size 0.508)
		(drill 0.254)
		(layers "F.Cu" "B.Cu")
		(net "GND")
	)
	(via
		(at 44.006516 -347.951806)
		(size 0.4572)
		(drill 0.254)
		(layers "F.Cu" "B.Cu")
		(net "GND")
	)
	(via
		(at 283.24429 -349.219774)
		(size 0.4572)
		(drill 0.254)
		(layers "F.Cu" "B.Cu")
		(net "GND")
	)
	(via
		(at 47.96028 -21.37156)
		(size 0.508)
		(drill 0.254)
		(layers "F.Cu" "B.Cu")
		(net "GND")
	)
	(via
		(at 155.325064 -272.624804)
		(size 0.4064)
		(drill 0.2032)
		(layers "F.Cu" "B.Cu")
		(net "GND")
	)
	(via
		(at 114.402108 -354.732082)
		(size 0.4064)
		(drill 0.2032)
		(layers "F.Cu" "B.Cu")
		(net "GND")
	)
	(via
		(at 325.651368 -114.075972)
		(size 0.508)
		(drill 0.254)
		(layers "F.Cu" "B.Cu")
		(net "GND")
	)
	(via
		(at 398.925034 -289.724846)
		(size 0.4064)
		(drill 0.2032)
		(layers "F.Cu" "B.Cu")
		(net "GND")
	)
	(via
		(at 416.580828 -34.990024)
		(size 0.508)
		(drill 0.254)
		(layers "F.Cu" "B.Cu")
		(net "GND")
	)
	(via
		(at 431.840386 -149.083522)
		(size 0.508)
		(drill 0.254)
		(layers "F.Cu" "B.Cu")
		(net "GND")
	)
	(via
		(at 195.699888 -310.149748)
		(size 0.4064)
		(drill 0.2032)
		(layers "F.Cu" "B.Cu")
		(net "GND")
	)
	(via
		(at 47.29988 -274.049744)
		(size 0.4064)
		(drill 0.2032)
		(layers "F.Cu" "B.Cu")
		(net "GND")
	)
	(via
		(at 36.374832 -282.124912)
		(size 0.4064)
		(drill 0.2032)
		(layers "F.Cu" "B.Cu")
		(net "GND")
	)
	(via
		(at 266.691618 -131.495546)
		(size 0.508)
		(drill 0.254)
		(layers "F.Cu" "B.Cu")
		(net "GND")
	)
	(via
		(at 306.574698 -294.4749)
		(size 0.4064)
		(drill 0.2032)
		(layers "F.Cu" "B.Cu")
		(net "GND")
	)
	(via
		(at 281.399742 -276.899878)
		(size 0.4064)
		(drill 0.2032)
		(layers "F.Cu" "B.Cu")
		(net "GND")
	)
	(via
		(at 428.84979 -311.099962)
		(size 0.4064)
		(drill 0.2032)
		(layers "F.Cu" "B.Cu")
		(net "GND")
	)
	(via
		(at 287.11017 -115.184682)
		(size 0.508)
		(drill 0.254)
		(layers "F.Cu" "B.Cu")
		(net "GND")
	)
	(via
		(at 51.63312 -98.845116)
		(size 0.508)
		(drill 0.254)
		(layers "F.Cu" "B.Cu")
		(net "GND")
	)
	(via
		(at 198.26605 -129.707894)
		(size 0.508)
		(drill 0.254)
		(layers "F.Cu" "B.Cu")
		(net "GND")
	)
	(via
		(at 330.13904 -32.911796)
		(size 0.508)
		(drill 0.254)
		(layers "F.Cu" "B.Cu")
		(net "GND")
	)
	(via
		(at 360.86796 -261.814564)
		(size 0.508)
		(drill 0.254)
		(layers "F.Cu" "B.Cu")
		(net "GND")
	)
	(via
		(at 257.85953 -108.78947)
		(size 0.508)
		(drill 0.254)
		(layers "F.Cu" "B.Cu")
		(net "GND")
	)
	(via
		(at 23.50262 -346.09913)
		(size 0.4572)
		(drill 0.254)
		(layers "F.Cu" "B.Cu")
		(net "GND")
	)
	(via
		(at 23.402036 -169.746422)
		(size 0.508)
		(drill 0.254)
		(layers "F.Cu" "B.Cu")
		(net "GND")
	)
	(via
		(at 172.753274 -49.574704)
		(size 0.508)
		(drill 0.254)
		(layers "F.Cu" "B.Cu")
		(net "GND")
	)
	(via
		(at 136.536176 -358.391714)
		(size 0.4572)
		(drill 0.254)
		(layers "F.Cu" "B.Cu")
		(net "GND")
	)
	(via
		(at 186.83097 -6.292342)
		(size 0.508)
		(drill 0.254)
		(layers "F.Cu" "B.Cu")
		(net "GND")
	)
	(via
		(at 298.024804 -306.824888)
		(size 0.4064)
		(drill 0.2032)
		(layers "F.Cu" "B.Cu")
		(net "GND")
	)
	(via
		(at 247.88495 -217.114882)
		(size 0.508)
		(drill 0.254)
		(layers "F.Cu" "B.Cu")
		(net "GND")
	)
	(via
		(at 390.327896 -380.040134)
		(size 0.508)
		(drill 0.254)
		(layers "F.Cu" "B.Cu")
		(net "GND")
	)
	(via
		(at 74.84999 -288.299906)
		(size 0.4064)
		(drill 0.2032)
		(layers "F.Cu" "B.Cu")
		(net "GND")
	)
	(via
		(at 351.38995 -173.77156)
		(size 0.508)
		(drill 0.254)
		(layers "F.Cu" "B.Cu")
		(net "GND")
	)
	(via
		(at 346.337382 -285.267654)
		(size 0.508)
		(drill 0.254)
		(layers "F.Cu" "B.Cu")
		(net "GND")
	)
	(via
		(at 128.156208 -33.19018)
		(size 0.508)
		(drill 0.254)
		(layers "F.Cu" "B.Cu")
		(net "GND")
	)
	(via
		(at 45.636688 -348.58579)
		(size 0.4064)
		(drill 0.2032)
		(layers "F.Cu" "B.Cu")
		(net "GND")
	)
	(via
		(at 158.649924 -319.65011)
		(size 0.4064)
		(drill 0.2032)
		(layers "F.Cu" "B.Cu")
		(net "GND")
	)
	(via
		(at 388.949946 -310.149748)
		(size 0.4064)
		(drill 0.2032)
		(layers "F.Cu" "B.Cu")
		(net "GND")
	)
	(via
		(at 174.747936 -380.040134)
		(size 0.508)
		(drill 0.254)
		(layers "F.Cu" "B.Cu")
		(net "GND")
	)
	(via
		(at 382.791716 -111.72317)
		(size 0.508)
		(drill 0.254)
		(layers "F.Cu" "B.Cu")
		(net "GND")
	)
	(via
		(at 141.369796 -173.743874)
		(size 0.508)
		(drill 0.254)
		(layers "F.Cu" "B.Cu")
		(net "GND")
	)
	(via
		(at 56.324754 -284.974792)
		(size 0.4064)
		(drill 0.2032)
		(layers "F.Cu" "B.Cu")
		(net "GND")
	)
	(via
		(at 0.766318 -6.292342)
		(size 0.508)
		(drill 0.254)
		(layers "F.Cu" "B.Cu")
		(net "GND")
	)
	(via
		(at 141.275308 -345.465146)
		(size 0.4064)
		(drill 0.2032)
		(layers "F.Cu" "B.Cu")
		(net "GND")
	)
	(via
		(at 380.19863 -206.502)
		(size 0.508)
		(drill 0.254)
		(layers "F.Cu" "B.Cu")
		(net "GND")
	)
	(via
		(at 386.866384 -253.45644)
		(size 0.508)
		(drill 0.254)
		(layers "F.Cu" "B.Cu")
		(net "GND")
	)
	(via
		(at 165.424104 -26.319734)
		(size 0.508)
		(drill 0.254)
		(layers "F.Cu" "B.Cu")
		(net "GND")
	)
	(via
		(at 83.400138 -287.3502)
		(size 0.4064)
		(drill 0.2032)
		(layers "F.Cu" "B.Cu")
		(net "GND")
	)
	(via
		(at 64.399922 -277.849838)
		(size 0.4064)
		(drill 0.2032)
		(layers "F.Cu" "B.Cu")
		(net "GND")
	)
	(via
		(at 277.251668 -133.565138)
		(size 0.508)
		(drill 0.254)
		(layers "F.Cu" "B.Cu")
		(net "GND")
	)
	(via
		(at 427.42485 -300.174914)
		(size 0.4064)
		(drill 0.2032)
		(layers "F.Cu" "B.Cu")
		(net "GND")
	)
	(via
		(at 338.237322 -304.373534)
		(size 0.508)
		(drill 0.254)
		(layers "F.Cu" "B.Cu")
		(net "GND")
	)
	(via
		(at 39.04742 -349.219774)
		(size 0.4572)
		(drill 0.254)
		(layers "F.Cu" "B.Cu")
		(net "GND")
	)
	(via
		(at 371.6401 -74.58583)
		(size 0.508)
		(drill 0.254)
		(layers "F.Cu" "B.Cu")
		(net "GND")
	)
	(via
		(at 103.390192 -390.627108)
		(size 0.508)
		(drill 0.254)
		(layers "F.Cu" "B.Cu")
		(net "GND")
	)
	(via
		(at 381.527812 -407.24201)
		(size 0.508)
		(drill 0.254)
		(layers "F.Cu" "B.Cu")
		(net "GND")
	)
	(via
		(at 82.93735 -352.245422)
		(size 0.4572)
		(drill 0.254)
		(layers "F.Cu" "B.Cu")
		(net "GND")
	)
	(via
		(at 45.39996 -310.149748)
		(size 0.4064)
		(drill 0.2032)
		(layers "F.Cu" "B.Cu")
		(net "GND")
	)
	(via
		(at 428.539656 -85.426296)
		(size 0.508)
		(drill 0.254)
		(layers "F.Cu" "B.Cu")
		(net "GND")
	)
	(via
		(at 23.873968 -342.439498)
		(size 0.4064)
		(drill 0.2032)
		(layers "F.Cu" "B.Cu")
		(net "GND")
	)
	(via
		(at 109.399324 -268.096492)
		(size 0.508)
		(drill 0.254)
		(layers "F.Cu" "B.Cu")
		(net "GND")
	)
	(via
		(at 206.941674 -225.89871)
		(size 0.508)
		(drill 0.254)
		(layers "F.Cu" "B.Cu")
		(net "GND")
	)
	(via
		(at 124.100336 -344.831162)
		(size 0.4572)
		(drill 0.254)
		(layers "F.Cu" "B.Cu")
		(net "GND")
	)
	(via
		(at 126.837948 -354.732082)
		(size 0.4064)
		(drill 0.2032)
		(layers "F.Cu" "B.Cu")
		(net "GND")
	)
	(via
		(at 81.458562 -351.611438)
		(size 0.4064)
		(drill 0.2032)
		(layers "F.Cu" "B.Cu")
		(net "GND")
	)
	(via
		(at 397.120872 -349.219774)
		(size 0.4572)
		(drill 0.254)
		(layers "F.Cu" "B.Cu")
		(net "GND")
	)
	(via
		(at 405.015192 -60.601606)
		(size 0.508)
		(drill 0.254)
		(layers "F.Cu" "B.Cu")
		(net "GND")
	)
	(via
		(at 18.120614 -63.218314)
		(size 0.508)
		(drill 0.254)
		(layers "F.Cu" "B.Cu")
		(net "GND")
	)
	(via
		(at 39.04742 -352.245422)
		(size 0.4572)
		(drill 0.254)
		(layers "F.Cu" "B.Cu")
		(net "GND")
	)
	(via
		(at 257.133852 -352.703638)
		(size 0.508)
		(drill 0.254)
		(layers "F.Cu" "B.Cu")
		(net "GND")
	)
	(via
		(at 424.64228 -344.831162)
		(size 0.4572)
		(drill 0.254)
		(layers "F.Cu" "B.Cu")
		(net "GND")
	)
	(via
		(at 53.194966 -158.8262)
		(size 0.508)
		(drill 0.254)
		(layers "F.Cu" "B.Cu")
		(net "GND")
	)
	(via
		(at 67.021202 -342.439498)
		(size 0.4064)
		(drill 0.2032)
		(layers "F.Cu" "B.Cu")
		(net "GND")
	)
	(via
		(at 277.124922 -301.124874)
		(size 0.4064)
		(drill 0.2032)
		(layers "F.Cu" "B.Cu")
		(net "GND")
	)
	(via
		(at 372.2751 -73.87463)
		(size 0.508)
		(drill 0.254)
		(layers "F.Cu" "B.Cu")
		(net "GND")
	)
	(via
		(at 282.824936 -303.974754)
		(size 0.4064)
		(drill 0.2032)
		(layers "F.Cu" "B.Cu")
		(net "GND")
	)
	(via
		(at 103.338122 -101.386894)
		(size 0.508)
		(drill 0.254)
		(layers "F.Cu" "B.Cu")
		(net "GND")
	)
	(via
		(at 407.949908 -319.65011)
		(size 0.4064)
		(drill 0.2032)
		(layers "F.Cu" "B.Cu")
		(net "GND")
	)
	(via
		(at 429.927766 -377.341892)
		(size 0.508)
		(drill 0.254)
		(layers "F.Cu" "B.Cu")
		(net "GND")
	)
	(via
		(at 423.15003 -307.299868)
		(size 0.4064)
		(drill 0.2032)
		(layers "F.Cu" "B.Cu")
		(net "GND")
	)
	(via
		(at 11.920728 -34.990024)
		(size 0.508)
		(drill 0.254)
		(layers "F.Cu" "B.Cu")
		(net "GND")
	)
	(via
		(at 281.394154 -350.977454)
		(size 0.4572)
		(drill 0.254)
		(layers "F.Cu" "B.Cu")
		(net "GND")
	)
	(via
		(at 121.467372 -286.842454)
		(size 0.508)
		(drill 0.254)
		(layers "F.Cu" "B.Cu")
		(net "GND")
	)
	(via
		(at 289.46221 -354.098098)
		(size 0.4572)
		(drill 0.254)
		(layers "F.Cu" "B.Cu")
		(net "GND")
	)
	(via
		(at 313.09818 -146.017996)
		(size 0.508)
		(drill 0.254)
		(layers "F.Cu" "B.Cu")
		(net "GND")
	)
	(via
		(at 195.699888 -306.349908)
		(size 0.4064)
		(drill 0.2032)
		(layers "F.Cu" "B.Cu")
		(net "GND")
	)
	(via
		(at 390.327896 -383.940304)
		(size 0.508)
		(drill 0.254)
		(layers "F.Cu" "B.Cu")
		(net "GND")
	)
	(via
		(at 398.4498 -275.949918)
		(size 0.4064)
		(drill 0.2032)
		(layers "F.Cu" "B.Cu")
		(net "GND")
	)
	(via
		(at 429.927766 -408.738578)
		(size 0.508)
		(drill 0.254)
		(layers "F.Cu" "B.Cu")
		(net "GND")
	)
	(via
		(at 389.424926 -278.324818)
		(size 0.4064)
		(drill 0.2032)
		(layers "F.Cu" "B.Cu")
		(net "GND")
	)
	(via
		(at 171.9453 -51.227482)
		(size 0.508)
		(drill 0.254)
		(layers "F.Cu" "B.Cu")
		(net "GND")
	)
	(via
		(at 81.499964 -309.199788)
		(size 0.4064)
		(drill 0.2032)
		(layers "F.Cu" "B.Cu")
		(net "GND")
	)
	(via
		(at 339.04809 -282.910788)
		(size 0.49022)
		(drill 0.254)
		(layers "F.Cu" "B.Cu")
		(net "GND")
	)
	(via
		(at 228.308154 -60.600082)
		(size 0.508)
		(drill 0.254)
		(layers "F.Cu" "B.Cu")
		(net "GND")
	)
	(via
		(at 178.124866 -291.624766)
		(size 0.4064)
		(drill 0.2032)
		(layers "F.Cu" "B.Cu")
		(net "GND")
	)
	(via
		(at 234.460288 -98.295968)
		(size 0.508)
		(drill 0.254)
		(layers "F.Cu" "B.Cu")
		(net "GND")
	)
	(via
		(at 420.299896 -312.999882)
		(size 0.4064)
		(drill 0.2032)
		(layers "F.Cu" "B.Cu")
		(net "GND")
	)
	(via
		(at 79.82839 -343.073482)
		(size 0.4572)
		(drill 0.254)
		(layers "F.Cu" "B.Cu")
		(net "GND")
	)
	(via
		(at 153.233628 -125.692154)
		(size 0.508)
		(drill 0.254)
		(layers "F.Cu" "B.Cu")
		(net "GND")
	)
	(via
		(at 383.72796 -373.83847)
		(size 0.508)
		(drill 0.254)
		(layers "F.Cu" "B.Cu")
		(net "GND")
	)
	(via
		(at 365.138462 -72.56526)
		(size 0.508)
		(drill 0.254)
		(layers "F.Cu" "B.Cu")
		(net "GND")
	)
	(via
		(at 340.894162 -220.38691)
		(size 0.4572)
		(drill 0.254)
		(layers "F.Cu" "B.Cu")
		(net "GND")
	)
	(via
		(at 392.52779 -410.041852)
		(size 0.508)
		(drill 0.254)
		(layers "F.Cu" "B.Cu")
		(net "GND")
	)
	(via
		(at 441.445904 -350.977454)
		(size 0.4572)
		(drill 0.254)
		(layers "F.Cu" "B.Cu")
		(net "GND")
	)
	(via
		(at 307.999892 -309.199788)
		(size 0.4064)
		(drill 0.2032)
		(layers "F.Cu" "B.Cu")
		(net "GND")
	)
	(via
		(at 149.292564 -11.372342)
		(size 0.508)
		(drill 0.254)
		(layers "F.Cu" "B.Cu")
		(net "GND")
	)
	(via
		(at 165.947852 -380.040134)
		(size 0.508)
		(drill 0.254)
		(layers "F.Cu" "B.Cu")
		(net "GND")
	)
	(via
		(at 164.198554 -37.201094)
		(size 0.508)
		(drill 0.254)
		(layers "F.Cu" "B.Cu")
		(net "GND")
	)
	(via
		(at 314.366148 -119.756936)
		(size 0.508)
		(drill 0.254)
		(layers "F.Cu" "B.Cu")
		(net "GND")
	)
	(via
		(at 181.44998 -281.649932)
		(size 0.4064)
		(drill 0.2032)
		(layers "F.Cu" "B.Cu")
		(net "GND")
	)
	(via
		(at 134.28472 -73.20026)
		(size 0.508)
		(drill 0.254)
		(layers "F.Cu" "B.Cu")
		(net "GND")
	)
	(via
		(at 167.200072 -276.899878)
		(size 0.4064)
		(drill 0.2032)
		(layers "F.Cu" "B.Cu")
		(net "GND")
	)
	(via
		(at 300.874684 -285.924752)
		(size 0.4064)
		(drill 0.2032)
		(layers "F.Cu" "B.Cu")
		(net "GND")
	)
	(via
		(at 104.431338 -374.648222)
		(size 0.508)
		(drill 0.254)
		(layers "F.Cu" "B.Cu")
		(net "GND")
	)
	(via
		(at 292.32479 -284.974792)
		(size 0.4064)
		(drill 0.2032)
		(layers "F.Cu" "B.Cu")
		(net "GND")
	)
	(via
		(at 167.675052 -302.074834)
		(size 0.4064)
		(drill 0.2032)
		(layers "F.Cu" "B.Cu")
		(net "GND")
	)
	(via
		(at 71.760334 -350.977454)
		(size 0.4572)
		(drill 0.254)
		(layers "F.Cu" "B.Cu")
		(net "GND")
	)
	(via
		(at 393.351766 -133.565138)
		(size 0.508)
		(drill 0.254)
		(layers "F.Cu" "B.Cu")
		(net "GND")
	)
	(via
		(at 37.788596 -355.366066)
		(size 0.4572)
		(drill 0.254)
		(layers "F.Cu" "B.Cu")
		(net "GND")
	)
	(via
		(at 369.062 -161.6075)
		(size 0.508)
		(drill 0.254)
		(layers "F.Cu" "B.Cu")
		(net "GND")
	)
	(via
		(at 82.347816 -376.140218)
		(size 0.508)
		(drill 0.254)
		(layers "F.Cu" "B.Cu")
		(net "GND")
	)
	(via
		(at 124.342652 -147.630388)
		(size 0.508)
		(drill 0.254)
		(layers "F.Cu" "B.Cu")
		(net "GND")
	)
	(via
		(at 55.374794 -303.974754)
		(size 0.4064)
		(drill 0.2032)
		(layers "F.Cu" "B.Cu")
		(net "GND")
	)
	(via
		(at 208.905348 -232.43413)
		(size 0.508)
		(drill 0.254)
		(layers "F.Cu" "B.Cu")
		(net "GND")
	)
	(via
		(at 284.503114 -354.098098)
		(size 0.4572)
		(drill 0.254)
		(layers "F.Cu" "B.Cu")
		(net "GND")
	)
	(via
		(at 342.245442 -307.18887)
		(size 0.508)
		(drill 0.254)
		(layers "F.Cu" "B.Cu")
		(net "GND")
	)
	(via
		(at 84.54771 -408.840178)
		(size 0.508)
		(drill 0.254)
		(layers "F.Cu" "B.Cu")
		(net "GND")
	)
	(via
		(at 59.820048 -29.590238)
		(size 0.508)
		(drill 0.254)
		(layers "F.Cu" "B.Cu")
		(net "GND")
	)
	(via
		(at 68.199762 -276.899878)
		(size 0.4064)
		(drill 0.2032)
		(layers "F.Cu" "B.Cu")
		(net "GND")
	)
	(via
		(at 76.71943 -343.073482)
		(size 0.4572)
		(drill 0.254)
		(layers "F.Cu" "B.Cu")
		(net "GND")
	)
	(via
		(at 368.9731 -23.880318)
		(size 0.508)
		(drill 0.254)
		(layers "F.Cu" "B.Cu")
		(net "GND")
	)
	(via
		(at 304.483262 -154.461718)
		(size 0.508)
		(drill 0.254)
		(layers "F.Cu" "B.Cu")
		(net "GND")
	)
	(via
		(at 161.500058 -303.499774)
		(size 0.4064)
		(drill 0.2032)
		(layers "F.Cu" "B.Cu")
		(net "GND")
	)
	(via
		(at 203.359258 -353.757992)
		(size 0.508)
		(drill 0.254)
		(layers "F.Cu" "B.Cu")
		(net "GND")
	)
	(via
		(at 179.163472 -348.58579)
		(size 0.4064)
		(drill 0.2032)
		(layers "F.Cu" "B.Cu")
		(net "GND")
	)
	(via
		(at 215.413336 -29.859478)
		(size 0.508)
		(drill 0.254)
		(layers "F.Cu" "B.Cu")
		(net "GND")
	)
	(via
		(at 166.725092 -284.024832)
		(size 0.4064)
		(drill 0.2032)
		(layers "F.Cu" "B.Cu")
		(net "GND")
	)
	(via
		(at 114.361976 -277.639272)
		(size 0.508)
		(drill 0.254)
		(layers "F.Cu" "B.Cu")
		(net "GND")
	)
	(via
		(at 198.753222 -49.574704)
		(size 0.508)
		(drill 0.254)
		(layers "F.Cu" "B.Cu")
		(net "GND")
	)
	(via
		(at 172.547788 -407.638504)
		(size 0.508)
		(drill 0.254)
		(layers "F.Cu" "B.Cu")
		(net "GND")
	)
	(via
		(at 70.099936 -313.949842)
		(size 0.4064)
		(drill 0.2032)
		(layers "F.Cu" "B.Cu")
		(net "GND")
	)
	(via
		(at 311.470294 -28.802076)
		(size 0.508)
		(drill 0.254)
		(layers "F.Cu" "B.Cu")
		(net "GND")
	)
	(via
		(at 357.000556 -155.217114)
		(size 0.508)
		(drill 0.254)
		(layers "F.Cu" "B.Cu")
		(net "GND")
	)
	(via
		(at 414.74771 -152.95499)
		(size 0.508)
		(drill 0.254)
		(layers "F.Cu" "B.Cu")
		(net "GND")
	)
	(via
		(at 313.506866 -49.574704)
		(size 0.508)
		(drill 0.254)
		(layers "F.Cu" "B.Cu")
		(net "GND")
	)
	(via
		(at 33.947862 -382.73863)
		(size 0.508)
		(drill 0.254)
		(layers "F.Cu" "B.Cu")
		(net "GND")
	)
	(via
		(at 195.37045 -28.802076)
		(size 0.508)
		(drill 0.254)
		(layers "F.Cu" "B.Cu")
		(net "GND")
	)
	(via
		(at 97.920048 -242.660424)
		(size 0.508)
		(drill 0.254)
		(layers "F.Cu" "B.Cu")
		(net "GND")
	)
	(via
		(at 106.037126 -305.008534)
		(size 0.508)
		(drill 0.254)
		(layers "F.Cu" "B.Cu")
		(net "GND")
	)
	(via
		(at 200.90003 -38.315138)
		(size 0.508)
		(drill 0.254)
		(layers "F.Cu" "B.Cu")
		(net "GND")
	)
	(via
		(at 100.033582 -107.681776)
		(size 0.508)
		(drill 0.254)
		(layers "F.Cu" "B.Cu")
		(net "GND")
	)
	(via
		(at 158.508192 -354.732082)
		(size 0.4064)
		(drill 0.2032)
		(layers "F.Cu" "B.Cu")
		(net "GND")
	)
	(via
		(at 99.568 -417.82492)
		(size 0.508)
		(drill 0.254)
		(layers "F.Cu" "B.Cu")
		(net "GND")
	)
	(via
		(at 142.754096 -357.123746)
		(size 0.4572)
		(drill 0.254)
		(layers "F.Cu" "B.Cu")
		(net "GND")
	)
	(via
		(at 429.381412 -348.58579)
		(size 0.4064)
		(drill 0.2032)
		(layers "F.Cu" "B.Cu")
		(net "GND")
	)
	(via
		(at 302.299878 -314.899802)
		(size 0.4064)
		(drill 0.2032)
		(layers "F.Cu" "B.Cu")
		(net "GND")
	)
	(via
		(at 107.980734 -238.553244)
		(size 0.508)
		(drill 0.254)
		(layers "F.Cu" "B.Cu")
		(net "GND")
	)
	(via
		(at 215.773 -193.294)
		(size 0.508)
		(drill 0.254)
		(layers "F.Cu" "B.Cu")
		(net "GND")
	)
	(via
		(at 430.466246 -118.498112)
		(size 0.508)
		(drill 0.254)
		(layers "F.Cu" "B.Cu")
		(net "GND")
	)
	(via
		(at 409.09748 -346.09913)
		(size 0.4572)
		(drill 0.254)
		(layers "F.Cu" "B.Cu")
		(net "GND")
	)
	(via
		(at 281.874722 -285.924752)
		(size 0.4064)
		(drill 0.2032)
		(layers "F.Cu" "B.Cu")
		(net "GND")
	)
	(via
		(at 375.358152 -347.92793)
		(size 0.4572)
		(drill 0.254)
		(layers "F.Cu" "B.Cu")
		(net "GND")
	)
	(via
		(at 129.06502 -200.021952)
		(size 0.508)
		(drill 0.254)
		(layers "F.Cu" "B.Cu")
		(net "GND")
	)
	(via
		(at 159.124904 -284.974792)
		(size 0.4064)
		(drill 0.2032)
		(layers "F.Cu" "B.Cu")
		(net "GND")
	)
	(via
		(at 52.85232 -120.555004)
		(size 0.508)
		(drill 0.254)
		(layers "F.Cu" "B.Cu")
		(net "GND")
	)
	(via
		(at 197.600062 -286.399732)
		(size 0.4064)
		(drill 0.2032)
		(layers "F.Cu" "B.Cu")
		(net "GND")
	)
	(via
		(at 89.544144 -294.682672)
		(size 0.508)
		(drill 0.254)
		(layers "F.Cu" "B.Cu")
		(net "GND")
	)
	(via
		(at 253.730506 -65.15989)
		(size 0.508)
		(drill 0.254)
		(layers "F.Cu" "B.Cu")
		(net "GND")
	)
	(via
		(at 25.352756 -350.977454)
		(size 0.4572)
		(drill 0.254)
		(layers "F.Cu" "B.Cu")
		(net "GND")
	)
	(via
		(at 335.328006 -410.041852)
		(size 0.508)
		(drill 0.254)
		(layers "F.Cu" "B.Cu")
		(net "GND")
	)
	(via
		(at 172.574204 -352.245422)
		(size 0.4572)
		(drill 0.254)
		(layers "F.Cu" "B.Cu")
		(net "GND")
	)
	(via
		(at 18.141188 -38.49116)
		(size 0.508)
		(drill 0.254)
		(layers "F.Cu" "B.Cu")
		(net "GND")
	)
	(via
		(at 160.549844 -315.849762)
		(size 0.4064)
		(drill 0.2032)
		(layers "F.Cu" "B.Cu")
		(net "GND")
	)
	(via
		(at 393.131294 -60.099194)
		(size 0.508)
		(drill 0.254)
		(layers "F.Cu" "B.Cu")
		(net "GND")
	)
	(via
		(at 409.76169 -205.350364)
		(size 0.508)
		(drill 0.254)
		(layers "F.Cu" "B.Cu")
		(net "GND")
	)
	(via
		(at 390.327896 -373.441976)
		(size 0.508)
		(drill 0.254)
		(layers "F.Cu" "B.Cu")
		(net "GND")
	)
	(via
		(at 273.622008 -82.174334)
		(size 0.508)
		(drill 0.254)
		(layers "F.Cu" "B.Cu")
		(net "GND")
	)
	(via
		(at 428.069502 -64.102234)
		(size 0.508)
		(drill 0.254)
		(layers "F.Cu" "B.Cu")
		(net "GND")
	)
	(via
		(at 169.587164 -109.644942)
		(size 0.508)
		(drill 0.254)
		(layers "F.Cu" "B.Cu")
		(net "GND")
	)
	(via
		(at 397.97482 -284.974792)
		(size 0.4064)
		(drill 0.2032)
		(layers "F.Cu" "B.Cu")
		(net "GND")
	)
	(via
		(at 52.999894 -312.999882)
		(size 0.4064)
		(drill 0.2032)
		(layers "F.Cu" "B.Cu")
		(net "GND")
	)
	(via
		(at 169.587164 -124.154946)
		(size 0.508)
		(drill 0.254)
		(layers "F.Cu" "B.Cu")
		(net "GND")
	)
	(via
		(at 209.724244 -220.851984)
		(size 0.508)
		(drill 0.254)
		(layers "F.Cu" "B.Cu")
		(net "GND")
	)
	(via
		(at 299.924724 -306.824888)
		(size 0.4064)
		(drill 0.2032)
		(layers "F.Cu" "B.Cu")
		(net "GND")
	)
	(via
		(at 245.84279 -287.74898)
		(size 0.508)
		(drill 0.254)
		(layers "F.Cu" "B.Cu")
		(net "GND")
	)
	(via
		(at 34.491676 -112.981994)
		(size 0.508)
		(drill 0.254)
		(layers "F.Cu" "B.Cu")
		(net "GND")
	)
	(via
		(at 300.757844 -57.521094)
		(size 0.508)
		(drill 0.254)
		(layers "F.Cu" "B.Cu")
		(net "GND")
	)
	(via
		(at 40.547798 -381.638556)
		(size 0.508)
		(drill 0.254)
		(layers "F.Cu" "B.Cu")
		(net "GND")
	)
	(via
		(at 62.499748 -313.949842)
		(size 0.4064)
		(drill 0.2032)
		(layers "F.Cu" "B.Cu")
		(net "GND")
	)
	(via
		(at 432.12766 -377.738386)
		(size 0.508)
		(drill 0.254)
		(layers "F.Cu" "B.Cu")
		(net "GND")
	)
	(via
		(at 323.56171 -287.654238)
		(size 0.508)
		(drill 0.254)
		(layers "F.Cu" "B.Cu")
		(net "GND")
	)
	(via
		(at 314.649866 -278.799798)
		(size 0.4064)
		(drill 0.2032)
		(layers "F.Cu" "B.Cu")
		(net "GND")
	)
	(via
		(at 77.69987 -317.749936)
		(size 0.4064)
		(drill 0.2032)
		(layers "F.Cu" "B.Cu")
		(net "GND")
	)
	(via
		(at 390.374886 -298.27474)
		(size 0.4064)
		(drill 0.2032)
		(layers "F.Cu" "B.Cu")
		(net "GND")
	)
	(via
		(at 169.574972 -285.924752)
		(size 0.4064)
		(drill 0.2032)
		(layers "F.Cu" "B.Cu")
		(net "GND")
	)
	(via
		(at 426.272452 -348.58579)
		(size 0.4064)
		(drill 0.2032)
		(layers "F.Cu" "B.Cu")
		(net "GND")
	)
	(via
		(at 308.949852 -319.65011)
		(size 0.4064)
		(drill 0.2032)
		(layers "F.Cu" "B.Cu")
		(net "GND")
	)
	(via
		(at 411.275022 -284.974792)
		(size 0.4064)
		(drill 0.2032)
		(layers "F.Cu" "B.Cu")
		(net "GND")
	)
	(via
		(at 466.827616 -41.852596)
		(size 0.508)
		(drill 0.254)
		(layers "F.Cu" "B.Cu")
		(net "GND")
	)
	(via
		(at 35.899598 -312.049668)
		(size 0.4064)
		(drill 0.2032)
		(layers "F.Cu" "B.Cu")
		(net "GND")
	)
	(via
		(at 315.60008 -306.349908)
		(size 0.4064)
		(drill 0.2032)
		(layers "F.Cu" "B.Cu")
		(net "GND")
	)
	(via
		(at 75.74788 -406.141936)
		(size 0.508)
		(drill 0.254)
		(layers "F.Cu" "B.Cu")
		(net "GND")
	)
	(via
		(at 450.314822 -107.681776)
		(size 0.508)
		(drill 0.254)
		(layers "F.Cu" "B.Cu")
		(net "GND")
	)
	(via
		(at 402.24329 -28.139136)
		(size 0.508)
		(drill 0.254)
		(layers "F.Cu" "B.Cu")
		(net "GND")
	)
	(via
		(at 270.25473 -34.990024)
		(size 0.508)
		(drill 0.254)
		(layers "F.Cu" "B.Cu")
		(net "GND")
	)
	(via
		(at 389.899906 -302.549814)
		(size 0.4064)
		(drill 0.2032)
		(layers "F.Cu" "B.Cu")
		(net "GND")
	)
	(via
		(at 269.52448 -300.174914)
		(size 0.4064)
		(drill 0.2032)
		(layers "F.Cu" "B.Cu")
		(net "GND")
	)
	(via
		(at 34.00298 -280.693114)
		(size 0.508)
		(drill 0.254)
		(layers "F.Cu" "B.Cu")
		(net "GND")
	)
	(via
		(at 115.34775 -376.241818)
		(size 0.4572)
		(drill 0.254)
		(layers "F.Cu" "B.Cu")
		(net "GND")
	)
	(via
		(at 336.71002 -130.362452)
		(size 0.508)
		(drill 0.254)
		(layers "F.Cu" "B.Cu")
		(net "GND")
	)
	(via
		(at 260.69036 -233.111294)
		(size 0.508)
		(drill 0.254)
		(layers "F.Cu" "B.Cu")
		(net "GND")
	)
	(via
		(at 395.350492 -86.603332)
		(size 0.508)
		(drill 0.254)
		(layers "F.Cu" "B.Cu")
		(net "GND")
	)
	(via
		(at 13.318998 -34.990024)
		(size 0.508)
		(drill 0.254)
		(layers "F.Cu" "B.Cu")
		(net "GND")
	)
	(via
		(at 438.355994 -33.19018)
		(size 0.508)
		(drill 0.254)
		(layers "F.Cu" "B.Cu")
		(net "GND")
	)
	(via
		(at 4.562856 -129.361692)
		(size 0.508)
		(drill 0.254)
		(layers "F.Cu" "B.Cu")
		(net "GND")
	)
	(via
		(at 172.547788 -398.34185)
		(size 0.508)
		(drill 0.254)
		(layers "F.Cu" "B.Cu")
		(net "GND")
	)
	(via
		(at 375.7295 -345.465146)
		(size 0.4064)
		(drill 0.2032)
		(layers "F.Cu" "B.Cu")
		(net "GND")
	)
	(via
		(at 190.950088 -312.049922)
		(size 0.4064)
		(drill 0.2032)
		(layers "F.Cu" "B.Cu")
		(net "GND")
	)
	(via
		(at 177.174906 -285.924752)
		(size 0.4064)
		(drill 0.2032)
		(layers "F.Cu" "B.Cu")
		(net "GND")
	)
	(via
		(at 274.274788 -281.174952)
		(size 0.4064)
		(drill 0.2032)
		(layers "F.Cu" "B.Cu")
		(net "GND")
	)
	(via
		(at 37.799772 -317.749936)
		(size 0.4064)
		(drill 0.2032)
		(layers "F.Cu" "B.Cu")
		(net "GND")
	)
	(via
		(at 24.981408 -342.439498)
		(size 0.4064)
		(drill 0.2032)
		(layers "F.Cu" "B.Cu")
		(net "GND")
	)
	(via
		(at 385.927854 -397.038576)
		(size 0.508)
		(drill 0.254)
		(layers "F.Cu" "B.Cu")
		(net "GND")
	)
	(via
		(at 421.127682 -380.040134)
		(size 0.508)
		(drill 0.254)
		(layers "F.Cu" "B.Cu")
		(net "GND")
	)
	(via
		(at 117.547644 -381.241808)
		(size 0.4572)
		(drill 0.254)
		(layers "F.Cu" "B.Cu")
		(net "GND")
	)
	(via
		(at 422.548304 -134.845044)
		(size 0.508)
		(drill 0.254)
		(layers "F.Cu" "B.Cu")
		(net "GND")
	)
	(via
		(at 114.316002 -264.95756)
		(size 0.508)
		(drill 0.254)
		(layers "F.Cu" "B.Cu")
		(net "GND")
	)
	(via
		(at 20.39366 -343.073482)
		(size 0.4572)
		(drill 0.254)
		(layers "F.Cu" "B.Cu")
		(net "GND")
	)
	(via
		(at 335.73847 -286.842454)
		(size 0.508)
		(drill 0.254)
		(layers "F.Cu" "B.Cu")
		(net "GND")
	)
	(via
		(at 154.501596 -111.175546)
		(size 0.508)
		(drill 0.254)
		(layers "F.Cu" "B.Cu")
		(net "GND")
	)
	(via
		(at 424.64228 -352.245422)
		(size 0.4572)
		(drill 0.254)
		(layers "F.Cu" "B.Cu")
		(net "GND")
	)
	(via
		(at 83.64982 -27.04973)
		(size 0.508)
		(drill 0.254)
		(layers "F.Cu" "B.Cu")
		(net "GND")
	)
	(via
		(at 31.213298 -224.536)
		(size 0.508)
		(drill 0.254)
		(layers "F.Cu" "B.Cu")
		(net "GND")
	)
	(via
		(at 7.531608 -150.16861)
		(size 0.508)
		(drill 0.254)
		(layers "F.Cu" "B.Cu")
		(net "GND")
	)
	(via
		(at 249.196098 -279.883108)
		(size 0.508)
		(drill 0.254)
		(layers "F.Cu" "B.Cu")
		(net "GND")
	)
	(via
		(at 307.906928 -0.762)
		(size 0.508)
		(drill 0.254)
		(layers "F.Cu" "B.Cu")
		(net "GND")
	)
	(via
		(at 121.947686 -409.940252)
		(size 0.4572)
		(drill 0.254)
		(layers "F.Cu" "B.Cu")
		(net "GND")
	)
	(via
		(at 67.66687 -149.355048)
		(size 0.508)
		(drill 0.254)
		(layers "F.Cu" "B.Cu")
		(net "GND")
	)
	(via
		(at 395.613382 -31.118302)
		(size 0.508)
		(drill 0.254)
		(layers "F.Cu" "B.Cu")
		(net "GND")
	)
	(via
		(at 319.781936 -358.391714)
		(size 0.4572)
		(drill 0.254)
		(layers "F.Cu" "B.Cu")
		(net "GND")
	)
	(via
		(at 89.680796 -25.990042)
		(size 0.508)
		(drill 0.254)
		(layers "F.Cu" "B.Cu")
		(net "GND")
	)
	(via
		(at 343.32418 -329.564492)
		(size 0.508)
		(drill 0.254)
		(layers "F.Cu" "B.Cu")
		(net "GND")
	)
	(via
		(at 232.207308 -106.172508)
		(size 0.508)
		(drill 0.254)
		(layers "F.Cu" "B.Cu")
		(net "GND")
	)
	(via
		(at 278.285194 -358.391714)
		(size 0.4572)
		(drill 0.254)
		(layers "F.Cu" "B.Cu")
		(net "GND")
	)
	(via
		(at 53.474874 -307.774848)
		(size 0.4064)
		(drill 0.2032)
		(layers "F.Cu" "B.Cu")
		(net "GND")
	)
	(via
		(at 425.99991 -317.749936)
		(size 0.4064)
		(drill 0.2032)
		(layers "F.Cu" "B.Cu")
		(net "GND")
	)
	(via
		(at 241.670078 -416.508438)
		(size 0.508)
		(drill 0.254)
		(layers "F.Cu" "B.Cu")
		(net "GND")
	)
	(via
		(at 55.845202 -51.227482)
		(size 0.508)
		(drill 0.254)
		(layers "F.Cu" "B.Cu")
		(net "GND")
	)
	(via
		(at 183.379872 -348.58579)
		(size 0.4064)
		(drill 0.2032)
		(layers "F.Cu" "B.Cu")
		(net "GND")
	)
	(via
		(at 345.024964 -351.611438)
		(size 0.4064)
		(drill 0.2032)
		(layers "F.Cu" "B.Cu")
		(net "GND")
	)
	(via
		(at 341.657432 -304.373534)
		(size 0.508)
		(drill 0.254)
		(layers "F.Cu" "B.Cu")
		(net "GND")
	)
	(via
		(at 414.599882 -312.999882)
		(size 0.4064)
		(drill 0.2032)
		(layers "F.Cu" "B.Cu")
		(net "GND")
	)
	(via
		(at 191.529462 -47.020734)
		(size 0.508)
		(drill 0.254)
		(layers "F.Cu" "B.Cu")
		(net "GND")
	)
	(via
		(at 423.149776 -282.599892)
		(size 0.4064)
		(drill 0.2032)
		(layers "F.Cu" "B.Cu")
		(net "GND")
	)
	(via
		(at 4.562856 -114.121692)
		(size 0.508)
		(drill 0.254)
		(layers "F.Cu" "B.Cu")
		(net "GND")
	)
	(via
		(at 118.043452 -28.139136)
		(size 0.508)
		(drill 0.254)
		(layers "F.Cu" "B.Cu")
		(net "GND")
	)
	(via
		(at 452.220838 -317.187326)
		(size 0.508)
		(drill 0.254)
		(layers "F.Cu" "B.Cu")
		(net "GND")
	)
	(via
		(at 99.987608 -122.525028)
		(size 0.508)
		(drill 0.254)
		(layers "F.Cu" "B.Cu")
		(net "GND")
	)
	(via
		(at 88.947752 -382.840484)
		(size 0.508)
		(drill 0.254)
		(layers "F.Cu" "B.Cu")
		(net "GND")
	)
	(via
		(at 161.975038 -297.32478)
		(size 0.4064)
		(drill 0.2032)
		(layers "F.Cu" "B.Cu")
		(net "GND")
	)
	(via
		(at 312.749692 -312.049922)
		(size 0.4064)
		(drill 0.2032)
		(layers "F.Cu" "B.Cu")
		(net "GND")
	)
	(via
		(at 307.999892 -286.399732)
		(size 0.4064)
		(drill 0.2032)
		(layers "F.Cu" "B.Cu")
		(net "GND")
	)
	(via
		(at 386.575046 -276.424898)
		(size 0.4064)
		(drill 0.2032)
		(layers "F.Cu" "B.Cu")
		(net "GND")
	)
	(via
		(at 277.599902 -304.449734)
		(size 0.4064)
		(drill 0.2032)
		(layers "F.Cu" "B.Cu")
		(net "GND")
	)
	(via
		(at 128.547622 -408.840178)
		(size 0.4572)
		(drill 0.254)
		(layers "F.Cu" "B.Cu")
		(net "GND")
	)
	(via
		(at 395.487144 -139.731242)
		(size 0.508)
		(drill 0.254)
		(layers "F.Cu" "B.Cu")
		(net "GND")
	)
	(via
		(at 421.724836 -307.774848)
		(size 0.4064)
		(drill 0.2032)
		(layers "F.Cu" "B.Cu")
		(net "GND")
	)
	(via
		(at 283.774896 -284.024832)
		(size 0.4064)
		(drill 0.2032)
		(layers "F.Cu" "B.Cu")
		(net "GND")
	)
	(via
		(at 302.320452 -63.218314)
		(size 0.508)
		(drill 0.254)
		(layers "F.Cu" "B.Cu")
		(net "GND")
	)
	(via
		(at 330.958952 -349.219774)
		(size 0.4572)
		(drill 0.254)
		(layers "F.Cu" "B.Cu")
		(net "GND")
	)
	(via
		(at 269.524734 -290.674806)
		(size 0.4064)
		(drill 0.2032)
		(layers "F.Cu" "B.Cu")
		(net "GND")
	)
	(via
		(at 420.23919 -31.652972)
		(size 0.508)
		(drill 0.254)
		(layers "F.Cu" "B.Cu")
		(net "GND")
	)
	(via
		(at 168.148 -402.241766)
		(size 0.508)
		(drill 0.254)
		(layers "F.Cu" "B.Cu")
		(net "GND")
	)
	(via
		(at 192.2272 -102.571296)
		(size 0.508)
		(drill 0.254)
		(layers "F.Cu" "B.Cu")
		(net "GND")
	)
	(via
		(at 139.645136 -343.073482)
		(size 0.4572)
		(drill 0.254)
		(layers "F.Cu" "B.Cu")
		(net "GND")
	)
	(via
		(at 119.747792 -407.638504)
		(size 0.508)
		(drill 0.254)
		(layers "F.Cu" "B.Cu")
		(net "GND")
	)
	(via
		(at 197.386956 -366.33658)
		(size 0.508)
		(drill 0.254)
		(layers "F.Cu" "B.Cu")
		(net "GND")
	)
	(via
		(at 395.862048 -343.073482)
		(size 0.4572)
		(drill 0.254)
		(layers "F.Cu" "B.Cu")
		(net "GND")
	)
	(via
		(at 175.749966 -281.649932)
		(size 0.4064)
		(drill 0.2032)
		(layers "F.Cu" "B.Cu")
		(net "GND")
	)
	(via
		(at 234.8484 -135.561324)
		(size 0.508)
		(drill 0.254)
		(layers "F.Cu" "B.Cu")
		(net "GND")
	)
	(via
		(at 432.490372 -348.58579)
		(size 0.4064)
		(drill 0.2032)
		(layers "F.Cu" "B.Cu")
		(net "GND")
	)
	(via
		(at 53.949854 -279.749758)
		(size 0.4064)
		(drill 0.2032)
		(layers "F.Cu" "B.Cu")
		(net "GND")
	)
	(via
		(at 396.54988 -274.999958)
		(size 0.4064)
		(drill 0.2032)
		(layers "F.Cu" "B.Cu")
		(net "GND")
	)
	(via
		(at 289.127692 -408.738578)
		(size 0.508)
		(drill 0.254)
		(layers "F.Cu" "B.Cu")
		(net "GND")
	)
	(via
		(at 124.007372 -286.842454)
		(size 0.508)
		(drill 0.254)
		(layers "F.Cu" "B.Cu")
		(net "GND")
	)
	(via
		(at 390.327896 -378.83846)
		(size 0.508)
		(drill 0.254)
		(layers "F.Cu" "B.Cu")
		(net "GND")
	)
	(via
		(at 145.331434 -213.955884)
		(size 0.508)
		(drill 0.254)
		(layers "F.Cu" "B.Cu")
		(net "GND")
	)
	(via
		(at 95.26016 -236.971586)
		(size 0.508)
		(drill 0.254)
		(layers "F.Cu" "B.Cu")
		(net "GND")
	)
	(via
		(at 294.201342 -345.465146)
		(size 0.4064)
		(drill 0.2032)
		(layers "F.Cu" "B.Cu")
		(net "GND")
	)
	(via
		(at 299.449744 -311.099962)
		(size 0.4064)
		(drill 0.2032)
		(layers "F.Cu" "B.Cu")
		(net "GND")
	)
	(via
		(at 37.417248 -342.439498)
		(size 0.4064)
		(drill 0.2032)
		(layers "F.Cu" "B.Cu")
		(net "GND")
	)
	(via
		(at 111.664496 -350.977454)
		(size 0.4572)
		(drill 0.254)
		(layers "F.Cu" "B.Cu")
		(net "GND")
	)
	(via
		(at 167.732964 -135.364982)
		(size 0.508)
		(drill 0.254)
		(layers "F.Cu" "B.Cu")
		(net "GND")
	)
	(via
		(at 401.15236 -113.245138)
		(size 0.508)
		(drill 0.254)
		(layers "F.Cu" "B.Cu")
		(net "GND")
	)
	(via
		(at 81.087214 -358.391714)
		(size 0.4572)
		(drill 0.254)
		(layers "F.Cu" "B.Cu")
		(net "GND")
	)
	(via
		(at 302.78197 -58.238644)
		(size 0.508)
		(drill 0.254)
		(layers "F.Cu" "B.Cu")
		(net "GND")
	)
	(via
		(at 40.547798 -403.738588)
		(size 0.508)
		(drill 0.254)
		(layers "F.Cu" "B.Cu")
		(net "GND")
	)
	(via
		(at 90.733372 -100.803964)
		(size 0.508)
		(drill 0.254)
		(layers "F.Cu" "B.Cu")
		(net "GND")
	)
	(via
		(at 216.060274 -21.37156)
		(size 0.508)
		(drill 0.254)
		(layers "F.Cu" "B.Cu")
		(net "GND")
	)
	(via
		(at 392.274806 -296.37482)
		(size 0.4064)
		(drill 0.2032)
		(layers "F.Cu" "B.Cu")
		(net "GND")
	)
	(via
		(at 377.12777 -403.34184)
		(size 0.508)
		(drill 0.254)
		(layers "F.Cu" "B.Cu")
		(net "GND")
	)
	(via
		(at 322.71081 -230.702358)
		(size 0.508)
		(drill 0.254)
		(layers "F.Cu" "B.Cu")
		(net "GND")
	)
	(via
		(at 17.323308 -133.890766)
		(size 0.508)
		(drill 0.254)
		(layers "F.Cu" "B.Cu")
		(net "GND")
	)
	(via
		(at 285.199836 -274.049744)
		(size 0.4064)
		(drill 0.2032)
		(layers "F.Cu" "B.Cu")
		(net "GND")
	)
	(via
		(at 423.639996 -74.58583)
		(size 0.508)
		(drill 0.254)
		(layers "F.Cu" "B.Cu")
		(net "GND")
	)
	(via
		(at 436.527702 -373.838724)
		(size 0.508)
		(drill 0.254)
		(layers "F.Cu" "B.Cu")
		(net "GND")
	)
	(via
		(at 31.747968 -369.938554)
		(size 0.508)
		(drill 0.254)
		(layers "F.Cu" "B.Cu")
		(net "GND")
	)
	(via
		(at 395.332966 -118.754906)
		(size 0.508)
		(drill 0.254)
		(layers "F.Cu" "B.Cu")
		(net "GND")
	)
	(via
		(at 399.874994 -297.32478)
		(size 0.4064)
		(drill 0.2032)
		(layers "F.Cu" "B.Cu")
		(net "GND")
	)
	(via
		(at 27.323288 -55.083456)
		(size 0.508)
		(drill 0.254)
		(layers "F.Cu" "B.Cu")
		(net "GND")
	)
	(via
		(at 188.366908 -145.755106)
		(size 0.508)
		(drill 0.254)
		(layers "F.Cu" "B.Cu")
		(net "GND")
	)
	(via
		(at 119.457978 -25.971246)
		(size 0.508)
		(drill 0.254)
		(layers "F.Cu" "B.Cu")
		(net "GND")
	)
	(via
		(at 424.007026 -0.762254)
		(size 0.508)
		(drill 0.254)
		(layers "F.Cu" "B.Cu")
		(net "GND")
	)
	(via
		(at 321.632072 -354.098098)
		(size 0.4572)
		(drill 0.254)
		(layers "F.Cu" "B.Cu")
		(net "GND")
	)
	(via
		(at 461.345788 -248.21261)
		(size 0.508)
		(drill 0.254)
		(layers "F.Cu" "B.Cu")
		(net "GND")
	)
	(via
		(at 108.89996 -136.87806)
		(size 0.508)
		(drill 0.254)
		(layers "F.Cu" "B.Cu")
		(net "GND")
	)
	(via
		(at 387.793992 -347.951806)
		(size 0.4572)
		(drill 0.254)
		(layers "F.Cu" "B.Cu")
		(net "GND")
	)
	(via
		(at 168.150032 -275.949918)
		(size 0.4064)
		(drill 0.2032)
		(layers "F.Cu" "B.Cu")
		(net "GND")
	)
	(via
		(at 21.255736 -153.782522)
		(size 0.508)
		(drill 0.254)
		(layers "F.Cu" "B.Cu")
		(net "GND")
	)
	(via
		(at 311.514998 -45.88891)
		(size 0.508)
		(drill 0.254)
		(layers "F.Cu" "B.Cu")
		(net "GND")
	)
	(via
		(at 329.480164 -348.58579)
		(size 0.4064)
		(drill 0.2032)
		(layers "F.Cu" "B.Cu")
		(net "GND")
	)
	(via
		(at 131.57708 -349.219774)
		(size 0.4572)
		(drill 0.254)
		(layers "F.Cu" "B.Cu")
		(net "GND")
	)
	(via
		(at 269.049754 -317.749936)
		(size 0.4064)
		(drill 0.2032)
		(layers "F.Cu" "B.Cu")
		(net "GND")
	)
	(via
		(at 416.499802 -313.949842)
		(size 0.4064)
		(drill 0.2032)
		(layers "F.Cu" "B.Cu")
		(net "GND")
	)
	(via
		(at 184.77484 -287.824926)
		(size 0.4064)
		(drill 0.2032)
		(layers "F.Cu" "B.Cu")
		(net "GND")
	)
	(via
		(at 130.74777 -407.24201)
		(size 0.4572)
		(drill 0.254)
		(layers "F.Cu" "B.Cu")
		(net "GND")
	)
	(via
		(at 332.217776 -347.951806)
		(size 0.4572)
		(drill 0.254)
		(layers "F.Cu" "B.Cu")
		(net "GND")
	)
	(via
		(at 87.6427 -116.416836)
		(size 0.508)
		(drill 0.254)
		(layers "F.Cu" "B.Cu")
		(net "GND")
	)
	(via
		(at 163.13277 -133.565138)
		(size 0.508)
		(drill 0.254)
		(layers "F.Cu" "B.Cu")
		(net "GND")
	)
	(via
		(at 164.681408 -34.718498)
		(size 0.508)
		(drill 0.254)
		(layers "F.Cu" "B.Cu")
		(net "GND")
	)
	(via
		(at 404.262844 -382.30302)
		(size 0.508)
		(drill 0.254)
		(layers "F.Cu" "B.Cu")
		(net "GND")
	)
	(via
		(at 150.331932 -386.979668)
		(size 0.508)
		(drill 0.254)
		(layers "F.Cu" "B.Cu")
		(net "GND")
	)
	(via
		(at 356.620826 -326.46366)
		(size 0.508)
		(drill 0.254)
		(layers "F.Cu" "B.Cu")
		(net "GND")
	)
	(via
		(at 1.53797 -275.982684)
		(size 0.508)
		(drill 0.254)
		(layers "F.Cu" "B.Cu")
		(net "GND")
	)
	(via
		(at 2.908808 -282.354782)
		(size 0.508)
		(drill 0.254)
		(layers "F.Cu" "B.Cu")
		(net "GND")
	)
	(via
		(at 307.539898 -73.23963)
		(size 0.508)
		(drill 0.254)
		(layers "F.Cu" "B.Cu")
		(net "GND")
	)
	(via
		(at 272.067274 -350.977454)
		(size 0.4572)
		(drill 0.254)
		(layers "F.Cu" "B.Cu")
		(net "GND")
	)
	(via
		(at 417.450016 -281.649932)
		(size 0.4064)
		(drill 0.2032)
		(layers "F.Cu" "B.Cu")
		(net "GND")
	)
	(via
		(at 421.127682 -402.140166)
		(size 0.508)
		(drill 0.254)
		(layers "F.Cu" "B.Cu")
		(net "GND")
	)
	(via
		(at 422.881298 -34.718498)
		(size 0.508)
		(drill 0.254)
		(layers "F.Cu" "B.Cu")
		(net "GND")
	)
	(via
		(at 144.384268 -345.465146)
		(size 0.4064)
		(drill 0.2032)
		(layers "F.Cu" "B.Cu")
		(net "GND")
	)
	(via
		(at 15.006574 -283.1592)
		(size 0.508)
		(drill 0.254)
		(layers "F.Cu" "B.Cu")
		(net "GND")
	)
	(via
		(at 139.645136 -354.074222)
		(size 0.4572)
		(drill 0.254)
		(layers "F.Cu" "B.Cu")
		(net "GND")
	)
	(via
		(at 68.651374 -350.977454)
		(size 0.4572)
		(drill 0.254)
		(layers "F.Cu" "B.Cu")
		(net "GND")
	)
	(via
		(at 161.975038 -291.624766)
		(size 0.4064)
		(drill 0.2032)
		(layers "F.Cu" "B.Cu")
		(net "GND")
	)
	(via
		(at 45.051726 -100.64496)
		(size 0.508)
		(drill 0.254)
		(layers "F.Cu" "B.Cu")
		(net "GND")
	)
	(via
		(at 302.299878 -310.149748)
		(size 0.4064)
		(drill 0.2032)
		(layers "F.Cu" "B.Cu")
		(net "GND")
	)
	(via
		(at 297.074844 -302.074834)
		(size 0.4064)
		(drill 0.2032)
		(layers "F.Cu" "B.Cu")
		(net "GND")
	)
	(via
		(at 380.605284 -231.74198)
		(size 0.508)
		(drill 0.254)
		(layers "F.Cu" "B.Cu")
		(net "GND")
	)
	(via
		(at 59.192668 -6.292342)
		(size 0.508)
		(drill 0.254)
		(layers "F.Cu" "B.Cu")
		(net "GND")
	)
	(via
		(at 151.2951 -60.633356)
		(size 0.508)
		(drill 0.254)
		(layers "F.Cu" "B.Cu")
		(net "GND")
	)
	(via
		(at 278.074882 -289.724846)
		(size 0.4064)
		(drill 0.2032)
		(layers "F.Cu" "B.Cu")
		(net "GND")
	)
	(via
		(at 294.69969 -314.899802)
		(size 0.4064)
		(drill 0.2032)
		(layers "F.Cu" "B.Cu")
		(net "GND")
	)
	(via
		(at 352.803968 -285.267654)
		(size 0.508)
		(drill 0.254)
		(layers "F.Cu" "B.Cu")
		(net "GND")
	)
	(via
		(at 390.902952 -341.805514)
		(size 0.4572)
		(drill 0.254)
		(layers "F.Cu" "B.Cu")
		(net "GND")
	)
	(via
		(at 289.47491 -289.724846)
		(size 0.4064)
		(drill 0.2032)
		(layers "F.Cu" "B.Cu")
		(net "GND")
	)
	(via
		(at 448.978782 -103.404416)
		(size 0.508)
		(drill 0.254)
		(layers "F.Cu" "B.Cu")
		(net "GND")
	)
	(via
		(at 82.166206 -153.218134)
		(size 0.508)
		(drill 0.254)
		(layers "F.Cu" "B.Cu")
		(net "GND")
	)
	(via
		(at 378.82195 -214.77605)
		(size 0.508)
		(drill 0.254)
		(layers "F.Cu" "B.Cu")
		(net "GND")
	)
	(via
		(at 277.124922 -286.874966)
		(size 0.4064)
		(drill 0.2032)
		(layers "F.Cu" "B.Cu")
		(net "GND")
	)
	(via
		(at 102.034594 -360.621834)
		(size 0.508)
		(drill 0.254)
		(layers "F.Cu" "B.Cu")
		(net "GND")
	)
	(via
		(at 366.522 -201.803)
		(size 0.508)
		(drill 0.254)
		(layers "F.Cu" "B.Cu")
		(net "GND")
	)
	(via
		(at 268.574774 -287.824926)
		(size 0.4064)
		(drill 0.2032)
		(layers "F.Cu" "B.Cu")
		(net "GND")
	)
	(via
		(at 369.613434 -31.118302)
		(size 0.508)
		(drill 0.254)
		(layers "F.Cu" "B.Cu")
		(net "GND")
	)
	(via
		(at 239.14227 -117.714268)
		(size 0.508)
		(drill 0.254)
		(layers "F.Cu" "B.Cu")
		(net "GND")
	)
	(via
		(at 139.645136 -357.123746)
		(size 0.4572)
		(drill 0.254)
		(layers "F.Cu" "B.Cu")
		(net "GND")
	)
	(via
		(at 9.358122 -141.019276)
		(size 0.508)
		(drill 0.254)
		(layers "F.Cu" "B.Cu")
		(net "GND")
	)
	(via
		(at 303.249838 -275.949918)
		(size 0.4064)
		(drill 0.2032)
		(layers "F.Cu" "B.Cu")
		(net "GND")
	)
	(via
		(at 253.661418 -81.848706)
		(size 0.508)
		(drill 0.254)
		(layers "F.Cu" "B.Cu")
		(net "GND")
	)
	(via
		(at 32.066484 -35.871912)
		(size 0.508)
		(drill 0.254)
		(layers "F.Cu" "B.Cu")
		(net "GND")
	)
	(via
		(at 163.564062 -142.41145)
		(size 0.508)
		(drill 0.254)
		(layers "F.Cu" "B.Cu")
		(net "GND")
	)
	(via
		(at 124.100336 -357.123746)
		(size 0.4572)
		(drill 0.254)
		(layers "F.Cu" "B.Cu")
		(net "GND")
	)
	(via
		(at 22.098 -405.85517)
		(size 0.508)
		(drill 0.254)
		(layers "F.Cu" "B.Cu")
		(net "GND")
	)
	(via
		(at 57.749948 -275.949918)
		(size 0.4064)
		(drill 0.2032)
		(layers "F.Cu" "B.Cu")
		(net "GND")
	)
	(via
		(at 188.490352 -342.439498)
		(size 0.4064)
		(drill 0.2032)
		(layers "F.Cu" "B.Cu")
		(net "GND")
	)
	(via
		(at 266.202922 -283.893514)
		(size 0.508)
		(drill 0.254)
		(layers "F.Cu" "B.Cu")
		(net "GND")
	)
	(via
		(at 153.42489 -287.824926)
		(size 0.4064)
		(drill 0.2032)
		(layers "F.Cu" "B.Cu")
		(net "GND")
	)
	(via
		(at 443.922658 -23.880318)
		(size 0.508)
		(drill 0.254)
		(layers "F.Cu" "B.Cu")
		(net "GND")
	)
	(via
		(at 325.002652 -74.624184)
		(size 0.508)
		(drill 0.254)
		(layers "F.Cu" "B.Cu")
		(net "GND")
	)
	(via
		(at 300.874684 -302.074834)
		(size 0.4064)
		(drill 0.2032)
		(layers "F.Cu" "B.Cu")
		(net "GND")
	)
	(via
		(at 221.014798 -170.043094)
		(size 0.508)
		(drill 0.254)
		(layers "F.Cu" "B.Cu")
		(net "GND")
	)
	(via
		(at 277.02637 -341.805514)
		(size 0.4572)
		(drill 0.254)
		(layers "F.Cu" "B.Cu")
		(net "GND")
	)
	(via
		(at 229.471474 -135.659622)
		(size 0.508)
		(drill 0.254)
		(layers "F.Cu" "B.Cu")
		(net "GND")
	)
	(via
		(at 39.418768 -348.58579)
		(size 0.4064)
		(drill 0.2032)
		(layers "F.Cu" "B.Cu")
		(net "GND")
	)
	(via
		(at 172.547788 -381.638556)
		(size 0.508)
		(drill 0.254)
		(layers "F.Cu" "B.Cu")
		(net "GND")
	)
	(via
		(at 278.549862 -274.999958)
		(size 0.4064)
		(drill 0.2032)
		(layers "F.Cu" "B.Cu")
		(net "GND")
	)
	(via
		(at 296.124884 -285.924752)
		(size 0.4064)
		(drill 0.2032)
		(layers "F.Cu" "B.Cu")
		(net "GND")
	)
	(via
		(at 43.974766 -294.4749)
		(size 0.4064)
		(drill 0.2032)
		(layers "F.Cu" "B.Cu")
		(net "GND")
	)
	(via
		(at 414.944052 -354.732082)
		(size 0.4064)
		(drill 0.2032)
		(layers "F.Cu" "B.Cu")
		(net "GND")
	)
	(via
		(at 84.567522 -345.465146)
		(size 0.4064)
		(drill 0.2032)
		(layers "F.Cu" "B.Cu")
		(net "GND")
	)
	(via
		(at 4.562856 -195.401692)
		(size 0.508)
		(drill 0.254)
		(layers "F.Cu" "B.Cu")
		(net "GND")
	)
	(via
		(at 71.347838 -407.638504)
		(size 0.508)
		(drill 0.254)
		(layers "F.Cu" "B.Cu")
		(net "GND")
	)
	(via
		(at 343.394792 -343.073482)
		(size 0.4572)
		(drill 0.254)
		(layers "F.Cu" "B.Cu")
		(net "GND")
	)
	(via
		(at 254.74422 -230.32339)
		(size 0.508)
		(drill 0.254)
		(layers "F.Cu" "B.Cu")
		(net "GND")
	)
	(via
		(at 15.303246 -213.466172)
		(size 0.508)
		(drill 0.254)
		(layers "F.Cu" "B.Cu")
		(net "GND")
	)
	(via
		(at 47.313342 -33.459674)
		(size 0.508)
		(drill 0.254)
		(layers "F.Cu" "B.Cu")
		(net "GND")
	)
	(via
		(at 424.09999 -281.649932)
		(size 0.4064)
		(drill 0.2032)
		(layers "F.Cu" "B.Cu")
		(net "GND")
	)
	(via
		(at 278.285194 -344.831162)
		(size 0.4572)
		(drill 0.254)
		(layers "F.Cu" "B.Cu")
		(net "GND")
	)
	(via
		(at 155.325064 -284.974792)
		(size 0.4064)
		(drill 0.2032)
		(layers "F.Cu" "B.Cu")
		(net "GND")
	)
	(via
		(at 117.409468 -205.687168)
		(size 0.508)
		(drill 0.254)
		(layers "F.Cu" "B.Cu")
		(net "GND")
	)
	(via
		(at 68.674742 -289.724846)
		(size 0.4064)
		(drill 0.2032)
		(layers "F.Cu" "B.Cu")
		(net "GND")
	)
	(via
		(at 196.998082 -149.617938)
		(size 0.508)
		(drill 0.254)
		(layers "F.Cu" "B.Cu")
		(net "GND")
	)
	(via
		(at 255.171194 -395.032738)
		(size 0.508)
		(drill 0.254)
		(layers "F.Cu" "B.Cu")
		(net "GND")
	)
	(via
		(at 161.15157 -100.64496)
		(size 0.508)
		(drill 0.254)
		(layers "F.Cu" "B.Cu")
		(net "GND")
	)
	(via
		(at 229.09276 -314.146946)
		(size 0.508)
		(drill 0.254)
		(layers "F.Cu" "B.Cu")
		(net "GND")
	)
	(via
		(at 55.415434 -374.51284)
		(size 0.508)
		(drill 0.254)
		(layers "F.Cu" "B.Cu")
		(net "GND")
	)
	(via
		(at 183.379872 -345.465146)
		(size 0.4064)
		(drill 0.2032)
		(layers "F.Cu" "B.Cu")
		(net "GND")
	)
	(via
		(at 417.450016 -275.949918)
		(size 0.4064)
		(drill 0.2032)
		(layers "F.Cu" "B.Cu")
		(net "GND")
	)
	(via
		(at 295.727882 -401.040092)
		(size 0.508)
		(drill 0.254)
		(layers "F.Cu" "B.Cu")
		(net "GND")
	)
	(via
		(at 364.580932 -27.79014)
		(size 0.508)
		(drill 0.254)
		(layers "F.Cu" "B.Cu")
		(net "GND")
	)
	(via
		(at 92.26423 -343.073482)
		(size 0.4572)
		(drill 0.254)
		(layers "F.Cu" "B.Cu")
		(net "GND")
	)
	(via
		(at 155.325064 -276.424898)
		(size 0.4064)
		(drill 0.2032)
		(layers "F.Cu" "B.Cu")
		(net "GND")
	)
	(via
		(at 189.96914 -341.805514)
		(size 0.4572)
		(drill 0.254)
		(layers "F.Cu" "B.Cu")
		(net "GND")
	)
	(via
		(at 412.533592 -179.897532)
		(size 0.508)
		(drill 0.254)
		(layers "F.Cu" "B.Cu")
		(net "GND")
	)
	(via
		(at 336.818986 -106.779822)
		(size 0.508)
		(drill 0.254)
		(layers "F.Cu" "B.Cu")
		(net "GND")
	)
	(via
		(at 463.037682 -108.217462)
		(size 0.508)
		(drill 0.254)
		(layers "F.Cu" "B.Cu")
		(net "GND")
	)
	(via
		(at 431.224944 -291.624766)
		(size 0.4064)
		(drill 0.2032)
		(layers "F.Cu" "B.Cu")
		(net "GND")
	)
	(via
		(at 283.774896 -287.824926)
		(size 0.4064)
		(drill 0.2032)
		(layers "F.Cu" "B.Cu")
		(net "GND")
	)
	(via
		(at 466.827616 -77.412596)
		(size 0.508)
		(drill 0.254)
		(layers "F.Cu" "B.Cu")
		(net "GND")
	)
	(via
		(at 463.037682 -219.977462)
		(size 0.508)
		(drill 0.254)
		(layers "F.Cu" "B.Cu")
		(net "GND")
	)
	(via
		(at 295.649904 -275.949918)
		(size 0.4064)
		(drill 0.2032)
		(layers "F.Cu" "B.Cu")
		(net "GND")
	)
	(via
		(at 419.683184 -349.219774)
		(size 0.4572)
		(drill 0.254)
		(layers "F.Cu" "B.Cu")
		(net "GND")
	)
	(via
		(at 66.248788 -33.19018)
		(size 0.508)
		(drill 0.254)
		(layers "F.Cu" "B.Cu")
		(net "GND")
	)
	(via
		(at 354.937568 -285.953454)
		(size 0.508)
		(drill 0.254)
		(layers "F.Cu" "B.Cu")
		(net "GND")
	)
	(via
		(at 244.748558 -108.303314)
		(size 0.508)
		(drill 0.254)
		(layers "F.Cu" "B.Cu")
		(net "GND")
	)
	(via
		(at 245.342918 -313.029346)
		(size 0.508)
		(drill 0.254)
		(layers "F.Cu" "B.Cu")
		(net "GND")
	)
	(via
		(at 128.839468 -345.465146)
		(size 0.4064)
		(drill 0.2032)
		(layers "F.Cu" "B.Cu")
		(net "GND")
	)
	(via
		(at 423.149776 -274.999958)
		(size 0.4064)
		(drill 0.2032)
		(layers "F.Cu" "B.Cu")
		(net "GND")
	)
	(via
		(at 115.596416 -136.926828)
		(size 0.508)
		(drill 0.254)
		(layers "F.Cu" "B.Cu")
		(net "GND")
	)
	(via
		(at 23.873968 -357.75773)
		(size 0.4064)
		(drill 0.2032)
		(layers "F.Cu" "B.Cu")
		(net "GND")
	)
	(via
		(at 70.50151 -352.245422)
		(size 0.4572)
		(drill 0.254)
		(layers "F.Cu" "B.Cu")
		(net "GND")
	)
	(via
		(at 26.193496 -283.131514)
		(size 0.508)
		(drill 0.254)
		(layers "F.Cu" "B.Cu")
		(net "GND")
	)
	(via
		(at 45.39996 -306.349908)
		(size 0.4064)
		(drill 0.2032)
		(layers "F.Cu" "B.Cu")
		(net "GND")
	)
	(via
		(at 113.294668 -345.465146)
		(size 0.4064)
		(drill 0.2032)
		(layers "F.Cu" "B.Cu")
		(net "GND")
	)
	(via
		(at 417.862512 -236.032802)
		(size 0.508)
		(drill 0.254)
		(layers "F.Cu" "B.Cu")
		(net "GND")
	)
	(via
		(at 185.725054 -297.32478)
		(size 0.4064)
		(drill 0.2032)
		(layers "F.Cu" "B.Cu")
		(net "GND")
	)
	(via
		(at 296.969942 -108.462318)
		(size 0.508)
		(drill 0.254)
		(layers "F.Cu" "B.Cu")
		(net "GND")
	)
	(via
		(at 45.051726 -137.16508)
		(size 0.508)
		(drill 0.254)
		(layers "F.Cu" "B.Cu")
		(net "GND")
	)
	(via
		(at 43.635168 -345.465146)
		(size 0.4064)
		(drill 0.2032)
		(layers "F.Cu" "B.Cu")
		(net "GND")
	)
	(via
		(at 53.714142 -368.714274)
		(size 0.4572)
		(drill 0.254)
		(layers "F.Cu" "B.Cu")
		(net "GND")
	)
	(via
		(at 391.13841 -72.56526)
		(size 0.508)
		(drill 0.254)
		(layers "F.Cu" "B.Cu")
		(net "GND")
	)
	(via
		(at 163.694364 -126.703836)
		(size 0.508)
		(drill 0.254)
		(layers "F.Cu" "B.Cu")
		(net "GND")
	)
	(via
		(at 31.570676 -355.366066)
		(size 0.4572)
		(drill 0.254)
		(layers "F.Cu" "B.Cu")
		(net "GND")
	)
	(via
		(at 69.624956 -285.924752)
		(size 0.4064)
		(drill 0.2032)
		(layers "F.Cu" "B.Cu")
		(net "GND")
	)
	(via
		(at 327.478644 -345.465146)
		(size 0.4064)
		(drill 0.2032)
		(layers "F.Cu" "B.Cu")
		(net "GND")
	)
	(via
		(at 33.200848 -357.75773)
		(size 0.4064)
		(drill 0.2032)
		(layers "F.Cu" "B.Cu")
		(net "GND")
	)
	(via
		(at 54.899814 -318.699896)
		(size 0.4064)
		(drill 0.2032)
		(layers "F.Cu" "B.Cu")
		(net "GND")
	)
	(via
		(at 38.401752 -136.901936)
		(size 0.508)
		(drill 0.254)
		(layers "F.Cu" "B.Cu")
		(net "GND")
	)
	(via
		(at 450.274944 -74.58583)
		(size 0.508)
		(drill 0.254)
		(layers "F.Cu" "B.Cu")
		(net "GND")
	)
	(via
		(at 383.667 -236.601)
		(size 0.508)
		(drill 0.254)
		(layers "F.Cu" "B.Cu")
		(net "GND")
	)
	(via
		(at 317.008256 -136.373362)
		(size 0.508)
		(drill 0.254)
		(layers "F.Cu" "B.Cu")
		(net "GND")
	)
	(via
		(at 173.240192 -27.729688)
		(size 0.508)
		(drill 0.254)
		(layers "F.Cu" "B.Cu")
		(net "GND")
	)
	(via
		(at 377.2154 -239.7506)
		(size 0.508)
		(drill 0.254)
		(layers "F.Cu" "B.Cu")
		(net "GND")
	)
	(via
		(at 195.699888 -308.249828)
		(size 0.4064)
		(drill 0.2032)
		(layers "F.Cu" "B.Cu")
		(net "GND")
	)
	(via
		(at 410.324808 -291.624766)
		(size 0.4064)
		(drill 0.2032)
		(layers "F.Cu" "B.Cu")
		(net "GND")
	)
	(via
		(at 296.938954 -357.123746)
		(size 0.4572)
		(drill 0.254)
		(layers "F.Cu" "B.Cu")
		(net "GND")
	)
	(via
		(at 62.974982 -293.52494)
		(size 0.4064)
		(drill 0.2032)
		(layers "F.Cu" "B.Cu")
		(net "GND")
	)
	(via
		(at 183.53786 -74.624184)
		(size 0.508)
		(drill 0.254)
		(layers "F.Cu" "B.Cu")
		(net "GND")
	)
	(via
		(at 188.366908 -120.035066)
		(size 0.508)
		(drill 0.254)
		(layers "F.Cu" "B.Cu")
		(net "GND")
	)
	(via
		(at 67.249802 -280.699718)
		(size 0.4064)
		(drill 0.2032)
		(layers "F.Cu" "B.Cu")
		(net "GND")
	)
	(via
		(at 310.849772 -288.299906)
		(size 0.4064)
		(drill 0.2032)
		(layers "F.Cu" "B.Cu")
		(net "GND")
	)
	(via
		(at 140.90396 -354.074222)
		(size 0.4572)
		(drill 0.254)
		(layers "F.Cu" "B.Cu")
		(net "GND")
	)
	(via
		(at 34.502344 -253.45644)
		(size 0.508)
		(drill 0.254)
		(layers "F.Cu" "B.Cu")
		(net "GND")
	)
	(via
		(at 230.9622 -257.718306)
		(size 0.508)
		(drill 0.254)
		(layers "F.Cu" "B.Cu")
		(net "GND")
	)
	(via
		(at 364.080044 -341.200486)
		(size 0.508)
		(drill 0.254)
		(layers "F.Cu" "B.Cu")
		(net "GND")
	)
	(via
		(at 430.8602 -346.09913)
		(size 0.4572)
		(drill 0.254)
		(layers "F.Cu" "B.Cu")
		(net "GND")
	)
	(via
		(at 59.09945 -372.567454)
		(size 0.508)
		(drill 0.254)
		(layers "F.Cu" "B.Cu")
		(net "GND")
	)
	(via
		(at 259.969508 -64.102234)
		(size 0.508)
		(drill 0.254)
		(layers "F.Cu" "B.Cu")
		(net "GND")
	)
	(via
		(at 57.979818 -103.814372)
		(size 0.508)
		(drill 0.254)
		(layers "F.Cu" "B.Cu")
		(net "GND")
	)
	(via
		(at 47.77486 -285.924752)
		(size 0.4064)
		(drill 0.2032)
		(layers "F.Cu" "B.Cu")
		(net "GND")
	)
	(via
		(at 75.74788 -380.141734)
		(size 0.508)
		(drill 0.254)
		(layers "F.Cu" "B.Cu")
		(net "GND")
	)
	(via
		(at 187.149994 -311.099962)
		(size 0.4064)
		(drill 0.2032)
		(layers "F.Cu" "B.Cu")
		(net "GND")
	)
	(via
		(at 370.69268 -228.403404)
		(size 0.508)
		(drill 0.254)
		(layers "F.Cu" "B.Cu")
		(net "GND")
	)
	(via
		(at 323.233542 -303.026826)
		(size 0.508)
		(drill 0.254)
		(layers "F.Cu" "B.Cu")
		(net "GND")
	)
	(via
		(at 416.974782 -286.874966)
		(size 0.4064)
		(drill 0.2032)
		(layers "F.Cu" "B.Cu")
		(net "GND")
	)
	(via
		(at 86.04631 -358.391714)
		(size 0.4572)
		(drill 0.254)
		(layers "F.Cu" "B.Cu")
		(net "GND")
	)
	(via
		(at 363.696504 -279.023572)
		(size 0.508)
		(drill 0.254)
		(layers "F.Cu" "B.Cu")
		(net "GND")
	)
	(via
		(at 109.165136 -393.248388)
		(size 0.508)
		(drill 0.254)
		(layers "F.Cu" "B.Cu")
		(net "GND")
	)
	(via
		(at 306.448206 -143.955008)
		(size 0.508)
		(drill 0.254)
		(layers "F.Cu" "B.Cu")
		(net "GND")
	)
	(via
		(at 338.435696 -344.831162)
		(size 0.4572)
		(drill 0.254)
		(layers "F.Cu" "B.Cu")
		(net "GND")
	)
	(via
		(at 61.549788 -274.999958)
		(size 0.4064)
		(drill 0.2032)
		(layers "F.Cu" "B.Cu")
		(net "GND")
	)
	(via
		(at 88.947752 -378.940314)
		(size 0.508)
		(drill 0.254)
		(layers "F.Cu" "B.Cu")
		(net "GND")
	)
	(via
		(at 177.174906 -305.874928)
		(size 0.4064)
		(drill 0.2032)
		(layers "F.Cu" "B.Cu")
		(net "GND")
	)
	(via
		(at 404.149814 -281.649932)
		(size 0.4064)
		(drill 0.2032)
		(layers "F.Cu" "B.Cu")
		(net "GND")
	)
	(via
		(at 131.57708 -352.245422)
		(size 0.4572)
		(drill 0.254)
		(layers "F.Cu" "B.Cu")
		(net "GND")
	)
	(via
		(at 277.599902 -312.999882)
		(size 0.4064)
		(drill 0.2032)
		(layers "F.Cu" "B.Cu")
		(net "GND")
	)
	(via
		(at 351.374964 -288.78149)
		(size 0.508)
		(drill 0.254)
		(layers "F.Cu" "B.Cu")
		(net "GND")
	)
	(via
		(at 91.902026 -57.461404)
		(size 0.508)
		(drill 0.254)
		(layers "F.Cu" "B.Cu")
		(net "GND")
	)
	(via
		(at 339.293962 -222.786956)
		(size 0.4572)
		(drill 0.254)
		(layers "F.Cu" "B.Cu")
		(net "GND")
	)
	(via
		(at 169.574972 -284.974792)
		(size 0.4064)
		(drill 0.2032)
		(layers "F.Cu" "B.Cu")
		(net "GND")
	)
	(via
		(at 301.824898 -300.174914)
		(size 0.4064)
		(drill 0.2032)
		(layers "F.Cu" "B.Cu")
		(net "GND")
	)
	(via
		(at 329.457812 -73.85177)
		(size 0.508)
		(drill 0.254)
		(layers "F.Cu" "B.Cu")
		(net "GND")
	)
	(via
		(at 170.347894 -407.24201)
		(size 0.508)
		(drill 0.254)
		(layers "F.Cu" "B.Cu")
		(net "GND")
	)
	(via
		(at 409.948888 -31.390082)
		(size 0.508)
		(drill 0.254)
		(layers "F.Cu" "B.Cu")
		(net "GND")
	)
	(via
		(at 127.97028 -289.41649)
		(size 0.508)
		(drill 0.254)
		(layers "F.Cu" "B.Cu")
		(net "GND")
	)
	(via
		(at 0.77089 -289.061144)
		(size 0.508)
		(drill 0.254)
		(layers "F.Cu" "B.Cu")
		(net "GND")
	)
	(via
		(at 78.64983 -272.14957)
		(size 0.4064)
		(drill 0.2032)
		(layers "F.Cu" "B.Cu")
		(net "GND")
	)
	(via
		(at 212.220556 -63.218314)
		(size 0.508)
		(drill 0.254)
		(layers "F.Cu" "B.Cu")
		(net "GND")
	)
	(via
		(at 414.74771 -120.035066)
		(size 0.508)
		(drill 0.254)
		(layers "F.Cu" "B.Cu")
		(net "GND")
	)
	(via
		(at 23.261574 -222.976186)
		(size 0.508)
		(drill 0.254)
		(layers "F.Cu" "B.Cu")
		(net "GND")
	)
	(via
		(at 67.66687 -136.645142)
		(size 0.508)
		(drill 0.254)
		(layers "F.Cu" "B.Cu")
		(net "GND")
	)
	(via
		(at 48.098456 -37.201094)
		(size 0.508)
		(drill 0.254)
		(layers "F.Cu" "B.Cu")
		(net "GND")
	)
	(via
		(at 151.748998 -31.390082)
		(size 0.508)
		(drill 0.254)
		(layers "F.Cu" "B.Cu")
		(net "GND")
	)
	(via
		(at 163.25596 -140.429488)
		(size 0.508)
		(drill 0.254)
		(layers "F.Cu" "B.Cu")
		(net "GND")
	)
	(via
		(at 300.399704 -314.899802)
		(size 0.4064)
		(drill 0.2032)
		(layers "F.Cu" "B.Cu")
		(net "GND")
	)
	(via
		(at 133.869684 -291.32149)
		(size 0.508)
		(drill 0.254)
		(layers "F.Cu" "B.Cu")
		(net "GND")
	)
	(via
		(at 390.327896 -398.24025)
		(size 0.508)
		(drill 0.254)
		(layers "F.Cu" "B.Cu")
		(net "GND")
	)
	(via
		(at 392.274806 -288.774886)
		(size 0.4064)
		(drill 0.2032)
		(layers "F.Cu" "B.Cu")
		(net "GND")
	)
	(via
		(at 302.871124 -32.911796)
		(size 0.508)
		(drill 0.254)
		(layers "F.Cu" "B.Cu")
		(net "GND")
	)
	(via
		(at 73.899776 -274.049744)
		(size 0.4064)
		(drill 0.2032)
		(layers "F.Cu" "B.Cu")
		(net "GND")
	)
	(via
		(at 163.252404 -145.821908)
		(size 0.508)
		(drill 0.254)
		(layers "F.Cu" "B.Cu")
		(net "GND")
	)
	(via
		(at 370.61902 -348.58579)
		(size 0.4064)
		(drill 0.2032)
		(layers "F.Cu" "B.Cu")
		(net "GND")
	)
	(via
		(at 338.41817 -284.333188)
		(size 0.49022)
		(drill 0.254)
		(layers "F.Cu" "B.Cu")
		(net "GND")
	)
	(via
		(at 412.699962 -318.699896)
		(size 0.4064)
		(drill 0.2032)
		(layers "F.Cu" "B.Cu")
		(net "GND")
	)
	(via
		(at 194.749928 -307.299868)
		(size 0.4064)
		(drill 0.2032)
		(layers "F.Cu" "B.Cu")
		(net "GND")
	)
	(via
		(at 53.474874 -297.32478)
		(size 0.4064)
		(drill 0.2032)
		(layers "F.Cu" "B.Cu")
		(net "GND")
	)
	(via
		(at 72.474836 -301.124874)
		(size 0.4064)
		(drill 0.2032)
		(layers "F.Cu" "B.Cu")
		(net "GND")
	)
	(via
		(at 56.324754 -289.724846)
		(size 0.4064)
		(drill 0.2032)
		(layers "F.Cu" "B.Cu")
		(net "GND")
	)
	(via
		(at 315.339984 -27.729688)
		(size 0.508)
		(drill 0.254)
		(layers "F.Cu" "B.Cu")
		(net "GND")
	)
	(via
		(at 115.34775 -397.140176)
		(size 0.4572)
		(drill 0.254)
		(layers "F.Cu" "B.Cu")
		(net "GND")
	)
	(via
		(at 434.327808 -374.938544)
		(size 0.508)
		(drill 0.254)
		(layers "F.Cu" "B.Cu")
		(net "GND")
	)
	(via
		(at 343.394792 -341.805514)
		(size 0.4572)
		(drill 0.254)
		(layers "F.Cu" "B.Cu")
		(net "GND")
	)
	(via
		(at 325.002906 -196.234304)
		(size 0.508)
		(drill 0.254)
		(layers "F.Cu" "B.Cu")
		(net "GND")
	)
	(via
		(at 301.824898 -298.27474)
		(size 0.4064)
		(drill 0.2032)
		(layers "F.Cu" "B.Cu")
		(net "GND")
	)
	(via
		(at 19.555714 -240.318036)
		(size 0.508)
		(drill 0.254)
		(layers "F.Cu" "B.Cu")
		(net "GND")
	)
	(via
		(at 279.499822 -278.799798)
		(size 0.4064)
		(drill 0.2032)
		(layers "F.Cu" "B.Cu")
		(net "GND")
	)
	(via
		(at 162.450018 -319.65011)
		(size 0.4064)
		(drill 0.2032)
		(layers "F.Cu" "B.Cu")
		(net "GND")
	)
	(via
		(at 190.348108 -142.15491)
		(size 0.508)
		(drill 0.254)
		(layers "F.Cu" "B.Cu")
		(net "GND")
	)
	(via
		(at 138.490198 -215.981026)
		(size 0.508)
		(drill 0.254)
		(layers "F.Cu" "B.Cu")
		(net "GND")
	)
	(via
		(at 50.624994 -305.874928)
		(size 0.4064)
		(drill 0.2032)
		(layers "F.Cu" "B.Cu")
		(net "GND")
	)
	(via
		(at 434.327808 -409.940252)
		(size 0.508)
		(drill 0.254)
		(layers "F.Cu" "B.Cu")
		(net "GND")
	)
	(via
		(at 301.349918 -311.099962)
		(size 0.4064)
		(drill 0.2032)
		(layers "F.Cu" "B.Cu")
		(net "GND")
	)
	(via
		(at 420.299896 -317.749936)
		(size 0.4064)
		(drill 0.2032)
		(layers "F.Cu" "B.Cu")
		(net "GND")
	)
	(via
		(at 70.099936 -314.899802)
		(size 0.4064)
		(drill 0.2032)
		(layers "F.Cu" "B.Cu")
		(net "GND")
	)
	(via
		(at 180.02504 -305.874928)
		(size 0.4064)
		(drill 0.2032)
		(layers "F.Cu" "B.Cu")
		(net "GND")
	)
	(via
		(at 181.92496 -303.974754)
		(size 0.4064)
		(drill 0.2032)
		(layers "F.Cu" "B.Cu")
		(net "GND")
	)
	(via
		(at 421.53332 -347.951806)
		(size 0.4572)
		(drill 0.254)
		(layers "F.Cu" "B.Cu")
		(net "GND")
	)
	(via
		(at 324.369684 -357.75773)
		(size 0.4064)
		(drill 0.2032)
		(layers "F.Cu" "B.Cu")
		(net "GND")
	)
	(via
		(at 398.925034 -306.824888)
		(size 0.4064)
		(drill 0.2032)
		(layers "F.Cu" "B.Cu")
		(net "GND")
	)
	(via
		(at 392.753088 -352.245422)
		(size 0.4572)
		(drill 0.254)
		(layers "F.Cu" "B.Cu")
		(net "GND")
	)
	(via
		(at 37.799772 -300.649894)
		(size 0.4064)
		(drill 0.2032)
		(layers "F.Cu" "B.Cu")
		(net "GND")
	)
	(via
		(at 295.649904 -281.649932)
		(size 0.4064)
		(drill 0.2032)
		(layers "F.Cu" "B.Cu")
		(net "GND")
	)
	(via
		(at 40.802814 -74.624184)
		(size 0.508)
		(drill 0.254)
		(layers "F.Cu" "B.Cu")
		(net "GND")
	)
	(via
		(at 47.032926 -100.64496)
		(size 0.508)
		(drill 0.254)
		(layers "F.Cu" "B.Cu")
		(net "GND")
	)
	(via
		(at 76.74991 -319.65011)
		(size 0.4064)
		(drill 0.2032)
		(layers "F.Cu" "B.Cu")
		(net "GND")
	)
	(via
		(at 449.679822 -107.681776)
		(size 0.508)
		(drill 0.254)
		(layers "F.Cu" "B.Cu")
		(net "GND")
	)
	(via
		(at 448.331082 -123.795028)
		(size 0.508)
		(drill 0.254)
		(layers "F.Cu" "B.Cu")
		(net "GND")
	)
	(via
		(at 213.620096 -57.076848)
		(size 0.508)
		(drill 0.254)
		(layers "F.Cu" "B.Cu")
		(net "GND")
	)
	(via
		(at 73.899776 -283.549852)
		(size 0.4064)
		(drill 0.2032)
		(layers "F.Cu" "B.Cu")
		(net "GND")
	)
	(via
		(at 119.747792 -402.241766)
		(size 0.4572)
		(drill 0.254)
		(layers "F.Cu" "B.Cu")
		(net "GND")
	)
	(via
		(at 386.099812 -307.299868)
		(size 0.4064)
		(drill 0.2032)
		(layers "F.Cu" "B.Cu")
		(net "GND")
	)
	(via
		(at 54.70652 -118.754906)
		(size 0.508)
		(drill 0.254)
		(layers "F.Cu" "B.Cu")
		(net "GND")
	)
	(via
		(at 360.35615 -33.19018)
		(size 0.508)
		(drill 0.254)
		(layers "F.Cu" "B.Cu")
		(net "GND")
	)
	(via
		(at 217.390218 -237.62716)
		(size 0.508)
		(drill 0.254)
		(layers "F.Cu" "B.Cu")
		(net "GND")
	)
	(via
		(at 425.657518 -29.784294)
		(size 0.508)
		(drill 0.254)
		(layers "F.Cu" "B.Cu")
		(net "GND")
	)
	(via
		(at 272.374868 -292.574726)
		(size 0.4064)
		(drill 0.2032)
		(layers "F.Cu" "B.Cu")
		(net "GND")
	)
	(via
		(at 277.02637 -349.219774)
		(size 0.4572)
		(drill 0.254)
		(layers "F.Cu" "B.Cu")
		(net "GND")
	)
	(via
		(at 410.356304 -344.831162)
		(size 0.4572)
		(drill 0.254)
		(layers "F.Cu" "B.Cu")
		(net "GND")
	)
	(via
		(at 428.37481 -290.674806)
		(size 0.4064)
		(drill 0.2032)
		(layers "F.Cu" "B.Cu")
		(net "GND")
	)
	(via
		(at 46.8249 -289.724846)
		(size 0.4064)
		(drill 0.2032)
		(layers "F.Cu" "B.Cu")
		(net "GND")
	)
	(via
		(at 31.747968 -378.94006)
		(size 0.508)
		(drill 0.254)
		(layers "F.Cu" "B.Cu")
		(net "GND")
	)
	(via
		(at 364.49762 -284.333188)
		(size 0.49022)
		(drill 0.254)
		(layers "F.Cu" "B.Cu")
		(net "GND")
	)
	(via
		(at 243.541042 -92.151708)
		(size 0.508)
		(drill 0.254)
		(layers "F.Cu" "B.Cu")
		(net "GND")
	)
	(via
		(at 158.174944 -289.724846)
		(size 0.4064)
		(drill 0.2032)
		(layers "F.Cu" "B.Cu")
		(net "GND")
	)
	(via
		(at 389.424926 -292.57498)
		(size 0.4064)
		(drill 0.2032)
		(layers "F.Cu" "B.Cu")
		(net "GND")
	)
	(via
		(at 118.736618 -51.661822)
		(size 0.508)
		(drill 0.254)
		(layers "F.Cu" "B.Cu")
		(net "GND")
	)
	(via
		(at 418.053012 -348.58579)
		(size 0.4064)
		(drill 0.2032)
		(layers "F.Cu" "B.Cu")
		(net "GND")
	)
	(via
		(at 37.550344 -253.45644)
		(size 0.508)
		(drill 0.254)
		(layers "F.Cu" "B.Cu")
		(net "GND")
	)
	(via
		(at 392.971274 -32.911796)
		(size 0.508)
		(drill 0.254)
		(layers "F.Cu" "B.Cu")
		(net "GND")
	)
	(via
		(at 164.349938 -315.849762)
		(size 0.4064)
		(drill 0.2032)
		(layers "F.Cu" "B.Cu")
		(net "GND")
	)
	(via
		(at 54.671976 -49.574704)
		(size 0.508)
		(drill 0.254)
		(layers "F.Cu" "B.Cu")
		(net "GND")
	)
	(via
		(at 128.547622 -407.638504)
		(size 0.508)
		(drill 0.254)
		(layers "F.Cu" "B.Cu")
		(net "GND")
	)
	(via
		(at 278.656542 -345.465146)
		(size 0.4064)
		(drill 0.2032)
		(layers "F.Cu" "B.Cu")
		(net "GND")
	)
	(via
		(at 64.59347 -121.835164)
		(size 0.508)
		(drill 0.254)
		(layers "F.Cu" "B.Cu")
		(net "GND")
	)
	(via
		(at 33.947862 -383.940304)
		(size 0.508)
		(drill 0.254)
		(layers "F.Cu" "B.Cu")
		(net "GND")
	)
	(via
		(at 405.575008 -284.024832)
		(size 0.4064)
		(drill 0.2032)
		(layers "F.Cu" "B.Cu")
		(net "GND")
	)
	(via
		(at 38.401752 -124.43333)
		(size 0.508)
		(drill 0.254)
		(layers "F.Cu" "B.Cu")
		(net "GND")
	)
	(via
		(at 337.5279 -373.441976)
		(size 0.508)
		(drill 0.254)
		(layers "F.Cu" "B.Cu")
		(net "GND")
	)
	(via
		(at 278.68753 -26.360882)
		(size 0.508)
		(drill 0.254)
		(layers "F.Cu" "B.Cu")
		(net "GND")
	)
	(via
		(at 30.715204 -60.601606)
		(size 0.508)
		(drill 0.254)
		(layers "F.Cu" "B.Cu")
		(net "GND")
	)
	(via
		(at 70.574916 -302.074834)
		(size 0.4064)
		(drill 0.2032)
		(layers "F.Cu" "B.Cu")
		(net "GND")
	)
	(via
		(at 1.564894 -273.301714)
		(size 0.508)
		(drill 0.254)
		(layers "F.Cu" "B.Cu")
		(net "GND")
	)
	(via
		(at 127.97028 -288.78149)
		(size 0.508)
		(drill 0.254)
		(layers "F.Cu" "B.Cu")
		(net "GND")
	)
	(via
		(at 448.881246 -33.459674)
		(size 0.508)
		(drill 0.254)
		(layers "F.Cu" "B.Cu")
		(net "GND")
	)
	(via
		(at 262.766302 -338.75091)
		(size 0.508)
		(drill 0.254)
		(layers "F.Cu" "B.Cu")
		(net "GND")
	)
	(via
		(at 416.574224 -350.977454)
		(size 0.4572)
		(drill 0.254)
		(layers "F.Cu" "B.Cu")
		(net "GND")
	)
	(via
		(at 215.52408 -258.28117)
		(size 0.508)
		(drill 0.254)
		(layers "F.Cu" "B.Cu")
		(net "GND")
	)
	(via
		(at 213.357968 -73.85177)
		(size 0.508)
		(drill 0.254)
		(layers "F.Cu" "B.Cu")
		(net "GND")
	)
	(via
		(at 39.382954 -34.990024)
		(size 0.508)
		(drill 0.254)
		(layers "F.Cu" "B.Cu")
		(net "GND")
	)
	(via
		(at 35.518344 -253.45644)
		(size 0.508)
		(drill 0.254)
		(layers "F.Cu" "B.Cu")
		(net "GND")
	)
	(via
		(at 297.074844 -305.874928)
		(size 0.4064)
		(drill 0.2032)
		(layers "F.Cu" "B.Cu")
		(net "GND")
	)
	(via
		(at 65.81267 -136.645142)
		(size 0.508)
		(drill 0.254)
		(layers "F.Cu" "B.Cu")
		(net "GND")
	)
	(via
		(at 152.47493 -277.374858)
		(size 0.4064)
		(drill 0.2032)
		(layers "F.Cu" "B.Cu")
		(net "GND")
	)
	(via
		(at 241.848894 -25.990042)
		(size 0.508)
		(drill 0.254)
		(layers "F.Cu" "B.Cu")
		(net "GND")
	)
	(via
		(at 339.728048 -372.341902)
		(size 0.508)
		(drill 0.254)
		(layers "F.Cu" "B.Cu")
		(net "GND")
	)
	(via
		(at 48.745648 -354.732082)
		(size 0.4064)
		(drill 0.2032)
		(layers "F.Cu" "B.Cu")
		(net "GND")
	)
	(via
		(at 335.328006 -407.638504)
		(size 0.508)
		(drill 0.254)
		(layers "F.Cu" "B.Cu")
		(net "GND")
	)
	(via
		(at 36.14801 -375.040144)
		(size 0.508)
		(drill 0.254)
		(layers "F.Cu" "B.Cu")
		(net "GND")
	)
	(via
		(at 111.391446 -337.805522)
		(size 0.6604)
		(drill 0.3302)
		(layers "F.Cu" "B.Cu")
		(net "GND")
	)
	(via
		(at 94.280736 -29.589984)
		(size 0.508)
		(drill 0.254)
		(layers "F.Cu" "B.Cu")
		(net "GND")
	)
	(via
		(at 163.399978 -278.799798)
		(size 0.4064)
		(drill 0.2032)
		(layers "F.Cu" "B.Cu")
		(net "GND")
	)
	(via
		(at 458.465936 -110.22965)
		(size 0.508)
		(drill 0.254)
		(layers "F.Cu" "B.Cu")
		(net "GND")
	)
	(via
		(at 124.653548 -279.086818)
		(size 0.508)
		(drill 0.254)
		(layers "F.Cu" "B.Cu")
		(net "GND")
	)
	(via
		(at 278.139144 -28.05303)
		(size 0.508)
		(drill 0.254)
		(layers "F.Cu" "B.Cu")
		(net "GND")
	)
	(via
		(at 453.623172 -51.019456)
		(size 0.508)
		(drill 0.254)
		(layers "F.Cu" "B.Cu")
		(net "GND")
	)
	(via
		(at 71.999856 -273.099784)
		(size 0.4064)
		(drill 0.2032)
		(layers "F.Cu" "B.Cu")
		(net "GND")
	)
	(via
		(at 164.351462 -47.03191)
		(size 0.508)
		(drill 0.254)
		(layers "F.Cu" "B.Cu")
		(net "GND")
	)
	(via
		(at 81.499964 -311.099962)
		(size 0.4064)
		(drill 0.2032)
		(layers "F.Cu" "B.Cu")
		(net "GND")
	)
	(via
		(at 411.275022 -293.52494)
		(size 0.4064)
		(drill 0.2032)
		(layers "F.Cu" "B.Cu")
		(net "GND")
	)
	(via
		(at 177.174906 -306.824888)
		(size 0.4064)
		(drill 0.2032)
		(layers "F.Cu" "B.Cu")
		(net "GND")
	)
	(via
		(at 310.849772 -303.499774)
		(size 0.4064)
		(drill 0.2032)
		(layers "F.Cu" "B.Cu")
		(net "GND")
	)
	(via
		(at 237.837726 -56.208168)
		(size 0.508)
		(drill 0.254)
		(layers "F.Cu" "B.Cu")
		(net "GND")
	)
	(via
		(at 319.848738 -27.79014)
		(size 0.508)
		(drill 0.254)
		(layers "F.Cu" "B.Cu")
		(net "GND")
	)
	(via
		(at 71.760334 -354.098098)
		(size 0.4572)
		(drill 0.254)
		(layers "F.Cu" "B.Cu")
		(net "GND")
	)
	(via
		(at 53.949854 -316.799722)
		(size 0.4064)
		(drill 0.2032)
		(layers "F.Cu" "B.Cu")
		(net "GND")
	)
	(via
		(at 38.275006 -274.524978)
		(size 0.4064)
		(drill 0.2032)
		(layers "F.Cu" "B.Cu")
		(net "GND")
	)
	(via
		(at 309.899812 -313.949842)
		(size 0.4064)
		(drill 0.2032)
		(layers "F.Cu" "B.Cu")
		(net "GND")
	)
	(via
		(at 255.171194 -395.794738)
		(size 0.508)
		(drill 0.254)
		(layers "F.Cu" "B.Cu")
		(net "GND")
	)
	(via
		(at 108.89996 -134.21106)
		(size 0.508)
		(drill 0.254)
		(layers "F.Cu" "B.Cu")
		(net "GND")
	)
	(via
		(at 323.48297 -34.990024)
		(size 0.508)
		(drill 0.254)
		(layers "F.Cu" "B.Cu")
		(net "GND")
	)
	(via
		(at 385.927854 -402.140166)
		(size 0.508)
		(drill 0.254)
		(layers "F.Cu" "B.Cu")
		(net "GND")
	)
	(via
		(at 420.567104 -121.83491)
		(size 0.508)
		(drill 0.254)
		(layers "F.Cu" "B.Cu")
		(net "GND")
	)
	(via
		(at 386.044948 -29.589984)
		(size 0.508)
		(drill 0.254)
		(layers "F.Cu" "B.Cu")
		(net "GND")
	)
	(via
		(at 63.912242 -357.75773)
		(size 0.4064)
		(drill 0.2032)
		(layers "F.Cu" "B.Cu")
		(net "GND")
	)
	(via
		(at 292.65499 -29.590238)
		(size 0.508)
		(drill 0.254)
		(layers "F.Cu" "B.Cu")
		(net "GND")
	)
	(via
		(at 244.87378 -206.503524)
		(size 0.508)
		(drill 0.254)
		(layers "F.Cu" "B.Cu")
		(net "GND")
	)
	(via
		(at 381.527812 -374.938544)
		(size 0.508)
		(drill 0.254)
		(layers "F.Cu" "B.Cu")
		(net "GND")
	)
	(via
		(at 149.273006 -382.453896)
		(size 0.508)
		(drill 0.254)
		(layers "F.Cu" "B.Cu")
		(net "GND")
	)
	(via
		(at 78.64983 -305.399948)
		(size 0.4064)
		(drill 0.2032)
		(layers "F.Cu" "B.Cu")
		(net "GND")
	)
	(via
		(at 168.952164 -122.354848)
		(size 0.508)
		(drill 0.254)
		(layers "F.Cu" "B.Cu")
		(net "GND")
	)
	(via
		(at 306.451254 -47.03191)
		(size 0.508)
		(drill 0.254)
		(layers "F.Cu" "B.Cu")
		(net "GND")
	)
	(via
		(at 124.829062 -211.974684)
		(size 0.508)
		(drill 0.254)
		(layers "F.Cu" "B.Cu")
		(net "GND")
	)
	(via
		(at 117.547644 -402.140166)
		(size 0.4572)
		(drill 0.254)
		(layers "F.Cu" "B.Cu")
		(net "GND")
	)
	(via
		(at 90.414094 -354.074222)
		(size 0.4572)
		(drill 0.254)
		(layers "F.Cu" "B.Cu")
		(net "GND")
	)
	(via
		(at 266.691618 -130.236722)
		(size 0.508)
		(drill 0.254)
		(layers "F.Cu" "B.Cu")
		(net "GND")
	)
	(via
		(at 133.808978 -187.730638)
		(size 0.508)
		(drill 0.254)
		(layers "F.Cu" "B.Cu")
		(net "GND")
	)
	(via
		(at 383.72796 -380.141734)
		(size 0.508)
		(drill 0.254)
		(layers "F.Cu" "B.Cu")
		(net "GND")
	)
	(via
		(at 299.449744 -315.849762)
		(size 0.4064)
		(drill 0.2032)
		(layers "F.Cu" "B.Cu")
		(net "GND")
	)
	(via
		(at 165.947852 -373.441976)
		(size 0.508)
		(drill 0.254)
		(layers "F.Cu" "B.Cu")
		(net "GND")
	)
	(via
		(at 415.3154 -355.366066)
		(size 0.4572)
		(drill 0.254)
		(layers "F.Cu" "B.Cu")
		(net "GND")
	)
	(via
		(at 392.52779 -403.738588)
		(size 0.508)
		(drill 0.254)
		(layers "F.Cu" "B.Cu")
		(net "GND")
	)
	(via
		(at 132.911088 -223.537018)
		(size 0.508)
		(drill 0.254)
		(layers "F.Cu" "B.Cu")
		(net "GND")
	)
	(via
		(at 275.224748 -290.674806)
		(size 0.4064)
		(drill 0.2032)
		(layers "F.Cu" "B.Cu")
		(net "GND")
	)
	(via
		(at 172.308266 -52.536852)
		(size 0.508)
		(drill 0.254)
		(layers "F.Cu" "B.Cu")
		(net "GND")
	)
	(via
		(at 34.679636 -355.366066)
		(size 0.4572)
		(drill 0.254)
		(layers "F.Cu" "B.Cu")
		(net "GND")
	)
	(via
		(at 342.172544 -198.13016)
		(size 0.508)
		(drill 0.254)
		(layers "F.Cu" "B.Cu")
		(net "GND")
	)
	(via
		(at 370.092224 -70.918832)
		(size 0.508)
		(drill 0.254)
		(layers "F.Cu" "B.Cu")
		(net "GND")
	)
	(via
		(at 286.149542 -272.14957)
		(size 0.4064)
		(drill 0.2032)
		(layers "F.Cu" "B.Cu")
		(net "GND")
	)
	(via
		(at 122.737372 -286.842454)
		(size 0.508)
		(drill 0.254)
		(layers "F.Cu" "B.Cu")
		(net "GND")
	)
	(via
		(at 260.987032 -0.762)
		(size 0.508)
		(drill 0.254)
		(layers "F.Cu" "B.Cu")
		(net "GND")
	)
	(via
		(at 385.433824 -106.316526)
		(size 0.508)
		(drill 0.254)
		(layers "F.Cu" "B.Cu")
		(net "GND")
	)
	(via
		(at 172.574204 -357.123746)
		(size 0.4572)
		(drill 0.254)
		(layers "F.Cu" "B.Cu")
		(net "GND")
	)
	(via
		(at 68.651374 -358.391714)
		(size 0.4572)
		(drill 0.254)
		(layers "F.Cu" "B.Cu")
		(net "GND")
	)
	(via
		(at 429.927766 -382.73863)
		(size 0.508)
		(drill 0.254)
		(layers "F.Cu" "B.Cu")
		(net "GND")
	)
	(via
		(at 240.655094 -31.390082)
		(size 0.508)
		(drill 0.254)
		(layers "F.Cu" "B.Cu")
		(net "GND")
	)
	(via
		(at 44.94784 -407.638504)
		(size 0.508)
		(drill 0.254)
		(layers "F.Cu" "B.Cu")
		(net "GND")
	)
	(via
		(at 81.974944 -293.52494)
		(size 0.4064)
		(drill 0.2032)
		(layers "F.Cu" "B.Cu")
		(net "GND")
	)
	(via
		(at 141.369796 -181.871874)
		(size 0.508)
		(drill 0.254)
		(layers "F.Cu" "B.Cu")
		(net "GND")
	)
	(via
		(at 27.347926 -408.840178)
		(size 0.508)
		(drill 0.254)
		(layers "F.Cu" "B.Cu")
		(net "GND")
	)
	(via
		(at 287.099756 -310.149748)
		(size 0.4064)
		(drill 0.2032)
		(layers "F.Cu" "B.Cu")
		(net "GND")
	)
	(via
		(at 75.79995 -313.949842)
		(size 0.4064)
		(drill 0.2032)
		(layers "F.Cu" "B.Cu")
		(net "GND")
	)
	(via
		(at 176.054512 -351.611438)
		(size 0.4064)
		(drill 0.2032)
		(layers "F.Cu" "B.Cu")
		(net "GND")
	)
	(via
		(at 263.043162 -52.536852)
		(size 0.508)
		(drill 0.254)
		(layers "F.Cu" "B.Cu")
		(net "GND")
	)
	(via
		(at 74.248264 -143.955008)
		(size 0.508)
		(drill 0.254)
		(layers "F.Cu" "B.Cu")
		(net "GND")
	)
	(via
		(at 416.574224 -358.391714)
		(size 0.4572)
		(drill 0.254)
		(layers "F.Cu" "B.Cu")
		(net "GND")
	)
	(via
		(at 137.413492 -33.459674)
		(size 0.508)
		(drill 0.254)
		(layers "F.Cu" "B.Cu")
		(net "GND")
	)
	(via
		(at 206.721456 -123.66498)
		(size 0.508)
		(drill 0.254)
		(layers "F.Cu" "B.Cu")
		(net "GND")
	)
	(via
		(at 439.59145 -287.619694)
		(size 0.508)
		(drill 0.254)
		(layers "F.Cu" "B.Cu")
		(net "GND")
	)
	(via
		(at 221.59976 -317.063882)
		(size 0.508)
		(drill 0.254)
		(layers "F.Cu" "B.Cu")
		(net "GND")
	)
	(via
		(at 336.89417 -225.186748)
		(size 0.4572)
		(drill 0.254)
		(layers "F.Cu" "B.Cu")
		(net "GND")
	)
	(via
		(at 277.251668 -100.64496)
		(size 0.508)
		(drill 0.254)
		(layers "F.Cu" "B.Cu")
		(net "GND")
	)
	(via
		(at 400.229832 -344.831162)
		(size 0.4572)
		(drill 0.254)
		(layers "F.Cu" "B.Cu")
		(net "GND")
	)
	(via
		(at 126.347728 -406.040336)
		(size 0.4572)
		(drill 0.254)
		(layers "F.Cu" "B.Cu")
		(net "GND")
	)
	(via
		(at 237.849918 -314.193682)
		(size 0.508)
		(drill 0.254)
		(layers "F.Cu" "B.Cu")
		(net "GND")
	)
	(via
		(at 301.88408 -122.597164)
		(size 0.508)
		(drill 0.254)
		(layers "F.Cu" "B.Cu")
		(net "GND")
	)
	(via
		(at 292.32479 -291.624766)
		(size 0.4064)
		(drill 0.2032)
		(layers "F.Cu" "B.Cu")
		(net "GND")
	)
	(via
		(at 43.499786 -314.899802)
		(size 0.4064)
		(drill 0.2032)
		(layers "F.Cu" "B.Cu")
		(net "GND")
	)
	(via
		(at 421.127682 -371.038628)
		(size 0.508)
		(drill 0.254)
		(layers "F.Cu" "B.Cu")
		(net "GND")
	)
	(via
		(at 108.726986 -0.762)
		(size 0.508)
		(drill 0.254)
		(layers "F.Cu" "B.Cu")
		(net "GND")
	)
	(via
		(at 114.402108 -345.465146)
		(size 0.4064)
		(drill 0.2032)
		(layers "F.Cu" "B.Cu")
		(net "GND")
	)
	(via
		(at 288.524696 -298.27474)
		(size 0.4064)
		(drill 0.2032)
		(layers "F.Cu" "B.Cu")
		(net "GND")
	)
	(via
		(at 403.00656 -100.64496)
		(size 0.508)
		(drill 0.254)
		(layers "F.Cu" "B.Cu")
		(net "GND")
	)
	(via
		(at 75.32497 -294.4749)
		(size 0.4064)
		(drill 0.2032)
		(layers "F.Cu" "B.Cu")
		(net "GND")
	)
	(via
		(at 438.088532 -31.642304)
		(size 0.508)
		(drill 0.254)
		(layers "F.Cu" "B.Cu")
		(net "GND")
	)
	(via
		(at 124.100336 -343.073482)
		(size 0.4572)
		(drill 0.254)
		(layers "F.Cu" "B.Cu")
		(net "GND")
	)
	(via
		(at 370.881402 -33.459674)
		(size 0.508)
		(drill 0.254)
		(layers "F.Cu" "B.Cu")
		(net "GND")
	)
	(via
		(at 158.649924 -314.899802)
		(size 0.4064)
		(drill 0.2032)
		(layers "F.Cu" "B.Cu")
		(net "GND")
	)
	(via
		(at 227.52812 -59.089036)
		(size 0.508)
		(drill 0.254)
		(layers "F.Cu" "B.Cu")
		(net "GND")
	)
	(via
		(at 397.02486 -291.624766)
		(size 0.4064)
		(drill 0.2032)
		(layers "F.Cu" "B.Cu")
		(net "GND")
	)
	(via
		(at 172.574204 -346.09913)
		(size 0.4572)
		(drill 0.254)
		(layers "F.Cu" "B.Cu")
		(net "GND")
	)
	(via
		(at 391.799826 -307.299868)
		(size 0.4064)
		(drill 0.2032)
		(layers "F.Cu" "B.Cu")
		(net "GND")
	)
	(via
		(at 170.347894 -397.038576)
		(size 0.508)
		(drill 0.254)
		(layers "F.Cu" "B.Cu")
		(net "GND")
	)
	(via
		(at 210.380834 -31.390082)
		(size 0.508)
		(drill 0.254)
		(layers "F.Cu" "B.Cu")
		(net "GND")
	)
	(via
		(at 228.298502 -37.201094)
		(size 0.508)
		(drill 0.254)
		(layers "F.Cu" "B.Cu")
		(net "GND")
	)
	(via
		(at 26.193496 -292.732714)
		(size 0.508)
		(drill 0.254)
		(layers "F.Cu" "B.Cu")
		(net "GND")
	)
	(via
		(at 66.248788 -31.390082)
		(size 0.508)
		(drill 0.254)
		(layers "F.Cu" "B.Cu")
		(net "GND")
	)
	(via
		(at 297.549824 -280.699718)
		(size 0.4064)
		(drill 0.2032)
		(layers "F.Cu" "B.Cu")
		(net "GND")
	)
	(via
		(at 269.561818 -150.457916)
		(size 0.508)
		(drill 0.254)
		(layers "F.Cu" "B.Cu")
		(net "GND")
	)
	(via
		(at 308.949852 -308.249828)
		(size 0.4064)
		(drill 0.2032)
		(layers "F.Cu" "B.Cu")
		(net "GND")
	)
	(via
		(at 466.827616 -52.012596)
		(size 0.508)
		(drill 0.254)
		(layers "F.Cu" "B.Cu")
		(net "GND")
	)
	(via
		(at 442.580776 -25.990042)
		(size 0.508)
		(drill 0.254)
		(layers "F.Cu" "B.Cu")
		(net "GND")
	)
	(via
		(at 169.415206 -45.88891)
		(size 0.508)
		(drill 0.254)
		(layers "F.Cu" "B.Cu")
		(net "GND")
	)
	(via
		(at 277.124922 -282.124912)
		(size 0.4064)
		(drill 0.2032)
		(layers "F.Cu" "B.Cu")
		(net "GND")
	)
	(via
		(at 259.56133 -196.081396)
		(size 0.508)
		(drill 0.254)
		(layers "F.Cu" "B.Cu")
		(net "GND")
	)
	(via
		(at 155.800044 -317.749936)
		(size 0.4064)
		(drill 0.2032)
		(layers "F.Cu" "B.Cu")
		(net "GND")
	)
	(via
		(at 186.200034 -313.949842)
		(size 0.4064)
		(drill 0.2032)
		(layers "F.Cu" "B.Cu")
		(net "GND")
	)
	(via
		(at 290.42487 -284.974792)
		(size 0.4064)
		(drill 0.2032)
		(layers "F.Cu" "B.Cu")
		(net "GND")
	)
	(via
		(at 269.161006 -260.338316)
		(size 0.508)
		(drill 0.254)
		(layers "F.Cu" "B.Cu")
		(net "GND")
	)
	(via
		(at 285.143702 -24.648668)
		(size 0.508)
		(drill 0.254)
		(layers "F.Cu" "B.Cu")
		(net "GND")
	)
	(via
		(at 366.887252 -332.311248)
		(size 0.508)
		(drill 0.254)
		(layers "F.Cu" "B.Cu")
		(net "GND")
	)
	(via
		(at 195.423282 -51.019456)
		(size 0.508)
		(drill 0.254)
		(layers "F.Cu" "B.Cu")
		(net "GND")
	)
	(via
		(at 249.020838 -120.15343)
		(size 0.508)
		(drill 0.254)
		(layers "F.Cu" "B.Cu")
		(net "GND")
	)
	(via
		(at 285.199836 -313.949842)
		(size 0.4064)
		(drill 0.2032)
		(layers "F.Cu" "B.Cu")
		(net "GND")
	)
	(via
		(at 315.414152 -347.92793)
		(size 0.4572)
		(drill 0.254)
		(layers "F.Cu" "B.Cu")
		(net "GND")
	)
	(via
		(at 150.602442 -253.45644)
		(size 0.508)
		(drill 0.254)
		(layers "F.Cu" "B.Cu")
		(net "GND")
	)
	(via
		(at 80.898238 -134.566914)
		(size 0.508)
		(drill 0.254)
		(layers "F.Cu" "B.Cu")
		(net "GND")
	)
	(via
		(at 422.548304 -147.55495)
		(size 0.508)
		(drill 0.254)
		(layers "F.Cu" "B.Cu")
		(net "GND")
	)
	(via
		(at 332.878684 -104.115616)
		(size 0.508)
		(drill 0.254)
		(layers "F.Cu" "B.Cu")
		(net "GND")
	)
	(via
		(at 207.133698 -303.026826)
		(size 0.508)
		(drill 0.254)
		(layers "F.Cu" "B.Cu")
		(net "GND")
	)
	(via
		(at 312.836306 -51.661822)
		(size 0.508)
		(drill 0.254)
		(layers "F.Cu" "B.Cu")
		(net "GND")
	)
	(via
		(at 34.491676 -135.095488)
		(size 0.508)
		(drill 0.254)
		(layers "F.Cu" "B.Cu")
		(net "GND")
	)
	(via
		(at 129.044446 -222.958406)
		(size 0.508)
		(drill 0.254)
		(layers "F.Cu" "B.Cu")
		(net "GND")
	)
	(via
		(at 243.998242 -21.738336)
		(size 0.508)
		(drill 0.254)
		(layers "F.Cu" "B.Cu")
		(net "GND")
	)
	(via
		(at 370.990368 -343.073482)
		(size 0.4572)
		(drill 0.254)
		(layers "F.Cu" "B.Cu")
		(net "GND")
	)
	(via
		(at 61.549788 -319.65011)
		(size 0.4064)
		(drill 0.2032)
		(layers "F.Cu" "B.Cu")
		(net "GND")
	)
	(via
		(at 183.82488 -306.824888)
		(size 0.4064)
		(drill 0.2032)
		(layers "F.Cu" "B.Cu")
		(net "GND")
	)
	(via
		(at 327.729088 -117.426486)
		(size 0.508)
		(drill 0.254)
		(layers "F.Cu" "B.Cu")
		(net "GND")
	)
	(via
		(at 180.64226 -347.951806)
		(size 0.4572)
		(drill 0.254)
		(layers "F.Cu" "B.Cu")
		(net "GND")
	)
	(via
		(at 216.060274 -20.35556)
		(size 0.508)
		(drill 0.254)
		(layers "F.Cu" "B.Cu")
		(net "GND")
	)
	(via
		(at 390.327896 -374.938544)
		(size 0.508)
		(drill 0.254)
		(layers "F.Cu" "B.Cu")
		(net "GND")
	)
	(via
		(at 43.499786 -276.899878)
		(size 0.4064)
		(drill 0.2032)
		(layers "F.Cu" "B.Cu")
		(net "GND")
	)
	(via
		(at 443.783466 -113.364772)
		(size 0.508)
		(drill 0.254)
		(layers "F.Cu" "B.Cu")
		(net "GND")
	)
	(via
		(at 45.87494 -287.824926)
		(size 0.4064)
		(drill 0.2032)
		(layers "F.Cu" "B.Cu")
		(net "GND")
	)
	(via
		(at 0.77089 -380.501144)
		(size 0.508)
		(drill 0.254)
		(layers "F.Cu" "B.Cu")
		(net "GND")
	)
	(via
		(at 192.375028 -289.724846)
		(size 0.4064)
		(drill 0.2032)
		(layers "F.Cu" "B.Cu")
		(net "GND")
	)
	(via
		(at 354.858066 -136.328404)
		(size 0.508)
		(drill 0.254)
		(layers "F.Cu" "B.Cu")
		(net "GND")
	)
	(via
		(at 45.87494 -300.174914)
		(size 0.4064)
		(drill 0.2032)
		(layers "F.Cu" "B.Cu")
		(net "GND")
	)
	(via
		(at 279.974802 -292.57498)
		(size 0.4064)
		(drill 0.2032)
		(layers "F.Cu" "B.Cu")
		(net "GND")
	)
	(via
		(at 198.51243 -407.12009)
		(size 0.508)
		(drill 0.254)
		(layers "F.Cu" "B.Cu")
		(net "GND")
	)
	(via
		(at 110.676182 -289.41649)
		(size 0.508)
		(drill 0.254)
		(layers "F.Cu" "B.Cu")
		(net "GND")
	)
	(via
		(at 291.499798 -62.812168)
		(size 0.508)
		(drill 0.254)
		(layers "F.Cu" "B.Cu")
		(net "GND")
	)
	(via
		(at 189.88786 -413.479234)
		(size 0.508)
		(drill 0.254)
		(layers "F.Cu" "B.Cu")
		(net "GND")
	)
	(via
		(at 323.262244 -348.58579)
		(size 0.4064)
		(drill 0.2032)
		(layers "F.Cu" "B.Cu")
		(net "GND")
	)
	(via
		(at 183.3499 -275.949918)
		(size 0.4064)
		(drill 0.2032)
		(layers "F.Cu" "B.Cu")
		(net "GND")
	)
	(via
		(at 292.199822 -348.58579)
		(size 0.4064)
		(drill 0.2032)
		(layers "F.Cu" "B.Cu")
		(net "GND")
	)
	(via
		(at 111.664496 -346.09913)
		(size 0.4572)
		(drill 0.254)
		(layers "F.Cu" "B.Cu")
		(net "GND")
	)
	(via
		(at 392.52779 -398.34185)
		(size 0.508)
		(drill 0.254)
		(layers "F.Cu" "B.Cu")
		(net "GND")
	)
	(via
		(at 399.93316 -98.845116)
		(size 0.508)
		(drill 0.254)
		(layers "F.Cu" "B.Cu")
		(net "GND")
	)
	(via
		(at 78.17485 -294.4749)
		(size 0.4064)
		(drill 0.2032)
		(layers "F.Cu" "B.Cu")
		(net "GND")
	)
	(via
		(at 380.317248 -347.951806)
		(size 0.4572)
		(drill 0.254)
		(layers "F.Cu" "B.Cu")
		(net "GND")
	)
	(via
		(at 231.067356 -221.904052)
		(size 0.4572)
		(drill 0.254)
		(layers "F.Cu" "B.Cu")
		(net "GND")
	)
	(via
		(at 132.993384 -159.573468)
		(size 0.508)
		(drill 0.254)
		(layers "F.Cu" "B.Cu")
		(net "GND")
	)
	(via
		(at 62.499748 -274.049744)
		(size 0.4064)
		(drill 0.2032)
		(layers "F.Cu" "B.Cu")
		(net "GND")
	)
	(via
		(at 70.574916 -288.774886)
		(size 0.4064)
		(drill 0.2032)
		(layers "F.Cu" "B.Cu")
		(net "GND")
	)
	(via
		(at 187.624974 -299.224954)
		(size 0.4064)
		(drill 0.2032)
		(layers "F.Cu" "B.Cu")
		(net "GND")
	)
	(via
		(at 128.547622 -398.34185)
		(size 0.4572)
		(drill 0.254)
		(layers "F.Cu" "B.Cu")
		(net "GND")
	)
	(via
		(at 400.229832 -341.781638)
		(size 0.4572)
		(drill 0.254)
		(layers "F.Cu" "B.Cu")
		(net "GND")
	)
	(via
		(at 7.72414 -310.133238)
		(size 0.508)
		(drill 0.254)
		(layers "F.Cu" "B.Cu")
		(net "GND")
	)
	(via
		(at 416.974782 -303.024794)
		(size 0.4064)
		(drill 0.2032)
		(layers "F.Cu" "B.Cu")
		(net "GND")
	)
	(via
		(at 430.8602 -355.366066)
		(size 0.4572)
		(drill 0.254)
		(layers "F.Cu" "B.Cu")
		(net "GND")
	)
	(via
		(at 399.852388 -159.987488)
		(size 0.508)
		(drill 0.254)
		(layers "F.Cu" "B.Cu")
		(net "GND")
	)
	(via
		(at 464.843876 -84.63534)
		(size 0.508)
		(drill 0.254)
		(layers "F.Cu" "B.Cu")
		(net "GND")
	)
	(via
		(at 222.154496 -309.604156)
		(size 0.508)
		(drill 0.254)
		(layers "F.Cu" "B.Cu")
		(net "GND")
	)
	(via
		(at 142.595854 -206.055468)
		(size 0.508)
		(drill 0.254)
		(layers "F.Cu" "B.Cu")
		(net "GND")
	)
	(via
		(at 312.986928 -0.762)
		(size 0.508)
		(drill 0.254)
		(layers "F.Cu" "B.Cu")
		(net "GND")
	)
	(via
		(at 29.54782 -371.038628)
		(size 0.508)
		(drill 0.254)
		(layers "F.Cu" "B.Cu")
		(net "GND")
	)
	(via
		(at 56.843168 -52.536852)
		(size 0.508)
		(drill 0.254)
		(layers "F.Cu" "B.Cu")
		(net "GND")
	)
	(via
		(at 197.600062 -318.699896)
		(size 0.4064)
		(drill 0.2032)
		(layers "F.Cu" "B.Cu")
		(net "GND")
	)
	(via
		(at 388.20217 -58.731404)
		(size 0.508)
		(drill 0.254)
		(layers "F.Cu" "B.Cu")
		(net "GND")
	)
	(via
		(at 36.374832 -289.724846)
		(size 0.4064)
		(drill 0.2032)
		(layers "F.Cu" "B.Cu")
		(net "GND")
	)
	(via
		(at 180.693314 -149.355302)
		(size 0.508)
		(drill 0.254)
		(layers "F.Cu" "B.Cu")
		(net "GND")
	)
	(via
		(at 278.285194 -341.805514)
		(size 0.4572)
		(drill 0.254)
		(layers "F.Cu" "B.Cu")
		(net "GND")
	)
	(via
		(at 431.700178 -281.650186)
		(size 0.4064)
		(drill 0.2032)
		(layers "F.Cu" "B.Cu")
		(net "GND")
	)
	(via
		(at 71.347838 -403.738588)
		(size 0.508)
		(drill 0.254)
		(layers "F.Cu" "B.Cu")
		(net "GND")
	)
	(via
		(at 71.524876 -297.32478)
		(size 0.4064)
		(drill 0.2032)
		(layers "F.Cu" "B.Cu")
		(net "GND")
	)
	(via
		(at 103.7336 -201.9808)
		(size 0.508)
		(drill 0.254)
		(layers "F.Cu" "B.Cu")
		(net "GND")
	)
	(via
		(at 217.440002 -73.23963)
		(size 0.508)
		(drill 0.254)
		(layers "F.Cu" "B.Cu")
		(net "GND")
	)
	(via
		(at 119.14124 -357.123746)
		(size 0.4572)
		(drill 0.254)
		(layers "F.Cu" "B.Cu")
		(net "GND")
	)
	(via
		(at 439.242708 -111.688372)
		(size 0.508)
		(drill 0.254)
		(layers "F.Cu" "B.Cu")
		(net "GND")
	)
	(via
		(at 280.670508 -131.277614)
		(size 0.508)
		(drill 0.254)
		(layers "F.Cu" "B.Cu")
		(net "GND")
	)
	(via
		(at 275.176234 -341.805514)
		(size 0.4572)
		(drill 0.254)
		(layers "F.Cu" "B.Cu")
		(net "GND")
	)
	(via
		(at 74.869294 -349.219774)
		(size 0.4572)
		(drill 0.254)
		(layers "F.Cu" "B.Cu")
		(net "GND")
	)
	(via
		(at 44.671234 -31.652972)
		(size 0.508)
		(drill 0.254)
		(layers "F.Cu" "B.Cu")
		(net "GND")
	)
	(via
		(at 325.999856 -349.219774)
		(size 0.4572)
		(drill 0.254)
		(layers "F.Cu" "B.Cu")
		(net "GND")
	)
	(via
		(at 301.855124 -145.881852)
		(size 0.508)
		(drill 0.254)
		(layers "F.Cu" "B.Cu")
		(net "GND")
	)
	(via
		(at 126.347728 -373.441976)
		(size 0.4572)
		(drill 0.254)
		(layers "F.Cu" "B.Cu")
		(net "GND")
	)
	(via
		(at 99.313238 -34.718498)
		(size 0.508)
		(drill 0.254)
		(layers "F.Cu" "B.Cu")
		(net "GND")
	)
	(via
		(at 320.452242 -113.661444)
		(size 0.508)
		(drill 0.254)
		(layers "F.Cu" "B.Cu")
		(net "GND")
	)
	(via
		(at 119.747792 -378.94006)
		(size 0.4572)
		(drill 0.254)
		(layers "F.Cu" "B.Cu")
		(net "GND")
	)
	(via
		(at 50.14976 -274.999958)
		(size 0.4064)
		(drill 0.2032)
		(layers "F.Cu" "B.Cu")
		(net "GND")
	)
	(via
		(at 170.524932 -283.074872)
		(size 0.4064)
		(drill 0.2032)
		(layers "F.Cu" "B.Cu")
		(net "GND")
	)
	(via
		(at 307.049932 -280.699718)
		(size 0.4064)
		(drill 0.2032)
		(layers "F.Cu" "B.Cu")
		(net "GND")
	)
	(via
		(at 127.935228 -115.688364)
		(size 0.508)
		(drill 0.254)
		(layers "F.Cu" "B.Cu")
		(net "GND")
	)
	(via
		(at 314.366148 -143.676878)
		(size 0.508)
		(drill 0.254)
		(layers "F.Cu" "B.Cu")
		(net "GND")
	)
	(via
		(at 426.94987 -304.449734)
		(size 0.4064)
		(drill 0.2032)
		(layers "F.Cu" "B.Cu")
		(net "GND")
	)
	(via
		(at 388.127748 -402.241766)
		(size 0.508)
		(drill 0.254)
		(layers "F.Cu" "B.Cu")
		(net "GND")
	)
	(via
		(at 40.547798 -402.241766)
		(size 0.508)
		(drill 0.254)
		(layers "F.Cu" "B.Cu")
		(net "GND")
	)
	(via
		(at 448.260216 -21.37156)
		(size 0.508)
		(drill 0.254)
		(layers "F.Cu" "B.Cu")
		(net "GND")
	)
	(via
		(at 295.649904 -280.699718)
		(size 0.4064)
		(drill 0.2032)
		(layers "F.Cu" "B.Cu")
		(net "GND")
	)
	(via
		(at 395.89456 -126.703836)
		(size 0.508)
		(drill 0.254)
		(layers "F.Cu" "B.Cu")
		(net "GND")
	)
	(via
		(at 22.243796 -354.074222)
		(size 0.4572)
		(drill 0.254)
		(layers "F.Cu" "B.Cu")
		(net "GND")
	)
	(via
		(at 416.574224 -343.073482)
		(size 0.4572)
		(drill 0.254)
		(layers "F.Cu" "B.Cu")
		(net "GND")
	)
	(via
		(at 400.229832 -355.366066)
		(size 0.4572)
		(drill 0.254)
		(layers "F.Cu" "B.Cu")
		(net "GND")
	)
	(via
		(at 194.749928 -306.349908)
		(size 0.4064)
		(drill 0.2032)
		(layers "F.Cu" "B.Cu")
		(net "GND")
	)
	(via
		(at 299.866812 -147.555204)
		(size 0.508)
		(drill 0.254)
		(layers "F.Cu" "B.Cu")
		(net "GND")
	)
	(via
		(at 318.654938 -29.590238)
		(size 0.508)
		(drill 0.254)
		(layers "F.Cu" "B.Cu")
		(net "GND")
	)
	(via
		(at 37.133784 -109.916722)
		(size 0.508)
		(drill 0.254)
		(layers "F.Cu" "B.Cu")
		(net "GND")
	)
	(via
		(at 280.13533 -357.123746)
		(size 0.4572)
		(drill 0.254)
		(layers "F.Cu" "B.Cu")
		(net "GND")
	)
	(via
		(at 296.124884 -302.074834)
		(size 0.4064)
		(drill 0.2032)
		(layers "F.Cu" "B.Cu")
		(net "GND")
	)
	(via
		(at 184.77484 -289.724846)
		(size 0.4064)
		(drill 0.2032)
		(layers "F.Cu" "B.Cu")
		(net "GND")
	)
	(via
		(at 106.747564 -163.230052)
		(size 0.508)
		(drill 0.254)
		(layers "F.Cu" "B.Cu")
		(net "GND")
	)
	(via
		(at 306.574698 -298.27474)
		(size 0.4064)
		(drill 0.2032)
		(layers "F.Cu" "B.Cu")
		(net "GND")
	)
	(via
		(at 242.906042 -190.096648)
		(size 0.508)
		(drill 0.254)
		(layers "F.Cu" "B.Cu")
		(net "GND")
	)
	(via
		(at 1.69926 -380.182628)
		(size 0.508)
		(drill 0.254)
		(layers "F.Cu" "B.Cu")
		(net "GND")
	)
	(via
		(at 101.568504 -216.071958)
		(size 0.508)
		(drill 0.254)
		(layers "F.Cu" "B.Cu")
		(net "GND")
	)
	(via
		(at 449.639944 -74.58583)
		(size 0.508)
		(drill 0.254)
		(layers "F.Cu" "B.Cu")
		(net "GND")
	)
	(via
		(at 303.719992 -56.441848)
		(size 0.508)
		(drill 0.254)
		(layers "F.Cu" "B.Cu")
		(net "GND")
	)
	(via
		(at 170.999912 -278.799798)
		(size 0.4064)
		(drill 0.2032)
		(layers "F.Cu" "B.Cu")
		(net "GND")
	)
	(via
		(at 194.749928 -283.549852)
		(size 0.4064)
		(drill 0.2032)
		(layers "F.Cu" "B.Cu")
		(net "GND")
	)
	(via
		(at 160.549844 -274.999958)
		(size 0.4064)
		(drill 0.2032)
		(layers "F.Cu" "B.Cu")
		(net "GND")
	)
	(via
		(at 169.423334 -54.067456)
		(size 0.508)
		(drill 0.254)
		(layers "F.Cu" "B.Cu")
		(net "GND")
	)
	(via
		(at 392.48461 -73.20026)
		(size 0.508)
		(drill 0.254)
		(layers "F.Cu" "B.Cu")
		(net "GND")
	)
	(via
		(at 297.927776 -399.441924)
		(size 0.508)
		(drill 0.254)
		(layers "F.Cu" "B.Cu")
		(net "GND")
	)
	(via
		(at 94.034356 -245.824248)
		(size 0.508)
		(drill 0.254)
		(layers "F.Cu" "B.Cu")
		(net "GND")
	)
	(via
		(at 397.640048 -73.87463)
		(size 0.508)
		(drill 0.254)
		(layers "F.Cu" "B.Cu")
		(net "GND")
	)
	(via
		(at 254.898906 -193.708528)
		(size 0.508)
		(drill 0.254)
		(layers "F.Cu" "B.Cu")
		(net "GND")
	)
	(via
		(at 315.414152 -349.219774)
		(size 0.4572)
		(drill 0.254)
		(layers "F.Cu" "B.Cu")
		(net "GND")
	)
	(via
		(at 144.65808 -279.931114)
		(size 0.508)
		(drill 0.254)
		(layers "F.Cu" "B.Cu")
		(net "GND")
	)
	(via
		(at 426.000164 -274.049744)
		(size 0.4064)
		(drill 0.2032)
		(layers "F.Cu" "B.Cu")
		(net "GND")
	)
	(via
		(at 340.285832 -355.366066)
		(size 0.4572)
		(drill 0.254)
		(layers "F.Cu" "B.Cu")
		(net "GND")
	)
	(via
		(at 179.55006 -316.799722)
		(size 0.4064)
		(drill 0.2032)
		(layers "F.Cu" "B.Cu")
		(net "GND")
	)
	(via
		(at 62.499748 -317.749936)
		(size 0.4064)
		(drill 0.2032)
		(layers "F.Cu" "B.Cu")
		(net "GND")
	)
	(via
		(at 403.00656 -111.44504)
		(size 0.508)
		(drill 0.254)
		(layers "F.Cu" "B.Cu")
		(net "GND")
	)
	(via
		(at 382.786636 -225.585782)
		(size 0.508)
		(drill 0.254)
		(layers "F.Cu" "B.Cu")
		(net "GND")
	)
	(via
		(at 181.143148 -110.361222)
		(size 0.508)
		(drill 0.254)
		(layers "F.Cu" "B.Cu")
		(net "GND")
	)
	(via
		(at 271.424908 -283.074872)
		(size 0.4064)
		(drill 0.2032)
		(layers "F.Cu" "B.Cu")
		(net "GND")
	)
	(via
		(at 160.771332 -28.05303)
		(size 0.508)
		(drill 0.254)
		(layers "F.Cu" "B.Cu")
		(net "GND")
	)
	(via
		(at 275.547582 -345.465146)
		(size 0.4064)
		(drill 0.2032)
		(layers "F.Cu" "B.Cu")
		(net "GND")
	)
	(via
		(at 392.52779 -384.042158)
		(size 0.508)
		(drill 0.254)
		(layers "F.Cu" "B.Cu")
		(net "GND")
	)
	(via
		(at 51.35753 -29.784294)
		(size 0.508)
		(drill 0.254)
		(layers "F.Cu" "B.Cu")
		(net "GND")
	)
	(via
		(at 260.757924 -283.131514)
		(size 0.508)
		(drill 0.254)
		(layers "F.Cu" "B.Cu")
		(net "GND")
	)
	(via
		(at 214.815166 -167.960802)
		(size 0.508)
		(drill 0.254)
		(layers "F.Cu" "B.Cu")
		(net "GND")
	)
	(via
		(at 300.12767 -384.041904)
		(size 0.508)
		(drill 0.254)
		(layers "F.Cu" "B.Cu")
		(net "GND")
	)
	(via
		(at 9.966198 -389.152384)
		(size 0.508)
		(drill 0.254)
		(layers "F.Cu" "B.Cu")
		(net "GND")
	)
	(via
		(at 307.049932 -286.399732)
		(size 0.4064)
		(drill 0.2032)
		(layers "F.Cu" "B.Cu")
		(net "GND")
	)
	(via
		(at 312.749692 -306.349908)
		(size 0.4064)
		(drill 0.2032)
		(layers "F.Cu" "B.Cu")
		(net "GND")
	)
	(via
		(at 296.599864 -273.099784)
		(size 0.4064)
		(drill 0.2032)
		(layers "F.Cu" "B.Cu")
		(net "GND")
	)
	(via
		(at 143.76908 -295.933114)
		(size 0.508)
		(drill 0.254)
		(layers "F.Cu" "B.Cu")
		(net "GND")
	)
	(via
		(at 400.05 -144.250156)
		(size 0.508)
		(drill 0.254)
		(layers "F.Cu" "B.Cu")
		(net "GND")
	)
	(via
		(at 234.855512 -235.737654)
		(size 0.508)
		(drill 0.254)
		(layers "F.Cu" "B.Cu")
		(net "GND")
	)
	(via
		(at 67.724782 -289.724846)
		(size 0.4064)
		(drill 0.2032)
		(layers "F.Cu" "B.Cu")
		(net "GND")
	)
	(via
		(at 423.623994 -26.319734)
		(size 0.508)
		(drill 0.254)
		(layers "F.Cu" "B.Cu")
		(net "GND")
	)
	(via
		(at 285.052262 -125.955044)
		(size 0.508)
		(drill 0.254)
		(layers "F.Cu" "B.Cu")
		(net "GND")
	)
	(via
		(at 397.5227 -129.964942)
		(size 0.508)
		(drill 0.254)
		(layers "F.Cu" "B.Cu")
		(net "GND")
	)
	(via
		(at 242.591844 -198.068692)
		(size 0.508)
		(drill 0.254)
		(layers "F.Cu" "B.Cu")
		(net "GND")
	)
	(via
		(at 386.575046 -290.674806)
		(size 0.4064)
		(drill 0.2032)
		(layers "F.Cu" "B.Cu")
		(net "GND")
	)
	(via
		(at 175.749966 -316.799722)
		(size 0.4064)
		(drill 0.2032)
		(layers "F.Cu" "B.Cu")
		(net "GND")
	)
	(via
		(at 37.788596 -350.977454)
		(size 0.4572)
		(drill 0.254)
		(layers "F.Cu" "B.Cu")
		(net "GND")
	)
	(via
		(at 35.424872 -288.774886)
		(size 0.4064)
		(drill 0.2032)
		(layers "F.Cu" "B.Cu")
		(net "GND")
	)
	(via
		(at 414.944052 -348.58579)
		(size 0.4064)
		(drill 0.2032)
		(layers "F.Cu" "B.Cu")
		(net "GND")
	)
	(via
		(at 4.562856 -205.561692)
		(size 0.508)
		(drill 0.254)
		(layers "F.Cu" "B.Cu")
		(net "GND")
	)
	(via
		(at 62.024768 -289.724846)
		(size 0.4064)
		(drill 0.2032)
		(layers "F.Cu" "B.Cu")
		(net "GND")
	)
	(via
		(at 83.540346 -135.114538)
		(size 0.508)
		(drill 0.254)
		(layers "F.Cu" "B.Cu")
		(net "GND")
	)
	(via
		(at 139.273788 -342.439498)
		(size 0.4064)
		(drill 0.2032)
		(layers "F.Cu" "B.Cu")
		(net "GND")
	)
	(via
		(at 197.445884 -341.805514)
		(size 0.4572)
		(drill 0.254)
		(layers "F.Cu" "B.Cu")
		(net "GND")
	)
	(via
		(at 36.14801 -410.041852)
		(size 0.508)
		(drill 0.254)
		(layers "F.Cu" "B.Cu")
		(net "GND")
	)
	(via
		(at 397.640048 -73.23963)
		(size 0.508)
		(drill 0.254)
		(layers "F.Cu" "B.Cu")
		(net "GND")
	)
	(via
		(at 333.696564 -342.439498)
		(size 0.4064)
		(drill 0.2032)
		(layers "F.Cu" "B.Cu")
		(net "GND")
	)
	(via
		(at 246.448834 -29.589984)
		(size 0.508)
		(drill 0.254)
		(layers "F.Cu" "B.Cu")
		(net "GND")
	)
	(via
		(at 183.82488 -289.724846)
		(size 0.4064)
		(drill 0.2032)
		(layers "F.Cu" "B.Cu")
		(net "GND")
	)
	(via
		(at 181.912514 -149.355302)
		(size 0.508)
		(drill 0.254)
		(layers "F.Cu" "B.Cu")
		(net "GND")
	)
	(via
		(at 138.679174 -214.982806)
		(size 0.508)
		(drill 0.254)
		(layers "F.Cu" "B.Cu")
		(net "GND")
	)
	(via
		(at 231.067356 -220.303852)
		(size 0.4572)
		(drill 0.254)
		(layers "F.Cu" "B.Cu")
		(net "GND")
	)
	(via
		(at 416.024822 -302.074834)
		(size 0.4064)
		(drill 0.2032)
		(layers "F.Cu" "B.Cu")
		(net "GND")
	)
	(via
		(at 304.44186 -112.56772)
		(size 0.508)
		(drill 0.254)
		(layers "F.Cu" "B.Cu")
		(net "GND")
	)
	(via
		(at 163.874958 -288.774886)
		(size 0.4064)
		(drill 0.2032)
		(layers "F.Cu" "B.Cu")
		(net "GND")
	)
	(via
		(at 302.327818 -373.441976)
		(size 0.508)
		(drill 0.254)
		(layers "F.Cu" "B.Cu")
		(net "GND")
	)
	(via
		(at 300.047914 -347.951806)
		(size 0.4572)
		(drill 0.254)
		(layers "F.Cu" "B.Cu")
		(net "GND")
	)
	(via
		(at 424.270932 -357.75773)
		(size 0.4064)
		(drill 0.2032)
		(layers "F.Cu" "B.Cu")
		(net "GND")
	)
	(via
		(at 294.22471 -284.974792)
		(size 0.4064)
		(drill 0.2032)
		(layers "F.Cu" "B.Cu")
		(net "GND")
	)
	(via
		(at 333.127858 -382.73863)
		(size 0.508)
		(drill 0.254)
		(layers "F.Cu" "B.Cu")
		(net "GND")
	)
	(via
		(at 313.935364 -345.465146)
		(size 0.4064)
		(drill 0.2032)
		(layers "F.Cu" "B.Cu")
		(net "GND")
	)
	(via
		(at 370.61902 -351.611438)
		(size 0.4064)
		(drill 0.2032)
		(layers "F.Cu" "B.Cu")
		(net "GND")
	)
	(via
		(at 155.800044 -300.649894)
		(size 0.4064)
		(drill 0.2032)
		(layers "F.Cu" "B.Cu")
		(net "GND")
	)
	(via
		(at 23.440898 -45.853858)
		(size 0.508)
		(drill 0.254)
		(layers "F.Cu" "B.Cu")
		(net "GND")
	)
	(via
		(at 310.849772 -275.949918)
		(size 0.4064)
		(drill 0.2032)
		(layers "F.Cu" "B.Cu")
		(net "GND")
	)
	(via
		(at 285.052262 -131.76504)
		(size 0.508)
		(drill 0.254)
		(layers "F.Cu" "B.Cu")
		(net "GND")
	)
	(via
		(at 424.120818 -113.260632)
		(size 0.508)
		(drill 0.254)
		(layers "F.Cu" "B.Cu")
		(net "GND")
	)
	(via
		(at 331.99197 -70.918832)
		(size 0.508)
		(drill 0.254)
		(layers "F.Cu" "B.Cu")
		(net "GND")
	)
	(via
		(at 292.79977 -314.899802)
		(size 0.4064)
		(drill 0.2032)
		(layers "F.Cu" "B.Cu")
		(net "GND")
	)
	(via
		(at 337.5279 -402.140166)
		(size 0.508)
		(drill 0.254)
		(layers "F.Cu" "B.Cu")
		(net "GND")
	)
	(via
		(at 49.67478 -294.4749)
		(size 0.4064)
		(drill 0.2032)
		(layers "F.Cu" "B.Cu")
		(net "GND")
	)
	(via
		(at 334.817212 -305.008534)
		(size 0.508)
		(drill 0.254)
		(layers "F.Cu" "B.Cu")
		(net "GND")
	)
	(via
		(at 156.750004 -309.199788)
		(size 0.4064)
		(drill 0.2032)
		(layers "F.Cu" "B.Cu")
		(net "GND")
	)
	(via
		(at 417.924996 -296.37482)
		(size 0.4064)
		(drill 0.2032)
		(layers "F.Cu" "B.Cu")
		(net "GND")
	)
	(via
		(at 44.671234 -32.911796)
		(size 0.508)
		(drill 0.254)
		(layers "F.Cu" "B.Cu")
		(net "GND")
	)
	(via
		(at 76.71943 -347.951806)
		(size 0.4572)
		(drill 0.254)
		(layers "F.Cu" "B.Cu")
		(net "GND")
	)
	(via
		(at 37.37737 -149.747224)
		(size 0.508)
		(drill 0.254)
		(layers "F.Cu" "B.Cu")
		(net "GND")
	)
	(via
		(at 181.9529 -177.667158)
		(size 0.508)
		(drill 0.254)
		(layers "F.Cu" "B.Cu")
		(net "GND")
	)
	(via
		(at 415.549842 -311.099962)
		(size 0.4064)
		(drill 0.2032)
		(layers "F.Cu" "B.Cu")
		(net "GND")
	)
	(via
		(at 466.835998 -348.803976)
		(size 0.508)
		(drill 0.254)
		(layers "F.Cu" "B.Cu")
		(net "GND")
	)
	(via
		(at 447.613278 -29.859478)
		(size 0.508)
		(drill 0.254)
		(layers "F.Cu" "B.Cu")
		(net "GND")
	)
	(via
		(at 23.873968 -354.732082)
		(size 0.4064)
		(drill 0.2032)
		(layers "F.Cu" "B.Cu")
		(net "GND")
	)
	(via
		(at 255.537462 -200.08723)
		(size 0.508)
		(drill 0.254)
		(layers "F.Cu" "B.Cu")
		(net "GND")
	)
	(via
		(at 66.299842 -276.899878)
		(size 0.4064)
		(drill 0.2032)
		(layers "F.Cu" "B.Cu")
		(net "GND")
	)
	(via
		(at 314.174886 -289.724846)
		(size 0.4064)
		(drill 0.2032)
		(layers "F.Cu" "B.Cu")
		(net "GND")
	)
	(via
		(at 452.013574 -309.0164)
		(size 0.508)
		(drill 0.254)
		(layers "F.Cu" "B.Cu")
		(net "GND")
	)
	(via
		(at 401.299934 -276.899878)
		(size 0.4064)
		(drill 0.2032)
		(layers "F.Cu" "B.Cu")
		(net "GND")
	)
	(via
		(at 380.90094 -31.390336)
		(size 0.508)
		(drill 0.254)
		(layers "F.Cu" "B.Cu")
		(net "GND")
	)
	(via
		(at 409.849828 -281.649932)
		(size 0.4064)
		(drill 0.2032)
		(layers "F.Cu" "B.Cu")
		(net "GND")
	)
	(via
		(at 457.922376 -311.83453)
		(size 0.508)
		(drill 0.254)
		(layers "F.Cu" "B.Cu")
		(net "GND")
	)
	(via
		(at 117.511068 -345.465146)
		(size 0.4064)
		(drill 0.2032)
		(layers "F.Cu" "B.Cu")
		(net "GND")
	)
	(via
		(at 273.324828 -289.724846)
		(size 0.4064)
		(drill 0.2032)
		(layers "F.Cu" "B.Cu")
		(net "GND")
	)
	(via
		(at 395.12494 -286.874966)
		(size 0.4064)
		(drill 0.2032)
		(layers "F.Cu" "B.Cu")
		(net "GND")
	)
	(via
		(at 201.29246 -6.292342)
		(size 0.508)
		(drill 0.254)
		(layers "F.Cu" "B.Cu")
		(net "GND")
	)
	(via
		(at 416.024822 -300.174914)
		(size 0.4064)
		(drill 0.2032)
		(layers "F.Cu" "B.Cu")
		(net "GND")
	)
	(via
		(at 394.239242 -32.911796)
		(size 0.508)
		(drill 0.254)
		(layers "F.Cu" "B.Cu")
		(net "GND")
	)
	(via
		(at 127.898398 -21.077936)
		(size 0.508)
		(drill 0.254)
		(layers "F.Cu" "B.Cu")
		(net "GND")
	)
	(via
		(at 14.248892 -31.390082)
		(size 0.508)
		(drill 0.254)
		(layers "F.Cu" "B.Cu")
		(net "GND")
	)
	(via
		(at 116.403628 -348.58579)
		(size 0.4064)
		(drill 0.2032)
		(layers "F.Cu" "B.Cu")
		(net "GND")
	)
	(via
		(at 13.494766 -159.498792)
		(size 0.508)
		(drill 0.254)
		(layers "F.Cu" "B.Cu")
		(net "GND")
	)
	(via
		(at 275.224748 -282.124912)
		(size 0.4064)
		(drill 0.2032)
		(layers "F.Cu" "B.Cu")
		(net "GND")
	)
	(via
		(at 423.32783 -408.840178)
		(size 0.508)
		(drill 0.254)
		(layers "F.Cu" "B.Cu")
		(net "GND")
	)
	(via
		(at 366.66297 -135.369046)
		(size 0.508)
		(drill 0.254)
		(layers "F.Cu" "B.Cu")
		(net "GND")
	)
	(via
		(at 138.06043 -20.35556)
		(size 0.508)
		(drill 0.254)
		(layers "F.Cu" "B.Cu")
		(net "GND")
	)
	(via
		(at 51.63312 -113.245138)
		(size 0.508)
		(drill 0.254)
		(layers "F.Cu" "B.Cu")
		(net "GND")
	)
	(via
		(at 361.75823 -392.007852)
		(size 0.508)
		(drill 0.254)
		(layers "F.Cu" "B.Cu")
		(net "GND")
	)
	(via
		(at 199.64019 -144.224502)
		(size 0.508)
		(drill 0.254)
		(layers "F.Cu" "B.Cu")
		(net "GND")
	)
	(via
		(at 305.624738 -292.574726)
		(size 0.4064)
		(drill 0.2032)
		(layers "F.Cu" "B.Cu")
		(net "GND")
	)
	(via
		(at 170.049952 -279.749758)
		(size 0.4064)
		(drill 0.2032)
		(layers "F.Cu" "B.Cu")
		(net "GND")
	)
	(via
		(at 267.938504 -136.241028)
		(size 0.508)
		(drill 0.254)
		(layers "F.Cu" "B.Cu")
		(net "GND")
	)
	(via
		(at 425.527724 -403.34184)
		(size 0.508)
		(drill 0.254)
		(layers "F.Cu" "B.Cu")
		(net "GND")
	)
	(via
		(at 399.93316 -118.754906)
		(size 0.508)
		(drill 0.254)
		(layers "F.Cu" "B.Cu")
		(net "GND")
	)
	(via
		(at 347.037406 -279.023572)
		(size 0.508)
		(drill 0.254)
		(layers "F.Cu" "B.Cu")
		(net "GND")
	)
	(via
		(at 173.849792 -272.14957)
		(size 0.4064)
		(drill 0.2032)
		(layers "F.Cu" "B.Cu")
		(net "GND")
	)
	(via
		(at 368.574066 -73.85177)
		(size 0.508)
		(drill 0.254)
		(layers "F.Cu" "B.Cu")
		(net "GND")
	)
	(via
		(at 288.524696 -291.624766)
		(size 0.4064)
		(drill 0.2032)
		(layers "F.Cu" "B.Cu")
		(net "GND")
	)
	(via
		(at 180.270912 -345.465146)
		(size 0.4064)
		(drill 0.2032)
		(layers "F.Cu" "B.Cu")
		(net "GND")
	)
	(via
		(at 198.26605 -122.098054)
		(size 0.508)
		(drill 0.254)
		(layers "F.Cu" "B.Cu")
		(net "GND")
	)
	(via
		(at 408.120088 -34.990278)
		(size 0.508)
		(drill 0.254)
		(layers "F.Cu" "B.Cu")
		(net "GND")
	)
	(via
		(at 283.833062 -129.964942)
		(size 0.508)
		(drill 0.254)
		(layers "F.Cu" "B.Cu")
		(net "GND")
	)
	(via
		(at 69.022722 -342.439498)
		(size 0.4064)
		(drill 0.2032)
		(layers "F.Cu" "B.Cu")
		(net "GND")
	)
	(via
		(at 416.974782 -290.674806)
		(size 0.4064)
		(drill 0.2032)
		(layers "F.Cu" "B.Cu")
		(net "GND")
	)
	(via
		(at 183.3499 -312.049922)
		(size 0.4064)
		(drill 0.2032)
		(layers "F.Cu" "B.Cu")
		(net "GND")
	)
	(via
		(at 389.644128 -349.219774)
		(size 0.4572)
		(drill 0.254)
		(layers "F.Cu" "B.Cu")
		(net "GND")
	)
	(via
		(at 104.67213 -293.424102)
		(size 0.508)
		(drill 0.254)
		(layers "F.Cu" "B.Cu")
		(net "GND")
	)
	(via
		(at 129.092198 -183.79059)
		(size 0.508)
		(drill 0.254)
		(layers "F.Cu" "B.Cu")
		(net "GND")
	)
	(via
		(at 421.127682 -399.441924)
		(size 0.508)
		(drill 0.254)
		(layers "F.Cu" "B.Cu")
		(net "GND")
	)
	(via
		(at 30.653228 -49.574704)
		(size 0.508)
		(drill 0.254)
		(layers "F.Cu" "B.Cu")
		(net "GND")
	)
	(via
		(at 438.7469 -23.583646)
		(size 0.508)
		(drill 0.254)
		(layers "F.Cu" "B.Cu")
		(net "GND")
	)
	(via
		(at 42.557954 -58.791094)
		(size 0.508)
		(drill 0.254)
		(layers "F.Cu" "B.Cu")
		(net "GND")
	)
	(via
		(at 344.127836 -384.041904)
		(size 0.508)
		(drill 0.254)
		(layers "F.Cu" "B.Cu")
		(net "GND")
	)
	(via
		(at 306.574698 -296.37482)
		(size 0.4064)
		(drill 0.2032)
		(layers "F.Cu" "B.Cu")
		(net "GND")
	)
	(via
		(at 295.308782 -351.611438)
		(size 0.4064)
		(drill 0.2032)
		(layers "F.Cu" "B.Cu")
		(net "GND")
	)
	(via
		(at 165.446456 -110.857538)
		(size 0.508)
		(drill 0.254)
		(layers "F.Cu" "B.Cu")
		(net "GND")
	)
	(via
		(at 414.124902 -307.774848)
		(size 0.4064)
		(drill 0.2032)
		(layers "F.Cu" "B.Cu")
		(net "GND")
	)
	(via
		(at 157.224984 -287.824926)
		(size 0.4064)
		(drill 0.2032)
		(layers "F.Cu" "B.Cu")
		(net "GND")
	)
	(via
		(at 438.098184 -21.077936)
		(size 0.508)
		(drill 0.254)
		(layers "F.Cu" "B.Cu")
		(net "GND")
	)
	(via
		(at 421.161972 -357.75773)
		(size 0.4064)
		(drill 0.2032)
		(layers "F.Cu" "B.Cu")
		(net "GND")
	)
	(via
		(at 82.653124 -49.574704)
		(size 0.508)
		(drill 0.254)
		(layers "F.Cu" "B.Cu")
		(net "GND")
	)
	(via
		(at 282.349702 -316.799722)
		(size 0.4064)
		(drill 0.2032)
		(layers "F.Cu" "B.Cu")
		(net "GND")
	)
	(via
		(at 107.509564 -162.518852)
		(size 0.508)
		(drill 0.254)
		(layers "F.Cu" "B.Cu")
		(net "GND")
	)
	(via
		(at 120.620028 -348.58579)
		(size 0.4064)
		(drill 0.2032)
		(layers "F.Cu" "B.Cu")
		(net "GND")
	)
	(via
		(at 196.18706 -346.09913)
		(size 0.4572)
		(drill 0.254)
		(layers "F.Cu" "B.Cu")
		(net "GND")
	)
	(via
		(at 120.620028 -357.75773)
		(size 0.4064)
		(drill 0.2032)
		(layers "F.Cu" "B.Cu")
		(net "GND")
	)
	(via
		(at 421.127682 -383.940304)
		(size 0.508)
		(drill 0.254)
		(layers "F.Cu" "B.Cu")
		(net "GND")
	)
	(via
		(at 397.49984 -277.849838)
		(size 0.4064)
		(drill 0.2032)
		(layers "F.Cu" "B.Cu")
		(net "GND")
	)
	(via
		(at 106.747564 -161.807652)
		(size 0.508)
		(drill 0.254)
		(layers "F.Cu" "B.Cu")
		(net "GND")
	)
	(via
		(at 270.437102 -342.439498)
		(size 0.4064)
		(drill 0.2032)
		(layers "F.Cu" "B.Cu")
		(net "GND")
	)
	(via
		(at 144.65808 -292.732714)
		(size 0.508)
		(drill 0.254)
		(layers "F.Cu" "B.Cu")
		(net "GND")
	)
	(via
		(at 343.511378 -288.14649)
		(size 0.508)
		(drill 0.254)
		(layers "F.Cu" "B.Cu")
		(net "GND")
	)
	(via
		(at 195.423282 -56.353456)
		(size 0.508)
		(drill 0.254)
		(layers "F.Cu" "B.Cu")
		(net "GND")
	)
	(via
		(at 34.4551 -33.19018)
		(size 0.508)
		(drill 0.254)
		(layers "F.Cu" "B.Cu")
		(net "GND")
	)
	(via
		(at 381.527812 -372.240302)
		(size 0.508)
		(drill 0.254)
		(layers "F.Cu" "B.Cu")
		(net "GND")
	)
	(via
		(at 213.754716 -23.880318)
		(size 0.508)
		(drill 0.254)
		(layers "F.Cu" "B.Cu")
		(net "GND")
	)
	(via
		(at 11.7983 -19.096736)
		(size 0.508)
		(drill 0.254)
		(layers "F.Cu" "B.Cu")
		(net "GND")
	)
	(via
		(at 165.947852 -376.140218)
		(size 0.508)
		(drill 0.254)
		(layers "F.Cu" "B.Cu")
		(net "GND")
	)
	(via
		(at 47.29988 -310.149748)
		(size 0.4064)
		(drill 0.2032)
		(layers "F.Cu" "B.Cu")
		(net "GND")
	)
	(via
		(at 438.336944 -343.073482)
		(size 0.4572)
		(drill 0.254)
		(layers "F.Cu" "B.Cu")
		(net "GND")
	)
	(via
		(at 38.275006 -281.174952)
		(size 0.4064)
		(drill 0.2032)
		(layers "F.Cu" "B.Cu")
		(net "GND")
	)
	(via
		(at 432.17973 -73.59269)
		(size 0.508)
		(drill 0.254)
		(layers "F.Cu" "B.Cu")
		(net "GND")
	)
	(via
		(at 377.571508 -51.661822)
		(size 0.508)
		(drill 0.254)
		(layers "F.Cu" "B.Cu")
		(net "GND")
	)
	(via
		(at 423.163492 -354.732082)
		(size 0.4064)
		(drill 0.2032)
		(layers "F.Cu" "B.Cu")
		(net "GND")
	)
	(via
		(at 414.11271 -147.555204)
		(size 0.508)
		(drill 0.254)
		(layers "F.Cu" "B.Cu")
		(net "GND")
	)
	(via
		(at 251.423678 -153.782522)
		(size 0.508)
		(drill 0.254)
		(layers "F.Cu" "B.Cu")
		(net "GND")
	)
	(via
		(at 395.12494 -304.924714)
		(size 0.4064)
		(drill 0.2032)
		(layers "F.Cu" "B.Cu")
		(net "GND")
	)
	(via
		(at 253.455678 -153.782522)
		(size 0.508)
		(drill 0.254)
		(layers "F.Cu" "B.Cu")
		(net "GND")
	)
	(via
		(at 165.774878 -288.774886)
		(size 0.4064)
		(drill 0.2032)
		(layers "F.Cu" "B.Cu")
		(net "GND")
	)
	(via
		(at 338.435696 -352.245422)
		(size 0.4572)
		(drill 0.254)
		(layers "F.Cu" "B.Cu")
		(net "GND")
	)
	(via
		(at 391.2743 -345.465146)
		(size 0.4064)
		(drill 0.2032)
		(layers "F.Cu" "B.Cu")
		(net "GND")
	)
	(via
		(at 425.527724 -400.938492)
		(size 0.508)
		(drill 0.254)
		(layers "F.Cu" "B.Cu")
		(net "GND")
	)
	(via
		(at 62.433454 -347.951806)
		(size 0.4572)
		(drill 0.254)
		(layers "F.Cu" "B.Cu")
		(net "GND")
	)
	(via
		(at 432.119024 -358.391714)
		(size 0.4572)
		(drill 0.254)
		(layers "F.Cu" "B.Cu")
		(net "GND")
	)
	(via
		(at 185.250074 -276.899878)
		(size 0.4064)
		(drill 0.2032)
		(layers "F.Cu" "B.Cu")
		(net "GND")
	)
	(via
		(at 68.674742 -291.624766)
		(size 0.4064)
		(drill 0.2032)
		(layers "F.Cu" "B.Cu")
		(net "GND")
	)
	(via
		(at 406.999948 -278.799798)
		(size 0.4064)
		(drill 0.2032)
		(layers "F.Cu" "B.Cu")
		(net "GND")
	)
	(via
		(at 137.322306 -52.51704)
		(size 0.508)
		(drill 0.254)
		(layers "F.Cu" "B.Cu")
		(net "GND")
	)
	(via
		(at 311.799732 -317.749936)
		(size 0.4064)
		(drill 0.2032)
		(layers "F.Cu" "B.Cu")
		(net "GND")
	)
	(via
		(at 163.399978 -281.649932)
		(size 0.4064)
		(drill 0.2032)
		(layers "F.Cu" "B.Cu")
		(net "GND")
	)
	(via
		(at 101.440742 -45.853858)
		(size 0.508)
		(drill 0.254)
		(layers "F.Cu" "B.Cu")
		(net "GND")
	)
	(via
		(at 335.698084 -357.75773)
		(size 0.4064)
		(drill 0.2032)
		(layers "F.Cu" "B.Cu")
		(net "GND")
	)
	(via
		(at 17.473422 -73.20026)
		(size 0.508)
		(drill 0.254)
		(layers "F.Cu" "B.Cu")
		(net "GND")
	)
	(via
		(at 313.09818 -122.098054)
		(size 0.508)
		(drill 0.254)
		(layers "F.Cu" "B.Cu")
		(net "GND")
	)
	(via
		(at 26.61158 -346.09913)
		(size 0.4572)
		(drill 0.254)
		(layers "F.Cu" "B.Cu")
		(net "GND")
	)
	(via
		(at 416.499802 -273.099784)
		(size 0.4064)
		(drill 0.2032)
		(layers "F.Cu" "B.Cu")
		(net "GND")
	)
	(via
		(at 422.674796 -300.174914)
		(size 0.4064)
		(drill 0.2032)
		(layers "F.Cu" "B.Cu")
		(net "GND")
	)
	(via
		(at 293.829994 -341.805514)
		(size 0.4572)
		(drill 0.254)
		(layers "F.Cu" "B.Cu")
		(net "GND")
	)
	(via
		(at 354.937568 -286.842454)
		(size 0.508)
		(drill 0.254)
		(layers "F.Cu" "B.Cu")
		(net "GND")
	)
	(via
		(at 453.787256 -375.629932)
		(size 0.508)
		(drill 0.254)
		(layers "F.Cu" "B.Cu")
		(net "GND")
	)
	(via
		(at 188.358272 -116.9035)
		(size 0.508)
		(drill 0.254)
		(layers "F.Cu" "B.Cu")
		(net "GND")
	)
	(via
		(at 170.049952 -310.149748)
		(size 0.4064)
		(drill 0.2032)
		(layers "F.Cu" "B.Cu")
		(net "GND")
	)
	(via
		(at 79.457042 -342.439498)
		(size 0.4064)
		(drill 0.2032)
		(layers "F.Cu" "B.Cu")
		(net "GND")
	)
	(via
		(at 75.79995 -286.399732)
		(size 0.4064)
		(drill 0.2032)
		(layers "F.Cu" "B.Cu")
		(net "GND")
	)
	(via
		(at 123.203462 -60.627006)
		(size 0.508)
		(drill 0.254)
		(layers "F.Cu" "B.Cu")
		(net "GND")
	)
	(via
		(at 400.349974 -316.799722)
		(size 0.4064)
		(drill 0.2032)
		(layers "F.Cu" "B.Cu")
		(net "GND")
	)
	(via
		(at 180.975 -284.974792)
		(size 0.4064)
		(drill 0.2032)
		(layers "F.Cu" "B.Cu")
		(net "GND")
	)
	(via
		(at 162.924998 -284.974792)
		(size 0.4064)
		(drill 0.2032)
		(layers "F.Cu" "B.Cu")
		(net "GND")
	)
	(via
		(at 356.173024 -292.789102)
		(size 0.508)
		(drill 0.254)
		(layers "F.Cu" "B.Cu")
		(net "GND")
	)
	(via
		(at 78.64983 -316.799722)
		(size 0.4064)
		(drill 0.2032)
		(layers "F.Cu" "B.Cu")
		(net "GND")
	)
	(via
		(at 419.95471 -23.880318)
		(size 0.508)
		(drill 0.254)
		(layers "F.Cu" "B.Cu")
		(net "GND")
	)
	(via
		(at 142.509494 -204.115924)
		(size 0.508)
		(drill 0.254)
		(layers "F.Cu" "B.Cu")
		(net "GND")
	)
	(via
		(at 428.84979 -283.549852)
		(size 0.4064)
		(drill 0.2032)
		(layers "F.Cu" "B.Cu")
		(net "GND")
	)
	(via
		(at 223.16694 -189.781434)
		(size 0.508)
		(drill 0.254)
		(layers "F.Cu" "B.Cu")
		(net "GND")
	)
	(via
		(at 163.618672 -357.75773)
		(size 0.4064)
		(drill 0.2032)
		(layers "F.Cu" "B.Cu")
		(net "GND")
	)
	(via
		(at 214.81923 -46.893226)
		(size 0.508)
		(drill 0.254)
		(layers "F.Cu" "B.Cu")
		(net "GND")
	)
	(via
		(at 153.233628 -111.175546)
		(size 0.508)
		(drill 0.254)
		(layers "F.Cu" "B.Cu")
		(net "GND")
	)
	(via
		(at 156.275024 -284.024832)
		(size 0.4064)
		(drill 0.2032)
		(layers "F.Cu" "B.Cu")
		(net "GND")
	)
	(via
		(at 114.772186 -285.267654)
		(size 0.508)
		(drill 0.254)
		(layers "F.Cu" "B.Cu")
		(net "GND")
	)
	(via
		(at 188.490352 -351.611438)
		(size 0.4064)
		(drill 0.2032)
		(layers "F.Cu" "B.Cu")
		(net "GND")
	)
	(via
		(at 281.399742 -310.149748)
		(size 0.4064)
		(drill 0.2032)
		(layers "F.Cu" "B.Cu")
		(net "GND")
	)
	(via
		(at 67.249802 -311.099962)
		(size 0.4064)
		(drill 0.2032)
		(layers "F.Cu" "B.Cu")
		(net "GND")
	)
	(via
		(at 305.149758 -311.099962)
		(size 0.4064)
		(drill 0.2032)
		(layers "F.Cu" "B.Cu")
		(net "GND")
	)
	(via
		(at 63.924942 -284.974792)
		(size 0.4064)
		(drill 0.2032)
		(layers "F.Cu" "B.Cu")
		(net "GND")
	)
	(via
		(at 346.245942 -252.598682)
		(size 0.508)
		(drill 0.254)
		(layers "F.Cu" "B.Cu")
		(net "GND")
	)
	(via
		(at 266.96797 -54.238906)
		(size 0.508)
		(drill 0.254)
		(layers "F.Cu" "B.Cu")
		(net "GND")
	)
	(via
		(at 398.4498 -311.099962)
		(size 0.4064)
		(drill 0.2032)
		(layers "F.Cu" "B.Cu")
		(net "GND")
	)
	(via
		(at 105.961434 -279.117298)
		(size 0.508)
		(drill 0.254)
		(layers "F.Cu" "B.Cu")
		(net "GND")
	)
	(via
		(at 392.274806 -290.674806)
		(size 0.4064)
		(drill 0.2032)
		(layers "F.Cu" "B.Cu")
		(net "GND")
	)
	(via
		(at 62.433454 -341.805514)
		(size 0.4572)
		(drill 0.254)
		(layers "F.Cu" "B.Cu")
		(net "GND")
	)
	(via
		(at 392.38174 -348.58579)
		(size 0.4064)
		(drill 0.2032)
		(layers "F.Cu" "B.Cu")
		(net "GND")
	)
	(via
		(at 49.65192 -125.955044)
		(size 0.508)
		(drill 0.254)
		(layers "F.Cu" "B.Cu")
		(net "GND")
	)
	(via
		(at 2.785364 -39.591742)
		(size 0.508)
		(drill 0.254)
		(layers "F.Cu" "B.Cu")
		(net "GND")
	)
	(via
		(at 77.978254 -352.245422)
		(size 0.4572)
		(drill 0.254)
		(layers "F.Cu" "B.Cu")
		(net "GND")
	)
	(via
		(at 174.747936 -381.241808)
		(size 0.508)
		(drill 0.254)
		(layers "F.Cu" "B.Cu")
		(net "GND")
	)
	(via
		(at 172.945552 -354.732082)
		(size 0.4064)
		(drill 0.2032)
		(layers "F.Cu" "B.Cu")
		(net "GND")
	)
	(via
		(at 333.127858 -409.940252)
		(size 0.508)
		(drill 0.254)
		(layers "F.Cu" "B.Cu")
		(net "GND")
	)
	(via
		(at 286.541718 -25.971246)
		(size 0.508)
		(drill 0.254)
		(layers "F.Cu" "B.Cu")
		(net "GND")
	)
	(via
		(at 172.900086 -318.699896)
		(size 0.4064)
		(drill 0.2032)
		(layers "F.Cu" "B.Cu")
		(net "GND")
	)
	(via
		(at 84.600796 -29.590238)
		(size 0.508)
		(drill 0.254)
		(layers "F.Cu" "B.Cu")
		(net "GND")
	)
	(via
		(at 161.500058 -313.949842)
		(size 0.4064)
		(drill 0.2032)
		(layers "F.Cu" "B.Cu")
		(net "GND")
	)
	(via
		(at 46.34992 -316.799722)
		(size 0.4064)
		(drill 0.2032)
		(layers "F.Cu" "B.Cu")
		(net "GND")
	)
	(via
		(at 284.503114 -347.951806)
		(size 0.4572)
		(drill 0.254)
		(layers "F.Cu" "B.Cu")
		(net "GND")
	)
	(via
		(at 176.94783 -371.140482)
		(size 0.508)
		(drill 0.254)
		(layers "F.Cu" "B.Cu")
		(net "GND")
	)
	(via
		(at 270.601694 -133.301994)
		(size 0.508)
		(drill 0.254)
		(layers "F.Cu" "B.Cu")
		(net "GND")
	)
	(via
		(at 230.528876 -107.843574)
		(size 0.508)
		(drill 0.254)
		(layers "F.Cu" "B.Cu")
		(net "GND")
	)
	(via
		(at 39.90213 -58.096404)
		(size 0.508)
		(drill 0.254)
		(layers "F.Cu" "B.Cu")
		(net "GND")
	)
	(via
		(at 42.074846 -299.2247)
		(size 0.4064)
		(drill 0.2032)
		(layers "F.Cu" "B.Cu")
		(net "GND")
	)
	(via
		(at 49.332388 -120.084088)
		(size 0.508)
		(drill 0.254)
		(layers "F.Cu" "B.Cu")
		(net "GND")
	)
	(via
		(at 285.674816 -305.874928)
		(size 0.4064)
		(drill 0.2032)
		(layers "F.Cu" "B.Cu")
		(net "GND")
	)
	(via
		(at 76.348082 -345.465146)
		(size 0.4064)
		(drill 0.2032)
		(layers "F.Cu" "B.Cu")
		(net "GND")
	)
	(via
		(at 316.672976 -346.09913)
		(size 0.4572)
		(drill 0.254)
		(layers "F.Cu" "B.Cu")
		(net "GND")
	)
	(via
		(at 216.060274 -19.33956)
		(size 0.508)
		(drill 0.254)
		(layers "F.Cu" "B.Cu")
		(net "GND")
	)
	(via
		(at 409.849828 -280.699718)
		(size 0.4064)
		(drill 0.2032)
		(layers "F.Cu" "B.Cu")
		(net "GND")
	)
	(via
		(at 23.34006 -74.58583)
		(size 0.508)
		(drill 0.254)
		(layers "F.Cu" "B.Cu")
		(net "GND")
	)
	(via
		(at 403.199854 -318.699896)
		(size 0.4064)
		(drill 0.2032)
		(layers "F.Cu" "B.Cu")
		(net "GND")
	)
	(via
		(at 284.874462 -345.465146)
		(size 0.4064)
		(drill 0.2032)
		(layers "F.Cu" "B.Cu")
		(net "GND")
	)
	(via
		(at 142.754096 -349.219774)
		(size 0.4572)
		(drill 0.254)
		(layers "F.Cu" "B.Cu")
		(net "GND")
	)
	(via
		(at 65.81267 -154.755088)
		(size 0.508)
		(drill 0.254)
		(layers "F.Cu" "B.Cu")
		(net "GND")
	)
	(via
		(at 307.049678 -282.599892)
		(size 0.4064)
		(drill 0.2032)
		(layers "F.Cu" "B.Cu")
		(net "GND")
	)
	(via
		(at 171.474892 -306.824888)
		(size 0.4064)
		(drill 0.2032)
		(layers "F.Cu" "B.Cu")
		(net "GND")
	)
	(via
		(at 411.980888 -25.990042)
		(size 0.508)
		(drill 0.254)
		(layers "F.Cu" "B.Cu")
		(net "GND")
	)
	(via
		(at 47.357792 -102.847394)
		(size 0.508)
		(drill 0.254)
		(layers "F.Cu" "B.Cu")
		(net "GND")
	)
	(via
		(at 210.566 -216.408)
		(size 0.508)
		(drill 0.254)
		(layers "F.Cu" "B.Cu")
		(net "GND")
	)
	(via
		(at 36.14801 -407.638504)
		(size 0.508)
		(drill 0.254)
		(layers "F.Cu" "B.Cu")
		(net "GND")
	)
	(via
		(at 174.002192 -27.729688)
		(size 0.508)
		(drill 0.254)
		(layers "F.Cu" "B.Cu")
		(net "GND")
	)
	(via
		(at 129.80035 -231.506522)
		(size 0.508)
		(drill 0.254)
		(layers "F.Cu" "B.Cu")
		(net "GND")
	)
	(via
		(at 394.17498 -284.974792)
		(size 0.4064)
		(drill 0.2032)
		(layers "F.Cu" "B.Cu")
		(net "GND")
	)
	(via
		(at 289.127692 -373.441976)
		(size 0.508)
		(drill 0.254)
		(layers "F.Cu" "B.Cu")
		(net "GND")
	)
	(via
		(at 230.065834 -285.445962)
		(size 0.508)
		(drill 0.254)
		(layers "F.Cu" "B.Cu")
		(net "GND")
	)
	(via
		(at 99.960176 -19.33956)
		(size 0.508)
		(drill 0.254)
		(layers "F.Cu" "B.Cu")
		(net "GND")
	)
	(via
		(at 166.725092 -284.974792)
		(size 0.4064)
		(drill 0.2032)
		(layers "F.Cu" "B.Cu")
		(net "GND")
	)
	(via
		(at 297.310302 -357.75773)
		(size 0.4064)
		(drill 0.2032)
		(layers "F.Cu" "B.Cu")
		(net "GND")
	)
	(via
		(at 81.499964 -313.949842)
		(size 0.4064)
		(drill 0.2032)
		(layers "F.Cu" "B.Cu")
		(net "GND")
	)
	(via
		(at 193.799968 -313.949842)
		(size 0.4064)
		(drill 0.2032)
		(layers "F.Cu" "B.Cu")
		(net "GND")
	)
	(via
		(at 0.766318 -57.092342)
		(size 0.508)
		(drill 0.254)
		(layers "F.Cu" "B.Cu")
		(net "GND")
	)
	(via
		(at 82.347816 -374.938544)
		(size 0.508)
		(drill 0.254)
		(layers "F.Cu" "B.Cu")
		(net "GND")
	)
	(via
		(at 208.789524 -287.072832)
		(size 0.508)
		(drill 0.254)
		(layers "F.Cu" "B.Cu")
		(net "GND")
	)
	(via
		(at 367.547144 -131.957572)
		(size 0.508)
		(drill 0.254)
		(layers "F.Cu" "B.Cu")
		(net "GND")
	)
	(via
		(at 175.683164 -347.951806)
		(size 0.4572)
		(drill 0.254)
		(layers "F.Cu" "B.Cu")
		(net "GND")
	)
	(via
		(at 409.374848 -298.27474)
		(size 0.4064)
		(drill 0.2032)
		(layers "F.Cu" "B.Cu")
		(net "GND")
	)
	(via
		(at 279.974802 -284.974792)
		(size 0.4064)
		(drill 0.2032)
		(layers "F.Cu" "B.Cu")
		(net "GND")
	)
	(via
		(at 436.527702 -403.738588)
		(size 0.508)
		(drill 0.254)
		(layers "F.Cu" "B.Cu")
		(net "GND")
	)
	(via
		(at 52.049934 -310.149748)
		(size 0.4064)
		(drill 0.2032)
		(layers "F.Cu" "B.Cu")
		(net "GND")
	)
	(via
		(at 54.98211 -371.508274)
		(size 0.4572)
		(drill 0.254)
		(layers "F.Cu" "B.Cu")
		(net "GND")
	)
	(via
		(at 195.415154 -45.88891)
		(size 0.508)
		(drill 0.254)
		(layers "F.Cu" "B.Cu")
		(net "GND")
	)
	(via
		(at 285.687262 -135.364982)
		(size 0.508)
		(drill 0.254)
		(layers "F.Cu" "B.Cu")
		(net "GND")
	)
	(via
		(at 170.049952 -314.899802)
		(size 0.4064)
		(drill 0.2032)
		(layers "F.Cu" "B.Cu")
		(net "GND")
	)
	(via
		(at 311.324752 -300.174914)
		(size 0.4064)
		(drill 0.2032)
		(layers "F.Cu" "B.Cu")
		(net "GND")
	)
	(via
		(at 165.774878 -286.874966)
		(size 0.4064)
		(drill 0.2032)
		(layers "F.Cu" "B.Cu")
		(net "GND")
	)
	(via
		(at 249.896122 -160.83407)
		(size 0.508)
		(drill 0.254)
		(layers "F.Cu" "B.Cu")
		(net "GND")
	)
	(via
		(at 354.858066 -140.392404)
		(size 0.508)
		(drill 0.254)
		(layers "F.Cu" "B.Cu")
		(net "GND")
	)
	(via
		(at 203.748894 -29.589984)
		(size 0.508)
		(drill 0.254)
		(layers "F.Cu" "B.Cu")
		(net "GND")
	)
	(via
		(at 242.321842 -184.235344)
		(size 0.508)
		(drill 0.254)
		(layers "F.Cu" "B.Cu")
		(net "GND")
	)
	(via
		(at 288.40811 -52.536852)
		(size 0.508)
		(drill 0.254)
		(layers "F.Cu" "B.Cu")
		(net "GND")
	)
	(via
		(at 171.949872 -279.749758)
		(size 0.4064)
		(drill 0.2032)
		(layers "F.Cu" "B.Cu")
		(net "GND")
	)
	(via
		(at 48.24984 -315.849762)
		(size 0.4064)
		(drill 0.2032)
		(layers "F.Cu" "B.Cu")
		(net "GND")
	)
	(via
		(at 427.615096 -45.88891)
		(size 0.508)
		(drill 0.254)
		(layers "F.Cu" "B.Cu")
		(net "GND")
	)
	(via
		(at 316.672976 -357.123746)
		(size 0.4572)
		(drill 0.254)
		(layers "F.Cu" "B.Cu")
		(net "GND")
	)
	(via
		(at 315.60008 -279.750012)
		(size 0.4064)
		(drill 0.2032)
		(layers "F.Cu" "B.Cu")
		(net "GND")
	)
	(via
		(at 371.348 -243.936012)
		(size 0.508)
		(drill 0.254)
		(layers "F.Cu" "B.Cu")
		(net "GND")
	)
	(via
		(at 182.87492 -302.074834)
		(size 0.4064)
		(drill 0.2032)
		(layers "F.Cu" "B.Cu")
		(net "GND")
	)
	(via
		(at 60.124848 -300.174914)
		(size 0.4064)
		(drill 0.2032)
		(layers "F.Cu" "B.Cu")
		(net "GND")
	)
	(via
		(at 166.725092 -302.074834)
		(size 0.4064)
		(drill 0.2032)
		(layers "F.Cu" "B.Cu")
		(net "GND")
	)
	(via
		(at 119.747792 -398.34185)
		(size 0.4572)
		(drill 0.254)
		(layers "F.Cu" "B.Cu")
		(net "GND")
	)
	(via
		(at 325.999856 -341.805514)
		(size 0.4572)
		(drill 0.254)
		(layers "F.Cu" "B.Cu")
		(net "GND")
	)
	(via
		(at 242.912392 -90.518234)
		(size 0.508)
		(drill 0.254)
		(layers "F.Cu" "B.Cu")
		(net "GND")
	)
	(via
		(at 13.625322 -120.11787)
		(size 0.508)
		(drill 0.254)
		(layers "F.Cu" "B.Cu")
		(net "GND")
	)
	(via
		(at 183.82488 -305.874928)
		(size 0.4064)
		(drill 0.2032)
		(layers "F.Cu" "B.Cu")
		(net "GND")
	)
	(via
		(at 409.948888 -33.19018)
		(size 0.508)
		(drill 0.254)
		(layers "F.Cu" "B.Cu")
		(net "GND")
	)
	(via
		(at 305.255676 -250.263406)
		(size 0.508)
		(drill 0.254)
		(layers "F.Cu" "B.Cu")
		(net "GND")
	)
	(via
		(at 350.069658 -64.102234)
		(size 0.508)
		(drill 0.254)
		(layers "F.Cu" "B.Cu")
		(net "GND")
	)
	(via
		(at 267.69949 -343.073482)
		(size 0.4572)
		(drill 0.254)
		(layers "F.Cu" "B.Cu")
		(net "GND")
	)
	(via
		(at 62.499748 -318.699896)
		(size 0.4064)
		(drill 0.2032)
		(layers "F.Cu" "B.Cu")
		(net "GND")
	)
	(via
		(at 101.339904 -73.23963)
		(size 0.508)
		(drill 0.254)
		(layers "F.Cu" "B.Cu")
		(net "GND")
	)
	(via
		(at 403.199854 -274.049744)
		(size 0.4064)
		(drill 0.2032)
		(layers "F.Cu" "B.Cu")
		(net "GND")
	)
	(via
		(at 151.859488 -133.836664)
		(size 0.508)
		(drill 0.254)
		(layers "F.Cu" "B.Cu")
		(net "GND")
	)
	(via
		(at 242.4938 -214.0458)
		(size 0.508)
		(drill 0.254)
		(layers "F.Cu" "B.Cu")
		(net "GND")
	)
	(via
		(at 160.549844 -281.649932)
		(size 0.4064)
		(drill 0.2032)
		(layers "F.Cu" "B.Cu")
		(net "GND")
	)
	(via
		(at 423.32783 -398.34185)
		(size 0.508)
		(drill 0.254)
		(layers "F.Cu" "B.Cu")
		(net "GND")
	)
	(via
		(at 39.04742 -344.831162)
		(size 0.4572)
		(drill 0.254)
		(layers "F.Cu" "B.Cu")
		(net "GND")
	)
	(via
		(at 309.55742 -29.784294)
		(size 0.508)
		(drill 0.254)
		(layers "F.Cu" "B.Cu")
		(net "GND")
	)
	(via
		(at 342.245442 -305.91887)
		(size 0.508)
		(drill 0.254)
		(layers "F.Cu" "B.Cu")
		(net "GND")
	)
	(via
		(at 145.251678 -256.375916)
		(size 0.508)
		(drill 0.254)
		(layers "F.Cu" "B.Cu")
		(net "GND")
	)
	(via
		(at 79.82839 -354.098098)
		(size 0.4572)
		(drill 0.254)
		(layers "F.Cu" "B.Cu")
		(net "GND")
	)
	(via
		(at 7.857236 -306.606194)
		(size 0.508)
		(drill 0.254)
		(layers "F.Cu" "B.Cu")
		(net "GND")
	)
	(via
		(at 314.649866 -282.599892)
		(size 0.4064)
		(drill 0.2032)
		(layers "F.Cu" "B.Cu")
		(net "GND")
	)
	(via
		(at 84.54771 -406.141936)
		(size 0.508)
		(drill 0.254)
		(layers "F.Cu" "B.Cu")
		(net "GND")
	)
	(via
		(at 158.649924 -312.049922)
		(size 0.4064)
		(drill 0.2032)
		(layers "F.Cu" "B.Cu")
		(net "GND")
	)
	(via
		(at 423.62501 -290.674806)
		(size 0.4064)
		(drill 0.2032)
		(layers "F.Cu" "B.Cu")
		(net "GND")
	)
	(via
		(at 348.488 -417.82492)
		(size 0.508)
		(drill 0.254)
		(layers "F.Cu" "B.Cu")
		(net "GND")
	)
	(via
		(at 289.94989 -312.049922)
		(size 0.4064)
		(drill 0.2032)
		(layers "F.Cu" "B.Cu")
		(net "GND")
	)
	(via
		(at 95.56115 -60.099194)
		(size 0.508)
		(drill 0.254)
		(layers "F.Cu" "B.Cu")
		(net "GND")
	)
	(via
		(at 37.788596 -357.123746)
		(size 0.4572)
		(drill 0.254)
		(layers "F.Cu" "B.Cu")
		(net "GND")
	)
	(via
		(at 36.374832 -294.4749)
		(size 0.4064)
		(drill 0.2032)
		(layers "F.Cu" "B.Cu")
		(net "GND")
	)
	(via
		(at 398.686528 -48.874934)
		(size 0.508)
		(drill 0.254)
		(layers "F.Cu" "B.Cu")
		(net "GND")
	)
	(via
		(at 315.740288 -152.683464)
		(size 0.508)
		(drill 0.254)
		(layers "F.Cu" "B.Cu")
		(net "GND")
	)
	(via
		(at 400.824954 -298.27474)
		(size 0.4064)
		(drill 0.2032)
		(layers "F.Cu" "B.Cu")
		(net "GND")
	)
	(via
		(at 50.150014 -319.65011)
		(size 0.4064)
		(drill 0.2032)
		(layers "F.Cu" "B.Cu")
		(net "GND")
	)
	(via
		(at 23.50262 -344.831162)
		(size 0.4572)
		(drill 0.254)
		(layers "F.Cu" "B.Cu")
		(net "GND")
	)
	(via
		(at 87.648796 -29.589984)
		(size 0.508)
		(drill 0.254)
		(layers "F.Cu" "B.Cu")
		(net "GND")
	)
	(via
		(at 46.8249 -287.824926)
		(size 0.4064)
		(drill 0.2032)
		(layers "F.Cu" "B.Cu")
		(net "GND")
	)
	(via
		(at 186.200034 -273.099784)
		(size 0.4064)
		(drill 0.2032)
		(layers "F.Cu" "B.Cu")
		(net "GND")
	)
	(via
		(at 363.985048 -131.312666)
		(size 0.508)
		(drill 0.254)
		(layers "F.Cu" "B.Cu")
		(net "GND")
	)
	(via
		(at 26.193496 -279.931114)
		(size 0.508)
		(drill 0.254)
		(layers "F.Cu" "B.Cu")
		(net "GND")
	)
	(via
		(at 301.848012 -129.445004)
		(size 0.508)
		(drill 0.254)
		(layers "F.Cu" "B.Cu")
		(net "GND")
	)
	(via
		(at 90.953844 -224.692464)
		(size 0.508)
		(drill 0.254)
		(layers "F.Cu" "B.Cu")
		(net "GND")
	)
	(via
		(at 13.902182 -58.096404)
		(size 0.508)
		(drill 0.254)
		(layers "F.Cu" "B.Cu")
		(net "GND")
	)
	(via
		(at 307.049932 -305.399948)
		(size 0.4064)
		(drill 0.2032)
		(layers "F.Cu" "B.Cu")
		(net "GND")
	)
	(via
		(at 300.12767 -375.040144)
		(size 0.508)
		(drill 0.254)
		(layers "F.Cu" "B.Cu")
		(net "GND")
	)
	(via
		(at 348.527878 -402.241766)
		(size 0.508)
		(drill 0.254)
		(layers "F.Cu" "B.Cu")
		(net "GND")
	)
	(via
		(at 68.651374 -344.831162)
		(size 0.4572)
		(drill 0.254)
		(layers "F.Cu" "B.Cu")
		(net "GND")
	)
	(via
		(at 395.4907 -354.732082)
		(size 0.4064)
		(drill 0.2032)
		(layers "F.Cu" "B.Cu")
		(net "GND")
	)
	(via
		(at 359.752138 -97.630742)
		(size 0.508)
		(drill 0.254)
		(layers "F.Cu" "B.Cu")
		(net "GND")
	)
	(via
		(at 314.649866 -284.499812)
		(size 0.4064)
		(drill 0.2032)
		(layers "F.Cu" "B.Cu")
		(net "GND")
	)
	(via
		(at 193.799968 -304.449734)
		(size 0.4064)
		(drill 0.2032)
		(layers "F.Cu" "B.Cu")
		(net "GND")
	)
	(via
		(at 418.51072 -57.439814)
		(size 0.508)
		(drill 0.254)
		(layers "F.Cu" "B.Cu")
		(net "GND")
	)
	(via
		(at 17.69618 -160.83407)
		(size 0.508)
		(drill 0.254)
		(layers "F.Cu" "B.Cu")
		(net "GND")
	)
	(via
		(at 424.09999 -317.749936)
		(size 0.4064)
		(drill 0.2032)
		(layers "F.Cu" "B.Cu")
		(net "GND")
	)
	(via
		(at 326.007476 -86.23173)
		(size 0.508)
		(drill 0.254)
		(layers "F.Cu" "B.Cu")
		(net "GND")
	)
	(via
		(at 4.562856 -139.521692)
		(size 0.508)
		(drill 0.254)
		(layers "F.Cu" "B.Cu")
		(net "GND")
	)
	(via
		(at 182.87492 -291.624766)
		(size 0.4064)
		(drill 0.2032)
		(layers "F.Cu" "B.Cu")
		(net "GND")
	)
	(via
		(at 42.747946 -409.940252)
		(size 0.508)
		(drill 0.254)
		(layers "F.Cu" "B.Cu")
		(net "GND")
	)
	(via
		(at 311.799732 -312.999882)
		(size 0.4064)
		(drill 0.2032)
		(layers "F.Cu" "B.Cu")
		(net "GND")
	)
	(via
		(at 169.587164 -118.754906)
		(size 0.508)
		(drill 0.254)
		(layers "F.Cu" "B.Cu")
		(net "GND")
	)
	(via
		(at 120.042178 -49.574704)
		(size 0.508)
		(drill 0.254)
		(layers "F.Cu" "B.Cu")
		(net "GND")
	)
	(via
		(at 71.52005 -56.441848)
		(size 0.508)
		(drill 0.254)
		(layers "F.Cu" "B.Cu")
		(net "GND")
	)
	(via
		(at 386.354828 -34.990024)
		(size 0.508)
		(drill 0.254)
		(layers "F.Cu" "B.Cu")
		(net "GND")
	)
	(via
		(at 434.327808 -373.441976)
		(size 0.508)
		(drill 0.254)
		(layers "F.Cu" "B.Cu")
		(net "GND")
	)
	(via
		(at 390.374886 -296.37482)
		(size 0.4064)
		(drill 0.2032)
		(layers "F.Cu" "B.Cu")
		(net "GND")
	)
	(via
		(at 383.72796 -377.738386)
		(size 0.508)
		(drill 0.254)
		(layers "F.Cu" "B.Cu")
		(net "GND")
	)
	(via
		(at 270.80845 -350.977454)
		(size 0.4572)
		(drill 0.254)
		(layers "F.Cu" "B.Cu")
		(net "GND")
	)
	(via
		(at 234.238292 -86.880954)
		(size 0.508)
		(drill 0.254)
		(layers "F.Cu" "B.Cu")
		(net "GND")
	)
	(via
		(at 295.68013 -347.951806)
		(size 0.4572)
		(drill 0.254)
		(layers "F.Cu" "B.Cu")
		(net "GND")
	)
	(via
		(at 396.54988 -275.949918)
		(size 0.4064)
		(drill 0.2032)
		(layers "F.Cu" "B.Cu")
		(net "GND")
	)
	(via
		(at 367.820194 -57.076848)
		(size 0.508)
		(drill 0.254)
		(layers "F.Cu" "B.Cu")
		(net "GND")
	)
	(via
		(at 135.067802 -187.730638)
		(size 0.508)
		(drill 0.254)
		(layers "F.Cu" "B.Cu")
		(net "GND")
	)
	(via
		(at 381.576072 -352.245422)
		(size 0.4572)
		(drill 0.254)
		(layers "F.Cu" "B.Cu")
		(net "GND")
	)
	(via
		(at 281.874722 -303.974754)
		(size 0.4064)
		(drill 0.2032)
		(layers "F.Cu" "B.Cu")
		(net "GND")
	)
	(via
		(at 298.024804 -291.624766)
		(size 0.4064)
		(drill 0.2032)
		(layers "F.Cu" "B.Cu")
		(net "GND")
	)
	(via
		(at 73.424796 -293.52494)
		(size 0.4064)
		(drill 0.2032)
		(layers "F.Cu" "B.Cu")
		(net "GND")
	)
	(via
		(at 273.799808 -306.349908)
		(size 0.4064)
		(drill 0.2032)
		(layers "F.Cu" "B.Cu")
		(net "GND")
	)
	(via
		(at 319.848738 -25.990042)
		(size 0.508)
		(drill 0.254)
		(layers "F.Cu" "B.Cu")
		(net "GND")
	)
	(via
		(at 244.102382 -278.379936)
		(size 0.508)
		(drill 0.254)
		(layers "F.Cu" "B.Cu")
		(net "GND")
	)
	(via
		(at 84.196174 -346.09913)
		(size 0.4572)
		(drill 0.254)
		(layers "F.Cu" "B.Cu")
		(net "GND")
	)
	(via
		(at 85.819996 -33.19018)
		(size 0.508)
		(drill 0.254)
		(layers "F.Cu" "B.Cu")
		(net "GND")
	)
	(via
		(at 18.184622 -72.56526)
		(size 0.508)
		(drill 0.254)
		(layers "F.Cu" "B.Cu")
		(net "GND")
	)
	(via
		(at 87.676482 -345.465146)
		(size 0.4064)
		(drill 0.2032)
		(layers "F.Cu" "B.Cu")
		(net "GND")
	)
	(via
		(at 427.42485 -296.37482)
		(size 0.4064)
		(drill 0.2032)
		(layers "F.Cu" "B.Cu")
		(net "GND")
	)
	(via
		(at 139.645136 -358.391714)
		(size 0.4572)
		(drill 0.254)
		(layers "F.Cu" "B.Cu")
		(net "GND")
	)
	(via
		(at 182.87492 -287.824926)
		(size 0.4064)
		(drill 0.2032)
		(layers "F.Cu" "B.Cu")
		(net "GND")
	)
	(via
		(at 157.699964 -300.649894)
		(size 0.4064)
		(drill 0.2032)
		(layers "F.Cu" "B.Cu")
		(net "GND")
	)
	(via
		(at 248.757948 -58.156094)
		(size 0.508)
		(drill 0.254)
		(layers "F.Cu" "B.Cu")
		(net "GND")
	)
	(via
		(at 28.090368 -345.465146)
		(size 0.4064)
		(drill 0.2032)
		(layers "F.Cu" "B.Cu")
		(net "GND")
	)
	(via
		(at 396.54988 -311.099962)
		(size 0.4064)
		(drill 0.2032)
		(layers "F.Cu" "B.Cu")
		(net "GND")
	)
	(via
		(at 306.448206 -116.435124)
		(size 0.508)
		(drill 0.254)
		(layers "F.Cu" "B.Cu")
		(net "GND")
	)
	(via
		(at 335.328006 -398.34185)
		(size 0.508)
		(drill 0.254)
		(layers "F.Cu" "B.Cu")
		(net "GND")
	)
	(via
		(at 335.026 -155.702)
		(size 0.508)
		(drill 0.254)
		(layers "F.Cu" "B.Cu")
		(net "GND")
	)
	(via
		(at 157.224984 -272.624804)
		(size 0.4064)
		(drill 0.2032)
		(layers "F.Cu" "B.Cu")
		(net "GND")
	)
	(via
		(at 36.849812 -315.849762)
		(size 0.4064)
		(drill 0.2032)
		(layers "F.Cu" "B.Cu")
		(net "GND")
	)
	(via
		(at 241.848894 -34.990024)
		(size 0.508)
		(drill 0.254)
		(layers "F.Cu" "B.Cu")
		(net "GND")
	)
	(via
		(at 421.61333 -31.118302)
		(size 0.508)
		(drill 0.254)
		(layers "F.Cu" "B.Cu")
		(net "GND")
	)
	(via
		(at 62.024768 -291.624766)
		(size 0.4064)
		(drill 0.2032)
		(layers "F.Cu" "B.Cu")
		(net "GND")
	)
	(via
		(at 173.375066 -300.174914)
		(size 0.4064)
		(drill 0.2032)
		(layers "F.Cu" "B.Cu")
		(net "GND")
	)
	(via
		(at 172.574204 -347.951806)
		(size 0.4572)
		(drill 0.254)
		(layers "F.Cu" "B.Cu")
		(net "GND")
	)
	(via
		(at 332.6765 -115.021614)
		(size 0.508)
		(drill 0.254)
		(layers "F.Cu" "B.Cu")
		(net "GND")
	)
	(via
		(at 73.899776 -287.349946)
		(size 0.4064)
		(drill 0.2032)
		(layers "F.Cu" "B.Cu")
		(net "GND")
	)
	(via
		(at 397.02486 -307.774848)
		(size 0.4064)
		(drill 0.2032)
		(layers "F.Cu" "B.Cu")
		(net "GND")
	)
	(via
		(at 413.465264 -357.123746)
		(size 0.4572)
		(drill 0.254)
		(layers "F.Cu" "B.Cu")
		(net "GND")
	)
	(via
		(at 33.8201 -29.590238)
		(size 0.508)
		(drill 0.254)
		(layers "F.Cu" "B.Cu")
		(net "GND")
	)
	(via
		(at 440.51474 -26.171398)
		(size 0.508)
		(drill 0.254)
		(layers "F.Cu" "B.Cu")
		(net "GND")
	)
	(via
		(at 172.424852 -284.974792)
		(size 0.4064)
		(drill 0.2032)
		(layers "F.Cu" "B.Cu")
		(net "GND")
	)
	(via
		(at 288.524696 -287.824926)
		(size 0.4064)
		(drill 0.2032)
		(layers "F.Cu" "B.Cu")
		(net "GND")
	)
	(via
		(at 248.06529 -212.094572)
		(size 0.508)
		(drill 0.254)
		(layers "F.Cu" "B.Cu")
		(net "GND")
	)
	(via
		(at 392.274806 -286.874712)
		(size 0.4064)
		(drill 0.2032)
		(layers "F.Cu" "B.Cu")
		(net "GND")
	)
	(via
		(at 50.624994 -302.074834)
		(size 0.4064)
		(drill 0.2032)
		(layers "F.Cu" "B.Cu")
		(net "GND")
	)
	(via
		(at 337.5279 -376.140218)
		(size 0.508)
		(drill 0.254)
		(layers "F.Cu" "B.Cu")
		(net "GND")
	)
	(via
		(at 223.75114 -119.172228)
		(size 0.508)
		(drill 0.254)
		(layers "F.Cu" "B.Cu")
		(net "GND")
	)
	(via
		(at 344.893646 -220.38691)
		(size 0.4572)
		(drill 0.254)
		(layers "F.Cu" "B.Cu")
		(net "GND")
	)
	(via
		(at 436.527702 -371.140482)
		(size 0.508)
		(drill 0.254)
		(layers "F.Cu" "B.Cu")
		(net "GND")
	)
	(via
		(at 395.332966 -100.64496)
		(size 0.508)
		(drill 0.254)
		(layers "F.Cu" "B.Cu")
		(net "GND")
	)
	(via
		(at 161.168334 -48.753014)
		(size 0.508)
		(drill 0.254)
		(layers "F.Cu" "B.Cu")
		(net "GND")
	)
	(via
		(at 306.7812 -33.459674)
		(size 0.508)
		(drill 0.254)
		(layers "F.Cu" "B.Cu")
		(net "GND")
	)
	(via
		(at 433.96916 -341.805514)
		(size 0.4572)
		(drill 0.254)
		(layers "F.Cu" "B.Cu")
		(net "GND")
	)
	(via
		(at 392.971274 -29.311854)
		(size 0.508)
		(drill 0.254)
		(layers "F.Cu" "B.Cu")
		(net "GND")
	)
	(via
		(at 218.679268 -287.105344)
		(size 0.508)
		(drill 0.254)
		(layers "F.Cu" "B.Cu")
		(net "GND")
	)
	(via
		(at 15.7607 -128.193546)
		(size 0.508)
		(drill 0.254)
		(layers "F.Cu" "B.Cu")
		(net "GND")
	)
	(via
		(at 140.075158 -73.23963)
		(size 0.508)
		(drill 0.254)
		(layers "F.Cu" "B.Cu")
		(net "GND")
	)
	(via
		(at 380.317248 -354.098098)
		(size 0.4572)
		(drill 0.254)
		(layers "F.Cu" "B.Cu")
		(net "GND")
	)
	(via
		(at 319.781936 -354.098098)
		(size 0.4572)
		(drill 0.254)
		(layers "F.Cu" "B.Cu")
		(net "GND")
	)
	(via
		(at 173.375066 -289.724846)
		(size 0.4064)
		(drill 0.2032)
		(layers "F.Cu" "B.Cu")
		(net "GND")
	)
	(via
		(at 297.927776 -409.940252)
		(size 0.508)
		(drill 0.254)
		(layers "F.Cu" "B.Cu")
		(net "GND")
	)
	(via
		(at 419.683184 -341.805514)
		(size 0.4572)
		(drill 0.254)
		(layers "F.Cu" "B.Cu")
		(net "GND")
	)
	(via
		(at 306.099718 -277.849838)
		(size 0.4064)
		(drill 0.2032)
		(layers "F.Cu" "B.Cu")
		(net "GND")
	)
	(via
		(at 231.388158 -60.600082)
		(size 0.508)
		(drill 0.254)
		(layers "F.Cu" "B.Cu")
		(net "GND")
	)
	(via
		(at 334.067912 -344.831162)
		(size 0.4572)
		(drill 0.254)
		(layers "F.Cu" "B.Cu")
		(net "GND")
	)
	(via
		(at 385.624578 -298.27474)
		(size 0.4064)
		(drill 0.2032)
		(layers "F.Cu" "B.Cu")
		(net "GND")
	)
	(via
		(at 73.31329 -29.859478)
		(size 0.508)
		(drill 0.254)
		(layers "F.Cu" "B.Cu")
		(net "GND")
	)
	(via
		(at 175.768 -417.82492)
		(size 0.508)
		(drill 0.254)
		(layers "F.Cu" "B.Cu")
		(net "GND")
	)
	(via
		(at 9.0551 -123.947428)
		(size 0.508)
		(drill 0.254)
		(layers "F.Cu" "B.Cu")
		(net "GND")
	)
	(via
		(at 41.124886 -300.174914)
		(size 0.4064)
		(drill 0.2032)
		(layers "F.Cu" "B.Cu")
		(net "GND")
	)
	(via
		(at 398.971008 -343.073482)
		(size 0.4572)
		(drill 0.254)
		(layers "F.Cu" "B.Cu")
		(net "GND")
	)
	(via
		(at 72.169528 -111.016288)
		(size 0.508)
		(drill 0.254)
		(layers "F.Cu" "B.Cu")
		(net "GND")
	)
	(via
		(at 16.558006 -58.156094)
		(size 0.508)
		(drill 0.254)
		(layers "F.Cu" "B.Cu")
		(net "GND")
	)
	(via
		(at 52.04968 -272.14957)
		(size 0.4064)
		(drill 0.2032)
		(layers "F.Cu" "B.Cu")
		(net "GND")
	)
	(via
		(at 274.274788 -299.2247)
		(size 0.4064)
		(drill 0.2032)
		(layers "F.Cu" "B.Cu")
		(net "GND")
	)
	(via
		(at 208.002124 -58.096404)
		(size 0.508)
		(drill 0.254)
		(layers "F.Cu" "B.Cu")
		(net "GND")
	)
	(via
		(at 81.271364 -51.661822)
		(size 0.508)
		(drill 0.254)
		(layers "F.Cu" "B.Cu")
		(net "GND")
	)
	(via
		(at 48.745648 -351.611438)
		(size 0.4064)
		(drill 0.2032)
		(layers "F.Cu" "B.Cu")
		(net "GND")
	)
	(via
		(at 163.747958 -371.140228)
		(size 0.508)
		(drill 0.254)
		(layers "F.Cu" "B.Cu")
		(net "GND")
	)
	(via
		(at 304.527712 -384.042158)
		(size 0.508)
		(drill 0.254)
		(layers "F.Cu" "B.Cu")
		(net "GND")
	)
	(via
		(at 50.14976 -314.899802)
		(size 0.4064)
		(drill 0.2032)
		(layers "F.Cu" "B.Cu")
		(net "GND")
	)
	(via
		(at 113.329466 -113.563654)
		(size 0.508)
		(drill 0.254)
		(layers "F.Cu" "B.Cu")
		(net "GND")
	)
	(via
		(at 143.76908 -283.131514)
		(size 0.508)
		(drill 0.254)
		(layers "F.Cu" "B.Cu")
		(net "GND")
	)
	(via
		(at 130.74777 -400.938492)
		(size 0.508)
		(drill 0.254)
		(layers "F.Cu" "B.Cu")
		(net "GND")
	)
	(via
		(at 74.84999 -314.899802)
		(size 0.4064)
		(drill 0.2032)
		(layers "F.Cu" "B.Cu")
		(net "GND")
	)
	(via
		(at 41.124886 -299.224954)
		(size 0.4064)
		(drill 0.2032)
		(layers "F.Cu" "B.Cu")
		(net "GND")
	)
	(via
		(at 45.26534 -358.391714)
		(size 0.4572)
		(drill 0.254)
		(layers "F.Cu" "B.Cu")
		(net "GND")
	)
	(via
		(at 32.8295 -347.951806)
		(size 0.4572)
		(drill 0.254)
		(layers "F.Cu" "B.Cu")
		(net "GND")
	)
	(via
		(at 65.542414 -347.92793)
		(size 0.4572)
		(drill 0.254)
		(layers "F.Cu" "B.Cu")
		(net "GND")
	)
	(via
		(at 379.327918 -406.141936)
		(size 0.508)
		(drill 0.254)
		(layers "F.Cu" "B.Cu")
		(net "GND")
	)
	(via
		(at 193.799968 -318.699896)
		(size 0.4064)
		(drill 0.2032)
		(layers "F.Cu" "B.Cu")
		(net "GND")
	)
	(via
		(at 276.649688 -276.899878)
		(size 0.4064)
		(drill 0.2032)
		(layers "F.Cu" "B.Cu")
		(net "GND")
	)
	(via
		(at 397.624046 -26.319734)
		(size 0.508)
		(drill 0.254)
		(layers "F.Cu" "B.Cu")
		(net "GND")
	)
	(via
		(at 296.888154 -114.267742)
		(size 0.508)
		(drill 0.254)
		(layers "F.Cu" "B.Cu")
		(net "GND")
	)
	(via
		(at 335.328006 -382.84023)
		(size 0.508)
		(drill 0.254)
		(layers "F.Cu" "B.Cu")
		(net "GND")
	)
	(via
		(at 33.947862 -406.040336)
		(size 0.508)
		(drill 0.254)
		(layers "F.Cu" "B.Cu")
		(net "GND")
	)
	(via
		(at 304.527712 -381.63881)
		(size 0.508)
		(drill 0.254)
		(layers "F.Cu" "B.Cu")
		(net "GND")
	)
	(via
		(at 61.549788 -312.049922)
		(size 0.4064)
		(drill 0.2032)
		(layers "F.Cu" "B.Cu")
		(net "GND")
	)
	(via
		(at 18.671286 -32.911796)
		(size 0.508)
		(drill 0.254)
		(layers "F.Cu" "B.Cu")
		(net "GND")
	)
	(via
		(at 150.428452 -223.675448)
		(size 0.508)
		(drill 0.254)
		(layers "F.Cu" "B.Cu")
		(net "GND")
	)
	(via
		(at 407.949908 -275.949918)
		(size 0.4064)
		(drill 0.2032)
		(layers "F.Cu" "B.Cu")
		(net "GND")
	)
	(via
		(at 135.32358 -153.782522)
		(size 0.508)
		(drill 0.254)
		(layers "F.Cu" "B.Cu")
		(net "GND")
	)
	(via
		(at 385.433824 -111.175546)
		(size 0.508)
		(drill 0.254)
		(layers "F.Cu" "B.Cu")
		(net "GND")
	)
	(via
		(at 83.400138 -308.249828)
		(size 0.4064)
		(drill 0.2032)
		(layers "F.Cu" "B.Cu")
		(net "GND")
	)
	(via
		(at 49.547526 -121.692416)
		(size 0.508)
		(drill 0.254)
		(layers "F.Cu" "B.Cu")
		(net "GND")
	)
	(via
		(at 345.703398 -279.000712)
		(size 0.508)
		(drill 0.254)
		(layers "F.Cu" "B.Cu")
		(net "GND")
	)
	(via
		(at 429.927766 -383.940304)
		(size 0.508)
		(drill 0.254)
		(layers "F.Cu" "B.Cu")
		(net "GND")
	)
	(via
		(at 231.867456 -213.904322)
		(size 0.4572)
		(drill 0.254)
		(layers "F.Cu" "B.Cu")
		(net "GND")
	)
	(via
		(at 4.229608 -282.354782)
		(size 0.508)
		(drill 0.254)
		(layers "F.Cu" "B.Cu")
		(net "GND")
	)
	(via
		(at 257.557524 -29.784294)
		(size 0.508)
		(drill 0.254)
		(layers "F.Cu" "B.Cu")
		(net "GND")
	)
	(via
		(at 42.747946 -407.24201)
		(size 0.508)
		(drill 0.254)
		(layers "F.Cu" "B.Cu")
		(net "GND")
	)
	(via
		(at 412.699962 -312.999882)
		(size 0.4064)
		(drill 0.2032)
		(layers "F.Cu" "B.Cu")
		(net "GND")
	)
	(via
		(at 289.949636 -272.14957)
		(size 0.4064)
		(drill 0.2032)
		(layers "F.Cu" "B.Cu")
		(net "GND")
	)
	(via
		(at 276.174708 -293.52494)
		(size 0.4064)
		(drill 0.2032)
		(layers "F.Cu" "B.Cu")
		(net "GND")
	)
	(via
		(at 353.440238 -27.729688)
		(size 0.508)
		(drill 0.254)
		(layers "F.Cu" "B.Cu")
		(net "GND")
	)
	(via
		(at 108.904786 -223.093534)
		(size 0.508)
		(drill 0.254)
		(layers "F.Cu" "B.Cu")
		(net "GND")
	)
	(via
		(at 121.947686 -378.83846)
		(size 0.508)
		(drill 0.254)
		(layers "F.Cu" "B.Cu")
		(net "GND")
	)
	(via
		(at 63.680848 -25.990042)
		(size 0.508)
		(drill 0.254)
		(layers "F.Cu" "B.Cu")
		(net "GND")
	)
	(via
		(at 182.547514 -118.234968)
		(size 0.508)
		(drill 0.254)
		(layers "F.Cu" "B.Cu")
		(net "GND")
	)
	(via
		(at 327.478644 -357.75773)
		(size 0.4064)
		(drill 0.2032)
		(layers "F.Cu" "B.Cu")
		(net "GND")
	)
	(via
		(at 346.465906 -85.083142)
		(size 0.508)
		(drill 0.254)
		(layers "F.Cu" "B.Cu")
		(net "GND")
	)
	(via
		(at 325.82104 -103.890064)
		(size 0.508)
		(drill 0.254)
		(layers "F.Cu" "B.Cu")
		(net "GND")
	)
	(via
		(at 80.147922 -398.34185)
		(size 0.508)
		(drill 0.254)
		(layers "F.Cu" "B.Cu")
		(net "GND")
	)
	(via
		(at 164.349938 -274.999958)
		(size 0.4064)
		(drill 0.2032)
		(layers "F.Cu" "B.Cu")
		(net "GND")
	)
	(via
		(at 174.700946 -31.390336)
		(size 0.508)
		(drill 0.254)
		(layers "F.Cu" "B.Cu")
		(net "GND")
	)
	(via
		(at 221.6658 -207.42021)
		(size 0.508)
		(drill 0.254)
		(layers "F.Cu" "B.Cu")
		(net "GND")
	)
	(via
		(at 54.899814 -317.749936)
		(size 0.4064)
		(drill 0.2032)
		(layers "F.Cu" "B.Cu")
		(net "GND")
	)
	(via
		(at 228.667818 -217.904314)
		(size 0.4572)
		(drill 0.254)
		(layers "F.Cu" "B.Cu")
		(net "GND")
	)
	(via
		(at 186.675014 -300.174914)
		(size 0.4064)
		(drill 0.2032)
		(layers "F.Cu" "B.Cu")
		(net "GND")
	)
	(via
		(at 286.624776 -289.724846)
		(size 0.4064)
		(drill 0.2032)
		(layers "F.Cu" "B.Cu")
		(net "GND")
	)
	(via
		(at 356.791006 -231.367838)
		(size 0.508)
		(drill 0.254)
		(layers "F.Cu" "B.Cu")
		(net "GND")
	)
	(via
		(at 100.834444 -71.451978)
		(size 0.508)
		(drill 0.254)
		(layers "F.Cu" "B.Cu")
		(net "GND")
	)
	(via
		(at 15.299182 -132.538216)
		(size 0.508)
		(drill 0.254)
		(layers "F.Cu" "B.Cu")
		(net "GND")
	)
	(via
		(at 48.3743 -341.781638)
		(size 0.4572)
		(drill 0.254)
		(layers "F.Cu" "B.Cu")
		(net "GND")
	)
	(via
		(at 42.28084 -34.990024)
		(size 0.508)
		(drill 0.254)
		(layers "F.Cu" "B.Cu")
		(net "GND")
	)
	(via
		(at 185.803794 -99.187)
		(size 0.508)
		(drill 0.254)
		(layers "F.Cu" "B.Cu")
		(net "GND")
	)
	(via
		(at 291.023294 -82.333592)
		(size 0.508)
		(drill 0.254)
		(layers "F.Cu" "B.Cu")
		(net "GND")
	)
	(via
		(at 386.701792 -125.692154)
		(size 0.508)
		(drill 0.254)
		(layers "F.Cu" "B.Cu")
		(net "GND")
	)
	(via
		(at 428.37481 -300.174914)
		(size 0.4064)
		(drill 0.2032)
		(layers "F.Cu" "B.Cu")
		(net "GND")
	)
	(via
		(at 283.299916 -318.699896)
		(size 0.4064)
		(drill 0.2032)
		(layers "F.Cu" "B.Cu")
		(net "GND")
	)
	(via
		(at 93.639894 -300.392846)
		(size 0.508)
		(drill 0.254)
		(layers "F.Cu" "B.Cu")
		(net "GND")
	)
	(via
		(at 353.141788 -268.731492)
		(size 0.508)
		(drill 0.254)
		(layers "F.Cu" "B.Cu")
		(net "GND")
	)
	(via
		(at 137.099802 -186.460638)
		(size 0.508)
		(drill 0.254)
		(layers "F.Cu" "B.Cu")
		(net "GND")
	)
	(via
		(at 231.867456 -221.103952)
		(size 0.4572)
		(drill 0.254)
		(layers "F.Cu" "B.Cu")
		(net "GND")
	)
	(via
		(at 429.010064 -346.09913)
		(size 0.4572)
		(drill 0.254)
		(layers "F.Cu" "B.Cu")
		(net "GND")
	)
	(via
		(at 392.749786 -301.599854)
		(size 0.4064)
		(drill 0.2032)
		(layers "F.Cu" "B.Cu")
		(net "GND")
	)
	(via
		(at 37.133784 -100.375466)
		(size 0.508)
		(drill 0.254)
		(layers "F.Cu" "B.Cu")
		(net "GND")
	)
	(via
		(at 355.146864 -1.135126)
		(size 0.508)
		(drill 0.254)
		(layers "F.Cu" "B.Cu")
		(net "GND")
	)
	(via
		(at 160.669986 -25.832054)
		(size 0.508)
		(drill 0.254)
		(layers "F.Cu" "B.Cu")
		(net "GND")
	)
	(via
		(at 200.700894 -34.990278)
		(size 0.508)
		(drill 0.254)
		(layers "F.Cu" "B.Cu")
		(net "GND")
	)
	(via
		(at 34.308288 -345.465146)
		(size 0.4064)
		(drill 0.2032)
		(layers "F.Cu" "B.Cu")
		(net "GND")
	)
	(via
		(at 401.78736 -109.644942)
		(size 0.508)
		(drill 0.254)
		(layers "F.Cu" "B.Cu")
		(net "GND")
	)
	(via
		(at 311.324752 -310.624728)
		(size 0.4064)
		(drill 0.2032)
		(layers "F.Cu" "B.Cu")
		(net "GND")
	)
	(via
		(at 103.764842 -338.573618)
		(size 0.4572)
		(drill 0.254)
		(layers "F.Cu" "B.Cu")
		(net "GND")
	)
	(via
		(at 287.557718 -25.971246)
		(size 0.508)
		(drill 0.254)
		(layers "F.Cu" "B.Cu")
		(net "GND")
	)
	(via
		(at 327.95591 -100.392992)
		(size 0.508)
		(drill 0.254)
		(layers "F.Cu" "B.Cu")
		(net "GND")
	)
	(via
		(at 106.747564 -160.385252)
		(size 0.508)
		(drill 0.254)
		(layers "F.Cu" "B.Cu")
		(net "GND")
	)
	(via
		(at 453.213724 -234.848654)
		(size 0.508)
		(drill 0.254)
		(layers "F.Cu" "B.Cu")
		(net "GND")
	)
	(via
		(at 419.349682 -272.14957)
		(size 0.4064)
		(drill 0.2032)
		(layers "F.Cu" "B.Cu")
		(net "GND")
	)
	(via
		(at 434.327808 -378.83846)
		(size 0.508)
		(drill 0.254)
		(layers "F.Cu" "B.Cu")
		(net "GND")
	)
	(via
		(at 279.499822 -276.899878)
		(size 0.4064)
		(drill 0.2032)
		(layers "F.Cu" "B.Cu")
		(net "GND")
	)
	(via
		(at 397.95196 -118.754906)
		(size 0.508)
		(drill 0.254)
		(layers "F.Cu" "B.Cu")
		(net "GND")
	)
	(via
		(at 370.881402 -29.859478)
		(size 0.508)
		(drill 0.254)
		(layers "F.Cu" "B.Cu")
		(net "GND")
	)
	(via
		(at 381.527812 -383.940304)
		(size 0.508)
		(drill 0.254)
		(layers "F.Cu" "B.Cu")
		(net "GND")
	)
	(via
		(at 279.422098 -52.51704)
		(size 0.508)
		(drill 0.254)
		(layers "F.Cu" "B.Cu")
		(net "GND")
	)
	(via
		(at 421.127682 -373.441976)
		(size 0.508)
		(drill 0.254)
		(layers "F.Cu" "B.Cu")
		(net "GND")
	)
	(via
		(at 71.049896 -314.899802)
		(size 0.4064)
		(drill 0.2032)
		(layers "F.Cu" "B.Cu")
		(net "GND")
	)
	(via
		(at 298.414694 -26.171398)
		(size 0.508)
		(drill 0.254)
		(layers "F.Cu" "B.Cu")
		(net "GND")
	)
	(via
		(at 333.539846 -73.23963)
		(size 0.508)
		(drill 0.254)
		(layers "F.Cu" "B.Cu")
		(net "GND")
	)
	(via
		(at 334.86725 -239.763554)
		(size 0.508)
		(drill 0.254)
		(layers "F.Cu" "B.Cu")
		(net "GND")
	)
	(via
		(at 430.274984 -289.724846)
		(size 0.4064)
		(drill 0.2032)
		(layers "F.Cu" "B.Cu")
		(net "GND")
	)
	(via
		(at 111.919766 -38.701218)
		(size 0.508)
		(drill 0.254)
		(layers "F.Cu" "B.Cu")
		(net "GND")
	)
	(via
		(at 374.493536 -295.933114)
		(size 0.508)
		(drill 0.254)
		(layers "F.Cu" "B.Cu")
		(net "GND")
	)
	(via
		(at 143.76908 -292.732714)
		(size 0.508)
		(drill 0.254)
		(layers "F.Cu" "B.Cu")
		(net "GND")
	)
	(via
		(at 407.599896 -62.812168)
		(size 0.508)
		(drill 0.254)
		(layers "F.Cu" "B.Cu")
		(net "GND")
	)
	(via
		(at 177.174906 -302.074834)
		(size 0.4064)
		(drill 0.2032)
		(layers "F.Cu" "B.Cu")
		(net "GND")
	)
	(via
		(at 372.642384 -253.45644)
		(size 0.508)
		(drill 0.254)
		(layers "F.Cu" "B.Cu")
		(net "GND")
	)
	(via
		(at 119.945404 -50.516282)
		(size 0.508)
		(drill 0.254)
		(layers "F.Cu" "B.Cu")
		(net "GND")
	)
	(via
		(at 82.449924 -315.849762)
		(size 0.4064)
		(drill 0.2032)
		(layers "F.Cu" "B.Cu")
		(net "GND")
	)
	(via
		(at 386.575046 -283.074872)
		(size 0.4064)
		(drill 0.2032)
		(layers "F.Cu" "B.Cu")
		(net "GND")
	)
	(via
		(at 377.208288 -357.123746)
		(size 0.4572)
		(drill 0.254)
		(layers "F.Cu" "B.Cu")
		(net "GND")
	)
	(via
		(at 409.849828 -274.999958)
		(size 0.4064)
		(drill 0.2032)
		(layers "F.Cu" "B.Cu")
		(net "GND")
	)
	(via
		(at 174.079662 -99.750372)
		(size 0.508)
		(drill 0.254)
		(layers "F.Cu" "B.Cu")
		(net "GND")
	)
	(via
		(at 455.383138 -279.19934)
		(size 0.508)
		(drill 0.254)
		(layers "F.Cu" "B.Cu")
		(net "GND")
	)
	(via
		(at 332.217776 -343.073482)
		(size 0.4572)
		(drill 0.254)
		(layers "F.Cu" "B.Cu")
		(net "GND")
	)
	(via
		(at 306.099718 -285.449772)
		(size 0.4064)
		(drill 0.2032)
		(layers "F.Cu" "B.Cu")
		(net "GND")
	)
	(via
		(at 303.724818 -298.27474)
		(size 0.4064)
		(drill 0.2032)
		(layers "F.Cu" "B.Cu")
		(net "GND")
	)
	(via
		(at 374.927876 -407.638504)
		(size 0.508)
		(drill 0.254)
		(layers "F.Cu" "B.Cu")
		(net "GND")
	)
	(via
		(at 289.94989 -315.849762)
		(size 0.4064)
		(drill 0.2032)
		(layers "F.Cu" "B.Cu")
		(net "GND")
	)
	(via
		(at 394.17498 -293.52494)
		(size 0.4064)
		(drill 0.2032)
		(layers "F.Cu" "B.Cu")
		(net "GND")
	)
	(via
		(at 138.166348 -348.58579)
		(size 0.4064)
		(drill 0.2032)
		(layers "F.Cu" "B.Cu")
		(net "GND")
	)
	(via
		(at 142.754096 -347.951806)
		(size 0.4572)
		(drill 0.254)
		(layers "F.Cu" "B.Cu")
		(net "GND")
	)
	(via
		(at 392.38174 -351.611438)
		(size 0.4064)
		(drill 0.2032)
		(layers "F.Cu" "B.Cu")
		(net "GND")
	)
	(via
		(at 418.874956 -287.824926)
		(size 0.4064)
		(drill 0.2032)
		(layers "F.Cu" "B.Cu")
		(net "GND")
	)
	(via
		(at 112.198658 -37.201094)
		(size 0.508)
		(drill 0.254)
		(layers "F.Cu" "B.Cu")
		(net "GND")
	)
	(via
		(at 170.806364 -100.64496)
		(size 0.508)
		(drill 0.254)
		(layers "F.Cu" "B.Cu")
		(net "GND")
	)
	(via
		(at 168.150032 -281.649932)
		(size 0.4064)
		(drill 0.2032)
		(layers "F.Cu" "B.Cu")
		(net "GND")
	)
	(via
		(at 113.677446 -307.877718)
		(size 0.508)
		(drill 0.254)
		(layers "F.Cu" "B.Cu")
		(net "GND")
	)
	(via
		(at 127.209296 -357.123746)
		(size 0.4572)
		(drill 0.254)
		(layers "F.Cu" "B.Cu")
		(net "GND")
	)
	(via
		(at 231.386634 -282.982162)
		(size 0.508)
		(drill 0.254)
		(layers "F.Cu" "B.Cu")
		(net "GND")
	)
	(via
		(at 286.040068 -33.857692)
		(size 0.508)
		(drill 0.254)
		(layers "F.Cu" "B.Cu")
		(net "GND")
	)
	(via
		(at 279.232868 -133.565138)
		(size 0.508)
		(drill 0.254)
		(layers "F.Cu" "B.Cu")
		(net "GND")
	)
	(via
		(at 280.449782 -274.999958)
		(size 0.4064)
		(drill 0.2032)
		(layers "F.Cu" "B.Cu")
		(net "GND")
	)
	(via
		(at 411.275022 -298.27474)
		(size 0.4064)
		(drill 0.2032)
		(layers "F.Cu" "B.Cu")
		(net "GND")
	)
	(via
		(at 277.599902 -274.049744)
		(size 0.4064)
		(drill 0.2032)
		(layers "F.Cu" "B.Cu")
		(net "GND")
	)
	(via
		(at 281.33548 -408.115008)
		(size 0.508)
		(drill 0.254)
		(layers "F.Cu" "B.Cu")
		(net "GND")
	)
	(via
		(at 51.099974 -281.649932)
		(size 0.4064)
		(drill 0.2032)
		(layers "F.Cu" "B.Cu")
		(net "GND")
	)
	(via
		(at 297.310302 -345.465146)
		(size 0.4064)
		(drill 0.2032)
		(layers "F.Cu" "B.Cu")
		(net "GND")
	)
	(via
		(at 39.224966 -293.52494)
		(size 0.4064)
		(drill 0.2032)
		(layers "F.Cu" "B.Cu")
		(net "GND")
	)
	(via
		(at 400.60118 -348.58579)
		(size 0.4064)
		(drill 0.2032)
		(layers "F.Cu" "B.Cu")
		(net "GND")
	)
	(via
		(at 176.224946 -284.974792)
		(size 0.4064)
		(drill 0.2032)
		(layers "F.Cu" "B.Cu")
		(net "GND")
	)
	(via
		(at 94.280736 -33.19018)
		(size 0.508)
		(drill 0.254)
		(layers "F.Cu" "B.Cu")
		(net "GND")
	)
	(via
		(at 346.327984 -372.240302)
		(size 0.508)
		(drill 0.254)
		(layers "F.Cu" "B.Cu")
		(net "GND")
	)
	(via
		(at 366.510824 -57.439814)
		(size 0.508)
		(drill 0.254)
		(layers "F.Cu" "B.Cu")
		(net "GND")
	)
	(via
		(at 385.624832 -289.724846)
		(size 0.4064)
		(drill 0.2032)
		(layers "F.Cu" "B.Cu")
		(net "GND")
	)
	(via
		(at 163.199064 -122.130312)
		(size 0.508)
		(drill 0.254)
		(layers "F.Cu" "B.Cu")
		(net "GND")
	)
	(via
		(at 304.50663 -253.620016)
		(size 0.508)
		(drill 0.254)
		(layers "F.Cu" "B.Cu")
		(net "GND")
	)
	(via
		(at 307.629306 -47.020734)
		(size 0.508)
		(drill 0.254)
		(layers "F.Cu" "B.Cu")
		(net "GND")
	)
	(via
		(at 161.617152 -351.611438)
		(size 0.4064)
		(drill 0.2032)
		(layers "F.Cu" "B.Cu")
		(net "GND")
	)
	(via
		(at 334.067912 -355.366066)
		(size 0.4572)
		(drill 0.254)
		(layers "F.Cu" "B.Cu")
		(net "GND")
	)
	(via
		(at 73.899776 -282.599892)
		(size 0.4064)
		(drill 0.2032)
		(layers "F.Cu" "B.Cu")
		(net "GND")
	)
	(via
		(at 135.057388 -345.465146)
		(size 0.4064)
		(drill 0.2032)
		(layers "F.Cu" "B.Cu")
		(net "GND")
	)
	(via
		(at 368.203226 -92.27566)
		(size 0.508)
		(drill 0.254)
		(layers "F.Cu" "B.Cu")
		(net "GND")
	)
	(via
		(at 381.527812 -382.73863)
		(size 0.508)
		(drill 0.254)
		(layers "F.Cu" "B.Cu")
		(net "GND")
	)
	(via
		(at 161.617152 -354.732082)
		(size 0.4064)
		(drill 0.2032)
		(layers "F.Cu" "B.Cu")
		(net "GND")
	)
	(via
		(at 177.174906 -293.52494)
		(size 0.4064)
		(drill 0.2032)
		(layers "F.Cu" "B.Cu")
		(net "GND")
	)
	(via
		(at 245.655592 -285.445962)
		(size 0.508)
		(drill 0.254)
		(layers "F.Cu" "B.Cu")
		(net "GND")
	)
	(via
		(at 375.358152 -354.074222)
		(size 0.4572)
		(drill 0.254)
		(layers "F.Cu" "B.Cu")
		(net "GND")
	)
	(via
		(at 447.58991 -73.85177)
		(size 0.508)
		(drill 0.254)
		(layers "F.Cu" "B.Cu")
		(net "GND")
	)
	(via
		(at 40.174926 -296.37482)
		(size 0.4064)
		(drill 0.2032)
		(layers "F.Cu" "B.Cu")
		(net "GND")
	)
	(via
		(at 48.24984 -311.099962)
		(size 0.4064)
		(drill 0.2032)
		(layers "F.Cu" "B.Cu")
		(net "GND")
	)
	(via
		(at 241.85118 -90.457274)
		(size 0.508)
		(drill 0.254)
		(layers "F.Cu" "B.Cu")
		(net "GND")
	)
	(via
		(at 188.490352 -348.58579)
		(size 0.4064)
		(drill 0.2032)
		(layers "F.Cu" "B.Cu")
		(net "GND")
	)
	(via
		(at 283.774896 -284.974792)
		(size 0.4064)
		(drill 0.2032)
		(layers "F.Cu" "B.Cu")
		(net "GND")
	)
	(via
		(at 307.999892 -305.399948)
		(size 0.4064)
		(drill 0.2032)
		(layers "F.Cu" "B.Cu")
		(net "GND")
	)
	(via
		(at 87.305134 -344.831162)
		(size 0.4572)
		(drill 0.254)
		(layers "F.Cu" "B.Cu")
		(net "GND")
	)
	(via
		(at 230.26751 -217.904314)
		(size 0.4572)
		(drill 0.254)
		(layers "F.Cu" "B.Cu")
		(net "GND")
	)
	(via
		(at 11.26871 -275.946616)
		(size 0.508)
		(drill 0.254)
		(layers "F.Cu" "B.Cu")
		(net "GND")
	)
	(via
		(at 300.399704 -313.949842)
		(size 0.4064)
		(drill 0.2032)
		(layers "F.Cu" "B.Cu")
		(net "GND")
	)
	(via
		(at 36.14801 -395.938502)
		(size 0.508)
		(drill 0.254)
		(layers "F.Cu" "B.Cu")
		(net "GND")
	)
	(via
		(at 284.191202 -168.397174)
		(size 0.508)
		(drill 0.254)
		(layers "F.Cu" "B.Cu")
		(net "GND")
	)
	(via
		(at 153.233628 -107.57535)
		(size 0.508)
		(drill 0.254)
		(layers "F.Cu" "B.Cu")
		(net "GND")
	)
	(via
		(at 133.845554 -177.658522)
		(size 0.508)
		(drill 0.254)
		(layers "F.Cu" "B.Cu")
		(net "GND")
	)
	(via
		(at 192.706752 -351.611438)
		(size 0.4064)
		(drill 0.2032)
		(layers "F.Cu" "B.Cu")
		(net "GND")
	)
	(via
		(at 387.482588 -246.65305)
		(size 0.508)
		(drill 0.254)
		(layers "F.Cu" "B.Cu")
		(net "GND")
	)
	(via
		(at 312.749692 -287.349946)
		(size 0.4064)
		(drill 0.2032)
		(layers "F.Cu" "B.Cu")
		(net "GND")
	)
	(via
		(at 374.927876 -406.141936)
		(size 0.508)
		(drill 0.254)
		(layers "F.Cu" "B.Cu")
		(net "GND")
	)
	(via
		(at 194.274948 -299.224954)
		(size 0.4064)
		(drill 0.2032)
		(layers "F.Cu" "B.Cu")
		(net "GND")
	)
	(via
		(at 84.54771 -371.140228)
		(size 0.508)
		(drill 0.254)
		(layers "F.Cu" "B.Cu")
		(net "GND")
	)
	(via
		(at 358.4956 -101.100128)
		(size 0.508)
		(drill 0.254)
		(layers "F.Cu" "B.Cu")
		(net "GND")
	)
	(via
		(at 236.535976 -182.999634)
		(size 0.508)
		(drill 0.254)
		(layers "F.Cu" "B.Cu")
		(net "GND")
	)
	(via
		(at 409.374848 -300.174914)
		(size 0.4064)
		(drill 0.2032)
		(layers "F.Cu" "B.Cu")
		(net "GND")
	)
	(via
		(at 328.781918 -58.238644)
		(size 0.508)
		(drill 0.254)
		(layers "F.Cu" "B.Cu")
		(net "GND")
	)
	(via
		(at 143.423386 -55.083456)
		(size 0.508)
		(drill 0.254)
		(layers "F.Cu" "B.Cu")
		(net "GND")
	)
	(via
		(at 341.544656 -355.366066)
		(size 0.4572)
		(drill 0.254)
		(layers "F.Cu" "B.Cu")
		(net "GND")
	)
	(via
		(at 417.94811 -142.15491)
		(size 0.508)
		(drill 0.254)
		(layers "F.Cu" "B.Cu")
		(net "GND")
	)
	(via
		(at 131.57708 -358.391714)
		(size 0.4572)
		(drill 0.254)
		(layers "F.Cu" "B.Cu")
		(net "GND")
	)
	(via
		(at 344.127836 -371.140228)
		(size 0.508)
		(drill 0.254)
		(layers "F.Cu" "B.Cu")
		(net "GND")
	)
	(via
		(at 328.83856 -23.880318)
		(size 0.508)
		(drill 0.254)
		(layers "F.Cu" "B.Cu")
		(net "GND")
	)
	(via
		(at 300.12767 -372.341902)
		(size 0.508)
		(drill 0.254)
		(layers "F.Cu" "B.Cu")
		(net "GND")
	)
	(via
		(at 386.701792 -103.975408)
		(size 0.508)
		(drill 0.254)
		(layers "F.Cu" "B.Cu")
		(net "GND")
	)
	(via
		(at 416.945572 -342.439498)
		(size 0.4064)
		(drill 0.2032)
		(layers "F.Cu" "B.Cu")
		(net "GND")
	)
	(via
		(at 187.598558 -65.15989)
		(size 0.508)
		(drill 0.254)
		(layers "F.Cu" "B.Cu")
		(net "GND")
	)
	(via
		(at 51.48326 -355.366066)
		(size 0.4572)
		(drill 0.254)
		(layers "F.Cu" "B.Cu")
		(net "GND")
	)
	(via
		(at 294.69969 -317.749936)
		(size 0.4064)
		(drill 0.2032)
		(layers "F.Cu" "B.Cu")
		(net "GND")
	)
	(via
		(at 64.28359 -341.805514)
		(size 0.4572)
		(drill 0.254)
		(layers "F.Cu" "B.Cu")
		(net "GND")
	)
	(via
		(at 242.578128 -278.233378)
		(size 0.508)
		(drill 0.254)
		(layers "F.Cu" "B.Cu")
		(net "GND")
	)
	(via
		(at 346.465906 -90.341958)
		(size 0.508)
		(drill 0.254)
		(layers "F.Cu" "B.Cu")
		(net "GND")
	)
	(via
		(at 169.465244 -354.074222)
		(size 0.4572)
		(drill 0.254)
		(layers "F.Cu" "B.Cu")
		(net "GND")
	)
	(via
		(at 395.4907 -357.75773)
		(size 0.4064)
		(drill 0.2032)
		(layers "F.Cu" "B.Cu")
		(net "GND")
	)
	(via
		(at 69.744844 -143.655796)
		(size 0.508)
		(drill 0.254)
		(layers "F.Cu" "B.Cu")
		(net "GND")
	)
	(via
		(at 444.510668 -57.439814)
		(size 0.508)
		(drill 0.254)
		(layers "F.Cu" "B.Cu")
		(net "GND")
	)
	(via
		(at 124.147834 -397.140176)
		(size 0.4572)
		(drill 0.254)
		(layers "F.Cu" "B.Cu")
		(net "GND")
	)
	(via
		(at 389.737854 -74.624184)
		(size 0.508)
		(drill 0.254)
		(layers "F.Cu" "B.Cu")
		(net "GND")
	)
	(via
		(at 275.699728 -301.599854)
		(size 0.4064)
		(drill 0.2032)
		(layers "F.Cu" "B.Cu")
		(net "GND")
	)
	(via
		(at 74.248264 -118.234968)
		(size 0.508)
		(drill 0.254)
		(layers "F.Cu" "B.Cu")
		(net "GND")
	)
	(via
		(at 234.143296 -28.139136)
		(size 0.508)
		(drill 0.254)
		(layers "F.Cu" "B.Cu")
		(net "GND")
	)
	(via
		(at 296.793412 -147.555204)
		(size 0.508)
		(drill 0.254)
		(layers "F.Cu" "B.Cu")
		(net "GND")
	)
	(via
		(at 296.793412 -154.755088)
		(size 0.508)
		(drill 0.254)
		(layers "F.Cu" "B.Cu")
		(net "GND")
	)
	(via
		(at 33.947862 -404.838662)
		(size 0.508)
		(drill 0.254)
		(layers "F.Cu" "B.Cu")
		(net "GND")
	)
	(via
		(at 290.89985 -313.949842)
		(size 0.4064)
		(drill 0.2032)
		(layers "F.Cu" "B.Cu")
		(net "GND")
	)
	(via
		(at 434.057806 -302.062134)
		(size 0.508)
		(drill 0.254)
		(layers "F.Cu" "B.Cu")
		(net "GND")
	)
	(via
		(at 239.22863 -70.857872)
		(size 0.508)
		(drill 0.254)
		(layers "F.Cu" "B.Cu")
		(net "GND")
	)
	(via
		(at 466.835998 -333.563976)
		(size 0.508)
		(drill 0.254)
		(layers "F.Cu" "B.Cu")
		(net "GND")
	)
	(via
		(at 382.30302 -293.494714)
		(size 0.508)
		(drill 0.254)
		(layers "F.Cu" "B.Cu")
		(net "GND")
	)
	(via
		(at 262.827008 -256.375916)
		(size 0.508)
		(drill 0.254)
		(layers "F.Cu" "B.Cu")
		(net "GND")
	)
	(via
		(at 421.249856 -275.949918)
		(size 0.4064)
		(drill 0.2032)
		(layers "F.Cu" "B.Cu")
		(net "GND")
	)
	(via
		(at 75.240642 -354.732082)
		(size 0.4064)
		(drill 0.2032)
		(layers "F.Cu" "B.Cu")
		(net "GND")
	)
	(via
		(at 28.406344 -253.45644)
		(size 0.508)
		(drill 0.254)
		(layers "F.Cu" "B.Cu")
		(net "GND")
	)
	(via
		(at 280.924762 -303.974754)
		(size 0.4064)
		(drill 0.2032)
		(layers "F.Cu" "B.Cu")
		(net "GND")
	)
	(via
		(at 78.17485 -301.124874)
		(size 0.4064)
		(drill 0.2032)
		(layers "F.Cu" "B.Cu")
		(net "GND")
	)
	(via
		(at 165.774878 -284.024832)
		(size 0.4064)
		(drill 0.2032)
		(layers "F.Cu" "B.Cu")
		(net "GND")
	)
	(via
		(at 370.260372 -21.37156)
		(size 0.508)
		(drill 0.254)
		(layers "F.Cu" "B.Cu")
		(net "GND")
	)
	(via
		(at 399.874994 -291.624766)
		(size 0.4064)
		(drill 0.2032)
		(layers "F.Cu" "B.Cu")
		(net "GND")
	)
	(via
		(at 285.674816 -294.4749)
		(size 0.4064)
		(drill 0.2032)
		(layers "F.Cu" "B.Cu")
		(net "GND")
	)
	(via
		(at 255.540002 -73.23963)
		(size 0.508)
		(drill 0.254)
		(layers "F.Cu" "B.Cu")
		(net "GND")
	)
	(via
		(at 154.850084 -312.049922)
		(size 0.4064)
		(drill 0.2032)
		(layers "F.Cu" "B.Cu")
		(net "GND")
	)
	(via
		(at 102.369366 -350.447864)
		(size 0.508)
		(drill 0.254)
		(layers "F.Cu" "B.Cu")
		(net "GND")
	)
	(via
		(at 416.574224 -346.09913)
		(size 0.4572)
		(drill 0.254)
		(layers "F.Cu" "B.Cu")
		(net "GND")
	)
	(via
		(at 340.093808 -217.187018)
		(size 0.4572)
		(drill 0.254)
		(layers "F.Cu" "B.Cu")
		(net "GND")
	)
	(via
		(at 18.288 -417.82492)
		(size 0.508)
		(drill 0.254)
		(layers "F.Cu" "B.Cu")
		(net "GND")
	)
	(via
		(at 300.12767 -398.34185)
		(size 0.508)
		(drill 0.254)
		(layers "F.Cu" "B.Cu")
		(net "GND")
	)
	(via
		(at 301.824898 -284.974792)
		(size 0.4064)
		(drill 0.2032)
		(layers "F.Cu" "B.Cu")
		(net "GND")
	)
	(via
		(at 79.59979 -285.449772)
		(size 0.4064)
		(drill 0.2032)
		(layers "F.Cu" "B.Cu")
		(net "GND")
	)
	(via
		(at 364.888018 -184.793128)
		(size 0.508)
		(drill 0.254)
		(layers "F.Cu" "B.Cu")
		(net "GND")
	)
	(via
		(at 408.899868 -313.949842)
		(size 0.4064)
		(drill 0.2032)
		(layers "F.Cu" "B.Cu")
		(net "GND")
	)
	(via
		(at 339.914484 -345.465146)
		(size 0.4064)
		(drill 0.2032)
		(layers "F.Cu" "B.Cu")
		(net "GND")
	)
	(via
		(at 170.347894 -380.040134)
		(size 0.508)
		(drill 0.254)
		(layers "F.Cu" "B.Cu")
		(net "GND")
	)
	(via
		(at 28.672028 -49.574704)
		(size 0.508)
		(drill 0.254)
		(layers "F.Cu" "B.Cu")
		(net "GND")
	)
	(via
		(at 74.869294 -357.123746)
		(size 0.4572)
		(drill 0.254)
		(layers "F.Cu" "B.Cu")
		(net "GND")
	)
	(via
		(at 167.732964 -152.96007)
		(size 0.508)
		(drill 0.254)
		(layers "F.Cu" "B.Cu")
		(net "GND")
	)
	(via
		(at 166.727632 -342.439498)
		(size 0.4064)
		(drill 0.2032)
		(layers "F.Cu" "B.Cu")
		(net "GND")
	)
	(via
		(at 49.853088 -354.732082)
		(size 0.4064)
		(drill 0.2032)
		(layers "F.Cu" "B.Cu")
		(net "GND")
	)
	(via
		(at 195.699888 -314.899802)
		(size 0.4064)
		(drill 0.2032)
		(layers "F.Cu" "B.Cu")
		(net "GND")
	)
	(via
		(at 185.250074 -315.849762)
		(size 0.4064)
		(drill 0.2032)
		(layers "F.Cu" "B.Cu")
		(net "GND")
	)
	(via
		(at 66.44767 -118.234968)
		(size 0.508)
		(drill 0.254)
		(layers "F.Cu" "B.Cu")
		(net "GND")
	)
	(via
		(at 132.481574 -133.972046)
		(size 0.508)
		(drill 0.254)
		(layers "F.Cu" "B.Cu")
		(net "GND")
	)
	(via
		(at 184.658 -56.809894)
		(size 0.508)
		(drill 0.254)
		(layers "F.Cu" "B.Cu")
		(net "GND")
	)
	(via
		(at 140.305536 -193.774568)
		(size 0.508)
		(drill 0.254)
		(layers "F.Cu" "B.Cu")
		(net "GND")
	)
	(via
		(at 4.248912 -27.40914)
		(size 0.508)
		(drill 0.254)
		(layers "F.Cu" "B.Cu")
		(net "GND")
	)
	(via
		(at 178.599846 -277.849838)
		(size 0.4064)
		(drill 0.2032)
		(layers "F.Cu" "B.Cu")
		(net "GND")
	)
	(via
		(at 341.927942 -402.140166)
		(size 0.508)
		(drill 0.254)
		(layers "F.Cu" "B.Cu")
		(net "GND")
	)
	(via
		(at 45.39996 -278.799798)
		(size 0.4064)
		(drill 0.2032)
		(layers "F.Cu" "B.Cu")
		(net "GND")
	)
	(via
		(at 331.002132 -94.244922)
		(size 0.508)
		(drill 0.254)
		(layers "F.Cu" "B.Cu")
		(net "GND")
	)
	(via
		(at 42.15638 -344.831162)
		(size 0.4572)
		(drill 0.254)
		(layers "F.Cu" "B.Cu")
		(net "GND")
	)
	(via
		(at 5.888736 -36.760912)
		(size 0.508)
		(drill 0.254)
		(layers "F.Cu" "B.Cu")
		(net "GND")
	)
	(via
		(at 331.489812 -73.85177)
		(size 0.508)
		(drill 0.254)
		(layers "F.Cu" "B.Cu")
		(net "GND")
	)
	(via
		(at 347.208602 -284.333188)
		(size 0.49022)
		(drill 0.254)
		(layers "F.Cu" "B.Cu")
		(net "GND")
	)
	(via
		(at 93.523054 -346.09913)
		(size 0.4572)
		(drill 0.254)
		(layers "F.Cu" "B.Cu")
		(net "GND")
	)
	(via
		(at 286.906462 -100.64496)
		(size 0.508)
		(drill 0.254)
		(layers "F.Cu" "B.Cu")
		(net "GND")
	)
	(via
		(at 190.950088 -314.899802)
		(size 0.4064)
		(drill 0.2032)
		(layers "F.Cu" "B.Cu")
		(net "GND")
	)
	(via
		(at 67.021202 -345.465146)
		(size 0.4064)
		(drill 0.2032)
		(layers "F.Cu" "B.Cu")
		(net "GND")
	)
	(via
		(at 305.624738 -294.4749)
		(size 0.4064)
		(drill 0.2032)
		(layers "F.Cu" "B.Cu")
		(net "GND")
	)
	(via
		(at 90.753438 -302.948086)
		(size 0.508)
		(drill 0.254)
		(layers "F.Cu" "B.Cu")
		(net "GND")
	)
	(via
		(at 154.375104 -283.074872)
		(size 0.4064)
		(drill 0.2032)
		(layers "F.Cu" "B.Cu")
		(net "GND")
	)
	(via
		(at 52.85232 -122.354848)
		(size 0.508)
		(drill 0.254)
		(layers "F.Cu" "B.Cu")
		(net "GND")
	)
	(via
		(at 429.381412 -354.732082)
		(size 0.4064)
		(drill 0.2032)
		(layers "F.Cu" "B.Cu")
		(net "GND")
	)
	(via
		(at 37.788596 -352.245422)
		(size 0.4572)
		(drill 0.254)
		(layers "F.Cu" "B.Cu")
		(net "GND")
	)
	(via
		(at 397.97482 -306.824888)
		(size 0.4064)
		(drill 0.2032)
		(layers "F.Cu" "B.Cu")
		(net "GND")
	)
	(via
		(at 77.978254 -358.391714)
		(size 0.4572)
		(drill 0.254)
		(layers "F.Cu" "B.Cu")
		(net "GND")
	)
	(via
		(at 122.830336 -95.46336)
		(size 0.508)
		(drill 0.254)
		(layers "F.Cu" "B.Cu")
		(net "GND")
	)
	(via
		(at 191.599312 -351.611438)
		(size 0.4064)
		(drill 0.2032)
		(layers "F.Cu" "B.Cu")
		(net "GND")
	)
	(via
		(at 401.615148 -43.85691)
		(size 0.508)
		(drill 0.254)
		(layers "F.Cu" "B.Cu")
		(net "GND")
	)
	(via
		(at 269.184628 -151.045672)
		(size 0.508)
		(drill 0.254)
		(layers "F.Cu" "B.Cu")
		(net "GND")
	)
	(via
		(at 229.09276 -312.394346)
		(size 0.508)
		(drill 0.254)
		(layers "F.Cu" "B.Cu")
		(net "GND")
	)
	(via
		(at 208.348834 -33.19018)
		(size 0.508)
		(drill 0.254)
		(layers "F.Cu" "B.Cu")
		(net "GND")
	)
	(via
		(at 364.47095 -306.607718)
		(size 0.508)
		(drill 0.254)
		(layers "F.Cu" "B.Cu")
		(net "GND")
	)
	(via
		(at 115.34775 -373.83847)
		(size 0.508)
		(drill 0.254)
		(layers "F.Cu" "B.Cu")
		(net "GND")
	)
	(via
		(at 185.24982 -272.14957)
		(size 0.4064)
		(drill 0.2032)
		(layers "F.Cu" "B.Cu")
		(net "GND")
	)
	(via
		(at 405.882348 -37.087048)
		(size 0.508)
		(drill 0.254)
		(layers "F.Cu" "B.Cu")
		(net "GND")
	)
	(via
		(at 122.65787 -140.392404)
		(size 0.508)
		(drill 0.254)
		(layers "F.Cu" "B.Cu")
		(net "GND")
	)
	(via
		(at 452.013574 -310.4388)
		(size 0.508)
		(drill 0.254)
		(layers "F.Cu" "B.Cu")
		(net "GND")
	)
	(via
		(at 379.327918 -369.938554)
		(size 0.508)
		(drill 0.254)
		(layers "F.Cu" "B.Cu")
		(net "GND")
	)
	(via
		(at 175.749966 -276.899878)
		(size 0.4064)
		(drill 0.2032)
		(layers "F.Cu" "B.Cu")
		(net "GND")
	)
	(via
		(at 166.725092 -300.174914)
		(size 0.4064)
		(drill 0.2032)
		(layers "F.Cu" "B.Cu")
		(net "GND")
	)
	(via
		(at 355.831648 -150.16861)
		(size 0.508)
		(drill 0.254)
		(layers "F.Cu" "B.Cu")
		(net "GND")
	)
	(via
		(at 164.060378 -19.33956)
		(size 0.508)
		(drill 0.254)
		(layers "F.Cu" "B.Cu")
		(net "GND")
	)
	(via
		(at 281.765502 -357.75773)
		(size 0.4064)
		(drill 0.2032)
		(layers "F.Cu" "B.Cu")
		(net "GND")
	)
	(via
		(at 370.990368 -352.245422)
		(size 0.4572)
		(drill 0.254)
		(layers "F.Cu" "B.Cu")
		(net "GND")
	)
	(via
		(at 301.349918 -281.649932)
		(size 0.4064)
		(drill 0.2032)
		(layers "F.Cu" "B.Cu")
		(net "GND")
	)
	(via
		(at 67.312794 -104.240076)
		(size 0.508)
		(drill 0.254)
		(layers "F.Cu" "B.Cu")
		(net "GND")
	)
	(via
		(at 76.27493 -290.674806)
		(size 0.4064)
		(drill 0.2032)
		(layers "F.Cu" "B.Cu")
		(net "GND")
	)
	(via
		(at 353.184968 -326.508364)
		(size 0.508)
		(drill 0.254)
		(layers "F.Cu" "B.Cu")
		(net "GND")
	)
	(via
		(at 49.340008 -73.87463)
		(size 0.508)
		(drill 0.254)
		(layers "F.Cu" "B.Cu")
		(net "GND")
	)
	(via
		(at 272.100802 -142.748762)
		(size 0.508)
		(drill 0.254)
		(layers "F.Cu" "B.Cu")
		(net "GND")
	)
	(via
		(at 283.833062 -107.844844)
		(size 0.508)
		(drill 0.254)
		(layers "F.Cu" "B.Cu")
		(net "GND")
	)
	(via
		(at 283.833062 -135.364982)
		(size 0.508)
		(drill 0.254)
		(layers "F.Cu" "B.Cu")
		(net "GND")
	)
	(via
		(at 286.624776 -283.074872)
		(size 0.4064)
		(drill 0.2032)
		(layers "F.Cu" "B.Cu")
		(net "GND")
	)
	(via
		(at 163.247324 -355.366066)
		(size 0.4572)
		(drill 0.254)
		(layers "F.Cu" "B.Cu")
		(net "GND")
	)
	(via
		(at 405.575008 -305.874928)
		(size 0.4064)
		(drill 0.2032)
		(layers "F.Cu" "B.Cu")
		(net "GND")
	)
	(via
		(at 84.196174 -355.366066)
		(size 0.4572)
		(drill 0.254)
		(layers "F.Cu" "B.Cu")
		(net "GND")
	)
	(via
		(at 380.317248 -344.831162)
		(size 0.4572)
		(drill 0.254)
		(layers "F.Cu" "B.Cu")
		(net "GND")
	)
	(via
		(at 97.939098 -32.911796)
		(size 0.508)
		(drill 0.254)
		(layers "F.Cu" "B.Cu")
		(net "GND")
	)
	(via
		(at 301.349918 -310.149748)
		(size 0.4064)
		(drill 0.2032)
		(layers "F.Cu" "B.Cu")
		(net "GND")
	)
	(via
		(at 364.847632 -331.079348)
		(size 0.508)
		(drill 0.254)
		(layers "F.Cu" "B.Cu")
		(net "GND")
	)
	(via
		(at 296.124884 -289.724846)
		(size 0.4064)
		(drill 0.2032)
		(layers "F.Cu" "B.Cu")
		(net "GND")
	)
	(via
		(at 281.399742 -318.699896)
		(size 0.4064)
		(drill 0.2032)
		(layers "F.Cu" "B.Cu")
		(net "GND")
	)
	(via
		(at 393.351766 -124.154946)
		(size 0.508)
		(drill 0.254)
		(layers "F.Cu" "B.Cu")
		(net "GND")
	)
	(via
		(at 136.536176 -344.831162)
		(size 0.4572)
		(drill 0.254)
		(layers "F.Cu" "B.Cu")
		(net "GND")
	)
	(via
		(at 174.800006 -281.649932)
		(size 0.4064)
		(drill 0.2032)
		(layers "F.Cu" "B.Cu")
		(net "GND")
	)
	(via
		(at 255.907032 -0.762)
		(size 0.508)
		(drill 0.254)
		(layers "F.Cu" "B.Cu")
		(net "GND")
	)
	(via
		(at 66.44767 -121.835164)
		(size 0.508)
		(drill 0.254)
		(layers "F.Cu" "B.Cu")
		(net "GND")
	)
	(via
		(at 121.947686 -380.040134)
		(size 0.4572)
		(drill 0.254)
		(layers "F.Cu" "B.Cu")
		(net "GND")
	)
	(via
		(at 390.327896 -403.34184)
		(size 0.508)
		(drill 0.254)
		(layers "F.Cu" "B.Cu")
		(net "GND")
	)
	(via
		(at 172.547788 -406.141936)
		(size 0.508)
		(drill 0.254)
		(layers "F.Cu" "B.Cu")
		(net "GND")
	)
	(via
		(at 231.159304 -77.430122)
		(size 0.508)
		(drill 0.254)
		(layers "F.Cu" "B.Cu")
		(net "GND")
	)
	(via
		(at 276.320504 -63.218314)
		(size 0.508)
		(drill 0.254)
		(layers "F.Cu" "B.Cu")
		(net "GND")
	)
	(via
		(at 279.763982 -357.75773)
		(size 0.4064)
		(drill 0.2032)
		(layers "F.Cu" "B.Cu")
		(net "GND")
	)
	(via
		(at 324.741032 -343.073482)
		(size 0.4572)
		(drill 0.254)
		(layers "F.Cu" "B.Cu")
		(net "GND")
	)
	(via
		(at 391.799572 -57.439814)
		(size 0.508)
		(drill 0.254)
		(layers "F.Cu" "B.Cu")
		(net "GND")
	)
	(via
		(at 374.099328 -347.92793)
		(size 0.4572)
		(drill 0.254)
		(layers "F.Cu" "B.Cu")
		(net "GND")
	)
	(via
		(at 143.490442 -253.45644)
		(size 0.508)
		(drill 0.254)
		(layers "F.Cu" "B.Cu")
		(net "GND")
	)
	(via
		(at 313.09818 -154.476958)
		(size 0.508)
		(drill 0.254)
		(layers "F.Cu" "B.Cu")
		(net "GND")
	)
	(via
		(at 164.349938 -314.899802)
		(size 0.4064)
		(drill 0.2032)
		(layers "F.Cu" "B.Cu")
		(net "GND")
	)
	(via
		(at 293.74973 -314.899802)
		(size 0.4064)
		(drill 0.2032)
		(layers "F.Cu" "B.Cu")
		(net "GND")
	)
	(via
		(at 81.087214 -346.09913)
		(size 0.4572)
		(drill 0.254)
		(layers "F.Cu" "B.Cu")
		(net "GND")
	)
	(via
		(at 86.04631 -347.951806)
		(size 0.4572)
		(drill 0.254)
		(layers "F.Cu" "B.Cu")
		(net "GND")
	)
	(via
		(at 82.924904 -299.224954)
		(size 0.4064)
		(drill 0.2032)
		(layers "F.Cu" "B.Cu")
		(net "GND")
	)
	(via
		(at 426.94987 -316.799722)
		(size 0.4064)
		(drill 0.2032)
		(layers "F.Cu" "B.Cu")
		(net "GND")
	)
	(via
		(at 71.347838 -371.140228)
		(size 0.508)
		(drill 0.254)
		(layers "F.Cu" "B.Cu")
		(net "GND")
	)
	(via
		(at 313.09818 -153.218134)
		(size 0.508)
		(drill 0.254)
		(layers "F.Cu" "B.Cu")
		(net "GND")
	)
	(via
		(at 341.927942 -385.141978)
		(size 0.508)
		(drill 0.254)
		(layers "F.Cu" "B.Cu")
		(net "GND")
	)
	(via
		(at 440.18708 -341.805514)
		(size 0.4572)
		(drill 0.254)
		(layers "F.Cu" "B.Cu")
		(net "GND")
	)
	(via
		(at 150.59152 -108.123228)
		(size 0.508)
		(drill 0.254)
		(layers "F.Cu" "B.Cu")
		(net "GND")
	)
	(via
		(at 163.399978 -277.849838)
		(size 0.4064)
		(drill 0.2032)
		(layers "F.Cu" "B.Cu")
		(net "GND")
	)
	(via
		(at 147.752562 -238.990378)
		(size 0.508)
		(drill 0.254)
		(layers "F.Cu" "B.Cu")
		(net "GND")
	)
	(via
		(at 42.549826 -300.649894)
		(size 0.4064)
		(drill 0.2032)
		(layers "F.Cu" "B.Cu")
		(net "GND")
	)
	(via
		(at 431.505106 -143.470122)
		(size 0.508)
		(drill 0.254)
		(layers "F.Cu" "B.Cu")
		(net "GND")
	)
	(via
		(at 40.897556 -347.951806)
		(size 0.4572)
		(drill 0.254)
		(layers "F.Cu" "B.Cu")
		(net "GND")
	)
	(via
		(at 103.646986 -0.762)
		(size 0.508)
		(drill 0.254)
		(layers "F.Cu" "B.Cu")
		(net "GND")
	)
	(via
		(at 336.249264 -84.924138)
		(size 0.508)
		(drill 0.254)
		(layers "F.Cu" "B.Cu")
		(net "GND")
	)
	(via
		(at 364.580932 -25.990042)
		(size 0.508)
		(drill 0.254)
		(layers "F.Cu" "B.Cu")
		(net "GND")
	)
	(via
		(at 153.08453 -151.045672)
		(size 0.508)
		(drill 0.254)
		(layers "F.Cu" "B.Cu")
		(net "GND")
	)
	(via
		(at 276.649688 -314.899802)
		(size 0.4064)
		(drill 0.2032)
		(layers "F.Cu" "B.Cu")
		(net "GND")
	)
	(via
		(at 29.54782 -398.24025)
		(size 0.508)
		(drill 0.254)
		(layers "F.Cu" "B.Cu")
		(net "GND")
	)
	(via
		(at 170.806364 -131.76504)
		(size 0.508)
		(drill 0.254)
		(layers "F.Cu" "B.Cu")
		(net "GND")
	)
	(via
		(at 321.944746 -27.79014)
		(size 0.508)
		(drill 0.254)
		(layers "F.Cu" "B.Cu")
		(net "GND")
	)
	(via
		(at 397.49984 -274.049744)
		(size 0.4064)
		(drill 0.2032)
		(layers "F.Cu" "B.Cu")
		(net "GND")
	)
	(via
		(at 180.975 -298.27474)
		(size 0.4064)
		(drill 0.2032)
		(layers "F.Cu" "B.Cu")
		(net "GND")
	)
	(via
		(at 38.275006 -283.074872)
		(size 0.4064)
		(drill 0.2032)
		(layers "F.Cu" "B.Cu")
		(net "GND")
	)
	(via
		(at 418.927788 -381.638556)
		(size 0.508)
		(drill 0.254)
		(layers "F.Cu" "B.Cu")
		(net "GND")
	)
	(via
		(at 183.82488 -300.174914)
		(size 0.4064)
		(drill 0.2032)
		(layers "F.Cu" "B.Cu")
		(net "GND")
	)
	(via
		(at 283.299916 -313.949842)
		(size 0.4064)
		(drill 0.2032)
		(layers "F.Cu" "B.Cu")
		(net "GND")
	)
	(via
		(at 394.17498 -287.824926)
		(size 0.4064)
		(drill 0.2032)
		(layers "F.Cu" "B.Cu")
		(net "GND")
	)
	(via
		(at 166.250112 -319.65011)
		(size 0.4064)
		(drill 0.2032)
		(layers "F.Cu" "B.Cu")
		(net "GND")
	)
	(via
		(at 255.031494 -71.325232)
		(size 0.508)
		(drill 0.254)
		(layers "F.Cu" "B.Cu")
		(net "GND")
	)
	(via
		(at 425.527724 -377.341892)
		(size 0.508)
		(drill 0.254)
		(layers "F.Cu" "B.Cu")
		(net "GND")
	)
	(via
		(at 162.450018 -315.849762)
		(size 0.4064)
		(drill 0.2032)
		(layers "F.Cu" "B.Cu")
		(net "GND")
	)
	(via
		(at 269.999714 -317.749936)
		(size 0.4064)
		(drill 0.2032)
		(layers "F.Cu" "B.Cu")
		(net "GND")
	)
	(via
		(at 409.49499 -60.633356)
		(size 0.508)
		(drill 0.254)
		(layers "F.Cu" "B.Cu")
		(net "GND")
	)
	(via
		(at 66.44767 -133.0452)
		(size 0.508)
		(drill 0.254)
		(layers "F.Cu" "B.Cu")
		(net "GND")
	)
	(via
		(at 300.874684 -305.874928)
		(size 0.4064)
		(drill 0.2032)
		(layers "F.Cu" "B.Cu")
		(net "GND")
	)
	(via
		(at 77.947774 -380.040134)
		(size 0.508)
		(drill 0.254)
		(layers "F.Cu" "B.Cu")
		(net "GND")
	)
	(via
		(at 334.067912 -343.073482)
		(size 0.4572)
		(drill 0.254)
		(layers "F.Cu" "B.Cu")
		(net "GND")
	)
	(via
		(at 269.524734 -277.374858)
		(size 0.4064)
		(drill 0.2032)
		(layers "F.Cu" "B.Cu")
		(net "GND")
	)
	(via
		(at 157.224984 -278.324818)
		(size 0.4064)
		(drill 0.2032)
		(layers "F.Cu" "B.Cu")
		(net "GND")
	)
	(via
		(at 128.46812 -350.977454)
		(size 0.4572)
		(drill 0.254)
		(layers "F.Cu" "B.Cu")
		(net "GND")
	)
	(via
		(at 398.4498 -310.149748)
		(size 0.4064)
		(drill 0.2032)
		(layers "F.Cu" "B.Cu")
		(net "GND")
	)
	(via
		(at 152.94991 -301.599854)
		(size 0.4064)
		(drill 0.2032)
		(layers "F.Cu" "B.Cu")
		(net "GND")
	)
	(via
		(at 332.515718 -101.333046)
		(size 0.508)
		(drill 0.254)
		(layers "F.Cu" "B.Cu")
		(net "GND")
	)
	(via
		(at 349.570548 -28.802076)
		(size 0.508)
		(drill 0.254)
		(layers "F.Cu" "B.Cu")
		(net "GND")
	)
	(via
		(at 39.224966 -296.37482)
		(size 0.4064)
		(drill 0.2032)
		(layers "F.Cu" "B.Cu")
		(net "GND")
	)
	(via
		(at 374.41505 -233.82605)
		(size 0.508)
		(drill 0.254)
		(layers "F.Cu" "B.Cu")
		(net "GND")
	)
	(via
		(at 52.049934 -315.849762)
		(size 0.4064)
		(drill 0.2032)
		(layers "F.Cu" "B.Cu")
		(net "GND")
	)
	(via
		(at 134.771384 -29.311854)
		(size 0.508)
		(drill 0.254)
		(layers "F.Cu" "B.Cu")
		(net "GND")
	)
	(via
		(at 137.795 -347.951806)
		(size 0.4572)
		(drill 0.254)
		(layers "F.Cu" "B.Cu")
		(net "GND")
	)
	(via
		(at 47.96028 -19.33956)
		(size 0.508)
		(drill 0.254)
		(layers "F.Cu" "B.Cu")
		(net "GND")
	)
	(via
		(at 376.243342 -28.139136)
		(size 0.508)
		(drill 0.254)
		(layers "F.Cu" "B.Cu")
		(net "GND")
	)
	(via
		(at 293.25189 -13.613638)
		(size 0.508)
		(drill 0.254)
		(layers "F.Cu" "B.Cu")
		(net "GND")
	)
	(via
		(at 278.285194 -349.219774)
		(size 0.4572)
		(drill 0.254)
		(layers "F.Cu" "B.Cu")
		(net "GND")
	)
	(via
		(at 115.34775 -375.040144)
		(size 0.4572)
		(drill 0.254)
		(layers "F.Cu" "B.Cu")
		(net "GND")
	)
	(via
		(at 392.274806 -297.32478)
		(size 0.4064)
		(drill 0.2032)
		(layers "F.Cu" "B.Cu")
		(net "GND")
	)
	(via
		(at 115.638326 -284.333188)
		(size 0.49022)
		(drill 0.254)
		(layers "F.Cu" "B.Cu")
		(net "GND")
	)
	(via
		(at 303.249838 -316.799722)
		(size 0.4064)
		(drill 0.2032)
		(layers "F.Cu" "B.Cu")
		(net "GND")
	)
	(via
		(at 183.766714 -116.435124)
		(size 0.508)
		(drill 0.254)
		(layers "F.Cu" "B.Cu")
		(net "GND")
	)
	(via
		(at 36.309808 -345.465146)
		(size 0.4064)
		(drill 0.2032)
		(layers "F.Cu" "B.Cu")
		(net "GND")
	)
	(via
		(at 259.69468 -305.613816)
		(size 0.508)
		(drill 0.254)
		(layers "F.Cu" "B.Cu")
		(net "GND")
	)
	(via
		(at 392.753088 -350.977454)
		(size 0.4572)
		(drill 0.254)
		(layers "F.Cu" "B.Cu")
		(net "GND")
	)
	(via
		(at 221.392496 -310.315356)
		(size 0.508)
		(drill 0.254)
		(layers "F.Cu" "B.Cu")
		(net "GND")
	)
	(via
		(at 295.727882 -404.940262)
		(size 0.508)
		(drill 0.254)
		(layers "F.Cu" "B.Cu")
		(net "GND")
	)
	(via
		(at 197.445884 -343.073482)
		(size 0.4572)
		(drill 0.254)
		(layers "F.Cu" "B.Cu")
		(net "GND")
	)
	(via
		(at 396.54988 -279.749758)
		(size 0.4064)
		(drill 0.2032)
		(layers "F.Cu" "B.Cu")
		(net "GND")
	)
	(via
		(at 132.658104 -58.156094)
		(size 0.508)
		(drill 0.254)
		(layers "F.Cu" "B.Cu")
		(net "GND")
	)
	(via
		(at 337.83778 -329.564492)
		(size 0.508)
		(drill 0.254)
		(layers "F.Cu" "B.Cu")
		(net "GND")
	)
	(via
		(at 1.537462 -274.65147)
		(size 0.508)
		(drill 0.254)
		(layers "F.Cu" "B.Cu")
		(net "GND")
	)
	(via
		(at 336.183986 -106.779822)
		(size 0.508)
		(drill 0.254)
		(layers "F.Cu" "B.Cu")
		(net "GND")
	)
	(via
		(at 73.424796 -297.32478)
		(size 0.4064)
		(drill 0.2032)
		(layers "F.Cu" "B.Cu")
		(net "GND")
	)
	(via
		(at 227.566982 -157.008322)
		(size 0.508)
		(drill 0.254)
		(layers "F.Cu" "B.Cu")
		(net "GND")
	)
	(via
		(at 466.827616 -46.932596)
		(size 0.508)
		(drill 0.254)
		(layers "F.Cu" "B.Cu")
		(net "GND")
	)
	(via
		(at 93.451426 -114.075972)
		(size 0.508)
		(drill 0.254)
		(layers "F.Cu" "B.Cu")
		(net "GND")
	)
	(via
		(at 365.922814 -23.880318)
		(size 0.508)
		(drill 0.254)
		(layers "F.Cu" "B.Cu")
		(net "GND")
	)
	(via
		(at 45.636688 -354.732082)
		(size 0.4064)
		(drill 0.2032)
		(layers "F.Cu" "B.Cu")
		(net "GND")
	)
	(via
		(at 269.99819 -20.417536)
		(size 0.508)
		(drill 0.254)
		(layers "F.Cu" "B.Cu")
		(net "GND")
	)
	(via
		(at 164.349938 -319.65011)
		(size 0.4064)
		(drill 0.2032)
		(layers "F.Cu" "B.Cu")
		(net "GND")
	)
	(via
		(at 64.454532 -110.497366)
		(size 0.508)
		(drill 0.254)
		(layers "F.Cu" "B.Cu")
		(net "GND")
	)
	(via
		(at 342.365838 -110.22965)
		(size 0.508)
		(drill 0.254)
		(layers "F.Cu" "B.Cu")
		(net "GND")
	)
	(via
		(at 312.305192 -347.951806)
		(size 0.4572)
		(drill 0.254)
		(layers "F.Cu" "B.Cu")
		(net "GND")
	)
	(via
		(at 322.890896 -358.391714)
		(size 0.4572)
		(drill 0.254)
		(layers "F.Cu" "B.Cu")
		(net "GND")
	)
	(via
		(at 46.8249 -285.924752)
		(size 0.4064)
		(drill 0.2032)
		(layers "F.Cu" "B.Cu")
		(net "GND")
	)
	(via
		(at 44.141136 -38.49116)
		(size 0.508)
		(drill 0.254)
		(layers "F.Cu" "B.Cu")
		(net "GND")
	)
	(via
		(at 176.94783 -369.938808)
		(size 0.508)
		(drill 0.254)
		(layers "F.Cu" "B.Cu")
		(net "GND")
	)
	(via
		(at 55.374794 -284.974792)
		(size 0.4064)
		(drill 0.2032)
		(layers "F.Cu" "B.Cu")
		(net "GND")
	)
	(via
		(at 382.997456 -114.4905)
		(size 0.508)
		(drill 0.254)
		(layers "F.Cu" "B.Cu")
		(net "GND")
	)
	(via
		(at 64.28359 -352.245422)
		(size 0.4572)
		(drill 0.254)
		(layers "F.Cu" "B.Cu")
		(net "GND")
	)
	(via
		(at 188.099954 -314.899802)
		(size 0.4064)
		(drill 0.2032)
		(layers "F.Cu" "B.Cu")
		(net "GND")
	)
	(via
		(at 109.050074 -291.32149)
		(size 0.508)
		(drill 0.254)
		(layers "F.Cu" "B.Cu")
		(net "GND")
	)
	(via
		(at 332.889606 -278.708612)
		(size 0.508)
		(drill 0.254)
		(layers "F.Cu" "B.Cu")
		(net "GND")
	)
	(via
		(at 220.805502 -174.875444)
		(size 0.508)
		(drill 0.254)
		(layers "F.Cu" "B.Cu")
		(net "GND")
	)
	(via
		(at 55.849774 -274.999958)
		(size 0.4064)
		(drill 0.2032)
		(layers "F.Cu" "B.Cu")
		(net "GND")
	)
	(via
		(at 174.800006 -310.149748)
		(size 0.4064)
		(drill 0.2032)
		(layers "F.Cu" "B.Cu")
		(net "GND")
	)
	(via
		(at 190.348108 -131.245102)
		(size 0.508)
		(drill 0.254)
		(layers "F.Cu" "B.Cu")
		(net "GND")
	)
	(via
		(at 294.12819 -200.950068)
		(size 0.508)
		(drill 0.254)
		(layers "F.Cu" "B.Cu")
		(net "GND")
	)
	(via
		(at 143.9672 -391.6172)
		(size 0.508)
		(drill 0.254)
		(layers "F.Cu" "B.Cu")
		(net "GND")
	)
	(via
		(at 143.423386 -51.019456)
		(size 0.508)
		(drill 0.254)
		(layers "F.Cu" "B.Cu")
		(net "GND")
	)
	(via
		(at 248.480834 -34.990024)
		(size 0.508)
		(drill 0.254)
		(layers "F.Cu" "B.Cu")
		(net "GND")
	)
	(via
		(at 110.691422 -87.817452)
		(size 0.508)
		(drill 0.254)
		(layers "F.Cu" "B.Cu")
		(net "GND")
	)
	(via
		(at 365.00308 -285.953454)
		(size 0.508)
		(drill 0.254)
		(layers "F.Cu" "B.Cu")
		(net "GND")
	)
	(via
		(at 358.648 -417.82492)
		(size 0.508)
		(drill 0.254)
		(layers "F.Cu" "B.Cu")
		(net "GND")
	)
	(via
		(at 79.59979 -278.799798)
		(size 0.4064)
		(drill 0.2032)
		(layers "F.Cu" "B.Cu")
		(net "GND")
	)
	(via
		(at 144.09166 -33.248092)
		(size 0.508)
		(drill 0.254)
		(layers "F.Cu" "B.Cu")
		(net "GND")
	)
	(via
		(at 174.42434 -354.098098)
		(size 0.4572)
		(drill 0.254)
		(layers "F.Cu" "B.Cu")
		(net "GND")
	)
	(via
		(at 105.00233 -353.075748)
		(size 0.508)
		(drill 0.254)
		(layers "F.Cu" "B.Cu")
		(net "GND")
	)
	(via
		(at 191.900048 -284.499812)
		(size 0.4064)
		(drill 0.2032)
		(layers "F.Cu" "B.Cu")
		(net "GND")
	)
	(via
		(at 140.90396 -355.366066)
		(size 0.4572)
		(drill 0.254)
		(layers "F.Cu" "B.Cu")
		(net "GND")
	)
	(via
		(at 229.041706 -277.201884)
		(size 0.508)
		(drill 0.254)
		(layers "F.Cu" "B.Cu")
		(net "GND")
	)
	(via
		(at 418.399976 -314.899802)
		(size 0.4064)
		(drill 0.2032)
		(layers "F.Cu" "B.Cu")
		(net "GND")
	)
	(via
		(at 243.998242 -19.096736)
		(size 0.508)
		(drill 0.254)
		(layers "F.Cu" "B.Cu")
		(net "GND")
	)
	(via
		(at 367.131346 -60.099194)
		(size 0.508)
		(drill 0.254)
		(layers "F.Cu" "B.Cu")
		(net "GND")
	)
	(via
		(at 375.358152 -352.245422)
		(size 0.4572)
		(drill 0.254)
		(layers "F.Cu" "B.Cu")
		(net "GND")
	)
	(via
		(at 42.28084 -27.79014)
		(size 0.508)
		(drill 0.254)
		(layers "F.Cu" "B.Cu")
		(net "GND")
	)
	(via
		(at 387.525006 -284.974792)
		(size 0.4064)
		(drill 0.2032)
		(layers "F.Cu" "B.Cu")
		(net "GND")
	)
	(via
		(at 431.700178 -308.249828)
		(size 0.4064)
		(drill 0.2032)
		(layers "F.Cu" "B.Cu")
		(net "GND")
	)
	(via
		(at 146.727164 -259.576316)
		(size 0.508)
		(drill 0.254)
		(layers "F.Cu" "B.Cu")
		(net "GND")
	)
	(via
		(at 177.649886 -274.999958)
		(size 0.4064)
		(drill 0.2032)
		(layers "F.Cu" "B.Cu")
		(net "GND")
	)
	(via
		(at 15.686786 -111.127032)
		(size 0.508)
		(drill 0.254)
		(layers "F.Cu" "B.Cu")
		(net "GND")
	)
	(via
		(at 296.793412 -145.755106)
		(size 0.508)
		(drill 0.254)
		(layers "F.Cu" "B.Cu")
		(net "GND")
	)
	(via
		(at 174.42434 -346.09913)
		(size 0.4572)
		(drill 0.254)
		(layers "F.Cu" "B.Cu")
		(net "GND")
	)
	(via
		(at 236.072172 -33.857692)
		(size 0.508)
		(drill 0.254)
		(layers "F.Cu" "B.Cu")
		(net "GND")
	)
	(via
		(at 463.475324 -274.61083)
		(size 0.508)
		(drill 0.254)
		(layers "F.Cu" "B.Cu")
		(net "GND")
	)
	(via
		(at 200.908158 -121.563384)
		(size 0.508)
		(drill 0.254)
		(layers "F.Cu" "B.Cu")
		(net "GND")
	)
	(via
		(at 71.999856 -274.049744)
		(size 0.4064)
		(drill 0.2032)
		(layers "F.Cu" "B.Cu")
		(net "GND")
	)
	(via
		(at 6.655054 -38.519354)
		(size 0.508)
		(drill 0.254)
		(layers "F.Cu" "B.Cu")
		(net "GND")
	)
	(via
		(at 249.629168 -113.606326)
		(size 0.508)
		(drill 0.254)
		(layers "F.Cu" "B.Cu")
		(net "GND")
	)
	(via
		(at 0.77089 -283.981144)
		(size 0.508)
		(drill 0.254)
		(layers "F.Cu" "B.Cu")
		(net "GND")
	)
	(via
		(at 285.369 -84.836)
		(size 0.508)
		(drill 0.254)
		(layers "F.Cu" "B.Cu")
		(net "GND")
	)
	(via
		(at 130.781044 -241.856006)
		(size 0.508)
		(drill 0.254)
		(layers "F.Cu" "B.Cu")
		(net "GND")
	)
	(via
		(at 227.693474 -135.659622)
		(size 0.508)
		(drill 0.254)
		(layers "F.Cu" "B.Cu")
		(net "GND")
	)
	(via
		(at 278.549862 -314.899802)
		(size 0.4064)
		(drill 0.2032)
		(layers "F.Cu" "B.Cu")
		(net "GND")
	)
	(via
		(at 341.916004 -345.465146)
		(size 0.4064)
		(drill 0.2032)
		(layers "F.Cu" "B.Cu")
		(net "GND")
	)
	(via
		(at 29.845254 -51.227482)
		(size 0.508)
		(drill 0.254)
		(layers "F.Cu" "B.Cu")
		(net "GND")
	)
	(via
		(at 44.94784 -410.041852)
		(size 0.508)
		(drill 0.254)
		(layers "F.Cu" "B.Cu")
		(net "GND")
	)
	(via
		(at 360.96448 -285.267654)
		(size 0.508)
		(drill 0.254)
		(layers "F.Cu" "B.Cu")
		(net "GND")
	)
	(via
		(at 401.78736 -102.444804)
		(size 0.508)
		(drill 0.254)
		(layers "F.Cu" "B.Cu")
		(net "GND")
	)
	(via
		(at 386.099812 -305.399948)
		(size 0.4064)
		(drill 0.2032)
		(layers "F.Cu" "B.Cu")
		(net "GND")
	)
	(via
		(at 79.59979 -314.899802)
		(size 0.4064)
		(drill 0.2032)
		(layers "F.Cu" "B.Cu")
		(net "GND")
	)
	(via
		(at 49.67478 -286.874966)
		(size 0.4064)
		(drill 0.2032)
		(layers "F.Cu" "B.Cu")
		(net "GND")
	)
	(via
		(at 189.999874 -277.849838)
		(size 0.4064)
		(drill 0.2032)
		(layers "F.Cu" "B.Cu")
		(net "GND")
	)
	(via
		(at 198.042022 -49.574704)
		(size 0.508)
		(drill 0.254)
		(layers "F.Cu" "B.Cu")
		(net "GND")
	)
	(via
		(at 420.567104 -142.15491)
		(size 0.508)
		(drill 0.254)
		(layers "F.Cu" "B.Cu")
		(net "GND")
	)
	(via
		(at 397.49222 -354.732082)
		(size 0.4064)
		(drill 0.2032)
		(layers "F.Cu" "B.Cu")
		(net "GND")
	)
	(via
		(at 31.78175 -92.050362)
		(size 0.508)
		(drill 0.254)
		(layers "F.Cu" "B.Cu")
		(net "GND")
	)
	(via
		(at 72.267064 -125.435106)
		(size 0.508)
		(drill 0.254)
		(layers "F.Cu" "B.Cu")
		(net "GND")
	)
	(via
		(at 173.375066 -297.32478)
		(size 0.4064)
		(drill 0.2032)
		(layers "F.Cu" "B.Cu")
		(net "GND")
	)
	(via
		(at 416.499802 -274.049744)
		(size 0.4064)
		(drill 0.2032)
		(layers "F.Cu" "B.Cu")
		(net "GND")
	)
	(via
		(at 77.69987 -285.449772)
		(size 0.4064)
		(drill 0.2032)
		(layers "F.Cu" "B.Cu")
		(net "GND")
	)
	(via
		(at 258.583176 -201.572368)
		(size 0.508)
		(drill 0.254)
		(layers "F.Cu" "B.Cu")
		(net "GND")
	)
	(via
		(at 156.275024 -292.574726)
		(size 0.4064)
		(drill 0.2032)
		(layers "F.Cu" "B.Cu")
		(net "GND")
	)
	(via
		(at 295.649904 -316.799722)
		(size 0.4064)
		(drill 0.2032)
		(layers "F.Cu" "B.Cu")
		(net "GND")
	)
	(via
		(at 298.974764 -300.174914)
		(size 0.4064)
		(drill 0.2032)
		(layers "F.Cu" "B.Cu")
		(net "GND")
	)
	(via
		(at 427.379892 -351.611438)
		(size 0.4064)
		(drill 0.2032)
		(layers "F.Cu" "B.Cu")
		(net "GND")
	)
	(via
		(at 374.927876 -377.738386)
		(size 0.508)
		(drill 0.254)
		(layers "F.Cu" "B.Cu")
		(net "GND")
	)
	(via
		(at 444.420498 -63.218314)
		(size 0.508)
		(drill 0.254)
		(layers "F.Cu" "B.Cu")
		(net "GND")
	)
	(via
		(at 416.580828 -29.589984)
		(size 0.508)
		(drill 0.254)
		(layers "F.Cu" "B.Cu")
		(net "GND")
	)
	(via
		(at 301.848012 -118.370858)
		(size 0.508)
		(drill 0.254)
		(layers "F.Cu" "B.Cu")
		(net "GND")
	)
	(via
		(at 196.649848 -310.149748)
		(size 0.4064)
		(drill 0.2032)
		(layers "F.Cu" "B.Cu")
		(net "GND")
	)
	(via
		(at 280.529792 -165.902894)
		(size 0.508)
		(drill 0.254)
		(layers "F.Cu" "B.Cu")
		(net "GND")
	)
	(via
		(at 184.77484 -298.27474)
		(size 0.4064)
		(drill 0.2032)
		(layers "F.Cu" "B.Cu")
		(net "GND")
	)
	(via
		(at 327.683368 -113.364772)
		(size 0.508)
		(drill 0.254)
		(layers "F.Cu" "B.Cu")
		(net "GND")
	)
	(via
		(at 238.266478 -35.871912)
		(size 0.508)
		(drill 0.254)
		(layers "F.Cu" "B.Cu")
		(net "GND")
	)
	(via
		(at 80.07477 -292.574726)
		(size 0.4064)
		(drill 0.2032)
		(layers "F.Cu" "B.Cu")
		(net "GND")
	)
	(via
		(at 278.549862 -312.049922)
		(size 0.4064)
		(drill 0.2032)
		(layers "F.Cu" "B.Cu")
		(net "GND")
	)
	(via
		(at 100.90023 -383.95656)
		(size 0.508)
		(drill 0.254)
		(layers "F.Cu" "B.Cu")
		(net "GND")
	)
	(via
		(at 68.674742 -290.674806)
		(size 0.4064)
		(drill 0.2032)
		(layers "F.Cu" "B.Cu")
		(net "GND")
	)
	(via
		(at 350.493584 -221.186756)
		(size 0.4572)
		(drill 0.254)
		(layers "F.Cu" "B.Cu")
		(net "GND")
	)
	(via
		(at 283.833062 -104.244902)
		(size 0.508)
		(drill 0.254)
		(layers "F.Cu" "B.Cu")
		(net "GND")
	)
	(via
		(at 273.324828 -294.4749)
		(size 0.4064)
		(drill 0.2032)
		(layers "F.Cu" "B.Cu")
		(net "GND")
	)
	(via
		(at 397.02486 -300.174914)
		(size 0.4064)
		(drill 0.2032)
		(layers "F.Cu" "B.Cu")
		(net "GND")
	)
	(via
		(at 73.239122 -342.439498)
		(size 0.4064)
		(drill 0.2032)
		(layers "F.Cu" "B.Cu")
		(net "GND")
	)
	(via
		(at 393.7 -309.199788)
		(size 0.4064)
		(drill 0.2032)
		(layers "F.Cu" "B.Cu")
		(net "GND")
	)
	(via
		(at 433.597812 -345.465146)
		(size 0.4064)
		(drill 0.2032)
		(layers "F.Cu" "B.Cu")
		(net "GND")
	)
	(via
		(at 313.09818 -134.566914)
		(size 0.508)
		(drill 0.254)
		(layers "F.Cu" "B.Cu")
		(net "GND")
	)
	(via
		(at 172.424852 -287.824926)
		(size 0.4064)
		(drill 0.2032)
		(layers "F.Cu" "B.Cu")
		(net "GND")
	)
	(via
		(at 84.54771 -404.940262)
		(size 0.508)
		(drill 0.254)
		(layers "F.Cu" "B.Cu")
		(net "GND")
	)
	(via
		(at 54.98211 -368.714274)
		(size 0.4572)
		(drill 0.254)
		(layers "F.Cu" "B.Cu")
		(net "GND")
	)
	(via
		(at 285.199836 -281.649932)
		(size 0.4064)
		(drill 0.2032)
		(layers "F.Cu" "B.Cu")
		(net "GND")
	)
	(via
		(at 74.581258 -33.459674)
		(size 0.508)
		(drill 0.254)
		(layers "F.Cu" "B.Cu")
		(net "GND")
	)
	(via
		(at 107.425236 -304.373534)
		(size 0.508)
		(drill 0.254)
		(layers "F.Cu" "B.Cu")
		(net "GND")
	)
	(via
		(at 441.817252 -357.75773)
		(size 0.4064)
		(drill 0.2032)
		(layers "F.Cu" "B.Cu")
		(net "GND")
	)
	(via
		(at 431.224944 -301.124874)
		(size 0.4064)
		(drill 0.2032)
		(layers "F.Cu" "B.Cu")
		(net "GND")
	)
	(via
		(at 74.248264 -116.435124)
		(size 0.508)
		(drill 0.254)
		(layers "F.Cu" "B.Cu")
		(net "GND")
	)
	(via
		(at 53.48732 -111.44504)
		(size 0.508)
		(drill 0.254)
		(layers "F.Cu" "B.Cu")
		(net "GND")
	)
	(via
		(at 119.747792 -408.840178)
		(size 0.4572)
		(drill 0.254)
		(layers "F.Cu" "B.Cu")
		(net "GND")
	)
	(via
		(at 191.900302 -274.049744)
		(size 0.4064)
		(drill 0.2032)
		(layers "F.Cu" "B.Cu")
		(net "GND")
	)
	(via
		(at 224.254314 -136.174988)
		(size 0.508)
		(drill 0.254)
		(layers "F.Cu" "B.Cu")
		(net "GND")
	)
	(via
		(at 170.944032 -348.58579)
		(size 0.4064)
		(drill 0.2032)
		(layers "F.Cu" "B.Cu")
		(net "GND")
	)
	(via
		(at 306.099718 -304.449734)
		(size 0.4064)
		(drill 0.2032)
		(layers "F.Cu" "B.Cu")
		(net "GND")
	)
	(via
		(at 64.399922 -313.949842)
		(size 0.4064)
		(drill 0.2032)
		(layers "F.Cu" "B.Cu")
		(net "GND")
	)
	(via
		(at 166.356284 -346.09913)
		(size 0.4572)
		(drill 0.254)
		(layers "F.Cu" "B.Cu")
		(net "GND")
	)
	(via
		(at 380.513336 -227.28555)
		(size 0.508)
		(drill 0.254)
		(layers "F.Cu" "B.Cu")
		(net "GND")
	)
	(via
		(at 43.974766 -300.174914)
		(size 0.4064)
		(drill 0.2032)
		(layers "F.Cu" "B.Cu")
		(net "GND")
	)
	(via
		(at 63.241936 -162.08375)
		(size 0.508)
		(drill 0.254)
		(layers "F.Cu" "B.Cu")
		(net "GND")
	)
	(via
		(at 43.688 -417.82492)
		(size 0.508)
		(drill 0.254)
		(layers "F.Cu" "B.Cu")
		(net "GND")
	)
	(via
		(at 364.858046 -58.791094)
		(size 0.508)
		(drill 0.254)
		(layers "F.Cu" "B.Cu")
		(net "GND")
	)
	(via
		(at 135.920226 -122.907044)
		(size 0.508)
		(drill 0.254)
		(layers "F.Cu" "B.Cu")
		(net "GND")
	)
	(via
		(at 51.48326 -341.781638)
		(size 0.4572)
		(drill 0.254)
		(layers "F.Cu" "B.Cu")
		(net "GND")
	)
	(via
		(at 436.527702 -376.242072)
		(size 0.508)
		(drill 0.254)
		(layers "F.Cu" "B.Cu")
		(net "GND")
	)
	(via
		(at 117.547644 -377.341892)
		(size 0.4572)
		(drill 0.254)
		(layers "F.Cu" "B.Cu")
		(net "GND")
	)
	(via
		(at 119.809768 -290.68649)
		(size 0.508)
		(drill 0.254)
		(layers "F.Cu" "B.Cu")
		(net "GND")
	)
	(via
		(at 354.858066 -135.058404)
		(size 0.508)
		(drill 0.254)
		(layers "F.Cu" "B.Cu")
		(net "GND")
	)
	(via
		(at 426.94987 -312.049922)
		(size 0.4064)
		(drill 0.2032)
		(layers "F.Cu" "B.Cu")
		(net "GND")
	)
	(via
		(at 281.394154 -357.123746)
		(size 0.4572)
		(drill 0.254)
		(layers "F.Cu" "B.Cu")
		(net "GND")
	)
	(via
		(at 285.687262 -118.754906)
		(size 0.508)
		(drill 0.254)
		(layers "F.Cu" "B.Cu")
		(net "GND")
	)
	(via
		(at 394.973048 -23.880318)
		(size 0.508)
		(drill 0.254)
		(layers "F.Cu" "B.Cu")
		(net "GND")
	)
	(via
		(at 60.124848 -291.624766)
		(size 0.4064)
		(drill 0.2032)
		(layers "F.Cu" "B.Cu")
		(net "GND")
	)
	(via
		(at 244.87378 -205.152244)
		(size 0.508)
		(drill 0.254)
		(layers "F.Cu" "B.Cu")
		(net "GND")
	)
	(via
		(at 7.72414 -313.003438)
		(size 0.508)
		(drill 0.254)
		(layers "F.Cu" "B.Cu")
		(net "GND")
	)
	(via
		(at 164.491416 -100.64496)
		(size 0.508)
		(drill 0.254)
		(layers "F.Cu" "B.Cu")
		(net "GND")
	)
	(via
		(at 40.649906 -315.849762)
		(size 0.4064)
		(drill 0.2032)
		(layers "F.Cu" "B.Cu")
		(net "GND")
	)
	(via
		(at 8.242808 -150.16861)
		(size 0.508)
		(drill 0.254)
		(layers "F.Cu" "B.Cu")
		(net "GND")
	)
	(via
		(at 45.39996 -282.599892)
		(size 0.4064)
		(drill 0.2032)
		(layers "F.Cu" "B.Cu")
		(net "GND")
	)
	(via
		(at 296.938954 -349.219774)
		(size 0.4572)
		(drill 0.254)
		(layers "F.Cu" "B.Cu")
		(net "GND")
	)
	(via
		(at 94.809056 -93.98254)
		(size 0.508)
		(drill 0.254)
		(layers "F.Cu" "B.Cu")
		(net "GND")
	)
	(via
		(at 76.74991 -310.149748)
		(size 0.4064)
		(drill 0.2032)
		(layers "F.Cu" "B.Cu")
		(net "GND")
	)
	(via
		(at 242.211098 -229.314756)
		(size 0.508)
		(drill 0.254)
		(layers "F.Cu" "B.Cu")
		(net "GND")
	)
	(via
		(at 72.949816 -314.899802)
		(size 0.4064)
		(drill 0.2032)
		(layers "F.Cu" "B.Cu")
		(net "GND")
	)
	(via
		(at 196.649848 -315.849762)
		(size 0.4064)
		(drill 0.2032)
		(layers "F.Cu" "B.Cu")
		(net "GND")
	)
	(via
		(at 10.412984 -372.796562)
		(size 0.508)
		(drill 0.254)
		(layers "F.Cu" "B.Cu")
		(net "GND")
	)
	(via
		(at 128.050544 -304.373534)
		(size 0.508)
		(drill 0.254)
		(layers "F.Cu" "B.Cu")
		(net "GND")
	)
	(via
		(at 0.77089 -299.221144)
		(size 0.508)
		(drill 0.254)
		(layers "F.Cu" "B.Cu")
		(net "GND")
	)
	(via
		(at 133.869684 -288.78149)
		(size 0.508)
		(drill 0.254)
		(layers "F.Cu" "B.Cu")
		(net "GND")
	)
	(via
		(at 295.68013 -343.073482)
		(size 0.4572)
		(drill 0.254)
		(layers "F.Cu" "B.Cu")
		(net "GND")
	)
	(via
		(at 393.351766 -125.955044)
		(size 0.508)
		(drill 0.254)
		(layers "F.Cu" "B.Cu")
		(net "GND")
	)
	(via
		(at 80.898238 -154.476958)
		(size 0.508)
		(drill 0.254)
		(layers "F.Cu" "B.Cu")
		(net "GND")
	)
	(via
		(at 73.899776 -273.099784)
		(size 0.4064)
		(drill 0.2032)
		(layers "F.Cu" "B.Cu")
		(net "GND")
	)
	(via
		(at 337.5279 -411.141926)
		(size 0.508)
		(drill 0.254)
		(layers "F.Cu" "B.Cu")
		(net "GND")
	)
	(via
		(at 66.774822 -293.52494)
		(size 0.4064)
		(drill 0.2032)
		(layers "F.Cu" "B.Cu")
		(net "GND")
	)
	(via
		(at 248.595642 -128.193546)
		(size 0.508)
		(drill 0.254)
		(layers "F.Cu" "B.Cu")
		(net "GND")
	)
	(via
		(at 169.465244 -349.219774)
		(size 0.4572)
		(drill 0.254)
		(layers "F.Cu" "B.Cu")
		(net "GND")
	)
	(via
		(at 377.571 -240.538)
		(size 0.508)
		(drill 0.254)
		(layers "F.Cu" "B.Cu")
		(net "GND")
	)
	(via
		(at 163.399978 -273.099784)
		(size 0.4064)
		(drill 0.2032)
		(layers "F.Cu" "B.Cu")
		(net "GND")
	)
	(via
		(at 122.563128 -106.289856)
		(size 0.508)
		(drill 0.254)
		(layers "F.Cu" "B.Cu")
		(net "GND")
	)
	(via
		(at 154.375104 -280.224738)
		(size 0.4064)
		(drill 0.2032)
		(layers "F.Cu" "B.Cu")
		(net "GND")
	)
	(via
		(at 54.70652 -135.364982)
		(size 0.508)
		(drill 0.254)
		(layers "F.Cu" "B.Cu")
		(net "GND")
	)
	(via
		(at 80.147922 -369.938554)
		(size 0.508)
		(drill 0.254)
		(layers "F.Cu" "B.Cu")
		(net "GND")
	)
	(via
		(at 301.349918 -319.65011)
		(size 0.4064)
		(drill 0.2032)
		(layers "F.Cu" "B.Cu")
		(net "GND")
	)
	(via
		(at 326.480678 -34.990024)
		(size 0.508)
		(drill 0.254)
		(layers "F.Cu" "B.Cu")
		(net "GND")
	)
	(via
		(at 196.174868 -296.37482)
		(size 0.4064)
		(drill 0.2032)
		(layers "F.Cu" "B.Cu")
		(net "GND")
	)
	(via
		(at 434.327808 -411.141926)
		(size 0.508)
		(drill 0.254)
		(layers "F.Cu" "B.Cu")
		(net "GND")
	)
	(via
		(at 58.224928 -296.37482)
		(size 0.4064)
		(drill 0.2032)
		(layers "F.Cu" "B.Cu")
		(net "GND")
	)
	(via
		(at 271.424908 -293.52494)
		(size 0.4064)
		(drill 0.2032)
		(layers "F.Cu" "B.Cu")
		(net "GND")
	)
	(via
		(at 215.413336 -31.118302)
		(size 0.508)
		(drill 0.254)
		(layers "F.Cu" "B.Cu")
		(net "GND")
	)
	(via
		(at 75.323954 -26.319734)
		(size 0.508)
		(drill 0.254)
		(layers "F.Cu" "B.Cu")
		(net "GND")
	)
	(via
		(at 40.649906 -306.349908)
		(size 0.4064)
		(drill 0.2032)
		(layers "F.Cu" "B.Cu")
		(net "GND")
	)
	(via
		(at 123.92025 -29.590238)
		(size 0.508)
		(drill 0.254)
		(layers "F.Cu" "B.Cu")
		(net "GND")
	)
	(via
		(at 422.548304 -118.234968)
		(size 0.508)
		(drill 0.254)
		(layers "F.Cu" "B.Cu")
		(net "GND")
	)
	(via
		(at 375.969022 -289.532314)
		(size 0.508)
		(drill 0.254)
		(layers "F.Cu" "B.Cu")
		(net "GND")
	)
	(via
		(at 330.927964 -376.241818)
		(size 0.508)
		(drill 0.254)
		(layers "F.Cu" "B.Cu")
		(net "GND")
	)
	(via
		(at 339.67801 -284.333188)
		(size 0.49022)
		(drill 0.254)
		(layers "F.Cu" "B.Cu")
		(net "GND")
	)
	(via
		(at 403.657816 -25.971246)
		(size 0.508)
		(drill 0.254)
		(layers "F.Cu" "B.Cu")
		(net "GND")
	)
	(via
		(at 75.32497 -292.574726)
		(size 0.4064)
		(drill 0.2032)
		(layers "F.Cu" "B.Cu")
		(net "GND")
	)
	(via
		(at 34.00298 -290.294314)
		(size 0.508)
		(drill 0.254)
		(layers "F.Cu" "B.Cu")
		(net "GND")
	)
	(via
		(at 398.4498 -312.049922)
		(size 0.4064)
		(drill 0.2032)
		(layers "F.Cu" "B.Cu")
		(net "GND")
	)
	(via
		(at 377.607068 -49.574704)
		(size 0.508)
		(drill 0.254)
		(layers "F.Cu" "B.Cu")
		(net "GND")
	)
	(via
		(at 394.38326 -342.439498)
		(size 0.4064)
		(drill 0.2032)
		(layers "F.Cu" "B.Cu")
		(net "GND")
	)
	(via
		(at 107.860846 -214.031576)
		(size 0.508)
		(drill 0.254)
		(layers "F.Cu" "B.Cu")
		(net "GND")
	)
	(via
		(at 44.449746 -311.099962)
		(size 0.4064)
		(drill 0.2032)
		(layers "F.Cu" "B.Cu")
		(net "GND")
	)
	(via
		(at 234.929426 -287.105344)
		(size 0.508)
		(drill 0.254)
		(layers "F.Cu" "B.Cu")
		(net "GND")
	)
	(via
		(at 148.2852 -385.572)
		(size 0.508)
		(drill 0.254)
		(layers "F.Cu" "B.Cu")
		(net "GND")
	)
	(via
		(at 46.34992 -314.899802)
		(size 0.4064)
		(drill 0.2032)
		(layers "F.Cu" "B.Cu")
		(net "GND")
	)
	(via
		(at 318.523112 -349.219774)
		(size 0.4572)
		(drill 0.254)
		(layers "F.Cu" "B.Cu")
		(net "GND")
	)
	(via
		(at 189.413388 -33.459674)
		(size 0.508)
		(drill 0.254)
		(layers "F.Cu" "B.Cu")
		(net "GND")
	)
	(via
		(at 168.148 -376.241818)
		(size 0.508)
		(drill 0.254)
		(layers "F.Cu" "B.Cu")
		(net "GND")
	)
	(via
		(at 268.574774 -290.674806)
		(size 0.4064)
		(drill 0.2032)
		(layers "F.Cu" "B.Cu")
		(net "GND")
	)
	(via
		(at 302.327818 -382.73863)
		(size 0.508)
		(drill 0.254)
		(layers "F.Cu" "B.Cu")
		(net "GND")
	)
	(via
		(at 147.616164 -259.576316)
		(size 0.508)
		(drill 0.254)
		(layers "F.Cu" "B.Cu")
		(net "GND")
	)
	(via
		(at 47.289974 -73.85177)
		(size 0.508)
		(drill 0.254)
		(layers "F.Cu" "B.Cu")
		(net "GND")
	)
	(via
		(at 173.850046 -281.649932)
		(size 0.4064)
		(drill 0.2032)
		(layers "F.Cu" "B.Cu")
		(net "GND")
	)
	(via
		(at 90.785442 -348.58579)
		(size 0.4064)
		(drill 0.2032)
		(layers "F.Cu" "B.Cu")
		(net "GND")
	)
	(via
		(at 420.054532 -357.75773)
		(size 0.4064)
		(drill 0.2032)
		(layers "F.Cu" "B.Cu")
		(net "GND")
	)
	(via
		(at 155.325064 -298.27474)
		(size 0.4064)
		(drill 0.2032)
		(layers "F.Cu" "B.Cu")
		(net "GND")
	)
	(via
		(at 150.555198 -33.19018)
		(size 0.508)
		(drill 0.254)
		(layers "F.Cu" "B.Cu")
		(net "GND")
	)
	(via
		(at 353.141788 -268.096492)
		(size 0.508)
		(drill 0.254)
		(layers "F.Cu" "B.Cu")
		(net "GND")
	)
	(via
		(at 74.248264 -134.845044)
		(size 0.508)
		(drill 0.254)
		(layers "F.Cu" "B.Cu")
		(net "GND")
	)
	(via
		(at 326.480678 -25.990042)
		(size 0.508)
		(drill 0.254)
		(layers "F.Cu" "B.Cu")
		(net "GND")
	)
	(via
		(at 431.840386 -123.904502)
		(size 0.508)
		(drill 0.254)
		(layers "F.Cu" "B.Cu")
		(net "GND")
	)
	(via
		(at 273.710908 -79.77124)
		(size 0.508)
		(drill 0.254)
		(layers "F.Cu" "B.Cu")
		(net "GND")
	)
	(via
		(at 170.049952 -280.699718)
		(size 0.4064)
		(drill 0.2032)
		(layers "F.Cu" "B.Cu")
		(net "GND")
	)
	(via
		(at 298.647612 -154.755088)
		(size 0.508)
		(drill 0.254)
		(layers "F.Cu" "B.Cu")
		(net "GND")
	)
	(via
		(at 407.05532 -376.709432)
		(size 0.508)
		(drill 0.254)
		(layers "F.Cu" "B.Cu")
		(net "GND")
	)
	(via
		(at 293.27475 -303.974754)
		(size 0.4064)
		(drill 0.2032)
		(layers "F.Cu" "B.Cu")
		(net "GND")
	)
	(via
		(at 411.275022 -300.174914)
		(size 0.4064)
		(drill 0.2032)
		(layers "F.Cu" "B.Cu")
		(net "GND")
	)
	(via
		(at 276.655022 -351.611438)
		(size 0.4064)
		(drill 0.2032)
		(layers "F.Cu" "B.Cu")
		(net "GND")
	)
	(via
		(at 302.410622 -57.439814)
		(size 0.508)
		(drill 0.254)
		(layers "F.Cu" "B.Cu")
		(net "GND")
	)
	(via
		(at 169.099992 -314.899802)
		(size 0.4064)
		(drill 0.2032)
		(layers "F.Cu" "B.Cu")
		(net "GND")
	)
	(via
		(at 276.174708 -286.874712)
		(size 0.4064)
		(drill 0.2032)
		(layers "F.Cu" "B.Cu")
		(net "GND")
	)
	(via
		(at 104.438196 -325.825104)
		(size 0.508)
		(drill 0.254)
		(layers "F.Cu" "B.Cu")
		(net "GND")
	)
	(via
		(at 106.217974 -284.333188)
		(size 0.49022)
		(drill 0.254)
		(layers "F.Cu" "B.Cu")
		(net "GND")
	)
	(via
		(at 243.880894 -25.990042)
		(size 0.508)
		(drill 0.254)
		(layers "F.Cu" "B.Cu")
		(net "GND")
	)
	(via
		(at 412.20644 -346.09913)
		(size 0.4572)
		(drill 0.254)
		(layers "F.Cu" "B.Cu")
		(net "GND")
	)
	(via
		(at 304.139092 -29.311854)
		(size 0.508)
		(drill 0.254)
		(layers "F.Cu" "B.Cu")
		(net "GND")
	)
	(via
		(at 42.074846 -275.474938)
		(size 0.4064)
		(drill 0.2032)
		(layers "F.Cu" "B.Cu")
		(net "GND")
	)
	(via
		(at 61.549788 -310.149748)
		(size 0.4064)
		(drill 0.2032)
		(layers "F.Cu" "B.Cu")
		(net "GND")
	)
	(via
		(at 70.50151 -349.219774)
		(size 0.4572)
		(drill 0.254)
		(layers "F.Cu" "B.Cu")
		(net "GND")
	)
	(via
		(at 67.66687 -152.95499)
		(size 0.508)
		(drill 0.254)
		(layers "F.Cu" "B.Cu")
		(net "GND")
	)
	(via
		(at 209.176366 -118.666006)
		(size 0.508)
		(drill 0.254)
		(layers "F.Cu" "B.Cu")
		(net "GND")
	)
	(via
		(at 367.820194 -56.441848)
		(size 0.508)
		(drill 0.254)
		(layers "F.Cu" "B.Cu")
		(net "GND")
	)
	(via
		(at 82.166206 -149.617938)
		(size 0.508)
		(drill 0.254)
		(layers "F.Cu" "B.Cu")
		(net "GND")
	)
	(via
		(at 456.87107 -182.573422)
		(size 0.508)
		(drill 0.254)
		(layers "F.Cu" "B.Cu")
		(net "GND")
	)
	(via
		(at 82.166206 -134.566914)
		(size 0.508)
		(drill 0.254)
		(layers "F.Cu" "B.Cu")
		(net "GND")
	)
	(via
		(at 233.148124 -81.70418)
		(size 0.508)
		(drill 0.254)
		(layers "F.Cu" "B.Cu")
		(net "GND")
	)
	(via
		(at 102.388162 -172.22724)
		(size 0.508)
		(drill 0.254)
		(layers "F.Cu" "B.Cu")
		(net "GND")
	)
	(via
		(at 409.374848 -307.774848)
		(size 0.4064)
		(drill 0.2032)
		(layers "F.Cu" "B.Cu")
		(net "GND")
	)
	(via
		(at 352.504756 -100.872544)
		(size 0.508)
		(drill 0.254)
		(layers "F.Cu" "B.Cu")
		(net "GND")
	)
	(via
		(at 390.849866 -302.549814)
		(size 0.4064)
		(drill 0.2032)
		(layers "F.Cu" "B.Cu")
		(net "GND")
	)
	(via
		(at 91.892882 -342.439498)
		(size 0.4064)
		(drill 0.2032)
		(layers "F.Cu" "B.Cu")
		(net "GND")
	)
	(via
		(at 411.1752 -388.253732)
		(size 0.508)
		(drill 0.254)
		(layers "F.Cu" "B.Cu")
		(net "GND")
	)
	(via
		(at 379.327918 -408.840178)
		(size 0.508)
		(drill 0.254)
		(layers "F.Cu" "B.Cu")
		(net "GND")
	)
	(via
		(at 99.435412 -175.43145)
		(size 0.508)
		(drill 0.254)
		(layers "F.Cu" "B.Cu")
		(net "GND")
	)
	(via
		(at 289.127692 -385.141978)
		(size 0.508)
		(drill 0.254)
		(layers "F.Cu" "B.Cu")
		(net "GND")
	)
	(via
		(at 282.17495 -73.87463)
		(size 0.508)
		(drill 0.254)
		(layers "F.Cu" "B.Cu")
		(net "GND")
	)
	(via
		(at 238.800132 -62.409578)
		(size 0.508)
		(drill 0.254)
		(layers "F.Cu" "B.Cu")
		(net "GND")
	)
	(via
		(at 391.799826 -310.149748)
		(size 0.4064)
		(drill 0.2032)
		(layers "F.Cu" "B.Cu")
		(net "GND")
	)
	(via
		(at 429.800004 -284.499812)
		(size 0.4064)
		(drill 0.2032)
		(layers "F.Cu" "B.Cu")
		(net "GND")
	)
	(via
		(at 97.519998 -56.441848)
		(size 0.508)
		(drill 0.254)
		(layers "F.Cu" "B.Cu")
		(net "GND")
	)
	(via
		(at 82.166206 -147.27682)
		(size 0.508)
		(drill 0.254)
		(layers "F.Cu" "B.Cu")
		(net "GND")
	)
	(via
		(at 186.675014 -285.924752)
		(size 0.4064)
		(drill 0.2032)
		(layers "F.Cu" "B.Cu")
		(net "GND")
	)
	(via
		(at 248.213372 -203.753212)
		(size 0.508)
		(drill 0.254)
		(layers "F.Cu" "B.Cu")
		(net "GND")
	)
	(via
		(at 339.925152 -79.516732)
		(size 0.508)
		(drill 0.254)
		(layers "F.Cu" "B.Cu")
		(net "GND")
	)
	(via
		(at 169.574972 -302.074834)
		(size 0.4064)
		(drill 0.2032)
		(layers "F.Cu" "B.Cu")
		(net "GND")
	)
	(via
		(at 327.849992 -341.805514)
		(size 0.4572)
		(drill 0.254)
		(layers "F.Cu" "B.Cu")
		(net "GND")
	)
	(via
		(at 68.674742 -305.874928)
		(size 0.4064)
		(drill 0.2032)
		(layers "F.Cu" "B.Cu")
		(net "GND")
	)
	(via
		(at 392.52779 -406.141936)
		(size 0.508)
		(drill 0.254)
		(layers "F.Cu" "B.Cu")
		(net "GND")
	)
	(via
		(at 301.349918 -312.049922)
		(size 0.4064)
		(drill 0.2032)
		(layers "F.Cu" "B.Cu")
		(net "GND")
	)
	(via
		(at 50.224436 -357.123746)
		(size 0.4572)
		(drill 0.254)
		(layers "F.Cu" "B.Cu")
		(net "GND")
	)
	(via
		(at 127.898398 -19.757136)
		(size 0.508)
		(drill 0.254)
		(layers "F.Cu" "B.Cu")
		(net "GND")
	)
	(via
		(at 385.433824 -120.833134)
		(size 0.508)
		(drill 0.254)
		(layers "F.Cu" "B.Cu")
		(net "GND")
	)
	(via
		(at 447.830448 -65.15989)
		(size 0.508)
		(drill 0.254)
		(layers "F.Cu" "B.Cu")
		(net "GND")
	)
	(via
		(at 411.1244 -389.128)
		(size 0.508)
		(drill 0.254)
		(layers "F.Cu" "B.Cu")
		(net "GND")
	)
	(via
		(at 429.010064 -341.805514)
		(size 0.4572)
		(drill 0.254)
		(layers "F.Cu" "B.Cu")
		(net "GND")
	)
	(via
		(at 283.833062 -122.355102)
		(size 0.508)
		(drill 0.254)
		(layers "F.Cu" "B.Cu")
		(net "GND")
	)
	(via
		(at 107.477814 -284.333188)
		(size 0.49022)
		(drill 0.254)
		(layers "F.Cu" "B.Cu")
		(net "GND")
	)
	(via
		(at 161.54781 -373.441976)
		(size 0.508)
		(drill 0.254)
		(layers "F.Cu" "B.Cu")
		(net "GND")
	)
	(via
		(at 37.799772 -307.299868)
		(size 0.4064)
		(drill 0.2032)
		(layers "F.Cu" "B.Cu")
		(net "GND")
	)
	(via
		(at 101.568504 -214.039958)
		(size 0.508)
		(drill 0.254)
		(layers "F.Cu" "B.Cu")
		(net "GND")
	)
	(via
		(at 29.72054 -344.831162)
		(size 0.4572)
		(drill 0.254)
		(layers "F.Cu" "B.Cu")
		(net "GND")
	)
	(via
		(at 298.012612 -152.955244)
		(size 0.508)
		(drill 0.254)
		(layers "F.Cu" "B.Cu")
		(net "GND")
	)
	(via
		(at 37.324792 -280.224738)
		(size 0.4064)
		(drill 0.2032)
		(layers "F.Cu" "B.Cu")
		(net "GND")
	)
	(via
		(at 312.14314 -28.139136)
		(size 0.508)
		(drill 0.254)
		(layers "F.Cu" "B.Cu")
		(net "GND")
	)
	(via
		(at 52.999894 -274.049744)
		(size 0.4064)
		(drill 0.2032)
		(layers "F.Cu" "B.Cu")
		(net "GND")
	)
	(via
		(at 70.099936 -281.649932)
		(size 0.4064)
		(drill 0.2032)
		(layers "F.Cu" "B.Cu")
		(net "GND")
	)
	(via
		(at 247.870472 -133.972046)
		(size 0.508)
		(drill 0.254)
		(layers "F.Cu" "B.Cu")
		(net "GND")
	)
	(via
		(at 206.117698 -303.026826)
		(size 0.508)
		(drill 0.254)
		(layers "F.Cu" "B.Cu")
		(net "GND")
	)
	(via
		(at 197.125082 -290.674806)
		(size 0.4064)
		(drill 0.2032)
		(layers "F.Cu" "B.Cu")
		(net "GND")
	)
	(via
		(at 145.972276 -33.857692)
		(size 0.508)
		(drill 0.254)
		(layers "F.Cu" "B.Cu")
		(net "GND")
	)
	(via
		(at 199.64019 -147.824698)
		(size 0.508)
		(drill 0.254)
		(layers "F.Cu" "B.Cu")
		(net "GND")
	)
	(via
		(at 172.900086 -281.649932)
		(size 0.4064)
		(drill 0.2032)
		(layers "F.Cu" "B.Cu")
		(net "GND")
	)
	(via
		(at 335.328006 -381.638556)
		(size 0.508)
		(drill 0.254)
		(layers "F.Cu" "B.Cu")
		(net "GND")
	)
	(via
		(at 405.747982 -64.312292)
		(size 0.508)
		(drill 0.254)
		(layers "F.Cu" "B.Cu")
		(net "GND")
	)
	(via
		(at 315.042804 -351.611438)
		(size 0.4064)
		(drill 0.2032)
		(layers "F.Cu" "B.Cu")
		(net "GND")
	)
	(via
		(at 45.87494 -286.874966)
		(size 0.4064)
		(drill 0.2032)
		(layers "F.Cu" "B.Cu")
		(net "GND")
	)
	(via
		(at 324.741032 -347.951806)
		(size 0.4572)
		(drill 0.254)
		(layers "F.Cu" "B.Cu")
		(net "GND")
	)
	(via
		(at 389.644128 -357.123746)
		(size 0.4572)
		(drill 0.254)
		(layers "F.Cu" "B.Cu")
		(net "GND")
	)
	(via
		(at 190.474854 -298.27474)
		(size 0.4064)
		(drill 0.2032)
		(layers "F.Cu" "B.Cu")
		(net "GND")
	)
	(via
		(at 297.310302 -351.611438)
		(size 0.4064)
		(drill 0.2032)
		(layers "F.Cu" "B.Cu")
		(net "GND")
	)
	(via
		(at 143.058896 -24.590502)
		(size 0.508)
		(drill 0.254)
		(layers "F.Cu" "B.Cu")
		(net "GND")
	)
	(via
		(at 177.5333 -358.391714)
		(size 0.4572)
		(drill 0.254)
		(layers "F.Cu" "B.Cu")
		(net "GND")
	)
	(via
		(at 175.278542 -11.344148)
		(size 0.508)
		(drill 0.254)
		(layers "F.Cu" "B.Cu")
		(net "GND")
	)
	(via
		(at 335.328006 -399.838418)
		(size 0.508)
		(drill 0.254)
		(layers "F.Cu" "B.Cu")
		(net "GND")
	)
	(via
		(at 416.974782 -292.574726)
		(size 0.4064)
		(drill 0.2032)
		(layers "F.Cu" "B.Cu")
		(net "GND")
	)
	(via
		(at 415.549842 -280.699718)
		(size 0.4064)
		(drill 0.2032)
		(layers "F.Cu" "B.Cu")
		(net "GND")
	)
	(via
		(at 438.098184 -19.096736)
		(size 0.508)
		(drill 0.254)
		(layers "F.Cu" "B.Cu")
		(net "GND")
	)
	(via
		(at 184.658 -58.791094)
		(size 0.508)
		(drill 0.254)
		(layers "F.Cu" "B.Cu")
		(net "GND")
	)
	(via
		(at 419.824916 -292.574726)
		(size 0.4064)
		(drill 0.2032)
		(layers "F.Cu" "B.Cu")
		(net "GND")
	)
	(via
		(at 128.547622 -397.140176)
		(size 0.4572)
		(drill 0.254)
		(layers "F.Cu" "B.Cu")
		(net "GND")
	)
	(via
		(at 187.624974 -291.624766)
		(size 0.4064)
		(drill 0.2032)
		(layers "F.Cu" "B.Cu")
		(net "GND")
	)
	(via
		(at 285.199836 -310.149748)
		(size 0.4064)
		(drill 0.2032)
		(layers "F.Cu" "B.Cu")
		(net "GND")
	)
	(via
		(at 109.050074 -288.14649)
		(size 0.508)
		(drill 0.254)
		(layers "F.Cu" "B.Cu")
		(net "GND")
	)
	(via
		(at 338.81187 -285.267654)
		(size 0.508)
		(drill 0.254)
		(layers "F.Cu" "B.Cu")
		(net "GND")
	)
	(via
		(at 67.724782 -300.174914)
		(size 0.4064)
		(drill 0.2032)
		(layers "F.Cu" "B.Cu")
		(net "GND")
	)
	(via
		(at 73.899776 -318.699896)
		(size 0.4064)
		(drill 0.2032)
		(layers "F.Cu" "B.Cu")
		(net "GND")
	)
	(via
		(at 430.8602 -350.977454)
		(size 0.4572)
		(drill 0.254)
		(layers "F.Cu" "B.Cu")
		(net "GND")
	)
	(via
		(at 403.338792 -354.098098)
		(size 0.4572)
		(drill 0.254)
		(layers "F.Cu" "B.Cu")
		(net "GND")
	)
	(via
		(at 252.020324 -121.560844)
		(size 0.508)
		(drill 0.254)
		(layers "F.Cu" "B.Cu")
		(net "GND")
	)
	(via
		(at 225.738944 -97.31375)
		(size 0.508)
		(drill 0.254)
		(layers "F.Cu" "B.Cu")
		(net "GND")
	)
	(via
		(at 401.70862 -357.75773)
		(size 0.4064)
		(drill 0.2032)
		(layers "F.Cu" "B.Cu")
		(net "GND")
	)
	(via
		(at 249.94743 -93.105986)
		(size 0.508)
		(drill 0.254)
		(layers "F.Cu" "B.Cu")
		(net "GND")
	)
	(via
		(at 134.68604 -343.073482)
		(size 0.4572)
		(drill 0.254)
		(layers "F.Cu" "B.Cu")
		(net "GND")
	)
	(via
		(at 48.72482 -296.37482)
		(size 0.4064)
		(drill 0.2032)
		(layers "F.Cu" "B.Cu")
		(net "GND")
	)
	(via
		(at 193.81216 -23.355554)
		(size 0.508)
		(drill 0.254)
		(layers "F.Cu" "B.Cu")
		(net "GND")
	)
	(via
		(at 371.155214 -220.33865)
		(size 0.508)
		(drill 0.254)
		(layers "F.Cu" "B.Cu")
		(net "GND")
	)
	(via
		(at 280.449782 -311.099962)
		(size 0.4064)
		(drill 0.2032)
		(layers "F.Cu" "B.Cu")
		(net "GND")
	)
	(via
		(at 299.449744 -275.949918)
		(size 0.4064)
		(drill 0.2032)
		(layers "F.Cu" "B.Cu")
		(net "GND")
	)
	(via
		(at 109.9058 -131.134358)
		(size 0.508)
		(drill 0.254)
		(layers "F.Cu" "B.Cu")
		(net "GND")
	)
	(via
		(at 411.750002 -279.749758)
		(size 0.4064)
		(drill 0.2032)
		(layers "F.Cu" "B.Cu")
		(net "GND")
	)
	(via
		(at 60.455048 -31.390082)
		(size 0.508)
		(drill 0.254)
		(layers "F.Cu" "B.Cu")
		(net "GND")
	)
	(via
		(at 272.849848 -319.65011)
		(size 0.4064)
		(drill 0.2032)
		(layers "F.Cu" "B.Cu")
		(net "GND")
	)
	(via
		(at 300.12767 -382.84023)
		(size 0.508)
		(drill 0.254)
		(layers "F.Cu" "B.Cu")
		(net "GND")
	)
	(via
		(at 167.732964 -122.355102)
		(size 0.508)
		(drill 0.254)
		(layers "F.Cu" "B.Cu")
		(net "GND")
	)
	(via
		(at 292.65499 -31.390082)
		(size 0.508)
		(drill 0.254)
		(layers "F.Cu" "B.Cu")
		(net "GND")
	)
	(via
		(at 295.727882 -399.838418)
		(size 0.508)
		(drill 0.254)
		(layers "F.Cu" "B.Cu")
		(net "GND")
	)
	(via
		(at 80.07477 -290.674806)
		(size 0.4064)
		(drill 0.2032)
		(layers "F.Cu" "B.Cu")
		(net "GND")
	)
	(via
		(at 126.356618 -211.588858)
		(size 0.508)
		(drill 0.254)
		(layers "F.Cu" "B.Cu")
		(net "GND")
	)
	(via
		(at 395.862048 -358.391714)
		(size 0.4572)
		(drill 0.254)
		(layers "F.Cu" "B.Cu")
		(net "GND")
	)
	(via
		(at 51.854608 -351.611438)
		(size 0.4064)
		(drill 0.2032)
		(layers "F.Cu" "B.Cu")
		(net "GND")
	)
	(via
		(at 158.174944 -297.32478)
		(size 0.4064)
		(drill 0.2032)
		(layers "F.Cu" "B.Cu")
		(net "GND")
	)
	(via
		(at 376.685556 -34.183066)
		(size 0.508)
		(drill 0.254)
		(layers "F.Cu" "B.Cu")
		(net "GND")
	)
	(via
		(at 174.325026 -284.024832)
		(size 0.4064)
		(drill 0.2032)
		(layers "F.Cu" "B.Cu")
		(net "GND")
	)
	(via
		(at 296.793412 -123.635008)
		(size 0.508)
		(drill 0.254)
		(layers "F.Cu" "B.Cu")
		(net "GND")
	)
	(via
		(at 427.727872 -399.838418)
		(size 0.508)
		(drill 0.254)
		(layers "F.Cu" "B.Cu")
		(net "GND")
	)
	(via
		(at 170.347894 -402.140166)
		(size 0.508)
		(drill 0.254)
		(layers "F.Cu" "B.Cu")
		(net "GND")
	)
	(via
		(at 422.59504 -104.240076)
		(size 0.508)
		(drill 0.254)
		(layers "F.Cu" "B.Cu")
		(net "GND")
	)
	(via
		(at 74.295 -102.439978)
		(size 0.508)
		(drill 0.254)
		(layers "F.Cu" "B.Cu")
		(net "GND")
	)
	(via
		(at 313.4614 -82.022696)
		(size 0.508)
		(drill 0.254)
		(layers "F.Cu" "B.Cu")
		(net "GND")
	)
	(via
		(at 346.465652 -305.008534)
		(size 0.508)
		(drill 0.254)
		(layers "F.Cu" "B.Cu")
		(net "GND")
	)
	(via
		(at 190.474854 -294.4749)
		(size 0.4064)
		(drill 0.2032)
		(layers "F.Cu" "B.Cu")
		(net "GND")
	)
	(via
		(at 117.547644 -399.441924)
		(size 0.4572)
		(drill 0.254)
		(layers "F.Cu" "B.Cu")
		(net "GND")
	)
	(via
		(at 466.481922 -1.13538)
		(size 0.508)
		(drill 0.254)
		(layers "F.Cu" "B.Cu")
		(net "GND")
	)
	(via
		(at 374.50395 -193.05905)
		(size 0.508)
		(drill 0.254)
		(layers "F.Cu" "B.Cu")
		(net "GND")
	)
	(via
		(at 166.727632 -351.611438)
		(size 0.4064)
		(drill 0.2032)
		(layers "F.Cu" "B.Cu")
		(net "GND")
	)
	(via
		(at 442.85789 -57.521094)
		(size 0.508)
		(drill 0.254)
		(layers "F.Cu" "B.Cu")
		(net "GND")
	)
	(via
		(at 67.66687 -123.635008)
		(size 0.508)
		(drill 0.254)
		(layers "F.Cu" "B.Cu")
		(net "GND")
	)
	(via
		(at 414.124902 -294.4749)
		(size 0.4064)
		(drill 0.2032)
		(layers "F.Cu" "B.Cu")
		(net "GND")
	)
	(via
		(at 69.149976 -316.799722)
		(size 0.4064)
		(drill 0.2032)
		(layers "F.Cu" "B.Cu")
		(net "GND")
	)
	(via
		(at 269.333726 -120.833134)
		(size 0.508)
		(drill 0.254)
		(layers "F.Cu" "B.Cu")
		(net "GND")
	)
	(via
		(at 26.61158 -358.391714)
		(size 0.4572)
		(drill 0.254)
		(layers "F.Cu" "B.Cu")
		(net "GND")
	)
	(via
		(at 269.524734 -289.724846)
		(size 0.4064)
		(drill 0.2032)
		(layers "F.Cu" "B.Cu")
		(net "GND")
	)
	(via
		(at 352.657156 -171.45)
		(size 0.508)
		(drill 0.254)
		(layers "F.Cu" "B.Cu")
		(net "GND")
	)
	(via
		(at 399.874994 -305.874928)
		(size 0.4064)
		(drill 0.2032)
		(layers "F.Cu" "B.Cu")
		(net "GND")
	)
	(via
		(at 60.124848 -284.974792)
		(size 0.4064)
		(drill 0.2032)
		(layers "F.Cu" "B.Cu")
		(net "GND")
	)
	(via
		(at 94.280736 -27.79014)
		(size 0.508)
		(drill 0.254)
		(layers "F.Cu" "B.Cu")
		(net "GND")
	)
	(via
		(at 26.982928 -354.732082)
		(size 0.4064)
		(drill 0.2032)
		(layers "F.Cu" "B.Cu")
		(net "GND")
	)
	(via
		(at 254.160274 -21.37156)
		(size 0.508)
		(drill 0.254)
		(layers "F.Cu" "B.Cu")
		(net "GND")
	)
	(via
		(at 183.412638 -102.439978)
		(size 0.508)
		(drill 0.254)
		(layers "F.Cu" "B.Cu")
		(net "GND")
	)
	(via
		(at 392.753088 -343.073482)
		(size 0.4572)
		(drill 0.254)
		(layers "F.Cu" "B.Cu")
		(net "GND")
	)
	(via
		(at 313.699906 -307.299868)
		(size 0.4064)
		(drill 0.2032)
		(layers "F.Cu" "B.Cu")
		(net "GND")
	)
	(via
		(at 161.025078 -284.974792)
		(size 0.4064)
		(drill 0.2032)
		(layers "F.Cu" "B.Cu")
		(net "GND")
	)
	(via
		(at 16.078962 -231.86009)
		(size 0.508)
		(drill 0.254)
		(layers "F.Cu" "B.Cu")
		(net "GND")
	)
	(via
		(at 401.774914 -303.974754)
		(size 0.4064)
		(drill 0.2032)
		(layers "F.Cu" "B.Cu")
		(net "GND")
	)
	(via
		(at 393.22502 -286.874966)
		(size 0.4064)
		(drill 0.2032)
		(layers "F.Cu" "B.Cu")
		(net "GND")
	)
	(via
		(at 135.198612 -193.734944)
		(size 0.508)
		(drill 0.254)
		(layers "F.Cu" "B.Cu")
		(net "GND")
	)
	(via
		(at 390.58088 -29.589984)
		(size 0.508)
		(drill 0.254)
		(layers "F.Cu" "B.Cu")
		(net "GND")
	)
	(via
		(at 249.52325 -132.620766)
		(size 0.508)
		(drill 0.254)
		(layers "F.Cu" "B.Cu")
		(net "GND")
	)
	(via
		(at 157.699964 -318.699896)
		(size 0.4064)
		(drill 0.2032)
		(layers "F.Cu" "B.Cu")
		(net "GND")
	)
	(via
		(at 40.897556 -352.245422)
		(size 0.4572)
		(drill 0.254)
		(layers "F.Cu" "B.Cu")
		(net "GND")
	)
	(via
		(at 35.739578 -297.324526)
		(size 0.4064)
		(drill 0.2032)
		(layers "F.Cu" "B.Cu")
		(net "GND")
	)
	(via
		(at 53.474874 -285.924752)
		(size 0.4064)
		(drill 0.2032)
		(layers "F.Cu" "B.Cu")
		(net "GND")
	)
	(via
		(at 106.087164 -161.807652)
		(size 0.508)
		(drill 0.254)
		(layers "F.Cu" "B.Cu")
		(net "GND")
	)
	(via
		(at 124.147834 -377.738386)
		(size 0.508)
		(drill 0.254)
		(layers "F.Cu" "B.Cu")
		(net "GND")
	)
	(via
		(at 384.059684 -109.382052)
		(size 0.508)
		(drill 0.254)
		(layers "F.Cu" "B.Cu")
		(net "GND")
	)
	(via
		(at 268.734286 -253.45644)
		(size 0.508)
		(drill 0.254)
		(layers "F.Cu" "B.Cu")
		(net "GND")
	)
	(via
		(at 454.990708 -210.573874)
		(size 0.508)
		(drill 0.254)
		(layers "F.Cu" "B.Cu")
		(net "GND")
	)
	(via
		(at 165.440106 -73.23963)
		(size 0.508)
		(drill 0.254)
		(layers "F.Cu" "B.Cu")
		(net "GND")
	)
	(via
		(at 192.850008 -302.549814)
		(size 0.4064)
		(drill 0.2032)
		(layers "F.Cu" "B.Cu")
		(net "GND")
	)
	(via
		(at 91.892882 -351.611438)
		(size 0.4064)
		(drill 0.2032)
		(layers "F.Cu" "B.Cu")
		(net "GND")
	)
	(via
		(at 196.649848 -287.349946)
		(size 0.4064)
		(drill 0.2032)
		(layers "F.Cu" "B.Cu")
		(net "GND")
	)
	(via
		(at 168.952164 -104.244902)
		(size 0.508)
		(drill 0.254)
		(layers "F.Cu" "B.Cu")
		(net "GND")
	)
	(via
		(at 243.944902 -27.79014)
		(size 0.508)
		(drill 0.254)
		(layers "F.Cu" "B.Cu")
		(net "GND")
	)
	(via
		(at 289.127692 -397.038576)
		(size 0.508)
		(drill 0.254)
		(layers "F.Cu" "B.Cu")
		(net "GND")
	)
	(via
		(at 125.730508 -345.465146)
		(size 0.4064)
		(drill 0.2032)
		(layers "F.Cu" "B.Cu")
		(net "GND")
	)
	(via
		(at 124.100336 -352.245422)
		(size 0.4572)
		(drill 0.254)
		(layers "F.Cu" "B.Cu")
		(net "GND")
	)
	(via
		(at 197.62343 -412.12643)
		(size 0.508)
		(drill 0.254)
		(layers "F.Cu" "B.Cu")
		(net "GND")
	)
	(via
		(at 382.791716 -112.981994)
		(size 0.508)
		(drill 0.254)
		(layers "F.Cu" "B.Cu")
		(net "GND")
	)
	(via
		(at 201.565256 -417.241228)
		(size 0.508)
		(drill 0.254)
		(layers "F.Cu" "B.Cu")
		(net "GND")
	)
	(via
		(at 422.548304 -136.645142)
		(size 0.508)
		(drill 0.254)
		(layers "F.Cu" "B.Cu")
		(net "GND")
	)
	(via
		(at 62.024768 -300.174914)
		(size 0.4064)
		(drill 0.2032)
		(layers "F.Cu" "B.Cu")
		(net "GND")
	)
	(via
		(at 406.279858 -102.798372)
		(size 0.508)
		(drill 0.254)
		(layers "F.Cu" "B.Cu")
		(net "GND")
	)
	(via
		(at 337.5279 -409.940252)
		(size 0.508)
		(drill 0.254)
		(layers "F.Cu" "B.Cu")
		(net "GND")
	)
	(via
		(at 418.399976 -274.049744)
		(size 0.4064)
		(drill 0.2032)
		(layers "F.Cu" "B.Cu")
		(net "GND")
	)
	(via
		(at 110.676182 -291.32149)
		(size 0.508)
		(drill 0.254)
		(layers "F.Cu" "B.Cu")
		(net "GND")
	)
	(via
		(at 365.158274 -122.462036)
		(size 0.508)
		(drill 0.254)
		(layers "F.Cu" "B.Cu")
		(net "GND")
	)
	(via
		(at 125.35916 -357.123746)
		(size 0.4572)
		(drill 0.254)
		(layers "F.Cu" "B.Cu")
		(net "GND")
	)
	(via
		(at 124.147834 -373.83847)
		(size 0.508)
		(drill 0.254)
		(layers "F.Cu" "B.Cu")
		(net "GND")
	)
	(via
		(at 187.624974 -302.074834)
		(size 0.4064)
		(drill 0.2032)
		(layers "F.Cu" "B.Cu")
		(net "GND")
	)
	(via
		(at 83.400138 -276.900132)
		(size 0.4064)
		(drill 0.2032)
		(layers "F.Cu" "B.Cu")
		(net "GND")
	)
	(via
		(at 283.24429 -355.366066)
		(size 0.4572)
		(drill 0.254)
		(layers "F.Cu" "B.Cu")
		(net "GND")
	)
	(via
		(at 290.721034 -357.123746)
		(size 0.4572)
		(drill 0.254)
		(layers "F.Cu" "B.Cu")
		(net "GND")
	)
	(via
		(at 385.927854 -376.140218)
		(size 0.508)
		(drill 0.254)
		(layers "F.Cu" "B.Cu")
		(net "GND")
	)
	(via
		(at 299.449744 -281.649932)
		(size 0.4064)
		(drill 0.2032)
		(layers "F.Cu" "B.Cu")
		(net "GND")
	)
	(via
		(at 369.555776 -153.782522)
		(size 0.508)
		(drill 0.254)
		(layers "F.Cu" "B.Cu")
		(net "GND")
	)
	(via
		(at 184.29986 -278.799798)
		(size 0.4064)
		(drill 0.2032)
		(layers "F.Cu" "B.Cu")
		(net "GND")
	)
	(via
		(at 159.59963 -57.439814)
		(size 0.508)
		(drill 0.254)
		(layers "F.Cu" "B.Cu")
		(net "GND")
	)
	(via
		(at 198.075042 -303.024794)
		(size 0.4064)
		(drill 0.2032)
		(layers "F.Cu" "B.Cu")
		(net "GND")
	)
	(via
		(at 81.499964 -315.849762)
		(size 0.4064)
		(drill 0.2032)
		(layers "F.Cu" "B.Cu")
		(net "GND")
	)
	(via
		(at 282.824936 -284.024832)
		(size 0.4064)
		(drill 0.2032)
		(layers "F.Cu" "B.Cu")
		(net "GND")
	)
	(via
		(at 199.500236 -287.3502)
		(size 0.4064)
		(drill 0.2032)
		(layers "F.Cu" "B.Cu")
		(net "GND")
	)
	(via
		(at 319.718944 -301.808642)
		(size 0.508)
		(drill 0.254)
		(layers "F.Cu" "B.Cu")
		(net "GND")
	)
	(via
		(at 126.837948 -351.611438)
		(size 0.4064)
		(drill 0.2032)
		(layers "F.Cu" "B.Cu")
		(net "GND")
	)
	(via
		(at 29.54782 -408.738578)
		(size 0.508)
		(drill 0.254)
		(layers "F.Cu" "B.Cu")
		(net "GND")
	)
	(via
		(at 168.148 -384.041904)
		(size 0.508)
		(drill 0.254)
		(layers "F.Cu" "B.Cu")
		(net "GND")
	)
	(via
		(at 51.63312 -124.154946)
		(size 0.508)
		(drill 0.254)
		(layers "F.Cu" "B.Cu")
		(net "GND")
	)
	(via
		(at 250.838716 -23.880318)
		(size 0.508)
		(drill 0.254)
		(layers "F.Cu" "B.Cu")
		(net "GND")
	)
	(via
		(at 129.23774 -292.789102)
		(size 0.508)
		(drill 0.254)
		(layers "F.Cu" "B.Cu")
		(net "GND")
	)
	(via
		(at 17.485614 -63.218314)
		(size 0.508)
		(drill 0.254)
		(layers "F.Cu" "B.Cu")
		(net "GND")
	)
	(via
		(at 80.898238 -133.30809)
		(size 0.508)
		(drill 0.254)
		(layers "F.Cu" "B.Cu")
		(net "GND")
	)
	(via
		(at 400.05 -143.615156)
		(size 0.508)
		(drill 0.254)
		(layers "F.Cu" "B.Cu")
		(net "GND")
	)
	(via
		(at 304.199798 -278.799798)
		(size 0.4064)
		(drill 0.2032)
		(layers "F.Cu" "B.Cu")
		(net "GND")
	)
	(via
		(at 57.979818 -101.782372)
		(size 0.508)
		(drill 0.254)
		(layers "F.Cu" "B.Cu")
		(net "GND")
	)
	(via
		(at 173.8503 -319.65011)
		(size 0.4064)
		(drill 0.2032)
		(layers "F.Cu" "B.Cu")
		(net "GND")
	)
	(via
		(at 291.32784 -399.838418)
		(size 0.508)
		(drill 0.254)
		(layers "F.Cu" "B.Cu")
		(net "GND")
	)
	(via
		(at 50.14976 -310.149748)
		(size 0.4064)
		(drill 0.2032)
		(layers "F.Cu" "B.Cu")
		(net "GND")
	)
	(via
		(at 379.327918 -376.241818)
		(size 0.508)
		(drill 0.254)
		(layers "F.Cu" "B.Cu")
		(net "GND")
	)
	(via
		(at 276.410674 -57.439814)
		(size 0.508)
		(drill 0.254)
		(layers "F.Cu" "B.Cu")
		(net "GND")
	)
	(via
		(at 195.699888 -312.999882)
		(size 0.4064)
		(drill 0.2032)
		(layers "F.Cu" "B.Cu")
		(net "GND")
	)
	(via
		(at 436.527702 -375.040398)
		(size 0.508)
		(drill 0.254)
		(layers "F.Cu" "B.Cu")
		(net "GND")
	)
	(via
		(at 298.012612 -147.555204)
		(size 0.508)
		(drill 0.254)
		(layers "F.Cu" "B.Cu")
		(net "GND")
	)
	(via
		(at 279.024842 -304.924714)
		(size 0.4064)
		(drill 0.2032)
		(layers "F.Cu" "B.Cu")
		(net "GND")
	)
	(via
		(at 426.94987 -284.499812)
		(size 0.4064)
		(drill 0.2032)
		(layers "F.Cu" "B.Cu")
		(net "GND")
	)
	(via
		(at 399.93316 -106.045)
		(size 0.508)
		(drill 0.254)
		(layers "F.Cu" "B.Cu")
		(net "GND")
	)
	(via
		(at 394.239242 -28.05303)
		(size 0.508)
		(drill 0.254)
		(layers "F.Cu" "B.Cu")
		(net "GND")
	)
	(via
		(at 235.9787 -114.380264)
		(size 0.508)
		(drill 0.254)
		(layers "F.Cu" "B.Cu")
		(net "GND")
	)
	(via
		(at 301.349918 -274.999958)
		(size 0.4064)
		(drill 0.2032)
		(layers "F.Cu" "B.Cu")
		(net "GND")
	)
	(via
		(at 6.558026 -135.058404)
		(size 0.508)
		(drill 0.254)
		(layers "F.Cu" "B.Cu")
		(net "GND")
	)
	(via
		(at 307.049678 -279.749758)
		(size 0.4064)
		(drill 0.2032)
		(layers "F.Cu" "B.Cu")
		(net "GND")
	)
	(via
		(at 274.480782 -29.589984)
		(size 0.508)
		(drill 0.254)
		(layers "F.Cu" "B.Cu")
		(net "GND")
	)
	(via
		(at 279.489916 -73.85177)
		(size 0.508)
		(drill 0.254)
		(layers "F.Cu" "B.Cu")
		(net "GND")
	)
	(via
		(at 82.347816 -408.738578)
		(size 0.508)
		(drill 0.254)
		(layers "F.Cu" "B.Cu")
		(net "GND")
	)
	(via
		(at 429.010064 -343.073482)
		(size 0.4572)
		(drill 0.254)
		(layers "F.Cu" "B.Cu")
		(net "GND")
	)
	(via
		(at 34.308288 -342.439498)
		(size 0.4064)
		(drill 0.2032)
		(layers "F.Cu" "B.Cu")
		(net "GND")
	)
	(via
		(at 371.6401 -73.23963)
		(size 0.508)
		(drill 0.254)
		(layers "F.Cu" "B.Cu")
		(net "GND")
	)
	(via
		(at 106.394504 -100.751894)
		(size 0.508)
		(drill 0.254)
		(layers "F.Cu" "B.Cu")
		(net "GND")
	)
	(via
		(at 400.60118 -351.611438)
		(size 0.4064)
		(drill 0.2032)
		(layers "F.Cu" "B.Cu")
		(net "GND")
	)
	(via
		(at 317.044324 -348.58579)
		(size 0.4064)
		(drill 0.2032)
		(layers "F.Cu" "B.Cu")
		(net "GND")
	)
	(via
		(at 374.674384 -253.45644)
		(size 0.508)
		(drill 0.254)
		(layers "F.Cu" "B.Cu")
		(net "GND")
	)
	(via
		(at 400.349974 -279.749758)
		(size 0.4064)
		(drill 0.2032)
		(layers "F.Cu" "B.Cu")
		(net "GND")
	)
	(via
		(at 299.866812 -136.645142)
		(size 0.508)
		(drill 0.254)
		(layers "F.Cu" "B.Cu")
		(net "GND")
	)
	(via
		(at 395.313662 -87.791544)
		(size 0.508)
		(drill 0.254)
		(layers "F.Cu" "B.Cu")
		(net "GND")
	)
	(via
		(at 424.09999 -303.499774)
		(size 0.4064)
		(drill 0.2032)
		(layers "F.Cu" "B.Cu")
		(net "GND")
	)
	(via
		(at 391.799826 -309.199788)
		(size 0.4064)
		(drill 0.2032)
		(layers "F.Cu" "B.Cu")
		(net "GND")
	)
	(via
		(at 131.57708 -354.098098)
		(size 0.4572)
		(drill 0.254)
		(layers "F.Cu" "B.Cu")
		(net "GND")
	)
	(via
		(at 357.254048 -147.630388)
		(size 0.508)
		(drill 0.254)
		(layers "F.Cu" "B.Cu")
		(net "GND")
	)
	(via
		(at 274.749768 -302.549814)
		(size 0.4064)
		(drill 0.2032)
		(layers "F.Cu" "B.Cu")
		(net "GND")
	)
	(via
		(at 36.961064 -257.137916)
		(size 0.508)
		(drill 0.254)
		(layers "F.Cu" "B.Cu")
		(net "GND")
	)
	(via
		(at 151.859488 -120.28551)
		(size 0.508)
		(drill 0.254)
		(layers "F.Cu" "B.Cu")
		(net "GND")
	)
	(via
		(at 252.961902 -161.6075)
		(size 0.508)
		(drill 0.254)
		(layers "F.Cu" "B.Cu")
		(net "GND")
	)
	(via
		(at 425.901104 -352.245422)
		(size 0.4572)
		(drill 0.254)
		(layers "F.Cu" "B.Cu")
		(net "GND")
	)
	(via
		(at 195.836794 -15.474188)
		(size 0.508)
		(drill 0.254)
		(layers "F.Cu" "B.Cu")
		(net "GND")
	)
	(via
		(at 428.37481 -298.27474)
		(size 0.4064)
		(drill 0.2032)
		(layers "F.Cu" "B.Cu")
		(net "GND")
	)
	(via
		(at 214.039196 -32.911796)
		(size 0.508)
		(drill 0.254)
		(layers "F.Cu" "B.Cu")
		(net "GND")
	)
	(via
		(at 357.909368 -290.68649)
		(size 0.508)
		(drill 0.254)
		(layers "F.Cu" "B.Cu")
		(net "GND")
	)
	(via
		(at 121.68251 -37.087048)
		(size 0.508)
		(drill 0.254)
		(layers "F.Cu" "B.Cu")
		(net "GND")
	)
	(via
		(at 147.129754 -229.454456)
		(size 0.508)
		(drill 0.254)
		(layers "F.Cu" "B.Cu")
		(net "GND")
	)
	(via
		(at 80.54975 -312.049922)
		(size 0.4064)
		(drill 0.2032)
		(layers "F.Cu" "B.Cu")
		(net "GND")
	)
	(via
		(at 428.37481 -288.774886)
		(size 0.4064)
		(drill 0.2032)
		(layers "F.Cu" "B.Cu")
		(net "GND")
	)
	(via
		(at 271.424908 -289.724846)
		(size 0.4064)
		(drill 0.2032)
		(layers "F.Cu" "B.Cu")
		(net "GND")
	)
	(via
		(at 345.693746 -222.786956)
		(size 0.4572)
		(drill 0.254)
		(layers "F.Cu" "B.Cu")
		(net "GND")
	)
	(via
		(at 283.299916 -310.149748)
		(size 0.4064)
		(drill 0.2032)
		(layers "F.Cu" "B.Cu")
		(net "GND")
	)
	(via
		(at 43.635168 -351.611438)
		(size 0.4064)
		(drill 0.2032)
		(layers "F.Cu" "B.Cu")
		(net "GND")
	)
	(via
		(at 70.50151 -344.831162)
		(size 0.4572)
		(drill 0.254)
		(layers "F.Cu" "B.Cu")
		(net "GND")
	)
	(via
		(at 406.999948 -273.099784)
		(size 0.4064)
		(drill 0.2032)
		(layers "F.Cu" "B.Cu")
		(net "GND")
	)
	(via
		(at 200.166478 -35.871912)
		(size 0.508)
		(drill 0.254)
		(layers "F.Cu" "B.Cu")
		(net "GND")
	)
	(via
		(at 194.651376 -100.056696)
		(size 0.508)
		(drill 0.254)
		(layers "F.Cu" "B.Cu")
		(net "GND")
	)
	(via
		(at 277.251668 -118.754906)
		(size 0.508)
		(drill 0.254)
		(layers "F.Cu" "B.Cu")
		(net "GND")
	)
	(via
		(at 146.72183 -391.409428)
		(size 0.508)
		(drill 0.254)
		(layers "F.Cu" "B.Cu")
		(net "GND")
	)
	(via
		(at 32.8295 -358.391714)
		(size 0.4572)
		(drill 0.254)
		(layers "F.Cu" "B.Cu")
		(net "GND")
	)
	(via
		(at 216.351358 -45.865288)
		(size 0.508)
		(drill 0.254)
		(layers "F.Cu" "B.Cu")
		(net "GND")
	)
	(via
		(at 276.174708 -290.674806)
		(size 0.4064)
		(drill 0.2032)
		(layers "F.Cu" "B.Cu")
		(net "GND")
	)
	(via
		(at 385.624832 -282.124912)
		(size 0.4064)
		(drill 0.2032)
		(layers "F.Cu" "B.Cu")
		(net "GND")
	)
	(via
		(at 53.949854 -276.899878)
		(size 0.4064)
		(drill 0.2032)
		(layers "F.Cu" "B.Cu")
		(net "GND")
	)
	(via
		(at 302.327818 -400.938492)
		(size 0.508)
		(drill 0.254)
		(layers "F.Cu" "B.Cu")
		(net "GND")
	)
	(via
		(at 215.905842 -278.175466)
		(size 0.508)
		(drill 0.254)
		(layers "F.Cu" "B.Cu")
		(net "GND")
	)
	(via
		(at 89.15527 -344.831162)
		(size 0.4572)
		(drill 0.254)
		(layers "F.Cu" "B.Cu")
		(net "GND")
	)
	(via
		(at 179.55006 -314.899802)
		(size 0.4064)
		(drill 0.2032)
		(layers "F.Cu" "B.Cu")
		(net "GND")
	)
	(via
		(at 122.621548 -345.465146)
		(size 0.4064)
		(drill 0.2032)
		(layers "F.Cu" "B.Cu")
		(net "GND")
	)
	(via
		(at 411.750002 -275.949918)
		(size 0.4064)
		(drill 0.2032)
		(layers "F.Cu" "B.Cu")
		(net "GND")
	)
	(via
		(at 51.74996 -146.155156)
		(size 0.508)
		(drill 0.254)
		(layers "F.Cu" "B.Cu")
		(net "GND")
	)
	(via
		(at 192.375028 -297.32478)
		(size 0.4064)
		(drill 0.2032)
		(layers "F.Cu" "B.Cu")
		(net "GND")
	)
	(via
		(at 410.0068 -385.953)
		(size 0.508)
		(drill 0.254)
		(layers "F.Cu" "B.Cu")
		(net "GND")
	)
	(via
		(at 339.728048 -398.34185)
		(size 0.508)
		(drill 0.254)
		(layers "F.Cu" "B.Cu")
		(net "GND")
	)
	(via
		(at 68.674742 -307.774848)
		(size 0.4064)
		(drill 0.2032)
		(layers "F.Cu" "B.Cu")
		(net "GND")
	)
	(via
		(at 82.449924 -275.949918)
		(size 0.4064)
		(drill 0.2032)
		(layers "F.Cu" "B.Cu")
		(net "GND")
	)
	(via
		(at 407.949908 -280.699718)
		(size 0.4064)
		(drill 0.2032)
		(layers "F.Cu" "B.Cu")
		(net "GND")
	)
	(via
		(at 415.96691 -156.554932)
		(size 0.508)
		(drill 0.254)
		(layers "F.Cu" "B.Cu")
		(net "GND")
	)
	(via
		(at 433.108354 -125.163326)
		(size 0.508)
		(drill 0.254)
		(layers "F.Cu" "B.Cu")
		(net "GND")
	)
	(via
		(at 171.972224 -33.857692)
		(size 0.508)
		(drill 0.254)
		(layers "F.Cu" "B.Cu")
		(net "GND")
	)
	(via
		(at 304.527712 -404.940262)
		(size 0.508)
		(drill 0.254)
		(layers "F.Cu" "B.Cu")
		(net "GND")
	)
	(via
		(at 375.358152 -341.805514)
		(size 0.4572)
		(drill 0.254)
		(layers "F.Cu" "B.Cu")
		(net "GND")
	)
	(via
		(at 86.04631 -355.366066)
		(size 0.4572)
		(drill 0.254)
		(layers "F.Cu" "B.Cu")
		(net "GND")
	)
	(via
		(at 49.67478 -299.224954)
		(size 0.4064)
		(drill 0.2032)
		(layers "F.Cu" "B.Cu")
		(net "GND")
	)
	(via
		(at 376.83694 -351.611438)
		(size 0.4064)
		(drill 0.2032)
		(layers "F.Cu" "B.Cu")
		(net "GND")
	)
	(via
		(at 393.7 -318.699896)
		(size 0.4064)
		(drill 0.2032)
		(layers "F.Cu" "B.Cu")
		(net "GND")
	)
	(via
		(at 422.792144 -347.951806)
		(size 0.4572)
		(drill 0.254)
		(layers "F.Cu" "B.Cu")
		(net "GND")
	)
	(via
		(at 296.793412 -121.835164)
		(size 0.508)
		(drill 0.254)
		(layers "F.Cu" "B.Cu")
		(net "GND")
	)
	(via
		(at 164.726112 -357.75773)
		(size 0.4064)
		(drill 0.2032)
		(layers "F.Cu" "B.Cu")
		(net "GND")
	)
	(via
		(at 156.275024 -281.174952)
		(size 0.4064)
		(drill 0.2032)
		(layers "F.Cu" "B.Cu")
		(net "GND")
	)
	(via
		(at 397.02486 -306.824888)
		(size 0.4064)
		(drill 0.2032)
		(layers "F.Cu" "B.Cu")
		(net "GND")
	)
	(via
		(at 67.724782 -284.974792)
		(size 0.4064)
		(drill 0.2032)
		(layers "F.Cu" "B.Cu")
		(net "GND")
	)
	(via
		(at 35.93846 -343.073482)
		(size 0.4572)
		(drill 0.254)
		(layers "F.Cu" "B.Cu")
		(net "GND")
	)
	(via
		(at 54.70652 -129.964942)
		(size 0.508)
		(drill 0.254)
		(layers "F.Cu" "B.Cu")
		(net "GND")
	)
	(via
		(at 285.981902 -345.465146)
		(size 0.4064)
		(drill 0.2032)
		(layers "F.Cu" "B.Cu")
		(net "GND")
	)
	(via
		(at 176.224946 -287.899856)
		(size 0.4064)
		(drill 0.2032)
		(layers "F.Cu" "B.Cu")
		(net "GND")
	)
	(via
		(at 41.124886 -277.374858)
		(size 0.4064)
		(drill 0.2032)
		(layers "F.Cu" "B.Cu")
		(net "GND")
	)
	(via
		(at 391.785602 -63.218314)
		(size 0.508)
		(drill 0.254)
		(layers "F.Cu" "B.Cu")
		(net "GND")
	)
	(via
		(at 442.097668 -118.183152)
		(size 0.508)
		(drill 0.254)
		(layers "F.Cu" "B.Cu")
		(net "GND")
	)
	(via
		(at 266.691618 -133.836664)
		(size 0.508)
		(drill 0.254)
		(layers "F.Cu" "B.Cu")
		(net "GND")
	)
	(via
		(at 183.75122 -355.34219)
		(size 0.4572)
		(drill 0.254)
		(layers "F.Cu" "B.Cu")
		(net "GND")
	)
	(via
		(at 301.349918 -279.749758)
		(size 0.4064)
		(drill 0.2032)
		(layers "F.Cu" "B.Cu")
		(net "GND")
	)
	(via
		(at 17.323308 -134.525766)
		(size 0.508)
		(drill 0.254)
		(layers "F.Cu" "B.Cu")
		(net "GND")
	)
	(via
		(at 119.013732 -130.217926)
		(size 0.508)
		(drill 0.254)
		(layers "F.Cu" "B.Cu")
		(net "GND")
	)
	(via
		(at 430.488852 -357.75773)
		(size 0.4064)
		(drill 0.2032)
		(layers "F.Cu" "B.Cu")
		(net "GND")
	)
	(via
		(at 142.382748 -351.611438)
		(size 0.4064)
		(drill 0.2032)
		(layers "F.Cu" "B.Cu")
		(net "GND")
	)
	(via
		(at 291.32784 -384.041904)
		(size 0.508)
		(drill 0.254)
		(layers "F.Cu" "B.Cu")
		(net "GND")
	)
	(via
		(at 33.200848 -351.611438)
		(size 0.4064)
		(drill 0.2032)
		(layers "F.Cu" "B.Cu")
		(net "GND")
	)
	(via
		(at 270.80845 -347.92793)
		(size 0.4572)
		(drill 0.254)
		(layers "F.Cu" "B.Cu")
		(net "GND")
	)
	(via
		(at 389.27278 -357.75773)
		(size 0.4064)
		(drill 0.2032)
		(layers "F.Cu" "B.Cu")
		(net "GND")
	)
	(via
		(at 348.931992 -101.030532)
		(size 0.508)
		(drill 0.254)
		(layers "F.Cu" "B.Cu")
		(net "GND")
	)
	(via
		(at 389.644128 -354.098098)
		(size 0.4572)
		(drill 0.254)
		(layers "F.Cu" "B.Cu")
		(net "GND")
	)
	(via
		(at 215.773 -197.866)
		(size 0.508)
		(drill 0.254)
		(layers "F.Cu" "B.Cu")
		(net "GND")
	)
	(via
		(at 286.927798 -407.638504)
		(size 0.508)
		(drill 0.254)
		(layers "F.Cu" "B.Cu")
		(net "GND")
	)
	(via
		(at 269.880842 -25.990042)
		(size 0.508)
		(drill 0.254)
		(layers "F.Cu" "B.Cu")
		(net "GND")
	)
	(via
		(at 396.691612 -100.64496)
		(size 0.508)
		(drill 0.254)
		(layers "F.Cu" "B.Cu")
		(net "GND")
	)
	(via
		(at 133.055868 -351.611438)
		(size 0.4064)
		(drill 0.2032)
		(layers "F.Cu" "B.Cu")
		(net "GND")
	)
	(via
		(at 62.433454 -352.245422)
		(size 0.4572)
		(drill 0.254)
		(layers "F.Cu" "B.Cu")
		(net "GND")
	)
	(via
		(at 414.202118 -58.731404)
		(size 0.508)
		(drill 0.254)
		(layers "F.Cu" "B.Cu")
		(net "GND")
	)
	(via
		(at 416.024822 -303.974754)
		(size 0.4064)
		(drill 0.2032)
		(layers "F.Cu" "B.Cu")
		(net "GND")
	)
	(via
		(at 184.230772 -226.149916)
		(size 0.508)
		(drill 0.254)
		(layers "F.Cu" "B.Cu")
		(net "GND")
	)
	(via
		(at 355.707188 -284.333188)
		(size 0.49022)
		(drill 0.254)
		(layers "F.Cu" "B.Cu")
		(net "GND")
	)
	(via
		(at 176.224946 -289.724846)
		(size 0.4064)
		(drill 0.2032)
		(layers "F.Cu" "B.Cu")
		(net "GND")
	)
	(via
		(at 164.824918 -305.874928)
		(size 0.4064)
		(drill 0.2032)
		(layers "F.Cu" "B.Cu")
		(net "GND")
	)
	(via
		(at 171.31538 -346.09913)
		(size 0.4572)
		(drill 0.254)
		(layers "F.Cu" "B.Cu")
		(net "GND")
	)
	(via
		(at 252.020324 -120.925844)
		(size 0.508)
		(drill 0.254)
		(layers "F.Cu" "B.Cu")
		(net "GND")
	)
	(via
		(at 37.417248 -354.732082)
		(size 0.4064)
		(drill 0.2032)
		(layers "F.Cu" "B.Cu")
		(net "GND")
	)
	(via
		(at 458.10678 -110.785656)
		(size 0.508)
		(drill 0.254)
		(layers "F.Cu" "B.Cu")
		(net "GND")
	)
	(via
		(at 185.250074 -281.649932)
		(size 0.4064)
		(drill 0.2032)
		(layers "F.Cu" "B.Cu")
		(net "GND")
	)
	(via
		(at 84.808314 -156.283406)
		(size 0.508)
		(drill 0.254)
		(layers "F.Cu" "B.Cu")
		(net "GND")
	)
	(via
		(at 130.74777 -372.240302)
		(size 0.4572)
		(drill 0.254)
		(layers "F.Cu" "B.Cu")
		(net "GND")
	)
	(via
		(at 26.374344 -253.45644)
		(size 0.508)
		(drill 0.254)
		(layers "F.Cu" "B.Cu")
		(net "GND")
	)
	(via
		(at 82.924904 -291.624766)
		(size 0.4064)
		(drill 0.2032)
		(layers "F.Cu" "B.Cu")
		(net "GND")
	)
	(via
		(at 122.477022 -120.087136)
		(size 0.508)
		(drill 0.254)
		(layers "F.Cu" "B.Cu")
		(net "GND")
	)
	(via
		(at 430.466246 -133.30809)
		(size 0.508)
		(drill 0.254)
		(layers "F.Cu" "B.Cu")
		(net "GND")
	)
	(via
		(at 361.437936 -293.424102)
		(size 0.508)
		(drill 0.254)
		(layers "F.Cu" "B.Cu")
		(net "GND")
	)
	(via
		(at 140.90396 -350.977454)
		(size 0.4572)
		(drill 0.254)
		(layers "F.Cu" "B.Cu")
		(net "GND")
	)
	(via
		(at 192.075054 -74.58583)
		(size 0.508)
		(drill 0.254)
		(layers "F.Cu" "B.Cu")
		(net "GND")
	)
	(via
		(at 29.54782 -383.940304)
		(size 0.508)
		(drill 0.254)
		(layers "F.Cu" "B.Cu")
		(net "GND")
	)
	(via
		(at 8.455152 -31.390082)
		(size 0.508)
		(drill 0.254)
		(layers "F.Cu" "B.Cu")
		(net "GND")
	)
	(via
		(at 260.181852 -352.703638)
		(size 0.508)
		(drill 0.254)
		(layers "F.Cu" "B.Cu")
		(net "GND")
	)
	(via
		(at 183.649874 -109.879892)
		(size 0.508)
		(drill 0.254)
		(layers "F.Cu" "B.Cu")
		(net "GND")
	)
	(via
		(at 208.407 -197.485)
		(size 0.508)
		(drill 0.254)
		(layers "F.Cu" "B.Cu")
		(net "GND")
	)
	(via
		(at 34.679636 -354.098098)
		(size 0.4572)
		(drill 0.254)
		(layers "F.Cu" "B.Cu")
		(net "GND")
	)
	(via
		(at 359.850944 -293.424102)
		(size 0.508)
		(drill 0.254)
		(layers "F.Cu" "B.Cu")
		(net "GND")
	)
	(via
		(at 165.09746 -343.073482)
		(size 0.4572)
		(drill 0.254)
		(layers "F.Cu" "B.Cu")
		(net "GND")
	)
	(via
		(at 423.15003 -314.899802)
		(size 0.4064)
		(drill 0.2032)
		(layers "F.Cu" "B.Cu")
		(net "GND")
	)
	(via
		(at 98.719132 -46.893226)
		(size 0.508)
		(drill 0.254)
		(layers "F.Cu" "B.Cu")
		(net "GND")
	)
	(via
		(at 409.849828 -316.799722)
		(size 0.4064)
		(drill 0.2032)
		(layers "F.Cu" "B.Cu")
		(net "GND")
	)
	(via
		(at 31.747968 -404.940262)
		(size 0.508)
		(drill 0.254)
		(layers "F.Cu" "B.Cu")
		(net "GND")
	)
	(via
		(at 194.749928 -315.849762)
		(size 0.4064)
		(drill 0.2032)
		(layers "F.Cu" "B.Cu")
		(net "GND")
	)
	(via
		(at 180.50002 -318.699896)
		(size 0.4064)
		(drill 0.2032)
		(layers "F.Cu" "B.Cu")
		(net "GND")
	)
	(via
		(at 412.89351 -154.755088)
		(size 0.508)
		(drill 0.254)
		(layers "F.Cu" "B.Cu")
		(net "GND")
	)
	(via
		(at 397.49984 -310.149748)
		(size 0.4064)
		(drill 0.2032)
		(layers "F.Cu" "B.Cu")
		(net "GND")
	)
	(via
		(at 226.573842 -144.824704)
		(size 0.508)
		(drill 0.254)
		(layers "F.Cu" "B.Cu")
		(net "GND")
	)
	(via
		(at 278.285194 -352.245422)
		(size 0.4572)
		(drill 0.254)
		(layers "F.Cu" "B.Cu")
		(net "GND")
	)
	(via
		(at 366.391952 -149.89683)
		(size 0.508)
		(drill 0.254)
		(layers "F.Cu" "B.Cu")
		(net "GND")
	)
	(via
		(at 30.091888 -354.732082)
		(size 0.4064)
		(drill 0.2032)
		(layers "F.Cu" "B.Cu")
		(net "GND")
	)
	(via
		(at 298.012612 -149.355302)
		(size 0.508)
		(drill 0.254)
		(layers "F.Cu" "B.Cu")
		(net "GND")
	)
	(via
		(at 329.108816 -341.805514)
		(size 0.4572)
		(drill 0.254)
		(layers "F.Cu" "B.Cu")
		(net "GND")
	)
	(via
		(at 286.906462 -98.844862)
		(size 0.508)
		(drill 0.254)
		(layers "F.Cu" "B.Cu")
		(net "GND")
	)
	(via
		(at 92.248736 -29.589984)
		(size 0.508)
		(drill 0.254)
		(layers "F.Cu" "B.Cu")
		(net "GND")
	)
	(via
		(at 142.40129 -392.056874)
		(size 0.508)
		(drill 0.254)
		(layers "F.Cu" "B.Cu")
		(net "GND")
	)
	(via
		(at 405.100028 -313.949842)
		(size 0.4064)
		(drill 0.2032)
		(layers "F.Cu" "B.Cu")
		(net "GND")
	)
	(via
		(at 177.649886 -310.149748)
		(size 0.4064)
		(drill 0.2032)
		(layers "F.Cu" "B.Cu")
		(net "GND")
	)
	(via
		(at 403.338792 -350.977454)
		(size 0.4572)
		(drill 0.254)
		(layers "F.Cu" "B.Cu")
		(net "GND")
	)
	(via
		(at 347.838522 -284.333188)
		(size 0.49022)
		(drill 0.254)
		(layers "F.Cu" "B.Cu")
		(net "GND")
	)
	(via
		(at 137.593324 -96.957642)
		(size 0.508)
		(drill 0.254)
		(layers "F.Cu" "B.Cu")
		(net "GND")
	)
	(via
		(at 161.975038 -290.674806)
		(size 0.4064)
		(drill 0.2032)
		(layers "F.Cu" "B.Cu")
		(net "GND")
	)
	(via
		(at 259.590286 -253.45644)
		(size 0.508)
		(drill 0.254)
		(layers "F.Cu" "B.Cu")
		(net "GND")
	)
	(via
		(at 322.890896 -344.831162)
		(size 0.4572)
		(drill 0.254)
		(layers "F.Cu" "B.Cu")
		(net "GND")
	)
	(via
		(at 128.75895 -138.89482)
		(size 0.508)
		(drill 0.254)
		(layers "F.Cu" "B.Cu")
		(net "GND")
	)
	(via
		(at 283.949902 -143.615156)
		(size 0.508)
		(drill 0.254)
		(layers "F.Cu" "B.Cu")
		(net "GND")
	)
	(via
		(at 131.57708 -350.977454)
		(size 0.4572)
		(drill 0.254)
		(layers "F.Cu" "B.Cu")
		(net "GND")
	)
	(via
		(at 269.764764 -152.295352)
		(size 0.508)
		(drill 0.254)
		(layers "F.Cu" "B.Cu")
		(net "GND")
	)
	(via
		(at 438.336944 -341.781638)
		(size 0.4572)
		(drill 0.254)
		(layers "F.Cu" "B.Cu")
		(net "GND")
	)
	(via
		(at 313.09818 -130.966718)
		(size 0.508)
		(drill 0.254)
		(layers "F.Cu" "B.Cu")
		(net "GND")
	)
	(via
		(at 283.949902 -144.885156)
		(size 0.508)
		(drill 0.254)
		(layers "F.Cu" "B.Cu")
		(net "GND")
	)
	(via
		(at 408.424888 -306.824888)
		(size 0.4064)
		(drill 0.2032)
		(layers "F.Cu" "B.Cu")
		(net "GND")
	)
	(via
		(at 440.053476 -102.328218)
		(size 0.508)
		(drill 0.254)
		(layers "F.Cu" "B.Cu")
		(net "GND")
	)
	(via
		(at 325.999856 -358.391714)
		(size 0.4572)
		(drill 0.254)
		(layers "F.Cu" "B.Cu")
		(net "GND")
	)
	(via
		(at 335.326736 -358.391714)
		(size 0.4572)
		(drill 0.254)
		(layers "F.Cu" "B.Cu")
		(net "GND")
	)
	(via
		(at 32.8295 -343.073482)
		(size 0.4572)
		(drill 0.254)
		(layers "F.Cu" "B.Cu")
		(net "GND")
	)
	(via
		(at 410.324808 -289.724846)
		(size 0.4064)
		(drill 0.2032)
		(layers "F.Cu" "B.Cu")
		(net "GND")
	)
	(via
		(at 298.647612 -143.955008)
		(size 0.508)
		(drill 0.254)
		(layers "F.Cu" "B.Cu")
		(net "GND")
	)
	(via
		(at 342.876378 -288.14649)
		(size 0.508)
		(drill 0.254)
		(layers "F.Cu" "B.Cu")
		(net "GND")
	)
	(via
		(at 345.529408 -113.563654)
		(size 0.508)
		(drill 0.254)
		(layers "F.Cu" "B.Cu")
		(net "GND")
	)
	(via
		(at 137.795 -346.09913)
		(size 0.4572)
		(drill 0.254)
		(layers "F.Cu" "B.Cu")
		(net "GND")
	)
	(via
		(at 409.849828 -314.899802)
		(size 0.4064)
		(drill 0.2032)
		(layers "F.Cu" "B.Cu")
		(net "GND")
	)
	(via
		(at 298.024804 -289.724846)
		(size 0.4064)
		(drill 0.2032)
		(layers "F.Cu" "B.Cu")
		(net "GND")
	)
	(via
		(at 123.972828 -293.424102)
		(size 0.508)
		(drill 0.254)
		(layers "F.Cu" "B.Cu")
		(net "GND")
	)
	(via
		(at 268.574774 -282.124912)
		(size 0.4064)
		(drill 0.2032)
		(layers "F.Cu" "B.Cu")
		(net "GND")
	)
	(via
		(at 37.133784 -122.091958)
		(size 0.508)
		(drill 0.254)
		(layers "F.Cu" "B.Cu")
		(net "GND")
	)
	(via
		(at 282.349702 -312.049922)
		(size 0.4064)
		(drill 0.2032)
		(layers "F.Cu" "B.Cu")
		(net "GND")
	)
	(via
		(at 364.06074 -128.193546)
		(size 0.508)
		(drill 0.254)
		(layers "F.Cu" "B.Cu")
		(net "GND")
	)
	(via
		(at 50.624994 -291.624766)
		(size 0.4064)
		(drill 0.2032)
		(layers "F.Cu" "B.Cu")
		(net "GND")
	)
	(via
		(at 386.535168 -357.123746)
		(size 0.4572)
		(drill 0.254)
		(layers "F.Cu" "B.Cu")
		(net "GND")
	)
	(via
		(at 425.901104 -355.366066)
		(size 0.4572)
		(drill 0.254)
		(layers "F.Cu" "B.Cu")
		(net "GND")
	)
	(via
		(at 70.50151 -354.098098)
		(size 0.4572)
		(drill 0.254)
		(layers "F.Cu" "B.Cu")
		(net "GND")
	)
	(via
		(at 384.059684 -105.78211)
		(size 0.508)
		(drill 0.254)
		(layers "F.Cu" "B.Cu")
		(net "GND")
	)
	(via
		(at 163.399978 -312.999882)
		(size 0.4064)
		(drill 0.2032)
		(layers "F.Cu" "B.Cu")
		(net "GND")
	)
	(via
		(at 80.07477 -296.37482)
		(size 0.4064)
		(drill 0.2032)
		(layers "F.Cu" "B.Cu")
		(net "GND")
	)
	(via
		(at 79.943198 -28.139136)
		(size 0.508)
		(drill 0.254)
		(layers "F.Cu" "B.Cu")
		(net "GND")
	)
	(via
		(at 156.275024 -286.874966)
		(size 0.4064)
		(drill 0.2032)
		(layers "F.Cu" "B.Cu")
		(net "GND")
	)
	(via
		(at 58.699908 -312.999882)
		(size 0.4064)
		(drill 0.2032)
		(layers "F.Cu" "B.Cu")
		(net "GND")
	)
	(via
		(at 378.242068 -49.574704)
		(size 0.508)
		(drill 0.254)
		(layers "F.Cu" "B.Cu")
		(net "GND")
	)
	(via
		(at 289.127692 -400.938492)
		(size 0.508)
		(drill 0.254)
		(layers "F.Cu" "B.Cu")
		(net "GND")
	)
	(via
		(at 188.039248 -31.652972)
		(size 0.508)
		(drill 0.254)
		(layers "F.Cu" "B.Cu")
		(net "GND")
	)
	(via
		(at 324.741032 -350.977454)
		(size 0.4572)
		(drill 0.254)
		(layers "F.Cu" "B.Cu")
		(net "GND")
	)
	(via
		(at 313.471306 -51.661822)
		(size 0.508)
		(drill 0.254)
		(layers "F.Cu" "B.Cu")
		(net "GND")
	)
	(via
		(at 410.324808 -306.824888)
		(size 0.4064)
		(drill 0.2032)
		(layers "F.Cu" "B.Cu")
		(net "GND")
	)
	(via
		(at 25.358344 -253.45644)
		(size 0.508)
		(drill 0.254)
		(layers "F.Cu" "B.Cu")
		(net "GND")
	)
	(via
		(at 279.024842 -289.724846)
		(size 0.4064)
		(drill 0.2032)
		(layers "F.Cu" "B.Cu")
		(net "GND")
	)
	(via
		(at 135.347202 -148.718778)
		(size 0.508)
		(drill 0.254)
		(layers "F.Cu" "B.Cu")
		(net "GND")
	)
	(via
		(at 223.647254 -180.495194)
		(size 0.508)
		(drill 0.254)
		(layers "F.Cu" "B.Cu")
		(net "GND")
	)
	(via
		(at 374.493536 -286.331914)
		(size 0.508)
		(drill 0.254)
		(layers "F.Cu" "B.Cu")
		(net "GND")
	)
	(via
		(at 228.578664 -203.40701)
		(size 0.508)
		(drill 0.254)
		(layers "F.Cu" "B.Cu")
		(net "GND")
	)
	(via
		(at 95.473266 -73.20026)
		(size 0.508)
		(drill 0.254)
		(layers "F.Cu" "B.Cu")
		(net "GND")
	)
	(via
		(at 18.427446 -213.059772)
		(size 0.508)
		(drill 0.254)
		(layers "F.Cu" "B.Cu")
		(net "GND")
	)
	(via
		(at 182.348886 -33.19018)
		(size 0.508)
		(drill 0.254)
		(layers "F.Cu" "B.Cu")
		(net "GND")
	)
	(via
		(at 97.939098 -28.05303)
		(size 0.508)
		(drill 0.254)
		(layers "F.Cu" "B.Cu")
		(net "GND")
	)
	(via
		(at 116.403628 -351.611438)
		(size 0.4064)
		(drill 0.2032)
		(layers "F.Cu" "B.Cu")
		(net "GND")
	)
	(via
		(at 162.450018 -314.899802)
		(size 0.4064)
		(drill 0.2032)
		(layers "F.Cu" "B.Cu")
		(net "GND")
	)
	(via
		(at 385.149852 -301.599854)
		(size 0.4064)
		(drill 0.2032)
		(layers "F.Cu" "B.Cu")
		(net "GND")
	)
	(via
		(at 101.974904 -73.87463)
		(size 0.508)
		(drill 0.254)
		(layers "F.Cu" "B.Cu")
		(net "GND")
	)
	(via
		(at 172.547788 -378.94006)
		(size 0.508)
		(drill 0.254)
		(layers "F.Cu" "B.Cu")
		(net "GND")
	)
	(via
		(at 395.59992 -277.849838)
		(size 0.4064)
		(drill 0.2032)
		(layers "F.Cu" "B.Cu")
		(net "GND")
	)
	(via
		(at 421.127682 -381.241808)
		(size 0.508)
		(drill 0.254)
		(layers "F.Cu" "B.Cu")
		(net "GND")
	)
	(via
		(at 429.927766 -406.040336)
		(size 0.508)
		(drill 0.254)
		(layers "F.Cu" "B.Cu")
		(net "GND")
	)
	(via
		(at 416.857942 -56.809894)
		(size 0.508)
		(drill 0.254)
		(layers "F.Cu" "B.Cu")
		(net "GND")
	)
	(via
		(at 253.9238 -258.6736)
		(size 0.508)
		(drill 0.254)
		(layers "F.Cu" "B.Cu")
		(net "GND")
	)
	(via
		(at 167.835072 -342.439498)
		(size 0.4064)
		(drill 0.2032)
		(layers "F.Cu" "B.Cu")
		(net "GND")
	)
	(via
		(at 297.549824 -276.899878)
		(size 0.4064)
		(drill 0.2032)
		(layers "F.Cu" "B.Cu")
		(net "GND")
	)
	(via
		(at 19.247358 -148.718778)
		(size 0.508)
		(drill 0.254)
		(layers "F.Cu" "B.Cu")
		(net "GND")
	)
	(via
		(at 16.327374 -280.6954)
		(size 0.508)
		(drill 0.254)
		(layers "F.Cu" "B.Cu")
		(net "GND")
	)
	(via
		(at 46.34992 -274.999958)
		(size 0.4064)
		(drill 0.2032)
		(layers "F.Cu" "B.Cu")
		(net "GND")
	)
	(via
		(at 48.72482 -298.27474)
		(size 0.4064)
		(drill 0.2032)
		(layers "F.Cu" "B.Cu")
		(net "GND")
	)
	(via
		(at 272.102072 -58.096404)
		(size 0.508)
		(drill 0.254)
		(layers "F.Cu" "B.Cu")
		(net "GND")
	)
	(via
		(at 63.912242 -342.439498)
		(size 0.4064)
		(drill 0.2032)
		(layers "F.Cu" "B.Cu")
		(net "GND")
	)
	(via
		(at 335.405222 -307.82387)
		(size 0.508)
		(drill 0.254)
		(layers "F.Cu" "B.Cu")
		(net "GND")
	)
	(via
		(at 131.256024 -127.021844)
		(size 0.508)
		(drill 0.254)
		(layers "F.Cu" "B.Cu")
		(net "GND")
	)
	(via
		(at 227.067872 -217.904314)
		(size 0.4572)
		(drill 0.254)
		(layers "F.Cu" "B.Cu")
		(net "GND")
	)
	(via
		(at 47.77486 -287.824926)
		(size 0.4064)
		(drill 0.2032)
		(layers "F.Cu" "B.Cu")
		(net "GND")
	)
	(via
		(at 121.568718 -59.974734)
		(size 0.508)
		(drill 0.254)
		(layers "F.Cu" "B.Cu")
		(net "GND")
	)
	(via
		(at 385.05638 -348.58579)
		(size 0.4064)
		(drill 0.2032)
		(layers "F.Cu" "B.Cu")
		(net "GND")
	)
	(via
		(at 437.30164 -303.026826)
		(size 0.508)
		(drill 0.254)
		(layers "F.Cu" "B.Cu")
		(net "GND")
	)
	(via
		(at 295.998138 -20.417536)
		(size 0.508)
		(drill 0.254)
		(layers "F.Cu" "B.Cu")
		(net "GND")
	)
	(via
		(at 75.79995 -282.599892)
		(size 0.4064)
		(drill 0.2032)
		(layers "F.Cu" "B.Cu")
		(net "GND")
	)
	(via
		(at 185.250074 -316.799722)
		(size 0.4064)
		(drill 0.2032)
		(layers "F.Cu" "B.Cu")
		(net "GND")
	)
	(via
		(at 272.798286 -253.45644)
		(size 0.508)
		(drill 0.254)
		(layers "F.Cu" "B.Cu")
		(net "GND")
	)
	(via
		(at 298.78909 -354.098098)
		(size 0.4572)
		(drill 0.254)
		(layers "F.Cu" "B.Cu")
		(net "GND")
	)
	(via
		(at 142.719044 -184.947052)
		(size 0.508)
		(drill 0.254)
		(layers "F.Cu" "B.Cu")
		(net "GND")
	)
	(via
		(at 161.9885 -355.366066)
		(size 0.4572)
		(drill 0.254)
		(layers "F.Cu" "B.Cu")
		(net "GND")
	)
	(via
		(at 254.781304 -33.459674)
		(size 0.508)
		(drill 0.254)
		(layers "F.Cu" "B.Cu")
		(net "GND")
	)
	(via
		(at 399.93316 -124.154946)
		(size 0.508)
		(drill 0.254)
		(layers "F.Cu" "B.Cu")
		(net "GND")
	)
	(via
		(at 322.032122 -125.378972)
		(size 0.508)
		(drill 0.254)
		(layers "F.Cu" "B.Cu")
		(net "GND")
	)
	(via
		(at 68.651374 -355.366066)
		(size 0.4572)
		(drill 0.254)
		(layers "F.Cu" "B.Cu")
		(net "GND")
	)
	(via
		(at 112.446816 -128.632458)
		(size 0.508)
		(drill 0.254)
		(layers "F.Cu" "B.Cu")
		(net "GND")
	)
	(via
		(at 277.251668 -107.845098)
		(size 0.508)
		(drill 0.254)
		(layers "F.Cu" "B.Cu")
		(net "GND")
	)
	(via
		(at 161.500058 -281.649932)
		(size 0.4064)
		(drill 0.2032)
		(layers "F.Cu" "B.Cu")
		(net "GND")
	)
	(via
		(at 117.882416 -358.391714)
		(size 0.4572)
		(drill 0.254)
		(layers "F.Cu" "B.Cu")
		(net "GND")
	)
	(via
		(at 228.238304 -64.276224)
		(size 0.508)
		(drill 0.254)
		(layers "F.Cu" "B.Cu")
		(net "GND")
	)
	(via
		(at 52.524914 -291.624766)
		(size 0.4064)
		(drill 0.2032)
		(layers "F.Cu" "B.Cu")
		(net "GND")
	)
	(via
		(at 210.380834 -27.79014)
		(size 0.508)
		(drill 0.254)
		(layers "F.Cu" "B.Cu")
		(net "GND")
	)
	(via
		(at 172.945552 -345.465146)
		(size 0.4064)
		(drill 0.2032)
		(layers "F.Cu" "B.Cu")
		(net "GND")
	)
	(via
		(at 269.333726 -99.116642)
		(size 0.508)
		(drill 0.254)
		(layers "F.Cu" "B.Cu")
		(net "GND")
	)
	(via
		(at 27.347926 -372.341902)
		(size 0.508)
		(drill 0.254)
		(layers "F.Cu" "B.Cu")
		(net "GND")
	)
	(via
		(at 38.749986 -314.899802)
		(size 0.4064)
		(drill 0.2032)
		(layers "F.Cu" "B.Cu")
		(net "GND")
	)
	(via
		(at 116.674646 -172.216064)
		(size 0.508)
		(drill 0.254)
		(layers "F.Cu" "B.Cu")
		(net "GND")
	)
	(via
		(at 74.84999 -316.799722)
		(size 0.4064)
		(drill 0.2032)
		(layers "F.Cu" "B.Cu")
		(net "GND")
	)
	(via
		(at 295.174924 -303.974754)
		(size 0.4064)
		(drill 0.2032)
		(layers "F.Cu" "B.Cu")
		(net "GND")
	)
	(via
		(at 418.399976 -281.649932)
		(size 0.4064)
		(drill 0.2032)
		(layers "F.Cu" "B.Cu")
		(net "GND")
	)
	(via
		(at 388.127748 -407.638504)
		(size 0.508)
		(drill 0.254)
		(layers "F.Cu" "B.Cu")
		(net "GND")
	)
	(via
		(at 282.872942 -345.465146)
		(size 0.4064)
		(drill 0.2032)
		(layers "F.Cu" "B.Cu")
		(net "GND")
	)
	(via
		(at 299.449744 -314.899802)
		(size 0.4064)
		(drill 0.2032)
		(layers "F.Cu" "B.Cu")
		(net "GND")
	)
	(via
		(at 407.949908 -281.649932)
		(size 0.4064)
		(drill 0.2032)
		(layers "F.Cu" "B.Cu")
		(net "GND")
	)
	(via
		(at 107.348274 -286.842454)
		(size 0.508)
		(drill 0.254)
		(layers "F.Cu" "B.Cu")
		(net "GND")
	)
	(via
		(at 165.299898 -318.699896)
		(size 0.4064)
		(drill 0.2032)
		(layers "F.Cu" "B.Cu")
		(net "GND")
	)
	(via
		(at 305.992022 -70.918832)
		(size 0.508)
		(drill 0.254)
		(layers "F.Cu" "B.Cu")
		(net "GND")
	)
	(via
		(at 415.549842 -274.999958)
		(size 0.4064)
		(drill 0.2032)
		(layers "F.Cu" "B.Cu")
		(net "GND")
	)
	(via
		(at 13.902182 -57.461404)
		(size 0.508)
		(drill 0.254)
		(layers "F.Cu" "B.Cu")
		(net "GND")
	)
	(via
		(at 409.374848 -302.074834)
		(size 0.4064)
		(drill 0.2032)
		(layers "F.Cu" "B.Cu")
		(net "GND")
	)
	(via
		(at 77.22489 -289.724846)
		(size 0.4064)
		(drill 0.2032)
		(layers "F.Cu" "B.Cu")
		(net "GND")
	)
	(via
		(at 448.260216 -19.33956)
		(size 0.508)
		(drill 0.254)
		(layers "F.Cu" "B.Cu")
		(net "GND")
	)
	(via
		(at 383.426208 -354.098098)
		(size 0.4572)
		(drill 0.254)
		(layers "F.Cu" "B.Cu")
		(net "GND")
	)
	(via
		(at 281.874722 -299.224954)
		(size 0.4064)
		(drill 0.2032)
		(layers "F.Cu" "B.Cu")
		(net "GND")
	)
	(via
		(at 71.524876 -299.224954)
		(size 0.4064)
		(drill 0.2032)
		(layers "F.Cu" "B.Cu")
		(net "GND")
	)
	(via
		(at 136.039352 -32.911796)
		(size 0.508)
		(drill 0.254)
		(layers "F.Cu" "B.Cu")
		(net "GND")
	)
	(via
		(at 315.740288 -135.114538)
		(size 0.508)
		(drill 0.254)
		(layers "F.Cu" "B.Cu")
		(net "GND")
	)
	(via
		(at 393.7 -274.049744)
		(size 0.4064)
		(drill 0.2032)
		(layers "F.Cu" "B.Cu")
		(net "GND")
	)
	(via
		(at 187.624974 -293.52494)
		(size 0.4064)
		(drill 0.2032)
		(layers "F.Cu" "B.Cu")
		(net "GND")
	)
	(via
		(at 240.020094 -29.590238)
		(size 0.508)
		(drill 0.254)
		(layers "F.Cu" "B.Cu")
		(net "GND")
	)
	(via
		(at 200.908158 -120.30456)
		(size 0.508)
		(drill 0.254)
		(layers "F.Cu" "B.Cu")
		(net "GND")
	)
	(via
		(at 47.032926 -131.76504)
		(size 0.508)
		(drill 0.254)
		(layers "F.Cu" "B.Cu")
		(net "GND")
	)
	(via
		(at 194.336924 -346.09913)
		(size 0.4572)
		(drill 0.254)
		(layers "F.Cu" "B.Cu")
		(net "GND")
	)
	(via
		(at 179.888642 -31.642304)
		(size 0.508)
		(drill 0.254)
		(layers "F.Cu" "B.Cu")
		(net "GND")
	)
	(via
		(at 108.839 -87.827104)
		(size 0.508)
		(drill 0.254)
		(layers "F.Cu" "B.Cu")
		(net "GND")
	)
	(via
		(at 436.527702 -408.840178)
		(size 0.508)
		(drill 0.254)
		(layers "F.Cu" "B.Cu")
		(net "GND")
	)
	(via
		(at 106.747564 -161.096452)
		(size 0.508)
		(drill 0.254)
		(layers "F.Cu" "B.Cu")
		(net "GND")
	)
	(via
		(at 289.94989 -276.899878)
		(size 0.4064)
		(drill 0.2032)
		(layers "F.Cu" "B.Cu")
		(net "GND")
	)
	(via
		(at 298.417742 -357.75773)
		(size 0.4064)
		(drill 0.2032)
		(layers "F.Cu" "B.Cu")
		(net "GND")
	)
	(via
		(at 255.154176 -80.7847)
		(size 0.508)
		(drill 0.254)
		(layers "F.Cu" "B.Cu")
		(net "GND")
	)
	(via
		(at 366.06988 -290.05149)
		(size 0.508)
		(drill 0.254)
		(layers "F.Cu" "B.Cu")
		(net "GND")
	)
	(via
		(at 308.474872 -296.37482)
		(size 0.4064)
		(drill 0.2032)
		(layers "F.Cu" "B.Cu")
		(net "GND")
	)
	(via
		(at 431.840386 -135.114538)
		(size 0.508)
		(drill 0.254)
		(layers "F.Cu" "B.Cu")
		(net "GND")
	)
	(via
		(at 144.01292 -343.073482)
		(size 0.4572)
		(drill 0.254)
		(layers "F.Cu" "B.Cu")
		(net "GND")
	)
	(via
		(at 133.423152 -134.601966)
		(size 0.508)
		(drill 0.254)
		(layers "F.Cu" "B.Cu")
		(net "GND")
	)
	(via
		(at 300.12767 -381.638556)
		(size 0.508)
		(drill 0.254)
		(layers "F.Cu" "B.Cu")
		(net "GND")
	)
	(via
		(at 315.647832 -64.312292)
		(size 0.508)
		(drill 0.254)
		(layers "F.Cu" "B.Cu")
		(net "GND")
	)
	(via
		(at 208.002124 -56.826404)
		(size 0.508)
		(drill 0.254)
		(layers "F.Cu" "B.Cu")
		(net "GND")
	)
	(via
		(at 170.999912 -313.949842)
		(size 0.4064)
		(drill 0.2032)
		(layers "F.Cu" "B.Cu")
		(net "GND")
	)
	(via
		(at 154.375104 -289.724846)
		(size 0.4064)
		(drill 0.2032)
		(layers "F.Cu" "B.Cu")
		(net "GND")
	)
	(via
		(at 239.989106 -229.2096)
		(size 0.508)
		(drill 0.254)
		(layers "F.Cu" "B.Cu")
		(net "GND")
	)
	(via
		(at 270.949928 -310.149748)
		(size 0.4064)
		(drill 0.2032)
		(layers "F.Cu" "B.Cu")
		(net "GND")
	)
	(via
		(at 189.524894 -301.124874)
		(size 0.4064)
		(drill 0.2032)
		(layers "F.Cu" "B.Cu")
		(net "GND")
	)
	(via
		(at 170.524932 -285.924752)
		(size 0.4064)
		(drill 0.2032)
		(layers "F.Cu" "B.Cu")
		(net "GND")
	)
	(via
		(at 221.08033 -24.571452)
		(size 0.508)
		(drill 0.254)
		(layers "F.Cu" "B.Cu")
		(net "GND")
	)
	(via
		(at 307.049678 -272.14957)
		(size 0.4064)
		(drill 0.2032)
		(layers "F.Cu" "B.Cu")
		(net "GND")
	)
	(via
		(at 424.274996 -74.58583)
		(size 0.508)
		(drill 0.254)
		(layers "F.Cu" "B.Cu")
		(net "GND")
	)
	(via
		(at 17.733264 -121.525284)
		(size 0.508)
		(drill 0.254)
		(layers "F.Cu" "B.Cu")
		(net "GND")
	)
	(via
		(at 282.824936 -298.27474)
		(size 0.4064)
		(drill 0.2032)
		(layers "F.Cu" "B.Cu")
		(net "GND")
	)
	(via
		(at 401.15236 -111.44504)
		(size 0.508)
		(drill 0.254)
		(layers "F.Cu" "B.Cu")
		(net "GND")
	)
	(via
		(at 446.238376 -115.021614)
		(size 0.508)
		(drill 0.254)
		(layers "F.Cu" "B.Cu")
		(net "GND")
	)
	(via
		(at 380.317248 -358.391714)
		(size 0.4572)
		(drill 0.254)
		(layers "F.Cu" "B.Cu")
		(net "GND")
	)
	(via
		(at 135.242046 -198.726806)
		(size 0.508)
		(drill 0.254)
		(layers "F.Cu" "B.Cu")
		(net "GND")
	)
	(via
		(at 53.949854 -314.899802)
		(size 0.4064)
		(drill 0.2032)
		(layers "F.Cu" "B.Cu")
		(net "GND")
	)
	(via
		(at 305.422046 -52.51704)
		(size 0.508)
		(drill 0.254)
		(layers "F.Cu" "B.Cu")
		(net "GND")
	)
	(via
		(at 341.927942 -411.141926)
		(size 0.508)
		(drill 0.254)
		(layers "F.Cu" "B.Cu")
		(net "GND")
	)
	(via
		(at 7.095236 -306.606194)
		(size 0.508)
		(drill 0.254)
		(layers "F.Cu" "B.Cu")
		(net "GND")
	)
	(via
		(at 333.594964 -105.057194)
		(size 0.508)
		(drill 0.254)
		(layers "F.Cu" "B.Cu")
		(net "GND")
	)
	(via
		(at 71.999856 -312.999882)
		(size 0.4064)
		(drill 0.2032)
		(layers "F.Cu" "B.Cu")
		(net "GND")
	)
	(via
		(at 287.612074 -354.098098)
		(size 0.4572)
		(drill 0.254)
		(layers "F.Cu" "B.Cu")
		(net "GND")
	)
	(via
		(at 277.124922 -283.074872)
		(size 0.4064)
		(drill 0.2032)
		(layers "F.Cu" "B.Cu")
		(net "GND")
	)
	(via
		(at 47.29988 -308.249828)
		(size 0.4064)
		(drill 0.2032)
		(layers "F.Cu" "B.Cu")
		(net "GND")
	)
	(via
		(at 404.624794 -300.174914)
		(size 0.4064)
		(drill 0.2032)
		(layers "F.Cu" "B.Cu")
		(net "GND")
	)
	(via
		(at 203.748894 -25.990042)
		(size 0.508)
		(drill 0.254)
		(layers "F.Cu" "B.Cu")
		(net "GND")
	)
	(via
		(at 216.8906 -159.4358)
		(size 0.508)
		(drill 0.254)
		(layers "F.Cu" "B.Cu")
		(net "GND")
	)
	(via
		(at 210.361022 -241.128296)
		(size 0.508)
		(drill 0.254)
		(layers "F.Cu" "B.Cu")
		(net "GND")
	)
	(via
		(at 422.09212 -70.918832)
		(size 0.508)
		(drill 0.254)
		(layers "F.Cu" "B.Cu")
		(net "GND")
	)
	(via
		(at 7.29996 -67.892168)
		(size 0.508)
		(drill 0.254)
		(layers "F.Cu" "B.Cu")
		(net "GND")
	)
	(via
		(at 259.52323 -56.353456)
		(size 0.508)
		(drill 0.254)
		(layers "F.Cu" "B.Cu")
		(net "GND")
	)
	(via
		(at 61.074808 -284.974792)
		(size 0.4064)
		(drill 0.2032)
		(layers "F.Cu" "B.Cu")
		(net "GND")
	)
	(via
		(at 163.874958 -287.824926)
		(size 0.4064)
		(drill 0.2032)
		(layers "F.Cu" "B.Cu")
		(net "GND")
	)
	(via
		(at 92.26423 -346.09913)
		(size 0.4572)
		(drill 0.254)
		(layers "F.Cu" "B.Cu")
		(net "GND")
	)
	(via
		(at 69.824092 -130.710432)
		(size 0.508)
		(drill 0.254)
		(layers "F.Cu" "B.Cu")
		(net "GND")
	)
	(via
		(at 424.57497 -290.674806)
		(size 0.4064)
		(drill 0.2032)
		(layers "F.Cu" "B.Cu")
		(net "GND")
	)
	(via
		(at 159.124904 -277.374858)
		(size 0.4064)
		(drill 0.2032)
		(layers "F.Cu" "B.Cu")
		(net "GND")
	)
	(via
		(at 432.490372 -345.465146)
		(size 0.4064)
		(drill 0.2032)
		(layers "F.Cu" "B.Cu")
		(net "GND")
	)
	(via
		(at 287.099756 -318.699896)
		(size 0.4064)
		(drill 0.2032)
		(layers "F.Cu" "B.Cu")
		(net "GND")
	)
	(via
		(at 32.8295 -341.805514)
		(size 0.4572)
		(drill 0.254)
		(layers "F.Cu" "B.Cu")
		(net "GND")
	)
	(via
		(at 272.067274 -343.073482)
		(size 0.4572)
		(drill 0.254)
		(layers "F.Cu" "B.Cu")
		(net "GND")
	)
	(via
		(at 304.527712 -397.140176)
		(size 0.508)
		(drill 0.254)
		(layers "F.Cu" "B.Cu")
		(net "GND")
	)
	(via
		(at 278.919178 -46.893226)
		(size 0.508)
		(drill 0.254)
		(layers "F.Cu" "B.Cu")
		(net "GND")
	)
	(via
		(at 176.224946 -297.32478)
		(size 0.4064)
		(drill 0.2032)
		(layers "F.Cu" "B.Cu")
		(net "GND")
	)
	(via
		(at 384.199384 -316.799468)
		(size 0.4064)
		(drill 0.2032)
		(layers "F.Cu" "B.Cu")
		(net "GND")
	)
	(via
		(at 309.899558 -281.649678)
		(size 0.4064)
		(drill 0.2032)
		(layers "F.Cu" "B.Cu")
		(net "GND")
	)
	(via
		(at 360.09834 -21.738336)
		(size 0.508)
		(drill 0.254)
		(layers "F.Cu" "B.Cu")
		(net "GND")
	)
	(via
		(at 51.63312 -140.765022)
		(size 0.508)
		(drill 0.254)
		(layers "F.Cu" "B.Cu")
		(net "GND")
	)
	(via
		(at 432.12766 -372.341902)
		(size 0.508)
		(drill 0.254)
		(layers "F.Cu" "B.Cu")
		(net "GND")
	)
	(via
		(at 65.81267 -134.845044)
		(size 0.508)
		(drill 0.254)
		(layers "F.Cu" "B.Cu")
		(net "GND")
	)
	(via
		(at 10.069322 -145.083276)
		(size 0.508)
		(drill 0.254)
		(layers "F.Cu" "B.Cu")
		(net "GND")
	)
	(via
		(at 466.835998 -389.443976)
		(size 0.508)
		(drill 0.254)
		(layers "F.Cu" "B.Cu")
		(net "GND")
	)
	(via
		(at 27.347926 -401.040092)
		(size 0.508)
		(drill 0.254)
		(layers "F.Cu" "B.Cu")
		(net "GND")
	)
	(via
		(at 117.547644 -400.938492)
		(size 0.508)
		(drill 0.254)
		(layers "F.Cu" "B.Cu")
		(net "GND")
	)
	(via
		(at 196.88683 -0.762)
		(size 0.508)
		(drill 0.254)
		(layers "F.Cu" "B.Cu")
		(net "GND")
	)
	(via
		(at 43.499786 -301.599854)
		(size 0.4064)
		(drill 0.2032)
		(layers "F.Cu" "B.Cu")
		(net "GND")
	)
	(via
		(at 305.149758 -310.149748)
		(size 0.4064)
		(drill 0.2032)
		(layers "F.Cu" "B.Cu")
		(net "GND")
	)
	(via
		(at 463.037682 -123.457462)
		(size 0.508)
		(drill 0.254)
		(layers "F.Cu" "B.Cu")
		(net "GND")
	)
	(via
		(at 47.313342 -34.718498)
		(size 0.508)
		(drill 0.254)
		(layers "F.Cu" "B.Cu")
		(net "GND")
	)
	(via
		(at 219.573856 -210.439762)
		(size 0.508)
		(drill 0.254)
		(layers "F.Cu" "B.Cu")
		(net "GND")
	)
	(via
		(at 161.54781 -404.838662)
		(size 0.508)
		(drill 0.254)
		(layers "F.Cu" "B.Cu")
		(net "GND")
	)
	(via
		(at 402.079968 -343.073482)
		(size 0.4572)
		(drill 0.254)
		(layers "F.Cu" "B.Cu")
		(net "GND")
	)
	(via
		(at 75.240642 -342.439498)
		(size 0.4064)
		(drill 0.2032)
		(layers "F.Cu" "B.Cu")
		(net "GND")
	)
	(via
		(at 132.38099 -29.589984)
		(size 0.508)
		(drill 0.254)
		(layers "F.Cu" "B.Cu")
		(net "GND")
	)
	(via
		(at 41.599866 -312.999882)
		(size 0.4064)
		(drill 0.2032)
		(layers "F.Cu" "B.Cu")
		(net "GND")
	)
	(via
		(at 335.538064 -101.386894)
		(size 0.508)
		(drill 0.254)
		(layers "F.Cu" "B.Cu")
		(net "GND")
	)
	(via
		(at 251.45873 -149.90826)
		(size 0.508)
		(drill 0.254)
		(layers "F.Cu" "B.Cu")
		(net "GND")
	)
	(via
		(at 329.105768 -1.364996)
		(size 0.508)
		(drill 0.254)
		(layers "F.Cu" "B.Cu")
		(net "GND")
	)
	(via
		(at 71.347838 -397.140176)
		(size 0.508)
		(drill 0.254)
		(layers "F.Cu" "B.Cu")
		(net "GND")
	)
	(via
		(at 70.731126 -11.372342)
		(size 0.508)
		(drill 0.254)
		(layers "F.Cu" "B.Cu")
		(net "GND")
	)
	(via
		(at 401.623276 -55.083456)
		(size 0.508)
		(drill 0.254)
		(layers "F.Cu" "B.Cu")
		(net "GND")
	)
	(via
		(at 186.200034 -312.999882)
		(size 0.4064)
		(drill 0.2032)
		(layers "F.Cu" "B.Cu")
		(net "GND")
	)
	(via
		(at 121.331228 -292.789102)
		(size 0.508)
		(drill 0.254)
		(layers "F.Cu" "B.Cu")
		(net "GND")
	)
	(via
		(at 224.978214 -66.3321)
		(size 0.508)
		(drill 0.254)
		(layers "F.Cu" "B.Cu")
		(net "GND")
	)
	(via
		(at 86.747858 -398.24025)
		(size 0.508)
		(drill 0.254)
		(layers "F.Cu" "B.Cu")
		(net "GND")
	)
	(via
		(at 77.69987 -287.349946)
		(size 0.4064)
		(drill 0.2032)
		(layers "F.Cu" "B.Cu")
		(net "GND")
	)
	(via
		(at 440.998356 -114.323114)
		(size 0.508)
		(drill 0.254)
		(layers "F.Cu" "B.Cu")
		(net "GND")
	)
	(via
		(at 423.32783 -377.738386)
		(size 0.508)
		(drill 0.254)
		(layers "F.Cu" "B.Cu")
		(net "GND")
	)
	(via
		(at 83.540346 -145.483326)
		(size 0.508)
		(drill 0.254)
		(layers "F.Cu" "B.Cu")
		(net "GND")
	)
	(via
		(at 435.599332 -345.465146)
		(size 0.4064)
		(drill 0.2032)
		(layers "F.Cu" "B.Cu")
		(net "GND")
	)
	(via
		(at 161.15157 -135.364982)
		(size 0.508)
		(drill 0.254)
		(layers "F.Cu" "B.Cu")
		(net "GND")
	)
	(via
		(at 431.840386 -145.483326)
		(size 0.508)
		(drill 0.254)
		(layers "F.Cu" "B.Cu")
		(net "GND")
	)
	(via
		(at 26.193496 -295.933114)
		(size 0.508)
		(drill 0.254)
		(layers "F.Cu" "B.Cu")
		(net "GND")
	)
	(via
		(at 328.871072 -29.311854)
		(size 0.508)
		(drill 0.254)
		(layers "F.Cu" "B.Cu")
		(net "GND")
	)
	(via
		(at 336.805524 -348.58579)
		(size 0.4064)
		(drill 0.2032)
		(layers "F.Cu" "B.Cu")
		(net "GND")
	)
	(via
		(at 350.14027 -33.857692)
		(size 0.508)
		(drill 0.254)
		(layers "F.Cu" "B.Cu")
		(net "GND")
	)
	(via
		(at 229.923848 -110.930436)
		(size 0.508)
		(drill 0.254)
		(layers "F.Cu" "B.Cu")
		(net "GND")
	)
	(via
		(at 72.267064 -120.035066)
		(size 0.508)
		(drill 0.254)
		(layers "F.Cu" "B.Cu")
		(net "GND")
	)
	(via
		(at 139.645136 -355.366066)
		(size 0.4572)
		(drill 0.254)
		(layers "F.Cu" "B.Cu")
		(net "GND")
	)
	(via
		(at 395.12494 -289.724846)
		(size 0.4064)
		(drill 0.2032)
		(layers "F.Cu" "B.Cu")
		(net "GND")
	)
	(via
		(at 298.024804 -305.874928)
		(size 0.4064)
		(drill 0.2032)
		(layers "F.Cu" "B.Cu")
		(net "GND")
	)
	(via
		(at 304.527712 -376.242072)
		(size 0.508)
		(drill 0.254)
		(layers "F.Cu" "B.Cu")
		(net "GND")
	)
	(via
		(at 404.149814 -309.199788)
		(size 0.4064)
		(drill 0.2032)
		(layers "F.Cu" "B.Cu")
		(net "GND")
	)
	(via
		(at 299.212 -237.871)
		(size 0.508)
		(drill 0.254)
		(layers "F.Cu" "B.Cu")
		(net "GND")
	)
	(via
		(at 397.97482 -301.124874)
		(size 0.4064)
		(drill 0.2032)
		(layers "F.Cu" "B.Cu")
		(net "GND")
	)
	(via
		(at 383.72796 -401.040092)
		(size 0.508)
		(drill 0.254)
		(layers "F.Cu" "B.Cu")
		(net "GND")
	)
	(via
		(at 161.500058 -310.149748)
		(size 0.4064)
		(drill 0.2032)
		(layers "F.Cu" "B.Cu")
		(net "GND")
	)
	(via
		(at 18.56994 -25.832054)
		(size 0.508)
		(drill 0.254)
		(layers "F.Cu" "B.Cu")
		(net "GND")
	)
	(via
		(at 302.774858 -286.874966)
		(size 0.4064)
		(drill 0.2032)
		(layers "F.Cu" "B.Cu")
		(net "GND")
	)
	(via
		(at 136.164828 -357.75773)
		(size 0.4064)
		(drill 0.2032)
		(layers "F.Cu" "B.Cu")
		(net "GND")
	)
	(via
		(at 96.755458 -63.218314)
		(size 0.508)
		(drill 0.254)
		(layers "F.Cu" "B.Cu")
		(net "GND")
	)
	(via
		(at 183.3499 -274.999958)
		(size 0.4064)
		(drill 0.2032)
		(layers "F.Cu" "B.Cu")
		(net "GND")
	)
	(via
		(at 38.347904 -409.940252)
		(size 0.508)
		(drill 0.254)
		(layers "F.Cu" "B.Cu")
		(net "GND")
	)
	(via
		(at 148.007324 -230.875586)
		(size 0.508)
		(drill 0.254)
		(layers "F.Cu" "B.Cu")
		(net "GND")
	)
	(via
		(at 377.158504 -83.661758)
		(size 0.508)
		(drill 0.254)
		(layers "F.Cu" "B.Cu")
		(net "GND")
	)
	(via
		(at 180.975 -302.074834)
		(size 0.4064)
		(drill 0.2032)
		(layers "F.Cu" "B.Cu")
		(net "GND")
	)
	(via
		(at 24.981408 -345.465146)
		(size 0.4064)
		(drill 0.2032)
		(layers "F.Cu" "B.Cu")
		(net "GND")
	)
	(via
		(at 375.6152 -43.85691)
		(size 0.508)
		(drill 0.254)
		(layers "F.Cu" "B.Cu")
		(net "GND")
	)
	(via
		(at 442.580776 -27.79014)
		(size 0.508)
		(drill 0.254)
		(layers "F.Cu" "B.Cu")
		(net "GND")
	)
	(via
		(at 390.857994 -56.809894)
		(size 0.508)
		(drill 0.254)
		(layers "F.Cu" "B.Cu")
		(net "GND")
	)
	(via
		(at 23.146512 -255.647698)
		(size 0.508)
		(drill 0.254)
		(layers "F.Cu" "B.Cu")
		(net "GND")
	)
	(via
		(at 176.555146 -31.390082)
		(size 0.508)
		(drill 0.254)
		(layers "F.Cu" "B.Cu")
		(net "GND")
	)
	(via
		(at 377.722384 -253.45644)
		(size 0.508)
		(drill 0.254)
		(layers "F.Cu" "B.Cu")
		(net "GND")
	)
	(via
		(at 339.728048 -369.938554)
		(size 0.508)
		(drill 0.254)
		(layers "F.Cu" "B.Cu")
		(net "GND")
	)
	(via
		(at 404.242016 -49.574704)
		(size 0.508)
		(drill 0.254)
		(layers "F.Cu" "B.Cu")
		(net "GND")
	)
	(via
		(at 300.399704 -310.149748)
		(size 0.4064)
		(drill 0.2032)
		(layers "F.Cu" "B.Cu")
		(net "GND")
	)
	(via
		(at 74.295 -104.240076)
		(size 0.508)
		(drill 0.254)
		(layers "F.Cu" "B.Cu")
		(net "GND")
	)
	(via
		(at 34.491676 -130.236722)
		(size 0.508)
		(drill 0.254)
		(layers "F.Cu" "B.Cu")
		(net "GND")
	)
	(via
		(at 396.54988 -312.049922)
		(size 0.4064)
		(drill 0.2032)
		(layers "F.Cu" "B.Cu")
		(net "GND")
	)
	(via
		(at 214.829136 -181.340506)
		(size 0.508)
		(drill 0.254)
		(layers "F.Cu" "B.Cu")
		(net "GND")
	)
	(via
		(at 64.59347 -154.755088)
		(size 0.508)
		(drill 0.254)
		(layers "F.Cu" "B.Cu")
		(net "GND")
	)
	(via
		(at 103.62311 -195.629784)
		(size 0.508)
		(drill 0.254)
		(layers "F.Cu" "B.Cu")
		(net "GND")
	)
	(via
		(at 285.052262 -122.354848)
		(size 0.508)
		(drill 0.254)
		(layers "F.Cu" "B.Cu")
		(net "GND")
	)
	(via
		(at 270.474694 -296.37482)
		(size 0.4064)
		(drill 0.2032)
		(layers "F.Cu" "B.Cu")
		(net "GND")
	)
	(via
		(at 296.793412 -125.435106)
		(size 0.508)
		(drill 0.254)
		(layers "F.Cu" "B.Cu")
		(net "GND")
	)
	(via
		(at 399.93316 -138.964924)
		(size 0.508)
		(drill 0.254)
		(layers "F.Cu" "B.Cu")
		(net "GND")
	)
	(via
		(at 92.595954 -103.894128)
		(size 0.508)
		(drill 0.254)
		(layers "F.Cu" "B.Cu")
		(net "GND")
	)
	(via
		(at 40.174926 -298.27474)
		(size 0.4064)
		(drill 0.2032)
		(layers "F.Cu" "B.Cu")
		(net "GND")
	)
	(via
		(at 461.629506 -113.563654)
		(size 0.508)
		(drill 0.254)
		(layers "F.Cu" "B.Cu")
		(net "GND")
	)
	(via
		(at 411.750002 -315.849762)
		(size 0.4064)
		(drill 0.2032)
		(layers "F.Cu" "B.Cu")
		(net "GND")
	)
	(via
		(at 310.849772 -279.749758)
		(size 0.4064)
		(drill 0.2032)
		(layers "F.Cu" "B.Cu")
		(net "GND")
	)
	(via
		(at 294.22471 -285.924752)
		(size 0.4064)
		(drill 0.2032)
		(layers "F.Cu" "B.Cu")
		(net "GND")
	)
	(via
		(at 54.899814 -277.849838)
		(size 0.4064)
		(drill 0.2032)
		(layers "F.Cu" "B.Cu")
		(net "GND")
	)
	(via
		(at 193.324988 -291.624766)
		(size 0.4064)
		(drill 0.2032)
		(layers "F.Cu" "B.Cu")
		(net "GND")
	)
	(via
		(at 106.43616 -136.21766)
		(size 0.508)
		(drill 0.254)
		(layers "F.Cu" "B.Cu")
		(net "GND")
	)
	(via
		(at 157.224984 -273.574764)
		(size 0.4064)
		(drill 0.2032)
		(layers "F.Cu" "B.Cu")
		(net "GND")
	)
	(via
		(at 164.824918 -296.37482)
		(size 0.4064)
		(drill 0.2032)
		(layers "F.Cu" "B.Cu")
		(net "GND")
	)
	(via
		(at 308.949852 -275.949918)
		(size 0.4064)
		(drill 0.2032)
		(layers "F.Cu" "B.Cu")
		(net "GND")
	)
	(via
		(at 163.11499 -142.860522)
		(size 0.508)
		(drill 0.254)
		(layers "F.Cu" "B.Cu")
		(net "GND")
	)
	(via
		(at 427.75124 -354.098098)
		(size 0.4572)
		(drill 0.254)
		(layers "F.Cu" "B.Cu")
		(net "GND")
	)
	(via
		(at 268.09954 -302.550068)
		(size 0.4064)
		(drill 0.2032)
		(layers "F.Cu" "B.Cu")
		(net "GND")
	)
	(via
		(at 147.697698 -85.515704)
		(size 0.508)
		(drill 0.254)
		(layers "F.Cu" "B.Cu")
		(net "GND")
	)
	(via
		(at 75.79995 -307.299868)
		(size 0.4064)
		(drill 0.2032)
		(layers "F.Cu" "B.Cu")
		(net "GND")
	)
	(via
		(at 69.149976 -310.149748)
		(size 0.4064)
		(drill 0.2032)
		(layers "F.Cu" "B.Cu")
		(net "GND")
	)
	(via
		(at 56.618632 -381.515112)
		(size 0.508)
		(drill 0.254)
		(layers "F.Cu" "B.Cu")
		(net "GND")
	)
	(via
		(at 286.149796 -319.65011)
		(size 0.4064)
		(drill 0.2032)
		(layers "F.Cu" "B.Cu")
		(net "GND")
	)
	(via
		(at 227.067872 -217.104468)
		(size 0.4572)
		(drill 0.254)
		(layers "F.Cu" "B.Cu")
		(net "GND")
	)
	(via
		(at 119.14124 -344.831162)
		(size 0.4572)
		(drill 0.254)
		(layers "F.Cu" "B.Cu")
		(net "GND")
	)
	(via
		(at 39.699946 -310.149748)
		(size 0.4064)
		(drill 0.2032)
		(layers "F.Cu" "B.Cu")
		(net "GND")
	)
	(via
		(at 287.574736 -302.074834)
		(size 0.4064)
		(drill 0.2032)
		(layers "F.Cu" "B.Cu")
		(net "GND")
	)
	(via
		(at 389.424926 -289.724846)
		(size 0.4064)
		(drill 0.2032)
		(layers "F.Cu" "B.Cu")
		(net "GND")
	)
	(via
		(at 53.323236 -51.019456)
		(size 0.508)
		(drill 0.254)
		(layers "F.Cu" "B.Cu")
		(net "GND")
	)
	(via
		(at 18.869914 -414.985454)
		(size 0.508)
		(drill 0.254)
		(layers "F.Cu" "B.Cu")
		(net "GND")
	)
	(via
		(at 169.587164 -122.354848)
		(size 0.508)
		(drill 0.254)
		(layers "F.Cu" "B.Cu")
		(net "GND")
	)
	(via
		(at 220.241622 -142.926562)
		(size 0.508)
		(drill 0.254)
		(layers "F.Cu" "B.Cu")
		(net "GND")
	)
	(via
		(at 267.939774 -299.2247)
		(size 0.4064)
		(drill 0.2032)
		(layers "F.Cu" "B.Cu")
		(net "GND")
	)
	(via
		(at 40.24884 -27.79014)
		(size 0.508)
		(drill 0.254)
		(layers "F.Cu" "B.Cu")
		(net "GND")
	)
	(via
		(at 57.979818 -102.798372)
		(size 0.508)
		(drill 0.254)
		(layers "F.Cu" "B.Cu")
		(net "GND")
	)
	(via
		(at 316.672976 -344.831162)
		(size 0.4572)
		(drill 0.254)
		(layers "F.Cu" "B.Cu")
		(net "GND")
	)
	(via
		(at 78.64983 -279.749758)
		(size 0.4064)
		(drill 0.2032)
		(layers "F.Cu" "B.Cu")
		(net "GND")
	)
	(via
		(at 385.433824 -122.091958)
		(size 0.508)
		(drill 0.254)
		(layers "F.Cu" "B.Cu")
		(net "GND")
	)
	(via
		(at 251.457968 -73.85177)
		(size 0.508)
		(drill 0.254)
		(layers "F.Cu" "B.Cu")
		(net "GND")
	)
	(via
		(at 422.881298 -31.118302)
		(size 0.508)
		(drill 0.254)
		(layers "F.Cu" "B.Cu")
		(net "GND")
	)
	(via
		(at 84.06638 -35.871912)
		(size 0.508)
		(drill 0.254)
		(layers "F.Cu" "B.Cu")
		(net "GND")
	)
	(via
		(at 273.799808 -310.149748)
		(size 0.4064)
		(drill 0.2032)
		(layers "F.Cu" "B.Cu")
		(net "GND")
	)
	(via
		(at 393.22502 -301.124874)
		(size 0.4064)
		(drill 0.2032)
		(layers "F.Cu" "B.Cu")
		(net "GND")
	)
	(via
		(at 168.625012 -287.824926)
		(size 0.4064)
		(drill 0.2032)
		(layers "F.Cu" "B.Cu")
		(net "GND")
	)
	(via
		(at 308.174898 -74.58583)
		(size 0.508)
		(drill 0.254)
		(layers "F.Cu" "B.Cu")
		(net "GND")
	)
	(via
		(at 394.17498 -296.37482)
		(size 0.4064)
		(drill 0.2032)
		(layers "F.Cu" "B.Cu")
		(net "GND")
	)
	(via
		(at 399.400014 -278.799798)
		(size 0.4064)
		(drill 0.2032)
		(layers "F.Cu" "B.Cu")
		(net "GND")
	)
	(via
		(at 272.067274 -355.366066)
		(size 0.4572)
		(drill 0.254)
		(layers "F.Cu" "B.Cu")
		(net "GND")
	)
	(via
		(at 331.020166 -5.911596)
		(size 0.508)
		(drill 0.254)
		(layers "F.Cu" "B.Cu")
		(net "GND")
	)
	(via
		(at 279.974802 -305.874928)
		(size 0.4064)
		(drill 0.2032)
		(layers "F.Cu" "B.Cu")
		(net "GND")
	)
	(via
		(at 307.049932 -310.149748)
		(size 0.4064)
		(drill 0.2032)
		(layers "F.Cu" "B.Cu")
		(net "GND")
	)
	(via
		(at 386.098288 -21.077936)
		(size 0.508)
		(drill 0.254)
		(layers "F.Cu" "B.Cu")
		(net "GND")
	)
	(via
		(at 259.52323 -54.067456)
		(size 0.508)
		(drill 0.254)
		(layers "F.Cu" "B.Cu")
		(net "GND")
	)
	(via
		(at 192.850008 -287.349946)
		(size 0.4064)
		(drill 0.2032)
		(layers "F.Cu" "B.Cu")
		(net "GND")
	)
	(via
		(at 201.203306 -60.627006)
		(size 0.508)
		(drill 0.254)
		(layers "F.Cu" "B.Cu")
		(net "GND")
	)
	(via
		(at 415.549842 -279.749758)
		(size 0.4064)
		(drill 0.2032)
		(layers "F.Cu" "B.Cu")
		(net "GND")
	)
	(via
		(at 460.72679 -288.775648)
		(size 0.508)
		(drill 0.254)
		(layers "F.Cu" "B.Cu")
		(net "GND")
	)
	(via
		(at 242.085114 -217.78976)
		(size 0.508)
		(drill 0.254)
		(layers "F.Cu" "B.Cu")
		(net "GND")
	)
	(via
		(at 50.224436 -350.977454)
		(size 0.4572)
		(drill 0.254)
		(layers "F.Cu" "B.Cu")
		(net "GND")
	)
	(via
		(at 37.133784 -106.316526)
		(size 0.508)
		(drill 0.254)
		(layers "F.Cu" "B.Cu")
		(net "GND")
	)
	(via
		(at 340.285832 -347.951806)
		(size 0.4572)
		(drill 0.254)
		(layers "F.Cu" "B.Cu")
		(net "GND")
	)
	(via
		(at 403.338792 -344.831162)
		(size 0.4572)
		(drill 0.254)
		(layers "F.Cu" "B.Cu")
		(net "GND")
	)
	(via
		(at 186.488832 -348.58579)
		(size 0.4064)
		(drill 0.2032)
		(layers "F.Cu" "B.Cu")
		(net "GND")
	)
	(via
		(at 18.755614 -63.218314)
		(size 0.508)
		(drill 0.254)
		(layers "F.Cu" "B.Cu")
		(net "GND")
	)
	(via
		(at 103.023162 -169.68724)
		(size 0.508)
		(drill 0.254)
		(layers "F.Cu" "B.Cu")
		(net "GND")
	)
	(via
		(at 124.007372 -285.953454)
		(size 0.508)
		(drill 0.254)
		(layers "F.Cu" "B.Cu")
		(net "GND")
	)
	(via
		(at 280.449782 -315.849762)
		(size 0.4064)
		(drill 0.2032)
		(layers "F.Cu" "B.Cu")
		(net "GND")
	)
	(via
		(at 87.305134 -357.123746)
		(size 0.4572)
		(drill 0.254)
		(layers "F.Cu" "B.Cu")
		(net "GND")
	)
	(via
		(at 169.574972 -284.024832)
		(size 0.4064)
		(drill 0.2032)
		(layers "F.Cu" "B.Cu")
		(net "GND")
	)
	(via
		(at 448.615816 -101.333046)
		(size 0.508)
		(drill 0.254)
		(layers "F.Cu" "B.Cu")
		(net "GND")
	)
	(via
		(at 144.750028 -310.832246)
		(size 0.508)
		(drill 0.254)
		(layers "F.Cu" "B.Cu")
		(net "GND")
	)
	(via
		(at 418.927788 -398.34185)
		(size 0.508)
		(drill 0.254)
		(layers "F.Cu" "B.Cu")
		(net "GND")
	)
	(via
		(at 160.074864 -292.57498)
		(size 0.4064)
		(drill 0.2032)
		(layers "F.Cu" "B.Cu")
		(net "GND")
	)
	(via
		(at 401.774914 -297.32478)
		(size 0.4064)
		(drill 0.2032)
		(layers "F.Cu" "B.Cu")
		(net "GND")
	)
	(via
		(at 416.024822 -305.874928)
		(size 0.4064)
		(drill 0.2032)
		(layers "F.Cu" "B.Cu")
		(net "GND")
	)
	(via
		(at 172.425106 -296.37482)
		(size 0.4064)
		(drill 0.2032)
		(layers "F.Cu" "B.Cu")
		(net "GND")
	)
	(via
		(at 440.202066 -57.461404)
		(size 0.508)
		(drill 0.254)
		(layers "F.Cu" "B.Cu")
		(net "GND")
	)
	(via
		(at 37.799772 -305.399948)
		(size 0.4064)
		(drill 0.2032)
		(layers "F.Cu" "B.Cu")
		(net "GND")
	)
	(via
		(at 284.724856 -289.724846)
		(size 0.4064)
		(drill 0.2032)
		(layers "F.Cu" "B.Cu")
		(net "GND")
	)
	(via
		(at 311.523126 -55.083456)
		(size 0.508)
		(drill 0.254)
		(layers "F.Cu" "B.Cu")
		(net "GND")
	)
	(via
		(at 92.26423 -350.977454)
		(size 0.4572)
		(drill 0.254)
		(layers "F.Cu" "B.Cu")
		(net "GND")
	)
	(via
		(at 169.465244 -358.391714)
		(size 0.4572)
		(drill 0.254)
		(layers "F.Cu" "B.Cu")
		(net "GND")
	)
	(via
		(at 387.050026 -310.149748)
		(size 0.4064)
		(drill 0.2032)
		(layers "F.Cu" "B.Cu")
		(net "GND")
	)
	(via
		(at 415.549588 -272.14957)
		(size 0.4064)
		(drill 0.2032)
		(layers "F.Cu" "B.Cu")
		(net "GND")
	)
	(via
		(at 277.599902 -273.099784)
		(size 0.4064)
		(drill 0.2032)
		(layers "F.Cu" "B.Cu")
		(net "GND")
	)
	(via
		(at 130.262884 -286.842454)
		(size 0.508)
		(drill 0.254)
		(layers "F.Cu" "B.Cu")
		(net "GND")
	)
	(via
		(at 411.275022 -291.624766)
		(size 0.4064)
		(drill 0.2032)
		(layers "F.Cu" "B.Cu")
		(net "GND")
	)
	(via
		(at 67.66687 -134.845044)
		(size 0.508)
		(drill 0.254)
		(layers "F.Cu" "B.Cu")
		(net "GND")
	)
	(via
		(at 0.766318 -36.772342)
		(size 0.508)
		(drill 0.254)
		(layers "F.Cu" "B.Cu")
		(net "GND")
	)
	(via
		(at 180.975 -285.924752)
		(size 0.4064)
		(drill 0.2032)
		(layers "F.Cu" "B.Cu")
		(net "GND")
	)
	(via
		(at 283.833062 -118.754906)
		(size 0.508)
		(drill 0.254)
		(layers "F.Cu" "B.Cu")
		(net "GND")
	)
	(via
		(at 434.327808 -381.241808)
		(size 0.508)
		(drill 0.254)
		(layers "F.Cu" "B.Cu")
		(net "GND")
	)
	(via
		(at 427.727872 -378.94006)
		(size 0.508)
		(drill 0.254)
		(layers "F.Cu" "B.Cu")
		(net "GND")
	)
	(via
		(at 132.802884 -286.842454)
		(size 0.508)
		(drill 0.254)
		(layers "F.Cu" "B.Cu")
		(net "GND")
	)
	(via
		(at 70.184518 -73.20026)
		(size 0.508)
		(drill 0.254)
		(layers "F.Cu" "B.Cu")
		(net "GND")
	)
	(via
		(at 47.115476 -341.781638)
		(size 0.4572)
		(drill 0.254)
		(layers "F.Cu" "B.Cu")
		(net "GND")
	)
	(via
		(at 273.637756 -74.624184)
		(size 0.508)
		(drill 0.254)
		(layers "F.Cu" "B.Cu")
		(net "GND")
	)
	(via
		(at 167.675052 -284.974792)
		(size 0.4064)
		(drill 0.2032)
		(layers "F.Cu" "B.Cu")
		(net "GND")
	)
	(via
		(at 54.899814 -310.149748)
		(size 0.4064)
		(drill 0.2032)
		(layers "F.Cu" "B.Cu")
		(net "GND")
	)
	(via
		(at 429.927766 -399.441924)
		(size 0.508)
		(drill 0.254)
		(layers "F.Cu" "B.Cu")
		(net "GND")
	)
	(via
		(at 425.99991 -304.449734)
		(size 0.4064)
		(drill 0.2032)
		(layers "F.Cu" "B.Cu")
		(net "GND")
	)
	(via
		(at 332.449678 -212.363304)
		(size 0.508)
		(drill 0.254)
		(layers "F.Cu" "B.Cu")
		(net "GND")
	)
	(via
		(at 107.225846 -214.031576)
		(size 0.508)
		(drill 0.254)
		(layers "F.Cu" "B.Cu")
		(net "GND")
	)
	(via
		(at 376.83694 -345.465146)
		(size 0.4064)
		(drill 0.2032)
		(layers "F.Cu" "B.Cu")
		(net "GND")
	)
	(via
		(at 183.3499 -315.849762)
		(size 0.4064)
		(drill 0.2032)
		(layers "F.Cu" "B.Cu")
		(net "GND")
	)
	(via
		(at 115.200176 -117.338094)
		(size 0.508)
		(drill 0.254)
		(layers "F.Cu" "B.Cu")
		(net "GND")
	)
	(via
		(at 438.339484 -95.801942)
		(size 0.508)
		(drill 0.254)
		(layers "F.Cu" "B.Cu")
		(net "GND")
	)
	(via
		(at 88.637872 -84.617052)
		(size 0.508)
		(drill 0.254)
		(layers "F.Cu" "B.Cu")
		(net "GND")
	)
	(via
		(at 392.38174 -345.465146)
		(size 0.4064)
		(drill 0.2032)
		(layers "F.Cu" "B.Cu")
		(net "GND")
	)
	(via
		(at 4.715256 -60.601606)
		(size 0.508)
		(drill 0.254)
		(layers "F.Cu" "B.Cu")
		(net "GND")
	)
	(via
		(at 296.124884 -291.624766)
		(size 0.4064)
		(drill 0.2032)
		(layers "F.Cu" "B.Cu")
		(net "GND")
	)
	(via
		(at 393.7 -281.649932)
		(size 0.4064)
		(drill 0.2032)
		(layers "F.Cu" "B.Cu")
		(net "GND")
	)
	(via
		(at 372.2751 -74.58583)
		(size 0.508)
		(drill 0.254)
		(layers "F.Cu" "B.Cu")
		(net "GND")
	)
	(via
		(at 140.90396 -352.245422)
		(size 0.4572)
		(drill 0.254)
		(layers "F.Cu" "B.Cu")
		(net "GND")
	)
	(via
		(at 47.187104 -139.731242)
		(size 0.508)
		(drill 0.254)
		(layers "F.Cu" "B.Cu")
		(net "GND")
	)
	(via
		(at 426.94987 -307.299868)
		(size 0.4064)
		(drill 0.2032)
		(layers "F.Cu" "B.Cu")
		(net "GND")
	)
	(via
		(at 231.867456 -217.904314)
		(size 0.4572)
		(drill 0.254)
		(layers "F.Cu" "B.Cu")
		(net "GND")
	)
	(via
		(at 434.327808 -398.24025)
		(size 0.508)
		(drill 0.254)
		(layers "F.Cu" "B.Cu")
		(net "GND")
	)
	(via
		(at 226.430078 -416.508438)
		(size 0.508)
		(drill 0.254)
		(layers "F.Cu" "B.Cu")
		(net "GND")
	)
	(via
		(at 170.806364 -118.754906)
		(size 0.508)
		(drill 0.254)
		(layers "F.Cu" "B.Cu")
		(net "GND")
	)
	(via
		(at 330.927964 -406.141936)
		(size 0.508)
		(drill 0.254)
		(layers "F.Cu" "B.Cu")
		(net "GND")
	)
	(via
		(at 36.309808 -351.611438)
		(size 0.4064)
		(drill 0.2032)
		(layers "F.Cu" "B.Cu")
		(net "GND")
	)
	(via
		(at 182.87492 -293.52494)
		(size 0.4064)
		(drill 0.2032)
		(layers "F.Cu" "B.Cu")
		(net "GND")
	)
	(via
		(at 42.28084 -31.390082)
		(size 0.508)
		(drill 0.254)
		(layers "F.Cu" "B.Cu")
		(net "GND")
	)
	(via
		(at 241.848894 -27.79014)
		(size 0.508)
		(drill 0.254)
		(layers "F.Cu" "B.Cu")
		(net "GND")
	)
	(via
		(at 436.527702 -382.840484)
		(size 0.508)
		(drill 0.254)
		(layers "F.Cu" "B.Cu")
		(net "GND")
	)
	(via
		(at 394.011912 -357.123746)
		(size 0.4572)
		(drill 0.254)
		(layers "F.Cu" "B.Cu")
		(net "GND")
	)
	(via
		(at 197.945248 -51.227482)
		(size 0.508)
		(drill 0.254)
		(layers "F.Cu" "B.Cu")
		(net "GND")
	)
	(via
		(at 420.567104 -145.755106)
		(size 0.508)
		(drill 0.254)
		(layers "F.Cu" "B.Cu")
		(net "GND")
	)
	(via
		(at 90.44686 -23.583646)
		(size 0.508)
		(drill 0.254)
		(layers "F.Cu" "B.Cu")
		(net "GND")
	)
	(via
		(at 150.59152 -119.026686)
		(size 0.508)
		(drill 0.254)
		(layers "F.Cu" "B.Cu")
		(net "GND")
	)
	(via
		(at 338.27847 -286.842454)
		(size 0.508)
		(drill 0.254)
		(layers "F.Cu" "B.Cu")
		(net "GND")
	)
	(via
		(at 364.612936 -119.39143)
		(size 0.508)
		(drill 0.254)
		(layers "F.Cu" "B.Cu")
		(net "GND")
	)
	(via
		(at 144.65808 -289.532314)
		(size 0.508)
		(drill 0.254)
		(layers "F.Cu" "B.Cu")
		(net "GND")
	)
	(via
		(at 166.725092 -303.974754)
		(size 0.4064)
		(drill 0.2032)
		(layers "F.Cu" "B.Cu")
		(net "GND")
	)
	(via
		(at 138.377422 -228.40188)
		(size 0.508)
		(drill 0.254)
		(layers "F.Cu" "B.Cu")
		(net "GND")
	)
	(via
		(at 168.148 -381.638556)
		(size 0.508)
		(drill 0.254)
		(layers "F.Cu" "B.Cu")
		(net "GND")
	)
	(via
		(at 277.251668 -98.845116)
		(size 0.508)
		(drill 0.254)
		(layers "F.Cu" "B.Cu")
		(net "GND")
	)
	(via
		(at 37.564822 -154.327352)
		(size 0.508)
		(drill 0.254)
		(layers "F.Cu" "B.Cu")
		(net "GND")
	)
	(via
		(at 375.793 -190.627)
		(size 0.508)
		(drill 0.254)
		(layers "F.Cu" "B.Cu")
		(net "GND")
	)
	(via
		(at 194.274948 -297.32478)
		(size 0.4064)
		(drill 0.2032)
		(layers "F.Cu" "B.Cu")
		(net "GND")
	)
	(via
		(at 401.78736 -118.754906)
		(size 0.508)
		(drill 0.254)
		(layers "F.Cu" "B.Cu")
		(net "GND")
	)
	(via
		(at 77.947774 -400.938492)
		(size 0.508)
		(drill 0.254)
		(layers "F.Cu" "B.Cu")
		(net "GND")
	)
	(via
		(at 106.43616 -136.87806)
		(size 0.508)
		(drill 0.254)
		(layers "F.Cu" "B.Cu")
		(net "GND")
	)
	(via
		(at 96.67113 -28.05303)
		(size 0.508)
		(drill 0.254)
		(layers "F.Cu" "B.Cu")
		(net "GND")
	)
	(via
		(at 133.869684 -287.51149)
		(size 0.508)
		(drill 0.254)
		(layers "F.Cu" "B.Cu")
		(net "GND")
	)
	(via
		(at 106.43616 -134.21106)
		(size 0.508)
		(drill 0.254)
		(layers "F.Cu" "B.Cu")
		(net "GND")
	)
	(via
		(at 260.405626 -213.90737)
		(size 0.508)
		(drill 0.254)
		(layers "F.Cu" "B.Cu")
		(net "GND")
	)
	(via
		(at 290.89985 -314.899802)
		(size 0.4064)
		(drill 0.2032)
		(layers "F.Cu" "B.Cu")
		(net "GND")
	)
	(via
		(at 59.649868 -319.65011)
		(size 0.4064)
		(drill 0.2032)
		(layers "F.Cu" "B.Cu")
		(net "GND")
	)
	(via
		(at 376.858022 -286.331914)
		(size 0.508)
		(drill 0.254)
		(layers "F.Cu" "B.Cu")
		(net "GND")
	)
	(via
		(at 302.768 -417.82492)
		(size 0.508)
		(drill 0.254)
		(layers "F.Cu" "B.Cu")
		(net "GND")
	)
	(via
		(at 76.348082 -348.58579)
		(size 0.4064)
		(drill 0.2032)
		(layers "F.Cu" "B.Cu")
		(net "GND")
	)
	(via
		(at 309.899812 -304.449734)
		(size 0.4064)
		(drill 0.2032)
		(layers "F.Cu" "B.Cu")
		(net "GND")
	)
	(via
		(at 427.727872 -407.638504)
		(size 0.508)
		(drill 0.254)
		(layers "F.Cu" "B.Cu")
		(net "GND")
	)
	(via
		(at 255.540002 -74.58583)
		(size 0.508)
		(drill 0.254)
		(layers "F.Cu" "B.Cu")
		(net "GND")
	)
	(via
		(at 45.39996 -304.449734)
		(size 0.4064)
		(drill 0.2032)
		(layers "F.Cu" "B.Cu")
		(net "GND")
	)
	(via
		(at 398.275048 -73.87463)
		(size 0.508)
		(drill 0.254)
		(layers "F.Cu" "B.Cu")
		(net "GND")
	)
	(via
		(at 161.54781 -374.938544)
		(size 0.508)
		(drill 0.254)
		(layers "F.Cu" "B.Cu")
		(net "GND")
	)
	(via
		(at 83.468464 -59.974734)
		(size 0.508)
		(drill 0.254)
		(layers "F.Cu" "B.Cu")
		(net "GND")
	)
	(via
		(at 187.149994 -319.65011)
		(size 0.4064)
		(drill 0.2032)
		(layers "F.Cu" "B.Cu")
		(net "GND")
	)
	(via
		(at 115.34775 -378.94006)
		(size 0.4572)
		(drill 0.254)
		(layers "F.Cu" "B.Cu")
		(net "GND")
	)
	(via
		(at 341.25027 -288.14649)
		(size 0.508)
		(drill 0.254)
		(layers "F.Cu" "B.Cu")
		(net "GND")
	)
	(via
		(at 107.635548 -331.545692)
		(size 0.508)
		(drill 0.254)
		(layers "F.Cu" "B.Cu")
		(net "GND")
	)
	(via
		(at 52.524914 -302.074834)
		(size 0.4064)
		(drill 0.2032)
		(layers "F.Cu" "B.Cu")
		(net "GND")
	)
	(via
		(at 38.347904 -378.83846)
		(size 0.508)
		(drill 0.254)
		(layers "F.Cu" "B.Cu")
		(net "GND")
	)
	(via
		(at 314.649866 -286.399732)
		(size 0.4064)
		(drill 0.2032)
		(layers "F.Cu" "B.Cu")
		(net "GND")
	)
	(via
		(at 425.04995 -315.849762)
		(size 0.4064)
		(drill 0.2032)
		(layers "F.Cu" "B.Cu")
		(net "GND")
	)
	(via
		(at 150.555198 -29.590238)
		(size 0.508)
		(drill 0.254)
		(layers "F.Cu" "B.Cu")
		(net "GND")
	)
	(via
		(at 249.52325 -133.890766)
		(size 0.508)
		(drill 0.254)
		(layers "F.Cu" "B.Cu")
		(net "GND")
	)
	(via
		(at 194.749928 -286.399732)
		(size 0.4064)
		(drill 0.2032)
		(layers "F.Cu" "B.Cu")
		(net "GND")
	)
	(via
		(at 37.324792 -292.57498)
		(size 0.4064)
		(drill 0.2032)
		(layers "F.Cu" "B.Cu")
		(net "GND")
	)
	(via
		(at 14.7955 -310.742584)
		(size 0.508)
		(drill 0.254)
		(layers "F.Cu" "B.Cu")
		(net "GND")
	)
	(via
		(at 307.999892 -277.849838)
		(size 0.4064)
		(drill 0.2032)
		(layers "F.Cu" "B.Cu")
		(net "GND")
	)
	(via
		(at 110.676182 -287.51149)
		(size 0.508)
		(drill 0.254)
		(layers "F.Cu" "B.Cu")
		(net "GND")
	)
	(via
		(at 184.380886 -31.390082)
		(size 0.508)
		(drill 0.254)
		(layers "F.Cu" "B.Cu")
		(net "GND")
	)
	(via
		(at 55.374794 -289.724846)
		(size 0.4064)
		(drill 0.2032)
		(layers "F.Cu" "B.Cu")
		(net "GND")
	)
	(via
		(at 185.010044 -352.245422)
		(size 0.4572)
		(drill 0.254)
		(layers "F.Cu" "B.Cu")
		(net "GND")
	)
	(via
		(at 385.864862 -152.295352)
		(size 0.508)
		(drill 0.254)
		(layers "F.Cu" "B.Cu")
		(net "GND")
	)
	(via
		(at 35.759644 -112.981994)
		(size 0.508)
		(drill 0.254)
		(layers "F.Cu" "B.Cu")
		(net "GND")
	)
	(via
		(at 409.374848 -305.874928)
		(size 0.4064)
		(drill 0.2032)
		(layers "F.Cu" "B.Cu")
		(net "GND")
	)
	(via
		(at 79.59979 -313.949842)
		(size 0.4064)
		(drill 0.2032)
		(layers "F.Cu" "B.Cu")
		(net "GND")
	)
	(via
		(at 383.72796 -402.241766)
		(size 0.508)
		(drill 0.254)
		(layers "F.Cu" "B.Cu")
		(net "GND")
	)
	(via
		(at 57.979818 -99.750372)
		(size 0.508)
		(drill 0.254)
		(layers "F.Cu" "B.Cu")
		(net "GND")
	)
	(via
		(at 45.051726 -106.045)
		(size 0.508)
		(drill 0.254)
		(layers "F.Cu" "B.Cu")
		(net "GND")
	)
	(via
		(at 420.774876 -303.024794)
		(size 0.4064)
		(drill 0.2032)
		(layers "F.Cu" "B.Cu")
		(net "GND")
	)
	(via
		(at 401.299934 -274.049744)
		(size 0.4064)
		(drill 0.2032)
		(layers "F.Cu" "B.Cu")
		(net "GND")
	)
	(via
		(at 119.14124 -354.098098)
		(size 0.4572)
		(drill 0.254)
		(layers "F.Cu" "B.Cu")
		(net "GND")
	)
	(via
		(at 12.343384 -116.450364)
		(size 0.508)
		(drill 0.254)
		(layers "F.Cu" "B.Cu")
		(net "GND")
	)
	(via
		(at 65.752218 -172.846746)
		(size 0.508)
		(drill 0.254)
		(layers "F.Cu" "B.Cu")
		(net "GND")
	)
	(via
		(at 360.86796 -258.131564)
		(size 0.508)
		(drill 0.254)
		(layers "F.Cu" "B.Cu")
		(net "GND")
	)
	(via
		(at 411.275022 -302.074834)
		(size 0.4064)
		(drill 0.2032)
		(layers "F.Cu" "B.Cu")
		(net "GND")
	)
	(via
		(at 48.3743 -344.831162)
		(size 0.4572)
		(drill 0.254)
		(layers "F.Cu" "B.Cu")
		(net "GND")
	)
	(via
		(at 283.24429 -343.073482)
		(size 0.4572)
		(drill 0.254)
		(layers "F.Cu" "B.Cu")
		(net "GND")
	)
	(via
		(at 73.547732 -409.940252)
		(size 0.508)
		(drill 0.254)
		(layers "F.Cu" "B.Cu")
		(net "GND")
	)
	(via
		(at 36.14801 -382.84023)
		(size 0.508)
		(drill 0.254)
		(layers "F.Cu" "B.Cu")
		(net "GND")
	)
	(via
		(at 424.09999 -305.399948)
		(size 0.4064)
		(drill 0.2032)
		(layers "F.Cu" "B.Cu")
		(net "GND")
	)
	(via
		(at 426.47489 -303.024794)
		(size 0.4064)
		(drill 0.2032)
		(layers "F.Cu" "B.Cu")
		(net "GND")
	)
	(via
		(at 23.50262 -358.391714)
		(size 0.4572)
		(drill 0.254)
		(layers "F.Cu" "B.Cu")
		(net "GND")
	)
	(via
		(at 94.034356 -243.792248)
		(size 0.508)
		(drill 0.254)
		(layers "F.Cu" "B.Cu")
		(net "GND")
	)
	(via
		(at 71.760334 -352.245422)
		(size 0.4572)
		(drill 0.254)
		(layers "F.Cu" "B.Cu")
		(net "GND")
	)
	(via
		(at 415.96691 -147.555204)
		(size 0.508)
		(drill 0.254)
		(layers "F.Cu" "B.Cu")
		(net "GND")
	)
	(via
		(at 45.39996 -274.049744)
		(size 0.4064)
		(drill 0.2032)
		(layers "F.Cu" "B.Cu")
		(net "GND")
	)
	(via
		(at 153.89987 -315.849762)
		(size 0.4064)
		(drill 0.2032)
		(layers "F.Cu" "B.Cu")
		(net "GND")
	)
	(via
		(at 201.920094 -34.990278)
		(size 0.508)
		(drill 0.254)
		(layers "F.Cu" "B.Cu")
		(net "GND")
	)
	(via
		(at 106.037126 -304.373534)
		(size 0.508)
		(drill 0.254)
		(layers "F.Cu" "B.Cu")
		(net "GND")
	)
	(via
		(at 138.198606 -37.201094)
		(size 0.508)
		(drill 0.254)
		(layers "F.Cu" "B.Cu")
		(net "GND")
	)
	(via
		(at 354.499926 -258.394962)
		(size 0.508)
		(drill 0.254)
		(layers "F.Cu" "B.Cu")
		(net "GND")
	)
	(via
		(at 162.450018 -280.699718)
		(size 0.4064)
		(drill 0.2032)
		(layers "F.Cu" "B.Cu")
		(net "GND")
	)
	(via
		(at 84.54771 -410.041852)
		(size 0.508)
		(drill 0.254)
		(layers "F.Cu" "B.Cu")
		(net "GND")
	)
	(via
		(at 311.933844 -348.58579)
		(size 0.4064)
		(drill 0.2032)
		(layers "F.Cu" "B.Cu")
		(net "GND")
	)
	(via
		(at 180.50002 -274.049744)
		(size 0.4064)
		(drill 0.2032)
		(layers "F.Cu" "B.Cu")
		(net "GND")
	)
	(via
		(at 42.549826 -312.049922)
		(size 0.4064)
		(drill 0.2032)
		(layers "F.Cu" "B.Cu")
		(net "GND")
	)
	(via
		(at 36.14801 -384.041904)
		(size 0.508)
		(drill 0.254)
		(layers "F.Cu" "B.Cu")
		(net "GND")
	)
	(via
		(at 384.039872 -299.2247)
		(size 0.4064)
		(drill 0.2032)
		(layers "F.Cu" "B.Cu")
		(net "GND")
	)
	(via
		(at 143.76908 -279.931114)
		(size 0.508)
		(drill 0.254)
		(layers "F.Cu" "B.Cu")
		(net "GND")
	)
	(via
		(at 146.042126 -49.574704)
		(size 0.508)
		(drill 0.254)
		(layers "F.Cu" "B.Cu")
		(net "GND")
	)
	(via
		(at 164.824918 -284.974792)
		(size 0.4064)
		(drill 0.2032)
		(layers "F.Cu" "B.Cu")
		(net "GND")
	)
	(via
		(at 398.971008 -352.245422)
		(size 0.4572)
		(drill 0.254)
		(layers "F.Cu" "B.Cu")
		(net "GND")
	)
	(via
		(at 138.68146 -33.459674)
		(size 0.508)
		(drill 0.254)
		(layers "F.Cu" "B.Cu")
		(net "GND")
	)
	(via
		(at 54.899814 -281.649932)
		(size 0.4064)
		(drill 0.2032)
		(layers "F.Cu" "B.Cu")
		(net "GND")
	)
	(via
		(at 332.781148 -34.718498)
		(size 0.508)
		(drill 0.254)
		(layers "F.Cu" "B.Cu")
		(net "GND")
	)
	(via
		(at 466.835998 -353.883976)
		(size 0.508)
		(drill 0.254)
		(layers "F.Cu" "B.Cu")
		(net "GND")
	)
	(via
		(at 44.8691 -152.958038)
		(size 0.508)
		(drill 0.254)
		(layers "F.Cu" "B.Cu")
		(net "GND")
	)
	(via
		(at 171.949872 -275.949918)
		(size 0.4064)
		(drill 0.2032)
		(layers "F.Cu" "B.Cu")
		(net "GND")
	)
	(via
		(at 414.012126 -188.169804)
		(size 0.508)
		(drill 0.254)
		(layers "F.Cu" "B.Cu")
		(net "GND")
	)
	(via
		(at 396.0749 -290.674806)
		(size 0.4064)
		(drill 0.2032)
		(layers "F.Cu" "B.Cu")
		(net "GND")
	)
	(via
		(at 241.016282 -280.10104)
		(size 0.508)
		(drill 0.254)
		(layers "F.Cu" "B.Cu")
		(net "GND")
	)
	(via
		(at 339.914484 -351.611438)
		(size 0.4064)
		(drill 0.2032)
		(layers "F.Cu" "B.Cu")
		(net "GND")
	)
	(via
		(at 417.924996 -297.32478)
		(size 0.4064)
		(drill 0.2032)
		(layers "F.Cu" "B.Cu")
		(net "GND")
	)
	(via
		(at 314.366148 -146.017996)
		(size 0.508)
		(drill 0.254)
		(layers "F.Cu" "B.Cu")
		(net "GND")
	)
	(via
		(at 106.837226 -307.877718)
		(size 0.508)
		(drill 0.254)
		(layers "F.Cu" "B.Cu")
		(net "GND")
	)
	(via
		(at 218.812872 -124.790962)
		(size 0.508)
		(drill 0.254)
		(layers "F.Cu" "B.Cu")
		(net "GND")
	)
	(via
		(at 288.049716 -280.699718)
		(size 0.4064)
		(drill 0.2032)
		(layers "F.Cu" "B.Cu")
		(net "GND")
	)
	(via
		(at 235.041186 -45.808138)
		(size 0.508)
		(drill 0.254)
		(layers "F.Cu" "B.Cu")
		(net "GND")
	)
	(via
		(at 169.587164 -98.844862)
		(size 0.508)
		(drill 0.254)
		(layers "F.Cu" "B.Cu")
		(net "GND")
	)
	(via
		(at 358.6353 -113.910364)
		(size 0.508)
		(drill 0.254)
		(layers "F.Cu" "B.Cu")
		(net "GND")
	)
	(via
		(at 19.134836 -347.951806)
		(size 0.4572)
		(drill 0.254)
		(layers "F.Cu" "B.Cu")
		(net "GND")
	)
	(via
		(at 69.70395 -99.187)
		(size 0.508)
		(drill 0.254)
		(layers "F.Cu" "B.Cu")
		(net "GND")
	)
	(via
		(at 134.220712 -63.218314)
		(size 0.508)
		(drill 0.254)
		(layers "F.Cu" "B.Cu")
		(net "GND")
	)
	(via
		(at 412.356046 -33.19018)
		(size 0.508)
		(drill 0.254)
		(layers "F.Cu" "B.Cu")
		(net "GND")
	)
	(via
		(at 20.76196 -162.3187)
		(size 0.508)
		(drill 0.254)
		(layers "F.Cu" "B.Cu")
		(net "GND")
	)
	(via
		(at 66.774822 -305.874928)
		(size 0.4064)
		(drill 0.2032)
		(layers "F.Cu" "B.Cu")
		(net "GND")
	)
	(via
		(at 171.949872 -315.849762)
		(size 0.4064)
		(drill 0.2032)
		(layers "F.Cu" "B.Cu")
		(net "GND")
	)
	(via
		(at 83.540346 -147.824698)
		(size 0.508)
		(drill 0.254)
		(layers "F.Cu" "B.Cu")
		(net "GND")
	)
	(via
		(at 403.674834 -289.724846)
		(size 0.4064)
		(drill 0.2032)
		(layers "F.Cu" "B.Cu")
		(net "GND")
	)
	(via
		(at 25.352756 -354.098098)
		(size 0.4572)
		(drill 0.254)
		(layers "F.Cu" "B.Cu")
		(net "GND")
	)
	(via
		(at 68.674742 -288.774886)
		(size 0.4064)
		(drill 0.2032)
		(layers "F.Cu" "B.Cu")
		(net "GND")
	)
	(via
		(at 299.866812 -145.755106)
		(size 0.508)
		(drill 0.254)
		(layers "F.Cu" "B.Cu")
		(net "GND")
	)
	(via
		(at 48.72482 -284.974792)
		(size 0.4064)
		(drill 0.2032)
		(layers "F.Cu" "B.Cu")
		(net "GND")
	)
	(via
		(at 324.101968 -58.096404)
		(size 0.508)
		(drill 0.254)
		(layers "F.Cu" "B.Cu")
		(net "GND")
	)
	(via
		(at 425.527724 -399.441924)
		(size 0.508)
		(drill 0.254)
		(layers "F.Cu" "B.Cu")
		(net "GND")
	)
	(via
		(at 84.54771 -381.638556)
		(size 0.508)
		(drill 0.254)
		(layers "F.Cu" "B.Cu")
		(net "GND")
	)
	(via
		(at 161.025078 -289.724846)
		(size 0.4064)
		(drill 0.2032)
		(layers "F.Cu" "B.Cu")
		(net "GND")
	)
	(via
		(at 170.999912 -310.149748)
		(size 0.4064)
		(drill 0.2032)
		(layers "F.Cu" "B.Cu")
		(net "GND")
	)
	(via
		(at 77.978254 -343.073482)
		(size 0.4572)
		(drill 0.254)
		(layers "F.Cu" "B.Cu")
		(net "GND")
	)
	(via
		(at 298.012612 -151.155146)
		(size 0.508)
		(drill 0.254)
		(layers "F.Cu" "B.Cu")
		(net "GND")
	)
	(via
		(at 466.835998 -364.043976)
		(size 0.508)
		(drill 0.254)
		(layers "F.Cu" "B.Cu")
		(net "GND")
	)
	(via
		(at 415.96691 -134.845044)
		(size 0.508)
		(drill 0.254)
		(layers "F.Cu" "B.Cu")
		(net "GND")
	)
	(via
		(at 60.124848 -289.724846)
		(size 0.4064)
		(drill 0.2032)
		(layers "F.Cu" "B.Cu")
		(net "GND")
	)
	(via
		(at 226.87026 -306.849526)
		(size 0.508)
		(drill 0.254)
		(layers "F.Cu" "B.Cu")
		(net "GND")
	)
	(via
		(at 179.844954 -27.79014)
		(size 0.508)
		(drill 0.254)
		(layers "F.Cu" "B.Cu")
		(net "GND")
	)
	(via
		(at 144.01292 -341.805514)
		(size 0.4572)
		(drill 0.254)
		(layers "F.Cu" "B.Cu")
		(net "GND")
	)
	(via
		(at 250.410726 -57.439814)
		(size 0.508)
		(drill 0.254)
		(layers "F.Cu" "B.Cu")
		(net "GND")
	)
	(via
		(at 301.5488 -244.7036)
		(size 0.508)
		(drill 0.254)
		(layers "F.Cu" "B.Cu")
		(net "GND")
	)
	(via
		(at 78.64983 -275.949918)
		(size 0.4064)
		(drill 0.2032)
		(layers "F.Cu" "B.Cu")
		(net "GND")
	)
	(via
		(at 193.800222 -274.049744)
		(size 0.4064)
		(drill 0.2032)
		(layers "F.Cu" "B.Cu")
		(net "GND")
	)
	(via
		(at 466.835998 -399.603976)
		(size 0.508)
		(drill 0.254)
		(layers "F.Cu" "B.Cu")
		(net "GND")
	)
	(via
		(at 320.153284 -354.732082)
		(size 0.4064)
		(drill 0.2032)
		(layers "F.Cu" "B.Cu")
		(net "GND")
	)
	(via
		(at 199.64019 -149.083522)
		(size 0.508)
		(drill 0.254)
		(layers "F.Cu" "B.Cu")
		(net "GND")
	)
	(via
		(at 117.547644 -398.24025)
		(size 0.4572)
		(drill 0.254)
		(layers "F.Cu" "B.Cu")
		(net "GND")
	)
	(via
		(at 327.849992 -350.977454)
		(size 0.4572)
		(drill 0.254)
		(layers "F.Cu" "B.Cu")
		(net "GND")
	)
	(via
		(at 185.010044 -349.219774)
		(size 0.4572)
		(drill 0.254)
		(layers "F.Cu" "B.Cu")
		(net "GND")
	)
	(via
		(at 325.637652 -74.624184)
		(size 0.508)
		(drill 0.254)
		(layers "F.Cu" "B.Cu")
		(net "GND")
	)
	(via
		(at 251.26823 -48.753014)
		(size 0.508)
		(drill 0.254)
		(layers "F.Cu" "B.Cu")
		(net "GND")
	)
	(via
		(at 197.600062 -273.099784)
		(size 0.4064)
		(drill 0.2032)
		(layers "F.Cu" "B.Cu")
		(net "GND")
	)
	(via
		(at 163.874958 -284.024832)
		(size 0.4064)
		(drill 0.2032)
		(layers "F.Cu" "B.Cu")
		(net "GND")
	)
	(via
		(at 28.557982 -299.133514)
		(size 0.508)
		(drill 0.254)
		(layers "F.Cu" "B.Cu")
		(net "GND")
	)
	(via
		(at 183.766714 -118.234968)
		(size 0.508)
		(drill 0.254)
		(layers "F.Cu" "B.Cu")
		(net "GND")
	)
	(via
		(at 427.75124 -355.366066)
		(size 0.4572)
		(drill 0.254)
		(layers "F.Cu" "B.Cu")
		(net "GND")
	)
	(via
		(at 122.001788 -279.000712)
		(size 0.508)
		(drill 0.254)
		(layers "F.Cu" "B.Cu")
		(net "GND")
	)
	(via
		(at 283.949902 -146.155156)
		(size 0.508)
		(drill 0.254)
		(layers "F.Cu" "B.Cu")
		(net "GND")
	)
	(via
		(at 39.699946 -318.699896)
		(size 0.4064)
		(drill 0.2032)
		(layers "F.Cu" "B.Cu")
		(net "GND")
	)
	(via
		(at 170.688 -417.82492)
		(size 0.508)
		(drill 0.254)
		(layers "F.Cu" "B.Cu")
		(net "GND")
	)
	(via
		(at 296.793412 -133.0452)
		(size 0.508)
		(drill 0.254)
		(layers "F.Cu" "B.Cu")
		(net "GND")
	)
	(via
		(at 390.902952 -344.831162)
		(size 0.4572)
		(drill 0.254)
		(layers "F.Cu" "B.Cu")
		(net "GND")
	)
	(via
		(at 328.41057 -57.439814)
		(size 0.508)
		(drill 0.254)
		(layers "F.Cu" "B.Cu")
		(net "GND")
	)
	(via
		(at 302.004222 -132.622036)
		(size 0.508)
		(drill 0.254)
		(layers "F.Cu" "B.Cu")
		(net "GND")
	)
	(via
		(at 352.116644 -88.955372)
		(size 0.508)
		(drill 0.254)
		(layers "F.Cu" "B.Cu")
		(net "GND")
	)
	(via
		(at 92.26423 -357.123746)
		(size 0.4572)
		(drill 0.254)
		(layers "F.Cu" "B.Cu")
		(net "GND")
	)
	(via
		(at 423.62501 -298.27474)
		(size 0.4064)
		(drill 0.2032)
		(layers "F.Cu" "B.Cu")
		(net "GND")
	)
	(via
		(at 76.74991 -312.049922)
		(size 0.4064)
		(drill 0.2032)
		(layers "F.Cu" "B.Cu")
		(net "GND")
	)
	(via
		(at 15.685008 -131.312666)
		(size 0.508)
		(drill 0.254)
		(layers "F.Cu" "B.Cu")
		(net "GND")
	)
	(via
		(at 389.899906 -318.699896)
		(size 0.4064)
		(drill 0.2032)
		(layers "F.Cu" "B.Cu")
		(net "GND")
	)
	(via
		(at 269.524734 -287.824926)
		(size 0.4064)
		(drill 0.2032)
		(layers "F.Cu" "B.Cu")
		(net "GND")
	)
	(via
		(at 62.499748 -278.799798)
		(size 0.4064)
		(drill 0.2032)
		(layers "F.Cu" "B.Cu")
		(net "GND")
	)
	(via
		(at 165.09746 -352.245422)
		(size 0.4572)
		(drill 0.254)
		(layers "F.Cu" "B.Cu")
		(net "GND")
	)
	(via
		(at 177.748946 -31.390082)
		(size 0.508)
		(drill 0.254)
		(layers "F.Cu" "B.Cu")
		(net "GND")
	)
	(via
		(at 430.466246 -130.966718)
		(size 0.508)
		(drill 0.254)
		(layers "F.Cu" "B.Cu")
		(net "GND")
	)
	(via
		(at 38.401752 -109.916722)
		(size 0.508)
		(drill 0.254)
		(layers "F.Cu" "B.Cu")
		(net "GND")
	)
	(via
		(at 278.549608 -272.14957)
		(size 0.4064)
		(drill 0.2032)
		(layers "F.Cu" "B.Cu")
		(net "GND")
	)
	(via
		(at 386.701792 -106.316526)
		(size 0.508)
		(drill 0.254)
		(layers "F.Cu" "B.Cu")
		(net "GND")
	)
	(via
		(at 338.435696 -350.977454)
		(size 0.4572)
		(drill 0.254)
		(layers "F.Cu" "B.Cu")
		(net "GND")
	)
	(via
		(at 159.599884 -317.749936)
		(size 0.4064)
		(drill 0.2032)
		(layers "F.Cu" "B.Cu")
		(net "GND")
	)
	(via
		(at 150.868126 -54.238906)
		(size 0.508)
		(drill 0.254)
		(layers "F.Cu" "B.Cu")
		(net "GND")
	)
	(via
		(at 45.654722 -23.880318)
		(size 0.508)
		(drill 0.254)
		(layers "F.Cu" "B.Cu")
		(net "GND")
	)
	(via
		(at 57.721246 -367.033302)
		(size 0.4064)
		(drill 0.2032)
		(layers "F.Cu" "B.Cu")
		(net "GND")
	)
	(via
		(at 153.650442 -253.45644)
		(size 0.508)
		(drill 0.254)
		(layers "F.Cu" "B.Cu")
		(net "GND")
	)
	(via
		(at 342.006682 -110.785656)
		(size 0.508)
		(drill 0.254)
		(layers "F.Cu" "B.Cu")
		(net "GND")
	)
	(via
		(at 436.527702 -399.838418)
		(size 0.508)
		(drill 0.254)
		(layers "F.Cu" "B.Cu")
		(net "GND")
	)
	(via
		(at 279.499822 -312.999882)
		(size 0.4064)
		(drill 0.2032)
		(layers "F.Cu" "B.Cu")
		(net "GND")
	)
	(via
		(at 281.765502 -351.611438)
		(size 0.4064)
		(drill 0.2032)
		(layers "F.Cu" "B.Cu")
		(net "GND")
	)
	(via
		(at 397.49984 -273.099784)
		(size 0.4064)
		(drill 0.2032)
		(layers "F.Cu" "B.Cu")
		(net "GND")
	)
	(via
		(at 31.747968 -380.141734)
		(size 0.508)
		(drill 0.254)
		(layers "F.Cu" "B.Cu")
		(net "GND")
	)
	(via
		(at 40.547798 -369.938554)
		(size 0.508)
		(drill 0.254)
		(layers "F.Cu" "B.Cu")
		(net "GND")
	)
	(via
		(at 280.924762 -284.974792)
		(size 0.4064)
		(drill 0.2032)
		(layers "F.Cu" "B.Cu")
		(net "GND")
	)
	(via
		(at 277.124922 -285.924752)
		(size 0.4064)
		(drill 0.2032)
		(layers "F.Cu" "B.Cu")
		(net "GND")
	)
	(via
		(at 291.956998 -185.049414)
		(size 0.508)
		(drill 0.254)
		(layers "F.Cu" "B.Cu")
		(net "GND")
	)
	(via
		(at 143.027146 -210.805522)
		(size 0.508)
		(drill 0.254)
		(layers "F.Cu" "B.Cu")
		(net "GND")
	)
	(via
		(at 295.68013 -349.219774)
		(size 0.4572)
		(drill 0.254)
		(layers "F.Cu" "B.Cu")
		(net "GND")
	)
	(via
		(at 432.202082 -27.729688)
		(size 0.508)
		(drill 0.254)
		(layers "F.Cu" "B.Cu")
		(net "GND")
	)
	(via
		(at 215.32215 -52.51704)
		(size 0.508)
		(drill 0.254)
		(layers "F.Cu" "B.Cu")
		(net "GND")
	)
	(via
		(at 188.366908 -129.445004)
		(size 0.508)
		(drill 0.254)
		(layers "F.Cu" "B.Cu")
		(net "GND")
	)
	(via
		(at 127.209296 -344.831162)
		(size 0.4572)
		(drill 0.254)
		(layers "F.Cu" "B.Cu")
		(net "GND")
	)
	(via
		(at 309.424832 -299.224954)
		(size 0.4064)
		(drill 0.2032)
		(layers "F.Cu" "B.Cu")
		(net "GND")
	)
	(via
		(at 42.15638 -343.073482)
		(size 0.4572)
		(drill 0.254)
		(layers "F.Cu" "B.Cu")
		(net "GND")
	)
	(via
		(at 426.94987 -279.749758)
		(size 0.4064)
		(drill 0.2032)
		(layers "F.Cu" "B.Cu")
		(net "GND")
	)
	(via
		(at 79.600044 -274.049744)
		(size 0.4064)
		(drill 0.2032)
		(layers "F.Cu" "B.Cu")
		(net "GND")
	)
	(via
		(at 2.300478 -35.290506)
		(size 0.508)
		(drill 0.254)
		(layers "F.Cu" "B.Cu")
		(net "GND")
	)
	(via
		(at 342.245442 -306.55387)
		(size 0.508)
		(drill 0.254)
		(layers "F.Cu" "B.Cu")
		(net "GND")
	)
	(via
		(at 71.52005 -57.076848)
		(size 0.508)
		(drill 0.254)
		(layers "F.Cu" "B.Cu")
		(net "GND")
	)
	(via
		(at 122.29973 -258.394962)
		(size 0.508)
		(drill 0.254)
		(layers "F.Cu" "B.Cu")
		(net "GND")
	)
	(via
		(at 268.09954 -312.049668)
		(size 0.4064)
		(drill 0.2032)
		(layers "F.Cu" "B.Cu")
		(net "GND")
	)
	(via
		(at 70.50151 -350.977454)
		(size 0.4572)
		(drill 0.254)
		(layers "F.Cu" "B.Cu")
		(net "GND")
	)
	(via
		(at 46.744128 -342.439498)
		(size 0.4064)
		(drill 0.2032)
		(layers "F.Cu" "B.Cu")
		(net "GND")
	)
	(via
		(at 165.751764 -118.754906)
		(size 0.508)
		(drill 0.254)
		(layers "F.Cu" "B.Cu")
		(net "GND")
	)
	(via
		(at 289.094164 -135.828786)
		(size 0.508)
		(drill 0.254)
		(layers "F.Cu" "B.Cu")
		(net "GND")
	)
	(via
		(at 208.348834 -29.589984)
		(size 0.508)
		(drill 0.254)
		(layers "F.Cu" "B.Cu")
		(net "GND")
	)
	(via
		(at 12.51331 -225.21164)
		(size 0.508)
		(drill 0.254)
		(layers "F.Cu" "B.Cu")
		(net "GND")
	)
	(via
		(at 210.657948 -58.791094)
		(size 0.508)
		(drill 0.254)
		(layers "F.Cu" "B.Cu")
		(net "GND")
	)
	(via
		(at 44.120562 -63.218314)
		(size 0.508)
		(drill 0.254)
		(layers "F.Cu" "B.Cu")
		(net "GND")
	)
	(via
		(at 347.208602 -282.910788)
		(size 0.49022)
		(drill 0.254)
		(layers "F.Cu" "B.Cu")
		(net "GND")
	)
	(via
		(at 49.67478 -297.32478)
		(size 0.4064)
		(drill 0.2032)
		(layers "F.Cu" "B.Cu")
		(net "GND")
	)
	(via
		(at 74.869294 -343.073482)
		(size 0.4572)
		(drill 0.254)
		(layers "F.Cu" "B.Cu")
		(net "GND")
	)
	(via
		(at 139.273788 -357.75773)
		(size 0.4064)
		(drill 0.2032)
		(layers "F.Cu" "B.Cu")
		(net "GND")
	)
	(via
		(at 62.974982 -291.624766)
		(size 0.4064)
		(drill 0.2032)
		(layers "F.Cu" "B.Cu")
		(net "GND")
	)
	(via
		(at 47.819564 -38.701218)
		(size 0.508)
		(drill 0.254)
		(layers "F.Cu" "B.Cu")
		(net "GND")
	)
	(via
		(at 49.853088 -351.611438)
		(size 0.4064)
		(drill 0.2032)
		(layers "F.Cu" "B.Cu")
		(net "GND")
	)
	(via
		(at 455.717402 -246.06504)
		(size 0.508)
		(drill 0.254)
		(layers "F.Cu" "B.Cu")
		(net "GND")
	)
	(via
		(at 321.998086 -20.417536)
		(size 0.508)
		(drill 0.254)
		(layers "F.Cu" "B.Cu")
		(net "GND")
	)
	(via
		(at 441.36564 -303.026826)
		(size 0.508)
		(drill 0.254)
		(layers "F.Cu" "B.Cu")
		(net "GND")
	)
	(via
		(at 182.974742 -238.83874)
		(size 0.508)
		(drill 0.254)
		(layers "F.Cu" "B.Cu")
		(net "GND")
	)
	(via
		(at 172.424852 -291.624766)
		(size 0.4064)
		(drill 0.2032)
		(layers "F.Cu" "B.Cu")
		(net "GND")
	)
	(via
		(at 450.824346 -291.546788)
		(size 0.508)
		(drill 0.254)
		(layers "F.Cu" "B.Cu")
		(net "GND")
	)
	(via
		(at 287.983422 -351.611438)
		(size 0.4064)
		(drill 0.2032)
		(layers "F.Cu" "B.Cu")
		(net "GND")
	)
	(via
		(at 194.749928 -285.449772)
		(size 0.4064)
		(drill 0.2032)
		(layers "F.Cu" "B.Cu")
		(net "GND")
	)
	(via
		(at 31.468568 -59.974734)
		(size 0.508)
		(drill 0.254)
		(layers "F.Cu" "B.Cu")
		(net "GND")
	)
	(via
		(at 183.766714 -136.645142)
		(size 0.508)
		(drill 0.254)
		(layers "F.Cu" "B.Cu")
		(net "GND")
	)
	(via
		(at 75.74788 -371.140228)
		(size 0.508)
		(drill 0.254)
		(layers "F.Cu" "B.Cu")
		(net "GND")
	)
	(via
		(at 34.679636 -350.977454)
		(size 0.4572)
		(drill 0.254)
		(layers "F.Cu" "B.Cu")
		(net "GND")
	)
	(via
		(at 332.160118 -21.37156)
		(size 0.508)
		(drill 0.254)
		(layers "F.Cu" "B.Cu")
		(net "GND")
	)
	(via
		(at 425.527724 -411.141926)
		(size 0.508)
		(drill 0.254)
		(layers "F.Cu" "B.Cu")
		(net "GND")
	)
	(via
		(at 401.15236 -100.64496)
		(size 0.508)
		(drill 0.254)
		(layers "F.Cu" "B.Cu")
		(net "GND")
	)
	(via
		(at 274.480782 -34.990024)
		(size 0.508)
		(drill 0.254)
		(layers "F.Cu" "B.Cu")
		(net "GND")
	)
	(via
		(at 281.399742 -281.649932)
		(size 0.4064)
		(drill 0.2032)
		(layers "F.Cu" "B.Cu")
		(net "GND")
	)
	(via
		(at 383.94894 -31.390082)
		(size 0.508)
		(drill 0.254)
		(layers "F.Cu" "B.Cu")
		(net "GND")
	)
	(via
		(at 114.773456 -343.073482)
		(size 0.4572)
		(drill 0.254)
		(layers "F.Cu" "B.Cu")
		(net "GND")
	)
	(via
		(at 38.275006 -276.424898)
		(size 0.4064)
		(drill 0.2032)
		(layers "F.Cu" "B.Cu")
		(net "GND")
	)
	(via
		(at 287.506918 -49.574704)
		(size 0.508)
		(drill 0.254)
		(layers "F.Cu" "B.Cu")
		(net "GND")
	)
	(via
		(at 299.866812 -156.554932)
		(size 0.508)
		(drill 0.254)
		(layers "F.Cu" "B.Cu")
		(net "GND")
	)
	(via
		(at 399.874994 -285.924752)
		(size 0.4064)
		(drill 0.2032)
		(layers "F.Cu" "B.Cu")
		(net "GND")
	)
	(via
		(at 376.888502 -93.603064)
		(size 0.508)
		(drill 0.254)
		(layers "F.Cu" "B.Cu")
		(net "GND")
	)
	(via
		(at 179.34178 -162.08375)
		(size 0.508)
		(drill 0.254)
		(layers "F.Cu" "B.Cu")
		(net "GND")
	)
	(via
		(at 208.894172 -123.20778)
		(size 0.508)
		(drill 0.254)
		(layers "F.Cu" "B.Cu")
		(net "GND")
	)
	(via
		(at 76.824078 -113.229898)
		(size 0.508)
		(drill 0.254)
		(layers "F.Cu" "B.Cu")
		(net "GND")
	)
	(via
		(at 349.410782 -290.05149)
		(size 0.508)
		(drill 0.254)
		(layers "F.Cu" "B.Cu")
		(net "GND")
	)
	(via
		(at 84.567522 -351.611438)
		(size 0.4064)
		(drill 0.2032)
		(layers "F.Cu" "B.Cu")
		(net "GND")
	)
	(via
		(at 57.274968 -291.624766)
		(size 0.4064)
		(drill 0.2032)
		(layers "F.Cu" "B.Cu")
		(net "GND")
	)
	(via
		(at 103.15067 -290.68649)
		(size 0.508)
		(drill 0.254)
		(layers "F.Cu" "B.Cu")
		(net "GND")
	)
	(via
		(at 429.325024 -303.024794)
		(size 0.4064)
		(drill 0.2032)
		(layers "F.Cu" "B.Cu")
		(net "GND")
	)
	(via
		(at 403.199854 -310.149748)
		(size 0.4064)
		(drill 0.2032)
		(layers "F.Cu" "B.Cu")
		(net "GND")
	)
	(via
		(at 14.132052 -13.613638)
		(size 0.508)
		(drill 0.254)
		(layers "F.Cu" "B.Cu")
		(net "GND")
	)
	(via
		(at 267.301218 -100.92309)
		(size 0.508)
		(drill 0.254)
		(layers "F.Cu" "B.Cu")
		(net "GND")
	)
	(via
		(at 383.426208 -357.123746)
		(size 0.4572)
		(drill 0.254)
		(layers "F.Cu" "B.Cu")
		(net "GND")
	)
	(via
		(at 333.127858 -373.441976)
		(size 0.508)
		(drill 0.254)
		(layers "F.Cu" "B.Cu")
		(net "GND")
	)
	(via
		(at 85.299804 -62.812168)
		(size 0.508)
		(drill 0.254)
		(layers "F.Cu" "B.Cu")
		(net "GND")
	)
	(via
		(at 396.551404 -47.03191)
		(size 0.508)
		(drill 0.254)
		(layers "F.Cu" "B.Cu")
		(net "GND")
	)
	(via
		(at 57.468516 -59.974734)
		(size 0.508)
		(drill 0.254)
		(layers "F.Cu" "B.Cu")
		(net "GND")
	)
	(via
		(at 305.624738 -290.674806)
		(size 0.4064)
		(drill 0.2032)
		(layers "F.Cu" "B.Cu")
		(net "GND")
	)
	(via
		(at 159.124904 -286.874712)
		(size 0.4064)
		(drill 0.2032)
		(layers "F.Cu" "B.Cu")
		(net "GND")
	)
	(via
		(at 184.938416 -72.56526)
		(size 0.508)
		(drill 0.254)
		(layers "F.Cu" "B.Cu")
		(net "GND")
	)
	(via
		(at 460.323184 -273.224752)
		(size 0.508)
		(drill 0.254)
		(layers "F.Cu" "B.Cu")
		(net "GND")
	)
	(via
		(at 15.666974 -283.1592)
		(size 0.508)
		(drill 0.254)
		(layers "F.Cu" "B.Cu")
		(net "GND")
	)
	(via
		(at 442.097668 -118.894352)
		(size 0.508)
		(drill 0.254)
		(layers "F.Cu" "B.Cu")
		(net "GND")
	)
	(via
		(at 38.274752 -297.32478)
		(size 0.4064)
		(drill 0.2032)
		(layers "F.Cu" "B.Cu")
		(net "GND")
	)
	(via
		(at 383.818384 -253.45644)
		(size 0.508)
		(drill 0.254)
		(layers "F.Cu" "B.Cu")
		(net "GND")
	)
	(via
		(at 352.009964 -291.32149)
		(size 0.508)
		(drill 0.254)
		(layers "F.Cu" "B.Cu")
		(net "GND")
	)
	(via
		(at 404.673816 -25.971246)
		(size 0.508)
		(drill 0.254)
		(layers "F.Cu" "B.Cu")
		(net "GND")
	)
	(via
		(at 258.625086 -14.100302)
		(size 0.508)
		(drill 0.254)
		(layers "F.Cu" "B.Cu")
		(net "GND")
	)
	(via
		(at 57.274968 -294.4749)
		(size 0.4064)
		(drill 0.2032)
		(layers "F.Cu" "B.Cu")
		(net "GND")
	)
	(via
		(at 38.347904 -400.938492)
		(size 0.508)
		(drill 0.254)
		(layers "F.Cu" "B.Cu")
		(net "GND")
	)
	(via
		(at 308.949852 -285.449772)
		(size 0.4064)
		(drill 0.2032)
		(layers "F.Cu" "B.Cu")
		(net "GND")
	)
	(via
		(at 304.527712 -382.840484)
		(size 0.508)
		(drill 0.254)
		(layers "F.Cu" "B.Cu")
		(net "GND")
	)
	(via
		(at 388.127748 -384.041904)
		(size 0.508)
		(drill 0.254)
		(layers "F.Cu" "B.Cu")
		(net "GND")
	)
	(via
		(at 440.188858 -99.625912)
		(size 0.508)
		(drill 0.254)
		(layers "F.Cu" "B.Cu")
		(net "GND")
	)
	(via
		(at 392.749786 -315.849762)
		(size 0.4064)
		(drill 0.2032)
		(layers "F.Cu" "B.Cu")
		(net "GND")
	)
	(via
		(at 295.649904 -276.899878)
		(size 0.4064)
		(drill 0.2032)
		(layers "F.Cu" "B.Cu")
		(net "GND")
	)
	(via
		(at 114.137186 -285.267654)
		(size 0.508)
		(drill 0.254)
		(layers "F.Cu" "B.Cu")
		(net "GND")
	)
	(via
		(at 381.576072 -347.951806)
		(size 0.4572)
		(drill 0.254)
		(layers "F.Cu" "B.Cu")
		(net "GND")
	)
	(via
		(at 82.924904 -297.32478)
		(size 0.4064)
		(drill 0.2032)
		(layers "F.Cu" "B.Cu")
		(net "GND")
	)
	(via
		(at 385.842002 -222.590106)
		(size 0.508)
		(drill 0.254)
		(layers "F.Cu" "B.Cu")
		(net "GND")
	)
	(via
		(at 267.69949 -349.219774)
		(size 0.4572)
		(drill 0.254)
		(layers "F.Cu" "B.Cu")
		(net "GND")
	)
	(via
		(at 245.953026 -209.852514)
		(size 0.508)
		(drill 0.254)
		(layers "F.Cu" "B.Cu")
		(net "GND")
	)
	(via
		(at 17.460722 -402.208492)
		(size 0.508)
		(drill 0.254)
		(layers "F.Cu" "B.Cu")
		(net "GND")
	)
	(via
		(at 429.927766 -402.140166)
		(size 0.508)
		(drill 0.254)
		(layers "F.Cu" "B.Cu")
		(net "GND")
	)
	(via
		(at 280.160222 -20.35556)
		(size 0.508)
		(drill 0.254)
		(layers "F.Cu" "B.Cu")
		(net "GND")
	)
	(via
		(at 56.799988 -317.749936)
		(size 0.4064)
		(drill 0.2032)
		(layers "F.Cu" "B.Cu")
		(net "GND")
	)
	(via
		(at 67.55003 -109.244892)
		(size 0.508)
		(drill 0.254)
		(layers "F.Cu" "B.Cu")
		(net "GND")
	)
	(via
		(at 283.774896 -285.924752)
		(size 0.4064)
		(drill 0.2032)
		(layers "F.Cu" "B.Cu")
		(net "GND")
	)
	(via
		(at 6.600952 -31.390336)
		(size 0.508)
		(drill 0.254)
		(layers "F.Cu" "B.Cu")
		(net "GND")
	)
	(via
		(at 341.544656 -344.831162)
		(size 0.4572)
		(drill 0.254)
		(layers "F.Cu" "B.Cu")
		(net "GND")
	)
	(via
		(at 377.208288 -344.831162)
		(size 0.4572)
		(drill 0.254)
		(layers "F.Cu" "B.Cu")
		(net "GND")
	)
	(via
		(at 174.079662 -101.782372)
		(size 0.508)
		(drill 0.254)
		(layers "F.Cu" "B.Cu")
		(net "GND")
	)
	(via
		(at 302.38446 -72.56526)
		(size 0.508)
		(drill 0.254)
		(layers "F.Cu" "B.Cu")
		(net "GND")
	)
	(via
		(at 416.974782 -304.924714)
		(size 0.4064)
		(drill 0.2032)
		(layers "F.Cu" "B.Cu")
		(net "GND")
	)
	(via
		(at 161.025078 -286.874966)
		(size 0.4064)
		(drill 0.2032)
		(layers "F.Cu" "B.Cu")
		(net "GND")
	)
	(via
		(at 61.17463 -352.245422)
		(size 0.4572)
		(drill 0.254)
		(layers "F.Cu" "B.Cu")
		(net "GND")
	)
	(via
		(at 238.404654 -308.892956)
		(size 0.508)
		(drill 0.254)
		(layers "F.Cu" "B.Cu")
		(net "GND")
	)
	(via
		(at 72.949816 -315.849762)
		(size 0.4064)
		(drill 0.2032)
		(layers "F.Cu" "B.Cu")
		(net "GND")
	)
	(via
		(at 268.958314 -343.073482)
		(size 0.4572)
		(drill 0.254)
		(layers "F.Cu" "B.Cu")
		(net "GND")
	)
	(via
		(at 378.467112 -358.391714)
		(size 0.4572)
		(drill 0.254)
		(layers "F.Cu" "B.Cu")
		(net "GND")
	)
	(via
		(at 346.327984 -408.738578)
		(size 0.508)
		(drill 0.254)
		(layers "F.Cu" "B.Cu")
		(net "GND")
	)
	(via
		(at 428.84979 -314.899802)
		(size 0.4064)
		(drill 0.2032)
		(layers "F.Cu" "B.Cu")
		(net "GND")
	)
	(via
		(at 352.975926 -259.918962)
		(size 0.508)
		(drill 0.254)
		(layers "F.Cu" "B.Cu")
		(net "GND")
	)
	(via
		(at 279.232868 -129.964942)
		(size 0.508)
		(drill 0.254)
		(layers "F.Cu" "B.Cu")
		(net "GND")
	)
	(via
		(at 228.04501 -273.822668)
		(size 0.508)
		(drill 0.254)
		(layers "F.Cu" "B.Cu")
		(net "GND")
	)
	(via
		(at 128.46812 -347.951806)
		(size 0.4572)
		(drill 0.254)
		(layers "F.Cu" "B.Cu")
		(net "GND")
	)
	(via
		(at 167.732964 -129.964942)
		(size 0.508)
		(drill 0.254)
		(layers "F.Cu" "B.Cu")
		(net "GND")
	)
	(via
		(at 461.36179 -288.775648)
		(size 0.508)
		(drill 0.254)
		(layers "F.Cu" "B.Cu")
		(net "GND")
	)
	(via
		(at 350.243394 -28.139136)
		(size 0.508)
		(drill 0.254)
		(layers "F.Cu" "B.Cu")
		(net "GND")
	)
	(via
		(at 299.924724 -303.974754)
		(size 0.4064)
		(drill 0.2032)
		(layers "F.Cu" "B.Cu")
		(net "GND")
	)
	(via
		(at 91.902026 -56.826404)
		(size 0.508)
		(drill 0.254)
		(layers "F.Cu" "B.Cu")
		(net "GND")
	)
	(via
		(at 160.074864 -300.174914)
		(size 0.4064)
		(drill 0.2032)
		(layers "F.Cu" "B.Cu")
		(net "GND")
	)
	(via
		(at 27.072844 -306.052728)
		(size 0.508)
		(drill 0.254)
		(layers "F.Cu" "B.Cu")
		(net "GND")
	)
	(via
		(at 339.728048 -399.838418)
		(size 0.508)
		(drill 0.254)
		(layers "F.Cu" "B.Cu")
		(net "GND")
	)
	(via
		(at 319.76695 -82.31505)
		(size 0.508)
		(drill 0.254)
		(layers "F.Cu" "B.Cu")
		(net "GND")
	)
	(via
		(at 428.84979 -272.14957)
		(size 0.4064)
		(drill 0.2032)
		(layers "F.Cu" "B.Cu")
		(net "GND")
	)
	(via
		(at 73.61047 -346.09913)
		(size 0.4572)
		(drill 0.254)
		(layers "F.Cu" "B.Cu")
		(net "GND")
	)
	(via
		(at 351.374964 -287.51149)
		(size 0.508)
		(drill 0.254)
		(layers "F.Cu" "B.Cu")
		(net "GND")
	)
	(via
		(at 227.067872 -221.103952)
		(size 0.4572)
		(drill 0.254)
		(layers "F.Cu" "B.Cu")
		(net "GND")
	)
	(via
		(at 375.824496 -262.915908)
		(size 0.508)
		(drill 0.254)
		(layers "F.Cu" "B.Cu")
		(net "GND")
	)
	(via
		(at 48.24984 -312.049922)
		(size 0.4064)
		(drill 0.2032)
		(layers "F.Cu" "B.Cu")
		(net "GND")
	)
	(via
		(at 352.009964 -290.05149)
		(size 0.508)
		(drill 0.254)
		(layers "F.Cu" "B.Cu")
		(net "GND")
	)
	(via
		(at 405.575008 -284.974792)
		(size 0.4064)
		(drill 0.2032)
		(layers "F.Cu" "B.Cu")
		(net "GND")
	)
	(via
		(at 337.523074 -56.353456)
		(size 0.508)
		(drill 0.254)
		(layers "F.Cu" "B.Cu")
		(net "GND")
	)
	(via
		(at 42.557954 -58.156094)
		(size 0.508)
		(drill 0.254)
		(layers "F.Cu" "B.Cu")
		(net "GND")
	)
	(via
		(at 365.620046 -248.668286)
		(size 0.508)
		(drill 0.254)
		(layers "F.Cu" "B.Cu")
		(net "GND")
	)
	(via
		(at 337.64347 -286.842454)
		(size 0.508)
		(drill 0.254)
		(layers "F.Cu" "B.Cu")
		(net "GND")
	)
	(via
		(at 173.375066 -306.824888)
		(size 0.4064)
		(drill 0.2032)
		(layers "F.Cu" "B.Cu")
		(net "GND")
	)
	(via
		(at 198.550022 -315.849762)
		(size 0.4064)
		(drill 0.2032)
		(layers "F.Cu" "B.Cu")
		(net "GND")
	)
	(via
		(at 338.41817 -282.910788)
		(size 0.49022)
		(drill 0.254)
		(layers "F.Cu" "B.Cu")
		(net "GND")
	)
	(via
		(at 339.914484 -342.439498)
		(size 0.4064)
		(drill 0.2032)
		(layers "F.Cu" "B.Cu")
		(net "GND")
	)
	(via
		(at 435.067964 -54.238906)
		(size 0.508)
		(drill 0.254)
		(layers "F.Cu" "B.Cu")
		(net "GND")
	)
	(via
		(at 463.037682 -235.217462)
		(size 0.508)
		(drill 0.254)
		(layers "F.Cu" "B.Cu")
		(net "GND")
	)
	(via
		(at 196.998082 -119.756936)
		(size 0.508)
		(drill 0.254)
		(layers "F.Cu" "B.Cu")
		(net "GND")
	)
	(via
		(at 176.94783 -376.242072)
		(size 0.508)
		(drill 0.254)
		(layers "F.Cu" "B.Cu")
		(net "GND")
	)
	(via
		(at 75.74788 -399.838418)
		(size 0.508)
		(drill 0.254)
		(layers "F.Cu" "B.Cu")
		(net "GND")
	)
	(via
		(at 277.251668 -104.244902)
		(size 0.508)
		(drill 0.254)
		(layers "F.Cu" "B.Cu")
		(net "GND")
	)
	(via
		(at 335.328006 -371.140228)
		(size 0.508)
		(drill 0.254)
		(layers "F.Cu" "B.Cu")
		(net "GND")
	)
	(via
		(at 33.947862 -407.24201)
		(size 0.508)
		(drill 0.254)
		(layers "F.Cu" "B.Cu")
		(net "GND")
	)
	(via
		(at 423.729404 -47.020734)
		(size 0.508)
		(drill 0.254)
		(layers "F.Cu" "B.Cu")
		(net "GND")
	)
	(via
		(at 409.09748 -344.831162)
		(size 0.4572)
		(drill 0.254)
		(layers "F.Cu" "B.Cu")
		(net "GND")
	)
	(via
		(at 72.949816 -316.799722)
		(size 0.4064)
		(drill 0.2032)
		(layers "F.Cu" "B.Cu")
		(net "GND")
	)
	(via
		(at 275.699728 -300.649894)
		(size 0.4064)
		(drill 0.2032)
		(layers "F.Cu" "B.Cu")
		(net "GND")
	)
	(via
		(at 384.199638 -312.049668)
		(size 0.4064)
		(drill 0.2032)
		(layers "F.Cu" "B.Cu")
		(net "GND")
	)
	(via
		(at 29.54782 -372.240302)
		(size 0.508)
		(drill 0.254)
		(layers "F.Cu" "B.Cu")
		(net "GND")
	)
	(via
		(at 245.694708 -159.498792)
		(size 0.508)
		(drill 0.254)
		(layers "F.Cu" "B.Cu")
		(net "GND")
	)
	(via
		(at 37.788596 -31.642304)
		(size 0.508)
		(drill 0.254)
		(layers "F.Cu" "B.Cu")
		(net "GND")
	)
	(via
		(at 272.067274 -344.831162)
		(size 0.4572)
		(drill 0.254)
		(layers "F.Cu" "B.Cu")
		(net "GND")
	)
	(via
		(at 7.72414 -314.756038)
		(size 0.508)
		(drill 0.254)
		(layers "F.Cu" "B.Cu")
		(net "GND")
	)
	(via
		(at 152.469088 -100.92309)
		(size 0.508)
		(drill 0.254)
		(layers "F.Cu" "B.Cu")
		(net "GND")
	)
	(via
		(at 41.599866 -313.949842)
		(size 0.4064)
		(drill 0.2032)
		(layers "F.Cu" "B.Cu")
		(net "GND")
	)
	(via
		(at 450.4944 -225.5774)
		(size 0.508)
		(drill 0.254)
		(layers "F.Cu" "B.Cu")
		(net "GND")
	)
	(via
		(at 382.12014 -31.390336)
		(size 0.508)
		(drill 0.254)
		(layers "F.Cu" "B.Cu")
		(net "GND")
	)
	(via
		(at 407.4033 -60.627006)
		(size 0.508)
		(drill 0.254)
		(layers "F.Cu" "B.Cu")
		(net "GND")
	)
	(via
		(at 466.835998 -267.523976)
		(size 0.508)
		(drill 0.254)
		(layers "F.Cu" "B.Cu")
		(net "GND")
	)
	(via
		(at 291.84981 -310.149748)
		(size 0.4064)
		(drill 0.2032)
		(layers "F.Cu" "B.Cu")
		(net "GND")
	)
	(via
		(at 277.186898 -151.157432)
		(size 0.508)
		(drill 0.254)
		(layers "F.Cu" "B.Cu")
		(net "GND")
	)
	(via
		(at 448.244976 -279.89022)
		(size 0.508)
		(drill 0.254)
		(layers "F.Cu" "B.Cu")
		(net "GND")
	)
	(via
		(at 37.324792 -275.474938)
		(size 0.4064)
		(drill 0.2032)
		(layers "F.Cu" "B.Cu")
		(net "GND")
	)
	(via
		(at 466.835998 -374.203976)
		(size 0.508)
		(drill 0.254)
		(layers "F.Cu" "B.Cu")
		(net "GND")
	)
	(via
		(at 244.543326 -116.450364)
		(size 0.508)
		(drill 0.254)
		(layers "F.Cu" "B.Cu")
		(net "GND")
	)
	(via
		(at 110.837726 -158.212282)
		(size 0.508)
		(drill 0.254)
		(layers "F.Cu" "B.Cu")
		(net "GND")
	)
	(via
		(at 100.760022 -105.057194)
		(size 0.508)
		(drill 0.254)
		(layers "F.Cu" "B.Cu")
		(net "GND")
	)
	(via
		(at 155.325064 -286.874966)
		(size 0.4064)
		(drill 0.2032)
		(layers "F.Cu" "B.Cu")
		(net "GND")
	)
	(via
		(at 414.124902 -289.724846)
		(size 0.4064)
		(drill 0.2032)
		(layers "F.Cu" "B.Cu")
		(net "GND")
	)
	(via
		(at 362.458 -211.963)
		(size 0.508)
		(drill 0.254)
		(layers "F.Cu" "B.Cu")
		(net "GND")
	)
	(via
		(at 366.086644 -339.287104)
		(size 0.508)
		(drill 0.254)
		(layers "F.Cu" "B.Cu")
		(net "GND")
	)
	(via
		(at 308.474872 -297.32478)
		(size 0.4064)
		(drill 0.2032)
		(layers "F.Cu" "B.Cu")
		(net "GND")
	)
	(via
		(at 272.067274 -349.219774)
		(size 0.4572)
		(drill 0.254)
		(layers "F.Cu" "B.Cu")
		(net "GND")
	)
	(via
		(at 186.589924 -96.408748)
		(size 0.508)
		(drill 0.254)
		(layers "F.Cu" "B.Cu")
		(net "GND")
	)
	(via
		(at 178.124866 -285.924752)
		(size 0.4064)
		(drill 0.2032)
		(layers "F.Cu" "B.Cu")
		(net "GND")
	)
	(via
		(at 72.246998 -115.504976)
		(size 0.508)
		(drill 0.254)
		(layers "F.Cu" "B.Cu")
		(net "GND")
	)
	(via
		(at 288.049716 -316.799722)
		(size 0.4064)
		(drill 0.2032)
		(layers "F.Cu" "B.Cu")
		(net "GND")
	)
	(via
		(at 134.68223 -58.873644)
		(size 0.508)
		(drill 0.254)
		(layers "F.Cu" "B.Cu")
		(net "GND")
	)
	(via
		(at 191.900048 -314.899802)
		(size 0.4064)
		(drill 0.2032)
		(layers "F.Cu" "B.Cu")
		(net "GND")
	)
	(via
		(at 279.499822 -314.899802)
		(size 0.4064)
		(drill 0.2032)
		(layers "F.Cu" "B.Cu")
		(net "GND")
	)
	(via
		(at 134.855712 -63.218314)
		(size 0.508)
		(drill 0.254)
		(layers "F.Cu" "B.Cu")
		(net "GND")
	)
	(via
		(at 283.833062 -102.445058)
		(size 0.508)
		(drill 0.254)
		(layers "F.Cu" "B.Cu")
		(net "GND")
	)
	(via
		(at 379.327918 -401.040092)
		(size 0.508)
		(drill 0.254)
		(layers "F.Cu" "B.Cu")
		(net "GND")
	)
	(via
		(at 386.842 -234.62996)
		(size 0.508)
		(drill 0.254)
		(layers "F.Cu" "B.Cu")
		(net "GND")
	)
	(via
		(at 302.774858 -289.724846)
		(size 0.4064)
		(drill 0.2032)
		(layers "F.Cu" "B.Cu")
		(net "GND")
	)
	(via
		(at 180.64226 -344.831162)
		(size 0.4572)
		(drill 0.254)
		(layers "F.Cu" "B.Cu")
		(net "GND")
	)
	(via
		(at 47.147988 -371.038628)
		(size 0.508)
		(drill 0.254)
		(layers "F.Cu" "B.Cu")
		(net "GND")
	)
	(via
		(at 82.93735 -355.366066)
		(size 0.4572)
		(drill 0.254)
		(layers "F.Cu" "B.Cu")
		(net "GND")
	)
	(via
		(at 82.93735 -346.09913)
		(size 0.4572)
		(drill 0.254)
		(layers "F.Cu" "B.Cu")
		(net "GND")
	)
	(via
		(at 430.566068 -77.175106)
		(size 0.508)
		(drill 0.254)
		(layers "F.Cu" "B.Cu")
		(net "GND")
	)
	(via
		(at 181.912514 -143.955008)
		(size 0.508)
		(drill 0.254)
		(layers "F.Cu" "B.Cu")
		(net "GND")
	)
	(via
		(at 258.229862 -399.203926)
		(size 0.508)
		(drill 0.254)
		(layers "F.Cu" "B.Cu")
		(net "GND")
	)
	(via
		(at 161.54781 -406.040336)
		(size 0.508)
		(drill 0.254)
		(layers "F.Cu" "B.Cu")
		(net "GND")
	)
	(via
		(at 288.99993 -274.049744)
		(size 0.4064)
		(drill 0.2032)
		(layers "F.Cu" "B.Cu")
		(net "GND")
	)
	(via
		(at 337.5279 -382.73863)
		(size 0.508)
		(drill 0.254)
		(layers "F.Cu" "B.Cu")
		(net "GND")
	)
	(via
		(at 52.524914 -289.724846)
		(size 0.4064)
		(drill 0.2032)
		(layers "F.Cu" "B.Cu")
		(net "GND")
	)
	(via
		(at 436.706772 -342.439498)
		(size 0.4064)
		(drill 0.2032)
		(layers "F.Cu" "B.Cu")
		(net "GND")
	)
	(via
		(at 48.24984 -310.149748)
		(size 0.4064)
		(drill 0.2032)
		(layers "F.Cu" "B.Cu")
		(net "GND")
	)
	(via
		(at 394.38326 -345.465146)
		(size 0.4064)
		(drill 0.2032)
		(layers "F.Cu" "B.Cu")
		(net "GND")
	)
	(via
		(at 73.222104 -52.51704)
		(size 0.508)
		(drill 0.254)
		(layers "F.Cu" "B.Cu")
		(net "GND")
	)
	(via
		(at 416.574224 -344.831162)
		(size 0.4572)
		(drill 0.254)
		(layers "F.Cu" "B.Cu")
		(net "GND")
	)
	(via
		(at 190.950088 -303.499774)
		(size 0.4064)
		(drill 0.2032)
		(layers "F.Cu" "B.Cu")
		(net "GND")
	)
	(via
		(at 316.672976 -354.074222)
		(size 0.4572)
		(drill 0.254)
		(layers "F.Cu" "B.Cu")
		(net "GND")
	)
	(via
		(at 87.648796 -31.390082)
		(size 0.508)
		(drill 0.254)
		(layers "F.Cu" "B.Cu")
		(net "GND")
	)
	(via
		(at 232.207308 -105.537508)
		(size 0.508)
		(drill 0.254)
		(layers "F.Cu" "B.Cu")
		(net "GND")
	)
	(via
		(at 51.574954 -291.624766)
		(size 0.4064)
		(drill 0.2032)
		(layers "F.Cu" "B.Cu")
		(net "GND")
	)
	(via
		(at 91.1479 -383.940304)
		(size 0.508)
		(drill 0.254)
		(layers "F.Cu" "B.Cu")
		(net "GND")
	)
	(via
		(at 422.548304 -143.955008)
		(size 0.508)
		(drill 0.254)
		(layers "F.Cu" "B.Cu")
		(net "GND")
	)
	(via
		(at 86.747858 -377.341892)
		(size 0.508)
		(drill 0.254)
		(layers "F.Cu" "B.Cu")
		(net "GND")
	)
	(via
		(at 70.574916 -307.774848)
		(size 0.4064)
		(drill 0.2032)
		(layers "F.Cu" "B.Cu")
		(net "GND")
	)
	(via
		(at 144.384268 -357.75773)
		(size 0.4064)
		(drill 0.2032)
		(layers "F.Cu" "B.Cu")
		(net "GND")
	)
	(via
		(at 199.500236 -310.149748)
		(size 0.4064)
		(drill 0.2032)
		(layers "F.Cu" "B.Cu")
		(net "GND")
	)
	(via
		(at 130.318256 -354.098098)
		(size 0.4572)
		(drill 0.254)
		(layers "F.Cu" "B.Cu")
		(net "GND")
	)
	(via
		(at 276.174708 -294.4749)
		(size 0.4064)
		(drill 0.2032)
		(layers "F.Cu" "B.Cu")
		(net "GND")
	)
	(via
		(at 132.564886 -187.59805)
		(size 0.508)
		(drill 0.254)
		(layers "F.Cu" "B.Cu")
		(net "GND")
	)
	(via
		(at 415.85007 -110.514892)
		(size 0.508)
		(drill 0.254)
		(layers "F.Cu" "B.Cu")
		(net "GND")
	)
	(via
		(at 38.275006 -290.674806)
		(size 0.4064)
		(drill 0.2032)
		(layers "F.Cu" "B.Cu")
		(net "GND")
	)
	(via
		(at 161.9885 -354.098098)
		(size 0.4572)
		(drill 0.254)
		(layers "F.Cu" "B.Cu")
		(net "GND")
	)
	(via
		(at 105.525062 -115.579906)
		(size 0.508)
		(drill 0.254)
		(layers "F.Cu" "B.Cu")
		(net "GND")
	)
	(via
		(at 289.46221 -341.805514)
		(size 0.4572)
		(drill 0.254)
		(layers "F.Cu" "B.Cu")
		(net "GND")
	)
	(via
		(at 303.268126 -48.753014)
		(size 0.508)
		(drill 0.254)
		(layers "F.Cu" "B.Cu")
		(net "GND")
	)
	(via
		(at 102.782878 -338.573618)
		(size 0.4572)
		(drill 0.254)
		(layers "F.Cu" "B.Cu")
		(net "GND")
	)
	(via
		(at 292.57117 -347.951806)
		(size 0.4572)
		(drill 0.254)
		(layers "F.Cu" "B.Cu")
		(net "GND")
	)
	(via
		(at 100.136198 -94.208346)
		(size 0.508)
		(drill 0.254)
		(layers "F.Cu" "B.Cu")
		(net "GND")
	)
	(via
		(at 394.011912 -346.09913)
		(size 0.4572)
		(drill 0.254)
		(layers "F.Cu" "B.Cu")
		(net "GND")
	)
	(via
		(at 78.42504 -14.100302)
		(size 0.508)
		(drill 0.254)
		(layers "F.Cu" "B.Cu")
		(net "GND")
	)
	(via
		(at 158.649924 -316.799722)
		(size 0.4064)
		(drill 0.2032)
		(layers "F.Cu" "B.Cu")
		(net "GND")
	)
	(via
		(at 28.26385 -256.987548)
		(size 0.508)
		(drill 0.254)
		(layers "F.Cu" "B.Cu")
		(net "GND")
	)
	(via
		(at 403.338792 -341.805514)
		(size 0.4572)
		(drill 0.254)
		(layers "F.Cu" "B.Cu")
		(net "GND")
	)
	(via
		(at 71.524876 -289.724846)
		(size 0.4064)
		(drill 0.2032)
		(layers "F.Cu" "B.Cu")
		(net "GND")
	)
	(via
		(at 351.60712 -49.574704)
		(size 0.508)
		(drill 0.254)
		(layers "F.Cu" "B.Cu")
		(net "GND")
	)
	(via
		(at 419.349936 -274.999958)
		(size 0.4064)
		(drill 0.2032)
		(layers "F.Cu" "B.Cu")
		(net "GND")
	)
	(via
		(at 285.523178 -55.083456)
		(size 0.508)
		(drill 0.254)
		(layers "F.Cu" "B.Cu")
		(net "GND")
	)
	(via
		(at 272.438622 -342.439498)
		(size 0.4064)
		(drill 0.2032)
		(layers "F.Cu" "B.Cu")
		(net "GND")
	)
	(via
		(at 103.916734 -238.553244)
		(size 0.508)
		(drill 0.254)
		(layers "F.Cu" "B.Cu")
		(net "GND")
	)
	(via
		(at 45.39996 -281.649932)
		(size 0.4064)
		(drill 0.2032)
		(layers "F.Cu" "B.Cu")
		(net "GND")
	)
	(via
		(at 174.747936 -397.038576)
		(size 0.508)
		(drill 0.254)
		(layers "F.Cu" "B.Cu")
		(net "GND")
	)
	(via
		(at 421.019224 -46.893226)
		(size 0.508)
		(drill 0.254)
		(layers "F.Cu" "B.Cu")
		(net "GND")
	)
	(via
		(at 436.706772 -357.75773)
		(size 0.4064)
		(drill 0.2032)
		(layers "F.Cu" "B.Cu")
		(net "GND")
	)
	(via
		(at 304.674778 -292.574726)
		(size 0.4064)
		(drill 0.2032)
		(layers "F.Cu" "B.Cu")
		(net "GND")
	)
	(via
		(at 384.669284 -100.92309)
		(size 0.508)
		(drill 0.254)
		(layers "F.Cu" "B.Cu")
		(net "GND")
	)
	(via
		(at 430.749964 -278.799798)
		(size 0.4064)
		(drill 0.2032)
		(layers "F.Cu" "B.Cu")
		(net "GND")
	)
	(via
		(at 299.749972 -111.784892)
		(size 0.508)
		(drill 0.254)
		(layers "F.Cu" "B.Cu")
		(net "GND")
	)
	(via
		(at 75.74788 -408.840178)
		(size 0.508)
		(drill 0.254)
		(layers "F.Cu" "B.Cu")
		(net "GND")
	)
	(via
		(at 275.176234 -354.098098)
		(size 0.4572)
		(drill 0.254)
		(layers "F.Cu" "B.Cu")
		(net "GND")
	)
	(via
		(at 377.208288 -341.805514)
		(size 0.4572)
		(drill 0.254)
		(layers "F.Cu" "B.Cu")
		(net "GND")
	)
	(via
		(at 344.127836 -399.838418)
		(size 0.508)
		(drill 0.254)
		(layers "F.Cu" "B.Cu")
		(net "GND")
	)
	(via
		(at 335.328006 -384.041904)
		(size 0.508)
		(drill 0.254)
		(layers "F.Cu" "B.Cu")
		(net "GND")
	)
	(via
		(at 190.950088 -311.099962)
		(size 0.4064)
		(drill 0.2032)
		(layers "F.Cu" "B.Cu")
		(net "GND")
	)
	(via
		(at 172.547788 -377.738386)
		(size 0.508)
		(drill 0.254)
		(layers "F.Cu" "B.Cu")
		(net "GND")
	)
	(via
		(at 266.691618 -111.72317)
		(size 0.508)
		(drill 0.254)
		(layers "F.Cu" "B.Cu")
		(net "GND")
	)
	(via
		(at 156.750004 -306.349908)
		(size 0.4064)
		(drill 0.2032)
		(layers "F.Cu" "B.Cu")
		(net "GND")
	)
	(via
		(at 134.670038 -25.832054)
		(size 0.508)
		(drill 0.254)
		(layers "F.Cu" "B.Cu")
		(net "GND")
	)
	(via
		(at 274.274788 -279.274778)
		(size 0.4064)
		(drill 0.2032)
		(layers "F.Cu" "B.Cu")
		(net "GND")
	)
	(via
		(at 425.52493 -297.32478)
		(size 0.4064)
		(drill 0.2032)
		(layers "F.Cu" "B.Cu")
		(net "GND")
	)
	(via
		(at 132.658104 -58.791094)
		(size 0.508)
		(drill 0.254)
		(layers "F.Cu" "B.Cu")
		(net "GND")
	)
	(via
		(at 59.649868 -279.749758)
		(size 0.4064)
		(drill 0.2032)
		(layers "F.Cu" "B.Cu")
		(net "GND")
	)
	(via
		(at 196.043296 -28.139136)
		(size 0.508)
		(drill 0.254)
		(layers "F.Cu" "B.Cu")
		(net "GND")
	)
	(via
		(at 296.793412 -131.245102)
		(size 0.508)
		(drill 0.254)
		(layers "F.Cu" "B.Cu")
		(net "GND")
	)
	(via
		(at 165.299898 -312.999882)
		(size 0.4064)
		(drill 0.2032)
		(layers "F.Cu" "B.Cu")
		(net "GND")
	)
	(via
		(at 283.833062 -131.76504)
		(size 0.508)
		(drill 0.254)
		(layers "F.Cu" "B.Cu")
		(net "GND")
	)
	(via
		(at 324.11924 -125.414532)
		(size 0.508)
		(drill 0.254)
		(layers "F.Cu" "B.Cu")
		(net "GND")
	)
	(via
		(at 327.673208 -73.20026)
		(size 0.508)
		(drill 0.254)
		(layers "F.Cu" "B.Cu")
		(net "GND")
	)
	(via
		(at 160.074864 -280.224738)
		(size 0.4064)
		(drill 0.2032)
		(layers "F.Cu" "B.Cu")
		(net "GND")
	)
	(via
		(at 330.473812 -73.85177)
		(size 0.508)
		(drill 0.254)
		(layers "F.Cu" "B.Cu")
		(net "GND")
	)
	(via
		(at 342.23452 -270.001492)
		(size 0.508)
		(drill 0.254)
		(layers "F.Cu" "B.Cu")
		(net "GND")
	)
	(via
		(at 168.150032 -319.65011)
		(size 0.4064)
		(drill 0.2032)
		(layers "F.Cu" "B.Cu")
		(net "GND")
	)
	(via
		(at 73.899776 -278.799798)
		(size 0.4064)
		(drill 0.2032)
		(layers "F.Cu" "B.Cu")
		(net "GND")
	)
	(via
		(at 194.749928 -284.499812)
		(size 0.4064)
		(drill 0.2032)
		(layers "F.Cu" "B.Cu")
		(net "GND")
	)
	(via
		(at 157.699964 -310.149748)
		(size 0.4064)
		(drill 0.2032)
		(layers "F.Cu" "B.Cu")
		(net "GND")
	)
	(via
		(at 394.64996 -319.65011)
		(size 0.4064)
		(drill 0.2032)
		(layers "F.Cu" "B.Cu")
		(net "GND")
	)
	(via
		(at 229.8827 -182.948072)
		(size 0.508)
		(drill 0.254)
		(layers "F.Cu" "B.Cu")
		(net "GND")
	)
	(via
		(at 281.394154 -352.245422)
		(size 0.4572)
		(drill 0.254)
		(layers "F.Cu" "B.Cu")
		(net "GND")
	)
	(via
		(at 314.649866 -288.299906)
		(size 0.4064)
		(drill 0.2032)
		(layers "F.Cu" "B.Cu")
		(net "GND")
	)
	(via
		(at 35.899598 -308.250082)
		(size 0.4064)
		(drill 0.2032)
		(layers "F.Cu" "B.Cu")
		(net "GND")
	)
	(via
		(at 23.50262 -349.219774)
		(size 0.4572)
		(drill 0.254)
		(layers "F.Cu" "B.Cu")
		(net "GND")
	)
	(via
		(at 412.098236 -21.077936)
		(size 0.508)
		(drill 0.254)
		(layers "F.Cu" "B.Cu")
		(net "GND")
	)
	(via
		(at 390.902952 -357.123746)
		(size 0.4572)
		(drill 0.254)
		(layers "F.Cu" "B.Cu")
		(net "GND")
	)
	(via
		(at 194.336924 -352.245422)
		(size 0.4572)
		(drill 0.254)
		(layers "F.Cu" "B.Cu")
		(net "GND")
	)
	(via
		(at 381.527812 -381.241808)
		(size 0.508)
		(drill 0.254)
		(layers "F.Cu" "B.Cu")
		(net "GND")
	)
	(via
		(at 113.294668 -342.439498)
		(size 0.4064)
		(drill 0.2032)
		(layers "F.Cu" "B.Cu")
		(net "GND")
	)
	(via
		(at 151.999696 -310.150002)
		(size 0.4064)
		(drill 0.2032)
		(layers "F.Cu" "B.Cu")
		(net "GND")
	)
	(via
		(at 285.199836 -273.099784)
		(size 0.4064)
		(drill 0.2032)
		(layers "F.Cu" "B.Cu")
		(net "GND")
	)
	(via
		(at 390.857994 -58.156094)
		(size 0.508)
		(drill 0.254)
		(layers "F.Cu" "B.Cu")
		(net "GND")
	)
	(via
		(at 430.241964 -49.574704)
		(size 0.508)
		(drill 0.254)
		(layers "F.Cu" "B.Cu")
		(net "GND")
	)
	(via
		(at 293.527734 -371.038628)
		(size 0.508)
		(drill 0.254)
		(layers "F.Cu" "B.Cu")
		(net "GND")
	)
	(via
		(at 315.124846 -291.624766)
		(size 0.4064)
		(drill 0.2032)
		(layers "F.Cu" "B.Cu")
		(net "GND")
	)
	(via
		(at 292.79977 -318.699896)
		(size 0.4064)
		(drill 0.2032)
		(layers "F.Cu" "B.Cu")
		(net "GND")
	)
	(via
		(at 329.108816 -357.123746)
		(size 0.4572)
		(drill 0.254)
		(layers "F.Cu" "B.Cu")
		(net "GND")
	)
	(via
		(at 274.274788 -298.27474)
		(size 0.4064)
		(drill 0.2032)
		(layers "F.Cu" "B.Cu")
		(net "GND")
	)
	(via
		(at 179.55006 -280.699718)
		(size 0.4064)
		(drill 0.2032)
		(layers "F.Cu" "B.Cu")
		(net "GND")
	)
	(via
		(at 302.327818 -409.940252)
		(size 0.508)
		(drill 0.254)
		(layers "F.Cu" "B.Cu")
		(net "GND")
	)
	(via
		(at 161.500058 -277.849838)
		(size 0.4064)
		(drill 0.2032)
		(layers "F.Cu" "B.Cu")
		(net "GND")
	)
	(via
		(at 150.103078 -293.494714)
		(size 0.508)
		(drill 0.254)
		(layers "F.Cu" "B.Cu")
		(net "GND")
	)
	(via
		(at 190.226696 -410.898086)
		(size 0.508)
		(drill 0.254)
		(layers "F.Cu" "B.Cu")
		(net "GND")
	)
	(via
		(at 440.548776 -29.589984)
		(size 0.508)
		(drill 0.254)
		(layers "F.Cu" "B.Cu")
		(net "GND")
	)
	(via
		(at 284.782514 -155.58897)
		(size 0.508)
		(drill 0.254)
		(layers "F.Cu" "B.Cu")
		(net "GND")
	)
	(via
		(at 356.842568 -286.842454)
		(size 0.508)
		(drill 0.254)
		(layers "F.Cu" "B.Cu")
		(net "GND")
	)
	(via
		(at 301.432468 -217.288364)
		(size 0.508)
		(drill 0.254)
		(layers "F.Cu" "B.Cu")
		(net "GND")
	)
	(via
		(at 276.649688 -301.599854)
		(size 0.4064)
		(drill 0.2032)
		(layers "F.Cu" "B.Cu")
		(net "GND")
	)
	(via
		(at 53.949854 -311.099962)
		(size 0.4064)
		(drill 0.2032)
		(layers "F.Cu" "B.Cu")
		(net "GND")
	)
	(via
		(at 272.102072 -56.826404)
		(size 0.508)
		(drill 0.254)
		(layers "F.Cu" "B.Cu")
		(net "GND")
	)
	(via
		(at 231.66959 -84.41309)
		(size 0.508)
		(drill 0.254)
		(layers "F.Cu" "B.Cu")
		(net "GND")
	)
	(via
		(at 123.92025 -31.390336)
		(size 0.508)
		(drill 0.254)
		(layers "F.Cu" "B.Cu")
		(net "GND")
	)
	(via
		(at 231.510078 -416.508438)
		(size 0.508)
		(drill 0.254)
		(layers "F.Cu" "B.Cu")
		(net "GND")
	)
	(via
		(at 109.331506 -90.96121)
		(size 0.508)
		(drill 0.254)
		(layers "F.Cu" "B.Cu")
		(net "GND")
	)
	(via
		(at 57.721246 -369.827302)
		(size 0.4064)
		(drill 0.2032)
		(layers "F.Cu" "B.Cu")
		(net "GND")
	)
	(via
		(at 175.683164 -344.831162)
		(size 0.4572)
		(drill 0.254)
		(layers "F.Cu" "B.Cu")
		(net "GND")
	)
	(via
		(at 231.867456 -215.504268)
		(size 0.4572)
		(drill 0.254)
		(layers "F.Cu" "B.Cu")
		(net "GND")
	)
	(via
		(at 402.724874 -291.624766)
		(size 0.4064)
		(drill 0.2032)
		(layers "F.Cu" "B.Cu")
		(net "GND")
	)
	(via
		(at 463.482182 -280.11882)
		(size 0.508)
		(drill 0.254)
		(layers "F.Cu" "B.Cu")
		(net "GND")
	)
	(via
		(at 311.799732 -308.249828)
		(size 0.4064)
		(drill 0.2032)
		(layers "F.Cu" "B.Cu")
		(net "GND")
	)
	(via
		(at 438.044844 -27.79014)
		(size 0.508)
		(drill 0.254)
		(layers "F.Cu" "B.Cu")
		(net "GND")
	)
	(via
		(at 38.401752 -103.975408)
		(size 0.508)
		(drill 0.254)
		(layers "F.Cu" "B.Cu")
		(net "GND")
	)
	(via
		(at 337.5279 -398.24025)
		(size 0.508)
		(drill 0.254)
		(layers "F.Cu" "B.Cu")
		(net "GND")
	)
	(via
		(at 48.54575 -154.0256)
		(size 0.508)
		(drill 0.254)
		(layers "F.Cu" "B.Cu")
		(net "GND")
	)
	(via
		(at 84.808314 -123.904502)
		(size 0.508)
		(drill 0.254)
		(layers "F.Cu" "B.Cu")
		(net "GND")
	)
	(via
		(at 121.947686 -404.838662)
		(size 0.508)
		(drill 0.254)
		(layers "F.Cu" "B.Cu")
		(net "GND")
	)
	(via
		(at 153.898346 -19.096736)
		(size 0.508)
		(drill 0.254)
		(layers "F.Cu" "B.Cu")
		(net "GND")
	)
	(via
		(at 192.375028 -301.124874)
		(size 0.4064)
		(drill 0.2032)
		(layers "F.Cu" "B.Cu")
		(net "GND")
	)
	(via
		(at 387.050026 -316.799722)
		(size 0.4064)
		(drill 0.2032)
		(layers "F.Cu" "B.Cu")
		(net "GND")
	)
	(via
		(at 285.255208 -14.607794)
		(size 0.508)
		(drill 0.254)
		(layers "F.Cu" "B.Cu")
		(net "GND")
	)
	(via
		(at 107.31373 -293.424102)
		(size 0.508)
		(drill 0.254)
		(layers "F.Cu" "B.Cu")
		(net "GND")
	)
	(via
		(at 412.89351 -152.955244)
		(size 0.508)
		(drill 0.254)
		(layers "F.Cu" "B.Cu")
		(net "GND")
	)
	(via
		(at 415.612834 -102.439978)
		(size 0.508)
		(drill 0.254)
		(layers "F.Cu" "B.Cu")
		(net "GND")
	)
	(via
		(at 103.205026 -307.18887)
		(size 0.508)
		(drill 0.254)
		(layers "F.Cu" "B.Cu")
		(net "GND")
	)
	(via
		(at 268.09954 -306.350162)
		(size 0.4064)
		(drill 0.2032)
		(layers "F.Cu" "B.Cu")
		(net "GND")
	)
	(via
		(at 416.499802 -317.749936)
		(size 0.4064)
		(drill 0.2032)
		(layers "F.Cu" "B.Cu")
		(net "GND")
	)
	(via
		(at 412.988252 -114.267742)
		(size 0.508)
		(drill 0.254)
		(layers "F.Cu" "B.Cu")
		(net "GND")
	)
	(via
		(at 286.906462 -131.76504)
		(size 0.508)
		(drill 0.254)
		(layers "F.Cu" "B.Cu")
		(net "GND")
	)
	(via
		(at 343.394792 -350.977454)
		(size 0.4572)
		(drill 0.254)
		(layers "F.Cu" "B.Cu")
		(net "GND")
	)
	(via
		(at 71.999856 -318.699896)
		(size 0.4064)
		(drill 0.2032)
		(layers "F.Cu" "B.Cu")
		(net "GND")
	)
	(via
		(at 231.847644 -77.901038)
		(size 0.508)
		(drill 0.254)
		(layers "F.Cu" "B.Cu")
		(net "GND")
	)
	(via
		(at 122.635772 -285.267654)
		(size 0.508)
		(drill 0.254)
		(layers "F.Cu" "B.Cu")
		(net "GND")
	)
	(via
		(at 274.285202 -87.79764)
		(size 0.508)
		(drill 0.254)
		(layers "F.Cu" "B.Cu")
		(net "GND")
	)
	(via
		(at 63.924942 -306.824888)
		(size 0.4064)
		(drill 0.2032)
		(layers "F.Cu" "B.Cu")
		(net "GND")
	)
	(via
		(at 57.749948 -312.049922)
		(size 0.4064)
		(drill 0.2032)
		(layers "F.Cu" "B.Cu")
		(net "GND")
	)
	(via
		(at 170.806364 -122.354848)
		(size 0.508)
		(drill 0.254)
		(layers "F.Cu" "B.Cu")
		(net "GND")
	)
	(via
		(at 173.54804 -64.312292)
		(size 0.508)
		(drill 0.254)
		(layers "F.Cu" "B.Cu")
		(net "GND")
	)
	(via
		(at 88.947752 -407.638504)
		(size 0.508)
		(drill 0.254)
		(layers "F.Cu" "B.Cu")
		(net "GND")
	)
	(via
		(at 369.062 -162.3187)
		(size 0.508)
		(drill 0.254)
		(layers "F.Cu" "B.Cu")
		(net "GND")
	)
	(via
		(at 68.674742 -287.824926)
		(size 0.4064)
		(drill 0.2032)
		(layers "F.Cu" "B.Cu")
		(net "GND")
	)
	(via
		(at 299.449744 -316.799722)
		(size 0.4064)
		(drill 0.2032)
		(layers "F.Cu" "B.Cu")
		(net "GND")
	)
	(via
		(at 119.747792 -373.83847)
		(size 0.508)
		(drill 0.254)
		(layers "F.Cu" "B.Cu")
		(net "GND")
	)
	(via
		(at 45.87494 -296.37482)
		(size 0.4064)
		(drill 0.2032)
		(layers "F.Cu" "B.Cu")
		(net "GND")
	)
	(via
		(at 298.417742 -348.58579)
		(size 0.4064)
		(drill 0.2032)
		(layers "F.Cu" "B.Cu")
		(net "GND")
	)
	(via
		(at 183.3499 -281.649932)
		(size 0.4064)
		(drill 0.2032)
		(layers "F.Cu" "B.Cu")
		(net "GND")
	)
	(via
		(at 397.97482 -294.4749)
		(size 0.4064)
		(drill 0.2032)
		(layers "F.Cu" "B.Cu")
		(net "GND")
	)
	(via
		(at 317.008256 -151.42464)
		(size 0.508)
		(drill 0.254)
		(layers "F.Cu" "B.Cu")
		(net "GND")
	)
	(via
		(at 424.09999 -286.399732)
		(size 0.4064)
		(drill 0.2032)
		(layers "F.Cu" "B.Cu")
		(net "GND")
	)
	(via
		(at 42.15638 -352.245422)
		(size 0.4572)
		(drill 0.254)
		(layers "F.Cu" "B.Cu")
		(net "GND")
	)
	(via
		(at 397.49984 -317.749936)
		(size 0.4064)
		(drill 0.2032)
		(layers "F.Cu" "B.Cu")
		(net "GND")
	)
	(via
		(at 152.47493 -294.4749)
		(size 0.4064)
		(drill 0.2032)
		(layers "F.Cu" "B.Cu")
		(net "GND")
	)
	(via
		(at 361.728004 -228.67493)
		(size 0.508)
		(drill 0.254)
		(layers "F.Cu" "B.Cu")
		(net "GND")
	)
	(via
		(at 339.625432 -305.008534)
		(size 0.508)
		(drill 0.254)
		(layers "F.Cu" "B.Cu")
		(net "GND")
	)
	(via
		(at 249.896122 -161.54527)
		(size 0.508)
		(drill 0.254)
		(layers "F.Cu" "B.Cu")
		(net "GND")
	)
	(via
		(at 151.859488 -130.236722)
		(size 0.508)
		(drill 0.254)
		(layers "F.Cu" "B.Cu")
		(net "GND")
	)
	(via
		(at 389.424926 -287.824926)
		(size 0.4064)
		(drill 0.2032)
		(layers "F.Cu" "B.Cu")
		(net "GND")
	)
	(via
		(at 370.990368 -341.805514)
		(size 0.4572)
		(drill 0.254)
		(layers "F.Cu" "B.Cu")
		(net "GND")
	)
	(via
		(at 346.327984 -399.441924)
		(size 0.508)
		(drill 0.254)
		(layers "F.Cu" "B.Cu")
		(net "GND")
	)
	(via
		(at 298.647612 -131.245102)
		(size 0.508)
		(drill 0.254)
		(layers "F.Cu" "B.Cu")
		(net "GND")
	)
	(via
		(at 383.426208 -352.245422)
		(size 0.4572)
		(drill 0.254)
		(layers "F.Cu" "B.Cu")
		(net "GND")
	)
	(via
		(at 371.740938 -45.853858)
		(size 0.508)
		(drill 0.254)
		(layers "F.Cu" "B.Cu")
		(net "GND")
	)
	(via
		(at 332.160118 -20.35556)
		(size 0.508)
		(drill 0.254)
		(layers "F.Cu" "B.Cu")
		(net "GND")
	)
	(via
		(at 227.842826 -108.445808)
		(size 0.508)
		(drill 0.254)
		(layers "F.Cu" "B.Cu")
		(net "GND")
	)
	(via
		(at 296.793412 -136.645142)
		(size 0.508)
		(drill 0.254)
		(layers "F.Cu" "B.Cu")
		(net "GND")
	)
	(via
		(at 42.83837 -73.20026)
		(size 0.508)
		(drill 0.254)
		(layers "F.Cu" "B.Cu")
		(net "GND")
	)
	(via
		(at 424.270932 -351.611438)
		(size 0.4064)
		(drill 0.2032)
		(layers "F.Cu" "B.Cu")
		(net "GND")
	)
	(via
		(at 381.527812 -408.738578)
		(size 0.508)
		(drill 0.254)
		(layers "F.Cu" "B.Cu")
		(net "GND")
	)
	(via
		(at 429.010064 -352.245422)
		(size 0.4572)
		(drill 0.254)
		(layers "F.Cu" "B.Cu")
		(net "GND")
	)
	(via
		(at 50.224436 -349.219774)
		(size 0.4572)
		(drill 0.254)
		(layers "F.Cu" "B.Cu")
		(net "GND")
	)
	(via
		(at 335.026 -147.955)
		(size 0.508)
		(drill 0.254)
		(layers "F.Cu" "B.Cu")
		(net "GND")
	)
	(via
		(at 197.600062 -313.949842)
		(size 0.4064)
		(drill 0.2032)
		(layers "F.Cu" "B.Cu")
		(net "GND")
	)
	(via
		(at 188.346842 -115.504976)
		(size 0.508)
		(drill 0.254)
		(layers "F.Cu" "B.Cu")
		(net "GND")
	)
	(via
		(at 172.900086 -277.849838)
		(size 0.4064)
		(drill 0.2032)
		(layers "F.Cu" "B.Cu")
		(net "GND")
	)
	(via
		(at 412.224982 -287.824926)
		(size 0.4064)
		(drill 0.2032)
		(layers "F.Cu" "B.Cu")
		(net "GND")
	)
	(via
		(at 260.757924 -280.058114)
		(size 0.508)
		(drill 0.254)
		(layers "F.Cu" "B.Cu")
		(net "GND")
	)
	(via
		(at 104.008936 -79.989934)
		(size 0.508)
		(drill 0.254)
		(layers "F.Cu" "B.Cu")
		(net "GND")
	)
	(via
		(at 374.099328 -357.123746)
		(size 0.4572)
		(drill 0.254)
		(layers "F.Cu" "B.Cu")
		(net "GND")
	)
	(via
		(at 191.900048 -277.849838)
		(size 0.4064)
		(drill 0.2032)
		(layers "F.Cu" "B.Cu")
		(net "GND")
	)
	(via
		(at 114.773456 -344.831162)
		(size 0.4572)
		(drill 0.254)
		(layers "F.Cu" "B.Cu")
		(net "GND")
	)
	(via
		(at 241.60353 -184.69991)
		(size 0.508)
		(drill 0.254)
		(layers "F.Cu" "B.Cu")
		(net "GND")
	)
	(via
		(at 29.54782 -381.241808)
		(size 0.508)
		(drill 0.254)
		(layers "F.Cu" "B.Cu")
		(net "GND")
	)
	(via
		(at 77.947774 -377.341892)
		(size 0.508)
		(drill 0.254)
		(layers "F.Cu" "B.Cu")
		(net "GND")
	)
	(via
		(at 55.849774 -315.849762)
		(size 0.4064)
		(drill 0.2032)
		(layers "F.Cu" "B.Cu")
		(net "GND")
	)
	(via
		(at 392.938762 -23.880318)
		(size 0.508)
		(drill 0.254)
		(layers "F.Cu" "B.Cu")
		(net "GND")
	)
	(via
		(at 312.749692 -276.899878)
		(size 0.4064)
		(drill 0.2032)
		(layers "F.Cu" "B.Cu")
		(net "GND")
	)
	(via
		(at 84.567522 -348.58579)
		(size 0.4064)
		(drill 0.2032)
		(layers "F.Cu" "B.Cu")
		(net "GND")
	)
	(via
		(at 406.999948 -276.899878)
		(size 0.4064)
		(drill 0.2032)
		(layers "F.Cu" "B.Cu")
		(net "GND")
	)
	(via
		(at 65.542414 -344.831162)
		(size 0.4572)
		(drill 0.254)
		(layers "F.Cu" "B.Cu")
		(net "GND")
	)
	(via
		(at 378.993654 -227.29444)
		(size 0.508)
		(drill 0.254)
		(layers "F.Cu" "B.Cu")
		(net "GND")
	)
	(via
		(at 184.77484 -291.624766)
		(size 0.4064)
		(drill 0.2032)
		(layers "F.Cu" "B.Cu")
		(net "GND")
	)
	(via
		(at 377.109228 -85.952076)
		(size 0.508)
		(drill 0.254)
		(layers "F.Cu" "B.Cu")
		(net "GND")
	)
	(via
		(at 3.620008 -284.818582)
		(size 0.508)
		(drill 0.254)
		(layers "F.Cu" "B.Cu")
		(net "GND")
	)
	(via
		(at 117.628416 -136.291828)
		(size 0.508)
		(drill 0.254)
		(layers "F.Cu" "B.Cu")
		(net "GND")
	)
	(via
		(at 430.749964 -274.049744)
		(size 0.4064)
		(drill 0.2032)
		(layers "F.Cu" "B.Cu")
		(net "GND")
	)
	(via
		(at 273.91741 -341.805514)
		(size 0.4572)
		(drill 0.254)
		(layers "F.Cu" "B.Cu")
		(net "GND")
	)
	(via
		(at 305.624738 -299.224954)
		(size 0.4064)
		(drill 0.2032)
		(layers "F.Cu" "B.Cu")
		(net "GND")
	)
	(via
		(at 119.747792 -380.141734)
		(size 0.4572)
		(drill 0.254)
		(layers "F.Cu" "B.Cu")
		(net "GND")
	)
	(via
		(at 192.706752 -342.439498)
		(size 0.4064)
		(drill 0.2032)
		(layers "F.Cu" "B.Cu")
		(net "GND")
	)
	(via
		(at 341.59952 -268.096492)
		(size 0.508)
		(drill 0.254)
		(layers "F.Cu" "B.Cu")
		(net "GND")
	)
	(via
		(at 290.17976 -104.830372)
		(size 0.508)
		(drill 0.254)
		(layers "F.Cu" "B.Cu")
		(net "GND")
	)
	(via
		(at 353.41052 -305.008534)
		(size 0.508)
		(drill 0.254)
		(layers "F.Cu" "B.Cu")
		(net "GND")
	)
	(via
		(at 103.338122 -100.751894)
		(size 0.508)
		(drill 0.254)
		(layers "F.Cu" "B.Cu")
		(net "GND")
	)
	(via
		(at 336.666332 -78.754732)
		(size 0.508)
		(drill 0.254)
		(layers "F.Cu" "B.Cu")
		(net "GND")
	)
	(via
		(at 106.611674 -285.267654)
		(size 0.508)
		(drill 0.254)
		(layers "F.Cu" "B.Cu")
		(net "GND")
	)
	(via
		(at 189.999874 -285.449772)
		(size 0.4064)
		(drill 0.2032)
		(layers "F.Cu" "B.Cu")
		(net "GND")
	)
	(via
		(at 432.119024 -352.245422)
		(size 0.4572)
		(drill 0.254)
		(layers "F.Cu" "B.Cu")
		(net "GND")
	)
	(via
		(at 4.562856 -93.801692)
		(size 0.508)
		(drill 0.254)
		(layers "F.Cu" "B.Cu")
		(net "GND")
	)
	(via
		(at 298.499784 -310.149748)
		(size 0.4064)
		(drill 0.2032)
		(layers "F.Cu" "B.Cu")
		(net "GND")
	)
	(via
		(at 386.088636 -31.642304)
		(size 0.508)
		(drill 0.254)
		(layers "F.Cu" "B.Cu")
		(net "GND")
	)
	(via
		(at 299.924724 -289.724846)
		(size 0.4064)
		(drill 0.2032)
		(layers "F.Cu" "B.Cu")
		(net "GND")
	)
	(via
		(at 312.749692 -316.799722)
		(size 0.4064)
		(drill 0.2032)
		(layers "F.Cu" "B.Cu")
		(net "GND")
	)
	(via
		(at 213.202774 -232.623106)
		(size 0.508)
		(drill 0.254)
		(layers "F.Cu" "B.Cu")
		(net "GND")
	)
	(via
		(at 289.46221 -347.951806)
		(size 0.4572)
		(drill 0.254)
		(layers "F.Cu" "B.Cu")
		(net "GND")
	)
	(via
		(at 216.194894 -217.22207)
		(size 0.508)
		(drill 0.254)
		(layers "F.Cu" "B.Cu")
		(net "GND")
	)
	(via
		(at 35.101276 -102.181914)
		(size 0.508)
		(drill 0.254)
		(layers "F.Cu" "B.Cu")
		(net "GND")
	)
	(via
		(at 298.647612 -118.234968)
		(size 0.508)
		(drill 0.254)
		(layers "F.Cu" "B.Cu")
		(net "GND")
	)
	(via
		(at 59.649868 -314.899802)
		(size 0.4064)
		(drill 0.2032)
		(layers "F.Cu" "B.Cu")
		(net "GND")
	)
	(via
		(at 430.749964 -317.749936)
		(size 0.4064)
		(drill 0.2032)
		(layers "F.Cu" "B.Cu")
		(net "GND")
	)
	(via
		(at 71.524876 -296.37482)
		(size 0.4064)
		(drill 0.2032)
		(layers "F.Cu" "B.Cu")
		(net "GND")
	)
	(via
		(at 339.037422 -305.972718)
		(size 0.508)
		(drill 0.254)
		(layers "F.Cu" "B.Cu")
		(net "GND")
	)
	(via
		(at 219.60205 -209.423)
		(size 0.508)
		(drill 0.254)
		(layers "F.Cu" "B.Cu")
		(net "GND")
	)
	(via
		(at 232.81386 -203.361544)
		(size 0.508)
		(drill 0.254)
		(layers "F.Cu" "B.Cu")
		(net "GND")
	)
	(via
		(at 287.574736 -300.174914)
		(size 0.4064)
		(drill 0.2032)
		(layers "F.Cu" "B.Cu")
		(net "GND")
	)
	(via
		(at 459.713838 -316.02299)
		(size 0.508)
		(drill 0.254)
		(layers "F.Cu" "B.Cu")
		(net "GND")
	)
	(via
		(at 338.435696 -349.219774)
		(size 0.4572)
		(drill 0.254)
		(layers "F.Cu" "B.Cu")
		(net "GND")
	)
	(via
		(at 385.927854 -371.038628)
		(size 0.508)
		(drill 0.254)
		(layers "F.Cu" "B.Cu")
		(net "GND")
	)
	(via
		(at 57.274968 -306.824888)
		(size 0.4064)
		(drill 0.2032)
		(layers "F.Cu" "B.Cu")
		(net "GND")
	)
	(via
		(at 256.111248 -346.337382)
		(size 0.508)
		(drill 0.254)
		(layers "F.Cu" "B.Cu")
		(net "GND")
	)
	(via
		(at 199.64019 -125.163326)
		(size 0.508)
		(drill 0.254)
		(layers "F.Cu" "B.Cu")
		(net "GND")
	)
	(via
		(at 96.581976 -58.873644)
		(size 0.508)
		(drill 0.254)
		(layers "F.Cu" "B.Cu")
		(net "GND")
	)
	(via
		(at 284.503114 -341.805514)
		(size 0.4572)
		(drill 0.254)
		(layers "F.Cu" "B.Cu")
		(net "GND")
	)
	(via
		(at 163.747958 -369.938554)
		(size 0.508)
		(drill 0.254)
		(layers "F.Cu" "B.Cu")
		(net "GND")
	)
	(via
		(at 421.127682 -409.940252)
		(size 0.508)
		(drill 0.254)
		(layers "F.Cu" "B.Cu")
		(net "GND")
	)
	(via
		(at 395.12494 -306.824888)
		(size 0.4064)
		(drill 0.2032)
		(layers "F.Cu" "B.Cu")
		(net "GND")
	)
	(via
		(at 176.699926 -310.149748)
		(size 0.4064)
		(drill 0.2032)
		(layers "F.Cu" "B.Cu")
		(net "GND")
	)
	(via
		(at 39.04742 -341.805514)
		(size 0.4572)
		(drill 0.254)
		(layers "F.Cu" "B.Cu")
		(net "GND")
	)
	(via
		(at 163.399978 -274.049744)
		(size 0.4064)
		(drill 0.2032)
		(layers "F.Cu" "B.Cu")
		(net "GND")
	)
	(via
		(at 404.624794 -289.724846)
		(size 0.4064)
		(drill 0.2032)
		(layers "F.Cu" "B.Cu")
		(net "GND")
	)
	(via
		(at 180.02504 -291.624766)
		(size 0.4064)
		(drill 0.2032)
		(layers "F.Cu" "B.Cu")
		(net "GND")
	)
	(via
		(at 114.873786 -285.953454)
		(size 0.508)
		(drill 0.254)
		(layers "F.Cu" "B.Cu")
		(net "GND")
	)
	(via
		(at 189.524894 -299.224954)
		(size 0.4064)
		(drill 0.2032)
		(layers "F.Cu" "B.Cu")
		(net "GND")
	)
	(via
		(at 40.547798 -397.140176)
		(size 0.508)
		(drill 0.254)
		(layers "F.Cu" "B.Cu")
		(net "GND")
	)
	(via
		(at 298.024804 -302.074834)
		(size 0.4064)
		(drill 0.2032)
		(layers "F.Cu" "B.Cu")
		(net "GND")
	)
	(via
		(at 408.120088 -33.19018)
		(size 0.508)
		(drill 0.254)
		(layers "F.Cu" "B.Cu")
		(net "GND")
	)
	(via
		(at 5.260086 -44.647358)
		(size 0.508)
		(drill 0.254)
		(layers "F.Cu" "B.Cu")
		(net "GND")
	)
	(via
		(at 399.93316 -137.16508)
		(size 0.508)
		(drill 0.254)
		(layers "F.Cu" "B.Cu")
		(net "GND")
	)
	(via
		(at 334.494124 -226.786948)
		(size 0.4572)
		(drill 0.254)
		(layers "F.Cu" "B.Cu")
		(net "GND")
	)
	(via
		(at 427.75124 -358.391714)
		(size 0.4572)
		(drill 0.254)
		(layers "F.Cu" "B.Cu")
		(net "GND")
	)
	(via
		(at 421.724836 -298.27474)
		(size 0.4064)
		(drill 0.2032)
		(layers "F.Cu" "B.Cu")
		(net "GND")
	)
	(via
		(at 383.401316 -100.92309)
		(size 0.508)
		(drill 0.254)
		(layers "F.Cu" "B.Cu")
		(net "GND")
	)
	(via
		(at 433.108354 -131.514596)
		(size 0.508)
		(drill 0.254)
		(layers "F.Cu" "B.Cu")
		(net "GND")
	)
	(via
		(at 125.295152 -60.633356)
		(size 0.508)
		(drill 0.254)
		(layers "F.Cu" "B.Cu")
		(net "GND")
	)
	(via
		(at 99.313238 -29.859478)
		(size 0.508)
		(drill 0.254)
		(layers "F.Cu" "B.Cu")
		(net "GND")
	)
	(via
		(at 410.04744 -391.88644)
		(size 0.508)
		(drill 0.254)
		(layers "F.Cu" "B.Cu")
		(net "GND")
	)
	(via
		(at 177.5333 -343.073482)
		(size 0.4572)
		(drill 0.254)
		(layers "F.Cu" "B.Cu")
		(net "GND")
	)
	(via
		(at 103.944674 -285.267654)
		(size 0.508)
		(drill 0.254)
		(layers "F.Cu" "B.Cu")
		(net "GND")
	)
	(via
		(at 412.224982 -289.724846)
		(size 0.4064)
		(drill 0.2032)
		(layers "F.Cu" "B.Cu")
		(net "GND")
	)
	(via
		(at 196.998082 -129.707894)
		(size 0.508)
		(drill 0.254)
		(layers "F.Cu" "B.Cu")
		(net "GND")
	)
	(via
		(at 452.374 -225.574098)
		(size 0.508)
		(drill 0.254)
		(layers "F.Cu" "B.Cu")
		(net "GND")
	)
	(via
		(at 168.625012 -284.024832)
		(size 0.4064)
		(drill 0.2032)
		(layers "F.Cu" "B.Cu")
		(net "GND")
	)
	(via
		(at 101.753162 -169.68724)
		(size 0.508)
		(drill 0.254)
		(layers "F.Cu" "B.Cu")
		(net "GND")
	)
	(via
		(at 113.806986 -0.762)
		(size 0.508)
		(drill 0.254)
		(layers "F.Cu" "B.Cu")
		(net "GND")
	)
	(via
		(at 381.527812 -380.040134)
		(size 0.508)
		(drill 0.254)
		(layers "F.Cu" "B.Cu")
		(net "GND")
	)
	(via
		(at 298.024804 -307.774848)
		(size 0.4064)
		(drill 0.2032)
		(layers "F.Cu" "B.Cu")
		(net "GND")
	)
	(via
		(at 306.448206 -136.645142)
		(size 0.508)
		(drill 0.254)
		(layers "F.Cu" "B.Cu")
		(net "GND")
	)
	(via
		(at 82.347816 -385.141978)
		(size 0.508)
		(drill 0.254)
		(layers "F.Cu" "B.Cu")
		(net "GND")
	)
	(via
		(at 410.727652 -342.439498)
		(size 0.4064)
		(drill 0.2032)
		(layers "F.Cu" "B.Cu")
		(net "GND")
	)
	(via
		(at 161.9885 -357.123746)
		(size 0.4572)
		(drill 0.254)
		(layers "F.Cu" "B.Cu")
		(net "GND")
	)
	(via
		(at 83.540346 -156.283406)
		(size 0.508)
		(drill 0.254)
		(layers "F.Cu" "B.Cu")
		(net "GND")
	)
	(via
		(at 426.94987 -283.549852)
		(size 0.4064)
		(drill 0.2032)
		(layers "F.Cu" "B.Cu")
		(net "GND")
	)
	(via
		(at 168.148 -375.040144)
		(size 0.508)
		(drill 0.254)
		(layers "F.Cu" "B.Cu")
		(net "GND")
	)
	(via
		(at 240.900458 -155.217114)
		(size 0.508)
		(drill 0.254)
		(layers "F.Cu" "B.Cu")
		(net "GND")
	)
	(via
		(at 185.250074 -310.149748)
		(size 0.4064)
		(drill 0.2032)
		(layers "F.Cu" "B.Cu")
		(net "GND")
	)
	(via
		(at 103.15067 -287.51149)
		(size 0.508)
		(drill 0.254)
		(layers "F.Cu" "B.Cu")
		(net "GND")
	)
	(via
		(at 34.679636 -352.245422)
		(size 0.4572)
		(drill 0.254)
		(layers "F.Cu" "B.Cu")
		(net "GND")
	)
	(via
		(at 136.861804 -161.6075)
		(size 0.508)
		(drill 0.254)
		(layers "F.Cu" "B.Cu")
		(net "GND")
	)
	(via
		(at 141.458442 -253.45644)
		(size 0.508)
		(drill 0.254)
		(layers "F.Cu" "B.Cu")
		(net "GND")
	)
	(via
		(at 336.14487 -285.267654)
		(size 0.508)
		(drill 0.254)
		(layers "F.Cu" "B.Cu")
		(net "GND")
	)
	(via
		(at 286.906462 -107.844844)
		(size 0.508)
		(drill 0.254)
		(layers "F.Cu" "B.Cu")
		(net "GND")
	)
	(via
		(at 28.854654 -223.841564)
		(size 0.508)
		(drill 0.254)
		(layers "F.Cu" "B.Cu")
		(net "GND")
	)
	(via
		(at 231.718612 -87.345774)
		(size 0.508)
		(drill 0.254)
		(layers "F.Cu" "B.Cu")
		(net "GND")
	)
	(via
		(at 190.474854 -300.174914)
		(size 0.4064)
		(drill 0.2032)
		(layers "F.Cu" "B.Cu")
		(net "GND")
	)
	(via
		(at 1.668018 -394.77061)
		(size 0.508)
		(drill 0.254)
		(layers "F.Cu" "B.Cu")
		(net "GND")
	)
	(via
		(at 169.836592 -342.439498)
		(size 0.4064)
		(drill 0.2032)
		(layers "F.Cu" "B.Cu")
		(net "GND")
	)
	(via
		(at 233.444288 -98.295968)
		(size 0.508)
		(drill 0.254)
		(layers "F.Cu" "B.Cu")
		(net "GND")
	)
	(via
		(at 129.627884 -286.842454)
		(size 0.508)
		(drill 0.254)
		(layers "F.Cu" "B.Cu")
		(net "GND")
	)
	(via
		(at 72.676766 -9.390634)
		(size 0.508)
		(drill 0.254)
		(layers "F.Cu" "B.Cu")
		(net "GND")
	)
	(via
		(at 93.076522 -119.936006)
		(size 0.508)
		(drill 0.254)
		(layers "F.Cu" "B.Cu")
		(net "GND")
	)
	(via
		(at 33.947862 -378.83846)
		(size 0.508)
		(drill 0.254)
		(layers "F.Cu" "B.Cu")
		(net "GND")
	)
	(via
		(at 345.803982 -286.842454)
		(size 0.508)
		(drill 0.254)
		(layers "F.Cu" "B.Cu")
		(net "GND")
	)
	(via
		(at 190.950088 -309.199788)
		(size 0.4064)
		(drill 0.2032)
		(layers "F.Cu" "B.Cu")
		(net "GND")
	)
	(via
		(at 299.866812 -114.635026)
		(size 0.508)
		(drill 0.254)
		(layers "F.Cu" "B.Cu")
		(net "GND")
	)
	(via
		(at 55.374794 -300.174914)
		(size 0.4064)
		(drill 0.2032)
		(layers "F.Cu" "B.Cu")
		(net "GND")
	)
	(via
		(at 134.68604 -354.098098)
		(size 0.4572)
		(drill 0.254)
		(layers "F.Cu" "B.Cu")
		(net "GND")
	)
	(via
		(at 240.189004 -200.599294)
		(size 0.508)
		(drill 0.254)
		(layers "F.Cu" "B.Cu")
		(net "GND")
	)
	(via
		(at 105.22585 -129.087118)
		(size 0.508)
		(drill 0.254)
		(layers "F.Cu" "B.Cu")
		(net "GND")
	)
	(via
		(at 241.558064 -141.019276)
		(size 0.508)
		(drill 0.254)
		(layers "F.Cu" "B.Cu")
		(net "GND")
	)
	(via
		(at 391.324846 -282.124912)
		(size 0.4064)
		(drill 0.2032)
		(layers "F.Cu" "B.Cu")
		(net "GND")
	)
	(via
		(at 42.074846 -296.37482)
		(size 0.4064)
		(drill 0.2032)
		(layers "F.Cu" "B.Cu")
		(net "GND")
	)
	(via
		(at 383.94894 -29.589984)
		(size 0.508)
		(drill 0.254)
		(layers "F.Cu" "B.Cu")
		(net "GND")
	)
	(via
		(at 286.927798 -376.241818)
		(size 0.508)
		(drill 0.254)
		(layers "F.Cu" "B.Cu")
		(net "GND")
	)
	(via
		(at 241.158522 -52.884324)
		(size 0.508)
		(drill 0.254)
		(layers "F.Cu" "B.Cu")
		(net "GND")
	)
	(via
		(at 131.149852 -131.312666)
		(size 0.508)
		(drill 0.254)
		(layers "F.Cu" "B.Cu")
		(net "GND")
	)
	(via
		(at 275.699728 -313.949842)
		(size 0.4064)
		(drill 0.2032)
		(layers "F.Cu" "B.Cu")
		(net "GND")
	)
	(via
		(at 414.599882 -281.649932)
		(size 0.4064)
		(drill 0.2032)
		(layers "F.Cu" "B.Cu")
		(net "GND")
	)
	(via
		(at 294.967914 -201.082148)
		(size 0.508)
		(drill 0.254)
		(layers "F.Cu" "B.Cu")
		(net "GND")
	)
	(via
		(at 361.794806 -159.498792)
		(size 0.508)
		(drill 0.254)
		(layers "F.Cu" "B.Cu")
		(net "GND")
	)
	(via
		(at 95.5802 -198.0692)
		(size 0.508)
		(drill 0.254)
		(layers "F.Cu" "B.Cu")
		(net "GND")
	)
	(via
		(at 286.624776 -285.924752)
		(size 0.4064)
		(drill 0.2032)
		(layers "F.Cu" "B.Cu")
		(net "GND")
	)
	(via
		(at 177.5333 -349.219774)
		(size 0.4572)
		(drill 0.254)
		(layers "F.Cu" "B.Cu")
		(net "GND")
	)
	(via
		(at 423.62501 -302.074834)
		(size 0.4064)
		(drill 0.2032)
		(layers "F.Cu" "B.Cu")
		(net "GND")
	)
	(via
		(at 77.69987 -306.349908)
		(size 0.4064)
		(drill 0.2032)
		(layers "F.Cu" "B.Cu")
		(net "GND")
	)
	(via
		(at 426.94987 -280.699718)
		(size 0.4064)
		(drill 0.2032)
		(layers "F.Cu" "B.Cu")
		(net "GND")
	)
	(via
		(at 153.960068 -245.27891)
		(size 0.508)
		(drill 0.254)
		(layers "F.Cu" "B.Cu")
		(net "GND")
	)
	(via
		(at 425.99991 -310.149748)
		(size 0.4064)
		(drill 0.2032)
		(layers "F.Cu" "B.Cu")
		(net "GND")
	)
	(via
		(at 306.574698 -290.674806)
		(size 0.4064)
		(drill 0.2032)
		(layers "F.Cu" "B.Cu")
		(net "GND")
	)
	(via
		(at 37.417248 -345.465146)
		(size 0.4064)
		(drill 0.2032)
		(layers "F.Cu" "B.Cu")
		(net "GND")
	)
	(via
		(at 119.888 -417.82492)
		(size 0.508)
		(drill 0.254)
		(layers "F.Cu" "B.Cu")
		(net "GND")
	)
	(via
		(at 88.783922 -354.732082)
		(size 0.4064)
		(drill 0.2032)
		(layers "F.Cu" "B.Cu")
		(net "GND")
	)
	(via
		(at 318.523112 -350.977454)
		(size 0.4572)
		(drill 0.254)
		(layers "F.Cu" "B.Cu")
		(net "GND")
	)
	(via
		(at 430.749964 -309.199788)
		(size 0.4064)
		(drill 0.2032)
		(layers "F.Cu" "B.Cu")
		(net "GND")
	)
	(via
		(at 187.149994 -279.749758)
		(size 0.4064)
		(drill 0.2032)
		(layers "F.Cu" "B.Cu")
		(net "GND")
	)
	(via
		(at 294.22471 -294.4749)
		(size 0.4064)
		(drill 0.2032)
		(layers "F.Cu" "B.Cu")
		(net "GND")
	)
	(via
		(at 386.535168 -354.098098)
		(size 0.4572)
		(drill 0.254)
		(layers "F.Cu" "B.Cu")
		(net "GND")
	)
	(via
		(at 77.978254 -347.951806)
		(size 0.4572)
		(drill 0.254)
		(layers "F.Cu" "B.Cu")
		(net "GND")
	)
	(via
		(at 231.556814 -286.087312)
		(size 0.508)
		(drill 0.254)
		(layers "F.Cu" "B.Cu")
		(net "GND")
	)
	(via
		(at 404.624794 -298.27474)
		(size 0.4064)
		(drill 0.2032)
		(layers "F.Cu" "B.Cu")
		(net "GND")
	)
	(via
		(at 27.668982 -279.931114)
		(size 0.508)
		(drill 0.254)
		(layers "F.Cu" "B.Cu")
		(net "GND")
	)
	(via
		(at 66.774822 -300.174914)
		(size 0.4064)
		(drill 0.2032)
		(layers "F.Cu" "B.Cu")
		(net "GND")
	)
	(via
		(at 157.699964 -302.549814)
		(size 0.4064)
		(drill 0.2032)
		(layers "F.Cu" "B.Cu")
		(net "GND")
	)
	(via
		(at 279.794462 -126.703836)
		(size 0.508)
		(drill 0.254)
		(layers "F.Cu" "B.Cu")
		(net "GND")
	)
	(via
		(at 256.570226 -237.190788)
		(size 0.508)
		(drill 0.254)
		(layers "F.Cu" "B.Cu")
		(net "GND")
	)
	(via
		(at 406.900888 -29.590238)
		(size 0.508)
		(drill 0.254)
		(layers "F.Cu" "B.Cu")
		(net "GND")
	)
	(via
		(at 349.410782 -288.14649)
		(size 0.508)
		(drill 0.254)
		(layers "F.Cu" "B.Cu")
		(net "GND")
	)
	(via
		(at 154.154886 -34.990024)
		(size 0.508)
		(drill 0.254)
		(layers "F.Cu" "B.Cu")
		(net "GND")
	)
	(via
		(at 269.049754 -301.599854)
		(size 0.4064)
		(drill 0.2032)
		(layers "F.Cu" "B.Cu")
		(net "GND")
	)
	(via
		(at 367.798604 -65.15989)
		(size 0.508)
		(drill 0.254)
		(layers "F.Cu" "B.Cu")
		(net "GND")
	)
	(via
		(at 224.76206 -279.075896)
		(size 0.508)
		(drill 0.254)
		(layers "F.Cu" "B.Cu")
		(net "GND")
	)
	(via
		(at 379.748034 -64.312292)
		(size 0.508)
		(drill 0.254)
		(layers "F.Cu" "B.Cu")
		(net "GND")
	)
	(via
		(at 197.366382 -405.18461)
		(size 0.508)
		(drill 0.254)
		(layers "F.Cu" "B.Cu")
		(net "GND")
	)
	(via
		(at 415.96691 -149.355048)
		(size 0.508)
		(drill 0.254)
		(layers "F.Cu" "B.Cu")
		(net "GND")
	)
	(via
		(at 120.620028 -354.732082)
		(size 0.4064)
		(drill 0.2032)
		(layers "F.Cu" "B.Cu")
		(net "GND")
	)
	(via
		(at 230.354886 -241.679476)
		(size 0.508)
		(drill 0.254)
		(layers "F.Cu" "B.Cu")
		(net "GND")
	)
	(via
		(at 363.97057 -133.972046)
		(size 0.508)
		(drill 0.254)
		(layers "F.Cu" "B.Cu")
		(net "GND")
	)
	(via
		(at 184.29986 -318.699896)
		(size 0.4064)
		(drill 0.2032)
		(layers "F.Cu" "B.Cu")
		(net "GND")
	)
	(via
		(at 27.347926 -375.040144)
		(size 0.508)
		(drill 0.254)
		(layers "F.Cu" "B.Cu")
		(net "GND")
	)
	(via
		(at 362.6612 -134.258812)
		(size 0.508)
		(drill 0.254)
		(layers "F.Cu" "B.Cu")
		(net "GND")
	)
	(via
		(at 80.786986 -0.762)
		(size 0.508)
		(drill 0.254)
		(layers "F.Cu" "B.Cu")
		(net "GND")
	)
	(via
		(at 448.881246 -31.118302)
		(size 0.508)
		(drill 0.254)
		(layers "F.Cu" "B.Cu")
		(net "GND")
	)
	(via
		(at 33.192466 -6.292342)
		(size 0.508)
		(drill 0.254)
		(layers "F.Cu" "B.Cu")
		(net "GND")
	)
	(via
		(at 12.170664 -240.695988)
		(size 0.508)
		(drill 0.254)
		(layers "F.Cu" "B.Cu")
		(net "GND")
	)
	(via
		(at 241.444018 -235.624116)
		(size 0.508)
		(drill 0.254)
		(layers "F.Cu" "B.Cu")
		(net "GND")
	)
	(via
		(at 114.773456 -349.219774)
		(size 0.4572)
		(drill 0.254)
		(layers "F.Cu" "B.Cu")
		(net "GND")
	)
	(via
		(at 374.099328 -355.366066)
		(size 0.4572)
		(drill 0.254)
		(layers "F.Cu" "B.Cu")
		(net "GND")
	)
	(via
		(at 32.8295 -357.123746)
		(size 0.4572)
		(drill 0.254)
		(layers "F.Cu" "B.Cu")
		(net "GND")
	)
	(via
		(at 299.924724 -307.774848)
		(size 0.4064)
		(drill 0.2032)
		(layers "F.Cu" "B.Cu")
		(net "GND")
	)
	(via
		(at 145.945352 -50.516282)
		(size 0.508)
		(drill 0.254)
		(layers "F.Cu" "B.Cu")
		(net "GND")
	)
	(via
		(at 398.4498 -279.749758)
		(size 0.4064)
		(drill 0.2032)
		(layers "F.Cu" "B.Cu")
		(net "GND")
	)
	(via
		(at 304.527712 -401.040092)
		(size 0.508)
		(drill 0.254)
		(layers "F.Cu" "B.Cu")
		(net "GND")
	)
	(via
		(at 269.333726 -102.716584)
		(size 0.508)
		(drill 0.254)
		(layers "F.Cu" "B.Cu")
		(net "GND")
	)
	(via
		(at 455.645266 -374.129808)
		(size 0.508)
		(drill 0.254)
		(layers "F.Cu" "B.Cu")
		(net "GND")
	)
	(via
		(at 153.233628 -136.901936)
		(size 0.508)
		(drill 0.254)
		(layers "F.Cu" "B.Cu")
		(net "GND")
	)
	(via
		(at 214.039196 -31.652972)
		(size 0.508)
		(drill 0.254)
		(layers "F.Cu" "B.Cu")
		(net "GND")
	)
	(via
		(at 74.84999 -307.299868)
		(size 0.4064)
		(drill 0.2032)
		(layers "F.Cu" "B.Cu")
		(net "GND")
	)
	(via
		(at 389.424926 -273.574764)
		(size 0.4064)
		(drill 0.2032)
		(layers "F.Cu" "B.Cu")
		(net "GND")
	)
	(via
		(at 189.96914 -349.219774)
		(size 0.4572)
		(drill 0.254)
		(layers "F.Cu" "B.Cu")
		(net "GND")
	)
	(via
		(at 155.325064 -281.174952)
		(size 0.4064)
		(drill 0.2032)
		(layers "F.Cu" "B.Cu")
		(net "GND")
	)
	(via
		(at 394.64996 -274.999958)
		(size 0.4064)
		(drill 0.2032)
		(layers "F.Cu" "B.Cu")
		(net "GND")
	)
	(via
		(at 43.974766 -291.624766)
		(size 0.4064)
		(drill 0.2032)
		(layers "F.Cu" "B.Cu")
		(net "GND")
	)
	(via
		(at 112.446816 -135.58266)
		(size 0.508)
		(drill 0.254)
		(layers "F.Cu" "B.Cu")
		(net "GND")
	)
	(via
		(at 67.249802 -274.999958)
		(size 0.4064)
		(drill 0.2032)
		(layers "F.Cu" "B.Cu")
		(net "GND")
	)
	(via
		(at 169.099992 -281.649932)
		(size 0.4064)
		(drill 0.2032)
		(layers "F.Cu" "B.Cu")
		(net "GND")
	)
	(via
		(at 73.61047 -344.831162)
		(size 0.4572)
		(drill 0.254)
		(layers "F.Cu" "B.Cu")
		(net "GND")
	)
	(via
		(at 69.149976 -280.699718)
		(size 0.4064)
		(drill 0.2032)
		(layers "F.Cu" "B.Cu")
		(net "GND")
	)
	(via
		(at 159.347916 -377.738386)
		(size 0.508)
		(drill 0.254)
		(layers "F.Cu" "B.Cu")
		(net "GND")
	)
	(via
		(at 43.974766 -298.27474)
		(size 0.4064)
		(drill 0.2032)
		(layers "F.Cu" "B.Cu")
		(net "GND")
	)
	(via
		(at 87.194898 -60.633356)
		(size 0.508)
		(drill 0.254)
		(layers "F.Cu" "B.Cu")
		(net "GND")
	)
	(via
		(at 51.63312 -133.565138)
		(size 0.508)
		(drill 0.254)
		(layers "F.Cu" "B.Cu")
		(net "GND")
	)
	(via
		(at 333.618586 -274.726146)
		(size 0.508)
		(drill 0.254)
		(layers "F.Cu" "B.Cu")
		(net "GND")
	)
	(via
		(at 116.03228 -358.391714)
		(size 0.4572)
		(drill 0.254)
		(layers "F.Cu" "B.Cu")
		(net "GND")
	)
	(via
		(at 131.399026 -133.173216)
		(size 0.508)
		(drill 0.254)
		(layers "F.Cu" "B.Cu")
		(net "GND")
	)
	(via
		(at 310.849772 -315.849762)
		(size 0.4064)
		(drill 0.2032)
		(layers "F.Cu" "B.Cu")
		(net "GND")
	)
	(via
		(at 68.280788 -27.79014)
		(size 0.508)
		(drill 0.254)
		(layers "F.Cu" "B.Cu")
		(net "GND")
	)
	(via
		(at 4.562856 -134.441692)
		(size 0.508)
		(drill 0.254)
		(layers "F.Cu" "B.Cu")
		(net "GND")
	)
	(via
		(at 224.766124 -280.10104)
		(size 0.508)
		(drill 0.254)
		(layers "F.Cu" "B.Cu")
		(net "GND")
	)
	(via
		(at 463.037682 -225.057462)
		(size 0.508)
		(drill 0.254)
		(layers "F.Cu" "B.Cu")
		(net "GND")
	)
	(via
		(at 405.100028 -317.749936)
		(size 0.4064)
		(drill 0.2032)
		(layers "F.Cu" "B.Cu")
		(net "GND")
	)
	(via
		(at 182.39994 -277.849838)
		(size 0.4064)
		(drill 0.2032)
		(layers "F.Cu" "B.Cu")
		(net "GND")
	)
	(via
		(at 154.501596 -136.901936)
		(size 0.508)
		(drill 0.254)
		(layers "F.Cu" "B.Cu")
		(net "GND")
	)
	(via
		(at 442.85789 -58.156094)
		(size 0.508)
		(drill 0.254)
		(layers "F.Cu" "B.Cu")
		(net "GND")
	)
	(via
		(at 361.1118 -31.2166)
		(size 0.508)
		(drill 0.254)
		(layers "F.Cu" "B.Cu")
		(net "GND")
	)
	(via
		(at 164.824918 -309.674768)
		(size 0.4064)
		(drill 0.2032)
		(layers "F.Cu" "B.Cu")
		(net "GND")
	)
	(via
		(at 174.42434 -343.073482)
		(size 0.4572)
		(drill 0.254)
		(layers "F.Cu" "B.Cu")
		(net "GND")
	)
	(via
		(at 341.927942 -403.34184)
		(size 0.508)
		(drill 0.254)
		(layers "F.Cu" "B.Cu")
		(net "GND")
	)
	(via
		(at 298.78909 -355.366066)
		(size 0.4572)
		(drill 0.254)
		(layers "F.Cu" "B.Cu")
		(net "GND")
	)
	(via
		(at 86.747858 -372.240302)
		(size 0.508)
		(drill 0.254)
		(layers "F.Cu" "B.Cu")
		(net "GND")
	)
	(via
		(at 288.049716 -311.099962)
		(size 0.4064)
		(drill 0.2032)
		(layers "F.Cu" "B.Cu")
		(net "GND")
	)
	(via
		(at 402.079968 -357.123746)
		(size 0.4572)
		(drill 0.254)
		(layers "F.Cu" "B.Cu")
		(net "GND")
	)
	(via
		(at 174.16653 -35.871912)
		(size 0.508)
		(drill 0.254)
		(layers "F.Cu" "B.Cu")
		(net "GND")
	)
	(via
		(at 300.12767 -399.838418)
		(size 0.508)
		(drill 0.254)
		(layers "F.Cu" "B.Cu")
		(net "GND")
	)
	(via
		(at 134.241286 -38.49116)
		(size 0.508)
		(drill 0.254)
		(layers "F.Cu" "B.Cu")
		(net "GND")
	)
	(via
		(at 289.127692 -383.940304)
		(size 0.508)
		(drill 0.254)
		(layers "F.Cu" "B.Cu")
		(net "GND")
	)
	(via
		(at 287.983422 -357.75773)
		(size 0.4064)
		(drill 0.2032)
		(layers "F.Cu" "B.Cu")
		(net "GND")
	)
	(via
		(at 230.991918 -82.118708)
		(size 0.508)
		(drill 0.254)
		(layers "F.Cu" "B.Cu")
		(net "GND")
	)
	(via
		(at 168.20642 -355.366066)
		(size 0.4572)
		(drill 0.254)
		(layers "F.Cu" "B.Cu")
		(net "GND")
	)
	(via
		(at 344.127836 -406.141936)
		(size 0.508)
		(drill 0.254)
		(layers "F.Cu" "B.Cu")
		(net "GND")
	)
	(via
		(at 283.833062 -125.955044)
		(size 0.508)
		(drill 0.254)
		(layers "F.Cu" "B.Cu")
		(net "GND")
	)
	(via
		(at 80.147922 -382.84023)
		(size 0.508)
		(drill 0.254)
		(layers "F.Cu" "B.Cu")
		(net "GND")
	)
	(via
		(at 306.099718 -283.549852)
		(size 0.4064)
		(drill 0.2032)
		(layers "F.Cu" "B.Cu")
		(net "GND")
	)
	(via
		(at 249.104404 -276.519386)
		(size 0.508)
		(drill 0.254)
		(layers "F.Cu" "B.Cu")
		(net "GND")
	)
	(via
		(at 126.347728 -383.940304)
		(size 0.4572)
		(drill 0.254)
		(layers "F.Cu" "B.Cu")
		(net "GND")
	)
	(via
		(at 169.587164 -111.44504)
		(size 0.508)
		(drill 0.254)
		(layers "F.Cu" "B.Cu")
		(net "GND")
	)
	(via
		(at 411.835092 -348.58579)
		(size 0.4064)
		(drill 0.2032)
		(layers "F.Cu" "B.Cu")
		(net "GND")
	)
	(via
		(at 349.410782 -288.78149)
		(size 0.508)
		(drill 0.254)
		(layers "F.Cu" "B.Cu")
		(net "GND")
	)
	(via
		(at 46.34992 -319.65011)
		(size 0.4064)
		(drill 0.2032)
		(layers "F.Cu" "B.Cu")
		(net "GND")
	)
	(via
		(at 418.399976 -310.149748)
		(size 0.4064)
		(drill 0.2032)
		(layers "F.Cu" "B.Cu")
		(net "GND")
	)
	(via
		(at 216.182194 -166.78529)
		(size 0.508)
		(drill 0.254)
		(layers "F.Cu" "B.Cu")
		(net "GND")
	)
	(via
		(at 233.47045 -28.802076)
		(size 0.508)
		(drill 0.254)
		(layers "F.Cu" "B.Cu")
		(net "GND")
	)
	(via
		(at 201.29246 -11.372342)
		(size 0.508)
		(drill 0.254)
		(layers "F.Cu" "B.Cu")
		(net "GND")
	)
	(via
		(at 57.749948 -279.749758)
		(size 0.4064)
		(drill 0.2032)
		(layers "F.Cu" "B.Cu")
		(net "GND")
	)
	(via
		(at 18.601944 -131.942332)
		(size 0.508)
		(drill 0.254)
		(layers "F.Cu" "B.Cu")
		(net "GND")
	)
	(via
		(at 136.536176 -346.09913)
		(size 0.4572)
		(drill 0.254)
		(layers "F.Cu" "B.Cu")
		(net "GND")
	)
	(via
		(at 250.419362 -147.18665)
		(size 0.508)
		(drill 0.254)
		(layers "F.Cu" "B.Cu")
		(net "GND")
	)
	(via
		(at 377.12777 -378.83846)
		(size 0.508)
		(drill 0.254)
		(layers "F.Cu" "B.Cu")
		(net "GND")
	)
	(via
		(at 413.174942 -305.874928)
		(size 0.4064)
		(drill 0.2032)
		(layers "F.Cu" "B.Cu")
		(net "GND")
	)
	(via
		(at 197.945248 -50.516282)
		(size 0.508)
		(drill 0.254)
		(layers "F.Cu" "B.Cu")
		(net "GND")
	)
	(via
		(at 218.679268 -289.391344)
		(size 0.508)
		(drill 0.254)
		(layers "F.Cu" "B.Cu")
		(net "GND")
	)
	(via
		(at 414.11271 -123.635008)
		(size 0.508)
		(drill 0.254)
		(layers "F.Cu" "B.Cu")
		(net "GND")
	)
	(via
		(at 326.371204 -348.58579)
		(size 0.4064)
		(drill 0.2032)
		(layers "F.Cu" "B.Cu")
		(net "GND")
	)
	(via
		(at 108.89996 -135.55726)
		(size 0.508)
		(drill 0.254)
		(layers "F.Cu" "B.Cu")
		(net "GND")
	)
	(via
		(at 69.149976 -274.999958)
		(size 0.4064)
		(drill 0.2032)
		(layers "F.Cu" "B.Cu")
		(net "GND")
	)
	(via
		(at 227.301298 -311.711086)
		(size 0.508)
		(drill 0.254)
		(layers "F.Cu" "B.Cu")
		(net "GND")
	)
	(via
		(at 310.374792 -303.024794)
		(size 0.4064)
		(drill 0.2032)
		(layers "F.Cu" "B.Cu")
		(net "GND")
	)
	(via
		(at 269.999714 -300.649894)
		(size 0.4064)
		(drill 0.2032)
		(layers "F.Cu" "B.Cu")
		(net "GND")
	)
	(via
		(at 280.924762 -306.824888)
		(size 0.4064)
		(drill 0.2032)
		(layers "F.Cu" "B.Cu")
		(net "GND")
	)
	(via
		(at 113.976404 -165.935152)
		(size 0.508)
		(drill 0.254)
		(layers "F.Cu" "B.Cu")
		(net "GND")
	)
	(via
		(at 390.849866 -319.65011)
		(size 0.4064)
		(drill 0.2032)
		(layers "F.Cu" "B.Cu")
		(net "GND")
	)
	(via
		(at 227.734368 -94.073726)
		(size 0.508)
		(drill 0.254)
		(layers "F.Cu" "B.Cu")
		(net "GND")
	)
	(via
		(at 19.134836 -344.831162)
		(size 0.4572)
		(drill 0.254)
		(layers "F.Cu" "B.Cu")
		(net "GND")
	)
	(via
		(at 87.305134 -358.391714)
		(size 0.4572)
		(drill 0.254)
		(layers "F.Cu" "B.Cu")
		(net "GND")
	)
	(via
		(at 111.710216 -136.317228)
		(size 0.508)
		(drill 0.254)
		(layers "F.Cu" "B.Cu")
		(net "GND")
	)
	(via
		(at 28.461716 -354.098098)
		(size 0.4572)
		(drill 0.254)
		(layers "F.Cu" "B.Cu")
		(net "GND")
	)
	(via
		(at 249.054366 -223.290638)
		(size 0.508)
		(drill 0.254)
		(layers "F.Cu" "B.Cu")
		(net "GND")
	)
	(via
		(at 414.74771 -151.155146)
		(size 0.508)
		(drill 0.254)
		(layers "F.Cu" "B.Cu")
		(net "GND")
	)
	(via
		(at 111.311182 -290.05149)
		(size 0.508)
		(drill 0.254)
		(layers "F.Cu" "B.Cu")
		(net "GND")
	)
	(via
		(at 190.348108 -116.435124)
		(size 0.508)
		(drill 0.254)
		(layers "F.Cu" "B.Cu")
		(net "GND")
	)
	(via
		(at 388.16534 -351.611438)
		(size 0.4064)
		(drill 0.2032)
		(layers "F.Cu" "B.Cu")
		(net "GND")
	)
	(via
		(at 411.750002 -312.049922)
		(size 0.4064)
		(drill 0.2032)
		(layers "F.Cu" "B.Cu")
		(net "GND")
	)
	(via
		(at 78.64983 -311.099962)
		(size 0.4064)
		(drill 0.2032)
		(layers "F.Cu" "B.Cu")
		(net "GND")
	)
	(via
		(at 293.527734 -378.83846)
		(size 0.508)
		(drill 0.254)
		(layers "F.Cu" "B.Cu")
		(net "GND")
	)
	(via
		(at 346.327984 -398.24025)
		(size 0.508)
		(drill 0.254)
		(layers "F.Cu" "B.Cu")
		(net "GND")
	)
	(via
		(at 169.370502 -28.802076)
		(size 0.508)
		(drill 0.254)
		(layers "F.Cu" "B.Cu")
		(net "GND")
	)
	(via
		(at 81.402682 -89.790524)
		(size 0.508)
		(drill 0.254)
		(layers "F.Cu" "B.Cu")
		(net "GND")
	)
	(via
		(at 452.254112 -103.69296)
		(size 0.508)
		(drill 0.254)
		(layers "F.Cu" "B.Cu")
		(net "GND")
	)
	(via
		(at 78.551532 -98.021648)
		(size 0.508)
		(drill 0.254)
		(layers "F.Cu" "B.Cu")
		(net "GND")
	)
	(via
		(at 378.467112 -346.09913)
		(size 0.4572)
		(drill 0.254)
		(layers "F.Cu" "B.Cu")
		(net "GND")
	)
	(via
		(at 180.64226 -355.366066)
		(size 0.4572)
		(drill 0.254)
		(layers "F.Cu" "B.Cu")
		(net "GND")
	)
	(via
		(at 433.96916 -358.391714)
		(size 0.4572)
		(drill 0.254)
		(layers "F.Cu" "B.Cu")
		(net "GND")
	)
	(via
		(at 452.086472 -367.453672)
		(size 0.508)
		(drill 0.254)
		(layers "F.Cu" "B.Cu")
		(net "GND")
	)
	(via
		(at 462.337912 -283.105606)
		(size 0.508)
		(drill 0.254)
		(layers "F.Cu" "B.Cu")
		(net "GND")
	)
	(via
		(at 439.242708 -112.399572)
		(size 0.508)
		(drill 0.254)
		(layers "F.Cu" "B.Cu")
		(net "GND")
	)
	(via
		(at 304.527712 -372.342156)
		(size 0.508)
		(drill 0.254)
		(layers "F.Cu" "B.Cu")
		(net "GND")
	)
	(via
		(at 111.311182 -291.32149)
		(size 0.508)
		(drill 0.254)
		(layers "F.Cu" "B.Cu")
		(net "GND")
	)
	(via
		(at 66.774822 -287.824926)
		(size 0.4064)
		(drill 0.2032)
		(layers "F.Cu" "B.Cu")
		(net "GND")
	)
	(via
		(at 426.851572 -103.104696)
		(size 0.508)
		(drill 0.254)
		(layers "F.Cu" "B.Cu")
		(net "GND")
	)
	(via
		(at 137.806684 -199.367394)
		(size 0.508)
		(drill 0.254)
		(layers "F.Cu" "B.Cu")
		(net "GND")
	)
	(via
		(at 385.433824 -135.643112)
		(size 0.508)
		(drill 0.254)
		(layers "F.Cu" "B.Cu")
		(net "GND")
	)
	(via
		(at 394.64996 -280.699718)
		(size 0.4064)
		(drill 0.2032)
		(layers "F.Cu" "B.Cu")
		(net "GND")
	)
	(via
		(at 256.175002 -74.58583)
		(size 0.508)
		(drill 0.254)
		(layers "F.Cu" "B.Cu")
		(net "GND")
	)
	(via
		(at 310.849772 -311.099962)
		(size 0.4064)
		(drill 0.2032)
		(layers "F.Cu" "B.Cu")
		(net "GND")
	)
	(via
		(at 353.531424 -292.789102)
		(size 0.508)
		(drill 0.254)
		(layers "F.Cu" "B.Cu")
		(net "GND")
	)
	(via
		(at 260.62686 -195.819522)
		(size 0.508)
		(drill 0.254)
		(layers "F.Cu" "B.Cu")
		(net "GND")
	)
	(via
		(at 363.737906 -74.624184)
		(size 0.508)
		(drill 0.254)
		(layers "F.Cu" "B.Cu")
		(net "GND")
	)
	(via
		(at 229.224586 -134.81177)
		(size 0.508)
		(drill 0.254)
		(layers "F.Cu" "B.Cu")
		(net "GND")
	)
	(via
		(at 120.941592 -268.731492)
		(size 0.508)
		(drill 0.254)
		(layers "F.Cu" "B.Cu")
		(net "GND")
	)
	(via
		(at 427.75124 -349.219774)
		(size 0.4572)
		(drill 0.254)
		(layers "F.Cu" "B.Cu")
		(net "GND")
	)
	(via
		(at 417.449762 -272.14957)
		(size 0.4064)
		(drill 0.2032)
		(layers "F.Cu" "B.Cu")
		(net "GND")
	)
	(via
		(at 161.975038 -285.924752)
		(size 0.4064)
		(drill 0.2032)
		(layers "F.Cu" "B.Cu")
		(net "GND")
	)
	(via
		(at 43.024806 -286.874712)
		(size 0.4064)
		(drill 0.2032)
		(layers "F.Cu" "B.Cu")
		(net "GND")
	)
	(via
		(at 284.249622 -272.14957)
		(size 0.4064)
		(drill 0.2032)
		(layers "F.Cu" "B.Cu")
		(net "GND")
	)
	(via
		(at 136.164828 -348.58579)
		(size 0.4064)
		(drill 0.2032)
		(layers "F.Cu" "B.Cu")
		(net "GND")
	)
	(via
		(at 450.686424 -48.874934)
		(size 0.508)
		(drill 0.254)
		(layers "F.Cu" "B.Cu")
		(net "GND")
	)
	(via
		(at 160.074864 -294.4749)
		(size 0.4064)
		(drill 0.2032)
		(layers "F.Cu" "B.Cu")
		(net "GND")
	)
	(via
		(at 435.599332 -348.58579)
		(size 0.4064)
		(drill 0.2032)
		(layers "F.Cu" "B.Cu")
		(net "GND")
	)
	(via
		(at 86.454996 -31.390082)
		(size 0.508)
		(drill 0.254)
		(layers "F.Cu" "B.Cu")
		(net "GND")
	)
	(via
		(at 190.949834 -279.749758)
		(size 0.4064)
		(drill 0.2032)
		(layers "F.Cu" "B.Cu")
		(net "GND")
	)
	(via
		(at 21.508466 -258.665472)
		(size 0.508)
		(drill 0.254)
		(layers "F.Cu" "B.Cu")
		(net "GND")
	)
	(via
		(at 232.323894 -287.683448)
		(size 0.508)
		(drill 0.254)
		(layers "F.Cu" "B.Cu")
		(net "GND")
	)
	(via
		(at 292.32479 -289.724846)
		(size 0.4064)
		(drill 0.2032)
		(layers "F.Cu" "B.Cu")
		(net "GND")
	)
	(via
		(at 79.82839 -341.805514)
		(size 0.4572)
		(drill 0.254)
		(layers "F.Cu" "B.Cu")
		(net "GND")
	)
	(via
		(at 163.874958 -303.974754)
		(size 0.4064)
		(drill 0.2032)
		(layers "F.Cu" "B.Cu")
		(net "GND")
	)
	(via
		(at 48.745648 -348.58579)
		(size 0.4064)
		(drill 0.2032)
		(layers "F.Cu" "B.Cu")
		(net "GND")
	)
	(via
		(at 313.09818 -149.617938)
		(size 0.508)
		(drill 0.254)
		(layers "F.Cu" "B.Cu")
		(net "GND")
	)
	(via
		(at 107.881674 -129.781808)
		(size 0.508)
		(drill 0.254)
		(layers "F.Cu" "B.Cu")
		(net "GND")
	)
	(via
		(at 421.53332 -354.098098)
		(size 0.4572)
		(drill 0.254)
		(layers "F.Cu" "B.Cu")
		(net "GND")
	)
	(via
		(at 199.009762 -303.024794)
		(size 0.4064)
		(drill 0.2032)
		(layers "F.Cu" "B.Cu")
		(net "GND")
	)
	(via
		(at 267.959586 -104.523286)
		(size 0.508)
		(drill 0.254)
		(layers "F.Cu" "B.Cu")
		(net "GND")
	)
	(via
		(at 119.25173 -256.870962)
		(size 0.508)
		(drill 0.254)
		(layers "F.Cu" "B.Cu")
		(net "GND")
	)
	(via
		(at 408.755088 -33.19018)
		(size 0.508)
		(drill 0.254)
		(layers "F.Cu" "B.Cu")
		(net "GND")
	)
	(via
		(at 327.478644 -348.58579)
		(size 0.4064)
		(drill 0.2032)
		(layers "F.Cu" "B.Cu")
		(net "GND")
	)
	(via
		(at 177.5333 -354.098098)
		(size 0.4572)
		(drill 0.254)
		(layers "F.Cu" "B.Cu")
		(net "GND")
	)
	(via
		(at 388.54888 -29.589984)
		(size 0.508)
		(drill 0.254)
		(layers "F.Cu" "B.Cu")
		(net "GND")
	)
	(via
		(at 159.599884 -314.899802)
		(size 0.4064)
		(drill 0.2032)
		(layers "F.Cu" "B.Cu")
		(net "GND")
	)
	(via
		(at 255.346454 -255.66624)
		(size 0.508)
		(drill 0.254)
		(layers "F.Cu" "B.Cu")
		(net "GND")
	)
	(via
		(at 123.506484 -204.342238)
		(size 0.508)
		(drill 0.254)
		(layers "F.Cu" "B.Cu")
		(net "GND")
	)
	(via
		(at 231.15016 -89.797128)
		(size 0.508)
		(drill 0.254)
		(layers "F.Cu" "B.Cu")
		(net "GND")
	)
	(via
		(at 421.161972 -342.439498)
		(size 0.4064)
		(drill 0.2032)
		(layers "F.Cu" "B.Cu")
		(net "GND")
	)
	(via
		(at 73.31329 -34.718498)
		(size 0.508)
		(drill 0.254)
		(layers "F.Cu" "B.Cu")
		(net "GND")
	)
	(via
		(at 141.369796 -175.002698)
		(size 0.508)
		(drill 0.254)
		(layers "F.Cu" "B.Cu")
		(net "GND")
	)
	(via
		(at 295.727882 -398.34185)
		(size 0.508)
		(drill 0.254)
		(layers "F.Cu" "B.Cu")
		(net "GND")
	)
	(via
		(at 3.200654 -23.39594)
		(size 0.508)
		(drill 0.254)
		(layers "F.Cu" "B.Cu")
		(net "GND")
	)
	(via
		(at 90.785442 -351.611438)
		(size 0.4064)
		(drill 0.2032)
		(layers "F.Cu" "B.Cu")
		(net "GND")
	)
	(via
		(at 60.803282 -345.465146)
		(size 0.4064)
		(drill 0.2032)
		(layers "F.Cu" "B.Cu")
		(net "GND")
	)
	(via
		(at 438.708292 -342.439498)
		(size 0.4064)
		(drill 0.2032)
		(layers "F.Cu" "B.Cu")
		(net "GND")
	)
	(via
		(at 63.744856 -29.589984)
		(size 0.508)
		(drill 0.254)
		(layers "F.Cu" "B.Cu")
		(net "GND")
	)
	(via
		(at 245.458996 -290.872926)
		(size 0.508)
		(drill 0.254)
		(layers "F.Cu" "B.Cu")
		(net "GND")
	)
	(via
		(at 402.724874 -303.974754)
		(size 0.4064)
		(drill 0.2032)
		(layers "F.Cu" "B.Cu")
		(net "GND")
	)
	(via
		(at 81.087214 -341.805514)
		(size 0.4572)
		(drill 0.254)
		(layers "F.Cu" "B.Cu")
		(net "GND")
	)
	(via
		(at 317.392558 -6.292342)
		(size 0.508)
		(drill 0.254)
		(layers "F.Cu" "B.Cu")
		(net "GND")
	)
	(via
		(at 44.94784 -402.241766)
		(size 0.508)
		(drill 0.254)
		(layers "F.Cu" "B.Cu")
		(net "GND")
	)
	(via
		(at 282.872942 -342.439498)
		(size 0.4064)
		(drill 0.2032)
		(layers "F.Cu" "B.Cu")
		(net "GND")
	)
	(via
		(at 237.1598 -225.427032)
		(size 0.508)
		(drill 0.254)
		(layers "F.Cu" "B.Cu")
		(net "GND")
	)
	(via
		(at 107.225846 -218.095576)
		(size 0.508)
		(drill 0.254)
		(layers "F.Cu" "B.Cu")
		(net "GND")
	)
	(via
		(at 196.998082 -133.30809)
		(size 0.508)
		(drill 0.254)
		(layers "F.Cu" "B.Cu")
		(net "GND")
	)
	(via
		(at 212.669882 -25.832054)
		(size 0.508)
		(drill 0.254)
		(layers "F.Cu" "B.Cu")
		(net "GND")
	)
	(via
		(at 49.853088 -348.58579)
		(size 0.4064)
		(drill 0.2032)
		(layers "F.Cu" "B.Cu")
		(net "GND")
	)
	(via
		(at 301.824898 -284.024832)
		(size 0.4064)
		(drill 0.2032)
		(layers "F.Cu" "B.Cu")
		(net "GND")
	)
	(via
		(at 315.414152 -344.831162)
		(size 0.4572)
		(drill 0.254)
		(layers "F.Cu" "B.Cu")
		(net "GND")
	)
	(via
		(at 339.728048 -401.040092)
		(size 0.508)
		(drill 0.254)
		(layers "F.Cu" "B.Cu")
		(net "GND")
	)
	(via
		(at 43.974766 -289.724846)
		(size 0.4064)
		(drill 0.2032)
		(layers "F.Cu" "B.Cu")
		(net "GND")
	)
	(via
		(at 47.77486 -303.024794)
		(size 0.4064)
		(drill 0.2032)
		(layers "F.Cu" "B.Cu")
		(net "GND")
	)
	(via
		(at 333.696564 -357.75773)
		(size 0.4064)
		(drill 0.2032)
		(layers "F.Cu" "B.Cu")
		(net "GND")
	)
	(via
		(at 323.14261 -111.688372)
		(size 0.508)
		(drill 0.254)
		(layers "F.Cu" "B.Cu")
		(net "GND")
	)
	(via
		(at 67.39255 -349.219774)
		(size 0.4572)
		(drill 0.254)
		(layers "F.Cu" "B.Cu")
		(net "GND")
	)
	(via
		(at 14.981174 -280.6954)
		(size 0.508)
		(drill 0.254)
		(layers "F.Cu" "B.Cu")
		(net "GND")
	)
	(via
		(at 117.249702 -326.841104)
		(size 0.508)
		(drill 0.254)
		(layers "F.Cu" "B.Cu")
		(net "GND")
	)
	(via
		(at 272.374868 -289.724846)
		(size 0.4064)
		(drill 0.2032)
		(layers "F.Cu" "B.Cu")
		(net "GND")
	)
	(via
		(at 73.547732 -398.24025)
		(size 0.508)
		(drill 0.254)
		(layers "F.Cu" "B.Cu")
		(net "GND")
	)
	(via
		(at 83.540346 -125.163326)
		(size 0.508)
		(drill 0.254)
		(layers "F.Cu" "B.Cu")
		(net "GND")
	)
	(via
		(at 445.008 -417.82492)
		(size 0.508)
		(drill 0.254)
		(layers "F.Cu" "B.Cu")
		(net "GND")
	)
	(via
		(at 195.699888 -317.749936)
		(size 0.4064)
		(drill 0.2032)
		(layers "F.Cu" "B.Cu")
		(net "GND")
	)
	(via
		(at 152.94991 -307.299868)
		(size 0.4064)
		(drill 0.2032)
		(layers "F.Cu" "B.Cu")
		(net "GND")
	)
	(via
		(at 448.776598 -115.021614)
		(size 0.508)
		(drill 0.254)
		(layers "F.Cu" "B.Cu")
		(net "GND")
	)
	(via
		(at 76.71943 -341.805514)
		(size 0.4572)
		(drill 0.254)
		(layers "F.Cu" "B.Cu")
		(net "GND")
	)
	(via
		(at 59.820048 -33.19018)
		(size 0.508)
		(drill 0.254)
		(layers "F.Cu" "B.Cu")
		(net "GND")
	)
	(via
		(at 291.32784 -408.840178)
		(size 0.508)
		(drill 0.254)
		(layers "F.Cu" "B.Cu")
		(net "GND")
	)
	(via
		(at 198.943214 -52.536852)
		(size 0.508)
		(drill 0.254)
		(layers "F.Cu" "B.Cu")
		(net "GND")
	)
	(via
		(at 133.460744 -131.964176)
		(size 0.508)
		(drill 0.254)
		(layers "F.Cu" "B.Cu")
		(net "GND")
	)
	(via
		(at 77.69987 -308.249828)
		(size 0.4064)
		(drill 0.2032)
		(layers "F.Cu" "B.Cu")
		(net "GND")
	)
	(via
		(at 295.944798 -27.79014)
		(size 0.508)
		(drill 0.254)
		(layers "F.Cu" "B.Cu")
		(net "GND")
	)
	(via
		(at 430.172114 -33.857692)
		(size 0.508)
		(drill 0.254)
		(layers "F.Cu" "B.Cu")
		(net "GND")
	)
	(via
		(at 390.327896 -381.241808)
		(size 0.508)
		(drill 0.254)
		(layers "F.Cu" "B.Cu")
		(net "GND")
	)
	(via
		(at 135.598662 -65.15989)
		(size 0.508)
		(drill 0.254)
		(layers "F.Cu" "B.Cu")
		(net "GND")
	)
	(via
		(at 370.398548 -37.201094)
		(size 0.508)
		(drill 0.254)
		(layers "F.Cu" "B.Cu")
		(net "GND")
	)
	(via
		(at 232.118662 -142.617698)
		(size 0.508)
		(drill 0.254)
		(layers "F.Cu" "B.Cu")
		(net "GND")
	)
	(via
		(at 364.47095 -305.972718)
		(size 0.508)
		(drill 0.254)
		(layers "F.Cu" "B.Cu")
		(net "GND")
	)
	(via
		(at 377.45162 -256.375916)
		(size 0.508)
		(drill 0.254)
		(layers "F.Cu" "B.Cu")
		(net "GND")
	)
	(via
		(at 397.729456 -47.020734)
		(size 0.508)
		(drill 0.254)
		(layers "F.Cu" "B.Cu")
		(net "GND")
	)
	(via
		(at 306.099464 -276.899878)
		(size 0.4064)
		(drill 0.2032)
		(layers "F.Cu" "B.Cu")
		(net "GND")
	)
	(via
		(at 51.854608 -354.732082)
		(size 0.4064)
		(drill 0.2032)
		(layers "F.Cu" "B.Cu")
		(net "GND")
	)
	(via
		(at 180.64226 -352.245422)
		(size 0.4572)
		(drill 0.254)
		(layers "F.Cu" "B.Cu")
		(net "GND")
	)
	(via
		(at 43.499786 -307.299868)
		(size 0.4064)
		(drill 0.2032)
		(layers "F.Cu" "B.Cu")
		(net "GND")
	)
	(via
		(at 419.349936 -310.149748)
		(size 0.4064)
		(drill 0.2032)
		(layers "F.Cu" "B.Cu")
		(net "GND")
	)
	(via
		(at 430.8602 -357.123746)
		(size 0.4572)
		(drill 0.254)
		(layers "F.Cu" "B.Cu")
		(net "GND")
	)
	(via
		(at 89.798144 -20.417536)
		(size 0.508)
		(drill 0.254)
		(layers "F.Cu" "B.Cu")
		(net "GND")
	)
	(via
		(at 80.54975 -308.249828)
		(size 0.4064)
		(drill 0.2032)
		(layers "F.Cu" "B.Cu")
		(net "GND")
	)
	(via
		(at 91.892882 -357.75773)
		(size 0.4064)
		(drill 0.2032)
		(layers "F.Cu" "B.Cu")
		(net "GND")
	)
	(via
		(at 296.599864 -277.849838)
		(size 0.4064)
		(drill 0.2032)
		(layers "F.Cu" "B.Cu")
		(net "GND")
	)
	(via
		(at 287.612074 -344.831162)
		(size 0.4572)
		(drill 0.254)
		(layers "F.Cu" "B.Cu")
		(net "GND")
	)
	(via
		(at 423.32783 -384.041904)
		(size 0.508)
		(drill 0.254)
		(layers "F.Cu" "B.Cu")
		(net "GND")
	)
	(via
		(at 160.241234 -38.49116)
		(size 0.508)
		(drill 0.254)
		(layers "F.Cu" "B.Cu")
		(net "GND")
	)
	(via
		(at 287.574736 -297.32478)
		(size 0.4064)
		(drill 0.2032)
		(layers "F.Cu" "B.Cu")
		(net "GND")
	)
	(via
		(at 306.7812 -34.718498)
		(size 0.508)
		(drill 0.254)
		(layers "F.Cu" "B.Cu")
		(net "GND")
	)
	(via
		(at 436.527702 -407.638504)
		(size 0.508)
		(drill 0.254)
		(layers "F.Cu" "B.Cu")
		(net "GND")
	)
	(via
		(at 154.501596 -122.091958)
		(size 0.508)
		(drill 0.254)
		(layers "F.Cu" "B.Cu")
		(net "GND")
	)
	(via
		(at 428.37481 -296.37482)
		(size 0.4064)
		(drill 0.2032)
		(layers "F.Cu" "B.Cu")
		(net "GND")
	)
	(via
		(at 78.349602 -348.58579)
		(size 0.4064)
		(drill 0.2032)
		(layers "F.Cu" "B.Cu")
		(net "GND")
	)
	(via
		(at 435.227984 -350.977454)
		(size 0.4572)
		(drill 0.254)
		(layers "F.Cu" "B.Cu")
		(net "GND")
	)
	(via
		(at 133.275832 -145.501868)
		(size 0.508)
		(drill 0.254)
		(layers "F.Cu" "B.Cu")
		(net "GND")
	)
	(via
		(at 44.94784 -372.342156)
		(size 0.508)
		(drill 0.254)
		(layers "F.Cu" "B.Cu")
		(net "GND")
	)
	(via
		(at 92.80271 -74.624184)
		(size 0.508)
		(drill 0.254)
		(layers "F.Cu" "B.Cu")
		(net "GND")
	)
	(via
		(at 96.67113 -29.311854)
		(size 0.508)
		(drill 0.254)
		(layers "F.Cu" "B.Cu")
		(net "GND")
	)
	(via
		(at 306.448206 -134.845044)
		(size 0.508)
		(drill 0.254)
		(layers "F.Cu" "B.Cu")
		(net "GND")
	)
	(via
		(at 241.82578 -347.400118)
		(size 0.508)
		(drill 0.254)
		(layers "F.Cu" "B.Cu")
		(net "GND")
	)
	(via
		(at 72.179942 -111.750602)
		(size 0.508)
		(drill 0.254)
		(layers "F.Cu" "B.Cu")
		(net "GND")
	)
	(via
		(at 384.674872 -290.674806)
		(size 0.4064)
		(drill 0.2032)
		(layers "F.Cu" "B.Cu")
		(net "GND")
	)
	(via
		(at 183.766714 -134.845044)
		(size 0.508)
		(drill 0.254)
		(layers "F.Cu" "B.Cu")
		(net "GND")
	)
	(via
		(at 287.099756 -273.099784)
		(size 0.4064)
		(drill 0.2032)
		(layers "F.Cu" "B.Cu")
		(net "GND")
	)
	(via
		(at 368.63782 -83.207352)
		(size 0.508)
		(drill 0.254)
		(layers "F.Cu" "B.Cu")
		(net "GND")
	)
	(via
		(at 36.374832 -280.224738)
		(size 0.4064)
		(drill 0.2032)
		(layers "F.Cu" "B.Cu")
		(net "GND")
	)
	(via
		(at 401.78736 -111.44504)
		(size 0.508)
		(drill 0.254)
		(layers "F.Cu" "B.Cu")
		(net "GND")
	)
	(via
		(at 159.347916 -399.838418)
		(size 0.508)
		(drill 0.254)
		(layers "F.Cu" "B.Cu")
		(net "GND")
	)
	(via
		(at 237.782354 -37.087048)
		(size 0.508)
		(drill 0.254)
		(layers "F.Cu" "B.Cu")
		(net "GND")
	)
	(via
		(at 375.969022 -292.732714)
		(size 0.508)
		(drill 0.254)
		(layers "F.Cu" "B.Cu")
		(net "GND")
	)
	(via
		(at 42.28084 -25.990042)
		(size 0.508)
		(drill 0.254)
		(layers "F.Cu" "B.Cu")
		(net "GND")
	)
	(via
		(at 382.30302 -296.695114)
		(size 0.508)
		(drill 0.254)
		(layers "F.Cu" "B.Cu")
		(net "GND")
	)
	(via
		(at 354.202238 -27.729688)
		(size 0.508)
		(drill 0.254)
		(layers "F.Cu" "B.Cu")
		(net "GND")
	)
	(via
		(at 284.503114 -350.977454)
		(size 0.4572)
		(drill 0.254)
		(layers "F.Cu" "B.Cu")
		(net "GND")
	)
	(via
		(at 302.327818 -399.441924)
		(size 0.508)
		(drill 0.254)
		(layers "F.Cu" "B.Cu")
		(net "GND")
	)
	(via
		(at 305.149758 -275.949918)
		(size 0.4064)
		(drill 0.2032)
		(layers "F.Cu" "B.Cu")
		(net "GND")
	)
	(via
		(at 69.624956 -284.024832)
		(size 0.4064)
		(drill 0.2032)
		(layers "F.Cu" "B.Cu")
		(net "GND")
	)
	(via
		(at 427.379892 -342.439498)
		(size 0.4064)
		(drill 0.2032)
		(layers "F.Cu" "B.Cu")
		(net "GND")
	)
	(via
		(at 312.274712 -298.27474)
		(size 0.4064)
		(drill 0.2032)
		(layers "F.Cu" "B.Cu")
		(net "GND")
	)
	(via
		(at 161.54781 -411.141926)
		(size 0.508)
		(drill 0.254)
		(layers "F.Cu" "B.Cu")
		(net "GND")
	)
	(via
		(at 154.375104 -284.974792)
		(size 0.4064)
		(drill 0.2032)
		(layers "F.Cu" "B.Cu")
		(net "GND")
	)
	(via
		(at 282.349702 -275.949918)
		(size 0.4064)
		(drill 0.2032)
		(layers "F.Cu" "B.Cu")
		(net "GND")
	)
	(via
		(at 400.229832 -352.245422)
		(size 0.4572)
		(drill 0.254)
		(layers "F.Cu" "B.Cu")
		(net "GND")
	)
	(via
		(at 340.894162 -218.787218)
		(size 0.4572)
		(drill 0.254)
		(layers "F.Cu" "B.Cu")
		(net "GND")
	)
	(via
		(at 408.755088 -27.79014)
		(size 0.508)
		(drill 0.254)
		(layers "F.Cu" "B.Cu")
		(net "GND")
	)
	(via
		(at 275.699728 -305.399948)
		(size 0.4064)
		(drill 0.2032)
		(layers "F.Cu" "B.Cu")
		(net "GND")
	)
	(via
		(at 85.674962 -348.58579)
		(size 0.4064)
		(drill 0.2032)
		(layers "F.Cu" "B.Cu")
		(net "GND")
	)
	(via
		(at 280.160222 -19.33956)
		(size 0.508)
		(drill 0.254)
		(layers "F.Cu" "B.Cu")
		(net "GND")
	)
	(via
		(at 73.899776 -307.299868)
		(size 0.4064)
		(drill 0.2032)
		(layers "F.Cu" "B.Cu")
		(net "GND")
	)
	(via
		(at 33.947862 -376.140218)
		(size 0.508)
		(drill 0.254)
		(layers "F.Cu" "B.Cu")
		(net "GND")
	)
	(via
		(at 181.92496 -302.074834)
		(size 0.4064)
		(drill 0.2032)
		(layers "F.Cu" "B.Cu")
		(net "GND")
	)
	(via
		(at 304.467006 -120.035066)
		(size 0.508)
		(drill 0.254)
		(layers "F.Cu" "B.Cu")
		(net "GND")
	)
	(via
		(at 159.347916 -401.040092)
		(size 0.508)
		(drill 0.254)
		(layers "F.Cu" "B.Cu")
		(net "GND")
	)
	(via
		(at 323.262244 -351.611438)
		(size 0.4064)
		(drill 0.2032)
		(layers "F.Cu" "B.Cu")
		(net "GND")
	)
	(via
		(at 383.72796 -376.241818)
		(size 0.508)
		(drill 0.254)
		(layers "F.Cu" "B.Cu")
		(net "GND")
	)
	(via
		(at 163.747958 -373.83847)
		(size 0.508)
		(drill 0.254)
		(layers "F.Cu" "B.Cu")
		(net "GND")
	)
	(via
		(at 126.347728 -403.34184)
		(size 0.4572)
		(drill 0.254)
		(layers "F.Cu" "B.Cu")
		(net "GND")
	)
	(via
		(at 184.77484 -284.024832)
		(size 0.4064)
		(drill 0.2032)
		(layers "F.Cu" "B.Cu")
		(net "GND")
	)
	(via
		(at 246.153686 -114.135408)
		(size 0.508)
		(drill 0.254)
		(layers "F.Cu" "B.Cu")
		(net "GND")
	)
	(via
		(at 121.576592 -269.366492)
		(size 0.508)
		(drill 0.254)
		(layers "F.Cu" "B.Cu")
		(net "GND")
	)
	(via
		(at 78.17485 -289.724846)
		(size 0.4064)
		(drill 0.2032)
		(layers "F.Cu" "B.Cu")
		(net "GND")
	)
	(via
		(at 344.653616 -347.951806)
		(size 0.4572)
		(drill 0.254)
		(layers "F.Cu" "B.Cu")
		(net "GND")
	)
	(via
		(at 115.34775 -399.838418)
		(size 0.508)
		(drill 0.254)
		(layers "F.Cu" "B.Cu")
		(net "GND")
	)
	(via
		(at 344.653616 -341.805514)
		(size 0.4572)
		(drill 0.254)
		(layers "F.Cu" "B.Cu")
		(net "GND")
	)
	(via
		(at 330.958952 -358.391714)
		(size 0.4572)
		(drill 0.254)
		(layers "F.Cu" "B.Cu")
		(net "GND")
	)
	(via
		(at 130.74777 -378.83846)
		(size 0.508)
		(drill 0.254)
		(layers "F.Cu" "B.Cu")
		(net "GND")
	)
	(via
		(at 180.50002 -276.899878)
		(size 0.4064)
		(drill 0.2032)
		(layers "F.Cu" "B.Cu")
		(net "GND")
	)
	(via
		(at 131.860544 -128.193546)
		(size 0.508)
		(drill 0.254)
		(layers "F.Cu" "B.Cu")
		(net "GND")
	)
	(via
		(at 295.727882 -382.84023)
		(size 0.508)
		(drill 0.254)
		(layers "F.Cu" "B.Cu")
		(net "GND")
	)
	(via
		(at 275.176234 -357.123746)
		(size 0.4572)
		(drill 0.254)
		(layers "F.Cu" "B.Cu")
		(net "GND")
	)
	(via
		(at 89.15527 -354.074222)
		(size 0.4572)
		(drill 0.254)
		(layers "F.Cu" "B.Cu")
		(net "GND")
	)
	(via
		(at 82.449924 -288.299906)
		(size 0.4064)
		(drill 0.2032)
		(layers "F.Cu" "B.Cu")
		(net "GND")
	)
	(via
		(at 153.89987 -300.649894)
		(size 0.4064)
		(drill 0.2032)
		(layers "F.Cu" "B.Cu")
		(net "GND")
	)
	(via
		(at 314.366148 -147.27682)
		(size 0.508)
		(drill 0.254)
		(layers "F.Cu" "B.Cu")
		(net "GND")
	)
	(via
		(at 311.936638 -15.474188)
		(size 0.508)
		(drill 0.254)
		(layers "F.Cu" "B.Cu")
		(net "GND")
	)
	(via
		(at 48.54575 -156.0576)
		(size 0.508)
		(drill 0.254)
		(layers "F.Cu" "B.Cu")
		(net "GND")
	)
	(via
		(at 126.347728 -372.240302)
		(size 0.4572)
		(drill 0.254)
		(layers "F.Cu" "B.Cu")
		(net "GND")
	)
	(via
		(at 393.16914 -152.958038)
		(size 0.508)
		(drill 0.254)
		(layers "F.Cu" "B.Cu")
		(net "GND")
	)
	(via
		(at 255.424178 -222.976186)
		(size 0.508)
		(drill 0.254)
		(layers "F.Cu" "B.Cu")
		(net "GND")
	)
	(via
		(at 377.657868 -25.971246)
		(size 0.508)
		(drill 0.254)
		(layers "F.Cu" "B.Cu")
		(net "GND")
	)
	(via
		(at 429.325024 -298.27474)
		(size 0.4064)
		(drill 0.2032)
		(layers "F.Cu" "B.Cu")
		(net "GND")
	)
	(via
		(at 377.12777 -371.038628)
		(size 0.508)
		(drill 0.254)
		(layers "F.Cu" "B.Cu")
		(net "GND")
	)
	(via
		(at 386.099812 -312.999882)
		(size 0.4064)
		(drill 0.2032)
		(layers "F.Cu" "B.Cu")
		(net "GND")
	)
	(via
		(at 382.791716 -133.836664)
		(size 0.508)
		(drill 0.254)
		(layers "F.Cu" "B.Cu")
		(net "GND")
	)
	(via
		(at 275.224748 -288.774886)
		(size 0.4064)
		(drill 0.2032)
		(layers "F.Cu" "B.Cu")
		(net "GND")
	)
	(via
		(at 348.527878 -395.938502)
		(size 0.508)
		(drill 0.254)
		(layers "F.Cu" "B.Cu")
		(net "GND")
	)
	(via
		(at 40.547798 -373.83847)
		(size 0.508)
		(drill 0.254)
		(layers "F.Cu" "B.Cu")
		(net "GND")
	)
	(via
		(at 46.8249 -303.974754)
		(size 0.4064)
		(drill 0.2032)
		(layers "F.Cu" "B.Cu")
		(net "GND")
	)
	(via
		(at 27.347926 -399.838418)
		(size 0.508)
		(drill 0.254)
		(layers "F.Cu" "B.Cu")
		(net "GND")
	)
	(via
		(at 255.540002 -73.87463)
		(size 0.508)
		(drill 0.254)
		(layers "F.Cu" "B.Cu")
		(net "GND")
	)
	(via
		(at 130.175508 -187.588906)
		(size 0.508)
		(drill 0.254)
		(layers "F.Cu" "B.Cu")
		(net "GND")
	)
	(via
		(at 423.639996 -73.87463)
		(size 0.508)
		(drill 0.254)
		(layers "F.Cu" "B.Cu")
		(net "GND")
	)
	(via
		(at 282.824936 -291.624766)
		(size 0.4064)
		(drill 0.2032)
		(layers "F.Cu" "B.Cu")
		(net "GND")
	)
	(via
		(at 139.273788 -348.58579)
		(size 0.4064)
		(drill 0.2032)
		(layers "F.Cu" "B.Cu")
		(net "GND")
	)
	(via
		(at 269.99819 -21.077936)
		(size 0.508)
		(drill 0.254)
		(layers "F.Cu" "B.Cu")
		(net "GND")
	)
	(via
		(at 376.83694 -342.439498)
		(size 0.4064)
		(drill 0.2032)
		(layers "F.Cu" "B.Cu")
		(net "GND")
	)
	(via
		(at 278.074882 -296.37482)
		(size 0.4064)
		(drill 0.2032)
		(layers "F.Cu" "B.Cu")
		(net "GND")
	)
	(via
		(at 265.618976 -203.41209)
		(size 0.508)
		(drill 0.254)
		(layers "F.Cu" "B.Cu")
		(net "GND")
	)
	(via
		(at 312.749946 -275.949918)
		(size 0.4064)
		(drill 0.2032)
		(layers "F.Cu" "B.Cu")
		(net "GND")
	)
	(via
		(at 189.597792 -342.439498)
		(size 0.4064)
		(drill 0.2032)
		(layers "F.Cu" "B.Cu")
		(net "GND")
	)
	(via
		(at 419.824916 -305.874928)
		(size 0.4064)
		(drill 0.2032)
		(layers "F.Cu" "B.Cu")
		(net "GND")
	)
	(via
		(at 169.099992 -277.849838)
		(size 0.4064)
		(drill 0.2032)
		(layers "F.Cu" "B.Cu")
		(net "GND")
	)
	(via
		(at 269.999714 -313.949842)
		(size 0.4064)
		(drill 0.2032)
		(layers "F.Cu" "B.Cu")
		(net "GND")
	)
	(via
		(at 429.325024 -291.624766)
		(size 0.4064)
		(drill 0.2032)
		(layers "F.Cu" "B.Cu")
		(net "GND")
	)
	(via
		(at 156.750004 -310.149748)
		(size 0.4064)
		(drill 0.2032)
		(layers "F.Cu" "B.Cu")
		(net "GND")
	)
	(via
		(at 302.931322 -11.372342)
		(size 0.508)
		(drill 0.254)
		(layers "F.Cu" "B.Cu")
		(net "GND")
	)
	(via
		(at 399.93316 -109.644942)
		(size 0.508)
		(drill 0.254)
		(layers "F.Cu" "B.Cu")
		(net "GND")
	)
	(via
		(at 186.86018 -357.09987)
		(size 0.4572)
		(drill 0.254)
		(layers "F.Cu" "B.Cu")
		(net "GND")
	)
	(via
		(at 302.774858 -284.974792)
		(size 0.4064)
		(drill 0.2032)
		(layers "F.Cu" "B.Cu")
		(net "GND")
	)
	(via
		(at 300.591474 -220.55836)
		(size 0.508)
		(drill 0.254)
		(layers "F.Cu" "B.Cu")
		(net "GND")
	)
	(via
		(at 259.492242 -348.796864)
		(size 0.508)
		(drill 0.254)
		(layers "F.Cu" "B.Cu")
		(net "GND")
	)
	(via
		(at 403.674834 -287.824926)
		(size 0.4064)
		(drill 0.2032)
		(layers "F.Cu" "B.Cu")
		(net "GND")
	)
	(via
		(at 44.449746 -275.949918)
		(size 0.4064)
		(drill 0.2032)
		(layers "F.Cu" "B.Cu")
		(net "GND")
	)
	(via
		(at 44.92498 -287.824926)
		(size 0.4064)
		(drill 0.2032)
		(layers "F.Cu" "B.Cu")
		(net "GND")
	)
	(via
		(at 121.947686 -372.240302)
		(size 0.4572)
		(drill 0.254)
		(layers "F.Cu" "B.Cu")
		(net "GND")
	)
	(via
		(at 404.624794 -309.674768)
		(size 0.4064)
		(drill 0.2032)
		(layers "F.Cu" "B.Cu")
		(net "GND")
	)
	(via
		(at 64.59347 -156.555186)
		(size 0.508)
		(drill 0.254)
		(layers "F.Cu" "B.Cu")
		(net "GND")
	)
	(via
		(at 183.75122 -346.09913)
		(size 0.4572)
		(drill 0.254)
		(layers "F.Cu" "B.Cu")
		(net "GND")
	)
	(via
		(at 177.748946 -25.990042)
		(size 0.508)
		(drill 0.254)
		(layers "F.Cu" "B.Cu")
		(net "GND")
	)
	(via
		(at 297.074844 -296.37482)
		(size 0.4064)
		(drill 0.2032)
		(layers "F.Cu" "B.Cu")
		(net "GND")
	)
	(via
		(at 141.275308 -357.75773)
		(size 0.4064)
		(drill 0.2032)
		(layers "F.Cu" "B.Cu")
		(net "GND")
	)
	(via
		(at 238.800894 -33.19018)
		(size 0.508)
		(drill 0.254)
		(layers "F.Cu" "B.Cu")
		(net "GND")
	)
	(via
		(at 122.65787 -135.058404)
		(size 0.508)
		(drill 0.254)
		(layers "F.Cu" "B.Cu")
		(net "GND")
	)
	(via
		(at 200.700894 -29.590238)
		(size 0.508)
		(drill 0.254)
		(layers "F.Cu" "B.Cu")
		(net "GND")
	)
	(via
		(at 291.32784 -381.638556)
		(size 0.508)
		(drill 0.254)
		(layers "F.Cu" "B.Cu")
		(net "GND")
	)
	(via
		(at 99.313238 -31.118302)
		(size 0.508)
		(drill 0.254)
		(layers "F.Cu" "B.Cu")
		(net "GND")
	)
	(via
		(at 4.562856 -185.241692)
		(size 0.508)
		(drill 0.254)
		(layers "F.Cu" "B.Cu")
		(net "GND")
	)
	(via
		(at 63.449962 -276.899878)
		(size 0.4064)
		(drill 0.2032)
		(layers "F.Cu" "B.Cu")
		(net "GND")
	)
	(via
		(at 28.461716 -346.09913)
		(size 0.4572)
		(drill 0.254)
		(layers "F.Cu" "B.Cu")
		(net "GND")
	)
	(via
		(at 250.34113 -38.49116)
		(size 0.508)
		(drill 0.254)
		(layers "F.Cu" "B.Cu")
		(net "GND")
	)
	(via
		(at 177.174906 -298.27474)
		(size 0.4064)
		(drill 0.2032)
		(layers "F.Cu" "B.Cu")
		(net "GND")
	)
	(via
		(at 85.572854 -303.887378)
		(size 0.508)
		(drill 0.254)
		(layers "F.Cu" "B.Cu")
		(net "GND")
	)
	(via
		(at 153.42489 -294.4749)
		(size 0.4064)
		(drill 0.2032)
		(layers "F.Cu" "B.Cu")
		(net "GND")
	)
	(via
		(at 121.947686 -382.73863)
		(size 0.508)
		(drill 0.254)
		(layers "F.Cu" "B.Cu")
		(net "GND")
	)
	(via
		(at 44.006516 -358.391714)
		(size 0.4572)
		(drill 0.254)
		(layers "F.Cu" "B.Cu")
		(net "GND")
	)
	(via
		(at 80.898238 -123.356878)
		(size 0.508)
		(drill 0.254)
		(layers "F.Cu" "B.Cu")
		(net "GND")
	)
	(via
		(at 184.77484 -302.074834)
		(size 0.4064)
		(drill 0.2032)
		(layers "F.Cu" "B.Cu")
		(net "GND")
	)
	(via
		(at 71.997824 -133.472682)
		(size 0.508)
		(drill 0.254)
		(layers "F.Cu" "B.Cu")
		(net "GND")
	)
	(via
		(at 260.606286 -253.45644)
		(size 0.508)
		(drill 0.254)
		(layers "F.Cu" "B.Cu")
		(net "GND")
	)
	(via
		(at 48.72482 -291.624766)
		(size 0.4064)
		(drill 0.2032)
		(layers "F.Cu" "B.Cu")
		(net "GND")
	)
	(via
		(at 402.079968 -358.391714)
		(size 0.4572)
		(drill 0.254)
		(layers "F.Cu" "B.Cu")
		(net "GND")
	)
	(via
		(at 51.099974 -276.899878)
		(size 0.4064)
		(drill 0.2032)
		(layers "F.Cu" "B.Cu")
		(net "GND")
	)
	(via
		(at 434.120036 -31.390336)
		(size 0.508)
		(drill 0.254)
		(layers "F.Cu" "B.Cu")
		(net "GND")
	)
	(via
		(at 35.93846 -341.805514)
		(size 0.4572)
		(drill 0.254)
		(layers "F.Cu" "B.Cu")
		(net "GND")
	)
	(via
		(at 13.208 -417.82492)
		(size 0.508)
		(drill 0.254)
		(layers "F.Cu" "B.Cu")
		(net "GND")
	)
	(via
		(at 404.624794 -303.974754)
		(size 0.4064)
		(drill 0.2032)
		(layers "F.Cu" "B.Cu")
		(net "GND")
	)
	(via
		(at 414.124902 -285.924752)
		(size 0.4064)
		(drill 0.2032)
		(layers "F.Cu" "B.Cu")
		(net "GND")
	)
	(via
		(at 393.184888 -77.446124)
		(size 0.508)
		(drill 0.254)
		(layers "F.Cu" "B.Cu")
		(net "GND")
	)
	(via
		(at 185.747914 -129.445004)
		(size 0.508)
		(drill 0.254)
		(layers "F.Cu" "B.Cu")
		(net "GND")
	)
	(via
		(at 198.550022 -282.599892)
		(size 0.4064)
		(drill 0.2032)
		(layers "F.Cu" "B.Cu")
		(net "GND")
	)
	(via
		(at 145.407126 -49.574704)
		(size 0.508)
		(drill 0.254)
		(layers "F.Cu" "B.Cu")
		(net "GND")
	)
	(via
		(at 112.446816 -136.24306)
		(size 0.508)
		(drill 0.254)
		(layers "F.Cu" "B.Cu")
		(net "GND")
	)
	(via
		(at 291.849556 -272.149316)
		(size 0.4064)
		(drill 0.2032)
		(layers "F.Cu" "B.Cu")
		(net "GND")
	)
	(via
		(at 285.369 -83.566)
		(size 0.508)
		(drill 0.254)
		(layers "F.Cu" "B.Cu")
		(net "GND")
	)
	(via
		(at 43.024806 -289.724846)
		(size 0.4064)
		(drill 0.2032)
		(layers "F.Cu" "B.Cu")
		(net "GND")
	)
	(via
		(at 429.325024 -297.32478)
		(size 0.4064)
		(drill 0.2032)
		(layers "F.Cu" "B.Cu")
		(net "GND")
	)
	(via
		(at 219.60205 -200.279)
		(size 0.508)
		(drill 0.254)
		(layers "F.Cu" "B.Cu")
		(net "GND")
	)
	(via
		(at 165.440106 -74.58583)
		(size 0.508)
		(drill 0.254)
		(layers "F.Cu" "B.Cu")
		(net "GND")
	)
	(via
		(at 181.44998 -310.149748)
		(size 0.4064)
		(drill 0.2032)
		(layers "F.Cu" "B.Cu")
		(net "GND")
	)
	(via
		(at 124.100336 -358.391714)
		(size 0.4572)
		(drill 0.254)
		(layers "F.Cu" "B.Cu")
		(net "GND")
	)
	(via
		(at 433.597812 -348.58579)
		(size 0.4064)
		(drill 0.2032)
		(layers "F.Cu" "B.Cu")
		(net "GND")
	)
	(via
		(at 283.24429 -358.391714)
		(size 0.4572)
		(drill 0.254)
		(layers "F.Cu" "B.Cu")
		(net "GND")
	)
	(via
		(at 114.378486 -282.910788)
		(size 0.49022)
		(drill 0.254)
		(layers "F.Cu" "B.Cu")
		(net "GND")
	)
	(via
		(at 112.545876 -124.777754)
		(size 0.508)
		(drill 0.254)
		(layers "F.Cu" "B.Cu")
		(net "GND")
	)
	(via
		(at 103.2764 -200.406)
		(size 0.508)
		(drill 0.254)
		(layers "F.Cu" "B.Cu")
		(net "GND")
	)
	(via
		(at 90.785442 -342.439498)
		(size 0.4064)
		(drill 0.2032)
		(layers "F.Cu" "B.Cu")
		(net "GND")
	)
	(via
		(at 221.928182 -90.892376)
		(size 0.508)
		(drill 0.254)
		(layers "F.Cu" "B.Cu")
		(net "GND")
	)
	(via
		(at 302.769778 -25.832054)
		(size 0.508)
		(drill 0.254)
		(layers "F.Cu" "B.Cu")
		(net "GND")
	)
	(via
		(at 296.124884 -297.32478)
		(size 0.4064)
		(drill 0.2032)
		(layers "F.Cu" "B.Cu")
		(net "GND")
	)
	(via
		(at 124.071126 -217.681302)
		(size 0.508)
		(drill 0.254)
		(layers "F.Cu" "B.Cu")
		(net "GND")
	)
	(via
		(at 170.347894 -376.140218)
		(size 0.508)
		(drill 0.254)
		(layers "F.Cu" "B.Cu")
		(net "GND")
	)
	(via
		(at 275.224748 -284.974792)
		(size 0.4064)
		(drill 0.2032)
		(layers "F.Cu" "B.Cu")
		(net "GND")
	)
	(via
		(at 268.09954 -310.150002)
		(size 0.4064)
		(drill 0.2032)
		(layers "F.Cu" "B.Cu")
		(net "GND")
	)
	(via
		(at 162.450018 -311.099962)
		(size 0.4064)
		(drill 0.2032)
		(layers "F.Cu" "B.Cu")
		(net "GND")
	)
	(via
		(at 41.124886 -294.4749)
		(size 0.4064)
		(drill 0.2032)
		(layers "F.Cu" "B.Cu")
		(net "GND")
	)
	(via
		(at 365.904272 -93.869764)
		(size 0.508)
		(drill 0.254)
		(layers "F.Cu" "B.Cu")
		(net "GND")
	)
	(via
		(at 238.404654 -309.604156)
		(size 0.508)
		(drill 0.254)
		(layers "F.Cu" "B.Cu")
		(net "GND")
	)
	(via
		(at 298.012612 -131.245102)
		(size 0.508)
		(drill 0.254)
		(layers "F.Cu" "B.Cu")
		(net "GND")
	)
	(via
		(at 416.574224 -349.219774)
		(size 0.4572)
		(drill 0.254)
		(layers "F.Cu" "B.Cu")
		(net "GND")
	)
	(via
		(at 6.600952 -29.590238)
		(size 0.508)
		(drill 0.254)
		(layers "F.Cu" "B.Cu")
		(net "GND")
	)
	(via
		(at 373.72798 -345.465146)
		(size 0.4064)
		(drill 0.2032)
		(layers "F.Cu" "B.Cu")
		(net "GND")
	)
	(via
		(at 167.200072 -273.099784)
		(size 0.4064)
		(drill 0.2032)
		(layers "F.Cu" "B.Cu")
		(net "GND")
	)
	(via
		(at 303.724818 -305.874928)
		(size 0.4064)
		(drill 0.2032)
		(layers "F.Cu" "B.Cu")
		(net "GND")
	)
	(via
		(at 89.83218 -126.013972)
		(size 0.508)
		(drill 0.254)
		(layers "F.Cu" "B.Cu")
		(net "GND")
	)
	(via
		(at 235.615226 -287.105344)
		(size 0.508)
		(drill 0.254)
		(layers "F.Cu" "B.Cu")
		(net "GND")
	)
	(via
		(at 358.369362 -141.019276)
		(size 0.508)
		(drill 0.254)
		(layers "F.Cu" "B.Cu")
		(net "GND")
	)
	(via
		(at 40.24884 -31.390082)
		(size 0.508)
		(drill 0.254)
		(layers "F.Cu" "B.Cu")
		(net "GND")
	)
	(via
		(at 414.124902 -291.624766)
		(size 0.4064)
		(drill 0.2032)
		(layers "F.Cu" "B.Cu")
		(net "GND")
	)
	(via
		(at 128.839468 -348.58579)
		(size 0.4064)
		(drill 0.2032)
		(layers "F.Cu" "B.Cu")
		(net "GND")
	)
	(via
		(at 162.0393 -28.05303)
		(size 0.508)
		(drill 0.254)
		(layers "F.Cu" "B.Cu")
		(net "GND")
	)
	(via
		(at 65.349882 -275.949918)
		(size 0.4064)
		(drill 0.2032)
		(layers "F.Cu" "B.Cu")
		(net "GND")
	)
	(via
		(at 38.275006 -288.774886)
		(size 0.4064)
		(drill 0.2032)
		(layers "F.Cu" "B.Cu")
		(net "GND")
	)
	(via
		(at 397.746982 -109.177328)
		(size 0.508)
		(drill 0.254)
		(layers "F.Cu" "B.Cu")
		(net "GND")
	)
	(via
		(at 143.836898 -15.474188)
		(size 0.508)
		(drill 0.254)
		(layers "F.Cu" "B.Cu")
		(net "GND")
	)
	(via
		(at 115.34648 -322.452492)
		(size 0.508)
		(drill 0.254)
		(layers "F.Cu" "B.Cu")
		(net "GND")
	)
	(via
		(at 142.004796 -179.839874)
		(size 0.508)
		(drill 0.254)
		(layers "F.Cu" "B.Cu")
		(net "GND")
	)
	(via
		(at 324.448678 -27.79014)
		(size 0.508)
		(drill 0.254)
		(layers "F.Cu" "B.Cu")
		(net "GND")
	)
	(via
		(at 341.927942 -400.938492)
		(size 0.508)
		(drill 0.254)
		(layers "F.Cu" "B.Cu")
		(net "GND")
	)
	(via
		(at 20.39366 -341.805514)
		(size 0.4572)
		(drill 0.254)
		(layers "F.Cu" "B.Cu")
		(net "GND")
	)
	(via
		(at 285.687262 -131.76504)
		(size 0.508)
		(drill 0.254)
		(layers "F.Cu" "B.Cu")
		(net "GND")
	)
	(via
		(at 55.374794 -306.824888)
		(size 0.4064)
		(drill 0.2032)
		(layers "F.Cu" "B.Cu")
		(net "GND")
	)
	(via
		(at 249.093482 -159.573468)
		(size 0.508)
		(drill 0.254)
		(layers "F.Cu" "B.Cu")
		(net "GND")
	)
	(via
		(at 196.441822 -25.971246)
		(size 0.508)
		(drill 0.254)
		(layers "F.Cu" "B.Cu")
		(net "GND")
	)
	(via
		(at 40.547798 -372.341902)
		(size 0.508)
		(drill 0.254)
		(layers "F.Cu" "B.Cu")
		(net "GND")
	)
	(via
		(at 433.108354 -144.224502)
		(size 0.508)
		(drill 0.254)
		(layers "F.Cu" "B.Cu")
		(net "GND")
	)
	(via
		(at 447.980816 -102.095046)
		(size 0.508)
		(drill 0.254)
		(layers "F.Cu" "B.Cu")
		(net "GND")
	)
	(via
		(at 397.49984 -313.949842)
		(size 0.4064)
		(drill 0.2032)
		(layers "F.Cu" "B.Cu")
		(net "GND")
	)
	(via
		(at 58.10504 -80.294988)
		(size 0.508)
		(drill 0.254)
		(layers "F.Cu" "B.Cu")
		(net "GND")
	)
	(via
		(at 288.049716 -276.899878)
		(size 0.4064)
		(drill 0.2032)
		(layers "F.Cu" "B.Cu")
		(net "GND")
	)
	(via
		(at 99.0981 -242.649248)
		(size 0.508)
		(drill 0.254)
		(layers "F.Cu" "B.Cu")
		(net "GND")
	)
	(via
		(at 167.732964 -106.045)
		(size 0.508)
		(drill 0.254)
		(layers "F.Cu" "B.Cu")
		(net "GND")
	)
	(via
		(at 176.224946 -300.174914)
		(size 0.4064)
		(drill 0.2032)
		(layers "F.Cu" "B.Cu")
		(net "GND")
	)
	(via
		(at 126.347728 -399.441924)
		(size 0.4572)
		(drill 0.254)
		(layers "F.Cu" "B.Cu")
		(net "GND")
	)
	(via
		(at 159.599884 -278.799798)
		(size 0.4064)
		(drill 0.2032)
		(layers "F.Cu" "B.Cu")
		(net "GND")
	)
	(via
		(at 53.474874 -303.974754)
		(size 0.4064)
		(drill 0.2032)
		(layers "F.Cu" "B.Cu")
		(net "GND")
	)
	(via
		(at 416.857942 -57.521094)
		(size 0.508)
		(drill 0.254)
		(layers "F.Cu" "B.Cu")
		(net "GND")
	)
	(via
		(at 347.073982 -286.842454)
		(size 0.508)
		(drill 0.254)
		(layers "F.Cu" "B.Cu")
		(net "GND")
	)
	(via
		(at 198.075042 -297.32478)
		(size 0.4064)
		(drill 0.2032)
		(layers "F.Cu" "B.Cu")
		(net "GND")
	)
	(via
		(at 121.210324 -304.373534)
		(size 0.508)
		(drill 0.254)
		(layers "F.Cu" "B.Cu")
		(net "GND")
	)
	(via
		(at 96.638618 -23.880318)
		(size 0.508)
		(drill 0.254)
		(layers "F.Cu" "B.Cu")
		(net "GND")
	)
	(via
		(at 298.78909 -341.805514)
		(size 0.4572)
		(drill 0.254)
		(layers "F.Cu" "B.Cu")
		(net "GND")
	)
	(via
		(at 424.57497 -292.574726)
		(size 0.4064)
		(drill 0.2032)
		(layers "F.Cu" "B.Cu")
		(net "GND")
	)
	(via
		(at 308.174898 -73.23963)
		(size 0.508)
		(drill 0.254)
		(layers "F.Cu" "B.Cu")
		(net "GND")
	)
	(via
		(at 281.399742 -277.849838)
		(size 0.4064)
		(drill 0.2032)
		(layers "F.Cu" "B.Cu")
		(net "GND")
	)
	(via
		(at 50.14976 -279.749758)
		(size 0.4064)
		(drill 0.2032)
		(layers "F.Cu" "B.Cu")
		(net "GND")
	)
	(via
		(at 196.649848 -312.049922)
		(size 0.4064)
		(drill 0.2032)
		(layers "F.Cu" "B.Cu")
		(net "GND")
	)
	(via
		(at 334.229964 -105.057194)
		(size 0.508)
		(drill 0.254)
		(layers "F.Cu" "B.Cu")
		(net "GND")
	)
	(via
		(at 463.037682 -230.137462)
		(size 0.508)
		(drill 0.254)
		(layers "F.Cu" "B.Cu")
		(net "GND")
	)
	(via
		(at 135.365744 -131.964176)
		(size 0.508)
		(drill 0.254)
		(layers "F.Cu" "B.Cu")
		(net "GND")
	)
	(via
		(at 426.94987 -272.14957)
		(size 0.4064)
		(drill 0.2032)
		(layers "F.Cu" "B.Cu")
		(net "GND")
	)
	(via
		(at 158.649924 -304.449734)
		(size 0.4064)
		(drill 0.2032)
		(layers "F.Cu" "B.Cu")
		(net "GND")
	)
	(via
		(at 163.874958 -299.224954)
		(size 0.4064)
		(drill 0.2032)
		(layers "F.Cu" "B.Cu")
		(net "GND")
	)
	(via
		(at 418.399976 -312.999882)
		(size 0.4064)
		(drill 0.2032)
		(layers "F.Cu" "B.Cu")
		(net "GND")
	)
	(via
		(at 278.074882 -293.52494)
		(size 0.4064)
		(drill 0.2032)
		(layers "F.Cu" "B.Cu")
		(net "GND")
	)
	(via
		(at 39.699946 -302.549814)
		(size 0.4064)
		(drill 0.2032)
		(layers "F.Cu" "B.Cu")
		(net "GND")
	)
	(via
		(at 179.55006 -315.849762)
		(size 0.4064)
		(drill 0.2032)
		(layers "F.Cu" "B.Cu")
		(net "GND")
	)
	(via
		(at 197.600062 -280.699718)
		(size 0.4064)
		(drill 0.2032)
		(layers "F.Cu" "B.Cu")
		(net "GND")
	)
	(via
		(at 334.174846 -73.87463)
		(size 0.508)
		(drill 0.254)
		(layers "F.Cu" "B.Cu")
		(net "GND")
	)
	(via
		(at 238.886238 -235.737654)
		(size 0.508)
		(drill 0.254)
		(layers "F.Cu" "B.Cu")
		(net "GND")
	)
	(via
		(at 295.727882 -402.241766)
		(size 0.508)
		(drill 0.254)
		(layers "F.Cu" "B.Cu")
		(net "GND")
	)
	(via
		(at 47.115476 -343.073482)
		(size 0.4572)
		(drill 0.254)
		(layers "F.Cu" "B.Cu")
		(net "GND")
	)
	(via
		(at 174.747936 -372.240302)
		(size 0.508)
		(drill 0.254)
		(layers "F.Cu" "B.Cu")
		(net "GND")
	)
	(via
		(at 38.275006 -291.624766)
		(size 0.4064)
		(drill 0.2032)
		(layers "F.Cu" "B.Cu")
		(net "GND")
	)
	(via
		(at 52.999894 -314.899802)
		(size 0.4064)
		(drill 0.2032)
		(layers "F.Cu" "B.Cu")
		(net "GND")
	)
	(via
		(at 35.759644 -111.72317)
		(size 0.508)
		(drill 0.254)
		(layers "F.Cu" "B.Cu")
		(net "GND")
	)
	(via
		(at 406.049988 -281.649932)
		(size 0.4064)
		(drill 0.2032)
		(layers "F.Cu" "B.Cu")
		(net "GND")
	)
	(via
		(at 81.499964 -288.299906)
		(size 0.4064)
		(drill 0.2032)
		(layers "F.Cu" "B.Cu")
		(net "GND")
	)
	(via
		(at 247.636792 -282.982162)
		(size 0.508)
		(drill 0.254)
		(layers "F.Cu" "B.Cu")
		(net "GND")
	)
	(via
		(at 281.874722 -302.074834)
		(size 0.4064)
		(drill 0.2032)
		(layers "F.Cu" "B.Cu")
		(net "GND")
	)
	(via
		(at 285.51505 -43.85691)
		(size 0.508)
		(drill 0.254)
		(layers "F.Cu" "B.Cu")
		(net "GND")
	)
	(via
		(at 249.685556 -63.218314)
		(size 0.508)
		(drill 0.254)
		(layers "F.Cu" "B.Cu")
		(net "GND")
	)
	(via
		(at 278.285194 -355.366066)
		(size 0.4572)
		(drill 0.254)
		(layers "F.Cu" "B.Cu")
		(net "GND")
	)
	(via
		(at 325.197724 -295.355518)
		(size 0.508)
		(drill 0.254)
		(layers "F.Cu" "B.Cu")
		(net "GND")
	)
	(via
		(at 430.749964 -311.099962)
		(size 0.4064)
		(drill 0.2032)
		(layers "F.Cu" "B.Cu")
		(net "GND")
	)
	(via
		(at 160.528 -417.82492)
		(size 0.508)
		(drill 0.254)
		(layers "F.Cu" "B.Cu")
		(net "GND")
	)
	(via
		(at 186.675014 -302.074834)
		(size 0.4064)
		(drill 0.2032)
		(layers "F.Cu" "B.Cu")
		(net "GND")
	)
	(via
		(at 200.908158 -136.373362)
		(size 0.508)
		(drill 0.254)
		(layers "F.Cu" "B.Cu")
		(net "GND")
	)
	(via
		(at 327.478644 -351.611438)
		(size 0.4064)
		(drill 0.2032)
		(layers "F.Cu" "B.Cu")
		(net "GND")
	)
	(via
		(at 56.373776 -25.971246)
		(size 0.508)
		(drill 0.254)
		(layers "F.Cu" "B.Cu")
		(net "GND")
	)
	(via
		(at 173.850046 -315.849762)
		(size 0.4064)
		(drill 0.2032)
		(layers "F.Cu" "B.Cu")
		(net "GND")
	)
	(via
		(at 124.642372 -286.842454)
		(size 0.508)
		(drill 0.254)
		(layers "F.Cu" "B.Cu")
		(net "GND")
	)
	(via
		(at 418.882068 -58.238644)
		(size 0.508)
		(drill 0.254)
		(layers "F.Cu" "B.Cu")
		(net "GND")
	)
	(via
		(at 353.776788 -269.366492)
		(size 0.508)
		(drill 0.254)
		(layers "F.Cu" "B.Cu")
		(net "GND")
	)
	(via
		(at 303.249838 -274.999958)
		(size 0.4064)
		(drill 0.2032)
		(layers "F.Cu" "B.Cu")
		(net "GND")
	)
	(via
		(at 341.927942 -381.241808)
		(size 0.508)
		(drill 0.254)
		(layers "F.Cu" "B.Cu")
		(net "GND")
	)
	(via
		(at 166.356284 -344.831162)
		(size 0.4572)
		(drill 0.254)
		(layers "F.Cu" "B.Cu")
		(net "GND")
	)
	(via
		(at 365.00308 -286.842454)
		(size 0.508)
		(drill 0.254)
		(layers "F.Cu" "B.Cu")
		(net "GND")
	)
	(via
		(at 381.458978 -82.236564)
		(size 0.508)
		(drill 0.254)
		(layers "F.Cu" "B.Cu")
		(net "GND")
	)
	(via
		(at 100.242878 -349.98025)
		(size 0.508)
		(drill 0.254)
		(layers "F.Cu" "B.Cu")
		(net "GND")
	)
	(via
		(at 304.199798 -273.099784)
		(size 0.4064)
		(drill 0.2032)
		(layers "F.Cu" "B.Cu")
		(net "GND")
	)
	(via
		(at 427.89983 -283.549852)
		(size 0.4064)
		(drill 0.2032)
		(layers "F.Cu" "B.Cu")
		(net "GND")
	)
	(via
		(at 80.54975 -279.749758)
		(size 0.4064)
		(drill 0.2032)
		(layers "F.Cu" "B.Cu")
		(net "GND")
	)
	(via
		(at 71.049896 -275.949918)
		(size 0.4064)
		(drill 0.2032)
		(layers "F.Cu" "B.Cu")
		(net "GND")
	)
	(via
		(at 423.15003 -280.699718)
		(size 0.4064)
		(drill 0.2032)
		(layers "F.Cu" "B.Cu")
		(net "GND")
	)
	(via
		(at 180.50002 -310.149748)
		(size 0.4064)
		(drill 0.2032)
		(layers "F.Cu" "B.Cu")
		(net "GND")
	)
	(via
		(at 297.074844 -284.974792)
		(size 0.4064)
		(drill 0.2032)
		(layers "F.Cu" "B.Cu")
		(net "GND")
	)
	(via
		(at 173.375066 -303.974754)
		(size 0.4064)
		(drill 0.2032)
		(layers "F.Cu" "B.Cu")
		(net "GND")
	)
	(via
		(at 295.727882 -372.341902)
		(size 0.508)
		(drill 0.254)
		(layers "F.Cu" "B.Cu")
		(net "GND")
	)
	(via
		(at 103.757222 -29.864558)
		(size 0.508)
		(drill 0.254)
		(layers "F.Cu" "B.Cu")
		(net "GND")
	)
	(via
		(at 291.392356 -11.372342)
		(size 0.508)
		(drill 0.254)
		(layers "F.Cu" "B.Cu")
		(net "GND")
	)
	(via
		(at 384.645916 -238.457994)
		(size 0.508)
		(drill 0.254)
		(layers "F.Cu" "B.Cu")
		(net "GND")
	)
	(via
		(at 293.84879 -34.990024)
		(size 0.508)
		(drill 0.254)
		(layers "F.Cu" "B.Cu")
		(net "GND")
	)
	(via
		(at 390.327896 -407.24201)
		(size 0.508)
		(drill 0.254)
		(layers "F.Cu" "B.Cu")
		(net "GND")
	)
	(via
		(at 78.64983 -285.449772)
		(size 0.4064)
		(drill 0.2032)
		(layers "F.Cu" "B.Cu")
		(net "GND")
	)
	(via
		(at 309.899812 -312.999882)
		(size 0.4064)
		(drill 0.2032)
		(layers "F.Cu" "B.Cu")
		(net "GND")
	)
	(via
		(at 300.757844 -58.791094)
		(size 0.508)
		(drill 0.254)
		(layers "F.Cu" "B.Cu")
		(net "GND")
	)
	(via
		(at 150.342092 -262.892794)
		(size 0.508)
		(drill 0.254)
		(layers "F.Cu" "B.Cu")
		(net "GND")
	)
	(via
		(at 296.793412 -134.845044)
		(size 0.508)
		(drill 0.254)
		(layers "F.Cu" "B.Cu")
		(net "GND")
	)
	(via
		(at 34.768028 -54.238906)
		(size 0.508)
		(drill 0.254)
		(layers "F.Cu" "B.Cu")
		(net "GND")
	)
	(via
		(at 362.46308 -286.842454)
		(size 0.508)
		(drill 0.254)
		(layers "F.Cu" "B.Cu")
		(net "GND")
	)
	(via
		(at 19.30527 -401.49272)
		(size 0.508)
		(drill 0.254)
		(layers "F.Cu" "B.Cu")
		(net "GND")
	)
	(via
		(at 298.499784 -274.049744)
		(size 0.4064)
		(drill 0.2032)
		(layers "F.Cu" "B.Cu")
		(net "GND")
	)
	(via
		(at 326.371204 -345.465146)
		(size 0.4064)
		(drill 0.2032)
		(layers "F.Cu" "B.Cu")
		(net "GND")
	)
	(via
		(at 210.03895 -209.042)
		(size 0.508)
		(drill 0.254)
		(layers "F.Cu" "B.Cu")
		(net "GND")
	)
	(via
		(at 330.138278 -115.021614)
		(size 0.508)
		(drill 0.254)
		(layers "F.Cu" "B.Cu")
		(net "GND")
	)
	(via
		(at 139.273788 -354.732082)
		(size 0.4064)
		(drill 0.2032)
		(layers "F.Cu" "B.Cu")
		(net "GND")
	)
	(via
		(at 175.920146 -34.990278)
		(size 0.508)
		(drill 0.254)
		(layers "F.Cu" "B.Cu")
		(net "GND")
	)
	(via
		(at 173.74997 -27.04973)
		(size 0.508)
		(drill 0.254)
		(layers "F.Cu" "B.Cu")
		(net "GND")
	)
	(via
		(at 132.41274 -119.39143)
		(size 0.508)
		(drill 0.254)
		(layers "F.Cu" "B.Cu")
		(net "GND")
	)
	(via
		(at 418.927788 -401.040092)
		(size 0.508)
		(drill 0.254)
		(layers "F.Cu" "B.Cu")
		(net "GND")
	)
	(via
		(at 452.013574 -311.15)
		(size 0.508)
		(drill 0.254)
		(layers "F.Cu" "B.Cu")
		(net "GND")
	)
	(via
		(at 305.149758 -314.899802)
		(size 0.4064)
		(drill 0.2032)
		(layers "F.Cu" "B.Cu")
		(net "GND")
	)
	(via
		(at 145.522442 -253.45644)
		(size 0.508)
		(drill 0.254)
		(layers "F.Cu" "B.Cu")
		(net "GND")
	)
	(via
		(at 250.384564 -73.20026)
		(size 0.508)
		(drill 0.254)
		(layers "F.Cu" "B.Cu")
		(net "GND")
	)
	(via
		(at 441.817252 -351.611438)
		(size 0.4064)
		(drill 0.2032)
		(layers "F.Cu" "B.Cu")
		(net "GND")
	)
	(via
		(at 356.337108 -282.910788)
		(size 0.49022)
		(drill 0.254)
		(layers "F.Cu" "B.Cu")
		(net "GND")
	)
	(via
		(at 382.75514 -31.390082)
		(size 0.508)
		(drill 0.254)
		(layers "F.Cu" "B.Cu")
		(net "GND")
	)
	(via
		(at 191.424052 -26.319734)
		(size 0.508)
		(drill 0.254)
		(layers "F.Cu" "B.Cu")
		(net "GND")
	)
	(via
		(at 384.038602 -136.241028)
		(size 0.508)
		(drill 0.254)
		(layers "F.Cu" "B.Cu")
		(net "GND")
	)
	(via
		(at 112.169448 -160.276794)
		(size 0.508)
		(drill 0.254)
		(layers "F.Cu" "B.Cu")
		(net "GND")
	)
	(via
		(at 154.375104 -279.274778)
		(size 0.4064)
		(drill 0.2032)
		(layers "F.Cu" "B.Cu")
		(net "GND")
	)
	(via
		(at 86.747858 -371.038628)
		(size 0.508)
		(drill 0.254)
		(layers "F.Cu" "B.Cu")
		(net "GND")
	)
	(via
		(at 362.99648 -285.267654)
		(size 0.508)
		(drill 0.254)
		(layers "F.Cu" "B.Cu")
		(net "GND")
	)
	(via
		(at 391.2743 -354.732082)
		(size 0.4064)
		(drill 0.2032)
		(layers "F.Cu" "B.Cu")
		(net "GND")
	)
	(via
		(at 395.522196 -52.51704)
		(size 0.508)
		(drill 0.254)
		(layers "F.Cu" "B.Cu")
		(net "GND")
	)
	(via
		(at 457.52639 -308.196742)
		(size 0.508)
		(drill 0.254)
		(layers "F.Cu" "B.Cu")
		(net "GND")
	)
	(via
		(at 270.601694 -109.916722)
		(size 0.508)
		(drill 0.254)
		(layers "F.Cu" "B.Cu")
		(net "GND")
	)
	(via
		(at 127.209296 -341.805514)
		(size 0.4572)
		(drill 0.254)
		(layers "F.Cu" "B.Cu")
		(net "GND")
	)
	(via
		(at 249.862848 -183.404256)
		(size 0.508)
		(drill 0.254)
		(layers "F.Cu" "B.Cu")
		(net "GND")
	)
	(via
		(at 217.073988 -91.187016)
		(size 0.508)
		(drill 0.254)
		(layers "F.Cu" "B.Cu")
		(net "GND")
	)
	(via
		(at 191.599312 -348.58579)
		(size 0.4064)
		(drill 0.2032)
		(layers "F.Cu" "B.Cu")
		(net "GND")
	)
	(via
		(at 177.5333 -350.977454)
		(size 0.4572)
		(drill 0.254)
		(layers "F.Cu" "B.Cu")
		(net "GND")
	)
	(via
		(at 298.012612 -123.635008)
		(size 0.508)
		(drill 0.254)
		(layers "F.Cu" "B.Cu")
		(net "GND")
	)
	(via
		(at 65.824862 -303.974754)
		(size 0.4064)
		(drill 0.2032)
		(layers "F.Cu" "B.Cu")
		(net "GND")
	)
	(via
		(at 135.134604 -47.936658)
		(size 0.508)
		(drill 0.254)
		(layers "F.Cu" "B.Cu")
		(net "GND")
	)
	(via
		(at 52.524914 -284.974792)
		(size 0.4064)
		(drill 0.2032)
		(layers "F.Cu" "B.Cu")
		(net "GND")
	)
	(via
		(at 298.012612 -156.555186)
		(size 0.508)
		(drill 0.254)
		(layers "F.Cu" "B.Cu")
		(net "GND")
	)
	(via
		(at 81.087214 -357.123746)
		(size 0.4572)
		(drill 0.254)
		(layers "F.Cu" "B.Cu")
		(net "GND")
	)
	(via
		(at 295.998138 -21.738336)
		(size 0.508)
		(drill 0.254)
		(layers "F.Cu" "B.Cu")
		(net "GND")
	)
	(via
		(at 37.788596 -358.391714)
		(size 0.4572)
		(drill 0.254)
		(layers "F.Cu" "B.Cu")
		(net "GND")
	)
	(via
		(at 108.142786 -221.671134)
		(size 0.508)
		(drill 0.254)
		(layers "F.Cu" "B.Cu")
		(net "GND")
	)
	(via
		(at 187.624974 -289.724846)
		(size 0.4064)
		(drill 0.2032)
		(layers "F.Cu" "B.Cu")
		(net "GND")
	)
	(via
		(at 310.751474 -100.056696)
		(size 0.508)
		(drill 0.254)
		(layers "F.Cu" "B.Cu")
		(net "GND")
	)
	(via
		(at 134.68604 -344.831162)
		(size 0.4572)
		(drill 0.254)
		(layers "F.Cu" "B.Cu")
		(net "GND")
	)
	(via
		(at 286.149796 -311.099962)
		(size 0.4064)
		(drill 0.2032)
		(layers "F.Cu" "B.Cu")
		(net "GND")
	)
	(via
		(at 276.649688 -280.699718)
		(size 0.4064)
		(drill 0.2032)
		(layers "F.Cu" "B.Cu")
		(net "GND")
	)
	(via
		(at 401.774914 -300.174914)
		(size 0.4064)
		(drill 0.2032)
		(layers "F.Cu" "B.Cu")
		(net "GND")
	)
	(via
		(at 107.090464 -393.67079)
		(size 0.508)
		(drill 0.254)
		(layers "F.Cu" "B.Cu")
		(net "GND")
	)
	(via
		(at 230.81742 -157.25648)
		(size 0.508)
		(drill 0.254)
		(layers "F.Cu" "B.Cu")
		(net "GND")
	)
	(via
		(at 416.974782 -293.52494)
		(size 0.4064)
		(drill 0.2032)
		(layers "F.Cu" "B.Cu")
		(net "GND")
	)
	(via
		(at 339.09 -172.085)
		(size 0.508)
		(drill 0.254)
		(layers "F.Cu" "B.Cu")
		(net "GND")
	)
	(via
		(at 423.15003 -311.099962)
		(size 0.4064)
		(drill 0.2032)
		(layers "F.Cu" "B.Cu")
		(net "GND")
	)
	(via
		(at 172.574204 -354.098098)
		(size 0.4572)
		(drill 0.254)
		(layers "F.Cu" "B.Cu")
		(net "GND")
	)
	(via
		(at 423.32783 -403.738588)
		(size 0.508)
		(drill 0.254)
		(layers "F.Cu" "B.Cu")
		(net "GND")
	)
	(via
		(at 43.499786 -313.949842)
		(size 0.4064)
		(drill 0.2032)
		(layers "F.Cu" "B.Cu")
		(net "GND")
	)
	(via
		(at 82.347816 -411.141926)
		(size 0.508)
		(drill 0.254)
		(layers "F.Cu" "B.Cu")
		(net "GND")
	)
	(via
		(at 425.253404 -82.331306)
		(size 0.508)
		(drill 0.254)
		(layers "F.Cu" "B.Cu")
		(net "GND")
	)
	(via
		(at 315.740288 -155.024582)
		(size 0.508)
		(drill 0.254)
		(layers "F.Cu" "B.Cu")
		(net "GND")
	)
	(via
		(at 215.413336 -34.718498)
		(size 0.508)
		(drill 0.254)
		(layers "F.Cu" "B.Cu")
		(net "GND")
	)
	(via
		(at 219.172028 -118.361714)
		(size 0.508)
		(drill 0.254)
		(layers "F.Cu" "B.Cu")
		(net "GND")
	)
	(via
		(at 106.633772 -374.63603)
		(size 0.508)
		(drill 0.254)
		(layers "F.Cu" "B.Cu")
		(net "GND")
	)
	(via
		(at 80.341724 -25.971246)
		(size 0.508)
		(drill 0.254)
		(layers "F.Cu" "B.Cu")
		(net "GND")
	)
	(via
		(at 270.949928 -314.899802)
		(size 0.4064)
		(drill 0.2032)
		(layers "F.Cu" "B.Cu")
		(net "GND")
	)
	(via
		(at 30.84322 -52.536852)
		(size 0.508)
		(drill 0.254)
		(layers "F.Cu" "B.Cu")
		(net "GND")
	)
	(via
		(at 454.939146 -320.146934)
		(size 0.508)
		(drill 0.254)
		(layers "F.Cu" "B.Cu")
		(net "GND")
	)
	(via
		(at 78.512924 -9.535922)
		(size 0.508)
		(drill 0.254)
		(layers "F.Cu" "B.Cu")
		(net "GND")
	)
	(via
		(at 241.15395 -150.16861)
		(size 0.508)
		(drill 0.254)
		(layers "F.Cu" "B.Cu")
		(net "GND")
	)
	(via
		(at 153.672794 -156.3624)
		(size 0.508)
		(drill 0.254)
		(layers "F.Cu" "B.Cu")
		(net "GND")
	)
	(via
		(at 337.424014 -103.69296)
		(size 0.508)
		(drill 0.254)
		(layers "F.Cu" "B.Cu")
		(net "GND")
	)
	(via
		(at 430.466246 -142.418054)
		(size 0.508)
		(drill 0.254)
		(layers "F.Cu" "B.Cu")
		(net "GND")
	)
	(via
		(at 66.44767 -134.845044)
		(size 0.508)
		(drill 0.254)
		(layers "F.Cu" "B.Cu")
		(net "GND")
	)
	(via
		(at 44.94784 -406.141936)
		(size 0.508)
		(drill 0.254)
		(layers "F.Cu" "B.Cu")
		(net "GND")
	)
	(via
		(at 31.902146 -27.729688)
		(size 0.508)
		(drill 0.254)
		(layers "F.Cu" "B.Cu")
		(net "GND")
	)
	(via
		(at 236.321092 -86.8807)
		(size 0.508)
		(drill 0.254)
		(layers "F.Cu" "B.Cu")
		(net "GND")
	)
	(via
		(at 45.051726 -102.445058)
		(size 0.508)
		(drill 0.254)
		(layers "F.Cu" "B.Cu")
		(net "GND")
	)
	(via
		(at 338.594446 -102.049072)
		(size 0.508)
		(drill 0.254)
		(layers "F.Cu" "B.Cu")
		(net "GND")
	)
	(via
		(at 186.284616 -72.56526)
		(size 0.508)
		(drill 0.254)
		(layers "F.Cu" "B.Cu")
		(net "GND")
	)
	(via
		(at 278.074882 -284.024832)
		(size 0.4064)
		(drill 0.2032)
		(layers "F.Cu" "B.Cu")
		(net "GND")
	)
	(via
		(at 80.54975 -315.849762)
		(size 0.4064)
		(drill 0.2032)
		(layers "F.Cu" "B.Cu")
		(net "GND")
	)
	(via
		(at 159.347916 -369.938554)
		(size 0.508)
		(drill 0.254)
		(layers "F.Cu" "B.Cu")
		(net "GND")
	)
	(via
		(at 430.466246 -123.356878)
		(size 0.508)
		(drill 0.254)
		(layers "F.Cu" "B.Cu")
		(net "GND")
	)
	(via
		(at 52.85232 -135.364982)
		(size 0.508)
		(drill 0.254)
		(layers "F.Cu" "B.Cu")
		(net "GND")
	)
	(via
		(at 273.324828 -292.57498)
		(size 0.4064)
		(drill 0.2032)
		(layers "F.Cu" "B.Cu")
		(net "GND")
	)
	(via
		(at 296.938954 -341.781638)
		(size 0.4572)
		(drill 0.254)
		(layers "F.Cu" "B.Cu")
		(net "GND")
	)
	(via
		(at 272.374868 -284.974792)
		(size 0.4064)
		(drill 0.2032)
		(layers "F.Cu" "B.Cu")
		(net "GND")
	)
	(via
		(at 62.024768 -285.924752)
		(size 0.4064)
		(drill 0.2032)
		(layers "F.Cu" "B.Cu")
		(net "GND")
	)
	(via
		(at 74.869294 -346.09913)
		(size 0.4572)
		(drill 0.254)
		(layers "F.Cu" "B.Cu")
		(net "GND")
	)
	(via
		(at 155.800044 -304.449734)
		(size 0.4064)
		(drill 0.2032)
		(layers "F.Cu" "B.Cu")
		(net "GND")
	)
	(via
		(at 401.78736 -122.354848)
		(size 0.508)
		(drill 0.254)
		(layers "F.Cu" "B.Cu")
		(net "GND")
	)
	(via
		(at 295.174924 -291.624766)
		(size 0.4064)
		(drill 0.2032)
		(layers "F.Cu" "B.Cu")
		(net "GND")
	)
	(via
		(at 209.870548 -117.430804)
		(size 0.508)
		(drill 0.254)
		(layers "F.Cu" "B.Cu")
		(net "GND")
	)
	(via
		(at 271.899888 -302.549814)
		(size 0.4064)
		(drill 0.2032)
		(layers "F.Cu" "B.Cu")
		(net "GND")
	)
	(via
		(at 406.999948 -277.849838)
		(size 0.4064)
		(drill 0.2032)
		(layers "F.Cu" "B.Cu")
		(net "GND")
	)
	(via
		(at 306.448206 -149.355048)
		(size 0.508)
		(drill 0.254)
		(layers "F.Cu" "B.Cu")
		(net "GND")
	)
	(via
		(at 280.781252 -29.859478)
		(size 0.508)
		(drill 0.254)
		(layers "F.Cu" "B.Cu")
		(net "GND")
	)
	(via
		(at 340.285832 -354.074222)
		(size 0.4572)
		(drill 0.254)
		(layers "F.Cu" "B.Cu")
		(net "GND")
	)
	(via
		(at 19.939254 -31.652972)
		(size 0.508)
		(drill 0.254)
		(layers "F.Cu" "B.Cu")
		(net "GND")
	)
	(via
		(at 430.274984 -293.52494)
		(size 0.4064)
		(drill 0.2032)
		(layers "F.Cu" "B.Cu")
		(net "GND")
	)
	(via
		(at 120.991376 -352.245422)
		(size 0.4572)
		(drill 0.254)
		(layers "F.Cu" "B.Cu")
		(net "GND")
	)
	(via
		(at 7.857236 -305.894994)
		(size 0.508)
		(drill 0.254)
		(layers "F.Cu" "B.Cu")
		(net "GND")
	)
	(via
		(at 438.336944 -358.391714)
		(size 0.4572)
		(drill 0.254)
		(layers "F.Cu" "B.Cu")
		(net "GND")
	)
	(via
		(at 217.140028 -119.072914)
		(size 0.508)
		(drill 0.254)
		(layers "F.Cu" "B.Cu")
		(net "GND")
	)
	(via
		(at 352.029522 -82.098388)
		(size 0.508)
		(drill 0.254)
		(layers "F.Cu" "B.Cu")
		(net "GND")
	)
	(via
		(at 249.809254 -347.89999)
		(size 0.508)
		(drill 0.254)
		(layers "F.Cu" "B.Cu")
		(net "GND")
	)
	(via
		(at 352.145346 -50.516282)
		(size 0.508)
		(drill 0.254)
		(layers "F.Cu" "B.Cu")
		(net "GND")
	)
	(via
		(at 174.247048 -86.30793)
		(size 0.508)
		(drill 0.254)
		(layers "F.Cu" "B.Cu")
		(net "GND")
	)
	(via
		(at 165.774878 -294.4749)
		(size 0.4064)
		(drill 0.2032)
		(layers "F.Cu" "B.Cu")
		(net "GND")
	)
	(via
		(at 466.782912 -82.482182)
		(size 0.508)
		(drill 0.254)
		(layers "F.Cu" "B.Cu")
		(net "GND")
	)
	(via
		(at 43.635168 -354.732082)
		(size 0.4064)
		(drill 0.2032)
		(layers "F.Cu" "B.Cu")
		(net "GND")
	)
	(via
		(at 421.724836 -308.724808)
		(size 0.4064)
		(drill 0.2032)
		(layers "F.Cu" "B.Cu")
		(net "GND")
	)
	(via
		(at 81.024984 -292.574726)
		(size 0.4064)
		(drill 0.2032)
		(layers "F.Cu" "B.Cu")
		(net "GND")
	)
	(via
		(at 239.046766 -1.135126)
		(size 0.508)
		(drill 0.254)
		(layers "F.Cu" "B.Cu")
		(net "GND")
	)
	(via
		(at 405.575008 -289.724846)
		(size 0.4064)
		(drill 0.2032)
		(layers "F.Cu" "B.Cu")
		(net "GND")
	)
	(via
		(at 165.947852 -411.141926)
		(size 0.508)
		(drill 0.254)
		(layers "F.Cu" "B.Cu")
		(net "GND")
	)
	(via
		(at 440.202066 -58.731404)
		(size 0.508)
		(drill 0.254)
		(layers "F.Cu" "B.Cu")
		(net "GND")
	)
	(via
		(at 245.342918 -314.146946)
		(size 0.508)
		(drill 0.254)
		(layers "F.Cu" "B.Cu")
		(net "GND")
	)
	(via
		(at 144.01292 -349.219774)
		(size 0.4572)
		(drill 0.254)
		(layers "F.Cu" "B.Cu")
		(net "GND")
	)
	(via
		(at 401.15236 -133.564884)
		(size 0.508)
		(drill 0.254)
		(layers "F.Cu" "B.Cu")
		(net "GND")
	)
	(via
		(at 18.99793 -135.318246)
		(size 0.508)
		(drill 0.254)
		(layers "F.Cu" "B.Cu")
		(net "GND")
	)
	(via
		(at 68.838318 -73.20026)
		(size 0.508)
		(drill 0.254)
		(layers "F.Cu" "B.Cu")
		(net "GND")
	)
	(via
		(at 314.649866 -305.399948)
		(size 0.4064)
		(drill 0.2032)
		(layers "F.Cu" "B.Cu")
		(net "GND")
	)
	(via
		(at 114.773456 -350.977454)
		(size 0.4572)
		(drill 0.254)
		(layers "F.Cu" "B.Cu")
		(net "GND")
	)
	(via
		(at 430.274984 -296.37482)
		(size 0.4064)
		(drill 0.2032)
		(layers "F.Cu" "B.Cu")
		(net "GND")
	)
	(via
		(at 64.59347 -147.555204)
		(size 0.508)
		(drill 0.254)
		(layers "F.Cu" "B.Cu")
		(net "GND")
	)
	(via
		(at 375.7295 -342.439498)
		(size 0.4064)
		(drill 0.2032)
		(layers "F.Cu" "B.Cu")
		(net "GND")
	)
	(via
		(at 335.328006 -372.341902)
		(size 0.508)
		(drill 0.254)
		(layers "F.Cu" "B.Cu")
		(net "GND")
	)
	(via
		(at 222.154496 -311.026556)
		(size 0.508)
		(drill 0.254)
		(layers "F.Cu" "B.Cu")
		(net "GND")
	)
	(via
		(at 354.366576 -35.871912)
		(size 0.508)
		(drill 0.254)
		(layers "F.Cu" "B.Cu")
		(net "GND")
	)
	(via
		(at 270.80845 -349.219774)
		(size 0.4572)
		(drill 0.254)
		(layers "F.Cu" "B.Cu")
		(net "GND")
	)
	(via
		(at 180.693314 -147.555204)
		(size 0.508)
		(drill 0.254)
		(layers "F.Cu" "B.Cu")
		(net "GND")
	)
	(via
		(at 38.608 -417.82492)
		(size 0.508)
		(drill 0.254)
		(layers "F.Cu" "B.Cu")
		(net "GND")
	)
	(via
		(at 102.987094 -398.66824)
		(size 0.508)
		(drill 0.254)
		(layers "F.Cu" "B.Cu")
		(net "GND")
	)
	(via
		(at 359.535476 -290.68649)
		(size 0.508)
		(drill 0.254)
		(layers "F.Cu" "B.Cu")
		(net "GND")
	)
	(via
		(at 406.279858 -99.750372)
		(size 0.508)
		(drill 0.254)
		(layers "F.Cu" "B.Cu")
		(net "GND")
	)
	(via
		(at 127.33528 -291.32149)
		(size 0.508)
		(drill 0.254)
		(layers "F.Cu" "B.Cu")
		(net "GND")
	)
	(via
		(at 366.882172 -58.238644)
		(size 0.508)
		(drill 0.254)
		(layers "F.Cu" "B.Cu")
		(net "GND")
	)
	(via
		(at 402.972016 -49.574704)
		(size 0.508)
		(drill 0.254)
		(layers "F.Cu" "B.Cu")
		(net "GND")
	)
	(via
		(at 176.224946 -294.4749)
		(size 0.4064)
		(drill 0.2032)
		(layers "F.Cu" "B.Cu")
		(net "GND")
	)
	(via
		(at 180.975 -289.724846)
		(size 0.4064)
		(drill 0.2032)
		(layers "F.Cu" "B.Cu")
		(net "GND")
	)
	(via
		(at 160.771332 -31.652972)
		(size 0.508)
		(drill 0.254)
		(layers "F.Cu" "B.Cu")
		(net "GND")
	)
	(via
		(at 31.454344 -253.45644)
		(size 0.508)
		(drill 0.254)
		(layers "F.Cu" "B.Cu")
		(net "GND")
	)
	(via
		(at 66.299842 -273.099784)
		(size 0.4064)
		(drill 0.2032)
		(layers "F.Cu" "B.Cu")
		(net "GND")
	)
	(via
		(at 378.82195 -203.60005)
		(size 0.508)
		(drill 0.254)
		(layers "F.Cu" "B.Cu")
		(net "GND")
	)
	(via
		(at 37.133784 -102.716584)
		(size 0.508)
		(drill 0.254)
		(layers "F.Cu" "B.Cu")
		(net "GND")
	)
	(via
		(at 407.254202 -370.98478)
		(size 0.508)
		(drill 0.254)
		(layers "F.Cu" "B.Cu")
		(net "GND")
	)
	(via
		(at 165.751764 -125.955044)
		(size 0.508)
		(drill 0.254)
		(layers "F.Cu" "B.Cu")
		(net "GND")
	)
	(via
		(at 313.564016 -346.09913)
		(size 0.4572)
		(drill 0.254)
		(layers "F.Cu" "B.Cu")
		(net "GND")
	)
	(via
		(at 135.358632 -149.90826)
		(size 0.508)
		(drill 0.254)
		(layers "F.Cu" "B.Cu")
		(net "GND")
	)
	(via
		(at 16.837914 -414.985454)
		(size 0.508)
		(drill 0.254)
		(layers "F.Cu" "B.Cu")
		(net "GND")
	)
	(via
		(at 195.699888 -278.799798)
		(size 0.4064)
		(drill 0.2032)
		(layers "F.Cu" "B.Cu")
		(net "GND")
	)
	(via
		(at 435.227984 -354.098098)
		(size 0.4572)
		(drill 0.254)
		(layers "F.Cu" "B.Cu")
		(net "GND")
	)
	(via
		(at 258.393438 -283.131514)
		(size 0.508)
		(drill 0.254)
		(layers "F.Cu" "B.Cu")
		(net "GND")
	)
	(via
		(at 286.624776 -291.624766)
		(size 0.4064)
		(drill 0.2032)
		(layers "F.Cu" "B.Cu")
		(net "GND")
	)
	(via
		(at 49.1998 -274.049744)
		(size 0.4064)
		(drill 0.2032)
		(layers "F.Cu" "B.Cu")
		(net "GND")
	)
	(via
		(at 72.131682 -348.58579)
		(size 0.4064)
		(drill 0.2032)
		(layers "F.Cu" "B.Cu")
		(net "GND")
	)
	(via
		(at 420.774876 -292.574726)
		(size 0.4064)
		(drill 0.2032)
		(layers "F.Cu" "B.Cu")
		(net "GND")
	)
	(via
		(at 222.482664 -205.47711)
		(size 0.508)
		(drill 0.254)
		(layers "F.Cu" "B.Cu")
		(net "GND")
	)
	(via
		(at 397.120872 -358.391714)
		(size 0.4572)
		(drill 0.254)
		(layers "F.Cu" "B.Cu")
		(net "GND")
	)
	(via
		(at 396.0749 -284.974792)
		(size 0.4064)
		(drill 0.2032)
		(layers "F.Cu" "B.Cu")
		(net "GND")
	)
	(via
		(at 196.649848 -316.799722)
		(size 0.4064)
		(drill 0.2032)
		(layers "F.Cu" "B.Cu")
		(net "GND")
	)
	(via
		(at 346.493592 -227.586794)
		(size 0.4572)
		(drill 0.254)
		(layers "F.Cu" "B.Cu")
		(net "GND")
	)
	(via
		(at 117.210586 -287.51149)
		(size 0.508)
		(drill 0.254)
		(layers "F.Cu" "B.Cu")
		(net "GND")
	)
	(via
		(at 345.024964 -357.75773)
		(size 0.4064)
		(drill 0.2032)
		(layers "F.Cu" "B.Cu")
		(net "GND")
	)
	(via
		(at 178.124866 -305.874928)
		(size 0.4064)
		(drill 0.2032)
		(layers "F.Cu" "B.Cu")
		(net "GND")
	)
	(via
		(at 377.208288 -346.09913)
		(size 0.4572)
		(drill 0.254)
		(layers "F.Cu" "B.Cu")
		(net "GND")
	)
	(via
		(at 293.829994 -346.09913)
		(size 0.4572)
		(drill 0.254)
		(layers "F.Cu" "B.Cu")
		(net "GND")
	)
	(via
		(at 268.574774 -285.924752)
		(size 0.4064)
		(drill 0.2032)
		(layers "F.Cu" "B.Cu")
		(net "GND")
	)
	(via
		(at 131.57708 -341.805514)
		(size 0.4572)
		(drill 0.254)
		(layers "F.Cu" "B.Cu")
		(net "GND")
	)
	(via
		(at 388.127748 -380.141734)
		(size 0.508)
		(drill 0.254)
		(layers "F.Cu" "B.Cu")
		(net "GND")
	)
	(via
		(at 149.920198 -34.990278)
		(size 0.508)
		(drill 0.254)
		(layers "F.Cu" "B.Cu")
		(net "GND")
	)
	(via
		(at 421.161972 -348.58579)
		(size 0.4064)
		(drill 0.2032)
		(layers "F.Cu" "B.Cu")
		(net "GND")
	)
	(via
		(at 66.299842 -312.999882)
		(size 0.4064)
		(drill 0.2032)
		(layers "F.Cu" "B.Cu")
		(net "GND")
	)
	(via
		(at 282.349702 -276.899878)
		(size 0.4064)
		(drill 0.2032)
		(layers "F.Cu" "B.Cu")
		(net "GND")
	)
	(via
		(at 177.136298 -13.619226)
		(size 0.508)
		(drill 0.254)
		(layers "F.Cu" "B.Cu")
		(net "GND")
	)
	(via
		(at 260.943852 -353.465638)
		(size 0.508)
		(drill 0.254)
		(layers "F.Cu" "B.Cu")
		(net "GND")
	)
	(via
		(at 184.380886 -29.589984)
		(size 0.508)
		(drill 0.254)
		(layers "F.Cu" "B.Cu")
		(net "GND")
	)
	(via
		(at 318.151764 -354.732082)
		(size 0.4064)
		(drill 0.2032)
		(layers "F.Cu" "B.Cu")
		(net "GND")
	)
	(via
		(at 128.46812 -358.391714)
		(size 0.4572)
		(drill 0.254)
		(layers "F.Cu" "B.Cu")
		(net "GND")
	)
	(via
		(at 144.926812 -190.4492)
		(size 0.508)
		(drill 0.254)
		(layers "F.Cu" "B.Cu")
		(net "GND")
	)
	(via
		(at 282.17495 -74.58583)
		(size 0.508)
		(drill 0.254)
		(layers "F.Cu" "B.Cu")
		(net "GND")
	)
	(via
		(at 163.399978 -314.899802)
		(size 0.4064)
		(drill 0.2032)
		(layers "F.Cu" "B.Cu")
		(net "GND")
	)
	(via
		(at 287.099756 -276.899878)
		(size 0.4064)
		(drill 0.2032)
		(layers "F.Cu" "B.Cu")
		(net "GND")
	)
	(via
		(at 16.850868 -223.537018)
		(size 0.508)
		(drill 0.254)
		(layers "F.Cu" "B.Cu")
		(net "GND")
	)
	(via
		(at 304.687478 -26.360882)
		(size 0.508)
		(drill 0.254)
		(layers "F.Cu" "B.Cu")
		(net "GND")
	)
	(via
		(at 38.347904 -376.140218)
		(size 0.508)
		(drill 0.254)
		(layers "F.Cu" "B.Cu")
		(net "GND")
	)
	(via
		(at 341.927942 -397.038576)
		(size 0.508)
		(drill 0.254)
		(layers "F.Cu" "B.Cu")
		(net "GND")
	)
	(via
		(at 102.014782 -107.681776)
		(size 0.508)
		(drill 0.254)
		(layers "F.Cu" "B.Cu")
		(net "GND")
	)
	(via
		(at 75.74788 -404.940262)
		(size 0.508)
		(drill 0.254)
		(layers "F.Cu" "B.Cu")
		(net "GND")
	)
	(via
		(at 435.599332 -342.439498)
		(size 0.4064)
		(drill 0.2032)
		(layers "F.Cu" "B.Cu")
		(net "GND")
	)
	(via
		(at 134.044182 -215.144604)
		(size 0.508)
		(drill 0.254)
		(layers "F.Cu" "B.Cu")
		(net "GND")
	)
	(via
		(at 47.29988 -273.099784)
		(size 0.4064)
		(drill 0.2032)
		(layers "F.Cu" "B.Cu")
		(net "GND")
	)
	(via
		(at 330.3016 -86.263226)
		(size 0.508)
		(drill 0.254)
		(layers "F.Cu" "B.Cu")
		(net "GND")
	)
	(via
		(at 210.938364 -72.56526)
		(size 0.508)
		(drill 0.254)
		(layers "F.Cu" "B.Cu")
		(net "GND")
	)
	(via
		(at 140.486638 -48.874934)
		(size 0.508)
		(drill 0.254)
		(layers "F.Cu" "B.Cu")
		(net "GND")
	)
	(via
		(at 322.890896 -349.219774)
		(size 0.4572)
		(drill 0.254)
		(layers "F.Cu" "B.Cu")
		(net "GND")
	)
	(via
		(at 175.749966 -275.949918)
		(size 0.4064)
		(drill 0.2032)
		(layers "F.Cu" "B.Cu")
		(net "GND")
	)
	(via
		(at 4.84505 -70.720966)
		(size 0.508)
		(drill 0.254)
		(layers "F.Cu" "B.Cu")
		(net "GND")
	)
	(via
		(at 289.127692 -374.938544)
		(size 0.508)
		(drill 0.254)
		(layers "F.Cu" "B.Cu")
		(net "GND")
	)
	(via
		(at 339.09 -173.101)
		(size 0.508)
		(drill 0.254)
		(layers "F.Cu" "B.Cu")
		(net "GND")
	)
	(via
		(at 36.849812 -301.599854)
		(size 0.4064)
		(drill 0.2032)
		(layers "F.Cu" "B.Cu")
		(net "GND")
	)
	(via
		(at 211.80298 -223.99244)
		(size 0.508)
		(drill 0.254)
		(layers "F.Cu" "B.Cu")
		(net "GND")
	)
	(via
		(at 71.347838 -402.241766)
		(size 0.508)
		(drill 0.254)
		(layers "F.Cu" "B.Cu")
		(net "GND")
	)
	(via
		(at 463.037682 -92.977462)
		(size 0.508)
		(drill 0.254)
		(layers "F.Cu" "B.Cu")
		(net "GND")
	)
	(via
		(at 425.04995 -308.249828)
		(size 0.4064)
		(drill 0.2032)
		(layers "F.Cu" "B.Cu")
		(net "GND")
	)
	(via
		(at 105.22585 -130.357118)
		(size 0.508)
		(drill 0.254)
		(layers "F.Cu" "B.Cu")
		(net "GND")
	)
	(via
		(at 308.949852 -272.14957)
		(size 0.4064)
		(drill 0.2032)
		(layers "F.Cu" "B.Cu")
		(net "GND")
	)
	(via
		(at 43.974766 -286.874712)
		(size 0.4064)
		(drill 0.2032)
		(layers "F.Cu" "B.Cu")
		(net "GND")
	)
	(via
		(at 105.22585 -130.992118)
		(size 0.508)
		(drill 0.254)
		(layers "F.Cu" "B.Cu")
		(net "GND")
	)
	(via
		(at 197.445884 -344.831162)
		(size 0.4572)
		(drill 0.254)
		(layers "F.Cu" "B.Cu")
		(net "GND")
	)
	(via
		(at 214.308436 -256.229612)
		(size 0.508)
		(drill 0.254)
		(layers "F.Cu" "B.Cu")
		(net "GND")
	)
	(via
		(at 433.108354 -145.483326)
		(size 0.508)
		(drill 0.254)
		(layers "F.Cu" "B.Cu")
		(net "GND")
	)
	(via
		(at 425.527724 -371.038628)
		(size 0.508)
		(drill 0.254)
		(layers "F.Cu" "B.Cu")
		(net "GND")
	)
	(via
		(at 71.347838 -378.94006)
		(size 0.508)
		(drill 0.254)
		(layers "F.Cu" "B.Cu")
		(net "GND")
	)
	(via
		(at 97.850198 -94.227904)
		(size 0.508)
		(drill 0.254)
		(layers "F.Cu" "B.Cu")
		(net "GND")
	)
	(via
		(at 300.399704 -278.799798)
		(size 0.4064)
		(drill 0.2032)
		(layers "F.Cu" "B.Cu")
		(net "GND")
	)
	(via
		(at 404.149814 -280.699718)
		(size 0.4064)
		(drill 0.2032)
		(layers "F.Cu" "B.Cu")
		(net "GND")
	)
	(via
		(at 85.674962 -345.465146)
		(size 0.4064)
		(drill 0.2032)
		(layers "F.Cu" "B.Cu")
		(net "GND")
	)
	(via
		(at 117.547644 -403.34184)
		(size 0.4572)
		(drill 0.254)
		(layers "F.Cu" "B.Cu")
		(net "GND")
	)
	(via
		(at 314.649866 -317.749936)
		(size 0.4064)
		(drill 0.2032)
		(layers "F.Cu" "B.Cu")
		(net "GND")
	)
	(via
		(at 221.59976 -313.558682)
		(size 0.508)
		(drill 0.254)
		(layers "F.Cu" "B.Cu")
		(net "GND")
	)
	(via
		(at 419.349936 -316.799722)
		(size 0.4064)
		(drill 0.2032)
		(layers "F.Cu" "B.Cu")
		(net "GND")
	)
	(via
		(at 348.527878 -382.840484)
		(size 0.508)
		(drill 0.254)
		(layers "F.Cu" "B.Cu")
		(net "GND")
	)
	(via
		(at 70.130162 -354.732082)
		(size 0.4064)
		(drill 0.2032)
		(layers "F.Cu" "B.Cu")
		(net "GND")
	)
	(via
		(at 304.467006 -145.755106)
		(size 0.508)
		(drill 0.254)
		(layers "F.Cu" "B.Cu")
		(net "GND")
	)
	(via
		(at 49.67478 -304.924714)
		(size 0.4064)
		(drill 0.2032)
		(layers "F.Cu" "B.Cu")
		(net "GND")
	)
	(via
		(at 274.757896 -57.521094)
		(size 0.508)
		(drill 0.254)
		(layers "F.Cu" "B.Cu")
		(net "GND")
	)
	(via
		(at 182.547514 -154.755088)
		(size 0.508)
		(drill 0.254)
		(layers "F.Cu" "B.Cu")
		(net "GND")
	)
	(via
		(at 82.347816 -399.441924)
		(size 0.508)
		(drill 0.254)
		(layers "F.Cu" "B.Cu")
		(net "GND")
	)
	(via
		(at 282.872942 -348.58579)
		(size 0.4064)
		(drill 0.2032)
		(layers "F.Cu" "B.Cu")
		(net "GND")
	)
	(via
		(at 377.12777 -380.040134)
		(size 0.508)
		(drill 0.254)
		(layers "F.Cu" "B.Cu")
		(net "GND")
	)
	(via
		(at 53.474874 -305.874928)
		(size 0.4064)
		(drill 0.2032)
		(layers "F.Cu" "B.Cu")
		(net "GND")
	)
	(via
		(at 420.054532 -342.439498)
		(size 0.4064)
		(drill 0.2032)
		(layers "F.Cu" "B.Cu")
		(net "GND")
	)
	(via
		(at 429.198278 -134.566914)
		(size 0.508)
		(drill 0.254)
		(layers "F.Cu" "B.Cu")
		(net "GND")
	)
	(via
		(at 272.067274 -347.92793)
		(size 0.4572)
		(drill 0.254)
		(layers "F.Cu" "B.Cu")
		(net "GND")
	)
	(via
		(at 292.005258 -206.584042)
		(size 0.508)
		(drill 0.254)
		(layers "F.Cu" "B.Cu")
		(net "GND")
	)
	(via
		(at 73.239122 -345.465146)
		(size 0.4064)
		(drill 0.2032)
		(layers "F.Cu" "B.Cu")
		(net "GND")
	)
	(via
		(at 452.220838 -316.069726)
		(size 0.508)
		(drill 0.254)
		(layers "F.Cu" "B.Cu")
		(net "GND")
	)
	(via
		(at 45.39996 -301.599854)
		(size 0.4064)
		(drill 0.2032)
		(layers "F.Cu" "B.Cu")
		(net "GND")
	)
	(via
		(at 399.874994 -302.074834)
		(size 0.4064)
		(drill 0.2032)
		(layers "F.Cu" "B.Cu")
		(net "GND")
	)
	(via
		(at 344.093546 -218.787218)
		(size 0.4572)
		(drill 0.254)
		(layers "F.Cu" "B.Cu")
		(net "GND")
	)
	(via
		(at 430.749964 -307.299868)
		(size 0.4064)
		(drill 0.2032)
		(layers "F.Cu" "B.Cu")
		(net "GND")
	)
	(via
		(at 201.920094 -31.390336)
		(size 0.508)
		(drill 0.254)
		(layers "F.Cu" "B.Cu")
		(net "GND")
	)
	(via
		(at 117.209316 -89.55659)
		(size 0.508)
		(drill 0.254)
		(layers "F.Cu" "B.Cu")
		(net "GND")
	)
	(via
		(at 421.127682 -377.341892)
		(size 0.508)
		(drill 0.254)
		(layers "F.Cu" "B.Cu")
		(net "GND")
	)
	(via
		(at 150.59152 -130.236722)
		(size 0.508)
		(drill 0.254)
		(layers "F.Cu" "B.Cu")
		(net "GND")
	)
	(via
		(at 385.624832 -287.824926)
		(size 0.4064)
		(drill 0.2032)
		(layers "F.Cu" "B.Cu")
		(net "GND")
	)
	(via
		(at 300.047914 -349.219774)
		(size 0.4572)
		(drill 0.254)
		(layers "F.Cu" "B.Cu")
		(net "GND")
	)
	(via
		(at 52.85232 -106.045)
		(size 0.508)
		(drill 0.254)
		(layers "F.Cu" "B.Cu")
		(net "GND")
	)
	(via
		(at 308.474872 -298.27474)
		(size 0.4064)
		(drill 0.2032)
		(layers "F.Cu" "B.Cu")
		(net "GND")
	)
	(via
		(at 414.599882 -278.799798)
		(size 0.4064)
		(drill 0.2032)
		(layers "F.Cu" "B.Cu")
		(net "GND")
	)
	(via
		(at 314.174886 -296.37482)
		(size 0.4064)
		(drill 0.2032)
		(layers "F.Cu" "B.Cu")
		(net "GND")
	)
	(via
		(at 128.46812 -341.805514)
		(size 0.4572)
		(drill 0.254)
		(layers "F.Cu" "B.Cu")
		(net "GND")
	)
	(via
		(at 289.46221 -355.366066)
		(size 0.4572)
		(drill 0.254)
		(layers "F.Cu" "B.Cu")
		(net "GND")
	)
	(via
		(at 306.448206 -151.155146)
		(size 0.508)
		(drill 0.254)
		(layers "F.Cu" "B.Cu")
		(net "GND")
	)
	(via
		(at 339.09 -149.987)
		(size 0.508)
		(drill 0.254)
		(layers "F.Cu" "B.Cu")
		(net "GND")
	)
	(via
		(at 199.568562 -59.974734)
		(size 0.508)
		(drill 0.254)
		(layers "F.Cu" "B.Cu")
		(net "GND")
	)
	(via
		(at 182.030624 -164.192966)
		(size 0.508)
		(drill 0.254)
		(layers "F.Cu" "B.Cu")
		(net "GND")
	)
	(via
		(at 39.699946 -312.999882)
		(size 0.4064)
		(drill 0.2032)
		(layers "F.Cu" "B.Cu")
		(net "GND")
	)
	(via
		(at 270.601694 -122.091958)
		(size 0.508)
		(drill 0.254)
		(layers "F.Cu" "B.Cu")
		(net "GND")
	)
	(via
		(at 386.099812 -318.699896)
		(size 0.4064)
		(drill 0.2032)
		(layers "F.Cu" "B.Cu")
		(net "GND")
	)
	(via
		(at 36.374832 -284.024832)
		(size 0.4064)
		(drill 0.2032)
		(layers "F.Cu" "B.Cu")
		(net "GND")
	)
	(via
		(at 404.624794 -293.52494)
		(size 0.4064)
		(drill 0.2032)
		(layers "F.Cu" "B.Cu")
		(net "GND")
	)
	(via
		(at 389.424926 -285.924752)
		(size 0.4064)
		(drill 0.2032)
		(layers "F.Cu" "B.Cu")
		(net "GND")
	)
	(via
		(at 235.536486 -90.745818)
		(size 0.508)
		(drill 0.254)
		(layers "F.Cu" "B.Cu")
		(net "GND")
	)
	(via
		(at 223.013016 -310.999124)
		(size 0.508)
		(drill 0.254)
		(layers "F.Cu" "B.Cu")
		(net "GND")
	)
	(via
		(at 363.73308 -286.842454)
		(size 0.508)
		(drill 0.254)
		(layers "F.Cu" "B.Cu")
		(net "GND")
	)
	(via
		(at 185.573416 -72.56526)
		(size 0.508)
		(drill 0.254)
		(layers "F.Cu" "B.Cu")
		(net "GND")
	)
	(via
		(at 100.89388 -386.386578)
		(size 0.508)
		(drill 0.254)
		(layers "F.Cu" "B.Cu")
		(net "GND")
	)
	(via
		(at 357.352092 -13.613638)
		(size 0.508)
		(drill 0.254)
		(layers "F.Cu" "B.Cu")
		(net "GND")
	)
	(via
		(at 81.458562 -348.58579)
		(size 0.4064)
		(drill 0.2032)
		(layers "F.Cu" "B.Cu")
		(net "GND")
	)
	(via
		(at 83.540346 -151.42464)
		(size 0.508)
		(drill 0.254)
		(layers "F.Cu" "B.Cu")
		(net "GND")
	)
	(via
		(at 78.64983 -286.399732)
		(size 0.4064)
		(drill 0.2032)
		(layers "F.Cu" "B.Cu")
		(net "GND")
	)
	(via
		(at 236.121194 -218.101926)
		(size 0.4572)
		(drill 0.254)
		(layers "F.Cu" "B.Cu")
		(net "GND")
	)
	(via
		(at 75.799696 -276.899878)
		(size 0.4064)
		(drill 0.2032)
		(layers "F.Cu" "B.Cu")
		(net "GND")
	)
	(via
		(at 126.435104 -113.910364)
		(size 0.508)
		(drill 0.254)
		(layers "F.Cu" "B.Cu")
		(net "GND")
	)
	(via
		(at 104.448356 -226.595686)
		(size 0.508)
		(drill 0.254)
		(layers "F.Cu" "B.Cu")
		(net "GND")
	)
	(via
		(at 284.724856 -302.074834)
		(size 0.4064)
		(drill 0.2032)
		(layers "F.Cu" "B.Cu")
		(net "GND")
	)
	(via
		(at 165.947852 -371.038628)
		(size 0.508)
		(drill 0.254)
		(layers "F.Cu" "B.Cu")
		(net "GND")
	)
	(via
		(at 344.127836 -382.84023)
		(size 0.508)
		(drill 0.254)
		(layers "F.Cu" "B.Cu")
		(net "GND")
	)
	(via
		(at 198.075042 -299.224954)
		(size 0.4064)
		(drill 0.2032)
		(layers "F.Cu" "B.Cu")
		(net "GND")
	)
	(via
		(at 48.24984 -274.999958)
		(size 0.4064)
		(drill 0.2032)
		(layers "F.Cu" "B.Cu")
		(net "GND")
	)
	(via
		(at 132.38099 -33.19018)
		(size 0.508)
		(drill 0.254)
		(layers "F.Cu" "B.Cu")
		(net "GND")
	)
	(via
		(at 98.853752 -347.734382)
		(size 0.508)
		(drill 0.254)
		(layers "F.Cu" "B.Cu")
		(net "GND")
	)
	(via
		(at 390.327896 -376.140218)
		(size 0.508)
		(drill 0.254)
		(layers "F.Cu" "B.Cu")
		(net "GND")
	)
	(via
		(at 433.597812 -357.75773)
		(size 0.4064)
		(drill 0.2032)
		(layers "F.Cu" "B.Cu")
		(net "GND")
	)
	(via
		(at 437.07812 -355.366066)
		(size 0.4572)
		(drill 0.254)
		(layers "F.Cu" "B.Cu")
		(net "GND")
	)
	(via
		(at 302.299878 -277.849838)
		(size 0.4064)
		(drill 0.2032)
		(layers "F.Cu" "B.Cu")
		(net "GND")
	)
	(via
		(at 246.102124 -57.461404)
		(size 0.508)
		(drill 0.254)
		(layers "F.Cu" "B.Cu")
		(net "GND")
	)
	(via
		(at 111.664496 -344.831162)
		(size 0.4572)
		(drill 0.254)
		(layers "F.Cu" "B.Cu")
		(net "GND")
	)
	(via
		(at 386.16382 -345.465146)
		(size 0.4064)
		(drill 0.2032)
		(layers "F.Cu" "B.Cu")
		(net "GND")
	)
	(via
		(at 199.64019 -121.563384)
		(size 0.508)
		(drill 0.254)
		(layers "F.Cu" "B.Cu")
		(net "GND")
	)
	(via
		(at 405.768556 -59.974734)
		(size 0.508)
		(drill 0.254)
		(layers "F.Cu" "B.Cu")
		(net "GND")
	)
	(via
		(at 418.927788 -404.940262)
		(size 0.508)
		(drill 0.254)
		(layers "F.Cu" "B.Cu")
		(net "GND")
	)
	(via
		(at 20.765008 -342.439498)
		(size 0.4064)
		(drill 0.2032)
		(layers "F.Cu" "B.Cu")
		(net "GND")
	)
	(via
		(at 329.480164 -342.439498)
		(size 0.4064)
		(drill 0.2032)
		(layers "F.Cu" "B.Cu")
		(net "GND")
	)
	(via
		(at 180.693314 -134.845044)
		(size 0.508)
		(drill 0.254)
		(layers "F.Cu" "B.Cu")
		(net "GND")
	)
	(via
		(at 50.14976 -312.049922)
		(size 0.4064)
		(drill 0.2032)
		(layers "F.Cu" "B.Cu")
		(net "GND")
	)
	(via
		(at 36.14801 -378.94006)
		(size 0.508)
		(drill 0.254)
		(layers "F.Cu" "B.Cu")
		(net "GND")
	)
	(via
		(at 403.00656 -129.964942)
		(size 0.508)
		(drill 0.254)
		(layers "F.Cu" "B.Cu")
		(net "GND")
	)
	(via
		(at 34.00298 -283.893514)
		(size 0.508)
		(drill 0.254)
		(layers "F.Cu" "B.Cu")
		(net "GND")
	)
	(via
		(at 20.937982 -401.46986)
		(size 0.508)
		(drill 0.254)
		(layers "F.Cu" "B.Cu")
		(net "GND")
	)
	(via
		(at 409.374848 -287.824926)
		(size 0.4064)
		(drill 0.2032)
		(layers "F.Cu" "B.Cu")
		(net "GND")
	)
	(via
		(at 58.224928 -283.074872)
		(size 0.4064)
		(drill 0.2032)
		(layers "F.Cu" "B.Cu")
		(net "GND")
	)
	(via
		(at 152.94991 -300.649894)
		(size 0.4064)
		(drill 0.2032)
		(layers "F.Cu" "B.Cu")
		(net "GND")
	)
	(via
		(at 402.249894 -311.099962)
		(size 0.4064)
		(drill 0.2032)
		(layers "F.Cu" "B.Cu")
		(net "GND")
	)
	(via
		(at 280.13533 -358.391714)
		(size 0.4572)
		(drill 0.254)
		(layers "F.Cu" "B.Cu")
		(net "GND")
	)
	(via
		(at 404.624794 -305.874928)
		(size 0.4064)
		(drill 0.2032)
		(layers "F.Cu" "B.Cu")
		(net "GND")
	)
	(via
		(at 385.927854 -409.940252)
		(size 0.508)
		(drill 0.254)
		(layers "F.Cu" "B.Cu")
		(net "GND")
	)
	(via
		(at 292.79977 -273.099784)
		(size 0.4064)
		(drill 0.2032)
		(layers "F.Cu" "B.Cu")
		(net "GND")
	)
	(via
		(at 11.41984 -302.417226)
		(size 0.508)
		(drill 0.254)
		(layers "F.Cu" "B.Cu")
		(net "GND")
	)
	(via
		(at 294.69969 -274.049744)
		(size 0.4064)
		(drill 0.2032)
		(layers "F.Cu" "B.Cu")
		(net "GND")
	)
	(via
		(at 279.499822 -310.149748)
		(size 0.4064)
		(drill 0.2032)
		(layers "F.Cu" "B.Cu")
		(net "GND")
	)
	(via
		(at 56.715152 -60.601606)
		(size 0.508)
		(drill 0.254)
		(layers "F.Cu" "B.Cu")
		(net "GND")
	)
	(via
		(at 421.249856 -279.749758)
		(size 0.4064)
		(drill 0.2032)
		(layers "F.Cu" "B.Cu")
		(net "GND")
	)
	(via
		(at 288.99993 -314.899802)
		(size 0.4064)
		(drill 0.2032)
		(layers "F.Cu" "B.Cu")
		(net "GND")
	)
	(via
		(at 255.62941 -47.020734)
		(size 0.508)
		(drill 0.254)
		(layers "F.Cu" "B.Cu")
		(net "GND")
	)
	(via
		(at 37.324792 -294.4749)
		(size 0.4064)
		(drill 0.2032)
		(layers "F.Cu" "B.Cu")
		(net "GND")
	)
	(via
		(at 279.593548 -108.279946)
		(size 0.508)
		(drill 0.254)
		(layers "F.Cu" "B.Cu")
		(net "GND")
	)
	(via
		(at 425.99991 -287.349946)
		(size 0.4064)
		(drill 0.2032)
		(layers "F.Cu" "B.Cu")
		(net "GND")
	)
	(via
		(at 357.909368 -288.78149)
		(size 0.508)
		(drill 0.254)
		(layers "F.Cu" "B.Cu")
		(net "GND")
	)
	(via
		(at 184.77484 -303.024794)
		(size 0.4064)
		(drill 0.2032)
		(layers "F.Cu" "B.Cu")
		(net "GND")
	)
	(via
		(at 419.131242 -60.099194)
		(size 0.508)
		(drill 0.254)
		(layers "F.Cu" "B.Cu")
		(net "GND")
	)
	(via
		(at 167.732964 -125.955044)
		(size 0.508)
		(drill 0.254)
		(layers "F.Cu" "B.Cu")
		(net "GND")
	)
	(via
		(at 284.724856 -284.974792)
		(size 0.4064)
		(drill 0.2032)
		(layers "F.Cu" "B.Cu")
		(net "GND")
	)
	(via
		(at 285.687262 -133.564884)
		(size 0.508)
		(drill 0.254)
		(layers "F.Cu" "B.Cu")
		(net "GND")
	)
	(via
		(at 391.77341 -73.20026)
		(size 0.508)
		(drill 0.254)
		(layers "F.Cu" "B.Cu")
		(net "GND")
	)
	(via
		(at 400.824954 -284.024832)
		(size 0.4064)
		(drill 0.2032)
		(layers "F.Cu" "B.Cu")
		(net "GND")
	)
	(via
		(at 278.139144 -31.652972)
		(size 0.508)
		(drill 0.254)
		(layers "F.Cu" "B.Cu")
		(net "GND")
	)
	(via
		(at 218.724226 -291.61232)
		(size 0.508)
		(drill 0.254)
		(layers "F.Cu" "B.Cu")
		(net "GND")
	)
	(via
		(at 314.649866 -315.849762)
		(size 0.4064)
		(drill 0.2032)
		(layers "F.Cu" "B.Cu")
		(net "GND")
	)
	(via
		(at 154.501596 -124.43333)
		(size 0.508)
		(drill 0.254)
		(layers "F.Cu" "B.Cu")
		(net "GND")
	)
	(via
		(at 381.576072 -344.831162)
		(size 0.4572)
		(drill 0.254)
		(layers "F.Cu" "B.Cu")
		(net "GND")
	)
	(via
		(at 365.99622 -161.54527)
		(size 0.508)
		(drill 0.254)
		(layers "F.Cu" "B.Cu")
		(net "GND")
	)
	(via
		(at 309.424832 -289.724846)
		(size 0.4064)
		(drill 0.2032)
		(layers "F.Cu" "B.Cu")
		(net "GND")
	)
	(via
		(at 232.076244 -157.25648)
		(size 0.508)
		(drill 0.254)
		(layers "F.Cu" "B.Cu")
		(net "GND")
	)
	(via
		(at 84.808314 -135.114538)
		(size 0.508)
		(drill 0.254)
		(layers "F.Cu" "B.Cu")
		(net "GND")
	)
	(via
		(at 416.024822 -289.724846)
		(size 0.4064)
		(drill 0.2032)
		(layers "F.Cu" "B.Cu")
		(net "GND")
	)
	(via
		(at 368.120422 -122.195844)
		(size 0.508)
		(drill 0.254)
		(layers "F.Cu" "B.Cu")
		(net "GND")
	)
	(via
		(at 330.687426 -26.360882)
		(size 0.508)
		(drill 0.254)
		(layers "F.Cu" "B.Cu")
		(net "GND")
	)
	(via
		(at 241.252502 -85.551518)
		(size 0.508)
		(drill 0.254)
		(layers "F.Cu" "B.Cu")
		(net "GND")
	)
	(via
		(at 117.210586 -290.68649)
		(size 0.508)
		(drill 0.254)
		(layers "F.Cu" "B.Cu")
		(net "GND")
	)
	(via
		(at 292.57117 -357.123746)
		(size 0.4572)
		(drill 0.254)
		(layers "F.Cu" "B.Cu")
		(net "GND")
	)
	(via
		(at 288.915094 -60.601606)
		(size 0.508)
		(drill 0.254)
		(layers "F.Cu" "B.Cu")
		(net "GND")
	)
	(via
		(at 40.174926 -276.424898)
		(size 0.4064)
		(drill 0.2032)
		(layers "F.Cu" "B.Cu")
		(net "GND")
	)
	(via
		(at 402.249894 -281.649932)
		(size 0.4064)
		(drill 0.2032)
		(layers "F.Cu" "B.Cu")
		(net "GND")
	)
	(via
		(at 257.469386 -398.467834)
		(size 0.508)
		(drill 0.254)
		(layers "F.Cu" "B.Cu")
		(net "GND")
	)
	(via
		(at 305.624738 -301.124874)
		(size 0.4064)
		(drill 0.2032)
		(layers "F.Cu" "B.Cu")
		(net "GND")
	)
	(via
		(at 101.395022 -105.057194)
		(size 0.508)
		(drill 0.254)
		(layers "F.Cu" "B.Cu")
		(net "GND")
	)
	(via
		(at 269.049754 -312.999882)
		(size 0.4064)
		(drill 0.2032)
		(layers "F.Cu" "B.Cu")
		(net "GND")
	)
	(via
		(at 300.48073 -33.19018)
		(size 0.508)
		(drill 0.254)
		(layers "F.Cu" "B.Cu")
		(net "GND")
	)
	(via
		(at 210.03895 -199.898)
		(size 0.508)
		(drill 0.254)
		(layers "F.Cu" "B.Cu")
		(net "GND")
	)
	(via
		(at 159.661352 -60.099194)
		(size 0.508)
		(drill 0.254)
		(layers "F.Cu" "B.Cu")
		(net "GND")
	)
	(via
		(at 286.927798 -397.140176)
		(size 0.508)
		(drill 0.254)
		(layers "F.Cu" "B.Cu")
		(net "GND")
	)
	(via
		(at 162.0393 -32.911796)
		(size 0.508)
		(drill 0.254)
		(layers "F.Cu" "B.Cu")
		(net "GND")
	)
	(via
		(at 397.97482 -304.924714)
		(size 0.4064)
		(drill 0.2032)
		(layers "F.Cu" "B.Cu")
		(net "GND")
	)
	(via
		(at 361.19308 -286.842454)
		(size 0.508)
		(drill 0.254)
		(layers "F.Cu" "B.Cu")
		(net "GND")
	)
	(via
		(at 315.740288 -123.904502)
		(size 0.508)
		(drill 0.254)
		(layers "F.Cu" "B.Cu")
		(net "GND")
	)
	(via
		(at 409.849828 -276.899878)
		(size 0.4064)
		(drill 0.2032)
		(layers "F.Cu" "B.Cu")
		(net "GND")
	)
	(via
		(at 405.143208 -52.536852)
		(size 0.508)
		(drill 0.254)
		(layers "F.Cu" "B.Cu")
		(net "GND")
	)
	(via
		(at 425.527724 -378.83846)
		(size 0.508)
		(drill 0.254)
		(layers "F.Cu" "B.Cu")
		(net "GND")
	)
	(via
		(at 184.29986 -276.899878)
		(size 0.4064)
		(drill 0.2032)
		(layers "F.Cu" "B.Cu")
		(net "GND")
	)
	(via
		(at 425.901104 -357.123746)
		(size 0.4572)
		(drill 0.254)
		(layers "F.Cu" "B.Cu")
		(net "GND")
	)
	(via
		(at 186.77128 -32.911796)
		(size 0.508)
		(drill 0.254)
		(layers "F.Cu" "B.Cu")
		(net "GND")
	)
	(via
		(at 10.069322 -143.051276)
		(size 0.508)
		(drill 0.254)
		(layers "F.Cu" "B.Cu")
		(net "GND")
	)
	(via
		(at 290.721034 -347.951806)
		(size 0.4572)
		(drill 0.254)
		(layers "F.Cu" "B.Cu")
		(net "GND")
	)
	(via
		(at 178.599846 -310.149748)
		(size 0.4064)
		(drill 0.2032)
		(layers "F.Cu" "B.Cu")
		(net "GND")
	)
	(via
		(at 309.899812 -277.849838)
		(size 0.4064)
		(drill 0.2032)
		(layers "F.Cu" "B.Cu")
		(net "GND")
	)
	(via
		(at 132.297424 -284.333188)
		(size 0.49022)
		(drill 0.254)
		(layers "F.Cu" "B.Cu")
		(net "GND")
	)
	(via
		(at 65.81267 -123.635008)
		(size 0.508)
		(drill 0.254)
		(layers "F.Cu" "B.Cu")
		(net "GND")
	)
	(via
		(at 379.327918 -380.141734)
		(size 0.508)
		(drill 0.254)
		(layers "F.Cu" "B.Cu")
		(net "GND")
	)
	(via
		(at 168.148 -407.638504)
		(size 0.508)
		(drill 0.254)
		(layers "F.Cu" "B.Cu")
		(net "GND")
	)
	(via
		(at 360.707178 -267.338556)
		(size 0.508)
		(drill 0.254)
		(layers "F.Cu" "B.Cu")
		(net "GND")
	)
	(via
		(at 134.68604 -350.977454)
		(size 0.4572)
		(drill 0.254)
		(layers "F.Cu" "B.Cu")
		(net "GND")
	)
	(via
		(at 339.09 -185.039)
		(size 0.508)
		(drill 0.254)
		(layers "F.Cu" "B.Cu")
		(net "GND")
	)
	(via
		(at 67.312794 -102.439978)
		(size 0.508)
		(drill 0.254)
		(layers "F.Cu" "B.Cu")
		(net "GND")
	)
	(via
		(at 63.912242 -348.58579)
		(size 0.4064)
		(drill 0.2032)
		(layers "F.Cu" "B.Cu")
		(net "GND")
	)
	(via
		(at 282.872942 -351.611438)
		(size 0.4064)
		(drill 0.2032)
		(layers "F.Cu" "B.Cu")
		(net "GND")
	)
	(via
		(at 385.624832 -280.224738)
		(size 0.4064)
		(drill 0.2032)
		(layers "F.Cu" "B.Cu")
		(net "GND")
	)
	(via
		(at 174.747936 -407.24201)
		(size 0.508)
		(drill 0.254)
		(layers "F.Cu" "B.Cu")
		(net "GND")
	)
	(via
		(at 393.144502 -230.271574)
		(size 0.508)
		(drill 0.254)
		(layers "F.Cu" "B.Cu")
		(net "GND")
	)
	(via
		(at 427.379892 -345.465146)
		(size 0.4064)
		(drill 0.2032)
		(layers "F.Cu" "B.Cu")
		(net "GND")
	)
	(via
		(at 186.200034 -276.899878)
		(size 0.4064)
		(drill 0.2032)
		(layers "F.Cu" "B.Cu")
		(net "GND")
	)
	(via
		(at 357.06812 -54.238906)
		(size 0.508)
		(drill 0.254)
		(layers "F.Cu" "B.Cu")
		(net "GND")
	)
	(via
		(at 440.941206 -308.472332)
		(size 0.508)
		(drill 0.254)
		(layers "F.Cu" "B.Cu")
		(net "GND")
	)
	(via
		(at 117.522498 -292.781736)
		(size 0.508)
		(drill 0.254)
		(layers "F.Cu" "B.Cu")
		(net "GND")
	)
	(via
		(at 44.449746 -276.899878)
		(size 0.4064)
		(drill 0.2032)
		(layers "F.Cu" "B.Cu")
		(net "GND")
	)
	(via
		(at 390.327896 -409.940252)
		(size 0.508)
		(drill 0.254)
		(layers "F.Cu" "B.Cu")
		(net "GND")
	)
	(via
		(at 132.658104 -56.809894)
		(size 0.508)
		(drill 0.254)
		(layers "F.Cu" "B.Cu")
		(net "GND")
	)
	(via
		(at 121.331228 -293.424102)
		(size 0.508)
		(drill 0.254)
		(layers "F.Cu" "B.Cu")
		(net "GND")
	)
	(via
		(at 272.849848 -302.549814)
		(size 0.4064)
		(drill 0.2032)
		(layers "F.Cu" "B.Cu")
		(net "GND")
	)
	(via
		(at 315.042804 -342.439498)
		(size 0.4064)
		(drill 0.2032)
		(layers "F.Cu" "B.Cu")
		(net "GND")
	)
	(via
		(at 418.044884 -143.655796)
		(size 0.508)
		(drill 0.254)
		(layers "F.Cu" "B.Cu")
		(net "GND")
	)
	(via
		(at 334.067912 -341.805514)
		(size 0.4572)
		(drill 0.254)
		(layers "F.Cu" "B.Cu")
		(net "GND")
	)
	(via
		(at 429.927766 -404.838662)
		(size 0.508)
		(drill 0.254)
		(layers "F.Cu" "B.Cu")
		(net "GND")
	)
	(via
		(at 62.499748 -273.099784)
		(size 0.4064)
		(drill 0.2032)
		(layers "F.Cu" "B.Cu")
		(net "GND")
	)
	(via
		(at 336.154014 -103.69296)
		(size 0.508)
		(drill 0.254)
		(layers "F.Cu" "B.Cu")
		(net "GND")
	)
	(via
		(at 128.667764 -261.814564)
		(size 0.508)
		(drill 0.254)
		(layers "F.Cu" "B.Cu")
		(net "GND")
	)
	(via
		(at 70.099936 -273.099784)
		(size 0.4064)
		(drill 0.2032)
		(layers "F.Cu" "B.Cu")
		(net "GND")
	)
	(via
		(at 387.050026 -314.899802)
		(size 0.4064)
		(drill 0.2032)
		(layers "F.Cu" "B.Cu")
		(net "GND")
	)
	(via
		(at 399.874994 -294.4749)
		(size 0.4064)
		(drill 0.2032)
		(layers "F.Cu" "B.Cu")
		(net "GND")
	)
	(via
		(at 69.624956 -293.52494)
		(size 0.4064)
		(drill 0.2032)
		(layers "F.Cu" "B.Cu")
		(net "GND")
	)
	(via
		(at 347.838522 -282.910788)
		(size 0.49022)
		(drill 0.254)
		(layers "F.Cu" "B.Cu")
		(net "GND")
	)
	(via
		(at 261.971028 -86.600538)
		(size 0.508)
		(drill 0.254)
		(layers "F.Cu" "B.Cu")
		(net "GND")
	)
	(via
		(at 182.272432 -354.732082)
		(size 0.4064)
		(drill 0.2032)
		(layers "F.Cu" "B.Cu")
		(net "GND")
	)
	(via
		(at 393.351766 -138.964924)
		(size 0.508)
		(drill 0.254)
		(layers "F.Cu" "B.Cu")
		(net "GND")
	)
	(via
		(at 246.331994 -13.613638)
		(size 0.508)
		(drill 0.254)
		(layers "F.Cu" "B.Cu")
		(net "GND")
	)
	(via
		(at 290.42487 -296.37482)
		(size 0.4064)
		(drill 0.2032)
		(layers "F.Cu" "B.Cu")
		(net "GND")
	)
	(via
		(at 72.267064 -129.445004)
		(size 0.508)
		(drill 0.254)
		(layers "F.Cu" "B.Cu")
		(net "GND")
	)
	(via
		(at 57.087262 -370.24945)
		(size 0.4572)
		(drill 0.254)
		(layers "F.Cu" "B.Cu")
		(net "GND")
	)
	(via
		(at 406.178258 -95.399098)
		(size 0.508)
		(drill 0.254)
		(layers "F.Cu" "B.Cu")
		(net "GND")
	)
	(via
		(at 332.217776 -349.219774)
		(size 0.4572)
		(drill 0.254)
		(layers "F.Cu" "B.Cu")
		(net "GND")
	)
	(via
		(at 16.280892 -31.390082)
		(size 0.508)
		(drill 0.254)
		(layers "F.Cu" "B.Cu")
		(net "GND")
	)
	(via
		(at 160.73882 -23.880318)
		(size 0.508)
		(drill 0.254)
		(layers "F.Cu" "B.Cu")
		(net "GND")
	)
	(via
		(at 124.147834 -407.638504)
		(size 0.508)
		(drill 0.254)
		(layers "F.Cu" "B.Cu")
		(net "GND")
	)
	(via
		(at 121.240296 -27.729688)
		(size 0.508)
		(drill 0.254)
		(layers "F.Cu" "B.Cu")
		(net "GND")
	)
	(via
		(at 293.527734 -377.341892)
		(size 0.508)
		(drill 0.254)
		(layers "F.Cu" "B.Cu")
		(net "GND")
	)
	(via
		(at 410.356304 -349.219774)
		(size 0.4572)
		(drill 0.254)
		(layers "F.Cu" "B.Cu")
		(net "GND")
	)
	(via
		(at 400.824954 -285.924752)
		(size 0.4064)
		(drill 0.2032)
		(layers "F.Cu" "B.Cu")
		(net "GND")
	)
	(via
		(at 356.755192 -33.19018)
		(size 0.508)
		(drill 0.254)
		(layers "F.Cu" "B.Cu")
		(net "GND")
	)
	(via
		(at 67.66687 -129.445004)
		(size 0.508)
		(drill 0.254)
		(layers "F.Cu" "B.Cu")
		(net "GND")
	)
	(via
		(at 78.64983 -309.199788)
		(size 0.4064)
		(drill 0.2032)
		(layers "F.Cu" "B.Cu")
		(net "GND")
	)
	(via
		(at 385.927854 -403.34184)
		(size 0.508)
		(drill 0.254)
		(layers "F.Cu" "B.Cu")
		(net "GND")
	)
	(via
		(at 419.824916 -297.32478)
		(size 0.4064)
		(drill 0.2032)
		(layers "F.Cu" "B.Cu")
		(net "GND")
	)
	(via
		(at 404.149814 -310.149748)
		(size 0.4064)
		(drill 0.2032)
		(layers "F.Cu" "B.Cu")
		(net "GND")
	)
	(via
		(at 406.279858 -104.830372)
		(size 0.508)
		(drill 0.254)
		(layers "F.Cu" "B.Cu")
		(net "GND")
	)
	(via
		(at 68.674742 -299.224954)
		(size 0.4064)
		(drill 0.2032)
		(layers "F.Cu" "B.Cu")
		(net "GND")
	)
	(via
		(at 174.747936 -376.140218)
		(size 0.508)
		(drill 0.254)
		(layers "F.Cu" "B.Cu")
		(net "GND")
	)
	(via
		(at 395.59992 -273.099784)
		(size 0.4064)
		(drill 0.2032)
		(layers "F.Cu" "B.Cu")
		(net "GND")
	)
	(via
		(at 197.600062 -282.599892)
		(size 0.4064)
		(drill 0.2032)
		(layers "F.Cu" "B.Cu")
		(net "GND")
	)
	(via
		(at 49.205642 -166.863268)
		(size 0.508)
		(drill 0.254)
		(layers "F.Cu" "B.Cu")
		(net "GND")
	)
	(via
		(at 304.674778 -301.124874)
		(size 0.4064)
		(drill 0.2032)
		(layers "F.Cu" "B.Cu")
		(net "GND")
	)
	(via
		(at 160.138364 -357.123746)
		(size 0.4572)
		(drill 0.254)
		(layers "F.Cu" "B.Cu")
		(net "GND")
	)
	(via
		(at 119.747792 -381.638556)
		(size 0.508)
		(drill 0.254)
		(layers "F.Cu" "B.Cu")
		(net "GND")
	)
	(via
		(at 295.727882 -403.738588)
		(size 0.508)
		(drill 0.254)
		(layers "F.Cu" "B.Cu")
		(net "GND")
	)
	(via
		(at 314.072016 -33.857692)
		(size 0.508)
		(drill 0.254)
		(layers "F.Cu" "B.Cu")
		(net "GND")
	)
	(via
		(at 115.34775 -402.241766)
		(size 0.4572)
		(drill 0.254)
		(layers "F.Cu" "B.Cu")
		(net "GND")
	)
	(via
		(at 423.32783 -371.140228)
		(size 0.508)
		(drill 0.254)
		(layers "F.Cu" "B.Cu")
		(net "GND")
	)
	(via
		(at 401.70862 -348.58579)
		(size 0.4064)
		(drill 0.2032)
		(layers "F.Cu" "B.Cu")
		(net "GND")
	)
	(via
		(at 128.547622 -376.241818)
		(size 0.4572)
		(drill 0.254)
		(layers "F.Cu" "B.Cu")
		(net "GND")
	)
	(via
		(at 311.799732 -310.149748)
		(size 0.4064)
		(drill 0.2032)
		(layers "F.Cu" "B.Cu")
		(net "GND")
	)
	(via
		(at 156.000704 -142.748762)
		(size 0.508)
		(drill 0.254)
		(layers "F.Cu" "B.Cu")
		(net "GND")
	)
	(via
		(at 6.129528 -243.370354)
		(size 0.508)
		(drill 0.254)
		(layers "F.Cu" "B.Cu")
		(net "GND")
	)
	(via
		(at 81.499964 -305.399948)
		(size 0.4064)
		(drill 0.2032)
		(layers "F.Cu" "B.Cu")
		(net "GND")
	)
	(via
		(at 51.63312 -106.045)
		(size 0.508)
		(drill 0.254)
		(layers "F.Cu" "B.Cu")
		(net "GND")
	)
	(via
		(at 138.166348 -357.75773)
		(size 0.4064)
		(drill 0.2032)
		(layers "F.Cu" "B.Cu")
		(net "GND")
	)
	(via
		(at 113.976404 -164.20592)
		(size 0.508)
		(drill 0.254)
		(layers "F.Cu" "B.Cu")
		(net "GND")
	)
	(via
		(at 270.474948 -290.674806)
		(size 0.4064)
		(drill 0.2032)
		(layers "F.Cu" "B.Cu")
		(net "GND")
	)
	(via
		(at 269.333726 -133.301994)
		(size 0.508)
		(drill 0.254)
		(layers "F.Cu" "B.Cu")
		(net "GND")
	)
	(via
		(at 383.72796 -395.938502)
		(size 0.508)
		(drill 0.254)
		(layers "F.Cu" "B.Cu")
		(net "GND")
	)
	(via
		(at 295.727882 -406.141936)
		(size 0.508)
		(drill 0.254)
		(layers "F.Cu" "B.Cu")
		(net "GND")
	)
	(via
		(at 387.793992 -355.366066)
		(size 0.4572)
		(drill 0.254)
		(layers "F.Cu" "B.Cu")
		(net "GND")
	)
	(via
		(at 281.394154 -343.073482)
		(size 0.4572)
		(drill 0.254)
		(layers "F.Cu" "B.Cu")
		(net "GND")
	)
	(via
		(at 74.098404 -37.201094)
		(size 0.508)
		(drill 0.254)
		(layers "F.Cu" "B.Cu")
		(net "GND")
	)
	(via
		(at 158.649924 -300.649894)
		(size 0.4064)
		(drill 0.2032)
		(layers "F.Cu" "B.Cu")
		(net "GND")
	)
	(via
		(at 67.39255 -357.123746)
		(size 0.4572)
		(drill 0.254)
		(layers "F.Cu" "B.Cu")
		(net "GND")
	)
	(via
		(at 16.38173 -133.972046)
		(size 0.508)
		(drill 0.254)
		(layers "F.Cu" "B.Cu")
		(net "GND")
	)
	(via
		(at 299.749972 -110.514892)
		(size 0.508)
		(drill 0.254)
		(layers "F.Cu" "B.Cu")
		(net "GND")
	)
	(via
		(at 177.649886 -315.849762)
		(size 0.4064)
		(drill 0.2032)
		(layers "F.Cu" "B.Cu")
		(net "GND")
	)
	(via
		(at 168.150032 -279.749758)
		(size 0.4064)
		(drill 0.2032)
		(layers "F.Cu" "B.Cu")
		(net "GND")
	)
	(via
		(at 313.699906 -309.199788)
		(size 0.4064)
		(drill 0.2032)
		(layers "F.Cu" "B.Cu")
		(net "GND")
	)
	(via
		(at 252.763782 -225.679762)
		(size 0.508)
		(drill 0.254)
		(layers "F.Cu" "B.Cu")
		(net "GND")
	)
	(via
		(at 18.831306 -60.099194)
		(size 0.508)
		(drill 0.254)
		(layers "F.Cu" "B.Cu")
		(net "GND")
	)
	(via
		(at 69.64807 -129.445004)
		(size 0.508)
		(drill 0.254)
		(layers "F.Cu" "B.Cu")
		(net "GND")
	)
	(via
		(at 301.349918 -280.699718)
		(size 0.4064)
		(drill 0.2032)
		(layers "F.Cu" "B.Cu")
		(net "GND")
	)
	(via
		(at 53.48732 -120.555004)
		(size 0.508)
		(drill 0.254)
		(layers "F.Cu" "B.Cu")
		(net "GND")
	)
	(via
		(at 194.708272 -342.439498)
		(size 0.4064)
		(drill 0.2032)
		(layers "F.Cu" "B.Cu")
		(net "GND")
	)
	(via
		(at 344.778838 -293.424102)
		(size 0.508)
		(drill 0.254)
		(layers "F.Cu" "B.Cu")
		(net "GND")
	)
	(via
		(at 16.420846 -210.011772)
		(size 0.508)
		(drill 0.254)
		(layers "F.Cu" "B.Cu")
		(net "GND")
	)
	(via
		(at 432.12766 -397.140176)
		(size 0.508)
		(drill 0.254)
		(layers "F.Cu" "B.Cu")
		(net "GND")
	)
	(via
		(at 425.527724 -372.240302)
		(size 0.508)
		(drill 0.254)
		(layers "F.Cu" "B.Cu")
		(net "GND")
	)
	(via
		(at 401.70862 -345.465146)
		(size 0.4064)
		(drill 0.2032)
		(layers "F.Cu" "B.Cu")
		(net "GND")
	)
	(via
		(at 401.299934 -312.999882)
		(size 0.4064)
		(drill 0.2032)
		(layers "F.Cu" "B.Cu")
		(net "GND")
	)
	(via
		(at 70.731126 -6.292342)
		(size 0.508)
		(drill 0.254)
		(layers "F.Cu" "B.Cu")
		(net "GND")
	)
	(via
		(at 343.511378 -287.51149)
		(size 0.508)
		(drill 0.254)
		(layers "F.Cu" "B.Cu")
		(net "GND")
	)
	(via
		(at 285.199836 -278.799798)
		(size 0.4064)
		(drill 0.2032)
		(layers "F.Cu" "B.Cu")
		(net "GND")
	)
	(via
		(at 298.974764 -306.824888)
		(size 0.4064)
		(drill 0.2032)
		(layers "F.Cu" "B.Cu")
		(net "GND")
	)
	(via
		(at 163.399978 -318.699896)
		(size 0.4064)
		(drill 0.2032)
		(layers "F.Cu" "B.Cu")
		(net "GND")
	)
	(via
		(at 48.251364 -47.03191)
		(size 0.508)
		(drill 0.254)
		(layers "F.Cu" "B.Cu")
		(net "GND")
	)
	(via
		(at 307.049932 -312.049922)
		(size 0.4064)
		(drill 0.2032)
		(layers "F.Cu" "B.Cu")
		(net "GND")
	)
	(via
		(at 176.224946 -302.074834)
		(size 0.4064)
		(drill 0.2032)
		(layers "F.Cu" "B.Cu")
		(net "GND")
	)
	(via
		(at 70.574916 -287.824926)
		(size 0.4064)
		(drill 0.2032)
		(layers "F.Cu" "B.Cu")
		(net "GND")
	)
	(via
		(at 381.492506 -11.372342)
		(size 0.508)
		(drill 0.254)
		(layers "F.Cu" "B.Cu")
		(net "GND")
	)
	(via
		(at 279.024842 -306.824888)
		(size 0.4064)
		(drill 0.2032)
		(layers "F.Cu" "B.Cu")
		(net "GND")
	)
	(via
		(at 346.327984 -381.241808)
		(size 0.508)
		(drill 0.254)
		(layers "F.Cu" "B.Cu")
		(net "GND")
	)
	(via
		(at 278.074882 -288.774886)
		(size 0.4064)
		(drill 0.2032)
		(layers "F.Cu" "B.Cu")
		(net "GND")
	)
	(via
		(at 384.685032 -346.09913)
		(size 0.4572)
		(drill 0.254)
		(layers "F.Cu" "B.Cu")
		(net "GND")
	)
	(via
		(at 411.571186 -196.80682)
		(size 0.508)
		(drill 0.254)
		(layers "F.Cu" "B.Cu")
		(net "GND")
	)
	(via
		(at 382.30302 -299.895514)
		(size 0.508)
		(drill 0.254)
		(layers "F.Cu" "B.Cu")
		(net "GND")
	)
	(via
		(at 438.13222 -124.108972)
		(size 0.508)
		(drill 0.254)
		(layers "F.Cu" "B.Cu")
		(net "GND")
	)
	(via
		(at 161.500058 -312.999882)
		(size 0.4064)
		(drill 0.2032)
		(layers "F.Cu" "B.Cu")
		(net "GND")
	)
	(via
		(at 354.858066 -137.344404)
		(size 0.508)
		(drill 0.254)
		(layers "F.Cu" "B.Cu")
		(net "GND")
	)
	(via
		(at 44.671234 -28.05303)
		(size 0.508)
		(drill 0.254)
		(layers "F.Cu" "B.Cu")
		(net "GND")
	)
	(via
		(at 72.474836 -300.174914)
		(size 0.4064)
		(drill 0.2032)
		(layers "F.Cu" "B.Cu")
		(net "GND")
	)
	(via
		(at 189.049914 -314.899802)
		(size 0.4064)
		(drill 0.2032)
		(layers "F.Cu" "B.Cu")
		(net "GND")
	)
	(via
		(at 195.224908 -294.4749)
		(size 0.4064)
		(drill 0.2032)
		(layers "F.Cu" "B.Cu")
		(net "GND")
	)
	(via
		(at 281.629104 -107.407456)
		(size 0.508)
		(drill 0.254)
		(layers "F.Cu" "B.Cu")
		(net "GND")
	)
	(via
		(at 419.368224 -48.753014)
		(size 0.508)
		(drill 0.254)
		(layers "F.Cu" "B.Cu")
		(net "GND")
	)
	(via
		(at 88.947752 -402.241766)
		(size 0.508)
		(drill 0.254)
		(layers "F.Cu" "B.Cu")
		(net "GND")
	)
	(via
		(at 199.284844 -105.664)
		(size 0.508)
		(drill 0.254)
		(layers "F.Cu" "B.Cu")
		(net "GND")
	)
	(via
		(at 131.129024 -238.545878)
		(size 0.508)
		(drill 0.254)
		(layers "F.Cu" "B.Cu")
		(net "GND")
	)
	(via
		(at 106.089958 -267.26261)
		(size 0.508)
		(drill 0.254)
		(layers "F.Cu" "B.Cu")
		(net "GND")
	)
	(via
		(at 285.674816 -302.074834)
		(size 0.4064)
		(drill 0.2032)
		(layers "F.Cu" "B.Cu")
		(net "GND")
	)
	(via
		(at 246.670576 -230.878888)
		(size 0.508)
		(drill 0.254)
		(layers "F.Cu" "B.Cu")
		(net "GND")
	)
	(via
		(at 335.560416 -244.957092)
		(size 0.508)
		(drill 0.254)
		(layers "F.Cu" "B.Cu")
		(net "GND")
	)
	(via
		(at 232.51033 -90.745818)
		(size 0.508)
		(drill 0.254)
		(layers "F.Cu" "B.Cu")
		(net "GND")
	)
	(via
		(at 188.819282 -46.893226)
		(size 0.508)
		(drill 0.254)
		(layers "F.Cu" "B.Cu")
		(net "GND")
	)
	(via
		(at 186.200034 -277.849838)
		(size 0.4064)
		(drill 0.2032)
		(layers "F.Cu" "B.Cu")
		(net "GND")
	)
	(via
		(at 79.59979 -318.699896)
		(size 0.4064)
		(drill 0.2032)
		(layers "F.Cu" "B.Cu")
		(net "GND")
	)
	(via
		(at 33.103312 -60.627006)
		(size 0.508)
		(drill 0.254)
		(layers "F.Cu" "B.Cu")
		(net "GND")
	)
	(via
		(at 441.445904 -341.805514)
		(size 0.4572)
		(drill 0.254)
		(layers "F.Cu" "B.Cu")
		(net "GND")
	)
	(via
		(at 277.251668 -106.045)
		(size 0.508)
		(drill 0.254)
		(layers "F.Cu" "B.Cu")
		(net "GND")
	)
	(via
		(at 197.972172 -33.857692)
		(size 0.508)
		(drill 0.254)
		(layers "F.Cu" "B.Cu")
		(net "GND")
	)
	(via
		(at 41.599866 -310.149748)
		(size 0.4064)
		(drill 0.2032)
		(layers "F.Cu" "B.Cu")
		(net "GND")
	)
	(via
		(at 414.58642 -83.9216)
		(size 0.508)
		(drill 0.254)
		(layers "F.Cu" "B.Cu")
		(net "GND")
	)
	(via
		(at 119.14124 -358.391714)
		(size 0.4572)
		(drill 0.254)
		(layers "F.Cu" "B.Cu")
		(net "GND")
	)
	(via
		(at 84.808314 -132.77342)
		(size 0.508)
		(drill 0.254)
		(layers "F.Cu" "B.Cu")
		(net "GND")
	)
	(via
		(at 311.799986 -273.099784)
		(size 0.4064)
		(drill 0.2032)
		(layers "F.Cu" "B.Cu")
		(net "GND")
	)
	(via
		(at 238.404654 -310.315356)
		(size 0.508)
		(drill 0.254)
		(layers "F.Cu" "B.Cu")
		(net "GND")
	)
	(via
		(at 408.726132 -345.465146)
		(size 0.4064)
		(drill 0.2032)
		(layers "F.Cu" "B.Cu")
		(net "GND")
	)
	(via
		(at 377.208288 -358.391714)
		(size 0.4572)
		(drill 0.254)
		(layers "F.Cu" "B.Cu")
		(net "GND")
	)
	(via
		(at 284.874462 -348.58579)
		(size 0.4064)
		(drill 0.2032)
		(layers "F.Cu" "B.Cu")
		(net "GND")
	)
	(via
		(at 14.248892 -27.79014)
		(size 0.508)
		(drill 0.254)
		(layers "F.Cu" "B.Cu")
		(net "GND")
	)
	(via
		(at 364.47095 -307.877718)
		(size 0.508)
		(drill 0.254)
		(layers "F.Cu" "B.Cu")
		(net "GND")
	)
	(via
		(at 269.999714 -311.099962)
		(size 0.4064)
		(drill 0.2032)
		(layers "F.Cu" "B.Cu")
		(net "GND")
	)
	(via
		(at 230.376984 -134.799578)
		(size 0.508)
		(drill 0.254)
		(layers "F.Cu" "B.Cu")
		(net "GND")
	)
	(via
		(at 414.11271 -154.755088)
		(size 0.508)
		(drill 0.254)
		(layers "F.Cu" "B.Cu")
		(net "GND")
	)
	(via
		(at 53.714142 -371.508274)
		(size 0.4572)
		(drill 0.254)
		(layers "F.Cu" "B.Cu")
		(net "GND")
	)
	(via
		(at 394.38326 -351.611438)
		(size 0.4064)
		(drill 0.2032)
		(layers "F.Cu" "B.Cu")
		(net "GND")
	)
	(via
		(at 69.149976 -275.949918)
		(size 0.4064)
		(drill 0.2032)
		(layers "F.Cu" "B.Cu")
		(net "GND")
	)
	(via
		(at 300.48073 -34.990024)
		(size 0.508)
		(drill 0.254)
		(layers "F.Cu" "B.Cu")
		(net "GND")
	)
	(via
		(at 113.677446 -305.972718)
		(size 0.508)
		(drill 0.254)
		(layers "F.Cu" "B.Cu")
		(net "GND")
	)
	(via
		(at 35.899344 -314.899548)
		(size 0.4064)
		(drill 0.2032)
		(layers "F.Cu" "B.Cu")
		(net "GND")
	)
	(via
		(at 134.283196 -245.072154)
		(size 0.508)
		(drill 0.254)
		(layers "F.Cu" "B.Cu")
		(net "GND")
	)
	(via
		(at 86.747858 -382.73863)
		(size 0.508)
		(drill 0.254)
		(layers "F.Cu" "B.Cu")
		(net "GND")
	)
	(via
		(at 184.77484 -307.774848)
		(size 0.4064)
		(drill 0.2032)
		(layers "F.Cu" "B.Cu")
		(net "GND")
	)
	(via
		(at 319.781936 -344.831162)
		(size 0.4572)
		(drill 0.254)
		(layers "F.Cu" "B.Cu")
		(net "GND")
	)
	(via
		(at 246.50319 -287.74898)
		(size 0.508)
		(drill 0.254)
		(layers "F.Cu" "B.Cu")
		(net "GND")
	)
	(via
		(at 436.527702 -410.041852)
		(size 0.508)
		(drill 0.254)
		(layers "F.Cu" "B.Cu")
		(net "GND")
	)
	(via
		(at 19.820382 -120.925844)
		(size 0.508)
		(drill 0.254)
		(layers "F.Cu" "B.Cu")
		(net "GND")
	)
	(via
		(at 316.101984 -27.729688)
		(size 0.508)
		(drill 0.254)
		(layers "F.Cu" "B.Cu")
		(net "GND")
	)
	(via
		(at 0.77089 -324.621144)
		(size 0.508)
		(drill 0.254)
		(layers "F.Cu" "B.Cu")
		(net "GND")
	)
	(via
		(at 403.00656 -102.444804)
		(size 0.508)
		(drill 0.254)
		(layers "F.Cu" "B.Cu")
		(net "GND")
	)
	(via
		(at 392.420602 -63.218314)
		(size 0.508)
		(drill 0.254)
		(layers "F.Cu" "B.Cu")
		(net "GND")
	)
	(via
		(at 197.343522 -81.698846)
		(size 0.508)
		(drill 0.254)
		(layers "F.Cu" "B.Cu")
		(net "GND")
	)
	(via
		(at 279.232868 -98.845116)
		(size 0.508)
		(drill 0.254)
		(layers "F.Cu" "B.Cu")
		(net "GND")
	)
	(via
		(at 121.798334 -307.18887)
		(size 0.508)
		(drill 0.254)
		(layers "F.Cu" "B.Cu")
		(net "GND")
	)
	(via
		(at 334.174846 -74.58583)
		(size 0.508)
		(drill 0.254)
		(layers "F.Cu" "B.Cu")
		(net "GND")
	)
	(via
		(at 251.223272 -135.369046)
		(size 0.508)
		(drill 0.254)
		(layers "F.Cu" "B.Cu")
		(net "GND")
	)
	(via
		(at 421.249856 -311.099962)
		(size 0.4064)
		(drill 0.2032)
		(layers "F.Cu" "B.Cu")
		(net "GND")
	)
	(via
		(at 120.991376 -347.951806)
		(size 0.4572)
		(drill 0.254)
		(layers "F.Cu" "B.Cu")
		(net "GND")
	)
	(via
		(at 417.916868 -244.37848)
		(size 0.508)
		(drill 0.254)
		(layers "F.Cu" "B.Cu")
		(net "GND")
	)
	(via
		(at 68.674742 -298.27474)
		(size 0.4064)
		(drill 0.2032)
		(layers "F.Cu" "B.Cu")
		(net "GND")
	)
	(via
		(at 328.871072 -32.911796)
		(size 0.508)
		(drill 0.254)
		(layers "F.Cu" "B.Cu")
		(net "GND")
	)
	(via
		(at 343.023444 -357.75773)
		(size 0.4064)
		(drill 0.2032)
		(layers "F.Cu" "B.Cu")
		(net "GND")
	)
	(via
		(at 49.340008 -73.23963)
		(size 0.508)
		(drill 0.254)
		(layers "F.Cu" "B.Cu")
		(net "GND")
	)
	(via
		(at 346.972382 -285.267654)
		(size 0.508)
		(drill 0.254)
		(layers "F.Cu" "B.Cu")
		(net "GND")
	)
	(via
		(at 171.949872 -276.899878)
		(size 0.4064)
		(drill 0.2032)
		(layers "F.Cu" "B.Cu")
		(net "GND")
	)
	(via
		(at 288.52495 -296.37482)
		(size 0.4064)
		(drill 0.2032)
		(layers "F.Cu" "B.Cu")
		(net "GND")
	)
	(via
		(at 342.23452 -269.366492)
		(size 0.508)
		(drill 0.254)
		(layers "F.Cu" "B.Cu")
		(net "GND")
	)
	(via
		(at 157.224984 -276.424898)
		(size 0.4064)
		(drill 0.2032)
		(layers "F.Cu" "B.Cu")
		(net "GND")
	)
	(via
		(at 96.731074 -11.372342)
		(size 0.508)
		(drill 0.254)
		(layers "F.Cu" "B.Cu")
		(net "GND")
	)
	(via
		(at 295.68013 -355.366066)
		(size 0.4572)
		(drill 0.254)
		(layers "F.Cu" "B.Cu")
		(net "GND")
	)
	(via
		(at 112.92332 -346.09913)
		(size 0.4572)
		(drill 0.254)
		(layers "F.Cu" "B.Cu")
		(net "GND")
	)
	(via
		(at 292.01999 -34.990278)
		(size 0.508)
		(drill 0.254)
		(layers "F.Cu" "B.Cu")
		(net "GND")
	)
	(via
		(at 434.327808 -399.441924)
		(size 0.508)
		(drill 0.254)
		(layers "F.Cu" "B.Cu")
		(net "GND")
	)
	(via
		(at 427.89983 -277.849838)
		(size 0.4064)
		(drill 0.2032)
		(layers "F.Cu" "B.Cu")
		(net "GND")
	)
	(via
		(at 369.25885 -206.510128)
		(size 0.508)
		(drill 0.254)
		(layers "F.Cu" "B.Cu")
		(net "GND")
	)
	(via
		(at 335.328006 -377.738386)
		(size 0.508)
		(drill 0.254)
		(layers "F.Cu" "B.Cu")
		(net "GND")
	)
	(via
		(at 367.547398 -148.718778)
		(size 0.508)
		(drill 0.254)
		(layers "F.Cu" "B.Cu")
		(net "GND")
	)
	(via
		(at 227.067872 -221.904052)
		(size 0.4572)
		(drill 0.254)
		(layers "F.Cu" "B.Cu")
		(net "GND")
	)
	(via
		(at 364.620048 -131.312666)
		(size 0.508)
		(drill 0.254)
		(layers "F.Cu" "B.Cu")
		(net "GND")
	)
	(via
		(at 163.747958 -377.738386)
		(size 0.508)
		(drill 0.254)
		(layers "F.Cu" "B.Cu")
		(net "GND")
	)
	(via
		(at 63.924942 -300.174914)
		(size 0.4064)
		(drill 0.2032)
		(layers "F.Cu" "B.Cu")
		(net "GND")
	)
	(via
		(at 379.087634 -308.65953)
		(size 0.508)
		(drill 0.254)
		(layers "F.Cu" "B.Cu")
		(net "GND")
	)
	(via
		(at 301.824898 -293.52494)
		(size 0.4064)
		(drill 0.2032)
		(layers "F.Cu" "B.Cu")
		(net "GND")
	)
	(via
		(at 87.676482 -351.611438)
		(size 0.4064)
		(drill 0.2032)
		(layers "F.Cu" "B.Cu")
		(net "GND")
	)
	(via
		(at 397.02486 -298.27474)
		(size 0.4064)
		(drill 0.2032)
		(layers "F.Cu" "B.Cu")
		(net "GND")
	)
	(via
		(at 188.490352 -354.708206)
		(size 0.4064)
		(drill 0.2032)
		(layers "F.Cu" "B.Cu")
		(net "GND")
	)
	(via
		(at 449.478146 -287.228788)
		(size 0.508)
		(drill 0.254)
		(layers "F.Cu" "B.Cu")
		(net "GND")
	)
	(via
		(at 63.798196 -20.417536)
		(size 0.508)
		(drill 0.254)
		(layers "F.Cu" "B.Cu")
		(net "GND")
	)
	(via
		(at 277.251668 -137.16508)
		(size 0.508)
		(drill 0.254)
		(layers "F.Cu" "B.Cu")
		(net "GND")
	)
	(via
		(at 299.822108 -117.415056)
		(size 0.508)
		(drill 0.254)
		(layers "F.Cu" "B.Cu")
		(net "GND")
	)
	(via
		(at 385.624832 -273.574764)
		(size 0.4064)
		(drill 0.2032)
		(layers "F.Cu" "B.Cu")
		(net "GND")
	)
	(via
		(at 159.347916 -397.140176)
		(size 0.508)
		(drill 0.254)
		(layers "F.Cu" "B.Cu")
		(net "GND")
	)
	(via
		(at 292.608 -417.82492)
		(size 0.508)
		(drill 0.254)
		(layers "F.Cu" "B.Cu")
		(net "GND")
	)
	(via
		(at 61.4299 -172.329348)
		(size 0.508)
		(drill 0.254)
		(layers "F.Cu" "B.Cu")
		(net "GND")
	)
	(via
		(at 352.009964 -288.78149)
		(size 0.508)
		(drill 0.254)
		(layers "F.Cu" "B.Cu")
		(net "GND")
	)
	(via
		(at 341.927942 -374.938544)
		(size 0.508)
		(drill 0.254)
		(layers "F.Cu" "B.Cu")
		(net "GND")
	)
	(via
		(at 413.465264 -341.805514)
		(size 0.4572)
		(drill 0.254)
		(layers "F.Cu" "B.Cu")
		(net "GND")
	)
	(via
		(at 356.755192 -29.590238)
		(size 0.508)
		(drill 0.254)
		(layers "F.Cu" "B.Cu")
		(net "GND")
	)
	(via
		(at 37.788596 -349.219774)
		(size 0.4572)
		(drill 0.254)
		(layers "F.Cu" "B.Cu")
		(net "GND")
	)
	(via
		(at 142.806674 -199.367394)
		(size 0.508)
		(drill 0.254)
		(layers "F.Cu" "B.Cu")
		(net "GND")
	)
	(via
		(at 56.799988 -310.149748)
		(size 0.4064)
		(drill 0.2032)
		(layers "F.Cu" "B.Cu")
		(net "GND")
	)
	(via
		(at 194.749928 -312.049922)
		(size 0.4064)
		(drill 0.2032)
		(layers "F.Cu" "B.Cu")
		(net "GND")
	)
	(via
		(at 289.127692 -380.040134)
		(size 0.508)
		(drill 0.254)
		(layers "F.Cu" "B.Cu")
		(net "GND")
	)
	(via
		(at 241.51971 -163.021518)
		(size 0.508)
		(drill 0.254)
		(layers "F.Cu" "B.Cu")
		(net "GND")
	)
	(via
		(at 38.347904 -383.940304)
		(size 0.508)
		(drill 0.254)
		(layers "F.Cu" "B.Cu")
		(net "GND")
	)
	(via
		(at 221.331028 -94.988634)
		(size 0.508)
		(drill 0.254)
		(layers "F.Cu" "B.Cu")
		(net "GND")
	)
	(via
		(at 183.379872 -351.611438)
		(size 0.4064)
		(drill 0.2032)
		(layers "F.Cu" "B.Cu")
		(net "GND")
	)
	(via
		(at 163.399978 -317.749936)
		(size 0.4064)
		(drill 0.2032)
		(layers "F.Cu" "B.Cu")
		(net "GND")
	)
	(via
		(at 404.149814 -315.849762)
		(size 0.4064)
		(drill 0.2032)
		(layers "F.Cu" "B.Cu")
		(net "GND")
	)
	(via
		(at 45.051726 -107.845098)
		(size 0.508)
		(drill 0.254)
		(layers "F.Cu" "B.Cu")
		(net "GND")
	)
	(via
		(at 180.50002 -317.749936)
		(size 0.4064)
		(drill 0.2032)
		(layers "F.Cu" "B.Cu")
		(net "GND")
	)
	(via
		(at 4.056888 -0.762)
		(size 0.508)
		(drill 0.254)
		(layers "F.Cu" "B.Cu")
		(net "GND")
	)
	(via
		(at 439.33364 -303.026826)
		(size 0.508)
		(drill 0.254)
		(layers "F.Cu" "B.Cu")
		(net "GND")
	)
	(via
		(at 261.15137 -223.370902)
		(size 0.508)
		(drill 0.254)
		(layers "F.Cu" "B.Cu")
		(net "GND")
	)
	(via
		(at 165.947852 -377.341892)
		(size 0.508)
		(drill 0.254)
		(layers "F.Cu" "B.Cu")
		(net "GND")
	)
	(via
		(at 134.095744 -131.964176)
		(size 0.508)
		(drill 0.254)
		(layers "F.Cu" "B.Cu")
		(net "GND")
	)
	(via
		(at 180.975 -305.874928)
		(size 0.4064)
		(drill 0.2032)
		(layers "F.Cu" "B.Cu")
		(net "GND")
	)
	(via
		(at 298.78909 -352.245422)
		(size 0.4572)
		(drill 0.254)
		(layers "F.Cu" "B.Cu")
		(net "GND")
	)
	(via
		(at 414.11271 -121.835164)
		(size 0.508)
		(drill 0.254)
		(layers "F.Cu" "B.Cu")
		(net "GND")
	)
	(via
		(at 71.524876 -291.624766)
		(size 0.4064)
		(drill 0.2032)
		(layers "F.Cu" "B.Cu")
		(net "GND")
	)
	(via
		(at 230.892096 -146.912076)
		(size 0.508)
		(drill 0.254)
		(layers "F.Cu" "B.Cu")
		(net "GND")
	)
	(via
		(at 378.953268 -49.574704)
		(size 0.508)
		(drill 0.254)
		(layers "F.Cu" "B.Cu")
		(net "GND")
	)
	(via
		(at 392.52779 -376.242072)
		(size 0.508)
		(drill 0.254)
		(layers "F.Cu" "B.Cu")
		(net "GND")
	)
	(via
		(at 304.527712 -402.241766)
		(size 0.508)
		(drill 0.254)
		(layers "F.Cu" "B.Cu")
		(net "GND")
	)
	(via
		(at 307.999892 -273.099784)
		(size 0.4064)
		(drill 0.2032)
		(layers "F.Cu" "B.Cu")
		(net "GND")
	)
	(via
		(at 68.199762 -313.949842)
		(size 0.4064)
		(drill 0.2032)
		(layers "F.Cu" "B.Cu")
		(net "GND")
	)
	(via
		(at 327.849992 -349.219774)
		(size 0.4572)
		(drill 0.254)
		(layers "F.Cu" "B.Cu")
		(net "GND")
	)
	(via
		(at 228.01961 -38.701218)
		(size 0.508)
		(drill 0.254)
		(layers "F.Cu" "B.Cu")
		(net "GND")
	)
	(via
		(at 376.56389 -256.987548)
		(size 0.508)
		(drill 0.254)
		(layers "F.Cu" "B.Cu")
		(net "GND")
	)
	(via
		(at 4.208272 -52.536852)
		(size 0.508)
		(drill 0.254)
		(layers "F.Cu" "B.Cu")
		(net "GND")
	)
	(via
		(at 39.699946 -314.899802)
		(size 0.4064)
		(drill 0.2032)
		(layers "F.Cu" "B.Cu")
		(net "GND")
	)
	(via
		(at 367.03127 -11.372342)
		(size 0.508)
		(drill 0.254)
		(layers "F.Cu" "B.Cu")
		(net "GND")
	)
	(via
		(at 435.948836 -31.390082)
		(size 0.508)
		(drill 0.254)
		(layers "F.Cu" "B.Cu")
		(net "GND")
	)
	(via
		(at 74.248264 -133.044946)
		(size 0.508)
		(drill 0.254)
		(layers "F.Cu" "B.Cu")
		(net "GND")
	)
	(via
		(at 181.449726 -272.14957)
		(size 0.4064)
		(drill 0.2032)
		(layers "F.Cu" "B.Cu")
		(net "GND")
	)
	(via
		(at 385.67741 -149.747224)
		(size 0.508)
		(drill 0.254)
		(layers "F.Cu" "B.Cu")
		(net "GND")
	)
	(via
		(at 75.79995 -309.199788)
		(size 0.4064)
		(drill 0.2032)
		(layers "F.Cu" "B.Cu")
		(net "GND")
	)
	(via
		(at 164.824918 -291.624766)
		(size 0.4064)
		(drill 0.2032)
		(layers "F.Cu" "B.Cu")
		(net "GND")
	)
	(via
		(at 80.54975 -314.899802)
		(size 0.4064)
		(drill 0.2032)
		(layers "F.Cu" "B.Cu")
		(net "GND")
	)
	(via
		(at 74.84999 -280.699718)
		(size 0.4064)
		(drill 0.2032)
		(layers "F.Cu" "B.Cu")
		(net "GND")
	)
	(via
		(at 161.54781 -397.038576)
		(size 0.508)
		(drill 0.254)
		(layers "F.Cu" "B.Cu")
		(net "GND")
	)
	(via
		(at 66.44767 -149.355048)
		(size 0.508)
		(drill 0.254)
		(layers "F.Cu" "B.Cu")
		(net "GND")
	)
	(via
		(at 76.71943 -358.391714)
		(size 0.4572)
		(drill 0.254)
		(layers "F.Cu" "B.Cu")
		(net "GND")
	)
	(via
		(at 286.927798 -406.141936)
		(size 0.508)
		(drill 0.254)
		(layers "F.Cu" "B.Cu")
		(net "GND")
	)
	(via
		(at 422.548304 -133.044946)
		(size 0.508)
		(drill 0.254)
		(layers "F.Cu" "B.Cu")
		(net "GND")
	)
	(via
		(at 167.732964 -104.244902)
		(size 0.508)
		(drill 0.254)
		(layers "F.Cu" "B.Cu")
		(net "GND")
	)
	(via
		(at 422.792144 -352.245422)
		(size 0.4572)
		(drill 0.254)
		(layers "F.Cu" "B.Cu")
		(net "GND")
	)
	(via
		(at 83.400138 -316.799722)
		(size 0.4064)
		(drill 0.2032)
		(layers "F.Cu" "B.Cu")
		(net "GND")
	)
	(via
		(at 294.832024 -168.94556)
		(size 0.508)
		(drill 0.254)
		(layers "F.Cu" "B.Cu")
		(net "GND")
	)
	(via
		(at 402.079968 -352.245422)
		(size 0.4572)
		(drill 0.254)
		(layers "F.Cu" "B.Cu")
		(net "GND")
	)
	(via
		(at 247.499124 -132.538216)
		(size 0.508)
		(drill 0.254)
		(layers "F.Cu" "B.Cu")
		(net "GND")
	)
	(via
		(at 339.037422 -307.242718)
		(size 0.508)
		(drill 0.254)
		(layers "F.Cu" "B.Cu")
		(net "GND")
	)
	(via
		(at 65.542414 -358.391714)
		(size 0.4572)
		(drill 0.254)
		(layers "F.Cu" "B.Cu")
		(net "GND")
	)
	(via
		(at 133.02107 -112.844326)
		(size 0.508)
		(drill 0.254)
		(layers "F.Cu" "B.Cu")
		(net "GND")
	)
	(via
		(at 77.22489 -297.32478)
		(size 0.4064)
		(drill 0.2032)
		(layers "F.Cu" "B.Cu")
		(net "GND")
	)
	(via
		(at 179.844954 -29.589984)
		(size 0.508)
		(drill 0.254)
		(layers "F.Cu" "B.Cu")
		(net "GND")
	)
	(via
		(at 51.574954 -294.4749)
		(size 0.4064)
		(drill 0.2032)
		(layers "F.Cu" "B.Cu")
		(net "GND")
	)
	(via
		(at 53.48732 -122.354848)
		(size 0.508)
		(drill 0.254)
		(layers "F.Cu" "B.Cu")
		(net "GND")
	)
	(via
		(at 401.78736 -120.555004)
		(size 0.508)
		(drill 0.254)
		(layers "F.Cu" "B.Cu")
		(net "GND")
	)
	(via
		(at 39.418768 -342.439498)
		(size 0.4064)
		(drill 0.2032)
		(layers "F.Cu" "B.Cu")
		(net "GND")
	)
	(via
		(at 144.485614 -34.183066)
		(size 0.508)
		(drill 0.254)
		(layers "F.Cu" "B.Cu")
		(net "GND")
	)
	(via
		(at 72.949816 -279.749758)
		(size 0.4064)
		(drill 0.2032)
		(layers "F.Cu" "B.Cu")
		(net "GND")
	)
	(via
		(at 201.399902 -62.812168)
		(size 0.508)
		(drill 0.254)
		(layers "F.Cu" "B.Cu")
		(net "GND")
	)
	(via
		(at 435.599332 -351.611438)
		(size 0.4064)
		(drill 0.2032)
		(layers "F.Cu" "B.Cu")
		(net "GND")
	)
	(via
		(at 301.349918 -275.949918)
		(size 0.4064)
		(drill 0.2032)
		(layers "F.Cu" "B.Cu")
		(net "GND")
	)
	(via
		(at 184.380886 -33.19018)
		(size 0.508)
		(drill 0.254)
		(layers "F.Cu" "B.Cu")
		(net "GND")
	)
	(via
		(at 173.375066 -285.924752)
		(size 0.4064)
		(drill 0.2032)
		(layers "F.Cu" "B.Cu")
		(net "GND")
	)
	(via
		(at 422.199816 -273.099784)
		(size 0.4064)
		(drill 0.2032)
		(layers "F.Cu" "B.Cu")
		(net "GND")
	)
	(via
		(at 154.850084 -300.649894)
		(size 0.4064)
		(drill 0.2032)
		(layers "F.Cu" "B.Cu")
		(net "GND")
	)
	(via
		(at 172.547788 -408.840178)
		(size 0.508)
		(drill 0.254)
		(layers "F.Cu" "B.Cu")
		(net "GND")
	)
	(via
		(at 77.978254 -344.831162)
		(size 0.4572)
		(drill 0.254)
		(layers "F.Cu" "B.Cu")
		(net "GND")
	)
	(via
		(at 91.902026 -58.096404)
		(size 0.508)
		(drill 0.254)
		(layers "F.Cu" "B.Cu")
		(net "GND")
	)
	(via
		(at 28.461716 -341.805514)
		(size 0.4572)
		(drill 0.254)
		(layers "F.Cu" "B.Cu")
		(net "GND")
	)
	(via
		(at 157.224984 -277.374858)
		(size 0.4064)
		(drill 0.2032)
		(layers "F.Cu" "B.Cu")
		(net "GND")
	)
	(via
		(at 116.03228 -357.123746)
		(size 0.4572)
		(drill 0.254)
		(layers "F.Cu" "B.Cu")
		(net "GND")
	)
	(via
		(at 322.890896 -346.09913)
		(size 0.4572)
		(drill 0.254)
		(layers "F.Cu" "B.Cu")
		(net "GND")
	)
	(via
		(at 43.974766 -293.52494)
		(size 0.4064)
		(drill 0.2032)
		(layers "F.Cu" "B.Cu")
		(net "GND")
	)
	(via
		(at 432.490372 -354.732082)
		(size 0.4064)
		(drill 0.2032)
		(layers "F.Cu" "B.Cu")
		(net "GND")
	)
	(via
		(at 260.757924 -289.532314)
		(size 0.508)
		(drill 0.254)
		(layers "F.Cu" "B.Cu")
		(net "GND")
	)
	(via
		(at 328.3204 -63.218314)
		(size 0.508)
		(drill 0.254)
		(layers "F.Cu" "B.Cu")
		(net "GND")
	)
	(via
		(at 427.727872 -406.141936)
		(size 0.508)
		(drill 0.254)
		(layers "F.Cu" "B.Cu")
		(net "GND")
	)
	(via
		(at 351.600262 -88.093804)
		(size 0.508)
		(drill 0.254)
		(layers "F.Cu" "B.Cu")
		(net "GND")
	)
	(via
		(at 353.335844 -146.606768)
		(size 0.508)
		(drill 0.254)
		(layers "F.Cu" "B.Cu")
		(net "GND")
	)
	(via
		(at 185.250074 -280.699718)
		(size 0.4064)
		(drill 0.2032)
		(layers "F.Cu" "B.Cu")
		(net "GND")
	)
	(via
		(at 122.877072 -282.910788)
		(size 0.49022)
		(drill 0.254)
		(layers "F.Cu" "B.Cu")
		(net "GND")
	)
	(via
		(at 53.949854 -315.849762)
		(size 0.4064)
		(drill 0.2032)
		(layers "F.Cu" "B.Cu")
		(net "GND")
	)
	(via
		(at 177.748946 -27.79014)
		(size 0.508)
		(drill 0.254)
		(layers "F.Cu" "B.Cu")
		(net "GND")
	)
	(via
		(at 412.89351 -123.635008)
		(size 0.508)
		(drill 0.254)
		(layers "F.Cu" "B.Cu")
		(net "GND")
	)
	(via
		(at 138.351514 -47.03191)
		(size 0.508)
		(drill 0.254)
		(layers "F.Cu" "B.Cu")
		(net "GND")
	)
	(via
		(at 330.958952 -350.977454)
		(size 0.4572)
		(drill 0.254)
		(layers "F.Cu" "B.Cu")
		(net "GND")
	)
	(via
		(at 301.349918 -316.799722)
		(size 0.4064)
		(drill 0.2032)
		(layers "F.Cu" "B.Cu")
		(net "GND")
	)
	(via
		(at 136.934194 -173.090586)
		(size 0.508)
		(drill 0.254)
		(layers "F.Cu" "B.Cu")
		(net "GND")
	)
	(via
		(at 376.83694 -354.732082)
		(size 0.4064)
		(drill 0.2032)
		(layers "F.Cu" "B.Cu")
		(net "GND")
	)
	(via
		(at 39.04742 -354.098098)
		(size 0.4572)
		(drill 0.254)
		(layers "F.Cu" "B.Cu")
		(net "GND")
	)
	(via
		(at 154.37485 -299.224954)
		(size 0.4064)
		(drill 0.2032)
		(layers "F.Cu" "B.Cu")
		(net "GND")
	)
	(via
		(at 344.653616 -354.098098)
		(size 0.4572)
		(drill 0.254)
		(layers "F.Cu" "B.Cu")
		(net "GND")
	)
	(via
		(at 172.574204 -355.366066)
		(size 0.4572)
		(drill 0.254)
		(layers "F.Cu" "B.Cu")
		(net "GND")
	)
	(via
		(at 356.542848 -150.16861)
		(size 0.508)
		(drill 0.254)
		(layers "F.Cu" "B.Cu")
		(net "GND")
	)
	(via
		(at 107.284266 -220.276166)
		(size 0.508)
		(drill 0.254)
		(layers "F.Cu" "B.Cu")
		(net "GND")
	)
	(via
		(at 383.72796 -371.140228)
		(size 0.508)
		(drill 0.254)
		(layers "F.Cu" "B.Cu")
		(net "GND")
	)
	(via
		(at 384.685032 -344.831162)
		(size 0.4572)
		(drill 0.254)
		(layers "F.Cu" "B.Cu")
		(net "GND")
	)
	(via
		(at 395.862048 -350.977454)
		(size 0.4572)
		(drill 0.254)
		(layers "F.Cu" "B.Cu")
		(net "GND")
	)
	(via
		(at 51.48326 -354.098098)
		(size 0.4572)
		(drill 0.254)
		(layers "F.Cu" "B.Cu")
		(net "GND")
	)
	(via
		(at 417.773358 -72.56526)
		(size 0.508)
		(drill 0.254)
		(layers "F.Cu" "B.Cu")
		(net "GND")
	)
	(via
		(at 50.624994 -293.52494)
		(size 0.4064)
		(drill 0.2032)
		(layers "F.Cu" "B.Cu")
		(net "GND")
	)
	(via
		(at 385.624832 -284.024832)
		(size 0.4064)
		(drill 0.2032)
		(layers "F.Cu" "B.Cu")
		(net "GND")
	)
	(via
		(at 231.388158 -65.39992)
		(size 0.508)
		(drill 0.254)
		(layers "F.Cu" "B.Cu")
		(net "GND")
	)
	(via
		(at 368.120422 -122.907044)
		(size 0.508)
		(drill 0.254)
		(layers "F.Cu" "B.Cu")
		(net "GND")
	)
	(via
		(at 314.573666 -25.971246)
		(size 0.508)
		(drill 0.254)
		(layers "F.Cu" "B.Cu")
		(net "GND")
	)
	(via
		(at 388.080504 -238.617506)
		(size 0.508)
		(drill 0.254)
		(layers "F.Cu" "B.Cu")
		(net "GND")
	)
	(via
		(at 137.795 -350.977454)
		(size 0.4572)
		(drill 0.254)
		(layers "F.Cu" "B.Cu")
		(net "GND")
	)
	(via
		(at 314.366148 -150.876762)
		(size 0.508)
		(drill 0.254)
		(layers "F.Cu" "B.Cu")
		(net "GND")
	)
	(via
		(at 182.272432 -348.58579)
		(size 0.4064)
		(drill 0.2032)
		(layers "F.Cu" "B.Cu")
		(net "GND")
	)
	(via
		(at 67.724782 -307.774848)
		(size 0.4064)
		(drill 0.2032)
		(layers "F.Cu" "B.Cu")
		(net "GND")
	)
	(via
		(at 352.009964 -290.68649)
		(size 0.508)
		(drill 0.254)
		(layers "F.Cu" "B.Cu")
		(net "GND")
	)
	(via
		(at 73.899776 -305.399948)
		(size 0.4064)
		(drill 0.2032)
		(layers "F.Cu" "B.Cu")
		(net "GND")
	)
	(via
		(at 122.002296 -27.729688)
		(size 0.508)
		(drill 0.254)
		(layers "F.Cu" "B.Cu")
		(net "GND")
	)
	(via
		(at 304.467006 -129.445004)
		(size 0.508)
		(drill 0.254)
		(layers "F.Cu" "B.Cu")
		(net "GND")
	)
	(via
		(at 37.57295 -156.3624)
		(size 0.508)
		(drill 0.254)
		(layers "F.Cu" "B.Cu")
		(net "GND")
	)
	(via
		(at 384.059684 -112.981994)
		(size 0.508)
		(drill 0.254)
		(layers "F.Cu" "B.Cu")
		(net "GND")
	)
	(via
		(at 117.628416 -136.926828)
		(size 0.508)
		(drill 0.254)
		(layers "F.Cu" "B.Cu")
		(net "GND")
	)
	(via
		(at 183.3499 -310.149748)
		(size 0.4064)
		(drill 0.2032)
		(layers "F.Cu" "B.Cu")
		(net "GND")
	)
	(via
		(at 293.27475 -302.074834)
		(size 0.4064)
		(drill 0.2032)
		(layers "F.Cu" "B.Cu")
		(net "GND")
	)
	(via
		(at 182.547514 -133.0452)
		(size 0.508)
		(drill 0.254)
		(layers "F.Cu" "B.Cu")
		(net "GND")
	)
	(via
		(at 409.09748 -349.219774)
		(size 0.4572)
		(drill 0.254)
		(layers "F.Cu" "B.Cu")
		(net "GND")
	)
	(via
		(at 173.850046 -316.799722)
		(size 0.4064)
		(drill 0.2032)
		(layers "F.Cu" "B.Cu")
		(net "GND")
	)
	(via
		(at 45.26534 -341.805514)
		(size 0.4572)
		(drill 0.254)
		(layers "F.Cu" "B.Cu")
		(net "GND")
	)
	(via
		(at 363.09808 -285.953454)
		(size 0.508)
		(drill 0.254)
		(layers "F.Cu" "B.Cu")
		(net "GND")
	)
	(via
		(at 299.002704 -74.624184)
		(size 0.508)
		(drill 0.254)
		(layers "F.Cu" "B.Cu")
		(net "GND")
	)
	(via
		(at 443.785498 -63.218314)
		(size 0.508)
		(drill 0.254)
		(layers "F.Cu" "B.Cu")
		(net "GND")
	)
	(via
		(at 50.224436 -355.366066)
		(size 0.4572)
		(drill 0.254)
		(layers "F.Cu" "B.Cu")
		(net "GND")
	)
	(via
		(at 341.544656 -354.074222)
		(size 0.4572)
		(drill 0.254)
		(layers "F.Cu" "B.Cu")
		(net "GND")
	)
	(via
		(at 395.59992 -318.699896)
		(size 0.4064)
		(drill 0.2032)
		(layers "F.Cu" "B.Cu")
		(net "GND")
	)
	(via
		(at 386.575046 -293.52494)
		(size 0.4064)
		(drill 0.2032)
		(layers "F.Cu" "B.Cu")
		(net "GND")
	)
	(via
		(at 176.555146 -33.19018)
		(size 0.508)
		(drill 0.254)
		(layers "F.Cu" "B.Cu")
		(net "GND")
	)
	(via
		(at 214.039196 -28.05303)
		(size 0.508)
		(drill 0.254)
		(layers "F.Cu" "B.Cu")
		(net "GND")
	)
	(via
		(at 161.975038 -294.4749)
		(size 0.4064)
		(drill 0.2032)
		(layers "F.Cu" "B.Cu")
		(net "GND")
	)
	(via
		(at 36.849812 -317.749936)
		(size 0.4064)
		(drill 0.2032)
		(layers "F.Cu" "B.Cu")
		(net "GND")
	)
	(via
		(at 132.04825 -154.510994)
		(size 0.508)
		(drill 0.254)
		(layers "F.Cu" "B.Cu")
		(net "GND")
	)
	(via
		(at 377.12777 -407.24201)
		(size 0.508)
		(drill 0.254)
		(layers "F.Cu" "B.Cu")
		(net "GND")
	)
	(via
		(at 395.59992 -314.899802)
		(size 0.4064)
		(drill 0.2032)
		(layers "F.Cu" "B.Cu")
		(net "GND")
	)
	(via
		(at 306.16017 -19.33956)
		(size 0.508)
		(drill 0.254)
		(layers "F.Cu" "B.Cu")
		(net "GND")
	)
	(via
		(at 308.949598 -276.899878)
		(size 0.4064)
		(drill 0.2032)
		(layers "F.Cu" "B.Cu")
		(net "GND")
	)
	(via
		(at 409.72994 -172.329348)
		(size 0.508)
		(drill 0.254)
		(layers "F.Cu" "B.Cu")
		(net "GND")
	)
	(via
		(at 27.978608 -33.248092)
		(size 0.508)
		(drill 0.254)
		(layers "F.Cu" "B.Cu")
		(net "GND")
	)
	(via
		(at 429.571404 -51.661822)
		(size 0.508)
		(drill 0.254)
		(layers "F.Cu" "B.Cu")
		(net "GND")
	)
	(via
		(at 338.876894 -279.023572)
		(size 0.508)
		(drill 0.254)
		(layers "F.Cu" "B.Cu")
		(net "GND")
	)
	(via
		(at 390.849866 -310.149748)
		(size 0.4064)
		(drill 0.2032)
		(layers "F.Cu" "B.Cu")
		(net "GND")
	)
	(via
		(at 84.54771 -395.938502)
		(size 0.508)
		(drill 0.254)
		(layers "F.Cu" "B.Cu")
		(net "GND")
	)
	(via
		(at 273.91741 -354.098098)
		(size 0.4572)
		(drill 0.254)
		(layers "F.Cu" "B.Cu")
		(net "GND")
	)
	(via
		(at 275.673312 -72.56526)
		(size 0.508)
		(drill 0.254)
		(layers "F.Cu" "B.Cu")
		(net "GND")
	)
	(via
		(at 178.599846 -313.949842)
		(size 0.4064)
		(drill 0.2032)
		(layers "F.Cu" "B.Cu")
		(net "GND")
	)
	(via
		(at 116.03228 -341.805514)
		(size 0.4572)
		(drill 0.254)
		(layers "F.Cu" "B.Cu")
		(net "GND")
	)
	(via
		(at 415.074862 -289.724846)
		(size 0.4064)
		(drill 0.2032)
		(layers "F.Cu" "B.Cu")
		(net "GND")
	)
	(via
		(at 311.324752 -294.4749)
		(size 0.4064)
		(drill 0.2032)
		(layers "F.Cu" "B.Cu")
		(net "GND")
	)
	(via
		(at 287.612074 -346.09913)
		(size 0.4572)
		(drill 0.254)
		(layers "F.Cu" "B.Cu")
		(net "GND")
	)
	(via
		(at 42.549826 -302.549814)
		(size 0.4064)
		(drill 0.2032)
		(layers "F.Cu" "B.Cu")
		(net "GND")
	)
	(via
		(at 266.691618 -109.382052)
		(size 0.508)
		(drill 0.254)
		(layers "F.Cu" "B.Cu")
		(net "GND")
	)
	(via
		(at 319.781936 -350.977454)
		(size 0.4572)
		(drill 0.254)
		(layers "F.Cu" "B.Cu")
		(net "GND")
	)
	(via
		(at 157.224984 -293.52494)
		(size 0.4064)
		(drill 0.2032)
		(layers "F.Cu" "B.Cu")
		(net "GND")
	)
	(via
		(at 168.625012 -291.624766)
		(size 0.4064)
		(drill 0.2032)
		(layers "F.Cu" "B.Cu")
		(net "GND")
	)
	(via
		(at 103.205026 -306.55387)
		(size 0.508)
		(drill 0.254)
		(layers "F.Cu" "B.Cu")
		(net "GND")
	)
	(via
		(at 156.275024 -289.724846)
		(size 0.4064)
		(drill 0.2032)
		(layers "F.Cu" "B.Cu")
		(net "GND")
	)
	(via
		(at 166.381684 -355.366066)
		(size 0.4572)
		(drill 0.254)
		(layers "F.Cu" "B.Cu")
		(net "GND")
	)
	(via
		(at 279.024842 -287.824926)
		(size 0.4064)
		(drill 0.2032)
		(layers "F.Cu" "B.Cu")
		(net "GND")
	)
	(via
		(at 324.99427 -123.84278)
		(size 0.508)
		(drill 0.254)
		(layers "F.Cu" "B.Cu")
		(net "GND")
	)
	(via
		(at 24.981408 -348.58579)
		(size 0.4064)
		(drill 0.2032)
		(layers "F.Cu" "B.Cu")
		(net "GND")
	)
	(via
		(at 102.31501 -241.7445)
		(size 0.508)
		(drill 0.254)
		(layers "F.Cu" "B.Cu")
		(net "GND")
	)
	(via
		(at 21.819616 -38.701218)
		(size 0.508)
		(drill 0.254)
		(layers "F.Cu" "B.Cu")
		(net "GND")
	)
	(via
		(at 297.549824 -315.849762)
		(size 0.4064)
		(drill 0.2032)
		(layers "F.Cu" "B.Cu")
		(net "GND")
	)
	(via
		(at 76.74991 -308.249828)
		(size 0.4064)
		(drill 0.2032)
		(layers "F.Cu" "B.Cu")
		(net "GND")
	)
	(via
		(at 295.68013 -350.977454)
		(size 0.4572)
		(drill 0.254)
		(layers "F.Cu" "B.Cu")
		(net "GND")
	)
	(via
		(at 61.648848 -25.990042)
		(size 0.508)
		(drill 0.254)
		(layers "F.Cu" "B.Cu")
		(net "GND")
	)
	(via
		(at 84.54771 -399.838418)
		(size 0.508)
		(drill 0.254)
		(layers "F.Cu" "B.Cu")
		(net "GND")
	)
	(via
		(at 389.424926 -281.174952)
		(size 0.4064)
		(drill 0.2032)
		(layers "F.Cu" "B.Cu")
		(net "GND")
	)
	(via
		(at 79.82839 -358.391714)
		(size 0.4572)
		(drill 0.254)
		(layers "F.Cu" "B.Cu")
		(net "GND")
	)
	(via
		(at 424.09999 -284.499812)
		(size 0.4064)
		(drill 0.2032)
		(layers "F.Cu" "B.Cu")
		(net "GND")
	)
	(via
		(at 121.947686 -407.24201)
		(size 0.4572)
		(drill 0.254)
		(layers "F.Cu" "B.Cu")
		(net "GND")
	)
	(via
		(at 89.744804 -29.589984)
		(size 0.508)
		(drill 0.254)
		(layers "F.Cu" "B.Cu")
		(net "GND")
	)
	(via
		(at 293.84879 -33.19018)
		(size 0.508)
		(drill 0.254)
		(layers "F.Cu" "B.Cu")
		(net "GND")
	)
	(via
		(at 43.499786 -277.849838)
		(size 0.4064)
		(drill 0.2032)
		(layers "F.Cu" "B.Cu")
		(net "GND")
	)
	(via
		(at 55.306976 -49.574704)
		(size 0.508)
		(drill 0.254)
		(layers "F.Cu" "B.Cu")
		(net "GND")
	)
	(via
		(at 443.109096 -93.98254)
		(size 0.508)
		(drill 0.254)
		(layers "F.Cu" "B.Cu")
		(net "GND")
	)
	(via
		(at 364.580932 -33.19018)
		(size 0.508)
		(drill 0.254)
		(layers "F.Cu" "B.Cu")
		(net "GND")
	)
	(via
		(at 362.458 -200.787)
		(size 0.508)
		(drill 0.254)
		(layers "F.Cu" "B.Cu")
		(net "GND")
	)
	(via
		(at 337.176872 -347.951806)
		(size 0.4572)
		(drill 0.254)
		(layers "F.Cu" "B.Cu")
		(net "GND")
	)
	(via
		(at 423.32783 -375.040144)
		(size 0.508)
		(drill 0.254)
		(layers "F.Cu" "B.Cu")
		(net "GND")
	)
	(via
		(at 425.99991 -308.249828)
		(size 0.4064)
		(drill 0.2032)
		(layers "F.Cu" "B.Cu")
		(net "GND")
	)
	(via
		(at 283.557472 -29.784294)
		(size 0.508)
		(drill 0.254)
		(layers "F.Cu" "B.Cu")
		(net "GND")
	)
	(via
		(at 414.74771 -133.0452)
		(size 0.508)
		(drill 0.254)
		(layers "F.Cu" "B.Cu")
		(net "GND")
	)
	(via
		(at 119.14124 -352.245422)
		(size 0.4572)
		(drill 0.254)
		(layers "F.Cu" "B.Cu")
		(net "GND")
	)
	(via
		(at 310.751474 -99.037648)
		(size 0.508)
		(drill 0.254)
		(layers "F.Cu" "B.Cu")
		(net "GND")
	)
	(via
		(at 54.348126 -369.827302)
		(size 0.4064)
		(drill 0.2032)
		(layers "F.Cu" "B.Cu")
		(net "GND")
	)
	(via
		(at 400.824954 -291.624766)
		(size 0.4064)
		(drill 0.2032)
		(layers "F.Cu" "B.Cu")
		(net "GND")
	)
	(via
		(at 84.808314 -144.224502)
		(size 0.508)
		(drill 0.254)
		(layers "F.Cu" "B.Cu")
		(net "GND")
	)
	(via
		(at 186.86018 -343.073482)
		(size 0.4572)
		(drill 0.254)
		(layers "F.Cu" "B.Cu")
		(net "GND")
	)
	(via
		(at 39.04742 -346.09913)
		(size 0.4572)
		(drill 0.254)
		(layers "F.Cu" "B.Cu")
		(net "GND")
	)
	(via
		(at 166.561008 -169.89679)
		(size 0.508)
		(drill 0.254)
		(layers "F.Cu" "B.Cu")
		(net "GND")
	)
	(via
		(at 117.511068 -357.75773)
		(size 0.4064)
		(drill 0.2032)
		(layers "F.Cu" "B.Cu")
		(net "GND")
	)
	(via
		(at 79.59979 -277.849838)
		(size 0.4064)
		(drill 0.2032)
		(layers "F.Cu" "B.Cu")
		(net "GND")
	)
	(via
		(at 47.77486 -305.874928)
		(size 0.4064)
		(drill 0.2032)
		(layers "F.Cu" "B.Cu")
		(net "GND")
	)
	(via
		(at 37.133784 -103.975408)
		(size 0.508)
		(drill 0.254)
		(layers "F.Cu" "B.Cu")
		(net "GND")
	)
	(via
		(at 302.327818 -376.140218)
		(size 0.508)
		(drill 0.254)
		(layers "F.Cu" "B.Cu")
		(net "GND")
	)
	(via
		(at 77.22489 -299.224954)
		(size 0.4064)
		(drill 0.2032)
		(layers "F.Cu" "B.Cu")
		(net "GND")
	)
	(via
		(at 106.992674 -84.13877)
		(size 0.508)
		(drill 0.254)
		(layers "F.Cu" "B.Cu")
		(net "GND")
	)
	(via
		(at 292.32479 -294.4749)
		(size 0.4064)
		(drill 0.2032)
		(layers "F.Cu" "B.Cu")
		(net "GND")
	)
	(via
		(at 199.500236 -283.550106)
		(size 0.4064)
		(drill 0.2032)
		(layers "F.Cu" "B.Cu")
		(net "GND")
	)
	(via
		(at 191.0461 -413.479234)
		(size 0.508)
		(drill 0.254)
		(layers "F.Cu" "B.Cu")
		(net "GND")
	)
	(via
		(at 374.927876 -404.940262)
		(size 0.508)
		(drill 0.254)
		(layers "F.Cu" "B.Cu")
		(net "GND")
	)
	(via
		(at 125.35916 -346.09913)
		(size 0.4572)
		(drill 0.254)
		(layers "F.Cu" "B.Cu")
		(net "GND")
	)
	(via
		(at 180.693314 -131.245102)
		(size 0.508)
		(drill 0.254)
		(layers "F.Cu" "B.Cu")
		(net "GND")
	)
	(via
		(at 352.009964 -288.14649)
		(size 0.508)
		(drill 0.254)
		(layers "F.Cu" "B.Cu")
		(net "GND")
	)
	(via
		(at 27.347926 -404.940262)
		(size 0.508)
		(drill 0.254)
		(layers "F.Cu" "B.Cu")
		(net "GND")
	)
	(via
		(at 32.8295 -346.09913)
		(size 0.4572)
		(drill 0.254)
		(layers "F.Cu" "B.Cu")
		(net "GND")
	)
	(via
		(at 131.948428 -351.611438)
		(size 0.4064)
		(drill 0.2032)
		(layers "F.Cu" "B.Cu")
		(net "GND")
	)
	(via
		(at 328.9554 -63.218314)
		(size 0.508)
		(drill 0.254)
		(layers "F.Cu" "B.Cu")
		(net "GND")
	)
	(via
		(at 167.732964 -113.245138)
		(size 0.508)
		(drill 0.254)
		(layers "F.Cu" "B.Cu")
		(net "GND")
	)
	(via
		(at 90.414094 -344.831162)
		(size 0.4572)
		(drill 0.254)
		(layers "F.Cu" "B.Cu")
		(net "GND")
	)
	(via
		(at 190.348108 -118.234968)
		(size 0.508)
		(drill 0.254)
		(layers "F.Cu" "B.Cu")
		(net "GND")
	)
	(via
		(at 186.77128 -31.652972)
		(size 0.508)
		(drill 0.254)
		(layers "F.Cu" "B.Cu")
		(net "GND")
	)
	(via
		(at 348.527878 -410.041852)
		(size 0.508)
		(drill 0.254)
		(layers "F.Cu" "B.Cu")
		(net "GND")
	)
	(via
		(at 387.793992 -357.123746)
		(size 0.4572)
		(drill 0.254)
		(layers "F.Cu" "B.Cu")
		(net "GND")
	)
	(via
		(at 40.649906 -309.199788)
		(size 0.4064)
		(drill 0.2032)
		(layers "F.Cu" "B.Cu")
		(net "GND")
	)
	(via
		(at 159.599884 -276.899878)
		(size 0.4064)
		(drill 0.2032)
		(layers "F.Cu" "B.Cu")
		(net "GND")
	)
	(via
		(at 377.12777 -377.341892)
		(size 0.508)
		(drill 0.254)
		(layers "F.Cu" "B.Cu")
		(net "GND")
	)
	(via
		(at 88.947752 -381.63881)
		(size 0.508)
		(drill 0.254)
		(layers "F.Cu" "B.Cu")
		(net "GND")
	)
	(via
		(at 77.947774 -411.141926)
		(size 0.508)
		(drill 0.254)
		(layers "F.Cu" "B.Cu")
		(net "GND")
	)
	(via
		(at 112.92332 -352.245422)
		(size 0.4572)
		(drill 0.254)
		(layers "F.Cu" "B.Cu")
		(net "GND")
	)
	(via
		(at 303.724818 -291.624766)
		(size 0.4064)
		(drill 0.2032)
		(layers "F.Cu" "B.Cu")
		(net "GND")
	)
	(via
		(at 196.48551 -34.183066)
		(size 0.508)
		(drill 0.254)
		(layers "F.Cu" "B.Cu")
		(net "GND")
	)
	(via
		(at 303.249838 -276.899878)
		(size 0.4064)
		(drill 0.2032)
		(layers "F.Cu" "B.Cu")
		(net "GND")
	)
	(via
		(at 420.299896 -273.099784)
		(size 0.4064)
		(drill 0.2032)
		(layers "F.Cu" "B.Cu")
		(net "GND")
	)
	(via
		(at 410.727652 -348.58579)
		(size 0.4064)
		(drill 0.2032)
		(layers "F.Cu" "B.Cu")
		(net "GND")
	)
	(via
		(at 71.049896 -276.899878)
		(size 0.4064)
		(drill 0.2032)
		(layers "F.Cu" "B.Cu")
		(net "GND")
	)
	(via
		(at 230.421942 -112.542574)
		(size 0.508)
		(drill 0.254)
		(layers "F.Cu" "B.Cu")
		(net "GND")
	)
	(via
		(at 273.324828 -298.27474)
		(size 0.4064)
		(drill 0.2032)
		(layers "F.Cu" "B.Cu")
		(net "GND")
	)
	(via
		(at 80.898238 -149.617938)
		(size 0.508)
		(drill 0.254)
		(layers "F.Cu" "B.Cu")
		(net "GND")
	)
	(via
		(at 401.299934 -314.899802)
		(size 0.4064)
		(drill 0.2032)
		(layers "F.Cu" "B.Cu")
		(net "GND")
	)
	(via
		(at 41.124886 -293.52494)
		(size 0.4064)
		(drill 0.2032)
		(layers "F.Cu" "B.Cu")
		(net "GND")
	)
	(via
		(at 427.75124 -357.123746)
		(size 0.4572)
		(drill 0.254)
		(layers "F.Cu" "B.Cu")
		(net "GND")
	)
	(via
		(at 173.122844 -140.97)
		(size 0.508)
		(drill 0.254)
		(layers "F.Cu" "B.Cu")
		(net "GND")
	)
	(via
		(at 5.472176 -375.834148)
		(size 0.508)
		(drill 0.254)
		(layers "F.Cu" "B.Cu")
		(net "GND")
	)
	(via
		(at 183.75122 -358.367838)
		(size 0.4572)
		(drill 0.254)
		(layers "F.Cu" "B.Cu")
		(net "GND")
	)
	(via
		(at 64.874902 -306.824888)
		(size 0.4064)
		(drill 0.2032)
		(layers "F.Cu" "B.Cu")
		(net "GND")
	)
	(via
		(at 335.328006 -380.141734)
		(size 0.508)
		(drill 0.254)
		(layers "F.Cu" "B.Cu")
		(net "GND")
	)
	(via
		(at 81.024984 -303.024794)
		(size 0.4064)
		(drill 0.2032)
		(layers "F.Cu" "B.Cu")
		(net "GND")
	)
	(via
		(at 119.013732 -124.883926)
		(size 0.508)
		(drill 0.254)
		(layers "F.Cu" "B.Cu")
		(net "GND")
	)
	(via
		(at 414.74771 -149.355048)
		(size 0.508)
		(drill 0.254)
		(layers "F.Cu" "B.Cu")
		(net "GND")
	)
	(via
		(at 315.60008 -304.449734)
		(size 0.4064)
		(drill 0.2032)
		(layers "F.Cu" "B.Cu")
		(net "GND")
	)
	(via
		(at 393.351766 -135.364982)
		(size 0.508)
		(drill 0.254)
		(layers "F.Cu" "B.Cu")
		(net "GND")
	)
	(via
		(at 185.725054 -303.974754)
		(size 0.4064)
		(drill 0.2032)
		(layers "F.Cu" "B.Cu")
		(net "GND")
	)
	(via
		(at 304.416206 -110.12678)
		(size 0.508)
		(drill 0.254)
		(layers "F.Cu" "B.Cu")
		(net "GND")
	)
	(via
		(at 376.289316 -231.53878)
		(size 0.508)
		(drill 0.254)
		(layers "F.Cu" "B.Cu")
		(net "GND")
	)
	(via
		(at 112.92332 -349.219774)
		(size 0.4572)
		(drill 0.254)
		(layers "F.Cu" "B.Cu")
		(net "GND")
	)
	(via
		(at 382.12014 -34.990278)
		(size 0.508)
		(drill 0.254)
		(layers "F.Cu" "B.Cu")
		(net "GND")
	)
	(via
		(at 178.599846 -281.649932)
		(size 0.4064)
		(drill 0.2032)
		(layers "F.Cu" "B.Cu")
		(net "GND")
	)
	(via
		(at 142.293594 -283.131514)
		(size 0.508)
		(drill 0.254)
		(layers "F.Cu" "B.Cu")
		(net "GND")
	)
	(via
		(at 165.947852 -404.838662)
		(size 0.508)
		(drill 0.254)
		(layers "F.Cu" "B.Cu")
		(net "GND")
	)
	(via
		(at 358.21874 -304.373534)
		(size 0.508)
		(drill 0.254)
		(layers "F.Cu" "B.Cu")
		(net "GND")
	)
	(via
		(at 156.314902 -26.171398)
		(size 0.508)
		(drill 0.254)
		(layers "F.Cu" "B.Cu")
		(net "GND")
	)
	(via
		(at 29.942028 -49.574704)
		(size 0.508)
		(drill 0.254)
		(layers "F.Cu" "B.Cu")
		(net "GND")
	)
	(via
		(at 73.547732 -374.938544)
		(size 0.508)
		(drill 0.254)
		(layers "F.Cu" "B.Cu")
		(net "GND")
	)
	(via
		(at 293.27475 -305.874928)
		(size 0.4064)
		(drill 0.2032)
		(layers "F.Cu" "B.Cu")
		(net "GND")
	)
	(via
		(at 272.438622 -357.75773)
		(size 0.4064)
		(drill 0.2032)
		(layers "F.Cu" "B.Cu")
		(net "GND")
	)
	(via
		(at 406.999948 -310.149748)
		(size 0.4064)
		(drill 0.2032)
		(layers "F.Cu" "B.Cu")
		(net "GND")
	)
	(via
		(at 461.36179 -290.807648)
		(size 0.508)
		(drill 0.254)
		(layers "F.Cu" "B.Cu")
		(net "GND")
	)
	(via
		(at 322.890896 -354.098098)
		(size 0.4572)
		(drill 0.254)
		(layers "F.Cu" "B.Cu")
		(net "GND")
	)
	(via
		(at 85.192616 -11.372342)
		(size 0.508)
		(drill 0.254)
		(layers "F.Cu" "B.Cu")
		(net "GND")
	)
	(via
		(at 338.165186 -279.120092)
		(size 0.508)
		(drill 0.254)
		(layers "F.Cu" "B.Cu")
		(net "GND")
	)
	(via
		(at 393.031218 -11.372342)
		(size 0.508)
		(drill 0.254)
		(layers "F.Cu" "B.Cu")
		(net "GND")
	)
	(via
		(at 87.305134 -341.805514)
		(size 0.4572)
		(drill 0.254)
		(layers "F.Cu" "B.Cu")
		(net "GND")
	)
	(via
		(at 343.511378 -290.05149)
		(size 0.508)
		(drill 0.254)
		(layers "F.Cu" "B.Cu")
		(net "GND")
	)
	(via
		(at 72.949816 -276.899878)
		(size 0.4064)
		(drill 0.2032)
		(layers "F.Cu" "B.Cu")
		(net "GND")
	)
	(via
		(at 346.327984 -403.34184)
		(size 0.508)
		(drill 0.254)
		(layers "F.Cu" "B.Cu")
		(net "GND")
	)
	(via
		(at 49.67478 -285.924752)
		(size 0.4064)
		(drill 0.2032)
		(layers "F.Cu" "B.Cu")
		(net "GND")
	)
	(via
		(at 329.480164 -354.732082)
		(size 0.4064)
		(drill 0.2032)
		(layers "F.Cu" "B.Cu")
		(net "GND")
	)
	(via
		(at 84.808314 -147.824698)
		(size 0.508)
		(drill 0.254)
		(layers "F.Cu" "B.Cu")
		(net "GND")
	)
	(via
		(at 394.17498 -290.674806)
		(size 0.4064)
		(drill 0.2032)
		(layers "F.Cu" "B.Cu")
		(net "GND")
	)
	(via
		(at 164.824918 -307.774848)
		(size 0.4064)
		(drill 0.2032)
		(layers "F.Cu" "B.Cu")
		(net "GND")
	)
	(via
		(at 410.799788 -278.799798)
		(size 0.4064)
		(drill 0.2032)
		(layers "F.Cu" "B.Cu")
		(net "GND")
	)
	(via
		(at 405.100028 -276.899878)
		(size 0.4064)
		(drill 0.2032)
		(layers "F.Cu" "B.Cu")
		(net "GND")
	)
	(via
		(at 356.755192 -27.79014)
		(size 0.508)
		(drill 0.254)
		(layers "F.Cu" "B.Cu")
		(net "GND")
	)
	(via
		(at 262.408162 -52.536852)
		(size 0.508)
		(drill 0.254)
		(layers "F.Cu" "B.Cu")
		(net "GND")
	)
	(via
		(at 16.820896 -120.15343)
		(size 0.508)
		(drill 0.254)
		(layers "F.Cu" "B.Cu")
		(net "GND")
	)
	(via
		(at 56.940704 -379.175264)
		(size 0.508)
		(drill 0.254)
		(layers "F.Cu" "B.Cu")
		(net "GND")
	)
	(via
		(at 21.872448 -342.439498)
		(size 0.4064)
		(drill 0.2032)
		(layers "F.Cu" "B.Cu")
		(net "GND")
	)
	(via
		(at 306.7812 -29.859478)
		(size 0.508)
		(drill 0.254)
		(layers "F.Cu" "B.Cu")
		(net "GND")
	)
	(via
		(at 132.93852 -73.20026)
		(size 0.508)
		(drill 0.254)
		(layers "F.Cu" "B.Cu")
		(net "GND")
	)
	(via
		(at 315.414152 -343.073482)
		(size 0.4572)
		(drill 0.254)
		(layers "F.Cu" "B.Cu")
		(net "GND")
	)
	(via
		(at 175.683164 -352.245422)
		(size 0.4572)
		(drill 0.254)
		(layers "F.Cu" "B.Cu")
		(net "GND")
	)
	(via
		(at 126.347728 -385.141978)
		(size 0.4572)
		(drill 0.254)
		(layers "F.Cu" "B.Cu")
		(net "GND")
	)
	(via
		(at 269.99819 -19.096736)
		(size 0.508)
		(drill 0.254)
		(layers "F.Cu" "B.Cu")
		(net "GND")
	)
	(via
		(at 319.848738 -31.390082)
		(size 0.508)
		(drill 0.254)
		(layers "F.Cu" "B.Cu")
		(net "GND")
	)
	(via
		(at 3.633724 -289.23107)
		(size 0.508)
		(drill 0.254)
		(layers "F.Cu" "B.Cu")
		(net "GND")
	)
	(via
		(at 151.83993 -299.2247)
		(size 0.4064)
		(drill 0.2032)
		(layers "F.Cu" "B.Cu")
		(net "GND")
	)
	(via
		(at 51.574954 -305.874928)
		(size 0.4064)
		(drill 0.2032)
		(layers "F.Cu" "B.Cu")
		(net "GND")
	)
	(via
		(at 335.405222 -306.55387)
		(size 0.508)
		(drill 0.254)
		(layers "F.Cu" "B.Cu")
		(net "GND")
	)
	(via
		(at 366.06988 -287.51149)
		(size 0.508)
		(drill 0.254)
		(layers "F.Cu" "B.Cu")
		(net "GND")
	)
	(via
		(at 415.549842 -315.849762)
		(size 0.4064)
		(drill 0.2032)
		(layers "F.Cu" "B.Cu")
		(net "GND")
	)
	(via
		(at 384.674872 -298.274486)
		(size 0.4064)
		(drill 0.2032)
		(layers "F.Cu" "B.Cu")
		(net "GND")
	)
	(via
		(at 73.424796 -296.37482)
		(size 0.4064)
		(drill 0.2032)
		(layers "F.Cu" "B.Cu")
		(net "GND")
	)
	(via
		(at 180.693314 -152.955244)
		(size 0.508)
		(drill 0.254)
		(layers "F.Cu" "B.Cu")
		(net "GND")
	)
	(via
		(at 285.981902 -357.75773)
		(size 0.4064)
		(drill 0.2032)
		(layers "F.Cu" "B.Cu")
		(net "GND")
	)
	(via
		(at 60.124848 -287.899856)
		(size 0.4064)
		(drill 0.2032)
		(layers "F.Cu" "B.Cu")
		(net "GND")
	)
	(via
		(at 296.938954 -352.245422)
		(size 0.4572)
		(drill 0.254)
		(layers "F.Cu" "B.Cu")
		(net "GND")
	)
	(via
		(at 65.542414 -343.073482)
		(size 0.4572)
		(drill 0.254)
		(layers "F.Cu" "B.Cu")
		(net "GND")
	)
	(via
		(at 97.437448 -7.776972)
		(size 0.508)
		(drill 0.254)
		(layers "F.Cu" "B.Cu")
		(net "GND")
	)
	(via
		(at 69.680328 -156.554932)
		(size 0.508)
		(drill 0.254)
		(layers "F.Cu" "B.Cu")
		(net "GND")
	)
	(via
		(at 236.214412 -47.460916)
		(size 0.508)
		(drill 0.254)
		(layers "F.Cu" "B.Cu")
		(net "GND")
	)
	(via
		(at 344.778838 -292.789102)
		(size 0.508)
		(drill 0.254)
		(layers "F.Cu" "B.Cu")
		(net "GND")
	)
	(via
		(at 46.8249 -303.024794)
		(size 0.4064)
		(drill 0.2032)
		(layers "F.Cu" "B.Cu")
		(net "GND")
	)
	(via
		(at 422.260268 -20.35556)
		(size 0.508)
		(drill 0.254)
		(layers "F.Cu" "B.Cu")
		(net "GND")
	)
	(via
		(at 144.506442 -253.45644)
		(size 0.508)
		(drill 0.254)
		(layers "F.Cu" "B.Cu")
		(net "GND")
	)
	(via
		(at 308.000146 -274.049744)
		(size 0.4064)
		(drill 0.2032)
		(layers "F.Cu" "B.Cu")
		(net "GND")
	)
	(via
		(at 184.77484 -301.124874)
		(size 0.4064)
		(drill 0.2032)
		(layers "F.Cu" "B.Cu")
		(net "GND")
	)
	(via
		(at 170.944032 -354.732082)
		(size 0.4064)
		(drill 0.2032)
		(layers "F.Cu" "B.Cu")
		(net "GND")
	)
	(via
		(at 418.399976 -273.099784)
		(size 0.4064)
		(drill 0.2032)
		(layers "F.Cu" "B.Cu")
		(net "GND")
	)
	(via
		(at 270.766286 -253.45644)
		(size 0.508)
		(drill 0.254)
		(layers "F.Cu" "B.Cu")
		(net "GND")
	)
	(via
		(at 419.824916 -303.024794)
		(size 0.4064)
		(drill 0.2032)
		(layers "F.Cu" "B.Cu")
		(net "GND")
	)
	(via
		(at 440.18708 -344.831162)
		(size 0.4572)
		(drill 0.254)
		(layers "F.Cu" "B.Cu")
		(net "GND")
	)
	(via
		(at 31.199328 -345.465146)
		(size 0.4064)
		(drill 0.2032)
		(layers "F.Cu" "B.Cu")
		(net "GND")
	)
	(via
		(at 274.749768 -314.899802)
		(size 0.4064)
		(drill 0.2032)
		(layers "F.Cu" "B.Cu")
		(net "GND")
	)
	(via
		(at 288.141918 -49.574704)
		(size 0.508)
		(drill 0.254)
		(layers "F.Cu" "B.Cu")
		(net "GND")
	)
	(via
		(at 102.386384 -48.874934)
		(size 0.508)
		(drill 0.254)
		(layers "F.Cu" "B.Cu")
		(net "GND")
	)
	(via
		(at 341.25027 -290.05149)
		(size 0.508)
		(drill 0.254)
		(layers "F.Cu" "B.Cu")
		(net "GND")
	)
	(via
		(at 432.12766 -401.040092)
		(size 0.508)
		(drill 0.254)
		(layers "F.Cu" "B.Cu")
		(net "GND")
	)
	(via
		(at 82.93735 -347.951806)
		(size 0.4572)
		(drill 0.254)
		(layers "F.Cu" "B.Cu")
		(net "GND")
	)
	(via
		(at 328.168 -417.82492)
		(size 0.508)
		(drill 0.254)
		(layers "F.Cu" "B.Cu")
		(net "GND")
	)
	(via
		(at 388.127748 -372.341902)
		(size 0.508)
		(drill 0.254)
		(layers "F.Cu" "B.Cu")
		(net "GND")
	)
	(via
		(at 42.557954 -56.809894)
		(size 0.508)
		(drill 0.254)
		(layers "F.Cu" "B.Cu")
		(net "GND")
	)
	(via
		(at 267.959586 -111.72317)
		(size 0.508)
		(drill 0.254)
		(layers "F.Cu" "B.Cu")
		(net "GND")
	)
	(via
		(at 422.792144 -344.831162)
		(size 0.4572)
		(drill 0.254)
		(layers "F.Cu" "B.Cu")
		(net "GND")
	)
	(via
		(at 298.499784 -312.999882)
		(size 0.4064)
		(drill 0.2032)
		(layers "F.Cu" "B.Cu")
		(net "GND")
	)
	(via
		(at 42.747946 -374.938544)
		(size 0.508)
		(drill 0.254)
		(layers "F.Cu" "B.Cu")
		(net "GND")
	)
	(via
		(at 359.127806 -105.573068)
		(size 0.508)
		(drill 0.254)
		(layers "F.Cu" "B.Cu")
		(net "GND")
	)
	(via
		(at 148.700998 -29.590238)
		(size 0.508)
		(drill 0.254)
		(layers "F.Cu" "B.Cu")
		(net "GND")
	)
	(via
		(at 379.327918 -382.84023)
		(size 0.508)
		(drill 0.254)
		(layers "F.Cu" "B.Cu")
		(net "GND")
	)
	(via
		(at 338.807044 -354.732082)
		(size 0.4064)
		(drill 0.2032)
		(layers "F.Cu" "B.Cu")
		(net "GND")
	)
	(via
		(at 166.725092 -289.724846)
		(size 0.4064)
		(drill 0.2032)
		(layers "F.Cu" "B.Cu")
		(net "GND")
	)
	(via
		(at 457.491338 -306.97297)
		(size 0.508)
		(drill 0.254)
		(layers "F.Cu" "B.Cu")
		(net "GND")
	)
	(via
		(at 37.799772 -303.499774)
		(size 0.4064)
		(drill 0.2032)
		(layers "F.Cu" "B.Cu")
		(net "GND")
	)
	(via
		(at 160.550098 -319.65011)
		(size 0.4064)
		(drill 0.2032)
		(layers "F.Cu" "B.Cu")
		(net "GND")
	)
	(via
		(at 161.975038 -293.52494)
		(size 0.4064)
		(drill 0.2032)
		(layers "F.Cu" "B.Cu")
		(net "GND")
	)
	(via
		(at 257.004566 -340.99881)
		(size 0.508)
		(drill 0.254)
		(layers "F.Cu" "B.Cu")
		(net "GND")
	)
	(via
		(at 402.724874 -283.074872)
		(size 0.4064)
		(drill 0.2032)
		(layers "F.Cu" "B.Cu")
		(net "GND")
	)
	(via
		(at 463.037682 -143.777462)
		(size 0.508)
		(drill 0.254)
		(layers "F.Cu" "B.Cu")
		(net "GND")
	)
	(via
		(at 269.999714 -315.849762)
		(size 0.4064)
		(drill 0.2032)
		(layers "F.Cu" "B.Cu")
		(net "GND")
	)
	(via
		(at 333.127858 -383.940304)
		(size 0.508)
		(drill 0.254)
		(layers "F.Cu" "B.Cu")
		(net "GND")
	)
	(via
		(at 161.975038 -289.724846)
		(size 0.4064)
		(drill 0.2032)
		(layers "F.Cu" "B.Cu")
		(net "GND")
	)
	(via
		(at 277.124922 -284.974792)
		(size 0.4064)
		(drill 0.2032)
		(layers "F.Cu" "B.Cu")
		(net "GND")
	)
	(via
		(at 43.024806 -282.124912)
		(size 0.4064)
		(drill 0.2032)
		(layers "F.Cu" "B.Cu")
		(net "GND")
	)
	(via
		(at 282.824936 -302.074834)
		(size 0.4064)
		(drill 0.2032)
		(layers "F.Cu" "B.Cu")
		(net "GND")
	)
	(via
		(at 244.646958 -23.583646)
		(size 0.508)
		(drill 0.254)
		(layers "F.Cu" "B.Cu")
		(net "GND")
	)
	(via
		(at 256.175002 -73.87463)
		(size 0.508)
		(drill 0.254)
		(layers "F.Cu" "B.Cu")
		(net "GND")
	)
	(via
		(at 243.15547 -308.073298)
		(size 0.508)
		(drill 0.254)
		(layers "F.Cu" "B.Cu")
		(net "GND")
	)
	(via
		(at 63.449962 -280.699718)
		(size 0.4064)
		(drill 0.2032)
		(layers "F.Cu" "B.Cu")
		(net "GND")
	)
	(via
		(at 417.450016 -279.749758)
		(size 0.4064)
		(drill 0.2032)
		(layers "F.Cu" "B.Cu")
		(net "GND")
	)
	(via
		(at 413.836612 -345.465146)
		(size 0.4064)
		(drill 0.2032)
		(layers "F.Cu" "B.Cu")
		(net "GND")
	)
	(via
		(at 111.311182 -288.78149)
		(size 0.508)
		(drill 0.254)
		(layers "F.Cu" "B.Cu")
		(net "GND")
	)
	(via
		(at 170.999912 -318.699896)
		(size 0.4064)
		(drill 0.2032)
		(layers "F.Cu" "B.Cu")
		(net "GND")
	)
	(via
		(at 108.89996 -134.87146)
		(size 0.508)
		(drill 0.254)
		(layers "F.Cu" "B.Cu")
		(net "GND")
	)
	(via
		(at 459.04658 -373.00789)
		(size 0.508)
		(drill 0.254)
		(layers "F.Cu" "B.Cu")
		(net "GND")
	)
	(via
		(at 79.12481 -302.074834)
		(size 0.4064)
		(drill 0.2032)
		(layers "F.Cu" "B.Cu")
		(net "GND")
	)
	(via
		(at 170.524932 -306.824888)
		(size 0.4064)
		(drill 0.2032)
		(layers "F.Cu" "B.Cu")
		(net "GND")
	)
	(via
		(at 439.815732 -354.732082)
		(size 0.4064)
		(drill 0.2032)
		(layers "F.Cu" "B.Cu")
		(net "GND")
	)
	(via
		(at 105.948734 -238.553244)
		(size 0.508)
		(drill 0.254)
		(layers "F.Cu" "B.Cu")
		(net "GND")
	)
	(via
		(at 425.04995 -281.649932)
		(size 0.4064)
		(drill 0.2032)
		(layers "F.Cu" "B.Cu")
		(net "GND")
	)
	(via
		(at 293.527734 -373.441976)
		(size 0.508)
		(drill 0.254)
		(layers "F.Cu" "B.Cu")
		(net "GND")
	)
	(via
		(at 160.074864 -282.124912)
		(size 0.4064)
		(drill 0.2032)
		(layers "F.Cu" "B.Cu")
		(net "GND")
	)
	(via
		(at 126.169166 -143.051276)
		(size 0.508)
		(drill 0.254)
		(layers "F.Cu" "B.Cu")
		(net "GND")
	)
	(via
		(at 192.375028 -292.574726)
		(size 0.4064)
		(drill 0.2032)
		(layers "F.Cu" "B.Cu")
		(net "GND")
	)
	(via
		(at 65.824862 -307.774848)
		(size 0.4064)
		(drill 0.2032)
		(layers "F.Cu" "B.Cu")
		(net "GND")
	)
	(via
		(at 52.85232 -125.955044)
		(size 0.508)
		(drill 0.254)
		(layers "F.Cu" "B.Cu")
		(net "GND")
	)
	(via
		(at 71.049896 -312.049922)
		(size 0.4064)
		(drill 0.2032)
		(layers "F.Cu" "B.Cu")
		(net "GND")
	)
	(via
		(at 127.898398 -19.096736)
		(size 0.508)
		(drill 0.254)
		(layers "F.Cu" "B.Cu")
		(net "GND")
	)
	(via
		(at 300.874684 -284.024832)
		(size 0.4064)
		(drill 0.2032)
		(layers "F.Cu" "B.Cu")
		(net "GND")
	)
	(via
		(at 55.849774 -276.899878)
		(size 0.4064)
		(drill 0.2032)
		(layers "F.Cu" "B.Cu")
		(net "GND")
	)
	(via
		(at 72.267064 -123.635008)
		(size 0.508)
		(drill 0.254)
		(layers "F.Cu" "B.Cu")
		(net "GND")
	)
	(via
		(at 181.92496 -287.824926)
		(size 0.4064)
		(drill 0.2032)
		(layers "F.Cu" "B.Cu")
		(net "GND")
	)
	(via
		(at 303.854612 -23.880318)
		(size 0.508)
		(drill 0.254)
		(layers "F.Cu" "B.Cu")
		(net "GND")
	)
	(via
		(at 36.534344 -253.45644)
		(size 0.508)
		(drill 0.254)
		(layers "F.Cu" "B.Cu")
		(net "GND")
	)
	(via
		(at 229.90048 -77.430122)
		(size 0.508)
		(drill 0.254)
		(layers "F.Cu" "B.Cu")
		(net "GND")
	)
	(via
		(at 41.124886 -290.674806)
		(size 0.4064)
		(drill 0.2032)
		(layers "F.Cu" "B.Cu")
		(net "GND")
	)
	(via
		(at 191.227964 -349.219774)
		(size 0.4572)
		(drill 0.254)
		(layers "F.Cu" "B.Cu")
		(net "GND")
	)
	(via
		(at 192.850008 -314.899802)
		(size 0.4064)
		(drill 0.2032)
		(layers "F.Cu" "B.Cu")
		(net "GND")
	)
	(via
		(at 103.685848 -350.44253)
		(size 0.508)
		(drill 0.254)
		(layers "F.Cu" "B.Cu")
		(net "GND")
	)
	(via
		(at 45.26534 -352.245422)
		(size 0.4572)
		(drill 0.254)
		(layers "F.Cu" "B.Cu")
		(net "GND")
	)
	(via
		(at 114.240818 -265.949938)
		(size 0.508)
		(drill 0.254)
		(layers "F.Cu" "B.Cu")
		(net "GND")
	)
	(via
		(at 405.575008 -297.32478)
		(size 0.4064)
		(drill 0.2032)
		(layers "F.Cu" "B.Cu")
		(net "GND")
	)
	(via
		(at 132.120386 -192.743328)
		(size 0.508)
		(drill 0.254)
		(layers "F.Cu" "B.Cu")
		(net "GND")
	)
	(via
		(at 112.92332 -344.831162)
		(size 0.4572)
		(drill 0.254)
		(layers "F.Cu" "B.Cu")
		(net "GND")
	)
	(via
		(at 450.330062 -105.057194)
		(size 0.508)
		(drill 0.254)
		(layers "F.Cu" "B.Cu")
		(net "GND")
	)
	(via
		(at 296.599864 -314.899802)
		(size 0.4064)
		(drill 0.2032)
		(layers "F.Cu" "B.Cu")
		(net "GND")
	)
	(via
		(at 79.599536 -276.899878)
		(size 0.4064)
		(drill 0.2032)
		(layers "F.Cu" "B.Cu")
		(net "GND")
	)
	(via
		(at 189.96914 -346.09913)
		(size 0.4572)
		(drill 0.254)
		(layers "F.Cu" "B.Cu")
		(net "GND")
	)
	(via
		(at 200.00214 -27.729688)
		(size 0.508)
		(drill 0.254)
		(layers "F.Cu" "B.Cu")
		(net "GND")
	)
	(via
		(at 43.974766 -297.32478)
		(size 0.4064)
		(drill 0.2032)
		(layers "F.Cu" "B.Cu")
		(net "GND")
	)
	(via
		(at 286.149796 -315.849762)
		(size 0.4064)
		(drill 0.2032)
		(layers "F.Cu" "B.Cu")
		(net "GND")
	)
	(via
		(at 75.79995 -310.149748)
		(size 0.4064)
		(drill 0.2032)
		(layers "F.Cu" "B.Cu")
		(net "GND")
	)
	(via
		(at 409.849828 -315.849762)
		(size 0.4064)
		(drill 0.2032)
		(layers "F.Cu" "B.Cu")
		(net "GND")
	)
	(via
		(at 406.524968 -305.874928)
		(size 0.4064)
		(drill 0.2032)
		(layers "F.Cu" "B.Cu")
		(net "GND")
	)
	(via
		(at 109.399324 -269.366492)
		(size 0.508)
		(drill 0.254)
		(layers "F.Cu" "B.Cu")
		(net "GND")
	)
	(via
		(at 418.42436 -355.366066)
		(size 0.4572)
		(drill 0.254)
		(layers "F.Cu" "B.Cu")
		(net "GND")
	)
	(via
		(at 33.486344 -253.45644)
		(size 0.508)
		(drill 0.254)
		(layers "F.Cu" "B.Cu")
		(net "GND")
	)
	(via
		(at 315.109606 -303.024794)
		(size 0.4064)
		(drill 0.2032)
		(layers "F.Cu" "B.Cu")
		(net "GND")
	)
	(via
		(at 198.075042 -296.37482)
		(size 0.4064)
		(drill 0.2032)
		(layers "F.Cu" "B.Cu")
		(net "GND")
	)
	(via
		(at 18.020538 -305.19751)
		(size 0.508)
		(drill 0.254)
		(layers "F.Cu" "B.Cu")
		(net "GND")
	)
	(via
		(at 396.0749 -306.824888)
		(size 0.4064)
		(drill 0.2032)
		(layers "F.Cu" "B.Cu")
		(net "GND")
	)
	(via
		(at 286.927798 -371.140228)
		(size 0.508)
		(drill 0.254)
		(layers "F.Cu" "B.Cu")
		(net "GND")
	)
	(via
		(at 243.998242 -21.077936)
		(size 0.508)
		(drill 0.254)
		(layers "F.Cu" "B.Cu")
		(net "GND")
	)
	(via
		(at 106.394504 -101.386894)
		(size 0.508)
		(drill 0.254)
		(layers "F.Cu" "B.Cu")
		(net "GND")
	)
	(via
		(at 117.944646 -172.216064)
		(size 0.508)
		(drill 0.254)
		(layers "F.Cu" "B.Cu")
		(net "GND")
	)
	(via
		(at 127.845058 -29.589984)
		(size 0.508)
		(drill 0.254)
		(layers "F.Cu" "B.Cu")
		(net "GND")
	)
	(via
		(at 424.686476 -48.874934)
		(size 0.508)
		(drill 0.254)
		(layers "F.Cu" "B.Cu")
		(net "GND")
	)
	(via
		(at 281.874722 -305.874928)
		(size 0.4064)
		(drill 0.2032)
		(layers "F.Cu" "B.Cu")
		(net "GND")
	)
	(via
		(at 109.050074 -290.05149)
		(size 0.508)
		(drill 0.254)
		(layers "F.Cu" "B.Cu")
		(net "GND")
	)
	(via
		(at 70.905624 -1.364996)
		(size 0.508)
		(drill 0.254)
		(layers "F.Cu" "B.Cu")
		(net "GND")
	)
	(via
		(at 338.807044 -342.439498)
		(size 0.4064)
		(drill 0.2032)
		(layers "F.Cu" "B.Cu")
		(net "GND")
	)
	(via
		(at 88.947752 -410.041852)
		(size 0.508)
		(drill 0.254)
		(layers "F.Cu" "B.Cu")
		(net "GND")
	)
	(via
		(at 378.738384 -253.45644)
		(size 0.508)
		(drill 0.254)
		(layers "F.Cu" "B.Cu")
		(net "GND")
	)
	(via
		(at 119.809768 -288.14649)
		(size 0.508)
		(drill 0.254)
		(layers "F.Cu" "B.Cu")
		(net "GND")
	)
	(via
		(at 430.749964 -282.599892)
		(size 0.4064)
		(drill 0.2032)
		(layers "F.Cu" "B.Cu")
		(net "GND")
	)
	(via
		(at 122.2502 -346.09913)
		(size 0.4572)
		(drill 0.254)
		(layers "F.Cu" "B.Cu")
		(net "GND")
	)
	(via
		(at 77.69987 -283.549852)
		(size 0.4064)
		(drill 0.2032)
		(layers "F.Cu" "B.Cu")
		(net "GND")
	)
	(via
		(at 410.799788 -310.149748)
		(size 0.4064)
		(drill 0.2032)
		(layers "F.Cu" "B.Cu")
		(net "GND")
	)
	(via
		(at 169.423334 -55.083456)
		(size 0.508)
		(drill 0.254)
		(layers "F.Cu" "B.Cu")
		(net "GND")
	)
	(via
		(at 413.649922 -312.049922)
		(size 0.4064)
		(drill 0.2032)
		(layers "F.Cu" "B.Cu")
		(net "GND")
	)
	(via
		(at 111.664496 -352.245422)
		(size 0.4572)
		(drill 0.254)
		(layers "F.Cu" "B.Cu")
		(net "GND")
	)
	(via
		(at 293.27475 -285.924752)
		(size 0.4064)
		(drill 0.2032)
		(layers "F.Cu" "B.Cu")
		(net "GND")
	)
	(via
		(at 418.42436 -344.831162)
		(size 0.4572)
		(drill 0.254)
		(layers "F.Cu" "B.Cu")
		(net "GND")
	)
	(via
		(at 186.86018 -341.805514)
		(size 0.4572)
		(drill 0.254)
		(layers "F.Cu" "B.Cu")
		(net "GND")
	)
	(via
		(at 418.927788 -375.040144)
		(size 0.508)
		(drill 0.254)
		(layers "F.Cu" "B.Cu")
		(net "GND")
	)
	(via
		(at 153.51887 -262.85698)
		(size 0.508)
		(drill 0.254)
		(layers "F.Cu" "B.Cu")
		(net "GND")
	)
	(via
		(at 446.239138 -29.311854)
		(size 0.508)
		(drill 0.254)
		(layers "F.Cu" "B.Cu")
		(net "GND")
	)
	(via
		(at 208.25206 -187.178696)
		(size 0.508)
		(drill 0.254)
		(layers "F.Cu" "B.Cu")
		(net "GND")
	)
	(via
		(at 56.799988 -312.999882)
		(size 0.4064)
		(drill 0.2032)
		(layers "F.Cu" "B.Cu")
		(net "GND")
	)
	(via
		(at 336.351118 -198.27113)
		(size 0.508)
		(drill 0.254)
		(layers "F.Cu" "B.Cu")
		(net "GND")
	)
	(via
		(at 38.749986 -304.449734)
		(size 0.4064)
		(drill 0.2032)
		(layers "F.Cu" "B.Cu")
		(net "GND")
	)
	(via
		(at 35.6489 -25.990042)
		(size 0.508)
		(drill 0.254)
		(layers "F.Cu" "B.Cu")
		(net "GND")
	)
	(via
		(at 326.371204 -351.611438)
		(size 0.4064)
		(drill 0.2032)
		(layers "F.Cu" "B.Cu")
		(net "GND")
	)
	(via
		(at 389.424926 -291.624766)
		(size 0.4064)
		(drill 0.2032)
		(layers "F.Cu" "B.Cu")
		(net "GND")
	)
	(via
		(at 105.5878 -191.8716)
		(size 0.508)
		(drill 0.254)
		(layers "F.Cu" "B.Cu")
		(net "GND")
	)
	(via
		(at 411.750002 -276.899878)
		(size 0.4064)
		(drill 0.2032)
		(layers "F.Cu" "B.Cu")
		(net "GND")
	)
	(via
		(at 120.991376 -354.098098)
		(size 0.4572)
		(drill 0.254)
		(layers "F.Cu" "B.Cu")
		(net "GND")
	)
	(via
		(at 168.20642 -358.391714)
		(size 0.4572)
		(drill 0.254)
		(layers "F.Cu" "B.Cu")
		(net "GND")
	)
	(via
		(at 344.127836 -395.938502)
		(size 0.508)
		(drill 0.254)
		(layers "F.Cu" "B.Cu")
		(net "GND")
	)
	(via
		(at 135.754872 -23.880318)
		(size 0.508)
		(drill 0.254)
		(layers "F.Cu" "B.Cu")
		(net "GND")
	)
	(via
		(at 192.375028 -291.624766)
		(size 0.4064)
		(drill 0.2032)
		(layers "F.Cu" "B.Cu")
		(net "GND")
	)
	(via
		(at 92.794328 -124.47778)
		(size 0.508)
		(drill 0.254)
		(layers "F.Cu" "B.Cu")
		(net "GND")
	)
	(via
		(at 98.447098 -329.35545)
		(size 0.508)
		(drill 0.254)
		(layers "F.Cu" "B.Cu")
		(net "GND")
	)
	(via
		(at 380.081282 -228.097842)
		(size 0.508)
		(drill 0.254)
		(layers "F.Cu" "B.Cu")
		(net "GND")
	)
	(via
		(at 7.095236 -308.739794)
		(size 0.508)
		(drill 0.254)
		(layers "F.Cu" "B.Cu")
		(net "GND")
	)
	(via
		(at 4.562856 -175.081692)
		(size 0.508)
		(drill 0.254)
		(layers "F.Cu" "B.Cu")
		(net "GND")
	)
	(via
		(at 432.36642 -35.871912)
		(size 0.508)
		(drill 0.254)
		(layers "F.Cu" "B.Cu")
		(net "GND")
	)
	(via
		(at 332.959964 -105.057194)
		(size 0.508)
		(drill 0.254)
		(layers "F.Cu" "B.Cu")
		(net "GND")
	)
	(via
		(at 125.74905 -27.79014)
		(size 0.508)
		(drill 0.254)
		(layers "F.Cu" "B.Cu")
		(net "GND")
	)
	(via
		(at 67.39255 -346.09913)
		(size 0.4572)
		(drill 0.254)
		(layers "F.Cu" "B.Cu")
		(net "GND")
	)
	(via
		(at 426.949616 -281.649932)
		(size 0.4064)
		(drill 0.2032)
		(layers "F.Cu" "B.Cu")
		(net "GND")
	)
	(via
		(at 309.912004 -23.355554)
		(size 0.508)
		(drill 0.254)
		(layers "F.Cu" "B.Cu")
		(net "GND")
	)
	(via
		(at 81.974944 -291.624766)
		(size 0.4064)
		(drill 0.2032)
		(layers "F.Cu" "B.Cu")
		(net "GND")
	)
	(via
		(at 422.199816 -274.049744)
		(size 0.4064)
		(drill 0.2032)
		(layers "F.Cu" "B.Cu")
		(net "GND")
	)
	(via
		(at 392.52779 -373.838724)
		(size 0.508)
		(drill 0.254)
		(layers "F.Cu" "B.Cu")
		(net "GND")
	)
	(via
		(at 185.904124 -132.622036)
		(size 0.508)
		(drill 0.254)
		(layers "F.Cu" "B.Cu")
		(net "GND")
	)
	(via
		(at 170.049952 -316.799722)
		(size 0.4064)
		(drill 0.2032)
		(layers "F.Cu" "B.Cu")
		(net "GND")
	)
	(via
		(at 397.740886 -45.853858)
		(size 0.508)
		(drill 0.254)
		(layers "F.Cu" "B.Cu")
		(net "GND")
	)
	(via
		(at 413.07004 -108.462318)
		(size 0.508)
		(drill 0.254)
		(layers "F.Cu" "B.Cu")
		(net "GND")
	)
	(via
		(at 65.542414 -357.123746)
		(size 0.4572)
		(drill 0.254)
		(layers "F.Cu" "B.Cu")
		(net "GND")
	)
	(via
		(at 60.124848 -306.824888)
		(size 0.4064)
		(drill 0.2032)
		(layers "F.Cu" "B.Cu")
		(net "GND")
	)
	(via
		(at 436.527702 -372.342156)
		(size 0.508)
		(drill 0.254)
		(layers "F.Cu" "B.Cu")
		(net "GND")
	)
	(via
		(at 52.049934 -279.749758)
		(size 0.4064)
		(drill 0.2032)
		(layers "F.Cu" "B.Cu")
		(net "GND")
	)
	(via
		(at 327.008998 -93.98254)
		(size 0.508)
		(drill 0.254)
		(layers "F.Cu" "B.Cu")
		(net "GND")
	)
	(via
		(at 291.84981 -276.899878)
		(size 0.4064)
		(drill 0.2032)
		(layers "F.Cu" "B.Cu")
		(net "GND")
	)
	(via
		(at 62.499748 -281.649932)
		(size 0.4064)
		(drill 0.2032)
		(layers "F.Cu" "B.Cu")
		(net "GND")
	)
	(via
		(at 170.347894 -408.738578)
		(size 0.508)
		(drill 0.254)
		(layers "F.Cu" "B.Cu")
		(net "GND")
	)
	(via
		(at 413.465264 -350.977454)
		(size 0.4572)
		(drill 0.254)
		(layers "F.Cu" "B.Cu")
		(net "GND")
	)
	(via
		(at 69.149976 -312.049922)
		(size 0.4064)
		(drill 0.2032)
		(layers "F.Cu" "B.Cu")
		(net "GND")
	)
	(via
		(at 46.744128 -345.465146)
		(size 0.4064)
		(drill 0.2032)
		(layers "F.Cu" "B.Cu")
		(net "GND")
	)
	(via
		(at 245.825264 -120.11787)
		(size 0.508)
		(drill 0.254)
		(layers "F.Cu" "B.Cu")
		(net "GND")
	)
	(via
		(at 59.820048 -31.390336)
		(size 0.508)
		(drill 0.254)
		(layers "F.Cu" "B.Cu")
		(net "GND")
	)
	(via
		(at 330.223114 -217.125296)
		(size 0.508)
		(drill 0.254)
		(layers "F.Cu" "B.Cu")
		(net "GND")
	)
	(via
		(at 272.374868 -285.924752)
		(size 0.4064)
		(drill 0.2032)
		(layers "F.Cu" "B.Cu")
		(net "GND")
	)
	(via
		(at 321.632072 -344.831162)
		(size 0.4572)
		(drill 0.254)
		(layers "F.Cu" "B.Cu")
		(net "GND")
	)
	(via
		(at 462.938876 -307.607716)
		(size 0.508)
		(drill 0.254)
		(layers "F.Cu" "B.Cu")
		(net "GND")
	)
	(via
		(at 328.93127 -11.372342)
		(size 0.508)
		(drill 0.254)
		(layers "F.Cu" "B.Cu")
		(net "GND")
	)
	(via
		(at 137.795 -343.073482)
		(size 0.4572)
		(drill 0.254)
		(layers "F.Cu" "B.Cu")
		(net "GND")
	)
	(via
		(at 34.4551 -27.79014)
		(size 0.508)
		(drill 0.254)
		(layers "F.Cu" "B.Cu")
		(net "GND")
	)
	(via
		(at 71.347838 -384.041904)
		(size 0.508)
		(drill 0.254)
		(layers "F.Cu" "B.Cu")
		(net "GND")
	)
	(via
		(at 367.03127 -6.292342)
		(size 0.508)
		(drill 0.254)
		(layers "F.Cu" "B.Cu")
		(net "GND")
	)
	(via
		(at 294.22471 -291.624766)
		(size 0.4064)
		(drill 0.2032)
		(layers "F.Cu" "B.Cu")
		(net "GND")
	)
	(via
		(at 388.949946 -303.499774)
		(size 0.4064)
		(drill 0.2032)
		(layers "F.Cu" "B.Cu")
		(net "GND")
	)
	(via
		(at 321.632072 -350.977454)
		(size 0.4572)
		(drill 0.254)
		(layers "F.Cu" "B.Cu")
		(net "GND")
	)
	(via
		(at 448.817746 -287.228788)
		(size 0.508)
		(drill 0.254)
		(layers "F.Cu" "B.Cu")
		(net "GND")
	)
	(via
		(at 399.93316 -113.245138)
		(size 0.508)
		(drill 0.254)
		(layers "F.Cu" "B.Cu")
		(net "GND")
	)
	(via
		(at 164.349938 -312.049922)
		(size 0.4064)
		(drill 0.2032)
		(layers "F.Cu" "B.Cu")
		(net "GND")
	)
	(via
		(at 65.913762 -342.439498)
		(size 0.4064)
		(drill 0.2032)
		(layers "F.Cu" "B.Cu")
		(net "GND")
	)
	(via
		(at 314.174886 -297.32478)
		(size 0.4064)
		(drill 0.2032)
		(layers "F.Cu" "B.Cu")
		(net "GND")
	)
	(via
		(at 161.025078 -287.824926)
		(size 0.4064)
		(drill 0.2032)
		(layers "F.Cu" "B.Cu")
		(net "GND")
	)
	(via
		(at 82.166206 -130.966718)
		(size 0.508)
		(drill 0.254)
		(layers "F.Cu" "B.Cu")
		(net "GND")
	)
	(via
		(at 130.897884 -285.953454)
		(size 0.508)
		(drill 0.254)
		(layers "F.Cu" "B.Cu")
		(net "GND")
	)
	(via
		(at 208.902808 -74.624184)
		(size 0.508)
		(drill 0.254)
		(layers "F.Cu" "B.Cu")
		(net "GND")
	)
	(via
		(at 355.492558 -11.372342)
		(size 0.508)
		(drill 0.254)
		(layers "F.Cu" "B.Cu")
		(net "GND")
	)
	(via
		(at 50.624994 -303.974754)
		(size 0.4064)
		(drill 0.2032)
		(layers "F.Cu" "B.Cu")
		(net "GND")
	)
	(via
		(at 376.069606 -64.102234)
		(size 0.508)
		(drill 0.254)
		(layers "F.Cu" "B.Cu")
		(net "GND")
	)
	(via
		(at 194.336924 -350.977454)
		(size 0.4572)
		(drill 0.254)
		(layers "F.Cu" "B.Cu")
		(net "GND")
	)
	(via
		(at 386.535168 -350.977454)
		(size 0.4572)
		(drill 0.254)
		(layers "F.Cu" "B.Cu")
		(net "GND")
	)
	(via
		(at 330.927964 -382.84023)
		(size 0.508)
		(drill 0.254)
		(layers "F.Cu" "B.Cu")
		(net "GND")
	)
	(via
		(at 192.706752 -345.465146)
		(size 0.4064)
		(drill 0.2032)
		(layers "F.Cu" "B.Cu")
		(net "GND")
	)
	(via
		(at 295.64965 -272.14957)
		(size 0.4064)
		(drill 0.2032)
		(layers "F.Cu" "B.Cu")
		(net "GND")
	)
	(via
		(at 247.177052 -169.575734)
		(size 0.508)
		(drill 0.254)
		(layers "F.Cu" "B.Cu")
		(net "GND")
	)
	(via
		(at 447.536062 -219.75064)
		(size 0.508)
		(drill 0.254)
		(layers "F.Cu" "B.Cu")
		(net "GND")
	)
	(via
		(at 137.795 -357.123746)
		(size 0.4572)
		(drill 0.254)
		(layers "F.Cu" "B.Cu")
		(net "GND")
	)
	(via
		(at 166.356284 -352.245422)
		(size 0.4572)
		(drill 0.254)
		(layers "F.Cu" "B.Cu")
		(net "GND")
	)
	(via
		(at 300.459394 -85.475064)
		(size 0.508)
		(drill 0.254)
		(layers "F.Cu" "B.Cu")
		(net "GND")
	)
	(via
		(at 183.82488 -302.074834)
		(size 0.4064)
		(drill 0.2032)
		(layers "F.Cu" "B.Cu")
		(net "GND")
	)
	(via
		(at 298.78909 -349.219774)
		(size 0.4572)
		(drill 0.254)
		(layers "F.Cu" "B.Cu")
		(net "GND")
	)
	(via
		(at 399.93316 -151.159972)
		(size 0.508)
		(drill 0.254)
		(layers "F.Cu" "B.Cu")
		(net "GND")
	)
	(via
		(at 60.124848 -294.4749)
		(size 0.4064)
		(drill 0.2032)
		(layers "F.Cu" "B.Cu")
		(net "GND")
	)
	(via
		(at 162.924998 -289.724846)
		(size 0.4064)
		(drill 0.2032)
		(layers "F.Cu" "B.Cu")
		(net "GND")
	)
	(via
		(at 174.800006 -277.849838)
		(size 0.4064)
		(drill 0.2032)
		(layers "F.Cu" "B.Cu")
		(net "GND")
	)
	(via
		(at 44.94784 -377.73864)
		(size 0.508)
		(drill 0.254)
		(layers "F.Cu" "B.Cu")
		(net "GND")
	)
	(via
		(at 77.947774 -372.240302)
		(size 0.508)
		(drill 0.254)
		(layers "F.Cu" "B.Cu")
		(net "GND")
	)
	(via
		(at 120.991376 -343.073482)
		(size 0.4572)
		(drill 0.254)
		(layers "F.Cu" "B.Cu")
		(net "GND")
	)
	(via
		(at 154.501596 -102.716584)
		(size 0.508)
		(drill 0.254)
		(layers "F.Cu" "B.Cu")
		(net "GND")
	)
	(via
		(at 300.12767 -395.938502)
		(size 0.508)
		(drill 0.254)
		(layers "F.Cu" "B.Cu")
		(net "GND")
	)
	(via
		(at 300.874684 -291.624766)
		(size 0.4064)
		(drill 0.2032)
		(layers "F.Cu" "B.Cu")
		(net "GND")
	)
	(via
		(at 194.749928 -272.14957)
		(size 0.4064)
		(drill 0.2032)
		(layers "F.Cu" "B.Cu")
		(net "GND")
	)
	(via
		(at 42.747946 -398.24025)
		(size 0.508)
		(drill 0.254)
		(layers "F.Cu" "B.Cu")
		(net "GND")
	)
	(via
		(at 339.914484 -354.732082)
		(size 0.4064)
		(drill 0.2032)
		(layers "F.Cu" "B.Cu")
		(net "GND")
	)
	(via
		(at 258.393438 -299.133514)
		(size 0.508)
		(drill 0.254)
		(layers "F.Cu" "B.Cu")
		(net "GND")
	)
	(via
		(at 424.57497 -300.174914)
		(size 0.4064)
		(drill 0.2032)
		(layers "F.Cu" "B.Cu")
		(net "GND")
	)
	(via
		(at 41.599866 -308.249828)
		(size 0.4064)
		(drill 0.2032)
		(layers "F.Cu" "B.Cu")
		(net "GND")
	)
	(via
		(at 170.347894 -404.838662)
		(size 0.508)
		(drill 0.254)
		(layers "F.Cu" "B.Cu")
		(net "GND")
	)
	(via
		(at 183.3499 -314.899802)
		(size 0.4064)
		(drill 0.2032)
		(layers "F.Cu" "B.Cu")
		(net "GND")
	)
	(via
		(at 47.29988 -318.699896)
		(size 0.4064)
		(drill 0.2032)
		(layers "F.Cu" "B.Cu")
		(net "GND")
	)
	(via
		(at 390.58088 -27.79014)
		(size 0.508)
		(drill 0.254)
		(layers "F.Cu" "B.Cu")
		(net "GND")
	)
	(via
		(at 196.088 -417.82492)
		(size 0.508)
		(drill 0.254)
		(layers "F.Cu" "B.Cu")
		(net "GND")
	)
	(via
		(at 141.275308 -348.58579)
		(size 0.4064)
		(drill 0.2032)
		(layers "F.Cu" "B.Cu")
		(net "GND")
	)
	(via
		(at 225.916744 -181.85638)
		(size 0.508)
		(drill 0.254)
		(layers "F.Cu" "B.Cu")
		(net "GND")
	)
	(via
		(at 269.333726 -107.57535)
		(size 0.508)
		(drill 0.254)
		(layers "F.Cu" "B.Cu")
		(net "GND")
	)
	(via
		(at 91.1479 -382.73863)
		(size 0.508)
		(drill 0.254)
		(layers "F.Cu" "B.Cu")
		(net "GND")
	)
	(via
		(at 309.899812 -314.899802)
		(size 0.4064)
		(drill 0.2032)
		(layers "F.Cu" "B.Cu")
		(net "GND")
	)
	(via
		(at 44.94784 -398.34185)
		(size 0.508)
		(drill 0.254)
		(layers "F.Cu" "B.Cu")
		(net "GND")
	)
	(via
		(at 305.149758 -316.799722)
		(size 0.4064)
		(drill 0.2032)
		(layers "F.Cu" "B.Cu")
		(net "GND")
	)
	(via
		(at 253.95555 -208.149952)
		(size 0.508)
		(drill 0.254)
		(layers "F.Cu" "B.Cu")
		(net "GND")
	)
	(via
		(at 243.248434 -251.857256)
		(size 0.508)
		(drill 0.254)
		(layers "F.Cu" "B.Cu")
		(net "GND")
	)
	(via
		(at 41.124886 -285.924752)
		(size 0.4064)
		(drill 0.2032)
		(layers "F.Cu" "B.Cu")
		(net "GND")
	)
	(via
		(at 313.564016 -343.073482)
		(size 0.4572)
		(drill 0.254)
		(layers "F.Cu" "B.Cu")
		(net "GND")
	)
	(via
		(at 224.269046 -141.570202)
		(size 0.508)
		(drill 0.254)
		(layers "F.Cu" "B.Cu")
		(net "GND")
	)
	(via
		(at 282.824936 -289.724846)
		(size 0.4064)
		(drill 0.2032)
		(layers "F.Cu" "B.Cu")
		(net "GND")
	)
	(via
		(at 163.247324 -354.098098)
		(size 0.4572)
		(drill 0.254)
		(layers "F.Cu" "B.Cu")
		(net "GND")
	)
	(via
		(at 167.732964 -102.445058)
		(size 0.508)
		(drill 0.254)
		(layers "F.Cu" "B.Cu")
		(net "GND")
	)
	(via
		(at 50.624994 -289.724846)
		(size 0.4064)
		(drill 0.2032)
		(layers "F.Cu" "B.Cu")
		(net "GND")
	)
	(via
		(at 301.349664 -272.14957)
		(size 0.4064)
		(drill 0.2032)
		(layers "F.Cu" "B.Cu")
		(net "GND")
	)
	(via
		(at 409.068016 -54.238906)
		(size 0.508)
		(drill 0.254)
		(layers "F.Cu" "B.Cu")
		(net "GND")
	)
	(via
		(at 275.176234 -347.951806)
		(size 0.4572)
		(drill 0.254)
		(layers "F.Cu" "B.Cu")
		(net "GND")
	)
	(via
		(at 313.09818 -147.27682)
		(size 0.508)
		(drill 0.254)
		(layers "F.Cu" "B.Cu")
		(net "GND")
	)
	(via
		(at 351.374964 -291.32149)
		(size 0.508)
		(drill 0.254)
		(layers "F.Cu" "B.Cu")
		(net "GND")
	)
	(via
		(at 250.320556 -63.218314)
		(size 0.508)
		(drill 0.254)
		(layers "F.Cu" "B.Cu")
		(net "GND")
	)
	(via
		(at 72.28332 -154.461718)
		(size 0.508)
		(drill 0.254)
		(layers "F.Cu" "B.Cu")
		(net "GND")
	)
	(via
		(at 0.77089 -329.701144)
		(size 0.508)
		(drill 0.254)
		(layers "F.Cu" "B.Cu")
		(net "GND")
	)
	(via
		(at 414.11271 -152.955244)
		(size 0.508)
		(drill 0.254)
		(layers "F.Cu" "B.Cu")
		(net "GND")
	)
	(via
		(at 414.11271 -133.0452)
		(size 0.508)
		(drill 0.254)
		(layers "F.Cu" "B.Cu")
		(net "GND")
	)
	(via
		(at 70.099936 -318.699896)
		(size 0.4064)
		(drill 0.2032)
		(layers "F.Cu" "B.Cu")
		(net "GND")
	)
	(via
		(at 61.549788 -314.899802)
		(size 0.4064)
		(drill 0.2032)
		(layers "F.Cu" "B.Cu")
		(net "GND")
	)
	(via
		(at 155.800044 -318.699896)
		(size 0.4064)
		(drill 0.2032)
		(layers "F.Cu" "B.Cu")
		(net "GND")
	)
	(via
		(at 61.549788 -311.099962)
		(size 0.4064)
		(drill 0.2032)
		(layers "F.Cu" "B.Cu")
		(net "GND")
	)
	(via
		(at 188.232288 -121.655332)
		(size 0.508)
		(drill 0.254)
		(layers "F.Cu" "B.Cu")
		(net "GND")
	)
	(via
		(at 185.381392 -348.58579)
		(size 0.4064)
		(drill 0.2032)
		(layers "F.Cu" "B.Cu")
		(net "GND")
	)
	(via
		(at 166.381684 -357.123746)
		(size 0.4572)
		(drill 0.254)
		(layers "F.Cu" "B.Cu")
		(net "GND")
	)
	(via
		(at 185.573416 -73.20026)
		(size 0.508)
		(drill 0.254)
		(layers "F.Cu" "B.Cu")
		(net "GND")
	)
	(via
		(at 19.939254 -29.311854)
		(size 0.508)
		(drill 0.254)
		(layers "F.Cu" "B.Cu")
		(net "GND")
	)
	(via
		(at 281.747468 -121.692416)
		(size 0.508)
		(drill 0.254)
		(layers "F.Cu" "B.Cu")
		(net "GND")
	)
	(via
		(at 398.971008 -350.977454)
		(size 0.4572)
		(drill 0.254)
		(layers "F.Cu" "B.Cu")
		(net "GND")
	)
	(via
		(at 361.437936 -292.789102)
		(size 0.508)
		(drill 0.254)
		(layers "F.Cu" "B.Cu")
		(net "GND")
	)
	(via
		(at 143.423386 -54.067456)
		(size 0.508)
		(drill 0.254)
		(layers "F.Cu" "B.Cu")
		(net "GND")
	)
	(via
		(at 392.38174 -357.75773)
		(size 0.4064)
		(drill 0.2032)
		(layers "F.Cu" "B.Cu")
		(net "GND")
	)
	(via
		(at 43.974766 -299.224954)
		(size 0.4064)
		(drill 0.2032)
		(layers "F.Cu" "B.Cu")
		(net "GND")
	)
	(via
		(at 39.224966 -272.624804)
		(size 0.4064)
		(drill 0.2032)
		(layers "F.Cu" "B.Cu")
		(net "GND")
	)
	(via
		(at 103.15067 -289.41649)
		(size 0.508)
		(drill 0.254)
		(layers "F.Cu" "B.Cu")
		(net "GND")
	)
	(via
		(at 175.683164 -357.123746)
		(size 0.4572)
		(drill 0.254)
		(layers "F.Cu" "B.Cu")
		(net "GND")
	)
	(via
		(at 420.567104 -143.955008)
		(size 0.508)
		(drill 0.254)
		(layers "F.Cu" "B.Cu")
		(net "GND")
	)
	(via
		(at 197.600062 -278.799798)
		(size 0.4064)
		(drill 0.2032)
		(layers "F.Cu" "B.Cu")
		(net "GND")
	)
	(via
		(at 392.88212 -58.238644)
		(size 0.508)
		(drill 0.254)
		(layers "F.Cu" "B.Cu")
		(net "GND")
	)
	(via
		(at 227.063046 -139.792202)
		(size 0.508)
		(drill 0.254)
		(layers "F.Cu" "B.Cu")
		(net "GND")
	)
	(via
		(at 406.900888 -31.390336)
		(size 0.508)
		(drill 0.254)
		(layers "F.Cu" "B.Cu")
		(net "GND")
	)
	(via
		(at 246.330724 -252.230382)
		(size 0.508)
		(drill 0.254)
		(layers "F.Cu" "B.Cu")
		(net "GND")
	)
	(via
		(at 400.01063 -86.066122)
		(size 0.508)
		(drill 0.254)
		(layers "F.Cu" "B.Cu")
		(net "GND")
	)
	(via
		(at 102.112572 -102.271068)
		(size 0.508)
		(drill 0.254)
		(layers "F.Cu" "B.Cu")
		(net "GND")
	)
	(via
		(at 136.536176 -357.123746)
		(size 0.4572)
		(drill 0.254)
		(layers "F.Cu" "B.Cu")
		(net "GND")
	)
	(via
		(at 174.052992 -348.58579)
		(size 0.4064)
		(drill 0.2032)
		(layers "F.Cu" "B.Cu")
		(net "GND")
	)
	(via
		(at 387.525006 -289.724846)
		(size 0.4064)
		(drill 0.2032)
		(layers "F.Cu" "B.Cu")
		(net "GND")
	)
	(via
		(at 277.599902 -306.349908)
		(size 0.4064)
		(drill 0.2032)
		(layers "F.Cu" "B.Cu")
		(net "GND")
	)
	(via
		(at 379.327918 -398.34185)
		(size 0.508)
		(drill 0.254)
		(layers "F.Cu" "B.Cu")
		(net "GND")
	)
	(via
		(at 193.324988 -299.224954)
		(size 0.4064)
		(drill 0.2032)
		(layers "F.Cu" "B.Cu")
		(net "GND")
	)
	(via
		(at 248.567956 -307.484272)
		(size 0.508)
		(drill 0.254)
		(layers "F.Cu" "B.Cu")
		(net "GND")
	)
	(via
		(at 168.625012 -296.37482)
		(size 0.4064)
		(drill 0.2032)
		(layers "F.Cu" "B.Cu")
		(net "GND")
	)
	(via
		(at 369.590066 -73.85177)
		(size 0.508)
		(drill 0.254)
		(layers "F.Cu" "B.Cu")
		(net "GND")
	)
	(via
		(at 417.94811 -129.445004)
		(size 0.508)
		(drill 0.254)
		(layers "F.Cu" "B.Cu")
		(net "GND")
	)
	(via
		(at 38.401752 -102.716584)
		(size 0.508)
		(drill 0.254)
		(layers "F.Cu" "B.Cu")
		(net "GND")
	)
	(via
		(at 198.550022 -313.949842)
		(size 0.4064)
		(drill 0.2032)
		(layers "F.Cu" "B.Cu")
		(net "GND")
	)
	(via
		(at 384.059684 -108.123228)
		(size 0.508)
		(drill 0.254)
		(layers "F.Cu" "B.Cu")
		(net "GND")
	)
	(via
		(at 122.2502 -357.123746)
		(size 0.4572)
		(drill 0.254)
		(layers "F.Cu" "B.Cu")
		(net "GND")
	)
	(via
		(at 413.649922 -316.799722)
		(size 0.4064)
		(drill 0.2032)
		(layers "F.Cu" "B.Cu")
		(net "GND")
	)
	(via
		(at 183.82488 -303.974754)
		(size 0.4064)
		(drill 0.2032)
		(layers "F.Cu" "B.Cu")
		(net "GND")
	)
	(via
		(at 236.638338 -150.690834)
		(size 0.508)
		(drill 0.254)
		(layers "F.Cu" "B.Cu")
		(net "GND")
	)
	(via
		(at 324.795896 -103.894128)
		(size 0.508)
		(drill 0.254)
		(layers "F.Cu" "B.Cu")
		(net "GND")
	)
	(via
		(at 268.574774 -278.324818)
		(size 0.4064)
		(drill 0.2032)
		(layers "F.Cu" "B.Cu")
		(net "GND")
	)
	(via
		(at 338.666328 -79.516732)
		(size 0.508)
		(drill 0.254)
		(layers "F.Cu" "B.Cu")
		(net "GND")
	)
	(via
		(at 446.809368 -403.386798)
		(size 0.508)
		(drill 0.254)
		(layers "F.Cu" "B.Cu")
		(net "GND")
	)
	(via
		(at 268.09954 -304.449988)
		(size 0.4064)
		(drill 0.2032)
		(layers "F.Cu" "B.Cu")
		(net "GND")
	)
	(via
		(at 197.457822 -25.971246)
		(size 0.508)
		(drill 0.254)
		(layers "F.Cu" "B.Cu")
		(net "GND")
	)
	(via
		(at 134.488174 -135.343646)
		(size 0.508)
		(drill 0.254)
		(layers "F.Cu" "B.Cu")
		(net "GND")
	)
	(via
		(at 247.467628 -212.854794)
		(size 0.508)
		(drill 0.254)
		(layers "F.Cu" "B.Cu")
		(net "GND")
	)
	(via
		(at 180.693314 -125.435106)
		(size 0.508)
		(drill 0.254)
		(layers "F.Cu" "B.Cu")
		(net "GND")
	)
	(via
		(at 7.192518 -11.372342)
		(size 0.508)
		(drill 0.254)
		(layers "F.Cu" "B.Cu")
		(net "GND")
	)
	(via
		(at 175.683164 -349.219774)
		(size 0.4572)
		(drill 0.254)
		(layers "F.Cu" "B.Cu")
		(net "GND")
	)
	(via
		(at 276.871176 -32.911796)
		(size 0.508)
		(drill 0.254)
		(layers "F.Cu" "B.Cu")
		(net "GND")
	)
	(via
		(at 325.561198 -114.99596)
		(size 0.508)
		(drill 0.254)
		(layers "F.Cu" "B.Cu")
		(net "GND")
	)
	(via
		(at 73.31329 -31.118302)
		(size 0.508)
		(drill 0.254)
		(layers "F.Cu" "B.Cu")
		(net "GND")
	)
	(via
		(at 310.374792 -299.224954)
		(size 0.4064)
		(drill 0.2032)
		(layers "F.Cu" "B.Cu")
		(net "GND")
	)
	(via
		(at 5.432044 -69.392292)
		(size 0.508)
		(drill 0.254)
		(layers "F.Cu" "B.Cu")
		(net "GND")
	)
	(via
		(at 165.546786 -109.177328)
		(size 0.508)
		(drill 0.254)
		(layers "F.Cu" "B.Cu")
		(net "GND")
	)
	(via
		(at 47.222156 -52.51704)
		(size 0.508)
		(drill 0.254)
		(layers "F.Cu" "B.Cu")
		(net "GND")
	)
	(via
		(at 386.535168 -341.805514)
		(size 0.4572)
		(drill 0.254)
		(layers "F.Cu" "B.Cu")
		(net "GND")
	)
	(via
		(at 241.06378 -347.400118)
		(size 0.508)
		(drill 0.254)
		(layers "F.Cu" "B.Cu")
		(net "GND")
	)
	(via
		(at 27.270456 -28.040076)
		(size 0.508)
		(drill 0.254)
		(layers "F.Cu" "B.Cu")
		(net "GND")
	)
	(via
		(at 438.336944 -344.831162)
		(size 0.4572)
		(drill 0.254)
		(layers "F.Cu" "B.Cu")
		(net "GND")
	)
	(via
		(at 306.099718 -307.299868)
		(size 0.4064)
		(drill 0.2032)
		(layers "F.Cu" "B.Cu")
		(net "GND")
	)
	(via
		(at 302.774858 -307.774848)
		(size 0.4064)
		(drill 0.2032)
		(layers "F.Cu" "B.Cu")
		(net "GND")
	)
	(via
		(at 236.577378 -48.770286)
		(size 0.508)
		(drill 0.254)
		(layers "F.Cu" "B.Cu")
		(net "GND")
	)
	(via
		(at 27.347926 -395.938502)
		(size 0.508)
		(drill 0.254)
		(layers "F.Cu" "B.Cu")
		(net "GND")
	)
	(via
		(at 424.57497 -299.224954)
		(size 0.4064)
		(drill 0.2032)
		(layers "F.Cu" "B.Cu")
		(net "GND")
	)
	(via
		(at 330.927964 -402.241766)
		(size 0.508)
		(drill 0.254)
		(layers "F.Cu" "B.Cu")
		(net "GND")
	)
	(via
		(at 316.4586 -388.112)
		(size 0.508)
		(drill 0.254)
		(layers "F.Cu" "B.Cu")
		(net "GND")
	)
	(via
		(at 269.577312 -149.747224)
		(size 0.508)
		(drill 0.254)
		(layers "F.Cu" "B.Cu")
		(net "GND")
	)
	(via
		(at 83.540346 -123.904502)
		(size 0.508)
		(drill 0.254)
		(layers "F.Cu" "B.Cu")
		(net "GND")
	)
	(via
		(at 293.84879 -25.990042)
		(size 0.508)
		(drill 0.254)
		(layers "F.Cu" "B.Cu")
		(net "GND")
	)
	(via
		(at 185.010044 -341.805514)
		(size 0.4572)
		(drill 0.254)
		(layers "F.Cu" "B.Cu")
		(net "GND")
	)
	(via
		(at 128.547622 -375.040144)
		(size 0.4572)
		(drill 0.254)
		(layers "F.Cu" "B.Cu")
		(net "GND")
	)
	(via
		(at 164.726112 -348.58579)
		(size 0.4064)
		(drill 0.2032)
		(layers "F.Cu" "B.Cu")
		(net "GND")
	)
	(via
		(at 306.099718 -308.249828)
		(size 0.4064)
		(drill 0.2032)
		(layers "F.Cu" "B.Cu")
		(net "GND")
	)
	(via
		(at 90.414094 -357.123746)
		(size 0.4572)
		(drill 0.254)
		(layers "F.Cu" "B.Cu")
		(net "GND")
	)
	(via
		(at 6.176264 -15.119858)
		(size 0.508)
		(drill 0.254)
		(layers "F.Cu" "B.Cu")
		(net "GND")
	)
	(via
		(at 386.701792 -99.116642)
		(size 0.508)
		(drill 0.254)
		(layers "F.Cu" "B.Cu")
		(net "GND")
	)
	(via
		(at 419.349936 -314.899802)
		(size 0.4064)
		(drill 0.2032)
		(layers "F.Cu" "B.Cu")
		(net "GND")
	)
	(via
		(at 131.537964 -74.624184)
		(size 0.508)
		(drill 0.254)
		(layers "F.Cu" "B.Cu")
		(net "GND")
	)
	(via
		(at 463.761328 -278.787606)
		(size 0.508)
		(drill 0.254)
		(layers "F.Cu" "B.Cu")
		(net "GND")
	)
	(via
		(at 76.27493 -289.724846)
		(size 0.4064)
		(drill 0.2032)
		(layers "F.Cu" "B.Cu")
		(net "GND")
	)
	(via
		(at 180.788056 -114.267742)
		(size 0.508)
		(drill 0.254)
		(layers "F.Cu" "B.Cu")
		(net "GND")
	)
	(via
		(at 280.745692 -151.9936)
		(size 0.508)
		(drill 0.254)
		(layers "F.Cu" "B.Cu")
		(net "GND")
	)
	(via
		(at 61.074808 -291.624766)
		(size 0.4064)
		(drill 0.2032)
		(layers "F.Cu" "B.Cu")
		(net "GND")
	)
	(via
		(at 302.299878 -317.749936)
		(size 0.4064)
		(drill 0.2032)
		(layers "F.Cu" "B.Cu")
		(net "GND")
	)
	(via
		(at 20.39366 -350.977454)
		(size 0.4572)
		(drill 0.254)
		(layers "F.Cu" "B.Cu")
		(net "GND")
	)
	(via
		(at 168.20642 -341.805514)
		(size 0.4572)
		(drill 0.254)
		(layers "F.Cu" "B.Cu")
		(net "GND")
	)
	(via
		(at 49.67478 -303.974754)
		(size 0.4064)
		(drill 0.2032)
		(layers "F.Cu" "B.Cu")
		(net "GND")
	)
	(via
		(at 333.127858 -380.040134)
		(size 0.508)
		(drill 0.254)
		(layers "F.Cu" "B.Cu")
		(net "GND")
	)
	(via
		(at 146.304762 -237.517178)
		(size 0.508)
		(drill 0.254)
		(layers "F.Cu" "B.Cu")
		(net "GND")
	)
	(via
		(at 385.624832 -274.524724)
		(size 0.4064)
		(drill 0.2032)
		(layers "F.Cu" "B.Cu")
		(net "GND")
	)
	(via
		(at 230.558848 -110.930436)
		(size 0.508)
		(drill 0.254)
		(layers "F.Cu" "B.Cu")
		(net "GND")
	)
	(via
		(at 27.347926 -373.83847)
		(size 0.508)
		(drill 0.254)
		(layers "F.Cu" "B.Cu")
		(net "GND")
	)
	(via
		(at 65.81267 -151.155146)
		(size 0.508)
		(drill 0.254)
		(layers "F.Cu" "B.Cu")
		(net "GND")
	)
	(via
		(at 39.500302 -270.547592)
		(size 0.508)
		(drill 0.254)
		(layers "F.Cu" "B.Cu")
		(net "GND")
	)
	(via
		(at 33.947862 -380.040134)
		(size 0.508)
		(drill 0.254)
		(layers "F.Cu" "B.Cu")
		(net "GND")
	)
	(via
		(at 200.908158 -151.42464)
		(size 0.508)
		(drill 0.254)
		(layers "F.Cu" "B.Cu")
		(net "GND")
	)
	(via
		(at 137.608564 -258.665472)
		(size 0.508)
		(drill 0.254)
		(layers "F.Cu" "B.Cu")
		(net "GND")
	)
	(via
		(at 312.305192 -352.245422)
		(size 0.4572)
		(drill 0.254)
		(layers "F.Cu" "B.Cu")
		(net "GND")
	)
	(via
		(at 332.944724 -107.681776)
		(size 0.508)
		(drill 0.254)
		(layers "F.Cu" "B.Cu")
		(net "GND")
	)
	(via
		(at 187.624974 -303.024794)
		(size 0.4064)
		(drill 0.2032)
		(layers "F.Cu" "B.Cu")
		(net "GND")
	)
	(via
		(at 48.764952 -98.845116)
		(size 0.508)
		(drill 0.254)
		(layers "F.Cu" "B.Cu")
		(net "GND")
	)
	(via
		(at 117.210586 -288.14649)
		(size 0.508)
		(drill 0.254)
		(layers "F.Cu" "B.Cu")
		(net "GND")
	)
	(via
		(at 300.047914 -355.366066)
		(size 0.4572)
		(drill 0.254)
		(layers "F.Cu" "B.Cu")
		(net "GND")
	)
	(via
		(at 43.974766 -292.57498)
		(size 0.4064)
		(drill 0.2032)
		(layers "F.Cu" "B.Cu")
		(net "GND")
	)
	(via
		(at 160.284668 -73.20026)
		(size 0.508)
		(drill 0.254)
		(layers "F.Cu" "B.Cu")
		(net "GND")
	)
	(via
		(at 172.042074 -49.574704)
		(size 0.508)
		(drill 0.254)
		(layers "F.Cu" "B.Cu")
		(net "GND")
	)
	(via
		(at 430.274984 -297.32478)
		(size 0.4064)
		(drill 0.2032)
		(layers "F.Cu" "B.Cu")
		(net "GND")
	)
	(via
		(at 419.824916 -293.52494)
		(size 0.4064)
		(drill 0.2032)
		(layers "F.Cu" "B.Cu")
		(net "GND")
	)
	(via
		(at 170.806364 -135.364982)
		(size 0.508)
		(drill 0.254)
		(layers "F.Cu" "B.Cu")
		(net "GND")
	)
	(via
		(at 148.209254 -203.411074)
		(size 0.508)
		(drill 0.254)
		(layers "F.Cu" "B.Cu")
		(net "GND")
	)
	(via
		(at 390.327896 -372.240302)
		(size 0.508)
		(drill 0.254)
		(layers "F.Cu" "B.Cu")
		(net "GND")
	)
	(via
		(at 167.675052 -305.874928)
		(size 0.4064)
		(drill 0.2032)
		(layers "F.Cu" "B.Cu")
		(net "GND")
	)
	(via
		(at 353.76866 -59.974734)
		(size 0.508)
		(drill 0.254)
		(layers "F.Cu" "B.Cu")
		(net "GND")
	)
	(via
		(at 47.115476 -349.219774)
		(size 0.4572)
		(drill 0.254)
		(layers "F.Cu" "B.Cu")
		(net "GND")
	)
	(via
		(at 54.424834 -305.874928)
		(size 0.4064)
		(drill 0.2032)
		(layers "F.Cu" "B.Cu")
		(net "GND")
	)
	(via
		(at 399.288 -417.82492)
		(size 0.508)
		(drill 0.254)
		(layers "F.Cu" "B.Cu")
		(net "GND")
	)
	(via
		(at 429.010064 -355.366066)
		(size 0.4572)
		(drill 0.254)
		(layers "F.Cu" "B.Cu")
		(net "GND")
	)
	(via
		(at 385.356862 -230.725218)
		(size 0.508)
		(drill 0.254)
		(layers "F.Cu" "B.Cu")
		(net "GND")
	)
	(via
		(at 354.835968 -285.267654)
		(size 0.508)
		(drill 0.254)
		(layers "F.Cu" "B.Cu")
		(net "GND")
	)
	(via
		(at 290.721034 -343.073482)
		(size 0.4572)
		(drill 0.254)
		(layers "F.Cu" "B.Cu")
		(net "GND")
	)
	(via
		(at 302.327818 -411.141926)
		(size 0.508)
		(drill 0.254)
		(layers "F.Cu" "B.Cu")
		(net "GND")
	)
	(via
		(at 270.474948 -274.524978)
		(size 0.4064)
		(drill 0.2032)
		(layers "F.Cu" "B.Cu")
		(net "GND")
	)
	(via
		(at 417.924996 -294.4749)
		(size 0.4064)
		(drill 0.2032)
		(layers "F.Cu" "B.Cu")
		(net "GND")
	)
	(via
		(at 191.900048 -313.949842)
		(size 0.4064)
		(drill 0.2032)
		(layers "F.Cu" "B.Cu")
		(net "GND")
	)
	(via
		(at 332.160118 -19.33956)
		(size 0.508)
		(drill 0.254)
		(layers "F.Cu" "B.Cu")
		(net "GND")
	)
	(via
		(at 165.947852 -397.038576)
		(size 0.508)
		(drill 0.254)
		(layers "F.Cu" "B.Cu")
		(net "GND")
	)
	(via
		(at 434.327808 -372.240302)
		(size 0.508)
		(drill 0.254)
		(layers "F.Cu" "B.Cu")
		(net "GND")
	)
	(via
		(at 335.350866 -290.68649)
		(size 0.508)
		(drill 0.254)
		(layers "F.Cu" "B.Cu")
		(net "GND")
	)
	(via
		(at 401.299934 -277.849838)
		(size 0.4064)
		(drill 0.2032)
		(layers "F.Cu" "B.Cu")
		(net "GND")
	)
	(via
		(at 282.824936 -284.974792)
		(size 0.4064)
		(drill 0.2032)
		(layers "F.Cu" "B.Cu")
		(net "GND")
	)
	(via
		(at 144.363948 -256.987548)
		(size 0.508)
		(drill 0.254)
		(layers "F.Cu" "B.Cu")
		(net "GND")
	)
	(via
		(at 60.599828 -281.649932)
		(size 0.4064)
		(drill 0.2032)
		(layers "F.Cu" "B.Cu")
		(net "GND")
	)
	(via
		(at 405.575008 -294.4749)
		(size 0.4064)
		(drill 0.2032)
		(layers "F.Cu" "B.Cu")
		(net "GND")
	)
	(via
		(at 282.824936 -300.174914)
		(size 0.4064)
		(drill 0.2032)
		(layers "F.Cu" "B.Cu")
		(net "GND")
	)
	(via
		(at 65.902078 -58.096404)
		(size 0.508)
		(drill 0.254)
		(layers "F.Cu" "B.Cu")
		(net "GND")
	)
	(via
		(at 76.348082 -357.75773)
		(size 0.4064)
		(drill 0.2032)
		(layers "F.Cu" "B.Cu")
		(net "GND")
	)
	(via
		(at 343.394792 -357.123746)
		(size 0.4572)
		(drill 0.254)
		(layers "F.Cu" "B.Cu")
		(net "GND")
	)
	(via
		(at 86.04631 -346.09913)
		(size 0.4572)
		(drill 0.254)
		(layers "F.Cu" "B.Cu")
		(net "GND")
	)
	(via
		(at 298.974764 -305.874928)
		(size 0.4064)
		(drill 0.2032)
		(layers "F.Cu" "B.Cu")
		(net "GND")
	)
	(via
		(at 315.414152 -352.245422)
		(size 0.4572)
		(drill 0.254)
		(layers "F.Cu" "B.Cu")
		(net "GND")
	)
	(via
		(at 316.672976 -355.366066)
		(size 0.4572)
		(drill 0.254)
		(layers "F.Cu" "B.Cu")
		(net "GND")
	)
	(via
		(at 110.701836 -129.43332)
		(size 0.508)
		(drill 0.254)
		(layers "F.Cu" "B.Cu")
		(net "GND")
	)
	(via
		(at 430.466246 -147.27682)
		(size 0.508)
		(drill 0.254)
		(layers "F.Cu" "B.Cu")
		(net "GND")
	)
	(via
		(at 180.02504 -285.924752)
		(size 0.4064)
		(drill 0.2032)
		(layers "F.Cu" "B.Cu")
		(net "GND")
	)
	(via
		(at 171.474892 -300.174914)
		(size 0.4064)
		(drill 0.2032)
		(layers "F.Cu" "B.Cu")
		(net "GND")
	)
	(via
		(at 144.098264 -210.241896)
		(size 0.508)
		(drill 0.254)
		(layers "F.Cu" "B.Cu")
		(net "GND")
	)
	(via
		(at 193.799968 -308.249828)
		(size 0.4064)
		(drill 0.2032)
		(layers "F.Cu" "B.Cu")
		(net "GND")
	)
	(via
		(at 6.818376 -233.769916)
		(size 0.508)
		(drill 0.254)
		(layers "F.Cu" "B.Cu")
		(net "GND")
	)
	(via
		(at 52.049934 -280.699718)
		(size 0.4064)
		(drill 0.2032)
		(layers "F.Cu" "B.Cu")
		(net "GND")
	)
	(via
		(at 82.347816 -373.441976)
		(size 0.508)
		(drill 0.254)
		(layers "F.Cu" "B.Cu")
		(net "GND")
	)
	(via
		(at 443.138306 -73.20026)
		(size 0.508)
		(drill 0.254)
		(layers "F.Cu" "B.Cu")
		(net "GND")
	)
	(via
		(at 381.527812 -404.838662)
		(size 0.508)
		(drill 0.254)
		(layers "F.Cu" "B.Cu")
		(net "GND")
	)
	(via
		(at 269.764764 -154.327352)
		(size 0.508)
		(drill 0.254)
		(layers "F.Cu" "B.Cu")
		(net "GND")
	)
	(via
		(at 358.403652 -250.286266)
		(size 0.508)
		(drill 0.254)
		(layers "F.Cu" "B.Cu")
		(net "GND")
	)
	(via
		(at 452.775574 -309.7276)
		(size 0.508)
		(drill 0.254)
		(layers "F.Cu" "B.Cu")
		(net "GND")
	)
	(via
		(at 51.574954 -289.724846)
		(size 0.4064)
		(drill 0.2032)
		(layers "F.Cu" "B.Cu")
		(net "GND")
	)
	(via
		(at 29.54782 -400.938492)
		(size 0.508)
		(drill 0.254)
		(layers "F.Cu" "B.Cu")
		(net "GND")
	)
	(via
		(at 354.900992 -29.590238)
		(size 0.508)
		(drill 0.254)
		(layers "F.Cu" "B.Cu")
		(net "GND")
	)
	(via
		(at 165.947852 -403.34184)
		(size 0.508)
		(drill 0.254)
		(layers "F.Cu" "B.Cu")
		(net "GND")
	)
	(via
		(at 125.154944 -122.931428)
		(size 0.508)
		(drill 0.254)
		(layers "F.Cu" "B.Cu")
		(net "GND")
	)
	(via
		(at 186.836304 -218.89212)
		(size 0.508)
		(drill 0.254)
		(layers "F.Cu" "B.Cu")
		(net "GND")
	)
	(via
		(at 285.687262 -106.044746)
		(size 0.508)
		(drill 0.254)
		(layers "F.Cu" "B.Cu")
		(net "GND")
	)
	(via
		(at 434.327808 -385.141978)
		(size 0.508)
		(drill 0.254)
		(layers "F.Cu" "B.Cu")
		(net "GND")
	)
	(via
		(at 422.792144 -355.366066)
		(size 0.4572)
		(drill 0.254)
		(layers "F.Cu" "B.Cu")
		(net "GND")
	)
	(via
		(at 330.13904 -28.05303)
		(size 0.508)
		(drill 0.254)
		(layers "F.Cu" "B.Cu")
		(net "GND")
	)
	(via
		(at 299.749972 -109.879892)
		(size 0.508)
		(drill 0.254)
		(layers "F.Cu" "B.Cu")
		(net "GND")
	)
	(via
		(at 106.713274 -286.842454)
		(size 0.508)
		(drill 0.254)
		(layers "F.Cu" "B.Cu")
		(net "GND")
	)
	(via
		(at 96.83115 -60.099194)
		(size 0.508)
		(drill 0.254)
		(layers "F.Cu" "B.Cu")
		(net "GND")
	)
	(via
		(at 169.465244 -346.09913)
		(size 0.4572)
		(drill 0.254)
		(layers "F.Cu" "B.Cu")
		(net "GND")
	)
	(via
		(at 416.499802 -312.999882)
		(size 0.4064)
		(drill 0.2032)
		(layers "F.Cu" "B.Cu")
		(net "GND")
	)
	(via
		(at 30.627066 -256.375916)
		(size 0.508)
		(drill 0.254)
		(layers "F.Cu" "B.Cu")
		(net "GND")
	)
	(via
		(at 414.599882 -273.099784)
		(size 0.4064)
		(drill 0.2032)
		(layers "F.Cu" "B.Cu")
		(net "GND")
	)
	(via
		(at 26.982928 -351.611438)
		(size 0.4064)
		(drill 0.2032)
		(layers "F.Cu" "B.Cu")
		(net "GND")
	)
	(via
		(at 163.41344 -31.118302)
		(size 0.508)
		(drill 0.254)
		(layers "F.Cu" "B.Cu")
		(net "GND")
	)
	(via
		(at 119.174768 -288.14649)
		(size 0.508)
		(drill 0.254)
		(layers "F.Cu" "B.Cu")
		(net "GND")
	)
	(via
		(at 250.931426 -11.372342)
		(size 0.508)
		(drill 0.254)
		(layers "F.Cu" "B.Cu")
		(net "GND")
	)
	(via
		(at 284.503114 -343.073482)
		(size 0.4572)
		(drill 0.254)
		(layers "F.Cu" "B.Cu")
		(net "GND")
	)
	(via
		(at 68.651374 -354.098098)
		(size 0.4572)
		(drill 0.254)
		(layers "F.Cu" "B.Cu")
		(net "GND")
	)
	(via
		(at 225.69043 -199.524112)
		(size 0.508)
		(drill 0.254)
		(layers "F.Cu" "B.Cu")
		(net "GND")
	)
	(via
		(at 427.727872 -401.040092)
		(size 0.508)
		(drill 0.254)
		(layers "F.Cu" "B.Cu")
		(net "GND")
	)
	(via
		(at 410.356304 -352.245422)
		(size 0.4572)
		(drill 0.254)
		(layers "F.Cu" "B.Cu")
		(net "GND")
	)
	(via
		(at 190.681356 -33.459674)
		(size 0.508)
		(drill 0.254)
		(layers "F.Cu" "B.Cu")
		(net "GND")
	)
	(via
		(at 395.764258 -142.41145)
		(size 0.508)
		(drill 0.254)
		(layers "F.Cu" "B.Cu")
		(net "GND")
	)
	(via
		(at 262.045196 -50.516282)
		(size 0.508)
		(drill 0.254)
		(layers "F.Cu" "B.Cu")
		(net "GND")
	)
	(via
		(at 47.77486 -286.874966)
		(size 0.4064)
		(drill 0.2032)
		(layers "F.Cu" "B.Cu")
		(net "GND")
	)
	(via
		(at 271.424908 -292.574726)
		(size 0.4064)
		(drill 0.2032)
		(layers "F.Cu" "B.Cu")
		(net "GND")
	)
	(via
		(at 27.347926 -410.041852)
		(size 0.508)
		(drill 0.254)
		(layers "F.Cu" "B.Cu")
		(net "GND")
	)
	(via
		(at 332.217776 -344.831162)
		(size 0.4572)
		(drill 0.254)
		(layers "F.Cu" "B.Cu")
		(net "GND")
	)
	(via
		(at 410.041852 -161.757868)
		(size 0.508)
		(drill 0.254)
		(layers "F.Cu" "B.Cu")
		(net "GND")
	)
	(via
		(at 10.20953 -383.864866)
		(size 0.508)
		(drill 0.254)
		(layers "F.Cu" "B.Cu")
		(net "GND")
	)
	(via
		(at 123.728988 -348.58579)
		(size 0.4064)
		(drill 0.2032)
		(layers "F.Cu" "B.Cu")
		(net "GND")
	)
	(via
		(at 160.296352 -60.099194)
		(size 0.508)
		(drill 0.254)
		(layers "F.Cu" "B.Cu")
		(net "GND")
	)
	(via
		(at 44.449746 -305.399948)
		(size 0.4064)
		(drill 0.2032)
		(layers "F.Cu" "B.Cu")
		(net "GND")
	)
	(via
		(at 400.349974 -276.899878)
		(size 0.4064)
		(drill 0.2032)
		(layers "F.Cu" "B.Cu")
		(net "GND")
	)
	(via
		(at 398.4498 -280.699718)
		(size 0.4064)
		(drill 0.2032)
		(layers "F.Cu" "B.Cu")
		(net "GND")
	)
	(via
		(at 133.661404 -60.099194)
		(size 0.508)
		(drill 0.254)
		(layers "F.Cu" "B.Cu")
		(net "GND")
	)
	(via
		(at 84.54771 -375.040144)
		(size 0.508)
		(drill 0.254)
		(layers "F.Cu" "B.Cu")
		(net "GND")
	)
	(via
		(at 160.138364 -354.098098)
		(size 0.4572)
		(drill 0.254)
		(layers "F.Cu" "B.Cu")
		(net "GND")
	)
	(via
		(at 191.900048 -278.799798)
		(size 0.4064)
		(drill 0.2032)
		(layers "F.Cu" "B.Cu")
		(net "GND")
	)
	(via
		(at 44.731178 -6.292342)
		(size 0.508)
		(drill 0.254)
		(layers "F.Cu" "B.Cu")
		(net "GND")
	)
	(via
		(at 191.900048 -273.099784)
		(size 0.4064)
		(drill 0.2032)
		(layers "F.Cu" "B.Cu")
		(net "GND")
	)
	(via
		(at 368.120422 -120.925844)
		(size 0.508)
		(drill 0.254)
		(layers "F.Cu" "B.Cu")
		(net "GND")
	)
	(via
		(at 19.939254 -32.911796)
		(size 0.508)
		(drill 0.254)
		(layers "F.Cu" "B.Cu")
		(net "GND")
	)
	(via
		(at 74.869294 -347.951806)
		(size 0.4572)
		(drill 0.254)
		(layers "F.Cu" "B.Cu")
		(net "GND")
	)
	(via
		(at 298.921932 -77.859636)
		(size 0.508)
		(drill 0.254)
		(layers "F.Cu" "B.Cu")
		(net "GND")
	)
	(via
		(at 238.671862 -80.638396)
		(size 0.508)
		(drill 0.254)
		(layers "F.Cu" "B.Cu")
		(net "GND")
	)
	(via
		(at 306.099718 -318.699896)
		(size 0.4064)
		(drill 0.2032)
		(layers "F.Cu" "B.Cu")
		(net "GND")
	)
	(via
		(at 177.649886 -281.649932)
		(size 0.4064)
		(drill 0.2032)
		(layers "F.Cu" "B.Cu")
		(net "GND")
	)
	(via
		(at 188.773054 -23.880318)
		(size 0.508)
		(drill 0.254)
		(layers "F.Cu" "B.Cu")
		(net "GND")
	)
	(via
		(at 400.05 -145.520156)
		(size 0.508)
		(drill 0.254)
		(layers "F.Cu" "B.Cu")
		(net "GND")
	)
	(via
		(at 376.94997 -310.832246)
		(size 0.508)
		(drill 0.254)
		(layers "F.Cu" "B.Cu")
		(net "GND")
	)
	(via
		(at 385.05638 -351.611438)
		(size 0.4064)
		(drill 0.2032)
		(layers "F.Cu" "B.Cu")
		(net "GND")
	)
	(via
		(at 200.946766 -1.135126)
		(size 0.508)
		(drill 0.254)
		(layers "F.Cu" "B.Cu")
		(net "GND")
	)
	(via
		(at 116.447316 -87.556594)
		(size 0.508)
		(drill 0.254)
		(layers "F.Cu" "B.Cu")
		(net "GND")
	)
	(via
		(at 164.934646 -71.451978)
		(size 0.508)
		(drill 0.254)
		(layers "F.Cu" "B.Cu")
		(net "GND")
	)
	(via
		(at 397.120872 -350.977454)
		(size 0.4572)
		(drill 0.254)
		(layers "F.Cu" "B.Cu")
		(net "GND")
	)
	(via
		(at 415.917888 -182.32882)
		(size 0.508)
		(drill 0.254)
		(layers "F.Cu" "B.Cu")
		(net "GND")
	)
	(via
		(at 212.284564 -72.56526)
		(size 0.508)
		(drill 0.254)
		(layers "F.Cu" "B.Cu")
		(net "GND")
	)
	(via
		(at 434.327808 -403.34184)
		(size 0.508)
		(drill 0.254)
		(layers "F.Cu" "B.Cu")
		(net "GND")
	)
	(via
		(at 191.540892 -45.853858)
		(size 0.508)
		(drill 0.254)
		(layers "F.Cu" "B.Cu")
		(net "GND")
	)
	(via
		(at 34.308288 -351.611438)
		(size 0.4064)
		(drill 0.2032)
		(layers "F.Cu" "B.Cu")
		(net "GND")
	)
	(via
		(at 422.199816 -278.799798)
		(size 0.4064)
		(drill 0.2032)
		(layers "F.Cu" "B.Cu")
		(net "GND")
	)
	(via
		(at 186.675014 -286.874966)
		(size 0.4064)
		(drill 0.2032)
		(layers "F.Cu" "B.Cu")
		(net "GND")
	)
	(via
		(at 157.699964 -313.949842)
		(size 0.4064)
		(drill 0.2032)
		(layers "F.Cu" "B.Cu")
		(net "GND")
	)
	(via
		(at 217.913712 -101.646736)
		(size 0.508)
		(drill 0.254)
		(layers "F.Cu" "B.Cu")
		(net "GND")
	)
	(via
		(at 101.974904 -73.23963)
		(size 0.508)
		(drill 0.254)
		(layers "F.Cu" "B.Cu")
		(net "GND")
	)
	(via
		(at 332.451202 -45.865288)
		(size 0.508)
		(drill 0.254)
		(layers "F.Cu" "B.Cu")
		(net "GND")
	)
	(via
		(at 404.37308 -363.997494)
		(size 0.508)
		(drill 0.254)
		(layers "F.Cu" "B.Cu")
		(net "GND")
	)
	(via
		(at 135.057388 -357.75773)
		(size 0.4064)
		(drill 0.2032)
		(layers "F.Cu" "B.Cu")
		(net "GND")
	)
	(via
		(at 84.196174 -347.951806)
		(size 0.4572)
		(drill 0.254)
		(layers "F.Cu" "B.Cu")
		(net "GND")
	)
	(via
		(at 131.037584 -284.333188)
		(size 0.49022)
		(drill 0.254)
		(layers "F.Cu" "B.Cu")
		(net "GND")
	)
	(via
		(at 135.199374 -135.343646)
		(size 0.508)
		(drill 0.254)
		(layers "F.Cu" "B.Cu")
		(net "GND")
	)
	(via
		(at 391.13841 -73.20026)
		(size 0.508)
		(drill 0.254)
		(layers "F.Cu" "B.Cu")
		(net "GND")
	)
	(via
		(at 55.374794 -305.874928)
		(size 0.4064)
		(drill 0.2032)
		(layers "F.Cu" "B.Cu")
		(net "GND")
	)
	(via
		(at 253.955804 -70.798436)
		(size 0.508)
		(drill 0.254)
		(layers "F.Cu" "B.Cu")
		(net "GND")
	)
	(via
		(at 426.272452 -354.732082)
		(size 0.4064)
		(drill 0.2032)
		(layers "F.Cu" "B.Cu")
		(net "GND")
	)
	(via
		(at 405.575008 -306.824888)
		(size 0.4064)
		(drill 0.2032)
		(layers "F.Cu" "B.Cu")
		(net "GND")
	)
	(via
		(at 332.302104 -324.217284)
		(size 0.508)
		(drill 0.254)
		(layers "F.Cu" "B.Cu")
		(net "GND")
	)
	(via
		(at 310.849772 -282.599892)
		(size 0.4064)
		(drill 0.2032)
		(layers "F.Cu" "B.Cu")
		(net "GND")
	)
	(via
		(at 17.622774 -23.880318)
		(size 0.508)
		(drill 0.254)
		(layers "F.Cu" "B.Cu")
		(net "GND")
	)
	(via
		(at 297.549824 -275.949918)
		(size 0.4064)
		(drill 0.2032)
		(layers "F.Cu" "B.Cu")
		(net "GND")
	)
	(via
		(at 126.347728 -381.241808)
		(size 0.4572)
		(drill 0.254)
		(layers "F.Cu" "B.Cu")
		(net "GND")
	)
	(via
		(at 40.649906 -314.899802)
		(size 0.4064)
		(drill 0.2032)
		(layers "F.Cu" "B.Cu")
		(net "GND")
	)
	(via
		(at 161.15157 -102.445058)
		(size 0.508)
		(drill 0.254)
		(layers "F.Cu" "B.Cu")
		(net "GND")
	)
	(via
		(at 392.971274 -31.652972)
		(size 0.508)
		(drill 0.254)
		(layers "F.Cu" "B.Cu")
		(net "GND")
	)
	(via
		(at 75.79995 -273.099784)
		(size 0.4064)
		(drill 0.2032)
		(layers "F.Cu" "B.Cu")
		(net "GND")
	)
	(via
		(at 345.703906 -88.341962)
		(size 0.508)
		(drill 0.254)
		(layers "F.Cu" "B.Cu")
		(net "GND")
	)
	(via
		(at 330.587604 -348.58579)
		(size 0.4064)
		(drill 0.2032)
		(layers "F.Cu" "B.Cu")
		(net "GND")
	)
	(via
		(at 153.42489 -275.474938)
		(size 0.4064)
		(drill 0.2032)
		(layers "F.Cu" "B.Cu")
		(net "GND")
	)
	(via
		(at 300.12767 -376.241818)
		(size 0.508)
		(drill 0.254)
		(layers "F.Cu" "B.Cu")
		(net "GND")
	)
	(via
		(at 294.22471 -307.774848)
		(size 0.4064)
		(drill 0.2032)
		(layers "F.Cu" "B.Cu")
		(net "GND")
	)
	(via
		(at 49.67478 -290.674806)
		(size 0.4064)
		(drill 0.2032)
		(layers "F.Cu" "B.Cu")
		(net "GND")
	)
	(via
		(at 55.374794 -297.32478)
		(size 0.4064)
		(drill 0.2032)
		(layers "F.Cu" "B.Cu")
		(net "GND")
	)
	(via
		(at 370.990368 -347.951806)
		(size 0.4572)
		(drill 0.254)
		(layers "F.Cu" "B.Cu")
		(net "GND")
	)
	(via
		(at 81.087214 -344.831162)
		(size 0.4572)
		(drill 0.254)
		(layers "F.Cu" "B.Cu")
		(net "GND")
	)
	(via
		(at 432.119024 -354.098098)
		(size 0.4572)
		(drill 0.254)
		(layers "F.Cu" "B.Cu")
		(net "GND")
	)
	(via
		(at 73.61047 -349.219774)
		(size 0.4572)
		(drill 0.254)
		(layers "F.Cu" "B.Cu")
		(net "GND")
	)
	(via
		(at 273.324828 -293.52494)
		(size 0.4064)
		(drill 0.2032)
		(layers "F.Cu" "B.Cu")
		(net "GND")
	)
	(via
		(at 412.224982 -291.624766)
		(size 0.4064)
		(drill 0.2032)
		(layers "F.Cu" "B.Cu")
		(net "GND")
	)
	(via
		(at 431.840386 -121.563384)
		(size 0.508)
		(drill 0.254)
		(layers "F.Cu" "B.Cu")
		(net "GND")
	)
	(via
		(at 26.61158 -355.366066)
		(size 0.4572)
		(drill 0.254)
		(layers "F.Cu" "B.Cu")
		(net "GND")
	)
	(via
		(at 153.89987 -312.999882)
		(size 0.4064)
		(drill 0.2032)
		(layers "F.Cu" "B.Cu")
		(net "GND")
	)
	(via
		(at 378.467112 -355.366066)
		(size 0.4572)
		(drill 0.254)
		(layers "F.Cu" "B.Cu")
		(net "GND")
	)
	(via
		(at 68.199762 -318.699896)
		(size 0.4064)
		(drill 0.2032)
		(layers "F.Cu" "B.Cu")
		(net "GND")
	)
	(via
		(at 281.394154 -355.366066)
		(size 0.4572)
		(drill 0.254)
		(layers "F.Cu" "B.Cu")
		(net "GND")
	)
	(via
		(at 362.204 -181.102)
		(size 0.508)
		(drill 0.254)
		(layers "F.Cu" "B.Cu")
		(net "GND")
	)
	(via
		(at 153.664666 -152.295352)
		(size 0.508)
		(drill 0.254)
		(layers "F.Cu" "B.Cu")
		(net "GND")
	)
	(via
		(at 191.900048 -281.649932)
		(size 0.4064)
		(drill 0.2032)
		(layers "F.Cu" "B.Cu")
		(net "GND")
	)
	(via
		(at 443.783466 -114.075972)
		(size 0.508)
		(drill 0.254)
		(layers "F.Cu" "B.Cu")
		(net "GND")
	)
	(via
		(at 285.052262 -124.154946)
		(size 0.508)
		(drill 0.254)
		(layers "F.Cu" "B.Cu")
		(net "GND")
	)
	(via
		(at 318.523112 -352.245422)
		(size 0.4572)
		(drill 0.254)
		(layers "F.Cu" "B.Cu")
		(net "GND")
	)
	(via
		(at 251.720096 -57.076848)
		(size 0.508)
		(drill 0.254)
		(layers "F.Cu" "B.Cu")
		(net "GND")
	)
	(via
		(at 417.984178 -120.716548)
		(size 0.508)
		(drill 0.254)
		(layers "F.Cu" "B.Cu")
		(net "GND")
	)
	(via
		(at 106.676698 -279.023572)
		(size 0.508)
		(drill 0.254)
		(layers "F.Cu" "B.Cu")
		(net "GND")
	)
	(via
		(at 205.932024 -122.838972)
		(size 0.508)
		(drill 0.254)
		(layers "F.Cu" "B.Cu")
		(net "GND")
	)
	(via
		(at 408.424888 -303.974754)
		(size 0.4064)
		(drill 0.2032)
		(layers "F.Cu" "B.Cu")
		(net "GND")
	)
	(via
		(at 361.82808 -286.842454)
		(size 0.508)
		(drill 0.254)
		(layers "F.Cu" "B.Cu")
		(net "GND")
	)
	(via
		(at 362.202222 -57.461404)
		(size 0.508)
		(drill 0.254)
		(layers "F.Cu" "B.Cu")
		(net "GND")
	)
	(via
		(at 366.381792 -292.781736)
		(size 0.508)
		(drill 0.254)
		(layers "F.Cu" "B.Cu")
		(net "GND")
	)
	(via
		(at 425.99991 -283.549852)
		(size 0.4064)
		(drill 0.2032)
		(layers "F.Cu" "B.Cu")
		(net "GND")
	)
	(via
		(at 352.036634 -83.232752)
		(size 0.508)
		(drill 0.254)
		(layers "F.Cu" "B.Cu")
		(net "GND")
	)
	(via
		(at 321.260724 -345.465146)
		(size 0.4064)
		(drill 0.2032)
		(layers "F.Cu" "B.Cu")
		(net "GND")
	)
	(via
		(at 182.547514 -142.15491)
		(size 0.508)
		(drill 0.254)
		(layers "F.Cu" "B.Cu")
		(net "GND")
	)
	(via
		(at 360.170476 -287.51149)
		(size 0.508)
		(drill 0.254)
		(layers "F.Cu" "B.Cu")
		(net "GND")
	)
	(via
		(at 273.546062 -351.611438)
		(size 0.4064)
		(drill 0.2032)
		(layers "F.Cu" "B.Cu")
		(net "GND")
	)
	(via
		(at 37.6809 -25.990042)
		(size 0.508)
		(drill 0.254)
		(layers "F.Cu" "B.Cu")
		(net "GND")
	)
	(via
		(at 357.909368 -291.32149)
		(size 0.508)
		(drill 0.254)
		(layers "F.Cu" "B.Cu")
		(net "GND")
	)
	(via
		(at 279.763982 -351.611438)
		(size 0.4064)
		(drill 0.2032)
		(layers "F.Cu" "B.Cu")
		(net "GND")
	)
	(via
		(at 330.927964 -373.83847)
		(size 0.508)
		(drill 0.254)
		(layers "F.Cu" "B.Cu")
		(net "GND")
	)
	(via
		(at 279.352502 -145.821908)
		(size 0.508)
		(drill 0.254)
		(layers "F.Cu" "B.Cu")
		(net "GND")
	)
	(via
		(at 123.022614 -177.934112)
		(size 0.508)
		(drill 0.254)
		(layers "F.Cu" "B.Cu")
		(net "GND")
	)
	(via
		(at 174.325026 -291.624766)
		(size 0.4064)
		(drill 0.2032)
		(layers "F.Cu" "B.Cu")
		(net "GND")
	)
	(via
		(at 27.270456 -28.802076)
		(size 0.508)
		(drill 0.254)
		(layers "F.Cu" "B.Cu")
		(net "GND")
	)
	(via
		(at 181.901084 -352.245422)
		(size 0.4572)
		(drill 0.254)
		(layers "F.Cu" "B.Cu")
		(net "GND")
	)
	(via
		(at 167.675052 -303.974754)
		(size 0.4064)
		(drill 0.2032)
		(layers "F.Cu" "B.Cu")
		(net "GND")
	)
	(via
		(at 130.34899 -29.589984)
		(size 0.508)
		(drill 0.254)
		(layers "F.Cu" "B.Cu")
		(net "GND")
	)
	(via
		(at 106.747564 -162.518852)
		(size 0.508)
		(drill 0.254)
		(layers "F.Cu" "B.Cu")
		(net "GND")
	)
	(via
		(at 79.12481 -300.174914)
		(size 0.4064)
		(drill 0.2032)
		(layers "F.Cu" "B.Cu")
		(net "GND")
	)
	(via
		(at 412.746952 -23.583646)
		(size 0.508)
		(drill 0.254)
		(layers "F.Cu" "B.Cu")
		(net "GND")
	)
	(via
		(at 424.270932 -345.465146)
		(size 0.4064)
		(drill 0.2032)
		(layers "F.Cu" "B.Cu")
		(net "GND")
	)
	(via
		(at 381.576072 -355.366066)
		(size 0.4572)
		(drill 0.254)
		(layers "F.Cu" "B.Cu")
		(net "GND")
	)
	(via
		(at 414.124902 -303.974754)
		(size 0.4064)
		(drill 0.2032)
		(layers "F.Cu" "B.Cu")
		(net "GND")
	)
	(via
		(at 308.474872 -289.724846)
		(size 0.4064)
		(drill 0.2032)
		(layers "F.Cu" "B.Cu")
		(net "GND")
	)
	(via
		(at 335.108804 -264.343642)
		(size 0.508)
		(drill 0.254)
		(layers "F.Cu" "B.Cu")
		(net "GND")
	)
	(via
		(at 45.636688 -342.439498)
		(size 0.4064)
		(drill 0.2032)
		(layers "F.Cu" "B.Cu")
		(net "GND")
	)
	(via
		(at 42.747946 -400.938492)
		(size 0.508)
		(drill 0.254)
		(layers "F.Cu" "B.Cu")
		(net "GND")
	)
	(via
		(at 269.94485 -27.79014)
		(size 0.508)
		(drill 0.254)
		(layers "F.Cu" "B.Cu")
		(net "GND")
	)
	(via
		(at 178.124866 -303.974754)
		(size 0.4064)
		(drill 0.2032)
		(layers "F.Cu" "B.Cu")
		(net "GND")
	)
	(via
		(at 412.20644 -350.977454)
		(size 0.4572)
		(drill 0.254)
		(layers "F.Cu" "B.Cu")
		(net "GND")
	)
	(via
		(at 153.233628 -124.43333)
		(size 0.508)
		(drill 0.254)
		(layers "F.Cu" "B.Cu")
		(net "GND")
	)
	(via
		(at 7.074916 -170.574462)
		(size 0.508)
		(drill 0.254)
		(layers "F.Cu" "B.Cu")
		(net "GND")
	)
	(via
		(at 27.347926 -402.241766)
		(size 0.508)
		(drill 0.254)
		(layers "F.Cu" "B.Cu")
		(net "GND")
	)
	(via
		(at 396.0749 -288.774886)
		(size 0.4064)
		(drill 0.2032)
		(layers "F.Cu" "B.Cu")
		(net "GND")
	)
	(via
		(at 282.063444 -113.780062)
		(size 0.508)
		(drill 0.254)
		(layers "F.Cu" "B.Cu")
		(net "GND")
	)
	(via
		(at 174.747936 -399.441924)
		(size 0.508)
		(drill 0.254)
		(layers "F.Cu" "B.Cu")
		(net "GND")
	)
	(via
		(at 48.72482 -309.674768)
		(size 0.4064)
		(drill 0.2032)
		(layers "F.Cu" "B.Cu")
		(net "GND")
	)
	(via
		(at 356.542848 -147.630388)
		(size 0.508)
		(drill 0.254)
		(layers "F.Cu" "B.Cu")
		(net "GND")
	)
	(via
		(at 180.02504 -284.974792)
		(size 0.4064)
		(drill 0.2032)
		(layers "F.Cu" "B.Cu")
		(net "GND")
	)
	(via
		(at 58.699908 -278.799798)
		(size 0.4064)
		(drill 0.2032)
		(layers "F.Cu" "B.Cu")
		(net "GND")
	)
	(via
		(at 154.850084 -308.249828)
		(size 0.4064)
		(drill 0.2032)
		(layers "F.Cu" "B.Cu")
		(net "GND")
	)
	(via
		(at 44.94784 -375.040398)
		(size 0.508)
		(drill 0.254)
		(layers "F.Cu" "B.Cu")
		(net "GND")
	)
	(via
		(at 193.0781 -350.977454)
		(size 0.4572)
		(drill 0.254)
		(layers "F.Cu" "B.Cu")
		(net "GND")
	)
	(via
		(at 221.204028 -118.361714)
		(size 0.508)
		(drill 0.254)
		(layers "F.Cu" "B.Cu")
		(net "GND")
	)
	(via
		(at 73.424796 -294.4749)
		(size 0.4064)
		(drill 0.2032)
		(layers "F.Cu" "B.Cu")
		(net "GND")
	)
	(via
		(at 297.927776 -377.341892)
		(size 0.508)
		(drill 0.254)
		(layers "F.Cu" "B.Cu")
		(net "GND")
	)
	(via
		(at 410.324808 -300.174914)
		(size 0.4064)
		(drill 0.2032)
		(layers "F.Cu" "B.Cu")
		(net "GND")
	)
	(via
		(at 77.947774 -397.038576)
		(size 0.508)
		(drill 0.254)
		(layers "F.Cu" "B.Cu")
		(net "GND")
	)
	(via
		(at 71.760334 -349.219774)
		(size 0.4572)
		(drill 0.254)
		(layers "F.Cu" "B.Cu")
		(net "GND")
	)
	(via
		(at 78.349602 -357.75773)
		(size 0.4064)
		(drill 0.2032)
		(layers "F.Cu" "B.Cu")
		(net "GND")
	)
	(via
		(at 399.93316 -133.565138)
		(size 0.508)
		(drill 0.254)
		(layers "F.Cu" "B.Cu")
		(net "GND")
	)
	(via
		(at 360.170476 -291.32149)
		(size 0.508)
		(drill 0.254)
		(layers "F.Cu" "B.Cu")
		(net "GND")
	)
	(via
		(at 281.646884 -109.177328)
		(size 0.508)
		(drill 0.254)
		(layers "F.Cu" "B.Cu")
		(net "GND")
	)
	(via
		(at 88.947752 -398.34185)
		(size 0.508)
		(drill 0.254)
		(layers "F.Cu" "B.Cu")
		(net "GND")
	)
	(via
		(at 73.61047 -355.366066)
		(size 0.4572)
		(drill 0.254)
		(layers "F.Cu" "B.Cu")
		(net "GND")
	)
	(via
		(at 427.89983 -304.449734)
		(size 0.4064)
		(drill 0.2032)
		(layers "F.Cu" "B.Cu")
		(net "GND")
	)
	(via
		(at 279.232868 -118.754906)
		(size 0.508)
		(drill 0.254)
		(layers "F.Cu" "B.Cu")
		(net "GND")
	)
	(via
		(at 174.747936 -398.24025)
		(size 0.508)
		(drill 0.254)
		(layers "F.Cu" "B.Cu")
		(net "GND")
	)
	(via
		(at 410.356304 -341.805514)
		(size 0.4572)
		(drill 0.254)
		(layers "F.Cu" "B.Cu")
		(net "GND")
	)
	(via
		(at 177.161952 -351.611438)
		(size 0.4064)
		(drill 0.2032)
		(layers "F.Cu" "B.Cu")
		(net "GND")
	)
	(via
		(at 55.271416 -51.661822)
		(size 0.508)
		(drill 0.254)
		(layers "F.Cu" "B.Cu")
		(net "GND")
	)
	(via
		(at 395.262354 -80.923384)
		(size 0.508)
		(drill 0.254)
		(layers "F.Cu" "B.Cu")
		(net "GND")
	)
	(via
		(at 341.25027 -288.78149)
		(size 0.508)
		(drill 0.254)
		(layers "F.Cu" "B.Cu")
		(net "GND")
	)
	(via
		(at 283.774896 -289.724846)
		(size 0.4064)
		(drill 0.2032)
		(layers "F.Cu" "B.Cu")
		(net "GND")
	)
	(via
		(at 327.849992 -355.366066)
		(size 0.4572)
		(drill 0.254)
		(layers "F.Cu" "B.Cu")
		(net "GND")
	)
	(via
		(at 408.424888 -291.624766)
		(size 0.4064)
		(drill 0.2032)
		(layers "F.Cu" "B.Cu")
		(net "GND")
	)
	(via
		(at 185.725054 -298.27474)
		(size 0.4064)
		(drill 0.2032)
		(layers "F.Cu" "B.Cu")
		(net "GND")
	)
	(via
		(at 275.204682 -386.951982)
		(size 0.508)
		(drill 0.254)
		(layers "F.Cu" "B.Cu")
		(net "GND")
	)
	(via
		(at 240.44275 -150.16861)
		(size 0.508)
		(drill 0.254)
		(layers "F.Cu" "B.Cu")
		(net "GND")
	)
	(via
		(at 321.619626 -95.0722)
		(size 0.508)
		(drill 0.254)
		(layers "F.Cu" "B.Cu")
		(net "GND")
	)
	(via
		(at 432.900836 -34.990278)
		(size 0.508)
		(drill 0.254)
		(layers "F.Cu" "B.Cu")
		(net "GND")
	)
	(via
		(at 164.824918 -306.824888)
		(size 0.4064)
		(drill 0.2032)
		(layers "F.Cu" "B.Cu")
		(net "GND")
	)
	(via
		(at 209.738976 -291.321998)
		(size 0.508)
		(drill 0.254)
		(layers "F.Cu" "B.Cu")
		(net "GND")
	)
	(via
		(at 395.4907 -342.439498)
		(size 0.4064)
		(drill 0.2032)
		(layers "F.Cu" "B.Cu")
		(net "GND")
	)
	(via
		(at 182.39994 -317.749936)
		(size 0.4064)
		(drill 0.2032)
		(layers "F.Cu" "B.Cu")
		(net "GND")
	)
	(via
		(at 413.465264 -347.92793)
		(size 0.4572)
		(drill 0.254)
		(layers "F.Cu" "B.Cu")
		(net "GND")
	)
	(via
		(at 71.049896 -315.849762)
		(size 0.4064)
		(drill 0.2032)
		(layers "F.Cu" "B.Cu")
		(net "GND")
	)
	(via
		(at 293.527734 -397.038576)
		(size 0.508)
		(drill 0.254)
		(layers "F.Cu" "B.Cu")
		(net "GND")
	)
	(via
		(at 310.849772 -283.549852)
		(size 0.4064)
		(drill 0.2032)
		(layers "F.Cu" "B.Cu")
		(net "GND")
	)
	(via
		(at 418.874956 -286.874966)
		(size 0.4064)
		(drill 0.2032)
		(layers "F.Cu" "B.Cu")
		(net "GND")
	)
	(via
		(at 237.849918 -315.946282)
		(size 0.508)
		(drill 0.254)
		(layers "F.Cu" "B.Cu")
		(net "GND")
	)
	(via
		(at 287.099756 -313.949842)
		(size 0.4064)
		(drill 0.2032)
		(layers "F.Cu" "B.Cu")
		(net "GND")
	)
	(via
		(at 142.293594 -279.931114)
		(size 0.508)
		(drill 0.254)
		(layers "F.Cu" "B.Cu")
		(net "GND")
	)
	(via
		(at 279.024842 -307.774848)
		(size 0.4064)
		(drill 0.2032)
		(layers "F.Cu" "B.Cu")
		(net "GND")
	)
	(via
		(at 42.557954 -57.521094)
		(size 0.508)
		(drill 0.254)
		(layers "F.Cu" "B.Cu")
		(net "GND")
	)
	(via
		(at 368.641376 -85.50148)
		(size 0.508)
		(drill 0.254)
		(layers "F.Cu" "B.Cu")
		(net "GND")
	)
	(via
		(at 383.05486 -348.58579)
		(size 0.4064)
		(drill 0.2032)
		(layers "F.Cu" "B.Cu")
		(net "GND")
	)
	(via
		(at 295.649904 -312.049922)
		(size 0.4064)
		(drill 0.2032)
		(layers "F.Cu" "B.Cu")
		(net "GND")
	)
	(via
		(at 199.025002 -293.52494)
		(size 0.4064)
		(drill 0.2032)
		(layers "F.Cu" "B.Cu")
		(net "GND")
	)
	(via
		(at 33.8201 -34.990278)
		(size 0.508)
		(drill 0.254)
		(layers "F.Cu" "B.Cu")
		(net "GND")
	)
	(via
		(at 299.866812 -123.635008)
		(size 0.508)
		(drill 0.254)
		(layers "F.Cu" "B.Cu")
		(net "GND")
	)
	(via
		(at 307.524912 -302.074834)
		(size 0.4064)
		(drill 0.2032)
		(layers "F.Cu" "B.Cu")
		(net "GND")
	)
	(via
		(at 187.624974 -298.27474)
		(size 0.4064)
		(drill 0.2032)
		(layers "F.Cu" "B.Cu")
		(net "GND")
	)
	(via
		(at 136.039352 -31.652972)
		(size 0.508)
		(drill 0.254)
		(layers "F.Cu" "B.Cu")
		(net "GND")
	)
	(via
		(at 194.749674 -276.899878)
		(size 0.4064)
		(drill 0.2032)
		(layers "F.Cu" "B.Cu")
		(net "GND")
	)
	(via
		(at 396.0749 -287.824926)
		(size 0.4064)
		(drill 0.2032)
		(layers "F.Cu" "B.Cu")
		(net "GND")
	)
	(via
		(at 318.967866 -54.238906)
		(size 0.508)
		(drill 0.254)
		(layers "F.Cu" "B.Cu")
		(net "GND")
	)
	(via
		(at 74.869294 -350.977454)
		(size 0.4572)
		(drill 0.254)
		(layers "F.Cu" "B.Cu")
		(net "GND")
	)
	(via
		(at 182.002176 -57.461404)
		(size 0.508)
		(drill 0.254)
		(layers "F.Cu" "B.Cu")
		(net "GND")
	)
	(via
		(at 40.174926 -274.524978)
		(size 0.4064)
		(drill 0.2032)
		(layers "F.Cu" "B.Cu")
		(net "GND")
	)
	(via
		(at 408.899868 -318.699896)
		(size 0.4064)
		(drill 0.2032)
		(layers "F.Cu" "B.Cu")
		(net "GND")
	)
	(via
		(at 341.927942 -372.240302)
		(size 0.508)
		(drill 0.254)
		(layers "F.Cu" "B.Cu")
		(net "GND")
	)
	(via
		(at 38.275006 -293.52494)
		(size 0.4064)
		(drill 0.2032)
		(layers "F.Cu" "B.Cu")
		(net "GND")
	)
	(via
		(at 166.356284 -349.219774)
		(size 0.4572)
		(drill 0.254)
		(layers "F.Cu" "B.Cu")
		(net "GND")
	)
	(via
		(at 170.524932 -298.27474)
		(size 0.4064)
		(drill 0.2032)
		(layers "F.Cu" "B.Cu")
		(net "GND")
	)
	(via
		(at 165.09746 -357.123746)
		(size 0.4572)
		(drill 0.254)
		(layers "F.Cu" "B.Cu")
		(net "GND")
	)
	(via
		(at 306.574698 -300.174914)
		(size 0.4064)
		(drill 0.2032)
		(layers "F.Cu" "B.Cu")
		(net "GND")
	)
	(via
		(at 329.85456 -23.880318)
		(size 0.508)
		(drill 0.254)
		(layers "F.Cu" "B.Cu")
		(net "GND")
	)
	(via
		(at 161.54781 -377.341892)
		(size 0.508)
		(drill 0.254)
		(layers "F.Cu" "B.Cu")
		(net "GND")
	)
	(via
		(at 335.326736 -357.123746)
		(size 0.4572)
		(drill 0.254)
		(layers "F.Cu" "B.Cu")
		(net "GND")
	)
	(via
		(at 19.844766 -166.8526)
		(size 0.508)
		(drill 0.254)
		(layers "F.Cu" "B.Cu")
		(net "GND")
	)
	(via
		(at 281.874722 -301.124874)
		(size 0.4064)
		(drill 0.2032)
		(layers "F.Cu" "B.Cu")
		(net "GND")
	)
	(via
		(at 156.002228 -57.461404)
		(size 0.508)
		(drill 0.254)
		(layers "F.Cu" "B.Cu")
		(net "GND")
	)
	(via
		(at 385.433824 -102.716584)
		(size 0.508)
		(drill 0.254)
		(layers "F.Cu" "B.Cu")
		(net "GND")
	)
	(via
		(at 418.927788 -372.341902)
		(size 0.508)
		(drill 0.254)
		(layers "F.Cu" "B.Cu")
		(net "GND")
	)
	(via
		(at 298.417742 -342.439498)
		(size 0.4064)
		(drill 0.2032)
		(layers "F.Cu" "B.Cu")
		(net "GND")
	)
	(via
		(at 210.380834 -33.19018)
		(size 0.508)
		(drill 0.254)
		(layers "F.Cu" "B.Cu")
		(net "GND")
	)
	(via
		(at 176.555146 -29.590238)
		(size 0.508)
		(drill 0.254)
		(layers "F.Cu" "B.Cu")
		(net "GND")
	)
	(via
		(at 254.781304 -29.859478)
		(size 0.508)
		(drill 0.254)
		(layers "F.Cu" "B.Cu")
		(net "GND")
	)
	(via
		(at 286.927798 -410.041852)
		(size 0.508)
		(drill 0.254)
		(layers "F.Cu" "B.Cu")
		(net "GND")
	)
	(via
		(at 251.010674 -223.063562)
		(size 0.508)
		(drill 0.254)
		(layers "F.Cu" "B.Cu")
		(net "GND")
	)
	(via
		(at 321.632072 -357.123746)
		(size 0.4572)
		(drill 0.254)
		(layers "F.Cu" "B.Cu")
		(net "GND")
	)
	(via
		(at 172.547788 -401.040092)
		(size 0.508)
		(drill 0.254)
		(layers "F.Cu" "B.Cu")
		(net "GND")
	)
	(via
		(at 403.338792 -347.951806)
		(size 0.4572)
		(drill 0.254)
		(layers "F.Cu" "B.Cu")
		(net "GND")
	)
	(via
		(at 191.227964 -347.951806)
		(size 0.4572)
		(drill 0.254)
		(layers "F.Cu" "B.Cu")
		(net "GND")
	)
	(via
		(at 429.800004 -288.299906)
		(size 0.4064)
		(drill 0.2032)
		(layers "F.Cu" "B.Cu")
		(net "GND")
	)
	(via
		(at 301.88408 -124.31649)
		(size 0.508)
		(drill 0.254)
		(layers "F.Cu" "B.Cu")
		(net "GND")
	)
	(via
		(at 98.1329 -176.163986)
		(size 0.508)
		(drill 0.254)
		(layers "F.Cu" "B.Cu")
		(net "GND")
	)
	(via
		(at 135.287512 -183.077104)
		(size 0.508)
		(drill 0.254)
		(layers "F.Cu" "B.Cu")
		(net "GND")
	)
	(via
		(at 389.899906 -314.899802)
		(size 0.4064)
		(drill 0.2032)
		(layers "F.Cu" "B.Cu")
		(net "GND")
	)
	(via
		(at 222.480378 -123.509024)
		(size 0.508)
		(drill 0.254)
		(layers "F.Cu" "B.Cu")
		(net "GND")
	)
	(via
		(at 78.64983 -287.349946)
		(size 0.4064)
		(drill 0.2032)
		(layers "F.Cu" "B.Cu")
		(net "GND")
	)
	(via
		(at 233.135932 -84.189062)
		(size 0.508)
		(drill 0.254)
		(layers "F.Cu" "B.Cu")
		(net "GND")
	)
	(via
		(at 69.624956 -284.974792)
		(size 0.4064)
		(drill 0.2032)
		(layers "F.Cu" "B.Cu")
		(net "GND")
	)
	(via
		(at 127.209296 -343.073482)
		(size 0.4572)
		(drill 0.254)
		(layers "F.Cu" "B.Cu")
		(net "GND")
	)
	(via
		(at 173.850046 -276.899878)
		(size 0.4064)
		(drill 0.2032)
		(layers "F.Cu" "B.Cu")
		(net "GND")
	)
	(via
		(at 269.329662 -348.58579)
		(size 0.4064)
		(drill 0.2032)
		(layers "F.Cu" "B.Cu")
		(net "GND")
	)
	(via
		(at 385.624832 -292.57498)
		(size 0.4064)
		(drill 0.2032)
		(layers "F.Cu" "B.Cu")
		(net "GND")
	)
	(via
		(at 190.35141 -45.865288)
		(size 0.508)
		(drill 0.254)
		(layers "F.Cu" "B.Cu")
		(net "GND")
	)
	(via
		(at 385.927854 -411.141926)
		(size 0.508)
		(drill 0.254)
		(layers "F.Cu" "B.Cu")
		(net "GND")
	)
	(via
		(at 54.177184 -365.30661)
		(size 0.508)
		(drill 0.254)
		(layers "F.Cu" "B.Cu")
		(net "GND")
	)
	(via
		(at 429.927766 -397.038576)
		(size 0.508)
		(drill 0.254)
		(layers "F.Cu" "B.Cu")
		(net "GND")
	)
	(via
		(at 19.068288 -48.753014)
		(size 0.508)
		(drill 0.254)
		(layers "F.Cu" "B.Cu")
		(net "GND")
	)
	(via
		(at 210.380834 -29.589984)
		(size 0.508)
		(drill 0.254)
		(layers "F.Cu" "B.Cu")
		(net "GND")
	)
	(via
		(at 188.328808 -147.314412)
		(size 0.508)
		(drill 0.254)
		(layers "F.Cu" "B.Cu")
		(net "GND")
	)
	(via
		(at 46.34992 -281.649932)
		(size 0.4064)
		(drill 0.2032)
		(layers "F.Cu" "B.Cu")
		(net "GND")
	)
	(via
		(at 35.759644 -120.28551)
		(size 0.508)
		(drill 0.254)
		(layers "F.Cu" "B.Cu")
		(net "GND")
	)
	(via
		(at 344.653616 -355.366066)
		(size 0.4572)
		(drill 0.254)
		(layers "F.Cu" "B.Cu")
		(net "GND")
	)
	(via
		(at 185.250074 -274.999958)
		(size 0.4064)
		(drill 0.2032)
		(layers "F.Cu" "B.Cu")
		(net "GND")
	)
	(via
		(at 337.5279 -381.241808)
		(size 0.508)
		(drill 0.254)
		(layers "F.Cu" "B.Cu")
		(net "GND")
	)
	(via
		(at 452.909178 -107.75696)
		(size 0.508)
		(drill 0.254)
		(layers "F.Cu" "B.Cu")
		(net "GND")
	)
	(via
		(at 390.327896 -397.038576)
		(size 0.508)
		(drill 0.254)
		(layers "F.Cu" "B.Cu")
		(net "GND")
	)
	(via
		(at 321.260724 -357.75773)
		(size 0.4064)
		(drill 0.2032)
		(layers "F.Cu" "B.Cu")
		(net "GND")
	)
	(via
		(at 70.099936 -312.999882)
		(size 0.4064)
		(drill 0.2032)
		(layers "F.Cu" "B.Cu")
		(net "GND")
	)
	(via
		(at 107.509564 -160.385252)
		(size 0.508)
		(drill 0.254)
		(layers "F.Cu" "B.Cu")
		(net "GND")
	)
	(via
		(at 248.463054 -227.965)
		(size 0.508)
		(drill 0.254)
		(layers "F.Cu" "B.Cu")
		(net "GND")
	)
	(via
		(at 40.547798 -407.638504)
		(size 0.508)
		(drill 0.254)
		(layers "F.Cu" "B.Cu")
		(net "GND")
	)
	(via
		(at 233.839512 -235.737654)
		(size 0.508)
		(drill 0.254)
		(layers "F.Cu" "B.Cu")
		(net "GND")
	)
	(via
		(at 1.551432 -271.935194)
		(size 0.508)
		(drill 0.254)
		(layers "F.Cu" "B.Cu")
		(net "GND")
	)
	(via
		(at 179.55006 -311.099962)
		(size 0.4064)
		(drill 0.2032)
		(layers "F.Cu" "B.Cu")
		(net "GND")
	)
	(via
		(at 418.874956 -290.674806)
		(size 0.4064)
		(drill 0.2032)
		(layers "F.Cu" "B.Cu")
		(net "GND")
	)
	(via
		(at 154.156156 -33.19018)
		(size 0.508)
		(drill 0.254)
		(layers "F.Cu" "B.Cu")
		(net "GND")
	)
	(via
		(at 413.649922 -315.849762)
		(size 0.4064)
		(drill 0.2032)
		(layers "F.Cu" "B.Cu")
		(net "GND")
	)
	(via
		(at 73.61047 -343.073482)
		(size 0.4572)
		(drill 0.254)
		(layers "F.Cu" "B.Cu")
		(net "GND")
	)
	(via
		(at 24.981408 -357.75773)
		(size 0.4064)
		(drill 0.2032)
		(layers "F.Cu" "B.Cu")
		(net "GND")
	)
	(via
		(at 185.250074 -279.749758)
		(size 0.4064)
		(drill 0.2032)
		(layers "F.Cu" "B.Cu")
		(net "GND")
	)
	(via
		(at 100.048822 -105.057194)
		(size 0.508)
		(drill 0.254)
		(layers "F.Cu" "B.Cu")
		(net "GND")
	)
	(via
		(at 417.450016 -274.999958)
		(size 0.4064)
		(drill 0.2032)
		(layers "F.Cu" "B.Cu")
		(net "GND")
	)
	(via
		(at 298.647612 -121.835164)
		(size 0.508)
		(drill 0.254)
		(layers "F.Cu" "B.Cu")
		(net "GND")
	)
	(via
		(at 129.394712 -225.65106)
		(size 0.508)
		(drill 0.254)
		(layers "F.Cu" "B.Cu")
		(net "GND")
	)
	(via
		(at 86.747858 -380.040134)
		(size 0.508)
		(drill 0.254)
		(layers "F.Cu" "B.Cu")
		(net "GND")
	)
	(via
		(at 397.02486 -303.974754)
		(size 0.4064)
		(drill 0.2032)
		(layers "F.Cu" "B.Cu")
		(net "GND")
	)
	(via
		(at 324.898258 -114.323114)
		(size 0.508)
		(drill 0.254)
		(layers "F.Cu" "B.Cu")
		(net "GND")
	)
	(via
		(at 291.092382 -351.611438)
		(size 0.4064)
		(drill 0.2032)
		(layers "F.Cu" "B.Cu")
		(net "GND")
	)
	(via
		(at 375.7295 -348.58579)
		(size 0.4064)
		(drill 0.2032)
		(layers "F.Cu" "B.Cu")
		(net "GND")
	)
	(via
		(at 171.949872 -280.699718)
		(size 0.4064)
		(drill 0.2032)
		(layers "F.Cu" "B.Cu")
		(net "GND")
	)
	(via
		(at 314.366148 -154.476958)
		(size 0.508)
		(drill 0.254)
		(layers "F.Cu" "B.Cu")
		(net "GND")
	)
	(via
		(at 393.22502 -297.32478)
		(size 0.4064)
		(drill 0.2032)
		(layers "F.Cu" "B.Cu")
		(net "GND")
	)
	(via
		(at 184.77484 -304.924714)
		(size 0.4064)
		(drill 0.2032)
		(layers "F.Cu" "B.Cu")
		(net "GND")
	)
	(via
		(at 65.902078 -56.826404)
		(size 0.508)
		(drill 0.254)
		(layers "F.Cu" "B.Cu")
		(net "GND")
	)
	(via
		(at 330.958952 -357.123746)
		(size 0.4572)
		(drill 0.254)
		(layers "F.Cu" "B.Cu")
		(net "GND")
	)
	(via
		(at 427.727872 -402.241766)
		(size 0.508)
		(drill 0.254)
		(layers "F.Cu" "B.Cu")
		(net "GND")
	)
	(via
		(at 394.011912 -347.951806)
		(size 0.4572)
		(drill 0.254)
		(layers "F.Cu" "B.Cu")
		(net "GND")
	)
	(via
		(at 278.139144 -32.911796)
		(size 0.508)
		(drill 0.254)
		(layers "F.Cu" "B.Cu")
		(net "GND")
	)
	(via
		(at 422.199816 -288.299906)
		(size 0.4064)
		(drill 0.2032)
		(layers "F.Cu" "B.Cu")
		(net "GND")
	)
	(via
		(at 387.999986 -304.449734)
		(size 0.4064)
		(drill 0.2032)
		(layers "F.Cu" "B.Cu")
		(net "GND")
	)
	(via
		(at 333.127858 -411.141926)
		(size 0.508)
		(drill 0.254)
		(layers "F.Cu" "B.Cu")
		(net "GND")
	)
	(via
		(at 95.529146 -116.410486)
		(size 0.508)
		(drill 0.254)
		(layers "F.Cu" "B.Cu")
		(net "GND")
	)
	(via
		(at 52.85232 -133.564884)
		(size 0.508)
		(drill 0.254)
		(layers "F.Cu" "B.Cu")
		(net "GND")
	)
	(via
		(at 81.499964 -312.999882)
		(size 0.4064)
		(drill 0.2032)
		(layers "F.Cu" "B.Cu")
		(net "GND")
	)
	(via
		(at 313.224926 -303.024794)
		(size 0.4064)
		(drill 0.2032)
		(layers "F.Cu" "B.Cu")
		(net "GND")
	)
	(via
		(at 321.632072 -343.073482)
		(size 0.4572)
		(drill 0.254)
		(layers "F.Cu" "B.Cu")
		(net "GND")
	)
	(via
		(at 141.369796 -179.066698)
		(size 0.508)
		(drill 0.254)
		(layers "F.Cu" "B.Cu")
		(net "GND")
	)
	(via
		(at 134.267448 -122.09907)
		(size 0.508)
		(drill 0.254)
		(layers "F.Cu" "B.Cu")
		(net "GND")
	)
	(via
		(at 373.72798 -351.611438)
		(size 0.4064)
		(drill 0.2032)
		(layers "F.Cu" "B.Cu")
		(net "GND")
	)
	(via
		(at 13.902182 -58.731404)
		(size 0.508)
		(drill 0.254)
		(layers "F.Cu" "B.Cu")
		(net "GND")
	)
	(via
		(at 197.125082 -297.32478)
		(size 0.4064)
		(drill 0.2032)
		(layers "F.Cu" "B.Cu")
		(net "GND")
	)
	(via
		(at 84.196174 -344.831162)
		(size 0.4572)
		(drill 0.254)
		(layers "F.Cu" "B.Cu")
		(net "GND")
	)
	(via
		(at 67.66687 -133.044946)
		(size 0.508)
		(drill 0.254)
		(layers "F.Cu" "B.Cu")
		(net "GND")
	)
	(via
		(at 196.650102 -275.949918)
		(size 0.4064)
		(drill 0.2032)
		(layers "F.Cu" "B.Cu")
		(net "GND")
	)
	(via
		(at 31.447994 -64.312292)
		(size 0.508)
		(drill 0.254)
		(layers "F.Cu" "B.Cu")
		(net "GND")
	)
	(via
		(at 89.798144 -19.096736)
		(size 0.508)
		(drill 0.254)
		(layers "F.Cu" "B.Cu")
		(net "GND")
	)
	(via
		(at 389.424926 -294.4749)
		(size 0.4064)
		(drill 0.2032)
		(layers "F.Cu" "B.Cu")
		(net "GND")
	)
	(via
		(at 398.925034 -284.974792)
		(size 0.4064)
		(drill 0.2032)
		(layers "F.Cu" "B.Cu")
		(net "GND")
	)
	(via
		(at 51.48326 -357.123746)
		(size 0.4572)
		(drill 0.254)
		(layers "F.Cu" "B.Cu")
		(net "GND")
	)
	(via
		(at 187.149994 -281.649932)
		(size 0.4064)
		(drill 0.2032)
		(layers "F.Cu" "B.Cu")
		(net "GND")
	)
	(via
		(at 25.352756 -357.123746)
		(size 0.4572)
		(drill 0.254)
		(layers "F.Cu" "B.Cu")
		(net "GND")
	)
	(via
		(at 86.04631 -344.831162)
		(size 0.4572)
		(drill 0.254)
		(layers "F.Cu" "B.Cu")
		(net "GND")
	)
	(via
		(at 335.698084 -345.465146)
		(size 0.4064)
		(drill 0.2032)
		(layers "F.Cu" "B.Cu")
		(net "GND")
	)
	(via
		(at 414.11271 -156.555186)
		(size 0.508)
		(drill 0.254)
		(layers "F.Cu" "B.Cu")
		(net "GND")
	)
	(via
		(at 58.600848 -34.990278)
		(size 0.508)
		(drill 0.254)
		(layers "F.Cu" "B.Cu")
		(net "GND")
	)
	(via
		(at 127.650748 -292.789102)
		(size 0.508)
		(drill 0.254)
		(layers "F.Cu" "B.Cu")
		(net "GND")
	)
	(via
		(at 337.582256 -94.221554)
		(size 0.508)
		(drill 0.254)
		(layers "F.Cu" "B.Cu")
		(net "GND")
	)
	(via
		(at 65.382902 -34.990024)
		(size 0.508)
		(drill 0.254)
		(layers "F.Cu" "B.Cu")
		(net "GND")
	)
	(via
		(at 150.59152 -135.095488)
		(size 0.508)
		(drill 0.254)
		(layers "F.Cu" "B.Cu")
		(net "GND")
	)
	(via
		(at 47.29988 -313.949842)
		(size 0.4064)
		(drill 0.2032)
		(layers "F.Cu" "B.Cu")
		(net "GND")
	)
	(via
		(at 84.808314 -121.563384)
		(size 0.508)
		(drill 0.254)
		(layers "F.Cu" "B.Cu")
		(net "GND")
	)
	(via
		(at 298.024804 -300.174914)
		(size 0.4064)
		(drill 0.2032)
		(layers "F.Cu" "B.Cu")
		(net "GND")
	)
	(via
		(at 426.851572 -104.120696)
		(size 0.508)
		(drill 0.254)
		(layers "F.Cu" "B.Cu")
		(net "GND")
	)
	(via
		(at 93.894402 -342.439498)
		(size 0.4064)
		(drill 0.2032)
		(layers "F.Cu" "B.Cu")
		(net "GND")
	)
	(via
		(at 14.047978 -174.872142)
		(size 0.508)
		(drill 0.254)
		(layers "F.Cu" "B.Cu")
		(net "GND")
	)
	(via
		(at 102.390194 -351.76968)
		(size 0.508)
		(drill 0.254)
		(layers "F.Cu" "B.Cu")
		(net "GND")
	)
	(via
		(at 386.575046 -280.224738)
		(size 0.4064)
		(drill 0.2032)
		(layers "F.Cu" "B.Cu")
		(net "GND")
	)
	(via
		(at 35.759644 -105.78211)
		(size 0.508)
		(drill 0.254)
		(layers "F.Cu" "B.Cu")
		(net "GND")
	)
	(via
		(at 411.275022 -287.824926)
		(size 0.4064)
		(drill 0.2032)
		(layers "F.Cu" "B.Cu")
		(net "GND")
	)
	(via
		(at 77.947774 -406.040336)
		(size 0.508)
		(drill 0.254)
		(layers "F.Cu" "B.Cu")
		(net "GND")
	)
	(via
		(at 378.467112 -341.805514)
		(size 0.4572)
		(drill 0.254)
		(layers "F.Cu" "B.Cu")
		(net "GND")
	)
	(via
		(at 185.010044 -358.367838)
		(size 0.4572)
		(drill 0.254)
		(layers "F.Cu" "B.Cu")
		(net "GND")
	)
	(via
		(at 455.387202 -280.224484)
		(size 0.508)
		(drill 0.254)
		(layers "F.Cu" "B.Cu")
		(net "GND")
	)
	(via
		(at 434.120036 -33.19018)
		(size 0.508)
		(drill 0.254)
		(layers "F.Cu" "B.Cu")
		(net "GND")
	)
	(via
		(at 124.147834 -408.840178)
		(size 0.4572)
		(drill 0.254)
		(layers "F.Cu" "B.Cu")
		(net "GND")
	)
	(via
		(at 164.681408 -163.948618)
		(size 0.508)
		(drill 0.254)
		(layers "F.Cu" "B.Cu")
		(net "GND")
	)
	(via
		(at 332.6765 -114.310414)
		(size 0.508)
		(drill 0.254)
		(layers "F.Cu" "B.Cu")
		(net "GND")
	)
	(via
		(at 191.425068 -292.574726)
		(size 0.4064)
		(drill 0.2032)
		(layers "F.Cu" "B.Cu")
		(net "GND")
	)
	(via
		(at 156.073094 -141.029436)
		(size 0.508)
		(drill 0.254)
		(layers "F.Cu" "B.Cu")
		(net "GND")
	)
	(via
		(at 395.613382 -29.859478)
		(size 0.508)
		(drill 0.254)
		(layers "F.Cu" "B.Cu")
		(net "GND")
	)
	(via
		(at 48.3743 -358.391714)
		(size 0.4572)
		(drill 0.254)
		(layers "F.Cu" "B.Cu")
		(net "GND")
	)
	(via
		(at 232.317798 -307.484272)
		(size 0.508)
		(drill 0.254)
		(layers "F.Cu" "B.Cu")
		(net "GND")
	)
	(via
		(at 260.585458 -34.183066)
		(size 0.508)
		(drill 0.254)
		(layers "F.Cu" "B.Cu")
		(net "GND")
	)
	(via
		(at 40.547798 -408.840178)
		(size 0.508)
		(drill 0.254)
		(layers "F.Cu" "B.Cu")
		(net "GND")
	)
	(via
		(at 297.927776 -372.240302)
		(size 0.508)
		(drill 0.254)
		(layers "F.Cu" "B.Cu")
		(net "GND")
	)
	(via
		(at 190.950088 -319.65011)
		(size 0.4064)
		(drill 0.2032)
		(layers "F.Cu" "B.Cu")
		(net "GND")
	)
	(via
		(at 252.237494 -211.61629)
		(size 0.508)
		(drill 0.254)
		(layers "F.Cu" "B.Cu")
		(net "GND")
	)
	(via
		(at 372.249192 -341.805514)
		(size 0.4572)
		(drill 0.254)
		(layers "F.Cu" "B.Cu")
		(net "GND")
	)
	(via
		(at 386.099812 -317.749936)
		(size 0.4064)
		(drill 0.2032)
		(layers "F.Cu" "B.Cu")
		(net "GND")
	)
	(via
		(at 277.02637 -357.123746)
		(size 0.4572)
		(drill 0.254)
		(layers "F.Cu" "B.Cu")
		(net "GND")
	)
	(via
		(at 153.845006 -27.79014)
		(size 0.508)
		(drill 0.254)
		(layers "F.Cu" "B.Cu")
		(net "GND")
	)
	(via
		(at 413.174942 -289.724846)
		(size 0.4064)
		(drill 0.2032)
		(layers "F.Cu" "B.Cu")
		(net "GND")
	)
	(via
		(at 212.771228 -29.311854)
		(size 0.508)
		(drill 0.254)
		(layers "F.Cu" "B.Cu")
		(net "GND")
	)
	(via
		(at 331.09408 -190.094362)
		(size 0.508)
		(drill 0.254)
		(layers "F.Cu" "B.Cu")
		(net "GND")
	)
	(via
		(at 216.937844 -97.79)
		(size 0.508)
		(drill 0.254)
		(layers "F.Cu" "B.Cu")
		(net "GND")
	)
	(via
		(at 65.824862 -302.074834)
		(size 0.4064)
		(drill 0.2032)
		(layers "F.Cu" "B.Cu")
		(net "GND")
	)
	(via
		(at 51.63312 -152.96007)
		(size 0.508)
		(drill 0.254)
		(layers "F.Cu" "B.Cu")
		(net "GND")
	)
	(via
		(at 33.200848 -348.58579)
		(size 0.4064)
		(drill 0.2032)
		(layers "F.Cu" "B.Cu")
		(net "GND")
	)
	(via
		(at 434.755036 -31.390082)
		(size 0.508)
		(drill 0.254)
		(layers "F.Cu" "B.Cu")
		(net "GND")
	)
	(via
		(at 395.862048 -352.245422)
		(size 0.4572)
		(drill 0.254)
		(layers "F.Cu" "B.Cu")
		(net "GND")
	)
	(via
		(at 426.94987 -315.849762)
		(size 0.4064)
		(drill 0.2032)
		(layers "F.Cu" "B.Cu")
		(net "GND")
	)
	(via
		(at 356.853744 -279.086818)
		(size 0.508)
		(drill 0.254)
		(layers "F.Cu" "B.Cu")
		(net "GND")
	)
	(via
		(at 111.664496 -347.951806)
		(size 0.4572)
		(drill 0.254)
		(layers "F.Cu" "B.Cu")
		(net "GND")
	)
	(via
		(at 124.847858 -214.174324)
		(size 0.508)
		(drill 0.254)
		(layers "F.Cu" "B.Cu")
		(net "GND")
	)
	(via
		(at 53.714142 -370.24945)
		(size 0.4572)
		(drill 0.254)
		(layers "F.Cu" "B.Cu")
		(net "GND")
	)
	(via
		(at 125.048518 -95.568008)
		(size 0.508)
		(drill 0.254)
		(layers "F.Cu" "B.Cu")
		(net "GND")
	)
	(via
		(at 186.488832 -342.439498)
		(size 0.4064)
		(drill 0.2032)
		(layers "F.Cu" "B.Cu")
		(net "GND")
	)
	(via
		(at 338.435696 -357.123746)
		(size 0.4572)
		(drill 0.254)
		(layers "F.Cu" "B.Cu")
		(net "GND")
	)
	(via
		(at 297.927776 -383.940304)
		(size 0.508)
		(drill 0.254)
		(layers "F.Cu" "B.Cu")
		(net "GND")
	)
	(via
		(at 267.328142 -348.58579)
		(size 0.4064)
		(drill 0.2032)
		(layers "F.Cu" "B.Cu")
		(net "GND")
	)
	(via
		(at 173.850046 -274.999958)
		(size 0.4064)
		(drill 0.2032)
		(layers "F.Cu" "B.Cu")
		(net "GND")
	)
	(via
		(at 14.52499 -376.125232)
		(size 0.508)
		(drill 0.254)
		(layers "F.Cu" "B.Cu")
		(net "GND")
	)
	(via
		(at 54.70652 -111.44504)
		(size 0.508)
		(drill 0.254)
		(layers "F.Cu" "B.Cu")
		(net "GND")
	)
	(via
		(at 133.055868 -348.58579)
		(size 0.4064)
		(drill 0.2032)
		(layers "F.Cu" "B.Cu")
		(net "GND")
	)
	(via
		(at 424.57497 -293.52494)
		(size 0.4064)
		(drill 0.2032)
		(layers "F.Cu" "B.Cu")
		(net "GND")
	)
	(via
		(at 134.831074 -6.292342)
		(size 0.508)
		(drill 0.254)
		(layers "F.Cu" "B.Cu")
		(net "GND")
	)
	(via
		(at 251.854716 -23.880318)
		(size 0.508)
		(drill 0.254)
		(layers "F.Cu" "B.Cu")
		(net "GND")
	)
	(via
		(at 176.224946 -303.974754)
		(size 0.4064)
		(drill 0.2032)
		(layers "F.Cu" "B.Cu")
		(net "GND")
	)
	(via
		(at 430.488852 -348.58579)
		(size 0.4064)
		(drill 0.2032)
		(layers "F.Cu" "B.Cu")
		(net "GND")
	)
	(via
		(at 385.433824 -136.901936)
		(size 0.508)
		(drill 0.254)
		(layers "F.Cu" "B.Cu")
		(net "GND")
	)
	(via
		(at 17.620742 -270.100806)
		(size 0.508)
		(drill 0.254)
		(layers "F.Cu" "B.Cu")
		(net "GND")
	)
	(via
		(at 52.85232 -107.844844)
		(size 0.508)
		(drill 0.254)
		(layers "F.Cu" "B.Cu")
		(net "GND")
	)
	(via
		(at 361.232704 -378.764292)
		(size 0.508)
		(drill 0.254)
		(layers "F.Cu" "B.Cu")
		(net "GND")
	)
	(via
		(at 389.424926 -286.874966)
		(size 0.4064)
		(drill 0.2032)
		(layers "F.Cu" "B.Cu")
		(net "GND")
	)
	(via
		(at 388.474966 -296.37482)
		(size 0.4064)
		(drill 0.2032)
		(layers "F.Cu" "B.Cu")
		(net "GND")
	)
	(via
		(at 280.924762 -309.674768)
		(size 0.4064)
		(drill 0.2032)
		(layers "F.Cu" "B.Cu")
		(net "GND")
	)
	(via
		(at 425.99991 -312.999882)
		(size 0.4064)
		(drill 0.2032)
		(layers "F.Cu" "B.Cu")
		(net "GND")
	)
	(via
		(at 419.349936 -280.699718)
		(size 0.4064)
		(drill 0.2032)
		(layers "F.Cu" "B.Cu")
		(net "GND")
	)
	(via
		(at 382.791716 -122.626628)
		(size 0.508)
		(drill 0.254)
		(layers "F.Cu" "B.Cu")
		(net "GND")
	)
	(via
		(at 271.424908 -276.424898)
		(size 0.4064)
		(drill 0.2032)
		(layers "F.Cu" "B.Cu")
		(net "GND")
	)
	(via
		(at 260.943852 -352.703638)
		(size 0.508)
		(drill 0.254)
		(layers "F.Cu" "B.Cu")
		(net "GND")
	)
	(via
		(at 339.92185 -86.767162)
		(size 0.508)
		(drill 0.254)
		(layers "F.Cu" "B.Cu")
		(net "GND")
	)
	(via
		(at 406.524968 -298.27474)
		(size 0.4064)
		(drill 0.2032)
		(layers "F.Cu" "B.Cu")
		(net "GND")
	)
	(via
		(at 68.280788 -34.990024)
		(size 0.508)
		(drill 0.254)
		(layers "F.Cu" "B.Cu")
		(net "GND")
	)
	(via
		(at 109.01934 -199.347582)
		(size 0.508)
		(drill 0.254)
		(layers "F.Cu" "B.Cu")
		(net "GND")
	)
	(via
		(at 82.369914 -141.42085)
		(size 0.508)
		(drill 0.254)
		(layers "F.Cu" "B.Cu")
		(net "GND")
	)
	(via
		(at 384.674872 -282.124912)
		(size 0.4064)
		(drill 0.2032)
		(layers "F.Cu" "B.Cu")
		(net "GND")
	)
	(via
		(at 38.347904 -399.441924)
		(size 0.508)
		(drill 0.254)
		(layers "F.Cu" "B.Cu")
		(net "GND")
	)
	(via
		(at 58.224928 -284.024832)
		(size 0.4064)
		(drill 0.2032)
		(layers "F.Cu" "B.Cu")
		(net "GND")
	)
	(via
		(at 219.359226 -291.61232)
		(size 0.508)
		(drill 0.254)
		(layers "F.Cu" "B.Cu")
		(net "GND")
	)
	(via
		(at 237.642654 -311.026556)
		(size 0.508)
		(drill 0.254)
		(layers "F.Cu" "B.Cu")
		(net "GND")
	)
	(via
		(at 381.599948 -62.812168)
		(size 0.508)
		(drill 0.254)
		(layers "F.Cu" "B.Cu")
		(net "GND")
	)
	(via
		(at 278.473916 -73.85177)
		(size 0.508)
		(drill 0.254)
		(layers "F.Cu" "B.Cu")
		(net "GND")
	)
	(via
		(at 202.555094 -29.590238)
		(size 0.508)
		(drill 0.254)
		(layers "F.Cu" "B.Cu")
		(net "GND")
	)
	(via
		(at 257.385058 -83.173062)
		(size 0.508)
		(drill 0.254)
		(layers "F.Cu" "B.Cu")
		(net "GND")
	)
	(via
		(at 0.77089 -375.421144)
		(size 0.508)
		(drill 0.254)
		(layers "F.Cu" "B.Cu")
		(net "GND")
	)
	(via
		(at 39.699946 -313.949842)
		(size 0.4064)
		(drill 0.2032)
		(layers "F.Cu" "B.Cu")
		(net "GND")
	)
	(via
		(at 401.774914 -285.924752)
		(size 0.4064)
		(drill 0.2032)
		(layers "F.Cu" "B.Cu")
		(net "GND")
	)
	(via
		(at 81.499964 -275.949918)
		(size 0.4064)
		(drill 0.2032)
		(layers "F.Cu" "B.Cu")
		(net "GND")
	)
	(via
		(at 423.32783 -372.341902)
		(size 0.508)
		(drill 0.254)
		(layers "F.Cu" "B.Cu")
		(net "GND")
	)
	(via
		(at 142.525242 -14.100302)
		(size 0.508)
		(drill 0.254)
		(layers "F.Cu" "B.Cu")
		(net "GND")
	)
	(via
		(at 18.73123 -11.372342)
		(size 0.508)
		(drill 0.254)
		(layers "F.Cu" "B.Cu")
		(net "GND")
	)
	(via
		(at 40.547798 -401.040092)
		(size 0.508)
		(drill 0.254)
		(layers "F.Cu" "B.Cu")
		(net "GND")
	)
	(via
		(at 388.54888 -33.19018)
		(size 0.508)
		(drill 0.254)
		(layers "F.Cu" "B.Cu")
		(net "GND")
	)
	(via
		(at 321.998086 -19.757136)
		(size 0.508)
		(drill 0.254)
		(layers "F.Cu" "B.Cu")
		(net "GND")
	)
	(via
		(at 390.374886 -283.074872)
		(size 0.4064)
		(drill 0.2032)
		(layers "F.Cu" "B.Cu")
		(net "GND")
	)
	(via
		(at 235.609638 -291.517832)
		(size 0.508)
		(drill 0.254)
		(layers "F.Cu" "B.Cu")
		(net "GND")
	)
	(via
		(at 393.22502 -284.974792)
		(size 0.4064)
		(drill 0.2032)
		(layers "F.Cu" "B.Cu")
		(net "GND")
	)
	(via
		(at 174.747936 -371.038628)
		(size 0.508)
		(drill 0.254)
		(layers "F.Cu" "B.Cu")
		(net "GND")
	)
	(via
		(at 459.713838 -313.15279)
		(size 0.508)
		(drill 0.254)
		(layers "F.Cu" "B.Cu")
		(net "GND")
	)
	(via
		(at 76.348082 -354.732082)
		(size 0.4064)
		(drill 0.2032)
		(layers "F.Cu" "B.Cu")
		(net "GND")
	)
	(via
		(at 412.89351 -156.555186)
		(size 0.508)
		(drill 0.254)
		(layers "F.Cu" "B.Cu")
		(net "GND")
	)
	(via
		(at 31.570676 -352.245422)
		(size 0.4572)
		(drill 0.254)
		(layers "F.Cu" "B.Cu")
		(net "GND")
	)
	(via
		(at 416.024822 -285.924752)
		(size 0.4064)
		(drill 0.2032)
		(layers "F.Cu" "B.Cu")
		(net "GND")
	)
	(via
		(at 376.09145 -305.334162)
		(size 0.508)
		(drill 0.254)
		(layers "F.Cu" "B.Cu")
		(net "GND")
	)
	(via
		(at 302.774858 -291.624766)
		(size 0.4064)
		(drill 0.2032)
		(layers "F.Cu" "B.Cu")
		(net "GND")
	)
	(via
		(at 54.424834 -300.174914)
		(size 0.4064)
		(drill 0.2032)
		(layers "F.Cu" "B.Cu")
		(net "GND")
	)
	(via
		(at 275.547582 -354.732082)
		(size 0.4064)
		(drill 0.2032)
		(layers "F.Cu" "B.Cu")
		(net "GND")
	)
	(via
		(at 170.944032 -357.75773)
		(size 0.4064)
		(drill 0.2032)
		(layers "F.Cu" "B.Cu")
		(net "GND")
	)
	(via
		(at 166.249858 -315.849762)
		(size 0.4064)
		(drill 0.2032)
		(layers "F.Cu" "B.Cu")
		(net "GND")
	)
	(via
		(at 152.47493 -275.474938)
		(size 0.4064)
		(drill 0.2032)
		(layers "F.Cu" "B.Cu")
		(net "GND")
	)
	(via
		(at 423.32783 -406.141936)
		(size 0.508)
		(drill 0.254)
		(layers "F.Cu" "B.Cu")
		(net "GND")
	)
	(via
		(at 404.150068 -319.65011)
		(size 0.4064)
		(drill 0.2032)
		(layers "F.Cu" "B.Cu")
		(net "GND")
	)
	(via
		(at 396.092172 -70.918832)
		(size 0.508)
		(drill 0.254)
		(layers "F.Cu" "B.Cu")
		(net "GND")
	)
	(via
		(at 413.649922 -279.749758)
		(size 0.4064)
		(drill 0.2032)
		(layers "F.Cu" "B.Cu")
		(net "GND")
	)
	(via
		(at 56.324754 -303.974754)
		(size 0.4064)
		(drill 0.2032)
		(layers "F.Cu" "B.Cu")
		(net "GND")
	)
	(via
		(at 180.975 -303.974754)
		(size 0.4064)
		(drill 0.2032)
		(layers "F.Cu" "B.Cu")
		(net "GND")
	)
	(via
		(at 413.465264 -344.831162)
		(size 0.4572)
		(drill 0.254)
		(layers "F.Cu" "B.Cu")
		(net "GND")
	)
	(via
		(at 397.97482 -290.674806)
		(size 0.4064)
		(drill 0.2032)
		(layers "F.Cu" "B.Cu")
		(net "GND")
	)
	(via
		(at 45.257974 -73.85177)
		(size 0.508)
		(drill 0.254)
		(layers "F.Cu" "B.Cu")
		(net "GND")
	)
	(via
		(at 159.124904 -282.124912)
		(size 0.4064)
		(drill 0.2032)
		(layers "F.Cu" "B.Cu")
		(net "GND")
	)
	(via
		(at 377.12777 -411.141926)
		(size 0.508)
		(drill 0.254)
		(layers "F.Cu" "B.Cu")
		(net "GND")
	)
	(via
		(at 44.94784 -376.242072)
		(size 0.508)
		(drill 0.254)
		(layers "F.Cu" "B.Cu")
		(net "GND")
	)
	(via
		(at 174.900082 -38.315138)
		(size 0.508)
		(drill 0.254)
		(layers "F.Cu" "B.Cu")
		(net "GND")
	)
	(via
		(at 226.905312 -308.073298)
		(size 0.508)
		(drill 0.254)
		(layers "F.Cu" "B.Cu")
		(net "GND")
	)
	(via
		(at 315.60008 -316.799722)
		(size 0.4064)
		(drill 0.2032)
		(layers "F.Cu" "B.Cu")
		(net "GND")
	)
	(via
		(at 244.215666 -235.621322)
		(size 0.508)
		(drill 0.254)
		(layers "F.Cu" "B.Cu")
		(net "GND")
	)
	(via
		(at 417.924996 -292.574726)
		(size 0.4064)
		(drill 0.2032)
		(layers "F.Cu" "B.Cu")
		(net "GND")
	)
	(via
		(at 49.1998 -277.849838)
		(size 0.4064)
		(drill 0.2032)
		(layers "F.Cu" "B.Cu")
		(net "GND")
	)
	(via
		(at 317.008256 -123.904502)
		(size 0.508)
		(drill 0.254)
		(layers "F.Cu" "B.Cu")
		(net "GND")
	)
	(via
		(at 370.881402 -31.118302)
		(size 0.508)
		(drill 0.254)
		(layers "F.Cu" "B.Cu")
		(net "GND")
	)
	(via
		(at 284.249876 -311.099962)
		(size 0.4064)
		(drill 0.2032)
		(layers "F.Cu" "B.Cu")
		(net "GND")
	)
	(via
		(at 155.448 -417.82492)
		(size 0.508)
		(drill 0.254)
		(layers "F.Cu" "B.Cu")
		(net "GND")
	)
	(via
		(at 279.974802 -299.224954)
		(size 0.4064)
		(drill 0.2032)
		(layers "F.Cu" "B.Cu")
		(net "GND")
	)
	(via
		(at 329.108816 -344.831162)
		(size 0.4572)
		(drill 0.254)
		(layers "F.Cu" "B.Cu")
		(net "GND")
	)
	(via
		(at 78.649576 -274.999958)
		(size 0.4064)
		(drill 0.2032)
		(layers "F.Cu" "B.Cu")
		(net "GND")
	)
	(via
		(at 299.44949 -272.14957)
		(size 0.4064)
		(drill 0.2032)
		(layers "F.Cu" "B.Cu")
		(net "GND")
	)
	(via
		(at 42.747946 -406.040336)
		(size 0.508)
		(drill 0.254)
		(layers "F.Cu" "B.Cu")
		(net "GND")
	)
	(via
		(at 166.249858 -311.099962)
		(size 0.4064)
		(drill 0.2032)
		(layers "F.Cu" "B.Cu")
		(net "GND")
	)
	(via
		(at 253.513336 -31.118302)
		(size 0.508)
		(drill 0.254)
		(layers "F.Cu" "B.Cu")
		(net "GND")
	)
	(via
		(at 421.127682 -411.141926)
		(size 0.508)
		(drill 0.254)
		(layers "F.Cu" "B.Cu")
		(net "GND")
	)
	(via
		(at 167.675052 -300.174914)
		(size 0.4064)
		(drill 0.2032)
		(layers "F.Cu" "B.Cu")
		(net "GND")
	)
	(via
		(at 346.327984 -400.938492)
		(size 0.508)
		(drill 0.254)
		(layers "F.Cu" "B.Cu")
		(net "GND")
	)
	(via
		(at 20.765008 -345.465146)
		(size 0.4064)
		(drill 0.2032)
		(layers "F.Cu" "B.Cu")
		(net "GND")
	)
	(via
		(at 161.617152 -348.58579)
		(size 0.4064)
		(drill 0.2032)
		(layers "F.Cu" "B.Cu")
		(net "GND")
	)
	(via
		(at 71.347838 -410.041852)
		(size 0.508)
		(drill 0.254)
		(layers "F.Cu" "B.Cu")
		(net "GND")
	)
	(via
		(at 395.392148 -104.793034)
		(size 0.508)
		(drill 0.254)
		(layers "F.Cu" "B.Cu")
		(net "GND")
	)
	(via
		(at 402.724874 -298.27474)
		(size 0.4064)
		(drill 0.2032)
		(layers "F.Cu" "B.Cu")
		(net "GND")
	)
	(via
		(at 119.646192 -117.999764)
		(size 0.508)
		(drill 0.254)
		(layers "F.Cu" "B.Cu")
		(net "GND")
	)
	(via
		(at 142.754096 -355.366066)
		(size 0.4572)
		(drill 0.254)
		(layers "F.Cu" "B.Cu")
		(net "GND")
	)
	(via
		(at 72.949816 -281.649932)
		(size 0.4064)
		(drill 0.2032)
		(layers "F.Cu" "B.Cu")
		(net "GND")
	)
	(via
		(at 119.214646 -172.216064)
		(size 0.508)
		(drill 0.254)
		(layers "F.Cu" "B.Cu")
		(net "GND")
	)
	(via
		(at 273.91741 -343.073482)
		(size 0.4572)
		(drill 0.254)
		(layers "F.Cu" "B.Cu")
		(net "GND")
	)
	(via
		(at 112.545114 -259.782564)
		(size 0.508)
		(drill 0.254)
		(layers "F.Cu" "B.Cu")
		(net "GND")
	)
	(via
		(at 189.049914 -311.099962)
		(size 0.4064)
		(drill 0.2032)
		(layers "F.Cu" "B.Cu")
		(net "GND")
	)
	(via
		(at 370.61902 -342.439498)
		(size 0.4064)
		(drill 0.2032)
		(layers "F.Cu" "B.Cu")
		(net "GND")
	)
	(via
		(at 426.94987 -305.399948)
		(size 0.4064)
		(drill 0.2032)
		(layers "F.Cu" "B.Cu")
		(net "GND")
	)
	(via
		(at 449.452746 -284.764988)
		(size 0.508)
		(drill 0.254)
		(layers "F.Cu" "B.Cu")
		(net "GND")
	)
	(via
		(at 248.148348 -154.510994)
		(size 0.508)
		(drill 0.254)
		(layers "F.Cu" "B.Cu")
		(net "GND")
	)
	(via
		(at 337.5279 -378.83846)
		(size 0.508)
		(drill 0.254)
		(layers "F.Cu" "B.Cu")
		(net "GND")
	)
	(via
		(at 329.480164 -351.611438)
		(size 0.4064)
		(drill 0.2032)
		(layers "F.Cu" "B.Cu")
		(net "GND")
	)
	(via
		(at 280.13533 -349.219774)
		(size 0.4572)
		(drill 0.254)
		(layers "F.Cu" "B.Cu")
		(net "GND")
	)
	(via
		(at 344.3986 -37.201094)
		(size 0.508)
		(drill 0.254)
		(layers "F.Cu" "B.Cu")
		(net "GND")
	)
	(via
		(at 253.489968 -73.85177)
		(size 0.508)
		(drill 0.254)
		(layers "F.Cu" "B.Cu")
		(net "GND")
	)
	(via
		(at 65.349882 -316.799722)
		(size 0.4064)
		(drill 0.2032)
		(layers "F.Cu" "B.Cu")
		(net "GND")
	)
	(via
		(at 177.748946 -29.589984)
		(size 0.508)
		(drill 0.254)
		(layers "F.Cu" "B.Cu")
		(net "GND")
	)
	(via
		(at 318.523112 -343.073482)
		(size 0.4572)
		(drill 0.254)
		(layers "F.Cu" "B.Cu")
		(net "GND")
	)
	(via
		(at 60.455048 -33.19018)
		(size 0.508)
		(drill 0.254)
		(layers "F.Cu" "B.Cu")
		(net "GND")
	)
	(via
		(at 142.754096 -354.098098)
		(size 0.4572)
		(drill 0.254)
		(layers "F.Cu" "B.Cu")
		(net "GND")
	)
	(via
		(at 417.450016 -311.099962)
		(size 0.4064)
		(drill 0.2032)
		(layers "F.Cu" "B.Cu")
		(net "GND")
	)
	(via
		(at 401.774914 -284.974792)
		(size 0.4064)
		(drill 0.2032)
		(layers "F.Cu" "B.Cu")
		(net "GND")
	)
	(via
		(at 383.05486 -345.465146)
		(size 0.4064)
		(drill 0.2032)
		(layers "F.Cu" "B.Cu")
		(net "GND")
	)
	(via
		(at 54.636416 -51.661822)
		(size 0.508)
		(drill 0.254)
		(layers "F.Cu" "B.Cu")
		(net "GND")
	)
	(via
		(at 283.774896 -300.174914)
		(size 0.4064)
		(drill 0.2032)
		(layers "F.Cu" "B.Cu")
		(net "GND")
	)
	(via
		(at 81.024984 -293.52494)
		(size 0.4064)
		(drill 0.2032)
		(layers "F.Cu" "B.Cu")
		(net "GND")
	)
	(via
		(at 106.229404 -165.935152)
		(size 0.508)
		(drill 0.254)
		(layers "F.Cu" "B.Cu")
		(net "GND")
	)
	(via
		(at 463.037682 -189.497462)
		(size 0.508)
		(drill 0.254)
		(layers "F.Cu" "B.Cu")
		(net "GND")
	)
	(via
		(at 287.099756 -278.799798)
		(size 0.4064)
		(drill 0.2032)
		(layers "F.Cu" "B.Cu")
		(net "GND")
	)
	(via
		(at 311.799732 -314.899802)
		(size 0.4064)
		(drill 0.2032)
		(layers "F.Cu" "B.Cu")
		(net "GND")
	)
	(via
		(at 286.906462 -120.555004)
		(size 0.508)
		(drill 0.254)
		(layers "F.Cu" "B.Cu")
		(net "GND")
	)
	(via
		(at 125.2347 -247.923812)
		(size 0.508)
		(drill 0.254)
		(layers "F.Cu" "B.Cu")
		(net "GND")
	)
	(via
		(at 270.601694 -125.692154)
		(size 0.508)
		(drill 0.254)
		(layers "F.Cu" "B.Cu")
		(net "GND")
	)
	(via
		(at 420.567104 -120.035066)
		(size 0.508)
		(drill 0.254)
		(layers "F.Cu" "B.Cu")
		(net "GND")
	)
	(via
		(at 195.699888 -281.649932)
		(size 0.4064)
		(drill 0.2032)
		(layers "F.Cu" "B.Cu")
		(net "GND")
	)
	(via
		(at 93.541342 -235.7374)
		(size 0.508)
		(drill 0.254)
		(layers "F.Cu" "B.Cu")
		(net "GND")
	)
	(via
		(at 400.824954 -289.724846)
		(size 0.4064)
		(drill 0.2032)
		(layers "F.Cu" "B.Cu")
		(net "GND")
	)
	(via
		(at 386.701792 -133.301994)
		(size 0.508)
		(drill 0.254)
		(layers "F.Cu" "B.Cu")
		(net "GND")
	)
	(via
		(at 295.727882 -395.938502)
		(size 0.508)
		(drill 0.254)
		(layers "F.Cu" "B.Cu")
		(net "GND")
	)
	(via
		(at 284.249876 -312.049922)
		(size 0.4064)
		(drill 0.2032)
		(layers "F.Cu" "B.Cu")
		(net "GND")
	)
	(via
		(at 387.793992 -341.805514)
		(size 0.4572)
		(drill 0.254)
		(layers "F.Cu" "B.Cu")
		(net "GND")
	)
	(via
		(at 88.783922 -342.439498)
		(size 0.4064)
		(drill 0.2032)
		(layers "F.Cu" "B.Cu")
		(net "GND")
	)
	(via
		(at 77.357478 -29.784294)
		(size 0.508)
		(drill 0.254)
		(layers "F.Cu" "B.Cu")
		(net "GND")
	)
	(via
		(at 242.91671 -163.021518)
		(size 0.508)
		(drill 0.254)
		(layers "F.Cu" "B.Cu")
		(net "GND")
	)
	(via
		(at 374.927876 -408.840178)
		(size 0.508)
		(drill 0.254)
		(layers "F.Cu" "B.Cu")
		(net "GND")
	)
	(via
		(at 57.649872 -27.04973)
		(size 0.508)
		(drill 0.254)
		(layers "F.Cu" "B.Cu")
		(net "GND")
	)
	(via
		(at 153.42489 -277.374858)
		(size 0.4064)
		(drill 0.2032)
		(layers "F.Cu" "B.Cu")
		(net "GND")
	)
	(via
		(at 41.599866 -306.349908)
		(size 0.4064)
		(drill 0.2032)
		(layers "F.Cu" "B.Cu")
		(net "GND")
	)
	(via
		(at 128.667764 -254.194564)
		(size 0.508)
		(drill 0.254)
		(layers "F.Cu" "B.Cu")
		(net "GND")
	)
	(via
		(at 160.22066 -63.218314)
		(size 0.508)
		(drill 0.254)
		(layers "F.Cu" "B.Cu")
		(net "GND")
	)
	(via
		(at 226.546664 -205.47711)
		(size 0.508)
		(drill 0.254)
		(layers "F.Cu" "B.Cu")
		(net "GND")
	)
	(via
		(at 375.623328 -56.353456)
		(size 0.508)
		(drill 0.254)
		(layers "F.Cu" "B.Cu")
		(net "GND")
	)
	(via
		(at 240.72469 -209.529934)
		(size 0.508)
		(drill 0.254)
		(layers "F.Cu" "B.Cu")
		(net "GND")
	)
	(via
		(at 399.874994 -303.974754)
		(size 0.4064)
		(drill 0.2032)
		(layers "F.Cu" "B.Cu")
		(net "GND")
	)
	(via
		(at 203.748894 -27.79014)
		(size 0.508)
		(drill 0.254)
		(layers "F.Cu" "B.Cu")
		(net "GND")
	)
	(via
		(at 18.905728 -1.364996)
		(size 0.508)
		(drill 0.254)
		(layers "F.Cu" "B.Cu")
		(net "GND")
	)
	(via
		(at 183.3499 -280.699718)
		(size 0.4064)
		(drill 0.2032)
		(layers "F.Cu" "B.Cu")
		(net "GND")
	)
	(via
		(at 48.54575 -150.9776)
		(size 0.508)
		(drill 0.254)
		(layers "F.Cu" "B.Cu")
		(net "GND")
	)
	(via
		(at 185.010044 -355.34219)
		(size 0.4572)
		(drill 0.254)
		(layers "F.Cu" "B.Cu")
		(net "GND")
	)
	(via
		(at 176.699926 -318.699896)
		(size 0.4064)
		(drill 0.2032)
		(layers "F.Cu" "B.Cu")
		(net "GND")
	)
	(via
		(at 292.73754 -214.539068)
		(size 0.508)
		(drill 0.254)
		(layers "F.Cu" "B.Cu")
		(net "GND")
	)
	(via
		(at 382.495552 -245.354856)
		(size 0.508)
		(drill 0.254)
		(layers "F.Cu" "B.Cu")
		(net "GND")
	)
	(via
		(at 281.765502 -345.465146)
		(size 0.4064)
		(drill 0.2032)
		(layers "F.Cu" "B.Cu")
		(net "GND")
	)
	(via
		(at 451.459346 -289.514788)
		(size 0.508)
		(drill 0.254)
		(layers "F.Cu" "B.Cu")
		(net "GND")
	)
	(via
		(at 175.920146 -33.19018)
		(size 0.508)
		(drill 0.254)
		(layers "F.Cu" "B.Cu")
		(net "GND")
	)
	(via
		(at 27.347926 -371.140228)
		(size 0.508)
		(drill 0.254)
		(layers "F.Cu" "B.Cu")
		(net "GND")
	)
	(via
		(at 120.94337 -52.536852)
		(size 0.508)
		(drill 0.254)
		(layers "F.Cu" "B.Cu")
		(net "GND")
	)
	(via
		(at 303.249584 -272.14957)
		(size 0.4064)
		(drill 0.2032)
		(layers "F.Cu" "B.Cu")
		(net "GND")
	)
	(via
		(at 130.23215 -13.613638)
		(size 0.508)
		(drill 0.254)
		(layers "F.Cu" "B.Cu")
		(net "GND")
	)
	(via
		(at 49.29632 -129.68351)
		(size 0.508)
		(drill 0.254)
		(layers "F.Cu" "B.Cu")
		(net "GND")
	)
	(via
		(at 306.448206 -120.035066)
		(size 0.508)
		(drill 0.254)
		(layers "F.Cu" "B.Cu")
		(net "GND")
	)
	(via
		(at 425.901104 -350.977454)
		(size 0.4572)
		(drill 0.254)
		(layers "F.Cu" "B.Cu")
		(net "GND")
	)
	(via
		(at 332.230984 -123.795028)
		(size 0.508)
		(drill 0.254)
		(layers "F.Cu" "B.Cu")
		(net "GND")
	)
	(via
		(at 174.052992 -342.439498)
		(size 0.4064)
		(drill 0.2032)
		(layers "F.Cu" "B.Cu")
		(net "GND")
	)
	(via
		(at 422.881298 -33.459674)
		(size 0.508)
		(drill 0.254)
		(layers "F.Cu" "B.Cu")
		(net "GND")
	)
	(via
		(at 34.491676 -104.523286)
		(size 0.508)
		(drill 0.254)
		(layers "F.Cu" "B.Cu")
		(net "GND")
	)
	(via
		(at 466.835998 -292.923976)
		(size 0.508)
		(drill 0.254)
		(layers "F.Cu" "B.Cu")
		(net "GND")
	)
	(via
		(at 426.47489 -301.124874)
		(size 0.4064)
		(drill 0.2032)
		(layers "F.Cu" "B.Cu")
		(net "GND")
	)
	(via
		(at 416.974782 -306.824888)
		(size 0.4064)
		(drill 0.2032)
		(layers "F.Cu" "B.Cu")
		(net "GND")
	)
	(via
		(at 330.587604 -354.732082)
		(size 0.4064)
		(drill 0.2032)
		(layers "F.Cu" "B.Cu")
		(net "GND")
	)
	(via
		(at 303.567846 -136.645142)
		(size 0.508)
		(drill 0.254)
		(layers "F.Cu" "B.Cu")
		(net "GND")
	)
	(via
		(at 51.099974 -312.999882)
		(size 0.4064)
		(drill 0.2032)
		(layers "F.Cu" "B.Cu")
		(net "GND")
	)
	(via
		(at 371.729508 -47.020734)
		(size 0.508)
		(drill 0.254)
		(layers "F.Cu" "B.Cu")
		(net "GND")
	)
	(via
		(at 124.063252 -108.067856)
		(size 0.508)
		(drill 0.254)
		(layers "F.Cu" "B.Cu")
		(net "GND")
	)
	(via
		(at 366.971326 -32.911796)
		(size 0.508)
		(drill 0.254)
		(layers "F.Cu" "B.Cu")
		(net "GND")
	)
	(via
		(at 466.835998 -318.323976)
		(size 0.508)
		(drill 0.254)
		(layers "F.Cu" "B.Cu")
		(net "GND")
	)
	(via
		(at 390.58088 -25.990042)
		(size 0.508)
		(drill 0.254)
		(layers "F.Cu" "B.Cu")
		(net "GND")
	)
	(via
		(at 60.599828 -274.049744)
		(size 0.4064)
		(drill 0.2032)
		(layers "F.Cu" "B.Cu")
		(net "GND")
	)
	(via
		(at 174.747936 -404.838662)
		(size 0.508)
		(drill 0.254)
		(layers "F.Cu" "B.Cu")
		(net "GND")
	)
	(via
		(at 300.399704 -276.899878)
		(size 0.4064)
		(drill 0.2032)
		(layers "F.Cu" "B.Cu")
		(net "GND")
	)
	(via
		(at 339.09 -148.971)
		(size 0.508)
		(drill 0.254)
		(layers "F.Cu" "B.Cu")
		(net "GND")
	)
	(via
		(at 295.649904 -314.899802)
		(size 0.4064)
		(drill 0.2032)
		(layers "F.Cu" "B.Cu")
		(net "GND")
	)
	(via
		(at 227.067872 -219.504006)
		(size 0.4572)
		(drill 0.254)
		(layers "F.Cu" "B.Cu")
		(net "GND")
	)
	(via
		(at 68.199762 -278.799798)
		(size 0.4064)
		(drill 0.2032)
		(layers "F.Cu" "B.Cu")
		(net "GND")
	)
	(via
		(at 413.465264 -355.366066)
		(size 0.4572)
		(drill 0.254)
		(layers "F.Cu" "B.Cu")
		(net "GND")
	)
	(via
		(at 54.341776 -25.971246)
		(size 0.508)
		(drill 0.254)
		(layers "F.Cu" "B.Cu")
		(net "GND")
	)
	(via
		(at 368.623088 -86.606634)
		(size 0.508)
		(drill 0.254)
		(layers "F.Cu" "B.Cu")
		(net "GND")
	)
	(via
		(at 158.87954 -355.366066)
		(size 0.4572)
		(drill 0.254)
		(layers "F.Cu" "B.Cu")
		(net "GND")
	)
	(via
		(at 176.224946 -291.624766)
		(size 0.4064)
		(drill 0.2032)
		(layers "F.Cu" "B.Cu")
		(net "GND")
	)
	(via
		(at 40.649906 -307.299868)
		(size 0.4064)
		(drill 0.2032)
		(layers "F.Cu" "B.Cu")
		(net "GND")
	)
	(via
		(at 414.599882 -310.149748)
		(size 0.4064)
		(drill 0.2032)
		(layers "F.Cu" "B.Cu")
		(net "GND")
	)
	(via
		(at 92.997782 -295.355518)
		(size 0.508)
		(drill 0.254)
		(layers "F.Cu" "B.Cu")
		(net "GND")
	)
	(via
		(at 292.32479 -302.074834)
		(size 0.4064)
		(drill 0.2032)
		(layers "F.Cu" "B.Cu")
		(net "GND")
	)
	(via
		(at 279.499822 -281.649932)
		(size 0.4064)
		(drill 0.2032)
		(layers "F.Cu" "B.Cu")
		(net "GND")
	)
	(via
		(at 452.01205 -23.355554)
		(size 0.508)
		(drill 0.254)
		(layers "F.Cu" "B.Cu")
		(net "GND")
	)
	(via
		(at 375.358152 -357.123746)
		(size 0.4572)
		(drill 0.254)
		(layers "F.Cu" "B.Cu")
		(net "GND")
	)
	(via
		(at 417.924996 -284.024832)
		(size 0.4064)
		(drill 0.2032)
		(layers "F.Cu" "B.Cu")
		(net "GND")
	)
	(via
		(at 292.01999 -29.590238)
		(size 0.508)
		(drill 0.254)
		(layers "F.Cu" "B.Cu")
		(net "GND")
	)
	(via
		(at 394.011912 -344.831162)
		(size 0.4572)
		(drill 0.254)
		(layers "F.Cu" "B.Cu")
		(net "GND")
	)
	(via
		(at 73.899776 -310.149748)
		(size 0.4064)
		(drill 0.2032)
		(layers "F.Cu" "B.Cu")
		(net "GND")
	)
	(via
		(at 161.9885 -347.951806)
		(size 0.4572)
		(drill 0.254)
		(layers "F.Cu" "B.Cu")
		(net "GND")
	)
	(via
		(at 69.624956 -305.874928)
		(size 0.4064)
		(drill 0.2032)
		(layers "F.Cu" "B.Cu")
		(net "GND")
	)
	(via
		(at 42.549826 -310.149748)
		(size 0.4064)
		(drill 0.2032)
		(layers "F.Cu" "B.Cu")
		(net "GND")
	)
	(via
		(at 168.148 -373.83847)
		(size 0.508)
		(drill 0.254)
		(layers "F.Cu" "B.Cu")
		(net "GND")
	)
	(via
		(at 205.659228 -287.854136)
		(size 0.508)
		(drill 0.254)
		(layers "F.Cu" "B.Cu")
		(net "GND")
	)
	(via
		(at 77.894942 -106.384852)
		(size 0.508)
		(drill 0.254)
		(layers "F.Cu" "B.Cu")
		(net "GND")
	)
	(via
		(at 378.467112 -349.219774)
		(size 0.4572)
		(drill 0.254)
		(layers "F.Cu" "B.Cu")
		(net "GND")
	)
	(via
		(at 49.1998 -278.799798)
		(size 0.4064)
		(drill 0.2032)
		(layers "F.Cu" "B.Cu")
		(net "GND")
	)
	(via
		(at 14.788896 -120.15343)
		(size 0.508)
		(drill 0.254)
		(layers "F.Cu" "B.Cu")
		(net "GND")
	)
	(via
		(at 169.465244 -350.977454)
		(size 0.4572)
		(drill 0.254)
		(layers "F.Cu" "B.Cu")
		(net "GND")
	)
	(via
		(at 61.549788 -275.949918)
		(size 0.4064)
		(drill 0.2032)
		(layers "F.Cu" "B.Cu")
		(net "GND")
	)
	(via
		(at 235.557822 -25.971246)
		(size 0.508)
		(drill 0.254)
		(layers "F.Cu" "B.Cu")
		(net "GND")
	)
	(via
		(at 412.20644 -358.391714)
		(size 0.4572)
		(drill 0.254)
		(layers "F.Cu" "B.Cu")
		(net "GND")
	)
	(via
		(at 428.036736 -15.474188)
		(size 0.508)
		(drill 0.254)
		(layers "F.Cu" "B.Cu")
		(net "GND")
	)
	(via
		(at 364.563152 -227.965)
		(size 0.508)
		(drill 0.254)
		(layers "F.Cu" "B.Cu")
		(net "GND")
	)
	(via
		(at 351.65792 -25.971246)
		(size 0.508)
		(drill 0.254)
		(layers "F.Cu" "B.Cu")
		(net "GND")
	)
	(via
		(at 32.6009 -33.19018)
		(size 0.508)
		(drill 0.254)
		(layers "F.Cu" "B.Cu")
		(net "GND")
	)
	(via
		(at 151.859488 -122.626628)
		(size 0.508)
		(drill 0.254)
		(layers "F.Cu" "B.Cu")
		(net "GND")
	)
	(via
		(at 43.974766 -296.37482)
		(size 0.4064)
		(drill 0.2032)
		(layers "F.Cu" "B.Cu")
		(net "GND")
	)
	(via
		(at 288.524696 -293.52494)
		(size 0.4064)
		(drill 0.2032)
		(layers "F.Cu" "B.Cu")
		(net "GND")
	)
	(via
		(at 62.974982 -287.824926)
		(size 0.4064)
		(drill 0.2032)
		(layers "F.Cu" "B.Cu")
		(net "GND")
	)
	(via
		(at 324.741032 -346.09913)
		(size 0.4572)
		(drill 0.254)
		(layers "F.Cu" "B.Cu")
		(net "GND")
	)
	(via
		(at 122.29973 -256.870962)
		(size 0.508)
		(drill 0.254)
		(layers "F.Cu" "B.Cu")
		(net "GND")
	)
	(via
		(at 463.060796 -252.179582)
		(size 0.508)
		(drill 0.254)
		(layers "F.Cu" "B.Cu")
		(net "GND")
	)
	(via
		(at 397.49984 -312.999882)
		(size 0.4064)
		(drill 0.2032)
		(layers "F.Cu" "B.Cu")
		(net "GND")
	)
	(via
		(at 134.68604 -346.09913)
		(size 0.4572)
		(drill 0.254)
		(layers "F.Cu" "B.Cu")
		(net "GND")
	)
	(via
		(at 292.57117 -355.366066)
		(size 0.4572)
		(drill 0.254)
		(layers "F.Cu" "B.Cu")
		(net "GND")
	)
	(via
		(at 289.78225 -37.087048)
		(size 0.508)
		(drill 0.254)
		(layers "F.Cu" "B.Cu")
		(net "GND")
	)
	(via
		(at 65.81267 -143.955008)
		(size 0.508)
		(drill 0.254)
		(layers "F.Cu" "B.Cu")
		(net "GND")
	)
	(via
		(at 188.119004 -357.09987)
		(size 0.4572)
		(drill 0.254)
		(layers "F.Cu" "B.Cu")
		(net "GND")
	)
	(via
		(at 199.500236 -281.650186)
		(size 0.4064)
		(drill 0.2032)
		(layers "F.Cu" "B.Cu")
		(net "GND")
	)
	(via
		(at 427.75124 -344.831162)
		(size 0.4572)
		(drill 0.254)
		(layers "F.Cu" "B.Cu")
		(net "GND")
	)
	(via
		(at 169.587164 -104.244902)
		(size 0.508)
		(drill 0.254)
		(layers "F.Cu" "B.Cu")
		(net "GND")
	)
	(via
		(at 360.25074 -305.008534)
		(size 0.508)
		(drill 0.254)
		(layers "F.Cu" "B.Cu")
		(net "GND")
	)
	(via
		(at 283.833062 -137.16508)
		(size 0.508)
		(drill 0.254)
		(layers "F.Cu" "B.Cu")
		(net "GND")
	)
	(via
		(at 271.424908 -297.32478)
		(size 0.4064)
		(drill 0.2032)
		(layers "F.Cu" "B.Cu")
		(net "GND")
	)
	(via
		(at 402.685504 -34.183066)
		(size 0.508)
		(drill 0.254)
		(layers "F.Cu" "B.Cu")
		(net "GND")
	)
	(via
		(at 369.613434 -34.718498)
		(size 0.508)
		(drill 0.254)
		(layers "F.Cu" "B.Cu")
		(net "GND")
	)
	(via
		(at 70.582028 -58.238644)
		(size 0.508)
		(drill 0.254)
		(layers "F.Cu" "B.Cu")
		(net "GND")
	)
	(via
		(at 151.859488 -108.123228)
		(size 0.508)
		(drill 0.254)
		(layers "F.Cu" "B.Cu")
		(net "GND")
	)
	(via
		(at 388.949946 -316.799722)
		(size 0.4064)
		(drill 0.2032)
		(layers "F.Cu" "B.Cu")
		(net "GND")
	)
	(via
		(at 418.874956 -300.174914)
		(size 0.4064)
		(drill 0.2032)
		(layers "F.Cu" "B.Cu")
		(net "GND")
	)
	(via
		(at 434.327808 -376.140218)
		(size 0.508)
		(drill 0.254)
		(layers "F.Cu" "B.Cu")
		(net "GND")
	)
	(via
		(at 9.195054 -60.633356)
		(size 0.508)
		(drill 0.254)
		(layers "F.Cu" "B.Cu")
		(net "GND")
	)
	(via
		(at 403.338792 -346.09913)
		(size 0.4572)
		(drill 0.254)
		(layers "F.Cu" "B.Cu")
		(net "GND")
	)
	(via
		(at 46.719236 -46.893226)
		(size 0.508)
		(drill 0.254)
		(layers "F.Cu" "B.Cu")
		(net "GND")
	)
	(via
		(at 346.562172 -277.004272)
		(size 0.508)
		(drill 0.254)
		(layers "F.Cu" "B.Cu")
		(net "GND")
	)
	(via
		(at 160.549844 -305.399948)
		(size 0.4064)
		(drill 0.2032)
		(layers "F.Cu" "B.Cu")
		(net "GND")
	)
	(via
		(at 163.874958 -305.874928)
		(size 0.4064)
		(drill 0.2032)
		(layers "F.Cu" "B.Cu")
		(net "GND")
	)
	(via
		(at 272.374868 -282.124912)
		(size 0.4064)
		(drill 0.2032)
		(layers "F.Cu" "B.Cu")
		(net "GND")
	)
	(via
		(at 426.94987 -285.449772)
		(size 0.4064)
		(drill 0.2032)
		(layers "F.Cu" "B.Cu")
		(net "GND")
	)
	(via
		(at 285.052262 -137.16508)
		(size 0.508)
		(drill 0.254)
		(layers "F.Cu" "B.Cu")
		(net "GND")
	)
	(via
		(at 315.60008 -281.650186)
		(size 0.4064)
		(drill 0.2032)
		(layers "F.Cu" "B.Cu")
		(net "GND")
	)
	(via
		(at 47.29988 -304.449734)
		(size 0.4064)
		(drill 0.2032)
		(layers "F.Cu" "B.Cu")
		(net "GND")
	)
	(via
		(at 168.20642 -346.09913)
		(size 0.4572)
		(drill 0.254)
		(layers "F.Cu" "B.Cu")
		(net "GND")
	)
	(via
		(at 356.551738 -398.889982)
		(size 0.508)
		(drill 0.254)
		(layers "F.Cu" "B.Cu")
		(net "GND")
	)
	(via
		(at 374.484646 -241.146076)
		(size 0.508)
		(drill 0.254)
		(layers "F.Cu" "B.Cu")
		(net "GND")
	)
	(via
		(at 74.248264 -142.15491)
		(size 0.508)
		(drill 0.254)
		(layers "F.Cu" "B.Cu")
		(net "GND")
	)
	(via
		(at 422.199816 -317.749936)
		(size 0.4064)
		(drill 0.2032)
		(layers "F.Cu" "B.Cu")
		(net "GND")
	)
	(via
		(at 168.150032 -276.899878)
		(size 0.4064)
		(drill 0.2032)
		(layers "F.Cu" "B.Cu")
		(net "GND")
	)
	(via
		(at 277.599902 -308.249828)
		(size 0.4064)
		(drill 0.2032)
		(layers "F.Cu" "B.Cu")
		(net "GND")
	)
	(via
		(at 65.824862 -297.32478)
		(size 0.4064)
		(drill 0.2032)
		(layers "F.Cu" "B.Cu")
		(net "GND")
	)
	(via
		(at 82.449924 -309.199788)
		(size 0.4064)
		(drill 0.2032)
		(layers "F.Cu" "B.Cu")
		(net "GND")
	)
	(via
		(at 136.587738 -26.360882)
		(size 0.508)
		(drill 0.254)
		(layers "F.Cu" "B.Cu")
		(net "GND")
	)
	(via
		(at 172.900086 -278.799798)
		(size 0.4064)
		(drill 0.2032)
		(layers "F.Cu" "B.Cu")
		(net "GND")
	)
	(via
		(at 114.231674 -254.21717)
		(size 0.508)
		(drill 0.254)
		(layers "F.Cu" "B.Cu")
		(net "GND")
	)
	(via
		(at 309.424832 -301.124874)
		(size 0.4064)
		(drill 0.2032)
		(layers "F.Cu" "B.Cu")
		(net "GND")
	)
	(via
		(at 99.680776 -102.095046)
		(size 0.508)
		(drill 0.254)
		(layers "F.Cu" "B.Cu")
		(net "GND")
	)
	(via
		(at 317.392558 -11.372342)
		(size 0.508)
		(drill 0.254)
		(layers "F.Cu" "B.Cu")
		(net "GND")
	)
	(via
		(at 72.949816 -275.949918)
		(size 0.4064)
		(drill 0.2032)
		(layers "F.Cu" "B.Cu")
		(net "GND")
	)
	(via
		(at 126.347728 -382.73863)
		(size 0.508)
		(drill 0.254)
		(layers "F.Cu" "B.Cu")
		(net "GND")
	)
	(via
		(at 227.190046 -154.016202)
		(size 0.508)
		(drill 0.254)
		(layers "F.Cu" "B.Cu")
		(net "GND")
	)
	(via
		(at 422.199816 -285.449772)
		(size 0.4064)
		(drill 0.2032)
		(layers "F.Cu" "B.Cu")
		(net "GND")
	)
	(via
		(at 176.054512 -348.58579)
		(size 0.4064)
		(drill 0.2032)
		(layers "F.Cu" "B.Cu")
		(net "GND")
	)
	(via
		(at 398.4498 -315.849762)
		(size 0.4064)
		(drill 0.2032)
		(layers "F.Cu" "B.Cu")
		(net "GND")
	)
	(via
		(at 164.726112 -342.439498)
		(size 0.4064)
		(drill 0.2032)
		(layers "F.Cu" "B.Cu")
		(net "GND")
	)
	(via
		(at 61.17463 -347.951806)
		(size 0.4572)
		(drill 0.254)
		(layers "F.Cu" "B.Cu")
		(net "GND")
	)
	(via
		(at 435.227984 -358.391714)
		(size 0.4572)
		(drill 0.254)
		(layers "F.Cu" "B.Cu")
		(net "GND")
	)
	(via
		(at 362.462826 -110.365032)
		(size 0.508)
		(drill 0.254)
		(layers "F.Cu" "B.Cu")
		(net "GND")
	)
	(via
		(at 129.366264 -201.478896)
		(size 0.508)
		(drill 0.254)
		(layers "F.Cu" "B.Cu")
		(net "GND")
	)
	(via
		(at 35.93846 -346.09913)
		(size 0.4572)
		(drill 0.254)
		(layers "F.Cu" "B.Cu")
		(net "GND")
	)
	(via
		(at 103.497126 -379.73889)
		(size 0.508)
		(drill 0.254)
		(layers "F.Cu" "B.Cu")
		(net "GND")
	)
	(via
		(at 158.508192 -357.75773)
		(size 0.4064)
		(drill 0.2032)
		(layers "F.Cu" "B.Cu")
		(net "GND")
	)
	(via
		(at 390.327896 -408.738578)
		(size 0.508)
		(drill 0.254)
		(layers "F.Cu" "B.Cu")
		(net "GND")
	)
	(via
		(at 271.424908 -273.574764)
		(size 0.4064)
		(drill 0.2032)
		(layers "F.Cu" "B.Cu")
		(net "GND")
	)
	(via
		(at 75.74788 -403.738588)
		(size 0.508)
		(drill 0.254)
		(layers "F.Cu" "B.Cu")
		(net "GND")
	)
	(via
		(at 181.901084 -347.951806)
		(size 0.4572)
		(drill 0.254)
		(layers "F.Cu" "B.Cu")
		(net "GND")
	)
	(via
		(at 136.039352 -29.311854)
		(size 0.508)
		(drill 0.254)
		(layers "F.Cu" "B.Cu")
		(net "GND")
	)
	(via
		(at 311.160414 -24.65832)
		(size 0.508)
		(drill 0.254)
		(layers "F.Cu" "B.Cu")
		(net "GND")
	)
	(via
		(at 153.233628 -135.643112)
		(size 0.508)
		(drill 0.254)
		(layers "F.Cu" "B.Cu")
		(net "GND")
	)
	(via
		(at 407.949908 -314.899802)
		(size 0.4064)
		(drill 0.2032)
		(layers "F.Cu" "B.Cu")
		(net "GND")
	)
	(via
		(at 160.549844 -310.149748)
		(size 0.4064)
		(drill 0.2032)
		(layers "F.Cu" "B.Cu")
		(net "GND")
	)
	(via
		(at 192.375028 -296.37482)
		(size 0.4064)
		(drill 0.2032)
		(layers "F.Cu" "B.Cu")
		(net "GND")
	)
	(via
		(at 400.824954 -306.824888)
		(size 0.4064)
		(drill 0.2032)
		(layers "F.Cu" "B.Cu")
		(net "GND")
	)
	(via
		(at 327.849992 -346.09913)
		(size 0.4572)
		(drill 0.254)
		(layers "F.Cu" "B.Cu")
		(net "GND")
	)
	(via
		(at 29.54782 -399.441924)
		(size 0.508)
		(drill 0.254)
		(layers "F.Cu" "B.Cu")
		(net "GND")
	)
	(via
		(at 132.47751 -208.516474)
		(size 0.508)
		(drill 0.254)
		(layers "F.Cu" "B.Cu")
		(net "GND")
	)
	(via
		(at 36.14801 -401.040092)
		(size 0.508)
		(drill 0.254)
		(layers "F.Cu" "B.Cu")
		(net "GND")
	)
	(via
		(at 415.074862 -285.924752)
		(size 0.4064)
		(drill 0.2032)
		(layers "F.Cu" "B.Cu")
		(net "GND")
	)
	(via
		(at 156.275024 -275.474938)
		(size 0.4064)
		(drill 0.2032)
		(layers "F.Cu" "B.Cu")
		(net "GND")
	)
	(via
		(at 252.45568 -85.205316)
		(size 0.508)
		(drill 0.254)
		(layers "F.Cu" "B.Cu")
		(net "GND")
	)
	(via
		(at 88.947752 -408.840178)
		(size 0.508)
		(drill 0.254)
		(layers "F.Cu" "B.Cu")
		(net "GND")
	)
	(via
		(at 334.494124 -224.386902)
		(size 0.4572)
		(drill 0.254)
		(layers "F.Cu" "B.Cu")
		(net "GND")
	)
	(via
		(at 165.774878 -305.874928)
		(size 0.4064)
		(drill 0.2032)
		(layers "F.Cu" "B.Cu")
		(net "GND")
	)
	(via
		(at 437.07812 -352.245422)
		(size 0.4572)
		(drill 0.254)
		(layers "F.Cu" "B.Cu")
		(net "GND")
	)
	(via
		(at 45.39996 -308.249828)
		(size 0.4064)
		(drill 0.2032)
		(layers "F.Cu" "B.Cu")
		(net "GND")
	)
	(via
		(at 434.327808 -404.838662)
		(size 0.508)
		(drill 0.254)
		(layers "F.Cu" "B.Cu")
		(net "GND")
	)
	(via
		(at 76.27493 -293.52494)
		(size 0.4064)
		(drill 0.2032)
		(layers "F.Cu" "B.Cu")
		(net "GND")
	)
	(via
		(at 351.374964 -289.41649)
		(size 0.508)
		(drill 0.254)
		(layers "F.Cu" "B.Cu")
		(net "GND")
	)
	(via
		(at 334.067912 -346.09913)
		(size 0.4572)
		(drill 0.254)
		(layers "F.Cu" "B.Cu")
		(net "GND")
	)
	(via
		(at 352.95332 -49.574704)
		(size 0.508)
		(drill 0.254)
		(layers "F.Cu" "B.Cu")
		(net "GND")
	)
	(via
		(at 389.899906 -298.74972)
		(size 0.4064)
		(drill 0.2032)
		(layers "F.Cu" "B.Cu")
		(net "GND")
	)
	(via
		(at 420.23919 -29.311854)
		(size 0.508)
		(drill 0.254)
		(layers "F.Cu" "B.Cu")
		(net "GND")
	)
	(via
		(at 303.724818 -292.574726)
		(size 0.4064)
		(drill 0.2032)
		(layers "F.Cu" "B.Cu")
		(net "GND")
	)
	(via
		(at 82.208116 -52.536852)
		(size 0.508)
		(drill 0.254)
		(layers "F.Cu" "B.Cu")
		(net "GND")
	)
	(via
		(at 309.899812 -318.699896)
		(size 0.4064)
		(drill 0.2032)
		(layers "F.Cu" "B.Cu")
		(net "GND")
	)
	(via
		(at 341.59952 -268.731492)
		(size 0.508)
		(drill 0.254)
		(layers "F.Cu" "B.Cu")
		(net "GND")
	)
	(via
		(at 389.644128 -341.805514)
		(size 0.4572)
		(drill 0.254)
		(layers "F.Cu" "B.Cu")
		(net "GND")
	)
	(via
		(at 425.99991 -313.949842)
		(size 0.4064)
		(drill 0.2032)
		(layers "F.Cu" "B.Cu")
		(net "GND")
	)
	(via
		(at 274.749768 -308.249828)
		(size 0.4064)
		(drill 0.2032)
		(layers "F.Cu" "B.Cu")
		(net "GND")
	)
	(via
		(at 117.210586 -291.32149)
		(size 0.508)
		(drill 0.254)
		(layers "F.Cu" "B.Cu")
		(net "GND")
	)
	(via
		(at 384.685032 -354.098098)
		(size 0.4572)
		(drill 0.254)
		(layers "F.Cu" "B.Cu")
		(net "GND")
	)
	(via
		(at 189.524894 -294.4749)
		(size 0.4064)
		(drill 0.2032)
		(layers "F.Cu" "B.Cu")
		(net "GND")
	)
	(via
		(at 366.06988 -288.14649)
		(size 0.508)
		(drill 0.254)
		(layers "F.Cu" "B.Cu")
		(net "GND")
	)
	(via
		(at 285.674816 -287.824926)
		(size 0.4064)
		(drill 0.2032)
		(layers "F.Cu" "B.Cu")
		(net "GND")
	)
	(via
		(at 422.398444 -37.201094)
		(size 0.508)
		(drill 0.254)
		(layers "F.Cu" "B.Cu")
		(net "GND")
	)
	(via
		(at 418.053012 -354.732082)
		(size 0.4064)
		(drill 0.2032)
		(layers "F.Cu" "B.Cu")
		(net "GND")
	)
	(via
		(at 429.010064 -349.219774)
		(size 0.4572)
		(drill 0.254)
		(layers "F.Cu" "B.Cu")
		(net "GND")
	)
	(via
		(at 163.247324 -347.951806)
		(size 0.4572)
		(drill 0.254)
		(layers "F.Cu" "B.Cu")
		(net "GND")
	)
	(via
		(at 256.371852 -352.703638)
		(size 0.508)
		(drill 0.254)
		(layers "F.Cu" "B.Cu")
		(net "GND")
	)
	(via
		(at 69.684138 -124.31649)
		(size 0.508)
		(drill 0.254)
		(layers "F.Cu" "B.Cu")
		(net "GND")
	)
	(via
		(at 385.624832 -278.324818)
		(size 0.4064)
		(drill 0.2032)
		(layers "F.Cu" "B.Cu")
		(net "GND")
	)
	(via
		(at 427.42485 -290.674806)
		(size 0.4064)
		(drill 0.2032)
		(layers "F.Cu" "B.Cu")
		(net "GND")
	)
	(via
		(at 153.780998 -25.990042)
		(size 0.508)
		(drill 0.254)
		(layers "F.Cu" "B.Cu")
		(net "GND")
	)
	(via
		(at 436.527702 -378.940314)
		(size 0.508)
		(drill 0.254)
		(layers "F.Cu" "B.Cu")
		(net "GND")
	)
	(via
		(at 42.15638 -349.219774)
		(size 0.4572)
		(drill 0.254)
		(layers "F.Cu" "B.Cu")
		(net "GND")
	)
	(via
		(at 189.049914 -274.999958)
		(size 0.4064)
		(drill 0.2032)
		(layers "F.Cu" "B.Cu")
		(net "GND")
	)
	(via
		(at 322.890896 -343.073482)
		(size 0.4572)
		(drill 0.254)
		(layers "F.Cu" "B.Cu")
		(net "GND")
	)
	(via
		(at 277.251668 -120.555004)
		(size 0.508)
		(drill 0.254)
		(layers "F.Cu" "B.Cu")
		(net "GND")
	)
	(via
		(at 292.57117 -346.09913)
		(size 0.4572)
		(drill 0.254)
		(layers "F.Cu" "B.Cu")
		(net "GND")
	)
	(via
		(at 418.927788 -403.738588)
		(size 0.508)
		(drill 0.254)
		(layers "F.Cu" "B.Cu")
		(net "GND")
	)
	(via
		(at 446.239138 -28.05303)
		(size 0.508)
		(drill 0.254)
		(layers "F.Cu" "B.Cu")
		(net "GND")
	)
	(via
		(at 161.9885 -349.219774)
		(size 0.4572)
		(drill 0.254)
		(layers "F.Cu" "B.Cu")
		(net "GND")
	)
	(via
		(at 168.952164 -106.045)
		(size 0.508)
		(drill 0.254)
		(layers "F.Cu" "B.Cu")
		(net "GND")
	)
	(via
		(at 376.83694 -348.58579)
		(size 0.4064)
		(drill 0.2032)
		(layers "F.Cu" "B.Cu")
		(net "GND")
	)
	(via
		(at 155.325064 -292.574726)
		(size 0.4064)
		(drill 0.2032)
		(layers "F.Cu" "B.Cu")
		(net "GND")
	)
	(via
		(at 222.154496 -308.892956)
		(size 0.508)
		(drill 0.254)
		(layers "F.Cu" "B.Cu")
		(net "GND")
	)
	(via
		(at 434.327808 -382.73863)
		(size 0.508)
		(drill 0.254)
		(layers "F.Cu" "B.Cu")
		(net "GND")
	)
	(via
		(at 273.002756 -74.624184)
		(size 0.508)
		(drill 0.254)
		(layers "F.Cu" "B.Cu")
		(net "GND")
	)
	(via
		(at 398.925034 -302.074834)
		(size 0.4064)
		(drill 0.2032)
		(layers "F.Cu" "B.Cu")
		(net "GND")
	)
	(via
		(at 132.81406 -279.086818)
		(size 0.508)
		(drill 0.254)
		(layers "F.Cu" "B.Cu")
		(net "GND")
	)
	(via
		(at 406.049988 -316.799722)
		(size 0.4064)
		(drill 0.2032)
		(layers "F.Cu" "B.Cu")
		(net "GND")
	)
	(via
		(at 416.974782 -284.974792)
		(size 0.4064)
		(drill 0.2032)
		(layers "F.Cu" "B.Cu")
		(net "GND")
	)
	(via
		(at 374.3706 -110.0074)
		(size 0.508)
		(drill 0.254)
		(layers "F.Cu" "B.Cu")
		(net "GND")
	)
	(via
		(at 357.948992 -29.589984)
		(size 0.508)
		(drill 0.254)
		(layers "F.Cu" "B.Cu")
		(net "GND")
	)
	(via
		(at 159.124904 -272.624804)
		(size 0.4064)
		(drill 0.2032)
		(layers "F.Cu" "B.Cu")
		(net "GND")
	)
	(via
		(at 170.806364 -98.844862)
		(size 0.508)
		(drill 0.254)
		(layers "F.Cu" "B.Cu")
		(net "GND")
	)
	(via
		(at 180.975 -293.52494)
		(size 0.4064)
		(drill 0.2032)
		(layers "F.Cu" "B.Cu")
		(net "GND")
	)
	(via
		(at 162.449764 -272.14957)
		(size 0.4064)
		(drill 0.2032)
		(layers "F.Cu" "B.Cu")
		(net "GND")
	)
	(via
		(at 275.224748 -277.374858)
		(size 0.4064)
		(drill 0.2032)
		(layers "F.Cu" "B.Cu")
		(net "GND")
	)
	(via
		(at 165.947852 -408.738578)
		(size 0.508)
		(drill 0.254)
		(layers "F.Cu" "B.Cu")
		(net "GND")
	)
	(via
		(at 365.628428 -332.311248)
		(size 0.508)
		(drill 0.254)
		(layers "F.Cu" "B.Cu")
		(net "GND")
	)
	(via
		(at 388.474966 -284.024832)
		(size 0.4064)
		(drill 0.2032)
		(layers "F.Cu" "B.Cu")
		(net "GND")
	)
	(via
		(at 122.900186 -38.315138)
		(size 0.508)
		(drill 0.254)
		(layers "F.Cu" "B.Cu")
		(net "GND")
	)
	(via
		(at 280.745692 -153.0096)
		(size 0.508)
		(drill 0.254)
		(layers "F.Cu" "B.Cu")
		(net "GND")
	)
	(via
		(at 394.38326 -354.732082)
		(size 0.4064)
		(drill 0.2032)
		(layers "F.Cu" "B.Cu")
		(net "GND")
	)
	(via
		(at 182.87492 -296.37482)
		(size 0.4064)
		(drill 0.2032)
		(layers "F.Cu" "B.Cu")
		(net "GND")
	)
	(via
		(at 364.36808 -285.953454)
		(size 0.508)
		(drill 0.254)
		(layers "F.Cu" "B.Cu")
		(net "GND")
	)
	(via
		(at 188.366908 -131.245102)
		(size 0.508)
		(drill 0.254)
		(layers "F.Cu" "B.Cu")
		(net "GND")
	)
	(via
		(at 341.927942 -380.040134)
		(size 0.508)
		(drill 0.254)
		(layers "F.Cu" "B.Cu")
		(net "GND")
	)
	(via
		(at 122.2502 -358.391714)
		(size 0.4572)
		(drill 0.254)
		(layers "F.Cu" "B.Cu")
		(net "GND")
	)
	(via
		(at 317.008256 -156.283406)
		(size 0.508)
		(drill 0.254)
		(layers "F.Cu" "B.Cu")
		(net "GND")
	)
	(via
		(at 445.798448 -65.15989)
		(size 0.508)
		(drill 0.254)
		(layers "F.Cu" "B.Cu")
		(net "GND")
	)
	(via
		(at 130.74777 -380.040134)
		(size 0.4572)
		(drill 0.254)
		(layers "F.Cu" "B.Cu")
		(net "GND")
	)
	(via
		(at 306.099718 -312.999882)
		(size 0.4064)
		(drill 0.2032)
		(layers "F.Cu" "B.Cu")
		(net "GND")
	)
	(via
		(at 278.656542 -342.439498)
		(size 0.4064)
		(drill 0.2032)
		(layers "F.Cu" "B.Cu")
		(net "GND")
	)
	(via
		(at 58.224928 -285.924752)
		(size 0.4064)
		(drill 0.2032)
		(layers "F.Cu" "B.Cu")
		(net "GND")
	)
	(via
		(at 15.455646 -210.011772)
		(size 0.508)
		(drill 0.254)
		(layers "F.Cu" "B.Cu")
		(net "GND")
	)
	(via
		(at 302.327818 -398.24025)
		(size 0.508)
		(drill 0.254)
		(layers "F.Cu" "B.Cu")
		(net "GND")
	)
	(via
		(at 130.74777 -374.938544)
		(size 0.508)
		(drill 0.254)
		(layers "F.Cu" "B.Cu")
		(net "GND")
	)
	(via
		(at 466.835998 -252.283976)
		(size 0.508)
		(drill 0.254)
		(layers "F.Cu" "B.Cu")
		(net "GND")
	)
	(via
		(at 191.227964 -343.073482)
		(size 0.4572)
		(drill 0.254)
		(layers "F.Cu" "B.Cu")
		(net "GND")
	)
	(via
		(at 84.808314 -125.163326)
		(size 0.508)
		(drill 0.254)
		(layers "F.Cu" "B.Cu")
		(net "GND")
	)
	(via
		(at 427.379892 -348.58579)
		(size 0.4064)
		(drill 0.2032)
		(layers "F.Cu" "B.Cu")
		(net "GND")
	)
	(via
		(at 68.651374 -349.219774)
		(size 0.4572)
		(drill 0.254)
		(layers "F.Cu" "B.Cu")
		(net "GND")
	)
	(via
		(at 247.499124 -133.173216)
		(size 0.508)
		(drill 0.254)
		(layers "F.Cu" "B.Cu")
		(net "GND")
	)
	(via
		(at 398.925034 -293.52494)
		(size 0.4064)
		(drill 0.2032)
		(layers "F.Cu" "B.Cu")
		(net "GND")
	)
	(via
		(at 185.725054 -285.924752)
		(size 0.4064)
		(drill 0.2032)
		(layers "F.Cu" "B.Cu")
		(net "GND")
	)
	(via
		(at 424.57497 -302.074834)
		(size 0.4064)
		(drill 0.2032)
		(layers "F.Cu" "B.Cu")
		(net "GND")
	)
	(via
		(at 117.210586 -290.05149)
		(size 0.508)
		(drill 0.254)
		(layers "F.Cu" "B.Cu")
		(net "GND")
	)
	(via
		(at 384.059684 -119.026686)
		(size 0.508)
		(drill 0.254)
		(layers "F.Cu" "B.Cu")
		(net "GND")
	)
	(via
		(at 78.649576 -276.899878)
		(size 0.4064)
		(drill 0.2032)
		(layers "F.Cu" "B.Cu")
		(net "GND")
	)
	(via
		(at 36.374832 -292.57498)
		(size 0.4064)
		(drill 0.2032)
		(layers "F.Cu" "B.Cu")
		(net "GND")
	)
	(via
		(at 121.947686 -398.24025)
		(size 0.4572)
		(drill 0.254)
		(layers "F.Cu" "B.Cu")
		(net "GND")
	)
	(via
		(at 333.524606 -278.708612)
		(size 0.508)
		(drill 0.254)
		(layers "F.Cu" "B.Cu")
		(net "GND")
	)
	(via
		(at 77.978254 -355.366066)
		(size 0.4572)
		(drill 0.254)
		(layers "F.Cu" "B.Cu")
		(net "GND")
	)
	(via
		(at 4.562856 -225.881692)
		(size 0.508)
		(drill 0.254)
		(layers "F.Cu" "B.Cu")
		(net "GND")
	)
	(via
		(at 168.952164 -100.64496)
		(size 0.508)
		(drill 0.254)
		(layers "F.Cu" "B.Cu")
		(net "GND")
	)
	(via
		(at 280.781252 -33.459674)
		(size 0.508)
		(drill 0.254)
		(layers "F.Cu" "B.Cu")
		(net "GND")
	)
	(via
		(at 65.824862 -305.874928)
		(size 0.4064)
		(drill 0.2032)
		(layers "F.Cu" "B.Cu")
		(net "GND")
	)
	(via
		(at 346.327984 -374.938544)
		(size 0.508)
		(drill 0.254)
		(layers "F.Cu" "B.Cu")
		(net "GND")
	)
	(via
		(at 250.384564 -72.56526)
		(size 0.508)
		(drill 0.254)
		(layers "F.Cu" "B.Cu")
		(net "GND")
	)
	(via
		(at 430.8602 -354.098098)
		(size 0.4572)
		(drill 0.254)
		(layers "F.Cu" "B.Cu")
		(net "GND")
	)
	(via
		(at 127.209296 -354.098098)
		(size 0.4572)
		(drill 0.254)
		(layers "F.Cu" "B.Cu")
		(net "GND")
	)
	(via
		(at 403.199854 -317.749936)
		(size 0.4064)
		(drill 0.2032)
		(layers "F.Cu" "B.Cu")
		(net "GND")
	)
	(via
		(at 48.24984 -275.949918)
		(size 0.4064)
		(drill 0.2032)
		(layers "F.Cu" "B.Cu")
		(net "GND")
	)
	(via
		(at 79.82839 -357.123746)
		(size 0.4572)
		(drill 0.254)
		(layers "F.Cu" "B.Cu")
		(net "GND")
	)
	(via
		(at 156.750004 -307.299868)
		(size 0.4064)
		(drill 0.2032)
		(layers "F.Cu" "B.Cu")
		(net "GND")
	)
	(via
		(at 394.011912 -358.391714)
		(size 0.4572)
		(drill 0.254)
		(layers "F.Cu" "B.Cu")
		(net "GND")
	)
	(via
		(at 272.374868 -276.424898)
		(size 0.4064)
		(drill 0.2032)
		(layers "F.Cu" "B.Cu")
		(net "GND")
	)
	(via
		(at 134.771384 -32.911796)
		(size 0.508)
		(drill 0.254)
		(layers "F.Cu" "B.Cu")
		(net "GND")
	)
	(via
		(at 283.833062 -113.245138)
		(size 0.508)
		(drill 0.254)
		(layers "F.Cu" "B.Cu")
		(net "GND")
	)
	(via
		(at 183.379872 -357.733854)
		(size 0.4064)
		(drill 0.2032)
		(layers "F.Cu" "B.Cu")
		(net "GND")
	)
	(via
		(at 161.54781 -378.83846)
		(size 0.508)
		(drill 0.254)
		(layers "F.Cu" "B.Cu")
		(net "GND")
	)
	(via
		(at 93.596714 -207.033368)
		(size 0.508)
		(drill 0.254)
		(layers "F.Cu" "B.Cu")
		(net "GND")
	)
	(via
		(at 386.356098 -33.19018)
		(size 0.508)
		(drill 0.254)
		(layers "F.Cu" "B.Cu")
		(net "GND")
	)
	(via
		(at 330.224638 -216.203022)
		(size 0.508)
		(drill 0.254)
		(layers "F.Cu" "B.Cu")
		(net "GND")
	)
	(via
		(at 181.44998 -274.999958)
		(size 0.4064)
		(drill 0.2032)
		(layers "F.Cu" "B.Cu")
		(net "GND")
	)
	(via
		(at 399.19275 -84.721446)
		(size 0.508)
		(drill 0.254)
		(layers "F.Cu" "B.Cu")
		(net "GND")
	)
	(via
		(at 317.046864 -1.135126)
		(size 0.508)
		(drill 0.254)
		(layers "F.Cu" "B.Cu")
		(net "GND")
	)
	(via
		(at 16.320008 -131.312666)
		(size 0.508)
		(drill 0.254)
		(layers "F.Cu" "B.Cu")
		(net "GND")
	)
	(via
		(at 401.299934 -317.749936)
		(size 0.4064)
		(drill 0.2032)
		(layers "F.Cu" "B.Cu")
		(net "GND")
	)
	(via
		(at 337.523074 -55.083456)
		(size 0.508)
		(drill 0.254)
		(layers "F.Cu" "B.Cu")
		(net "GND")
	)
	(via
		(at 120.991376 -357.123746)
		(size 0.4572)
		(drill 0.254)
		(layers "F.Cu" "B.Cu")
		(net "GND")
	)
	(via
		(at 179.07508 -289.724846)
		(size 0.4064)
		(drill 0.2032)
		(layers "F.Cu" "B.Cu")
		(net "GND")
	)
	(via
		(at 93.894402 -345.465146)
		(size 0.4064)
		(drill 0.2032)
		(layers "F.Cu" "B.Cu")
		(net "GND")
	)
	(via
		(at 97.939098 -31.652972)
		(size 0.508)
		(drill 0.254)
		(layers "F.Cu" "B.Cu")
		(net "GND")
	)
	(via
		(at 146.308318 -52.536852)
		(size 0.508)
		(drill 0.254)
		(layers "F.Cu" "B.Cu")
		(net "GND")
	)
	(via
		(at 386.575046 -284.974792)
		(size 0.4064)
		(drill 0.2032)
		(layers "F.Cu" "B.Cu")
		(net "GND")
	)
	(via
		(at 213.136988 -238.67237)
		(size 0.508)
		(drill 0.254)
		(layers "F.Cu" "B.Cu")
		(net "GND")
	)
	(via
		(at 203.748894 -34.990024)
		(size 0.508)
		(drill 0.254)
		(layers "F.Cu" "B.Cu")
		(net "GND")
	)
	(via
		(at 281.874722 -304.924714)
		(size 0.4064)
		(drill 0.2032)
		(layers "F.Cu" "B.Cu")
		(net "GND")
	)
	(via
		(at 34.491676 -120.28551)
		(size 0.508)
		(drill 0.254)
		(layers "F.Cu" "B.Cu")
		(net "GND")
	)
	(via
		(at 393.351766 -104.244902)
		(size 0.508)
		(drill 0.254)
		(layers "F.Cu" "B.Cu")
		(net "GND")
	)
	(via
		(at 181.912514 -145.755106)
		(size 0.508)
		(drill 0.254)
		(layers "F.Cu" "B.Cu")
		(net "GND")
	)
	(via
		(at 320.863468 -386.958332)
		(size 0.508)
		(drill 0.254)
		(layers "F.Cu" "B.Cu")
		(net "GND")
	)
	(via
		(at 174.747936 -373.441976)
		(size 0.508)
		(drill 0.254)
		(layers "F.Cu" "B.Cu")
		(net "GND")
	)
	(via
		(at 172.945552 -351.611438)
		(size 0.4064)
		(drill 0.2032)
		(layers "F.Cu" "B.Cu")
		(net "GND")
	)
	(via
		(at 277.874476 -94.996762)
		(size 0.508)
		(drill 0.254)
		(layers "F.Cu" "B.Cu")
		(net "GND")
	)
	(via
		(at 300.874684 -301.124874)
		(size 0.4064)
		(drill 0.2032)
		(layers "F.Cu" "B.Cu")
		(net "GND")
	)
	(via
		(at 421.61333 -34.718498)
		(size 0.508)
		(drill 0.254)
		(layers "F.Cu" "B.Cu")
		(net "GND")
	)
	(via
		(at 276.655022 -348.58579)
		(size 0.4064)
		(drill 0.2032)
		(layers "F.Cu" "B.Cu")
		(net "GND")
	)
	(via
		(at 419.557962 -73.85177)
		(size 0.508)
		(drill 0.254)
		(layers "F.Cu" "B.Cu")
		(net "GND")
	)
	(via
		(at 189.049914 -279.749758)
		(size 0.4064)
		(drill 0.2032)
		(layers "F.Cu" "B.Cu")
		(net "GND")
	)
	(via
		(at 390.327896 -399.441924)
		(size 0.508)
		(drill 0.254)
		(layers "F.Cu" "B.Cu")
		(net "GND")
	)
	(via
		(at 165.529514 -47.020734)
		(size 0.508)
		(drill 0.254)
		(layers "F.Cu" "B.Cu")
		(net "GND")
	)
	(via
		(at 111.987584 -333.086964)
		(size 0.508)
		(drill 0.254)
		(layers "F.Cu" "B.Cu")
		(net "GND")
	)
	(via
		(at 379.949964 -27.04973)
		(size 0.508)
		(drill 0.254)
		(layers "F.Cu" "B.Cu")
		(net "GND")
	)
	(via
		(at 40.132 -13.613638)
		(size 0.508)
		(drill 0.254)
		(layers "F.Cu" "B.Cu")
		(net "GND")
	)
	(via
		(at 390.58088 -31.390082)
		(size 0.508)
		(drill 0.254)
		(layers "F.Cu" "B.Cu")
		(net "GND")
	)
	(via
		(at 381.527812 -406.040336)
		(size 0.508)
		(drill 0.254)
		(layers "F.Cu" "B.Cu")
		(net "GND")
	)
	(via
		(at 21.872448 -357.75773)
		(size 0.4064)
		(drill 0.2032)
		(layers "F.Cu" "B.Cu")
		(net "GND")
	)
	(via
		(at 277.268178 -48.753014)
		(size 0.508)
		(drill 0.254)
		(layers "F.Cu" "B.Cu")
		(net "GND")
	)
	(via
		(at 410.324808 -303.974754)
		(size 0.4064)
		(drill 0.2032)
		(layers "F.Cu" "B.Cu")
		(net "GND")
	)
	(via
		(at 285.674816 -306.824888)
		(size 0.4064)
		(drill 0.2032)
		(layers "F.Cu" "B.Cu")
		(net "GND")
	)
	(via
		(at 40.526208 -345.465146)
		(size 0.4064)
		(drill 0.2032)
		(layers "F.Cu" "B.Cu")
		(net "GND")
	)
	(via
		(at 126.837948 -345.465146)
		(size 0.4064)
		(drill 0.2032)
		(layers "F.Cu" "B.Cu")
		(net "GND")
	)
	(via
		(at 291.84981 -275.949918)
		(size 0.4064)
		(drill 0.2032)
		(layers "F.Cu" "B.Cu")
		(net "GND")
	)
	(via
		(at 259.52323 -51.019456)
		(size 0.508)
		(drill 0.254)
		(layers "F.Cu" "B.Cu")
		(net "GND")
	)
	(via
		(at 128.46812 -344.831162)
		(size 0.4572)
		(drill 0.254)
		(layers "F.Cu" "B.Cu")
		(net "GND")
	)
	(via
		(at 160.138364 -355.366066)
		(size 0.4572)
		(drill 0.254)
		(layers "F.Cu" "B.Cu")
		(net "GND")
	)
	(via
		(at 306.099718 -314.899802)
		(size 0.4064)
		(drill 0.2032)
		(layers "F.Cu" "B.Cu")
		(net "GND")
	)
	(via
		(at 199.749918 -27.04973)
		(size 0.508)
		(drill 0.254)
		(layers "F.Cu" "B.Cu")
		(net "GND")
	)
	(via
		(at 424.64228 -358.391714)
		(size 0.4572)
		(drill 0.254)
		(layers "F.Cu" "B.Cu")
		(net "GND")
	)
	(via
		(at 73.547732 -382.73863)
		(size 0.508)
		(drill 0.254)
		(layers "F.Cu" "B.Cu")
		(net "GND")
	)
	(via
		(at 402.249894 -274.999958)
		(size 0.4064)
		(drill 0.2032)
		(layers "F.Cu" "B.Cu")
		(net "GND")
	)
	(via
		(at 103.205026 -305.91887)
		(size 0.508)
		(drill 0.254)
		(layers "F.Cu" "B.Cu")
		(net "GND")
	)
	(via
		(at 11.74496 -29.589984)
		(size 0.508)
		(drill 0.254)
		(layers "F.Cu" "B.Cu")
		(net "GND")
	)
	(via
		(at 33.8201 -31.390336)
		(size 0.508)
		(drill 0.254)
		(layers "F.Cu" "B.Cu")
		(net "GND")
	)
	(via
		(at 353.99853 -307.82387)
		(size 0.508)
		(drill 0.254)
		(layers "F.Cu" "B.Cu")
		(net "GND")
	)
	(via
		(at 427.727872 -376.241818)
		(size 0.508)
		(drill 0.254)
		(layers "F.Cu" "B.Cu")
		(net "GND")
	)
	(via
		(at 44.731178 -11.372342)
		(size 0.508)
		(drill 0.254)
		(layers "F.Cu" "B.Cu")
		(net "GND")
	)
	(via
		(at 155.325064 -283.074872)
		(size 0.4064)
		(drill 0.2032)
		(layers "F.Cu" "B.Cu")
		(net "GND")
	)
	(via
		(at 77.947774 -407.24201)
		(size 0.508)
		(drill 0.254)
		(layers "F.Cu" "B.Cu")
		(net "GND")
	)
	(via
		(at 98.473768 -200.674224)
		(size 0.508)
		(drill 0.254)
		(layers "F.Cu" "B.Cu")
		(net "GND")
	)
	(via
		(at 286.927798 -380.141734)
		(size 0.508)
		(drill 0.254)
		(layers "F.Cu" "B.Cu")
		(net "GND")
	)
	(via
		(at 19.223736 -153.782522)
		(size 0.508)
		(drill 0.254)
		(layers "F.Cu" "B.Cu")
		(net "GND")
	)
	(via
		(at 230.30434 -244.457982)
		(size 0.508)
		(drill 0.254)
		(layers "F.Cu" "B.Cu")
		(net "GND")
	)
	(via
		(at 116.03228 -347.92793)
		(size 0.4572)
		(drill 0.254)
		(layers "F.Cu" "B.Cu")
		(net "GND")
	)
	(via
		(at 302.774858 -288.774886)
		(size 0.4064)
		(drill 0.2032)
		(layers "F.Cu" "B.Cu")
		(net "GND")
	)
	(via
		(at 418.927788 -382.84023)
		(size 0.508)
		(drill 0.254)
		(layers "F.Cu" "B.Cu")
		(net "GND")
	)
	(via
		(at 398.59966 -348.58579)
		(size 0.4064)
		(drill 0.2032)
		(layers "F.Cu" "B.Cu")
		(net "GND")
	)
	(via
		(at 353.141788 -269.366492)
		(size 0.508)
		(drill 0.254)
		(layers "F.Cu" "B.Cu")
		(net "GND")
	)
	(via
		(at 395.4907 -345.465146)
		(size 0.4064)
		(drill 0.2032)
		(layers "F.Cu" "B.Cu")
		(net "GND")
	)
	(via
		(at 310.849518 -274.999958)
		(size 0.4064)
		(drill 0.2032)
		(layers "F.Cu" "B.Cu")
		(net "GND")
	)
	(via
		(at 412.89351 -145.755106)
		(size 0.508)
		(drill 0.254)
		(layers "F.Cu" "B.Cu")
		(net "GND")
	)
	(via
		(at 93.523054 -355.366066)
		(size 0.4572)
		(drill 0.254)
		(layers "F.Cu" "B.Cu")
		(net "GND")
	)
	(via
		(at 206.110078 -416.508438)
		(size 0.508)
		(drill 0.254)
		(layers "F.Cu" "B.Cu")
		(net "GND")
	)
	(via
		(at 339.54847 -286.842454)
		(size 0.508)
		(drill 0.254)
		(layers "F.Cu" "B.Cu")
		(net "GND")
	)
	(via
		(at 343.394792 -349.219774)
		(size 0.4572)
		(drill 0.254)
		(layers "F.Cu" "B.Cu")
		(net "GND")
	)
	(via
		(at 43.024806 -284.974792)
		(size 0.4064)
		(drill 0.2032)
		(layers "F.Cu" "B.Cu")
		(net "GND")
	)
	(via
		(at 417.78555 -63.218314)
		(size 0.508)
		(drill 0.254)
		(layers "F.Cu" "B.Cu")
		(net "GND")
	)
	(via
		(at 310.849772 -284.499812)
		(size 0.4064)
		(drill 0.2032)
		(layers "F.Cu" "B.Cu")
		(net "GND")
	)
	(via
		(at 43.499786 -303.499774)
		(size 0.4064)
		(drill 0.2032)
		(layers "F.Cu" "B.Cu")
		(net "GND")
	)
	(via
		(at 409.351988 -13.613638)
		(size 0.508)
		(drill 0.254)
		(layers "F.Cu" "B.Cu")
		(net "GND")
	)
	(via
		(at 289.090862 -357.75773)
		(size 0.4064)
		(drill 0.2032)
		(layers "F.Cu" "B.Cu")
		(net "GND")
	)
	(via
		(at 51.574954 -306.824888)
		(size 0.4064)
		(drill 0.2032)
		(layers "F.Cu" "B.Cu")
		(net "GND")
	)
	(via
		(at 171.474892 -297.32478)
		(size 0.4064)
		(drill 0.2032)
		(layers "F.Cu" "B.Cu")
		(net "GND")
	)
	(via
		(at 336.785458 -120.526302)
		(size 0.508)
		(drill 0.254)
		(layers "F.Cu" "B.Cu")
		(net "GND")
	)
	(via
		(at 89.798144 -21.077936)
		(size 0.508)
		(drill 0.254)
		(layers "F.Cu" "B.Cu")
		(net "GND")
	)
	(via
		(at 374.099328 -354.074222)
		(size 0.4572)
		(drill 0.254)
		(layers "F.Cu" "B.Cu")
		(net "GND")
	)
	(via
		(at 28.461716 -347.951806)
		(size 0.4572)
		(drill 0.254)
		(layers "F.Cu" "B.Cu")
		(net "GND")
	)
	(via
		(at 118.485666 -34.183066)
		(size 0.508)
		(drill 0.254)
		(layers "F.Cu" "B.Cu")
		(net "GND")
	)
	(via
		(at 423.32783 -381.638556)
		(size 0.508)
		(drill 0.254)
		(layers "F.Cu" "B.Cu")
		(net "GND")
	)
	(via
		(at 167.200072 -314.899802)
		(size 0.4064)
		(drill 0.2032)
		(layers "F.Cu" "B.Cu")
		(net "GND")
	)
	(via
		(at 78.64983 -308.249828)
		(size 0.4064)
		(drill 0.2032)
		(layers "F.Cu" "B.Cu")
		(net "GND")
	)
	(via
		(at 172.900086 -314.899802)
		(size 0.4064)
		(drill 0.2032)
		(layers "F.Cu" "B.Cu")
		(net "GND")
	)
	(via
		(at 164.349938 -275.949918)
		(size 0.4064)
		(drill 0.2032)
		(layers "F.Cu" "B.Cu")
		(net "GND")
	)
	(via
		(at 227.734368 -92.041726)
		(size 0.508)
		(drill 0.254)
		(layers "F.Cu" "B.Cu")
		(net "GND")
	)
	(via
		(at 255.524 -26.319734)
		(size 0.508)
		(drill 0.254)
		(layers "F.Cu" "B.Cu")
		(net "GND")
	)
	(via
		(at 37.417248 -351.611438)
		(size 0.4064)
		(drill 0.2032)
		(layers "F.Cu" "B.Cu")
		(net "GND")
	)
	(via
		(at 429.010064 -357.123746)
		(size 0.4572)
		(drill 0.254)
		(layers "F.Cu" "B.Cu")
		(net "GND")
	)
	(via
		(at 132.167884 -286.842454)
		(size 0.508)
		(drill 0.254)
		(layers "F.Cu" "B.Cu")
		(net "GND")
	)
	(via
		(at 257.895852 -352.703638)
		(size 0.508)
		(drill 0.254)
		(layers "F.Cu" "B.Cu")
		(net "GND")
	)
	(via
		(at 163.618672 -348.58579)
		(size 0.4064)
		(drill 0.2032)
		(layers "F.Cu" "B.Cu")
		(net "GND")
	)
	(via
		(at 388.949946 -312.049922)
		(size 0.4064)
		(drill 0.2032)
		(layers "F.Cu" "B.Cu")
		(net "GND")
	)
	(via
		(at 343.394792 -344.831162)
		(size 0.4572)
		(drill 0.254)
		(layers "F.Cu" "B.Cu")
		(net "GND")
	)
	(via
		(at 179.07508 -306.824888)
		(size 0.4064)
		(drill 0.2032)
		(layers "F.Cu" "B.Cu")
		(net "GND")
	)
	(via
		(at 28.341828 -25.971246)
		(size 0.508)
		(drill 0.254)
		(layers "F.Cu" "B.Cu")
		(net "GND")
	)
	(via
		(at 385.05638 -357.75773)
		(size 0.4064)
		(drill 0.2032)
		(layers "F.Cu" "B.Cu")
		(net "GND")
	)
	(via
		(at 93.523054 -344.831162)
		(size 0.4572)
		(drill 0.254)
		(layers "F.Cu" "B.Cu")
		(net "GND")
	)
	(via
		(at 384.059684 -133.836664)
		(size 0.508)
		(drill 0.254)
		(layers "F.Cu" "B.Cu")
		(net "GND")
	)
	(via
		(at 27.347926 -377.738386)
		(size 0.508)
		(drill 0.254)
		(layers "F.Cu" "B.Cu")
		(net "GND")
	)
	(via
		(at 332.217776 -357.123746)
		(size 0.4572)
		(drill 0.254)
		(layers "F.Cu" "B.Cu")
		(net "GND")
	)
	(via
		(at 117.882416 -346.09913)
		(size 0.4572)
		(drill 0.254)
		(layers "F.Cu" "B.Cu")
		(net "GND")
	)
	(via
		(at 410.356304 -343.073482)
		(size 0.4572)
		(drill 0.254)
		(layers "F.Cu" "B.Cu")
		(net "GND")
	)
	(via
		(at 1.787144 -68.166234)
		(size 0.508)
		(drill 0.254)
		(layers "F.Cu" "B.Cu")
		(net "GND")
	)
	(via
		(at 126.169166 -141.019276)
		(size 0.508)
		(drill 0.254)
		(layers "F.Cu" "B.Cu")
		(net "GND")
	)
	(via
		(at 188.12256 -403.06879)
		(size 0.508)
		(drill 0.254)
		(layers "F.Cu" "B.Cu")
		(net "GND")
	)
	(via
		(at 400.349974 -310.149748)
		(size 0.4064)
		(drill 0.2032)
		(layers "F.Cu" "B.Cu")
		(net "GND")
	)
	(via
		(at 334.628998 -292.781736)
		(size 0.508)
		(drill 0.254)
		(layers "F.Cu" "B.Cu")
		(net "GND")
	)
	(via
		(at 20.48764 -26.360882)
		(size 0.508)
		(drill 0.254)
		(layers "F.Cu" "B.Cu")
		(net "GND")
	)
	(via
		(at 395.862048 -341.805514)
		(size 0.4572)
		(drill 0.254)
		(layers "F.Cu" "B.Cu")
		(net "GND")
	)
	(via
		(at 48.3743 -354.074222)
		(size 0.4572)
		(drill 0.254)
		(layers "F.Cu" "B.Cu")
		(net "GND")
	)
	(via
		(at 56.324754 -298.27474)
		(size 0.4064)
		(drill 0.2032)
		(layers "F.Cu" "B.Cu")
		(net "GND")
	)
	(via
		(at 405.575008 -302.074834)
		(size 0.4064)
		(drill 0.2032)
		(layers "F.Cu" "B.Cu")
		(net "GND")
	)
	(via
		(at 155.800044 -302.549814)
		(size 0.4064)
		(drill 0.2032)
		(layers "F.Cu" "B.Cu")
		(net "GND")
	)
	(via
		(at 370.959888 -225.04019)
		(size 0.508)
		(drill 0.254)
		(layers "F.Cu" "B.Cu")
		(net "GND")
	)
	(via
		(at 56.799988 -277.849838)
		(size 0.4064)
		(drill 0.2032)
		(layers "F.Cu" "B.Cu")
		(net "GND")
	)
	(via
		(at 326.757792 -58.156094)
		(size 0.508)
		(drill 0.254)
		(layers "F.Cu" "B.Cu")
		(net "GND")
	)
	(via
		(at 401.78736 -131.76504)
		(size 0.508)
		(drill 0.254)
		(layers "F.Cu" "B.Cu")
		(net "GND")
	)
	(via
		(at 235.495084 -336.204814)
		(size 0.508)
		(drill 0.254)
		(layers "F.Cu" "B.Cu")
		(net "GND")
	)
	(via
		(at 43.499786 -317.749936)
		(size 0.4064)
		(drill 0.2032)
		(layers "F.Cu" "B.Cu")
		(net "GND")
	)
	(via
		(at 160.549844 -275.949918)
		(size 0.4064)
		(drill 0.2032)
		(layers "F.Cu" "B.Cu")
		(net "GND")
	)
	(via
		(at 252.961902 -162.3187)
		(size 0.508)
		(drill 0.254)
		(layers "F.Cu" "B.Cu")
		(net "GND")
	)
	(via
		(at 276.649688 -305.399948)
		(size 0.4064)
		(drill 0.2032)
		(layers "F.Cu" "B.Cu")
		(net "GND")
	)
	(via
		(at 177.5333 -352.245422)
		(size 0.4572)
		(drill 0.254)
		(layers "F.Cu" "B.Cu")
		(net "GND")
	)
	(via
		(at 131.27863 -110.365032)
		(size 0.508)
		(drill 0.254)
		(layers "F.Cu" "B.Cu")
		(net "GND")
	)
	(via
		(at 36.14801 -398.34185)
		(size 0.508)
		(drill 0.254)
		(layers "F.Cu" "B.Cu")
		(net "GND")
	)
	(via
		(at 73.899776 -286.399732)
		(size 0.4064)
		(drill 0.2032)
		(layers "F.Cu" "B.Cu")
		(net "GND")
	)
	(via
		(at 284.874462 -351.611438)
		(size 0.4064)
		(drill 0.2032)
		(layers "F.Cu" "B.Cu")
		(net "GND")
	)
	(via
		(at 408.899868 -312.999882)
		(size 0.4064)
		(drill 0.2032)
		(layers "F.Cu" "B.Cu")
		(net "GND")
	)
	(via
		(at 56.324754 -302.074834)
		(size 0.4064)
		(drill 0.2032)
		(layers "F.Cu" "B.Cu")
		(net "GND")
	)
	(via
		(at 230.377746 -149.421596)
		(size 0.508)
		(drill 0.254)
		(layers "F.Cu" "B.Cu")
		(net "GND")
	)
	(via
		(at 384.059684 -122.626628)
		(size 0.508)
		(drill 0.254)
		(layers "F.Cu" "B.Cu")
		(net "GND")
	)
	(via
		(at 275.224748 -289.724846)
		(size 0.4064)
		(drill 0.2032)
		(layers "F.Cu" "B.Cu")
		(net "GND")
	)
	(via
		(at 364.858046 -57.521094)
		(size 0.508)
		(drill 0.254)
		(layers "F.Cu" "B.Cu")
		(net "GND")
	)
	(via
		(at 270.474694 -300.174914)
		(size 0.4064)
		(drill 0.2032)
		(layers "F.Cu" "B.Cu")
		(net "GND")
	)
	(via
		(at 126.169166 -145.083276)
		(size 0.508)
		(drill 0.254)
		(layers "F.Cu" "B.Cu")
		(net "GND")
	)
	(via
		(at 124.100336 -346.09913)
		(size 0.4572)
		(drill 0.254)
		(layers "F.Cu" "B.Cu")
		(net "GND")
	)
	(via
		(at 72.267064 -142.15491)
		(size 0.508)
		(drill 0.254)
		(layers "F.Cu" "B.Cu")
		(net "GND")
	)
	(via
		(at 377.71705 -233.91495)
		(size 0.508)
		(drill 0.254)
		(layers "F.Cu" "B.Cu")
		(net "GND")
	)
	(via
		(at 270.949928 -304.449734)
		(size 0.4064)
		(drill 0.2032)
		(layers "F.Cu" "B.Cu")
		(net "GND")
	)
	(via
		(at 334.494124 -213.98738)
		(size 0.4572)
		(drill 0.254)
		(layers "F.Cu" "B.Cu")
		(net "GND")
	)
	(via
		(at 397.97482 -303.024794)
		(size 0.4064)
		(drill 0.2032)
		(layers "F.Cu" "B.Cu")
		(net "GND")
	)
	(via
		(at 51.854608 -342.439498)
		(size 0.4064)
		(drill 0.2032)
		(layers "F.Cu" "B.Cu")
		(net "GND")
	)
	(via
		(at 128.839468 -357.75773)
		(size 0.4064)
		(drill 0.2032)
		(layers "F.Cu" "B.Cu")
		(net "GND")
	)
	(via
		(at 174.325026 -298.27474)
		(size 0.4064)
		(drill 0.2032)
		(layers "F.Cu" "B.Cu")
		(net "GND")
	)
	(via
		(at 396.398496 -37.201094)
		(size 0.508)
		(drill 0.254)
		(layers "F.Cu" "B.Cu")
		(net "GND")
	)
	(via
		(at 207.631284 -307.362606)
		(size 0.508)
		(drill 0.254)
		(layers "F.Cu" "B.Cu")
		(net "GND")
	)
	(via
		(at 174.325026 -302.074834)
		(size 0.4064)
		(drill 0.2032)
		(layers "F.Cu" "B.Cu")
		(net "GND")
	)
	(via
		(at 344.127836 -401.040092)
		(size 0.508)
		(drill 0.254)
		(layers "F.Cu" "B.Cu")
		(net "GND")
	)
	(via
		(at 188.099954 -317.749936)
		(size 0.4064)
		(drill 0.2032)
		(layers "F.Cu" "B.Cu")
		(net "GND")
	)
	(via
		(at 73.899776 -285.449772)
		(size 0.4064)
		(drill 0.2032)
		(layers "F.Cu" "B.Cu")
		(net "GND")
	)
	(via
		(at 77.699616 -281.649678)
		(size 0.4064)
		(drill 0.2032)
		(layers "F.Cu" "B.Cu")
		(net "GND")
	)
	(via
		(at 269.333726 -136.901936)
		(size 0.508)
		(drill 0.254)
		(layers "F.Cu" "B.Cu")
		(net "GND")
	)
	(via
		(at 197.125082 -300.174914)
		(size 0.4064)
		(drill 0.2032)
		(layers "F.Cu" "B.Cu")
		(net "GND")
	)
	(via
		(at 251.078746 -122.09907)
		(size 0.508)
		(drill 0.254)
		(layers "F.Cu" "B.Cu")
		(net "GND")
	)
	(via
		(at 431.224944 -296.37482)
		(size 0.4064)
		(drill 0.2032)
		(layers "F.Cu" "B.Cu")
		(net "GND")
	)
	(via
		(at 323.14261 -112.399572)
		(size 0.508)
		(drill 0.254)
		(layers "F.Cu" "B.Cu")
		(net "GND")
	)
	(via
		(at 124.100336 -355.366066)
		(size 0.4572)
		(drill 0.254)
		(layers "F.Cu" "B.Cu")
		(net "GND")
	)
	(via
		(at 74.849736 -284.499812)
		(size 0.4064)
		(drill 0.2032)
		(layers "F.Cu" "B.Cu")
		(net "GND")
	)
	(via
		(at 142.382748 -345.465146)
		(size 0.4064)
		(drill 0.2032)
		(layers "F.Cu" "B.Cu")
		(net "GND")
	)
	(via
		(at 426.94987 -282.599892)
		(size 0.4064)
		(drill 0.2032)
		(layers "F.Cu" "B.Cu")
		(net "GND")
	)
	(via
		(at 197.86219 -112.394492)
		(size 0.508)
		(drill 0.254)
		(layers "F.Cu" "B.Cu")
		(net "GND")
	)
	(via
		(at 128.689862 -30.899608)
		(size 0.508)
		(drill 0.254)
		(layers "F.Cu" "B.Cu")
		(net "GND")
	)
	(via
		(at 179.163472 -345.465146)
		(size 0.4064)
		(drill 0.2032)
		(layers "F.Cu" "B.Cu")
		(net "GND")
	)
	(via
		(at 150.59152 -112.981994)
		(size 0.508)
		(drill 0.254)
		(layers "F.Cu" "B.Cu")
		(net "GND")
	)
	(via
		(at 254.160274 -20.35556)
		(size 0.508)
		(drill 0.254)
		(layers "F.Cu" "B.Cu")
		(net "GND")
	)
	(via
		(at 424.270932 -354.732082)
		(size 0.4064)
		(drill 0.2032)
		(layers "F.Cu" "B.Cu")
		(net "GND")
	)
	(via
		(at 225.957384 -111.065056)
		(size 0.508)
		(drill 0.254)
		(layers "F.Cu" "B.Cu")
		(net "GND")
	)
	(via
		(at 423.32783 -404.940262)
		(size 0.508)
		(drill 0.254)
		(layers "F.Cu" "B.Cu")
		(net "GND")
	)
	(via
		(at 189.999874 -313.949842)
		(size 0.4064)
		(drill 0.2032)
		(layers "F.Cu" "B.Cu")
		(net "GND")
	)
	(via
		(at 307.539898 -74.58583)
		(size 0.508)
		(drill 0.254)
		(layers "F.Cu" "B.Cu")
		(net "GND")
	)
	(via
		(at 405.69515 -365.001556)
		(size 0.508)
		(drill 0.254)
		(layers "F.Cu" "B.Cu")
		(net "GND")
	)
	(via
		(at 71.524876 -294.4749)
		(size 0.4064)
		(drill 0.2032)
		(layers "F.Cu" "B.Cu")
		(net "GND")
	)
	(via
		(at 298.417742 -354.732082)
		(size 0.4064)
		(drill 0.2032)
		(layers "F.Cu" "B.Cu")
		(net "GND")
	)
	(via
		(at 357.35514 -126.995428)
		(size 0.508)
		(drill 0.254)
		(layers "F.Cu" "B.Cu")
		(net "GND")
	)
	(via
		(at 257.467862 -399.203926)
		(size 0.508)
		(drill 0.254)
		(layers "F.Cu" "B.Cu")
		(net "GND")
	)
	(via
		(at 88.947752 -406.141936)
		(size 0.508)
		(drill 0.254)
		(layers "F.Cu" "B.Cu")
		(net "GND")
	)
	(via
		(at 403.199854 -273.099784)
		(size 0.4064)
		(drill 0.2032)
		(layers "F.Cu" "B.Cu")
		(net "GND")
	)
	(via
		(at 303.724818 -302.074834)
		(size 0.4064)
		(drill 0.2032)
		(layers "F.Cu" "B.Cu")
		(net "GND")
	)
	(via
		(at 324.741032 -358.391714)
		(size 0.4572)
		(drill 0.254)
		(layers "F.Cu" "B.Cu")
		(net "GND")
	)
	(via
		(at 357.658162 -141.019276)
		(size 0.508)
		(drill 0.254)
		(layers "F.Cu" "B.Cu")
		(net "GND")
	)
	(via
		(at 356.120192 -34.990278)
		(size 0.508)
		(drill 0.254)
		(layers "F.Cu" "B.Cu")
		(net "GND")
	)
	(via
		(at 66.299842 -318.699896)
		(size 0.4064)
		(drill 0.2032)
		(layers "F.Cu" "B.Cu")
		(net "GND")
	)
	(via
		(at 426.272452 -345.465146)
		(size 0.4064)
		(drill 0.2032)
		(layers "F.Cu" "B.Cu")
		(net "GND")
	)
	(via
		(at 76.74991 -280.699718)
		(size 0.4064)
		(drill 0.2032)
		(layers "F.Cu" "B.Cu")
		(net "GND")
	)
	(via
		(at 375.358152 -343.073482)
		(size 0.4572)
		(drill 0.254)
		(layers "F.Cu" "B.Cu")
		(net "GND")
	)
	(via
		(at 258.957826 -238.232188)
		(size 0.508)
		(drill 0.254)
		(layers "F.Cu" "B.Cu")
		(net "GND")
	)
	(via
		(at 2.67208 -49.574704)
		(size 0.508)
		(drill 0.254)
		(layers "F.Cu" "B.Cu")
		(net "GND")
	)
	(via
		(at 449.060062 -105.057194)
		(size 0.508)
		(drill 0.254)
		(layers "F.Cu" "B.Cu")
		(net "GND")
	)
	(via
		(at 33.192466 -11.372342)
		(size 0.508)
		(drill 0.254)
		(layers "F.Cu" "B.Cu")
		(net "GND")
	)
	(via
		(at 306.448206 -156.554932)
		(size 0.508)
		(drill 0.254)
		(layers "F.Cu" "B.Cu")
		(net "GND")
	)
	(via
		(at 445.820038 -57.076848)
		(size 0.508)
		(drill 0.254)
		(layers "F.Cu" "B.Cu")
		(net "GND")
	)
	(via
		(at 35.93846 -350.977454)
		(size 0.4572)
		(drill 0.254)
		(layers "F.Cu" "B.Cu")
		(net "GND")
	)
	(via
		(at 466.835998 -262.443976)
		(size 0.508)
		(drill 0.254)
		(layers "F.Cu" "B.Cu")
		(net "GND")
	)
	(via
		(at 375.690384 -253.45644)
		(size 0.508)
		(drill 0.254)
		(layers "F.Cu" "B.Cu")
		(net "GND")
	)
	(via
		(at 344.8939 -221.98711)
		(size 0.4572)
		(drill 0.254)
		(layers "F.Cu" "B.Cu")
		(net "GND")
	)
	(via
		(at 390.374886 -289.724846)
		(size 0.4064)
		(drill 0.2032)
		(layers "F.Cu" "B.Cu")
		(net "GND")
	)
	(via
		(at 168.148 -399.838418)
		(size 0.508)
		(drill 0.254)
		(layers "F.Cu" "B.Cu")
		(net "GND")
	)
	(via
		(at 221.568772 -103.781606)
		(size 0.508)
		(drill 0.254)
		(layers "F.Cu" "B.Cu")
		(net "GND")
	)
	(via
		(at 293.84879 -27.79014)
		(size 0.508)
		(drill 0.254)
		(layers "F.Cu" "B.Cu")
		(net "GND")
	)
	(via
		(at 422.548304 -154.755088)
		(size 0.508)
		(drill 0.254)
		(layers "F.Cu" "B.Cu")
		(net "GND")
	)
	(via
		(at 127.209296 -358.391714)
		(size 0.4572)
		(drill 0.254)
		(layers "F.Cu" "B.Cu")
		(net "GND")
	)
	(via
		(at 172.547788 -376.241818)
		(size 0.508)
		(drill 0.254)
		(layers "F.Cu" "B.Cu")
		(net "GND")
	)
	(via
		(at 241.02949 -212.2932)
		(size 0.508)
		(drill 0.254)
		(layers "F.Cu" "B.Cu")
		(net "GND")
	)
	(via
		(at 45.26534 -355.366066)
		(size 0.4572)
		(drill 0.254)
		(layers "F.Cu" "B.Cu")
		(net "GND")
	)
	(via
		(at 77.22489 -291.624766)
		(size 0.4064)
		(drill 0.2032)
		(layers "F.Cu" "B.Cu")
		(net "GND")
	)
	(via
		(at 414.514792 -26.171398)
		(size 0.508)
		(drill 0.254)
		(layers "F.Cu" "B.Cu")
		(net "GND")
	)
	(via
		(at 424.099736 -276.899878)
		(size 0.4064)
		(drill 0.2032)
		(layers "F.Cu" "B.Cu")
		(net "GND")
	)
	(via
		(at 102.617016 -304.373534)
		(size 0.508)
		(drill 0.254)
		(layers "F.Cu" "B.Cu")
		(net "GND")
	)
	(via
		(at 427.727872 -398.34185)
		(size 0.508)
		(drill 0.254)
		(layers "F.Cu" "B.Cu")
		(net "GND")
	)
	(via
		(at 180.975 -296.37482)
		(size 0.4064)
		(drill 0.2032)
		(layers "F.Cu" "B.Cu")
		(net "GND")
	)
	(via
		(at 416.499802 -281.649932)
		(size 0.4064)
		(drill 0.2032)
		(layers "F.Cu" "B.Cu")
		(net "GND")
	)
	(via
		(at 286.624776 -296.37482)
		(size 0.4064)
		(drill 0.2032)
		(layers "F.Cu" "B.Cu")
		(net "GND")
	)
	(via
		(at 239.47247 -56.86044)
		(size 0.508)
		(drill 0.254)
		(layers "F.Cu" "B.Cu")
		(net "GND")
	)
	(via
		(at 167.732964 -137.16508)
		(size 0.508)
		(drill 0.254)
		(layers "F.Cu" "B.Cu")
		(net "GND")
	)
	(via
		(at 66.44767 -152.95499)
		(size 0.508)
		(drill 0.254)
		(layers "F.Cu" "B.Cu")
		(net "GND")
	)
	(via
		(at 105.5878 -195.6308)
		(size 0.508)
		(drill 0.254)
		(layers "F.Cu" "B.Cu")
		(net "GND")
	)
	(via
		(at 87.305134 -354.098098)
		(size 0.4572)
		(drill 0.254)
		(layers "F.Cu" "B.Cu")
		(net "GND")
	)
	(via
		(at 269.333726 -106.316526)
		(size 0.508)
		(drill 0.254)
		(layers "F.Cu" "B.Cu")
		(net "GND")
	)
	(via
		(at 170.999912 -277.849838)
		(size 0.4064)
		(drill 0.2032)
		(layers "F.Cu" "B.Cu")
		(net "GND")
	)
	(via
		(at 178.479958 -199.303386)
		(size 0.508)
		(drill 0.254)
		(layers "F.Cu" "B.Cu")
		(net "GND")
	)
	(via
		(at 130.74777 -383.940304)
		(size 0.4572)
		(drill 0.254)
		(layers "F.Cu" "B.Cu")
		(net "GND")
	)
	(via
		(at 105.471214 -379.21946)
		(size 0.508)
		(drill 0.254)
		(layers "F.Cu" "B.Cu")
		(net "GND")
	)
	(via
		(at 36.374832 -290.674806)
		(size 0.4064)
		(drill 0.2032)
		(layers "F.Cu" "B.Cu")
		(net "GND")
	)
	(via
		(at 131.037584 -282.910788)
		(size 0.49022)
		(drill 0.254)
		(layers "F.Cu" "B.Cu")
		(net "GND")
	)
	(via
		(at 142.382748 -342.439498)
		(size 0.4064)
		(drill 0.2032)
		(layers "F.Cu" "B.Cu")
		(net "GND")
	)
	(via
		(at 394.64996 -311.099962)
		(size 0.4064)
		(drill 0.2032)
		(layers "F.Cu" "B.Cu")
		(net "GND")
	)
	(via
		(at 413.718502 -184.66943)
		(size 0.508)
		(drill 0.254)
		(layers "F.Cu" "B.Cu")
		(net "GND")
	)
	(via
		(at 168.952164 -102.445058)
		(size 0.508)
		(drill 0.254)
		(layers "F.Cu" "B.Cu")
		(net "GND")
	)
	(via
		(at 114.773456 -347.92793)
		(size 0.4572)
		(drill 0.254)
		(layers "F.Cu" "B.Cu")
		(net "GND")
	)
	(via
		(at 427.42485 -288.774886)
		(size 0.4064)
		(drill 0.2032)
		(layers "F.Cu" "B.Cu")
		(net "GND")
	)
	(via
		(at 320.153284 -348.58579)
		(size 0.4064)
		(drill 0.2032)
		(layers "F.Cu" "B.Cu")
		(net "GND")
	)
	(via
		(at 182.87492 -300.174914)
		(size 0.4064)
		(drill 0.2032)
		(layers "F.Cu" "B.Cu")
		(net "GND")
	)
	(via
		(at 139.806934 -0.762)
		(size 0.508)
		(drill 0.254)
		(layers "F.Cu" "B.Cu")
		(net "GND")
	)
	(via
		(at 380.104142 -195.326)
		(size 0.508)
		(drill 0.254)
		(layers "F.Cu" "B.Cu")
		(net "GND")
	)
	(via
		(at 187.620148 -56.441848)
		(size 0.508)
		(drill 0.254)
		(layers "F.Cu" "B.Cu")
		(net "GND")
	)
	(via
		(at 326.480678 -31.390082)
		(size 0.508)
		(drill 0.254)
		(layers "F.Cu" "B.Cu")
		(net "GND")
	)
	(via
		(at 304.467006 -125.435106)
		(size 0.508)
		(drill 0.254)
		(layers "F.Cu" "B.Cu")
		(net "GND")
	)
	(via
		(at 135.2423 -194.938396)
		(size 0.508)
		(drill 0.254)
		(layers "F.Cu" "B.Cu")
		(net "GND")
	)
	(via
		(at 394.64996 -312.049922)
		(size 0.4064)
		(drill 0.2032)
		(layers "F.Cu" "B.Cu")
		(net "GND")
	)
	(via
		(at 159.124904 -284.024832)
		(size 0.4064)
		(drill 0.2032)
		(layers "F.Cu" "B.Cu")
		(net "GND")
	)
	(via
		(at 334.586326 -48.874934)
		(size 0.508)
		(drill 0.254)
		(layers "F.Cu" "B.Cu")
		(net "GND")
	)
	(via
		(at 257.391916 -82.133948)
		(size 0.508)
		(drill 0.254)
		(layers "F.Cu" "B.Cu")
		(net "GND")
	)
	(via
		(at 291.84981 -315.849762)
		(size 0.4064)
		(drill 0.2032)
		(layers "F.Cu" "B.Cu")
		(net "GND")
	)
	(via
		(at 285.052262 -102.445058)
		(size 0.508)
		(drill 0.254)
		(layers "F.Cu" "B.Cu")
		(net "GND")
	)
	(via
		(at 335.405222 -307.18887)
		(size 0.508)
		(drill 0.254)
		(layers "F.Cu" "B.Cu")
		(net "GND")
	)
	(via
		(at 199.500236 -314.899548)
		(size 0.4064)
		(drill 0.2032)
		(layers "F.Cu" "B.Cu")
		(net "GND")
	)
	(via
		(at 338.30006 -267.187426)
		(size 0.508)
		(drill 0.254)
		(layers "F.Cu" "B.Cu")
		(net "GND")
	)
	(via
		(at 45.26534 -357.123746)
		(size 0.4572)
		(drill 0.254)
		(layers "F.Cu" "B.Cu")
		(net "GND")
	)
	(via
		(at 52.85232 -131.76504)
		(size 0.508)
		(drill 0.254)
		(layers "F.Cu" "B.Cu")
		(net "GND")
	)
	(via
		(at 63.912242 -354.732082)
		(size 0.4064)
		(drill 0.2032)
		(layers "F.Cu" "B.Cu")
		(net "GND")
	)
	(via
		(at 47.792132 -70.918832)
		(size 0.508)
		(drill 0.254)
		(layers "F.Cu" "B.Cu")
		(net "GND")
	)
	(via
		(at 20.76196 -160.8963)
		(size 0.508)
		(drill 0.254)
		(layers "F.Cu" "B.Cu")
		(net "GND")
	)
	(via
		(at 186.83097 -11.372342)
		(size 0.508)
		(drill 0.254)
		(layers "F.Cu" "B.Cu")
		(net "GND")
	)
	(via
		(at 286.143192 -28.139136)
		(size 0.508)
		(drill 0.254)
		(layers "F.Cu" "B.Cu")
		(net "GND")
	)
	(via
		(at 165.299898 -317.749936)
		(size 0.4064)
		(drill 0.2032)
		(layers "F.Cu" "B.Cu")
		(net "GND")
	)
	(via
		(at 173.850046 -275.949918)
		(size 0.4064)
		(drill 0.2032)
		(layers "F.Cu" "B.Cu")
		(net "GND")
	)
	(via
		(at 25.352756 -352.245422)
		(size 0.4572)
		(drill 0.254)
		(layers "F.Cu" "B.Cu")
		(net "GND")
	)
	(via
		(at 84.846922 -1.135126)
		(size 0.508)
		(drill 0.254)
		(layers "F.Cu" "B.Cu")
		(net "GND")
	)
	(via
		(at 76.74991 -304.449734)
		(size 0.4064)
		(drill 0.2032)
		(layers "F.Cu" "B.Cu")
		(net "GND")
	)
	(via
		(at 350.803972 -161.044382)
		(size 0.508)
		(drill 0.254)
		(layers "F.Cu" "B.Cu")
		(net "GND")
	)
	(via
		(at 287.574736 -305.874928)
		(size 0.4064)
		(drill 0.2032)
		(layers "F.Cu" "B.Cu")
		(net "GND")
	)
	(via
		(at 318.523112 -344.831162)
		(size 0.4572)
		(drill 0.254)
		(layers "F.Cu" "B.Cu")
		(net "GND")
	)
	(via
		(at 189.999874 -304.449734)
		(size 0.4064)
		(drill 0.2032)
		(layers "F.Cu" "B.Cu")
		(net "GND")
	)
	(via
		(at 35.6489 -34.990024)
		(size 0.508)
		(drill 0.254)
		(layers "F.Cu" "B.Cu")
		(net "GND")
	)
	(via
		(at 38.275006 -292.57498)
		(size 0.4064)
		(drill 0.2032)
		(layers "F.Cu" "B.Cu")
		(net "GND")
	)
	(via
		(at 72.672956 -23.880318)
		(size 0.508)
		(drill 0.254)
		(layers "F.Cu" "B.Cu")
		(net "GND")
	)
	(via
		(at 165.947852 -398.24025)
		(size 0.508)
		(drill 0.254)
		(layers "F.Cu" "B.Cu")
		(net "GND")
	)
	(via
		(at 74.248264 -145.755106)
		(size 0.508)
		(drill 0.254)
		(layers "F.Cu" "B.Cu")
		(net "GND")
	)
	(via
		(at 334.174846 -73.23963)
		(size 0.508)
		(drill 0.254)
		(layers "F.Cu" "B.Cu")
		(net "GND")
	)
	(via
		(at 353.032568 -286.842454)
		(size 0.508)
		(drill 0.254)
		(layers "F.Cu" "B.Cu")
		(net "GND")
	)
	(via
		(at 148.700998 -34.990278)
		(size 0.508)
		(drill 0.254)
		(layers "F.Cu" "B.Cu")
		(net "GND")
	)
	(via
		(at 304.139092 -31.652972)
		(size 0.508)
		(drill 0.254)
		(layers "F.Cu" "B.Cu")
		(net "GND")
	)
	(via
		(at 362.548932 -33.19018)
		(size 0.508)
		(drill 0.254)
		(layers "F.Cu" "B.Cu")
		(net "GND")
	)
	(via
		(at 100.91801 -121.80824)
		(size 0.508)
		(drill 0.254)
		(layers "F.Cu" "B.Cu")
		(net "GND")
	)
	(via
		(at 440.18708 -349.219774)
		(size 0.4572)
		(drill 0.254)
		(layers "F.Cu" "B.Cu")
		(net "GND")
	)
	(via
		(at 137.35558 -153.782522)
		(size 0.508)
		(drill 0.254)
		(layers "F.Cu" "B.Cu")
		(net "GND")
	)
	(via
		(at 298.119038 -201.145394)
		(size 0.508)
		(drill 0.254)
		(layers "F.Cu" "B.Cu")
		(net "GND")
	)
	(via
		(at 393.7 -313.949842)
		(size 0.4064)
		(drill 0.2032)
		(layers "F.Cu" "B.Cu")
		(net "GND")
	)
	(via
		(at 158.649924 -302.549814)
		(size 0.4064)
		(drill 0.2032)
		(layers "F.Cu" "B.Cu")
		(net "GND")
	)
	(via
		(at 291.84981 -319.65011)
		(size 0.4064)
		(drill 0.2032)
		(layers "F.Cu" "B.Cu")
		(net "GND")
	)
	(via
		(at 295.308782 -348.58579)
		(size 0.4064)
		(drill 0.2032)
		(layers "F.Cu" "B.Cu")
		(net "GND")
	)
	(via
		(at 315.043058 -52.536852)
		(size 0.508)
		(drill 0.254)
		(layers "F.Cu" "B.Cu")
		(net "GND")
	)
	(via
		(at 53.48732 -109.644942)
		(size 0.508)
		(drill 0.254)
		(layers "F.Cu" "B.Cu")
		(net "GND")
	)
	(via
		(at 340.285832 -341.781638)
		(size 0.4572)
		(drill 0.254)
		(layers "F.Cu" "B.Cu")
		(net "GND")
	)
	(via
		(at 172.900086 -276.899878)
		(size 0.4064)
		(drill 0.2032)
		(layers "F.Cu" "B.Cu")
		(net "GND")
	)
	(via
		(at 272.067274 -341.805514)
		(size 0.4572)
		(drill 0.254)
		(layers "F.Cu" "B.Cu")
		(net "GND")
	)
	(via
		(at 406.049988 -315.849762)
		(size 0.4064)
		(drill 0.2032)
		(layers "F.Cu" "B.Cu")
		(net "GND")
	)
	(via
		(at 284.503114 -349.219774)
		(size 0.4572)
		(drill 0.254)
		(layers "F.Cu" "B.Cu")
		(net "GND")
	)
	(via
		(at 235.619544 -114.93627)
		(size 0.508)
		(drill 0.254)
		(layers "F.Cu" "B.Cu")
		(net "GND")
	)
	(via
		(at 422.548304 -145.755106)
		(size 0.508)
		(drill 0.254)
		(layers "F.Cu" "B.Cu")
		(net "GND")
	)
	(via
		(at 270.437102 -348.58579)
		(size 0.4064)
		(drill 0.2032)
		(layers "F.Cu" "B.Cu")
		(net "GND")
	)
	(via
		(at 45.26534 -354.098098)
		(size 0.4572)
		(drill 0.254)
		(layers "F.Cu" "B.Cu")
		(net "GND")
	)
	(via
		(at 158.649924 -308.249828)
		(size 0.4064)
		(drill 0.2032)
		(layers "F.Cu" "B.Cu")
		(net "GND")
	)
	(via
		(at 89.798144 -19.757136)
		(size 0.508)
		(drill 0.254)
		(layers "F.Cu" "B.Cu")
		(net "GND")
	)
	(via
		(at 190.950088 -281.649932)
		(size 0.4064)
		(drill 0.2032)
		(layers "F.Cu" "B.Cu")
		(net "GND")
	)
	(via
		(at 288.049716 -279.749758)
		(size 0.4064)
		(drill 0.2032)
		(layers "F.Cu" "B.Cu")
		(net "GND")
	)
	(via
		(at 53.48732 -107.844844)
		(size 0.508)
		(drill 0.254)
		(layers "F.Cu" "B.Cu")
		(net "GND")
	)
	(via
		(at 188.039248 -32.911796)
		(size 0.508)
		(drill 0.254)
		(layers "F.Cu" "B.Cu")
		(net "GND")
	)
	(via
		(at 349.410782 -291.32149)
		(size 0.508)
		(drill 0.254)
		(layers "F.Cu" "B.Cu")
		(net "GND")
	)
	(via
		(at 290.721034 -346.09913)
		(size 0.4572)
		(drill 0.254)
		(layers "F.Cu" "B.Cu")
		(net "GND")
	)
	(via
		(at 72.131682 -357.75773)
		(size 0.4064)
		(drill 0.2032)
		(layers "F.Cu" "B.Cu")
		(net "GND")
	)
	(via
		(at 276.655022 -342.439498)
		(size 0.4064)
		(drill 0.2032)
		(layers "F.Cu" "B.Cu")
		(net "GND")
	)
	(via
		(at 306.099718 -281.649932)
		(size 0.4064)
		(drill 0.2032)
		(layers "F.Cu" "B.Cu")
		(net "GND")
	)
	(via
		(at 37.798248 -20.417536)
		(size 0.508)
		(drill 0.254)
		(layers "F.Cu" "B.Cu")
		(net "GND")
	)
	(via
		(at 185.928 -417.82492)
		(size 0.508)
		(drill 0.254)
		(layers "F.Cu" "B.Cu")
		(net "GND")
	)
	(via
		(at 66.299842 -310.149748)
		(size 0.4064)
		(drill 0.2032)
		(layers "F.Cu" "B.Cu")
		(net "GND")
	)
	(via
		(at 306.16017 -20.35556)
		(size 0.508)
		(drill 0.254)
		(layers "F.Cu" "B.Cu")
		(net "GND")
	)
	(via
		(at 194.708272 -348.58579)
		(size 0.4064)
		(drill 0.2032)
		(layers "F.Cu" "B.Cu")
		(net "GND")
	)
	(via
		(at 306.448206 -152.95499)
		(size 0.508)
		(drill 0.254)
		(layers "F.Cu" "B.Cu")
		(net "GND")
	)
	(via
		(at 298.974764 -293.52494)
		(size 0.4064)
		(drill 0.2032)
		(layers "F.Cu" "B.Cu")
		(net "GND")
	)
	(via
		(at 42.074846 -280.224738)
		(size 0.4064)
		(drill 0.2032)
		(layers "F.Cu" "B.Cu")
		(net "GND")
	)
	(via
		(at 395.862048 -344.831162)
		(size 0.4572)
		(drill 0.254)
		(layers "F.Cu" "B.Cu")
		(net "GND")
	)
	(via
		(at 291.092382 -348.58579)
		(size 0.4064)
		(drill 0.2032)
		(layers "F.Cu" "B.Cu")
		(net "GND")
	)
	(via
		(at 279.024842 -305.874928)
		(size 0.4064)
		(drill 0.2032)
		(layers "F.Cu" "B.Cu")
		(net "GND")
	)
	(via
		(at 265.392662 -6.292342)
		(size 0.508)
		(drill 0.254)
		(layers "F.Cu" "B.Cu")
		(net "GND")
	)
	(via
		(at 403.00656 -133.564884)
		(size 0.508)
		(drill 0.254)
		(layers "F.Cu" "B.Cu")
		(net "GND")
	)
	(via
		(at 179.07508 -285.924752)
		(size 0.4064)
		(drill 0.2032)
		(layers "F.Cu" "B.Cu")
		(net "GND")
	)
	(via
		(at 302.299878 -278.799798)
		(size 0.4064)
		(drill 0.2032)
		(layers "F.Cu" "B.Cu")
		(net "GND")
	)
	(via
		(at 160.074864 -279.274778)
		(size 0.4064)
		(drill 0.2032)
		(layers "F.Cu" "B.Cu")
		(net "GND")
	)
	(via
		(at 197.600062 -309.199788)
		(size 0.4064)
		(drill 0.2032)
		(layers "F.Cu" "B.Cu")
		(net "GND")
	)
	(via
		(at 82.449924 -274.049744)
		(size 0.4064)
		(drill 0.2032)
		(layers "F.Cu" "B.Cu")
		(net "GND")
	)
	(via
		(at 121.947686 -374.938544)
		(size 0.508)
		(drill 0.254)
		(layers "F.Cu" "B.Cu")
		(net "GND")
	)
	(via
		(at 8.954008 -150.16861)
		(size 0.508)
		(drill 0.254)
		(layers "F.Cu" "B.Cu")
		(net "GND")
	)
	(via
		(at 62.632082 -168.94556)
		(size 0.508)
		(drill 0.254)
		(layers "F.Cu" "B.Cu")
		(net "GND")
	)
	(via
		(at 335.509362 -94.23273)
		(size 0.508)
		(drill 0.254)
		(layers "F.Cu" "B.Cu")
		(net "GND")
	)
	(via
		(at 102.611174 -343.298272)
		(size 0.508)
		(drill 0.254)
		(layers "F.Cu" "B.Cu")
		(net "GND")
	)
	(via
		(at 396.0749 -301.124874)
		(size 0.4064)
		(drill 0.2032)
		(layers "F.Cu" "B.Cu")
		(net "GND")
	)
	(via
		(at 133.833108 -121.525284)
		(size 0.508)
		(drill 0.254)
		(layers "F.Cu" "B.Cu")
		(net "GND")
	)
	(via
		(at 355.831648 -147.630388)
		(size 0.508)
		(drill 0.254)
		(layers "F.Cu" "B.Cu")
		(net "GND")
	)
	(via
		(at 379.768608 -59.974734)
		(size 0.508)
		(drill 0.254)
		(layers "F.Cu" "B.Cu")
		(net "GND")
	)
	(via
		(at 437.07812 -346.09913)
		(size 0.4572)
		(drill 0.254)
		(layers "F.Cu" "B.Cu")
		(net "GND")
	)
	(via
		(at 101.379782 -107.681776)
		(size 0.508)
		(drill 0.254)
		(layers "F.Cu" "B.Cu")
		(net "GND")
	)
	(via
		(at 118.772178 -49.574704)
		(size 0.508)
		(drill 0.254)
		(layers "F.Cu" "B.Cu")
		(net "GND")
	)
	(via
		(at 29.54782 -411.141926)
		(size 0.508)
		(drill 0.254)
		(layers "F.Cu" "B.Cu")
		(net "GND")
	)
	(via
		(at 133.148324 -89.946226)
		(size 0.508)
		(drill 0.254)
		(layers "F.Cu" "B.Cu")
		(net "GND")
	)
	(via
		(at 429.657764 -25.971246)
		(size 0.508)
		(drill 0.254)
		(layers "F.Cu" "B.Cu")
		(net "GND")
	)
	(via
		(at 360.55808 -286.842454)
		(size 0.508)
		(drill 0.254)
		(layers "F.Cu" "B.Cu")
		(net "GND")
	)
	(via
		(at 112.545114 -261.687564)
		(size 0.508)
		(drill 0.254)
		(layers "F.Cu" "B.Cu")
		(net "GND")
	)
	(via
		(at 396.0749 -297.32478)
		(size 0.4064)
		(drill 0.2032)
		(layers "F.Cu" "B.Cu")
		(net "GND")
	)
	(via
		(at 71.999856 -277.849838)
		(size 0.4064)
		(drill 0.2032)
		(layers "F.Cu" "B.Cu")
		(net "GND")
	)
	(via
		(at 181.901084 -357.123746)
		(size 0.4572)
		(drill 0.254)
		(layers "F.Cu" "B.Cu")
		(net "GND")
	)
	(via
		(at 114.910616 -134.21106)
		(size 0.508)
		(drill 0.254)
		(layers "F.Cu" "B.Cu")
		(net "GND")
	)
	(via
		(at 295.174924 -302.074834)
		(size 0.4064)
		(drill 0.2032)
		(layers "F.Cu" "B.Cu")
		(net "GND")
	)
	(via
		(at 74.251312 -45.865288)
		(size 0.508)
		(drill 0.254)
		(layers "F.Cu" "B.Cu")
		(net "GND")
	)
	(via
		(at 273.546062 -348.58579)
		(size 0.4064)
		(drill 0.2032)
		(layers "F.Cu" "B.Cu")
		(net "GND")
	)
	(via
		(at 306.7812 -31.118302)
		(size 0.508)
		(drill 0.254)
		(layers "F.Cu" "B.Cu")
		(net "GND")
	)
	(via
		(at 415.931604 -177.78222)
		(size 0.508)
		(drill 0.254)
		(layers "F.Cu" "B.Cu")
		(net "GND")
	)
	(via
		(at 142.004796 -181.098698)
		(size 0.508)
		(drill 0.254)
		(layers "F.Cu" "B.Cu")
		(net "GND")
	)
	(via
		(at 315.740288 -132.77342)
		(size 0.508)
		(drill 0.254)
		(layers "F.Cu" "B.Cu")
		(net "GND")
	)
	(via
		(at 401.299934 -310.149748)
		(size 0.4064)
		(drill 0.2032)
		(layers "F.Cu" "B.Cu")
		(net "GND")
	)
	(via
		(at 466.835998 -384.363976)
		(size 0.508)
		(drill 0.254)
		(layers "F.Cu" "B.Cu")
		(net "GND")
	)
	(via
		(at 180.02504 -287.824926)
		(size 0.4064)
		(drill 0.2032)
		(layers "F.Cu" "B.Cu")
		(net "GND")
	)
	(via
		(at 272.849848 -305.399948)
		(size 0.4064)
		(drill 0.2032)
		(layers "F.Cu" "B.Cu")
		(net "GND")
	)
	(via
		(at 272.438622 -351.611438)
		(size 0.4064)
		(drill 0.2032)
		(layers "F.Cu" "B.Cu")
		(net "GND")
	)
	(via
		(at 40.526208 -351.611438)
		(size 0.4064)
		(drill 0.2032)
		(layers "F.Cu" "B.Cu")
		(net "GND")
	)
	(via
		(at 22.925278 -113.158524)
		(size 0.508)
		(drill 0.254)
		(layers "F.Cu" "B.Cu")
		(net "GND")
	)
	(via
		(at 172.424852 -285.924752)
		(size 0.4064)
		(drill 0.2032)
		(layers "F.Cu" "B.Cu")
		(net "GND")
	)
	(via
		(at 28.090368 -354.732082)
		(size 0.4064)
		(drill 0.2032)
		(layers "F.Cu" "B.Cu")
		(net "GND")
	)
	(via
		(at 374.493536 -299.133514)
		(size 0.508)
		(drill 0.254)
		(layers "F.Cu" "B.Cu")
		(net "GND")
	)
	(via
		(at 25.352756 -358.391714)
		(size 0.4572)
		(drill 0.254)
		(layers "F.Cu" "B.Cu")
		(net "GND")
	)
	(via
		(at 414.74771 -121.835164)
		(size 0.508)
		(drill 0.254)
		(layers "F.Cu" "B.Cu")
		(net "GND")
	)
	(via
		(at 221.59976 -315.946282)
		(size 0.508)
		(drill 0.254)
		(layers "F.Cu" "B.Cu")
		(net "GND")
	)
	(via
		(at 431.700178 -312.049922)
		(size 0.4064)
		(drill 0.2032)
		(layers "F.Cu" "B.Cu")
		(net "GND")
	)
	(via
		(at 36.309808 -348.58579)
		(size 0.4064)
		(drill 0.2032)
		(layers "F.Cu" "B.Cu")
		(net "GND")
	)
	(via
		(at 168.148 -408.840178)
		(size 0.508)
		(drill 0.254)
		(layers "F.Cu" "B.Cu")
		(net "GND")
	)
	(via
		(at 343.394792 -354.098098)
		(size 0.4572)
		(drill 0.254)
		(layers "F.Cu" "B.Cu")
		(net "GND")
	)
	(via
		(at 422.199816 -310.149748)
		(size 0.4064)
		(drill 0.2032)
		(layers "F.Cu" "B.Cu")
		(net "GND")
	)
	(via
		(at 425.999656 -276.899878)
		(size 0.4064)
		(drill 0.2032)
		(layers "F.Cu" "B.Cu")
		(net "GND")
	)
	(via
		(at 119.013732 -127.931926)
		(size 0.508)
		(drill 0.254)
		(layers "F.Cu" "B.Cu")
		(net "GND")
	)
	(via
		(at 321.178174 -76.256642)
		(size 0.508)
		(drill 0.254)
		(layers "F.Cu" "B.Cu")
		(net "GND")
	)
	(via
		(at 34.4551 -29.590238)
		(size 0.508)
		(drill 0.254)
		(layers "F.Cu" "B.Cu")
		(net "GND")
	)
	(via
		(at 257.469386 -397.705834)
		(size 0.508)
		(drill 0.254)
		(layers "F.Cu" "B.Cu")
		(net "GND")
	)
	(via
		(at 31.747968 -397.140176)
		(size 0.508)
		(drill 0.254)
		(layers "F.Cu" "B.Cu")
		(net "GND")
	)
	(via
		(at 322.217542 -303.026826)
		(size 0.508)
		(drill 0.254)
		(layers "F.Cu" "B.Cu")
		(net "GND")
	)
	(via
		(at 72.949816 -310.149748)
		(size 0.4064)
		(drill 0.2032)
		(layers "F.Cu" "B.Cu")
		(net "GND")
	)
	(via
		(at 427.75124 -350.977454)
		(size 0.4572)
		(drill 0.254)
		(layers "F.Cu" "B.Cu")
		(net "GND")
	)
	(via
		(at 424.993562 -84.332318)
		(size 0.508)
		(drill 0.254)
		(layers "F.Cu" "B.Cu")
		(net "GND")
	)
	(via
		(at 130.1623 -279.000712)
		(size 0.508)
		(drill 0.254)
		(layers "F.Cu" "B.Cu")
		(net "GND")
	)
	(via
		(at 82.347816 -406.040336)
		(size 0.508)
		(drill 0.254)
		(layers "F.Cu" "B.Cu")
		(net "GND")
	)
	(via
		(at 285.687262 -100.64496)
		(size 0.508)
		(drill 0.254)
		(layers "F.Cu" "B.Cu")
		(net "GND")
	)
	(via
		(at 337.5279 -406.040336)
		(size 0.508)
		(drill 0.254)
		(layers "F.Cu" "B.Cu")
		(net "GND")
	)
	(via
		(at 384.674872 -275.474938)
		(size 0.4064)
		(drill 0.2032)
		(layers "F.Cu" "B.Cu")
		(net "GND")
	)
	(via
		(at 130.318256 -347.951806)
		(size 0.4572)
		(drill 0.254)
		(layers "F.Cu" "B.Cu")
		(net "GND")
	)
	(via
		(at 430.488852 -342.439498)
		(size 0.4064)
		(drill 0.2032)
		(layers "F.Cu" "B.Cu")
		(net "GND")
	)
	(via
		(at 174.325026 -296.37482)
		(size 0.4064)
		(drill 0.2032)
		(layers "F.Cu" "B.Cu")
		(net "GND")
	)
	(via
		(at 0.766318 -26.612342)
		(size 0.508)
		(drill 0.254)
		(layers "F.Cu" "B.Cu")
		(net "GND")
	)
	(via
		(at 427.89983 -278.799798)
		(size 0.4064)
		(drill 0.2032)
		(layers "F.Cu" "B.Cu")
		(net "GND")
	)
	(via
		(at 399.93316 -131.76504)
		(size 0.508)
		(drill 0.254)
		(layers "F.Cu" "B.Cu")
		(net "GND")
	)
	(via
		(at 448.5513 -45.865288)
		(size 0.508)
		(drill 0.254)
		(layers "F.Cu" "B.Cu")
		(net "GND")
	)
	(via
		(at 279.974802 -297.32478)
		(size 0.4064)
		(drill 0.2032)
		(layers "F.Cu" "B.Cu")
		(net "GND")
	)
	(via
		(at 173.375066 -305.874928)
		(size 0.4064)
		(drill 0.2032)
		(layers "F.Cu" "B.Cu")
		(net "GND")
	)
	(via
		(at 333.265526 -80.775302)
		(size 0.508)
		(drill 0.254)
		(layers "F.Cu" "B.Cu")
		(net "GND")
	)
	(via
		(at 298.012612 -143.955008)
		(size 0.508)
		(drill 0.254)
		(layers "F.Cu" "B.Cu")
		(net "GND")
	)
	(via
		(at 9.648952 -31.390082)
		(size 0.508)
		(drill 0.254)
		(layers "F.Cu" "B.Cu")
		(net "GND")
	)
	(via
		(at 303.249838 -314.899802)
		(size 0.4064)
		(drill 0.2032)
		(layers "F.Cu" "B.Cu")
		(net "GND")
	)
	(via
		(at 357.495094 -60.633356)
		(size 0.508)
		(drill 0.254)
		(layers "F.Cu" "B.Cu")
		(net "GND")
	)
	(via
		(at 378.172218 -33.857692)
		(size 0.508)
		(drill 0.254)
		(layers "F.Cu" "B.Cu")
		(net "GND")
	)
	(via
		(at 213.741 -201.716894)
		(size 0.508)
		(drill 0.254)
		(layers "F.Cu" "B.Cu")
		(net "GND")
	)
	(via
		(at 424.64228 -354.098098)
		(size 0.4572)
		(drill 0.254)
		(layers "F.Cu" "B.Cu")
		(net "GND")
	)
	(via
		(at 31.747968 -402.241766)
		(size 0.508)
		(drill 0.254)
		(layers "F.Cu" "B.Cu")
		(net "GND")
	)
	(via
		(at 63.924942 -302.074834)
		(size 0.4064)
		(drill 0.2032)
		(layers "F.Cu" "B.Cu")
		(net "GND")
	)
	(via
		(at 426.47489 -293.52494)
		(size 0.4064)
		(drill 0.2032)
		(layers "F.Cu" "B.Cu")
		(net "GND")
	)
	(via
		(at 150.103078 -283.893514)
		(size 0.508)
		(drill 0.254)
		(layers "F.Cu" "B.Cu")
		(net "GND")
	)
	(via
		(at 177.161952 -354.732082)
		(size 0.4064)
		(drill 0.2032)
		(layers "F.Cu" "B.Cu")
		(net "GND")
	)
	(via
		(at 272.849848 -311.099962)
		(size 0.4064)
		(drill 0.2032)
		(layers "F.Cu" "B.Cu")
		(net "GND")
	)
	(via
		(at 356.207568 -285.953454)
		(size 0.508)
		(drill 0.254)
		(layers "F.Cu" "B.Cu")
		(net "GND")
	)
	(via
		(at 194.708272 -351.611438)
		(size 0.4064)
		(drill 0.2032)
		(layers "F.Cu" "B.Cu")
		(net "GND")
	)
	(via
		(at 330.927964 -404.940262)
		(size 0.508)
		(drill 0.254)
		(layers "F.Cu" "B.Cu")
		(net "GND")
	)
	(via
		(at 400.60118 -354.732082)
		(size 0.4064)
		(drill 0.2032)
		(layers "F.Cu" "B.Cu")
		(net "GND")
	)
	(via
		(at 78.64983 -314.899802)
		(size 0.4064)
		(drill 0.2032)
		(layers "F.Cu" "B.Cu")
		(net "GND")
	)
	(via
		(at 418.42436 -341.805514)
		(size 0.4572)
		(drill 0.254)
		(layers "F.Cu" "B.Cu")
		(net "GND")
	)
	(via
		(at 184.77992 -303.969928)
		(size 0.4064)
		(drill 0.2032)
		(layers "F.Cu" "B.Cu")
		(net "GND")
	)
	(via
		(at 421.249856 -315.849762)
		(size 0.4064)
		(drill 0.2032)
		(layers "F.Cu" "B.Cu")
		(net "GND")
	)
	(via
		(at 34.491676 -111.72317)
		(size 0.508)
		(drill 0.254)
		(layers "F.Cu" "B.Cu")
		(net "GND")
	)
	(via
		(at 348.527878 -373.838724)
		(size 0.508)
		(drill 0.254)
		(layers "F.Cu" "B.Cu")
		(net "GND")
	)
	(via
		(at 288.072068 -33.857692)
		(size 0.508)
		(drill 0.254)
		(layers "F.Cu" "B.Cu")
		(net "GND")
	)
	(via
		(at 278.074882 -294.4749)
		(size 0.4064)
		(drill 0.2032)
		(layers "F.Cu" "B.Cu")
		(net "GND")
	)
	(via
		(at 192.850008 -311.099962)
		(size 0.4064)
		(drill 0.2032)
		(layers "F.Cu" "B.Cu")
		(net "GND")
	)
	(via
		(at 56.799988 -281.649932)
		(size 0.4064)
		(drill 0.2032)
		(layers "F.Cu" "B.Cu")
		(net "GND")
	)
	(via
		(at 81.024984 -298.27474)
		(size 0.4064)
		(drill 0.2032)
		(layers "F.Cu" "B.Cu")
		(net "GND")
	)
	(via
		(at 270.949928 -315.849762)
		(size 0.4064)
		(drill 0.2032)
		(layers "F.Cu" "B.Cu")
		(net "GND")
	)
	(via
		(at 285.470346 -28.802076)
		(size 0.508)
		(drill 0.254)
		(layers "F.Cu" "B.Cu")
		(net "GND")
	)
	(via
		(at 70.574916 -291.624766)
		(size 0.4064)
		(drill 0.2032)
		(layers "F.Cu" "B.Cu")
		(net "GND")
	)
	(via
		(at 181.92496 -305.874928)
		(size 0.4064)
		(drill 0.2032)
		(layers "F.Cu" "B.Cu")
		(net "GND")
	)
	(via
		(at 286.35325 -344.831162)
		(size 0.4572)
		(drill 0.254)
		(layers "F.Cu" "B.Cu")
		(net "GND")
	)
	(via
		(at 75.74788 -398.34185)
		(size 0.508)
		(drill 0.254)
		(layers "F.Cu" "B.Cu")
		(net "GND")
	)
	(via
		(at 196.550788 -413.364172)
		(size 0.508)
		(drill 0.254)
		(layers "F.Cu" "B.Cu")
		(net "GND")
	)
	(via
		(at 92.26423 -355.366066)
		(size 0.4572)
		(drill 0.254)
		(layers "F.Cu" "B.Cu")
		(net "GND")
	)
	(via
		(at 367.205768 -1.364996)
		(size 0.508)
		(drill 0.254)
		(layers "F.Cu" "B.Cu")
		(net "GND")
	)
	(via
		(at 51.63312 -129.964942)
		(size 0.508)
		(drill 0.254)
		(layers "F.Cu" "B.Cu")
		(net "GND")
	)
	(via
		(at 154.666442 -253.45644)
		(size 0.508)
		(drill 0.254)
		(layers "F.Cu" "B.Cu")
		(net "GND")
	)
	(via
		(at 398.761204 -169.89679)
		(size 0.508)
		(drill 0.254)
		(layers "F.Cu" "B.Cu")
		(net "GND")
	)
	(via
		(at 53.714142 -367.45545)
		(size 0.4572)
		(drill 0.254)
		(layers "F.Cu" "B.Cu")
		(net "GND")
	)
	(via
		(at 68.674742 -304.924714)
		(size 0.4064)
		(drill 0.2032)
		(layers "F.Cu" "B.Cu")
		(net "GND")
	)
	(via
		(at 176.94783 -408.840178)
		(size 0.508)
		(drill 0.254)
		(layers "F.Cu" "B.Cu")
		(net "GND")
	)
	(via
		(at 428.287434 -33.248092)
		(size 0.508)
		(drill 0.254)
		(layers "F.Cu" "B.Cu")
		(net "GND")
	)
	(via
		(at 343.023444 -342.439498)
		(size 0.4064)
		(drill 0.2032)
		(layers "F.Cu" "B.Cu")
		(net "GND")
	)
	(via
		(at 29.54782 -406.040336)
		(size 0.508)
		(drill 0.254)
		(layers "F.Cu" "B.Cu")
		(net "GND")
	)
	(via
		(at 106.394504 -102.021894)
		(size 0.508)
		(drill 0.254)
		(layers "F.Cu" "B.Cu")
		(net "GND")
	)
	(via
		(at 252.32868 -85.840316)
		(size 0.508)
		(drill 0.254)
		(layers "F.Cu" "B.Cu")
		(net "GND")
	)
	(via
		(at 126.347728 -407.24201)
		(size 0.4572)
		(drill 0.254)
		(layers "F.Cu" "B.Cu")
		(net "GND")
	)
	(via
		(at 125.430534 -307.242718)
		(size 0.508)
		(drill 0.254)
		(layers "F.Cu" "B.Cu")
		(net "GND")
	)
	(via
		(at 14.346174 -283.1592)
		(size 0.508)
		(drill 0.254)
		(layers "F.Cu" "B.Cu")
		(net "GND")
	)
	(via
		(at 395.12494 -287.824926)
		(size 0.4064)
		(drill 0.2032)
		(layers "F.Cu" "B.Cu")
		(net "GND")
	)
	(via
		(at 372.62054 -342.439498)
		(size 0.4064)
		(drill 0.2032)
		(layers "F.Cu" "B.Cu")
		(net "GND")
	)
	(via
		(at 57.274968 -287.824926)
		(size 0.4064)
		(drill 0.2032)
		(layers "F.Cu" "B.Cu")
		(net "GND")
	)
	(via
		(at 274.274788 -276.424898)
		(size 0.4064)
		(drill 0.2032)
		(layers "F.Cu" "B.Cu")
		(net "GND")
	)
	(via
		(at 36.961064 -260.338316)
		(size 0.508)
		(drill 0.254)
		(layers "F.Cu" "B.Cu")
		(net "GND")
	)
	(via
		(at 394.17498 -297.32478)
		(size 0.4064)
		(drill 0.2032)
		(layers "F.Cu" "B.Cu")
		(net "GND")
	)
	(via
		(at 444.97117 -29.311854)
		(size 0.508)
		(drill 0.254)
		(layers "F.Cu" "B.Cu")
		(net "GND")
	)
	(via
		(at 299.449744 -276.899878)
		(size 0.4064)
		(drill 0.2032)
		(layers "F.Cu" "B.Cu")
		(net "GND")
	)
	(via
		(at 48.72482 -293.52494)
		(size 0.4064)
		(drill 0.2032)
		(layers "F.Cu" "B.Cu")
		(net "GND")
	)
	(via
		(at 186.675014 -307.774848)
		(size 0.4064)
		(drill 0.2032)
		(layers "F.Cu" "B.Cu")
		(net "GND")
	)
	(via
		(at 342.23452 -268.096492)
		(size 0.508)
		(drill 0.254)
		(layers "F.Cu" "B.Cu")
		(net "GND")
	)
	(via
		(at 232.823512 -235.737654)
		(size 0.508)
		(drill 0.254)
		(layers "F.Cu" "B.Cu")
		(net "GND")
	)
	(via
		(at 94.870016 -131.560316)
		(size 0.508)
		(drill 0.254)
		(layers "F.Cu" "B.Cu")
		(net "GND")
	)
	(via
		(at 34.491676 -131.495546)
		(size 0.508)
		(drill 0.254)
		(layers "F.Cu" "B.Cu")
		(net "GND")
	)
	(via
		(at 402.079968 -341.805514)
		(size 0.4572)
		(drill 0.254)
		(layers "F.Cu" "B.Cu")
		(net "GND")
	)
	(via
		(at 287.983422 -354.732082)
		(size 0.4064)
		(drill 0.2032)
		(layers "F.Cu" "B.Cu")
		(net "GND")
	)
	(via
		(at 390.902952 -347.951806)
		(size 0.4572)
		(drill 0.254)
		(layers "F.Cu" "B.Cu")
		(net "GND")
	)
	(via
		(at 39.90213 -58.731404)
		(size 0.508)
		(drill 0.254)
		(layers "F.Cu" "B.Cu")
		(net "GND")
	)
	(via
		(at 398.449546 -272.14957)
		(size 0.4064)
		(drill 0.2032)
		(layers "F.Cu" "B.Cu")
		(net "GND")
	)
	(via
		(at 54.899814 -313.949842)
		(size 0.4064)
		(drill 0.2032)
		(layers "F.Cu" "B.Cu")
		(net "GND")
	)
	(via
		(at 355.077268 -284.333188)
		(size 0.49022)
		(drill 0.254)
		(layers "F.Cu" "B.Cu")
		(net "GND")
	)
	(via
		(at 119.747792 -404.940262)
		(size 0.4572)
		(drill 0.254)
		(layers "F.Cu" "B.Cu")
		(net "GND")
	)
	(via
		(at 279.974802 -286.874966)
		(size 0.4064)
		(drill 0.2032)
		(layers "F.Cu" "B.Cu")
		(net "GND")
	)
	(via
		(at 283.299916 -281.649932)
		(size 0.4064)
		(drill 0.2032)
		(layers "F.Cu" "B.Cu")
		(net "GND")
	)
	(via
		(at 128.547622 -372.341902)
		(size 0.4572)
		(drill 0.254)
		(layers "F.Cu" "B.Cu")
		(net "GND")
	)
	(via
		(at 421.53332 -341.805514)
		(size 0.4572)
		(drill 0.254)
		(layers "F.Cu" "B.Cu")
		(net "GND")
	)
	(via
		(at 155.325064 -289.724846)
		(size 0.4064)
		(drill 0.2032)
		(layers "F.Cu" "B.Cu")
		(net "GND")
	)
	(via
		(at 246.925338 -82.214974)
		(size 0.508)
		(drill 0.254)
		(layers "F.Cu" "B.Cu")
		(net "GND")
	)
	(via
		(at 111.16945 -393.740132)
		(size 0.508)
		(drill 0.254)
		(layers "F.Cu" "B.Cu")
		(net "GND")
	)
	(via
		(at 71.977758 -135.320024)
		(size 0.508)
		(drill 0.254)
		(layers "F.Cu" "B.Cu")
		(net "GND")
	)
	(via
		(at 349.722694 -292.781736)
		(size 0.508)
		(drill 0.254)
		(layers "F.Cu" "B.Cu")
		(net "GND")
	)
	(via
		(at 41.124886 -278.324818)
		(size 0.4064)
		(drill 0.2032)
		(layers "F.Cu" "B.Cu")
		(net "GND")
	)
	(via
		(at 22.57425 -213.59876)
		(size 0.508)
		(drill 0.254)
		(layers "F.Cu" "B.Cu")
		(net "GND")
	)
	(via
		(at 58.600848 -31.390336)
		(size 0.508)
		(drill 0.254)
		(layers "F.Cu" "B.Cu")
		(net "GND")
	)
	(via
		(at 446.239138 -32.911796)
		(size 0.508)
		(drill 0.254)
		(layers "F.Cu" "B.Cu")
		(net "GND")
	)
	(via
		(at 451.815454 -212.463126)
		(size 0.508)
		(drill 0.254)
		(layers "F.Cu" "B.Cu")
		(net "GND")
	)
	(via
		(at 429.800004 -275.949918)
		(size 0.4064)
		(drill 0.2032)
		(layers "F.Cu" "B.Cu")
		(net "GND")
	)
	(via
		(at 132.297424 -282.910788)
		(size 0.49022)
		(drill 0.254)
		(layers "F.Cu" "B.Cu")
		(net "GND")
	)
	(via
		(at 399.93316 -152.96007)
		(size 0.508)
		(drill 0.254)
		(layers "F.Cu" "B.Cu")
		(net "GND")
	)
	(via
		(at 130.74777 -398.24025)
		(size 0.4572)
		(drill 0.254)
		(layers "F.Cu" "B.Cu")
		(net "GND")
	)
	(via
		(at 396.0749 -305.874928)
		(size 0.4064)
		(drill 0.2032)
		(layers "F.Cu" "B.Cu")
		(net "GND")
	)
	(via
		(at 197.600062 -284.499812)
		(size 0.4064)
		(drill 0.2032)
		(layers "F.Cu" "B.Cu")
		(net "GND")
	)
	(via
		(at 242.815618 -218.535504)
		(size 0.508)
		(drill 0.254)
		(layers "F.Cu" "B.Cu")
		(net "GND")
	)
	(via
		(at 228.308154 -62.399926)
		(size 0.508)
		(drill 0.254)
		(layers "F.Cu" "B.Cu")
		(net "GND")
	)
	(via
		(at 398.925034 -303.974754)
		(size 0.4064)
		(drill 0.2032)
		(layers "F.Cu" "B.Cu")
		(net "GND")
	)
	(via
		(at 171.474892 -284.974792)
		(size 0.4064)
		(drill 0.2032)
		(layers "F.Cu" "B.Cu")
		(net "GND")
	)
	(via
		(at 380.202186 -27.729688)
		(size 0.508)
		(drill 0.254)
		(layers "F.Cu" "B.Cu")
		(net "GND")
	)
	(via
		(at 423.163492 -351.611438)
		(size 0.4064)
		(drill 0.2032)
		(layers "F.Cu" "B.Cu")
		(net "GND")
	)
	(via
		(at 160.54959 -272.14957)
		(size 0.4064)
		(drill 0.2032)
		(layers "F.Cu" "B.Cu")
		(net "GND")
	)
	(via
		(at 98.27387 -73.85177)
		(size 0.508)
		(drill 0.254)
		(layers "F.Cu" "B.Cu")
		(net "GND")
	)
	(via
		(at 143.172942 -306.052728)
		(size 0.508)
		(drill 0.254)
		(layers "F.Cu" "B.Cu")
		(net "GND")
	)
	(via
		(at 391.324846 -277.374858)
		(size 0.4064)
		(drill 0.2032)
		(layers "F.Cu" "B.Cu")
		(net "GND")
	)
	(via
		(at 104.643936 -79.989934)
		(size 0.508)
		(drill 0.254)
		(layers "F.Cu" "B.Cu")
		(net "GND")
	)
	(via
		(at 266.655042 -29.590238)
		(size 0.508)
		(drill 0.254)
		(layers "F.Cu" "B.Cu")
		(net "GND")
	)
	(via
		(at 302.327818 -408.738578)
		(size 0.508)
		(drill 0.254)
		(layers "F.Cu" "B.Cu")
		(net "GND")
	)
	(via
		(at 414.74771 -131.245102)
		(size 0.508)
		(drill 0.254)
		(layers "F.Cu" "B.Cu")
		(net "GND")
	)
	(via
		(at 366.484662 -73.20026)
		(size 0.508)
		(drill 0.254)
		(layers "F.Cu" "B.Cu")
		(net "GND")
	)
	(via
		(at 229.150926 -104.902508)
		(size 0.508)
		(drill 0.254)
		(layers "F.Cu" "B.Cu")
		(net "GND")
	)
	(via
		(at 71.524876 -301.124874)
		(size 0.4064)
		(drill 0.2032)
		(layers "F.Cu" "B.Cu")
		(net "GND")
	)
	(via
		(at 297.927776 -381.241808)
		(size 0.508)
		(drill 0.254)
		(layers "F.Cu" "B.Cu")
		(net "GND")
	)
	(via
		(at 281.394154 -344.831162)
		(size 0.4572)
		(drill 0.254)
		(layers "F.Cu" "B.Cu")
		(net "GND")
	)
	(via
		(at 332.217776 -354.098098)
		(size 0.4572)
		(drill 0.254)
		(layers "F.Cu" "B.Cu")
		(net "GND")
	)
	(via
		(at 248.757948 -57.521094)
		(size 0.508)
		(drill 0.254)
		(layers "F.Cu" "B.Cu")
		(net "GND")
	)
	(via
		(at 136.536176 -350.977454)
		(size 0.4572)
		(drill 0.254)
		(layers "F.Cu" "B.Cu")
		(net "GND")
	)
	(via
		(at 243.998242 -19.757136)
		(size 0.508)
		(drill 0.254)
		(layers "F.Cu" "B.Cu")
		(net "GND")
	)
	(via
		(at 313.699906 -311.099962)
		(size 0.4064)
		(drill 0.2032)
		(layers "F.Cu" "B.Cu")
		(net "GND")
	)
	(via
		(at 280.13533 -352.245422)
		(size 0.4572)
		(drill 0.254)
		(layers "F.Cu" "B.Cu")
		(net "GND")
	)
	(via
		(at 46.34992 -311.099962)
		(size 0.4064)
		(drill 0.2032)
		(layers "F.Cu" "B.Cu")
		(net "GND")
	)
	(via
		(at 199.24014 -27.729688)
		(size 0.508)
		(drill 0.254)
		(layers "F.Cu" "B.Cu")
		(net "GND")
	)
	(via
		(at 182.39994 -276.899878)
		(size 0.4064)
		(drill 0.2032)
		(layers "F.Cu" "B.Cu")
		(net "GND")
	)
	(via
		(at 83.400138 -306.349908)
		(size 0.4064)
		(drill 0.2032)
		(layers "F.Cu" "B.Cu")
		(net "GND")
	)
	(via
		(at 165.774878 -303.024794)
		(size 0.4064)
		(drill 0.2032)
		(layers "F.Cu" "B.Cu")
		(net "GND")
	)
	(via
		(at 182.948834 -198.750174)
		(size 0.508)
		(drill 0.254)
		(layers "F.Cu" "B.Cu")
		(net "GND")
	)
	(via
		(at 345.024964 -348.58579)
		(size 0.4064)
		(drill 0.2032)
		(layers "F.Cu" "B.Cu")
		(net "GND")
	)
	(via
		(at 267.69949 -341.805514)
		(size 0.4572)
		(drill 0.254)
		(layers "F.Cu" "B.Cu")
		(net "GND")
	)
	(via
		(at 386.575046 -274.524978)
		(size 0.4064)
		(drill 0.2032)
		(layers "F.Cu" "B.Cu")
		(net "GND")
	)
	(via
		(at 90.414094 -355.366066)
		(size 0.4572)
		(drill 0.254)
		(layers "F.Cu" "B.Cu")
		(net "GND")
	)
	(via
		(at 404.149814 -279.749758)
		(size 0.4064)
		(drill 0.2032)
		(layers "F.Cu" "B.Cu")
		(net "GND")
	)
	(via
		(at 383.426208 -355.366066)
		(size 0.4572)
		(drill 0.254)
		(layers "F.Cu" "B.Cu")
		(net "GND")
	)
	(via
		(at 341.927942 -404.838662)
		(size 0.508)
		(drill 0.254)
		(layers "F.Cu" "B.Cu")
		(net "GND")
	)
	(via
		(at 68.557902 -56.809894)
		(size 0.508)
		(drill 0.254)
		(layers "F.Cu" "B.Cu")
		(net "GND")
	)
	(via
		(at 402.724874 -302.074834)
		(size 0.4064)
		(drill 0.2032)
		(layers "F.Cu" "B.Cu")
		(net "GND")
	)
	(via
		(at 62.804802 -348.58579)
		(size 0.4064)
		(drill 0.2032)
		(layers "F.Cu" "B.Cu")
		(net "GND")
	)
	(via
		(at 377.208288 -350.977454)
		(size 0.4572)
		(drill 0.254)
		(layers "F.Cu" "B.Cu")
		(net "GND")
	)
	(via
		(at 451.638162 -100.751894)
		(size 0.508)
		(drill 0.254)
		(layers "F.Cu" "B.Cu")
		(net "GND")
	)
	(via
		(at 111.698786 -286.842454)
		(size 0.508)
		(drill 0.254)
		(layers "F.Cu" "B.Cu")
		(net "GND")
	)
	(via
		(at 250.927362 -207.93583)
		(size 0.508)
		(drill 0.254)
		(layers "F.Cu" "B.Cu")
		(net "GND")
	)
	(via
		(at 241.967258 -304.703988)
		(size 0.508)
		(drill 0.254)
		(layers "F.Cu" "B.Cu")
		(net "GND")
	)
	(via
		(at 234.974638 -291.517832)
		(size 0.508)
		(drill 0.254)
		(layers "F.Cu" "B.Cu")
		(net "GND")
	)
	(via
		(at 299.866812 -152.95499)
		(size 0.508)
		(drill 0.254)
		(layers "F.Cu" "B.Cu")
		(net "GND")
	)
	(via
		(at 300.12767 -402.241766)
		(size 0.508)
		(drill 0.254)
		(layers "F.Cu" "B.Cu")
		(net "GND")
	)
	(via
		(at 366.277144 -131.957572)
		(size 0.508)
		(drill 0.254)
		(layers "F.Cu" "B.Cu")
		(net "GND")
	)
	(via
		(at 260.87197 -49.574704)
		(size 0.508)
		(drill 0.254)
		(layers "F.Cu" "B.Cu")
		(net "GND")
	)
	(via
		(at 332.217776 -341.805514)
		(size 0.4572)
		(drill 0.254)
		(layers "F.Cu" "B.Cu")
		(net "GND")
	)
	(via
		(at 49.853088 -345.465146)
		(size 0.4064)
		(drill 0.2032)
		(layers "F.Cu" "B.Cu")
		(net "GND")
	)
	(via
		(at 77.978254 -357.123746)
		(size 0.4572)
		(drill 0.254)
		(layers "F.Cu" "B.Cu")
		(net "GND")
	)
	(via
		(at 276.174708 -291.624766)
		(size 0.4064)
		(drill 0.2032)
		(layers "F.Cu" "B.Cu")
		(net "GND")
	)
	(via
		(at 315.60008 -287.3502)
		(size 0.4064)
		(drill 0.2032)
		(layers "F.Cu" "B.Cu")
		(net "GND")
	)
	(via
		(at 100.315776 -101.333046)
		(size 0.508)
		(drill 0.254)
		(layers "F.Cu" "B.Cu")
		(net "GND")
	)
	(via
		(at 289.127692 -371.038628)
		(size 0.508)
		(drill 0.254)
		(layers "F.Cu" "B.Cu")
		(net "GND")
	)
	(via
		(at 272.374868 -280.224738)
		(size 0.4064)
		(drill 0.2032)
		(layers "F.Cu" "B.Cu")
		(net "GND")
	)
	(via
		(at 321.632072 -352.245422)
		(size 0.4572)
		(drill 0.254)
		(layers "F.Cu" "B.Cu")
		(net "GND")
	)
	(via
		(at 330.251816 -218.208352)
		(size 0.508)
		(drill 0.254)
		(layers "F.Cu" "B.Cu")
		(net "GND")
	)
	(via
		(at 284.249876 -314.899802)
		(size 0.4064)
		(drill 0.2032)
		(layers "F.Cu" "B.Cu")
		(net "GND")
	)
	(via
		(at 28.461716 -349.219774)
		(size 0.4572)
		(drill 0.254)
		(layers "F.Cu" "B.Cu")
		(net "GND")
	)
	(via
		(at 290.721034 -355.366066)
		(size 0.4572)
		(drill 0.254)
		(layers "F.Cu" "B.Cu")
		(net "GND")
	)
	(via
		(at 170.524932 -289.724846)
		(size 0.4064)
		(drill 0.2032)
		(layers "F.Cu" "B.Cu")
		(net "GND")
	)
	(via
		(at 393.351766 -111.44504)
		(size 0.508)
		(drill 0.254)
		(layers "F.Cu" "B.Cu")
		(net "GND")
	)
	(via
		(at 125.730508 -351.611438)
		(size 0.4064)
		(drill 0.2032)
		(layers "F.Cu" "B.Cu")
		(net "GND")
	)
	(via
		(at 80.147922 -395.938502)
		(size 0.508)
		(drill 0.254)
		(layers "F.Cu" "B.Cu")
		(net "GND")
	)
	(via
		(at 163.919662 -38.701218)
		(size 0.508)
		(drill 0.254)
		(layers "F.Cu" "B.Cu")
		(net "GND")
	)
	(via
		(at 158.174944 -281.174952)
		(size 0.4064)
		(drill 0.2032)
		(layers "F.Cu" "B.Cu")
		(net "GND")
	)
	(via
		(at 184.380886 -25.990042)
		(size 0.508)
		(drill 0.254)
		(layers "F.Cu" "B.Cu")
		(net "GND")
	)
	(via
		(at 234.040172 -33.857692)
		(size 0.508)
		(drill 0.254)
		(layers "F.Cu" "B.Cu")
		(net "GND")
	)
	(via
		(at 393.7 -301.599854)
		(size 0.4064)
		(drill 0.2032)
		(layers "F.Cu" "B.Cu")
		(net "GND")
	)
	(via
		(at 333.127858 -377.341892)
		(size 0.508)
		(drill 0.254)
		(layers "F.Cu" "B.Cu")
		(net "GND")
	)
	(via
		(at 259.868924 -286.331914)
		(size 0.508)
		(drill 0.254)
		(layers "F.Cu" "B.Cu")
		(net "GND")
	)
	(via
		(at 73.547732 -402.140166)
		(size 0.508)
		(drill 0.254)
		(layers "F.Cu" "B.Cu")
		(net "GND")
	)
	(via
		(at 13.982446 -274.915122)
		(size 0.508)
		(drill 0.254)
		(layers "F.Cu" "B.Cu")
		(net "GND")
	)
	(via
		(at 165.540944 -45.853858)
		(size 0.508)
		(drill 0.254)
		(layers "F.Cu" "B.Cu")
		(net "GND")
	)
	(via
		(at 51.854608 -345.465146)
		(size 0.4064)
		(drill 0.2032)
		(layers "F.Cu" "B.Cu")
		(net "GND")
	)
	(via
		(at 287.612074 -343.073482)
		(size 0.4572)
		(drill 0.254)
		(layers "F.Cu" "B.Cu")
		(net "GND")
	)
	(via
		(at 381.527812 -371.038628)
		(size 0.508)
		(drill 0.254)
		(layers "F.Cu" "B.Cu")
		(net "GND")
	)
	(via
		(at 90.785442 -354.732082)
		(size 0.4064)
		(drill 0.2032)
		(layers "F.Cu" "B.Cu")
		(net "GND")
	)
	(via
		(at 399.400014 -318.699896)
		(size 0.4064)
		(drill 0.2032)
		(layers "F.Cu" "B.Cu")
		(net "GND")
	)
	(via
		(at 314.366148 -149.617938)
		(size 0.508)
		(drill 0.254)
		(layers "F.Cu" "B.Cu")
		(net "GND")
	)
	(via
		(at 60.124848 -303.974754)
		(size 0.4064)
		(drill 0.2032)
		(layers "F.Cu" "B.Cu")
		(net "GND")
	)
	(via
		(at 111.293148 -348.58579)
		(size 0.4064)
		(drill 0.2032)
		(layers "F.Cu" "B.Cu")
		(net "GND")
	)
	(via
		(at 61.549788 -279.749758)
		(size 0.4064)
		(drill 0.2032)
		(layers "F.Cu" "B.Cu")
		(net "GND")
	)
	(via
		(at 329.69835 -65.15989)
		(size 0.508)
		(drill 0.254)
		(layers "F.Cu" "B.Cu")
		(net "GND")
	)
	(via
		(at 116.447316 -82.297778)
		(size 0.508)
		(drill 0.254)
		(layers "F.Cu" "B.Cu")
		(net "GND")
	)
	(via
		(at 177.161952 -342.439498)
		(size 0.4064)
		(drill 0.2032)
		(layers "F.Cu" "B.Cu")
		(net "GND")
	)
	(via
		(at 463.037682 -118.377462)
		(size 0.508)
		(drill 0.254)
		(layers "F.Cu" "B.Cu")
		(net "GND")
	)
	(via
		(at 304.70221 -241.47018)
		(size 0.508)
		(drill 0.254)
		(layers "F.Cu" "B.Cu")
		(net "GND")
	)
	(via
		(at 324.249542 -303.026826)
		(size 0.508)
		(drill 0.254)
		(layers "F.Cu" "B.Cu")
		(net "GND")
	)
	(via
		(at 230.763318 -144.824704)
		(size 0.508)
		(drill 0.254)
		(layers "F.Cu" "B.Cu")
		(net "GND")
	)
	(via
		(at 168.150032 -314.899802)
		(size 0.4064)
		(drill 0.2032)
		(layers "F.Cu" "B.Cu")
		(net "GND")
	)
	(via
		(at 276.174708 -288.774886)
		(size 0.4064)
		(drill 0.2032)
		(layers "F.Cu" "B.Cu")
		(net "GND")
	)
	(via
		(at 289.47491 -294.4749)
		(size 0.4064)
		(drill 0.2032)
		(layers "F.Cu" "B.Cu")
		(net "GND")
	)
	(via
		(at 393.7 -278.799798)
		(size 0.4064)
		(drill 0.2032)
		(layers "F.Cu" "B.Cu")
		(net "GND")
	)
	(via
		(at 330.927964 -369.938554)
		(size 0.508)
		(drill 0.254)
		(layers "F.Cu" "B.Cu")
		(net "GND")
	)
	(via
		(at 246.284242 -103.025956)
		(size 0.508)
		(drill 0.254)
		(layers "F.Cu" "B.Cu")
		(net "GND")
	)
	(via
		(at 144.886934 -0.762)
		(size 0.508)
		(drill 0.254)
		(layers "F.Cu" "B.Cu")
		(net "GND")
	)
	(via
		(at 408.899868 -274.049744)
		(size 0.4064)
		(drill 0.2032)
		(layers "F.Cu" "B.Cu")
		(net "GND")
	)
	(via
		(at 273.91741 -350.977454)
		(size 0.4572)
		(drill 0.254)
		(layers "F.Cu" "B.Cu")
		(net "GND")
	)
	(via
		(at 437.07812 -341.781638)
		(size 0.4572)
		(drill 0.254)
		(layers "F.Cu" "B.Cu")
		(net "GND")
	)
	(via
		(at 391.549636 -82.0039)
		(size 0.508)
		(drill 0.254)
		(layers "F.Cu" "B.Cu")
		(net "GND")
	)
	(via
		(at 170.999912 -317.749936)
		(size 0.4064)
		(drill 0.2032)
		(layers "F.Cu" "B.Cu")
		(net "GND")
	)
	(via
		(at 217.334084 -174.04842)
		(size 0.508)
		(drill 0.254)
		(layers "F.Cu" "B.Cu")
		(net "GND")
	)
	(via
		(at 71.999856 -278.799798)
		(size 0.4064)
		(drill 0.2032)
		(layers "F.Cu" "B.Cu")
		(net "GND")
	)
	(via
		(at 243.998242 -20.417536)
		(size 0.508)
		(drill 0.254)
		(layers "F.Cu" "B.Cu")
		(net "GND")
	)
	(via
		(at 208.407 -201.168)
		(size 0.508)
		(drill 0.254)
		(layers "F.Cu" "B.Cu")
		(net "GND")
	)
	(via
		(at 419.03142 -11.372342)
		(size 0.508)
		(drill 0.254)
		(layers "F.Cu" "B.Cu")
		(net "GND")
	)
	(via
		(at 296.993564 -203.402946)
		(size 0.508)
		(drill 0.254)
		(layers "F.Cu" "B.Cu")
		(net "GND")
	)
	(via
		(at 438.921652 -124.93498)
		(size 0.508)
		(drill 0.254)
		(layers "F.Cu" "B.Cu")
		(net "GND")
	)
	(via
		(at 123.728988 -342.439498)
		(size 0.4064)
		(drill 0.2032)
		(layers "F.Cu" "B.Cu")
		(net "GND")
	)
	(via
		(at 344.653616 -349.219774)
		(size 0.4572)
		(drill 0.254)
		(layers "F.Cu" "B.Cu")
		(net "GND")
	)
	(via
		(at 82.449924 -278.799798)
		(size 0.4064)
		(drill 0.2032)
		(layers "F.Cu" "B.Cu")
		(net "GND")
	)
	(via
		(at 73.547732 -407.24201)
		(size 0.508)
		(drill 0.254)
		(layers "F.Cu" "B.Cu")
		(net "GND")
	)
	(via
		(at 200.908158 -147.824698)
		(size 0.508)
		(drill 0.254)
		(layers "F.Cu" "B.Cu")
		(net "GND")
	)
	(via
		(at 237.046516 -332.301342)
		(size 0.508)
		(drill 0.254)
		(layers "F.Cu" "B.Cu")
		(net "GND")
	)
	(via
		(at 187.624974 -294.4749)
		(size 0.4064)
		(drill 0.2032)
		(layers "F.Cu" "B.Cu")
		(net "GND")
	)
	(via
		(at 271.424908 -278.324818)
		(size 0.4064)
		(drill 0.2032)
		(layers "F.Cu" "B.Cu")
		(net "GND")
	)
	(via
		(at 443.138306 -72.56526)
		(size 0.508)
		(drill 0.254)
		(layers "F.Cu" "B.Cu")
		(net "GND")
	)
	(via
		(at 110.676182 -290.05149)
		(size 0.508)
		(drill 0.254)
		(layers "F.Cu" "B.Cu")
		(net "GND")
	)
	(via
		(at 385.405376 -227.837746)
		(size 0.508)
		(drill 0.254)
		(layers "F.Cu" "B.Cu")
		(net "GND")
	)
	(via
		(at 389.424926 -277.374858)
		(size 0.4064)
		(drill 0.2032)
		(layers "F.Cu" "B.Cu")
		(net "GND")
	)
	(via
		(at 3.228086 -44.647358)
		(size 0.508)
		(drill 0.254)
		(layers "F.Cu" "B.Cu")
		(net "GND")
	)
	(via
		(at 117.547644 -376.140218)
		(size 0.4572)
		(drill 0.254)
		(layers "F.Cu" "B.Cu")
		(net "GND")
	)
	(via
		(at 136.536176 -347.951806)
		(size 0.4572)
		(drill 0.254)
		(layers "F.Cu" "B.Cu")
		(net "GND")
	)
	(via
		(at 120.473978 -25.971246)
		(size 0.508)
		(drill 0.254)
		(layers "F.Cu" "B.Cu")
		(net "GND")
	)
	(via
		(at 178.599846 -276.899878)
		(size 0.4064)
		(drill 0.2032)
		(layers "F.Cu" "B.Cu")
		(net "GND")
	)
	(via
		(at 7.72414 -311.885838)
		(size 0.508)
		(drill 0.254)
		(layers "F.Cu" "B.Cu")
		(net "GND")
	)
	(via
		(at 81.087214 -354.098098)
		(size 0.4572)
		(drill 0.254)
		(layers "F.Cu" "B.Cu")
		(net "GND")
	)
	(via
		(at 168.148 -380.141734)
		(size 0.508)
		(drill 0.254)
		(layers "F.Cu" "B.Cu")
		(net "GND")
	)
	(via
		(at 49.67478 -284.974792)
		(size 0.4064)
		(drill 0.2032)
		(layers "F.Cu" "B.Cu")
		(net "GND")
	)
	(via
		(at 343.511378 -288.78149)
		(size 0.508)
		(drill 0.254)
		(layers "F.Cu" "B.Cu")
		(net "GND")
	)
	(via
		(at 21.313394 -31.118302)
		(size 0.508)
		(drill 0.254)
		(layers "F.Cu" "B.Cu")
		(net "GND")
	)
	(via
		(at 286.624776 -300.174914)
		(size 0.4064)
		(drill 0.2032)
		(layers "F.Cu" "B.Cu")
		(net "GND")
	)
	(via
		(at 300.12767 -378.94006)
		(size 0.508)
		(drill 0.254)
		(layers "F.Cu" "B.Cu")
		(net "GND")
	)
	(via
		(at 423.163492 -345.465146)
		(size 0.4064)
		(drill 0.2032)
		(layers "F.Cu" "B.Cu")
		(net "GND")
	)
	(via
		(at 189.96914 -343.073482)
		(size 0.4572)
		(drill 0.254)
		(layers "F.Cu" "B.Cu")
		(net "GND")
	)
	(via
		(at 167.849804 -146.155156)
		(size 0.508)
		(drill 0.254)
		(layers "F.Cu" "B.Cu")
		(net "GND")
	)
	(via
		(at 7.820152 -31.390336)
		(size 0.508)
		(drill 0.254)
		(layers "F.Cu" "B.Cu")
		(net "GND")
	)
	(via
		(at 426.94987 -309.199788)
		(size 0.4064)
		(drill 0.2032)
		(layers "F.Cu" "B.Cu")
		(net "GND")
	)
	(via
		(at 144.01292 -358.391714)
		(size 0.4572)
		(drill 0.254)
		(layers "F.Cu" "B.Cu")
		(net "GND")
	)
	(via
		(at 212.284564 -73.20026)
		(size 0.508)
		(drill 0.254)
		(layers "F.Cu" "B.Cu")
		(net "GND")
	)
	(via
		(at 423.32783 -402.241766)
		(size 0.508)
		(drill 0.254)
		(layers "F.Cu" "B.Cu")
		(net "GND")
	)
	(via
		(at 215.892126 -70.918832)
		(size 0.508)
		(drill 0.254)
		(layers "F.Cu" "B.Cu")
		(net "GND")
	)
	(via
		(at 336.789014 -103.69296)
		(size 0.508)
		(drill 0.254)
		(layers "F.Cu" "B.Cu")
		(net "GND")
	)
	(via
		(at 57.749948 -280.699718)
		(size 0.4064)
		(drill 0.2032)
		(layers "F.Cu" "B.Cu")
		(net "GND")
	)
	(via
		(at 56.799988 -314.899802)
		(size 0.4064)
		(drill 0.2032)
		(layers "F.Cu" "B.Cu")
		(net "GND")
	)
	(via
		(at 45.498512 -65.15989)
		(size 0.508)
		(drill 0.254)
		(layers "F.Cu" "B.Cu")
		(net "GND")
	)
	(via
		(at 41.124886 -298.27474)
		(size 0.4064)
		(drill 0.2032)
		(layers "F.Cu" "B.Cu")
		(net "GND")
	)
	(via
		(at 103.369618 -223.206056)
		(size 0.508)
		(drill 0.254)
		(layers "F.Cu" "B.Cu")
		(net "GND")
	)
	(via
		(at 410.799788 -317.749936)
		(size 0.4064)
		(drill 0.2032)
		(layers "F.Cu" "B.Cu")
		(net "GND")
	)
	(via
		(at 57.902094 -27.729688)
		(size 0.508)
		(drill 0.254)
		(layers "F.Cu" "B.Cu")
		(net "GND")
	)
	(via
		(at 130.00228 -58.096404)
		(size 0.508)
		(drill 0.254)
		(layers "F.Cu" "B.Cu")
		(net "GND")
	)
	(via
		(at 391.799826 -314.899802)
		(size 0.4064)
		(drill 0.2032)
		(layers "F.Cu" "B.Cu")
		(net "GND")
	)
	(via
		(at 290.42487 -302.074834)
		(size 0.4064)
		(drill 0.2032)
		(layers "F.Cu" "B.Cu")
		(net "GND")
	)
	(via
		(at 36.14801 -376.241818)
		(size 0.508)
		(drill 0.254)
		(layers "F.Cu" "B.Cu")
		(net "GND")
	)
	(via
		(at 260.612128 -82.018124)
		(size 0.508)
		(drill 0.254)
		(layers "F.Cu" "B.Cu")
		(net "GND")
	)
	(via
		(at 241.980974 -186.755024)
		(size 0.508)
		(drill 0.254)
		(layers "F.Cu" "B.Cu")
		(net "GND")
	)
	(via
		(at 197.125082 -299.224954)
		(size 0.4064)
		(drill 0.2032)
		(layers "F.Cu" "B.Cu")
		(net "GND")
	)
	(via
		(at 296.938954 -350.977454)
		(size 0.4572)
		(drill 0.254)
		(layers "F.Cu" "B.Cu")
		(net "GND")
	)
	(via
		(at 44.986956 -151.157432)
		(size 0.508)
		(drill 0.254)
		(layers "F.Cu" "B.Cu")
		(net "GND")
	)
	(via
		(at 270.80845 -343.073482)
		(size 0.4572)
		(drill 0.254)
		(layers "F.Cu" "B.Cu")
		(net "GND")
	)
	(via
		(at 167.732964 -133.565138)
		(size 0.508)
		(drill 0.254)
		(layers "F.Cu" "B.Cu")
		(net "GND")
	)
	(via
		(at 339.625432 -304.373534)
		(size 0.508)
		(drill 0.254)
		(layers "F.Cu" "B.Cu")
		(net "GND")
	)
	(via
		(at 321.260724 -342.439498)
		(size 0.4064)
		(drill 0.2032)
		(layers "F.Cu" "B.Cu")
		(net "GND")
	)
	(via
		(at 208.019142 -124.144532)
		(size 0.508)
		(drill 0.254)
		(layers "F.Cu" "B.Cu")
		(net "GND")
	)
	(via
		(at 270.601694 -106.316526)
		(size 0.508)
		(drill 0.254)
		(layers "F.Cu" "B.Cu")
		(net "GND")
	)
	(via
		(at 346.327984 -376.140218)
		(size 0.508)
		(drill 0.254)
		(layers "F.Cu" "B.Cu")
		(net "GND")
	)
	(via
		(at 196.763132 -406.657048)
		(size 0.508)
		(drill 0.254)
		(layers "F.Cu" "B.Cu")
		(net "GND")
	)
	(via
		(at 394.64996 -279.749758)
		(size 0.4064)
		(drill 0.2032)
		(layers "F.Cu" "B.Cu")
		(net "GND")
	)
	(via
		(at 8.148066 -386.496814)
		(size 0.508)
		(drill 0.254)
		(layers "F.Cu" "B.Cu")
		(net "GND")
	)
	(via
		(at 374.303036 -219.541598)
		(size 0.508)
		(drill 0.254)
		(layers "F.Cu" "B.Cu")
		(net "GND")
	)
	(via
		(at 167.849804 -145.520156)
		(size 0.508)
		(drill 0.254)
		(layers "F.Cu" "B.Cu")
		(net "GND")
	)
	(via
		(at 19.134836 -349.219774)
		(size 0.4572)
		(drill 0.254)
		(layers "F.Cu" "B.Cu")
		(net "GND")
	)
	(via
		(at 424.09999 -312.999882)
		(size 0.4064)
		(drill 0.2032)
		(layers "F.Cu" "B.Cu")
		(net "GND")
	)
	(via
		(at 211.573364 -72.56526)
		(size 0.508)
		(drill 0.254)
		(layers "F.Cu" "B.Cu")
		(net "GND")
	)
	(via
		(at 293.527734 -404.838662)
		(size 0.508)
		(drill 0.254)
		(layers "F.Cu" "B.Cu")
		(net "GND")
	)
	(via
		(at 374.099328 -346.09913)
		(size 0.4572)
		(drill 0.254)
		(layers "F.Cu" "B.Cu")
		(net "GND")
	)
	(via
		(at 341.927942 -378.83846)
		(size 0.508)
		(drill 0.254)
		(layers "F.Cu" "B.Cu")
		(net "GND")
	)
	(via
		(at 163.747958 -404.940262)
		(size 0.508)
		(drill 0.254)
		(layers "F.Cu" "B.Cu")
		(net "GND")
	)
	(via
		(at 302.955452 -63.218314)
		(size 0.508)
		(drill 0.254)
		(layers "F.Cu" "B.Cu")
		(net "GND")
	)
	(via
		(at 167.675052 -287.824926)
		(size 0.4064)
		(drill 0.2032)
		(layers "F.Cu" "B.Cu")
		(net "GND")
	)
	(via
		(at 86.04631 -350.977454)
		(size 0.4572)
		(drill 0.254)
		(layers "F.Cu" "B.Cu")
		(net "GND")
	)
	(via
		(at 227.07981 -149.416262)
		(size 0.508)
		(drill 0.254)
		(layers "F.Cu" "B.Cu")
		(net "GND")
	)
	(via
		(at 261.969758 -84.752434)
		(size 0.508)
		(drill 0.254)
		(layers "F.Cu" "B.Cu")
		(net "GND")
	)
	(via
		(at 118.579646 -172.216064)
		(size 0.508)
		(drill 0.254)
		(layers "F.Cu" "B.Cu")
		(net "GND")
	)
	(via
		(at 291.93363 -195.965318)
		(size 0.508)
		(drill 0.254)
		(layers "F.Cu" "B.Cu")
		(net "GND")
	)
	(via
		(at 394.011912 -341.805514)
		(size 0.4572)
		(drill 0.254)
		(layers "F.Cu" "B.Cu")
		(net "GND")
	)
	(via
		(at 103.658162 -169.68724)
		(size 0.508)
		(drill 0.254)
		(layers "F.Cu" "B.Cu")
		(net "GND")
	)
	(via
		(at 334.067912 -358.391714)
		(size 0.4572)
		(drill 0.254)
		(layers "F.Cu" "B.Cu")
		(net "GND")
	)
	(via
		(at 54.424834 -283.074872)
		(size 0.4064)
		(drill 0.2032)
		(layers "F.Cu" "B.Cu")
		(net "GND")
	)
	(via
		(at 376.03684 -15.474188)
		(size 0.508)
		(drill 0.254)
		(layers "F.Cu" "B.Cu")
		(net "GND")
	)
	(via
		(at 300.12767 -407.638504)
		(size 0.508)
		(drill 0.254)
		(layers "F.Cu" "B.Cu")
		(net "GND")
	)
	(via
		(at 381.94742 -348.58579)
		(size 0.4064)
		(drill 0.2032)
		(layers "F.Cu" "B.Cu")
		(net "GND")
	)
	(via
		(at 293.74973 -276.899878)
		(size 0.4064)
		(drill 0.2032)
		(layers "F.Cu" "B.Cu")
		(net "GND")
	)
	(via
		(at 299.33392 -232.46588)
		(size 0.508)
		(drill 0.254)
		(layers "F.Cu" "B.Cu")
		(net "GND")
	)
	(via
		(at 415.074862 -298.27474)
		(size 0.4064)
		(drill 0.2032)
		(layers "F.Cu" "B.Cu")
		(net "GND")
	)
	(via
		(at 29.54782 -403.34184)
		(size 0.508)
		(drill 0.254)
		(layers "F.Cu" "B.Cu")
		(net "GND")
	)
	(via
		(at 31.570676 -347.951806)
		(size 0.4572)
		(drill 0.254)
		(layers "F.Cu" "B.Cu")
		(net "GND")
	)
	(via
		(at 344.653616 -346.09913)
		(size 0.4572)
		(drill 0.254)
		(layers "F.Cu" "B.Cu")
		(net "GND")
	)
	(via
		(at 84.54771 -373.83847)
		(size 0.508)
		(drill 0.254)
		(layers "F.Cu" "B.Cu")
		(net "GND")
	)
	(via
		(at 115.34775 -372.341902)
		(size 0.4572)
		(drill 0.254)
		(layers "F.Cu" "B.Cu")
		(net "GND")
	)
	(via
		(at 237.212378 -48.770286)
		(size 0.508)
		(drill 0.254)
		(layers "F.Cu" "B.Cu")
		(net "GND")
	)
	(via
		(at 440.548776 -27.79014)
		(size 0.508)
		(drill 0.254)
		(layers "F.Cu" "B.Cu")
		(net "GND")
	)
	(via
		(at 74.869294 -341.805514)
		(size 0.4572)
		(drill 0.254)
		(layers "F.Cu" "B.Cu")
		(net "GND")
	)
	(via
		(at 308.949852 -283.549852)
		(size 0.4064)
		(drill 0.2032)
		(layers "F.Cu" "B.Cu")
		(net "GND")
	)
	(via
		(at 14.248892 -33.19018)
		(size 0.508)
		(drill 0.254)
		(layers "F.Cu" "B.Cu")
		(net "GND")
	)
	(via
		(at 276.782022 -58.873644)
		(size 0.508)
		(drill 0.254)
		(layers "F.Cu" "B.Cu")
		(net "GND")
	)
	(via
		(at 277.599902 -314.899802)
		(size 0.4064)
		(drill 0.2032)
		(layers "F.Cu" "B.Cu")
		(net "GND")
	)
	(via
		(at 76.74991 -281.649932)
		(size 0.4064)
		(drill 0.2032)
		(layers "F.Cu" "B.Cu")
		(net "GND")
	)
	(via
		(at 179.07508 -300.174914)
		(size 0.4064)
		(drill 0.2032)
		(layers "F.Cu" "B.Cu")
		(net "GND")
	)
	(via
		(at 389.899906 -308.249828)
		(size 0.4064)
		(drill 0.2032)
		(layers "F.Cu" "B.Cu")
		(net "GND")
	)
	(via
		(at 393.351766 -131.76504)
		(size 0.508)
		(drill 0.254)
		(layers "F.Cu" "B.Cu")
		(net "GND")
	)
	(via
		(at 271.899888 -300.649894)
		(size 0.4064)
		(drill 0.2032)
		(layers "F.Cu" "B.Cu")
		(net "GND")
	)
	(via
		(at 344.305382 -285.267654)
		(size 0.508)
		(drill 0.254)
		(layers "F.Cu" "B.Cu")
		(net "GND")
	)
	(via
		(at 379.754384 -253.45644)
		(size 0.508)
		(drill 0.254)
		(layers "F.Cu" "B.Cu")
		(net "GND")
	)
	(via
		(at 270.80845 -344.831162)
		(size 0.4572)
		(drill 0.254)
		(layers "F.Cu" "B.Cu")
		(net "GND")
	)
	(via
		(at 82.347816 -372.240302)
		(size 0.508)
		(drill 0.254)
		(layers "F.Cu" "B.Cu")
		(net "GND")
	)
	(via
		(at 266.897358 -114.4905)
		(size 0.508)
		(drill 0.254)
		(layers "F.Cu" "B.Cu")
		(net "GND")
	)
	(via
		(at 70.574916 -303.024794)
		(size 0.4064)
		(drill 0.2032)
		(layers "F.Cu" "B.Cu")
		(net "GND")
	)
	(via
		(at 390.849866 -306.349908)
		(size 0.4064)
		(drill 0.2032)
		(layers "F.Cu" "B.Cu")
		(net "GND")
	)
	(via
		(at 210.938364 -73.20026)
		(size 0.508)
		(drill 0.254)
		(layers "F.Cu" "B.Cu")
		(net "GND")
	)
	(via
		(at 79.82839 -346.09913)
		(size 0.4572)
		(drill 0.254)
		(layers "F.Cu" "B.Cu")
		(net "GND")
	)
	(via
		(at 421.127682 -408.738578)
		(size 0.508)
		(drill 0.254)
		(layers "F.Cu" "B.Cu")
		(net "GND")
	)
	(via
		(at 415.074862 -300.174914)
		(size 0.4064)
		(drill 0.2032)
		(layers "F.Cu" "B.Cu")
		(net "GND")
	)
	(via
		(at 395.862048 -346.09913)
		(size 0.4572)
		(drill 0.254)
		(layers "F.Cu" "B.Cu")
		(net "GND")
	)
	(via
		(at 335.698084 -354.732082)
		(size 0.4064)
		(drill 0.2032)
		(layers "F.Cu" "B.Cu")
		(net "GND")
	)
	(via
		(at 279.3746 -390.0678)
		(size 0.508)
		(drill 0.254)
		(layers "F.Cu" "B.Cu")
		(net "GND")
	)
	(via
		(at 413.174942 -306.824888)
		(size 0.4064)
		(drill 0.2032)
		(layers "F.Cu" "B.Cu")
		(net "GND")
	)
	(via
		(at 62.024768 -287.824926)
		(size 0.4064)
		(drill 0.2032)
		(layers "F.Cu" "B.Cu")
		(net "GND")
	)
	(via
		(at 316.266322 -35.871912)
		(size 0.508)
		(drill 0.254)
		(layers "F.Cu" "B.Cu")
		(net "GND")
	)
	(via
		(at 306.448206 -147.55495)
		(size 0.508)
		(drill 0.254)
		(layers "F.Cu" "B.Cu")
		(net "GND")
	)
	(via
		(at 307.999892 -310.149748)
		(size 0.4064)
		(drill 0.2032)
		(layers "F.Cu" "B.Cu")
		(net "GND")
	)
	(via
		(at 266.202922 -280.693114)
		(size 0.508)
		(drill 0.254)
		(layers "F.Cu" "B.Cu")
		(net "GND")
	)
	(via
		(at 106.837226 -305.972718)
		(size 0.508)
		(drill 0.254)
		(layers "F.Cu" "B.Cu")
		(net "GND")
	)
	(via
		(at 80.898238 -129.707894)
		(size 0.508)
		(drill 0.254)
		(layers "F.Cu" "B.Cu")
		(net "GND")
	)
	(via
		(at 163.247324 -350.977454)
		(size 0.4572)
		(drill 0.254)
		(layers "F.Cu" "B.Cu")
		(net "GND")
	)
	(via
		(at 424.57497 -289.724846)
		(size 0.4064)
		(drill 0.2032)
		(layers "F.Cu" "B.Cu")
		(net "GND")
	)
	(via
		(at 324.741032 -357.123746)
		(size 0.4572)
		(drill 0.254)
		(layers "F.Cu" "B.Cu")
		(net "GND")
	)
	(via
		(at 386.16382 -354.732082)
		(size 0.4064)
		(drill 0.2032)
		(layers "F.Cu" "B.Cu")
		(net "GND")
	)
	(via
		(at 381.527812 -377.341892)
		(size 0.508)
		(drill 0.254)
		(layers "F.Cu" "B.Cu")
		(net "GND")
	)
	(via
		(at 73.289922 -73.85177)
		(size 0.508)
		(drill 0.254)
		(layers "F.Cu" "B.Cu")
		(net "GND")
	)
	(via
		(at 321.632072 -341.805514)
		(size 0.4572)
		(drill 0.254)
		(layers "F.Cu" "B.Cu")
		(net "GND")
	)
	(via
		(at 195.224908 -292.574726)
		(size 0.4064)
		(drill 0.2032)
		(layers "F.Cu" "B.Cu")
		(net "GND")
	)
	(via
		(at 112.578642 -293.424102)
		(size 0.508)
		(drill 0.254)
		(layers "F.Cu" "B.Cu")
		(net "GND")
	)
	(via
		(at 326.757792 -56.809894)
		(size 0.508)
		(drill 0.254)
		(layers "F.Cu" "B.Cu")
		(net "GND")
	)
	(via
		(at 395.332966 -131.76504)
		(size 0.508)
		(drill 0.254)
		(layers "F.Cu" "B.Cu")
		(net "GND")
	)
	(via
		(at 298.967144 -84.873592)
		(size 0.508)
		(drill 0.254)
		(layers "F.Cu" "B.Cu")
		(net "GND")
	)
	(via
		(at 314.649866 -307.299868)
		(size 0.4064)
		(drill 0.2032)
		(layers "F.Cu" "B.Cu")
		(net "GND")
	)
	(via
		(at 188.039248 -29.311854)
		(size 0.508)
		(drill 0.254)
		(layers "F.Cu" "B.Cu")
		(net "GND")
	)
	(via
		(at 136.164828 -351.611438)
		(size 0.4064)
		(drill 0.2032)
		(layers "F.Cu" "B.Cu")
		(net "GND")
	)
	(via
		(at 367.558828 -149.90826)
		(size 0.508)
		(drill 0.254)
		(layers "F.Cu" "B.Cu")
		(net "GND")
	)
	(via
		(at 335.350866 -291.32149)
		(size 0.508)
		(drill 0.254)
		(layers "F.Cu" "B.Cu")
		(net "GND")
	)
	(via
		(at 4.843272 -52.536852)
		(size 0.508)
		(drill 0.254)
		(layers "F.Cu" "B.Cu")
		(net "GND")
	)
	(via
		(at 67.249802 -275.949918)
		(size 0.4064)
		(drill 0.2032)
		(layers "F.Cu" "B.Cu")
		(net "GND")
	)
	(via
		(at 176.224946 -285.924752)
		(size 0.4064)
		(drill 0.2032)
		(layers "F.Cu" "B.Cu")
		(net "GND")
	)
	(via
		(at 93.638878 -291.321998)
		(size 0.508)
		(drill 0.254)
		(layers "F.Cu" "B.Cu")
		(net "GND")
	)
	(via
		(at 332.589124 -348.58579)
		(size 0.4064)
		(drill 0.2032)
		(layers "F.Cu" "B.Cu")
		(net "GND")
	)
	(via
		(at 429.800004 -311.099962)
		(size 0.4064)
		(drill 0.2032)
		(layers "F.Cu" "B.Cu")
		(net "GND")
	)
	(via
		(at 45.87494 -293.52494)
		(size 0.4064)
		(drill 0.2032)
		(layers "F.Cu" "B.Cu")
		(net "GND")
	)
	(via
		(at 388.16534 -348.58579)
		(size 0.4064)
		(drill 0.2032)
		(layers "F.Cu" "B.Cu")
		(net "GND")
	)
	(via
		(at 389.424926 -276.424898)
		(size 0.4064)
		(drill 0.2032)
		(layers "F.Cu" "B.Cu")
		(net "GND")
	)
	(via
		(at 166.725092 -306.824888)
		(size 0.4064)
		(drill 0.2032)
		(layers "F.Cu" "B.Cu")
		(net "GND")
	)
	(via
		(at 401.78736 -100.64496)
		(size 0.508)
		(drill 0.254)
		(layers "F.Cu" "B.Cu")
		(net "GND")
	)
	(via
		(at 321.744086 -294.682672)
		(size 0.508)
		(drill 0.254)
		(layers "F.Cu" "B.Cu")
		(net "GND")
	)
	(via
		(at 46.34992 -282.599892)
		(size 0.4064)
		(drill 0.2032)
		(layers "F.Cu" "B.Cu")
		(net "GND")
	)
	(via
		(at 189.999874 -302.549814)
		(size 0.4064)
		(drill 0.2032)
		(layers "F.Cu" "B.Cu")
		(net "GND")
	)
	(via
		(at 429.010064 -354.098098)
		(size 0.4572)
		(drill 0.254)
		(layers "F.Cu" "B.Cu")
		(net "GND")
	)
	(via
		(at 396.54988 -310.149748)
		(size 0.4064)
		(drill 0.2032)
		(layers "F.Cu" "B.Cu")
		(net "GND")
	)
	(via
		(at 259.419852 -353.465638)
		(size 0.508)
		(drill 0.254)
		(layers "F.Cu" "B.Cu")
		(net "GND")
	)
	(via
		(at 168.148 -378.94006)
		(size 0.508)
		(drill 0.254)
		(layers "F.Cu" "B.Cu")
		(net "GND")
	)
	(via
		(at 174.747936 -378.83846)
		(size 0.508)
		(drill 0.254)
		(layers "F.Cu" "B.Cu")
		(net "GND")
	)
	(via
		(at 424.274996 -73.23963)
		(size 0.508)
		(drill 0.254)
		(layers "F.Cu" "B.Cu")
		(net "GND")
	)
	(via
		(at 212.831426 -6.292342)
		(size 0.508)
		(drill 0.254)
		(layers "F.Cu" "B.Cu")
		(net "GND")
	)
	(via
		(at 38.056058 -33.19018)
		(size 0.508)
		(drill 0.254)
		(layers "F.Cu" "B.Cu")
		(net "GND")
	)
	(via
		(at 414.202118 -56.826404)
		(size 0.508)
		(drill 0.254)
		(layers "F.Cu" "B.Cu")
		(net "GND")
	)
	(via
		(at 262.915146 -60.601606)
		(size 0.508)
		(drill 0.254)
		(layers "F.Cu" "B.Cu")
		(net "GND")
	)
	(via
		(at 421.161972 -354.732082)
		(size 0.4064)
		(drill 0.2032)
		(layers "F.Cu" "B.Cu")
		(net "GND")
	)
	(via
		(at 134.67461 -92.563188)
		(size 0.508)
		(drill 0.254)
		(layers "F.Cu" "B.Cu")
		(net "GND")
	)
	(via
		(at 406.900888 -33.19018)
		(size 0.508)
		(drill 0.254)
		(layers "F.Cu" "B.Cu")
		(net "GND")
	)
	(via
		(at 178.124866 -289.724846)
		(size 0.4064)
		(drill 0.2032)
		(layers "F.Cu" "B.Cu")
		(net "GND")
	)
	(via
		(at 427.899576 -287.349946)
		(size 0.4064)
		(drill 0.2032)
		(layers "F.Cu" "B.Cu")
		(net "GND")
	)
	(via
		(at 270.949928 -302.549814)
		(size 0.4064)
		(drill 0.2032)
		(layers "F.Cu" "B.Cu")
		(net "GND")
	)
	(via
		(at 162.0393 -29.311854)
		(size 0.508)
		(drill 0.254)
		(layers "F.Cu" "B.Cu")
		(net "GND")
	)
	(via
		(at 46.34992 -309.199788)
		(size 0.4064)
		(drill 0.2032)
		(layers "F.Cu" "B.Cu")
		(net "GND")
	)
	(via
		(at 156.698442 -253.45644)
		(size 0.508)
		(drill 0.254)
		(layers "F.Cu" "B.Cu")
		(net "GND")
	)
	(via
		(at 17.69618 -162.25647)
		(size 0.508)
		(drill 0.254)
		(layers "F.Cu" "B.Cu")
		(net "GND")
	)
	(via
		(at 211.62899 -115.902486)
		(size 0.508)
		(drill 0.254)
		(layers "F.Cu" "B.Cu")
		(net "GND")
	)
	(via
		(at 333.127858 -406.040336)
		(size 0.508)
		(drill 0.254)
		(layers "F.Cu" "B.Cu")
		(net "GND")
	)
	(via
		(at 382.791716 -130.236722)
		(size 0.508)
		(drill 0.254)
		(layers "F.Cu" "B.Cu")
		(net "GND")
	)
	(via
		(at 170.347894 -373.441976)
		(size 0.508)
		(drill 0.254)
		(layers "F.Cu" "B.Cu")
		(net "GND")
	)
	(via
		(at 158.649924 -306.349908)
		(size 0.4064)
		(drill 0.2032)
		(layers "F.Cu" "B.Cu")
		(net "GND")
	)
	(via
		(at 80.385412 -34.183066)
		(size 0.508)
		(drill 0.254)
		(layers "F.Cu" "B.Cu")
		(net "GND")
	)
	(via
		(at 429.325024 -293.52494)
		(size 0.4064)
		(drill 0.2032)
		(layers "F.Cu" "B.Cu")
		(net "GND")
	)
	(via
		(at 160.968944 -152.958038)
		(size 0.508)
		(drill 0.254)
		(layers "F.Cu" "B.Cu")
		(net "GND")
	)
	(via
		(at 139.529566 -47.020734)
		(size 0.508)
		(drill 0.254)
		(layers "F.Cu" "B.Cu")
		(net "GND")
	)
	(via
		(at 288.99993 -276.899878)
		(size 0.4064)
		(drill 0.2032)
		(layers "F.Cu" "B.Cu")
		(net "GND")
	)
	(via
		(at 40.649906 -300.649894)
		(size 0.4064)
		(drill 0.2032)
		(layers "F.Cu" "B.Cu")
		(net "GND")
	)
	(via
		(at 302.024034 -130.710432)
		(size 0.508)
		(drill 0.254)
		(layers "F.Cu" "B.Cu")
		(net "GND")
	)
	(via
		(at 388.474966 -275.474938)
		(size 0.4064)
		(drill 0.2032)
		(layers "F.Cu" "B.Cu")
		(net "GND")
	)
	(via
		(at 180.64226 -349.219774)
		(size 0.4572)
		(drill 0.254)
		(layers "F.Cu" "B.Cu")
		(net "GND")
	)
	(via
		(at 325.999856 -350.977454)
		(size 0.4572)
		(drill 0.254)
		(layers "F.Cu" "B.Cu")
		(net "GND")
	)
	(via
		(at 406.049734 -272.14957)
		(size 0.4064)
		(drill 0.2032)
		(layers "F.Cu" "B.Cu")
		(net "GND")
	)
	(via
		(at 348.527878 -403.738588)
		(size 0.508)
		(drill 0.254)
		(layers "F.Cu" "B.Cu")
		(net "GND")
	)
	(via
		(at 283.299916 -273.099784)
		(size 0.4064)
		(drill 0.2032)
		(layers "F.Cu" "B.Cu")
		(net "GND")
	)
	(via
		(at 197.125082 -291.624766)
		(size 0.4064)
		(drill 0.2032)
		(layers "F.Cu" "B.Cu")
		(net "GND")
	)
	(via
		(at 452.440802 -245.02364)
		(size 0.508)
		(drill 0.254)
		(layers "F.Cu" "B.Cu")
		(net "GND")
	)
	(via
		(at 368.78768 -26.360882)
		(size 0.508)
		(drill 0.254)
		(layers "F.Cu" "B.Cu")
		(net "GND")
	)
	(via
		(at 466.835998 -277.683976)
		(size 0.508)
		(drill 0.254)
		(layers "F.Cu" "B.Cu")
		(net "GND")
	)
	(via
		(at 110.034324 -270.001492)
		(size 0.508)
		(drill 0.254)
		(layers "F.Cu" "B.Cu")
		(net "GND")
	)
	(via
		(at 331.51318 -34.718498)
		(size 0.508)
		(drill 0.254)
		(layers "F.Cu" "B.Cu")
		(net "GND")
	)
	(via
		(at 232.217214 -286.087312)
		(size 0.508)
		(drill 0.254)
		(layers "F.Cu" "B.Cu")
		(net "GND")
	)
	(via
		(at 335.350866 -290.05149)
		(size 0.508)
		(drill 0.254)
		(layers "F.Cu" "B.Cu")
		(net "GND")
	)
	(via
		(at 449.639944 -73.87463)
		(size 0.508)
		(drill 0.254)
		(layers "F.Cu" "B.Cu")
		(net "GND")
	)
	(via
		(at 128.154938 -34.990024)
		(size 0.508)
		(drill 0.254)
		(layers "F.Cu" "B.Cu")
		(net "GND")
	)
	(via
		(at 421.249856 -280.699718)
		(size 0.4064)
		(drill 0.2032)
		(layers "F.Cu" "B.Cu")
		(net "GND")
	)
	(via
		(at 16.558006 -56.809894)
		(size 0.508)
		(drill 0.254)
		(layers "F.Cu" "B.Cu")
		(net "GND")
	)
	(via
		(at 113.294668 -351.611438)
		(size 0.4064)
		(drill 0.2032)
		(layers "F.Cu" "B.Cu")
		(net "GND")
	)
	(via
		(at 48.251364 -45.865288)
		(size 0.508)
		(drill 0.254)
		(layers "F.Cu" "B.Cu")
		(net "GND")
	)
	(via
		(at 49.1998 -307.299868)
		(size 0.4064)
		(drill 0.2032)
		(layers "F.Cu" "B.Cu")
		(net "GND")
	)
	(via
		(at 100.076 -383.0574)
		(size 0.508)
		(drill 0.254)
		(layers "F.Cu" "B.Cu")
		(net "GND")
	)
	(via
		(at 398.163542 -113.780062)
		(size 0.508)
		(drill 0.254)
		(layers "F.Cu" "B.Cu")
		(net "GND")
	)
	(via
		(at 85.757766 -301.262034)
		(size 0.508)
		(drill 0.254)
		(layers "F.Cu" "B.Cu")
		(net "GND")
	)
	(via
		(at 0.77089 -344.941144)
		(size 0.508)
		(drill 0.254)
		(layers "F.Cu" "B.Cu")
		(net "GND")
	)
	(via
		(at 67.66687 -143.955008)
		(size 0.508)
		(drill 0.254)
		(layers "F.Cu" "B.Cu")
		(net "GND")
	)
	(via
		(at 196.736462 -51.661822)
		(size 0.508)
		(drill 0.254)
		(layers "F.Cu" "B.Cu")
		(net "GND")
	)
	(via
		(at 317.008256 -135.114538)
		(size 0.508)
		(drill 0.254)
		(layers "F.Cu" "B.Cu")
		(net "GND")
	)
	(via
		(at 285.052262 -120.555004)
		(size 0.508)
		(drill 0.254)
		(layers "F.Cu" "B.Cu")
		(net "GND")
	)
	(via
		(at 151.20112 -102.181914)
		(size 0.508)
		(drill 0.254)
		(layers "F.Cu" "B.Cu")
		(net "GND")
	)
	(via
		(at 138.68146 -34.718498)
		(size 0.508)
		(drill 0.254)
		(layers "F.Cu" "B.Cu")
		(net "GND")
	)
	(via
		(at 250.280678 -148.718778)
		(size 0.508)
		(drill 0.254)
		(layers "F.Cu" "B.Cu")
		(net "GND")
	)
	(via
		(at 410.324808 -285.924752)
		(size 0.4064)
		(drill 0.2032)
		(layers "F.Cu" "B.Cu")
		(net "GND")
	)
	(via
		(at 296.938954 -358.391714)
		(size 0.4572)
		(drill 0.254)
		(layers "F.Cu" "B.Cu")
		(net "GND")
	)
	(via
		(at 70.099936 -277.849838)
		(size 0.4064)
		(drill 0.2032)
		(layers "F.Cu" "B.Cu")
		(net "GND")
	)
	(via
		(at 163.874958 -286.874966)
		(size 0.4064)
		(drill 0.2032)
		(layers "F.Cu" "B.Cu")
		(net "GND")
	)
	(via
		(at 186.488832 -345.465146)
		(size 0.4064)
		(drill 0.2032)
		(layers "F.Cu" "B.Cu")
		(net "GND")
	)
	(via
		(at 186.669934 -25.832054)
		(size 0.508)
		(drill 0.254)
		(layers "F.Cu" "B.Cu")
		(net "GND")
	)
	(via
		(at 362.432092 -13.613638)
		(size 0.508)
		(drill 0.254)
		(layers "F.Cu" "B.Cu")
		(net "GND")
	)
	(via
		(at 176.94783 -373.838724)
		(size 0.508)
		(drill 0.254)
		(layers "F.Cu" "B.Cu")
		(net "GND")
	)
	(via
		(at 77.69987 -310.149748)
		(size 0.4064)
		(drill 0.2032)
		(layers "F.Cu" "B.Cu")
		(net "GND")
	)
	(via
		(at 93.523054 -350.977454)
		(size 0.4572)
		(drill 0.254)
		(layers "F.Cu" "B.Cu")
		(net "GND")
	)
	(via
		(at 397.49984 -318.699896)
		(size 0.4064)
		(drill 0.2032)
		(layers "F.Cu" "B.Cu")
		(net "GND")
	)
	(via
		(at 297.927776 -411.141926)
		(size 0.508)
		(drill 0.254)
		(layers "F.Cu" "B.Cu")
		(net "GND")
	)
	(via
		(at 69.022722 -348.58579)
		(size 0.4064)
		(drill 0.2032)
		(layers "F.Cu" "B.Cu")
		(net "GND")
	)
	(via
		(at 415.549842 -312.049922)
		(size 0.4064)
		(drill 0.2032)
		(layers "F.Cu" "B.Cu")
		(net "GND")
	)
	(via
		(at 258.657852 -352.703638)
		(size 0.508)
		(drill 0.254)
		(layers "F.Cu" "B.Cu")
		(net "GND")
	)
	(via
		(at 423.149776 -272.14957)
		(size 0.4064)
		(drill 0.2032)
		(layers "F.Cu" "B.Cu")
		(net "GND")
	)
	(via
		(at 292.79977 -274.049744)
		(size 0.4064)
		(drill 0.2032)
		(layers "F.Cu" "B.Cu")
		(net "GND")
	)
	(via
		(at 84.196174 -357.123746)
		(size 0.4572)
		(drill 0.254)
		(layers "F.Cu" "B.Cu")
		(net "GND")
	)
	(via
		(at 113.294668 -348.58579)
		(size 0.4064)
		(drill 0.2032)
		(layers "F.Cu" "B.Cu")
		(net "GND")
	)
	(via
		(at 260.463792 -256.098548)
		(size 0.508)
		(drill 0.254)
		(layers "F.Cu" "B.Cu")
		(net "GND")
	)
	(via
		(at 236.728 -211.074)
		(size 0.508)
		(drill 0.254)
		(layers "F.Cu" "B.Cu")
		(net "GND")
	)
	(via
		(at 438.13222 -125.378972)
		(size 0.508)
		(drill 0.254)
		(layers "F.Cu" "B.Cu")
		(net "GND")
	)
	(via
		(at 362.01604 -395.750288)
		(size 0.508)
		(drill 0.254)
		(layers "F.Cu" "B.Cu")
		(net "GND")
	)
	(via
		(at 356.696518 -251.316744)
		(size 0.508)
		(drill 0.254)
		(layers "F.Cu" "B.Cu")
		(net "GND")
	)
	(via
		(at 147.554442 -253.45644)
		(size 0.508)
		(drill 0.254)
		(layers "F.Cu" "B.Cu")
		(net "GND")
	)
	(via
		(at 39.699946 -306.349908)
		(size 0.4064)
		(drill 0.2032)
		(layers "F.Cu" "B.Cu")
		(net "GND")
	)
	(via
		(at 416.580828 -27.79014)
		(size 0.508)
		(drill 0.254)
		(layers "F.Cu" "B.Cu")
		(net "GND")
	)
	(via
		(at 50.624994 -296.37482)
		(size 0.4064)
		(drill 0.2032)
		(layers "F.Cu" "B.Cu")
		(net "GND")
	)
	(via
		(at 432.12766 -399.838418)
		(size 0.508)
		(drill 0.254)
		(layers "F.Cu" "B.Cu")
		(net "GND")
	)
	(via
		(at 28.786836 -0.762)
		(size 0.508)
		(drill 0.254)
		(layers "F.Cu" "B.Cu")
		(net "GND")
	)
	(via
		(at 403.199854 -314.899802)
		(size 0.4064)
		(drill 0.2032)
		(layers "F.Cu" "B.Cu")
		(net "GND")
	)
	(via
		(at 387.050026 -300.649894)
		(size 0.4064)
		(drill 0.2032)
		(layers "F.Cu" "B.Cu")
		(net "GND")
	)
	(via
		(at 383.72796 -399.838418)
		(size 0.508)
		(drill 0.254)
		(layers "F.Cu" "B.Cu")
		(net "GND")
	)
	(via
		(at 416.499802 -277.849838)
		(size 0.4064)
		(drill 0.2032)
		(layers "F.Cu" "B.Cu")
		(net "GND")
	)
	(via
		(at 419.349936 -281.649932)
		(size 0.4064)
		(drill 0.2032)
		(layers "F.Cu" "B.Cu")
		(net "GND")
	)
	(via
		(at 186.675014 -292.57498)
		(size 0.4064)
		(drill 0.2032)
		(layers "F.Cu" "B.Cu")
		(net "GND")
	)
	(via
		(at 83.582256 -37.087048)
		(size 0.508)
		(drill 0.254)
		(layers "F.Cu" "B.Cu")
		(net "GND")
	)
	(via
		(at 188.366908 -125.435106)
		(size 0.508)
		(drill 0.254)
		(layers "F.Cu" "B.Cu")
		(net "GND")
	)
	(via
		(at 80.550004 -275.949918)
		(size 0.4064)
		(drill 0.2032)
		(layers "F.Cu" "B.Cu")
		(net "GND")
	)
	(via
		(at 44.92498 -297.32478)
		(size 0.4064)
		(drill 0.2032)
		(layers "F.Cu" "B.Cu")
		(net "GND")
	)
	(via
		(at 293.527734 -381.241808)
		(size 0.508)
		(drill 0.254)
		(layers "F.Cu" "B.Cu")
		(net "GND")
	)
	(via
		(at 57.274968 -285.924752)
		(size 0.4064)
		(drill 0.2032)
		(layers "F.Cu" "B.Cu")
		(net "GND")
	)
	(via
		(at 315.60008 -276.900132)
		(size 0.4064)
		(drill 0.2032)
		(layers "F.Cu" "B.Cu")
		(net "GND")
	)
	(via
		(at 385.007866 -89.304876)
		(size 0.508)
		(drill 0.254)
		(layers "F.Cu" "B.Cu")
		(net "GND")
	)
	(via
		(at 31.140146 -27.729688)
		(size 0.508)
		(drill 0.254)
		(layers "F.Cu" "B.Cu")
		(net "GND")
	)
	(via
		(at 386.575046 -281.174952)
		(size 0.4064)
		(drill 0.2032)
		(layers "F.Cu" "B.Cu")
		(net "GND")
	)
	(via
		(at 168.952164 -124.154946)
		(size 0.508)
		(drill 0.254)
		(layers "F.Cu" "B.Cu")
		(net "GND")
	)
	(via
		(at 131.948428 -348.58579)
		(size 0.4064)
		(drill 0.2032)
		(layers "F.Cu" "B.Cu")
		(net "GND")
	)
	(via
		(at 161.500058 -307.299868)
		(size 0.4064)
		(drill 0.2032)
		(layers "F.Cu" "B.Cu")
		(net "GND")
	)
	(via
		(at 380.111 -233.426)
		(size 0.508)
		(drill 0.254)
		(layers "F.Cu" "B.Cu")
		(net "GND")
	)
	(via
		(at 49.1998 -314.899802)
		(size 0.4064)
		(drill 0.2032)
		(layers "F.Cu" "B.Cu")
		(net "GND")
	)
	(via
		(at 28.557982 -289.532314)
		(size 0.508)
		(drill 0.254)
		(layers "F.Cu" "B.Cu")
		(net "GND")
	)
	(via
		(at 382.75514 -29.590238)
		(size 0.508)
		(drill 0.254)
		(layers "F.Cu" "B.Cu")
		(net "GND")
	)
	(via
		(at 47.115476 -346.09913)
		(size 0.4572)
		(drill 0.254)
		(layers "F.Cu" "B.Cu")
		(net "GND")
	)
	(via
		(at 124.147834 -403.738588)
		(size 0.508)
		(drill 0.254)
		(layers "F.Cu" "B.Cu")
		(net "GND")
	)
	(via
		(at 12.284456 -23.488142)
		(size 0.508)
		(drill 0.254)
		(layers "F.Cu" "B.Cu")
		(net "GND")
	)
	(via
		(at 396.770606 -131.277614)
		(size 0.508)
		(drill 0.254)
		(layers "F.Cu" "B.Cu")
		(net "GND")
	)
	(via
		(at 43.47337 -72.56526)
		(size 0.508)
		(drill 0.254)
		(layers "F.Cu" "B.Cu")
		(net "GND")
	)
	(via
		(at 447.166238 -94.25178)
		(size 0.508)
		(drill 0.254)
		(layers "F.Cu" "B.Cu")
		(net "GND")
	)
	(via
		(at 67.724782 -303.974754)
		(size 0.4064)
		(drill 0.2032)
		(layers "F.Cu" "B.Cu")
		(net "GND")
	)
	(via
		(at 315.60008 -314.899548)
		(size 0.4064)
		(drill 0.2032)
		(layers "F.Cu" "B.Cu")
		(net "GND")
	)
	(via
		(at 119.512588 -348.58579)
		(size 0.4064)
		(drill 0.2032)
		(layers "F.Cu" "B.Cu")
		(net "GND")
	)
	(via
		(at 189.630558 -65.15989)
		(size 0.508)
		(drill 0.254)
		(layers "F.Cu" "B.Cu")
		(net "GND")
	)
	(via
		(at 298.024804 -303.974754)
		(size 0.4064)
		(drill 0.2032)
		(layers "F.Cu" "B.Cu")
		(net "GND")
	)
	(via
		(at 242.09883 -222.05696)
		(size 0.508)
		(drill 0.254)
		(layers "F.Cu" "B.Cu")
		(net "GND")
	)
	(via
		(at 397.97482 -303.974754)
		(size 0.4064)
		(drill 0.2032)
		(layers "F.Cu" "B.Cu")
		(net "GND")
	)
	(via
		(at 276.396196 -60.099194)
		(size 0.508)
		(drill 0.254)
		(layers "F.Cu" "B.Cu")
		(net "GND")
	)
	(via
		(at 331.51318 -33.459674)
		(size 0.508)
		(drill 0.254)
		(layers "F.Cu" "B.Cu")
		(net "GND")
	)
	(via
		(at 34.00298 -287.093914)
		(size 0.508)
		(drill 0.254)
		(layers "F.Cu" "B.Cu")
		(net "GND")
	)
	(via
		(at 161.54781 -399.441924)
		(size 0.508)
		(drill 0.254)
		(layers "F.Cu" "B.Cu")
		(net "GND")
	)
	(via
		(at 104.609138 -108.39196)
		(size 0.508)
		(drill 0.254)
		(layers "F.Cu" "B.Cu")
		(net "GND")
	)
	(via
		(at 289.46221 -350.977454)
		(size 0.4572)
		(drill 0.254)
		(layers "F.Cu" "B.Cu")
		(net "GND")
	)
	(via
		(at 8.950198 -389.152384)
		(size 0.508)
		(drill 0.254)
		(layers "F.Cu" "B.Cu")
		(net "GND")
	)
	(via
		(at 44.92498 -284.974792)
		(size 0.4064)
		(drill 0.2032)
		(layers "F.Cu" "B.Cu")
		(net "GND")
	)
	(via
		(at 165.09746 -346.09913)
		(size 0.4572)
		(drill 0.254)
		(layers "F.Cu" "B.Cu")
		(net "GND")
	)
	(via
		(at 429.800004 -274.049744)
		(size 0.4064)
		(drill 0.2032)
		(layers "F.Cu" "B.Cu")
		(net "GND")
	)
	(via
		(at 310.849772 -308.249828)
		(size 0.4064)
		(drill 0.2032)
		(layers "F.Cu" "B.Cu")
		(net "GND")
	)
	(via
		(at 4.562856 -200.481692)
		(size 0.508)
		(drill 0.254)
		(layers "F.Cu" "B.Cu")
		(net "GND")
	)
	(via
		(at 267.69949 -344.831162)
		(size 0.4572)
		(drill 0.254)
		(layers "F.Cu" "B.Cu")
		(net "GND")
	)
	(via
		(at 160.549844 -307.299868)
		(size 0.4064)
		(drill 0.2032)
		(layers "F.Cu" "B.Cu")
		(net "GND")
	)
	(via
		(at 359.850944 -292.789102)
		(size 0.508)
		(drill 0.254)
		(layers "F.Cu" "B.Cu")
		(net "GND")
	)
	(via
		(at 153.061162 -260.338316)
		(size 0.508)
		(drill 0.254)
		(layers "F.Cu" "B.Cu")
		(net "GND")
	)
	(via
		(at 37.788596 -341.805514)
		(size 0.4572)
		(drill 0.254)
		(layers "F.Cu" "B.Cu")
		(net "GND")
	)
	(via
		(at 42.549826 -306.349908)
		(size 0.4064)
		(drill 0.2032)
		(layers "F.Cu" "B.Cu")
		(net "GND")
	)
	(via
		(at 205.898242 -19.757136)
		(size 0.508)
		(drill 0.254)
		(layers "F.Cu" "B.Cu")
		(net "GND")
	)
	(via
		(at 84.196174 -343.073482)
		(size 0.4572)
		(drill 0.254)
		(layers "F.Cu" "B.Cu")
		(net "GND")
	)
	(via
		(at 412.224982 -297.32478)
		(size 0.4064)
		(drill 0.2032)
		(layers "F.Cu" "B.Cu")
		(net "GND")
	)
	(via
		(at 364.49762 -282.910788)
		(size 0.49022)
		(drill 0.254)
		(layers "F.Cu" "B.Cu")
		(net "GND")
	)
	(via
		(at 153.42489 -282.124912)
		(size 0.4064)
		(drill 0.2032)
		(layers "F.Cu" "B.Cu")
		(net "GND")
	)
	(via
		(at 391.922762 -23.880318)
		(size 0.508)
		(drill 0.254)
		(layers "F.Cu" "B.Cu")
		(net "GND")
	)
	(via
		(at 269.161006 -257.137916)
		(size 0.508)
		(drill 0.254)
		(layers "F.Cu" "B.Cu")
		(net "GND")
	)
	(via
		(at 128.638554 -305.91887)
		(size 0.508)
		(drill 0.254)
		(layers "F.Cu" "B.Cu")
		(net "GND")
	)
	(via
		(at 287.612074 -350.977454)
		(size 0.4572)
		(drill 0.254)
		(layers "F.Cu" "B.Cu")
		(net "GND")
	)
	(via
		(at 44.006516 -344.831162)
		(size 0.4572)
		(drill 0.254)
		(layers "F.Cu" "B.Cu")
		(net "GND")
	)
	(via
		(at 21.745956 -171.375578)
		(size 0.508)
		(drill 0.254)
		(layers "F.Cu" "B.Cu")
		(net "GND")
	)
	(via
		(at 44.92498 -286.874966)
		(size 0.4064)
		(drill 0.2032)
		(layers "F.Cu" "B.Cu")
		(net "GND")
	)
	(via
		(at 250.808744 -131.960874)
		(size 0.508)
		(drill 0.254)
		(layers "F.Cu" "B.Cu")
		(net "GND")
	)
	(via
		(at 212.738716 -23.880318)
		(size 0.508)
		(drill 0.254)
		(layers "F.Cu" "B.Cu")
		(net "GND")
	)
	(via
		(at 168.625012 -302.074834)
		(size 0.4064)
		(drill 0.2032)
		(layers "F.Cu" "B.Cu")
		(net "GND")
	)
	(via
		(at 153.233628 -100.375466)
		(size 0.508)
		(drill 0.254)
		(layers "F.Cu" "B.Cu")
		(net "GND")
	)
	(via
		(at 62.499748 -312.999882)
		(size 0.4064)
		(drill 0.2032)
		(layers "F.Cu" "B.Cu")
		(net "GND")
	)
	(via
		(at 134.68604 -347.951806)
		(size 0.4572)
		(drill 0.254)
		(layers "F.Cu" "B.Cu")
		(net "GND")
	)
	(via
		(at 18.901156 -173.204378)
		(size 0.508)
		(drill 0.254)
		(layers "F.Cu" "B.Cu")
		(net "GND")
	)
	(via
		(at 168.20642 -357.123746)
		(size 0.4572)
		(drill 0.254)
		(layers "F.Cu" "B.Cu")
		(net "GND")
	)
	(via
		(at 37.133784 -125.692154)
		(size 0.508)
		(drill 0.254)
		(layers "F.Cu" "B.Cu")
		(net "GND")
	)
	(via
		(at 286.35325 -349.219774)
		(size 0.4572)
		(drill 0.254)
		(layers "F.Cu" "B.Cu")
		(net "GND")
	)
	(via
		(at 59.649868 -311.099962)
		(size 0.4064)
		(drill 0.2032)
		(layers "F.Cu" "B.Cu")
		(net "GND")
	)
	(via
		(at 421.53332 -346.09913)
		(size 0.4572)
		(drill 0.254)
		(layers "F.Cu" "B.Cu")
		(net "GND")
	)
	(via
		(at 431.840386 -156.283406)
		(size 0.508)
		(drill 0.254)
		(layers "F.Cu" "B.Cu")
		(net "GND")
	)
	(via
		(at 165.774878 -285.924752)
		(size 0.4064)
		(drill 0.2032)
		(layers "F.Cu" "B.Cu")
		(net "GND")
	)
	(via
		(at 26.61158 -354.098098)
		(size 0.4572)
		(drill 0.254)
		(layers "F.Cu" "B.Cu")
		(net "GND")
	)
	(via
		(at 420.567104 -118.234968)
		(size 0.508)
		(drill 0.254)
		(layers "F.Cu" "B.Cu")
		(net "GND")
	)
	(via
		(at 186.675014 -287.824926)
		(size 0.4064)
		(drill 0.2032)
		(layers "F.Cu" "B.Cu")
		(net "GND")
	)
	(via
		(at 385.05638 -354.732082)
		(size 0.4064)
		(drill 0.2032)
		(layers "F.Cu" "B.Cu")
		(net "GND")
	)
	(via
		(at 7.01675 -168.425876)
		(size 0.508)
		(drill 0.254)
		(layers "F.Cu" "B.Cu")
		(net "GND")
	)
	(via
		(at 104.173274 -286.842454)
		(size 0.508)
		(drill 0.254)
		(layers "F.Cu" "B.Cu")
		(net "GND")
	)
	(via
		(at 352.613214 -183.388)
		(size 0.508)
		(drill 0.254)
		(layers "F.Cu" "B.Cu")
		(net "GND")
	)
	(via
		(at 275.224748 -286.874712)
		(size 0.4064)
		(drill 0.2032)
		(layers "F.Cu" "B.Cu")
		(net "GND")
	)
	(via
		(at 124.136912 -284.333188)
		(size 0.49022)
		(drill 0.254)
		(layers "F.Cu" "B.Cu")
		(net "GND")
	)
	(via
		(at 397.97482 -285.924752)
		(size 0.4064)
		(drill 0.2032)
		(layers "F.Cu" "B.Cu")
		(net "GND")
	)
	(via
		(at 394.818362 -89.500202)
		(size 0.508)
		(drill 0.254)
		(layers "F.Cu" "B.Cu")
		(net "GND")
	)
	(via
		(at 275.224748 -278.324818)
		(size 0.4064)
		(drill 0.2032)
		(layers "F.Cu" "B.Cu")
		(net "GND")
	)
	(via
		(at 380.90094 -29.590238)
		(size 0.508)
		(drill 0.254)
		(layers "F.Cu" "B.Cu")
		(net "GND")
	)
	(via
		(at 338.594446 -100.779072)
		(size 0.508)
		(drill 0.254)
		(layers "F.Cu" "B.Cu")
		(net "GND")
	)
	(via
		(at 86.747858 -399.441924)
		(size 0.508)
		(drill 0.254)
		(layers "F.Cu" "B.Cu")
		(net "GND")
	)
	(via
		(at 52.85232 -113.245138)
		(size 0.508)
		(drill 0.254)
		(layers "F.Cu" "B.Cu")
		(net "GND")
	)
	(via
		(at 277.599902 -278.799798)
		(size 0.4064)
		(drill 0.2032)
		(layers "F.Cu" "B.Cu")
		(net "GND")
	)
	(via
		(at 323.456554 -124.93498)
		(size 0.508)
		(drill 0.254)
		(layers "F.Cu" "B.Cu")
		(net "GND")
	)
	(via
		(at 388.949946 -307.299868)
		(size 0.4064)
		(drill 0.2032)
		(layers "F.Cu" "B.Cu")
		(net "GND")
	)
	(via
		(at 290.89985 -310.149748)
		(size 0.4064)
		(drill 0.2032)
		(layers "F.Cu" "B.Cu")
		(net "GND")
	)
	(via
		(at 449.729352 -47.020734)
		(size 0.508)
		(drill 0.254)
		(layers "F.Cu" "B.Cu")
		(net "GND")
	)
	(via
		(at 441.817252 -354.732082)
		(size 0.4064)
		(drill 0.2032)
		(layers "F.Cu" "B.Cu")
		(net "GND")
	)
	(via
		(at 70.574916 -290.674806)
		(size 0.4064)
		(drill 0.2032)
		(layers "F.Cu" "B.Cu")
		(net "GND")
	)
	(via
		(at 234.58551 -34.183066)
		(size 0.508)
		(drill 0.254)
		(layers "F.Cu" "B.Cu")
		(net "GND")
	)
	(via
		(at 244.102382 -277.213314)
		(size 0.508)
		(drill 0.254)
		(layers "F.Cu" "B.Cu")
		(net "GND")
	)
	(via
		(at 176.94783 -380.141988)
		(size 0.508)
		(drill 0.254)
		(layers "F.Cu" "B.Cu")
		(net "GND")
	)
	(via
		(at 55.849774 -309.199788)
		(size 0.4064)
		(drill 0.2032)
		(layers "F.Cu" "B.Cu")
		(net "GND")
	)
	(via
		(at 412.224982 -285.924752)
		(size 0.4064)
		(drill 0.2032)
		(layers "F.Cu" "B.Cu")
		(net "GND")
	)
	(via
		(at 417.924996 -306.824888)
		(size 0.4064)
		(drill 0.2032)
		(layers "F.Cu" "B.Cu")
		(net "GND")
	)
	(via
		(at 210.766914 -213.11108)
		(size 0.508)
		(drill 0.254)
		(layers "F.Cu" "B.Cu")
		(net "GND")
	)
	(via
		(at 80.147922 -372.341902)
		(size 0.508)
		(drill 0.254)
		(layers "F.Cu" "B.Cu")
		(net "GND")
	)
	(via
		(at 144.363948 -256.098548)
		(size 0.508)
		(drill 0.254)
		(layers "F.Cu" "B.Cu")
		(net "GND")
	)
	(via
		(at 29.72054 -355.366066)
		(size 0.4572)
		(drill 0.254)
		(layers "F.Cu" "B.Cu")
		(net "GND")
	)
	(via
		(at 313.699906 -280.699718)
		(size 0.4064)
		(drill 0.2032)
		(layers "F.Cu" "B.Cu")
		(net "GND")
	)
	(via
		(at 125.35916 -354.098098)
		(size 0.4572)
		(drill 0.254)
		(layers "F.Cu" "B.Cu")
		(net "GND")
	)
	(via
		(at 357.63073 -307.242718)
		(size 0.508)
		(drill 0.254)
		(layers "F.Cu" "B.Cu")
		(net "GND")
	)
	(via
		(at 161.500058 -302.549814)
		(size 0.4064)
		(drill 0.2032)
		(layers "F.Cu" "B.Cu")
		(net "GND")
	)
	(via
		(at 252.139196 -29.311854)
		(size 0.508)
		(drill 0.254)
		(layers "F.Cu" "B.Cu")
		(net "GND")
	)
	(via
		(at 52.049934 -275.949918)
		(size 0.4064)
		(drill 0.2032)
		(layers "F.Cu" "B.Cu")
		(net "GND")
	)
	(via
		(at 328.871072 -28.05303)
		(size 0.508)
		(drill 0.254)
		(layers "F.Cu" "B.Cu")
		(net "GND")
	)
	(via
		(at 75.79995 -281.649932)
		(size 0.4064)
		(drill 0.2032)
		(layers "F.Cu" "B.Cu")
		(net "GND")
	)
	(via
		(at 74.374756 -292.574726)
		(size 0.4064)
		(drill 0.2032)
		(layers "F.Cu" "B.Cu")
		(net "GND")
	)
	(via
		(at 63.924942 -305.874928)
		(size 0.4064)
		(drill 0.2032)
		(layers "F.Cu" "B.Cu")
		(net "GND")
	)
	(via
		(at 246.950992 -282.982162)
		(size 0.508)
		(drill 0.254)
		(layers "F.Cu" "B.Cu")
		(net "GND")
	)
	(via
		(at 357.619808 -163.021518)
		(size 0.508)
		(drill 0.254)
		(layers "F.Cu" "B.Cu")
		(net "GND")
	)
	(via
		(at 65.824862 -291.624766)
		(size 0.4064)
		(drill 0.2032)
		(layers "F.Cu" "B.Cu")
		(net "GND")
	)
	(via
		(at 288.573718 -25.971246)
		(size 0.508)
		(drill 0.254)
		(layers "F.Cu" "B.Cu")
		(net "GND")
	)
	(via
		(at 172.424852 -306.824888)
		(size 0.4064)
		(drill 0.2032)
		(layers "F.Cu" "B.Cu")
		(net "GND")
	)
	(via
		(at 280.449782 -276.899878)
		(size 0.4064)
		(drill 0.2032)
		(layers "F.Cu" "B.Cu")
		(net "GND")
	)
	(via
		(at 259.868924 -283.131514)
		(size 0.508)
		(drill 0.254)
		(layers "F.Cu" "B.Cu")
		(net "GND")
	)
	(via
		(at 295.727882 -371.140228)
		(size 0.508)
		(drill 0.254)
		(layers "F.Cu" "B.Cu")
		(net "GND")
	)
	(via
		(at 73.960228 -21.37156)
		(size 0.508)
		(drill 0.254)
		(layers "F.Cu" "B.Cu")
		(net "GND")
	)
	(via
		(at 324.101968 -57.461404)
		(size 0.508)
		(drill 0.254)
		(layers "F.Cu" "B.Cu")
		(net "GND")
	)
	(via
		(at 28.557982 -283.131514)
		(size 0.508)
		(drill 0.254)
		(layers "F.Cu" "B.Cu")
		(net "GND")
	)
	(via
		(at 465.306156 -252.190758)
		(size 0.508)
		(drill 0.254)
		(layers "F.Cu" "B.Cu")
		(net "GND")
	)
	(via
		(at 152.94991 -313.949842)
		(size 0.4064)
		(drill 0.2032)
		(layers "F.Cu" "B.Cu")
		(net "GND")
	)
	(via
		(at 4.268724 -289.23107)
		(size 0.508)
		(drill 0.254)
		(layers "F.Cu" "B.Cu")
		(net "GND")
	)
	(via
		(at 433.492656 -6.292596)
		(size 0.508)
		(drill 0.254)
		(layers "F.Cu" "B.Cu")
		(net "GND")
	)
	(via
		(at 38.347904 -372.240302)
		(size 0.508)
		(drill 0.254)
		(layers "F.Cu" "B.Cu")
		(net "GND")
	)
	(via
		(at 51.63312 -104.244902)
		(size 0.508)
		(drill 0.254)
		(layers "F.Cu" "B.Cu")
		(net "GND")
	)
	(via
		(at 87.648796 -33.19018)
		(size 0.508)
		(drill 0.254)
		(layers "F.Cu" "B.Cu")
		(net "GND")
	)
	(via
		(at 343.394792 -358.391714)
		(size 0.4572)
		(drill 0.254)
		(layers "F.Cu" "B.Cu")
		(net "GND")
	)
	(via
		(at 124.147834 -378.94006)
		(size 0.4572)
		(drill 0.254)
		(layers "F.Cu" "B.Cu")
		(net "GND")
	)
	(via
		(at 331.880718 -102.095046)
		(size 0.508)
		(drill 0.254)
		(layers "F.Cu" "B.Cu")
		(net "GND")
	)
	(via
		(at 42.074846 -288.774886)
		(size 0.4064)
		(drill 0.2032)
		(layers "F.Cu" "B.Cu")
		(net "GND")
	)
	(via
		(at 188.279786 -111.750602)
		(size 0.508)
		(drill 0.254)
		(layers "F.Cu" "B.Cu")
		(net "GND")
	)
	(via
		(at 76.138786 -48.33239)
		(size 0.508)
		(drill 0.254)
		(layers "F.Cu" "B.Cu")
		(net "GND")
	)
	(via
		(at 0.766318 -41.852342)
		(size 0.508)
		(drill 0.254)
		(layers "F.Cu" "B.Cu")
		(net "GND")
	)
	(via
		(at 276.649688 -309.199788)
		(size 0.4064)
		(drill 0.2032)
		(layers "F.Cu" "B.Cu")
		(net "GND")
	)
	(via
		(at 41.599866 -300.649894)
		(size 0.4064)
		(drill 0.2032)
		(layers "F.Cu" "B.Cu")
		(net "GND")
	)
	(via
		(at 154.375104 -274.524978)
		(size 0.4064)
		(drill 0.2032)
		(layers "F.Cu" "B.Cu")
		(net "GND")
	)
	(via
		(at 221.42323 -56.353456)
		(size 0.508)
		(drill 0.254)
		(layers "F.Cu" "B.Cu")
		(net "GND")
	)
	(via
		(at 273.91741 -355.366066)
		(size 0.4572)
		(drill 0.254)
		(layers "F.Cu" "B.Cu")
		(net "GND")
	)
	(via
		(at 388.127748 -404.940262)
		(size 0.508)
		(drill 0.254)
		(layers "F.Cu" "B.Cu")
		(net "GND")
	)
	(via
		(at 289.46221 -343.073482)
		(size 0.4572)
		(drill 0.254)
		(layers "F.Cu" "B.Cu")
		(net "GND")
	)
	(via
		(at 313.699906 -275.949918)
		(size 0.4064)
		(drill 0.2032)
		(layers "F.Cu" "B.Cu")
		(net "GND")
	)
	(via
		(at 339.513926 -293.424102)
		(size 0.508)
		(drill 0.254)
		(layers "F.Cu" "B.Cu")
		(net "GND")
	)
	(via
		(at 420.23919 -28.05303)
		(size 0.508)
		(drill 0.254)
		(layers "F.Cu" "B.Cu")
		(net "GND")
	)
	(via
		(at 0.77089 -400.821144)
		(size 0.508)
		(drill 0.254)
		(layers "F.Cu" "B.Cu")
		(net "GND")
	)
	(via
		(at 397.120872 -354.098098)
		(size 0.4572)
		(drill 0.254)
		(layers "F.Cu" "B.Cu")
		(net "GND")
	)
	(via
		(at 393.351766 -106.045)
		(size 0.508)
		(drill 0.254)
		(layers "F.Cu" "B.Cu")
		(net "GND")
	)
	(via
		(at 47.77486 -284.024832)
		(size 0.4064)
		(drill 0.2032)
		(layers "F.Cu" "B.Cu")
		(net "GND")
	)
	(via
		(at 420.532306 -114.812572)
		(size 0.508)
		(drill 0.254)
		(layers "F.Cu" "B.Cu")
		(net "GND")
	)
	(via
		(at 414.202118 -57.461404)
		(size 0.508)
		(drill 0.254)
		(layers "F.Cu" "B.Cu")
		(net "GND")
	)
	(via
		(at 228.667818 -219.504006)
		(size 0.4572)
		(drill 0.254)
		(layers "F.Cu" "B.Cu")
		(net "GND")
	)
	(via
		(at 339.67801 -282.910788)
		(size 0.49022)
		(drill 0.254)
		(layers "F.Cu" "B.Cu")
		(net "GND")
	)
	(via
		(at 402.724874 -300.174914)
		(size 0.4064)
		(drill 0.2032)
		(layers "F.Cu" "B.Cu")
		(net "GND")
	)
	(via
		(at 37.324538 -298.27474)
		(size 0.4064)
		(drill 0.2032)
		(layers "F.Cu" "B.Cu")
		(net "GND")
	)
	(via
		(at 72.15505 -96.901)
		(size 0.508)
		(drill 0.254)
		(layers "F.Cu" "B.Cu")
		(net "GND")
	)
	(via
		(at 60.032646 -86.214712)
		(size 0.508)
		(drill 0.254)
		(layers "F.Cu" "B.Cu")
		(net "GND")
	)
	(via
		(at 180.02504 -294.4749)
		(size 0.4064)
		(drill 0.2032)
		(layers "F.Cu" "B.Cu")
		(net "GND")
	)
	(via
		(at 429.800004 -280.699718)
		(size 0.4064)
		(drill 0.2032)
		(layers "F.Cu" "B.Cu")
		(net "GND")
	)
	(via
		(at 57.274968 -303.974754)
		(size 0.4064)
		(drill 0.2032)
		(layers "F.Cu" "B.Cu")
		(net "GND")
	)
	(via
		(at 332.217776 -355.366066)
		(size 0.4572)
		(drill 0.254)
		(layers "F.Cu" "B.Cu")
		(net "GND")
	)
	(via
		(at 411.444186 -213.237826)
		(size 0.508)
		(drill 0.254)
		(layers "F.Cu" "B.Cu")
		(net "GND")
	)
	(via
		(at 67.66687 -125.435106)
		(size 0.508)
		(drill 0.254)
		(layers "F.Cu" "B.Cu")
		(net "GND")
	)
	(via
		(at 155.572206 -239.020096)
		(size 0.508)
		(drill 0.254)
		(layers "F.Cu" "B.Cu")
		(net "GND")
	)
	(via
		(at 448.348862 -105.057194)
		(size 0.508)
		(drill 0.254)
		(layers "F.Cu" "B.Cu")
		(net "GND")
	)
	(via
		(at 185.010044 -343.073482)
		(size 0.4572)
		(drill 0.254)
		(layers "F.Cu" "B.Cu")
		(net "GND")
	)
	(via
		(at 232.854246 -276.519386)
		(size 0.508)
		(drill 0.254)
		(layers "F.Cu" "B.Cu")
		(net "GND")
	)
	(via
		(at 68.6054 -240.411)
		(size 0.508)
		(drill 0.254)
		(layers "F.Cu" "B.Cu")
		(net "GND")
	)
	(via
		(at 192.850008 -275.949918)
		(size 0.4064)
		(drill 0.2032)
		(layers "F.Cu" "B.Cu")
		(net "GND")
	)
	(via
		(at 33.947862 -400.938492)
		(size 0.508)
		(drill 0.254)
		(layers "F.Cu" "B.Cu")
		(net "GND")
	)
	(via
		(at 298.78909 -347.951806)
		(size 0.4572)
		(drill 0.254)
		(layers "F.Cu" "B.Cu")
		(net "GND")
	)
	(via
		(at 291.84981 -281.649932)
		(size 0.4064)
		(drill 0.2032)
		(layers "F.Cu" "B.Cu")
		(net "GND")
	)
	(via
		(at 308.474872 -300.174914)
		(size 0.4064)
		(drill 0.2032)
		(layers "F.Cu" "B.Cu")
		(net "GND")
	)
	(via
		(at 311.969404 -64.102234)
		(size 0.508)
		(drill 0.254)
		(layers "F.Cu" "B.Cu")
		(net "GND")
	)
	(via
		(at 421.53332 -349.219774)
		(size 0.4572)
		(drill 0.254)
		(layers "F.Cu" "B.Cu")
		(net "GND")
	)
	(via
		(at 7.095236 -308.028594)
		(size 0.508)
		(drill 0.254)
		(layers "F.Cu" "B.Cu")
		(net "GND")
	)
	(via
		(at 315.60008 -310.149748)
		(size 0.4064)
		(drill 0.2032)
		(layers "F.Cu" "B.Cu")
		(net "GND")
	)
	(via
		(at 58.224928 -289.724846)
		(size 0.4064)
		(drill 0.2032)
		(layers "F.Cu" "B.Cu")
		(net "GND")
	)
	(via
		(at 229.288848 -110.930436)
		(size 0.508)
		(drill 0.254)
		(layers "F.Cu" "B.Cu")
		(net "GND")
	)
	(via
		(at 386.701792 -135.643112)
		(size 0.508)
		(drill 0.254)
		(layers "F.Cu" "B.Cu")
		(net "GND")
	)
	(via
		(at 172.424852 -305.874928)
		(size 0.4064)
		(drill 0.2032)
		(layers "F.Cu" "B.Cu")
		(net "GND")
	)
	(via
		(at 48.768 -417.82492)
		(size 0.508)
		(drill 0.254)
		(layers "F.Cu" "B.Cu")
		(net "GND")
	)
	(via
		(at 291.32784 -406.141936)
		(size 0.508)
		(drill 0.254)
		(layers "F.Cu" "B.Cu")
		(net "GND")
	)
	(via
		(at 300.874684 -284.974792)
		(size 0.4064)
		(drill 0.2032)
		(layers "F.Cu" "B.Cu")
		(net "GND")
	)
	(via
		(at 298.78909 -346.09913)
		(size 0.4572)
		(drill 0.254)
		(layers "F.Cu" "B.Cu")
		(net "GND")
	)
	(via
		(at 105.00233 -332.862174)
		(size 0.508)
		(drill 0.254)
		(layers "F.Cu" "B.Cu")
		(net "GND")
	)
	(via
		(at 235.640626 -47.895256)
		(size 0.508)
		(drill 0.254)
		(layers "F.Cu" "B.Cu")
		(net "GND")
	)
	(via
		(at 405.575008 -300.174914)
		(size 0.4064)
		(drill 0.2032)
		(layers "F.Cu" "B.Cu")
		(net "GND")
	)
	(via
		(at 450.798946 -284.764988)
		(size 0.508)
		(drill 0.254)
		(layers "F.Cu" "B.Cu")
		(net "GND")
	)
	(via
		(at 90.039444 -95.801942)
		(size 0.508)
		(drill 0.254)
		(layers "F.Cu" "B.Cu")
		(net "GND")
	)
	(via
		(at 97.938336 -114.310414)
		(size 0.508)
		(drill 0.254)
		(layers "F.Cu" "B.Cu")
		(net "GND")
	)
	(via
		(at 50.624994 -285.924752)
		(size 0.4064)
		(drill 0.2032)
		(layers "F.Cu" "B.Cu")
		(net "GND")
	)
	(via
		(at 424.09999 -282.599892)
		(size 0.4064)
		(drill 0.2032)
		(layers "F.Cu" "B.Cu")
		(net "GND")
	)
	(via
		(at 126.837948 -342.439498)
		(size 0.4064)
		(drill 0.2032)
		(layers "F.Cu" "B.Cu")
		(net "GND")
	)
	(via
		(at 403.338792 -343.073482)
		(size 0.4572)
		(drill 0.254)
		(layers "F.Cu" "B.Cu")
		(net "GND")
	)
	(via
		(at 127.33528 -289.41649)
		(size 0.508)
		(drill 0.254)
		(layers "F.Cu" "B.Cu")
		(net "GND")
	)
	(via
		(at 197.125082 -296.37482)
		(size 0.4064)
		(drill 0.2032)
		(layers "F.Cu" "B.Cu")
		(net "GND")
	)
	(via
		(at 186.200034 -318.699896)
		(size 0.4064)
		(drill 0.2032)
		(layers "F.Cu" "B.Cu")
		(net "GND")
	)
	(via
		(at 101.832156 -193.71945)
		(size 0.508)
		(drill 0.254)
		(layers "F.Cu" "B.Cu")
		(net "GND")
	)
	(via
		(at 312.749692 -314.899802)
		(size 0.4064)
		(drill 0.2032)
		(layers "F.Cu" "B.Cu")
		(net "GND")
	)
	(via
		(at 391.324846 -289.724846)
		(size 0.4064)
		(drill 0.2032)
		(layers "F.Cu" "B.Cu")
		(net "GND")
	)
	(via
		(at 287.612074 -355.366066)
		(size 0.4572)
		(drill 0.254)
		(layers "F.Cu" "B.Cu")
		(net "GND")
	)
	(via
		(at 374.493536 -283.131514)
		(size 0.508)
		(drill 0.254)
		(layers "F.Cu" "B.Cu")
		(net "GND")
	)
	(via
		(at 144.65808 -283.131514)
		(size 0.508)
		(drill 0.254)
		(layers "F.Cu" "B.Cu")
		(net "GND")
	)
	(via
		(at 315.740288 -131.514596)
		(size 0.508)
		(drill 0.254)
		(layers "F.Cu" "B.Cu")
		(net "GND")
	)
	(via
		(at 231.867456 -220.303852)
		(size 0.4572)
		(drill 0.254)
		(layers "F.Cu" "B.Cu")
		(net "GND")
	)
	(via
		(at 336.805524 -351.611438)
		(size 0.4064)
		(drill 0.2032)
		(layers "F.Cu" "B.Cu")
		(net "GND")
	)
	(via
		(at 113.815368 -95.44558)
		(size 0.508)
		(drill 0.254)
		(layers "F.Cu" "B.Cu")
		(net "GND")
	)
	(via
		(at 66.299842 -313.949842)
		(size 0.4064)
		(drill 0.2032)
		(layers "F.Cu" "B.Cu")
		(net "GND")
	)
	(via
		(at 305.624738 -298.27474)
		(size 0.4064)
		(drill 0.2032)
		(layers "F.Cu" "B.Cu")
		(net "GND")
	)
	(via
		(at 108.097828 -328.102722)
		(size 0.508)
		(drill 0.254)
		(layers "F.Cu" "B.Cu")
		(net "GND")
	)
	(via
		(at 117.547644 -406.040336)
		(size 0.4572)
		(drill 0.254)
		(layers "F.Cu" "B.Cu")
		(net "GND")
	)
	(via
		(at 122.2502 -349.219774)
		(size 0.4572)
		(drill 0.254)
		(layers "F.Cu" "B.Cu")
		(net "GND")
	)
	(via
		(at 276.782022 -58.238644)
		(size 0.508)
		(drill 0.254)
		(layers "F.Cu" "B.Cu")
		(net "GND")
	)
	(via
		(at 80.07477 -294.4749)
		(size 0.4064)
		(drill 0.2032)
		(layers "F.Cu" "B.Cu")
		(net "GND")
	)
	(via
		(at 188.574934 -292.574726)
		(size 0.4064)
		(drill 0.2032)
		(layers "F.Cu" "B.Cu")
		(net "GND")
	)
	(via
		(at 198.550022 -284.499812)
		(size 0.4064)
		(drill 0.2032)
		(layers "F.Cu" "B.Cu")
		(net "GND")
	)
	(via
		(at 151.859488 -119.026686)
		(size 0.508)
		(drill 0.254)
		(layers "F.Cu" "B.Cu")
		(net "GND")
	)
	(via
		(at 415.074862 -302.074834)
		(size 0.4064)
		(drill 0.2032)
		(layers "F.Cu" "B.Cu")
		(net "GND")
	)
	(via
		(at 191.008 -417.82492)
		(size 0.508)
		(drill 0.254)
		(layers "F.Cu" "B.Cu")
		(net "GND")
	)
	(via
		(at 390.327896 -402.140166)
		(size 0.508)
		(drill 0.254)
		(layers "F.Cu" "B.Cu")
		(net "GND")
	)
	(via
		(at 375.358152 -349.219774)
		(size 0.4572)
		(drill 0.254)
		(layers "F.Cu" "B.Cu")
		(net "GND")
	)
	(via
		(at 126.347728 -380.040134)
		(size 0.4572)
		(drill 0.254)
		(layers "F.Cu" "B.Cu")
		(net "GND")
	)
	(via
		(at 221.96679 -86.586568)
		(size 0.508)
		(drill 0.254)
		(layers "F.Cu" "B.Cu")
		(net "GND")
	)
	(via
		(at 190.681356 -34.718498)
		(size 0.508)
		(drill 0.254)
		(layers "F.Cu" "B.Cu")
		(net "GND")
	)
	(via
		(at 298.78909 -350.977454)
		(size 0.4572)
		(drill 0.254)
		(layers "F.Cu" "B.Cu")
		(net "GND")
	)
	(via
		(at 401.15236 -102.445058)
		(size 0.508)
		(drill 0.254)
		(layers "F.Cu" "B.Cu")
		(net "GND")
	)
	(via
		(at 159.72282 -23.880318)
		(size 0.508)
		(drill 0.254)
		(layers "F.Cu" "B.Cu")
		(net "GND")
	)
	(via
		(at 40.174926 -275.474938)
		(size 0.4064)
		(drill 0.2032)
		(layers "F.Cu" "B.Cu")
		(net "GND")
	)
	(via
		(at 297.549824 -279.749758)
		(size 0.4064)
		(drill 0.2032)
		(layers "F.Cu" "B.Cu")
		(net "GND")
	)
	(via
		(at 384.059684 -123.885452)
		(size 0.508)
		(drill 0.254)
		(layers "F.Cu" "B.Cu")
		(net "GND")
	)
	(via
		(at 173.850046 -279.749758)
		(size 0.4064)
		(drill 0.2032)
		(layers "F.Cu" "B.Cu")
		(net "GND")
	)
	(via
		(at 68.199762 -312.999882)
		(size 0.4064)
		(drill 0.2032)
		(layers "F.Cu" "B.Cu")
		(net "GND")
	)
	(via
		(at 391.324846 -300.174914)
		(size 0.4064)
		(drill 0.2032)
		(layers "F.Cu" "B.Cu")
		(net "GND")
	)
	(via
		(at 394.011912 -352.245422)
		(size 0.4572)
		(drill 0.254)
		(layers "F.Cu" "B.Cu")
		(net "GND")
	)
	(via
		(at 304.527712 -373.838724)
		(size 0.508)
		(drill 0.254)
		(layers "F.Cu" "B.Cu")
		(net "GND")
	)
	(via
		(at 48.54575 -153.0096)
		(size 0.508)
		(drill 0.254)
		(layers "F.Cu" "B.Cu")
		(net "GND")
	)
	(via
		(at 387.999986 -300.649894)
		(size 0.4064)
		(drill 0.2032)
		(layers "F.Cu" "B.Cu")
		(net "GND")
	)
	(via
		(at 76.27493 -297.32478)
		(size 0.4064)
		(drill 0.2032)
		(layers "F.Cu" "B.Cu")
		(net "GND")
	)
	(via
		(at 67.39255 -343.073482)
		(size 0.4572)
		(drill 0.254)
		(layers "F.Cu" "B.Cu")
		(net "GND")
	)
	(via
		(at 55.374794 -287.824926)
		(size 0.4064)
		(drill 0.2032)
		(layers "F.Cu" "B.Cu")
		(net "GND")
	)
	(via
		(at 359.016808 -163.021518)
		(size 0.508)
		(drill 0.254)
		(layers "F.Cu" "B.Cu")
		(net "GND")
	)
	(via
		(at 418.927788 -377.738386)
		(size 0.508)
		(drill 0.254)
		(layers "F.Cu" "B.Cu")
		(net "GND")
	)
	(via
		(at 393.22502 -289.724846)
		(size 0.4064)
		(drill 0.2032)
		(layers "F.Cu" "B.Cu")
		(net "GND")
	)
	(via
		(at 269.94485 -29.589984)
		(size 0.508)
		(drill 0.254)
		(layers "F.Cu" "B.Cu")
		(net "GND")
	)
	(via
		(at 84.54771 -377.738386)
		(size 0.508)
		(drill 0.254)
		(layers "F.Cu" "B.Cu")
		(net "GND")
	)
	(via
		(at 285.369 -86.106)
		(size 0.508)
		(drill 0.254)
		(layers "F.Cu" "B.Cu")
		(net "GND")
	)
	(via
		(at 46.34992 -301.599854)
		(size 0.4064)
		(drill 0.2032)
		(layers "F.Cu" "B.Cu")
		(net "GND")
	)
	(via
		(at 328.396092 -60.099194)
		(size 0.508)
		(drill 0.254)
		(layers "F.Cu" "B.Cu")
		(net "GND")
	)
	(via
		(at 330.927964 -372.341902)
		(size 0.508)
		(drill 0.254)
		(layers "F.Cu" "B.Cu")
		(net "GND")
	)
	(via
		(at 278.549862 -275.949918)
		(size 0.4064)
		(drill 0.2032)
		(layers "F.Cu" "B.Cu")
		(net "GND")
	)
	(via
		(at 31.199328 -348.58579)
		(size 0.4064)
		(drill 0.2032)
		(layers "F.Cu" "B.Cu")
		(net "GND")
	)
	(via
		(at 159.347916 -398.34185)
		(size 0.508)
		(drill 0.254)
		(layers "F.Cu" "B.Cu")
		(net "GND")
	)
	(via
		(at 158.174944 -286.874966)
		(size 0.4064)
		(drill 0.2032)
		(layers "F.Cu" "B.Cu")
		(net "GND")
	)
	(via
		(at 80.147922 -410.041852)
		(size 0.508)
		(drill 0.254)
		(layers "F.Cu" "B.Cu")
		(net "GND")
	)
	(via
		(at 173.850046 -310.149748)
		(size 0.4064)
		(drill 0.2032)
		(layers "F.Cu" "B.Cu")
		(net "GND")
	)
	(via
		(at 419.349936 -315.849762)
		(size 0.4064)
		(drill 0.2032)
		(layers "F.Cu" "B.Cu")
		(net "GND")
	)
	(via
		(at 115.34775 -384.041904)
		(size 0.4572)
		(drill 0.254)
		(layers "F.Cu" "B.Cu")
		(net "GND")
	)
	(via
		(at 192.850008 -304.449734)
		(size 0.4064)
		(drill 0.2032)
		(layers "F.Cu" "B.Cu")
		(net "GND")
	)
	(via
		(at 29.72054 -343.073482)
		(size 0.4572)
		(drill 0.254)
		(layers "F.Cu" "B.Cu")
		(net "GND")
	)
	(via
		(at 389.27278 -348.58579)
		(size 0.4064)
		(drill 0.2032)
		(layers "F.Cu" "B.Cu")
		(net "GND")
	)
	(via
		(at 413.465264 -354.074222)
		(size 0.4572)
		(drill 0.254)
		(layers "F.Cu" "B.Cu")
		(net "GND")
	)
	(via
		(at 397.818864 -123.878594)
		(size 0.508)
		(drill 0.254)
		(layers "F.Cu" "B.Cu")
		(net "GND")
	)
	(via
		(at 52.049934 -316.799722)
		(size 0.4064)
		(drill 0.2032)
		(layers "F.Cu" "B.Cu")
		(net "GND")
	)
	(via
		(at 373.200422 -108.91901)
		(size 0.508)
		(drill 0.254)
		(layers "F.Cu" "B.Cu")
		(net "GND")
	)
	(via
		(at 274.480782 -25.990042)
		(size 0.508)
		(drill 0.254)
		(layers "F.Cu" "B.Cu")
		(net "GND")
	)
	(via
		(at 341.544656 -346.09913)
		(size 0.4572)
		(drill 0.254)
		(layers "F.Cu" "B.Cu")
		(net "GND")
	)
	(via
		(at 165.947852 -409.940252)
		(size 0.508)
		(drill 0.254)
		(layers "F.Cu" "B.Cu")
		(net "GND")
	)
	(via
		(at 295.174924 -300.174914)
		(size 0.4064)
		(drill 0.2032)
		(layers "F.Cu" "B.Cu")
		(net "GND")
	)
	(via
		(at 397.49222 -351.611438)
		(size 0.4064)
		(drill 0.2032)
		(layers "F.Cu" "B.Cu")
		(net "GND")
	)
	(via
		(at 348.355158 -279.086818)
		(size 0.508)
		(drill 0.254)
		(layers "F.Cu" "B.Cu")
		(net "GND")
	)
	(via
		(at 314.649866 -311.099962)
		(size 0.4064)
		(drill 0.2032)
		(layers "F.Cu" "B.Cu")
		(net "GND")
	)
	(via
		(at 9.0551 -122.931428)
		(size 0.508)
		(drill 0.254)
		(layers "F.Cu" "B.Cu")
		(net "GND")
	)
	(via
		(at 153.89987 -305.399948)
		(size 0.4064)
		(drill 0.2032)
		(layers "F.Cu" "B.Cu")
		(net "GND")
	)
	(via
		(at 432.12766 -382.84023)
		(size 0.508)
		(drill 0.254)
		(layers "F.Cu" "B.Cu")
		(net "GND")
	)
	(via
		(at 181.912514 -120.035066)
		(size 0.508)
		(drill 0.254)
		(layers "F.Cu" "B.Cu")
		(net "GND")
	)
	(via
		(at 179.163472 -342.439498)
		(size 0.4064)
		(drill 0.2032)
		(layers "F.Cu" "B.Cu")
		(net "GND")
	)
	(via
		(at 217.333068 -287.105344)
		(size 0.508)
		(drill 0.254)
		(layers "F.Cu" "B.Cu")
		(net "GND")
	)
	(via
		(at 62.433454 -344.831162)
		(size 0.4572)
		(drill 0.254)
		(layers "F.Cu" "B.Cu")
		(net "GND")
	)
	(via
		(at 32.846772 -1.135126)
		(size 0.508)
		(drill 0.254)
		(layers "F.Cu" "B.Cu")
		(net "GND")
	)
	(via
		(at 432.12766 -384.041904)
		(size 0.508)
		(drill 0.254)
		(layers "F.Cu" "B.Cu")
		(net "GND")
	)
	(via
		(at 273.546062 -354.732082)
		(size 0.4064)
		(drill 0.2032)
		(layers "F.Cu" "B.Cu")
		(net "GND")
	)
	(via
		(at 302.299878 -273.099784)
		(size 0.4064)
		(drill 0.2032)
		(layers "F.Cu" "B.Cu")
		(net "GND")
	)
	(via
		(at 187.149994 -280.699718)
		(size 0.4064)
		(drill 0.2032)
		(layers "F.Cu" "B.Cu")
		(net "GND")
	)
	(via
		(at 52.999894 -281.649932)
		(size 0.4064)
		(drill 0.2032)
		(layers "F.Cu" "B.Cu")
		(net "GND")
	)
	(via
		(at 433.96916 -349.219774)
		(size 0.4572)
		(drill 0.254)
		(layers "F.Cu" "B.Cu")
		(net "GND")
	)
	(via
		(at 37.324792 -290.674806)
		(size 0.4064)
		(drill 0.2032)
		(layers "F.Cu" "B.Cu")
		(net "GND")
	)
	(via
		(at 241.255042 -122.931428)
		(size 0.508)
		(drill 0.254)
		(layers "F.Cu" "B.Cu")
		(net "GND")
	)
	(via
		(at 341.744554 -177.554128)
		(size 0.508)
		(drill 0.254)
		(layers "F.Cu" "B.Cu")
		(net "GND")
	)
	(via
		(at 392.753088 -358.391714)
		(size 0.4572)
		(drill 0.254)
		(layers "F.Cu" "B.Cu")
		(net "GND")
	)
	(via
		(at 268.722094 -236.707426)
		(size 0.508)
		(drill 0.254)
		(layers "F.Cu" "B.Cu")
		(net "GND")
	)
	(via
		(at 161.975038 -296.37482)
		(size 0.4064)
		(drill 0.2032)
		(layers "F.Cu" "B.Cu")
		(net "GND")
	)
	(via
		(at 38.401752 -99.116642)
		(size 0.508)
		(drill 0.254)
		(layers "F.Cu" "B.Cu")
		(net "GND")
	)
	(via
		(at 275.699728 -310.149748)
		(size 0.4064)
		(drill 0.2032)
		(layers "F.Cu" "B.Cu")
		(net "GND")
	)
	(via
		(at 439.815732 -342.439498)
		(size 0.4064)
		(drill 0.2032)
		(layers "F.Cu" "B.Cu")
		(net "GND")
	)
	(via
		(at 195.053966 -24.61006)
		(size 0.508)
		(drill 0.254)
		(layers "F.Cu" "B.Cu")
		(net "GND")
	)
	(via
		(at 196.649848 -281.649932)
		(size 0.4064)
		(drill 0.2032)
		(layers "F.Cu" "B.Cu")
		(net "GND")
	)
	(via
		(at 174.800006 -314.899802)
		(size 0.4064)
		(drill 0.2032)
		(layers "F.Cu" "B.Cu")
		(net "GND")
	)
	(via
		(at 168.148 -377.738386)
		(size 0.508)
		(drill 0.254)
		(layers "F.Cu" "B.Cu")
		(net "GND")
	)
	(via
		(at 166.249858 -312.049922)
		(size 0.4064)
		(drill 0.2032)
		(layers "F.Cu" "B.Cu")
		(net "GND")
	)
	(via
		(at 429.381412 -357.75773)
		(size 0.4064)
		(drill 0.2032)
		(layers "F.Cu" "B.Cu")
		(net "GND")
	)
	(via
		(at 288.853118 -49.574704)
		(size 0.508)
		(drill 0.254)
		(layers "F.Cu" "B.Cu")
		(net "GND")
	)
	(via
		(at 270.474948 -275.474938)
		(size 0.4064)
		(drill 0.2032)
		(layers "F.Cu" "B.Cu")
		(net "GND")
	)
	(via
		(at 61.17463 -346.09913)
		(size 0.4572)
		(drill 0.254)
		(layers "F.Cu" "B.Cu")
		(net "GND")
	)
	(via
		(at 98.7044 -354.457)
		(size 0.508)
		(drill 0.254)
		(layers "F.Cu" "B.Cu")
		(net "GND")
	)
	(via
		(at 434.755036 -29.590238)
		(size 0.508)
		(drill 0.254)
		(layers "F.Cu" "B.Cu")
		(net "GND")
	)
	(via
		(at 313.699906 -274.049744)
		(size 0.4064)
		(drill 0.2032)
		(layers "F.Cu" "B.Cu")
		(net "GND")
	)
	(via
		(at 410.799788 -313.949842)
		(size 0.4064)
		(drill 0.2032)
		(layers "F.Cu" "B.Cu")
		(net "GND")
	)
	(via
		(at 324.369684 -342.439498)
		(size 0.4064)
		(drill 0.2032)
		(layers "F.Cu" "B.Cu")
		(net "GND")
	)
	(via
		(at 382.791716 -105.78211)
		(size 0.508)
		(drill 0.254)
		(layers "F.Cu" "B.Cu")
		(net "GND")
	)
	(via
		(at 402.079968 -347.951806)
		(size 0.4572)
		(drill 0.254)
		(layers "F.Cu" "B.Cu")
		(net "GND")
	)
	(via
		(at 77.699616 -276.899878)
		(size 0.4064)
		(drill 0.2032)
		(layers "F.Cu" "B.Cu")
		(net "GND")
	)
	(via
		(at 141.793214 -202.282806)
		(size 0.508)
		(drill 0.254)
		(layers "F.Cu" "B.Cu")
		(net "GND")
	)
	(via
		(at 219.711016 -211.143342)
		(size 0.508)
		(drill 0.254)
		(layers "F.Cu" "B.Cu")
		(net "GND")
	)
	(via
		(at 373.658384 -253.45644)
		(size 0.508)
		(drill 0.254)
		(layers "F.Cu" "B.Cu")
		(net "GND")
	)
	(via
		(at 159.347916 -406.141936)
		(size 0.508)
		(drill 0.254)
		(layers "F.Cu" "B.Cu")
		(net "GND")
	)
	(via
		(at 16.352774 -283.1592)
		(size 0.508)
		(drill 0.254)
		(layers "F.Cu" "B.Cu")
		(net "GND")
	)
	(via
		(at 430.8602 -358.391714)
		(size 0.4572)
		(drill 0.254)
		(layers "F.Cu" "B.Cu")
		(net "GND")
	)
	(via
		(at 313.564016 -350.977454)
		(size 0.4572)
		(drill 0.254)
		(layers "F.Cu" "B.Cu")
		(net "GND")
	)
	(via
		(at 56.324754 -300.174914)
		(size 0.4064)
		(drill 0.2032)
		(layers "F.Cu" "B.Cu")
		(net "GND")
	)
	(via
		(at 198.550022 -277.849838)
		(size 0.4064)
		(drill 0.2032)
		(layers "F.Cu" "B.Cu")
		(net "GND")
	)
	(via
		(at 311.933844 -345.465146)
		(size 0.4064)
		(drill 0.2032)
		(layers "F.Cu" "B.Cu")
		(net "GND")
	)
	(via
		(at 183.189372 -188.501274)
		(size 0.508)
		(drill 0.254)
		(layers "F.Cu" "B.Cu")
		(net "GND")
	)
	(via
		(at 177.649886 -314.899802)
		(size 0.4064)
		(drill 0.2032)
		(layers "F.Cu" "B.Cu")
		(net "GND")
	)
	(via
		(at 341.927942 -408.738578)
		(size 0.508)
		(drill 0.254)
		(layers "F.Cu" "B.Cu")
		(net "GND")
	)
	(via
		(at 281.851862 -118.754906)
		(size 0.508)
		(drill 0.254)
		(layers "F.Cu" "B.Cu")
		(net "GND")
	)
	(via
		(at 313.224926 -292.574726)
		(size 0.4064)
		(drill 0.2032)
		(layers "F.Cu" "B.Cu")
		(net "GND")
	)
	(via
		(at 82.566002 -345.465146)
		(size 0.4064)
		(drill 0.2032)
		(layers "F.Cu" "B.Cu")
		(net "GND")
	)
	(via
		(at 36.984686 -151.045672)
		(size 0.508)
		(drill 0.254)
		(layers "F.Cu" "B.Cu")
		(net "GND")
	)
	(via
		(at 211.62899 -113.870486)
		(size 0.508)
		(drill 0.254)
		(layers "F.Cu" "B.Cu")
		(net "GND")
	)
	(via
		(at 403.199854 -278.799798)
		(size 0.4064)
		(drill 0.2032)
		(layers "F.Cu" "B.Cu")
		(net "GND")
	)
	(via
		(at 114.631216 -328.43343)
		(size 0.508)
		(drill 0.254)
		(layers "F.Cu" "B.Cu")
		(net "GND")
	)
	(via
		(at 33.200848 -354.732082)
		(size 0.4064)
		(drill 0.2032)
		(layers "F.Cu" "B.Cu")
		(net "GND")
	)
	(via
		(at 163.747958 -408.840178)
		(size 0.508)
		(drill 0.254)
		(layers "F.Cu" "B.Cu")
		(net "GND")
	)
	(via
		(at 52.049934 -274.999958)
		(size 0.4064)
		(drill 0.2032)
		(layers "F.Cu" "B.Cu")
		(net "GND")
	)
	(via
		(at 80.898238 -150.876762)
		(size 0.508)
		(drill 0.254)
		(layers "F.Cu" "B.Cu")
		(net "GND")
	)
	(via
		(at 296.610024 -23.554436)
		(size 0.508)
		(drill 0.254)
		(layers "F.Cu" "B.Cu")
		(net "GND")
	)
	(via
		(at 6.600952 -34.990278)
		(size 0.508)
		(drill 0.254)
		(layers "F.Cu" "B.Cu")
		(net "GND")
	)
	(via
		(at 370.990368 -349.219774)
		(size 0.4572)
		(drill 0.254)
		(layers "F.Cu" "B.Cu")
		(net "GND")
	)
	(via
		(at 79.82839 -352.245422)
		(size 0.4572)
		(drill 0.254)
		(layers "F.Cu" "B.Cu")
		(net "GND")
	)
	(via
		(at 393.7 -312.999882)
		(size 0.4064)
		(drill 0.2032)
		(layers "F.Cu" "B.Cu")
		(net "GND")
	)
	(via
		(at 188.119004 -352.245422)
		(size 0.4572)
		(drill 0.254)
		(layers "F.Cu" "B.Cu")
		(net "GND")
	)
	(via
		(at 426.000164 -273.099784)
		(size 0.4064)
		(drill 0.2032)
		(layers "F.Cu" "B.Cu")
		(net "GND")
	)
	(via
		(at 384.674872 -284.024832)
		(size 0.4064)
		(drill 0.2032)
		(layers "F.Cu" "B.Cu")
		(net "GND")
	)
	(via
		(at 14.802866 -74.624184)
		(size 0.508)
		(drill 0.254)
		(layers "F.Cu" "B.Cu")
		(net "GND")
	)
	(via
		(at 374.927876 -399.838418)
		(size 0.508)
		(drill 0.254)
		(layers "F.Cu" "B.Cu")
		(net "GND")
	)
	(via
		(at 170.049952 -274.999958)
		(size 0.4064)
		(drill 0.2032)
		(layers "F.Cu" "B.Cu")
		(net "GND")
	)
	(via
		(at 332.020418 -316.406784)
		(size 0.508)
		(drill 0.254)
		(layers "F.Cu" "B.Cu")
		(net "GND")
	)
	(via
		(at 365.785654 -63.218314)
		(size 0.508)
		(drill 0.254)
		(layers "F.Cu" "B.Cu")
		(net "GND")
	)
	(via
		(at 76.532232 -100.417884)
		(size 0.508)
		(drill 0.254)
		(layers "F.Cu" "B.Cu")
		(net "GND")
	)
	(via
		(at 112.105186 -285.953454)
		(size 0.508)
		(drill 0.254)
		(layers "F.Cu" "B.Cu")
		(net "GND")
	)
	(via
		(at 411.750002 -311.099962)
		(size 0.4064)
		(drill 0.2032)
		(layers "F.Cu" "B.Cu")
		(net "GND")
	)
	(via
		(at 425.04995 -314.899802)
		(size 0.4064)
		(drill 0.2032)
		(layers "F.Cu" "B.Cu")
		(net "GND")
	)
	(via
		(at 63.798196 -19.757136)
		(size 0.508)
		(drill 0.254)
		(layers "F.Cu" "B.Cu")
		(net "GND")
	)
	(via
		(at 189.049914 -276.899878)
		(size 0.4064)
		(drill 0.2032)
		(layers "F.Cu" "B.Cu")
		(net "GND")
	)
	(via
		(at 321.998086 -21.077936)
		(size 0.508)
		(drill 0.254)
		(layers "F.Cu" "B.Cu")
		(net "GND")
	)
	(via
		(at 287.574736 -303.974754)
		(size 0.4064)
		(drill 0.2032)
		(layers "F.Cu" "B.Cu")
		(net "GND")
	)
	(via
		(at 427.89983 -285.449772)
		(size 0.4064)
		(drill 0.2032)
		(layers "F.Cu" "B.Cu")
		(net "GND")
	)
	(via
		(at 341.544656 -357.123746)
		(size 0.4572)
		(drill 0.254)
		(layers "F.Cu" "B.Cu")
		(net "GND")
	)
	(via
		(at 388.898384 -253.45644)
		(size 0.508)
		(drill 0.254)
		(layers "F.Cu" "B.Cu")
		(net "GND")
	)
	(via
		(at 386.575046 -286.874966)
		(size 0.4064)
		(drill 0.2032)
		(layers "F.Cu" "B.Cu")
		(net "GND")
	)
	(via
		(at 427.727872 -404.940262)
		(size 0.508)
		(drill 0.254)
		(layers "F.Cu" "B.Cu")
		(net "GND")
	)
	(via
		(at 162.450018 -274.999958)
		(size 0.4064)
		(drill 0.2032)
		(layers "F.Cu" "B.Cu")
		(net "GND")
	)
	(via
		(at 315.60008 -283.550106)
		(size 0.4064)
		(drill 0.2032)
		(layers "F.Cu" "B.Cu")
		(net "GND")
	)
	(via
		(at 171.474892 -302.074834)
		(size 0.4064)
		(drill 0.2032)
		(layers "F.Cu" "B.Cu")
		(net "GND")
	)
	(via
		(at 96.581976 -58.238644)
		(size 0.508)
		(drill 0.254)
		(layers "F.Cu" "B.Cu")
		(net "GND")
	)
	(via
		(at 338.435696 -343.073482)
		(size 0.4572)
		(drill 0.254)
		(layers "F.Cu" "B.Cu")
		(net "GND")
	)
	(via
		(at 307.049932 -319.65011)
		(size 0.4064)
		(drill 0.2032)
		(layers "F.Cu" "B.Cu")
		(net "GND")
	)
	(via
		(at 73.61047 -354.098098)
		(size 0.4572)
		(drill 0.254)
		(layers "F.Cu" "B.Cu")
		(net "GND")
	)
	(via
		(at 333.127858 -385.141978)
		(size 0.508)
		(drill 0.254)
		(layers "F.Cu" "B.Cu")
		(net "GND")
	)
	(via
		(at 129.59461 -159.498792)
		(size 0.508)
		(drill 0.254)
		(layers "F.Cu" "B.Cu")
		(net "GND")
	)
	(via
		(at 82.347816 -407.24201)
		(size 0.508)
		(drill 0.254)
		(layers "F.Cu" "B.Cu")
		(net "GND")
	)
	(via
		(at 69.624956 -296.37482)
		(size 0.4064)
		(drill 0.2032)
		(layers "F.Cu" "B.Cu")
		(net "GND")
	)
	(via
		(at 402.069554 -64.102234)
		(size 0.508)
		(drill 0.254)
		(layers "F.Cu" "B.Cu")
		(net "GND")
	)
	(via
		(at 42.074846 -274.524978)
		(size 0.4064)
		(drill 0.2032)
		(layers "F.Cu" "B.Cu")
		(net "GND")
	)
	(via
		(at 170.524932 -284.974792)
		(size 0.4064)
		(drill 0.2032)
		(layers "F.Cu" "B.Cu")
		(net "GND")
	)
	(via
		(at 27.347926 -407.638504)
		(size 0.508)
		(drill 0.254)
		(layers "F.Cu" "B.Cu")
		(net "GND")
	)
	(via
		(at 343.2937 -221.986856)
		(size 0.4572)
		(drill 0.254)
		(layers "F.Cu" "B.Cu")
		(net "GND")
	)
	(via
		(at 70.831202 -60.099194)
		(size 0.508)
		(drill 0.254)
		(layers "F.Cu" "B.Cu")
		(net "GND")
	)
	(via
		(at 229.258876 -107.843574)
		(size 0.508)
		(drill 0.254)
		(layers "F.Cu" "B.Cu")
		(net "GND")
	)
	(via
		(at 374.927876 -372.341902)
		(size 0.508)
		(drill 0.254)
		(layers "F.Cu" "B.Cu")
		(net "GND")
	)
	(via
		(at 153.233628 -99.116642)
		(size 0.508)
		(drill 0.254)
		(layers "F.Cu" "B.Cu")
		(net "GND")
	)
	(via
		(at 296.938954 -347.951806)
		(size 0.4572)
		(drill 0.254)
		(layers "F.Cu" "B.Cu")
		(net "GND")
	)
	(via
		(at 189.999874 -273.099784)
		(size 0.4064)
		(drill 0.2032)
		(layers "F.Cu" "B.Cu")
		(net "GND")
	)
	(via
		(at 351.374964 -290.05149)
		(size 0.508)
		(drill 0.254)
		(layers "F.Cu" "B.Cu")
		(net "GND")
	)
	(via
		(at 190.060326 -21.37156)
		(size 0.508)
		(drill 0.254)
		(layers "F.Cu" "B.Cu")
		(net "GND")
	)
	(via
		(at 0.766318 -46.932342)
		(size 0.508)
		(drill 0.254)
		(layers "F.Cu" "B.Cu")
		(net "GND")
	)
	(via
		(at 57.087262 -371.508274)
		(size 0.4572)
		(drill 0.254)
		(layers "F.Cu" "B.Cu")
		(net "GND")
	)
	(via
		(at 404.625048 -296.37482)
		(size 0.4064)
		(drill 0.2032)
		(layers "F.Cu" "B.Cu")
		(net "GND")
	)
	(via
		(at 197.600062 -312.999882)
		(size 0.4064)
		(drill 0.2032)
		(layers "F.Cu" "B.Cu")
		(net "GND")
	)
	(via
		(at 356.120192 -31.390336)
		(size 0.508)
		(drill 0.254)
		(layers "F.Cu" "B.Cu")
		(net "GND")
	)
	(via
		(at 313.699906 -313.949842)
		(size 0.4064)
		(drill 0.2032)
		(layers "F.Cu" "B.Cu")
		(net "GND")
	)
	(via
		(at 298.499784 -278.799798)
		(size 0.4064)
		(drill 0.2032)
		(layers "F.Cu" "B.Cu")
		(net "GND")
	)
	(via
		(at 45.39996 -317.749936)
		(size 0.4064)
		(drill 0.2032)
		(layers "F.Cu" "B.Cu")
		(net "GND")
	)
	(via
		(at 258.92125 -198.896224)
		(size 0.508)
		(drill 0.254)
		(layers "F.Cu" "B.Cu")
		(net "GND")
	)
	(via
		(at 303.724818 -289.724846)
		(size 0.4064)
		(drill 0.2032)
		(layers "F.Cu" "B.Cu")
		(net "GND")
	)
	(via
		(at 417.450016 -316.799722)
		(size 0.4064)
		(drill 0.2032)
		(layers "F.Cu" "B.Cu")
		(net "GND")
	)
	(via
		(at 294.69969 -276.899878)
		(size 0.4064)
		(drill 0.2032)
		(layers "F.Cu" "B.Cu")
		(net "GND")
	)
	(via
		(at 442.580776 -34.990024)
		(size 0.508)
		(drill 0.254)
		(layers "F.Cu" "B.Cu")
		(net "GND")
	)
	(via
		(at 155.800044 -310.149748)
		(size 0.4064)
		(drill 0.2032)
		(layers "F.Cu" "B.Cu")
		(net "GND")
	)
	(via
		(at 168.148 -406.141936)
		(size 0.508)
		(drill 0.254)
		(layers "F.Cu" "B.Cu")
		(net "GND")
	)
	(via
		(at 190.950088 -307.299868)
		(size 0.4064)
		(drill 0.2032)
		(layers "F.Cu" "B.Cu")
		(net "GND")
	)
	(via
		(at 395.298676 -83.264756)
		(size 0.508)
		(drill 0.254)
		(layers "F.Cu" "B.Cu")
		(net "GND")
	)
	(via
		(at 179.55006 -279.749758)
		(size 0.4064)
		(drill 0.2032)
		(layers "F.Cu" "B.Cu")
		(net "GND")
	)
	(via
		(at 94.280736 -34.990024)
		(size 0.508)
		(drill 0.254)
		(layers "F.Cu" "B.Cu")
		(net "GND")
	)
	(via
		(at 429.325024 -300.174914)
		(size 0.4064)
		(drill 0.2032)
		(layers "F.Cu" "B.Cu")
		(net "GND")
	)
	(via
		(at 417.450016 -314.899802)
		(size 0.4064)
		(drill 0.2032)
		(layers "F.Cu" "B.Cu")
		(net "GND")
	)
	(via
		(at 372.006876 -0.762)
		(size 0.508)
		(drill 0.254)
		(layers "F.Cu" "B.Cu")
		(net "GND")
	)
	(via
		(at 335.326736 -355.366066)
		(size 0.4572)
		(drill 0.254)
		(layers "F.Cu" "B.Cu")
		(net "GND")
	)
	(via
		(at 317.044324 -354.732082)
		(size 0.4064)
		(drill 0.2032)
		(layers "F.Cu" "B.Cu")
		(net "GND")
	)
	(via
		(at 334.666336 -79.516732)
		(size 0.508)
		(drill 0.254)
		(layers "F.Cu" "B.Cu")
		(net "GND")
	)
	(via
		(at 388.127748 -403.738588)
		(size 0.508)
		(drill 0.254)
		(layers "F.Cu" "B.Cu")
		(net "GND")
	)
	(via
		(at 160.074864 -290.674806)
		(size 0.4064)
		(drill 0.2032)
		(layers "F.Cu" "B.Cu")
		(net "GND")
	)
	(via
		(at 168.20642 -354.074222)
		(size 0.4572)
		(drill 0.254)
		(layers "F.Cu" "B.Cu")
		(net "GND")
	)
	(via
		(at 170.049952 -275.949918)
		(size 0.4064)
		(drill 0.2032)
		(layers "F.Cu" "B.Cu")
		(net "GND")
	)
	(via
		(at 44.92498 -289.724846)
		(size 0.4064)
		(drill 0.2032)
		(layers "F.Cu" "B.Cu")
		(net "GND")
	)
	(via
		(at 241.848894 -31.390082)
		(size 0.508)
		(drill 0.254)
		(layers "F.Cu" "B.Cu")
		(net "GND")
	)
	(via
		(at 109.728 -417.82492)
		(size 0.508)
		(drill 0.254)
		(layers "F.Cu" "B.Cu")
		(net "GND")
	)
	(via
		(at 46.34992 -304.449734)
		(size 0.4064)
		(drill 0.2032)
		(layers "F.Cu" "B.Cu")
		(net "GND")
	)
	(via
		(at 123.972828 -292.789102)
		(size 0.508)
		(drill 0.254)
		(layers "F.Cu" "B.Cu")
		(net "GND")
	)
	(via
		(at 92.26423 -349.219774)
		(size 0.4572)
		(drill 0.254)
		(layers "F.Cu" "B.Cu")
		(net "GND")
	)
	(via
		(at 158.658052 -58.791094)
		(size 0.508)
		(drill 0.254)
		(layers "F.Cu" "B.Cu")
		(net "GND")
	)
	(via
		(at 255.171194 -396.556738)
		(size 0.508)
		(drill 0.254)
		(layers "F.Cu" "B.Cu")
		(net "GND")
	)
	(via
		(at 398.59966 -345.465146)
		(size 0.4064)
		(drill 0.2032)
		(layers "F.Cu" "B.Cu")
		(net "GND")
	)
	(via
		(at 377.12777 -385.141978)
		(size 0.508)
		(drill 0.254)
		(layers "F.Cu" "B.Cu")
		(net "GND")
	)
	(via
		(at 31.570676 -343.073482)
		(size 0.4572)
		(drill 0.254)
		(layers "F.Cu" "B.Cu")
		(net "GND")
	)
	(via
		(at 380.43104 -85.481922)
		(size 0.508)
		(drill 0.254)
		(layers "F.Cu" "B.Cu")
		(net "GND")
	)
	(via
		(at 377.12777 -399.441924)
		(size 0.508)
		(drill 0.254)
		(layers "F.Cu" "B.Cu")
		(net "GND")
	)
	(via
		(at 38.749986 -311.099962)
		(size 0.4064)
		(drill 0.2032)
		(layers "F.Cu" "B.Cu")
		(net "GND")
	)
	(via
		(at 63.449962 -312.049922)
		(size 0.4064)
		(drill 0.2032)
		(layers "F.Cu" "B.Cu")
		(net "GND")
	)
	(via
		(at 283.24429 -352.245422)
		(size 0.4572)
		(drill 0.254)
		(layers "F.Cu" "B.Cu")
		(net "GND")
	)
	(via
		(at 194.336924 -344.831162)
		(size 0.4572)
		(drill 0.254)
		(layers "F.Cu" "B.Cu")
		(net "GND")
	)
	(via
		(at 194.749928 -280.699718)
		(size 0.4064)
		(drill 0.2032)
		(layers "F.Cu" "B.Cu")
		(net "GND")
	)
	(via
		(at 266.202922 -290.294314)
		(size 0.508)
		(drill 0.254)
		(layers "F.Cu" "B.Cu")
		(net "GND")
	)
	(via
		(at 404.508208 -52.536852)
		(size 0.508)
		(drill 0.254)
		(layers "F.Cu" "B.Cu")
		(net "GND")
	)
	(via
		(at 351.288096 -292.781736)
		(size 0.508)
		(drill 0.254)
		(layers "F.Cu" "B.Cu")
		(net "GND")
	)
	(via
		(at 42.074846 -286.874966)
		(size 0.4064)
		(drill 0.2032)
		(layers "F.Cu" "B.Cu")
		(net "GND")
	)
	(via
		(at 341.657432 -305.008534)
		(size 0.508)
		(drill 0.254)
		(layers "F.Cu" "B.Cu")
		(net "GND")
	)
	(via
		(at 207.645 -193.04)
		(size 0.508)
		(drill 0.254)
		(layers "F.Cu" "B.Cu")
		(net "GND")
	)
	(via
		(at 188.587634 -26.360882)
		(size 0.508)
		(drill 0.254)
		(layers "F.Cu" "B.Cu")
		(net "GND")
	)
	(via
		(at 97.938336 -115.732814)
		(size 0.508)
		(drill 0.254)
		(layers "F.Cu" "B.Cu")
		(net "GND")
	)
	(via
		(at 139.540996 -45.853858)
		(size 0.508)
		(drill 0.254)
		(layers "F.Cu" "B.Cu")
		(net "GND")
	)
	(via
		(at 306.099718 -286.399732)
		(size 0.4064)
		(drill 0.2032)
		(layers "F.Cu" "B.Cu")
		(net "GND")
	)
	(via
		(at 94.488 -417.82492)
		(size 0.508)
		(drill 0.254)
		(layers "F.Cu" "B.Cu")
		(net "GND")
	)
	(via
		(at 15.1257 -128.193546)
		(size 0.508)
		(drill 0.254)
		(layers "F.Cu" "B.Cu")
		(net "GND")
	)
	(via
		(at 301.824898 -305.874928)
		(size 0.4064)
		(drill 0.2032)
		(layers "F.Cu" "B.Cu")
		(net "GND")
	)
	(via
		(at 116.03228 -343.073482)
		(size 0.4572)
		(drill 0.254)
		(layers "F.Cu" "B.Cu")
		(net "GND")
	)
	(via
		(at 43.974766 -282.124912)
		(size 0.4064)
		(drill 0.2032)
		(layers "F.Cu" "B.Cu")
		(net "GND")
	)
	(via
		(at 151.859488 -104.523286)
		(size 0.508)
		(drill 0.254)
		(layers "F.Cu" "B.Cu")
		(net "GND")
	)
	(via
		(at 430.274984 -299.224954)
		(size 0.4064)
		(drill 0.2032)
		(layers "F.Cu" "B.Cu")
		(net "GND")
	)
	(via
		(at 292.32479 -297.32478)
		(size 0.4064)
		(drill 0.2032)
		(layers "F.Cu" "B.Cu")
		(net "GND")
	)
	(via
		(at 171.31538 -344.831162)
		(size 0.4572)
		(drill 0.254)
		(layers "F.Cu" "B.Cu")
		(net "GND")
	)
	(via
		(at 143.891508 -305.334162)
		(size 0.508)
		(drill 0.254)
		(layers "F.Cu" "B.Cu")
		(net "GND")
	)
	(via
		(at 211.190078 -416.508438)
		(size 0.508)
		(drill 0.254)
		(layers "F.Cu" "B.Cu")
		(net "GND")
	)
	(via
		(at 305.149758 -312.049922)
		(size 0.4064)
		(drill 0.2032)
		(layers "F.Cu" "B.Cu")
		(net "GND")
	)
	(via
		(at 156.348938 -29.589984)
		(size 0.508)
		(drill 0.254)
		(layers "F.Cu" "B.Cu")
		(net "GND")
	)
	(via
		(at 287.612074 -349.219774)
		(size 0.4572)
		(drill 0.254)
		(layers "F.Cu" "B.Cu")
		(net "GND")
	)
	(via
		(at 14.7955 -314.247784)
		(size 0.508)
		(drill 0.254)
		(layers "F.Cu" "B.Cu")
		(net "GND")
	)
	(via
		(at 72.267064 -131.245102)
		(size 0.508)
		(drill 0.254)
		(layers "F.Cu" "B.Cu")
		(net "GND")
	)
	(via
		(at 159.599884 -273.099784)
		(size 0.4064)
		(drill 0.2032)
		(layers "F.Cu" "B.Cu")
		(net "GND")
	)
	(via
		(at 124.147834 -375.040144)
		(size 0.4572)
		(drill 0.254)
		(layers "F.Cu" "B.Cu")
		(net "GND")
	)
	(via
		(at 277.599902 -317.749936)
		(size 0.4064)
		(drill 0.2032)
		(layers "F.Cu" "B.Cu")
		(net "GND")
	)
	(via
		(at 302.327818 -406.040336)
		(size 0.508)
		(drill 0.254)
		(layers "F.Cu" "B.Cu")
		(net "GND")
	)
	(via
		(at 162.924998 -286.874966)
		(size 0.4064)
		(drill 0.2032)
		(layers "F.Cu" "B.Cu")
		(net "GND")
	)
	(via
		(at 161.975038 -299.224954)
		(size 0.4064)
		(drill 0.2032)
		(layers "F.Cu" "B.Cu")
		(net "GND")
	)
	(via
		(at 390.902952 -350.977454)
		(size 0.4572)
		(drill 0.254)
		(layers "F.Cu" "B.Cu")
		(net "GND")
	)
	(via
		(at 318.523112 -355.366066)
		(size 0.4572)
		(drill 0.254)
		(layers "F.Cu" "B.Cu")
		(net "GND")
	)
	(via
		(at 98.487484 -26.360882)
		(size 0.508)
		(drill 0.254)
		(layers "F.Cu" "B.Cu")
		(net "GND")
	)
	(via
		(at 321.260724 -354.732082)
		(size 0.4064)
		(drill 0.2032)
		(layers "F.Cu" "B.Cu")
		(net "GND")
	)
	(via
		(at 198.550022 -280.699718)
		(size 0.4064)
		(drill 0.2032)
		(layers "F.Cu" "B.Cu")
		(net "GND")
	)
	(via
		(at 343.511378 -291.32149)
		(size 0.508)
		(drill 0.254)
		(layers "F.Cu" "B.Cu")
		(net "GND")
	)
	(via
		(at 206.546958 -23.583646)
		(size 0.508)
		(drill 0.254)
		(layers "F.Cu" "B.Cu")
		(net "GND")
	)
	(via
		(at 315.740288 -125.163326)
		(size 0.508)
		(drill 0.254)
		(layers "F.Cu" "B.Cu")
		(net "GND")
	)
	(via
		(at 279.215088 -142.860522)
		(size 0.508)
		(drill 0.254)
		(layers "F.Cu" "B.Cu")
		(net "GND")
	)
	(via
		(at 122.621548 -351.611438)
		(size 0.4064)
		(drill 0.2032)
		(layers "F.Cu" "B.Cu")
		(net "GND")
	)
	(via
		(at 341.95258 -329.564492)
		(size 0.508)
		(drill 0.254)
		(layers "F.Cu" "B.Cu")
		(net "GND")
	)
	(via
		(at 273.91741 -346.09913)
		(size 0.4572)
		(drill 0.254)
		(layers "F.Cu" "B.Cu")
		(net "GND")
	)
	(via
		(at 217.925142 -102.836218)
		(size 0.508)
		(drill 0.254)
		(layers "F.Cu" "B.Cu")
		(net "GND")
	)
	(via
		(at 374.927876 -380.141734)
		(size 0.508)
		(drill 0.254)
		(layers "F.Cu" "B.Cu")
		(net "GND")
	)
	(via
		(at 140.075158 -73.87463)
		(size 0.508)
		(drill 0.254)
		(layers "F.Cu" "B.Cu")
		(net "GND")
	)
	(via
		(at 299.866812 -116.435124)
		(size 0.508)
		(drill 0.254)
		(layers "F.Cu" "B.Cu")
		(net "GND")
	)
	(via
		(at 421.249856 -276.899878)
		(size 0.4064)
		(drill 0.2032)
		(layers "F.Cu" "B.Cu")
		(net "GND")
	)
	(via
		(at 273.799808 -304.449734)
		(size 0.4064)
		(drill 0.2032)
		(layers "F.Cu" "B.Cu")
		(net "GND")
	)
	(via
		(at 22.243796 -358.391714)
		(size 0.4572)
		(drill 0.254)
		(layers "F.Cu" "B.Cu")
		(net "GND")
	)
	(via
		(at 55.249826 -390.441688)
		(size 0.508)
		(drill 0.254)
		(layers "F.Cu" "B.Cu")
		(net "GND")
	)
	(via
		(at 195.815712 -342.439498)
		(size 0.4064)
		(drill 0.2032)
		(layers "F.Cu" "B.Cu")
		(net "GND")
	)
	(via
		(at 286.35325 -358.391714)
		(size 0.4572)
		(drill 0.254)
		(layers "F.Cu" "B.Cu")
		(net "GND")
	)
	(via
		(at 395.315186 -142.860522)
		(size 0.508)
		(drill 0.254)
		(layers "F.Cu" "B.Cu")
		(net "GND")
	)
	(via
		(at 67.724782 -285.924752)
		(size 0.4064)
		(drill 0.2032)
		(layers "F.Cu" "B.Cu")
		(net "GND")
	)
	(via
		(at 75.74788 -372.341902)
		(size 0.508)
		(drill 0.254)
		(layers "F.Cu" "B.Cu")
		(net "GND")
	)
	(via
		(at 57.749948 -316.799722)
		(size 0.4064)
		(drill 0.2032)
		(layers "F.Cu" "B.Cu")
		(net "GND")
	)
	(via
		(at 441.817252 -342.439498)
		(size 0.4064)
		(drill 0.2032)
		(layers "F.Cu" "B.Cu")
		(net "GND")
	)
	(via
		(at 283.833062 -124.154946)
		(size 0.508)
		(drill 0.254)
		(layers "F.Cu" "B.Cu")
		(net "GND")
	)
	(via
		(at 385.149852 -311.099962)
		(size 0.4064)
		(drill 0.2032)
		(layers "F.Cu" "B.Cu")
		(net "GND")
	)
	(via
		(at 70.184518 -72.56526)
		(size 0.508)
		(drill 0.254)
		(layers "F.Cu" "B.Cu")
		(net "GND")
	)
	(via
		(at 114.773456 -352.245422)
		(size 0.4572)
		(drill 0.254)
		(layers "F.Cu" "B.Cu")
		(net "GND")
	)
	(via
		(at 44.449492 -272.14957)
		(size 0.4064)
		(drill 0.2032)
		(layers "F.Cu" "B.Cu")
		(net "GND")
	)
	(via
		(at 245.630192 -282.982162)
		(size 0.508)
		(drill 0.254)
		(layers "F.Cu" "B.Cu")
		(net "GND")
	)
	(via
		(at 182.547514 -123.635008)
		(size 0.508)
		(drill 0.254)
		(layers "F.Cu" "B.Cu")
		(net "GND")
	)
	(via
		(at 86.747858 -378.83846)
		(size 0.508)
		(drill 0.254)
		(layers "F.Cu" "B.Cu")
		(net "GND")
	)
	(via
		(at 122.621548 -354.732082)
		(size 0.4064)
		(drill 0.2032)
		(layers "F.Cu" "B.Cu")
		(net "GND")
	)
	(via
		(at 198.075042 -289.724846)
		(size 0.4064)
		(drill 0.2032)
		(layers "F.Cu" "B.Cu")
		(net "GND")
	)
	(via
		(at 237.849918 -317.063882)
		(size 0.508)
		(drill 0.254)
		(layers "F.Cu" "B.Cu")
		(net "GND")
	)
	(via
		(at 48.745648 -342.439498)
		(size 0.4064)
		(drill 0.2032)
		(layers "F.Cu" "B.Cu")
		(net "GND")
	)
	(via
		(at 307.524912 -290.674806)
		(size 0.4064)
		(drill 0.2032)
		(layers "F.Cu" "B.Cu")
		(net "GND")
	)
	(via
		(at 365.072422 -392.71575)
		(size 0.508)
		(drill 0.254)
		(layers "F.Cu" "B.Cu")
		(net "GND")
	)
	(via
		(at 352.975926 -256.870962)
		(size 0.508)
		(drill 0.254)
		(layers "F.Cu" "B.Cu")
		(net "GND")
	)
	(via
		(at 90.918538 -294.50157)
		(size 0.508)
		(drill 0.254)
		(layers "F.Cu" "B.Cu")
		(net "GND")
	)
	(via
		(at 100.25126 -47.03191)
		(size 0.508)
		(drill 0.254)
		(layers "F.Cu" "B.Cu")
		(net "GND")
	)
	(via
		(at 111.341662 -129.20599)
		(size 0.508)
		(drill 0.254)
		(layers "F.Cu" "B.Cu")
		(net "GND")
	)
	(via
		(at 429.198278 -143.676878)
		(size 0.508)
		(drill 0.254)
		(layers "F.Cu" "B.Cu")
		(net "GND")
	)
	(via
		(at 38.347904 -381.241808)
		(size 0.508)
		(drill 0.254)
		(layers "F.Cu" "B.Cu")
		(net "GND")
	)
	(via
		(at 311.933844 -342.439498)
		(size 0.4064)
		(drill 0.2032)
		(layers "F.Cu" "B.Cu")
		(net "GND")
	)
	(via
		(at 161.15157 -124.154946)
		(size 0.508)
		(drill 0.254)
		(layers "F.Cu" "B.Cu")
		(net "GND")
	)
	(via
		(at 81.087214 -347.951806)
		(size 0.4572)
		(drill 0.254)
		(layers "F.Cu" "B.Cu")
		(net "GND")
	)
	(via
		(at 45.051726 -133.565138)
		(size 0.508)
		(drill 0.254)
		(layers "F.Cu" "B.Cu")
		(net "GND")
	)
	(via
		(at 102.10546 -367.488978)
		(size 0.508)
		(drill 0.254)
		(layers "F.Cu" "B.Cu")
		(net "GND")
	)
	(via
		(at 167.732964 -111.44504)
		(size 0.508)
		(drill 0.254)
		(layers "F.Cu" "B.Cu")
		(net "GND")
	)
	(via
		(at 298.647612 -133.0452)
		(size 0.508)
		(drill 0.254)
		(layers "F.Cu" "B.Cu")
		(net "GND")
	)
	(via
		(at 388.949946 -309.199788)
		(size 0.4064)
		(drill 0.2032)
		(layers "F.Cu" "B.Cu")
		(net "GND")
	)
	(via
		(at 54.424834 -293.52494)
		(size 0.4064)
		(drill 0.2032)
		(layers "F.Cu" "B.Cu")
		(net "GND")
	)
	(via
		(at 200.284588 -73.737216)
		(size 0.508)
		(drill 0.254)
		(layers "F.Cu" "B.Cu")
		(net "GND")
	)
	(via
		(at 174.42434 -347.951806)
		(size 0.4572)
		(drill 0.254)
		(layers "F.Cu" "B.Cu")
		(net "GND")
	)
	(via
		(at 36.309808 -342.439498)
		(size 0.4064)
		(drill 0.2032)
		(layers "F.Cu" "B.Cu")
		(net "GND")
	)
	(via
		(at 17.135094 -231.897682)
		(size 0.508)
		(drill 0.254)
		(layers "F.Cu" "B.Cu")
		(net "GND")
	)
	(via
		(at 456.733402 -249.51944)
		(size 0.508)
		(drill 0.254)
		(layers "F.Cu" "B.Cu")
		(net "GND")
	)
	(via
		(at 176.699926 -317.749936)
		(size 0.4064)
		(drill 0.2032)
		(layers "F.Cu" "B.Cu")
		(net "GND")
	)
	(via
		(at 413.649922 -319.65011)
		(size 0.4064)
		(drill 0.2032)
		(layers "F.Cu" "B.Cu")
		(net "GND")
	)
	(via
		(at 294.201342 -351.611438)
		(size 0.4064)
		(drill 0.2032)
		(layers "F.Cu" "B.Cu")
		(net "GND")
	)
	(via
		(at 122.2502 -354.098098)
		(size 0.4572)
		(drill 0.254)
		(layers "F.Cu" "B.Cu")
		(net "GND")
	)
	(via
		(at 387.525006 -278.324818)
		(size 0.4064)
		(drill 0.2032)
		(layers "F.Cu" "B.Cu")
		(net "GND")
	)
	(via
		(at 397.120872 -352.245422)
		(size 0.4572)
		(drill 0.254)
		(layers "F.Cu" "B.Cu")
		(net "GND")
	)
	(via
		(at 397.632428 -120.084088)
		(size 0.508)
		(drill 0.254)
		(layers "F.Cu" "B.Cu")
		(net "GND")
	)
	(via
		(at 178.792124 -350.977454)
		(size 0.4572)
		(drill 0.254)
		(layers "F.Cu" "B.Cu")
		(net "GND")
	)
	(via
		(at 312.749692 -315.849762)
		(size 0.4064)
		(drill 0.2032)
		(layers "F.Cu" "B.Cu")
		(net "GND")
	)
	(via
		(at 401.623276 -56.353456)
		(size 0.508)
		(drill 0.254)
		(layers "F.Cu" "B.Cu")
		(net "GND")
	)
	(via
		(at 110.668308 -93.424502)
		(size 0.508)
		(drill 0.254)
		(layers "F.Cu" "B.Cu")
		(net "GND")
	)
	(via
		(at 42.15638 -354.098098)
		(size 0.4572)
		(drill 0.254)
		(layers "F.Cu" "B.Cu")
		(net "GND")
	)
	(via
		(at 85.674962 -357.75773)
		(size 0.4064)
		(drill 0.2032)
		(layers "F.Cu" "B.Cu")
		(net "GND")
	)
	(via
		(at 72.131682 -342.439498)
		(size 0.4064)
		(drill 0.2032)
		(layers "F.Cu" "B.Cu")
		(net "GND")
	)
	(via
		(at 418.874956 -289.724846)
		(size 0.4064)
		(drill 0.2032)
		(layers "F.Cu" "B.Cu")
		(net "GND")
	)
	(via
		(at 242.836954 -201.659998)
		(size 0.508)
		(drill 0.254)
		(layers "F.Cu" "B.Cu")
		(net "GND")
	)
	(via
		(at 51.099974 -314.899802)
		(size 0.4064)
		(drill 0.2032)
		(layers "F.Cu" "B.Cu")
		(net "GND")
	)
	(via
		(at 29.422344 -253.45644)
		(size 0.508)
		(drill 0.254)
		(layers "F.Cu" "B.Cu")
		(net "GND")
	)
	(via
		(at 66.299842 -274.049744)
		(size 0.4064)
		(drill 0.2032)
		(layers "F.Cu" "B.Cu")
		(net "GND")
	)
	(via
		(at 305.149758 -280.699718)
		(size 0.4064)
		(drill 0.2032)
		(layers "F.Cu" "B.Cu")
		(net "GND")
	)
	(via
		(at 109.050074 -287.51149)
		(size 0.508)
		(drill 0.254)
		(layers "F.Cu" "B.Cu")
		(net "GND")
	)
	(via
		(at 317.957708 -301.262034)
		(size 0.508)
		(drill 0.254)
		(layers "F.Cu" "B.Cu")
		(net "GND")
	)
	(via
		(at 40.897556 -358.391714)
		(size 0.4572)
		(drill 0.254)
		(layers "F.Cu" "B.Cu")
		(net "GND")
	)
	(via
		(at 301.824898 -292.574726)
		(size 0.4064)
		(drill 0.2032)
		(layers "F.Cu" "B.Cu")
		(net "GND")
	)
	(via
		(at 92.698316 -114.323114)
		(size 0.508)
		(drill 0.254)
		(layers "F.Cu" "B.Cu")
		(net "GND")
	)
	(via
		(at 72.474836 -303.024794)
		(size 0.4064)
		(drill 0.2032)
		(layers "F.Cu" "B.Cu")
		(net "GND")
	)
	(via
		(at 199.025002 -289.724846)
		(size 0.4064)
		(drill 0.2032)
		(layers "F.Cu" "B.Cu")
		(net "GND")
	)
	(via
		(at 7.72414 -311.250838)
		(size 0.508)
		(drill 0.254)
		(layers "F.Cu" "B.Cu")
		(net "GND")
	)
	(via
		(at 309.424832 -293.52494)
		(size 0.4064)
		(drill 0.2032)
		(layers "F.Cu" "B.Cu")
		(net "GND")
	)
	(via
		(at 397.02486 -284.974792)
		(size 0.4064)
		(drill 0.2032)
		(layers "F.Cu" "B.Cu")
		(net "GND")
	)
	(via
		(at 443.975998 -231.779318)
		(size 0.508)
		(drill 0.254)
		(layers "F.Cu" "B.Cu")
		(net "GND")
	)
	(via
		(at 44.449746 -309.199788)
		(size 0.4064)
		(drill 0.2032)
		(layers "F.Cu" "B.Cu")
		(net "GND")
	)
	(via
		(at 208.002124 -58.731404)
		(size 0.508)
		(drill 0.254)
		(layers "F.Cu" "B.Cu")
		(net "GND")
	)
	(via
		(at 416.945572 -351.611438)
		(size 0.4064)
		(drill 0.2032)
		(layers "F.Cu" "B.Cu")
		(net "GND")
	)
	(via
		(at 80.898238 -153.218134)
		(size 0.508)
		(drill 0.254)
		(layers "F.Cu" "B.Cu")
		(net "GND")
	)
	(via
		(at 372.249192 -343.073482)
		(size 0.4572)
		(drill 0.254)
		(layers "F.Cu" "B.Cu")
		(net "GND")
	)
	(via
		(at 304.199798 -314.899802)
		(size 0.4064)
		(drill 0.2032)
		(layers "F.Cu" "B.Cu")
		(net "GND")
	)
	(via
		(at 274.274788 -297.32478)
		(size 0.4064)
		(drill 0.2032)
		(layers "F.Cu" "B.Cu")
		(net "GND")
	)
	(via
		(at 282.824936 -287.824926)
		(size 0.4064)
		(drill 0.2032)
		(layers "F.Cu" "B.Cu")
		(net "GND")
	)
	(via
		(at 132.379212 -206.756254)
		(size 0.508)
		(drill 0.254)
		(layers "F.Cu" "B.Cu")
		(net "GND")
	)
	(via
		(at 16.858234 -123.097036)
		(size 0.508)
		(drill 0.254)
		(layers "F.Cu" "B.Cu")
		(net "GND")
	)
	(via
		(at 17.794986 -274.232624)
		(size 0.508)
		(drill 0.254)
		(layers "F.Cu" "B.Cu")
		(net "GND")
	)
	(via
		(at 281.874722 -294.4749)
		(size 0.4064)
		(drill 0.2032)
		(layers "F.Cu" "B.Cu")
		(net "GND")
	)
	(via
		(at 406.524968 -285.924752)
		(size 0.4064)
		(drill 0.2032)
		(layers "F.Cu" "B.Cu")
		(net "GND")
	)
	(via
		(at 159.347916 -404.940262)
		(size 0.508)
		(drill 0.254)
		(layers "F.Cu" "B.Cu")
		(net "GND")
	)
	(via
		(at 385.05638 -345.465146)
		(size 0.4064)
		(drill 0.2032)
		(layers "F.Cu" "B.Cu")
		(net "GND")
	)
	(via
		(at 69.80428 -132.622036)
		(size 0.508)
		(drill 0.254)
		(layers "F.Cu" "B.Cu")
		(net "GND")
	)
	(via
		(at 159.599884 -310.149748)
		(size 0.4064)
		(drill 0.2032)
		(layers "F.Cu" "B.Cu")
		(net "GND")
	)
	(via
		(at 58.224928 -305.874928)
		(size 0.4064)
		(drill 0.2032)
		(layers "F.Cu" "B.Cu")
		(net "GND")
	)
	(via
		(at 398.59966 -342.439498)
		(size 0.4064)
		(drill 0.2032)
		(layers "F.Cu" "B.Cu")
		(net "GND")
	)
	(via
		(at 188.310774 -109.41304)
		(size 0.508)
		(drill 0.254)
		(layers "F.Cu" "B.Cu")
		(net "GND")
	)
	(via
		(at 409.948888 -27.79014)
		(size 0.508)
		(drill 0.254)
		(layers "F.Cu" "B.Cu")
		(net "GND")
	)
	(via
		(at 387.793992 -358.391714)
		(size 0.4572)
		(drill 0.254)
		(layers "F.Cu" "B.Cu")
		(net "GND")
	)
	(via
		(at 164.824918 -303.974754)
		(size 0.4064)
		(drill 0.2032)
		(layers "F.Cu" "B.Cu")
		(net "GND")
	)
	(via
		(at 119.809768 -291.32149)
		(size 0.508)
		(drill 0.254)
		(layers "F.Cu" "B.Cu")
		(net "GND")
	)
	(via
		(at 424.09999 -288.299906)
		(size 0.4064)
		(drill 0.2032)
		(layers "F.Cu" "B.Cu")
		(net "GND")
	)
	(via
		(at 258.014216 -193.155316)
		(size 0.508)
		(drill 0.254)
		(layers "F.Cu" "B.Cu")
		(net "GND")
	)
	(via
		(at 187.1345 -47.936658)
		(size 0.508)
		(drill 0.254)
		(layers "F.Cu" "B.Cu")
		(net "GND")
	)
	(via
		(at 167.732964 -120.555004)
		(size 0.508)
		(drill 0.254)
		(layers "F.Cu" "B.Cu")
		(net "GND")
	)
	(via
		(at 443.880494 -97.830894)
		(size 0.508)
		(drill 0.254)
		(layers "F.Cu" "B.Cu")
		(net "GND")
	)
	(via
		(at 406.019 -374.015)
		(size 0.508)
		(drill 0.254)
		(layers "F.Cu" "B.Cu")
		(net "GND")
	)
	(via
		(at 78.349602 -354.732082)
		(size 0.4064)
		(drill 0.2032)
		(layers "F.Cu" "B.Cu")
		(net "GND")
	)
	(via
		(at 309.899812 -317.749936)
		(size 0.4064)
		(drill 0.2032)
		(layers "F.Cu" "B.Cu")
		(net "GND")
	)
	(via
		(at 66.44767 -131.245102)
		(size 0.508)
		(drill 0.254)
		(layers "F.Cu" "B.Cu")
		(net "GND")
	)
	(via
		(at 164.57041 -131.277614)
		(size 0.508)
		(drill 0.254)
		(layers "F.Cu" "B.Cu")
		(net "GND")
	)
	(via
		(at 171.474892 -285.924752)
		(size 0.4064)
		(drill 0.2032)
		(layers "F.Cu" "B.Cu")
		(net "GND")
	)
	(via
		(at 209.09788 -295.355518)
		(size 0.508)
		(drill 0.254)
		(layers "F.Cu" "B.Cu")
		(net "GND")
	)
	(via
		(at 333.696564 -345.465146)
		(size 0.4064)
		(drill 0.2032)
		(layers "F.Cu" "B.Cu")
		(net "GND")
	)
	(via
		(at 335.328006 -402.241766)
		(size 0.508)
		(drill 0.254)
		(layers "F.Cu" "B.Cu")
		(net "GND")
	)
	(via
		(at 270.474694 -297.32478)
		(size 0.4064)
		(drill 0.2032)
		(layers "F.Cu" "B.Cu")
		(net "GND")
	)
	(via
		(at 75.79995 -303.499774)
		(size 0.4064)
		(drill 0.2032)
		(layers "F.Cu" "B.Cu")
		(net "GND")
	)
	(via
		(at 388.474966 -280.224738)
		(size 0.4064)
		(drill 0.2032)
		(layers "F.Cu" "B.Cu")
		(net "GND")
	)
	(via
		(at 286.927798 -382.84023)
		(size 0.508)
		(drill 0.254)
		(layers "F.Cu" "B.Cu")
		(net "GND")
	)
	(via
		(at 177.174906 -307.774848)
		(size 0.4064)
		(drill 0.2032)
		(layers "F.Cu" "B.Cu")
		(net "GND")
	)
	(via
		(at 33.947862 -372.240302)
		(size 0.508)
		(drill 0.254)
		(layers "F.Cu" "B.Cu")
		(net "GND")
	)
	(via
		(at 341.25027 -289.41649)
		(size 0.508)
		(drill 0.254)
		(layers "F.Cu" "B.Cu")
		(net "GND")
	)
	(via
		(at 125.154944 -123.947428)
		(size 0.508)
		(drill 0.254)
		(layers "F.Cu" "B.Cu")
		(net "GND")
	)
	(via
		(at 288.524696 -303.974754)
		(size 0.4064)
		(drill 0.2032)
		(layers "F.Cu" "B.Cu")
		(net "GND")
	)
	(via
		(at 290.42487 -293.52494)
		(size 0.4064)
		(drill 0.2032)
		(layers "F.Cu" "B.Cu")
		(net "GND")
	)
	(via
		(at 405.100028 -318.699896)
		(size 0.4064)
		(drill 0.2032)
		(layers "F.Cu" "B.Cu")
		(net "GND")
	)
	(via
		(at 92.794328 -123.84278)
		(size 0.508)
		(drill 0.254)
		(layers "F.Cu" "B.Cu")
		(net "GND")
	)
	(via
		(at 23.429468 -47.020734)
		(size 0.508)
		(drill 0.254)
		(layers "F.Cu" "B.Cu")
		(net "GND")
	)
	(via
		(at 425.901104 -354.098098)
		(size 0.4572)
		(drill 0.254)
		(layers "F.Cu" "B.Cu")
		(net "GND")
	)
	(via
		(at 422.199816 -283.549852)
		(size 0.4064)
		(drill 0.2032)
		(layers "F.Cu" "B.Cu")
		(net "GND")
	)
	(via
		(at 186.738768 -23.880318)
		(size 0.508)
		(drill 0.254)
		(layers "F.Cu" "B.Cu")
		(net "GND")
	)
	(via
		(at 51.48326 -352.245422)
		(size 0.4572)
		(drill 0.254)
		(layers "F.Cu" "B.Cu")
		(net "GND")
	)
	(via
		(at 64.399922 -317.749936)
		(size 0.4064)
		(drill 0.2032)
		(layers "F.Cu" "B.Cu")
		(net "GND")
	)
	(via
		(at 0.77089 -365.261144)
		(size 0.508)
		(drill 0.254)
		(layers "F.Cu" "B.Cu")
		(net "GND")
	)
	(via
		(at 170.524932 -302.074834)
		(size 0.4064)
		(drill 0.2032)
		(layers "F.Cu" "B.Cu")
		(net "GND")
	)
	(via
		(at 64.688212 -114.267742)
		(size 0.508)
		(drill 0.254)
		(layers "F.Cu" "B.Cu")
		(net "GND")
	)
	(via
		(at 339.728048 -378.94006)
		(size 0.508)
		(drill 0.254)
		(layers "F.Cu" "B.Cu")
		(net "GND")
	)
	(via
		(at 466.827616 -57.092596)
		(size 0.508)
		(drill 0.254)
		(layers "F.Cu" "B.Cu")
		(net "GND")
	)
	(via
		(at 289.47491 -285.924752)
		(size 0.4064)
		(drill 0.2032)
		(layers "F.Cu" "B.Cu")
		(net "GND")
	)
	(via
		(at 199.500236 -308.249828)
		(size 0.4064)
		(drill 0.2032)
		(layers "F.Cu" "B.Cu")
		(net "GND")
	)
	(via
		(at 75.79995 -317.749936)
		(size 0.4064)
		(drill 0.2032)
		(layers "F.Cu" "B.Cu")
		(net "GND")
	)
	(via
		(at 220.241622 -148.038312)
		(size 0.508)
		(drill 0.254)
		(layers "F.Cu" "B.Cu")
		(net "GND")
	)
	(via
		(at 187.624974 -303.974754)
		(size 0.4064)
		(drill 0.2032)
		(layers "F.Cu" "B.Cu")
		(net "GND")
	)
	(via
		(at 300.399704 -273.099784)
		(size 0.4064)
		(drill 0.2032)
		(layers "F.Cu" "B.Cu")
		(net "GND")
	)
	(via
		(at 384.674872 -280.224738)
		(size 0.4064)
		(drill 0.2032)
		(layers "F.Cu" "B.Cu")
		(net "GND")
	)
	(via
		(at 160.074864 -296.37482)
		(size 0.4064)
		(drill 0.2032)
		(layers "F.Cu" "B.Cu")
		(net "GND")
	)
	(via
		(at 239.263174 -310.999124)
		(size 0.508)
		(drill 0.254)
		(layers "F.Cu" "B.Cu")
		(net "GND")
	)
	(via
		(at 318.523112 -354.098098)
		(size 0.4572)
		(drill 0.254)
		(layers "F.Cu" "B.Cu")
		(net "GND")
	)
	(via
		(at 70.569836 -25.832054)
		(size 0.508)
		(drill 0.254)
		(layers "F.Cu" "B.Cu")
		(net "GND")
	)
	(via
		(at 311.799732 -313.949842)
		(size 0.4064)
		(drill 0.2032)
		(layers "F.Cu" "B.Cu")
		(net "GND")
	)
	(via
		(at 75.820778 -113.260632)
		(size 0.508)
		(drill 0.254)
		(layers "F.Cu" "B.Cu")
		(net "GND")
	)
	(via
		(at 397.97482 -288.774886)
		(size 0.4064)
		(drill 0.2032)
		(layers "F.Cu" "B.Cu")
		(net "GND")
	)
	(via
		(at 188.099954 -310.149748)
		(size 0.4064)
		(drill 0.2032)
		(layers "F.Cu" "B.Cu")
		(net "GND")
	)
	(via
		(at 27.347926 -369.938554)
		(size 0.508)
		(drill 0.254)
		(layers "F.Cu" "B.Cu")
		(net "GND")
	)
	(via
		(at 289.090862 -354.732082)
		(size 0.4064)
		(drill 0.2032)
		(layers "F.Cu" "B.Cu")
		(net "GND")
	)
	(via
		(at 293.27475 -289.724846)
		(size 0.4064)
		(drill 0.2032)
		(layers "F.Cu" "B.Cu")
		(net "GND")
	)
	(via
		(at 303.249838 -310.149748)
		(size 0.4064)
		(drill 0.2032)
		(layers "F.Cu" "B.Cu")
		(net "GND")
	)
	(via
		(at 383.72796 -407.638504)
		(size 0.508)
		(drill 0.254)
		(layers "F.Cu" "B.Cu")
		(net "GND")
	)
	(via
		(at 415.3154 -358.391714)
		(size 0.4572)
		(drill 0.254)
		(layers "F.Cu" "B.Cu")
		(net "GND")
	)
	(via
		(at 71.49846 -65.15989)
		(size 0.508)
		(drill 0.254)
		(layers "F.Cu" "B.Cu")
		(net "GND")
	)
	(via
		(at 33.947862 -397.038576)
		(size 0.508)
		(drill 0.254)
		(layers "F.Cu" "B.Cu")
		(net "GND")
	)
	(via
		(at 153.89987 -301.599854)
		(size 0.4064)
		(drill 0.2032)
		(layers "F.Cu" "B.Cu")
		(net "GND")
	)
	(via
		(at 290.89985 -276.899878)
		(size 0.4064)
		(drill 0.2032)
		(layers "F.Cu" "B.Cu")
		(net "GND")
	)
	(via
		(at 377.53544 -89.9668)
		(size 0.508)
		(drill 0.254)
		(layers "F.Cu" "B.Cu")
		(net "GND")
	)
	(via
		(at 293.27475 -293.52494)
		(size 0.4064)
		(drill 0.2032)
		(layers "F.Cu" "B.Cu")
		(net "GND")
	)
	(via
		(at 194.749928 -303.499774)
		(size 0.4064)
		(drill 0.2032)
		(layers "F.Cu" "B.Cu")
		(net "GND")
	)
	(via
		(at 434.755036 -27.79014)
		(size 0.508)
		(drill 0.254)
		(layers "F.Cu" "B.Cu")
		(net "GND")
	)
	(via
		(at 391.799826 -303.499774)
		(size 0.4064)
		(drill 0.2032)
		(layers "F.Cu" "B.Cu")
		(net "GND")
	)
	(via
		(at 241.848894 -33.19018)
		(size 0.508)
		(drill 0.254)
		(layers "F.Cu" "B.Cu")
		(net "GND")
	)
	(via
		(at 58.35523 -368.714274)
		(size 0.4572)
		(drill 0.254)
		(layers "F.Cu" "B.Cu")
		(net "GND")
	)
	(via
		(at 327.038208 -73.20026)
		(size 0.508)
		(drill 0.254)
		(layers "F.Cu" "B.Cu")
		(net "GND")
	)
	(via
		(at 47.29988 -312.999882)
		(size 0.4064)
		(drill 0.2032)
		(layers "F.Cu" "B.Cu")
		(net "GND")
	)
	(via
		(at 396.26032 -19.33956)
		(size 0.508)
		(drill 0.254)
		(layers "F.Cu" "B.Cu")
		(net "GND")
	)
	(via
		(at 9.648952 -25.990042)
		(size 0.508)
		(drill 0.254)
		(layers "F.Cu" "B.Cu")
		(net "GND")
	)
	(via
		(at 409.374848 -306.824888)
		(size 0.4064)
		(drill 0.2032)
		(layers "F.Cu" "B.Cu")
		(net "GND")
	)
	(via
		(at 449.777612 -102.271068)
		(size 0.508)
		(drill 0.254)
		(layers "F.Cu" "B.Cu")
		(net "GND")
	)
	(via
		(at 406.999948 -318.699896)
		(size 0.4064)
		(drill 0.2032)
		(layers "F.Cu" "B.Cu")
		(net "GND")
	)
	(via
		(at 160.771332 -29.311854)
		(size 0.508)
		(drill 0.254)
		(layers "F.Cu" "B.Cu")
		(net "GND")
	)
	(via
		(at 74.849736 -276.899878)
		(size 0.4064)
		(drill 0.2032)
		(layers "F.Cu" "B.Cu")
		(net "GND")
	)
	(via
		(at 61.17463 -349.219774)
		(size 0.4572)
		(drill 0.254)
		(layers "F.Cu" "B.Cu")
		(net "GND")
	)
	(via
		(at 310.849772 -316.799722)
		(size 0.4064)
		(drill 0.2032)
		(layers "F.Cu" "B.Cu")
		(net "GND")
	)
	(via
		(at 45.87494 -292.57498)
		(size 0.4064)
		(drill 0.2032)
		(layers "F.Cu" "B.Cu")
		(net "GND")
	)
	(via
		(at 48.24984 -314.899802)
		(size 0.4064)
		(drill 0.2032)
		(layers "F.Cu" "B.Cu")
		(net "GND")
	)
	(via
		(at 317.008256 -145.483326)
		(size 0.508)
		(drill 0.254)
		(layers "F.Cu" "B.Cu")
		(net "GND")
	)
	(via
		(at 408.424888 -305.874928)
		(size 0.4064)
		(drill 0.2032)
		(layers "F.Cu" "B.Cu")
		(net "GND")
	)
	(via
		(at 313.224926 -302.074834)
		(size 0.4064)
		(drill 0.2032)
		(layers "F.Cu" "B.Cu")
		(net "GND")
	)
	(via
		(at 344.305382 -285.953454)
		(size 0.508)
		(drill 0.254)
		(layers "F.Cu" "B.Cu")
		(net "GND")
	)
	(via
		(at 79.769462 -64.102234)
		(size 0.508)
		(drill 0.254)
		(layers "F.Cu" "B.Cu")
		(net "GND")
	)
	(via
		(at 304.44694 -115.504976)
		(size 0.508)
		(drill 0.254)
		(layers "F.Cu" "B.Cu")
		(net "GND")
	)
	(via
		(at 295.174924 -296.37482)
		(size 0.4064)
		(drill 0.2032)
		(layers "F.Cu" "B.Cu")
		(net "GND")
	)
	(via
		(at 172.574204 -341.805514)
		(size 0.4572)
		(drill 0.254)
		(layers "F.Cu" "B.Cu")
		(net "GND")
	)
	(via
		(at 412.699962 -277.849838)
		(size 0.4064)
		(drill 0.2032)
		(layers "F.Cu" "B.Cu")
		(net "GND")
	)
	(via
		(at 312.305192 -350.977454)
		(size 0.4572)
		(drill 0.254)
		(layers "F.Cu" "B.Cu")
		(net "GND")
	)
	(via
		(at 279.499822 -274.049744)
		(size 0.4064)
		(drill 0.2032)
		(layers "F.Cu" "B.Cu")
		(net "GND")
	)
	(via
		(at 121.947686 -376.140218)
		(size 0.4572)
		(drill 0.254)
		(layers "F.Cu" "B.Cu")
		(net "GND")
	)
	(via
		(at 197.600062 -307.299868)
		(size 0.4064)
		(drill 0.2032)
		(layers "F.Cu" "B.Cu")
		(net "GND")
	)
	(via
		(at 27.79141 -305.334162)
		(size 0.508)
		(drill 0.254)
		(layers "F.Cu" "B.Cu")
		(net "GND")
	)
	(via
		(at 13.004038 -309.424324)
		(size 0.508)
		(drill 0.254)
		(layers "F.Cu" "B.Cu")
		(net "GND")
	)
	(via
		(at 161.975038 -302.074834)
		(size 0.4064)
		(drill 0.2032)
		(layers "F.Cu" "B.Cu")
		(net "GND")
	)
	(via
		(at 83.540346 -152.683464)
		(size 0.508)
		(drill 0.254)
		(layers "F.Cu" "B.Cu")
		(net "GND")
	)
	(via
		(at 417.861242 -60.099194)
		(size 0.508)
		(drill 0.254)
		(layers "F.Cu" "B.Cu")
		(net "GND")
	)
	(via
		(at 307.999892 -307.299868)
		(size 0.4064)
		(drill 0.2032)
		(layers "F.Cu" "B.Cu")
		(net "GND")
	)
	(via
		(at 73.899776 -313.949842)
		(size 0.4064)
		(drill 0.2032)
		(layers "F.Cu" "B.Cu")
		(net "GND")
	)
	(via
		(at 271.424908 -286.874966)
		(size 0.4064)
		(drill 0.2032)
		(layers "F.Cu" "B.Cu")
		(net "GND")
	)
	(via
		(at 83.140042 -27.729688)
		(size 0.508)
		(drill 0.254)
		(layers "F.Cu" "B.Cu")
		(net "GND")
	)
	(via
		(at 185.737246 -125.752352)
		(size 0.508)
		(drill 0.254)
		(layers "F.Cu" "B.Cu")
		(net "GND")
	)
	(via
		(at 365.642144 -131.957572)
		(size 0.508)
		(drill 0.254)
		(layers "F.Cu" "B.Cu")
		(net "GND")
	)
	(via
		(at 67.021202 -357.75773)
		(size 0.4064)
		(drill 0.2032)
		(layers "F.Cu" "B.Cu")
		(net "GND")
	)
	(via
		(at 84.600796 -31.390336)
		(size 0.508)
		(drill 0.254)
		(layers "F.Cu" "B.Cu")
		(net "GND")
	)
	(via
		(at 168.148 -403.738588)
		(size 0.508)
		(drill 0.254)
		(layers "F.Cu" "B.Cu")
		(net "GND")
	)
	(via
		(at 320.10604 -392.811)
		(size 0.508)
		(drill 0.254)
		(layers "F.Cu" "B.Cu")
		(net "GND")
	)
	(via
		(at 39.224966 -278.324818)
		(size 0.4064)
		(drill 0.2032)
		(layers "F.Cu" "B.Cu")
		(net "GND")
	)
	(via
		(at 401.774914 -284.024832)
		(size 0.4064)
		(drill 0.2032)
		(layers "F.Cu" "B.Cu")
		(net "GND")
	)
	(via
		(at 55.849774 -279.749758)
		(size 0.4064)
		(drill 0.2032)
		(layers "F.Cu" "B.Cu")
		(net "GND")
	)
	(via
		(at 423.149776 -284.499812)
		(size 0.4064)
		(drill 0.2032)
		(layers "F.Cu" "B.Cu")
		(net "GND")
	)
	(via
		(at 385.927854 -400.938492)
		(size 0.508)
		(drill 0.254)
		(layers "F.Cu" "B.Cu")
		(net "GND")
	)
	(via
		(at 336.249264 -86.77021)
		(size 0.508)
		(drill 0.254)
		(layers "F.Cu" "B.Cu")
		(net "GND")
	)
	(via
		(at 288.049716 -275.949918)
		(size 0.4064)
		(drill 0.2032)
		(layers "F.Cu" "B.Cu")
		(net "GND")
	)
	(via
		(at 71.999856 -314.899802)
		(size 0.4064)
		(drill 0.2032)
		(layers "F.Cu" "B.Cu")
		(net "GND")
	)
	(via
		(at 74.248264 -147.55495)
		(size 0.508)
		(drill 0.254)
		(layers "F.Cu" "B.Cu")
		(net "GND")
	)
	(via
		(at 292.79977 -310.149748)
		(size 0.4064)
		(drill 0.2032)
		(layers "F.Cu" "B.Cu")
		(net "GND")
	)
	(via
		(at 82.166206 -150.876762)
		(size 0.508)
		(drill 0.254)
		(layers "F.Cu" "B.Cu")
		(net "GND")
	)
	(via
		(at 420.558468 -116.9035)
		(size 0.508)
		(drill 0.254)
		(layers "F.Cu" "B.Cu")
		(net "GND")
	)
	(via
		(at 42.549826 -319.65011)
		(size 0.4064)
		(drill 0.2032)
		(layers "F.Cu" "B.Cu")
		(net "GND")
	)
	(via
		(at 235.536486 -93.77934)
		(size 0.508)
		(drill 0.254)
		(layers "F.Cu" "B.Cu")
		(net "GND")
	)
	(via
		(at 432.119024 -347.951806)
		(size 0.4572)
		(drill 0.254)
		(layers "F.Cu" "B.Cu")
		(net "GND")
	)
	(via
		(at 314.174886 -301.124874)
		(size 0.4064)
		(drill 0.2032)
		(layers "F.Cu" "B.Cu")
		(net "GND")
	)
	(via
		(at 88.947752 -399.838418)
		(size 0.508)
		(drill 0.254)
		(layers "F.Cu" "B.Cu")
		(net "GND")
	)
	(via
		(at 431.440082 -27.729688)
		(size 0.508)
		(drill 0.254)
		(layers "F.Cu" "B.Cu")
		(net "GND")
	)
	(via
		(at 415.96691 -121.83491)
		(size 0.508)
		(drill 0.254)
		(layers "F.Cu" "B.Cu")
		(net "GND")
	)
	(via
		(at 365.861346 -60.099194)
		(size 0.508)
		(drill 0.254)
		(layers "F.Cu" "B.Cu")
		(net "GND")
	)
	(via
		(at 398.925034 -305.874928)
		(size 0.4064)
		(drill 0.2032)
		(layers "F.Cu" "B.Cu")
		(net "GND")
	)
	(via
		(at 177.161952 -345.465146)
		(size 0.4064)
		(drill 0.2032)
		(layers "F.Cu" "B.Cu")
		(net "GND")
	)
	(via
		(at 124.100336 -347.951806)
		(size 0.4572)
		(drill 0.254)
		(layers "F.Cu" "B.Cu")
		(net "GND")
	)
	(via
		(at 430.8602 -349.219774)
		(size 0.4572)
		(drill 0.254)
		(layers "F.Cu" "B.Cu")
		(net "GND")
	)
	(via
		(at 152.469088 -102.181914)
		(size 0.508)
		(drill 0.254)
		(layers "F.Cu" "B.Cu")
		(net "GND")
	)
	(via
		(at 116.03228 -346.09913)
		(size 0.4572)
		(drill 0.254)
		(layers "F.Cu" "B.Cu")
		(net "GND")
	)
	(via
		(at 310.849772 -309.199788)
		(size 0.4064)
		(drill 0.2032)
		(layers "F.Cu" "B.Cu")
		(net "GND")
	)
	(via
		(at 236.633258 -142.640812)
		(size 0.508)
		(drill 0.254)
		(layers "F.Cu" "B.Cu")
		(net "GND")
	)
	(via
		(at 168.148 -369.938554)
		(size 0.508)
		(drill 0.254)
		(layers "F.Cu" "B.Cu")
		(net "GND")
	)
	(via
		(at 409.09748 -343.073482)
		(size 0.4572)
		(drill 0.254)
		(layers "F.Cu" "B.Cu")
		(net "GND")
	)
	(via
		(at 332.233524 -107.681776)
		(size 0.508)
		(drill 0.254)
		(layers "F.Cu" "B.Cu")
		(net "GND")
	)
	(via
		(at 292.32479 -285.924752)
		(size 0.4064)
		(drill 0.2032)
		(layers "F.Cu" "B.Cu")
		(net "GND")
	)
	(via
		(at 338.807044 -351.611438)
		(size 0.4064)
		(drill 0.2032)
		(layers "F.Cu" "B.Cu")
		(net "GND")
	)
	(via
		(at 438.336944 -354.074222)
		(size 0.4572)
		(drill 0.254)
		(layers "F.Cu" "B.Cu")
		(net "GND")
	)
	(via
		(at 211.508594 -252.290072)
		(size 0.508)
		(drill 0.254)
		(layers "F.Cu" "B.Cu")
		(net "GND")
	)
	(via
		(at 391.324846 -278.324818)
		(size 0.4064)
		(drill 0.2032)
		(layers "F.Cu" "B.Cu")
		(net "GND")
	)
	(via
		(at 179.780946 -25.990042)
		(size 0.508)
		(drill 0.254)
		(layers "F.Cu" "B.Cu")
		(net "GND")
	)
	(via
		(at 425.04995 -285.449772)
		(size 0.4064)
		(drill 0.2032)
		(layers "F.Cu" "B.Cu")
		(net "GND")
	)
	(via
		(at 156.902912 -74.624184)
		(size 0.508)
		(drill 0.254)
		(layers "F.Cu" "B.Cu")
		(net "GND")
	)
	(via
		(at 142.754096 -344.831162)
		(size 0.4572)
		(drill 0.254)
		(layers "F.Cu" "B.Cu")
		(net "GND")
	)
	(via
		(at 432.490372 -342.439498)
		(size 0.4064)
		(drill 0.2032)
		(layers "F.Cu" "B.Cu")
		(net "GND")
	)
	(via
		(at 183.412638 -104.240076)
		(size 0.508)
		(drill 0.254)
		(layers "F.Cu" "B.Cu")
		(net "GND")
	)
	(via
		(at 341.927942 -399.441924)
		(size 0.508)
		(drill 0.254)
		(layers "F.Cu" "B.Cu")
		(net "GND")
	)
	(via
		(at 164.645594 -150.9776)
		(size 0.508)
		(drill 0.254)
		(layers "F.Cu" "B.Cu")
		(net "GND")
	)
	(via
		(at 251.031248 -60.099194)
		(size 0.508)
		(drill 0.254)
		(layers "F.Cu" "B.Cu")
		(net "GND")
	)
	(via
		(at 277.069042 -152.958038)
		(size 0.508)
		(drill 0.254)
		(layers "F.Cu" "B.Cu")
		(net "GND")
	)
	(via
		(at 40.547798 -382.84023)
		(size 0.508)
		(drill 0.254)
		(layers "F.Cu" "B.Cu")
		(net "GND")
	)
	(via
		(at 159.573468 -73.20026)
		(size 0.508)
		(drill 0.254)
		(layers "F.Cu" "B.Cu")
		(net "GND")
	)
	(via
		(at 199.025002 -296.37482)
		(size 0.4064)
		(drill 0.2032)
		(layers "F.Cu" "B.Cu")
		(net "GND")
	)
	(via
		(at 100.573586 -343.446862)
		(size 0.508)
		(drill 0.254)
		(layers "F.Cu" "B.Cu")
		(net "GND")
	)
	(via
		(at 216.681304 -34.718498)
		(size 0.508)
		(drill 0.254)
		(layers "F.Cu" "B.Cu")
		(net "GND")
	)
	(via
		(at 394.17498 -302.074834)
		(size 0.4064)
		(drill 0.2032)
		(layers "F.Cu" "B.Cu")
		(net "GND")
	)
	(via
		(at 185.250074 -319.65011)
		(size 0.4064)
		(drill 0.2032)
		(layers "F.Cu" "B.Cu")
		(net "GND")
	)
	(via
		(at 23.50262 -355.366066)
		(size 0.4572)
		(drill 0.254)
		(layers "F.Cu" "B.Cu")
		(net "GND")
	)
	(via
		(at 78.64983 -315.849762)
		(size 0.4064)
		(drill 0.2032)
		(layers "F.Cu" "B.Cu")
		(net "GND")
	)
	(via
		(at 170.806364 -109.644942)
		(size 0.508)
		(drill 0.254)
		(layers "F.Cu" "B.Cu")
		(net "GND")
	)
	(via
		(at 380.317248 -346.09913)
		(size 0.4572)
		(drill 0.254)
		(layers "F.Cu" "B.Cu")
		(net "GND")
	)
	(via
		(at 298.012612 -134.845044)
		(size 0.508)
		(drill 0.254)
		(layers "F.Cu" "B.Cu")
		(net "GND")
	)
	(via
		(at 251.069094 -257.515614)
		(size 0.508)
		(drill 0.254)
		(layers "F.Cu" "B.Cu")
		(net "GND")
	)
	(via
		(at 385.927854 -399.441924)
		(size 0.508)
		(drill 0.254)
		(layers "F.Cu" "B.Cu")
		(net "GND")
	)
	(via
		(at 287.983422 -342.439498)
		(size 0.4064)
		(drill 0.2032)
		(layers "F.Cu" "B.Cu")
		(net "GND")
	)
	(via
		(at 135.057388 -342.439498)
		(size 0.4064)
		(drill 0.2032)
		(layers "F.Cu" "B.Cu")
		(net "GND")
	)
	(via
		(at 0.766318 -52.012342)
		(size 0.508)
		(drill 0.254)
		(layers "F.Cu" "B.Cu")
		(net "GND")
	)
	(via
		(at 302.299878 -274.049744)
		(size 0.4064)
		(drill 0.2032)
		(layers "F.Cu" "B.Cu")
		(net "GND")
	)
	(via
		(at 106.847894 -284.333188)
		(size 0.49022)
		(drill 0.254)
		(layers "F.Cu" "B.Cu")
		(net "GND")
	)
	(via
		(at 102.617016 -305.008534)
		(size 0.508)
		(drill 0.254)
		(layers "F.Cu" "B.Cu")
		(net "GND")
	)
	(via
		(at 144.01292 -355.366066)
		(size 0.4572)
		(drill 0.254)
		(layers "F.Cu" "B.Cu")
		(net "GND")
	)
	(via
		(at 424.57497 -297.32478)
		(size 0.4064)
		(drill 0.2032)
		(layers "F.Cu" "B.Cu")
		(net "GND")
	)
	(via
		(at 73.899776 -314.899802)
		(size 0.4064)
		(drill 0.2032)
		(layers "F.Cu" "B.Cu")
		(net "GND")
	)
	(via
		(at 80.898238 -118.498112)
		(size 0.508)
		(drill 0.254)
		(layers "F.Cu" "B.Cu")
		(net "GND")
	)
	(via
		(at 319.781936 -341.805514)
		(size 0.4572)
		(drill 0.254)
		(layers "F.Cu" "B.Cu")
		(net "GND")
	)
	(via
		(at 180.64226 -343.073482)
		(size 0.4572)
		(drill 0.254)
		(layers "F.Cu" "B.Cu")
		(net "GND")
	)
	(via
		(at 48.24984 -281.649932)
		(size 0.4064)
		(drill 0.2032)
		(layers "F.Cu" "B.Cu")
		(net "GND")
	)
	(via
		(at 310.849772 -286.399732)
		(size 0.4064)
		(drill 0.2032)
		(layers "F.Cu" "B.Cu")
		(net "GND")
	)
	(via
		(at 304.674778 -300.174914)
		(size 0.4064)
		(drill 0.2032)
		(layers "F.Cu" "B.Cu")
		(net "GND")
	)
	(via
		(at 125.74905 -25.990042)
		(size 0.508)
		(drill 0.254)
		(layers "F.Cu" "B.Cu")
		(net "GND")
	)
	(via
		(at 359.980992 -25.990042)
		(size 0.508)
		(drill 0.254)
		(layers "F.Cu" "B.Cu")
		(net "GND")
	)
	(via
		(at 348.527878 -407.638504)
		(size 0.508)
		(drill 0.254)
		(layers "F.Cu" "B.Cu")
		(net "GND")
	)
	(via
		(at 149.20341 -60.627006)
		(size 0.508)
		(drill 0.254)
		(layers "F.Cu" "B.Cu")
		(net "GND")
	)
	(via
		(at 273.324828 -278.324818)
		(size 0.4064)
		(drill 0.2032)
		(layers "F.Cu" "B.Cu")
		(net "GND")
	)
	(via
		(at 221.392496 -308.892956)
		(size 0.508)
		(drill 0.254)
		(layers "F.Cu" "B.Cu")
		(net "GND")
	)
	(via
		(at 270.80845 -341.805514)
		(size 0.4572)
		(drill 0.254)
		(layers "F.Cu" "B.Cu")
		(net "GND")
	)
	(via
		(at 127.898398 -21.738336)
		(size 0.508)
		(drill 0.254)
		(layers "F.Cu" "B.Cu")
		(net "GND")
	)
	(via
		(at 391.799826 -305.399948)
		(size 0.4064)
		(drill 0.2032)
		(layers "F.Cu" "B.Cu")
		(net "GND")
	)
	(via
		(at 84.196174 -350.977454)
		(size 0.4572)
		(drill 0.254)
		(layers "F.Cu" "B.Cu")
		(net "GND")
	)
	(via
		(at 80.54975 -306.349908)
		(size 0.4064)
		(drill 0.2032)
		(layers "F.Cu" "B.Cu")
		(net "GND")
	)
	(via
		(at 169.465244 -347.951806)
		(size 0.4572)
		(drill 0.254)
		(layers "F.Cu" "B.Cu")
		(net "GND")
	)
	(via
		(at 246.290592 -282.982162)
		(size 0.508)
		(drill 0.254)
		(layers "F.Cu" "B.Cu")
		(net "GND")
	)
	(via
		(at 466.834982 -415.587434)
		(size 0.508)
		(drill 0.254)
		(layers "F.Cu" "B.Cu")
		(net "GND")
	)
	(via
		(at 303.724818 -301.124874)
		(size 0.4064)
		(drill 0.2032)
		(layers "F.Cu" "B.Cu")
		(net "GND")
	)
	(via
		(at 301.761144 -60.099194)
		(size 0.508)
		(drill 0.254)
		(layers "F.Cu" "B.Cu")
		(net "GND")
	)
	(via
		(at 370.119656 -38.701218)
		(size 0.508)
		(drill 0.254)
		(layers "F.Cu" "B.Cu")
		(net "GND")
	)
	(via
		(at 10.020808 -317.736728)
		(size 0.508)
		(drill 0.254)
		(layers "F.Cu" "B.Cu")
		(net "GND")
	)
	(via
		(at 389.899906 -306.349908)
		(size 0.4064)
		(drill 0.2032)
		(layers "F.Cu" "B.Cu")
		(net "GND")
	)
	(via
		(at 200.908158 -135.114538)
		(size 0.508)
		(drill 0.254)
		(layers "F.Cu" "B.Cu")
		(net "GND")
	)
	(via
		(at 14.523212 -249.272044)
		(size 0.508)
		(drill 0.254)
		(layers "F.Cu" "B.Cu")
		(net "GND")
	)
	(via
		(at 422.674796 -292.574726)
		(size 0.4064)
		(drill 0.2032)
		(layers "F.Cu" "B.Cu")
		(net "GND")
	)
	(via
		(at 180.64226 -357.123746)
		(size 0.4572)
		(drill 0.254)
		(layers "F.Cu" "B.Cu")
		(net "GND")
	)
	(via
		(at 338.237322 -305.008534)
		(size 0.508)
		(drill 0.254)
		(layers "F.Cu" "B.Cu")
		(net "GND")
	)
	(via
		(at 69.62267 -23.880318)
		(size 0.508)
		(drill 0.254)
		(layers "F.Cu" "B.Cu")
		(net "GND")
	)
	(via
		(at 104.589072 -103.69296)
		(size 0.508)
		(drill 0.254)
		(layers "F.Cu" "B.Cu")
		(net "GND")
	)
	(via
		(at 70.574916 -284.974792)
		(size 0.4064)
		(drill 0.2032)
		(layers "F.Cu" "B.Cu")
		(net "GND")
	)
	(via
		(at 73.547732 -372.240302)
		(size 0.508)
		(drill 0.254)
		(layers "F.Cu" "B.Cu")
		(net "GND")
	)
	(via
		(at 313.224926 -301.124874)
		(size 0.4064)
		(drill 0.2032)
		(layers "F.Cu" "B.Cu")
		(net "GND")
	)
	(via
		(at 386.701792 -102.716584)
		(size 0.508)
		(drill 0.254)
		(layers "F.Cu" "B.Cu")
		(net "GND")
	)
	(via
		(at 304.545238 -200.81494)
		(size 0.508)
		(drill 0.254)
		(layers "F.Cu" "B.Cu")
		(net "GND")
	)
	(via
		(at 302.774858 -287.824926)
		(size 0.4064)
		(drill 0.2032)
		(layers "F.Cu" "B.Cu")
		(net "GND")
	)
	(via
		(at 161.025078 -301.124874)
		(size 0.4064)
		(drill 0.2032)
		(layers "F.Cu" "B.Cu")
		(net "GND")
	)
	(via
		(at 153.42489 -280.224738)
		(size 0.4064)
		(drill 0.2032)
		(layers "F.Cu" "B.Cu")
		(net "GND")
	)
	(via
		(at 142.446756 -228.859588)
		(size 0.508)
		(drill 0.254)
		(layers "F.Cu" "B.Cu")
		(net "GND")
	)
	(via
		(at 422.548304 -152.95499)
		(size 0.508)
		(drill 0.254)
		(layers "F.Cu" "B.Cu")
		(net "GND")
	)
	(via
		(at 44.831254 -60.099194)
		(size 0.508)
		(drill 0.254)
		(layers "F.Cu" "B.Cu")
		(net "GND")
	)
	(via
		(at 122.2502 -344.831162)
		(size 0.4572)
		(drill 0.254)
		(layers "F.Cu" "B.Cu")
		(net "GND")
	)
	(via
		(at 21.872448 -345.465146)
		(size 0.4064)
		(drill 0.2032)
		(layers "F.Cu" "B.Cu")
		(net "GND")
	)
	(via
		(at 132.990082 -113.589054)
		(size 0.508)
		(drill 0.254)
		(layers "F.Cu" "B.Cu")
		(net "GND")
	)
	(via
		(at 166.249604 -272.14957)
		(size 0.4064)
		(drill 0.2032)
		(layers "F.Cu" "B.Cu")
		(net "GND")
	)
	(via
		(at 171.949872 -316.799722)
		(size 0.4064)
		(drill 0.2032)
		(layers "F.Cu" "B.Cu")
		(net "GND")
	)
	(via
		(at 93.523054 -347.951806)
		(size 0.4572)
		(drill 0.254)
		(layers "F.Cu" "B.Cu")
		(net "GND")
	)
	(via
		(at 48.24984 -276.899878)
		(size 0.4064)
		(drill 0.2032)
		(layers "F.Cu" "B.Cu")
		(net "GND")
	)
	(via
		(at 163.747958 -397.140176)
		(size 0.508)
		(drill 0.254)
		(layers "F.Cu" "B.Cu")
		(net "GND")
	)
	(via
		(at 74.834496 -71.451978)
		(size 0.508)
		(drill 0.254)
		(layers "F.Cu" "B.Cu")
		(net "GND")
	)
	(via
		(at 319.781936 -349.219774)
		(size 0.4572)
		(drill 0.254)
		(layers "F.Cu" "B.Cu")
		(net "GND")
	)
	(via
		(at 284.503114 -352.245422)
		(size 0.4572)
		(drill 0.254)
		(layers "F.Cu" "B.Cu")
		(net "GND")
	)
	(via
		(at 357.948992 -25.990042)
		(size 0.508)
		(drill 0.254)
		(layers "F.Cu" "B.Cu")
		(net "GND")
	)
	(via
		(at 66.774822 -306.824888)
		(size 0.4064)
		(drill 0.2032)
		(layers "F.Cu" "B.Cu")
		(net "GND")
	)
	(via
		(at 392.749786 -312.049922)
		(size 0.4064)
		(drill 0.2032)
		(layers "F.Cu" "B.Cu")
		(net "GND")
	)
	(via
		(at 157.699964 -314.899802)
		(size 0.4064)
		(drill 0.2032)
		(layers "F.Cu" "B.Cu")
		(net "GND")
	)
	(via
		(at 177.748946 -34.990024)
		(size 0.508)
		(drill 0.254)
		(layers "F.Cu" "B.Cu")
		(net "GND")
	)
	(via
		(at 289.340036 -27.729688)
		(size 0.508)
		(drill 0.254)
		(layers "F.Cu" "B.Cu")
		(net "GND")
	)
	(via
		(at 96.67113 -32.911796)
		(size 0.508)
		(drill 0.254)
		(layers "F.Cu" "B.Cu")
		(net "GND")
	)
	(via
		(at 276.76983 -25.832054)
		(size 0.508)
		(drill 0.254)
		(layers "F.Cu" "B.Cu")
		(net "GND")
	)
	(via
		(at 375.358152 -350.977454)
		(size 0.4572)
		(drill 0.254)
		(layers "F.Cu" "B.Cu")
		(net "GND")
	)
	(via
		(at 305.624738 -297.32478)
		(size 0.4064)
		(drill 0.2032)
		(layers "F.Cu" "B.Cu")
		(net "GND")
	)
	(via
		(at 102.030022 -105.057194)
		(size 0.508)
		(drill 0.254)
		(layers "F.Cu" "B.Cu")
		(net "GND")
	)
	(via
		(at 374.927876 -382.84023)
		(size 0.508)
		(drill 0.254)
		(layers "F.Cu" "B.Cu")
		(net "GND")
	)
	(via
		(at 250.19762 -198.425816)
		(size 0.508)
		(drill 0.254)
		(layers "F.Cu" "B.Cu")
		(net "GND")
	)
	(via
		(at 324.369684 -354.732082)
		(size 0.4064)
		(drill 0.2032)
		(layers "F.Cu" "B.Cu")
		(net "GND")
	)
	(via
		(at 278.074882 -291.624766)
		(size 0.4064)
		(drill 0.2032)
		(layers "F.Cu" "B.Cu")
		(net "GND")
	)
	(via
		(at 383.426208 -347.951806)
		(size 0.4572)
		(drill 0.254)
		(layers "F.Cu" "B.Cu")
		(net "GND")
	)
	(via
		(at 111.352584 -129.919222)
		(size 0.508)
		(drill 0.254)
		(layers "F.Cu" "B.Cu")
		(net "GND")
	)
	(via
		(at 77.978254 -346.09913)
		(size 0.4572)
		(drill 0.254)
		(layers "F.Cu" "B.Cu")
		(net "GND")
	)
	(via
		(at 391.485882 -90.056462)
		(size 0.508)
		(drill 0.254)
		(layers "F.Cu" "B.Cu")
		(net "GND")
	)
	(via
		(at 251.97943 -93.105986)
		(size 0.508)
		(drill 0.254)
		(layers "F.Cu" "B.Cu")
		(net "GND")
	)
	(via
		(at 396.54988 -319.65011)
		(size 0.4064)
		(drill 0.2032)
		(layers "F.Cu" "B.Cu")
		(net "GND")
	)
	(via
		(at 429.927766 -380.040134)
		(size 0.508)
		(drill 0.254)
		(layers "F.Cu" "B.Cu")
		(net "GND")
	)
	(via
		(at 133.869684 -289.41649)
		(size 0.508)
		(drill 0.254)
		(layers "F.Cu" "B.Cu")
		(net "GND")
	)
	(via
		(at 201.920094 -33.19018)
		(size 0.508)
		(drill 0.254)
		(layers "F.Cu" "B.Cu")
		(net "GND")
	)
	(via
		(at 191.920622 -113.260632)
		(size 0.508)
		(drill 0.254)
		(layers "F.Cu" "B.Cu")
		(net "GND")
	)
	(via
		(at 42.549826 -314.899802)
		(size 0.4064)
		(drill 0.2032)
		(layers "F.Cu" "B.Cu")
		(net "GND")
	)
	(via
		(at 425.901104 -346.09913)
		(size 0.4572)
		(drill 0.254)
		(layers "F.Cu" "B.Cu")
		(net "GND")
	)
	(via
		(at 192.849754 -276.899878)
		(size 0.4064)
		(drill 0.2032)
		(layers "F.Cu" "B.Cu")
		(net "GND")
	)
	(via
		(at 77.947774 -402.140166)
		(size 0.508)
		(drill 0.254)
		(layers "F.Cu" "B.Cu")
		(net "GND")
	)
	(via
		(at 315.740288 -147.824698)
		(size 0.508)
		(drill 0.254)
		(layers "F.Cu" "B.Cu")
		(net "GND")
	)
	(via
		(at 415.549842 -275.949918)
		(size 0.4064)
		(drill 0.2032)
		(layers "F.Cu" "B.Cu")
		(net "GND")
	)
	(via
		(at 277.599902 -305.399948)
		(size 0.4064)
		(drill 0.2032)
		(layers "F.Cu" "B.Cu")
		(net "GND")
	)
	(via
		(at 373.990362 -106.003852)
		(size 0.508)
		(drill 0.254)
		(layers "F.Cu" "B.Cu")
		(net "GND")
	)
	(via
		(at 75.32497 -290.674806)
		(size 0.4064)
		(drill 0.2032)
		(layers "F.Cu" "B.Cu")
		(net "GND")
	)
	(via
		(at 175.920146 -29.590238)
		(size 0.508)
		(drill 0.254)
		(layers "F.Cu" "B.Cu")
		(net "GND")
	)
	(via
		(at 171.407074 -49.574704)
		(size 0.508)
		(drill 0.254)
		(layers "F.Cu" "B.Cu")
		(net "GND")
	)
	(via
		(at 378.83846 -351.611438)
		(size 0.4064)
		(drill 0.2032)
		(layers "F.Cu" "B.Cu")
		(net "GND")
	)
	(via
		(at 165.947852 -399.441924)
		(size 0.508)
		(drill 0.254)
		(layers "F.Cu" "B.Cu")
		(net "GND")
	)
	(via
		(at 82.449924 -282.599892)
		(size 0.4064)
		(drill 0.2032)
		(layers "F.Cu" "B.Cu")
		(net "GND")
	)
	(via
		(at 312.749692 -311.099962)
		(size 0.4064)
		(drill 0.2032)
		(layers "F.Cu" "B.Cu")
		(net "GND")
	)
	(via
		(at 275.176234 -355.366066)
		(size 0.4572)
		(drill 0.254)
		(layers "F.Cu" "B.Cu")
		(net "GND")
	)
	(via
		(at 240.300256 -64.261492)
		(size 0.508)
		(drill 0.254)
		(layers "F.Cu" "B.Cu")
		(net "GND")
	)
	(via
		(at 312.274712 -290.674806)
		(size 0.4064)
		(drill 0.2032)
		(layers "F.Cu" "B.Cu")
		(net "GND")
	)
	(via
		(at 366.06988 -288.78149)
		(size 0.508)
		(drill 0.254)
		(layers "F.Cu" "B.Cu")
		(net "GND")
	)
	(via
		(at 418.42436 -358.391714)
		(size 0.4572)
		(drill 0.254)
		(layers "F.Cu" "B.Cu")
		(net "GND")
	)
	(via
		(at 273.799808 -318.699896)
		(size 0.4064)
		(drill 0.2032)
		(layers "F.Cu" "B.Cu")
		(net "GND")
	)
	(via
		(at 414.11271 -145.755106)
		(size 0.508)
		(drill 0.254)
		(layers "F.Cu" "B.Cu")
		(net "GND")
	)
	(via
		(at 284.724856 -296.37482)
		(size 0.4064)
		(drill 0.2032)
		(layers "F.Cu" "B.Cu")
		(net "GND")
	)
	(via
		(at 415.96691 -131.245102)
		(size 0.508)
		(drill 0.254)
		(layers "F.Cu" "B.Cu")
		(net "GND")
	)
	(via
		(at 289.46221 -352.245422)
		(size 0.4572)
		(drill 0.254)
		(layers "F.Cu" "B.Cu")
		(net "GND")
	)
	(via
		(at 0.77089 -263.661144)
		(size 0.508)
		(drill 0.254)
		(layers "F.Cu" "B.Cu")
		(net "GND")
	)
	(via
		(at 425.52493 -301.124874)
		(size 0.4064)
		(drill 0.2032)
		(layers "F.Cu" "B.Cu")
		(net "GND")
	)
	(via
		(at 258.393438 -289.532314)
		(size 0.508)
		(drill 0.254)
		(layers "F.Cu" "B.Cu")
		(net "GND")
	)
	(via
		(at 323.262244 -357.75773)
		(size 0.4064)
		(drill 0.2032)
		(layers "F.Cu" "B.Cu")
		(net "GND")
	)
	(via
		(at 87.648796 -25.990042)
		(size 0.508)
		(drill 0.254)
		(layers "F.Cu" "B.Cu")
		(net "GND")
	)
	(via
		(at 385.261104 -257.137916)
		(size 0.508)
		(drill 0.254)
		(layers "F.Cu" "B.Cu")
		(net "GND")
	)
	(via
		(at 316.800738 -29.590238)
		(size 0.508)
		(drill 0.254)
		(layers "F.Cu" "B.Cu")
		(net "GND")
	)
	(via
		(at 123.506992 -282.910788)
		(size 0.49022)
		(drill 0.254)
		(layers "F.Cu" "B.Cu")
		(net "GND")
	)
	(via
		(at 187.149994 -315.849762)
		(size 0.4064)
		(drill 0.2032)
		(layers "F.Cu" "B.Cu")
		(net "GND")
	)
	(via
		(at 388.134098 -237.844076)
		(size 0.508)
		(drill 0.254)
		(layers "F.Cu" "B.Cu")
		(net "GND")
	)
	(via
		(at 386.701792 -107.57535)
		(size 0.508)
		(drill 0.254)
		(layers "F.Cu" "B.Cu")
		(net "GND")
	)
	(via
		(at 78.64983 -312.049922)
		(size 0.4064)
		(drill 0.2032)
		(layers "F.Cu" "B.Cu")
		(net "GND")
	)
	(via
		(at 313.699906 -317.749936)
		(size 0.4064)
		(drill 0.2032)
		(layers "F.Cu" "B.Cu")
		(net "GND")
	)
	(via
		(at 64.59347 -145.755106)
		(size 0.508)
		(drill 0.254)
		(layers "F.Cu" "B.Cu")
		(net "GND")
	)
	(via
		(at 32.8295 -349.219774)
		(size 0.4572)
		(drill 0.254)
		(layers "F.Cu" "B.Cu")
		(net "GND")
	)
	(via
		(at 38.275006 -284.974792)
		(size 0.4064)
		(drill 0.2032)
		(layers "F.Cu" "B.Cu")
		(net "GND")
	)
	(via
		(at 430.488852 -345.465146)
		(size 0.4064)
		(drill 0.2032)
		(layers "F.Cu" "B.Cu")
		(net "GND")
	)
	(via
		(at 149.920198 -31.390336)
		(size 0.508)
		(drill 0.254)
		(layers "F.Cu" "B.Cu")
		(net "GND")
	)
	(via
		(at 341.927942 -409.940252)
		(size 0.508)
		(drill 0.254)
		(layers "F.Cu" "B.Cu")
		(net "GND")
	)
	(via
		(at 40.174926 -284.024832)
		(size 0.4064)
		(drill 0.2032)
		(layers "F.Cu" "B.Cu")
		(net "GND")
	)
	(via
		(at 379.327918 -395.938502)
		(size 0.508)
		(drill 0.254)
		(layers "F.Cu" "B.Cu")
		(net "GND")
	)
	(via
		(at 130.00228 -58.731404)
		(size 0.508)
		(drill 0.254)
		(layers "F.Cu" "B.Cu")
		(net "GND")
	)
	(via
		(at 38.274752 -298.27474)
		(size 0.4064)
		(drill 0.2032)
		(layers "F.Cu" "B.Cu")
		(net "GND")
	)
	(via
		(at 295.998138 -19.096736)
		(size 0.508)
		(drill 0.254)
		(layers "F.Cu" "B.Cu")
		(net "GND")
	)
	(via
		(at 390.857994 -58.791094)
		(size 0.508)
		(drill 0.254)
		(layers "F.Cu" "B.Cu")
		(net "GND")
	)
	(via
		(at 339.948012 -84.924138)
		(size 0.508)
		(drill 0.254)
		(layers "F.Cu" "B.Cu")
		(net "GND")
	)
	(via
		(at 439.021982 -99.614482)
		(size 0.508)
		(drill 0.254)
		(layers "F.Cu" "B.Cu")
		(net "GND")
	)
	(via
		(at 416.974782 -299.224954)
		(size 0.4064)
		(drill 0.2032)
		(layers "F.Cu" "B.Cu")
		(net "GND")
	)
	(via
		(at 302.931322 -6.292342)
		(size 0.508)
		(drill 0.254)
		(layers "F.Cu" "B.Cu")
		(net "GND")
	)
	(via
		(at 383.61112 -228.531928)
		(size 0.508)
		(drill 0.254)
		(layers "F.Cu" "B.Cu")
		(net "GND")
	)
	(via
		(at 45.39996 -318.699896)
		(size 0.4064)
		(drill 0.2032)
		(layers "F.Cu" "B.Cu")
		(net "GND")
	)
	(via
		(at 62.499748 -310.149748)
		(size 0.4064)
		(drill 0.2032)
		(layers "F.Cu" "B.Cu")
		(net "GND")
	)
	(via
		(at 341.59952 -270.001492)
		(size 0.508)
		(drill 0.254)
		(layers "F.Cu" "B.Cu")
		(net "GND")
	)
	(via
		(at 182.547514 -145.755106)
		(size 0.508)
		(drill 0.254)
		(layers "F.Cu" "B.Cu")
		(net "GND")
	)
	(via
		(at 182.216298 -13.619226)
		(size 0.508)
		(drill 0.254)
		(layers "F.Cu" "B.Cu")
		(net "GND")
	)
	(via
		(at 431.700178 -304.449734)
		(size 0.4064)
		(drill 0.2032)
		(layers "F.Cu" "B.Cu")
		(net "GND")
	)
	(via
		(at 38.275006 -279.274778)
		(size 0.4064)
		(drill 0.2032)
		(layers "F.Cu" "B.Cu")
		(net "GND")
	)
	(via
		(at 179.898294 -19.757136)
		(size 0.508)
		(drill 0.254)
		(layers "F.Cu" "B.Cu")
		(net "GND")
	)
	(via
		(at 114.773456 -357.123746)
		(size 0.4572)
		(drill 0.254)
		(layers "F.Cu" "B.Cu")
		(net "GND")
	)
	(via
		(at 60.3758 -389.0264)
		(size 0.508)
		(drill 0.254)
		(layers "F.Cu" "B.Cu")
		(net "GND")
	)
	(via
		(at 167.849804 -144.885156)
		(size 0.508)
		(drill 0.254)
		(layers "F.Cu" "B.Cu")
		(net "GND")
	)
	(via
		(at 286.149796 -281.649932)
		(size 0.4064)
		(drill 0.2032)
		(layers "F.Cu" "B.Cu")
		(net "GND")
	)
	(via
		(at 62.974982 -303.974754)
		(size 0.4064)
		(drill 0.2032)
		(layers "F.Cu" "B.Cu")
		(net "GND")
	)
	(via
		(at 276.649688 -311.099962)
		(size 0.4064)
		(drill 0.2032)
		(layers "F.Cu" "B.Cu")
		(net "GND")
	)
	(via
		(at 144.01292 -357.123746)
		(size 0.4572)
		(drill 0.254)
		(layers "F.Cu" "B.Cu")
		(net "GND")
	)
	(via
		(at 131.948428 -354.732082)
		(size 0.4064)
		(drill 0.2032)
		(layers "F.Cu" "B.Cu")
		(net "GND")
	)
	(via
		(at 106.992674 -85.984842)
		(size 0.508)
		(drill 0.254)
		(layers "F.Cu" "B.Cu")
		(net "GND")
	)
	(via
		(at 366.496346 -60.099194)
		(size 0.508)
		(drill 0.254)
		(layers "F.Cu" "B.Cu")
		(net "GND")
	)
	(via
		(at 298.417742 -351.611438)
		(size 0.4064)
		(drill 0.2032)
		(layers "F.Cu" "B.Cu")
		(net "GND")
	)
	(via
		(at 257.455924 -393.147296)
		(size 0.508)
		(drill 0.254)
		(layers "F.Cu" "B.Cu")
		(net "GND")
	)
	(via
		(at 29.54782 -409.940252)
		(size 0.508)
		(drill 0.254)
		(layers "F.Cu" "B.Cu")
		(net "GND")
	)
	(via
		(at 130.34899 -27.79014)
		(size 0.508)
		(drill 0.254)
		(layers "F.Cu" "B.Cu")
		(net "GND")
	)
	(via
		(at 96.184466 -72.56526)
		(size 0.508)
		(drill 0.254)
		(layers "F.Cu" "B.Cu")
		(net "GND")
	)
	(via
		(at 387.223 -241.173)
		(size 0.508)
		(drill 0.254)
		(layers "F.Cu" "B.Cu")
		(net "GND")
	)
	(via
		(at 226.314762 -328.36231)
		(size 0.508)
		(drill 0.254)
		(layers "F.Cu" "B.Cu")
		(net "GND")
	)
	(via
		(at 330.958952 -341.805514)
		(size 0.4572)
		(drill 0.254)
		(layers "F.Cu" "B.Cu")
		(net "GND")
	)
	(via
		(at 186.86018 -347.951806)
		(size 0.4572)
		(drill 0.254)
		(layers "F.Cu" "B.Cu")
		(net "GND")
	)
	(via
		(at 287.471358 -51.661822)
		(size 0.508)
		(drill 0.254)
		(layers "F.Cu" "B.Cu")
		(net "GND")
	)
	(via
		(at 53.474874 -287.824926)
		(size 0.4064)
		(drill 0.2032)
		(layers "F.Cu" "B.Cu")
		(net "GND")
	)
	(via
		(at 327.673208 -72.56526)
		(size 0.508)
		(drill 0.254)
		(layers "F.Cu" "B.Cu")
		(net "GND")
	)
	(via
		(at 447.613278 -33.459674)
		(size 0.508)
		(drill 0.254)
		(layers "F.Cu" "B.Cu")
		(net "GND")
	)
	(via
		(at 232.590848 -155.903168)
		(size 0.508)
		(drill 0.254)
		(layers "F.Cu" "B.Cu")
		(net "GND")
	)
	(via
		(at 31.58236 -37.087048)
		(size 0.508)
		(drill 0.254)
		(layers "F.Cu" "B.Cu")
		(net "GND")
	)
	(via
		(at 62.974982 -289.724846)
		(size 0.4064)
		(drill 0.2032)
		(layers "F.Cu" "B.Cu")
		(net "GND")
	)
	(via
		(at 39.418768 -345.465146)
		(size 0.4064)
		(drill 0.2032)
		(layers "F.Cu" "B.Cu")
		(net "GND")
	)
	(via
		(at 335.328006 -369.938554)
		(size 0.508)
		(drill 0.254)
		(layers "F.Cu" "B.Cu")
		(net "GND")
	)
	(via
		(at 168.625012 -285.924752)
		(size 0.4064)
		(drill 0.2032)
		(layers "F.Cu" "B.Cu")
		(net "GND")
	)
	(via
		(at 34.679636 -349.219774)
		(size 0.4572)
		(drill 0.254)
		(layers "F.Cu" "B.Cu")
		(net "GND")
	)
	(via
		(at 431.143156 -52.536852)
		(size 0.508)
		(drill 0.254)
		(layers "F.Cu" "B.Cu")
		(net "GND")
	)
	(via
		(at 188.574934 -301.124874)
		(size 0.4064)
		(drill 0.2032)
		(layers "F.Cu" "B.Cu")
		(net "GND")
	)
	(via
		(at 70.574916 -286.874966)
		(size 0.4064)
		(drill 0.2032)
		(layers "F.Cu" "B.Cu")
		(net "GND")
	)
	(via
		(at 406.524968 -296.37482)
		(size 0.4064)
		(drill 0.2032)
		(layers "F.Cu" "B.Cu")
		(net "GND")
	)
	(via
		(at 163.701476 -145.372836)
		(size 0.508)
		(drill 0.254)
		(layers "F.Cu" "B.Cu")
		(net "GND")
	)
	(via
		(at 431.700178 -310.149748)
		(size 0.4064)
		(drill 0.2032)
		(layers "F.Cu" "B.Cu")
		(net "GND")
	)
	(via
		(at 293.829994 -352.245422)
		(size 0.4572)
		(drill 0.254)
		(layers "F.Cu" "B.Cu")
		(net "GND")
	)
	(via
		(at 175.749966 -280.699718)
		(size 0.4064)
		(drill 0.2032)
		(layers "F.Cu" "B.Cu")
		(net "GND")
	)
	(via
		(at 380.366524 -35.871912)
		(size 0.508)
		(drill 0.254)
		(layers "F.Cu" "B.Cu")
		(net "GND")
	)
	(via
		(at 447.613278 -34.718498)
		(size 0.508)
		(drill 0.254)
		(layers "F.Cu" "B.Cu")
		(net "GND")
	)
	(via
		(at 72.232266 -114.812572)
		(size 0.508)
		(drill 0.254)
		(layers "F.Cu" "B.Cu")
		(net "GND")
	)
	(via
		(at 18.269712 -221.915482)
		(size 0.508)
		(drill 0.254)
		(layers "F.Cu" "B.Cu")
		(net "GND")
	)
	(via
		(at 423.62501 -296.37482)
		(size 0.4064)
		(drill 0.2032)
		(layers "F.Cu" "B.Cu")
		(net "GND")
	)
	(via
		(at 421.724836 -303.974754)
		(size 0.4064)
		(drill 0.2032)
		(layers "F.Cu" "B.Cu")
		(net "GND")
	)
	(via
		(at 5.183632 -14.045184)
		(size 0.508)
		(drill 0.254)
		(layers "F.Cu" "B.Cu")
		(net "GND")
	)
	(via
		(at 85.103208 -60.627006)
		(size 0.508)
		(drill 0.254)
		(layers "F.Cu" "B.Cu")
		(net "GND")
	)
	(via
		(at 179.55006 -310.149748)
		(size 0.4064)
		(drill 0.2032)
		(layers "F.Cu" "B.Cu")
		(net "GND")
	)
	(via
		(at 386.575046 -291.624766)
		(size 0.4064)
		(drill 0.2032)
		(layers "F.Cu" "B.Cu")
		(net "GND")
	)
	(via
		(at 153.233628 -132.04317)
		(size 0.508)
		(drill 0.254)
		(layers "F.Cu" "B.Cu")
		(net "GND")
	)
	(via
		(at 64.874902 -302.074834)
		(size 0.4064)
		(drill 0.2032)
		(layers "F.Cu" "B.Cu")
		(net "GND")
	)
	(via
		(at 113.677446 -307.242718)
		(size 0.508)
		(drill 0.254)
		(layers "F.Cu" "B.Cu")
		(net "GND")
	)
	(via
		(at 446.380108 -209.578194)
		(size 0.508)
		(drill 0.254)
		(layers "F.Cu" "B.Cu")
		(net "GND")
	)
	(via
		(at 466.835998 -298.003976)
		(size 0.508)
		(drill 0.254)
		(layers "F.Cu" "B.Cu")
		(net "GND")
	)
	(via
		(at 43.47337 -73.20026)
		(size 0.508)
		(drill 0.254)
		(layers "F.Cu" "B.Cu")
		(net "GND")
	)
	(via
		(at 40.24884 -33.19018)
		(size 0.508)
		(drill 0.254)
		(layers "F.Cu" "B.Cu")
		(net "GND")
	)
	(via
		(at 268.958314 -347.951806)
		(size 0.4572)
		(drill 0.254)
		(layers "F.Cu" "B.Cu")
		(net "GND")
	)
	(via
		(at 42.549826 -311.099962)
		(size 0.4064)
		(drill 0.2032)
		(layers "F.Cu" "B.Cu")
		(net "GND")
	)
	(via
		(at 304.527712 -378.940314)
		(size 0.508)
		(drill 0.254)
		(layers "F.Cu" "B.Cu")
		(net "GND")
	)
	(via
		(at 298.012612 -120.035066)
		(size 0.508)
		(drill 0.254)
		(layers "F.Cu" "B.Cu")
		(net "GND")
	)
	(via
		(at 185.725054 -305.874928)
		(size 0.4064)
		(drill 0.2032)
		(layers "F.Cu" "B.Cu")
		(net "GND")
	)
	(via
		(at 438.336944 -346.09913)
		(size 0.4572)
		(drill 0.254)
		(layers "F.Cu" "B.Cu")
		(net "GND")
	)
	(via
		(at 292.57117 -358.391714)
		(size 0.4572)
		(drill 0.254)
		(layers "F.Cu" "B.Cu")
		(net "GND")
	)
	(via
		(at 400.229832 -357.123746)
		(size 0.4572)
		(drill 0.254)
		(layers "F.Cu" "B.Cu")
		(net "GND")
	)
	(via
		(at 422.548304 -151.155146)
		(size 0.508)
		(drill 0.254)
		(layers "F.Cu" "B.Cu")
		(net "GND")
	)
	(via
		(at 205.644242 -294.682672)
		(size 0.508)
		(drill 0.254)
		(layers "F.Cu" "B.Cu")
		(net "GND")
	)
	(via
		(at 77.947774 -374.938544)
		(size 0.508)
		(drill 0.254)
		(layers "F.Cu" "B.Cu")
		(net "GND")
	)
	(via
		(at 178.792124 -341.781638)
		(size 0.4572)
		(drill 0.254)
		(layers "F.Cu" "B.Cu")
		(net "GND")
	)
	(via
		(at 347.708982 -285.953454)
		(size 0.508)
		(drill 0.254)
		(layers "F.Cu" "B.Cu")
		(net "GND")
	)
	(via
		(at 153.233628 -109.916722)
		(size 0.508)
		(drill 0.254)
		(layers "F.Cu" "B.Cu")
		(net "GND")
	)
	(via
		(at 293.27475 -298.27474)
		(size 0.4064)
		(drill 0.2032)
		(layers "F.Cu" "B.Cu")
		(net "GND")
	)
	(via
		(at 295.174924 -289.724846)
		(size 0.4064)
		(drill 0.2032)
		(layers "F.Cu" "B.Cu")
		(net "GND")
	)
	(via
		(at 94.55785 -57.521094)
		(size 0.508)
		(drill 0.254)
		(layers "F.Cu" "B.Cu")
		(net "GND")
	)
	(via
		(at 119.747792 -376.241818)
		(size 0.4572)
		(drill 0.254)
		(layers "F.Cu" "B.Cu")
		(net "GND")
	)
	(via
		(at 334.067912 -354.098098)
		(size 0.4572)
		(drill 0.254)
		(layers "F.Cu" "B.Cu")
		(net "GND")
	)
	(via
		(at 418.971222 -32.911796)
		(size 0.508)
		(drill 0.254)
		(layers "F.Cu" "B.Cu")
		(net "GND")
	)
	(via
		(at 267.848842 -31.390082)
		(size 0.508)
		(drill 0.254)
		(layers "F.Cu" "B.Cu")
		(net "GND")
	)
	(via
		(at 66.214752 -26.171398)
		(size 0.508)
		(drill 0.254)
		(layers "F.Cu" "B.Cu")
		(net "GND")
	)
	(via
		(at 132.167884 -285.953454)
		(size 0.508)
		(drill 0.254)
		(layers "F.Cu" "B.Cu")
		(net "GND")
	)
	(via
		(at 449.695062 -105.057194)
		(size 0.508)
		(drill 0.254)
		(layers "F.Cu" "B.Cu")
		(net "GND")
	)
	(via
		(at 326.480678 -29.589984)
		(size 0.508)
		(drill 0.254)
		(layers "F.Cu" "B.Cu")
		(net "GND")
	)
	(via
		(at 395.4907 -351.611438)
		(size 0.4064)
		(drill 0.2032)
		(layers "F.Cu" "B.Cu")
		(net "GND")
	)
	(via
		(at 299.449744 -310.149748)
		(size 0.4064)
		(drill 0.2032)
		(layers "F.Cu" "B.Cu")
		(net "GND")
	)
	(via
		(at 55.850028 -319.65011)
		(size 0.4064)
		(drill 0.2032)
		(layers "F.Cu" "B.Cu")
		(net "GND")
	)
	(via
		(at 59.649868 -312.049922)
		(size 0.4064)
		(drill 0.2032)
		(layers "F.Cu" "B.Cu")
		(net "GND")
	)
	(via
		(at 169.099992 -276.899878)
		(size 0.4064)
		(drill 0.2032)
		(layers "F.Cu" "B.Cu")
		(net "GND")
	)
	(via
		(at 280.449782 -314.899802)
		(size 0.4064)
		(drill 0.2032)
		(layers "F.Cu" "B.Cu")
		(net "GND")
	)
	(via
		(at 388.127748 -397.140176)
		(size 0.508)
		(drill 0.254)
		(layers "F.Cu" "B.Cu")
		(net "GND")
	)
	(via
		(at 91.607386 -307.286406)
		(size 0.508)
		(drill 0.254)
		(layers "F.Cu" "B.Cu")
		(net "GND")
	)
	(via
		(at 383.72796 -369.938554)
		(size 0.508)
		(drill 0.254)
		(layers "F.Cu" "B.Cu")
		(net "GND")
	)
	(via
		(at 46.673008 -23.880318)
		(size 0.508)
		(drill 0.254)
		(layers "F.Cu" "B.Cu")
		(net "GND")
	)
	(via
		(at 397.97482 -284.024832)
		(size 0.4064)
		(drill 0.2032)
		(layers "F.Cu" "B.Cu")
		(net "GND")
	)
	(via
		(at 315.782198 -37.087048)
		(size 0.508)
		(drill 0.254)
		(layers "F.Cu" "B.Cu")
		(net "GND")
	)
	(via
		(at 301.67326 -72.56526)
		(size 0.508)
		(drill 0.254)
		(layers "F.Cu" "B.Cu")
		(net "GND")
	)
	(via
		(at 117.511068 -342.439498)
		(size 0.4064)
		(drill 0.2032)
		(layers "F.Cu" "B.Cu")
		(net "GND")
	)
	(via
		(at 230.421942 -111.907574)
		(size 0.508)
		(drill 0.254)
		(layers "F.Cu" "B.Cu")
		(net "GND")
	)
	(via
		(at 375.570496 -28.802076)
		(size 0.508)
		(drill 0.254)
		(layers "F.Cu" "B.Cu")
		(net "GND")
	)
	(via
		(at 371.6401 -73.87463)
		(size 0.508)
		(drill 0.254)
		(layers "F.Cu" "B.Cu")
		(net "GND")
	)
	(via
		(at 106.992674 -87.827104)
		(size 0.508)
		(drill 0.254)
		(layers "F.Cu" "B.Cu")
		(net "GND")
	)
	(via
		(at 269.049754 -309.199788)
		(size 0.4064)
		(drill 0.2032)
		(layers "F.Cu" "B.Cu")
		(net "GND")
	)
	(via
		(at 330.587604 -345.465146)
		(size 0.4064)
		(drill 0.2032)
		(layers "F.Cu" "B.Cu")
		(net "GND")
	)
	(via
		(at 375.969022 -283.131514)
		(size 0.508)
		(drill 0.254)
		(layers "F.Cu" "B.Cu")
		(net "GND")
	)
	(via
		(at 385.433824 -103.975408)
		(size 0.508)
		(drill 0.254)
		(layers "F.Cu" "B.Cu")
		(net "GND")
	)
	(via
		(at 219.60205 -204.851)
		(size 0.508)
		(drill 0.254)
		(layers "F.Cu" "B.Cu")
		(net "GND")
	)
	(via
		(at 194.274948 -302.074834)
		(size 0.4064)
		(drill 0.2032)
		(layers "F.Cu" "B.Cu")
		(net "GND")
	)
	(via
		(at 324.414642 -26.171398)
		(size 0.508)
		(drill 0.254)
		(layers "F.Cu" "B.Cu")
		(net "GND")
	)
	(via
		(at 82.449924 -284.499812)
		(size 0.4064)
		(drill 0.2032)
		(layers "F.Cu" "B.Cu")
		(net "GND")
	)
	(via
		(at 399.400014 -281.649932)
		(size 0.4064)
		(drill 0.2032)
		(layers "F.Cu" "B.Cu")
		(net "GND")
	)
	(via
		(at 169.465244 -343.073482)
		(size 0.4572)
		(drill 0.254)
		(layers "F.Cu" "B.Cu")
		(net "GND")
	)
	(via
		(at 196.998082 -146.017996)
		(size 0.508)
		(drill 0.254)
		(layers "F.Cu" "B.Cu")
		(net "GND")
	)
	(via
		(at 278.549862 -276.899878)
		(size 0.4064)
		(drill 0.2032)
		(layers "F.Cu" "B.Cu")
		(net "GND")
	)
	(via
		(at 392.52779 -404.940262)
		(size 0.508)
		(drill 0.254)
		(layers "F.Cu" "B.Cu")
		(net "GND")
	)
	(via
		(at 171.31538 -350.977454)
		(size 0.4572)
		(drill 0.254)
		(layers "F.Cu" "B.Cu")
		(net "GND")
	)
	(via
		(at 186.200034 -281.649932)
		(size 0.4064)
		(drill 0.2032)
		(layers "F.Cu" "B.Cu")
		(net "GND")
	)
	(via
		(at 50.224436 -354.098098)
		(size 0.4572)
		(drill 0.254)
		(layers "F.Cu" "B.Cu")
		(net "GND")
	)
	(via
		(at 269.524734 -273.574764)
		(size 0.4064)
		(drill 0.2032)
		(layers "F.Cu" "B.Cu")
		(net "GND")
	)
	(via
		(at 136.773158 -23.880318)
		(size 0.508)
		(drill 0.254)
		(layers "F.Cu" "B.Cu")
		(net "GND")
	)
	(via
		(at 290.721034 -352.245422)
		(size 0.4572)
		(drill 0.254)
		(layers "F.Cu" "B.Cu")
		(net "GND")
	)
	(via
		(at 305.513232 -34.718498)
		(size 0.508)
		(drill 0.254)
		(layers "F.Cu" "B.Cu")
		(net "GND")
	)
	(via
		(at 363.42574 -128.193546)
		(size 0.508)
		(drill 0.254)
		(layers "F.Cu" "B.Cu")
		(net "GND")
	)
	(via
		(at 44.449746 -307.299868)
		(size 0.4064)
		(drill 0.2032)
		(layers "F.Cu" "B.Cu")
		(net "GND")
	)
	(via
		(at 429.800004 -313.949842)
		(size 0.4064)
		(drill 0.2032)
		(layers "F.Cu" "B.Cu")
		(net "GND")
	)
	(via
		(at 47.015146 -142.860522)
		(size 0.508)
		(drill 0.254)
		(layers "F.Cu" "B.Cu")
		(net "GND")
	)
	(via
		(at 433.96916 -357.123746)
		(size 0.4572)
		(drill 0.254)
		(layers "F.Cu" "B.Cu")
		(net "GND")
	)
	(via
		(at 165.299898 -313.949842)
		(size 0.4064)
		(drill 0.2032)
		(layers "F.Cu" "B.Cu")
		(net "GND")
	)
	(via
		(at 157.699964 -312.999882)
		(size 0.4064)
		(drill 0.2032)
		(layers "F.Cu" "B.Cu")
		(net "GND")
	)
	(via
		(at 413.174942 -300.174914)
		(size 0.4064)
		(drill 0.2032)
		(layers "F.Cu" "B.Cu")
		(net "GND")
	)
	(via
		(at 280.745692 -156.0576)
		(size 0.508)
		(drill 0.254)
		(layers "F.Cu" "B.Cu")
		(net "GND")
	)
	(via
		(at 294.22471 -297.32478)
		(size 0.4064)
		(drill 0.2032)
		(layers "F.Cu" "B.Cu")
		(net "GND")
	)
	(via
		(at 280.449782 -312.049922)
		(size 0.4064)
		(drill 0.2032)
		(layers "F.Cu" "B.Cu")
		(net "GND")
	)
	(via
		(at 235.564426 -289.391344)
		(size 0.508)
		(drill 0.254)
		(layers "F.Cu" "B.Cu")
		(net "GND")
	)
	(via
		(at 293.27475 -291.624766)
		(size 0.4064)
		(drill 0.2032)
		(layers "F.Cu" "B.Cu")
		(net "GND")
	)
	(via
		(at 322.890896 -341.805514)
		(size 0.4572)
		(drill 0.254)
		(layers "F.Cu" "B.Cu")
		(net "GND")
	)
	(via
		(at 116.403628 -357.75773)
		(size 0.4064)
		(drill 0.2032)
		(layers "F.Cu" "B.Cu")
		(net "GND")
	)
	(via
		(at 316.999874 -38.315138)
		(size 0.508)
		(drill 0.254)
		(layers "F.Cu" "B.Cu")
		(net "GND")
	)
	(via
		(at 68.557902 -58.791094)
		(size 0.508)
		(drill 0.254)
		(layers "F.Cu" "B.Cu")
		(net "GND")
	)
	(via
		(at 437.07812 -343.073482)
		(size 0.4572)
		(drill 0.254)
		(layers "F.Cu" "B.Cu")
		(net "GND")
	)
	(via
		(at 445.13119 -60.099194)
		(size 0.508)
		(drill 0.254)
		(layers "F.Cu" "B.Cu")
		(net "GND")
	)
	(via
		(at 426.47489 -299.224954)
		(size 0.4064)
		(drill 0.2032)
		(layers "F.Cu" "B.Cu")
		(net "GND")
	)
	(via
		(at 264.800842 -33.19018)
		(size 0.508)
		(drill 0.254)
		(layers "F.Cu" "B.Cu")
		(net "GND")
	)
	(via
		(at 125.730508 -342.439498)
		(size 0.4064)
		(drill 0.2032)
		(layers "F.Cu" "B.Cu")
		(net "GND")
	)
	(via
		(at 390.327896 -382.73863)
		(size 0.508)
		(drill 0.254)
		(layers "F.Cu" "B.Cu")
		(net "GND")
	)
	(via
		(at 3.845306 -50.516282)
		(size 0.508)
		(drill 0.254)
		(layers "F.Cu" "B.Cu")
		(net "GND")
	)
	(via
		(at 204.804772 -356.021894)
		(size 0.508)
		(drill 0.254)
		(layers "F.Cu" "B.Cu")
		(net "GND")
	)
	(via
		(at 163.874958 -285.924752)
		(size 0.4064)
		(drill 0.2032)
		(layers "F.Cu" "B.Cu")
		(net "GND")
	)
	(via
		(at 404.624794 -287.824926)
		(size 0.4064)
		(drill 0.2032)
		(layers "F.Cu" "B.Cu")
		(net "GND")
	)
	(via
		(at 289.849814 -27.04973)
		(size 0.508)
		(drill 0.254)
		(layers "F.Cu" "B.Cu")
		(net "GND")
	)
	(via
		(at 19.134836 -352.245422)
		(size 0.4572)
		(drill 0.254)
		(layers "F.Cu" "B.Cu")
		(net "GND")
	)
	(via
		(at 191.094614 -103.415592)
		(size 0.508)
		(drill 0.254)
		(layers "F.Cu" "B.Cu")
		(net "GND")
	)
	(via
		(at 300.12767 -377.738386)
		(size 0.508)
		(drill 0.254)
		(layers "F.Cu" "B.Cu")
		(net "GND")
	)
	(via
		(at 170.524932 -296.37482)
		(size 0.4064)
		(drill 0.2032)
		(layers "F.Cu" "B.Cu")
		(net "GND")
	)
	(via
		(at 357.63073 -306.607718)
		(size 0.508)
		(drill 0.254)
		(layers "F.Cu" "B.Cu")
		(net "GND")
	)
	(via
		(at 318.151764 -342.439498)
		(size 0.4064)
		(drill 0.2032)
		(layers "F.Cu" "B.Cu")
		(net "GND")
	)
	(via
		(at 153.42489 -289.724846)
		(size 0.4064)
		(drill 0.2032)
		(layers "F.Cu" "B.Cu")
		(net "GND")
	)
	(via
		(at 116.910358 -276.928072)
		(size 0.508)
		(drill 0.254)
		(layers "F.Cu" "B.Cu")
		(net "GND")
	)
	(via
		(at 395.32052 -85.576918)
		(size 0.508)
		(drill 0.254)
		(layers "F.Cu" "B.Cu")
		(net "GND")
	)
	(via
		(at 76.74991 -272.14957)
		(size 0.4064)
		(drill 0.2032)
		(layers "F.Cu" "B.Cu")
		(net "GND")
	)
	(via
		(at 19.034506 -47.936658)
		(size 0.508)
		(drill 0.254)
		(layers "F.Cu" "B.Cu")
		(net "GND")
	)
	(via
		(at 305.149758 -281.649932)
		(size 0.4064)
		(drill 0.2032)
		(layers "F.Cu" "B.Cu")
		(net "GND")
	)
	(via
		(at 395.334998 -84.333588)
		(size 0.508)
		(drill 0.254)
		(layers "F.Cu" "B.Cu")
		(net "GND")
	)
	(via
		(at 155.800044 -312.999882)
		(size 0.4064)
		(drill 0.2032)
		(layers "F.Cu" "B.Cu")
		(net "GND")
	)
	(via
		(at 448.092068 -70.918832)
		(size 0.508)
		(drill 0.254)
		(layers "F.Cu" "B.Cu")
		(net "GND")
	)
	(via
		(at 433.108354 -156.283406)
		(size 0.508)
		(drill 0.254)
		(layers "F.Cu" "B.Cu")
		(net "GND")
	)
	(via
		(at 153.477214 -149.747224)
		(size 0.508)
		(drill 0.254)
		(layers "F.Cu" "B.Cu")
		(net "GND")
	)
	(via
		(at 70.574916 -292.57498)
		(size 0.4064)
		(drill 0.2032)
		(layers "F.Cu" "B.Cu")
		(net "GND")
	)
	(via
		(at 385.927854 -377.341892)
		(size 0.508)
		(drill 0.254)
		(layers "F.Cu" "B.Cu")
		(net "GND")
	)
	(via
		(at 105.254044 -106.779822)
		(size 0.508)
		(drill 0.254)
		(layers "F.Cu" "B.Cu")
		(net "GND")
	)
	(via
		(at 74.84999 -310.149748)
		(size 0.4064)
		(drill 0.2032)
		(layers "F.Cu" "B.Cu")
		(net "GND")
	)
	(via
		(at 73.547732 -403.34184)
		(size 0.508)
		(drill 0.254)
		(layers "F.Cu" "B.Cu")
		(net "GND")
	)
	(via
		(at 157.247844 -268.339062)
		(size 0.508)
		(drill 0.254)
		(layers "F.Cu" "B.Cu")
		(net "GND")
	)
	(via
		(at 384.685032 -350.977454)
		(size 0.4572)
		(drill 0.254)
		(layers "F.Cu" "B.Cu")
		(net "GND")
	)
	(via
		(at 298.647612 -129.445004)
		(size 0.508)
		(drill 0.254)
		(layers "F.Cu" "B.Cu")
		(net "GND")
	)
	(via
		(at 196.649848 -285.449772)
		(size 0.4064)
		(drill 0.2032)
		(layers "F.Cu" "B.Cu")
		(net "GND")
	)
	(via
		(at 199.64019 -145.483326)
		(size 0.508)
		(drill 0.254)
		(layers "F.Cu" "B.Cu")
		(net "GND")
	)
	(via
		(at 431.700178 -314.899548)
		(size 0.4064)
		(drill 0.2032)
		(layers "F.Cu" "B.Cu")
		(net "GND")
	)
	(via
		(at 153.42489 -292.57498)
		(size 0.4064)
		(drill 0.2032)
		(layers "F.Cu" "B.Cu")
		(net "GND")
	)
	(via
		(at 388.127748 -378.94006)
		(size 0.508)
		(drill 0.254)
		(layers "F.Cu" "B.Cu")
		(net "GND")
	)
	(via
		(at 64.59347 -152.955244)
		(size 0.508)
		(drill 0.254)
		(layers "F.Cu" "B.Cu")
		(net "GND")
	)
	(via
		(at 337.176872 -350.977454)
		(size 0.4572)
		(drill 0.254)
		(layers "F.Cu" "B.Cu")
		(net "GND")
	)
	(via
		(at 42.83837 -72.56526)
		(size 0.508)
		(drill 0.254)
		(layers "F.Cu" "B.Cu")
		(net "GND")
	)
	(via
		(at 341.927942 -373.441976)
		(size 0.508)
		(drill 0.254)
		(layers "F.Cu" "B.Cu")
		(net "GND")
	)
	(via
		(at 79.323184 -54.067456)
		(size 0.508)
		(drill 0.254)
		(layers "F.Cu" "B.Cu")
		(net "GND")
	)
	(via
		(at 416.024822 -306.824888)
		(size 0.4064)
		(drill 0.2032)
		(layers "F.Cu" "B.Cu")
		(net "GND")
	)
	(via
		(at 42.074846 -289.724846)
		(size 0.4064)
		(drill 0.2032)
		(layers "F.Cu" "B.Cu")
		(net "GND")
	)
	(via
		(at 353.143312 -52.536852)
		(size 0.508)
		(drill 0.254)
		(layers "F.Cu" "B.Cu")
		(net "GND")
	)
	(via
		(at 416.499802 -278.799798)
		(size 0.4064)
		(drill 0.2032)
		(layers "F.Cu" "B.Cu")
		(net "GND")
	)
	(via
		(at 335.350866 -288.78149)
		(size 0.508)
		(drill 0.254)
		(layers "F.Cu" "B.Cu")
		(net "GND")
	)
	(via
		(at 306.448206 -145.755106)
		(size 0.508)
		(drill 0.254)
		(layers "F.Cu" "B.Cu")
		(net "GND")
	)
	(via
		(at 249.538744 -131.960874)
		(size 0.508)
		(drill 0.254)
		(layers "F.Cu" "B.Cu")
		(net "GND")
	)
	(via
		(at 75.240642 -351.611438)
		(size 0.4064)
		(drill 0.2032)
		(layers "F.Cu" "B.Cu")
		(net "GND")
	)
	(via
		(at 234.149138 -88.041988)
		(size 0.508)
		(drill 0.254)
		(layers "F.Cu" "B.Cu")
		(net "GND")
	)
	(via
		(at 396.0749 -307.774848)
		(size 0.4064)
		(drill 0.2032)
		(layers "F.Cu" "B.Cu")
		(net "GND")
	)
	(via
		(at 397.49984 -281.649932)
		(size 0.4064)
		(drill 0.2032)
		(layers "F.Cu" "B.Cu")
		(net "GND")
	)
	(via
		(at 186.488832 -357.733854)
		(size 0.4064)
		(drill 0.2032)
		(layers "F.Cu" "B.Cu")
		(net "GND")
	)
	(via
		(at 299.924724 -285.924752)
		(size 0.4064)
		(drill 0.2032)
		(layers "F.Cu" "B.Cu")
		(net "GND")
	)
	(via
		(at 163.747958 -398.34185)
		(size 0.508)
		(drill 0.254)
		(layers "F.Cu" "B.Cu")
		(net "GND")
	)
	(via
		(at 408.120088 -29.590238)
		(size 0.508)
		(drill 0.254)
		(layers "F.Cu" "B.Cu")
		(net "GND")
	)
	(via
		(at 274.749768 -319.65011)
		(size 0.4064)
		(drill 0.2032)
		(layers "F.Cu" "B.Cu")
		(net "GND")
	)
	(via
		(at 404.145242 -51.227482)
		(size 0.508)
		(drill 0.254)
		(layers "F.Cu" "B.Cu")
		(net "GND")
	)
	(via
		(at 35.6489 -31.390082)
		(size 0.508)
		(drill 0.254)
		(layers "F.Cu" "B.Cu")
		(net "GND")
	)
	(via
		(at 341.25027 -291.32149)
		(size 0.508)
		(drill 0.254)
		(layers "F.Cu" "B.Cu")
		(net "GND")
	)
	(via
		(at 429.198278 -129.707894)
		(size 0.508)
		(drill 0.254)
		(layers "F.Cu" "B.Cu")
		(net "GND")
	)
	(via
		(at 422.260268 -19.33956)
		(size 0.508)
		(drill 0.254)
		(layers "F.Cu" "B.Cu")
		(net "GND")
	)
	(via
		(at 13.068046 -208.970372)
		(size 0.508)
		(drill 0.254)
		(layers "F.Cu" "B.Cu")
		(net "GND")
	)
	(via
		(at 132.858764 -305.008534)
		(size 0.508)
		(drill 0.254)
		(layers "F.Cu" "B.Cu")
		(net "GND")
	)
	(via
		(at 229.893876 -107.843574)
		(size 0.508)
		(drill 0.254)
		(layers "F.Cu" "B.Cu")
		(net "GND")
	)
	(via
		(at 383.72796 -384.041904)
		(size 0.508)
		(drill 0.254)
		(layers "F.Cu" "B.Cu")
		(net "GND")
	)
	(via
		(at 181.44998 -275.949918)
		(size 0.4064)
		(drill 0.2032)
		(layers "F.Cu" "B.Cu")
		(net "GND")
	)
	(via
		(at 427.615096 -43.85691)
		(size 0.508)
		(drill 0.254)
		(layers "F.Cu" "B.Cu")
		(net "GND")
	)
	(via
		(at 282.824936 -285.924752)
		(size 0.4064)
		(drill 0.2032)
		(layers "F.Cu" "B.Cu")
		(net "GND")
	)
	(via
		(at 218.95308 -104.368346)
		(size 0.508)
		(drill 0.254)
		(layers "F.Cu" "B.Cu")
		(net "GND")
	)
	(via
		(at 144.736566 -51.661822)
		(size 0.508)
		(drill 0.254)
		(layers "F.Cu" "B.Cu")
		(net "GND")
	)
	(via
		(at 143.415258 -43.85691)
		(size 0.508)
		(drill 0.254)
		(layers "F.Cu" "B.Cu")
		(net "GND")
	)
	(via
		(at 106.43616 -135.55726)
		(size 0.508)
		(drill 0.254)
		(layers "F.Cu" "B.Cu")
		(net "GND")
	)
	(via
		(at 28.636468 -51.661822)
		(size 0.508)
		(drill 0.254)
		(layers "F.Cu" "B.Cu")
		(net "GND")
	)
	(via
		(at 157.224984 -298.27474)
		(size 0.4064)
		(drill 0.2032)
		(layers "F.Cu" "B.Cu")
		(net "GND")
	)
	(via
		(at 386.701792 -100.375466)
		(size 0.508)
		(drill 0.254)
		(layers "F.Cu" "B.Cu")
		(net "GND")
	)
	(via
		(at 382.791716 -108.123228)
		(size 0.508)
		(drill 0.254)
		(layers "F.Cu" "B.Cu")
		(net "GND")
	)
	(via
		(at 38.749986 -302.549814)
		(size 0.4064)
		(drill 0.2032)
		(layers "F.Cu" "B.Cu")
		(net "GND")
	)
	(via
		(at 375.358152 -344.831162)
		(size 0.4572)
		(drill 0.254)
		(layers "F.Cu" "B.Cu")
		(net "GND")
	)
	(via
		(at 117.940328 -33.857692)
		(size 0.508)
		(drill 0.254)
		(layers "F.Cu" "B.Cu")
		(net "GND")
	)
	(via
		(at 381.576072 -341.805514)
		(size 0.4572)
		(drill 0.254)
		(layers "F.Cu" "B.Cu")
		(net "GND")
	)
	(via
		(at 151.152098 -13.613638)
		(size 0.508)
		(drill 0.254)
		(layers "F.Cu" "B.Cu")
		(net "GND")
	)
	(via
		(at 84.54771 -407.638504)
		(size 0.508)
		(drill 0.254)
		(layers "F.Cu" "B.Cu")
		(net "GND")
	)
	(via
		(at 298.647612 -151.155146)
		(size 0.508)
		(drill 0.254)
		(layers "F.Cu" "B.Cu")
		(net "GND")
	)
	(via
		(at 306.099718 -284.499812)
		(size 0.4064)
		(drill 0.2032)
		(layers "F.Cu" "B.Cu")
		(net "GND")
	)
	(via
		(at 269.765526 -151.40813)
		(size 0.508)
		(drill 0.254)
		(layers "F.Cu" "B.Cu")
		(net "GND")
	)
	(via
		(at 73.899776 -312.999882)
		(size 0.4064)
		(drill 0.2032)
		(layers "F.Cu" "B.Cu")
		(net "GND")
	)
	(via
		(at 56.324754 -287.824926)
		(size 0.4064)
		(drill 0.2032)
		(layers "F.Cu" "B.Cu")
		(net "GND")
	)
	(via
		(at 379.9459 -354.732082)
		(size 0.4064)
		(drill 0.2032)
		(layers "F.Cu" "B.Cu")
		(net "GND")
	)
	(via
		(at 296.599864 -274.049744)
		(size 0.4064)
		(drill 0.2032)
		(layers "F.Cu" "B.Cu")
		(net "GND")
	)
	(via
		(at 419.683184 -346.09913)
		(size 0.4572)
		(drill 0.254)
		(layers "F.Cu" "B.Cu")
		(net "GND")
	)
	(via
		(at 208.149698 -303.026826)
		(size 0.508)
		(drill 0.254)
		(layers "F.Cu" "B.Cu")
		(net "GND")
	)
	(via
		(at 4.562856 -210.641692)
		(size 0.508)
		(drill 0.254)
		(layers "F.Cu" "B.Cu")
		(net "GND")
	)
	(via
		(at 193.324988 -289.724846)
		(size 0.4064)
		(drill 0.2032)
		(layers "F.Cu" "B.Cu")
		(net "GND")
	)
	(via
		(at 286.836358 -51.661822)
		(size 0.508)
		(drill 0.254)
		(layers "F.Cu" "B.Cu")
		(net "GND")
	)
	(via
		(at 335.326736 -352.245422)
		(size 0.4572)
		(drill 0.254)
		(layers "F.Cu" "B.Cu")
		(net "GND")
	)
	(via
		(at 116.03228 -355.366066)
		(size 0.4572)
		(drill 0.254)
		(layers "F.Cu" "B.Cu")
		(net "GND")
	)
	(via
		(at 23.50262 -354.074222)
		(size 0.4572)
		(drill 0.254)
		(layers "F.Cu" "B.Cu")
		(net "GND")
	)
	(via
		(at 291.32784 -373.83847)
		(size 0.508)
		(drill 0.254)
		(layers "F.Cu" "B.Cu")
		(net "GND")
	)
	(via
		(at 194.274948 -293.52494)
		(size 0.4064)
		(drill 0.2032)
		(layers "F.Cu" "B.Cu")
		(net "GND")
	)
	(via
		(at 37.788596 -354.098098)
		(size 0.4572)
		(drill 0.254)
		(layers "F.Cu" "B.Cu")
		(net "GND")
	)
	(via
		(at 309.153306 -82.331306)
		(size 0.508)
		(drill 0.254)
		(layers "F.Cu" "B.Cu")
		(net "GND")
	)
	(via
		(at 188.119004 -347.951806)
		(size 0.4572)
		(drill 0.254)
		(layers "F.Cu" "B.Cu")
		(net "GND")
	)
	(via
		(at 181.912514 -134.845044)
		(size 0.508)
		(drill 0.254)
		(layers "F.Cu" "B.Cu")
		(net "GND")
	)
	(via
		(at 7.857236 -308.028594)
		(size 0.508)
		(drill 0.254)
		(layers "F.Cu" "B.Cu")
		(net "GND")
	)
	(via
		(at 418.399976 -276.899878)
		(size 0.4064)
		(drill 0.2032)
		(layers "F.Cu" "B.Cu")
		(net "GND")
	)
	(via
		(at 415.96691 -136.645142)
		(size 0.508)
		(drill 0.254)
		(layers "F.Cu" "B.Cu")
		(net "GND")
	)
	(via
		(at 150.59152 -105.78211)
		(size 0.508)
		(drill 0.254)
		(layers "F.Cu" "B.Cu")
		(net "GND")
	)
	(via
		(at 377.138184 -81.371186)
		(size 0.508)
		(drill 0.254)
		(layers "F.Cu" "B.Cu")
		(net "GND")
	)
	(via
		(at 4.562856 -154.761692)
		(size 0.508)
		(drill 0.254)
		(layers "F.Cu" "B.Cu")
		(net "GND")
	)
	(via
		(at 123.270772 -285.267654)
		(size 0.508)
		(drill 0.254)
		(layers "F.Cu" "B.Cu")
		(net "GND")
	)
	(via
		(at 90.414094 -350.977454)
		(size 0.4572)
		(drill 0.254)
		(layers "F.Cu" "B.Cu")
		(net "GND")
	)
	(via
		(at 327.729088 -116.410486)
		(size 0.508)
		(drill 0.254)
		(layers "F.Cu" "B.Cu")
		(net "GND")
	)
	(via
		(at 380.649734 -6.868922)
		(size 0.508)
		(drill 0.254)
		(layers "F.Cu" "B.Cu")
		(net "GND")
	)
	(via
		(at 397.95196 -125.955044)
		(size 0.508)
		(drill 0.254)
		(layers "F.Cu" "B.Cu")
		(net "GND")
	)
	(via
		(at 44.755562 -63.218314)
		(size 0.508)
		(drill 0.254)
		(layers "F.Cu" "B.Cu")
		(net "GND")
	)
	(via
		(at 412.699962 -313.949842)
		(size 0.4064)
		(drill 0.2032)
		(layers "F.Cu" "B.Cu")
		(net "GND")
	)
	(via
		(at 270.601694 -103.975408)
		(size 0.508)
		(drill 0.254)
		(layers "F.Cu" "B.Cu")
		(net "GND")
	)
	(via
		(at 9.648952 -34.990024)
		(size 0.508)
		(drill 0.254)
		(layers "F.Cu" "B.Cu")
		(net "GND")
	)
	(via
		(at 208.894172 -122.57278)
		(size 0.508)
		(drill 0.254)
		(layers "F.Cu" "B.Cu")
		(net "GND")
	)
	(via
		(at 56.324754 -305.874928)
		(size 0.4064)
		(drill 0.2032)
		(layers "F.Cu" "B.Cu")
		(net "GND")
	)
	(via
		(at 376.936508 -51.661822)
		(size 0.508)
		(drill 0.254)
		(layers "F.Cu" "B.Cu")
		(net "GND")
	)
	(via
		(at 388.949946 -315.849762)
		(size 0.4064)
		(drill 0.2032)
		(layers "F.Cu" "B.Cu")
		(net "GND")
	)
	(via
		(at 269.333726 -111.175546)
		(size 0.508)
		(drill 0.254)
		(layers "F.Cu" "B.Cu")
		(net "GND")
	)
	(via
		(at 251.035566 -198.48703)
		(size 0.508)
		(drill 0.254)
		(layers "F.Cu" "B.Cu")
		(net "GND")
	)
	(via
		(at 134.332472 -221.915482)
		(size 0.508)
		(drill 0.254)
		(layers "F.Cu" "B.Cu")
		(net "GND")
	)
	(via
		(at 248.480834 -27.79014)
		(size 0.508)
		(drill 0.254)
		(layers "F.Cu" "B.Cu")
		(net "GND")
	)
	(via
		(at 194.651376 -99.037648)
		(size 0.508)
		(drill 0.254)
		(layers "F.Cu" "B.Cu")
		(net "GND")
	)
	(via
		(at 222.626174 -239.046004)
		(size 0.508)
		(drill 0.254)
		(layers "F.Cu" "B.Cu")
		(net "GND")
	)
	(via
		(at 23.261574 -222.214186)
		(size 0.508)
		(drill 0.254)
		(layers "F.Cu" "B.Cu")
		(net "GND")
	)
	(via
		(at 105.323132 -56.353456)
		(size 0.508)
		(drill 0.254)
		(layers "F.Cu" "B.Cu")
		(net "GND")
	)
	(via
		(at 334.817212 -304.373534)
		(size 0.508)
		(drill 0.254)
		(layers "F.Cu" "B.Cu")
		(net "GND")
	)
	(via
		(at 130.314954 -26.171398)
		(size 0.508)
		(drill 0.254)
		(layers "F.Cu" "B.Cu")
		(net "GND")
	)
	(via
		(at 215.630506 -65.15989)
		(size 0.508)
		(drill 0.254)
		(layers "F.Cu" "B.Cu")
		(net "GND")
	)
	(via
		(at 79.457042 -351.611438)
		(size 0.4064)
		(drill 0.2032)
		(layers "F.Cu" "B.Cu")
		(net "GND")
	)
	(via
		(at 232.207308 -104.902508)
		(size 0.508)
		(drill 0.254)
		(layers "F.Cu" "B.Cu")
		(net "GND")
	)
	(via
		(at 426.72508 -14.100302)
		(size 0.508)
		(drill 0.254)
		(layers "F.Cu" "B.Cu")
		(net "GND")
	)
	(via
		(at 355.403404 -60.627006)
		(size 0.508)
		(drill 0.254)
		(layers "F.Cu" "B.Cu")
		(net "GND")
	)
	(via
		(at 298.850558 -225.037396)
		(size 0.508)
		(drill 0.254)
		(layers "F.Cu" "B.Cu")
		(net "GND")
	)
	(via
		(at 117.882416 -357.123746)
		(size 0.4572)
		(drill 0.254)
		(layers "F.Cu" "B.Cu")
		(net "GND")
	)
	(via
		(at 351.451926 -259.918962)
		(size 0.508)
		(drill 0.254)
		(layers "F.Cu" "B.Cu")
		(net "GND")
	)
	(via
		(at 429.010064 -350.977454)
		(size 0.4572)
		(drill 0.254)
		(layers "F.Cu" "B.Cu")
		(net "GND")
	)
	(via
		(at 413.465264 -343.073482)
		(size 0.4572)
		(drill 0.254)
		(layers "F.Cu" "B.Cu")
		(net "GND")
	)
	(via
		(at 288.045144 -50.516282)
		(size 0.508)
		(drill 0.254)
		(layers "F.Cu" "B.Cu")
		(net "GND")
	)
	(via
		(at 39.224966 -297.32478)
		(size 0.4064)
		(drill 0.2032)
		(layers "F.Cu" "B.Cu")
		(net "GND")
	)
	(via
		(at 128.547622 -380.141734)
		(size 0.4572)
		(drill 0.254)
		(layers "F.Cu" "B.Cu")
		(net "GND")
	)
	(via
		(at 266.202922 -296.695114)
		(size 0.508)
		(drill 0.254)
		(layers "F.Cu" "B.Cu")
		(net "GND")
	)
	(via
		(at 229.380034 -282.982162)
		(size 0.508)
		(drill 0.254)
		(layers "F.Cu" "B.Cu")
		(net "GND")
	)
	(via
		(at 390.327896 -385.141978)
		(size 0.508)
		(drill 0.254)
		(layers "F.Cu" "B.Cu")
		(net "GND")
	)
	(via
		(at 392.753088 -349.219774)
		(size 0.4572)
		(drill 0.254)
		(layers "F.Cu" "B.Cu")
		(net "GND")
	)
	(via
		(at 297.549824 -274.999958)
		(size 0.4064)
		(drill 0.2032)
		(layers "F.Cu" "B.Cu")
		(net "GND")
	)
	(via
		(at 272.849848 -307.299868)
		(size 0.4064)
		(drill 0.2032)
		(layers "F.Cu" "B.Cu")
		(net "GND")
	)
	(via
		(at 242.269264 -141.019276)
		(size 0.508)
		(drill 0.254)
		(layers "F.Cu" "B.Cu")
		(net "GND")
	)
	(via
		(at 101.120448 -356.550214)
		(size 0.508)
		(drill 0.254)
		(layers "F.Cu" "B.Cu")
		(net "GND")
	)
	(via
		(at 332.589124 -351.611438)
		(size 0.4064)
		(drill 0.2032)
		(layers "F.Cu" "B.Cu")
		(net "GND")
	)
	(via
		(at 355.077268 -282.910788)
		(size 0.49022)
		(drill 0.254)
		(layers "F.Cu" "B.Cu")
		(net "GND")
	)
	(via
		(at 381.576072 -358.391714)
		(size 0.4572)
		(drill 0.254)
		(layers "F.Cu" "B.Cu")
		(net "GND")
	)
	(via
		(at 81.024984 -297.32478)
		(size 0.4064)
		(drill 0.2032)
		(layers "F.Cu" "B.Cu")
		(net "GND")
	)
	(via
		(at 422.674796 -294.4749)
		(size 0.4064)
		(drill 0.2032)
		(layers "F.Cu" "B.Cu")
		(net "GND")
	)
	(via
		(at 367.954814 -23.880318)
		(size 0.508)
		(drill 0.254)
		(layers "F.Cu" "B.Cu")
		(net "GND")
	)
	(via
		(at 194.749928 -287.349946)
		(size 0.4064)
		(drill 0.2032)
		(layers "F.Cu" "B.Cu")
		(net "GND")
	)
	(via
		(at 67.55003 -111.784892)
		(size 0.508)
		(drill 0.254)
		(layers "F.Cu" "B.Cu")
		(net "GND")
	)
	(via
		(at 286.624776 -306.824888)
		(size 0.4064)
		(drill 0.2032)
		(layers "F.Cu" "B.Cu")
		(net "GND")
	)
	(via
		(at 88.2523 -113.661444)
		(size 0.508)
		(drill 0.254)
		(layers "F.Cu" "B.Cu")
		(net "GND")
	)
	(via
		(at 302.774858 -300.174914)
		(size 0.4064)
		(drill 0.2032)
		(layers "F.Cu" "B.Cu")
		(net "GND")
	)
	(via
		(at 176.94783 -406.141936)
		(size 0.508)
		(drill 0.254)
		(layers "F.Cu" "B.Cu")
		(net "GND")
	)
	(via
		(at 386.701792 -132.04317)
		(size 0.508)
		(drill 0.254)
		(layers "F.Cu" "B.Cu")
		(net "GND")
	)
	(via
		(at 50.14976 -280.699718)
		(size 0.4064)
		(drill 0.2032)
		(layers "F.Cu" "B.Cu")
		(net "GND")
	)
	(via
		(at 28.557982 -286.331914)
		(size 0.508)
		(drill 0.254)
		(layers "F.Cu" "B.Cu")
		(net "GND")
	)
	(via
		(at 415.3154 -349.219774)
		(size 0.4572)
		(drill 0.254)
		(layers "F.Cu" "B.Cu")
		(net "GND")
	)
	(via
		(at 134.68604 -357.123746)
		(size 0.4572)
		(drill 0.254)
		(layers "F.Cu" "B.Cu")
		(net "GND")
	)
	(via
		(at 300.047914 -357.123746)
		(size 0.4572)
		(drill 0.254)
		(layers "F.Cu" "B.Cu")
		(net "GND")
	)
	(via
		(at 314.366148 -153.218134)
		(size 0.508)
		(drill 0.254)
		(layers "F.Cu" "B.Cu")
		(net "GND")
	)
	(via
		(at 291.32784 -376.241818)
		(size 0.508)
		(drill 0.254)
		(layers "F.Cu" "B.Cu")
		(net "GND")
	)
	(via
		(at 161.54781 -380.040134)
		(size 0.508)
		(drill 0.254)
		(layers "F.Cu" "B.Cu")
		(net "GND")
	)
	(via
		(at 45.051726 -111.44504)
		(size 0.508)
		(drill 0.254)
		(layers "F.Cu" "B.Cu")
		(net "GND")
	)
	(via
		(at 48.3743 -349.219774)
		(size 0.4572)
		(drill 0.254)
		(layers "F.Cu" "B.Cu")
		(net "GND")
	)
	(via
		(at 48.58131 -34.718498)
		(size 0.508)
		(drill 0.254)
		(layers "F.Cu" "B.Cu")
		(net "GND")
	)
	(via
		(at 117.882416 -354.098098)
		(size 0.4572)
		(drill 0.254)
		(layers "F.Cu" "B.Cu")
		(net "GND")
	)
	(via
		(at 301.349918 -276.899878)
		(size 0.4064)
		(drill 0.2032)
		(layers "F.Cu" "B.Cu")
		(net "GND")
	)
	(via
		(at 386.701792 -122.091958)
		(size 0.508)
		(drill 0.254)
		(layers "F.Cu" "B.Cu")
		(net "GND")
	)
	(via
		(at 423.32783 -378.94006)
		(size 0.508)
		(drill 0.254)
		(layers "F.Cu" "B.Cu")
		(net "GND")
	)
	(via
		(at 125.636528 -166.273988)
		(size 0.508)
		(drill 0.254)
		(layers "F.Cu" "B.Cu")
		(net "GND")
	)
	(via
		(at 130.318256 -350.977454)
		(size 0.4572)
		(drill 0.254)
		(layers "F.Cu" "B.Cu")
		(net "GND")
	)
	(via
		(at 35.759644 -131.495546)
		(size 0.508)
		(drill 0.254)
		(layers "F.Cu" "B.Cu")
		(net "GND")
	)
	(via
		(at 422.548304 -116.435124)
		(size 0.508)
		(drill 0.254)
		(layers "F.Cu" "B.Cu")
		(net "GND")
	)
	(via
		(at 117.547644 -411.141926)
		(size 0.4572)
		(drill 0.254)
		(layers "F.Cu" "B.Cu")
		(net "GND")
	)
	(via
		(at 127.33528 -290.05149)
		(size 0.508)
		(drill 0.254)
		(layers "F.Cu" "B.Cu")
		(net "GND")
	)
	(via
		(at 18.671286 -28.05303)
		(size 0.508)
		(drill 0.254)
		(layers "F.Cu" "B.Cu")
		(net "GND")
	)
	(via
		(at 53.315108 -43.85691)
		(size 0.508)
		(drill 0.254)
		(layers "F.Cu" "B.Cu")
		(net "GND")
	)
	(via
		(at 115.008406 -284.333188)
		(size 0.49022)
		(drill 0.254)
		(layers "F.Cu" "B.Cu")
		(net "GND")
	)
	(via
		(at 106.087164 -162.518852)
		(size 0.508)
		(drill 0.254)
		(layers "F.Cu" "B.Cu")
		(net "GND")
	)
	(via
		(at 282.349448 -272.14957)
		(size 0.4064)
		(drill 0.2032)
		(layers "F.Cu" "B.Cu")
		(net "GND")
	)
	(via
		(at 183.349646 -272.14957)
		(size 0.4064)
		(drill 0.2032)
		(layers "F.Cu" "B.Cu")
		(net "GND")
	)
	(via
		(at 397.97482 -286.874966)
		(size 0.4064)
		(drill 0.2032)
		(layers "F.Cu" "B.Cu")
		(net "GND")
	)
	(via
		(at 176.94783 -372.342156)
		(size 0.508)
		(drill 0.254)
		(layers "F.Cu" "B.Cu")
		(net "GND")
	)
	(via
		(at 415.96691 -151.155146)
		(size 0.508)
		(drill 0.254)
		(layers "F.Cu" "B.Cu")
		(net "GND")
	)
	(via
		(at 90.054684 -34.990024)
		(size 0.508)
		(drill 0.254)
		(layers "F.Cu" "B.Cu")
		(net "GND")
	)
	(via
		(at 327.849992 -343.073482)
		(size 0.4572)
		(drill 0.254)
		(layers "F.Cu" "B.Cu")
		(net "GND")
	)
	(via
		(at 102.203504 -216.071958)
		(size 0.508)
		(drill 0.254)
		(layers "F.Cu" "B.Cu")
		(net "GND")
	)
	(via
		(at 61.235336 -162.113722)
		(size 0.508)
		(drill 0.254)
		(layers "F.Cu" "B.Cu")
		(net "GND")
	)
	(via
		(at 267.959586 -105.78211)
		(size 0.508)
		(drill 0.254)
		(layers "F.Cu" "B.Cu")
		(net "GND")
	)
	(via
		(at 56.799988 -276.899878)
		(size 0.4064)
		(drill 0.2032)
		(layers "F.Cu" "B.Cu")
		(net "GND")
	)
	(via
		(at 279.730454 -65.15989)
		(size 0.508)
		(drill 0.254)
		(layers "F.Cu" "B.Cu")
		(net "GND")
	)
	(via
		(at 381.3556 -245.364)
		(size 0.508)
		(drill 0.254)
		(layers "F.Cu" "B.Cu")
		(net "GND")
	)
	(via
		(at 315.60008 -308.249828)
		(size 0.4064)
		(drill 0.2032)
		(layers "F.Cu" "B.Cu")
		(net "GND")
	)
	(via
		(at 177.5333 -347.951806)
		(size 0.4572)
		(drill 0.254)
		(layers "F.Cu" "B.Cu")
		(net "GND")
	)
	(via
		(at 80.147922 -376.241818)
		(size 0.508)
		(drill 0.254)
		(layers "F.Cu" "B.Cu")
		(net "GND")
	)
	(via
		(at 295.727882 -407.638504)
		(size 0.508)
		(drill 0.254)
		(layers "F.Cu" "B.Cu")
		(net "GND")
	)
	(via
		(at 295.727882 -378.94006)
		(size 0.508)
		(drill 0.254)
		(layers "F.Cu" "B.Cu")
		(net "GND")
	)
	(via
		(at 437.07812 -344.831162)
		(size 0.4572)
		(drill 0.254)
		(layers "F.Cu" "B.Cu")
		(net "GND")
	)
	(via
		(at 364.36808 -286.842454)
		(size 0.508)
		(drill 0.254)
		(layers "F.Cu" "B.Cu")
		(net "GND")
	)
	(via
		(at 54.899814 -278.799798)
		(size 0.4064)
		(drill 0.2032)
		(layers "F.Cu" "B.Cu")
		(net "GND")
	)
	(via
		(at 62.974982 -296.37482)
		(size 0.4064)
		(drill 0.2032)
		(layers "F.Cu" "B.Cu")
		(net "GND")
	)
	(via
		(at 336.80908 -107.75696)
		(size 0.508)
		(drill 0.254)
		(layers "F.Cu" "B.Cu")
		(net "GND")
	)
	(via
		(at 269.999714 -307.299868)
		(size 0.4064)
		(drill 0.2032)
		(layers "F.Cu" "B.Cu")
		(net "GND")
	)
	(via
		(at 306.448206 -142.15491)
		(size 0.508)
		(drill 0.254)
		(layers "F.Cu" "B.Cu")
		(net "GND")
	)
	(via
		(at 450.240146 -252.235462)
		(size 0.508)
		(drill 0.254)
		(layers "F.Cu" "B.Cu")
		(net "GND")
	)
	(via
		(at 393.7 -314.899802)
		(size 0.4064)
		(drill 0.2032)
		(layers "F.Cu" "B.Cu")
		(net "GND")
	)
	(via
		(at 138.06043 -21.37156)
		(size 0.508)
		(drill 0.254)
		(layers "F.Cu" "B.Cu")
		(net "GND")
	)
	(via
		(at 170.347894 -377.341892)
		(size 0.508)
		(drill 0.254)
		(layers "F.Cu" "B.Cu")
		(net "GND")
	)
	(via
		(at 313.09818 -118.498112)
		(size 0.508)
		(drill 0.254)
		(layers "F.Cu" "B.Cu")
		(net "GND")
	)
	(via
		(at 45.39996 -305.399948)
		(size 0.4064)
		(drill 0.2032)
		(layers "F.Cu" "B.Cu")
		(net "GND")
	)
	(via
		(at 161.134552 -47.936658)
		(size 0.508)
		(drill 0.254)
		(layers "F.Cu" "B.Cu")
		(net "GND")
	)
	(via
		(at 124.55525 -27.79014)
		(size 0.508)
		(drill 0.254)
		(layers "F.Cu" "B.Cu")
		(net "GND")
	)
	(via
		(at 172.945552 -348.58579)
		(size 0.4064)
		(drill 0.2032)
		(layers "F.Cu" "B.Cu")
		(net "GND")
	)
	(via
		(at 162.924998 -306.824888)
		(size 0.4064)
		(drill 0.2032)
		(layers "F.Cu" "B.Cu")
		(net "GND")
	)
	(via
		(at 169.465244 -341.805514)
		(size 0.4572)
		(drill 0.254)
		(layers "F.Cu" "B.Cu")
		(net "GND")
	)
	(via
		(at 293.74973 -316.799722)
		(size 0.4064)
		(drill 0.2032)
		(layers "F.Cu" "B.Cu")
		(net "GND")
	)
	(via
		(at 148.002244 -27.729688)
		(size 0.508)
		(drill 0.254)
		(layers "F.Cu" "B.Cu")
		(net "GND")
	)
	(via
		(at 240.655094 -33.19018)
		(size 0.508)
		(drill 0.254)
		(layers "F.Cu" "B.Cu")
		(net "GND")
	)
	(via
		(at 378.819156 -222.347282)
		(size 0.508)
		(drill 0.254)
		(layers "F.Cu" "B.Cu")
		(net "GND")
	)
	(via
		(at 172.473874 -25.971246)
		(size 0.508)
		(drill 0.254)
		(layers "F.Cu" "B.Cu")
		(net "GND")
	)
	(via
		(at 181.912514 -121.835164)
		(size 0.508)
		(drill 0.254)
		(layers "F.Cu" "B.Cu")
		(net "GND")
	)
	(via
		(at 125.35916 -358.391714)
		(size 0.4572)
		(drill 0.254)
		(layers "F.Cu" "B.Cu")
		(net "GND")
	)
	(via
		(at 307.524912 -300.174914)
		(size 0.4064)
		(drill 0.2032)
		(layers "F.Cu" "B.Cu")
		(net "GND")
	)
	(via
		(at 435.599332 -357.75773)
		(size 0.4064)
		(drill 0.2032)
		(layers "F.Cu" "B.Cu")
		(net "GND")
	)
	(via
		(at 436.706772 -348.58579)
		(size 0.4064)
		(drill 0.2032)
		(layers "F.Cu" "B.Cu")
		(net "GND")
	)
	(via
		(at 428.84979 -304.449734)
		(size 0.4064)
		(drill 0.2032)
		(layers "F.Cu" "B.Cu")
		(net "GND")
	)
	(via
		(at 388.127748 -369.938554)
		(size 0.508)
		(drill 0.254)
		(layers "F.Cu" "B.Cu")
		(net "GND")
	)
	(via
		(at 254.781304 -34.718498)
		(size 0.508)
		(drill 0.254)
		(layers "F.Cu" "B.Cu")
		(net "GND")
	)
	(via
		(at 82.843116 -52.536852)
		(size 0.508)
		(drill 0.254)
		(layers "F.Cu" "B.Cu")
		(net "GND")
	)
	(via
		(at 394.011912 -355.366066)
		(size 0.4572)
		(drill 0.254)
		(layers "F.Cu" "B.Cu")
		(net "GND")
	)
	(via
		(at 392.753088 -347.951806)
		(size 0.4572)
		(drill 0.254)
		(layers "F.Cu" "B.Cu")
		(net "GND")
	)
	(via
		(at 166.727632 -354.732082)
		(size 0.4064)
		(drill 0.2032)
		(layers "F.Cu" "B.Cu")
		(net "GND")
	)
	(via
		(at 142.754096 -346.09913)
		(size 0.4572)
		(drill 0.254)
		(layers "F.Cu" "B.Cu")
		(net "GND")
	)
	(via
		(at 322.890896 -357.123746)
		(size 0.4572)
		(drill 0.254)
		(layers "F.Cu" "B.Cu")
		(net "GND")
	)
	(via
		(at 279.672542 -113.245138)
		(size 0.508)
		(drill 0.254)
		(layers "F.Cu" "B.Cu")
		(net "GND")
	)
	(via
		(at 277.698454 -65.15989)
		(size 0.508)
		(drill 0.254)
		(layers "F.Cu" "B.Cu")
		(net "GND")
	)
	(via
		(at 162.450018 -312.049922)
		(size 0.4064)
		(drill 0.2032)
		(layers "F.Cu" "B.Cu")
		(net "GND")
	)
	(via
		(at 172.574204 -358.391714)
		(size 0.4572)
		(drill 0.254)
		(layers "F.Cu" "B.Cu")
		(net "GND")
	)
	(via
		(at 362.091732 -390.507728)
		(size 0.508)
		(drill 0.254)
		(layers "F.Cu" "B.Cu")
		(net "GND")
	)
	(via
		(at 335.026 -143.891)
		(size 0.508)
		(drill 0.254)
		(layers "F.Cu" "B.Cu")
		(net "GND")
	)
	(via
		(at 230.26751 -219.504006)
		(size 0.4572)
		(drill 0.254)
		(layers "F.Cu" "B.Cu")
		(net "GND")
	)
	(via
		(at 40.649906 -304.449734)
		(size 0.4064)
		(drill 0.2032)
		(layers "F.Cu" "B.Cu")
		(net "GND")
	)
	(via
		(at 419.205918 -1.364996)
		(size 0.508)
		(drill 0.254)
		(layers "F.Cu" "B.Cu")
		(net "GND")
	)
	(via
		(at 133.055868 -342.439498)
		(size 0.4064)
		(drill 0.2032)
		(layers "F.Cu" "B.Cu")
		(net "GND")
	)
	(via
		(at 116.447316 -83.556602)
		(size 0.508)
		(drill 0.254)
		(layers "F.Cu" "B.Cu")
		(net "GND")
	)
	(via
		(at 67.724782 -291.624766)
		(size 0.4064)
		(drill 0.2032)
		(layers "F.Cu" "B.Cu")
		(net "GND")
	)
	(via
		(at 381.527812 -411.141926)
		(size 0.508)
		(drill 0.254)
		(layers "F.Cu" "B.Cu")
		(net "GND")
	)
	(via
		(at 89.15527 -347.951806)
		(size 0.4572)
		(drill 0.254)
		(layers "F.Cu" "B.Cu")
		(net "GND")
	)
	(via
		(at 279.763982 -354.732082)
		(size 0.4064)
		(drill 0.2032)
		(layers "F.Cu" "B.Cu")
		(net "GND")
	)
	(via
		(at 71.049896 -319.65011)
		(size 0.4064)
		(drill 0.2032)
		(layers "F.Cu" "B.Cu")
		(net "GND")
	)
	(via
		(at 416.974782 -302.074834)
		(size 0.4064)
		(drill 0.2032)
		(layers "F.Cu" "B.Cu")
		(net "GND")
	)
	(via
		(at 164.726112 -351.611438)
		(size 0.4064)
		(drill 0.2032)
		(layers "F.Cu" "B.Cu")
		(net "GND")
	)
	(via
		(at 67.021202 -348.58579)
		(size 0.4064)
		(drill 0.2032)
		(layers "F.Cu" "B.Cu")
		(net "GND")
	)
	(via
		(at 390.374886 -276.424898)
		(size 0.4064)
		(drill 0.2032)
		(layers "F.Cu" "B.Cu")
		(net "GND")
	)
	(via
		(at 114.402108 -357.75773)
		(size 0.4064)
		(drill 0.2032)
		(layers "F.Cu" "B.Cu")
		(net "GND")
	)
	(via
		(at 273.91741 -349.219774)
		(size 0.4572)
		(drill 0.254)
		(layers "F.Cu" "B.Cu")
		(net "GND")
	)
	(via
		(at 419.824916 -302.074834)
		(size 0.4064)
		(drill 0.2032)
		(layers "F.Cu" "B.Cu")
		(net "GND")
	)
	(via
		(at 50.624994 -284.974792)
		(size 0.4064)
		(drill 0.2032)
		(layers "F.Cu" "B.Cu")
		(net "GND")
	)
	(via
		(at 14.7955 -310.107584)
		(size 0.508)
		(drill 0.254)
		(layers "F.Cu" "B.Cu")
		(net "GND")
	)
	(via
		(at 166.727632 -348.58579)
		(size 0.4064)
		(drill 0.2032)
		(layers "F.Cu" "B.Cu")
		(net "GND")
	)
	(via
		(at 25.352756 -344.831162)
		(size 0.4572)
		(drill 0.254)
		(layers "F.Cu" "B.Cu")
		(net "GND")
	)
	(via
		(at 307.049932 -315.849762)
		(size 0.4064)
		(drill 0.2032)
		(layers "F.Cu" "B.Cu")
		(net "GND")
	)
	(via
		(at 281.399742 -312.999882)
		(size 0.4064)
		(drill 0.2032)
		(layers "F.Cu" "B.Cu")
		(net "GND")
	)
	(via
		(at 363.8677 -284.333188)
		(size 0.49022)
		(drill 0.254)
		(layers "F.Cu" "B.Cu")
		(net "GND")
	)
	(via
		(at 466.835998 -338.643976)
		(size 0.508)
		(drill 0.254)
		(layers "F.Cu" "B.Cu")
		(net "GND")
	)
	(via
		(at 394.64996 -275.949918)
		(size 0.4064)
		(drill 0.2032)
		(layers "F.Cu" "B.Cu")
		(net "GND")
	)
	(via
		(at 389.102854 -74.624184)
		(size 0.508)
		(drill 0.254)
		(layers "F.Cu" "B.Cu")
		(net "GND")
	)
	(via
		(at 97.498408 -65.15989)
		(size 0.508)
		(drill 0.254)
		(layers "F.Cu" "B.Cu")
		(net "GND")
	)
	(via
		(at 304.872898 -23.880318)
		(size 0.508)
		(drill 0.254)
		(layers "F.Cu" "B.Cu")
		(net "GND")
	)
	(via
		(at 160.771332 -32.911796)
		(size 0.508)
		(drill 0.254)
		(layers "F.Cu" "B.Cu")
		(net "GND")
	)
	(via
		(at 423.15003 -288.299906)
		(size 0.4064)
		(drill 0.2032)
		(layers "F.Cu" "B.Cu")
		(net "GND")
	)
	(via
		(at 250.871228 -28.05303)
		(size 0.508)
		(drill 0.254)
		(layers "F.Cu" "B.Cu")
		(net "GND")
	)
	(via
		(at 76.27493 -300.174914)
		(size 0.4064)
		(drill 0.2032)
		(layers "F.Cu" "B.Cu")
		(net "GND")
	)
	(via
		(at 425.52493 -291.624766)
		(size 0.4064)
		(drill 0.2032)
		(layers "F.Cu" "B.Cu")
		(net "GND")
	)
	(via
		(at 191.900048 -317.749936)
		(size 0.4064)
		(drill 0.2032)
		(layers "F.Cu" "B.Cu")
		(net "GND")
	)
	(via
		(at 149.292564 -6.292342)
		(size 0.508)
		(drill 0.254)
		(layers "F.Cu" "B.Cu")
		(net "GND")
	)
	(via
		(at 396.54988 -314.899802)
		(size 0.4064)
		(drill 0.2032)
		(layers "F.Cu" "B.Cu")
		(net "GND")
	)
	(via
		(at 252.687582 -26.360882)
		(size 0.508)
		(drill 0.254)
		(layers "F.Cu" "B.Cu")
		(net "GND")
	)
	(via
		(at 163.13277 -131.76504)
		(size 0.508)
		(drill 0.254)
		(layers "F.Cu" "B.Cu")
		(net "GND")
	)
	(via
		(at 184.938416 -73.20026)
		(size 0.508)
		(drill 0.254)
		(layers "F.Cu" "B.Cu")
		(net "GND")
	)
	(via
		(at 40.897556 -346.09913)
		(size 0.4572)
		(drill 0.254)
		(layers "F.Cu" "B.Cu")
		(net "GND")
	)
	(via
		(at 154.501596 -133.301994)
		(size 0.508)
		(drill 0.254)
		(layers "F.Cu" "B.Cu")
		(net "GND")
	)
	(via
		(at 393.7 -302.549814)
		(size 0.4064)
		(drill 0.2032)
		(layers "F.Cu" "B.Cu")
		(net "GND")
	)
	(via
		(at 427.727872 -408.840178)
		(size 0.508)
		(drill 0.254)
		(layers "F.Cu" "B.Cu")
		(net "GND")
	)
	(via
		(at 186.200034 -310.149748)
		(size 0.4064)
		(drill 0.2032)
		(layers "F.Cu" "B.Cu")
		(net "GND")
	)
	(via
		(at 446.787524 -26.360882)
		(size 0.508)
		(drill 0.254)
		(layers "F.Cu" "B.Cu")
		(net "GND")
	)
	(via
		(at 142.004796 -175.775874)
		(size 0.508)
		(drill 0.254)
		(layers "F.Cu" "B.Cu")
		(net "GND")
	)
	(via
		(at 64.056006 -33.19018)
		(size 0.508)
		(drill 0.254)
		(layers "F.Cu" "B.Cu")
		(net "GND")
	)
	(via
		(at 152.47493 -290.674806)
		(size 0.4064)
		(drill 0.2032)
		(layers "F.Cu" "B.Cu")
		(net "GND")
	)
	(via
		(at 360.045 -27.79014)
		(size 0.508)
		(drill 0.254)
		(layers "F.Cu" "B.Cu")
		(net "GND")
	)
	(via
		(at 170.524932 -287.824926)
		(size 0.4064)
		(drill 0.2032)
		(layers "F.Cu" "B.Cu")
		(net "GND")
	)
	(via
		(at 307.999638 -276.899878)
		(size 0.4064)
		(drill 0.2032)
		(layers "F.Cu" "B.Cu")
		(net "GND")
	)
	(via
		(at 412.224982 -284.974792)
		(size 0.4064)
		(drill 0.2032)
		(layers "F.Cu" "B.Cu")
		(net "GND")
	)
	(via
		(at 171.31538 -352.245422)
		(size 0.4572)
		(drill 0.254)
		(layers "F.Cu" "B.Cu")
		(net "GND")
	)
	(via
		(at 266.36853 -71.160894)
		(size 0.508)
		(drill 0.254)
		(layers "F.Cu" "B.Cu")
		(net "GND")
	)
	(via
		(at 423.15003 -312.049922)
		(size 0.4064)
		(drill 0.2032)
		(layers "F.Cu" "B.Cu")
		(net "GND")
	)
	(via
		(at 85.819996 -34.990278)
		(size 0.508)
		(drill 0.254)
		(layers "F.Cu" "B.Cu")
		(net "GND")
	)
	(via
		(at 89.15527 -349.219774)
		(size 0.4572)
		(drill 0.254)
		(layers "F.Cu" "B.Cu")
		(net "GND")
	)
	(via
		(at 286.906462 -118.754906)
		(size 0.508)
		(drill 0.254)
		(layers "F.Cu" "B.Cu")
		(net "GND")
	)
	(via
		(at 189.999874 -305.399948)
		(size 0.4064)
		(drill 0.2032)
		(layers "F.Cu" "B.Cu")
		(net "GND")
	)
	(via
		(at 402.249894 -310.149748)
		(size 0.4064)
		(drill 0.2032)
		(layers "F.Cu" "B.Cu")
		(net "GND")
	)
	(via
		(at 330.927964 -377.738386)
		(size 0.508)
		(drill 0.254)
		(layers "F.Cu" "B.Cu")
		(net "GND")
	)
	(via
		(at 137.795 -341.805514)
		(size 0.4572)
		(drill 0.254)
		(layers "F.Cu" "B.Cu")
		(net "GND")
	)
	(via
		(at 302.327818 -403.34184)
		(size 0.508)
		(drill 0.254)
		(layers "F.Cu" "B.Cu")
		(net "GND")
	)
	(via
		(at 45.26534 -346.09913)
		(size 0.4572)
		(drill 0.254)
		(layers "F.Cu" "B.Cu")
		(net "GND")
	)
	(via
		(at 119.747792 -384.041904)
		(size 0.4572)
		(drill 0.254)
		(layers "F.Cu" "B.Cu")
		(net "GND")
	)
	(via
		(at 392.38174 -342.439498)
		(size 0.4064)
		(drill 0.2032)
		(layers "F.Cu" "B.Cu")
		(net "GND")
	)
	(via
		(at 33.947862 -374.938544)
		(size 0.508)
		(drill 0.254)
		(layers "F.Cu" "B.Cu")
		(net "GND")
	)
	(via
		(at 440.43219 -13.613892)
		(size 0.508)
		(drill 0.254)
		(layers "F.Cu" "B.Cu")
		(net "GND")
	)
	(via
		(at 358.983788 -243.562632)
		(size 0.508)
		(drill 0.254)
		(layers "F.Cu" "B.Cu")
		(net "GND")
	)
	(via
		(at 207.860138 -238.66094)
		(size 0.508)
		(drill 0.254)
		(layers "F.Cu" "B.Cu")
		(net "GND")
	)
	(via
		(at 307.999892 -312.999882)
		(size 0.4064)
		(drill 0.2032)
		(layers "F.Cu" "B.Cu")
		(net "GND")
	)
	(via
		(at 388.43204 -13.613638)
		(size 0.508)
		(drill 0.254)
		(layers "F.Cu" "B.Cu")
		(net "GND")
	)
	(via
		(at 466.827616 -11.372596)
		(size 0.508)
		(drill 0.254)
		(layers "F.Cu" "B.Cu")
		(net "GND")
	)
	(via
		(at 220.525086 -14.100302)
		(size 0.508)
		(drill 0.254)
		(layers "F.Cu" "B.Cu")
		(net "GND")
	)
	(via
		(at 269.049754 -315.849762)
		(size 0.4064)
		(drill 0.2032)
		(layers "F.Cu" "B.Cu")
		(net "GND")
	)
	(via
		(at 448.436238 -94.208346)
		(size 0.508)
		(drill 0.254)
		(layers "F.Cu" "B.Cu")
		(net "GND")
	)
	(via
		(at 324.448678 -33.19018)
		(size 0.508)
		(drill 0.254)
		(layers "F.Cu" "B.Cu")
		(net "GND")
	)
	(via
		(at 179.55006 -275.949918)
		(size 0.4064)
		(drill 0.2032)
		(layers "F.Cu" "B.Cu")
		(net "GND")
	)
	(via
		(at 225.682556 -202.590908)
		(size 0.508)
		(drill 0.254)
		(layers "F.Cu" "B.Cu")
		(net "GND")
	)
	(via
		(at 434.755036 -33.19018)
		(size 0.508)
		(drill 0.254)
		(layers "F.Cu" "B.Cu")
		(net "GND")
	)
	(via
		(at 275.176234 -346.09913)
		(size 0.4572)
		(drill 0.254)
		(layers "F.Cu" "B.Cu")
		(net "GND")
	)
	(via
		(at 290.89985 -277.849838)
		(size 0.4064)
		(drill 0.2032)
		(layers "F.Cu" "B.Cu")
		(net "GND")
	)
	(via
		(at 289.46221 -346.09913)
		(size 0.4572)
		(drill 0.254)
		(layers "F.Cu" "B.Cu")
		(net "GND")
	)
	(via
		(at 449.134484 -71.451978)
		(size 0.508)
		(drill 0.254)
		(layers "F.Cu" "B.Cu")
		(net "GND")
	)
	(via
		(at 108.656628 -117.862604)
		(size 0.508)
		(drill 0.254)
		(layers "F.Cu" "B.Cu")
		(net "GND")
	)
	(via
		(at 161.15157 -138.964924)
		(size 0.508)
		(drill 0.254)
		(layers "F.Cu" "B.Cu")
		(net "GND")
	)
	(via
		(at 328.781918 -58.873644)
		(size 0.508)
		(drill 0.254)
		(layers "F.Cu" "B.Cu")
		(net "GND")
	)
	(via
		(at 307.848 -417.82492)
		(size 0.508)
		(drill 0.254)
		(layers "F.Cu" "B.Cu")
		(net "GND")
	)
	(via
		(at 88.8238 -291.592)
		(size 0.508)
		(drill 0.254)
		(layers "F.Cu" "B.Cu")
		(net "GND")
	)
	(via
		(at 170.944032 -351.611438)
		(size 0.4064)
		(drill 0.2032)
		(layers "F.Cu" "B.Cu")
		(net "GND")
	)
	(via
		(at 151.859488 -123.885452)
		(size 0.508)
		(drill 0.254)
		(layers "F.Cu" "B.Cu")
		(net "GND")
	)
	(via
		(at 212.831426 -11.372342)
		(size 0.508)
		(drill 0.254)
		(layers "F.Cu" "B.Cu")
		(net "GND")
	)
	(via
		(at 383.72796 -378.94006)
		(size 0.508)
		(drill 0.254)
		(layers "F.Cu" "B.Cu")
		(net "GND")
	)
	(via
		(at 122.877072 -284.333188)
		(size 0.49022)
		(drill 0.254)
		(layers "F.Cu" "B.Cu")
		(net "GND")
	)
	(via
		(at 421.249856 -310.149748)
		(size 0.4064)
		(drill 0.2032)
		(layers "F.Cu" "B.Cu")
		(net "GND")
	)
	(via
		(at 360.09834 -19.757136)
		(size 0.508)
		(drill 0.254)
		(layers "F.Cu" "B.Cu")
		(net "GND")
	)
	(via
		(at 307.049932 -303.499774)
		(size 0.4064)
		(drill 0.2032)
		(layers "F.Cu" "B.Cu")
		(net "GND")
	)
	(via
		(at 168.150032 -310.149748)
		(size 0.4064)
		(drill 0.2032)
		(layers "F.Cu" "B.Cu")
		(net "GND")
	)
	(via
		(at 218.075002 -73.87463)
		(size 0.508)
		(drill 0.254)
		(layers "F.Cu" "B.Cu")
		(net "GND")
	)
	(via
		(at 209.870548 -116.668804)
		(size 0.508)
		(drill 0.254)
		(layers "F.Cu" "B.Cu")
		(net "GND")
	)
	(via
		(at 53.949854 -319.65011)
		(size 0.4064)
		(drill 0.2032)
		(layers "F.Cu" "B.Cu")
		(net "GND")
	)
	(via
		(at 443.829186 -115.394486)
		(size 0.508)
		(drill 0.254)
		(layers "F.Cu" "B.Cu")
		(net "GND")
	)
	(via
		(at 38.401752 -133.301994)
		(size 0.508)
		(drill 0.254)
		(layers "F.Cu" "B.Cu")
		(net "GND")
	)
	(via
		(at 130.74777 -397.038576)
		(size 0.508)
		(drill 0.254)
		(layers "F.Cu" "B.Cu")
		(net "GND")
	)
	(via
		(at 121.576592 -270.001492)
		(size 0.508)
		(drill 0.254)
		(layers "F.Cu" "B.Cu")
		(net "GND")
	)
	(via
		(at 188.099954 -278.799798)
		(size 0.4064)
		(drill 0.2032)
		(layers "F.Cu" "B.Cu")
		(net "GND")
	)
	(via
		(at 335.328006 -376.241818)
		(size 0.508)
		(drill 0.254)
		(layers "F.Cu" "B.Cu")
		(net "GND")
	)
	(via
		(at 35.899598 -310.150002)
		(size 0.4064)
		(drill 0.2032)
		(layers "F.Cu" "B.Cu")
		(net "GND")
	)
	(via
		(at 268.958314 -352.245422)
		(size 0.4572)
		(drill 0.254)
		(layers "F.Cu" "B.Cu")
		(net "GND")
	)
	(via
		(at 278.285194 -354.098098)
		(size 0.4572)
		(drill 0.254)
		(layers "F.Cu" "B.Cu")
		(net "GND")
	)
	(via
		(at 57.721246 -369.136422)
		(size 0.4064)
		(drill 0.2032)
		(layers "F.Cu" "B.Cu")
		(net "GND")
	)
	(via
		(at 179.55006 -319.65011)
		(size 0.4064)
		(drill 0.2032)
		(layers "F.Cu" "B.Cu")
		(net "GND")
	)
	(via
		(at 116.143786 -285.953454)
		(size 0.508)
		(drill 0.254)
		(layers "F.Cu" "B.Cu")
		(net "GND")
	)
	(via
		(at 8.455152 -29.590238)
		(size 0.508)
		(drill 0.254)
		(layers "F.Cu" "B.Cu")
		(net "GND")
	)
	(via
		(at 387.999986 -318.699896)
		(size 0.4064)
		(drill 0.2032)
		(layers "F.Cu" "B.Cu")
		(net "GND")
	)
	(via
		(at 186.675014 -288.774886)
		(size 0.4064)
		(drill 0.2032)
		(layers "F.Cu" "B.Cu")
		(net "GND")
	)
	(via
		(at 335.026 -159.766)
		(size 0.508)
		(drill 0.254)
		(layers "F.Cu" "B.Cu")
		(net "GND")
	)
	(via
		(at 303.249838 -319.65011)
		(size 0.4064)
		(drill 0.2032)
		(layers "F.Cu" "B.Cu")
		(net "GND")
	)
	(via
		(at 272.448782 -27.79014)
		(size 0.508)
		(drill 0.254)
		(layers "F.Cu" "B.Cu")
		(net "GND")
	)
	(via
		(at 320.153284 -357.75773)
		(size 0.4064)
		(drill 0.2032)
		(layers "F.Cu" "B.Cu")
		(net "GND")
	)
	(via
		(at 340.82228 -240.641378)
		(size 0.508)
		(drill 0.254)
		(layers "F.Cu" "B.Cu")
		(net "GND")
	)
	(via
		(at 411.750002 -314.899802)
		(size 0.4064)
		(drill 0.2032)
		(layers "F.Cu" "B.Cu")
		(net "GND")
	)
	(via
		(at 405.100028 -277.849838)
		(size 0.4064)
		(drill 0.2032)
		(layers "F.Cu" "B.Cu")
		(net "GND")
	)
	(via
		(at 385.661916 -150.457916)
		(size 0.508)
		(drill 0.254)
		(layers "F.Cu" "B.Cu")
		(net "GND")
	)
	(via
		(at 308.949852 -280.699718)
		(size 0.4064)
		(drill 0.2032)
		(layers "F.Cu" "B.Cu")
		(net "GND")
	)
	(via
		(at 106.750866 -387.598412)
		(size 0.508)
		(drill 0.254)
		(layers "F.Cu" "B.Cu")
		(net "GND")
	)
	(via
		(at 440.18708 -355.366066)
		(size 0.4572)
		(drill 0.254)
		(layers "F.Cu" "B.Cu")
		(net "GND")
	)
	(via
		(at 58.699908 -281.649932)
		(size 0.4064)
		(drill 0.2032)
		(layers "F.Cu" "B.Cu")
		(net "GND")
	)
	(via
		(at 346.465906 -89.083134)
		(size 0.508)
		(drill 0.254)
		(layers "F.Cu" "B.Cu")
		(net "GND")
	)
	(via
		(at 452.013574 -308.3052)
		(size 0.508)
		(drill 0.254)
		(layers "F.Cu" "B.Cu")
		(net "GND")
	)
	(via
		(at 41.599866 -302.549814)
		(size 0.4064)
		(drill 0.2032)
		(layers "F.Cu" "B.Cu")
		(net "GND")
	)
	(via
		(at 119.14124 -341.805514)
		(size 0.4572)
		(drill 0.254)
		(layers "F.Cu" "B.Cu")
		(net "GND")
	)
	(via
		(at 418.399976 -313.949842)
		(size 0.4064)
		(drill 0.2032)
		(layers "F.Cu" "B.Cu")
		(net "GND")
	)
	(via
		(at 75.74788 -410.041852)
		(size 0.508)
		(drill 0.254)
		(layers "F.Cu" "B.Cu")
		(net "GND")
	)
	(via
		(at 67.249802 -279.749758)
		(size 0.4064)
		(drill 0.2032)
		(layers "F.Cu" "B.Cu")
		(net "GND")
	)
	(via
		(at 424.09999 -278.799798)
		(size 0.4064)
		(drill 0.2032)
		(layers "F.Cu" "B.Cu")
		(net "GND")
	)
	(via
		(at 449.639944 -73.23963)
		(size 0.508)
		(drill 0.254)
		(layers "F.Cu" "B.Cu")
		(net "GND")
	)
	(via
		(at 422.59504 -102.439978)
		(size 0.508)
		(drill 0.254)
		(layers "F.Cu" "B.Cu")
		(net "GND")
	)
	(via
		(at 66.44767 -123.635008)
		(size 0.508)
		(drill 0.254)
		(layers "F.Cu" "B.Cu")
		(net "GND")
	)
	(via
		(at 344.74531 -261.687564)
		(size 0.508)
		(drill 0.254)
		(layers "F.Cu" "B.Cu")
		(net "GND")
	)
	(via
		(at 292.65499 -27.79014)
		(size 0.508)
		(drill 0.254)
		(layers "F.Cu" "B.Cu")
		(net "GND")
	)
	(via
		(at 89.408 -417.82492)
		(size 0.508)
		(drill 0.254)
		(layers "F.Cu" "B.Cu")
		(net "GND")
	)
	(via
		(at 52.85232 -124.154946)
		(size 0.508)
		(drill 0.254)
		(layers "F.Cu" "B.Cu")
		(net "GND")
	)
	(via
		(at 50.624994 -298.27474)
		(size 0.4064)
		(drill 0.2032)
		(layers "F.Cu" "B.Cu")
		(net "GND")
	)
	(via
		(at 388.949946 -305.399948)
		(size 0.4064)
		(drill 0.2032)
		(layers "F.Cu" "B.Cu")
		(net "GND")
	)
	(via
		(at 47.313342 -29.859478)
		(size 0.508)
		(drill 0.254)
		(layers "F.Cu" "B.Cu")
		(net "GND")
	)
	(via
		(at 36.14801 -371.140228)
		(size 0.508)
		(drill 0.254)
		(layers "F.Cu" "B.Cu")
		(net "GND")
	)
	(via
		(at 64.59347 -149.355302)
		(size 0.508)
		(drill 0.254)
		(layers "F.Cu" "B.Cu")
		(net "GND")
	)
	(via
		(at 186.675014 -289.724846)
		(size 0.4064)
		(drill 0.2032)
		(layers "F.Cu" "B.Cu")
		(net "GND")
	)
	(via
		(at 196.649848 -319.65011)
		(size 0.4064)
		(drill 0.2032)
		(layers "F.Cu" "B.Cu")
		(net "GND")
	)
	(via
		(at 304.354992 -96.901)
		(size 0.508)
		(drill 0.254)
		(layers "F.Cu" "B.Cu")
		(net "GND")
	)
	(via
		(at 169.415206 -43.85691)
		(size 0.508)
		(drill 0.254)
		(layers "F.Cu" "B.Cu")
		(net "GND")
	)
	(via
		(at 345.693746 -216.387172)
		(size 0.4572)
		(drill 0.254)
		(layers "F.Cu" "B.Cu")
		(net "GND")
	)
	(via
		(at 424.09999 -318.699896)
		(size 0.4064)
		(drill 0.2032)
		(layers "F.Cu" "B.Cu")
		(net "GND")
	)
	(via
		(at 79.600044 -273.099784)
		(size 0.4064)
		(drill 0.2032)
		(layers "F.Cu" "B.Cu")
		(net "GND")
	)
	(via
		(at 341.694008 -217.187272)
		(size 0.4572)
		(drill 0.254)
		(layers "F.Cu" "B.Cu")
		(net "GND")
	)
	(via
		(at 300.399704 -317.749936)
		(size 0.4064)
		(drill 0.2032)
		(layers "F.Cu" "B.Cu")
		(net "GND")
	)
	(via
		(at 395.12494 -284.024832)
		(size 0.4064)
		(drill 0.2032)
		(layers "F.Cu" "B.Cu")
		(net "GND")
	)
	(via
		(at 239.429036 -225.17608)
		(size 0.508)
		(drill 0.254)
		(layers "F.Cu" "B.Cu")
		(net "GND")
	)
	(via
		(at 76.27493 -302.074834)
		(size 0.4064)
		(drill 0.2032)
		(layers "F.Cu" "B.Cu")
		(net "GND")
	)
	(via
		(at 428.850044 -280.699718)
		(size 0.4064)
		(drill 0.2032)
		(layers "F.Cu" "B.Cu")
		(net "GND")
	)
	(via
		(at 436.527702 -369.938808)
		(size 0.508)
		(drill 0.254)
		(layers "F.Cu" "B.Cu")
		(net "GND")
	)
	(via
		(at 338.91347 -286.842454)
		(size 0.508)
		(drill 0.254)
		(layers "F.Cu" "B.Cu")
		(net "GND")
	)
	(via
		(at 180.693314 -123.635008)
		(size 0.508)
		(drill 0.254)
		(layers "F.Cu" "B.Cu")
		(net "GND")
	)
	(via
		(at 192.850008 -310.149748)
		(size 0.4064)
		(drill 0.2032)
		(layers "F.Cu" "B.Cu")
		(net "GND")
	)
	(via
		(at 327.683368 -114.075972)
		(size 0.508)
		(drill 0.254)
		(layers "F.Cu" "B.Cu")
		(net "GND")
	)
	(via
		(at 450.274944 -73.23963)
		(size 0.508)
		(drill 0.254)
		(layers "F.Cu" "B.Cu")
		(net "GND")
	)
	(via
		(at 266.691618 -112.981994)
		(size 0.508)
		(drill 0.254)
		(layers "F.Cu" "B.Cu")
		(net "GND")
	)
	(via
		(at 340.094062 -220.38691)
		(size 0.4572)
		(drill 0.254)
		(layers "F.Cu" "B.Cu")
		(net "GND")
	)
	(via
		(at 352.080322 -84.323428)
		(size 0.508)
		(drill 0.254)
		(layers "F.Cu" "B.Cu")
		(net "GND")
	)
	(via
		(at 159.347916 -384.041904)
		(size 0.508)
		(drill 0.254)
		(layers "F.Cu" "B.Cu")
		(net "GND")
	)
	(via
		(at 47.29988 -307.299868)
		(size 0.4064)
		(drill 0.2032)
		(layers "F.Cu" "B.Cu")
		(net "GND")
	)
	(via
		(at 396.54988 -315.849762)
		(size 0.4064)
		(drill 0.2032)
		(layers "F.Cu" "B.Cu")
		(net "GND")
	)
	(via
		(at 157.224984 -285.924752)
		(size 0.4064)
		(drill 0.2032)
		(layers "F.Cu" "B.Cu")
		(net "GND")
	)
	(via
		(at 407.949908 -311.099962)
		(size 0.4064)
		(drill 0.2032)
		(layers "F.Cu" "B.Cu")
		(net "GND")
	)
	(via
		(at 60.599828 -312.999882)
		(size 0.4064)
		(drill 0.2032)
		(layers "F.Cu" "B.Cu")
		(net "GND")
	)
	(via
		(at 231.067356 -217.904314)
		(size 0.4572)
		(drill 0.254)
		(layers "F.Cu" "B.Cu")
		(net "GND")
	)
	(via
		(at 192.850008 -285.449772)
		(size 0.4064)
		(drill 0.2032)
		(layers "F.Cu" "B.Cu")
		(net "GND")
	)
	(via
		(at 386.535168 -343.073482)
		(size 0.4572)
		(drill 0.254)
		(layers "F.Cu" "B.Cu")
		(net "GND")
	)
	(via
		(at 58.699908 -317.749936)
		(size 0.4064)
		(drill 0.2032)
		(layers "F.Cu" "B.Cu")
		(net "GND")
	)
	(via
		(at 39.699946 -308.249828)
		(size 0.4064)
		(drill 0.2032)
		(layers "F.Cu" "B.Cu")
		(net "GND")
	)
	(via
		(at 195.700142 -273.099784)
		(size 0.4064)
		(drill 0.2032)
		(layers "F.Cu" "B.Cu")
		(net "GND")
	)
	(via
		(at 223.75114 -118.461028)
		(size 0.508)
		(drill 0.254)
		(layers "F.Cu" "B.Cu")
		(net "GND")
	)
	(via
		(at 418.874956 -284.974792)
		(size 0.4064)
		(drill 0.2032)
		(layers "F.Cu" "B.Cu")
		(net "GND")
	)
	(via
		(at 392.52779 -378.940314)
		(size 0.508)
		(drill 0.254)
		(layers "F.Cu" "B.Cu")
		(net "GND")
	)
	(via
		(at 34.697416 -114.4905)
		(size 0.508)
		(drill 0.254)
		(layers "F.Cu" "B.Cu")
		(net "GND")
	)
	(via
		(at 48.3743 -357.123746)
		(size 0.4572)
		(drill 0.254)
		(layers "F.Cu" "B.Cu")
		(net "GND")
	)
	(via
		(at 138.166348 -351.611438)
		(size 0.4064)
		(drill 0.2032)
		(layers "F.Cu" "B.Cu")
		(net "GND")
	)
	(via
		(at 302.275748 -214.472012)
		(size 0.508)
		(drill 0.254)
		(layers "F.Cu" "B.Cu")
		(net "GND")
	)
	(via
		(at 148.26996 -386.24256)
		(size 0.508)
		(drill 0.254)
		(layers "F.Cu" "B.Cu")
		(net "GND")
	)
	(via
		(at 162.924998 -284.024832)
		(size 0.4064)
		(drill 0.2032)
		(layers "F.Cu" "B.Cu")
		(net "GND")
	)
	(via
		(at 273.799808 -313.949842)
		(size 0.4064)
		(drill 0.2032)
		(layers "F.Cu" "B.Cu")
		(net "GND")
	)
	(via
		(at 159.573468 -72.56526)
		(size 0.508)
		(drill 0.254)
		(layers "F.Cu" "B.Cu")
		(net "GND")
	)
	(via
		(at 84.808314 -151.42464)
		(size 0.508)
		(drill 0.254)
		(layers "F.Cu" "B.Cu")
		(net "GND")
	)
	(via
		(at 388.474966 -274.524978)
		(size 0.4064)
		(drill 0.2032)
		(layers "F.Cu" "B.Cu")
		(net "GND")
	)
	(via
		(at 401.15236 -124.154946)
		(size 0.508)
		(drill 0.254)
		(layers "F.Cu" "B.Cu")
		(net "GND")
	)
	(via
		(at 286.927798 -401.040092)
		(size 0.508)
		(drill 0.254)
		(layers "F.Cu" "B.Cu")
		(net "GND")
	)
	(via
		(at 407.330656 -87.019384)
		(size 0.508)
		(drill 0.254)
		(layers "F.Cu" "B.Cu")
		(net "GND")
	)
	(via
		(at 289.47491 -284.974792)
		(size 0.4064)
		(drill 0.2032)
		(layers "F.Cu" "B.Cu")
		(net "GND")
	)
	(via
		(at 52.999894 -276.899878)
		(size 0.4064)
		(drill 0.2032)
		(layers "F.Cu" "B.Cu")
		(net "GND")
	)
	(via
		(at 104.483662 -385.93776)
		(size 0.508)
		(drill 0.254)
		(layers "F.Cu" "B.Cu")
		(net "GND")
	)
	(via
		(at 67.66687 -154.755088)
		(size 0.508)
		(drill 0.254)
		(layers "F.Cu" "B.Cu")
		(net "GND")
	)
	(via
		(at 387.525006 -273.574764)
		(size 0.4064)
		(drill 0.2032)
		(layers "F.Cu" "B.Cu")
		(net "GND")
	)
	(via
		(at 258.475226 -236.758988)
		(size 0.508)
		(drill 0.254)
		(layers "F.Cu" "B.Cu")
		(net "GND")
	)
	(via
		(at 205.88859 -31.642304)
		(size 0.508)
		(drill 0.254)
		(layers "F.Cu" "B.Cu")
		(net "GND")
	)
	(via
		(at 302.327818 -385.141978)
		(size 0.508)
		(drill 0.254)
		(layers "F.Cu" "B.Cu")
		(net "GND")
	)
	(via
		(at 403.71014 -345.465146)
		(size 0.4064)
		(drill 0.2032)
		(layers "F.Cu" "B.Cu")
		(net "GND")
	)
	(via
		(at 296.938954 -343.073482)
		(size 0.4572)
		(drill 0.254)
		(layers "F.Cu" "B.Cu")
		(net "GND")
	)
	(via
		(at 75.240642 -345.465146)
		(size 0.4064)
		(drill 0.2032)
		(layers "F.Cu" "B.Cu")
		(net "GND")
	)
	(via
		(at 64.59347 -123.635008)
		(size 0.508)
		(drill 0.254)
		(layers "F.Cu" "B.Cu")
		(net "GND")
	)
	(via
		(at 419.824916 -298.27474)
		(size 0.4064)
		(drill 0.2032)
		(layers "F.Cu" "B.Cu")
		(net "GND")
	)
	(via
		(at 383.401316 -102.181914)
		(size 0.508)
		(drill 0.254)
		(layers "F.Cu" "B.Cu")
		(net "GND")
	)
	(via
		(at 156.275024 -274.524978)
		(size 0.4064)
		(drill 0.2032)
		(layers "F.Cu" "B.Cu")
		(net "GND")
	)
	(via
		(at 442.15939 -309.690516)
		(size 0.508)
		(drill 0.254)
		(layers "F.Cu" "B.Cu")
		(net "GND")
	)
	(via
		(at 267.959586 -108.123228)
		(size 0.508)
		(drill 0.254)
		(layers "F.Cu" "B.Cu")
		(net "GND")
	)
	(via
		(at 47.29988 -276.899878)
		(size 0.4064)
		(drill 0.2032)
		(layers "F.Cu" "B.Cu")
		(net "GND")
	)
	(via
		(at 267.252196 -13.613638)
		(size 0.508)
		(drill 0.254)
		(layers "F.Cu" "B.Cu")
		(net "GND")
	)
	(via
		(at 234.929426 -289.391344)
		(size 0.508)
		(drill 0.254)
		(layers "F.Cu" "B.Cu")
		(net "GND")
	)
	(via
		(at 362.362496 -279.000712)
		(size 0.508)
		(drill 0.254)
		(layers "F.Cu" "B.Cu")
		(net "GND")
	)
	(via
		(at 151.748998 -29.589984)
		(size 0.508)
		(drill 0.254)
		(layers "F.Cu" "B.Cu")
		(net "GND")
	)
	(via
		(at 23.706836 -0.762)
		(size 0.508)
		(drill 0.254)
		(layers "F.Cu" "B.Cu")
		(net "GND")
	)
	(via
		(at 301.349918 -314.899802)
		(size 0.4064)
		(drill 0.2032)
		(layers "F.Cu" "B.Cu")
		(net "GND")
	)
	(via
		(at 393.7 -277.849838)
		(size 0.4064)
		(drill 0.2032)
		(layers "F.Cu" "B.Cu")
		(net "GND")
	)
	(via
		(at 463.037682 -138.697462)
		(size 0.508)
		(drill 0.254)
		(layers "F.Cu" "B.Cu")
		(net "GND")
	)
	(via
		(at 75.79995 -301.599854)
		(size 0.4064)
		(drill 0.2032)
		(layers "F.Cu" "B.Cu")
		(net "GND")
	)
	(via
		(at 422.551352 -45.865288)
		(size 0.508)
		(drill 0.254)
		(layers "F.Cu" "B.Cu")
		(net "GND")
	)
	(via
		(at 332.33614 -94.208346)
		(size 0.508)
		(drill 0.254)
		(layers "F.Cu" "B.Cu")
		(net "GND")
	)
	(via
		(at 182.39994 -314.899802)
		(size 0.4064)
		(drill 0.2032)
		(layers "F.Cu" "B.Cu")
		(net "GND")
	)
	(via
		(at 228.150928 -149.43328)
		(size 0.508)
		(drill 0.254)
		(layers "F.Cu" "B.Cu")
		(net "GND")
	)
	(via
		(at 336.37347 -286.842454)
		(size 0.508)
		(drill 0.254)
		(layers "F.Cu" "B.Cu")
		(net "GND")
	)
	(via
		(at 36.374832 -285.924752)
		(size 0.4064)
		(drill 0.2032)
		(layers "F.Cu" "B.Cu")
		(net "GND")
	)
	(via
		(at 7.820152 -34.990278)
		(size 0.508)
		(drill 0.254)
		(layers "F.Cu" "B.Cu")
		(net "GND")
	)
	(via
		(at 71.524876 -303.024794)
		(size 0.4064)
		(drill 0.2032)
		(layers "F.Cu" "B.Cu")
		(net "GND")
	)
	(via
		(at 158.658052 -57.521094)
		(size 0.508)
		(drill 0.254)
		(layers "F.Cu" "B.Cu")
		(net "GND")
	)
	(via
		(at 290.721034 -358.391714)
		(size 0.4572)
		(drill 0.254)
		(layers "F.Cu" "B.Cu")
		(net "GND")
	)
	(via
		(at 337.514946 -45.88891)
		(size 0.508)
		(drill 0.254)
		(layers "F.Cu" "B.Cu")
		(net "GND")
	)
	(via
		(at 104.648 -417.82492)
		(size 0.508)
		(drill 0.254)
		(layers "F.Cu" "B.Cu")
		(net "GND")
	)
	(via
		(at 290.266374 -35.871912)
		(size 0.508)
		(drill 0.254)
		(layers "F.Cu" "B.Cu")
		(net "GND")
	)
	(via
		(at 201.214482 -338.13242)
		(size 0.508)
		(drill 0.254)
		(layers "F.Cu" "B.Cu")
		(net "GND")
	)
	(via
		(at 419.667944 -136.645142)
		(size 0.508)
		(drill 0.254)
		(layers "F.Cu" "B.Cu")
		(net "GND")
	)
	(via
		(at 227.867972 -220.303852)
		(size 0.4572)
		(drill 0.254)
		(layers "F.Cu" "B.Cu")
		(net "GND")
	)
	(via
		(at 128.547622 -381.638556)
		(size 0.508)
		(drill 0.254)
		(layers "F.Cu" "B.Cu")
		(net "GND")
	)
	(via
		(at 392.52779 -380.141988)
		(size 0.508)
		(drill 0.254)
		(layers "F.Cu" "B.Cu")
		(net "GND")
	)
	(via
		(at 401.15236 -125.955044)
		(size 0.508)
		(drill 0.254)
		(layers "F.Cu" "B.Cu")
		(net "GND")
	)
	(via
		(at 234.032806 -90.745818)
		(size 0.508)
		(drill 0.254)
		(layers "F.Cu" "B.Cu")
		(net "GND")
	)
	(via
		(at 71.760334 -355.366066)
		(size 0.4572)
		(drill 0.254)
		(layers "F.Cu" "B.Cu")
		(net "GND")
	)
	(via
		(at 290.721034 -350.977454)
		(size 0.4572)
		(drill 0.254)
		(layers "F.Cu" "B.Cu")
		(net "GND")
	)
	(via
		(at 434.120036 -29.590238)
		(size 0.508)
		(drill 0.254)
		(layers "F.Cu" "B.Cu")
		(net "GND")
	)
	(via
		(at 127.209296 -352.245422)
		(size 0.4572)
		(drill 0.254)
		(layers "F.Cu" "B.Cu")
		(net "GND")
	)
	(via
		(at 58.224928 -291.624766)
		(size 0.4064)
		(drill 0.2032)
		(layers "F.Cu" "B.Cu")
		(net "GND")
	)
	(via
		(at 52.85232 -137.16508)
		(size 0.508)
		(drill 0.254)
		(layers "F.Cu" "B.Cu")
		(net "GND")
	)
	(via
		(at 34.308288 -348.58579)
		(size 0.4064)
		(drill 0.2032)
		(layers "F.Cu" "B.Cu")
		(net "GND")
	)
	(via
		(at 103.869998 -343.298272)
		(size 0.508)
		(drill 0.254)
		(layers "F.Cu" "B.Cu")
		(net "GND")
	)
	(via
		(at 391.324846 -272.624804)
		(size 0.4064)
		(drill 0.2032)
		(layers "F.Cu" "B.Cu")
		(net "GND")
	)
	(via
		(at 277.124922 -284.024832)
		(size 0.4064)
		(drill 0.2032)
		(layers "F.Cu" "B.Cu")
		(net "GND")
	)
	(via
		(at 268.574774 -275.474938)
		(size 0.4064)
		(drill 0.2032)
		(layers "F.Cu" "B.Cu")
		(net "GND")
	)
	(via
		(at 304.467006 -143.955008)
		(size 0.508)
		(drill 0.254)
		(layers "F.Cu" "B.Cu")
		(net "GND")
	)
	(via
		(at 425.04995 -310.149748)
		(size 0.4064)
		(drill 0.2032)
		(layers "F.Cu" "B.Cu")
		(net "GND")
	)
	(via
		(at 315.042804 -345.465146)
		(size 0.4064)
		(drill 0.2032)
		(layers "F.Cu" "B.Cu")
		(net "GND")
	)
	(via
		(at 189.999874 -306.349908)
		(size 0.4064)
		(drill 0.2032)
		(layers "F.Cu" "B.Cu")
		(net "GND")
	)
	(via
		(at 415.96691 -129.445004)
		(size 0.508)
		(drill 0.254)
		(layers "F.Cu" "B.Cu")
		(net "GND")
	)
	(via
		(at 286.35325 -347.951806)
		(size 0.4572)
		(drill 0.254)
		(layers "F.Cu" "B.Cu")
		(net "GND")
	)
	(via
		(at 180.156104 -33.19018)
		(size 0.508)
		(drill 0.254)
		(layers "F.Cu" "B.Cu")
		(net "GND")
	)
	(via
		(at 208.418938 -198.199756)
		(size 0.508)
		(drill 0.254)
		(layers "F.Cu" "B.Cu")
		(net "GND")
	)
	(via
		(at 403.00656 -98.844862)
		(size 0.508)
		(drill 0.254)
		(layers "F.Cu" "B.Cu")
		(net "GND")
	)
	(via
		(at 272.849848 -300.649894)
		(size 0.4064)
		(drill 0.2032)
		(layers "F.Cu" "B.Cu")
		(net "GND")
	)
	(via
		(at 373.72798 -354.732082)
		(size 0.4064)
		(drill 0.2032)
		(layers "F.Cu" "B.Cu")
		(net "GND")
	)
	(via
		(at 417.955222 -145.881852)
		(size 0.508)
		(drill 0.254)
		(layers "F.Cu" "B.Cu")
		(net "GND")
	)
	(via
		(at 103.538274 -286.842454)
		(size 0.508)
		(drill 0.254)
		(layers "F.Cu" "B.Cu")
		(net "GND")
	)
	(via
		(at 84.54771 -384.041904)
		(size 0.508)
		(drill 0.254)
		(layers "F.Cu" "B.Cu")
		(net "GND")
	)
	(via
		(at 187.149994 -316.799722)
		(size 0.4064)
		(drill 0.2032)
		(layers "F.Cu" "B.Cu")
		(net "GND")
	)
	(via
		(at 382.30302 -283.893514)
		(size 0.508)
		(drill 0.254)
		(layers "F.Cu" "B.Cu")
		(net "GND")
	)
	(via
		(at 466.835998 -272.603976)
		(size 0.508)
		(drill 0.254)
		(layers "F.Cu" "B.Cu")
		(net "GND")
	)
	(via
		(at 295.308782 -354.732082)
		(size 0.4064)
		(drill 0.2032)
		(layers "F.Cu" "B.Cu")
		(net "GND")
	)
	(via
		(at 38.347904 -373.441976)
		(size 0.508)
		(drill 0.254)
		(layers "F.Cu" "B.Cu")
		(net "GND")
	)
	(via
		(at 269.999714 -305.399948)
		(size 0.4064)
		(drill 0.2032)
		(layers "F.Cu" "B.Cu")
		(net "GND")
	)
	(via
		(at 160.074864 -299.224954)
		(size 0.4064)
		(drill 0.2032)
		(layers "F.Cu" "B.Cu")
		(net "GND")
	)
	(via
		(at 267.69949 -346.09913)
		(size 0.4572)
		(drill 0.254)
		(layers "F.Cu" "B.Cu")
		(net "GND")
	)
	(via
		(at 80.54975 -281.649932)
		(size 0.4064)
		(drill 0.2032)
		(layers "F.Cu" "B.Cu")
		(net "GND")
	)
	(via
		(at 229.632002 -288.530284)
		(size 0.508)
		(drill 0.254)
		(layers "F.Cu" "B.Cu")
		(net "GND")
	)
	(via
		(at 36.369244 -102.181914)
		(size 0.508)
		(drill 0.254)
		(layers "F.Cu" "B.Cu")
		(net "GND")
	)
	(via
		(at 403.338792 -357.123746)
		(size 0.4572)
		(drill 0.254)
		(layers "F.Cu" "B.Cu")
		(net "GND")
	)
	(via
		(at 418.874956 -284.024832)
		(size 0.4064)
		(drill 0.2032)
		(layers "F.Cu" "B.Cu")
		(net "GND")
	)
	(via
		(at 415.102802 -74.624184)
		(size 0.508)
		(drill 0.254)
		(layers "F.Cu" "B.Cu")
		(net "GND")
	)
	(via
		(at 60.803282 -351.611438)
		(size 0.4064)
		(drill 0.2032)
		(layers "F.Cu" "B.Cu")
		(net "GND")
	)
	(via
		(at 80.54975 -310.149748)
		(size 0.4064)
		(drill 0.2032)
		(layers "F.Cu" "B.Cu")
		(net "GND")
	)
	(via
		(at 400.840956 -154.321002)
		(size 0.508)
		(drill 0.254)
		(layers "F.Cu" "B.Cu")
		(net "GND")
	)
	(via
		(at 38.275006 -289.724846)
		(size 0.4064)
		(drill 0.2032)
		(layers "F.Cu" "B.Cu")
		(net "GND")
	)
	(via
		(at 41.124886 -276.424898)
		(size 0.4064)
		(drill 0.2032)
		(layers "F.Cu" "B.Cu")
		(net "GND")
	)
	(via
		(at 380.111 -212.344)
		(size 0.508)
		(drill 0.254)
		(layers "F.Cu" "B.Cu")
		(net "GND")
	)
	(via
		(at 414.599882 -274.049744)
		(size 0.4064)
		(drill 0.2032)
		(layers "F.Cu" "B.Cu")
		(net "GND")
	)
	(via
		(at 412.89351 -133.0452)
		(size 0.508)
		(drill 0.254)
		(layers "F.Cu" "B.Cu")
		(net "GND")
	)
	(via
		(at 2.47523 -62.429136)
		(size 0.508)
		(drill 0.254)
		(layers "F.Cu" "B.Cu")
		(net "GND")
	)
	(via
		(at 285.981902 -342.439498)
		(size 0.4064)
		(drill 0.2032)
		(layers "F.Cu" "B.Cu")
		(net "GND")
	)
	(via
		(at 172.900086 -317.749936)
		(size 0.4064)
		(drill 0.2032)
		(layers "F.Cu" "B.Cu")
		(net "GND")
	)
	(via
		(at 277.251668 -102.445058)
		(size 0.508)
		(drill 0.254)
		(layers "F.Cu" "B.Cu")
		(net "GND")
	)
	(via
		(at 330.919074 -46.893226)
		(size 0.508)
		(drill 0.254)
		(layers "F.Cu" "B.Cu")
		(net "GND")
	)
	(via
		(at 128.916684 -187.588906)
		(size 0.508)
		(drill 0.254)
		(layers "F.Cu" "B.Cu")
		(net "GND")
	)
	(via
		(at 184.29986 -317.749936)
		(size 0.4064)
		(drill 0.2032)
		(layers "F.Cu" "B.Cu")
		(net "GND")
	)
	(via
		(at 11.679936 -41.469056)
		(size 0.508)
		(drill 0.254)
		(layers "F.Cu" "B.Cu")
		(net "GND")
	)
	(via
		(at 68.199762 -310.149748)
		(size 0.4064)
		(drill 0.2032)
		(layers "F.Cu" "B.Cu")
		(net "GND")
	)
	(via
		(at 412.354776 -34.990024)
		(size 0.508)
		(drill 0.254)
		(layers "F.Cu" "B.Cu")
		(net "GND")
	)
	(via
		(at 54.70652 -122.354848)
		(size 0.508)
		(drill 0.254)
		(layers "F.Cu" "B.Cu")
		(net "GND")
	)
	(via
		(at 405.32304 -140.97)
		(size 0.508)
		(drill 0.254)
		(layers "F.Cu" "B.Cu")
		(net "GND")
	)
	(via
		(at 335.698084 -348.58579)
		(size 0.4064)
		(drill 0.2032)
		(layers "F.Cu" "B.Cu")
		(net "GND")
	)
	(via
		(at 190.060326 -19.33956)
		(size 0.508)
		(drill 0.254)
		(layers "F.Cu" "B.Cu")
		(net "GND")
	)
	(via
		(at 387.050026 -306.349908)
		(size 0.4064)
		(drill 0.2032)
		(layers "F.Cu" "B.Cu")
		(net "GND")
	)
	(via
		(at 415.074862 -303.974754)
		(size 0.4064)
		(drill 0.2032)
		(layers "F.Cu" "B.Cu")
		(net "GND")
	)
	(via
		(at 360.25074 -304.373534)
		(size 0.508)
		(drill 0.254)
		(layers "F.Cu" "B.Cu")
		(net "GND")
	)
	(via
		(at 277.599902 -277.849838)
		(size 0.4064)
		(drill 0.2032)
		(layers "F.Cu" "B.Cu")
		(net "GND")
	)
	(via
		(at 191.900048 -307.299868)
		(size 0.4064)
		(drill 0.2032)
		(layers "F.Cu" "B.Cu")
		(net "GND")
	)
	(via
		(at 150.103078 -299.895514)
		(size 0.508)
		(drill 0.254)
		(layers "F.Cu" "B.Cu")
		(net "GND")
	)
	(via
		(at 157.224984 -291.624766)
		(size 0.4064)
		(drill 0.2032)
		(layers "F.Cu" "B.Cu")
		(net "GND")
	)
	(via
		(at 406.049988 -280.699718)
		(size 0.4064)
		(drill 0.2032)
		(layers "F.Cu" "B.Cu")
		(net "GND")
	)
	(via
		(at 286.906462 -109.644942)
		(size 0.508)
		(drill 0.254)
		(layers "F.Cu" "B.Cu")
		(net "GND")
	)
	(via
		(at 21.872448 -348.58579)
		(size 0.4064)
		(drill 0.2032)
		(layers "F.Cu" "B.Cu")
		(net "GND")
	)
	(via
		(at 174.700946 -33.19018)
		(size 0.508)
		(drill 0.254)
		(layers "F.Cu" "B.Cu")
		(net "GND")
	)
	(via
		(at 165.343332 -172.172122)
		(size 0.508)
		(drill 0.254)
		(layers "F.Cu" "B.Cu")
		(net "GND")
	)
	(via
		(at 39.224966 -281.174952)
		(size 0.4064)
		(drill 0.2032)
		(layers "F.Cu" "B.Cu")
		(net "GND")
	)
	(via
		(at 76.74991 -287.349946)
		(size 0.4064)
		(drill 0.2032)
		(layers "F.Cu" "B.Cu")
		(net "GND")
	)
	(via
		(at 28.26385 -256.098548)
		(size 0.508)
		(drill 0.254)
		(layers "F.Cu" "B.Cu")
		(net "GND")
	)
	(via
		(at 10.716768 -163.021518)
		(size 0.508)
		(drill 0.254)
		(layers "F.Cu" "B.Cu")
		(net "GND")
	)
	(via
		(at 196.998082 -134.566914)
		(size 0.508)
		(drill 0.254)
		(layers "F.Cu" "B.Cu")
		(net "GND")
	)
	(via
		(at 195.699888 -313.949842)
		(size 0.4064)
		(drill 0.2032)
		(layers "F.Cu" "B.Cu")
		(net "GND")
	)
	(via
		(at 332.248764 -105.057194)
		(size 0.508)
		(drill 0.254)
		(layers "F.Cu" "B.Cu")
		(net "GND")
	)
	(via
		(at 361.745784 -113.373408)
		(size 0.508)
		(drill 0.254)
		(layers "F.Cu" "B.Cu")
		(net "GND")
	)
	(via
		(at 289.668458 -59.974734)
		(size 0.508)
		(drill 0.254)
		(layers "F.Cu" "B.Cu")
		(net "GND")
	)
	(via
		(at 67.724782 -302.074834)
		(size 0.4064)
		(drill 0.2032)
		(layers "F.Cu" "B.Cu")
		(net "GND")
	)
	(via
		(at 52.999894 -278.799798)
		(size 0.4064)
		(drill 0.2032)
		(layers "F.Cu" "B.Cu")
		(net "GND")
	)
	(via
		(at 306.099718 -273.099784)
		(size 0.4064)
		(drill 0.2032)
		(layers "F.Cu" "B.Cu")
		(net "GND")
	)
	(via
		(at 127.33528 -290.68649)
		(size 0.508)
		(drill 0.254)
		(layers "F.Cu" "B.Cu")
		(net "GND")
	)
	(via
		(at 406.049988 -314.899802)
		(size 0.4064)
		(drill 0.2032)
		(layers "F.Cu" "B.Cu")
		(net "GND")
	)
	(via
		(at 120.832372 -286.842454)
		(size 0.508)
		(drill 0.254)
		(layers "F.Cu" "B.Cu")
		(net "GND")
	)
	(via
		(at 356.120192 -33.19018)
		(size 0.508)
		(drill 0.254)
		(layers "F.Cu" "B.Cu")
		(net "GND")
	)
	(via
		(at 280.13533 -347.951806)
		(size 0.4572)
		(drill 0.254)
		(layers "F.Cu" "B.Cu")
		(net "GND")
	)
	(via
		(at 278.656542 -348.58579)
		(size 0.4064)
		(drill 0.2032)
		(layers "F.Cu" "B.Cu")
		(net "GND")
	)
	(via
		(at 370.551456 -45.865288)
		(size 0.508)
		(drill 0.254)
		(layers "F.Cu" "B.Cu")
		(net "GND")
	)
	(via
		(at 307.049932 -275.949918)
		(size 0.4064)
		(drill 0.2032)
		(layers "F.Cu" "B.Cu")
		(net "GND")
	)
	(via
		(at 261.622286 -253.45644)
		(size 0.508)
		(drill 0.254)
		(layers "F.Cu" "B.Cu")
		(net "GND")
	)
	(via
		(at 255.933194 -395.032738)
		(size 0.508)
		(drill 0.254)
		(layers "F.Cu" "B.Cu")
		(net "GND")
	)
	(via
		(at 285.674816 -291.624766)
		(size 0.4064)
		(drill 0.2032)
		(layers "F.Cu" "B.Cu")
		(net "GND")
	)
	(via
		(at 29.72054 -357.123746)
		(size 0.4572)
		(drill 0.254)
		(layers "F.Cu" "B.Cu")
		(net "GND")
	)
	(via
		(at 150.59152 -133.836664)
		(size 0.508)
		(drill 0.254)
		(layers "F.Cu" "B.Cu")
		(net "GND")
	)
	(via
		(at 21.792184 -70.918832)
		(size 0.508)
		(drill 0.254)
		(layers "F.Cu" "B.Cu")
		(net "GND")
	)
	(via
		(at 299.449744 -312.049922)
		(size 0.4064)
		(drill 0.2032)
		(layers "F.Cu" "B.Cu")
		(net "GND")
	)
	(via
		(at 436.527702 -406.141936)
		(size 0.508)
		(drill 0.254)
		(layers "F.Cu" "B.Cu")
		(net "GND")
	)
	(via
		(at 385.433824 -133.301994)
		(size 0.508)
		(drill 0.254)
		(layers "F.Cu" "B.Cu")
		(net "GND")
	)
	(via
		(at 31.199328 -351.611438)
		(size 0.4064)
		(drill 0.2032)
		(layers "F.Cu" "B.Cu")
		(net "GND")
	)
	(via
		(at 306.494942 -104.240076)
		(size 0.508)
		(drill 0.254)
		(layers "F.Cu" "B.Cu")
		(net "GND")
	)
	(via
		(at 74.248264 -123.635008)
		(size 0.508)
		(drill 0.254)
		(layers "F.Cu" "B.Cu")
		(net "GND")
	)
	(via
		(at 249.047254 -347.89999)
		(size 0.508)
		(drill 0.254)
		(layers "F.Cu" "B.Cu")
		(net "GND")
	)
	(via
		(at 196.649848 -311.099962)
		(size 0.4064)
		(drill 0.2032)
		(layers "F.Cu" "B.Cu")
		(net "GND")
	)
	(via
		(at 290.42487 -285.924752)
		(size 0.4064)
		(drill 0.2032)
		(layers "F.Cu" "B.Cu")
		(net "GND")
	)
	(via
		(at 75.74788 -376.241818)
		(size 0.508)
		(drill 0.254)
		(layers "F.Cu" "B.Cu")
		(net "GND")
	)
	(via
		(at 182.39994 -312.999882)
		(size 0.4064)
		(drill 0.2032)
		(layers "F.Cu" "B.Cu")
		(net "GND")
	)
	(via
		(at 441.445904 -355.366066)
		(size 0.4572)
		(drill 0.254)
		(layers "F.Cu" "B.Cu")
		(net "GND")
	)
	(via
		(at 170.999912 -273.099784)
		(size 0.4064)
		(drill 0.2032)
		(layers "F.Cu" "B.Cu")
		(net "GND")
	)
	(via
		(at 294.22471 -306.824888)
		(size 0.4064)
		(drill 0.2032)
		(layers "F.Cu" "B.Cu")
		(net "GND")
	)
	(via
		(at 295.174924 -285.924752)
		(size 0.4064)
		(drill 0.2032)
		(layers "F.Cu" "B.Cu")
		(net "GND")
	)
	(via
		(at 65.542414 -349.219774)
		(size 0.4572)
		(drill 0.254)
		(layers "F.Cu" "B.Cu")
		(net "GND")
	)
	(via
		(at 99.222052 -52.51704)
		(size 0.508)
		(drill 0.254)
		(layers "F.Cu" "B.Cu")
		(net "GND")
	)
	(via
		(at 361.646724 -387.160008)
		(size 0.508)
		(drill 0.254)
		(layers "F.Cu" "B.Cu")
		(net "GND")
	)
	(via
		(at 105.315004 -43.85691)
		(size 0.508)
		(drill 0.254)
		(layers "F.Cu" "B.Cu")
		(net "GND")
	)
	(via
		(at 266.691618 -123.885452)
		(size 0.508)
		(drill 0.254)
		(layers "F.Cu" "B.Cu")
		(net "GND")
	)
	(via
		(at 226.303586 -147.266152)
		(size 0.508)
		(drill 0.254)
		(layers "F.Cu" "B.Cu")
		(net "GND")
	)
	(via
		(at 344.653616 -358.391714)
		(size 0.4572)
		(drill 0.254)
		(layers "F.Cu" "B.Cu")
		(net "GND")
	)
	(via
		(at 31.747968 -376.241818)
		(size 0.508)
		(drill 0.254)
		(layers "F.Cu" "B.Cu")
		(net "GND")
	)
	(via
		(at 302.774858 -299.224954)
		(size 0.4064)
		(drill 0.2032)
		(layers "F.Cu" "B.Cu")
		(net "GND")
	)
	(via
		(at 60.124848 -302.074834)
		(size 0.4064)
		(drill 0.2032)
		(layers "F.Cu" "B.Cu")
		(net "GND")
	)
	(via
		(at 418.874956 -303.024794)
		(size 0.4064)
		(drill 0.2032)
		(layers "F.Cu" "B.Cu")
		(net "GND")
	)
	(via
		(at 209.256122 -185.955686)
		(size 0.508)
		(drill 0.254)
		(layers "F.Cu" "B.Cu")
		(net "GND")
	)
	(via
		(at 46.273974 -73.85177)
		(size 0.508)
		(drill 0.254)
		(layers "F.Cu" "B.Cu")
		(net "GND")
	)
	(via
		(at 44.449746 -280.699718)
		(size 0.4064)
		(drill 0.2032)
		(layers "F.Cu" "B.Cu")
		(net "GND")
	)
	(via
		(at 280.924762 -291.624766)
		(size 0.4064)
		(drill 0.2032)
		(layers "F.Cu" "B.Cu")
		(net "GND")
	)
	(via
		(at 71.760334 -344.831162)
		(size 0.4572)
		(drill 0.254)
		(layers "F.Cu" "B.Cu")
		(net "GND")
	)
	(via
		(at 160.85566 -63.218314)
		(size 0.508)
		(drill 0.254)
		(layers "F.Cu" "B.Cu")
		(net "GND")
	)
	(via
		(at 292.32479 -303.974754)
		(size 0.4064)
		(drill 0.2032)
		(layers "F.Cu" "B.Cu")
		(net "GND")
	)
	(via
		(at 299.866812 -118.234968)
		(size 0.508)
		(drill 0.254)
		(layers "F.Cu" "B.Cu")
		(net "GND")
	)
	(via
		(at 286.624776 -302.074834)
		(size 0.4064)
		(drill 0.2032)
		(layers "F.Cu" "B.Cu")
		(net "GND")
	)
	(via
		(at 317.044324 -345.465146)
		(size 0.4064)
		(drill 0.2032)
		(layers "F.Cu" "B.Cu")
		(net "GND")
	)
	(via
		(at 80.54975 -311.099962)
		(size 0.4064)
		(drill 0.2032)
		(layers "F.Cu" "B.Cu")
		(net "GND")
	)
	(via
		(at 33.947862 -373.441976)
		(size 0.508)
		(drill 0.254)
		(layers "F.Cu" "B.Cu")
		(net "GND")
	)
	(via
		(at 304.379884 -111.750602)
		(size 0.508)
		(drill 0.254)
		(layers "F.Cu" "B.Cu")
		(net "GND")
	)
	(via
		(at 151.999442 -314.899548)
		(size 0.4064)
		(drill 0.2032)
		(layers "F.Cu" "B.Cu")
		(net "GND")
	)
	(via
		(at 45.520102 -56.441848)
		(size 0.508)
		(drill 0.254)
		(layers "F.Cu" "B.Cu")
		(net "GND")
	)
	(via
		(at 96.210628 -57.439814)
		(size 0.508)
		(drill 0.254)
		(layers "F.Cu" "B.Cu")
		(net "GND")
	)
	(via
		(at 100.581206 -33.459674)
		(size 0.508)
		(drill 0.254)
		(layers "F.Cu" "B.Cu")
		(net "GND")
	)
	(via
		(at 154.850084 -310.149748)
		(size 0.4064)
		(drill 0.2032)
		(layers "F.Cu" "B.Cu")
		(net "GND")
	)
	(via
		(at 153.898346 -19.757136)
		(size 0.508)
		(drill 0.254)
		(layers "F.Cu" "B.Cu")
		(net "GND")
	)
	(via
		(at 159.124904 -278.324818)
		(size 0.4064)
		(drill 0.2032)
		(layers "F.Cu" "B.Cu")
		(net "GND")
	)
	(via
		(at 164.824918 -284.024832)
		(size 0.4064)
		(drill 0.2032)
		(layers "F.Cu" "B.Cu")
		(net "GND")
	)
	(via
		(at 310.374792 -294.4749)
		(size 0.4064)
		(drill 0.2032)
		(layers "F.Cu" "B.Cu")
		(net "GND")
	)
	(via
		(at 278.549862 -310.149748)
		(size 0.4064)
		(drill 0.2032)
		(layers "F.Cu" "B.Cu")
		(net "GND")
	)
	(via
		(at 346.327984 -382.73863)
		(size 0.508)
		(drill 0.254)
		(layers "F.Cu" "B.Cu")
		(net "GND")
	)
	(via
		(at 160.509712 -354.732082)
		(size 0.4064)
		(drill 0.2032)
		(layers "F.Cu" "B.Cu")
		(net "GND")
	)
	(via
		(at 414.11271 -120.035066)
		(size 0.508)
		(drill 0.254)
		(layers "F.Cu" "B.Cu")
		(net "GND")
	)
	(via
		(at 324.101968 -58.731404)
		(size 0.508)
		(drill 0.254)
		(layers "F.Cu" "B.Cu")
		(net "GND")
	)
	(via
		(at 298.974764 -285.924752)
		(size 0.4064)
		(drill 0.2032)
		(layers "F.Cu" "B.Cu")
		(net "GND")
	)
	(via
		(at 125.419612 -163.021518)
		(size 0.508)
		(drill 0.254)
		(layers "F.Cu" "B.Cu")
		(net "GND")
	)
	(via
		(at 250.013978 -190.101728)
		(size 0.508)
		(drill 0.254)
		(layers "F.Cu" "B.Cu")
		(net "GND")
	)
	(via
		(at 149.920198 -29.590238)
		(size 0.508)
		(drill 0.254)
		(layers "F.Cu" "B.Cu")
		(net "GND")
	)
	(via
		(at 163.747958 -382.84023)
		(size 0.508)
		(drill 0.254)
		(layers "F.Cu" "B.Cu")
		(net "GND")
	)
	(via
		(at 405.949912 -27.04973)
		(size 0.508)
		(drill 0.254)
		(layers "F.Cu" "B.Cu")
		(net "GND")
	)
	(via
		(at 300.874684 -298.27474)
		(size 0.4064)
		(drill 0.2032)
		(layers "F.Cu" "B.Cu")
		(net "GND")
	)
	(via
		(at 68.199762 -274.049744)
		(size 0.4064)
		(drill 0.2032)
		(layers "F.Cu" "B.Cu")
		(net "GND")
	)
	(via
		(at 194.749928 -305.399948)
		(size 0.4064)
		(drill 0.2032)
		(layers "F.Cu" "B.Cu")
		(net "GND")
	)
	(via
		(at 175.749966 -311.099962)
		(size 0.4064)
		(drill 0.2032)
		(layers "F.Cu" "B.Cu")
		(net "GND")
	)
	(via
		(at 314.045092 -50.516282)
		(size 0.508)
		(drill 0.254)
		(layers "F.Cu" "B.Cu")
		(net "GND")
	)
	(via
		(at 169.940224 -33.857692)
		(size 0.508)
		(drill 0.254)
		(layers "F.Cu" "B.Cu")
		(net "GND")
	)
	(via
		(at 247.325642 -128.193546)
		(size 0.508)
		(drill 0.254)
		(layers "F.Cu" "B.Cu")
		(net "GND")
	)
	(via
		(at 31.570676 -358.391714)
		(size 0.4572)
		(drill 0.254)
		(layers "F.Cu" "B.Cu")
		(net "GND")
	)
	(via
		(at 227.290376 -106.421682)
		(size 0.508)
		(drill 0.254)
		(layers "F.Cu" "B.Cu")
		(net "GND")
	)
	(via
		(at 161.54781 -402.140166)
		(size 0.508)
		(drill 0.254)
		(layers "F.Cu" "B.Cu")
		(net "GND")
	)
	(via
		(at 421.127682 -407.24201)
		(size 0.508)
		(drill 0.254)
		(layers "F.Cu" "B.Cu")
		(net "GND")
	)
	(via
		(at 70.130162 -351.611438)
		(size 0.4064)
		(drill 0.2032)
		(layers "F.Cu" "B.Cu")
		(net "GND")
	)
	(via
		(at 66.248788 -29.589984)
		(size 0.508)
		(drill 0.254)
		(layers "F.Cu" "B.Cu")
		(net "GND")
	)
	(via
		(at 172.574204 -344.831162)
		(size 0.4572)
		(drill 0.254)
		(layers "F.Cu" "B.Cu")
		(net "GND")
	)
	(via
		(at 343.394792 -355.366066)
		(size 0.4572)
		(drill 0.254)
		(layers "F.Cu" "B.Cu")
		(net "GND")
	)
	(via
		(at 306.298346 -37.201094)
		(size 0.508)
		(drill 0.254)
		(layers "F.Cu" "B.Cu")
		(net "GND")
	)
	(via
		(at 330.927964 -410.041852)
		(size 0.508)
		(drill 0.254)
		(layers "F.Cu" "B.Cu")
		(net "GND")
	)
	(via
		(at 95.76308 -198.76389)
		(size 0.508)
		(drill 0.254)
		(layers "F.Cu" "B.Cu")
		(net "GND")
	)
	(via
		(at 315.124846 -297.32478)
		(size 0.4064)
		(drill 0.2032)
		(layers "F.Cu" "B.Cu")
		(net "GND")
	)
	(via
		(at 430.466246 -154.476958)
		(size 0.508)
		(drill 0.254)
		(layers "F.Cu" "B.Cu")
		(net "GND")
	)
	(via
		(at 363.599222 -132.538216)
		(size 0.508)
		(drill 0.254)
		(layers "F.Cu" "B.Cu")
		(net "GND")
	)
	(via
		(at 390.374886 -275.474938)
		(size 0.4064)
		(drill 0.2032)
		(layers "F.Cu" "B.Cu")
		(net "GND")
	)
	(via
		(at 290.102036 -27.729688)
		(size 0.508)
		(drill 0.254)
		(layers "F.Cu" "B.Cu")
		(net "GND")
	)
	(via
		(at 415.074862 -287.824926)
		(size 0.4064)
		(drill 0.2032)
		(layers "F.Cu" "B.Cu")
		(net "GND")
	)
	(via
		(at 178.929284 -193.195194)
		(size 0.508)
		(drill 0.254)
		(layers "F.Cu" "B.Cu")
		(net "GND")
	)
	(via
		(at 335.698084 -342.439498)
		(size 0.4064)
		(drill 0.2032)
		(layers "F.Cu" "B.Cu")
		(net "GND")
	)
	(via
		(at 191.900048 -312.999882)
		(size 0.4064)
		(drill 0.2032)
		(layers "F.Cu" "B.Cu")
		(net "GND")
	)
	(via
		(at 121.576592 -268.731492)
		(size 0.508)
		(drill 0.254)
		(layers "F.Cu" "B.Cu")
		(net "GND")
	)
	(via
		(at 42.074846 -283.074872)
		(size 0.4064)
		(drill 0.2032)
		(layers "F.Cu" "B.Cu")
		(net "GND")
	)
	(via
		(at 62.8904 -215.519)
		(size 0.508)
		(drill 0.254)
		(layers "F.Cu" "B.Cu")
		(net "GND")
	)
	(via
		(at 387.793992 -352.245422)
		(size 0.4572)
		(drill 0.254)
		(layers "F.Cu" "B.Cu")
		(net "GND")
	)
	(via
		(at 429.800004 -278.799798)
		(size 0.4064)
		(drill 0.2032)
		(layers "F.Cu" "B.Cu")
		(net "GND")
	)
	(via
		(at 109.812328 -228.002846)
		(size 0.508)
		(drill 0.254)
		(layers "F.Cu" "B.Cu")
		(net "GND")
	)
	(via
		(at 107.509564 -161.807652)
		(size 0.508)
		(drill 0.254)
		(layers "F.Cu" "B.Cu")
		(net "GND")
	)
	(via
		(at 383.426208 -350.977454)
		(size 0.4572)
		(drill 0.254)
		(layers "F.Cu" "B.Cu")
		(net "GND")
	)
	(via
		(at 82.449924 -286.399732)
		(size 0.4064)
		(drill 0.2032)
		(layers "F.Cu" "B.Cu")
		(net "GND")
	)
	(via
		(at 135.358124 -73.85177)
		(size 0.508)
		(drill 0.254)
		(layers "F.Cu" "B.Cu")
		(net "GND")
	)
	(via
		(at 397.02486 -296.37482)
		(size 0.4064)
		(drill 0.2032)
		(layers "F.Cu" "B.Cu")
		(net "GND")
	)
	(via
		(at 280.019506 -38.701218)
		(size 0.508)
		(drill 0.254)
		(layers "F.Cu" "B.Cu")
		(net "GND")
	)
	(via
		(at 115.34775 -395.938502)
		(size 0.508)
		(drill 0.254)
		(layers "F.Cu" "B.Cu")
		(net "GND")
	)
	(via
		(at 54.424834 -284.024832)
		(size 0.4064)
		(drill 0.2032)
		(layers "F.Cu" "B.Cu")
		(net "GND")
	)
	(via
		(at 166.725092 -287.824926)
		(size 0.4064)
		(drill 0.2032)
		(layers "F.Cu" "B.Cu")
		(net "GND")
	)
	(via
		(at 165.432232 -120.084088)
		(size 0.508)
		(drill 0.254)
		(layers "F.Cu" "B.Cu")
		(net "GND")
	)
	(via
		(at 431.224944 -293.52494)
		(size 0.4064)
		(drill 0.2032)
		(layers "F.Cu" "B.Cu")
		(net "GND")
	)
	(via
		(at 452.284084 -106.779822)
		(size 0.508)
		(drill 0.254)
		(layers "F.Cu" "B.Cu")
		(net "GND")
	)
	(via
		(at 158.174944 -275.474938)
		(size 0.4064)
		(drill 0.2032)
		(layers "F.Cu" "B.Cu")
		(net "GND")
	)
	(via
		(at 129.456942 -228.67493)
		(size 0.508)
		(drill 0.254)
		(layers "F.Cu" "B.Cu")
		(net "GND")
	)
	(via
		(at 393.351766 -129.964942)
		(size 0.508)
		(drill 0.254)
		(layers "F.Cu" "B.Cu")
		(net "GND")
	)
	(via
		(at 402.724874 -287.824926)
		(size 0.4064)
		(drill 0.2032)
		(layers "F.Cu" "B.Cu")
		(net "GND")
	)
	(via
		(at 383.426208 -349.219774)
		(size 0.4572)
		(drill 0.254)
		(layers "F.Cu" "B.Cu")
		(net "GND")
	)
	(via
		(at 300.12767 -404.940262)
		(size 0.508)
		(drill 0.254)
		(layers "F.Cu" "B.Cu")
		(net "GND")
	)
	(via
		(at 292.967918 -54.238906)
		(size 0.508)
		(drill 0.254)
		(layers "F.Cu" "B.Cu")
		(net "GND")
	)
	(via
		(at 431.700178 -283.550106)
		(size 0.4064)
		(drill 0.2032)
		(layers "F.Cu" "B.Cu")
		(net "GND")
	)
	(via
		(at 31.570676 -354.098098)
		(size 0.4572)
		(drill 0.254)
		(layers "F.Cu" "B.Cu")
		(net "GND")
	)
	(via
		(at 382.75514 -27.79014)
		(size 0.508)
		(drill 0.254)
		(layers "F.Cu" "B.Cu")
		(net "GND")
	)
	(via
		(at 148.494496 -198.5899)
		(size 0.508)
		(drill 0.254)
		(layers "F.Cu" "B.Cu")
		(net "GND")
	)
	(via
		(at 82.347816 -381.241808)
		(size 0.508)
		(drill 0.254)
		(layers "F.Cu" "B.Cu")
		(net "GND")
	)
	(via
		(at 75.74788 -384.041904)
		(size 0.508)
		(drill 0.254)
		(layers "F.Cu" "B.Cu")
		(net "GND")
	)
	(via
		(at 267.301218 -102.181914)
		(size 0.508)
		(drill 0.254)
		(layers "F.Cu" "B.Cu")
		(net "GND")
	)
	(via
		(at 119.174768 -289.41649)
		(size 0.508)
		(drill 0.254)
		(layers "F.Cu" "B.Cu")
		(net "GND")
	)
	(via
		(at 416.574224 -347.951806)
		(size 0.4572)
		(drill 0.254)
		(layers "F.Cu" "B.Cu")
		(net "GND")
	)
	(via
		(at 419.349936 -276.899878)
		(size 0.4064)
		(drill 0.2032)
		(layers "F.Cu" "B.Cu")
		(net "GND")
	)
	(via
		(at 64.399922 -273.099784)
		(size 0.4064)
		(drill 0.2032)
		(layers "F.Cu" "B.Cu")
		(net "GND")
	)
	(via
		(at 188.099954 -313.949842)
		(size 0.4064)
		(drill 0.2032)
		(layers "F.Cu" "B.Cu")
		(net "GND")
	)
	(via
		(at 210.03895 -195.326)
		(size 0.508)
		(drill 0.254)
		(layers "F.Cu" "B.Cu")
		(net "GND")
	)
	(via
		(at 318.019938 -29.590238)
		(size 0.508)
		(drill 0.254)
		(layers "F.Cu" "B.Cu")
		(net "GND")
	)
	(via
		(at 384.199638 -310.150002)
		(size 0.4064)
		(drill 0.2032)
		(layers "F.Cu" "B.Cu")
		(net "GND")
	)
	(via
		(at 199.64019 -120.30456)
		(size 0.508)
		(drill 0.254)
		(layers "F.Cu" "B.Cu")
		(net "GND")
	)
	(via
		(at 156.275024 -285.924752)
		(size 0.4064)
		(drill 0.2032)
		(layers "F.Cu" "B.Cu")
		(net "GND")
	)
	(via
		(at 90.785442 -357.75773)
		(size 0.4064)
		(drill 0.2032)
		(layers "F.Cu" "B.Cu")
		(net "GND")
	)
	(via
		(at 427.89983 -310.149748)
		(size 0.4064)
		(drill 0.2032)
		(layers "F.Cu" "B.Cu")
		(net "GND")
	)
	(via
		(at 191.900048 -309.199788)
		(size 0.4064)
		(drill 0.2032)
		(layers "F.Cu" "B.Cu")
		(net "GND")
	)
	(via
		(at 28.557982 -295.933114)
		(size 0.508)
		(drill 0.254)
		(layers "F.Cu" "B.Cu")
		(net "GND")
	)
	(via
		(at 365.401352 -96.669606)
		(size 0.508)
		(drill 0.254)
		(layers "F.Cu" "B.Cu")
		(net "GND")
	)
	(via
		(at 261.990078 -416.508438)
		(size 0.508)
		(drill 0.254)
		(layers "F.Cu" "B.Cu")
		(net "GND")
	)
	(via
		(at 54.424834 -282.124912)
		(size 0.4064)
		(drill 0.2032)
		(layers "F.Cu" "B.Cu")
		(net "GND")
	)
	(via
		(at 366.380776 -148.718778)
		(size 0.508)
		(drill 0.254)
		(layers "F.Cu" "B.Cu")
		(net "GND")
	)
	(via
		(at 172.547788 -402.241766)
		(size 0.508)
		(drill 0.254)
		(layers "F.Cu" "B.Cu")
		(net "GND")
	)
	(via
		(at 26.61158 -347.951806)
		(size 0.4572)
		(drill 0.254)
		(layers "F.Cu" "B.Cu")
		(net "GND")
	)
	(via
		(at 77.700124 -273.099784)
		(size 0.4064)
		(drill 0.2032)
		(layers "F.Cu" "B.Cu")
		(net "GND")
	)
	(via
		(at 249.59818 -114.351054)
		(size 0.508)
		(drill 0.254)
		(layers "F.Cu" "B.Cu")
		(net "GND")
	)
	(via
		(at 269.333726 -122.091958)
		(size 0.508)
		(drill 0.254)
		(layers "F.Cu" "B.Cu")
		(net "GND")
	)
	(via
		(at 260.757924 -295.933114)
		(size 0.508)
		(drill 0.254)
		(layers "F.Cu" "B.Cu")
		(net "GND")
	)
	(via
		(at 217.54084 -45.853858)
		(size 0.508)
		(drill 0.254)
		(layers "F.Cu" "B.Cu")
		(net "GND")
	)
	(via
		(at 295.998138 -21.077936)
		(size 0.508)
		(drill 0.254)
		(layers "F.Cu" "B.Cu")
		(net "GND")
	)
	(via
		(at 278.074882 -287.824926)
		(size 0.4064)
		(drill 0.2032)
		(layers "F.Cu" "B.Cu")
		(net "GND")
	)
	(via
		(at 45.26534 -350.977454)
		(size 0.4572)
		(drill 0.254)
		(layers "F.Cu" "B.Cu")
		(net "GND")
	)
	(via
		(at 294.22471 -302.074834)
		(size 0.4064)
		(drill 0.2032)
		(layers "F.Cu" "B.Cu")
		(net "GND")
	)
	(via
		(at 335.328006 -404.940262)
		(size 0.508)
		(drill 0.254)
		(layers "F.Cu" "B.Cu")
		(net "GND")
	)
	(via
		(at 282.872942 -357.75773)
		(size 0.4064)
		(drill 0.2032)
		(layers "F.Cu" "B.Cu")
		(net "GND")
	)
	(via
		(at 4.562856 -98.881692)
		(size 0.508)
		(drill 0.254)
		(layers "F.Cu" "B.Cu")
		(net "GND")
	)
	(via
		(at 430.466246 -150.876762)
		(size 0.508)
		(drill 0.254)
		(layers "F.Cu" "B.Cu")
		(net "GND")
	)
	(via
		(at 7.820152 -29.590238)
		(size 0.508)
		(drill 0.254)
		(layers "F.Cu" "B.Cu")
		(net "GND")
	)
	(via
		(at 394.787628 -26.360882)
		(size 0.508)
		(drill 0.254)
		(layers "F.Cu" "B.Cu")
		(net "GND")
	)
	(via
		(at 297.310302 -354.732082)
		(size 0.4064)
		(drill 0.2032)
		(layers "F.Cu" "B.Cu")
		(net "GND")
	)
	(via
		(at 81.499964 -277.849838)
		(size 0.4064)
		(drill 0.2032)
		(layers "F.Cu" "B.Cu")
		(net "GND")
	)
	(via
		(at 102.629462 -384.472942)
		(size 0.508)
		(drill 0.254)
		(layers "F.Cu" "B.Cu")
		(net "GND")
	)
	(via
		(at 406.202134 -27.729688)
		(size 0.508)
		(drill 0.254)
		(layers "F.Cu" "B.Cu")
		(net "GND")
	)
	(via
		(at 413.836612 -351.611438)
		(size 0.4064)
		(drill 0.2032)
		(layers "F.Cu" "B.Cu")
		(net "GND")
	)
	(via
		(at 47.393606 -108.279946)
		(size 0.508)
		(drill 0.254)
		(layers "F.Cu" "B.Cu")
		(net "GND")
	)
	(via
		(at 120.991376 -350.977454)
		(size 0.4572)
		(drill 0.254)
		(layers "F.Cu" "B.Cu")
		(net "GND")
	)
	(via
		(at 313.224926 -293.52494)
		(size 0.4064)
		(drill 0.2032)
		(layers "F.Cu" "B.Cu")
		(net "GND")
	)
	(via
		(at 283.833062 -111.44504)
		(size 0.508)
		(drill 0.254)
		(layers "F.Cu" "B.Cu")
		(net "GND")
	)
	(via
		(at 117.309646 -169.676064)
		(size 0.508)
		(drill 0.254)
		(layers "F.Cu" "B.Cu")
		(net "GND")
	)
	(via
		(at 395.12494 -307.774848)
		(size 0.4064)
		(drill 0.2032)
		(layers "F.Cu" "B.Cu")
		(net "GND")
	)
	(via
		(at 439.815732 -348.58579)
		(size 0.4064)
		(drill 0.2032)
		(layers "F.Cu" "B.Cu")
		(net "GND")
	)
	(via
		(at 87.305134 -349.219774)
		(size 0.4572)
		(drill 0.254)
		(layers "F.Cu" "B.Cu")
		(net "GND")
	)
	(via
		(at 313.224926 -291.624766)
		(size 0.4064)
		(drill 0.2032)
		(layers "F.Cu" "B.Cu")
		(net "GND")
	)
	(via
		(at 290.17976 -99.750372)
		(size 0.508)
		(drill 0.254)
		(layers "F.Cu" "B.Cu")
		(net "GND")
	)
	(via
		(at 322.255896 -33.19018)
		(size 0.508)
		(drill 0.254)
		(layers "F.Cu" "B.Cu")
		(net "GND")
	)
	(via
		(at 128.638554 -306.55387)
		(size 0.508)
		(drill 0.254)
		(layers "F.Cu" "B.Cu")
		(net "GND")
	)
	(via
		(at 183.3499 -279.749758)
		(size 0.4064)
		(drill 0.2032)
		(layers "F.Cu" "B.Cu")
		(net "GND")
	)
	(via
		(at 388.16534 -354.732082)
		(size 0.4064)
		(drill 0.2032)
		(layers "F.Cu" "B.Cu")
		(net "GND")
	)
	(via
		(at 219.172028 -119.072914)
		(size 0.508)
		(drill 0.254)
		(layers "F.Cu" "B.Cu")
		(net "GND")
	)
	(via
		(at 130.74777 -373.441976)
		(size 0.4572)
		(drill 0.254)
		(layers "F.Cu" "B.Cu")
		(net "GND")
	)
	(via
		(at 140.806678 -199.361806)
		(size 0.508)
		(drill 0.254)
		(layers "F.Cu" "B.Cu")
		(net "GND")
	)
	(via
		(at 53.48732 -133.564884)
		(size 0.508)
		(drill 0.254)
		(layers "F.Cu" "B.Cu")
		(net "GND")
	)
	(via
		(at 78.17485 -303.024794)
		(size 0.4064)
		(drill 0.2032)
		(layers "F.Cu" "B.Cu")
		(net "GND")
	)
	(via
		(at 55.849774 -312.049922)
		(size 0.4064)
		(drill 0.2032)
		(layers "F.Cu" "B.Cu")
		(net "GND")
	)
	(via
		(at 270.80845 -354.074222)
		(size 0.4572)
		(drill 0.254)
		(layers "F.Cu" "B.Cu")
		(net "GND")
	)
	(via
		(at 299.924724 -300.174914)
		(size 0.4064)
		(drill 0.2032)
		(layers "F.Cu" "B.Cu")
		(net "GND")
	)
	(via
		(at 301.67326 -73.20026)
		(size 0.508)
		(drill 0.254)
		(layers "F.Cu" "B.Cu")
		(net "GND")
	)
	(via
		(at 399.93316 -100.64496)
		(size 0.508)
		(drill 0.254)
		(layers "F.Cu" "B.Cu")
		(net "GND")
	)
	(via
		(at 459.077822 -364.83163)
		(size 0.508)
		(drill 0.254)
		(layers "F.Cu" "B.Cu")
		(net "GND")
	)
	(via
		(at 183.75122 -352.245422)
		(size 0.4572)
		(drill 0.254)
		(layers "F.Cu" "B.Cu")
		(net "GND")
	)
	(via
		(at 379.327918 -371.140228)
		(size 0.508)
		(drill 0.254)
		(layers "F.Cu" "B.Cu")
		(net "GND")
	)
	(via
		(at 188.366908 -142.15491)
		(size 0.508)
		(drill 0.254)
		(layers "F.Cu" "B.Cu")
		(net "GND")
	)
	(via
		(at 385.927854 -385.141978)
		(size 0.508)
		(drill 0.254)
		(layers "F.Cu" "B.Cu")
		(net "GND")
	)
	(via
		(at 164.060378 -21.37156)
		(size 0.508)
		(drill 0.254)
		(layers "F.Cu" "B.Cu")
		(net "GND")
	)
	(via
		(at 111.311182 -289.41649)
		(size 0.508)
		(drill 0.254)
		(layers "F.Cu" "B.Cu")
		(net "GND")
	)
	(via
		(at 399.93316 -107.844844)
		(size 0.508)
		(drill 0.254)
		(layers "F.Cu" "B.Cu")
		(net "GND")
	)
	(via
		(at 315.740288 -121.563384)
		(size 0.508)
		(drill 0.254)
		(layers "F.Cu" "B.Cu")
		(net "GND")
	)
	(via
		(at 70.130162 -357.75773)
		(size 0.4064)
		(drill 0.2032)
		(layers "F.Cu" "B.Cu")
		(net "GND")
	)
	(via
		(at 117.547644 -378.83846)
		(size 0.508)
		(drill 0.254)
		(layers "F.Cu" "B.Cu")
		(net "GND")
	)
	(via
		(at 270.601694 -107.57535)
		(size 0.508)
		(drill 0.254)
		(layers "F.Cu" "B.Cu")
		(net "GND")
	)
	(via
		(at 299.924724 -302.074834)
		(size 0.4064)
		(drill 0.2032)
		(layers "F.Cu" "B.Cu")
		(net "GND")
	)
	(via
		(at 264.800842 -29.590238)
		(size 0.508)
		(drill 0.254)
		(layers "F.Cu" "B.Cu")
		(net "GND")
	)
	(via
		(at 341.25027 -287.51149)
		(size 0.508)
		(drill 0.254)
		(layers "F.Cu" "B.Cu")
		(net "GND")
	)
	(via
		(at 296.124884 -305.874928)
		(size 0.4064)
		(drill 0.2032)
		(layers "F.Cu" "B.Cu")
		(net "GND")
	)
	(via
		(at 422.199816 -318.699896)
		(size 0.4064)
		(drill 0.2032)
		(layers "F.Cu" "B.Cu")
		(net "GND")
	)
	(via
		(at 163.747958 -402.241766)
		(size 0.508)
		(drill 0.254)
		(layers "F.Cu" "B.Cu")
		(net "GND")
	)
	(via
		(at 42.074846 -297.32478)
		(size 0.4064)
		(drill 0.2032)
		(layers "F.Cu" "B.Cu")
		(net "GND")
	)
	(via
		(at 393.7 -310.149748)
		(size 0.4064)
		(drill 0.2032)
		(layers "F.Cu" "B.Cu")
		(net "GND")
	)
	(via
		(at 412.20644 -352.245422)
		(size 0.4572)
		(drill 0.254)
		(layers "F.Cu" "B.Cu")
		(net "GND")
	)
	(via
		(at 103.293418 -360.621834)
		(size 0.508)
		(drill 0.254)
		(layers "F.Cu" "B.Cu")
		(net "GND")
	)
	(via
		(at 346.516198 -264.95756)
		(size 0.508)
		(drill 0.254)
		(layers "F.Cu" "B.Cu")
		(net "GND")
	)
	(via
		(at 53.949854 -312.049922)
		(size 0.4064)
		(drill 0.2032)
		(layers "F.Cu" "B.Cu")
		(net "GND")
	)
	(via
		(at 301.88027 -156.554932)
		(size 0.508)
		(drill 0.254)
		(layers "F.Cu" "B.Cu")
		(net "GND")
	)
	(via
		(at 84.799932 -38.315138)
		(size 0.508)
		(drill 0.254)
		(layers "F.Cu" "B.Cu")
		(net "GND")
	)
	(via
		(at 142.293594 -289.532314)
		(size 0.508)
		(drill 0.254)
		(layers "F.Cu" "B.Cu")
		(net "GND")
	)
	(via
		(at 306.448206 -125.435106)
		(size 0.508)
		(drill 0.254)
		(layers "F.Cu" "B.Cu")
		(net "GND")
	)
	(via
		(at 403.338792 -355.366066)
		(size 0.4572)
		(drill 0.254)
		(layers "F.Cu" "B.Cu")
		(net "GND")
	)
	(via
		(at 329.031092 -60.099194)
		(size 0.508)
		(drill 0.254)
		(layers "F.Cu" "B.Cu")
		(net "GND")
	)
	(via
		(at 176.94783 -381.63881)
		(size 0.508)
		(drill 0.254)
		(layers "F.Cu" "B.Cu")
		(net "GND")
	)
	(via
		(at 45.051726 -131.76504)
		(size 0.508)
		(drill 0.254)
		(layers "F.Cu" "B.Cu")
		(net "GND")
	)
	(via
		(at 200.908158 -152.683464)
		(size 0.508)
		(drill 0.254)
		(layers "F.Cu" "B.Cu")
		(net "GND")
	)
	(via
		(at 415.96691 -125.435106)
		(size 0.508)
		(drill 0.254)
		(layers "F.Cu" "B.Cu")
		(net "GND")
	)
	(via
		(at 362.204 -192.278)
		(size 0.508)
		(drill 0.254)
		(layers "F.Cu" "B.Cu")
		(net "GND")
	)
	(via
		(at 122.621548 -342.439498)
		(size 0.4064)
		(drill 0.2032)
		(layers "F.Cu" "B.Cu")
		(net "GND")
	)
	(via
		(at 292.79977 -312.999882)
		(size 0.4064)
		(drill 0.2032)
		(layers "F.Cu" "B.Cu")
		(net "GND")
	)
	(via
		(at 330.138278 -114.310414)
		(size 0.508)
		(drill 0.254)
		(layers "F.Cu" "B.Cu")
		(net "GND")
	)
	(via
		(at 126.345696 -90.057986)
		(size 0.508)
		(drill 0.254)
		(layers "F.Cu" "B.Cu")
		(net "GND")
	)
	(via
		(at 79.12481 -294.4749)
		(size 0.4064)
		(drill 0.2032)
		(layers "F.Cu" "B.Cu")
		(net "GND")
	)
	(via
		(at 299.924724 -291.624766)
		(size 0.4064)
		(drill 0.2032)
		(layers "F.Cu" "B.Cu")
		(net "GND")
	)
	(via
		(at 399.874994 -284.974792)
		(size 0.4064)
		(drill 0.2032)
		(layers "F.Cu" "B.Cu")
		(net "GND")
	)
	(via
		(at 401.15236 -120.555004)
		(size 0.508)
		(drill 0.254)
		(layers "F.Cu" "B.Cu")
		(net "GND")
	)
	(via
		(at 343.023444 -354.732082)
		(size 0.4064)
		(drill 0.2032)
		(layers "F.Cu" "B.Cu")
		(net "GND")
	)
	(via
		(at 386.098288 -20.417536)
		(size 0.508)
		(drill 0.254)
		(layers "F.Cu" "B.Cu")
		(net "GND")
	)
	(via
		(at 391.324846 -281.174952)
		(size 0.4064)
		(drill 0.2032)
		(layers "F.Cu" "B.Cu")
		(net "GND")
	)
	(via
		(at 161.15157 -129.964942)
		(size 0.508)
		(drill 0.254)
		(layers "F.Cu" "B.Cu")
		(net "GND")
	)
	(via
		(at 339.728048 -406.141936)
		(size 0.508)
		(drill 0.254)
		(layers "F.Cu" "B.Cu")
		(net "GND")
	)
	(via
		(at 78.64983 -288.299906)
		(size 0.4064)
		(drill 0.2032)
		(layers "F.Cu" "B.Cu")
		(net "GND")
	)
	(via
		(at 402.249894 -314.899802)
		(size 0.4064)
		(drill 0.2032)
		(layers "F.Cu" "B.Cu")
		(net "GND")
	)
	(via
		(at 417.924996 -284.974792)
		(size 0.4064)
		(drill 0.2032)
		(layers "F.Cu" "B.Cu")
		(net "GND")
	)
	(via
		(at 313.09818 -123.356878)
		(size 0.508)
		(drill 0.254)
		(layers "F.Cu" "B.Cu")
		(net "GND")
	)
	(via
		(at 79.82839 -344.831162)
		(size 0.4572)
		(drill 0.254)
		(layers "F.Cu" "B.Cu")
		(net "GND")
	)
	(via
		(at 49.429162 -107.407456)
		(size 0.508)
		(drill 0.254)
		(layers "F.Cu" "B.Cu")
		(net "GND")
	)
	(via
		(at 265.062462 -262.987536)
		(size 0.508)
		(drill 0.254)
		(layers "F.Cu" "B.Cu")
		(net "GND")
	)
	(via
		(at 381.576072 -357.123746)
		(size 0.4572)
		(drill 0.254)
		(layers "F.Cu" "B.Cu")
		(net "GND")
	)
	(via
		(at 391.861294 -60.099194)
		(size 0.508)
		(drill 0.254)
		(layers "F.Cu" "B.Cu")
		(net "GND")
	)
	(via
		(at 191.425068 -300.174914)
		(size 0.4064)
		(drill 0.2032)
		(layers "F.Cu" "B.Cu")
		(net "GND")
	)
	(via
		(at 431.700178 -287.3502)
		(size 0.4064)
		(drill 0.2032)
		(layers "F.Cu" "B.Cu")
		(net "GND")
	)
	(via
		(at 269.750286 -253.45644)
		(size 0.508)
		(drill 0.254)
		(layers "F.Cu" "B.Cu")
		(net "GND")
	)
	(via
		(at 79.59979 -281.649932)
		(size 0.4064)
		(drill 0.2032)
		(layers "F.Cu" "B.Cu")
		(net "GND")
	)
	(via
		(at 24.700738 -261.764272)
		(size 0.508)
		(drill 0.254)
		(layers "F.Cu" "B.Cu")
		(net "GND")
	)
	(via
		(at 332.217776 -358.391714)
		(size 0.4572)
		(drill 0.254)
		(layers "F.Cu" "B.Cu")
		(net "GND")
	)
	(via
		(at 132.958078 -122.462036)
		(size 0.508)
		(drill 0.254)
		(layers "F.Cu" "B.Cu")
		(net "GND")
	)
	(via
		(at 277.02637 -350.977454)
		(size 0.4572)
		(drill 0.254)
		(layers "F.Cu" "B.Cu")
		(net "GND")
	)
	(via
		(at 278.549862 -311.099962)
		(size 0.4064)
		(drill 0.2032)
		(layers "F.Cu" "B.Cu")
		(net "GND")
	)
	(via
		(at 79.82839 -350.977454)
		(size 0.4572)
		(drill 0.254)
		(layers "F.Cu" "B.Cu")
		(net "GND")
	)
	(via
		(at 72.267064 -118.234968)
		(size 0.508)
		(drill 0.254)
		(layers "F.Cu" "B.Cu")
		(net "GND")
	)
	(via
		(at 326.757792 -58.791094)
		(size 0.508)
		(drill 0.254)
		(layers "F.Cu" "B.Cu")
		(net "GND")
	)
	(via
		(at 414.599882 -317.749936)
		(size 0.4064)
		(drill 0.2032)
		(layers "F.Cu" "B.Cu")
		(net "GND")
	)
	(via
		(at 61.074808 -287.824926)
		(size 0.4064)
		(drill 0.2032)
		(layers "F.Cu" "B.Cu")
		(net "GND")
	)
	(via
		(at 324.99427 -124.47778)
		(size 0.508)
		(drill 0.254)
		(layers "F.Cu" "B.Cu")
		(net "GND")
	)
	(via
		(at 388.474966 -293.52494)
		(size 0.4064)
		(drill 0.2032)
		(layers "F.Cu" "B.Cu")
		(net "GND")
	)
	(via
		(at 421.724836 -305.874928)
		(size 0.4064)
		(drill 0.2032)
		(layers "F.Cu" "B.Cu")
		(net "GND")
	)
	(via
		(at 231.867456 -217.104468)
		(size 0.4572)
		(drill 0.254)
		(layers "F.Cu" "B.Cu")
		(net "GND")
	)
	(via
		(at 12.179046 -208.970372)
		(size 0.508)
		(drill 0.254)
		(layers "F.Cu" "B.Cu")
		(net "GND")
	)
	(via
		(at 304.674778 -303.024794)
		(size 0.4064)
		(drill 0.2032)
		(layers "F.Cu" "B.Cu")
		(net "GND")
	)
	(via
		(at 374.927876 -397.140176)
		(size 0.508)
		(drill 0.254)
		(layers "F.Cu" "B.Cu")
		(net "GND")
	)
	(via
		(at 396.0749 -284.024832)
		(size 0.4064)
		(drill 0.2032)
		(layers "F.Cu" "B.Cu")
		(net "GND")
	)
	(via
		(at 392.749786 -275.949918)
		(size 0.4064)
		(drill 0.2032)
		(layers "F.Cu" "B.Cu")
		(net "GND")
	)
	(via
		(at 238.585756 -179.793138)
		(size 0.508)
		(drill 0.254)
		(layers "F.Cu" "B.Cu")
		(net "GND")
	)
	(via
		(at 381.576072 -343.073482)
		(size 0.4572)
		(drill 0.254)
		(layers "F.Cu" "B.Cu")
		(net "GND")
	)
	(via
		(at 373.888 -417.82492)
		(size 0.508)
		(drill 0.254)
		(layers "F.Cu" "B.Cu")
		(net "GND")
	)
	(via
		(at 418.927788 -371.140228)
		(size 0.508)
		(drill 0.254)
		(layers "F.Cu" "B.Cu")
		(net "GND")
	)
	(via
		(at 40.526208 -342.439498)
		(size 0.4064)
		(drill 0.2032)
		(layers "F.Cu" "B.Cu")
		(net "GND")
	)
	(via
		(at 438.648602 -287.609026)
		(size 0.508)
		(drill 0.254)
		(layers "F.Cu" "B.Cu")
		(net "GND")
	)
	(via
		(at 432.900836 -33.19018)
		(size 0.508)
		(drill 0.254)
		(layers "F.Cu" "B.Cu")
		(net "GND")
	)
	(via
		(at 169.574972 -287.824926)
		(size 0.4064)
		(drill 0.2032)
		(layers "F.Cu" "B.Cu")
		(net "GND")
	)
	(via
		(at 239.690402 -90.341196)
		(size 0.508)
		(drill 0.254)
		(layers "F.Cu" "B.Cu")
		(net "GND")
	)
	(via
		(at 386.535168 -347.951806)
		(size 0.4572)
		(drill 0.254)
		(layers "F.Cu" "B.Cu")
		(net "GND")
	)
	(via
		(at 397.02486 -304.924714)
		(size 0.4064)
		(drill 0.2032)
		(layers "F.Cu" "B.Cu")
		(net "GND")
	)
	(via
		(at 280.924762 -304.924714)
		(size 0.4064)
		(drill 0.2032)
		(layers "F.Cu" "B.Cu")
		(net "GND")
	)
	(via
		(at 53.769514 -64.102234)
		(size 0.508)
		(drill 0.254)
		(layers "F.Cu" "B.Cu")
		(net "GND")
	)
	(via
		(at 392.749786 -314.899802)
		(size 0.4064)
		(drill 0.2032)
		(layers "F.Cu" "B.Cu")
		(net "GND")
	)
	(via
		(at 253.513336 -34.718498)
		(size 0.508)
		(drill 0.254)
		(layers "F.Cu" "B.Cu")
		(net "GND")
	)
	(via
		(at 225.322384 -111.065056)
		(size 0.508)
		(drill 0.254)
		(layers "F.Cu" "B.Cu")
		(net "GND")
	)
	(via
		(at 110.034324 -268.096492)
		(size 0.508)
		(drill 0.254)
		(layers "F.Cu" "B.Cu")
		(net "GND")
	)
	(via
		(at 61.052202 -13.613638)
		(size 0.508)
		(drill 0.254)
		(layers "F.Cu" "B.Cu")
		(net "GND")
	)
	(via
		(at 424.57497 -301.124874)
		(size 0.4064)
		(drill 0.2032)
		(layers "F.Cu" "B.Cu")
		(net "GND")
	)
	(via
		(at 112.968786 -286.842454)
		(size 0.508)
		(drill 0.254)
		(layers "F.Cu" "B.Cu")
		(net "GND")
	)
	(via
		(at 436.527702 -402.241766)
		(size 0.508)
		(drill 0.254)
		(layers "F.Cu" "B.Cu")
		(net "GND")
	)
	(via
		(at 161.15157 -133.565138)
		(size 0.508)
		(drill 0.254)
		(layers "F.Cu" "B.Cu")
		(net "GND")
	)
	(via
		(at 425.527724 -397.038576)
		(size 0.508)
		(drill 0.254)
		(layers "F.Cu" "B.Cu")
		(net "GND")
	)
	(via
		(at 426.47489 -291.624766)
		(size 0.4064)
		(drill 0.2032)
		(layers "F.Cu" "B.Cu")
		(net "GND")
	)
	(via
		(at 445.55791 -73.85177)
		(size 0.508)
		(drill 0.254)
		(layers "F.Cu" "B.Cu")
		(net "GND")
	)
	(via
		(at 365.176562 -223.537018)
		(size 0.508)
		(drill 0.254)
		(layers "F.Cu" "B.Cu")
		(net "GND")
	)
	(via
		(at 293.829994 -358.391714)
		(size 0.4572)
		(drill 0.254)
		(layers "F.Cu" "B.Cu")
		(net "GND")
	)
	(via
		(at 131.70662 -178.710336)
		(size 0.508)
		(drill 0.254)
		(layers "F.Cu" "B.Cu")
		(net "GND")
	)
	(via
		(at 44.638722 -23.880318)
		(size 0.508)
		(drill 0.254)
		(layers "F.Cu" "B.Cu")
		(net "GND")
	)
	(via
		(at 450.138546 -287.228788)
		(size 0.508)
		(drill 0.254)
		(layers "F.Cu" "B.Cu")
		(net "GND")
	)
	(via
		(at 319.842642 -116.416836)
		(size 0.508)
		(drill 0.254)
		(layers "F.Cu" "B.Cu")
		(net "GND")
	)
	(via
		(at 141.45768 -29.784294)
		(size 0.508)
		(drill 0.254)
		(layers "F.Cu" "B.Cu")
		(net "GND")
	)
	(via
		(at 400.824954 -287.824926)
		(size 0.4064)
		(drill 0.2032)
		(layers "F.Cu" "B.Cu")
		(net "GND")
	)
	(via
		(at 8.76808 -54.238906)
		(size 0.508)
		(drill 0.254)
		(layers "F.Cu" "B.Cu")
		(net "GND")
	)
	(via
		(at 399.400014 -312.999882)
		(size 0.4064)
		(drill 0.2032)
		(layers "F.Cu" "B.Cu")
		(net "GND")
	)
	(via
		(at 51.48326 -349.219774)
		(size 0.4572)
		(drill 0.254)
		(layers "F.Cu" "B.Cu")
		(net "GND")
	)
	(via
		(at 92.13469 -307.813456)
		(size 0.508)
		(drill 0.254)
		(layers "F.Cu" "B.Cu")
		(net "GND")
	)
	(via
		(at 58.224928 -298.27474)
		(size 0.4064)
		(drill 0.2032)
		(layers "F.Cu" "B.Cu")
		(net "GND")
	)
	(via
		(at 158.174944 -274.524978)
		(size 0.4064)
		(drill 0.2032)
		(layers "F.Cu" "B.Cu")
		(net "GND")
	)
	(via
		(at 67.249802 -319.65011)
		(size 0.4064)
		(drill 0.2032)
		(layers "F.Cu" "B.Cu")
		(net "GND")
	)
	(via
		(at 156.750004 -305.399948)
		(size 0.4064)
		(drill 0.2032)
		(layers "F.Cu" "B.Cu")
		(net "GND")
	)
	(via
		(at 82.347816 -402.140166)
		(size 0.508)
		(drill 0.254)
		(layers "F.Cu" "B.Cu")
		(net "GND")
	)
	(via
		(at 26.61158 -343.073482)
		(size 0.4572)
		(drill 0.254)
		(layers "F.Cu" "B.Cu")
		(net "GND")
	)
	(via
		(at 177.841656 -161.757868)
		(size 0.508)
		(drill 0.254)
		(layers "F.Cu" "B.Cu")
		(net "GND")
	)
	(via
		(at 164.645594 -154.0256)
		(size 0.508)
		(drill 0.254)
		(layers "F.Cu" "B.Cu")
		(net "GND")
	)
	(via
		(at 419.82009 -57.076848)
		(size 0.508)
		(drill 0.254)
		(layers "F.Cu" "B.Cu")
		(net "GND")
	)
	(via
		(at 285.687262 -98.844862)
		(size 0.508)
		(drill 0.254)
		(layers "F.Cu" "B.Cu")
		(net "GND")
	)
	(via
		(at 38.401752 -106.316526)
		(size 0.508)
		(drill 0.254)
		(layers "F.Cu" "B.Cu")
		(net "GND")
	)
	(via
		(at 409.374848 -303.974754)
		(size 0.4064)
		(drill 0.2032)
		(layers "F.Cu" "B.Cu")
		(net "GND")
	)
	(via
		(at 385.433824 -100.375466)
		(size 0.508)
		(drill 0.254)
		(layers "F.Cu" "B.Cu")
		(net "GND")
	)
	(via
		(at 57.140094 -27.729688)
		(size 0.508)
		(drill 0.254)
		(layers "F.Cu" "B.Cu")
		(net "GND")
	)
	(via
		(at 241.29238 -335.724246)
		(size 0.508)
		(drill 0.254)
		(layers "F.Cu" "B.Cu")
		(net "GND")
	)
	(via
		(at 427.899576 -276.899878)
		(size 0.4064)
		(drill 0.2032)
		(layers "F.Cu" "B.Cu")
		(net "GND")
	)
	(via
		(at 376.858022 -295.933114)
		(size 0.508)
		(drill 0.254)
		(layers "F.Cu" "B.Cu")
		(net "GND")
	)
	(via
		(at 56.653176 -49.574704)
		(size 0.508)
		(drill 0.254)
		(layers "F.Cu" "B.Cu")
		(net "GND")
	)
	(via
		(at 192.850008 -280.699718)
		(size 0.4064)
		(drill 0.2032)
		(layers "F.Cu" "B.Cu")
		(net "GND")
	)
	(via
		(at 30.091888 -342.439498)
		(size 0.4064)
		(drill 0.2032)
		(layers "F.Cu" "B.Cu")
		(net "GND")
	)
	(via
		(at 179.898294 -21.738336)
		(size 0.508)
		(drill 0.254)
		(layers "F.Cu" "B.Cu")
		(net "GND")
	)
	(via
		(at 53.9496 -272.14957)
		(size 0.4064)
		(drill 0.2032)
		(layers "F.Cu" "B.Cu")
		(net "GND")
	)
	(via
		(at 178.792124 -355.366066)
		(size 0.4572)
		(drill 0.254)
		(layers "F.Cu" "B.Cu")
		(net "GND")
	)
	(via
		(at 310.751474 -102.088696)
		(size 0.508)
		(drill 0.254)
		(layers "F.Cu" "B.Cu")
		(net "GND")
	)
	(via
		(at 259.448554 -82.011266)
		(size 0.508)
		(drill 0.254)
		(layers "F.Cu" "B.Cu")
		(net "GND")
	)
	(via
		(at 463.037682 -148.857462)
		(size 0.508)
		(drill 0.254)
		(layers "F.Cu" "B.Cu")
		(net "GND")
	)
	(via
		(at 427.727872 -377.738386)
		(size 0.508)
		(drill 0.254)
		(layers "F.Cu" "B.Cu")
		(net "GND")
	)
	(via
		(at 40.897556 -354.098098)
		(size 0.4572)
		(drill 0.254)
		(layers "F.Cu" "B.Cu")
		(net "GND")
	)
	(via
		(at 420.567104 -131.245102)
		(size 0.508)
		(drill 0.254)
		(layers "F.Cu" "B.Cu")
		(net "GND")
	)
	(via
		(at 221.59976 -317.698882)
		(size 0.508)
		(drill 0.254)
		(layers "F.Cu" "B.Cu")
		(net "GND")
	)
	(via
		(at 429.800004 -273.099784)
		(size 0.4064)
		(drill 0.2032)
		(layers "F.Cu" "B.Cu")
		(net "GND")
	)
	(via
		(at 125.74905 -29.589984)
		(size 0.508)
		(drill 0.254)
		(layers "F.Cu" "B.Cu")
		(net "GND")
	)
	(via
		(at 73.899776 -277.849838)
		(size 0.4064)
		(drill 0.2032)
		(layers "F.Cu" "B.Cu")
		(net "GND")
	)
	(via
		(at 270.474948 -281.174952)
		(size 0.4064)
		(drill 0.2032)
		(layers "F.Cu" "B.Cu")
		(net "GND")
	)
	(via
		(at 186.675014 -284.974792)
		(size 0.4064)
		(drill 0.2032)
		(layers "F.Cu" "B.Cu")
		(net "GND")
	)
	(via
		(at 218.075002 -73.23963)
		(size 0.508)
		(drill 0.254)
		(layers "F.Cu" "B.Cu")
		(net "GND")
	)
	(via
		(at 409.374848 -296.37482)
		(size 0.4064)
		(drill 0.2032)
		(layers "F.Cu" "B.Cu")
		(net "GND")
	)
	(via
		(at 44.449746 -301.599854)
		(size 0.4064)
		(drill 0.2032)
		(layers "F.Cu" "B.Cu")
		(net "GND")
	)
	(via
		(at 384.685032 -357.123746)
		(size 0.4572)
		(drill 0.254)
		(layers "F.Cu" "B.Cu")
		(net "GND")
	)
	(via
		(at 174.747936 -377.341892)
		(size 0.508)
		(drill 0.254)
		(layers "F.Cu" "B.Cu")
		(net "GND")
	)
	(via
		(at 107.817666 -93.436186)
		(size 0.508)
		(drill 0.254)
		(layers "F.Cu" "B.Cu")
		(net "GND")
	)
	(via
		(at 83.540346 -132.77342)
		(size 0.508)
		(drill 0.254)
		(layers "F.Cu" "B.Cu")
		(net "GND")
	)
	(via
		(at 188.341762 -112.56772)
		(size 0.508)
		(drill 0.254)
		(layers "F.Cu" "B.Cu")
		(net "GND")
	)
	(via
		(at 304.527712 -377.73864)
		(size 0.508)
		(drill 0.254)
		(layers "F.Cu" "B.Cu")
		(net "GND")
	)
	(via
		(at 310.219598 -84.332318)
		(size 0.508)
		(drill 0.254)
		(layers "F.Cu" "B.Cu")
		(net "GND")
	)
	(via
		(at 146.134328 -387.02996)
		(size 0.508)
		(drill 0.254)
		(layers "F.Cu" "B.Cu")
		(net "GND")
	)
	(via
		(at 298.499784 -276.899878)
		(size 0.4064)
		(drill 0.2032)
		(layers "F.Cu" "B.Cu")
		(net "GND")
	)
	(via
		(at 344.127836 -378.94006)
		(size 0.508)
		(drill 0.254)
		(layers "F.Cu" "B.Cu")
		(net "GND")
	)
	(via
		(at 229.150926 -106.172508)
		(size 0.508)
		(drill 0.254)
		(layers "F.Cu" "B.Cu")
		(net "GND")
	)
	(via
		(at 231.412034 -285.445962)
		(size 0.508)
		(drill 0.254)
		(layers "F.Cu" "B.Cu")
		(net "GND")
	)
	(via
		(at 405.565356 -97.282762)
		(size 0.508)
		(drill 0.254)
		(layers "F.Cu" "B.Cu")
		(net "GND")
	)
	(via
		(at 178.792124 -354.098098)
		(size 0.4572)
		(drill 0.254)
		(layers "F.Cu" "B.Cu")
		(net "GND")
	)
	(via
		(at 92.2147 -26.171398)
		(size 0.508)
		(drill 0.254)
		(layers "F.Cu" "B.Cu")
		(net "GND")
	)
	(via
		(at 106.087164 -161.096452)
		(size 0.508)
		(drill 0.254)
		(layers "F.Cu" "B.Cu")
		(net "GND")
	)
	(via
		(at 194.749674 -281.649932)
		(size 0.4064)
		(drill 0.2032)
		(layers "F.Cu" "B.Cu")
		(net "GND")
	)
	(via
		(at 74.248264 -151.155146)
		(size 0.508)
		(drill 0.254)
		(layers "F.Cu" "B.Cu")
		(net "GND")
	)
	(via
		(at 385.149852 -305.399948)
		(size 0.4064)
		(drill 0.2032)
		(layers "F.Cu" "B.Cu")
		(net "GND")
	)
	(via
		(at 383.426208 -344.831162)
		(size 0.4572)
		(drill 0.254)
		(layers "F.Cu" "B.Cu")
		(net "GND")
	)
	(via
		(at 402.936456 -51.661822)
		(size 0.508)
		(drill 0.254)
		(layers "F.Cu" "B.Cu")
		(net "GND")
	)
	(via
		(at 416.499802 -276.899878)
		(size 0.4064)
		(drill 0.2032)
		(layers "F.Cu" "B.Cu")
		(net "GND")
	)
	(via
		(at 375.358152 -355.366066)
		(size 0.4572)
		(drill 0.254)
		(layers "F.Cu" "B.Cu")
		(net "GND")
	)
	(via
		(at 432.119024 -341.805514)
		(size 0.4572)
		(drill 0.254)
		(layers "F.Cu" "B.Cu")
		(net "GND")
	)
	(via
		(at 125.709172 -288.78149)
		(size 0.508)
		(drill 0.254)
		(layers "F.Cu" "B.Cu")
		(net "GND")
	)
	(via
		(at 65.542414 -354.074222)
		(size 0.4572)
		(drill 0.254)
		(layers "F.Cu" "B.Cu")
		(net "GND")
	)
	(via
		(at 261.705852 -352.703638)
		(size 0.508)
		(drill 0.254)
		(layers "F.Cu" "B.Cu")
		(net "GND")
	)
	(via
		(at 4.562856 -170.001692)
		(size 0.508)
		(drill 0.254)
		(layers "F.Cu" "B.Cu")
		(net "GND")
	)
	(via
		(at 248.717562 -212.638386)
		(size 0.508)
		(drill 0.254)
		(layers "F.Cu" "B.Cu")
		(net "GND")
	)
	(via
		(at 266.275312 -205.274164)
		(size 0.508)
		(drill 0.254)
		(layers "F.Cu" "B.Cu")
		(net "GND")
	)
	(via
		(at 292.79977 -281.649932)
		(size 0.4064)
		(drill 0.2032)
		(layers "F.Cu" "B.Cu")
		(net "GND")
	)
	(via
		(at 394.17498 -298.27474)
		(size 0.4064)
		(drill 0.2032)
		(layers "F.Cu" "B.Cu")
		(net "GND")
	)
	(via
		(at 165.774878 -284.974792)
		(size 0.4064)
		(drill 0.2032)
		(layers "F.Cu" "B.Cu")
		(net "GND")
	)
	(via
		(at 227.852224 -277.213314)
		(size 0.508)
		(drill 0.254)
		(layers "F.Cu" "B.Cu")
		(net "GND")
	)
	(via
		(at 406.999948 -281.649932)
		(size 0.4064)
		(drill 0.2032)
		(layers "F.Cu" "B.Cu")
		(net "GND")
	)
	(via
		(at 184.77484 -286.874966)
		(size 0.4064)
		(drill 0.2032)
		(layers "F.Cu" "B.Cu")
		(net "GND")
	)
	(via
		(at 390.849866 -315.849762)
		(size 0.4064)
		(drill 0.2032)
		(layers "F.Cu" "B.Cu")
		(net "GND")
	)
	(via
		(at 68.557902 -57.521094)
		(size 0.508)
		(drill 0.254)
		(layers "F.Cu" "B.Cu")
		(net "GND")
	)
	(via
		(at 286.624776 -284.024832)
		(size 0.4064)
		(drill 0.2032)
		(layers "F.Cu" "B.Cu")
		(net "GND")
	)
	(via
		(at 269.333726 -132.04317)
		(size 0.508)
		(drill 0.254)
		(layers "F.Cu" "B.Cu")
		(net "GND")
	)
	(via
		(at 329.71486 -238.976408)
		(size 0.508)
		(drill 0.254)
		(layers "F.Cu" "B.Cu")
		(net "GND")
	)
	(via
		(at 273.799808 -308.249828)
		(size 0.4064)
		(drill 0.2032)
		(layers "F.Cu" "B.Cu")
		(net "GND")
	)
	(via
		(at 202.555094 -27.79014)
		(size 0.508)
		(drill 0.254)
		(layers "F.Cu" "B.Cu")
		(net "GND")
	)
	(via
		(at 23.34006 -73.87463)
		(size 0.508)
		(drill 0.254)
		(layers "F.Cu" "B.Cu")
		(net "GND")
	)
	(via
		(at 280.13533 -355.366066)
		(size 0.4572)
		(drill 0.254)
		(layers "F.Cu" "B.Cu")
		(net "GND")
	)
	(via
		(at 422.119552 -38.701218)
		(size 0.508)
		(drill 0.254)
		(layers "F.Cu" "B.Cu")
		(net "GND")
	)
	(via
		(at 300.047914 -344.831162)
		(size 0.4572)
		(drill 0.254)
		(layers "F.Cu" "B.Cu")
		(net "GND")
	)
	(via
		(at 285.674816 -284.024832)
		(size 0.4064)
		(drill 0.2032)
		(layers "F.Cu" "B.Cu")
		(net "GND")
	)
	(via
		(at 161.54781 -398.24025)
		(size 0.508)
		(drill 0.254)
		(layers "F.Cu" "B.Cu")
		(net "GND")
	)
	(via
		(at 333.127858 -399.441924)
		(size 0.508)
		(drill 0.254)
		(layers "F.Cu" "B.Cu")
		(net "GND")
	)
	(via
		(at 336.872326 -293.424102)
		(size 0.508)
		(drill 0.254)
		(layers "F.Cu" "B.Cu")
		(net "GND")
	)
	(via
		(at 240.4618 -215.6968)
		(size 0.508)
		(drill 0.254)
		(layers "F.Cu" "B.Cu")
		(net "GND")
	)
	(via
		(at 399.93316 -140.765022)
		(size 0.508)
		(drill 0.254)
		(layers "F.Cu" "B.Cu")
		(net "GND")
	)
	(via
		(at 269.412466 -91.478354)
		(size 0.508)
		(drill 0.254)
		(layers "F.Cu" "B.Cu")
		(net "GND")
	)
	(via
		(at 385.927854 -407.24201)
		(size 0.508)
		(drill 0.254)
		(layers "F.Cu" "B.Cu")
		(net "GND")
	)
	(via
		(at 344.653616 -343.073482)
		(size 0.4572)
		(drill 0.254)
		(layers "F.Cu" "B.Cu")
		(net "GND")
	)
	(via
		(at 186.675014 -284.024832)
		(size 0.4064)
		(drill 0.2032)
		(layers "F.Cu" "B.Cu")
		(net "GND")
	)
	(via
		(at 125.74905 -34.990024)
		(size 0.508)
		(drill 0.254)
		(layers "F.Cu" "B.Cu")
		(net "GND")
	)
	(via
		(at 416.945572 -345.465146)
		(size 0.4064)
		(drill 0.2032)
		(layers "F.Cu" "B.Cu")
		(net "GND")
	)
	(via
		(at 409.948888 -34.990024)
		(size 0.508)
		(drill 0.254)
		(layers "F.Cu" "B.Cu")
		(net "GND")
	)
	(via
		(at 283.24429 -350.977454)
		(size 0.4572)
		(drill 0.254)
		(layers "F.Cu" "B.Cu")
		(net "GND")
	)
	(via
		(at 272.374868 -293.52494)
		(size 0.4064)
		(drill 0.2032)
		(layers "F.Cu" "B.Cu")
		(net "GND")
	)
	(via
		(at 296.599864 -278.799798)
		(size 0.4064)
		(drill 0.2032)
		(layers "F.Cu" "B.Cu")
		(net "GND")
	)
	(via
		(at 322.254626 -34.990024)
		(size 0.508)
		(drill 0.254)
		(layers "F.Cu" "B.Cu")
		(net "GND")
	)
	(via
		(at 174.700946 -29.590238)
		(size 0.508)
		(drill 0.254)
		(layers "F.Cu" "B.Cu")
		(net "GND")
	)
	(via
		(at 43.485562 -63.218314)
		(size 0.508)
		(drill 0.254)
		(layers "F.Cu" "B.Cu")
		(net "GND")
	)
	(via
		(at 75.974956 -73.87463)
		(size 0.508)
		(drill 0.254)
		(layers "F.Cu" "B.Cu")
		(net "GND")
	)
	(via
		(at 44.449746 -312.049922)
		(size 0.4064)
		(drill 0.2032)
		(layers "F.Cu" "B.Cu")
		(net "GND")
	)
	(via
		(at 425.04995 -306.349908)
		(size 0.4064)
		(drill 0.2032)
		(layers "F.Cu" "B.Cu")
		(net "GND")
	)
	(via
		(at 399.400014 -313.949842)
		(size 0.4064)
		(drill 0.2032)
		(layers "F.Cu" "B.Cu")
		(net "GND")
	)
	(via
		(at 189.524894 -298.27474)
		(size 0.4064)
		(drill 0.2032)
		(layers "F.Cu" "B.Cu")
		(net "GND")
	)
	(via
		(at 310.849772 -272.14957)
		(size 0.4064)
		(drill 0.2032)
		(layers "F.Cu" "B.Cu")
		(net "GND")
	)
	(via
		(at 340.285832 -358.391714)
		(size 0.4572)
		(drill 0.254)
		(layers "F.Cu" "B.Cu")
		(net "GND")
	)
	(via
		(at 407.949908 -279.749758)
		(size 0.4064)
		(drill 0.2032)
		(layers "F.Cu" "B.Cu")
		(net "GND")
	)
	(via
		(at 208.002124 -57.461404)
		(size 0.508)
		(drill 0.254)
		(layers "F.Cu" "B.Cu")
		(net "GND")
	)
	(via
		(at 243.043202 -114.672364)
		(size 0.508)
		(drill 0.254)
		(layers "F.Cu" "B.Cu")
		(net "GND")
	)
	(via
		(at 430.8602 -343.073482)
		(size 0.4572)
		(drill 0.254)
		(layers "F.Cu" "B.Cu")
		(net "GND")
	)
	(via
		(at 191.227964 -341.805514)
		(size 0.4572)
		(drill 0.254)
		(layers "F.Cu" "B.Cu")
		(net "GND")
	)
	(via
		(at 406.524968 -291.624766)
		(size 0.4064)
		(drill 0.2032)
		(layers "F.Cu" "B.Cu")
		(net "GND")
	)
	(via
		(at 435.034436 -86.495636)
		(size 0.508)
		(drill 0.254)
		(layers "F.Cu" "B.Cu")
		(net "GND")
	)
	(via
		(at 7.72414 -315.391038)
		(size 0.508)
		(drill 0.254)
		(layers "F.Cu" "B.Cu")
		(net "GND")
	)
	(via
		(at 404.624794 -285.924752)
		(size 0.4064)
		(drill 0.2032)
		(layers "F.Cu" "B.Cu")
		(net "GND")
	)
	(via
		(at 227.867972 -219.504006)
		(size 0.4572)
		(drill 0.254)
		(layers "F.Cu" "B.Cu")
		(net "GND")
	)
	(via
		(at 285.687262 -122.354848)
		(size 0.508)
		(drill 0.254)
		(layers "F.Cu" "B.Cu")
		(net "GND")
	)
	(via
		(at 134.822184 -167.992298)
		(size 0.508)
		(drill 0.254)
		(layers "F.Cu" "B.Cu")
		(net "GND")
	)
	(via
		(at 151.618442 -253.45644)
		(size 0.508)
		(drill 0.254)
		(layers "F.Cu" "B.Cu")
		(net "GND")
	)
	(via
		(at 417.450016 -280.699718)
		(size 0.4064)
		(drill 0.2032)
		(layers "F.Cu" "B.Cu")
		(net "GND")
	)
	(via
		(at 109.386878 -397.144748)
		(size 0.508)
		(drill 0.254)
		(layers "F.Cu" "B.Cu")
		(net "GND")
	)
	(via
		(at 447.019172 -46.893226)
		(size 0.508)
		(drill 0.254)
		(layers "F.Cu" "B.Cu")
		(net "GND")
	)
	(via
		(at 165.618668 -123.878594)
		(size 0.508)
		(drill 0.254)
		(layers "F.Cu" "B.Cu")
		(net "GND")
	)
	(via
		(at 324.099936 -100.803964)
		(size 0.508)
		(drill 0.254)
		(layers "F.Cu" "B.Cu")
		(net "GND")
	)
	(via
		(at 214.796116 -227.440998)
		(size 0.508)
		(drill 0.254)
		(layers "F.Cu" "B.Cu")
		(net "GND")
	)
	(via
		(at 415.96691 -114.635026)
		(size 0.508)
		(drill 0.254)
		(layers "F.Cu" "B.Cu")
		(net "GND")
	)
	(via
		(at 443.773306 -72.56526)
		(size 0.508)
		(drill 0.254)
		(layers "F.Cu" "B.Cu")
		(net "GND")
	)
	(via
		(at 81.458562 -354.732082)
		(size 0.4064)
		(drill 0.2032)
		(layers "F.Cu" "B.Cu")
		(net "GND")
	)
	(via
		(at 425.99991 -318.699896)
		(size 0.4064)
		(drill 0.2032)
		(layers "F.Cu" "B.Cu")
		(net "GND")
	)
	(via
		(at 450.283072 -207.948784)
		(size 0.508)
		(drill 0.254)
		(layers "F.Cu" "B.Cu")
		(net "GND")
	)
	(via
		(at 320.153284 -345.465146)
		(size 0.4064)
		(drill 0.2032)
		(layers "F.Cu" "B.Cu")
		(net "GND")
	)
	(via
		(at 130.461004 -134.258812)
		(size 0.508)
		(drill 0.254)
		(layers "F.Cu" "B.Cu")
		(net "GND")
	)
	(via
		(at 395.456156 -140.429488)
		(size 0.508)
		(drill 0.254)
		(layers "F.Cu" "B.Cu")
		(net "GND")
	)
	(via
		(at 294.201342 -357.75773)
		(size 0.4064)
		(drill 0.2032)
		(layers "F.Cu" "B.Cu")
		(net "GND")
	)
	(via
		(at 211.437728 -248.407428)
		(size 0.508)
		(drill 0.254)
		(layers "F.Cu" "B.Cu")
		(net "GND")
	)
	(via
		(at 341.25027 -290.68649)
		(size 0.508)
		(drill 0.254)
		(layers "F.Cu" "B.Cu")
		(net "GND")
	)
	(via
		(at 104.991916 -330.250038)
		(size 0.508)
		(drill 0.254)
		(layers "F.Cu" "B.Cu")
		(net "GND")
	)
	(via
		(at 134.68604 -358.391714)
		(size 0.4572)
		(drill 0.254)
		(layers "F.Cu" "B.Cu")
		(net "GND")
	)
	(via
		(at 40.649906 -305.399948)
		(size 0.4064)
		(drill 0.2032)
		(layers "F.Cu" "B.Cu")
		(net "GND")
	)
	(via
		(at 287.099756 -317.749936)
		(size 0.4064)
		(drill 0.2032)
		(layers "F.Cu" "B.Cu")
		(net "GND")
	)
	(via
		(at 285.052262 -133.564884)
		(size 0.508)
		(drill 0.254)
		(layers "F.Cu" "B.Cu")
		(net "GND")
	)
	(via
		(at 159.347916 -381.638556)
		(size 0.508)
		(drill 0.254)
		(layers "F.Cu" "B.Cu")
		(net "GND")
	)
	(via
		(at 296.599864 -276.899878)
		(size 0.4064)
		(drill 0.2032)
		(layers "F.Cu" "B.Cu")
		(net "GND")
	)
	(via
		(at 62.024768 -303.974754)
		(size 0.4064)
		(drill 0.2032)
		(layers "F.Cu" "B.Cu")
		(net "GND")
	)
	(via
		(at 86.747858 -374.938544)
		(size 0.508)
		(drill 0.254)
		(layers "F.Cu" "B.Cu")
		(net "GND")
	)
	(via
		(at 25.352756 -346.09913)
		(size 0.4572)
		(drill 0.254)
		(layers "F.Cu" "B.Cu")
		(net "GND")
	)
	(via
		(at 396.88135 -31.118302)
		(size 0.508)
		(drill 0.254)
		(layers "F.Cu" "B.Cu")
		(net "GND")
	)
	(via
		(at 129.946908 -348.58579)
		(size 0.4064)
		(drill 0.2032)
		(layers "F.Cu" "B.Cu")
		(net "GND")
	)
	(via
		(at 96.120458 -63.218314)
		(size 0.508)
		(drill 0.254)
		(layers "F.Cu" "B.Cu")
		(net "GND")
	)
	(via
		(at 171.474892 -305.874928)
		(size 0.4064)
		(drill 0.2032)
		(layers "F.Cu" "B.Cu")
		(net "GND")
	)
	(via
		(at 249.52325 -133.255766)
		(size 0.508)
		(drill 0.254)
		(layers "F.Cu" "B.Cu")
		(net "GND")
	)
	(via
		(at 383.72796 -398.34185)
		(size 0.508)
		(drill 0.254)
		(layers "F.Cu" "B.Cu")
		(net "GND")
	)
	(via
		(at 455.168 -417.82492)
		(size 0.508)
		(drill 0.254)
		(layers "F.Cu" "B.Cu")
		(net "GND")
	)
	(via
		(at 44.449746 -281.649932)
		(size 0.4064)
		(drill 0.2032)
		(layers "F.Cu" "B.Cu")
		(net "GND")
	)
	(via
		(at 276.174708 -282.124912)
		(size 0.4064)
		(drill 0.2032)
		(layers "F.Cu" "B.Cu")
		(net "GND")
	)
	(via
		(at 103.22941 -222.20936)
		(size 0.508)
		(drill 0.254)
		(layers "F.Cu" "B.Cu")
		(net "GND")
	)
	(via
		(at 280.449782 -310.149748)
		(size 0.4064)
		(drill 0.2032)
		(layers "F.Cu" "B.Cu")
		(net "GND")
	)
	(via
		(at 192.850008 -319.65011)
		(size 0.4064)
		(drill 0.2032)
		(layers "F.Cu" "B.Cu")
		(net "GND")
	)
	(via
		(at 281.53233 -120.084088)
		(size 0.508)
		(drill 0.254)
		(layers "F.Cu" "B.Cu")
		(net "GND")
	)
	(via
		(at 311.324752 -292.574726)
		(size 0.4064)
		(drill 0.2032)
		(layers "F.Cu" "B.Cu")
		(net "GND")
	)
	(via
		(at 439.815732 -351.611438)
		(size 0.4064)
		(drill 0.2032)
		(layers "F.Cu" "B.Cu")
		(net "GND")
	)
	(via
		(at 64.59347 -143.955008)
		(size 0.508)
		(drill 0.254)
		(layers "F.Cu" "B.Cu")
		(net "GND")
	)
	(via
		(at 287.574736 -294.4749)
		(size 0.4064)
		(drill 0.2032)
		(layers "F.Cu" "B.Cu")
		(net "GND")
	)
	(via
		(at 227.067872 -220.303852)
		(size 0.4572)
		(drill 0.254)
		(layers "F.Cu" "B.Cu")
		(net "GND")
	)
	(via
		(at 90.414094 -352.245422)
		(size 0.4572)
		(drill 0.254)
		(layers "F.Cu" "B.Cu")
		(net "GND")
	)
	(via
		(at 282.824936 -293.52494)
		(size 0.4064)
		(drill 0.2032)
		(layers "F.Cu" "B.Cu")
		(net "GND")
	)
	(via
		(at 234.819698 -241.615976)
		(size 0.508)
		(drill 0.254)
		(layers "F.Cu" "B.Cu")
		(net "GND")
	)
	(via
		(at 386.098288 -21.738336)
		(size 0.508)
		(drill 0.254)
		(layers "F.Cu" "B.Cu")
		(net "GND")
	)
	(via
		(at 82.347816 -404.838662)
		(size 0.508)
		(drill 0.254)
		(layers "F.Cu" "B.Cu")
		(net "GND")
	)
	(via
		(at 120.658128 -214.186008)
		(size 0.508)
		(drill 0.254)
		(layers "F.Cu" "B.Cu")
		(net "GND")
	)
	(via
		(at 452.889112 -103.69296)
		(size 0.508)
		(drill 0.254)
		(layers "F.Cu" "B.Cu")
		(net "GND")
	)
	(via
		(at 84.808314 -131.514596)
		(size 0.508)
		(drill 0.254)
		(layers "F.Cu" "B.Cu")
		(net "GND")
	)
	(via
		(at 237.750604 -185.5724)
		(size 0.508)
		(drill 0.254)
		(layers "F.Cu" "B.Cu")
		(net "GND")
	)
	(via
		(at 94.55785 -56.809894)
		(size 0.508)
		(drill 0.254)
		(layers "F.Cu" "B.Cu")
		(net "GND")
	)
	(via
		(at 394.64996 -310.149748)
		(size 0.4064)
		(drill 0.2032)
		(layers "F.Cu" "B.Cu")
		(net "GND")
	)
	(via
		(at 240.020094 -33.19018)
		(size 0.508)
		(drill 0.254)
		(layers "F.Cu" "B.Cu")
		(net "GND")
	)
	(via
		(at 334.067912 -349.219774)
		(size 0.4572)
		(drill 0.254)
		(layers "F.Cu" "B.Cu")
		(net "GND")
	)
	(via
		(at 166.249858 -276.899878)
		(size 0.4064)
		(drill 0.2032)
		(layers "F.Cu" "B.Cu")
		(net "GND")
	)
	(via
		(at 290.721034 -341.805514)
		(size 0.4572)
		(drill 0.254)
		(layers "F.Cu" "B.Cu")
		(net "GND")
	)
	(via
		(at 420.054532 -345.465146)
		(size 0.4064)
		(drill 0.2032)
		(layers "F.Cu" "B.Cu")
		(net "GND")
	)
	(via
		(at 196.174868 -302.074834)
		(size 0.4064)
		(drill 0.2032)
		(layers "F.Cu" "B.Cu")
		(net "GND")
	)
	(via
		(at 172.945552 -342.439498)
		(size 0.4064)
		(drill 0.2032)
		(layers "F.Cu" "B.Cu")
		(net "GND")
	)
	(via
		(at 341.544656 -343.073482)
		(size 0.4572)
		(drill 0.254)
		(layers "F.Cu" "B.Cu")
		(net "GND")
	)
	(via
		(at 298.012612 -121.835164)
		(size 0.508)
		(drill 0.254)
		(layers "F.Cu" "B.Cu")
		(net "GND")
	)
	(via
		(at 325.585836 -95.209106)
		(size 0.508)
		(drill 0.254)
		(layers "F.Cu" "B.Cu")
		(net "GND")
	)
	(via
		(at 0.77089 -339.861144)
		(size 0.508)
		(drill 0.254)
		(layers "F.Cu" "B.Cu")
		(net "GND")
	)
	(via
		(at 106.847894 -282.910788)
		(size 0.49022)
		(drill 0.254)
		(layers "F.Cu" "B.Cu")
		(net "GND")
	)
	(via
		(at 430.14519 -51.227482)
		(size 0.508)
		(drill 0.254)
		(layers "F.Cu" "B.Cu")
		(net "GND")
	)
	(via
		(at 293.829994 -350.977454)
		(size 0.4572)
		(drill 0.254)
		(layers "F.Cu" "B.Cu")
		(net "GND")
	)
	(via
		(at 406.999948 -274.049744)
		(size 0.4064)
		(drill 0.2032)
		(layers "F.Cu" "B.Cu")
		(net "GND")
	)
	(via
		(at 270.80845 -355.366066)
		(size 0.4572)
		(drill 0.254)
		(layers "F.Cu" "B.Cu")
		(net "GND")
	)
	(via
		(at 73.899522 -276.899878)
		(size 0.4064)
		(drill 0.2032)
		(layers "F.Cu" "B.Cu")
		(net "GND")
	)
	(via
		(at 297.927776 -374.938544)
		(size 0.508)
		(drill 0.254)
		(layers "F.Cu" "B.Cu")
		(net "GND")
	)
	(via
		(at 267.328142 -351.611438)
		(size 0.4064)
		(drill 0.2032)
		(layers "F.Cu" "B.Cu")
		(net "GND")
	)
	(via
		(at 185.6613 -60.099194)
		(size 0.508)
		(drill 0.254)
		(layers "F.Cu" "B.Cu")
		(net "GND")
	)
	(via
		(at 438.098184 -21.738336)
		(size 0.508)
		(drill 0.254)
		(layers "F.Cu" "B.Cu")
		(net "GND")
	)
	(via
		(at 363.728 -417.82492)
		(size 0.508)
		(drill 0.254)
		(layers "F.Cu" "B.Cu")
		(net "GND")
	)
	(via
		(at 178.599846 -318.699896)
		(size 0.4064)
		(drill 0.2032)
		(layers "F.Cu" "B.Cu")
		(net "GND")
	)
	(via
		(at 388.27329 -141.029436)
		(size 0.508)
		(drill 0.254)
		(layers "F.Cu" "B.Cu")
		(net "GND")
	)
	(via
		(at 413.649668 -272.14957)
		(size 0.4064)
		(drill 0.2032)
		(layers "F.Cu" "B.Cu")
		(net "GND")
	)
	(via
		(at 397.97482 -299.224954)
		(size 0.4064)
		(drill 0.2032)
		(layers "F.Cu" "B.Cu")
		(net "GND")
	)
	(via
		(at 56.324754 -306.824888)
		(size 0.4064)
		(drill 0.2032)
		(layers "F.Cu" "B.Cu")
		(net "GND")
	)
	(via
		(at 183.3499 -316.799722)
		(size 0.4064)
		(drill 0.2032)
		(layers "F.Cu" "B.Cu")
		(net "GND")
	)
	(via
		(at 349.110554 -277.639272)
		(size 0.508)
		(drill 0.254)
		(layers "F.Cu" "B.Cu")
		(net "GND")
	)
	(via
		(at 4.562856 -109.041692)
		(size 0.508)
		(drill 0.254)
		(layers "F.Cu" "B.Cu")
		(net "GND")
	)
	(via
		(at 388.127748 -410.041852)
		(size 0.508)
		(drill 0.254)
		(layers "F.Cu" "B.Cu")
		(net "GND")
	)
	(via
		(at 330.927964 -380.141734)
		(size 0.508)
		(drill 0.254)
		(layers "F.Cu" "B.Cu")
		(net "GND")
	)
	(via
		(at 452.220838 -311.929526)
		(size 0.508)
		(drill 0.254)
		(layers "F.Cu" "B.Cu")
		(net "GND")
	)
	(via
		(at 345.703906 -84.34197)
		(size 0.508)
		(drill 0.254)
		(layers "F.Cu" "B.Cu")
		(net "GND")
	)
	(via
		(at 74.248264 -149.355048)
		(size 0.508)
		(drill 0.254)
		(layers "F.Cu" "B.Cu")
		(net "GND")
	)
	(via
		(at 107.509564 -163.230052)
		(size 0.508)
		(drill 0.254)
		(layers "F.Cu" "B.Cu")
		(net "GND")
	)
	(via
		(at 290.999926 -38.315138)
		(size 0.508)
		(drill 0.254)
		(layers "F.Cu" "B.Cu")
		(net "GND")
	)
	(via
		(at 427.42485 -302.074834)
		(size 0.4064)
		(drill 0.2032)
		(layers "F.Cu" "B.Cu")
		(net "GND")
	)
	(via
		(at 35.759644 -119.026686)
		(size 0.508)
		(drill 0.254)
		(layers "F.Cu" "B.Cu")
		(net "GND")
	)
	(via
		(at 268.09954 -308.250082)
		(size 0.4064)
		(drill 0.2032)
		(layers "F.Cu" "B.Cu")
		(net "GND")
	)
	(via
		(at 418.42436 -347.951806)
		(size 0.4572)
		(drill 0.254)
		(layers "F.Cu" "B.Cu")
		(net "GND")
	)
	(via
		(at 192.486534 -48.874934)
		(size 0.508)
		(drill 0.254)
		(layers "F.Cu" "B.Cu")
		(net "GND")
	)
	(via
		(at 86.04631 -352.245422)
		(size 0.4572)
		(drill 0.254)
		(layers "F.Cu" "B.Cu")
		(net "GND")
	)
	(via
		(at 430.466246 -143.676878)
		(size 0.508)
		(drill 0.254)
		(layers "F.Cu" "B.Cu")
		(net "GND")
	)
	(via
		(at 66.299842 -314.899802)
		(size 0.4064)
		(drill 0.2032)
		(layers "F.Cu" "B.Cu")
		(net "GND")
	)
	(via
		(at 229.592632 -287.74898)
		(size 0.508)
		(drill 0.254)
		(layers "F.Cu" "B.Cu")
		(net "GND")
	)
	(via
		(at 215.773 -207.01)
		(size 0.508)
		(drill 0.254)
		(layers "F.Cu" "B.Cu")
		(net "GND")
	)
	(via
		(at 289.127692 -399.441924)
		(size 0.508)
		(drill 0.254)
		(layers "F.Cu" "B.Cu")
		(net "GND")
	)
	(via
		(at 188.119004 -349.219774)
		(size 0.4572)
		(drill 0.254)
		(layers "F.Cu" "B.Cu")
		(net "GND")
	)
	(via
		(at 422.199562 -276.899878)
		(size 0.4064)
		(drill 0.2032)
		(layers "F.Cu" "B.Cu")
		(net "GND")
	)
	(via
		(at 241.363754 -222.064072)
		(size 0.508)
		(drill 0.254)
		(layers "F.Cu" "B.Cu")
		(net "GND")
	)
	(via
		(at 44.006516 -341.805514)
		(size 0.4572)
		(drill 0.254)
		(layers "F.Cu" "B.Cu")
		(net "GND")
	)
	(via
		(at 294.69969 -313.949842)
		(size 0.4064)
		(drill 0.2032)
		(layers "F.Cu" "B.Cu")
		(net "GND")
	)
	(via
		(at 4.255008 -284.818582)
		(size 0.508)
		(drill 0.254)
		(layers "F.Cu" "B.Cu")
		(net "GND")
	)
	(via
		(at 151.859488 -105.78211)
		(size 0.508)
		(drill 0.254)
		(layers "F.Cu" "B.Cu")
		(net "GND")
	)
	(via
		(at 71.93915 -32.911796)
		(size 0.508)
		(drill 0.254)
		(layers "F.Cu" "B.Cu")
		(net "GND")
	)
	(via
		(at 291.32784 -372.341902)
		(size 0.508)
		(drill 0.254)
		(layers "F.Cu" "B.Cu")
		(net "GND")
	)
	(via
		(at 298.024804 -294.4749)
		(size 0.4064)
		(drill 0.2032)
		(layers "F.Cu" "B.Cu")
		(net "GND")
	)
	(via
		(at 383.72796 -406.141936)
		(size 0.508)
		(drill 0.254)
		(layers "F.Cu" "B.Cu")
		(net "GND")
	)
	(via
		(at 392.52779 -381.63881)
		(size 0.508)
		(drill 0.254)
		(layers "F.Cu" "B.Cu")
		(net "GND")
	)
	(via
		(at 298.499784 -314.899802)
		(size 0.4064)
		(drill 0.2032)
		(layers "F.Cu" "B.Cu")
		(net "GND")
	)
	(via
		(at 405.100028 -310.149748)
		(size 0.4064)
		(drill 0.2032)
		(layers "F.Cu" "B.Cu")
		(net "GND")
	)
	(via
		(at 407.949654 -272.149316)
		(size 0.4064)
		(drill 0.2032)
		(layers "F.Cu" "B.Cu")
		(net "GND")
	)
	(via
		(at 179.898294 -20.417536)
		(size 0.508)
		(drill 0.254)
		(layers "F.Cu" "B.Cu")
		(net "GND")
	)
	(via
		(at 81.243678 -81.698846)
		(size 0.508)
		(drill 0.254)
		(layers "F.Cu" "B.Cu")
		(net "GND")
	)
	(via
		(at 412.098236 -20.417536)
		(size 0.508)
		(drill 0.254)
		(layers "F.Cu" "B.Cu")
		(net "GND")
	)
	(via
		(at 44.94784 -378.940314)
		(size 0.508)
		(drill 0.254)
		(layers "F.Cu" "B.Cu")
		(net "GND")
	)
	(via
		(at 170.485562 -34.183066)
		(size 0.508)
		(drill 0.254)
		(layers "F.Cu" "B.Cu")
		(net "GND")
	)
	(via
		(at 134.831074 -11.372342)
		(size 0.508)
		(drill 0.254)
		(layers "F.Cu" "B.Cu")
		(net "GND")
	)
	(via
		(at 424.57497 -303.024794)
		(size 0.4064)
		(drill 0.2032)
		(layers "F.Cu" "B.Cu")
		(net "GND")
	)
	(via
		(at 161.025078 -284.024832)
		(size 0.4064)
		(drill 0.2032)
		(layers "F.Cu" "B.Cu")
		(net "GND")
	)
	(via
		(at 409.09748 -341.805514)
		(size 0.4572)
		(drill 0.254)
		(layers "F.Cu" "B.Cu")
		(net "GND")
	)
	(via
		(at 64.399922 -310.149748)
		(size 0.4064)
		(drill 0.2032)
		(layers "F.Cu" "B.Cu")
		(net "GND")
	)
	(via
		(at 184.77484 -293.52494)
		(size 0.4064)
		(drill 0.2032)
		(layers "F.Cu" "B.Cu")
		(net "GND")
	)
	(via
		(at 414.944052 -345.465146)
		(size 0.4064)
		(drill 0.2032)
		(layers "F.Cu" "B.Cu")
		(net "GND")
	)
	(via
		(at 19.258026 -73.85177)
		(size 0.508)
		(drill 0.254)
		(layers "F.Cu" "B.Cu")
		(net "GND")
	)
	(via
		(at 26.982928 -342.439498)
		(size 0.4064)
		(drill 0.2032)
		(layers "F.Cu" "B.Cu")
		(net "GND")
	)
	(via
		(at 285.981902 -354.732082)
		(size 0.4064)
		(drill 0.2032)
		(layers "F.Cu" "B.Cu")
		(net "GND")
	)
	(via
		(at 361.417362 -119.35587)
		(size 0.508)
		(drill 0.254)
		(layers "F.Cu" "B.Cu")
		(net "GND")
	)
	(via
		(at 304.467006 -121.83491)
		(size 0.508)
		(drill 0.254)
		(layers "F.Cu" "B.Cu")
		(net "GND")
	)
	(via
		(at 389.899906 -300.649894)
		(size 0.4064)
		(drill 0.2032)
		(layers "F.Cu" "B.Cu")
		(net "GND")
	)
	(via
		(at 103.7336 -201.2188)
		(size 0.508)
		(drill 0.254)
		(layers "F.Cu" "B.Cu")
		(net "GND")
	)
	(via
		(at 414.74771 -145.755106)
		(size 0.508)
		(drill 0.254)
		(layers "F.Cu" "B.Cu")
		(net "GND")
	)
	(via
		(at 167.732964 -140.765022)
		(size 0.508)
		(drill 0.254)
		(layers "F.Cu" "B.Cu")
		(net "GND")
	)
	(via
		(at 429.325024 -289.724846)
		(size 0.4064)
		(drill 0.2032)
		(layers "F.Cu" "B.Cu")
		(net "GND")
	)
	(via
		(at 409.374848 -291.624766)
		(size 0.4064)
		(drill 0.2032)
		(layers "F.Cu" "B.Cu")
		(net "GND")
	)
	(via
		(at 298.647612 -123.635008)
		(size 0.508)
		(drill 0.254)
		(layers "F.Cu" "B.Cu")
		(net "GND")
	)
	(via
		(at 216.111328 -120.239028)
		(size 0.508)
		(drill 0.254)
		(layers "F.Cu" "B.Cu")
		(net "GND")
	)
	(via
		(at 321.632072 -349.219774)
		(size 0.4572)
		(drill 0.254)
		(layers "F.Cu" "B.Cu")
		(net "GND")
	)
	(via
		(at 270.474948 -280.224738)
		(size 0.4064)
		(drill 0.2032)
		(layers "F.Cu" "B.Cu")
		(net "GND")
	)
	(via
		(at 274.757896 -58.791094)
		(size 0.508)
		(drill 0.254)
		(layers "F.Cu" "B.Cu")
		(net "GND")
	)
	(via
		(at 42.298112 -79.347568)
		(size 0.508)
		(drill 0.254)
		(layers "F.Cu" "B.Cu")
		(net "GND")
	)
	(via
		(at 177.649886 -319.65011)
		(size 0.4064)
		(drill 0.2032)
		(layers "F.Cu" "B.Cu")
		(net "GND")
	)
	(via
		(at 295.441878 -162.08375)
		(size 0.508)
		(drill 0.254)
		(layers "F.Cu" "B.Cu")
		(net "GND")
	)
	(via
		(at 99.960938 -200.674224)
		(size 0.508)
		(drill 0.254)
		(layers "F.Cu" "B.Cu")
		(net "GND")
	)
	(via
		(at 35.93846 -349.219774)
		(size 0.4572)
		(drill 0.254)
		(layers "F.Cu" "B.Cu")
		(net "GND")
	)
	(via
		(at 316.800738 -33.19018)
		(size 0.508)
		(drill 0.254)
		(layers "F.Cu" "B.Cu")
		(net "GND")
	)
	(via
		(at 90.721942 -99.614482)
		(size 0.508)
		(drill 0.254)
		(layers "F.Cu" "B.Cu")
		(net "GND")
	)
	(via
		(at 129.405634 -249.328432)
		(size 0.508)
		(drill 0.254)
		(layers "F.Cu" "B.Cu")
		(net "GND")
	)
	(via
		(at 192.923922 -113.229898)
		(size 0.508)
		(drill 0.254)
		(layers "F.Cu" "B.Cu")
		(net "GND")
	)
	(via
		(at 158.380938 -33.19018)
		(size 0.508)
		(drill 0.254)
		(layers "F.Cu" "B.Cu")
		(net "GND")
	)
	(via
		(at 304.527712 -403.738588)
		(size 0.508)
		(drill 0.254)
		(layers "F.Cu" "B.Cu")
		(net "GND")
	)
	(via
		(at 176.224946 -306.824888)
		(size 0.4064)
		(drill 0.2032)
		(layers "F.Cu" "B.Cu")
		(net "GND")
	)
	(via
		(at 426.949616 -274.999958)
		(size 0.4064)
		(drill 0.2032)
		(layers "F.Cu" "B.Cu")
		(net "GND")
	)
	(via
		(at 257.558286 -253.45644)
		(size 0.508)
		(drill 0.254)
		(layers "F.Cu" "B.Cu")
		(net "GND")
	)
	(via
		(at 429.927766 -374.938544)
		(size 0.508)
		(drill 0.254)
		(layers "F.Cu" "B.Cu")
		(net "GND")
	)
	(via
		(at 306.448206 -154.755088)
		(size 0.508)
		(drill 0.254)
		(layers "F.Cu" "B.Cu")
		(net "GND")
	)
	(via
		(at 64.28359 -354.074222)
		(size 0.4572)
		(drill 0.254)
		(layers "F.Cu" "B.Cu")
		(net "GND")
	)
	(via
		(at 298.024804 -287.824926)
		(size 0.4064)
		(drill 0.2032)
		(layers "F.Cu" "B.Cu")
		(net "GND")
	)
	(via
		(at 401.15236 -104.244902)
		(size 0.508)
		(drill 0.254)
		(layers "F.Cu" "B.Cu")
		(net "GND")
	)
	(via
		(at 55.941976 -49.574704)
		(size 0.508)
		(drill 0.254)
		(layers "F.Cu" "B.Cu")
		(net "GND")
	)
	(via
		(at 16.471646 -213.466172)
		(size 0.508)
		(drill 0.254)
		(layers "F.Cu" "B.Cu")
		(net "GND")
	)
	(via
		(at 295.727882 -377.738386)
		(size 0.508)
		(drill 0.254)
		(layers "F.Cu" "B.Cu")
		(net "GND")
	)
	(via
		(at 23.873968 -345.465146)
		(size 0.4064)
		(drill 0.2032)
		(layers "F.Cu" "B.Cu")
		(net "GND")
	)
	(via
		(at 344.127836 -402.241766)
		(size 0.508)
		(drill 0.254)
		(layers "F.Cu" "B.Cu")
		(net "GND")
	)
	(via
		(at 427.727872 -403.738588)
		(size 0.508)
		(drill 0.254)
		(layers "F.Cu" "B.Cu")
		(net "GND")
	)
	(via
		(at 409.849828 -312.049922)
		(size 0.4064)
		(drill 0.2032)
		(layers "F.Cu" "B.Cu")
		(net "GND")
	)
	(via
		(at 158.174944 -298.27474)
		(size 0.4064)
		(drill 0.2032)
		(layers "F.Cu" "B.Cu")
		(net "GND")
	)
	(via
		(at 179.549806 -272.14957)
		(size 0.4064)
		(drill 0.2032)
		(layers "F.Cu" "B.Cu")
		(net "GND")
	)
	(via
		(at 284.724856 -305.874928)
		(size 0.4064)
		(drill 0.2032)
		(layers "F.Cu" "B.Cu")
		(net "GND")
	)
	(via
		(at 161.500058 -273.099784)
		(size 0.4064)
		(drill 0.2032)
		(layers "F.Cu" "B.Cu")
		(net "GND")
	)
	(via
		(at 165.947852 -402.140166)
		(size 0.508)
		(drill 0.254)
		(layers "F.Cu" "B.Cu")
		(net "GND")
	)
	(via
		(at 199.64019 -152.683464)
		(size 0.508)
		(drill 0.254)
		(layers "F.Cu" "B.Cu")
		(net "GND")
	)
	(via
		(at 209.4611 -113.47196)
		(size 0.508)
		(drill 0.254)
		(layers "F.Cu" "B.Cu")
		(net "GND")
	)
	(via
		(at 40.897556 -350.977454)
		(size 0.4572)
		(drill 0.254)
		(layers "F.Cu" "B.Cu")
		(net "GND")
	)
	(via
		(at 370.260372 -20.35556)
		(size 0.508)
		(drill 0.254)
		(layers "F.Cu" "B.Cu")
		(net "GND")
	)
	(via
		(at 284.249876 -276.899878)
		(size 0.4064)
		(drill 0.2032)
		(layers "F.Cu" "B.Cu")
		(net "GND")
	)
	(via
		(at 379.984 -234.188)
		(size 0.508)
		(drill 0.254)
		(layers "F.Cu" "B.Cu")
		(net "GND")
	)
	(via
		(at 253.42215 -52.51704)
		(size 0.508)
		(drill 0.254)
		(layers "F.Cu" "B.Cu")
		(net "GND")
	)
	(via
		(at 393.351766 -113.245138)
		(size 0.508)
		(drill 0.254)
		(layers "F.Cu" "B.Cu")
		(net "GND")
	)
	(via
		(at 130.461004 -134.970012)
		(size 0.508)
		(drill 0.254)
		(layers "F.Cu" "B.Cu")
		(net "GND")
	)
	(via
		(at 249.104404 -274.487386)
		(size 0.508)
		(drill 0.254)
		(layers "F.Cu" "B.Cu")
		(net "GND")
	)
	(via
		(at 5.100066 -363.054138)
		(size 0.508)
		(drill 0.254)
		(layers "F.Cu" "B.Cu")
		(net "GND")
	)
	(via
		(at 395.901672 -145.372836)
		(size 0.508)
		(drill 0.254)
		(layers "F.Cu" "B.Cu")
		(net "GND")
	)
	(via
		(at 397.120872 -346.09913)
		(size 0.4572)
		(drill 0.254)
		(layers "F.Cu" "B.Cu")
		(net "GND")
	)
	(via
		(at 84.328 -417.82492)
		(size 0.508)
		(drill 0.254)
		(layers "F.Cu" "B.Cu")
		(net "GND")
	)
	(via
		(at 267.848842 -25.990042)
		(size 0.508)
		(drill 0.254)
		(layers "F.Cu" "B.Cu")
		(net "GND")
	)
	(via
		(at 238.800894 -34.990278)
		(size 0.508)
		(drill 0.254)
		(layers "F.Cu" "B.Cu")
		(net "GND")
	)
	(via
		(at 286.35325 -346.09913)
		(size 0.4572)
		(drill 0.254)
		(layers "F.Cu" "B.Cu")
		(net "GND")
	)
	(via
		(at 267.848842 -34.990024)
		(size 0.508)
		(drill 0.254)
		(layers "F.Cu" "B.Cu")
		(net "GND")
	)
	(via
		(at 123.022614 -179.192936)
		(size 0.508)
		(drill 0.254)
		(layers "F.Cu" "B.Cu")
		(net "GND")
	)
	(via
		(at 340.894162 -217.187272)
		(size 0.4572)
		(drill 0.254)
		(layers "F.Cu" "B.Cu")
		(net "GND")
	)
	(via
		(at 265.49985 -62.812168)
		(size 0.508)
		(drill 0.254)
		(layers "F.Cu" "B.Cu")
		(net "GND")
	)
	(via
		(at 78.17485 -291.624766)
		(size 0.4064)
		(drill 0.2032)
		(layers "F.Cu" "B.Cu")
		(net "GND")
	)
	(via
		(at 45.051726 -129.964942)
		(size 0.508)
		(drill 0.254)
		(layers "F.Cu" "B.Cu")
		(net "GND")
	)
	(via
		(at 108.904786 -220.959934)
		(size 0.508)
		(drill 0.254)
		(layers "F.Cu" "B.Cu")
		(net "GND")
	)
	(via
		(at 47.032926 -129.964942)
		(size 0.508)
		(drill 0.254)
		(layers "F.Cu" "B.Cu")
		(net "GND")
	)
	(via
		(at 176.94783 -404.940262)
		(size 0.508)
		(drill 0.254)
		(layers "F.Cu" "B.Cu")
		(net "GND")
	)
	(via
		(at 329.108816 -358.391714)
		(size 0.4572)
		(drill 0.254)
		(layers "F.Cu" "B.Cu")
		(net "GND")
	)
	(via
		(at 262.57377 -25.971246)
		(size 0.508)
		(drill 0.254)
		(layers "F.Cu" "B.Cu")
		(net "GND")
	)
	(via
		(at 446.380108 -208.31937)
		(size 0.508)
		(drill 0.254)
		(layers "F.Cu" "B.Cu")
		(net "GND")
	)
	(via
		(at 311.799732 -278.799798)
		(size 0.4064)
		(drill 0.2032)
		(layers "F.Cu" "B.Cu")
		(net "GND")
	)
	(via
		(at 402.249894 -315.849762)
		(size 0.4064)
		(drill 0.2032)
		(layers "F.Cu" "B.Cu")
		(net "GND")
	)
	(via
		(at 330.927964 -397.140176)
		(size 0.508)
		(drill 0.254)
		(layers "F.Cu" "B.Cu")
		(net "GND")
	)
	(via
		(at 172.900086 -310.149748)
		(size 0.4064)
		(drill 0.2032)
		(layers "F.Cu" "B.Cu")
		(net "GND")
	)
	(via
		(at 148.700998 -33.19018)
		(size 0.508)
		(drill 0.254)
		(layers "F.Cu" "B.Cu")
		(net "GND")
	)
	(via
		(at 387.525006 -296.37482)
		(size 0.4064)
		(drill 0.2032)
		(layers "F.Cu" "B.Cu")
		(net "GND")
	)
	(via
		(at 153.100024 -151.78532)
		(size 0.508)
		(drill 0.254)
		(layers "F.Cu" "B.Cu")
		(net "GND")
	)
	(via
		(at 380.770384 -253.45644)
		(size 0.508)
		(drill 0.254)
		(layers "F.Cu" "B.Cu")
		(net "GND")
	)
	(via
		(at 215.898984 -277.132542)
		(size 0.508)
		(drill 0.254)
		(layers "F.Cu" "B.Cu")
		(net "GND")
	)
	(via
		(at 403.674834 -297.32478)
		(size 0.4064)
		(drill 0.2032)
		(layers "F.Cu" "B.Cu")
		(net "GND")
	)
	(via
		(at 262.987536 -308.65953)
		(size 0.508)
		(drill 0.254)
		(layers "F.Cu" "B.Cu")
		(net "GND")
	)
	(via
		(at 296.124884 -294.4749)
		(size 0.4064)
		(drill 0.2032)
		(layers "F.Cu" "B.Cu")
		(net "GND")
	)
	(via
		(at 163.747958 -380.141734)
		(size 0.508)
		(drill 0.254)
		(layers "F.Cu" "B.Cu")
		(net "GND")
	)
	(via
		(at 414.124902 -284.974792)
		(size 0.4064)
		(drill 0.2032)
		(layers "F.Cu" "B.Cu")
		(net "GND")
	)
	(via
		(at 178.731926 -168.94556)
		(size 0.508)
		(drill 0.254)
		(layers "F.Cu" "B.Cu")
		(net "GND")
	)
	(via
		(at 272.150078 -416.508438)
		(size 0.508)
		(drill 0.254)
		(layers "F.Cu" "B.Cu")
		(net "GND")
	)
	(via
		(at 427.89983 -317.749936)
		(size 0.4064)
		(drill 0.2032)
		(layers "F.Cu" "B.Cu")
		(net "GND")
	)
	(via
		(at 315.042804 -357.75773)
		(size 0.4064)
		(drill 0.2032)
		(layers "F.Cu" "B.Cu")
		(net "GND")
	)
	(via
		(at 87.305134 -347.951806)
		(size 0.4572)
		(drill 0.254)
		(layers "F.Cu" "B.Cu")
		(net "GND")
	)
	(via
		(at 414.599882 -314.899802)
		(size 0.4064)
		(drill 0.2032)
		(layers "F.Cu" "B.Cu")
		(net "GND")
	)
	(via
		(at 41.599866 -304.449734)
		(size 0.4064)
		(drill 0.2032)
		(layers "F.Cu" "B.Cu")
		(net "GND")
	)
	(via
		(at 404.149814 -312.049922)
		(size 0.4064)
		(drill 0.2032)
		(layers "F.Cu" "B.Cu")
		(net "GND")
	)
	(via
		(at 170.806364 -104.244902)
		(size 0.508)
		(drill 0.254)
		(layers "F.Cu" "B.Cu")
		(net "GND")
	)
	(via
		(at 307.049932 -314.899802)
		(size 0.4064)
		(drill 0.2032)
		(layers "F.Cu" "B.Cu")
		(net "GND")
	)
	(via
		(at 266.202922 -287.093914)
		(size 0.508)
		(drill 0.254)
		(layers "F.Cu" "B.Cu")
		(net "GND")
	)
	(via
		(at 200.011538 -404.770844)
		(size 0.508)
		(drill 0.254)
		(layers "F.Cu" "B.Cu")
		(net "GND")
	)
	(via
		(at 279.974802 -301.124874)
		(size 0.4064)
		(drill 0.2032)
		(layers "F.Cu" "B.Cu")
		(net "GND")
	)
	(via
		(at 4.562856 -103.961692)
		(size 0.508)
		(drill 0.254)
		(layers "F.Cu" "B.Cu")
		(net "GND")
	)
	(via
		(at 42.747946 -381.241808)
		(size 0.508)
		(drill 0.254)
		(layers "F.Cu" "B.Cu")
		(net "GND")
	)
	(via
		(at 397.120872 -341.805514)
		(size 0.4572)
		(drill 0.254)
		(layers "F.Cu" "B.Cu")
		(net "GND")
	)
	(via
		(at 273.324828 -273.574764)
		(size 0.4064)
		(drill 0.2032)
		(layers "F.Cu" "B.Cu")
		(net "GND")
	)
	(via
		(at 128.519174 -267.331698)
		(size 0.508)
		(drill 0.254)
		(layers "F.Cu" "B.Cu")
		(net "GND")
	)
	(via
		(at 387.793992 -346.09913)
		(size 0.4572)
		(drill 0.254)
		(layers "F.Cu" "B.Cu")
		(net "GND")
	)
	(via
		(at 365.773462 -72.56526)
		(size 0.508)
		(drill 0.254)
		(layers "F.Cu" "B.Cu")
		(net "GND")
	)
	(via
		(at 117.511068 -354.732082)
		(size 0.4064)
		(drill 0.2032)
		(layers "F.Cu" "B.Cu")
		(net "GND")
	)
	(via
		(at 448.776598 -115.732814)
		(size 0.508)
		(drill 0.254)
		(layers "F.Cu" "B.Cu")
		(net "GND")
	)
	(via
		(at 157.224984 -281.174952)
		(size 0.4064)
		(drill 0.2032)
		(layers "F.Cu" "B.Cu")
		(net "GND")
	)
	(via
		(at 171.949872 -314.899802)
		(size 0.4064)
		(drill 0.2032)
		(layers "F.Cu" "B.Cu")
		(net "GND")
	)
	(via
		(at 401.299934 -313.949842)
		(size 0.4064)
		(drill 0.2032)
		(layers "F.Cu" "B.Cu")
		(net "GND")
	)
	(via
		(at 126.816612 -163.021518)
		(size 0.508)
		(drill 0.254)
		(layers "F.Cu" "B.Cu")
		(net "GND")
	)
	(via
		(at 293.527734 -380.040134)
		(size 0.508)
		(drill 0.254)
		(layers "F.Cu" "B.Cu")
		(net "GND")
	)
	(via
		(at 281.765502 -354.732082)
		(size 0.4064)
		(drill 0.2032)
		(layers "F.Cu" "B.Cu")
		(net "GND")
	)
	(via
		(at 363.22127 -277.004272)
		(size 0.508)
		(drill 0.254)
		(layers "F.Cu" "B.Cu")
		(net "GND")
	)
	(via
		(at 289.090862 -342.439498)
		(size 0.4064)
		(drill 0.2032)
		(layers "F.Cu" "B.Cu")
		(net "GND")
	)
	(via
		(at 94.838266 -73.20026)
		(size 0.508)
		(drill 0.254)
		(layers "F.Cu" "B.Cu")
		(net "GND")
	)
	(via
		(at 304.527712 -410.041852)
		(size 0.508)
		(drill 0.254)
		(layers "F.Cu" "B.Cu")
		(net "GND")
	)
	(via
		(at 23.50262 -352.245422)
		(size 0.4572)
		(drill 0.254)
		(layers "F.Cu" "B.Cu")
		(net "GND")
	)
	(via
		(at 252.139196 -31.652972)
		(size 0.508)
		(drill 0.254)
		(layers "F.Cu" "B.Cu")
		(net "GND")
	)
	(via
		(at 194.749928 -288.299906)
		(size 0.4064)
		(drill 0.2032)
		(layers "F.Cu" "B.Cu")
		(net "GND")
	)
	(via
		(at 78.64983 -307.299868)
		(size 0.4064)
		(drill 0.2032)
		(layers "F.Cu" "B.Cu")
		(net "GND")
	)
	(via
		(at 22.279356 -173.890178)
		(size 0.508)
		(drill 0.254)
		(layers "F.Cu" "B.Cu")
		(net "GND")
	)
	(via
		(at 132.38099 -31.390082)
		(size 0.508)
		(drill 0.254)
		(layers "F.Cu" "B.Cu")
		(net "GND")
	)
	(via
		(at 298.647612 -134.845044)
		(size 0.508)
		(drill 0.254)
		(layers "F.Cu" "B.Cu")
		(net "GND")
	)
	(via
		(at 42.527728 -354.732082)
		(size 0.4064)
		(drill 0.2032)
		(layers "F.Cu" "B.Cu")
		(net "GND")
	)
	(via
		(at 231.867456 -214.704422)
		(size 0.4572)
		(drill 0.254)
		(layers "F.Cu" "B.Cu")
		(net "GND")
	)
	(via
		(at 167.675052 -284.024832)
		(size 0.4064)
		(drill 0.2032)
		(layers "F.Cu" "B.Cu")
		(net "GND")
	)
	(via
		(at 374.099328 -350.977454)
		(size 0.4572)
		(drill 0.254)
		(layers "F.Cu" "B.Cu")
		(net "GND")
	)
	(via
		(at 271.899888 -313.949842)
		(size 0.4064)
		(drill 0.2032)
		(layers "F.Cu" "B.Cu")
		(net "GND")
	)
	(via
		(at 163.247324 -349.219774)
		(size 0.4572)
		(drill 0.254)
		(layers "F.Cu" "B.Cu")
		(net "GND")
	)
	(via
		(at 187.14974 -272.14957)
		(size 0.4064)
		(drill 0.2032)
		(layers "F.Cu" "B.Cu")
		(net "GND")
	)
	(via
		(at 393.055602 -63.218314)
		(size 0.508)
		(drill 0.254)
		(layers "F.Cu" "B.Cu")
		(net "GND")
	)
	(via
		(at 171.950126 -319.65011)
		(size 0.4064)
		(drill 0.2032)
		(layers "F.Cu" "B.Cu")
		(net "GND")
	)
	(via
		(at 419.683184 -357.123746)
		(size 0.4572)
		(drill 0.254)
		(layers "F.Cu" "B.Cu")
		(net "GND")
	)
	(via
		(at 91.899994 -100.803964)
		(size 0.508)
		(drill 0.254)
		(layers "F.Cu" "B.Cu")
		(net "GND")
	)
	(via
		(at 422.674796 -290.674806)
		(size 0.4064)
		(drill 0.2032)
		(layers "F.Cu" "B.Cu")
		(net "GND")
	)
	(via
		(at 180.693314 -154.755088)
		(size 0.508)
		(drill 0.254)
		(layers "F.Cu" "B.Cu")
		(net "GND")
	)
	(via
		(at 250.162568 -220.65488)
		(size 0.508)
		(drill 0.254)
		(layers "F.Cu" "B.Cu")
		(net "GND")
	)
	(via
		(at 42.747946 -411.141926)
		(size 0.508)
		(drill 0.254)
		(layers "F.Cu" "B.Cu")
		(net "GND")
	)
	(via
		(at 337.176872 -346.09913)
		(size 0.4572)
		(drill 0.254)
		(layers "F.Cu" "B.Cu")
		(net "GND")
	)
	(via
		(at 161.500058 -317.749936)
		(size 0.4064)
		(drill 0.2032)
		(layers "F.Cu" "B.Cu")
		(net "GND")
	)
	(via
		(at 398.925034 -300.174914)
		(size 0.4064)
		(drill 0.2032)
		(layers "F.Cu" "B.Cu")
		(net "GND")
	)
	(via
		(at 324.741032 -355.366066)
		(size 0.4572)
		(drill 0.254)
		(layers "F.Cu" "B.Cu")
		(net "GND")
	)
	(via
		(at 338.17687 -285.267654)
		(size 0.508)
		(drill 0.254)
		(layers "F.Cu" "B.Cu")
		(net "GND")
	)
	(via
		(at 179.07508 -303.974754)
		(size 0.4064)
		(drill 0.2032)
		(layers "F.Cu" "B.Cu")
		(net "GND")
	)
	(via
		(at 386.535168 -349.219774)
		(size 0.4572)
		(drill 0.254)
		(layers "F.Cu" "B.Cu")
		(net "GND")
	)
	(via
		(at 189.413388 -34.718498)
		(size 0.508)
		(drill 0.254)
		(layers "F.Cu" "B.Cu")
		(net "GND")
	)
	(via
		(at 171.474892 -284.024832)
		(size 0.4064)
		(drill 0.2032)
		(layers "F.Cu" "B.Cu")
		(net "GND")
	)
	(via
		(at 115.508786 -285.953454)
		(size 0.508)
		(drill 0.254)
		(layers "F.Cu" "B.Cu")
		(net "GND")
	)
	(via
		(at 177.649886 -316.799722)
		(size 0.4064)
		(drill 0.2032)
		(layers "F.Cu" "B.Cu")
		(net "GND")
	)
	(via
		(at 48.24984 -280.699718)
		(size 0.4064)
		(drill 0.2032)
		(layers "F.Cu" "B.Cu")
		(net "GND")
	)
	(via
		(at 61.074808 -298.27474)
		(size 0.4064)
		(drill 0.2032)
		(layers "F.Cu" "B.Cu")
		(net "GND")
	)
	(via
		(at 192.850008 -312.049922)
		(size 0.4064)
		(drill 0.2032)
		(layers "F.Cu" "B.Cu")
		(net "GND")
	)
	(via
		(at 230.040434 -282.982162)
		(size 0.508)
		(drill 0.254)
		(layers "F.Cu" "B.Cu")
		(net "GND")
	)
	(via
		(at 257.750818 -262.912352)
		(size 0.508)
		(drill 0.254)
		(layers "F.Cu" "B.Cu")
		(net "GND")
	)
	(via
		(at 183.766714 -143.955008)
		(size 0.508)
		(drill 0.254)
		(layers "F.Cu" "B.Cu")
		(net "GND")
	)
	(via
		(at 187.149994 -314.899802)
		(size 0.4064)
		(drill 0.2032)
		(layers "F.Cu" "B.Cu")
		(net "GND")
	)
	(via
		(at 131.399026 -132.538216)
		(size 0.508)
		(drill 0.254)
		(layers "F.Cu" "B.Cu")
		(net "GND")
	)
	(via
		(at 181.912514 -133.0452)
		(size 0.508)
		(drill 0.254)
		(layers "F.Cu" "B.Cu")
		(net "GND")
	)
	(via
		(at 338.666074 -94.20987)
		(size 0.508)
		(drill 0.254)
		(layers "F.Cu" "B.Cu")
		(net "GND")
	)
	(via
		(at 297.549824 -281.649932)
		(size 0.4064)
		(drill 0.2032)
		(layers "F.Cu" "B.Cu")
		(net "GND")
	)
	(via
		(at 353.99853 -305.91887)
		(size 0.508)
		(drill 0.254)
		(layers "F.Cu" "B.Cu")
		(net "GND")
	)
	(via
		(at 117.882416 -350.977454)
		(size 0.4572)
		(drill 0.254)
		(layers "F.Cu" "B.Cu")
		(net "GND")
	)
	(via
		(at 83.540346 -144.224502)
		(size 0.508)
		(drill 0.254)
		(layers "F.Cu" "B.Cu")
		(net "GND")
	)
	(via
		(at 431.840386 -155.024582)
		(size 0.508)
		(drill 0.254)
		(layers "F.Cu" "B.Cu")
		(net "GND")
	)
	(via
		(at 174.800006 -273.099784)
		(size 0.4064)
		(drill 0.2032)
		(layers "F.Cu" "B.Cu")
		(net "GND")
	)
	(via
		(at 39.04742 -343.073482)
		(size 0.4572)
		(drill 0.254)
		(layers "F.Cu" "B.Cu")
		(net "GND")
	)
	(via
		(at 80.898238 -119.756936)
		(size 0.508)
		(drill 0.254)
		(layers "F.Cu" "B.Cu")
		(net "GND")
	)
	(via
		(at 285.170372 -152.109678)
		(size 0.508)
		(drill 0.254)
		(layers "F.Cu" "B.Cu")
		(net "GND")
	)
	(via
		(at 274.749768 -316.799722)
		(size 0.4064)
		(drill 0.2032)
		(layers "F.Cu" "B.Cu")
		(net "GND")
	)
	(via
		(at 264.266426 -35.871912)
		(size 0.508)
		(drill 0.254)
		(layers "F.Cu" "B.Cu")
		(net "GND")
	)
	(via
		(at 285.052262 -106.045)
		(size 0.508)
		(drill 0.254)
		(layers "F.Cu" "B.Cu")
		(net "GND")
	)
	(via
		(at 309.899812 -287.349946)
		(size 0.4064)
		(drill 0.2032)
		(layers "F.Cu" "B.Cu")
		(net "GND")
	)
	(via
		(at 161.15157 -120.555004)
		(size 0.508)
		(drill 0.254)
		(layers "F.Cu" "B.Cu")
		(net "GND")
	)
	(via
		(at 356.842568 -285.953454)
		(size 0.508)
		(drill 0.254)
		(layers "F.Cu" "B.Cu")
		(net "GND")
	)
	(via
		(at 400.349974 -311.099962)
		(size 0.4064)
		(drill 0.2032)
		(layers "F.Cu" "B.Cu")
		(net "GND")
	)
	(via
		(at 93.797628 -118.183152)
		(size 0.508)
		(drill 0.254)
		(layers "F.Cu" "B.Cu")
		(net "GND")
	)
	(via
		(at 352.67392 -25.971246)
		(size 0.508)
		(drill 0.254)
		(layers "F.Cu" "B.Cu")
		(net "GND")
	)
	(via
		(at 385.927854 -373.441976)
		(size 0.508)
		(drill 0.254)
		(layers "F.Cu" "B.Cu")
		(net "GND")
	)
	(via
		(at 66.299842 -278.799798)
		(size 0.4064)
		(drill 0.2032)
		(layers "F.Cu" "B.Cu")
		(net "GND")
	)
	(via
		(at 55.849774 -281.649932)
		(size 0.4064)
		(drill 0.2032)
		(layers "F.Cu" "B.Cu")
		(net "GND")
	)
	(via
		(at 67.622166 -117.415056)
		(size 0.508)
		(drill 0.254)
		(layers "F.Cu" "B.Cu")
		(net "GND")
	)
	(via
		(at 175.683164 -350.977454)
		(size 0.4572)
		(drill 0.254)
		(layers "F.Cu" "B.Cu")
		(net "GND")
	)
	(via
		(at 375.969022 -286.331914)
		(size 0.508)
		(drill 0.254)
		(layers "F.Cu" "B.Cu")
		(net "GND")
	)
	(via
		(at 258.979924 -393.147296)
		(size 0.508)
		(drill 0.254)
		(layers "F.Cu" "B.Cu")
		(net "GND")
	)
	(via
		(at 362.580936 -119.39143)
		(size 0.508)
		(drill 0.254)
		(layers "F.Cu" "B.Cu")
		(net "GND")
	)
	(via
		(at 330.3016 -87.52205)
		(size 0.508)
		(drill 0.254)
		(layers "F.Cu" "B.Cu")
		(net "GND")
	)
	(via
		(at 438.13222 -126.013972)
		(size 0.508)
		(drill 0.254)
		(layers "F.Cu" "B.Cu")
		(net "GND")
	)
	(via
		(at 130.318256 -341.805514)
		(size 0.4572)
		(drill 0.254)
		(layers "F.Cu" "B.Cu")
		(net "GND")
	)
	(via
		(at 162.450018 -276.899878)
		(size 0.4064)
		(drill 0.2032)
		(layers "F.Cu" "B.Cu")
		(net "GND")
	)
	(via
		(at 170.347894 -403.34184)
		(size 0.508)
		(drill 0.254)
		(layers "F.Cu" "B.Cu")
		(net "GND")
	)
	(via
		(at 392.274806 -279.274778)
		(size 0.4064)
		(drill 0.2032)
		(layers "F.Cu" "B.Cu")
		(net "GND")
	)
	(via
		(at 269.524734 -285.924752)
		(size 0.4064)
		(drill 0.2032)
		(layers "F.Cu" "B.Cu")
		(net "GND")
	)
	(via
		(at 441.445904 -344.831162)
		(size 0.4572)
		(drill 0.254)
		(layers "F.Cu" "B.Cu")
		(net "GND")
	)
	(via
		(at 172.424852 -298.27474)
		(size 0.4064)
		(drill 0.2032)
		(layers "F.Cu" "B.Cu")
		(net "GND")
	)
	(via
		(at 257.705098 -203.908152)
		(size 0.508)
		(drill 0.254)
		(layers "F.Cu" "B.Cu")
		(net "GND")
	)
	(via
		(at 167.835072 -351.611438)
		(size 0.4064)
		(drill 0.2032)
		(layers "F.Cu" "B.Cu")
		(net "GND")
	)
	(via
		(at 258.574286 -253.45644)
		(size 0.508)
		(drill 0.254)
		(layers "F.Cu" "B.Cu")
		(net "GND")
	)
	(via
		(at 164.824918 -300.174914)
		(size 0.4064)
		(drill 0.2032)
		(layers "F.Cu" "B.Cu")
		(net "GND")
	)
	(via
		(at 298.10202 -56.826404)
		(size 0.508)
		(drill 0.254)
		(layers "F.Cu" "B.Cu")
		(net "GND")
	)
	(via
		(at 250.71197 -81.349342)
		(size 0.508)
		(drill 0.254)
		(layers "F.Cu" "B.Cu")
		(net "GND")
	)
	(via
		(at 92.692982 -95.054928)
		(size 0.508)
		(drill 0.254)
		(layers "F.Cu" "B.Cu")
		(net "GND")
	)
	(via
		(at 67.021202 -351.611438)
		(size 0.4064)
		(drill 0.2032)
		(layers "F.Cu" "B.Cu")
		(net "GND")
	)
	(via
		(at 440.219338 -126.049532)
		(size 0.508)
		(drill 0.254)
		(layers "F.Cu" "B.Cu")
		(net "GND")
	)
	(via
		(at 298.012612 -154.755088)
		(size 0.508)
		(drill 0.254)
		(layers "F.Cu" "B.Cu")
		(net "GND")
	)
	(via
		(at 393.7 -303.499774)
		(size 0.4064)
		(drill 0.2032)
		(layers "F.Cu" "B.Cu")
		(net "GND")
	)
	(via
		(at 66.774822 -296.37482)
		(size 0.4064)
		(drill 0.2032)
		(layers "F.Cu" "B.Cu")
		(net "GND")
	)
	(via
		(at 420.469568 -111.016288)
		(size 0.508)
		(drill 0.254)
		(layers "F.Cu" "B.Cu")
		(net "GND")
	)
	(via
		(at 128.547622 -410.041852)
		(size 0.4572)
		(drill 0.254)
		(layers "F.Cu" "B.Cu")
		(net "GND")
	)
	(via
		(at 431.840386 -151.42464)
		(size 0.508)
		(drill 0.254)
		(layers "F.Cu" "B.Cu")
		(net "GND")
	)
	(via
		(at 8.148066 -385.480814)
		(size 0.508)
		(drill 0.254)
		(layers "F.Cu" "B.Cu")
		(net "GND")
	)
	(via
		(at 150.59152 -109.382052)
		(size 0.508)
		(drill 0.254)
		(layers "F.Cu" "B.Cu")
		(net "GND")
	)
	(via
		(at 281.399742 -278.799798)
		(size 0.4064)
		(drill 0.2032)
		(layers "F.Cu" "B.Cu")
		(net "GND")
	)
	(via
		(at 267.959586 -120.28551)
		(size 0.508)
		(drill 0.254)
		(layers "F.Cu" "B.Cu")
		(net "GND")
	)
	(via
		(at 409.849574 -272.14957)
		(size 0.4064)
		(drill 0.2032)
		(layers "F.Cu" "B.Cu")
		(net "GND")
	)
	(via
		(at 351.38995 -150.76805)
		(size 0.508)
		(drill 0.254)
		(layers "F.Cu" "B.Cu")
		(net "GND")
	)
	(via
		(at 323.262244 -354.732082)
		(size 0.4064)
		(drill 0.2032)
		(layers "F.Cu" "B.Cu")
		(net "GND")
	)
	(via
		(at 263.716008 -256.375916)
		(size 0.508)
		(drill 0.254)
		(layers "F.Cu" "B.Cu")
		(net "GND")
	)
	(via
		(at 332.6765 -115.732814)
		(size 0.508)
		(drill 0.254)
		(layers "F.Cu" "B.Cu")
		(net "GND")
	)
	(via
		(at 45.87494 -284.974792)
		(size 0.4064)
		(drill 0.2032)
		(layers "F.Cu" "B.Cu")
		(net "GND")
	)
	(via
		(at 163.747958 -376.241818)
		(size 0.508)
		(drill 0.254)
		(layers "F.Cu" "B.Cu")
		(net "GND")
	)
	(via
		(at 351.423224 -141.817852)
		(size 0.508)
		(drill 0.254)
		(layers "F.Cu" "B.Cu")
		(net "GND")
	)
	(via
		(at 391.2743 -351.611438)
		(size 0.4064)
		(drill 0.2032)
		(layers "F.Cu" "B.Cu")
		(net "GND")
	)
	(via
		(at 365.623348 -133.255766)
		(size 0.508)
		(drill 0.254)
		(layers "F.Cu" "B.Cu")
		(net "GND")
	)
	(via
		(at 335.328006 -395.938502)
		(size 0.508)
		(drill 0.254)
		(layers "F.Cu" "B.Cu")
		(net "GND")
	)
	(via
		(at 174.42434 -355.366066)
		(size 0.4572)
		(drill 0.254)
		(layers "F.Cu" "B.Cu")
		(net "GND")
	)
	(via
		(at 71.347838 -404.940262)
		(size 0.508)
		(drill 0.254)
		(layers "F.Cu" "B.Cu")
		(net "GND")
	)
	(via
		(at 286.35325 -355.366066)
		(size 0.4572)
		(drill 0.254)
		(layers "F.Cu" "B.Cu")
		(net "GND")
	)
	(via
		(at 134.28472 -72.56526)
		(size 0.508)
		(drill 0.254)
		(layers "F.Cu" "B.Cu")
		(net "GND")
	)
	(via
		(at 273.546062 -345.465146)
		(size 0.4064)
		(drill 0.2032)
		(layers "F.Cu" "B.Cu")
		(net "GND")
	)
	(via
		(at 125.35916 -349.219774)
		(size 0.4572)
		(drill 0.254)
		(layers "F.Cu" "B.Cu")
		(net "GND")
	)
	(via
		(at 369.019328 -46.893226)
		(size 0.508)
		(drill 0.254)
		(layers "F.Cu" "B.Cu")
		(net "GND")
	)
	(via
		(at 276.174708 -281.174952)
		(size 0.4064)
		(drill 0.2032)
		(layers "F.Cu" "B.Cu")
		(net "GND")
	)
	(via
		(at 167.732964 -118.754906)
		(size 0.508)
		(drill 0.254)
		(layers "F.Cu" "B.Cu")
		(net "GND")
	)
	(via
		(at 196.649848 -306.349908)
		(size 0.4064)
		(drill 0.2032)
		(layers "F.Cu" "B.Cu")
		(net "GND")
	)
	(via
		(at 182.002176 -58.096404)
		(size 0.508)
		(drill 0.254)
		(layers "F.Cu" "B.Cu")
		(net "GND")
	)
	(via
		(at 250.396248 -60.099194)
		(size 0.508)
		(drill 0.254)
		(layers "F.Cu" "B.Cu")
		(net "GND")
	)
	(via
		(at 176.699926 -314.899802)
		(size 0.4064)
		(drill 0.2032)
		(layers "F.Cu" "B.Cu")
		(net "GND")
	)
	(via
		(at 68.280788 -29.589984)
		(size 0.508)
		(drill 0.254)
		(layers "F.Cu" "B.Cu")
		(net "GND")
	)
	(via
		(at 177.649886 -311.099962)
		(size 0.4064)
		(drill 0.2032)
		(layers "F.Cu" "B.Cu")
		(net "GND")
	)
	(via
		(at 242.117118 -218.80576)
		(size 0.508)
		(drill 0.254)
		(layers "F.Cu" "B.Cu")
		(net "GND")
	)
	(via
		(at 290.721034 -349.219774)
		(size 0.4572)
		(drill 0.254)
		(layers "F.Cu" "B.Cu")
		(net "GND")
	)
	(via
		(at 439.815732 -345.465146)
		(size 0.4064)
		(drill 0.2032)
		(layers "F.Cu" "B.Cu")
		(net "GND")
	)
	(via
		(at 126.347728 -411.141926)
		(size 0.4572)
		(drill 0.254)
		(layers "F.Cu" "B.Cu")
		(net "GND")
	)
	(via
		(at 65.913762 -348.58579)
		(size 0.4064)
		(drill 0.2032)
		(layers "F.Cu" "B.Cu")
		(net "GND")
	)
	(via
		(at 136.164828 -354.732082)
		(size 0.4064)
		(drill 0.2032)
		(layers "F.Cu" "B.Cu")
		(net "GND")
	)
	(via
		(at 425.527724 -376.140218)
		(size 0.508)
		(drill 0.254)
		(layers "F.Cu" "B.Cu")
		(net "GND")
	)
	(via
		(at 165.947852 -372.240302)
		(size 0.508)
		(drill 0.254)
		(layers "F.Cu" "B.Cu")
		(net "GND")
	)
	(via
		(at 173.682406 -37.087048)
		(size 0.508)
		(drill 0.254)
		(layers "F.Cu" "B.Cu")
		(net "GND")
	)
	(via
		(at 82.347816 -383.940304)
		(size 0.508)
		(drill 0.254)
		(layers "F.Cu" "B.Cu")
		(net "GND")
	)
	(via
		(at 106.713274 -285.953454)
		(size 0.508)
		(drill 0.254)
		(layers "F.Cu" "B.Cu")
		(net "GND")
	)
	(via
		(at 165.529006 -107.407456)
		(size 0.508)
		(drill 0.254)
		(layers "F.Cu" "B.Cu")
		(net "GND")
	)
	(via
		(at 340.18347 -286.842454)
		(size 0.508)
		(drill 0.254)
		(layers "F.Cu" "B.Cu")
		(net "GND")
	)
	(via
		(at 276.649942 -319.65011)
		(size 0.4064)
		(drill 0.2032)
		(layers "F.Cu" "B.Cu")
		(net "GND")
	)
	(via
		(at 45.39996 -309.199788)
		(size 0.4064)
		(drill 0.2032)
		(layers "F.Cu" "B.Cu")
		(net "GND")
	)
	(via
		(at 0.766318 -16.452342)
		(size 0.508)
		(drill 0.254)
		(layers "F.Cu" "B.Cu")
		(net "GND")
	)
	(via
		(at 189.96914 -352.245422)
		(size 0.4572)
		(drill 0.254)
		(layers "F.Cu" "B.Cu")
		(net "GND")
	)
	(via
		(at 106.078274 -286.842454)
		(size 0.508)
		(drill 0.254)
		(layers "F.Cu" "B.Cu")
		(net "GND")
	)
	(via
		(at 83.902042 -27.729688)
		(size 0.508)
		(drill 0.254)
		(layers "F.Cu" "B.Cu")
		(net "GND")
	)
	(via
		(at 369.522248 -52.51704)
		(size 0.508)
		(drill 0.254)
		(layers "F.Cu" "B.Cu")
		(net "GND")
	)
	(via
		(at 222.566484 -76.899516)
		(size 0.508)
		(drill 0.254)
		(layers "F.Cu" "B.Cu")
		(net "GND")
	)
	(via
		(at 114.773456 -354.074222)
		(size 0.4572)
		(drill 0.254)
		(layers "F.Cu" "B.Cu")
		(net "GND")
	)
	(via
		(at 416.574224 -355.366066)
		(size 0.4572)
		(drill 0.254)
		(layers "F.Cu" "B.Cu")
		(net "GND")
	)
	(via
		(at 39.699946 -300.649894)
		(size 0.4064)
		(drill 0.2032)
		(layers "F.Cu" "B.Cu")
		(net "GND")
	)
	(via
		(at 232.51033 -93.77934)
		(size 0.508)
		(drill 0.254)
		(layers "F.Cu" "B.Cu")
		(net "GND")
	)
	(via
		(at 278.074882 -282.124912)
		(size 0.4064)
		(drill 0.2032)
		(layers "F.Cu" "B.Cu")
		(net "GND")
	)
	(via
		(at 38.446964 -23.583646)
		(size 0.508)
		(drill 0.254)
		(layers "F.Cu" "B.Cu")
		(net "GND")
	)
	(via
		(at 35.759644 -108.123228)
		(size 0.508)
		(drill 0.254)
		(layers "F.Cu" "B.Cu")
		(net "GND")
	)
	(via
		(at 186.86018 -349.219774)
		(size 0.4572)
		(drill 0.254)
		(layers "F.Cu" "B.Cu")
		(net "GND")
	)
	(via
		(at 170.999912 -314.899802)
		(size 0.4064)
		(drill 0.2032)
		(layers "F.Cu" "B.Cu")
		(net "GND")
	)
	(via
		(at 112.446816 -136.90346)
		(size 0.508)
		(drill 0.254)
		(layers "F.Cu" "B.Cu")
		(net "GND")
	)
	(via
		(at 170.944032 -345.465146)
		(size 0.4064)
		(drill 0.2032)
		(layers "F.Cu" "B.Cu")
		(net "GND")
	)
	(via
		(at 405.100028 -281.649932)
		(size 0.4064)
		(drill 0.2032)
		(layers "F.Cu" "B.Cu")
		(net "GND")
	)
	(via
		(at 284.249876 -279.749758)
		(size 0.4064)
		(drill 0.2032)
		(layers "F.Cu" "B.Cu")
		(net "GND")
	)
	(via
		(at 167.675052 -297.32478)
		(size 0.4064)
		(drill 0.2032)
		(layers "F.Cu" "B.Cu")
		(net "GND")
	)
	(via
		(at 86.04631 -354.098098)
		(size 0.4572)
		(drill 0.254)
		(layers "F.Cu" "B.Cu")
		(net "GND")
	)
	(via
		(at 378.145294 -51.227482)
		(size 0.508)
		(drill 0.254)
		(layers "F.Cu" "B.Cu")
		(net "GND")
	)
	(via
		(at 463.037682 -153.937462)
		(size 0.508)
		(drill 0.254)
		(layers "F.Cu" "B.Cu")
		(net "GND")
	)
	(via
		(at 80.147922 -375.040144)
		(size 0.508)
		(drill 0.254)
		(layers "F.Cu" "B.Cu")
		(net "GND")
	)
	(via
		(at 91.892882 -354.732082)
		(size 0.4064)
		(drill 0.2032)
		(layers "F.Cu" "B.Cu")
		(net "GND")
	)
	(via
		(at 174.747936 -403.34184)
		(size 0.508)
		(drill 0.254)
		(layers "F.Cu" "B.Cu")
		(net "GND")
	)
	(via
		(at 226.12858 -105.48366)
		(size 0.508)
		(drill 0.254)
		(layers "F.Cu" "B.Cu")
		(net "GND")
	)
	(via
		(at 111.311182 -290.68649)
		(size 0.508)
		(drill 0.254)
		(layers "F.Cu" "B.Cu")
		(net "GND")
	)
	(via
		(at 82.449924 -277.849838)
		(size 0.4064)
		(drill 0.2032)
		(layers "F.Cu" "B.Cu")
		(net "GND")
	)
	(via
		(at 164.726112 -354.732082)
		(size 0.4064)
		(drill 0.2032)
		(layers "F.Cu" "B.Cu")
		(net "GND")
	)
	(via
		(at 414.11271 -143.955008)
		(size 0.508)
		(drill 0.254)
		(layers "F.Cu" "B.Cu")
		(net "GND")
	)
	(via
		(at 418.399976 -318.699896)
		(size 0.4064)
		(drill 0.2032)
		(layers "F.Cu" "B.Cu")
		(net "GND")
	)
	(via
		(at 282.824936 -296.37482)
		(size 0.4064)
		(drill 0.2032)
		(layers "F.Cu" "B.Cu")
		(net "GND")
	)
	(via
		(at 248.559574 -145.53565)
		(size 0.508)
		(drill 0.254)
		(layers "F.Cu" "B.Cu")
		(net "GND")
	)
	(via
		(at 210.942936 -189.662054)
		(size 0.508)
		(drill 0.254)
		(layers "F.Cu" "B.Cu")
		(net "GND")
	)
	(via
		(at 387.999986 -314.899802)
		(size 0.4064)
		(drill 0.2032)
		(layers "F.Cu" "B.Cu")
		(net "GND")
	)
	(via
		(at 318.151764 -345.465146)
		(size 0.4064)
		(drill 0.2032)
		(layers "F.Cu" "B.Cu")
		(net "GND")
	)
	(via
		(at 150.59152 -122.626628)
		(size 0.508)
		(drill 0.254)
		(layers "F.Cu" "B.Cu")
		(net "GND")
	)
	(via
		(at 321.632072 -355.366066)
		(size 0.4572)
		(drill 0.254)
		(layers "F.Cu" "B.Cu")
		(net "GND")
	)
	(via
		(at 184.77484 -292.574726)
		(size 0.4064)
		(drill 0.2032)
		(layers "F.Cu" "B.Cu")
		(net "GND")
	)
	(via
		(at 195.699888 -285.449772)
		(size 0.4064)
		(drill 0.2032)
		(layers "F.Cu" "B.Cu")
		(net "GND")
	)
	(via
		(at 135.043164 -207.193896)
		(size 0.508)
		(drill 0.254)
		(layers "F.Cu" "B.Cu")
		(net "GND")
	)
	(via
		(at 58.600848 -29.590238)
		(size 0.508)
		(drill 0.254)
		(layers "F.Cu" "B.Cu")
		(net "GND")
	)
	(via
		(at 304.467006 -142.15491)
		(size 0.508)
		(drill 0.254)
		(layers "F.Cu" "B.Cu")
		(net "GND")
	)
	(via
		(at 288.524696 -306.824888)
		(size 0.4064)
		(drill 0.2032)
		(layers "F.Cu" "B.Cu")
		(net "GND")
	)
	(via
		(at 310.374792 -301.124874)
		(size 0.4064)
		(drill 0.2032)
		(layers "F.Cu" "B.Cu")
		(net "GND")
	)
	(via
		(at 169.574972 -297.32478)
		(size 0.4064)
		(drill 0.2032)
		(layers "F.Cu" "B.Cu")
		(net "GND")
	)
	(via
		(at 166.356284 -347.951806)
		(size 0.4572)
		(drill 0.254)
		(layers "F.Cu" "B.Cu")
		(net "GND")
	)
	(via
		(at 185.250074 -311.099962)
		(size 0.4064)
		(drill 0.2032)
		(layers "F.Cu" "B.Cu")
		(net "GND")
	)
	(via
		(at 28.385516 -34.183066)
		(size 0.508)
		(drill 0.254)
		(layers "F.Cu" "B.Cu")
		(net "GND")
	)
	(via
		(at 72.487536 -26.360882)
		(size 0.508)
		(drill 0.254)
		(layers "F.Cu" "B.Cu")
		(net "GND")
	)
	(via
		(at 280.924762 -285.924752)
		(size 0.4064)
		(drill 0.2032)
		(layers "F.Cu" "B.Cu")
		(net "GND")
	)
	(via
		(at 174.052992 -354.732082)
		(size 0.4064)
		(drill 0.2032)
		(layers "F.Cu" "B.Cu")
		(net "GND")
	)
	(via
		(at 365.623348 -133.890766)
		(size 0.508)
		(drill 0.254)
		(layers "F.Cu" "B.Cu")
		(net "GND")
	)
	(via
		(at 62.974982 -285.924752)
		(size 0.4064)
		(drill 0.2032)
		(layers "F.Cu" "B.Cu")
		(net "GND")
	)
	(via
		(at 75.79995 -312.999882)
		(size 0.4064)
		(drill 0.2032)
		(layers "F.Cu" "B.Cu")
		(net "GND")
	)
	(via
		(at 137.73785 -193.238628)
		(size 0.508)
		(drill 0.254)
		(layers "F.Cu" "B.Cu")
		(net "GND")
	)
	(via
		(at 42.527728 -348.58579)
		(size 0.4064)
		(drill 0.2032)
		(layers "F.Cu" "B.Cu")
		(net "GND")
	)
	(via
		(at 416.580828 -33.19018)
		(size 0.508)
		(drill 0.254)
		(layers "F.Cu" "B.Cu")
		(net "GND")
	)
	(via
		(at 295.68013 -346.09913)
		(size 0.4572)
		(drill 0.254)
		(layers "F.Cu" "B.Cu")
		(net "GND")
	)
	(via
		(at 8.148066 -387.512814)
		(size 0.508)
		(drill 0.254)
		(layers "F.Cu" "B.Cu")
		(net "GND")
	)
	(via
		(at 158.174944 -283.074872)
		(size 0.4064)
		(drill 0.2032)
		(layers "F.Cu" "B.Cu")
		(net "GND")
	)
	(via
		(at 200.908158 -131.514596)
		(size 0.508)
		(drill 0.254)
		(layers "F.Cu" "B.Cu")
		(net "GND")
	)
	(via
		(at 101.339904 -73.87463)
		(size 0.508)
		(drill 0.254)
		(layers "F.Cu" "B.Cu")
		(net "GND")
	)
	(via
		(at 348.527878 -397.140176)
		(size 0.508)
		(drill 0.254)
		(layers "F.Cu" "B.Cu")
		(net "GND")
	)
	(via
		(at 319.781936 -355.366066)
		(size 0.4572)
		(drill 0.254)
		(layers "F.Cu" "B.Cu")
		(net "GND")
	)
	(via
		(at 161.975038 -300.174914)
		(size 0.4064)
		(drill 0.2032)
		(layers "F.Cu" "B.Cu")
		(net "GND")
	)
	(via
		(at 341.544656 -358.391714)
		(size 0.4572)
		(drill 0.254)
		(layers "F.Cu" "B.Cu")
		(net "GND")
	)
	(via
		(at 76.74991 -314.899802)
		(size 0.4064)
		(drill 0.2032)
		(layers "F.Cu" "B.Cu")
		(net "GND")
	)
	(via
		(at 398.59966 -354.732082)
		(size 0.4064)
		(drill 0.2032)
		(layers "F.Cu" "B.Cu")
		(net "GND")
	)
	(via
		(at 304.199798 -312.999882)
		(size 0.4064)
		(drill 0.2032)
		(layers "F.Cu" "B.Cu")
		(net "GND")
	)
	(via
		(at 454.694544 -101.386894)
		(size 0.508)
		(drill 0.254)
		(layers "F.Cu" "B.Cu")
		(net "GND")
	)
	(via
		(at 153.233628 -106.316526)
		(size 0.508)
		(drill 0.254)
		(layers "F.Cu" "B.Cu")
		(net "GND")
	)
	(via
		(at 321.260724 -351.611438)
		(size 0.4064)
		(drill 0.2032)
		(layers "F.Cu" "B.Cu")
		(net "GND")
	)
	(via
		(at 188.099954 -274.049744)
		(size 0.4064)
		(drill 0.2032)
		(layers "F.Cu" "B.Cu")
		(net "GND")
	)
	(via
		(at 404.69566 -86.328504)
		(size 0.508)
		(drill 0.254)
		(layers "F.Cu" "B.Cu")
		(net "GND")
	)
	(via
		(at 0.766318 -21.532342)
		(size 0.508)
		(drill 0.254)
		(layers "F.Cu" "B.Cu")
		(net "GND")
	)
	(via
		(at 0.77089 -360.181144)
		(size 0.508)
		(drill 0.254)
		(layers "F.Cu" "B.Cu")
		(net "GND")
	)
	(via
		(at 385.927854 -380.040134)
		(size 0.508)
		(drill 0.254)
		(layers "F.Cu" "B.Cu")
		(net "GND")
	)
	(via
		(at 429.198278 -119.756936)
		(size 0.508)
		(drill 0.254)
		(layers "F.Cu" "B.Cu")
		(net "GND")
	)
	(via
		(at 414.11271 -125.435106)
		(size 0.508)
		(drill 0.254)
		(layers "F.Cu" "B.Cu")
		(net "GND")
	)
	(via
		(at 431.840386 -132.77342)
		(size 0.508)
		(drill 0.254)
		(layers "F.Cu" "B.Cu")
		(net "GND")
	)
	(via
		(at 299.637704 -74.624184)
		(size 0.508)
		(drill 0.254)
		(layers "F.Cu" "B.Cu")
		(net "GND")
	)
	(via
		(at 71.049896 -316.799722)
		(size 0.4064)
		(drill 0.2032)
		(layers "F.Cu" "B.Cu")
		(net "GND")
	)
	(via
		(at 69.624956 -292.574726)
		(size 0.4064)
		(drill 0.2032)
		(layers "F.Cu" "B.Cu")
		(net "GND")
	)
	(via
		(at 312.305192 -344.831162)
		(size 0.4572)
		(drill 0.254)
		(layers "F.Cu" "B.Cu")
		(net "GND")
	)
	(via
		(at 20.76196 -161.6075)
		(size 0.508)
		(drill 0.254)
		(layers "F.Cu" "B.Cu")
		(net "GND")
	)
	(via
		(at 161.975038 -301.124874)
		(size 0.4064)
		(drill 0.2032)
		(layers "F.Cu" "B.Cu")
		(net "GND")
	)
	(via
		(at 450.412612 -102.271068)
		(size 0.508)
		(drill 0.254)
		(layers "F.Cu" "B.Cu")
		(net "GND")
	)
	(via
		(at 147.616164 -256.375916)
		(size 0.508)
		(drill 0.254)
		(layers "F.Cu" "B.Cu")
		(net "GND")
	)
	(via
		(at 228.946964 -273.829526)
		(size 0.508)
		(drill 0.254)
		(layers "F.Cu" "B.Cu")
		(net "GND")
	)
	(via
		(at 65.349882 -281.649932)
		(size 0.4064)
		(drill 0.2032)
		(layers "F.Cu" "B.Cu")
		(net "GND")
	)
	(via
		(at 14.7955 -311.860184)
		(size 0.508)
		(drill 0.254)
		(layers "F.Cu" "B.Cu")
		(net "GND")
	)
	(via
		(at 165.09746 -344.831162)
		(size 0.4572)
		(drill 0.254)
		(layers "F.Cu" "B.Cu")
		(net "GND")
	)
	(via
		(at 106.229404 -166.570152)
		(size 0.508)
		(drill 0.254)
		(layers "F.Cu" "B.Cu")
		(net "GND")
	)
	(via
		(at 33.299908 -62.812168)
		(size 0.508)
		(drill 0.254)
		(layers "F.Cu" "B.Cu")
		(net "GND")
	)
	(via
		(at 61.074808 -303.974754)
		(size 0.4064)
		(drill 0.2032)
		(layers "F.Cu" "B.Cu")
		(net "GND")
	)
	(via
		(at 282.349702 -311.099962)
		(size 0.4064)
		(drill 0.2032)
		(layers "F.Cu" "B.Cu")
		(net "GND")
	)
	(via
		(at 280.924762 -298.27474)
		(size 0.4064)
		(drill 0.2032)
		(layers "F.Cu" "B.Cu")
		(net "GND")
	)
	(via
		(at 169.587164 -106.044746)
		(size 0.508)
		(drill 0.254)
		(layers "F.Cu" "B.Cu")
		(net "GND")
	)
	(via
		(at 182.272432 -357.75773)
		(size 0.4064)
		(drill 0.2032)
		(layers "F.Cu" "B.Cu")
		(net "GND")
	)
	(via
		(at 466.835998 -287.843976)
		(size 0.508)
		(drill 0.254)
		(layers "F.Cu" "B.Cu")
		(net "GND")
	)
	(via
		(at 71.347838 -406.141936)
		(size 0.508)
		(drill 0.254)
		(layers "F.Cu" "B.Cu")
		(net "GND")
	)
	(via
		(at 322.821554 -124.93498)
		(size 0.508)
		(drill 0.254)
		(layers "F.Cu" "B.Cu")
		(net "GND")
	)
	(via
		(at 44.006516 -346.09913)
		(size 0.4572)
		(drill 0.254)
		(layers "F.Cu" "B.Cu")
		(net "GND")
	)
	(via
		(at 329.108816 -355.366066)
		(size 0.4572)
		(drill 0.254)
		(layers "F.Cu" "B.Cu")
		(net "GND")
	)
	(via
		(at 334.312514 -102.271068)
		(size 0.508)
		(drill 0.254)
		(layers "F.Cu" "B.Cu")
		(net "GND")
	)
	(via
		(at 281.874722 -284.974792)
		(size 0.4064)
		(drill 0.2032)
		(layers "F.Cu" "B.Cu")
		(net "GND")
	)
	(via
		(at 420.479982 -111.750602)
		(size 0.508)
		(drill 0.254)
		(layers "F.Cu" "B.Cu")
		(net "GND")
	)
	(via
		(at 390.327896 -371.038628)
		(size 0.508)
		(drill 0.254)
		(layers "F.Cu" "B.Cu")
		(net "GND")
	)
	(via
		(at 42.747946 -380.040134)
		(size 0.508)
		(drill 0.254)
		(layers "F.Cu" "B.Cu")
		(net "GND")
	)
	(via
		(at 16.838422 -73.20026)
		(size 0.508)
		(drill 0.254)
		(layers "F.Cu" "B.Cu")
		(net "GND")
	)
	(via
		(at 295.727882 -373.83847)
		(size 0.508)
		(drill 0.254)
		(layers "F.Cu" "B.Cu")
		(net "GND")
	)
	(via
		(at 321.998086 -21.738336)
		(size 0.508)
		(drill 0.254)
		(layers "F.Cu" "B.Cu")
		(net "GND")
	)
	(via
		(at 438.336944 -350.977454)
		(size 0.4572)
		(drill 0.254)
		(layers "F.Cu" "B.Cu")
		(net "GND")
	)
	(via
		(at 276.655022 -354.732082)
		(size 0.4064)
		(drill 0.2032)
		(layers "F.Cu" "B.Cu")
		(net "GND")
	)
	(via
		(at 125.709172 -290.05149)
		(size 0.508)
		(drill 0.254)
		(layers "F.Cu" "B.Cu")
		(net "GND")
	)
	(via
		(at 159.347916 -380.141734)
		(size 0.508)
		(drill 0.254)
		(layers "F.Cu" "B.Cu")
		(net "GND")
	)
	(via
		(at 405.440134 -27.729688)
		(size 0.508)
		(drill 0.254)
		(layers "F.Cu" "B.Cu")
		(net "GND")
	)
	(via
		(at 192.850008 -281.649932)
		(size 0.4064)
		(drill 0.2032)
		(layers "F.Cu" "B.Cu")
		(net "GND")
	)
	(via
		(at 343.023444 -348.58579)
		(size 0.4064)
		(drill 0.2032)
		(layers "F.Cu" "B.Cu")
		(net "GND")
	)
	(via
		(at 286.906462 -133.564884)
		(size 0.508)
		(drill 0.254)
		(layers "F.Cu" "B.Cu")
		(net "GND")
	)
	(via
		(at 136.861804 -162.3187)
		(size 0.508)
		(drill 0.254)
		(layers "F.Cu" "B.Cu")
		(net "GND")
	)
	(via
		(at 117.944646 -169.676064)
		(size 0.508)
		(drill 0.254)
		(layers "F.Cu" "B.Cu")
		(net "GND")
	)
	(via
		(at 124.147834 -410.041852)
		(size 0.4572)
		(drill 0.254)
		(layers "F.Cu" "B.Cu")
		(net "GND")
	)
	(via
		(at 19.520154 -56.441848)
		(size 0.508)
		(drill 0.254)
		(layers "F.Cu" "B.Cu")
		(net "GND")
	)
	(via
		(at 199.025002 -299.224954)
		(size 0.4064)
		(drill 0.2032)
		(layers "F.Cu" "B.Cu")
		(net "GND")
	)
	(via
		(at 240.8936 -93.99143)
		(size 0.508)
		(drill 0.254)
		(layers "F.Cu" "B.Cu")
		(net "GND")
	)
	(via
		(at 41.124886 -286.874966)
		(size 0.4064)
		(drill 0.2032)
		(layers "F.Cu" "B.Cu")
		(net "GND")
	)
	(via
		(at 428.84979 -306.349908)
		(size 0.4064)
		(drill 0.2032)
		(layers "F.Cu" "B.Cu")
		(net "GND")
	)
	(via
		(at 169.836592 -348.58579)
		(size 0.4064)
		(drill 0.2032)
		(layers "F.Cu" "B.Cu")
		(net "GND")
	)
	(via
		(at 180.848 -417.82492)
		(size 0.508)
		(drill 0.254)
		(layers "F.Cu" "B.Cu")
		(net "GND")
	)
	(via
		(at 190.060326 -20.35556)
		(size 0.508)
		(drill 0.254)
		(layers "F.Cu" "B.Cu")
		(net "GND")
	)
	(via
		(at 257.133852 -353.465638)
		(size 0.508)
		(drill 0.254)
		(layers "F.Cu" "B.Cu")
		(net "GND")
	)
	(via
		(at 46.34992 -280.699718)
		(size 0.4064)
		(drill 0.2032)
		(layers "F.Cu" "B.Cu")
		(net "GND")
	)
	(via
		(at 165.774878 -287.824926)
		(size 0.4064)
		(drill 0.2032)
		(layers "F.Cu" "B.Cu")
		(net "GND")
	)
	(via
		(at 281.394154 -347.951806)
		(size 0.4572)
		(drill 0.254)
		(layers "F.Cu" "B.Cu")
		(net "GND")
	)
	(via
		(at 427.623224 -51.019456)
		(size 0.508)
		(drill 0.254)
		(layers "F.Cu" "B.Cu")
		(net "GND")
	)
	(via
		(at 273.324828 -276.424898)
		(size 0.4064)
		(drill 0.2032)
		(layers "F.Cu" "B.Cu")
		(net "GND")
	)
	(via
		(at 92.248736 -27.79014)
		(size 0.508)
		(drill 0.254)
		(layers "F.Cu" "B.Cu")
		(net "GND")
	)
	(via
		(at 333.539846 -74.58583)
		(size 0.508)
		(drill 0.254)
		(layers "F.Cu" "B.Cu")
		(net "GND")
	)
	(via
		(at 27.347926 -376.241818)
		(size 0.508)
		(drill 0.254)
		(layers "F.Cu" "B.Cu")
		(net "GND")
	)
	(via
		(at 70.582028 -58.873644)
		(size 0.508)
		(drill 0.254)
		(layers "F.Cu" "B.Cu")
		(net "GND")
	)
	(via
		(at 274.274788 -286.874966)
		(size 0.4064)
		(drill 0.2032)
		(layers "F.Cu" "B.Cu")
		(net "GND")
	)
	(via
		(at 278.549862 -281.649932)
		(size 0.4064)
		(drill 0.2032)
		(layers "F.Cu" "B.Cu")
		(net "GND")
	)
	(via
		(at 93.894402 -354.732082)
		(size 0.4064)
		(drill 0.2032)
		(layers "F.Cu" "B.Cu")
		(net "GND")
	)
	(via
		(at 62.433454 -346.09913)
		(size 0.4572)
		(drill 0.254)
		(layers "F.Cu" "B.Cu")
		(net "GND")
	)
	(via
		(at 65.335404 -79.268574)
		(size 0.508)
		(drill 0.254)
		(layers "F.Cu" "B.Cu")
		(net "GND")
	)
	(via
		(at 75.74788 -375.040144)
		(size 0.508)
		(drill 0.254)
		(layers "F.Cu" "B.Cu")
		(net "GND")
	)
	(via
		(at 50.14976 -276.899878)
		(size 0.4064)
		(drill 0.2032)
		(layers "F.Cu" "B.Cu")
		(net "GND")
	)
	(via
		(at 109.409738 -77.969364)
		(size 0.508)
		(drill 0.254)
		(layers "F.Cu" "B.Cu")
		(net "GND")
	)
	(via
		(at 430.508156 -52.536852)
		(size 0.508)
		(drill 0.254)
		(layers "F.Cu" "B.Cu")
		(net "GND")
	)
	(via
		(at 161.15157 -122.355102)
		(size 0.508)
		(drill 0.254)
		(layers "F.Cu" "B.Cu")
		(net "GND")
	)
	(via
		(at 303.724818 -299.224954)
		(size 0.4064)
		(drill 0.2032)
		(layers "F.Cu" "B.Cu")
		(net "GND")
	)
	(via
		(at 410.324808 -284.974792)
		(size 0.4064)
		(drill 0.2032)
		(layers "F.Cu" "B.Cu")
		(net "GND")
	)
	(via
		(at 387.793992 -350.977454)
		(size 0.4572)
		(drill 0.254)
		(layers "F.Cu" "B.Cu")
		(net "GND")
	)
	(via
		(at 82.93735 -349.219774)
		(size 0.4572)
		(drill 0.254)
		(layers "F.Cu" "B.Cu")
		(net "GND")
	)
	(via
		(at 420.787576 -26.360882)
		(size 0.508)
		(drill 0.254)
		(layers "F.Cu" "B.Cu")
		(net "GND")
	)
	(via
		(at 288.99993 -313.949842)
		(size 0.4064)
		(drill 0.2032)
		(layers "F.Cu" "B.Cu")
		(net "GND")
	)
	(via
		(at 153.42489 -278.324818)
		(size 0.4064)
		(drill 0.2032)
		(layers "F.Cu" "B.Cu")
		(net "GND")
	)
	(via
		(at 317.008256 -155.024582)
		(size 0.508)
		(drill 0.254)
		(layers "F.Cu" "B.Cu")
		(net "GND")
	)
	(via
		(at 269.524734 -278.324818)
		(size 0.4064)
		(drill 0.2032)
		(layers "F.Cu" "B.Cu")
		(net "GND")
	)
	(via
		(at 218.075002 -74.58583)
		(size 0.508)
		(drill 0.254)
		(layers "F.Cu" "B.Cu")
		(net "GND")
	)
	(via
		(at 157.699964 -304.449734)
		(size 0.4064)
		(drill 0.2032)
		(layers "F.Cu" "B.Cu")
		(net "GND")
	)
	(via
		(at 358.14 -179.07)
		(size 0.508)
		(drill 0.254)
		(layers "F.Cu" "B.Cu")
		(net "GND")
	)
	(via
		(at 297.074844 -300.174914)
		(size 0.4064)
		(drill 0.2032)
		(layers "F.Cu" "B.Cu")
		(net "GND")
	)
	(via
		(at 296.938954 -354.074222)
		(size 0.4572)
		(drill 0.254)
		(layers "F.Cu" "B.Cu")
		(net "GND")
	)
	(via
		(at 422.548304 -129.445004)
		(size 0.508)
		(drill 0.254)
		(layers "F.Cu" "B.Cu")
		(net "GND")
	)
	(via
		(at 340.285832 -357.123746)
		(size 0.4572)
		(drill 0.254)
		(layers "F.Cu" "B.Cu")
		(net "GND")
	)
	(via
		(at 92.26423 -358.391714)
		(size 0.4572)
		(drill 0.254)
		(layers "F.Cu" "B.Cu")
		(net "GND")
	)
	(via
		(at 77.69987 -314.899802)
		(size 0.4064)
		(drill 0.2032)
		(layers "F.Cu" "B.Cu")
		(net "GND")
	)
	(via
		(at 36.849812 -305.399948)
		(size 0.4064)
		(drill 0.2032)
		(layers "F.Cu" "B.Cu")
		(net "GND")
	)
	(via
		(at 54.424834 -298.27474)
		(size 0.4064)
		(drill 0.2032)
		(layers "F.Cu" "B.Cu")
		(net "GND")
	)
	(via
		(at 421.724836 -304.924714)
		(size 0.4064)
		(drill 0.2032)
		(layers "F.Cu" "B.Cu")
		(net "GND")
	)
	(via
		(at 108.904786 -221.671134)
		(size 0.508)
		(drill 0.254)
		(layers "F.Cu" "B.Cu")
		(net "GND")
	)
	(via
		(at 422.199816 -277.849838)
		(size 0.4064)
		(drill 0.2032)
		(layers "F.Cu" "B.Cu")
		(net "GND")
	)
	(via
		(at 113.976404 -166.570152)
		(size 0.508)
		(drill 0.254)
		(layers "F.Cu" "B.Cu")
		(net "GND")
	)
	(via
		(at 402.249894 -275.949918)
		(size 0.4064)
		(drill 0.2032)
		(layers "F.Cu" "B.Cu")
		(net "GND")
	)
	(via
		(at 21.009356 -171.375578)
		(size 0.508)
		(drill 0.254)
		(layers "F.Cu" "B.Cu")
		(net "GND")
	)
	(via
		(at 163.41344 -29.859478)
		(size 0.508)
		(drill 0.254)
		(layers "F.Cu" "B.Cu")
		(net "GND")
	)
	(via
		(at 290.89985 -274.049744)
		(size 0.4064)
		(drill 0.2032)
		(layers "F.Cu" "B.Cu")
		(net "GND")
	)
	(via
		(at 63.912242 -351.611438)
		(size 0.4064)
		(drill 0.2032)
		(layers "F.Cu" "B.Cu")
		(net "GND")
	)
	(via
		(at 128.547622 -406.141936)
		(size 0.4572)
		(drill 0.254)
		(layers "F.Cu" "B.Cu")
		(net "GND")
	)
	(via
		(at 164.645594 -153.0096)
		(size 0.508)
		(drill 0.254)
		(layers "F.Cu" "B.Cu")
		(net "GND")
	)
	(via
		(at 243.198396 -194.164204)
		(size 0.508)
		(drill 0.254)
		(layers "F.Cu" "B.Cu")
		(net "GND")
	)
	(via
		(at 98.461576 -330.730606)
		(size 0.508)
		(drill 0.254)
		(layers "F.Cu" "B.Cu")
		(net "GND")
	)
	(via
		(at 316.800738 -34.990278)
		(size 0.508)
		(drill 0.254)
		(layers "F.Cu" "B.Cu")
		(net "GND")
	)
	(via
		(at 64.399922 -312.999882)
		(size 0.4064)
		(drill 0.2032)
		(layers "F.Cu" "B.Cu")
		(net "GND")
	)
	(via
		(at 45.051726 -113.245138)
		(size 0.508)
		(drill 0.254)
		(layers "F.Cu" "B.Cu")
		(net "GND")
	)
	(via
		(at 280.449782 -275.949918)
		(size 0.4064)
		(drill 0.2032)
		(layers "F.Cu" "B.Cu")
		(net "GND")
	)
	(via
		(at 276.871176 -28.05303)
		(size 0.508)
		(drill 0.254)
		(layers "F.Cu" "B.Cu")
		(net "GND")
	)
	(via
		(at 315.60008 -274.999958)
		(size 0.4064)
		(drill 0.2032)
		(layers "F.Cu" "B.Cu")
		(net "GND")
	)
	(via
		(at 337.176872 -354.098098)
		(size 0.4572)
		(drill 0.254)
		(layers "F.Cu" "B.Cu")
		(net "GND")
	)
	(via
		(at 3.65125 -394.492734)
		(size 0.508)
		(drill 0.254)
		(layers "F.Cu" "B.Cu")
		(net "GND")
	)
	(via
		(at 169.423334 -56.353456)
		(size 0.508)
		(drill 0.254)
		(layers "F.Cu" "B.Cu")
		(net "GND")
	)
	(via
		(at 446.972944 -23.880318)
		(size 0.508)
		(drill 0.254)
		(layers "F.Cu" "B.Cu")
		(net "GND")
	)
	(via
		(at 424.64228 -346.09913)
		(size 0.4572)
		(drill 0.254)
		(layers "F.Cu" "B.Cu")
		(net "GND")
	)
	(via
		(at 56.799988 -274.049744)
		(size 0.4064)
		(drill 0.2032)
		(layers "F.Cu" "B.Cu")
		(net "GND")
	)
	(via
		(at 248.51995 -131.312666)
		(size 0.508)
		(drill 0.254)
		(layers "F.Cu" "B.Cu")
		(net "GND")
	)
	(via
		(at 45.39996 -277.849838)
		(size 0.4064)
		(drill 0.2032)
		(layers "F.Cu" "B.Cu")
		(net "GND")
	)
	(via
		(at 315.124846 -289.724846)
		(size 0.4064)
		(drill 0.2032)
		(layers "F.Cu" "B.Cu")
		(net "GND")
	)
	(via
		(at 311.324752 -302.074834)
		(size 0.4064)
		(drill 0.2032)
		(layers "F.Cu" "B.Cu")
		(net "GND")
	)
	(via
		(at 310.624982 -14.100302)
		(size 0.508)
		(drill 0.254)
		(layers "F.Cu" "B.Cu")
		(net "GND")
	)
	(via
		(at 158.87954 -358.391714)
		(size 0.4572)
		(drill 0.254)
		(layers "F.Cu" "B.Cu")
		(net "GND")
	)
	(via
		(at 426.94987 -308.249828)
		(size 0.4064)
		(drill 0.2032)
		(layers "F.Cu" "B.Cu")
		(net "GND")
	)
	(via
		(at 38.275006 -275.474938)
		(size 0.4064)
		(drill 0.2032)
		(layers "F.Cu" "B.Cu")
		(net "GND")
	)
	(via
		(at 302.299878 -276.899878)
		(size 0.4064)
		(drill 0.2032)
		(layers "F.Cu" "B.Cu")
		(net "GND")
	)
	(via
		(at 304.197766 -133.472682)
		(size 0.508)
		(drill 0.254)
		(layers "F.Cu" "B.Cu")
		(net "GND")
	)
	(via
		(at 352.24212 -49.574704)
		(size 0.508)
		(drill 0.254)
		(layers "F.Cu" "B.Cu")
		(net "GND")
	)
	(via
		(at 205.780894 -25.990042)
		(size 0.508)
		(drill 0.254)
		(layers "F.Cu" "B.Cu")
		(net "GND")
	)
	(via
		(at 22.581362 -31.118302)
		(size 0.508)
		(drill 0.254)
		(layers "F.Cu" "B.Cu")
		(net "GND")
	)
	(via
		(at 313.602624 -89.790524)
		(size 0.508)
		(drill 0.254)
		(layers "F.Cu" "B.Cu")
		(net "GND")
	)
	(via
		(at 212.149944 -135.426196)
		(size 0.508)
		(drill 0.254)
		(layers "F.Cu" "B.Cu")
		(net "GND")
	)
	(via
		(at 382.30302 -287.093914)
		(size 0.508)
		(drill 0.254)
		(layers "F.Cu" "B.Cu")
		(net "GND")
	)
	(via
		(at 359.535476 -288.78149)
		(size 0.508)
		(drill 0.254)
		(layers "F.Cu" "B.Cu")
		(net "GND")
	)
	(via
		(at 54.424834 -284.974792)
		(size 0.4064)
		(drill 0.2032)
		(layers "F.Cu" "B.Cu")
		(net "GND")
	)
	(via
		(at 119.14124 -346.09913)
		(size 0.4572)
		(drill 0.254)
		(layers "F.Cu" "B.Cu")
		(net "GND")
	)
	(via
		(at 315.740288 -144.224502)
		(size 0.508)
		(drill 0.254)
		(layers "F.Cu" "B.Cu")
		(net "GND")
	)
	(via
		(at 140.90396 -349.219774)
		(size 0.4572)
		(drill 0.254)
		(layers "F.Cu" "B.Cu")
		(net "GND")
	)
	(via
		(at 410.324808 -307.774848)
		(size 0.4064)
		(drill 0.2032)
		(layers "F.Cu" "B.Cu")
		(net "GND")
	)
	(via
		(at 394.64996 -276.899878)
		(size 0.4064)
		(drill 0.2032)
		(layers "F.Cu" "B.Cu")
		(net "GND")
	)
	(via
		(at 298.974764 -302.074834)
		(size 0.4064)
		(drill 0.2032)
		(layers "F.Cu" "B.Cu")
		(net "GND")
	)
	(via
		(at 166.727632 -357.75773)
		(size 0.4064)
		(drill 0.2032)
		(layers "F.Cu" "B.Cu")
		(net "GND")
	)
	(via
		(at 42.15638 -358.391714)
		(size 0.4572)
		(drill 0.254)
		(layers "F.Cu" "B.Cu")
		(net "GND")
	)
	(via
		(at 75.440794 -45.853858)
		(size 0.508)
		(drill 0.254)
		(layers "F.Cu" "B.Cu")
		(net "GND")
	)
	(via
		(at 84.54771 -378.94006)
		(size 0.508)
		(drill 0.254)
		(layers "F.Cu" "B.Cu")
		(net "GND")
	)
	(via
		(at 95.622618 -23.880318)
		(size 0.508)
		(drill 0.254)
		(layers "F.Cu" "B.Cu")
		(net "GND")
	)
	(via
		(at 344.893646 -221.186756)
		(size 0.4572)
		(drill 0.254)
		(layers "F.Cu" "B.Cu")
		(net "GND")
	)
	(via
		(at 198.26605 -149.617938)
		(size 0.508)
		(drill 0.254)
		(layers "F.Cu" "B.Cu")
		(net "GND")
	)
	(via
		(at 0.766318 -72.332342)
		(size 0.508)
		(drill 0.254)
		(layers "F.Cu" "B.Cu")
		(net "GND")
	)
	(via
		(at 254.719836 -197.458076)
		(size 0.508)
		(drill 0.254)
		(layers "F.Cu" "B.Cu")
		(net "GND")
	)
	(via
		(at 259.936742 -15.474188)
		(size 0.508)
		(drill 0.254)
		(layers "F.Cu" "B.Cu")
		(net "GND")
	)
	(via
		(at 423.32783 -380.141734)
		(size 0.508)
		(drill 0.254)
		(layers "F.Cu" "B.Cu")
		(net "GND")
	)
	(via
		(at 381.94742 -351.611438)
		(size 0.4064)
		(drill 0.2032)
		(layers "F.Cu" "B.Cu")
		(net "GND")
	)
	(via
		(at 177.5333 -346.09913)
		(size 0.4572)
		(drill 0.254)
		(layers "F.Cu" "B.Cu")
		(net "GND")
	)
	(via
		(at 55.849774 -310.149748)
		(size 0.4064)
		(drill 0.2032)
		(layers "F.Cu" "B.Cu")
		(net "GND")
	)
	(via
		(at 360.86796 -255.210564)
		(size 0.508)
		(drill 0.254)
		(layers "F.Cu" "B.Cu")
		(net "GND")
	)
	(via
		(at 411.835092 -354.732082)
		(size 0.4064)
		(drill 0.2032)
		(layers "F.Cu" "B.Cu")
		(net "GND")
	)
	(via
		(at 38.347904 -385.141978)
		(size 0.508)
		(drill 0.254)
		(layers "F.Cu" "B.Cu")
		(net "GND")
	)
	(via
		(at 297.927776 -382.73863)
		(size 0.508)
		(drill 0.254)
		(layers "F.Cu" "B.Cu")
		(net "GND")
	)
	(via
		(at 51.099974 -318.699896)
		(size 0.4064)
		(drill 0.2032)
		(layers "F.Cu" "B.Cu")
		(net "GND")
	)
	(via
		(at 303.724818 -303.974754)
		(size 0.4064)
		(drill 0.2032)
		(layers "F.Cu" "B.Cu")
		(net "GND")
	)
	(via
		(at 117.547644 -404.838662)
		(size 0.508)
		(drill 0.254)
		(layers "F.Cu" "B.Cu")
		(net "GND")
	)
	(via
		(at 433.403248 -60.627006)
		(size 0.508)
		(drill 0.254)
		(layers "F.Cu" "B.Cu")
		(net "GND")
	)
	(via
		(at 73.547732 -397.038576)
		(size 0.508)
		(drill 0.254)
		(layers "F.Cu" "B.Cu")
		(net "GND")
	)
	(via
		(at 456.338178 -304.827432)
		(size 0.508)
		(drill 0.254)
		(layers "F.Cu" "B.Cu")
		(net "GND")
	)
	(via
		(at 104.293162 -169.68724)
		(size 0.508)
		(drill 0.254)
		(layers "F.Cu" "B.Cu")
		(net "GND")
	)
	(via
		(at 43.499786 -278.799798)
		(size 0.4064)
		(drill 0.2032)
		(layers "F.Cu" "B.Cu")
		(net "GND")
	)
	(via
		(at 71.068184 -48.753014)
		(size 0.508)
		(drill 0.254)
		(layers "F.Cu" "B.Cu")
		(net "GND")
	)
	(via
		(at 51.74996 -144.885156)
		(size 0.508)
		(drill 0.254)
		(layers "F.Cu" "B.Cu")
		(net "GND")
	)
	(via
		(at 272.374868 -275.474938)
		(size 0.4064)
		(drill 0.2032)
		(layers "F.Cu" "B.Cu")
		(net "GND")
	)
	(via
		(at 232.231946 -286.889952)
		(size 0.508)
		(drill 0.254)
		(layers "F.Cu" "B.Cu")
		(net "GND")
	)
	(via
		(at 187.149994 -275.949918)
		(size 0.4064)
		(drill 0.2032)
		(layers "F.Cu" "B.Cu")
		(net "GND")
	)
	(via
		(at 271.000982 -264.304018)
		(size 0.508)
		(drill 0.254)
		(layers "F.Cu" "B.Cu")
		(net "GND")
	)
	(via
		(at 57.749948 -314.899802)
		(size 0.4064)
		(drill 0.2032)
		(layers "F.Cu" "B.Cu")
		(net "GND")
	)
	(via
		(at 49.67478 -288.774886)
		(size 0.4064)
		(drill 0.2032)
		(layers "F.Cu" "B.Cu")
		(net "GND")
	)
	(via
		(at 33.947862 -399.441924)
		(size 0.508)
		(drill 0.254)
		(layers "F.Cu" "B.Cu")
		(net "GND")
	)
	(via
		(at 121.947686 -383.940304)
		(size 0.4572)
		(drill 0.254)
		(layers "F.Cu" "B.Cu")
		(net "GND")
	)
	(via
		(at 35.759644 -104.523286)
		(size 0.508)
		(drill 0.254)
		(layers "F.Cu" "B.Cu")
		(net "GND")
	)
	(via
		(at 198.550022 -312.999882)
		(size 0.4064)
		(drill 0.2032)
		(layers "F.Cu" "B.Cu")
		(net "GND")
	)
	(via
		(at 178.124866 -306.824888)
		(size 0.4064)
		(drill 0.2032)
		(layers "F.Cu" "B.Cu")
		(net "GND")
	)
	(via
		(at 158.174944 -299.2247)
		(size 0.4064)
		(drill 0.2032)
		(layers "F.Cu" "B.Cu")
		(net "GND")
	)
	(via
		(at 340.194646 -279.086818)
		(size 0.508)
		(drill 0.254)
		(layers "F.Cu" "B.Cu")
		(net "GND")
	)
	(via
		(at 431.700178 -316.799722)
		(size 0.4064)
		(drill 0.2032)
		(layers "F.Cu" "B.Cu")
		(net "GND")
	)
	(via
		(at 270.949928 -308.249828)
		(size 0.4064)
		(drill 0.2032)
		(layers "F.Cu" "B.Cu")
		(net "GND")
	)
	(via
		(at 298.417742 -345.465146)
		(size 0.4064)
		(drill 0.2032)
		(layers "F.Cu" "B.Cu")
		(net "GND")
	)
	(via
		(at 228.667818 -217.104468)
		(size 0.4572)
		(drill 0.254)
		(layers "F.Cu" "B.Cu")
		(net "GND")
	)
	(via
		(at 286.624776 -287.824926)
		(size 0.4064)
		(drill 0.2032)
		(layers "F.Cu" "B.Cu")
		(net "GND")
	)
	(via
		(at 69.022722 -357.75773)
		(size 0.4064)
		(drill 0.2032)
		(layers "F.Cu" "B.Cu")
		(net "GND")
	)
	(via
		(at 180.270912 -357.75773)
		(size 0.4064)
		(drill 0.2032)
		(layers "F.Cu" "B.Cu")
		(net "GND")
	)
	(via
		(at 40.547798 -404.940262)
		(size 0.508)
		(drill 0.254)
		(layers "F.Cu" "B.Cu")
		(net "GND")
	)
	(via
		(at 180.975 -300.174914)
		(size 0.4064)
		(drill 0.2032)
		(layers "F.Cu" "B.Cu")
		(net "GND")
	)
	(via
		(at 275.673312 -73.20026)
		(size 0.508)
		(drill 0.254)
		(layers "F.Cu" "B.Cu")
		(net "GND")
	)
	(via
		(at 74.84999 -312.049922)
		(size 0.4064)
		(drill 0.2032)
		(layers "F.Cu" "B.Cu")
		(net "GND")
	)
	(via
		(at 377.12777 -402.140166)
		(size 0.508)
		(drill 0.254)
		(layers "F.Cu" "B.Cu")
		(net "GND")
	)
	(via
		(at 74.581258 -34.718498)
		(size 0.508)
		(drill 0.254)
		(layers "F.Cu" "B.Cu")
		(net "GND")
	)
	(via
		(at 413.174942 -298.27474)
		(size 0.4064)
		(drill 0.2032)
		(layers "F.Cu" "B.Cu")
		(net "GND")
	)
	(via
		(at 67.39255 -358.391714)
		(size 0.4572)
		(drill 0.254)
		(layers "F.Cu" "B.Cu")
		(net "GND")
	)
	(via
		(at 329.268074 -48.753014)
		(size 0.508)
		(drill 0.254)
		(layers "F.Cu" "B.Cu")
		(net "GND")
	)
	(via
		(at 66.774822 -284.974792)
		(size 0.4064)
		(drill 0.2032)
		(layers "F.Cu" "B.Cu")
		(net "GND")
	)
	(via
		(at 154.37485 -297.32478)
		(size 0.4064)
		(drill 0.2032)
		(layers "F.Cu" "B.Cu")
		(net "GND")
	)
	(via
		(at 116.03228 -350.977454)
		(size 0.4572)
		(drill 0.254)
		(layers "F.Cu" "B.Cu")
		(net "GND")
	)
	(via
		(at 293.27475 -300.174914)
		(size 0.4064)
		(drill 0.2032)
		(layers "F.Cu" "B.Cu")
		(net "GND")
	)
	(via
		(at 59.649868 -276.899878)
		(size 0.4064)
		(drill 0.2032)
		(layers "F.Cu" "B.Cu")
		(net "GND")
	)
	(via
		(at 174.325026 -300.174914)
		(size 0.4064)
		(drill 0.2032)
		(layers "F.Cu" "B.Cu")
		(net "GND")
	)
	(via
		(at 417.450016 -310.149748)
		(size 0.4064)
		(drill 0.2032)
		(layers "F.Cu" "B.Cu")
		(net "GND")
	)
	(via
		(at 68.280788 -25.990042)
		(size 0.508)
		(drill 0.254)
		(layers "F.Cu" "B.Cu")
		(net "GND")
	)
	(via
		(at 167.675052 -285.924752)
		(size 0.4064)
		(drill 0.2032)
		(layers "F.Cu" "B.Cu")
		(net "GND")
	)
	(via
		(at 299.101764 -197.748906)
		(size 0.508)
		(drill 0.254)
		(layers "F.Cu" "B.Cu")
		(net "GND")
	)
	(via
		(at 184.29986 -281.649932)
		(size 0.4064)
		(drill 0.2032)
		(layers "F.Cu" "B.Cu")
		(net "GND")
	)
	(via
		(at 67.39255 -352.245422)
		(size 0.4572)
		(drill 0.254)
		(layers "F.Cu" "B.Cu")
		(net "GND")
	)
	(via
		(at 374.099328 -343.073482)
		(size 0.4572)
		(drill 0.254)
		(layers "F.Cu" "B.Cu")
		(net "GND")
	)
	(via
		(at 406.049988 -311.099962)
		(size 0.4064)
		(drill 0.2032)
		(layers "F.Cu" "B.Cu")
		(net "GND")
	)
	(via
		(at 387.087364 -248.991374)
		(size 0.508)
		(drill 0.254)
		(layers "F.Cu" "B.Cu")
		(net "GND")
	)
	(via
		(at 306.574698 -292.574726)
		(size 0.4064)
		(drill 0.2032)
		(layers "F.Cu" "B.Cu")
		(net "GND")
	)
	(via
		(at 392.52779 -408.840178)
		(size 0.508)
		(drill 0.254)
		(layers "F.Cu" "B.Cu")
		(net "GND")
	)
	(via
		(at 199.547988 -64.312292)
		(size 0.508)
		(drill 0.254)
		(layers "F.Cu" "B.Cu")
		(net "GND")
	)
	(via
		(at 107.983274 -286.842454)
		(size 0.508)
		(drill 0.254)
		(layers "F.Cu" "B.Cu")
		(net "GND")
	)
	(via
		(at 294.22471 -303.974754)
		(size 0.4064)
		(drill 0.2032)
		(layers "F.Cu" "B.Cu")
		(net "GND")
	)
	(via
		(at 304.527712 -380.141988)
		(size 0.508)
		(drill 0.254)
		(layers "F.Cu" "B.Cu")
		(net "GND")
	)
	(via
		(at 394.38326 -357.75773)
		(size 0.4064)
		(drill 0.2032)
		(layers "F.Cu" "B.Cu")
		(net "GND")
	)
	(via
		(at 315.759846 -288.774886)
		(size 0.4064)
		(drill 0.2032)
		(layers "F.Cu" "B.Cu")
		(net "GND")
	)
	(via
		(at 130.648202 -326.99198)
		(size 0.508)
		(drill 0.254)
		(layers "F.Cu" "B.Cu")
		(net "GND")
	)
	(via
		(at 386.099812 -313.949842)
		(size 0.4064)
		(drill 0.2032)
		(layers "F.Cu" "B.Cu")
		(net "GND")
	)
	(via
		(at 125.170946 -215.007952)
		(size 0.508)
		(drill 0.254)
		(layers "F.Cu" "B.Cu")
		(net "GND")
	)
	(via
		(at 376.858022 -292.732714)
		(size 0.508)
		(drill 0.254)
		(layers "F.Cu" "B.Cu")
		(net "GND")
	)
	(via
		(at 298.499784 -313.949842)
		(size 0.4064)
		(drill 0.2032)
		(layers "F.Cu" "B.Cu")
		(net "GND")
	)
	(via
		(at 73.547732 -383.940304)
		(size 0.508)
		(drill 0.254)
		(layers "F.Cu" "B.Cu")
		(net "GND")
	)
	(via
		(at 400.349974 -312.049922)
		(size 0.4064)
		(drill 0.2032)
		(layers "F.Cu" "B.Cu")
		(net "GND")
	)
	(via
		(at 63.449962 -315.849762)
		(size 0.4064)
		(drill 0.2032)
		(layers "F.Cu" "B.Cu")
		(net "GND")
	)
	(via
		(at 417.984178 -122.597164)
		(size 0.508)
		(drill 0.254)
		(layers "F.Cu" "B.Cu")
		(net "GND")
	)
	(via
		(at 182.87492 -298.27474)
		(size 0.4064)
		(drill 0.2032)
		(layers "F.Cu" "B.Cu")
		(net "GND")
	)
	(via
		(at 278.074882 -292.57498)
		(size 0.4064)
		(drill 0.2032)
		(layers "F.Cu" "B.Cu")
		(net "GND")
	)
	(via
		(at 86.04631 -349.219774)
		(size 0.4572)
		(drill 0.254)
		(layers "F.Cu" "B.Cu")
		(net "GND")
	)
	(via
		(at 405.100028 -314.899802)
		(size 0.4064)
		(drill 0.2032)
		(layers "F.Cu" "B.Cu")
		(net "GND")
	)
	(via
		(at 236.624876 -152.25268)
		(size 0.508)
		(drill 0.254)
		(layers "F.Cu" "B.Cu")
		(net "GND")
	)
	(via
		(at 356.83063 -305.008534)
		(size 0.508)
		(drill 0.254)
		(layers "F.Cu" "B.Cu")
		(net "GND")
	)
	(via
		(at 127.97028 -290.05149)
		(size 0.508)
		(drill 0.254)
		(layers "F.Cu" "B.Cu")
		(net "GND")
	)
	(via
		(at 199.500236 -276.900132)
		(size 0.4064)
		(drill 0.2032)
		(layers "F.Cu" "B.Cu")
		(net "GND")
	)
	(via
		(at 284.503114 -358.391714)
		(size 0.4572)
		(drill 0.254)
		(layers "F.Cu" "B.Cu")
		(net "GND")
	)
	(via
		(at 161.975038 -292.57498)
		(size 0.4064)
		(drill 0.2032)
		(layers "F.Cu" "B.Cu")
		(net "GND")
	)
	(via
		(at 386.575046 -275.474938)
		(size 0.4064)
		(drill 0.2032)
		(layers "F.Cu" "B.Cu")
		(net "GND")
	)
	(via
		(at 382.791716 -131.495546)
		(size 0.508)
		(drill 0.254)
		(layers "F.Cu" "B.Cu")
		(net "GND")
	)
	(via
		(at 215.773 -202.438)
		(size 0.508)
		(drill 0.254)
		(layers "F.Cu" "B.Cu")
		(net "GND")
	)
	(via
		(at 440.219338 -125.414532)
		(size 0.508)
		(drill 0.254)
		(layers "F.Cu" "B.Cu")
		(net "GND")
	)
	(via
		(at 280.160222 -21.37156)
		(size 0.508)
		(drill 0.254)
		(layers "F.Cu" "B.Cu")
		(net "GND")
	)
	(via
		(at 426.94987 -287.349946)
		(size 0.4064)
		(drill 0.2032)
		(layers "F.Cu" "B.Cu")
		(net "GND")
	)
	(via
		(at 302.327818 -374.938544)
		(size 0.508)
		(drill 0.254)
		(layers "F.Cu" "B.Cu")
		(net "GND")
	)
	(via
		(at 285.674816 -300.174914)
		(size 0.4064)
		(drill 0.2032)
		(layers "F.Cu" "B.Cu")
		(net "GND")
	)
	(via
		(at 258.14528 -210.434174)
		(size 0.508)
		(drill 0.254)
		(layers "F.Cu" "B.Cu")
		(net "GND")
	)
	(via
		(at 315.124846 -299.224954)
		(size 0.4064)
		(drill 0.2032)
		(layers "F.Cu" "B.Cu")
		(net "GND")
	)
	(via
		(at 269.333726 -109.916722)
		(size 0.508)
		(drill 0.254)
		(layers "F.Cu" "B.Cu")
		(net "GND")
	)
	(via
		(at 167.835072 -357.75773)
		(size 0.4064)
		(drill 0.2032)
		(layers "F.Cu" "B.Cu")
		(net "GND")
	)
	(via
		(at 28.568396 -181.94401)
		(size 0.508)
		(drill 0.254)
		(layers "F.Cu" "B.Cu")
		(net "GND")
	)
	(via
		(at 4.65328 -49.574704)
		(size 0.508)
		(drill 0.254)
		(layers "F.Cu" "B.Cu")
		(net "GND")
	)
	(via
		(at 66.774822 -298.27474)
		(size 0.4064)
		(drill 0.2032)
		(layers "F.Cu" "B.Cu")
		(net "GND")
	)
	(via
		(at 106.217974 -282.910788)
		(size 0.49022)
		(drill 0.254)
		(layers "F.Cu" "B.Cu")
		(net "GND")
	)
	(via
		(at 82.347816 -378.83846)
		(size 0.508)
		(drill 0.254)
		(layers "F.Cu" "B.Cu")
		(net "GND")
	)
	(via
		(at 70.574916 -301.124874)
		(size 0.4064)
		(drill 0.2032)
		(layers "F.Cu" "B.Cu")
		(net "GND")
	)
	(via
		(at 433.96916 -350.977454)
		(size 0.4572)
		(drill 0.254)
		(layers "F.Cu" "B.Cu")
		(net "GND")
	)
	(via
		(at 365.476028 -145.501868)
		(size 0.508)
		(drill 0.254)
		(layers "F.Cu" "B.Cu")
		(net "GND")
	)
	(via
		(at 0.77089 -390.661144)
		(size 0.508)
		(drill 0.254)
		(layers "F.Cu" "B.Cu")
		(net "GND")
	)
	(via
		(at 133.427216 -357.123746)
		(size 0.4572)
		(drill 0.254)
		(layers "F.Cu" "B.Cu")
		(net "GND")
	)
	(via
		(at 425.99991 -314.899802)
		(size 0.4064)
		(drill 0.2032)
		(layers "F.Cu" "B.Cu")
		(net "GND")
	)
	(via
		(at 273.799808 -312.999882)
		(size 0.4064)
		(drill 0.2032)
		(layers "F.Cu" "B.Cu")
		(net "GND")
	)
	(via
		(at 217.440002 -74.58583)
		(size 0.508)
		(drill 0.254)
		(layers "F.Cu" "B.Cu")
		(net "GND")
	)
	(via
		(at 41.124886 -292.57498)
		(size 0.4064)
		(drill 0.2032)
		(layers "F.Cu" "B.Cu")
		(net "GND")
	)
	(via
		(at 4.562856 -180.161692)
		(size 0.508)
		(drill 0.254)
		(layers "F.Cu" "B.Cu")
		(net "GND")
	)
	(via
		(at 122.357896 -99.463606)
		(size 0.508)
		(drill 0.254)
		(layers "F.Cu" "B.Cu")
		(net "GND")
	)
	(via
		(at 240.020094 -34.990278)
		(size 0.508)
		(drill 0.254)
		(layers "F.Cu" "B.Cu")
		(net "GND")
	)
	(via
		(at 154.501596 -103.975408)
		(size 0.508)
		(drill 0.254)
		(layers "F.Cu" "B.Cu")
		(net "GND")
	)
	(via
		(at 238.10214 -27.729688)
		(size 0.508)
		(drill 0.254)
		(layers "F.Cu" "B.Cu")
		(net "GND")
	)
	(via
		(at 302.299878 -318.699896)
		(size 0.4064)
		(drill 0.2032)
		(layers "F.Cu" "B.Cu")
		(net "GND")
	)
	(via
		(at 43.499786 -312.999882)
		(size 0.4064)
		(drill 0.2032)
		(layers "F.Cu" "B.Cu")
		(net "GND")
	)
	(via
		(at 89.15527 -358.391714)
		(size 0.4572)
		(drill 0.254)
		(layers "F.Cu" "B.Cu")
		(net "GND")
	)
	(via
		(at 165.09746 -350.977454)
		(size 0.4572)
		(drill 0.254)
		(layers "F.Cu" "B.Cu")
		(net "GND")
	)
	(via
		(at 418.42436 -346.09913)
		(size 0.4572)
		(drill 0.254)
		(layers "F.Cu" "B.Cu")
		(net "GND")
	)
	(via
		(at 272.414746 -26.171398)
		(size 0.508)
		(drill 0.254)
		(layers "F.Cu" "B.Cu")
		(net "GND")
	)
	(via
		(at 434.327808 -400.938492)
		(size 0.508)
		(drill 0.254)
		(layers "F.Cu" "B.Cu")
		(net "GND")
	)
	(via
		(at 183.3499 -276.899878)
		(size 0.4064)
		(drill 0.2032)
		(layers "F.Cu" "B.Cu")
		(net "GND")
	)
	(via
		(at 332.878684 -103.404416)
		(size 0.508)
		(drill 0.254)
		(layers "F.Cu" "B.Cu")
		(net "GND")
	)
	(via
		(at 47.156116 -140.429488)
		(size 0.508)
		(drill 0.254)
		(layers "F.Cu" "B.Cu")
		(net "GND")
	)
	(via
		(at 226.289362 -119.883428)
		(size 0.508)
		(drill 0.254)
		(layers "F.Cu" "B.Cu")
		(net "GND")
	)
	(via
		(at 212.296248 -60.099194)
		(size 0.508)
		(drill 0.254)
		(layers "F.Cu" "B.Cu")
		(net "GND")
	)
	(via
		(at 44.92498 -284.024832)
		(size 0.4064)
		(drill 0.2032)
		(layers "F.Cu" "B.Cu")
		(net "GND")
	)
	(via
		(at 48.58131 -29.859478)
		(size 0.508)
		(drill 0.254)
		(layers "F.Cu" "B.Cu")
		(net "GND")
	)
	(via
		(at 77.947774 -399.441924)
		(size 0.508)
		(drill 0.254)
		(layers "F.Cu" "B.Cu")
		(net "GND")
	)
	(via
		(at 271.899888 -310.149748)
		(size 0.4064)
		(drill 0.2032)
		(layers "F.Cu" "B.Cu")
		(net "GND")
	)
	(via
		(at 160.549844 -303.499774)
		(size 0.4064)
		(drill 0.2032)
		(layers "F.Cu" "B.Cu")
		(net "GND")
	)
	(via
		(at 44.92498 -283.074872)
		(size 0.4064)
		(drill 0.2032)
		(layers "F.Cu" "B.Cu")
		(net "GND")
	)
	(via
		(at 192.375028 -290.674806)
		(size 0.4064)
		(drill 0.2032)
		(layers "F.Cu" "B.Cu")
		(net "GND")
	)
	(via
		(at 182.547514 -143.955008)
		(size 0.508)
		(drill 0.254)
		(layers "F.Cu" "B.Cu")
		(net "GND")
	)
	(via
		(at 383.72796 -403.738588)
		(size 0.508)
		(drill 0.254)
		(layers "F.Cu" "B.Cu")
		(net "GND")
	)
	(via
		(at 60.599828 -276.899878)
		(size 0.4064)
		(drill 0.2032)
		(layers "F.Cu" "B.Cu")
		(net "GND")
	)
	(via
		(at 189.049914 -315.849762)
		(size 0.4064)
		(drill 0.2032)
		(layers "F.Cu" "B.Cu")
		(net "GND")
	)
	(via
		(at 72.719184 -46.893226)
		(size 0.508)
		(drill 0.254)
		(layers "F.Cu" "B.Cu")
		(net "GND")
	)
	(via
		(at 292.79977 -278.799798)
		(size 0.4064)
		(drill 0.2032)
		(layers "F.Cu" "B.Cu")
		(net "GND")
	)
	(via
		(at 172.547788 -410.041852)
		(size 0.508)
		(drill 0.254)
		(layers "F.Cu" "B.Cu")
		(net "GND")
	)
	(via
		(at 413.649922 -314.899802)
		(size 0.4064)
		(drill 0.2032)
		(layers "F.Cu" "B.Cu")
		(net "GND")
	)
	(via
		(at 394.64996 -309.199788)
		(size 0.4064)
		(drill 0.2032)
		(layers "F.Cu" "B.Cu")
		(net "GND")
	)
	(via
		(at 456.682602 -246.06504)
		(size 0.508)
		(drill 0.254)
		(layers "F.Cu" "B.Cu")
		(net "GND")
	)
	(via
		(at 422.792144 -349.219774)
		(size 0.4572)
		(drill 0.254)
		(layers "F.Cu" "B.Cu")
		(net "GND")
	)
	(via
		(at 435.227984 -347.951806)
		(size 0.4572)
		(drill 0.254)
		(layers "F.Cu" "B.Cu")
		(net "GND")
	)
	(via
		(at 429.800004 -318.699896)
		(size 0.4064)
		(drill 0.2032)
		(layers "F.Cu" "B.Cu")
		(net "GND")
	)
	(via
		(at 303.249838 -279.749758)
		(size 0.4064)
		(drill 0.2032)
		(layers "F.Cu" "B.Cu")
		(net "GND")
	)
	(via
		(at 342.876378 -290.05149)
		(size 0.508)
		(drill 0.254)
		(layers "F.Cu" "B.Cu")
		(net "GND")
	)
	(via
		(at 229.09276 -314.781946)
		(size 0.508)
		(drill 0.254)
		(layers "F.Cu" "B.Cu")
		(net "GND")
	)
	(via
		(at 289.127692 -377.341892)
		(size 0.508)
		(drill 0.254)
		(layers "F.Cu" "B.Cu")
		(net "GND")
	)
	(via
		(at 412.20644 -355.366066)
		(size 0.4572)
		(drill 0.254)
		(layers "F.Cu" "B.Cu")
		(net "GND")
	)
	(via
		(at 174.42434 -344.831162)
		(size 0.4572)
		(drill 0.254)
		(layers "F.Cu" "B.Cu")
		(net "GND")
	)
	(via
		(at 266.020042 -29.590238)
		(size 0.508)
		(drill 0.254)
		(layers "F.Cu" "B.Cu")
		(net "GND")
	)
	(via
		(at 100.630228 -242.787932)
		(size 0.508)
		(drill 0.254)
		(layers "F.Cu" "B.Cu")
		(net "GND")
	)
	(via
		(at 401.570444 -28.802076)
		(size 0.508)
		(drill 0.254)
		(layers "F.Cu" "B.Cu")
		(net "GND")
	)
	(via
		(at 0.766318 -77.412342)
		(size 0.508)
		(drill 0.254)
		(layers "F.Cu" "B.Cu")
		(net "GND")
	)
	(via
		(at 167.732964 -138.964924)
		(size 0.508)
		(drill 0.254)
		(layers "F.Cu" "B.Cu")
		(net "GND")
	)
	(via
		(at 163.390072 -73.85177)
		(size 0.508)
		(drill 0.254)
		(layers "F.Cu" "B.Cu")
		(net "GND")
	)
	(via
		(at 166.486586 -48.874934)
		(size 0.508)
		(drill 0.254)
		(layers "F.Cu" "B.Cu")
		(net "GND")
	)
	(via
		(at 295.727882 -408.840178)
		(size 0.508)
		(drill 0.254)
		(layers "F.Cu" "B.Cu")
		(net "GND")
	)
	(via
		(at 74.849736 -272.14957)
		(size 0.4064)
		(drill 0.2032)
		(layers "F.Cu" "B.Cu")
		(net "GND")
	)
	(via
		(at 249.52325 -134.601966)
		(size 0.508)
		(drill 0.254)
		(layers "F.Cu" "B.Cu")
		(net "GND")
	)
	(via
		(at 432.119024 -343.073482)
		(size 0.4572)
		(drill 0.254)
		(layers "F.Cu" "B.Cu")
		(net "GND")
	)
	(via
		(at 103.023162 -172.22724)
		(size 0.508)
		(drill 0.254)
		(layers "F.Cu" "B.Cu")
		(net "GND")
	)
	(via
		(at 81.024984 -291.624766)
		(size 0.4064)
		(drill 0.2032)
		(layers "F.Cu" "B.Cu")
		(net "GND")
	)
	(via
		(at 182.547514 -151.155146)
		(size 0.508)
		(drill 0.254)
		(layers "F.Cu" "B.Cu")
		(net "GND")
	)
	(via
		(at 258.393438 -286.331914)
		(size 0.508)
		(drill 0.254)
		(layers "F.Cu" "B.Cu")
		(net "GND")
	)
	(via
		(at 420.299896 -281.649932)
		(size 0.4064)
		(drill 0.2032)
		(layers "F.Cu" "B.Cu")
		(net "GND")
	)
	(via
		(at 386.701792 -120.833134)
		(size 0.508)
		(drill 0.254)
		(layers "F.Cu" "B.Cu")
		(net "GND")
	)
	(via
		(at 377.12777 -397.038576)
		(size 0.508)
		(drill 0.254)
		(layers "F.Cu" "B.Cu")
		(net "GND")
	)
	(via
		(at 121.947686 -397.038576)
		(size 0.508)
		(drill 0.254)
		(layers "F.Cu" "B.Cu")
		(net "GND")
	)
	(via
		(at 393.820142 -56.441848)
		(size 0.508)
		(drill 0.254)
		(layers "F.Cu" "B.Cu")
		(net "GND")
	)
	(via
		(at 114.238786 -286.842454)
		(size 0.508)
		(drill 0.254)
		(layers "F.Cu" "B.Cu")
		(net "GND")
	)
	(via
		(at 69.684138 -120.716548)
		(size 0.508)
		(drill 0.254)
		(layers "F.Cu" "B.Cu")
		(net "GND")
	)
	(via
		(at 441.817252 -345.465146)
		(size 0.4064)
		(drill 0.2032)
		(layers "F.Cu" "B.Cu")
		(net "GND")
	)
	(via
		(at 119.747792 -397.140176)
		(size 0.4572)
		(drill 0.254)
		(layers "F.Cu" "B.Cu")
		(net "GND")
	)
	(via
		(at 31.199328 -357.75773)
		(size 0.4064)
		(drill 0.2032)
		(layers "F.Cu" "B.Cu")
		(net "GND")
	)
	(via
		(at 119.0879 -292.781736)
		(size 0.508)
		(drill 0.254)
		(layers "F.Cu" "B.Cu")
		(net "GND")
	)
	(via
		(at 381.527812 -376.140218)
		(size 0.508)
		(drill 0.254)
		(layers "F.Cu" "B.Cu")
		(net "GND")
	)
	(via
		(at 245.342918 -314.781946)
		(size 0.508)
		(drill 0.254)
		(layers "F.Cu" "B.Cu")
		(net "GND")
	)
	(via
		(at 28.090368 -348.58579)
		(size 0.4064)
		(drill 0.2032)
		(layers "F.Cu" "B.Cu")
		(net "GND")
	)
	(via
		(at 173.850046 -312.049922)
		(size 0.4064)
		(drill 0.2032)
		(layers "F.Cu" "B.Cu")
		(net "GND")
	)
	(via
		(at 297.549824 -311.099962)
		(size 0.4064)
		(drill 0.2032)
		(layers "F.Cu" "B.Cu")
		(net "GND")
	)
	(via
		(at 438.708292 -345.465146)
		(size 0.4064)
		(drill 0.2032)
		(layers "F.Cu" "B.Cu")
		(net "GND")
	)
	(via
		(at 282.349702 -274.999958)
		(size 0.4064)
		(drill 0.2032)
		(layers "F.Cu" "B.Cu")
		(net "GND")
	)
	(via
		(at 277.124922 -297.32478)
		(size 0.4064)
		(drill 0.2032)
		(layers "F.Cu" "B.Cu")
		(net "GND")
	)
	(via
		(at 323.858128 -307.235606)
		(size 0.508)
		(drill 0.254)
		(layers "F.Cu" "B.Cu")
		(net "GND")
	)
	(via
		(at 280.298398 -37.201094)
		(size 0.508)
		(drill 0.254)
		(layers "F.Cu" "B.Cu")
		(net "GND")
	)
	(via
		(at 372.249192 -350.977454)
		(size 0.4572)
		(drill 0.254)
		(layers "F.Cu" "B.Cu")
		(net "GND")
	)
	(via
		(at 78.551532 -104.120696)
		(size 0.508)
		(drill 0.254)
		(layers "F.Cu" "B.Cu")
		(net "GND")
	)
	(via
		(at 65.349628 -272.14957)
		(size 0.4064)
		(drill 0.2032)
		(layers "F.Cu" "B.Cu")
		(net "GND")
	)
	(via
		(at 304.467006 -118.234968)
		(size 0.508)
		(drill 0.254)
		(layers "F.Cu" "B.Cu")
		(net "GND")
	)
	(via
		(at 63.924942 -289.724846)
		(size 0.4064)
		(drill 0.2032)
		(layers "F.Cu" "B.Cu")
		(net "GND")
	)
	(via
		(at 294.22471 -305.874928)
		(size 0.4064)
		(drill 0.2032)
		(layers "F.Cu" "B.Cu")
		(net "GND")
	)
	(via
		(at 287.574736 -284.024832)
		(size 0.4064)
		(drill 0.2032)
		(layers "F.Cu" "B.Cu")
		(net "GND")
	)
	(via
		(at 138.166348 -354.732082)
		(size 0.4064)
		(drill 0.2032)
		(layers "F.Cu" "B.Cu")
		(net "GND")
	)
	(via
		(at 413.682942 -34.990024)
		(size 0.508)
		(drill 0.254)
		(layers "F.Cu" "B.Cu")
		(net "GND")
	)
	(via
		(at 391.324846 -276.424898)
		(size 0.4064)
		(drill 0.2032)
		(layers "F.Cu" "B.Cu")
		(net "GND")
	)
	(via
		(at 411.601666 -207.19542)
		(size 0.508)
		(drill 0.254)
		(layers "F.Cu" "B.Cu")
		(net "GND")
	)
	(via
		(at 297.074844 -289.724846)
		(size 0.4064)
		(drill 0.2032)
		(layers "F.Cu" "B.Cu")
		(net "GND")
	)
	(via
		(at 352.508312 -52.536852)
		(size 0.508)
		(drill 0.254)
		(layers "F.Cu" "B.Cu")
		(net "GND")
	)
	(via
		(at 399.93316 -122.355102)
		(size 0.508)
		(drill 0.254)
		(layers "F.Cu" "B.Cu")
		(net "GND")
	)
	(via
		(at 139.507214 -213.712552)
		(size 0.508)
		(drill 0.254)
		(layers "F.Cu" "B.Cu")
		(net "GND")
	)
	(via
		(at 156.275024 -283.074872)
		(size 0.4064)
		(drill 0.2032)
		(layers "F.Cu" "B.Cu")
		(net "GND")
	)
	(via
		(at 372.62054 -351.611438)
		(size 0.4064)
		(drill 0.2032)
		(layers "F.Cu" "B.Cu")
		(net "GND")
	)
	(via
		(at 324.101968 -56.826404)
		(size 0.508)
		(drill 0.254)
		(layers "F.Cu" "B.Cu")
		(net "GND")
	)
	(via
		(at 175.920146 -31.390336)
		(size 0.508)
		(drill 0.254)
		(layers "F.Cu" "B.Cu")
		(net "GND")
	)
	(via
		(at 19.820382 -121.560844)
		(size 0.508)
		(drill 0.254)
		(layers "F.Cu" "B.Cu")
		(net "GND")
	)
	(via
		(at 72.949816 -311.099962)
		(size 0.4064)
		(drill 0.2032)
		(layers "F.Cu" "B.Cu")
		(net "GND")
	)
	(via
		(at 40.547798 -375.040144)
		(size 0.508)
		(drill 0.254)
		(layers "F.Cu" "B.Cu")
		(net "GND")
	)
	(via
		(at 269.049754 -307.299868)
		(size 0.4064)
		(drill 0.2032)
		(layers "F.Cu" "B.Cu")
		(net "GND")
	)
	(via
		(at 79.457042 -348.58579)
		(size 0.4064)
		(drill 0.2032)
		(layers "F.Cu" "B.Cu")
		(net "GND")
	)
	(via
		(at 104.003094 -398.66824)
		(size 0.508)
		(drill 0.254)
		(layers "F.Cu" "B.Cu")
		(net "GND")
	)
	(via
		(at 34.491676 -123.885452)
		(size 0.508)
		(drill 0.254)
		(layers "F.Cu" "B.Cu")
		(net "GND")
	)
	(via
		(at 163.747958 -407.638504)
		(size 0.508)
		(drill 0.254)
		(layers "F.Cu" "B.Cu")
		(net "GND")
	)
	(via
		(at 162.924998 -303.974754)
		(size 0.4064)
		(drill 0.2032)
		(layers "F.Cu" "B.Cu")
		(net "GND")
	)
	(via
		(at 327.69937 -57.439814)
		(size 0.508)
		(drill 0.254)
		(layers "F.Cu" "B.Cu")
		(net "GND")
	)
	(via
		(at 3.594608 -282.354782)
		(size 0.508)
		(drill 0.254)
		(layers "F.Cu" "B.Cu")
		(net "GND")
	)
	(via
		(at 169.836592 -357.75773)
		(size 0.4064)
		(drill 0.2032)
		(layers "F.Cu" "B.Cu")
		(net "GND")
	)
	(via
		(at 182.39994 -278.799798)
		(size 0.4064)
		(drill 0.2032)
		(layers "F.Cu" "B.Cu")
		(net "GND")
	)
	(via
		(at 71.760334 -346.09913)
		(size 0.4572)
		(drill 0.254)
		(layers "F.Cu" "B.Cu")
		(net "GND")
	)
	(via
		(at 392.753088 -341.805514)
		(size 0.4572)
		(drill 0.254)
		(layers "F.Cu" "B.Cu")
		(net "GND")
	)
	(via
		(at 463.037682 -103.137462)
		(size 0.508)
		(drill 0.254)
		(layers "F.Cu" "B.Cu")
		(net "GND")
	)
	(via
		(at 388.127748 -408.840178)
		(size 0.508)
		(drill 0.254)
		(layers "F.Cu" "B.Cu")
		(net "GND")
	)
	(via
		(at 277.803102 -402.738082)
		(size 0.508)
		(drill 0.254)
		(layers "F.Cu" "B.Cu")
		(net "GND")
	)
	(via
		(at 298.499784 -318.699896)
		(size 0.4064)
		(drill 0.2032)
		(layers "F.Cu" "B.Cu")
		(net "GND")
	)
	(via
		(at 336.09407 -218.787218)
		(size 0.4572)
		(drill 0.254)
		(layers "F.Cu" "B.Cu")
		(net "GND")
	)
	(via
		(at 190.35141 -47.03191)
		(size 0.508)
		(drill 0.254)
		(layers "F.Cu" "B.Cu")
		(net "GND")
	)
	(via
		(at 272.448782 -31.390082)
		(size 0.508)
		(drill 0.254)
		(layers "F.Cu" "B.Cu")
		(net "GND")
	)
	(via
		(at 174.747936 -406.040336)
		(size 0.508)
		(drill 0.254)
		(layers "F.Cu" "B.Cu")
		(net "GND")
	)
	(via
		(at 11.7983 -20.417536)
		(size 0.508)
		(drill 0.254)
		(layers "F.Cu" "B.Cu")
		(net "GND")
	)
	(via
		(at 145.457926 -25.971246)
		(size 0.508)
		(drill 0.254)
		(layers "F.Cu" "B.Cu")
		(net "GND")
	)
	(via
		(at 295.308782 -345.465146)
		(size 0.4064)
		(drill 0.2032)
		(layers "F.Cu" "B.Cu")
		(net "GND")
	)
	(via
		(at 130.74777 -403.34184)
		(size 0.4572)
		(drill 0.254)
		(layers "F.Cu" "B.Cu")
		(net "GND")
	)
	(via
		(at 299.749972 -111.149892)
		(size 0.508)
		(drill 0.254)
		(layers "F.Cu" "B.Cu")
		(net "GND")
	)
	(via
		(at 388.664196 -243.074444)
		(size 0.508)
		(drill 0.254)
		(layers "F.Cu" "B.Cu")
		(net "GND")
	)
	(via
		(at 424.09999 -277.849838)
		(size 0.4064)
		(drill 0.2032)
		(layers "F.Cu" "B.Cu")
		(net "GND")
	)
	(via
		(at 309.899812 -283.549852)
		(size 0.4064)
		(drill 0.2032)
		(layers "F.Cu" "B.Cu")
		(net "GND")
	)
	(via
		(at 240.0046 -92.3798)
		(size 0.508)
		(drill 0.254)
		(layers "F.Cu" "B.Cu")
		(net "GND")
	)
	(via
		(at 182.87492 -307.774848)
		(size 0.4064)
		(drill 0.2032)
		(layers "F.Cu" "B.Cu")
		(net "GND")
	)
	(via
		(at 185.010044 -357.09987)
		(size 0.4572)
		(drill 0.254)
		(layers "F.Cu" "B.Cu")
		(net "GND")
	)
	(via
		(at 217.583512 -232.471468)
		(size 0.508)
		(drill 0.254)
		(layers "F.Cu" "B.Cu")
		(net "GND")
	)
	(via
		(at 299.449744 -274.999958)
		(size 0.4064)
		(drill 0.2032)
		(layers "F.Cu" "B.Cu")
		(net "GND")
	)
	(via
		(at 451.391274 -407.506678)
		(size 0.508)
		(drill 0.254)
		(layers "F.Cu" "B.Cu")
		(net "GND")
	)
	(via
		(at 31.570676 -350.977454)
		(size 0.4572)
		(drill 0.254)
		(layers "F.Cu" "B.Cu")
		(net "GND")
	)
	(via
		(at 435.94274 -116.416836)
		(size 0.508)
		(drill 0.254)
		(layers "F.Cu" "B.Cu")
		(net "GND")
	)
	(via
		(at 394.17498 -300.174914)
		(size 0.4064)
		(drill 0.2032)
		(layers "F.Cu" "B.Cu")
		(net "GND")
	)
	(via
		(at 430.749964 -284.499812)
		(size 0.4064)
		(drill 0.2032)
		(layers "F.Cu" "B.Cu")
		(net "GND")
	)
	(via
		(at 295.308782 -357.75773)
		(size 0.4064)
		(drill 0.2032)
		(layers "F.Cu" "B.Cu")
		(net "GND")
	)
	(via
		(at 122.946922 -1.135126)
		(size 0.508)
		(drill 0.254)
		(layers "F.Cu" "B.Cu")
		(net "GND")
	)
	(via
		(at 295.68013 -341.781638)
		(size 0.4572)
		(drill 0.254)
		(layers "F.Cu" "B.Cu")
		(net "GND")
	)
	(via
		(at 209.746596 -227.470462)
		(size 0.508)
		(drill 0.254)
		(layers "F.Cu" "B.Cu")
		(net "GND")
	)
	(via
		(at 160.074864 -289.724846)
		(size 0.4064)
		(drill 0.2032)
		(layers "F.Cu" "B.Cu")
		(net "GND")
	)
	(via
		(at 216.130886 -122.525028)
		(size 0.508)
		(drill 0.254)
		(layers "F.Cu" "B.Cu")
		(net "GND")
	)
	(via
		(at 191.599312 -342.439498)
		(size 0.4064)
		(drill 0.2032)
		(layers "F.Cu" "B.Cu")
		(net "GND")
	)
	(via
		(at 183.766714 -133.044946)
		(size 0.508)
		(drill 0.254)
		(layers "F.Cu" "B.Cu")
		(net "GND")
	)
	(via
		(at 193.56451 -29.72816)
		(size 0.508)
		(drill 0.254)
		(layers "F.Cu" "B.Cu")
		(net "GND")
	)
	(via
		(at 330.581 -83.566)
		(size 0.508)
		(drill 0.254)
		(layers "F.Cu" "B.Cu")
		(net "GND")
	)
	(via
		(at 45.39996 -303.499774)
		(size 0.4064)
		(drill 0.2032)
		(layers "F.Cu" "B.Cu")
		(net "GND")
	)
	(via
		(at 333.694024 -228.386894)
		(size 0.4572)
		(drill 0.254)
		(layers "F.Cu" "B.Cu")
		(net "GND")
	)
	(via
		(at 339.914484 -348.58579)
		(size 0.4064)
		(drill 0.2032)
		(layers "F.Cu" "B.Cu")
		(net "GND")
	)
	(via
		(at 124.868178 -54.238906)
		(size 0.508)
		(drill 0.254)
		(layers "F.Cu" "B.Cu")
		(net "GND")
	)
	(via
		(at 109.80674 -110.785656)
		(size 0.508)
		(drill 0.254)
		(layers "F.Cu" "B.Cu")
		(net "GND")
	)
	(via
		(at 259.868924 -279.931114)
		(size 0.508)
		(drill 0.254)
		(layers "F.Cu" "B.Cu")
		(net "GND")
	)
	(via
		(at 241.012218 -279.075896)
		(size 0.508)
		(drill 0.254)
		(layers "F.Cu" "B.Cu")
		(net "GND")
	)
	(via
		(at 61.648848 -31.390082)
		(size 0.508)
		(drill 0.254)
		(layers "F.Cu" "B.Cu")
		(net "GND")
	)
	(via
		(at 300.047914 -354.098098)
		(size 0.4572)
		(drill 0.254)
		(layers "F.Cu" "B.Cu")
		(net "GND")
	)
	(via
		(at 307.524912 -292.574726)
		(size 0.4064)
		(drill 0.2032)
		(layers "F.Cu" "B.Cu")
		(net "GND")
	)
	(via
		(at 64.399922 -274.049744)
		(size 0.4064)
		(drill 0.2032)
		(layers "F.Cu" "B.Cu")
		(net "GND")
	)
	(via
		(at 294.963596 -139.817348)
		(size 0.508)
		(drill 0.254)
		(layers "F.Cu" "B.Cu")
		(net "GND")
	)
	(via
		(at 307.049678 -276.899878)
		(size 0.4064)
		(drill 0.2032)
		(layers "F.Cu" "B.Cu")
		(net "GND")
	)
	(via
		(at 280.449782 -316.799722)
		(size 0.4064)
		(drill 0.2032)
		(layers "F.Cu" "B.Cu")
		(net "GND")
	)
	(via
		(at 178.599846 -273.099784)
		(size 0.4064)
		(drill 0.2032)
		(layers "F.Cu" "B.Cu")
		(net "GND")
	)
	(via
		(at 67.66687 -142.15491)
		(size 0.508)
		(drill 0.254)
		(layers "F.Cu" "B.Cu")
		(net "GND")
	)
	(via
		(at 73.899776 -304.449734)
		(size 0.4064)
		(drill 0.2032)
		(layers "F.Cu" "B.Cu")
		(net "GND")
	)
	(via
		(at 144.0434 -28.139136)
		(size 0.508)
		(drill 0.254)
		(layers "F.Cu" "B.Cu")
		(net "GND")
	)
	(via
		(at 277.124922 -288.774886)
		(size 0.4064)
		(drill 0.2032)
		(layers "F.Cu" "B.Cu")
		(net "GND")
	)
	(via
		(at 394.17498 -289.724846)
		(size 0.4064)
		(drill 0.2032)
		(layers "F.Cu" "B.Cu")
		(net "GND")
	)
	(via
		(at 315.668406 -59.974734)
		(size 0.508)
		(drill 0.254)
		(layers "F.Cu" "B.Cu")
		(net "GND")
	)
	(via
		(at 249.673364 -72.56526)
		(size 0.508)
		(drill 0.254)
		(layers "F.Cu" "B.Cu")
		(net "GND")
	)
	(via
		(at 269.524734 -274.524724)
		(size 0.4064)
		(drill 0.2032)
		(layers "F.Cu" "B.Cu")
		(net "GND")
	)
	(via
		(at 133.599682 -57.439814)
		(size 0.508)
		(drill 0.254)
		(layers "F.Cu" "B.Cu")
		(net "GND")
	)
	(via
		(at 296.599864 -281.649932)
		(size 0.4064)
		(drill 0.2032)
		(layers "F.Cu" "B.Cu")
		(net "GND")
	)
	(via
		(at 256.146808 -349.695008)
		(size 0.508)
		(drill 0.254)
		(layers "F.Cu" "B.Cu")
		(net "GND")
	)
	(via
		(at 279.763982 -345.465146)
		(size 0.4064)
		(drill 0.2032)
		(layers "F.Cu" "B.Cu")
		(net "GND")
	)
	(via
		(at 51.63312 -137.16508)
		(size 0.508)
		(drill 0.254)
		(layers "F.Cu" "B.Cu")
		(net "GND")
	)
	(via
		(at 73.239122 -348.58579)
		(size 0.4064)
		(drill 0.2032)
		(layers "F.Cu" "B.Cu")
		(net "GND")
	)
	(via
		(at 74.84999 -319.65011)
		(size 0.4064)
		(drill 0.2032)
		(layers "F.Cu" "B.Cu")
		(net "GND")
	)
	(via
		(at 330.927964 -407.638504)
		(size 0.508)
		(drill 0.254)
		(layers "F.Cu" "B.Cu")
		(net "GND")
	)
	(via
		(at 125.430534 -305.972718)
		(size 0.508)
		(drill 0.254)
		(layers "F.Cu" "B.Cu")
		(net "GND")
	)
	(via
		(at 185.725054 -306.824888)
		(size 0.4064)
		(drill 0.2032)
		(layers "F.Cu" "B.Cu")
		(net "GND")
	)
	(via
		(at 341.927942 -377.341892)
		(size 0.508)
		(drill 0.254)
		(layers "F.Cu" "B.Cu")
		(net "GND")
	)
	(via
		(at 394.574014 -73.85177)
		(size 0.508)
		(drill 0.254)
		(layers "F.Cu" "B.Cu")
		(net "GND")
	)
	(via
		(at 272.438622 -345.465146)
		(size 0.4064)
		(drill 0.2032)
		(layers "F.Cu" "B.Cu")
		(net "GND")
	)
	(via
		(at 404.26894 -373.36476)
		(size 0.508)
		(drill 0.254)
		(layers "F.Cu" "B.Cu")
		(net "GND")
	)
	(via
		(at 283.24429 -346.09913)
		(size 0.4572)
		(drill 0.254)
		(layers "F.Cu" "B.Cu")
		(net "GND")
	)
	(via
		(at 386.099812 -315.849762)
		(size 0.4064)
		(drill 0.2032)
		(layers "F.Cu" "B.Cu")
		(net "GND")
	)
	(via
		(at 453.329802 -245.02364)
		(size 0.508)
		(drill 0.254)
		(layers "F.Cu" "B.Cu")
		(net "GND")
	)
	(via
		(at 175.749966 -274.999958)
		(size 0.4064)
		(drill 0.2032)
		(layers "F.Cu" "B.Cu")
		(net "GND")
	)
	(via
		(at 270.80845 -358.391714)
		(size 0.4572)
		(drill 0.254)
		(layers "F.Cu" "B.Cu")
		(net "GND")
	)
	(via
		(at 433.108354 -121.563384)
		(size 0.508)
		(drill 0.254)
		(layers "F.Cu" "B.Cu")
		(net "GND")
	)
	(via
		(at 172.547788 -375.040144)
		(size 0.508)
		(drill 0.254)
		(layers "F.Cu" "B.Cu")
		(net "GND")
	)
	(via
		(at 258.632452 -172.376338)
		(size 0.508)
		(drill 0.254)
		(layers "F.Cu" "B.Cu")
		(net "GND")
	)
	(via
		(at 416.024822 -284.974792)
		(size 0.4064)
		(drill 0.2032)
		(layers "F.Cu" "B.Cu")
		(net "GND")
	)
	(via
		(at 119.747792 -371.140228)
		(size 0.4572)
		(drill 0.254)
		(layers "F.Cu" "B.Cu")
		(net "GND")
	)
	(via
		(at 337.523074 -51.019456)
		(size 0.508)
		(drill 0.254)
		(layers "F.Cu" "B.Cu")
		(net "GND")
	)
	(via
		(at 417.450016 -315.849762)
		(size 0.4064)
		(drill 0.2032)
		(layers "F.Cu" "B.Cu")
		(net "GND")
	)
	(via
		(at 37.324792 -278.324818)
		(size 0.4064)
		(drill 0.2032)
		(layers "F.Cu" "B.Cu")
		(net "GND")
	)
	(via
		(at 279.299162 -122.130312)
		(size 0.508)
		(drill 0.254)
		(layers "F.Cu" "B.Cu")
		(net "GND")
	)
	(via
		(at 153.898346 -20.417536)
		(size 0.508)
		(drill 0.254)
		(layers "F.Cu" "B.Cu")
		(net "GND")
	)
	(via
		(at 53.96484 -142.367)
		(size 0.508)
		(drill 0.254)
		(layers "F.Cu" "B.Cu")
		(net "GND")
	)
	(via
		(at 14.973046 -208.538572)
		(size 0.508)
		(drill 0.254)
		(layers "F.Cu" "B.Cu")
		(net "GND")
	)
	(via
		(at 70.671182 -29.311854)
		(size 0.508)
		(drill 0.254)
		(layers "F.Cu" "B.Cu")
		(net "GND")
	)
	(via
		(at 47.147988 -376.140472)
		(size 0.508)
		(drill 0.254)
		(layers "F.Cu" "B.Cu")
		(net "GND")
	)
	(via
		(at 65.913762 -357.75773)
		(size 0.4064)
		(drill 0.2032)
		(layers "F.Cu" "B.Cu")
		(net "GND")
	)
	(via
		(at 339.924898 -94.20987)
		(size 0.508)
		(drill 0.254)
		(layers "F.Cu" "B.Cu")
		(net "GND")
	)
	(via
		(at 46.34992 -315.849762)
		(size 0.4064)
		(drill 0.2032)
		(layers "F.Cu" "B.Cu")
		(net "GND")
	)
	(via
		(at 298.78909 -344.831162)
		(size 0.4572)
		(drill 0.254)
		(layers "F.Cu" "B.Cu")
		(net "GND")
	)
	(via
		(at 363.825536 -292.789102)
		(size 0.508)
		(drill 0.254)
		(layers "F.Cu" "B.Cu")
		(net "GND")
	)
	(via
		(at 406.524968 -284.024832)
		(size 0.4064)
		(drill 0.2032)
		(layers "F.Cu" "B.Cu")
		(net "GND")
	)
	(via
		(at 344.127836 -408.840178)
		(size 0.508)
		(drill 0.254)
		(layers "F.Cu" "B.Cu")
		(net "GND")
	)
	(via
		(at 208.389728 -203.334366)
		(size 0.508)
		(drill 0.254)
		(layers "F.Cu" "B.Cu")
		(net "GND")
	)
	(via
		(at 161.9885 -352.245422)
		(size 0.4572)
		(drill 0.254)
		(layers "F.Cu" "B.Cu")
		(net "GND")
	)
	(via
		(at 150.79726 -114.4905)
		(size 0.508)
		(drill 0.254)
		(layers "F.Cu" "B.Cu")
		(net "GND")
	)
	(via
		(at 285.052262 -113.245138)
		(size 0.508)
		(drill 0.254)
		(layers "F.Cu" "B.Cu")
		(net "GND")
	)
	(via
		(at 167.732964 -98.845116)
		(size 0.508)
		(drill 0.254)
		(layers "F.Cu" "B.Cu")
		(net "GND")
	)
	(via
		(at 90.531442 -76.527152)
		(size 0.508)
		(drill 0.254)
		(layers "F.Cu" "B.Cu")
		(net "GND")
	)
	(via
		(at 135.005572 -1.364996)
		(size 0.508)
		(drill 0.254)
		(layers "F.Cu" "B.Cu")
		(net "GND")
	)
	(via
		(at 339.728048 -375.040144)
		(size 0.508)
		(drill 0.254)
		(layers "F.Cu" "B.Cu")
		(net "GND")
	)
	(via
		(at 421.724836 -290.674806)
		(size 0.4064)
		(drill 0.2032)
		(layers "F.Cu" "B.Cu")
		(net "GND")
	)
	(via
		(at 306.448206 -123.635008)
		(size 0.508)
		(drill 0.254)
		(layers "F.Cu" "B.Cu")
		(net "GND")
	)
	(via
		(at 78.64983 -306.349908)
		(size 0.4064)
		(drill 0.2032)
		(layers "F.Cu" "B.Cu")
		(net "GND")
	)
	(via
		(at 198.550022 -288.299906)
		(size 0.4064)
		(drill 0.2032)
		(layers "F.Cu" "B.Cu")
		(net "GND")
	)
	(via
		(at 124.55525 -31.390082)
		(size 0.508)
		(drill 0.254)
		(layers "F.Cu" "B.Cu")
		(net "GND")
	)
	(via
		(at 333.034386 -71.451978)
		(size 0.508)
		(drill 0.254)
		(layers "F.Cu" "B.Cu")
		(net "GND")
	)
	(via
		(at 182.547514 -129.445004)
		(size 0.508)
		(drill 0.254)
		(layers "F.Cu" "B.Cu")
		(net "GND")
	)
	(via
		(at 341.571072 -195.49745)
		(size 0.508)
		(drill 0.254)
		(layers "F.Cu" "B.Cu")
		(net "GND")
	)
	(via
		(at 51.48326 -350.977454)
		(size 0.4572)
		(drill 0.254)
		(layers "F.Cu" "B.Cu")
		(net "GND")
	)
	(via
		(at 182.547514 -147.555204)
		(size 0.508)
		(drill 0.254)
		(layers "F.Cu" "B.Cu")
		(net "GND")
	)
	(via
		(at 351.38995 -185.82005)
		(size 0.508)
		(drill 0.254)
		(layers "F.Cu" "B.Cu")
		(net "GND")
	)
	(via
		(at 424.274996 -73.87463)
		(size 0.508)
		(drill 0.254)
		(layers "F.Cu" "B.Cu")
		(net "GND")
	)
	(via
		(at 52.524914 -300.174914)
		(size 0.4064)
		(drill 0.2032)
		(layers "F.Cu" "B.Cu")
		(net "GND")
	)
	(via
		(at 196.649848 -304.449734)
		(size 0.4064)
		(drill 0.2032)
		(layers "F.Cu" "B.Cu")
		(net "GND")
	)
	(via
		(at 404.149814 -314.899802)
		(size 0.4064)
		(drill 0.2032)
		(layers "F.Cu" "B.Cu")
		(net "GND")
	)
	(via
		(at 387.793992 -344.831162)
		(size 0.4572)
		(drill 0.254)
		(layers "F.Cu" "B.Cu")
		(net "GND")
	)
	(via
		(at 300.047914 -343.073482)
		(size 0.4572)
		(drill 0.254)
		(layers "F.Cu" "B.Cu")
		(net "GND")
	)
	(via
		(at 126.837948 -348.58579)
		(size 0.4064)
		(drill 0.2032)
		(layers "F.Cu" "B.Cu")
		(net "GND")
	)
	(via
		(at 443.86119 -60.099194)
		(size 0.508)
		(drill 0.254)
		(layers "F.Cu" "B.Cu")
		(net "GND")
	)
	(via
		(at 186.77128 -29.311854)
		(size 0.508)
		(drill 0.254)
		(layers "F.Cu" "B.Cu")
		(net "GND")
	)
	(via
		(at 275.699728 -318.699896)
		(size 0.4064)
		(drill 0.2032)
		(layers "F.Cu" "B.Cu")
		(net "GND")
	)
	(via
		(at 273.799808 -300.649894)
		(size 0.4064)
		(drill 0.2032)
		(layers "F.Cu" "B.Cu")
		(net "GND")
	)
	(via
		(at 68.651374 -347.951806)
		(size 0.4572)
		(drill 0.254)
		(layers "F.Cu" "B.Cu")
		(net "GND")
	)
	(via
		(at 74.84999 -286.399732)
		(size 0.4064)
		(drill 0.2032)
		(layers "F.Cu" "B.Cu")
		(net "GND")
	)
	(via
		(at 271.424908 -281.174952)
		(size 0.4064)
		(drill 0.2032)
		(layers "F.Cu" "B.Cu")
		(net "GND")
	)
	(via
		(at 161.54781 -400.938492)
		(size 0.508)
		(drill 0.254)
		(layers "F.Cu" "B.Cu")
		(net "GND")
	)
	(via
		(at 298.012612 -136.645142)
		(size 0.508)
		(drill 0.254)
		(layers "F.Cu" "B.Cu")
		(net "GND")
	)
	(via
		(at 180.270912 -354.732082)
		(size 0.4064)
		(drill 0.2032)
		(layers "F.Cu" "B.Cu")
		(net "GND")
	)
	(via
		(at 210.006438 -224.474024)
		(size 0.508)
		(drill 0.254)
		(layers "F.Cu" "B.Cu")
		(net "GND")
	)
	(via
		(at 387.050026 -308.249828)
		(size 0.4064)
		(drill 0.2032)
		(layers "F.Cu" "B.Cu")
		(net "GND")
	)
	(via
		(at 100.25126 -45.865288)
		(size 0.508)
		(drill 0.254)
		(layers "F.Cu" "B.Cu")
		(net "GND")
	)
	(via
		(at 295.174924 -306.824888)
		(size 0.4064)
		(drill 0.2032)
		(layers "F.Cu" "B.Cu")
		(net "GND")
	)
	(via
		(at 288.99993 -312.999882)
		(size 0.4064)
		(drill 0.2032)
		(layers "F.Cu" "B.Cu")
		(net "GND")
	)
	(via
		(at 183.82488 -287.824926)
		(size 0.4064)
		(drill 0.2032)
		(layers "F.Cu" "B.Cu")
		(net "GND")
	)
	(via
		(at 313.09818 -119.756936)
		(size 0.508)
		(drill 0.254)
		(layers "F.Cu" "B.Cu")
		(net "GND")
	)
	(via
		(at 447.776092 -252.192282)
		(size 0.508)
		(drill 0.254)
		(layers "F.Cu" "B.Cu")
		(net "GND")
	)
	(via
		(at 270.80845 -352.245422)
		(size 0.4572)
		(drill 0.254)
		(layers "F.Cu" "B.Cu")
		(net "GND")
	)
	(via
		(at 101.831394 -393.683744)
		(size 0.508)
		(drill 0.254)
		(layers "F.Cu" "B.Cu")
		(net "GND")
	)
	(via
		(at 199.284844 -106.934)
		(size 0.508)
		(drill 0.254)
		(layers "F.Cu" "B.Cu")
		(net "GND")
	)
	(via
		(at 160.31083 -57.439814)
		(size 0.508)
		(drill 0.254)
		(layers "F.Cu" "B.Cu")
		(net "GND")
	)
	(via
		(at 91.31935 -34.990024)
		(size 0.508)
		(drill 0.254)
		(layers "F.Cu" "B.Cu")
		(net "GND")
	)
	(via
		(at 205.932024 -123.473972)
		(size 0.508)
		(drill 0.254)
		(layers "F.Cu" "B.Cu")
		(net "GND")
	)
	(via
		(at 171.31538 -347.951806)
		(size 0.4572)
		(drill 0.254)
		(layers "F.Cu" "B.Cu")
		(net "GND")
	)
	(via
		(at 40.649906 -311.099962)
		(size 0.4064)
		(drill 0.2032)
		(layers "F.Cu" "B.Cu")
		(net "GND")
	)
	(via
		(at 415.96691 -116.435124)
		(size 0.508)
		(drill 0.254)
		(layers "F.Cu" "B.Cu")
		(net "GND")
	)
	(via
		(at 464.939888 -244.08638)
		(size 0.508)
		(drill 0.254)
		(layers "F.Cu" "B.Cu")
		(net "GND")
	)
	(via
		(at 452.220838 -312.564526)
		(size 0.508)
		(drill 0.254)
		(layers "F.Cu" "B.Cu")
		(net "GND")
	)
	(via
		(at 444.484506 -72.56526)
		(size 0.508)
		(drill 0.254)
		(layers "F.Cu" "B.Cu")
		(net "GND")
	)
	(via
		(at 306.451254 -45.865288)
		(size 0.508)
		(drill 0.254)
		(layers "F.Cu" "B.Cu")
		(net "GND")
	)
	(via
		(at 161.54781 -407.24201)
		(size 0.508)
		(drill 0.254)
		(layers "F.Cu" "B.Cu")
		(net "GND")
	)
	(via
		(at 429.381412 -345.465146)
		(size 0.4064)
		(drill 0.2032)
		(layers "F.Cu" "B.Cu")
		(net "GND")
	)
	(via
		(at 29.54782 -402.140166)
		(size 0.508)
		(drill 0.254)
		(layers "F.Cu" "B.Cu")
		(net "GND")
	)
	(via
		(at 79.457042 -357.75773)
		(size 0.4064)
		(drill 0.2032)
		(layers "F.Cu" "B.Cu")
		(net "GND")
	)
	(via
		(at 418.927788 -399.838418)
		(size 0.508)
		(drill 0.254)
		(layers "F.Cu" "B.Cu")
		(net "GND")
	)
	(via
		(at 18.878804 -122.09907)
		(size 0.508)
		(drill 0.254)
		(layers "F.Cu" "B.Cu")
		(net "GND")
	)
	(via
		(at 79.12481 -303.974754)
		(size 0.4064)
		(drill 0.2032)
		(layers "F.Cu" "B.Cu")
		(net "GND")
	)
	(via
		(at 302.327818 -402.140166)
		(size 0.508)
		(drill 0.254)
		(layers "F.Cu" "B.Cu")
		(net "GND")
	)
	(via
		(at 270.949928 -319.65011)
		(size 0.4064)
		(drill 0.2032)
		(layers "F.Cu" "B.Cu")
		(net "GND")
	)
	(via
		(at 209.751168 -77.52715)
		(size 0.508)
		(drill 0.254)
		(layers "F.Cu" "B.Cu")
		(net "GND")
	)
	(via
		(at 421.724836 -292.574726)
		(size 0.4064)
		(drill 0.2032)
		(layers "F.Cu" "B.Cu")
		(net "GND")
	)
	(via
		(at 266.202922 -299.895514)
		(size 0.508)
		(drill 0.254)
		(layers "F.Cu" "B.Cu")
		(net "GND")
	)
	(via
		(at 166.249858 -316.799722)
		(size 0.4064)
		(drill 0.2032)
		(layers "F.Cu" "B.Cu")
		(net "GND")
	)
	(via
		(at 135.057388 -348.58579)
		(size 0.4064)
		(drill 0.2032)
		(layers "F.Cu" "B.Cu")
		(net "GND")
	)
	(via
		(at 463.037682 -184.417462)
		(size 0.508)
		(drill 0.254)
		(layers "F.Cu" "B.Cu")
		(net "GND")
	)
	(via
		(at 41.124886 -283.074872)
		(size 0.4064)
		(drill 0.2032)
		(layers "F.Cu" "B.Cu")
		(net "GND")
	)
	(via
		(at 289.46221 -358.391714)
		(size 0.4572)
		(drill 0.254)
		(layers "F.Cu" "B.Cu")
		(net "GND")
	)
	(via
		(at 81.941924 -49.574704)
		(size 0.508)
		(drill 0.254)
		(layers "F.Cu" "B.Cu")
		(net "GND")
	)
	(via
		(at 300.874684 -306.824888)
		(size 0.4064)
		(drill 0.2032)
		(layers "F.Cu" "B.Cu")
		(net "GND")
	)
	(via
		(at 45.87494 -291.624766)
		(size 0.4064)
		(drill 0.2032)
		(layers "F.Cu" "B.Cu")
		(net "GND")
	)
	(via
		(at 312.305192 -346.09913)
		(size 0.4572)
		(drill 0.254)
		(layers "F.Cu" "B.Cu")
		(net "GND")
	)
	(via
		(at 385.855464 -231.70896)
		(size 0.508)
		(drill 0.254)
		(layers "F.Cu" "B.Cu")
		(net "GND")
	)
	(via
		(at 165.09746 -347.951806)
		(size 0.4572)
		(drill 0.254)
		(layers "F.Cu" "B.Cu")
		(net "GND")
	)
	(via
		(at 412.20644 -341.805514)
		(size 0.4572)
		(drill 0.254)
		(layers "F.Cu" "B.Cu")
		(net "GND")
	)
	(via
		(at 42.074846 -300.174914)
		(size 0.4064)
		(drill 0.2032)
		(layers "F.Cu" "B.Cu")
		(net "GND")
	)
	(via
		(at 433.96916 -344.831162)
		(size 0.4572)
		(drill 0.254)
		(layers "F.Cu" "B.Cu")
		(net "GND")
	)
	(via
		(at 339.728048 -373.83847)
		(size 0.508)
		(drill 0.254)
		(layers "F.Cu" "B.Cu")
		(net "GND")
	)
	(via
		(at 421.61333 -33.459674)
		(size 0.508)
		(drill 0.254)
		(layers "F.Cu" "B.Cu")
		(net "GND")
	)
	(via
		(at 387.050026 -315.849762)
		(size 0.4064)
		(drill 0.2032)
		(layers "F.Cu" "B.Cu")
		(net "GND")
	)
	(via
		(at 286.35325 -341.805514)
		(size 0.4572)
		(drill 0.254)
		(layers "F.Cu" "B.Cu")
		(net "GND")
	)
	(via
		(at 202.555094 -31.390082)
		(size 0.508)
		(drill 0.254)
		(layers "F.Cu" "B.Cu")
		(net "GND")
	)
	(via
		(at 192.850008 -308.249828)
		(size 0.4064)
		(drill 0.2032)
		(layers "F.Cu" "B.Cu")
		(net "GND")
	)
	(via
		(at 190.681356 -31.118302)
		(size 0.508)
		(drill 0.254)
		(layers "F.Cu" "B.Cu")
		(net "GND")
	)
	(via
		(at 153.42489 -284.024832)
		(size 0.4064)
		(drill 0.2032)
		(layers "F.Cu" "B.Cu")
		(net "GND")
	)
	(via
		(at 352.803968 -285.953454)
		(size 0.508)
		(drill 0.254)
		(layers "F.Cu" "B.Cu")
		(net "GND")
	)
	(via
		(at 404.149814 -276.899878)
		(size 0.4064)
		(drill 0.2032)
		(layers "F.Cu" "B.Cu")
		(net "GND")
	)
	(via
		(at 81.087214 -350.977454)
		(size 0.4572)
		(drill 0.254)
		(layers "F.Cu" "B.Cu")
		(net "GND")
	)
	(via
		(at 180.975 -306.824888)
		(size 0.4064)
		(drill 0.2032)
		(layers "F.Cu" "B.Cu")
		(net "GND")
	)
	(via
		(at 264.3124 -307.4924)
		(size 0.508)
		(drill 0.254)
		(layers "F.Cu" "B.Cu")
		(net "GND")
	)
	(via
		(at 414.11271 -136.645142)
		(size 0.508)
		(drill 0.254)
		(layers "F.Cu" "B.Cu")
		(net "GND")
	)
	(via
		(at 411.275022 -289.724846)
		(size 0.4064)
		(drill 0.2032)
		(layers "F.Cu" "B.Cu")
		(net "GND")
	)
	(via
		(at 273.77517 -84.438236)
		(size 0.508)
		(drill 0.254)
		(layers "F.Cu" "B.Cu")
		(net "GND")
	)
	(via
		(at 240.182146 -87.727282)
		(size 0.508)
		(drill 0.254)
		(layers "F.Cu" "B.Cu")
		(net "GND")
	)
	(via
		(at 125.730508 -354.732082)
		(size 0.4064)
		(drill 0.2032)
		(layers "F.Cu" "B.Cu")
		(net "GND")
	)
	(via
		(at 206.156052 -33.19018)
		(size 0.508)
		(drill 0.254)
		(layers "F.Cu" "B.Cu")
		(net "GND")
	)
	(via
		(at 219.091764 -102.836218)
		(size 0.508)
		(drill 0.254)
		(layers "F.Cu" "B.Cu")
		(net "GND")
	)
	(via
		(at 289.127692 -409.940252)
		(size 0.508)
		(drill 0.254)
		(layers "F.Cu" "B.Cu")
		(net "GND")
	)
	(via
		(at 26.61158 -350.977454)
		(size 0.4572)
		(drill 0.254)
		(layers "F.Cu" "B.Cu")
		(net "GND")
	)
	(via
		(at 80.147922 -402.241766)
		(size 0.508)
		(drill 0.254)
		(layers "F.Cu" "B.Cu")
		(net "GND")
	)
	(via
		(at 29.72054 -352.245422)
		(size 0.4572)
		(drill 0.254)
		(layers "F.Cu" "B.Cu")
		(net "GND")
	)
	(via
		(at 325.83882 -291.321998)
		(size 0.508)
		(drill 0.254)
		(layers "F.Cu" "B.Cu")
		(net "GND")
	)
	(via
		(at 101.429312 -47.020734)
		(size 0.508)
		(drill 0.254)
		(layers "F.Cu" "B.Cu")
		(net "GND")
	)
	(via
		(at 310.849772 -312.049922)
		(size 0.4064)
		(drill 0.2032)
		(layers "F.Cu" "B.Cu")
		(net "GND")
	)
	(via
		(at 329.108816 -354.098098)
		(size 0.4572)
		(drill 0.254)
		(layers "F.Cu" "B.Cu")
		(net "GND")
	)
	(via
		(at 38.749986 -310.149748)
		(size 0.4064)
		(drill 0.2032)
		(layers "F.Cu" "B.Cu")
		(net "GND")
	)
	(via
		(at 289.127692 -378.83846)
		(size 0.508)
		(drill 0.254)
		(layers "F.Cu" "B.Cu")
		(net "GND")
	)
	(via
		(at 120.753378 -49.574704)
		(size 0.508)
		(drill 0.254)
		(layers "F.Cu" "B.Cu")
		(net "GND")
	)
	(via
		(at 124.80036 -155.217114)
		(size 0.508)
		(drill 0.254)
		(layers "F.Cu" "B.Cu")
		(net "GND")
	)
	(via
		(at 100.678742 -104.115616)
		(size 0.508)
		(drill 0.254)
		(layers "F.Cu" "B.Cu")
		(net "GND")
	)
	(via
		(at 56.324754 -291.624766)
		(size 0.4064)
		(drill 0.2032)
		(layers "F.Cu" "B.Cu")
		(net "GND")
	)
	(via
		(at 284.739588 -154.3685)
		(size 0.508)
		(drill 0.254)
		(layers "F.Cu" "B.Cu")
		(net "GND")
	)
	(via
		(at 181.92496 -297.32478)
		(size 0.4064)
		(drill 0.2032)
		(layers "F.Cu" "B.Cu")
		(net "GND")
	)
	(via
		(at 165.774878 -304.924714)
		(size 0.4064)
		(drill 0.2032)
		(layers "F.Cu" "B.Cu")
		(net "GND")
	)
	(via
		(at 75.79995 -318.699896)
		(size 0.4064)
		(drill 0.2032)
		(layers "F.Cu" "B.Cu")
		(net "GND")
	)
	(via
		(at 395.332966 -129.964942)
		(size 0.508)
		(drill 0.254)
		(layers "F.Cu" "B.Cu")
		(net "GND")
	)
	(via
		(at 381.527812 -378.83846)
		(size 0.508)
		(drill 0.254)
		(layers "F.Cu" "B.Cu")
		(net "GND")
	)
	(via
		(at 79.12481 -290.674806)
		(size 0.4064)
		(drill 0.2032)
		(layers "F.Cu" "B.Cu")
		(net "GND")
	)
	(via
		(at 76.953364 -82.331306)
		(size 0.508)
		(drill 0.254)
		(layers "F.Cu" "B.Cu")
		(net "GND")
	)
	(via
		(at 105.443274 -286.842454)
		(size 0.508)
		(drill 0.254)
		(layers "F.Cu" "B.Cu")
		(net "GND")
	)
	(via
		(at 429.010064 -347.951806)
		(size 0.4572)
		(drill 0.254)
		(layers "F.Cu" "B.Cu")
		(net "GND")
	)
	(via
		(at 432.12766 -406.141936)
		(size 0.508)
		(drill 0.254)
		(layers "F.Cu" "B.Cu")
		(net "GND")
	)
	(via
		(at 70.50151 -341.805514)
		(size 0.4572)
		(drill 0.254)
		(layers "F.Cu" "B.Cu")
		(net "GND")
	)
	(via
		(at 52.049934 -312.049922)
		(size 0.4064)
		(drill 0.2032)
		(layers "F.Cu" "B.Cu")
		(net "GND")
	)
	(via
		(at 200.908158 -144.224502)
		(size 0.508)
		(drill 0.254)
		(layers "F.Cu" "B.Cu")
		(net "GND")
	)
	(via
		(at 375.623328 -55.083456)
		(size 0.508)
		(drill 0.254)
		(layers "F.Cu" "B.Cu")
		(net "GND")
	)
	(via
		(at 298.33189 -13.613638)
		(size 0.508)
		(drill 0.254)
		(layers "F.Cu" "B.Cu")
		(net "GND")
	)
	(via
		(at 57.721246 -371.930422)
		(size 0.4064)
		(drill 0.2032)
		(layers "F.Cu" "B.Cu")
		(net "GND")
	)
	(via
		(at 273.91741 -352.245422)
		(size 0.4572)
		(drill 0.254)
		(layers "F.Cu" "B.Cu")
		(net "GND")
	)
	(via
		(at 113.603786 -286.842454)
		(size 0.508)
		(drill 0.254)
		(layers "F.Cu" "B.Cu")
		(net "GND")
	)
	(via
		(at 272.849848 -315.849762)
		(size 0.4064)
		(drill 0.2032)
		(layers "F.Cu" "B.Cu")
		(net "GND")
	)
	(via
		(at 390.902952 -349.219774)
		(size 0.4572)
		(drill 0.254)
		(layers "F.Cu" "B.Cu")
		(net "GND")
	)
	(via
		(at 374.099328 -358.391714)
		(size 0.4572)
		(drill 0.254)
		(layers "F.Cu" "B.Cu")
		(net "GND")
	)
	(via
		(at 273.324828 -277.374858)
		(size 0.4064)
		(drill 0.2032)
		(layers "F.Cu" "B.Cu")
		(net "GND")
	)
	(via
		(at 315.405008 -143.470122)
		(size 0.508)
		(drill 0.254)
		(layers "F.Cu" "B.Cu")
		(net "GND")
	)
	(via
		(at 6.557772 -173.263306)
		(size 0.508)
		(drill 0.254)
		(layers "F.Cu" "B.Cu")
		(net "GND")
	)
	(via
		(at 201.920094 -29.590238)
		(size 0.508)
		(drill 0.254)
		(layers "F.Cu" "B.Cu")
		(net "GND")
	)
	(via
		(at 294.69969 -273.099784)
		(size 0.4064)
		(drill 0.2032)
		(layers "F.Cu" "B.Cu")
		(net "GND")
	)
	(via
		(at 17.592802 -267.500608)
		(size 0.508)
		(drill 0.254)
		(layers "F.Cu" "B.Cu")
		(net "GND")
	)
	(via
		(at 394.64996 -315.849762)
		(size 0.4064)
		(drill 0.2032)
		(layers "F.Cu" "B.Cu")
		(net "GND")
	)
	(via
		(at 132.419852 -131.312666)
		(size 0.508)
		(drill 0.254)
		(layers "F.Cu" "B.Cu")
		(net "GND")
	)
	(via
		(at 413.174942 -284.974792)
		(size 0.4064)
		(drill 0.2032)
		(layers "F.Cu" "B.Cu")
		(net "GND")
	)
	(via
		(at 114.773456 -358.391714)
		(size 0.4572)
		(drill 0.254)
		(layers "F.Cu" "B.Cu")
		(net "GND")
	)
	(via
		(at 427.89983 -308.249828)
		(size 0.4064)
		(drill 0.2032)
		(layers "F.Cu" "B.Cu")
		(net "GND")
	)
	(via
		(at 43.024806 -281.174952)
		(size 0.4064)
		(drill 0.2032)
		(layers "F.Cu" "B.Cu")
		(net "GND")
	)
	(via
		(at 414.548828 -29.589984)
		(size 0.508)
		(drill 0.254)
		(layers "F.Cu" "B.Cu")
		(net "GND")
	)
	(via
		(at 61.648848 -34.990024)
		(size 0.508)
		(drill 0.254)
		(layers "F.Cu" "B.Cu")
		(net "GND")
	)
	(via
		(at 340.285832 -349.219774)
		(size 0.4572)
		(drill 0.254)
		(layers "F.Cu" "B.Cu")
		(net "GND")
	)
	(via
		(at 375.358152 -358.391714)
		(size 0.4572)
		(drill 0.254)
		(layers "F.Cu" "B.Cu")
		(net "GND")
	)
	(via
		(at 300.874684 -288.774886)
		(size 0.4064)
		(drill 0.2032)
		(layers "F.Cu" "B.Cu")
		(net "GND")
	)
	(via
		(at 211.62899 -114.886486)
		(size 0.508)
		(drill 0.254)
		(layers "F.Cu" "B.Cu")
		(net "GND")
	)
	(via
		(at 210.40979 -284.632146)
		(size 0.508)
		(drill 0.254)
		(layers "F.Cu" "B.Cu")
		(net "GND")
	)
	(via
		(at 151.999442 -316.799468)
		(size 0.4064)
		(drill 0.2032)
		(layers "F.Cu" "B.Cu")
		(net "GND")
	)
	(via
		(at 381.527812 -385.141978)
		(size 0.508)
		(drill 0.254)
		(layers "F.Cu" "B.Cu")
		(net "GND")
	)
	(via
		(at 172.547788 -395.938502)
		(size 0.508)
		(drill 0.254)
		(layers "F.Cu" "B.Cu")
		(net "GND")
	)
	(via
		(at 263.716008 -259.576316)
		(size 0.508)
		(drill 0.254)
		(layers "F.Cu" "B.Cu")
		(net "GND")
	)
	(via
		(at 288.524696 -289.724846)
		(size 0.4064)
		(drill 0.2032)
		(layers "F.Cu" "B.Cu")
		(net "GND")
	)
	(via
		(at 255.933194 -394.270738)
		(size 0.508)
		(drill 0.254)
		(layers "F.Cu" "B.Cu")
		(net "GND")
	)
	(via
		(at 106.087164 -160.385252)
		(size 0.508)
		(drill 0.254)
		(layers "F.Cu" "B.Cu")
		(net "GND")
	)
	(via
		(at 388.949946 -302.549814)
		(size 0.4064)
		(drill 0.2032)
		(layers "F.Cu" "B.Cu")
		(net "GND")
	)
	(via
		(at 333.579724 -107.681776)
		(size 0.508)
		(drill 0.254)
		(layers "F.Cu" "B.Cu")
		(net "GND")
	)
	(via
		(at 406.900888 -34.990278)
		(size 0.508)
		(drill 0.254)
		(layers "F.Cu" "B.Cu")
		(net "GND")
	)
	(via
		(at 400.34972 -272.14957)
		(size 0.4064)
		(drill 0.2032)
		(layers "F.Cu" "B.Cu")
		(net "GND")
	)
	(via
		(at 209.84591 -219.202)
		(size 0.508)
		(drill 0.254)
		(layers "F.Cu" "B.Cu")
		(net "GND")
	)
	(via
		(at 18.582132 -58.238644)
		(size 0.508)
		(drill 0.254)
		(layers "F.Cu" "B.Cu")
		(net "GND")
	)
	(via
		(at 353.776788 -268.731492)
		(size 0.508)
		(drill 0.254)
		(layers "F.Cu" "B.Cu")
		(net "GND")
	)
	(via
		(at 292.79977 -313.949842)
		(size 0.4064)
		(drill 0.2032)
		(layers "F.Cu" "B.Cu")
		(net "GND")
	)
	(via
		(at 348.527878 -371.140482)
		(size 0.508)
		(drill 0.254)
		(layers "F.Cu" "B.Cu")
		(net "GND")
	)
	(via
		(at 426.94987 -288.299906)
		(size 0.4064)
		(drill 0.2032)
		(layers "F.Cu" "B.Cu")
		(net "GND")
	)
	(via
		(at 74.168 -417.82492)
		(size 0.508)
		(drill 0.254)
		(layers "F.Cu" "B.Cu")
		(net "GND")
	)
	(via
		(at 180.64226 -341.805514)
		(size 0.4572)
		(drill 0.254)
		(layers "F.Cu" "B.Cu")
		(net "GND")
	)
	(via
		(at 331.51318 -31.118302)
		(size 0.508)
		(drill 0.254)
		(layers "F.Cu" "B.Cu")
		(net "GND")
	)
	(via
		(at 303.01946 -232.377742)
		(size 0.508)
		(drill 0.254)
		(layers "F.Cu" "B.Cu")
		(net "GND")
	)
	(via
		(at 314.174886 -293.52494)
		(size 0.4064)
		(drill 0.2032)
		(layers "F.Cu" "B.Cu")
		(net "GND")
	)
	(via
		(at 276.174708 -296.37482)
		(size 0.4064)
		(drill 0.2032)
		(layers "F.Cu" "B.Cu")
		(net "GND")
	)
	(via
		(at 197.125082 -294.4749)
		(size 0.4064)
		(drill 0.2032)
		(layers "F.Cu" "B.Cu")
		(net "GND")
	)
	(via
		(at 417.980368 -156.554932)
		(size 0.508)
		(drill 0.254)
		(layers "F.Cu" "B.Cu")
		(net "GND")
	)
	(via
		(at 436.527702 -377.73864)
		(size 0.508)
		(drill 0.254)
		(layers "F.Cu" "B.Cu")
		(net "GND")
	)
	(via
		(at 82.347816 -377.341892)
		(size 0.508)
		(drill 0.254)
		(layers "F.Cu" "B.Cu")
		(net "GND")
	)
	(via
		(at 165.299898 -314.899802)
		(size 0.4064)
		(drill 0.2032)
		(layers "F.Cu" "B.Cu")
		(net "GND")
	)
	(via
		(at 127.209296 -355.366066)
		(size 0.4572)
		(drill 0.254)
		(layers "F.Cu" "B.Cu")
		(net "GND")
	)
	(via
		(at 305.149758 -279.749758)
		(size 0.4064)
		(drill 0.2032)
		(layers "F.Cu" "B.Cu")
		(net "GND")
	)
	(via
		(at 336.805524 -354.732082)
		(size 0.4064)
		(drill 0.2032)
		(layers "F.Cu" "B.Cu")
		(net "GND")
	)
	(via
		(at 412.89351 -121.835164)
		(size 0.508)
		(drill 0.254)
		(layers "F.Cu" "B.Cu")
		(net "GND")
	)
	(via
		(at 346.327984 -385.141978)
		(size 0.508)
		(drill 0.254)
		(layers "F.Cu" "B.Cu")
		(net "GND")
	)
	(via
		(at 193.324988 -297.32478)
		(size 0.4064)
		(drill 0.2032)
		(layers "F.Cu" "B.Cu")
		(net "GND")
	)
	(via
		(at 425.04995 -287.349946)
		(size 0.4064)
		(drill 0.2032)
		(layers "F.Cu" "B.Cu")
		(net "GND")
	)
	(via
		(at 179.55006 -274.999958)
		(size 0.4064)
		(drill 0.2032)
		(layers "F.Cu" "B.Cu")
		(net "GND")
	)
	(via
		(at 416.857942 -58.791094)
		(size 0.508)
		(drill 0.254)
		(layers "F.Cu" "B.Cu")
		(net "GND")
	)
	(via
		(at 421.127682 -374.938544)
		(size 0.508)
		(drill 0.254)
		(layers "F.Cu" "B.Cu")
		(net "GND")
	)
	(via
		(at 216.681304 -31.118302)
		(size 0.508)
		(drill 0.254)
		(layers "F.Cu" "B.Cu")
		(net "GND")
	)
	(via
		(at 400.824954 -305.874928)
		(size 0.4064)
		(drill 0.2032)
		(layers "F.Cu" "B.Cu")
		(net "GND")
	)
	(via
		(at 162.450018 -281.649932)
		(size 0.4064)
		(drill 0.2032)
		(layers "F.Cu" "B.Cu")
		(net "GND")
	)
	(via
		(at 166.725092 -291.624766)
		(size 0.4064)
		(drill 0.2032)
		(layers "F.Cu" "B.Cu")
		(net "GND")
	)
	(via
		(at 312.749692 -281.649932)
		(size 0.4064)
		(drill 0.2032)
		(layers "F.Cu" "B.Cu")
		(net "GND")
	)
	(via
		(at 189.96914 -347.951806)
		(size 0.4572)
		(drill 0.254)
		(layers "F.Cu" "B.Cu")
		(net "GND")
	)
	(via
		(at 360.83875 -307.18887)
		(size 0.508)
		(drill 0.254)
		(layers "F.Cu" "B.Cu")
		(net "GND")
	)
	(via
		(at 402.249894 -319.65011)
		(size 0.4064)
		(drill 0.2032)
		(layers "F.Cu" "B.Cu")
		(net "GND")
	)
	(via
		(at 133.055868 -357.75773)
		(size 0.4064)
		(drill 0.2032)
		(layers "F.Cu" "B.Cu")
		(net "GND")
	)
	(via
		(at 84.808314 -120.30456)
		(size 0.508)
		(drill 0.254)
		(layers "F.Cu" "B.Cu")
		(net "GND")
	)
	(via
		(at 414.599882 -277.849838)
		(size 0.4064)
		(drill 0.2032)
		(layers "F.Cu" "B.Cu")
		(net "GND")
	)
	(via
		(at 278.285194 -346.09913)
		(size 0.4572)
		(drill 0.254)
		(layers "F.Cu" "B.Cu")
		(net "GND")
	)
	(via
		(at 388.16534 -342.439498)
		(size 0.4064)
		(drill 0.2032)
		(layers "F.Cu" "B.Cu")
		(net "GND")
	)
	(via
		(at 369.613434 -33.459674)
		(size 0.508)
		(drill 0.254)
		(layers "F.Cu" "B.Cu")
		(net "GND")
	)
	(via
		(at 264.670286 -253.45644)
		(size 0.508)
		(drill 0.254)
		(layers "F.Cu" "B.Cu")
		(net "GND")
	)
	(via
		(at 333.127858 -403.34184)
		(size 0.508)
		(drill 0.254)
		(layers "F.Cu" "B.Cu")
		(net "GND")
	)
	(via
		(at 392.749786 -316.799722)
		(size 0.4064)
		(drill 0.2032)
		(layers "F.Cu" "B.Cu")
		(net "GND")
	)
	(via
		(at 431.224944 -299.224954)
		(size 0.4064)
		(drill 0.2032)
		(layers "F.Cu" "B.Cu")
		(net "GND")
	)
	(via
		(at 419.824916 -296.37482)
		(size 0.4064)
		(drill 0.2032)
		(layers "F.Cu" "B.Cu")
		(net "GND")
	)
	(via
		(at 424.64228 -349.219774)
		(size 0.4572)
		(drill 0.254)
		(layers "F.Cu" "B.Cu")
		(net "GND")
	)
	(via
		(at 241.137186 -50.47234)
		(size 0.508)
		(drill 0.254)
		(layers "F.Cu" "B.Cu")
		(net "GND")
	)
	(via
		(at 285.687262 -104.244902)
		(size 0.508)
		(drill 0.254)
		(layers "F.Cu" "B.Cu")
		(net "GND")
	)
	(via
		(at 412.098236 -21.738336)
		(size 0.508)
		(drill 0.254)
		(layers "F.Cu" "B.Cu")
		(net "GND")
	)
	(via
		(at 365.014256 -279.086818)
		(size 0.508)
		(drill 0.254)
		(layers "F.Cu" "B.Cu")
		(net "GND")
	)
	(via
		(at 275.699728 -317.749936)
		(size 0.4064)
		(drill 0.2032)
		(layers "F.Cu" "B.Cu")
		(net "GND")
	)
	(via
		(at 183.3499 -311.099962)
		(size 0.4064)
		(drill 0.2032)
		(layers "F.Cu" "B.Cu")
		(net "GND")
	)
	(via
		(at 390.374886 -280.224738)
		(size 0.4064)
		(drill 0.2032)
		(layers "F.Cu" "B.Cu")
		(net "GND")
	)
	(via
		(at 119.809768 -288.78149)
		(size 0.508)
		(drill 0.254)
		(layers "F.Cu" "B.Cu")
		(net "GND")
	)
	(via
		(at 104.905048 -390.627108)
		(size 0.508)
		(drill 0.254)
		(layers "F.Cu" "B.Cu")
		(net "GND")
	)
	(via
		(at 179.163472 -357.75773)
		(size 0.4064)
		(drill 0.2032)
		(layers "F.Cu" "B.Cu")
		(net "GND")
	)
	(via
		(at 95.755968 -100.392992)
		(size 0.508)
		(drill 0.254)
		(layers "F.Cu" "B.Cu")
		(net "GND")
	)
	(via
		(at 196.998082 -150.876762)
		(size 0.508)
		(drill 0.254)
		(layers "F.Cu" "B.Cu")
		(net "GND")
	)
	(via
		(at 304.527712 -398.34185)
		(size 0.508)
		(drill 0.254)
		(layers "F.Cu" "B.Cu")
		(net "GND")
	)
	(via
		(at 161.54781 -381.241808)
		(size 0.508)
		(drill 0.254)
		(layers "F.Cu" "B.Cu")
		(net "GND")
	)
	(via
		(at 348.527878 -369.938808)
		(size 0.508)
		(drill 0.254)
		(layers "F.Cu" "B.Cu")
		(net "GND")
	)
	(via
		(at 277.599902 -301.599854)
		(size 0.4064)
		(drill 0.2032)
		(layers "F.Cu" "B.Cu")
		(net "GND")
	)
	(via
		(at 185.747914 -142.15491)
		(size 0.508)
		(drill 0.254)
		(layers "F.Cu" "B.Cu")
		(net "GND")
	)
	(via
		(at 76.553822 -101.609906)
		(size 0.508)
		(drill 0.254)
		(layers "F.Cu" "B.Cu")
		(net "GND")
	)
	(via
		(at 381.94742 -354.732082)
		(size 0.4064)
		(drill 0.2032)
		(layers "F.Cu" "B.Cu")
		(net "GND")
	)
	(via
		(at 280.451306 -47.03191)
		(size 0.508)
		(drill 0.254)
		(layers "F.Cu" "B.Cu")
		(net "GND")
	)
	(via
		(at 117.882416 -341.805514)
		(size 0.4572)
		(drill 0.254)
		(layers "F.Cu" "B.Cu")
		(net "GND")
	)
	(via
		(at 246.102124 -56.826404)
		(size 0.508)
		(drill 0.254)
		(layers "F.Cu" "B.Cu")
		(net "GND")
	)
	(via
		(at 399.93316 -102.445058)
		(size 0.508)
		(drill 0.254)
		(layers "F.Cu" "B.Cu")
		(net "GND")
	)
	(via
		(at 248.902728 -111.127032)
		(size 0.508)
		(drill 0.254)
		(layers "F.Cu" "B.Cu")
		(net "GND")
	)
	(via
		(at 366.522 -202.819)
		(size 0.508)
		(drill 0.254)
		(layers "F.Cu" "B.Cu")
		(net "GND")
	)
	(via
		(at 374.234456 -104.323896)
		(size 0.508)
		(drill 0.254)
		(layers "F.Cu" "B.Cu")
		(net "GND")
	)
	(via
		(at 217.440002 -73.87463)
		(size 0.508)
		(drill 0.254)
		(layers "F.Cu" "B.Cu")
		(net "GND")
	)
	(via
		(at 37.727636 -265.804904)
		(size 0.508)
		(drill 0.254)
		(layers "F.Cu" "B.Cu")
		(net "GND")
	)
	(via
		(at 168.148 -401.040092)
		(size 0.508)
		(drill 0.254)
		(layers "F.Cu" "B.Cu")
		(net "GND")
	)
	(via
		(at 53.474874 -306.824888)
		(size 0.4064)
		(drill 0.2032)
		(layers "F.Cu" "B.Cu")
		(net "GND")
	)
	(via
		(at 125.457966 -141.019276)
		(size 0.508)
		(drill 0.254)
		(layers "F.Cu" "B.Cu")
		(net "GND")
	)
	(via
		(at 6.558026 -136.328404)
		(size 0.508)
		(drill 0.254)
		(layers "F.Cu" "B.Cu")
		(net "GND")
	)
	(via
		(at 122.2502 -343.073482)
		(size 0.4572)
		(drill 0.254)
		(layers "F.Cu" "B.Cu")
		(net "GND")
	)
	(via
		(at 220.275658 -183.40324)
		(size 0.508)
		(drill 0.254)
		(layers "F.Cu" "B.Cu")
		(net "GND")
	)
	(via
		(at 236.573822 -25.971246)
		(size 0.508)
		(drill 0.254)
		(layers "F.Cu" "B.Cu")
		(net "GND")
	)
	(via
		(at 90.414094 -346.09913)
		(size 0.4572)
		(drill 0.254)
		(layers "F.Cu" "B.Cu")
		(net "GND")
	)
	(via
		(at 246.250714 -159.857948)
		(size 0.508)
		(drill 0.254)
		(layers "F.Cu" "B.Cu")
		(net "GND")
	)
	(via
		(at 234.541822 -25.971246)
		(size 0.508)
		(drill 0.254)
		(layers "F.Cu" "B.Cu")
		(net "GND")
	)
	(via
		(at 184.29986 -273.099784)
		(size 0.4064)
		(drill 0.2032)
		(layers "F.Cu" "B.Cu")
		(net "GND")
	)
	(via
		(at 82.347816 -380.040134)
		(size 0.508)
		(drill 0.254)
		(layers "F.Cu" "B.Cu")
		(net "GND")
	)
	(via
		(at 386.099812 -301.599854)
		(size 0.4064)
		(drill 0.2032)
		(layers "F.Cu" "B.Cu")
		(net "GND")
	)
	(via
		(at 12.573 -304.562764)
		(size 0.508)
		(drill 0.254)
		(layers "F.Cu" "B.Cu")
		(net "GND")
	)
	(via
		(at 265.303254 -60.627006)
		(size 0.508)
		(drill 0.254)
		(layers "F.Cu" "B.Cu")
		(net "GND")
	)
	(via
		(at 429.198278 -146.017996)
		(size 0.508)
		(drill 0.254)
		(layers "F.Cu" "B.Cu")
		(net "GND")
	)
	(via
		(at 41.124886 -281.174952)
		(size 0.4064)
		(drill 0.2032)
		(layers "F.Cu" "B.Cu")
		(net "GND")
	)
	(via
		(at 430.749964 -315.849762)
		(size 0.4064)
		(drill 0.2032)
		(layers "F.Cu" "B.Cu")
		(net "GND")
	)
	(via
		(at 82.166206 -133.30809)
		(size 0.508)
		(drill 0.254)
		(layers "F.Cu" "B.Cu")
		(net "GND")
	)
	(via
		(at 80.147922 -373.83847)
		(size 0.508)
		(drill 0.254)
		(layers "F.Cu" "B.Cu")
		(net "GND")
	)
	(via
		(at 426.949616 -276.899878)
		(size 0.4064)
		(drill 0.2032)
		(layers "F.Cu" "B.Cu")
		(net "GND")
	)
	(via
		(at 293.941754 -161.757868)
		(size 0.508)
		(drill 0.254)
		(layers "F.Cu" "B.Cu")
		(net "GND")
	)
	(via
		(at 53.48732 -118.754906)
		(size 0.508)
		(drill 0.254)
		(layers "F.Cu" "B.Cu")
		(net "GND")
	)
	(via
		(at 429.198278 -154.476958)
		(size 0.508)
		(drill 0.254)
		(layers "F.Cu" "B.Cu")
		(net "GND")
	)
	(via
		(at 131.367276 -196.400928)
		(size 0.508)
		(drill 0.254)
		(layers "F.Cu" "B.Cu")
		(net "GND")
	)
	(via
		(at 131.57708 -346.09913)
		(size 0.4572)
		(drill 0.254)
		(layers "F.Cu" "B.Cu")
		(net "GND")
	)
	(via
		(at 74.248264 -131.245102)
		(size 0.508)
		(drill 0.254)
		(layers "F.Cu" "B.Cu")
		(net "GND")
	)
	(via
		(at 433.108354 -151.42464)
		(size 0.508)
		(drill 0.254)
		(layers "F.Cu" "B.Cu")
		(net "GND")
	)
	(via
		(at 147.750022 -27.04973)
		(size 0.508)
		(drill 0.254)
		(layers "F.Cu" "B.Cu")
		(net "GND")
	)
	(via
		(at 172.547788 -373.83847)
		(size 0.508)
		(drill 0.254)
		(layers "F.Cu" "B.Cu")
		(net "GND")
	)
	(via
		(at 314.366148 -130.966718)
		(size 0.508)
		(drill 0.254)
		(layers "F.Cu" "B.Cu")
		(net "GND")
	)
	(via
		(at 272.849848 -312.049922)
		(size 0.4064)
		(drill 0.2032)
		(layers "F.Cu" "B.Cu")
		(net "GND")
	)
	(via
		(at 371.13464 -71.451978)
		(size 0.508)
		(drill 0.254)
		(layers "F.Cu" "B.Cu")
		(net "GND")
	)
	(via
		(at 400.229832 -343.073482)
		(size 0.4572)
		(drill 0.254)
		(layers "F.Cu" "B.Cu")
		(net "GND")
	)
	(via
		(at 347.166438 -292.789102)
		(size 0.508)
		(drill 0.254)
		(layers "F.Cu" "B.Cu")
		(net "GND")
	)
	(via
		(at 416.574224 -341.805514)
		(size 0.4572)
		(drill 0.254)
		(layers "F.Cu" "B.Cu")
		(net "GND")
	)
	(via
		(at 125.457966 -145.083276)
		(size 0.508)
		(drill 0.254)
		(layers "F.Cu" "B.Cu")
		(net "GND")
	)
	(via
		(at 161.75482 -23.880318)
		(size 0.508)
		(drill 0.254)
		(layers "F.Cu" "B.Cu")
		(net "GND")
	)
	(via
		(at 152.94991 -311.099962)
		(size 0.4064)
		(drill 0.2032)
		(layers "F.Cu" "B.Cu")
		(net "GND")
	)
	(via
		(at 393.351766 -107.845098)
		(size 0.508)
		(drill 0.254)
		(layers "F.Cu" "B.Cu")
		(net "GND")
	)
	(via
		(at 290.89985 -278.799798)
		(size 0.4064)
		(drill 0.2032)
		(layers "F.Cu" "B.Cu")
		(net "GND")
	)
	(via
		(at 183.75122 -357.09987)
		(size 0.4572)
		(drill 0.254)
		(layers "F.Cu" "B.Cu")
		(net "GND")
	)
	(via
		(at 337.176872 -341.805514)
		(size 0.4572)
		(drill 0.254)
		(layers "F.Cu" "B.Cu")
		(net "GND")
	)
	(via
		(at 363.22127 -277.639272)
		(size 0.508)
		(drill 0.254)
		(layers "F.Cu" "B.Cu")
		(net "GND")
	)
	(via
		(at 313.699906 -312.999882)
		(size 0.4064)
		(drill 0.2032)
		(layers "F.Cu" "B.Cu")
		(net "GND")
	)
	(via
		(at 67.724782 -305.874928)
		(size 0.4064)
		(drill 0.2032)
		(layers "F.Cu" "B.Cu")
		(net "GND")
	)
	(via
		(at 21.872448 -351.611438)
		(size 0.4064)
		(drill 0.2032)
		(layers "F.Cu" "B.Cu")
		(net "GND")
	)
	(via
		(at 285.687262 -129.964942)
		(size 0.508)
		(drill 0.254)
		(layers "F.Cu" "B.Cu")
		(net "GND")
	)
	(via
		(at 276.341078 -38.49116)
		(size 0.508)
		(drill 0.254)
		(layers "F.Cu" "B.Cu")
		(net "GND")
	)
	(via
		(at 373.73941 -190.151766)
		(size 0.508)
		(drill 0.254)
		(layers "F.Cu" "B.Cu")
		(net "GND")
	)
	(via
		(at 286.149796 -275.949918)
		(size 0.4064)
		(drill 0.2032)
		(layers "F.Cu" "B.Cu")
		(net "GND")
	)
	(via
		(at 45.068236 -48.753014)
		(size 0.508)
		(drill 0.254)
		(layers "F.Cu" "B.Cu")
		(net "GND")
	)
	(via
		(at 311.799732 -285.449772)
		(size 0.4064)
		(drill 0.2032)
		(layers "F.Cu" "B.Cu")
		(net "GND")
	)
	(via
		(at 341.927942 -376.140218)
		(size 0.508)
		(drill 0.254)
		(layers "F.Cu" "B.Cu")
		(net "GND")
	)
	(via
		(at 32.8295 -354.098098)
		(size 0.4572)
		(drill 0.254)
		(layers "F.Cu" "B.Cu")
		(net "GND")
	)
	(via
		(at 27.347926 -382.84023)
		(size 0.508)
		(drill 0.254)
		(layers "F.Cu" "B.Cu")
		(net "GND")
	)
	(via
		(at 249.673364 -73.20026)
		(size 0.508)
		(drill 0.254)
		(layers "F.Cu" "B.Cu")
		(net "GND")
	)
	(via
		(at 175.749712 -272.149316)
		(size 0.4064)
		(drill 0.2032)
		(layers "F.Cu" "B.Cu")
		(net "GND")
	)
	(via
		(at 307.999892 -314.899802)
		(size 0.4064)
		(drill 0.2032)
		(layers "F.Cu" "B.Cu")
		(net "GND")
	)
	(via
		(at 244.254782 -34.990024)
		(size 0.508)
		(drill 0.254)
		(layers "F.Cu" "B.Cu")
		(net "GND")
	)
	(via
		(at 84.54771 -401.040092)
		(size 0.508)
		(drill 0.254)
		(layers "F.Cu" "B.Cu")
		(net "GND")
	)
	(via
		(at 57.447942 -64.312292)
		(size 0.508)
		(drill 0.254)
		(layers "F.Cu" "B.Cu")
		(net "GND")
	)
	(via
		(at 406.049988 -279.749758)
		(size 0.4064)
		(drill 0.2032)
		(layers "F.Cu" "B.Cu")
		(net "GND")
	)
	(via
		(at 50.14976 -311.099962)
		(size 0.4064)
		(drill 0.2032)
		(layers "F.Cu" "B.Cu")
		(net "GND")
	)
	(via
		(at 58.699908 -277.849838)
		(size 0.4064)
		(drill 0.2032)
		(layers "F.Cu" "B.Cu")
		(net "GND")
	)
	(via
		(at 205.898242 -21.738336)
		(size 0.508)
		(drill 0.254)
		(layers "F.Cu" "B.Cu")
		(net "GND")
	)
	(via
		(at 12.792964 -276.093174)
		(size 0.508)
		(drill 0.254)
		(layers "F.Cu" "B.Cu")
		(net "GND")
	)
	(via
		(at 53.48732 -98.844862)
		(size 0.508)
		(drill 0.254)
		(layers "F.Cu" "B.Cu")
		(net "GND")
	)
	(via
		(at 438.098184 -20.417536)
		(size 0.508)
		(drill 0.254)
		(layers "F.Cu" "B.Cu")
		(net "GND")
	)
	(via
		(at 198.550022 -286.399732)
		(size 0.4064)
		(drill 0.2032)
		(layers "F.Cu" "B.Cu")
		(net "GND")
	)
	(via
		(at 293.829994 -355.366066)
		(size 0.4572)
		(drill 0.254)
		(layers "F.Cu" "B.Cu")
		(net "GND")
	)
	(via
		(at 51.63312 -109.644942)
		(size 0.508)
		(drill 0.254)
		(layers "F.Cu" "B.Cu")
		(net "GND")
	)
	(via
		(at 231.807512 -235.737654)
		(size 0.508)
		(drill 0.254)
		(layers "F.Cu" "B.Cu")
		(net "GND")
	)
	(via
		(at 311.799732 -318.699896)
		(size 0.4064)
		(drill 0.2032)
		(layers "F.Cu" "B.Cu")
		(net "GND")
	)
	(via
		(at 463.037682 -113.297462)
		(size 0.508)
		(drill 0.254)
		(layers "F.Cu" "B.Cu")
		(net "GND")
	)
	(via
		(at 92.248736 -31.390082)
		(size 0.508)
		(drill 0.254)
		(layers "F.Cu" "B.Cu")
		(net "GND")
	)
	(via
		(at 426.94987 -311.099962)
		(size 0.4064)
		(drill 0.2032)
		(layers "F.Cu" "B.Cu")
		(net "GND")
	)
	(via
		(at 8.700516 -155.217114)
		(size 0.508)
		(drill 0.254)
		(layers "F.Cu" "B.Cu")
		(net "GND")
	)
	(via
		(at 120.603772 -285.267654)
		(size 0.508)
		(drill 0.254)
		(layers "F.Cu" "B.Cu")
		(net "GND")
	)
	(via
		(at 196.174868 -294.4749)
		(size 0.4064)
		(drill 0.2032)
		(layers "F.Cu" "B.Cu")
		(net "GND")
	)
	(via
		(at 55.849774 -275.949918)
		(size 0.4064)
		(drill 0.2032)
		(layers "F.Cu" "B.Cu")
		(net "GND")
	)
	(via
		(at 122.413522 -234.856782)
		(size 0.508)
		(drill 0.254)
		(layers "F.Cu" "B.Cu")
		(net "GND")
	)
	(via
		(at 119.174768 -290.68649)
		(size 0.508)
		(drill 0.254)
		(layers "F.Cu" "B.Cu")
		(net "GND")
	)
	(via
		(at 88.947752 -404.940262)
		(size 0.508)
		(drill 0.254)
		(layers "F.Cu" "B.Cu")
		(net "GND")
	)
	(via
		(at 117.547644 -382.73863)
		(size 0.508)
		(drill 0.254)
		(layers "F.Cu" "B.Cu")
		(net "GND")
	)
	(via
		(at 339.728048 -377.738386)
		(size 0.508)
		(drill 0.254)
		(layers "F.Cu" "B.Cu")
		(net "GND")
	)
	(via
		(at 281.394154 -341.805514)
		(size 0.4572)
		(drill 0.254)
		(layers "F.Cu" "B.Cu")
		(net "GND")
	)
	(via
		(at 196.998082 -122.098054)
		(size 0.508)
		(drill 0.254)
		(layers "F.Cu" "B.Cu")
		(net "GND")
	)
	(via
		(at 190.950088 -310.149748)
		(size 0.4064)
		(drill 0.2032)
		(layers "F.Cu" "B.Cu")
		(net "GND")
	)
	(via
		(at 155.800044 -314.899802)
		(size 0.4064)
		(drill 0.2032)
		(layers "F.Cu" "B.Cu")
		(net "GND")
	)
	(via
		(at 429.800004 -315.849762)
		(size 0.4064)
		(drill 0.2032)
		(layers "F.Cu" "B.Cu")
		(net "GND")
	)
	(via
		(at 52.524914 -296.37482)
		(size 0.4064)
		(drill 0.2032)
		(layers "F.Cu" "B.Cu")
		(net "GND")
	)
	(via
		(at 142.754096 -343.073482)
		(size 0.4572)
		(drill 0.254)
		(layers "F.Cu" "B.Cu")
		(net "GND")
	)
	(via
		(at 37.799772 -315.849762)
		(size 0.4064)
		(drill 0.2032)
		(layers "F.Cu" "B.Cu")
		(net "GND")
	)
	(via
		(at 296.938954 -344.831162)
		(size 0.4572)
		(drill 0.254)
		(layers "F.Cu" "B.Cu")
		(net "GND")
	)
	(via
		(at 300.12767 -408.840178)
		(size 0.508)
		(drill 0.254)
		(layers "F.Cu" "B.Cu")
		(net "GND")
	)
	(via
		(at 71.524876 -292.574726)
		(size 0.4064)
		(drill 0.2032)
		(layers "F.Cu" "B.Cu")
		(net "GND")
	)
	(via
		(at 57.274968 -297.32478)
		(size 0.4064)
		(drill 0.2032)
		(layers "F.Cu" "B.Cu")
		(net "GND")
	)
	(via
		(at 386.16382 -357.75773)
		(size 0.4064)
		(drill 0.2032)
		(layers "F.Cu" "B.Cu")
		(net "GND")
	)
	(via
		(at 154.37485 -273.574764)
		(size 0.4064)
		(drill 0.2032)
		(layers "F.Cu" "B.Cu")
		(net "GND")
	)
	(via
		(at 399.400014 -274.049744)
		(size 0.4064)
		(drill 0.2032)
		(layers "F.Cu" "B.Cu")
		(net "GND")
	)
	(via
		(at 47.15256 -145.821908)
		(size 0.508)
		(drill 0.254)
		(layers "F.Cu" "B.Cu")
		(net "GND")
	)
	(via
		(at 42.28084 -29.589984)
		(size 0.508)
		(drill 0.254)
		(layers "F.Cu" "B.Cu")
		(net "GND")
	)
	(via
		(at 35.899344 -316.799468)
		(size 0.4064)
		(drill 0.2032)
		(layers "F.Cu" "B.Cu")
		(net "GND")
	)
	(via
		(at 441.817252 -348.58579)
		(size 0.4064)
		(drill 0.2032)
		(layers "F.Cu" "B.Cu")
		(net "GND")
	)
	(via
		(at 66.299842 -277.849838)
		(size 0.4064)
		(drill 0.2032)
		(layers "F.Cu" "B.Cu")
		(net "GND")
	)
	(via
		(at 66.248788 -27.79014)
		(size 0.508)
		(drill 0.254)
		(layers "F.Cu" "B.Cu")
		(net "GND")
	)
	(via
		(at 307.049932 -307.299868)
		(size 0.4064)
		(drill 0.2032)
		(layers "F.Cu" "B.Cu")
		(net "GND")
	)
	(via
		(at 122.70105 -34.990278)
		(size 0.508)
		(drill 0.254)
		(layers "F.Cu" "B.Cu")
		(net "GND")
	)
	(via
		(at 340.894162 -221.986856)
		(size 0.4572)
		(drill 0.254)
		(layers "F.Cu" "B.Cu")
		(net "GND")
	)
	(via
		(at 243.120418 -306.849526)
		(size 0.508)
		(drill 0.254)
		(layers "F.Cu" "B.Cu")
		(net "GND")
	)
	(via
		(at 212.771228 -32.911796)
		(size 0.508)
		(drill 0.254)
		(layers "F.Cu" "B.Cu")
		(net "GND")
	)
	(via
		(at 198.550022 -275.949918)
		(size 0.4064)
		(drill 0.2032)
		(layers "F.Cu" "B.Cu")
		(net "GND")
	)
	(via
		(at 302.327818 -378.83846)
		(size 0.508)
		(drill 0.254)
		(layers "F.Cu" "B.Cu")
		(net "GND")
	)
	(via
		(at 298.499784 -317.749936)
		(size 0.4064)
		(drill 0.2032)
		(layers "F.Cu" "B.Cu")
		(net "GND")
	)
	(via
		(at 133.869684 -290.68649)
		(size 0.508)
		(drill 0.254)
		(layers "F.Cu" "B.Cu")
		(net "GND")
	)
	(via
		(at 80.147922 -380.141734)
		(size 0.508)
		(drill 0.254)
		(layers "F.Cu" "B.Cu")
		(net "GND")
	)
	(via
		(at 377.208288 -347.951806)
		(size 0.4572)
		(drill 0.254)
		(layers "F.Cu" "B.Cu")
		(net "GND")
	)
	(via
		(at 86.747858 -404.838662)
		(size 0.508)
		(drill 0.254)
		(layers "F.Cu" "B.Cu")
		(net "GND")
	)
	(via
		(at 83.44789 -64.312292)
		(size 0.508)
		(drill 0.254)
		(layers "F.Cu" "B.Cu")
		(net "GND")
	)
	(via
		(at 21.222208 -52.51704)
		(size 0.508)
		(drill 0.254)
		(layers "F.Cu" "B.Cu")
		(net "GND")
	)
	(via
		(at 72.228964 -147.314412)
		(size 0.508)
		(drill 0.254)
		(layers "F.Cu" "B.Cu")
		(net "GND")
	)
	(via
		(at 47.29988 -278.799798)
		(size 0.4064)
		(drill 0.2032)
		(layers "F.Cu" "B.Cu")
		(net "GND")
	)
	(via
		(at 199.500236 -306.349908)
		(size 0.4064)
		(drill 0.2032)
		(layers "F.Cu" "B.Cu")
		(net "GND")
	)
	(via
		(at 18.763488 -345.465146)
		(size 0.4064)
		(drill 0.2032)
		(layers "F.Cu" "B.Cu")
		(net "GND")
	)
	(via
		(at 445.33439 -47.936658)
		(size 0.508)
		(drill 0.254)
		(layers "F.Cu" "B.Cu")
		(net "GND")
	)
	(via
		(at 394.011912 -349.219774)
		(size 0.4572)
		(drill 0.254)
		(layers "F.Cu" "B.Cu")
		(net "GND")
	)
	(via
		(at 281.394154 -358.391714)
		(size 0.4572)
		(drill 0.254)
		(layers "F.Cu" "B.Cu")
		(net "GND")
	)
	(via
		(at 414.124902 -300.174914)
		(size 0.4064)
		(drill 0.2032)
		(layers "F.Cu" "B.Cu")
		(net "GND")
	)
	(via
		(at 127.97028 -291.32149)
		(size 0.508)
		(drill 0.254)
		(layers "F.Cu" "B.Cu")
		(net "GND")
	)
	(via
		(at 279.974802 -288.774886)
		(size 0.4064)
		(drill 0.2032)
		(layers "F.Cu" "B.Cu")
		(net "GND")
	)
	(via
		(at 194.749928 -275.949918)
		(size 0.4064)
		(drill 0.2032)
		(layers "F.Cu" "B.Cu")
		(net "GND")
	)
	(via
		(at 33.947862 -403.34184)
		(size 0.508)
		(drill 0.254)
		(layers "F.Cu" "B.Cu")
		(net "GND")
	)
	(via
		(at 262.827008 -259.576316)
		(size 0.508)
		(drill 0.254)
		(layers "F.Cu" "B.Cu")
		(net "GND")
	)
	(via
		(at 70.574916 -289.724846)
		(size 0.4064)
		(drill 0.2032)
		(layers "F.Cu" "B.Cu")
		(net "GND")
	)
	(via
		(at 279.974802 -303.024794)
		(size 0.4064)
		(drill 0.2032)
		(layers "F.Cu" "B.Cu")
		(net "GND")
	)
	(via
		(at 77.22489 -301.124874)
		(size 0.4064)
		(drill 0.2032)
		(layers "F.Cu" "B.Cu")
		(net "GND")
	)
	(via
		(at 333.900526 -80.775302)
		(size 0.508)
		(drill 0.254)
		(layers "F.Cu" "B.Cu")
		(net "GND")
	)
	(via
		(at 140.087096 -199.361806)
		(size 0.508)
		(drill 0.254)
		(layers "F.Cu" "B.Cu")
		(net "GND")
	)
	(via
		(at 84.54771 -398.34185)
		(size 0.508)
		(drill 0.254)
		(layers "F.Cu" "B.Cu")
		(net "GND")
	)
	(via
		(at 233.572558 -62.399926)
		(size 0.508)
		(drill 0.254)
		(layers "F.Cu" "B.Cu")
		(net "GND")
	)
	(via
		(at 42.747946 -397.038576)
		(size 0.508)
		(drill 0.254)
		(layers "F.Cu" "B.Cu")
		(net "GND")
	)
	(via
		(at 167.675052 -294.4749)
		(size 0.4064)
		(drill 0.2032)
		(layers "F.Cu" "B.Cu")
		(net "GND")
	)
	(via
		(at 235.536486 -92.262706)
		(size 0.508)
		(drill 0.254)
		(layers "F.Cu" "B.Cu")
		(net "GND")
	)
	(via
		(at 348.527878 -380.141988)
		(size 0.508)
		(drill 0.254)
		(layers "F.Cu" "B.Cu")
		(net "GND")
	)
	(via
		(at 244.649498 -169.57548)
		(size 0.508)
		(drill 0.254)
		(layers "F.Cu" "B.Cu")
		(net "GND")
	)
	(via
		(at 249.038364 -73.20026)
		(size 0.508)
		(drill 0.254)
		(layers "F.Cu" "B.Cu")
		(net "GND")
	)
	(via
		(at 413.174942 -302.074834)
		(size 0.4064)
		(drill 0.2032)
		(layers "F.Cu" "B.Cu")
		(net "GND")
	)
	(via
		(at 389.899906 -317.749936)
		(size 0.4064)
		(drill 0.2032)
		(layers "F.Cu" "B.Cu")
		(net "GND")
	)
	(via
		(at 160.549844 -312.049922)
		(size 0.4064)
		(drill 0.2032)
		(layers "F.Cu" "B.Cu")
		(net "GND")
	)
	(via
		(at 35.93846 -355.366066)
		(size 0.4572)
		(drill 0.254)
		(layers "F.Cu" "B.Cu")
		(net "GND")
	)
	(via
		(at 384.199384 -314.899548)
		(size 0.4064)
		(drill 0.2032)
		(layers "F.Cu" "B.Cu")
		(net "GND")
	)
	(via
		(at 189.999874 -318.699896)
		(size 0.4064)
		(drill 0.2032)
		(layers "F.Cu" "B.Cu")
		(net "GND")
	)
	(via
		(at 68.280788 -31.390082)
		(size 0.508)
		(drill 0.254)
		(layers "F.Cu" "B.Cu")
		(net "GND")
	)
	(via
		(at 263.66851 -59.974734)
		(size 0.508)
		(drill 0.254)
		(layers "F.Cu" "B.Cu")
		(net "GND")
	)
	(via
		(at 255.64084 -45.853858)
		(size 0.508)
		(drill 0.254)
		(layers "F.Cu" "B.Cu")
		(net "GND")
	)
	(via
		(at 136.164828 -342.439498)
		(size 0.4064)
		(drill 0.2032)
		(layers "F.Cu" "B.Cu")
		(net "GND")
	)
	(via
		(at 374.099328 -349.219774)
		(size 0.4572)
		(drill 0.254)
		(layers "F.Cu" "B.Cu")
		(net "GND")
	)
	(via
		(at 343.898982 -286.842454)
		(size 0.508)
		(drill 0.254)
		(layers "F.Cu" "B.Cu")
		(net "GND")
	)
	(via
		(at 31.747968 -375.040144)
		(size 0.508)
		(drill 0.254)
		(layers "F.Cu" "B.Cu")
		(net "GND")
	)
	(via
		(at 194.274948 -291.624766)
		(size 0.4064)
		(drill 0.2032)
		(layers "F.Cu" "B.Cu")
		(net "GND")
	)
	(via
		(at 310.849772 -280.699718)
		(size 0.4064)
		(drill 0.2032)
		(layers "F.Cu" "B.Cu")
		(net "GND")
	)
	(via
		(at 323.262244 -342.439498)
		(size 0.4064)
		(drill 0.2032)
		(layers "F.Cu" "B.Cu")
		(net "GND")
	)
	(via
		(at 139.424156 -26.319734)
		(size 0.508)
		(drill 0.254)
		(layers "F.Cu" "B.Cu")
		(net "GND")
	)
	(via
		(at 238.800894 -31.390336)
		(size 0.508)
		(drill 0.254)
		(layers "F.Cu" "B.Cu")
		(net "GND")
	)
	(via
		(at 128.547622 -384.041904)
		(size 0.4572)
		(drill 0.254)
		(layers "F.Cu" "B.Cu")
		(net "GND")
	)
	(via
		(at 73.547732 -408.738578)
		(size 0.508)
		(drill 0.254)
		(layers "F.Cu" "B.Cu")
		(net "GND")
	)
	(via
		(at 152.47493 -289.724846)
		(size 0.4064)
		(drill 0.2032)
		(layers "F.Cu" "B.Cu")
		(net "GND")
	)
	(via
		(at 167.835072 -345.465146)
		(size 0.4064)
		(drill 0.2032)
		(layers "F.Cu" "B.Cu")
		(net "GND")
	)
	(via
		(at 305.513232 -33.459674)
		(size 0.508)
		(drill 0.254)
		(layers "F.Cu" "B.Cu")
		(net "GND")
	)
	(via
		(at 366.51946 -147.18665)
		(size 0.508)
		(drill 0.254)
		(layers "F.Cu" "B.Cu")
		(net "GND")
	)
	(via
		(at 132.38099 -34.990024)
		(size 0.508)
		(drill 0.254)
		(layers "F.Cu" "B.Cu")
		(net "GND")
	)
	(via
		(at 410.324808 -297.32478)
		(size 0.4064)
		(drill 0.2032)
		(layers "F.Cu" "B.Cu")
		(net "GND")
	)
	(via
		(at 23.97506 -73.87463)
		(size 0.508)
		(drill 0.254)
		(layers "F.Cu" "B.Cu")
		(net "GND")
	)
	(via
		(at 197.125082 -289.724846)
		(size 0.4064)
		(drill 0.2032)
		(layers "F.Cu" "B.Cu")
		(net "GND")
	)
	(via
		(at 288.045144 -51.227482)
		(size 0.508)
		(drill 0.254)
		(layers "F.Cu" "B.Cu")
		(net "GND")
	)
	(via
		(at 45.051726 -98.845116)
		(size 0.508)
		(drill 0.254)
		(layers "F.Cu" "B.Cu")
		(net "GND")
	)
	(via
		(at 426.47489 -294.4749)
		(size 0.4064)
		(drill 0.2032)
		(layers "F.Cu" "B.Cu")
		(net "GND")
	)
	(via
		(at 451.638162 -101.386894)
		(size 0.508)
		(drill 0.254)
		(layers "F.Cu" "B.Cu")
		(net "GND")
	)
	(via
		(at 430.8602 -347.951806)
		(size 0.4572)
		(drill 0.254)
		(layers "F.Cu" "B.Cu")
		(net "GND")
	)
	(via
		(at 155.325064 -278.324818)
		(size 0.4064)
		(drill 0.2032)
		(layers "F.Cu" "B.Cu")
		(net "GND")
	)
	(via
		(at 396.84579 -150.9776)
		(size 0.508)
		(drill 0.254)
		(layers "F.Cu" "B.Cu")
		(net "GND")
	)
	(via
		(at 266.691618 -104.523286)
		(size 0.508)
		(drill 0.254)
		(layers "F.Cu" "B.Cu")
		(net "GND")
	)
	(via
		(at 330.587604 -357.75773)
		(size 0.4064)
		(drill 0.2032)
		(layers "F.Cu" "B.Cu")
		(net "GND")
	)
	(via
		(at 396.84579 -154.0256)
		(size 0.508)
		(drill 0.254)
		(layers "F.Cu" "B.Cu")
		(net "GND")
	)
	(via
		(at 126.347728 -376.140218)
		(size 0.4572)
		(drill 0.254)
		(layers "F.Cu" "B.Cu")
		(net "GND")
	)
	(via
		(at 114.966242 -292.789102)
		(size 0.508)
		(drill 0.254)
		(layers "F.Cu" "B.Cu")
		(net "GND")
	)
	(via
		(at 397.120872 -343.073482)
		(size 0.4572)
		(drill 0.254)
		(layers "F.Cu" "B.Cu")
		(net "GND")
	)
	(via
		(at 366.522 -213.995)
		(size 0.508)
		(drill 0.254)
		(layers "F.Cu" "B.Cu")
		(net "GND")
	)
	(via
		(at 49.1998 -317.749936)
		(size 0.4064)
		(drill 0.2032)
		(layers "F.Cu" "B.Cu")
		(net "GND")
	)
	(via
		(at 301.699422 -57.439814)
		(size 0.508)
		(drill 0.254)
		(layers "F.Cu" "B.Cu")
		(net "GND")
	)
	(via
		(at 71.049896 -311.099962)
		(size 0.4064)
		(drill 0.2032)
		(layers "F.Cu" "B.Cu")
		(net "GND")
	)
	(via
		(at 366.532414 -221.915482)
		(size 0.508)
		(drill 0.254)
		(layers "F.Cu" "B.Cu")
		(net "GND")
	)
	(via
		(at 172.976794 -138.15695)
		(size 0.508)
		(drill 0.254)
		(layers "F.Cu" "B.Cu")
		(net "GND")
	)
	(via
		(at 392.274806 -298.27474)
		(size 0.4064)
		(drill 0.2032)
		(layers "F.Cu" "B.Cu")
		(net "GND")
	)
	(via
		(at 328.93127 -6.292342)
		(size 0.508)
		(drill 0.254)
		(layers "F.Cu" "B.Cu")
		(net "GND")
	)
	(via
		(at 440.200034 -100.803964)
		(size 0.508)
		(drill 0.254)
		(layers "F.Cu" "B.Cu")
		(net "GND")
	)
	(via
		(at 80.147922 -408.840178)
		(size 0.508)
		(drill 0.254)
		(layers "F.Cu" "B.Cu")
		(net "GND")
	)
	(via
		(at 10.84326 -114.672364)
		(size 0.508)
		(drill 0.254)
		(layers "F.Cu" "B.Cu")
		(net "GND")
	)
	(via
		(at 159.347916 -395.938502)
		(size 0.508)
		(drill 0.254)
		(layers "F.Cu" "B.Cu")
		(net "GND")
	)
	(via
		(at 50.14976 -307.299868)
		(size 0.4064)
		(drill 0.2032)
		(layers "F.Cu" "B.Cu")
		(net "GND")
	)
	(via
		(at 100.031042 -123.795028)
		(size 0.508)
		(drill 0.254)
		(layers "F.Cu" "B.Cu")
		(net "GND")
	)
	(via
		(at 196.650102 -280.699718)
		(size 0.4064)
		(drill 0.2032)
		(layers "F.Cu" "B.Cu")
		(net "GND")
	)
	(via
		(at 6.600952 -33.19018)
		(size 0.508)
		(drill 0.254)
		(layers "F.Cu" "B.Cu")
		(net "GND")
	)
	(via
		(at 463.037682 -98.057462)
		(size 0.508)
		(drill 0.254)
		(layers "F.Cu" "B.Cu")
		(net "GND")
	)
	(via
		(at 209.24266 -181.19725)
		(size 0.508)
		(drill 0.254)
		(layers "F.Cu" "B.Cu")
		(net "GND")
	)
	(via
		(at 53.949854 -280.699718)
		(size 0.4064)
		(drill 0.2032)
		(layers "F.Cu" "B.Cu")
		(net "GND")
	)
	(via
		(at 246.102124 -58.731404)
		(size 0.508)
		(drill 0.254)
		(layers "F.Cu" "B.Cu")
		(net "GND")
	)
	(via
		(at 454.694544 -102.021894)
		(size 0.508)
		(drill 0.254)
		(layers "F.Cu" "B.Cu")
		(net "GND")
	)
	(via
		(at 184.77484 -299.224954)
		(size 0.4064)
		(drill 0.2032)
		(layers "F.Cu" "B.Cu")
		(net "GND")
	)
	(via
		(at 34.491676 -105.78211)
		(size 0.508)
		(drill 0.254)
		(layers "F.Cu" "B.Cu")
		(net "GND")
	)
	(via
		(at 163.247324 -352.245422)
		(size 0.4572)
		(drill 0.254)
		(layers "F.Cu" "B.Cu")
		(net "GND")
	)
	(via
		(at 419.824916 -299.224954)
		(size 0.4064)
		(drill 0.2032)
		(layers "F.Cu" "B.Cu")
		(net "GND")
	)
	(via
		(at 421.249602 -272.14957)
		(size 0.4064)
		(drill 0.2032)
		(layers "F.Cu" "B.Cu")
		(net "GND")
	)
	(via
		(at 88.947752 -397.140176)
		(size 0.508)
		(drill 0.254)
		(layers "F.Cu" "B.Cu")
		(net "GND")
	)
	(via
		(at 426.94987 -286.399732)
		(size 0.4064)
		(drill 0.2032)
		(layers "F.Cu" "B.Cu")
		(net "GND")
	)
	(via
		(at 63.912242 -345.465146)
		(size 0.4064)
		(drill 0.2032)
		(layers "F.Cu" "B.Cu")
		(net "GND")
	)
	(via
		(at 383.72796 -397.140176)
		(size 0.508)
		(drill 0.254)
		(layers "F.Cu" "B.Cu")
		(net "GND")
	)
	(via
		(at 440.548776 -33.19018)
		(size 0.508)
		(drill 0.254)
		(layers "F.Cu" "B.Cu")
		(net "GND")
	)
	(via
		(at 423.134536 -71.451978)
		(size 0.508)
		(drill 0.254)
		(layers "F.Cu" "B.Cu")
		(net "GND")
	)
	(via
		(at 452.775574 -311.15)
		(size 0.508)
		(drill 0.254)
		(layers "F.Cu" "B.Cu")
		(net "GND")
	)
	(via
		(at 298.974764 -296.37482)
		(size 0.4064)
		(drill 0.2032)
		(layers "F.Cu" "B.Cu")
		(net "GND")
	)
	(via
		(at 259.515102 -43.85691)
		(size 0.508)
		(drill 0.254)
		(layers "F.Cu" "B.Cu")
		(net "GND")
	)
	(via
		(at 381.146812 -1.135126)
		(size 0.508)
		(drill 0.254)
		(layers "F.Cu" "B.Cu")
		(net "GND")
	)
	(via
		(at 58.23204 -373.275098)
		(size 0.508)
		(drill 0.254)
		(layers "F.Cu" "B.Cu")
		(net "GND")
	)
	(via
		(at 299.512736 -104.240076)
		(size 0.508)
		(drill 0.254)
		(layers "F.Cu" "B.Cu")
		(net "GND")
	)
	(via
		(at 209.959448 -309.690516)
		(size 0.508)
		(drill 0.254)
		(layers "F.Cu" "B.Cu")
		(net "GND")
	)
	(via
		(at 269.329662 -342.439498)
		(size 0.4064)
		(drill 0.2032)
		(layers "F.Cu" "B.Cu")
		(net "GND")
	)
	(via
		(at 169.099992 -278.799798)
		(size 0.4064)
		(drill 0.2032)
		(layers "F.Cu" "B.Cu")
		(net "GND")
	)
	(via
		(at 147.258532 -207.709262)
		(size 0.508)
		(drill 0.254)
		(layers "F.Cu" "B.Cu")
		(net "GND")
	)
	(via
		(at 425.901104 -347.951806)
		(size 0.4572)
		(drill 0.254)
		(layers "F.Cu" "B.Cu")
		(net "GND")
	)
	(via
		(at 62.024768 -297.32478)
		(size 0.4064)
		(drill 0.2032)
		(layers "F.Cu" "B.Cu")
		(net "GND")
	)
	(via
		(at 377.12777 -382.73863)
		(size 0.508)
		(drill 0.254)
		(layers "F.Cu" "B.Cu")
		(net "GND")
	)
	(via
		(at 429.927766 -372.240302)
		(size 0.508)
		(drill 0.254)
		(layers "F.Cu" "B.Cu")
		(net "GND")
	)
	(via
		(at 426.94987 -303.499774)
		(size 0.4064)
		(drill 0.2032)
		(layers "F.Cu" "B.Cu")
		(net "GND")
	)
	(via
		(at 285.674816 -303.974754)
		(size 0.4064)
		(drill 0.2032)
		(layers "F.Cu" "B.Cu")
		(net "GND")
	)
	(via
		(at 438.336944 -352.245422)
		(size 0.4572)
		(drill 0.254)
		(layers "F.Cu" "B.Cu")
		(net "GND")
	)
	(via
		(at 404.624794 -284.974792)
		(size 0.4064)
		(drill 0.2032)
		(layers "F.Cu" "B.Cu")
		(net "GND")
	)
	(via
		(at 38.347904 -397.038576)
		(size 0.508)
		(drill 0.254)
		(layers "F.Cu" "B.Cu")
		(net "GND")
	)
	(via
		(at 365.773462 -73.20026)
		(size 0.508)
		(drill 0.254)
		(layers "F.Cu" "B.Cu")
		(net "GND")
	)
	(via
		(at 301.685452 -63.218314)
		(size 0.508)
		(drill 0.254)
		(layers "F.Cu" "B.Cu")
		(net "GND")
	)
	(via
		(at 198.308214 -52.536852)
		(size 0.508)
		(drill 0.254)
		(layers "F.Cu" "B.Cu")
		(net "GND")
	)
	(via
		(at 109.399324 -270.001492)
		(size 0.508)
		(drill 0.254)
		(layers "F.Cu" "B.Cu")
		(net "GND")
	)
	(via
		(at 153.42489 -285.924752)
		(size 0.4064)
		(drill 0.2032)
		(layers "F.Cu" "B.Cu")
		(net "GND")
	)
	(via
		(at 83.400138 -310.149748)
		(size 0.4064)
		(drill 0.2032)
		(layers "F.Cu" "B.Cu")
		(net "GND")
	)
	(via
		(at 181.483 -34.990024)
		(size 0.508)
		(drill 0.254)
		(layers "F.Cu" "B.Cu")
		(net "GND")
	)
	(via
		(at 281.496262 -129.68351)
		(size 0.508)
		(drill 0.254)
		(layers "F.Cu" "B.Cu")
		(net "GND")
	)
	(via
		(at 201.06894 -404.801832)
		(size 0.508)
		(drill 0.254)
		(layers "F.Cu" "B.Cu")
		(net "GND")
	)
	(via
		(at 51.712114 -23.355554)
		(size 0.508)
		(drill 0.254)
		(layers "F.Cu" "B.Cu")
		(net "GND")
	)
	(via
		(at 422.674796 -305.874928)
		(size 0.4064)
		(drill 0.2032)
		(layers "F.Cu" "B.Cu")
		(net "GND")
	)
	(via
		(at 165.09746 -358.391714)
		(size 0.4572)
		(drill 0.254)
		(layers "F.Cu" "B.Cu")
		(net "GND")
	)
	(via
		(at 92.26423 -341.805514)
		(size 0.4572)
		(drill 0.254)
		(layers "F.Cu" "B.Cu")
		(net "GND")
	)
	(via
		(at 300.12767 -403.738588)
		(size 0.508)
		(drill 0.254)
		(layers "F.Cu" "B.Cu")
		(net "GND")
	)
	(via
		(at 166.725092 -285.924752)
		(size 0.4064)
		(drill 0.2032)
		(layers "F.Cu" "B.Cu")
		(net "GND")
	)
	(via
		(at 131.57708 -343.073482)
		(size 0.4572)
		(drill 0.254)
		(layers "F.Cu" "B.Cu")
		(net "GND")
	)
	(via
		(at 170.347894 -382.73863)
		(size 0.508)
		(drill 0.254)
		(layers "F.Cu" "B.Cu")
		(net "GND")
	)
	(via
		(at 21.290026 -73.85177)
		(size 0.508)
		(drill 0.254)
		(layers "F.Cu" "B.Cu")
		(net "GND")
	)
	(via
		(at 133.57352 -72.56526)
		(size 0.508)
		(drill 0.254)
		(layers "F.Cu" "B.Cu")
		(net "GND")
	)
	(via
		(at 2.63652 -51.661822)
		(size 0.508)
		(drill 0.254)
		(layers "F.Cu" "B.Cu")
		(net "GND")
	)
	(via
		(at 385.87299 -156.3624)
		(size 0.508)
		(drill 0.254)
		(layers "F.Cu" "B.Cu")
		(net "GND")
	)
	(via
		(at 313.224926 -297.32478)
		(size 0.4064)
		(drill 0.2032)
		(layers "F.Cu" "B.Cu")
		(net "GND")
	)
	(via
		(at 124.55525 -29.590238)
		(size 0.508)
		(drill 0.254)
		(layers "F.Cu" "B.Cu")
		(net "GND")
	)
	(via
		(at 372.966234 -261.798054)
		(size 0.508)
		(drill 0.254)
		(layers "F.Cu" "B.Cu")
		(net "GND")
	)
	(via
		(at 131.62534 -292.789102)
		(size 0.508)
		(drill 0.254)
		(layers "F.Cu" "B.Cu")
		(net "GND")
	)
	(via
		(at 366.971326 -29.311854)
		(size 0.508)
		(drill 0.254)
		(layers "F.Cu" "B.Cu")
		(net "GND")
	)
	(via
		(at 169.574972 -289.724846)
		(size 0.4064)
		(drill 0.2032)
		(layers "F.Cu" "B.Cu")
		(net "GND")
	)
	(via
		(at 338.435696 -346.09913)
		(size 0.4572)
		(drill 0.254)
		(layers "F.Cu" "B.Cu")
		(net "GND")
	)
	(via
		(at 103.219758 -380.782068)
		(size 0.508)
		(drill 0.254)
		(layers "F.Cu" "B.Cu")
		(net "GND")
	)
	(via
		(at 45.87494 -288.774886)
		(size 0.4064)
		(drill 0.2032)
		(layers "F.Cu" "B.Cu")
		(net "GND")
	)
	(via
		(at 466.835998 -394.523976)
		(size 0.508)
		(drill 0.254)
		(layers "F.Cu" "B.Cu")
		(net "GND")
	)
	(via
		(at 408.424888 -289.724846)
		(size 0.4064)
		(drill 0.2032)
		(layers "F.Cu" "B.Cu")
		(net "GND")
	)
	(via
		(at 304.527712 -395.938502)
		(size 0.508)
		(drill 0.254)
		(layers "F.Cu" "B.Cu")
		(net "GND")
	)
	(via
		(at 132.270754 -306.607718)
		(size 0.508)
		(drill 0.254)
		(layers "F.Cu" "B.Cu")
		(net "GND")
	)
	(via
		(at 226.491546 -107.50423)
		(size 0.508)
		(drill 0.254)
		(layers "F.Cu" "B.Cu")
		(net "GND")
	)
	(via
		(at 190.348108 -134.845044)
		(size 0.508)
		(drill 0.254)
		(layers "F.Cu" "B.Cu")
		(net "GND")
	)
	(via
		(at 295.174924 -287.824926)
		(size 0.4064)
		(drill 0.2032)
		(layers "F.Cu" "B.Cu")
		(net "GND")
	)
	(via
		(at 286.906462 -111.44504)
		(size 0.508)
		(drill 0.254)
		(layers "F.Cu" "B.Cu")
		(net "GND")
	)
	(via
		(at 259.973826 -241.686588)
		(size 0.508)
		(drill 0.254)
		(layers "F.Cu" "B.Cu")
		(net "GND")
	)
	(via
		(at 29.54782 -407.24201)
		(size 0.508)
		(drill 0.254)
		(layers "F.Cu" "B.Cu")
		(net "GND")
	)
	(via
		(at 80.147922 -371.140228)
		(size 0.508)
		(drill 0.254)
		(layers "F.Cu" "B.Cu")
		(net "GND")
	)
	(via
		(at 159.347916 -371.140228)
		(size 0.508)
		(drill 0.254)
		(layers "F.Cu" "B.Cu")
		(net "GND")
	)
	(via
		(at 147.276058 -224.536)
		(size 0.508)
		(drill 0.254)
		(layers "F.Cu" "B.Cu")
		(net "GND")
	)
	(via
		(at 69.624956 -294.4749)
		(size 0.4064)
		(drill 0.2032)
		(layers "F.Cu" "B.Cu")
		(net "GND")
	)
	(via
		(at 374.927876 -398.34185)
		(size 0.508)
		(drill 0.254)
		(layers "F.Cu" "B.Cu")
		(net "GND")
	)
	(via
		(at 417.138358 -73.20026)
		(size 0.508)
		(drill 0.254)
		(layers "F.Cu" "B.Cu")
		(net "GND")
	)
	(via
		(at 83.400138 -283.550106)
		(size 0.4064)
		(drill 0.2032)
		(layers "F.Cu" "B.Cu")
		(net "GND")
	)
	(via
		(at 176.94783 -401.040092)
		(size 0.508)
		(drill 0.254)
		(layers "F.Cu" "B.Cu")
		(net "GND")
	)
	(via
		(at 416.499802 -318.699896)
		(size 0.4064)
		(drill 0.2032)
		(layers "F.Cu" "B.Cu")
		(net "GND")
	)
	(via
		(at 121.947686 -403.34184)
		(size 0.4572)
		(drill 0.254)
		(layers "F.Cu" "B.Cu")
		(net "GND")
	)
	(via
		(at 199.64019 -136.373362)
		(size 0.508)
		(drill 0.254)
		(layers "F.Cu" "B.Cu")
		(net "GND")
	)
	(via
		(at 413.465264 -346.09913)
		(size 0.4572)
		(drill 0.254)
		(layers "F.Cu" "B.Cu")
		(net "GND")
	)
	(via
		(at 249.038364 -72.56526)
		(size 0.508)
		(drill 0.254)
		(layers "F.Cu" "B.Cu")
		(net "GND")
	)
	(via
		(at 378.467112 -343.073482)
		(size 0.4572)
		(drill 0.254)
		(layers "F.Cu" "B.Cu")
		(net "GND")
	)
	(via
		(at 167.732964 -100.64496)
		(size 0.508)
		(drill 0.254)
		(layers "F.Cu" "B.Cu")
		(net "GND")
	)
	(via
		(at 34.308288 -354.732082)
		(size 0.4064)
		(drill 0.2032)
		(layers "F.Cu" "B.Cu")
		(net "GND")
	)
	(via
		(at 144.098264 -204.780896)
		(size 0.508)
		(drill 0.254)
		(layers "F.Cu" "B.Cu")
		(net "GND")
	)
	(via
		(at 335.328006 -378.94006)
		(size 0.508)
		(drill 0.254)
		(layers "F.Cu" "B.Cu")
		(net "GND")
	)
	(via
		(at 462.363312 -285.569406)
		(size 0.508)
		(drill 0.254)
		(layers "F.Cu" "B.Cu")
		(net "GND")
	)
	(via
		(at 425.527724 -373.441976)
		(size 0.508)
		(drill 0.254)
		(layers "F.Cu" "B.Cu")
		(net "GND")
	)
	(via
		(at 285.199836 -318.699896)
		(size 0.4064)
		(drill 0.2032)
		(layers "F.Cu" "B.Cu")
		(net "GND")
	)
	(via
		(at 275.699728 -309.199788)
		(size 0.4064)
		(drill 0.2032)
		(layers "F.Cu" "B.Cu")
		(net "GND")
	)
	(via
		(at 28.461716 -357.123746)
		(size 0.4572)
		(drill 0.254)
		(layers "F.Cu" "B.Cu")
		(net "GND")
	)
	(via
		(at 70.574916 -300.174914)
		(size 0.4064)
		(drill 0.2032)
		(layers "F.Cu" "B.Cu")
		(net "GND")
	)
	(via
		(at 327.478644 -342.439498)
		(size 0.4064)
		(drill 0.2032)
		(layers "F.Cu" "B.Cu")
		(net "GND")
	)
	(via
		(at 298.024804 -285.924752)
		(size 0.4064)
		(drill 0.2032)
		(layers "F.Cu" "B.Cu")
		(net "GND")
	)
	(via
		(at 293.527734 -383.940304)
		(size 0.508)
		(drill 0.254)
		(layers "F.Cu" "B.Cu")
		(net "GND")
	)
	(via
		(at 339.09 -160.782)
		(size 0.508)
		(drill 0.254)
		(layers "F.Cu" "B.Cu")
		(net "GND")
	)
	(via
		(at 414.431988 -13.613638)
		(size 0.508)
		(drill 0.254)
		(layers "F.Cu" "B.Cu")
		(net "GND")
	)
	(via
		(at 128.586484 -209.471006)
		(size 0.508)
		(drill 0.254)
		(layers "F.Cu" "B.Cu")
		(net "GND")
	)
	(via
		(at 326.371204 -357.75773)
		(size 0.4064)
		(drill 0.2032)
		(layers "F.Cu" "B.Cu")
		(net "GND")
	)
	(via
		(at 328.384408 -72.56526)
		(size 0.508)
		(drill 0.254)
		(layers "F.Cu" "B.Cu")
		(net "GND")
	)
	(via
		(at 114.910616 -135.55726)
		(size 0.508)
		(drill 0.254)
		(layers "F.Cu" "B.Cu")
		(net "GND")
	)
	(via
		(at 294.771064 -203.4286)
		(size 0.508)
		(drill 0.254)
		(layers "F.Cu" "B.Cu")
		(net "GND")
	)
	(via
		(at 26.208736 -299.133514)
		(size 0.508)
		(drill 0.254)
		(layers "F.Cu" "B.Cu")
		(net "GND")
	)
	(via
		(at 297.074844 -293.52494)
		(size 0.4064)
		(drill 0.2032)
		(layers "F.Cu" "B.Cu")
		(net "GND")
	)
	(via
		(at 270.80845 -346.09913)
		(size 0.4572)
		(drill 0.254)
		(layers "F.Cu" "B.Cu")
		(net "GND")
	)
	(via
		(at 0.77089 -355.101144)
		(size 0.508)
		(drill 0.254)
		(layers "F.Cu" "B.Cu")
		(net "GND")
	)
	(via
		(at 422.548304 -142.15491)
		(size 0.508)
		(drill 0.254)
		(layers "F.Cu" "B.Cu")
		(net "GND")
	)
	(via
		(at 248.757948 -58.791094)
		(size 0.508)
		(drill 0.254)
		(layers "F.Cu" "B.Cu")
		(net "GND")
	)
	(via
		(at 76.71943 -350.977454)
		(size 0.4572)
		(drill 0.254)
		(layers "F.Cu" "B.Cu")
		(net "GND")
	)
	(via
		(at 190.348108 -149.355048)
		(size 0.508)
		(drill 0.254)
		(layers "F.Cu" "B.Cu")
		(net "GND")
	)
	(via
		(at 275.699474 -57.439814)
		(size 0.508)
		(drill 0.254)
		(layers "F.Cu" "B.Cu")
		(net "GND")
	)
	(via
		(at 74.84999 -311.099962)
		(size 0.4064)
		(drill 0.2032)
		(layers "F.Cu" "B.Cu")
		(net "GND")
	)
	(via
		(at 300.12767 -401.040092)
		(size 0.508)
		(drill 0.254)
		(layers "F.Cu" "B.Cu")
		(net "GND")
	)
	(via
		(at 38.401752 -122.091958)
		(size 0.508)
		(drill 0.254)
		(layers "F.Cu" "B.Cu")
		(net "GND")
	)
	(via
		(at 190.348108 -129.445004)
		(size 0.508)
		(drill 0.254)
		(layers "F.Cu" "B.Cu")
		(net "GND")
	)
	(via
		(at 163.747958 -410.041852)
		(size 0.508)
		(drill 0.254)
		(layers "F.Cu" "B.Cu")
		(net "GND")
	)
	(via
		(at 292.32479 -287.899856)
		(size 0.4064)
		(drill 0.2032)
		(layers "F.Cu" "B.Cu")
		(net "GND")
	)
	(via
		(at 124.050552 -238.481362)
		(size 0.508)
		(drill 0.254)
		(layers "F.Cu" "B.Cu")
		(net "GND")
	)
	(via
		(at 45.939202 -29.311854)
		(size 0.508)
		(drill 0.254)
		(layers "F.Cu" "B.Cu")
		(net "GND")
	)
	(via
		(at 387.525006 -286.874966)
		(size 0.4064)
		(drill 0.2032)
		(layers "F.Cu" "B.Cu")
		(net "GND")
	)
	(via
		(at 34.679636 -358.391714)
		(size 0.4572)
		(drill 0.254)
		(layers "F.Cu" "B.Cu")
		(net "GND")
	)
	(via
		(at 366.522 -212.979)
		(size 0.508)
		(drill 0.254)
		(layers "F.Cu" "B.Cu")
		(net "GND")
	)
	(via
		(at 73.61047 -341.805514)
		(size 0.4572)
		(drill 0.254)
		(layers "F.Cu" "B.Cu")
		(net "GND")
	)
	(via
		(at 101.974904 -74.58583)
		(size 0.508)
		(drill 0.254)
		(layers "F.Cu" "B.Cu")
		(net "GND")
	)
	(via
		(at 14.705838 -287.956752)
		(size 0.508)
		(drill 0.254)
		(layers "F.Cu" "B.Cu")
		(net "GND")
	)
	(via
		(at 302.871124 -29.311854)
		(size 0.508)
		(drill 0.254)
		(layers "F.Cu" "B.Cu")
		(net "GND")
	)
	(via
		(at 431.74793 -64.312292)
		(size 0.508)
		(drill 0.254)
		(layers "F.Cu" "B.Cu")
		(net "GND")
	)
	(via
		(at 429.381412 -351.611438)
		(size 0.4064)
		(drill 0.2032)
		(layers "F.Cu" "B.Cu")
		(net "GND")
	)
	(via
		(at 73.547732 -411.141926)
		(size 0.508)
		(drill 0.254)
		(layers "F.Cu" "B.Cu")
		(net "GND")
	)
	(via
		(at 164.349938 -280.699718)
		(size 0.4064)
		(drill 0.2032)
		(layers "F.Cu" "B.Cu")
		(net "GND")
	)
	(via
		(at 197.407022 -49.574704)
		(size 0.508)
		(drill 0.254)
		(layers "F.Cu" "B.Cu")
		(net "GND")
	)
	(via
		(at 178.124866 -297.32478)
		(size 0.4064)
		(drill 0.2032)
		(layers "F.Cu" "B.Cu")
		(net "GND")
	)
	(via
		(at 45.87494 -284.024832)
		(size 0.4064)
		(drill 0.2032)
		(layers "F.Cu" "B.Cu")
		(net "GND")
	)
	(via
		(at 77.947774 -409.940252)
		(size 0.508)
		(drill 0.254)
		(layers "F.Cu" "B.Cu")
		(net "GND")
	)
	(via
		(at 219.60205 -195.707)
		(size 0.508)
		(drill 0.254)
		(layers "F.Cu" "B.Cu")
		(net "GND")
	)
	(via
		(at 432.12766 -373.83847)
		(size 0.508)
		(drill 0.254)
		(layers "F.Cu" "B.Cu")
		(net "GND")
	)
	(via
		(at 94.55785 -58.156094)
		(size 0.508)
		(drill 0.254)
		(layers "F.Cu" "B.Cu")
		(net "GND")
	)
	(via
		(at 381.527812 -373.441976)
		(size 0.508)
		(drill 0.254)
		(layers "F.Cu" "B.Cu")
		(net "GND")
	)
	(via
		(at 385.625086 -296.37482)
		(size 0.4064)
		(drill 0.2032)
		(layers "F.Cu" "B.Cu")
		(net "GND")
	)
	(via
		(at 232.53446 -246.351044)
		(size 0.508)
		(drill 0.254)
		(layers "F.Cu" "B.Cu")
		(net "GND")
	)
	(via
		(at 301.676562 -215.832436)
		(size 0.508)
		(drill 0.254)
		(layers "F.Cu" "B.Cu")
		(net "GND")
	)
	(via
		(at 405.17699 -138.15695)
		(size 0.508)
		(drill 0.254)
		(layers "F.Cu" "B.Cu")
		(net "GND")
	)
	(via
		(at 246.414798 -26.171398)
		(size 0.508)
		(drill 0.254)
		(layers "F.Cu" "B.Cu")
		(net "GND")
	)
	(via
		(at 286.35325 -357.123746)
		(size 0.4572)
		(drill 0.254)
		(layers "F.Cu" "B.Cu")
		(net "GND")
	)
	(via
		(at 46.744128 -354.732082)
		(size 0.4064)
		(drill 0.2032)
		(layers "F.Cu" "B.Cu")
		(net "GND")
	)
	(via
		(at 283.299916 -274.049744)
		(size 0.4064)
		(drill 0.2032)
		(layers "F.Cu" "B.Cu")
		(net "GND")
	)
	(via
		(at 66.299842 -317.749936)
		(size 0.4064)
		(drill 0.2032)
		(layers "F.Cu" "B.Cu")
		(net "GND")
	)
	(via
		(at 370.61902 -345.465146)
		(size 0.4064)
		(drill 0.2032)
		(layers "F.Cu" "B.Cu")
		(net "GND")
	)
	(via
		(at 287.099756 -281.649932)
		(size 0.4064)
		(drill 0.2032)
		(layers "F.Cu" "B.Cu")
		(net "GND")
	)
	(via
		(at 67.249802 -312.049922)
		(size 0.4064)
		(drill 0.2032)
		(layers "F.Cu" "B.Cu")
		(net "GND")
	)
	(via
		(at 301.03826 -73.20026)
		(size 0.508)
		(drill 0.254)
		(layers "F.Cu" "B.Cu")
		(net "GND")
	)
	(via
		(at 302.774858 -292.57498)
		(size 0.4064)
		(drill 0.2032)
		(layers "F.Cu" "B.Cu")
		(net "GND")
	)
	(via
		(at 302.38446 -73.20026)
		(size 0.508)
		(drill 0.254)
		(layers "F.Cu" "B.Cu")
		(net "GND")
	)
	(via
		(at 329.108816 -346.09913)
		(size 0.4572)
		(drill 0.254)
		(layers "F.Cu" "B.Cu")
		(net "GND")
	)
	(via
		(at 181.92496 -307.774848)
		(size 0.4064)
		(drill 0.2032)
		(layers "F.Cu" "B.Cu")
		(net "GND")
	)
	(via
		(at 182.272432 -351.611438)
		(size 0.4064)
		(drill 0.2032)
		(layers "F.Cu" "B.Cu")
		(net "GND")
	)
	(via
		(at 141.650974 -262.912352)
		(size 0.508)
		(drill 0.254)
		(layers "F.Cu" "B.Cu")
		(net "GND")
	)
	(via
		(at 324.369684 -351.611438)
		(size 0.4064)
		(drill 0.2032)
		(layers "F.Cu" "B.Cu")
		(net "GND")
	)
	(via
		(at 255.681226 -237.190788)
		(size 0.508)
		(drill 0.254)
		(layers "F.Cu" "B.Cu")
		(net "GND")
	)
	(via
		(at 420.299896 -318.699896)
		(size 0.4064)
		(drill 0.2032)
		(layers "F.Cu" "B.Cu")
		(net "GND")
	)
	(via
		(at 226.491546 -106.79303)
		(size 0.508)
		(drill 0.254)
		(layers "F.Cu" "B.Cu")
		(net "GND")
	)
	(via
		(at 44.671234 -29.311854)
		(size 0.508)
		(drill 0.254)
		(layers "F.Cu" "B.Cu")
		(net "GND")
	)
	(via
		(at 424.64228 -341.805514)
		(size 0.4572)
		(drill 0.254)
		(layers "F.Cu" "B.Cu")
		(net "GND")
	)
	(via
		(at 281.874722 -288.774886)
		(size 0.4064)
		(drill 0.2032)
		(layers "F.Cu" "B.Cu")
		(net "GND")
	)
	(via
		(at 247.356122 -127.021844)
		(size 0.508)
		(drill 0.254)
		(layers "F.Cu" "B.Cu")
		(net "GND")
	)
	(via
		(at 346.43187 -254.21717)
		(size 0.508)
		(drill 0.254)
		(layers "F.Cu" "B.Cu")
		(net "GND")
	)
	(via
		(at 313.935364 -342.439498)
		(size 0.4064)
		(drill 0.2032)
		(layers "F.Cu" "B.Cu")
		(net "GND")
	)
	(via
		(at 163.874958 -292.57498)
		(size 0.4064)
		(drill 0.2032)
		(layers "F.Cu" "B.Cu")
		(net "GND")
	)
	(via
		(at 295.727882 -369.938554)
		(size 0.508)
		(drill 0.254)
		(layers "F.Cu" "B.Cu")
		(net "GND")
	)
	(via
		(at 337.00847 -286.842454)
		(size 0.508)
		(drill 0.254)
		(layers "F.Cu" "B.Cu")
		(net "GND")
	)
	(via
		(at 403.00656 -107.844844)
		(size 0.508)
		(drill 0.254)
		(layers "F.Cu" "B.Cu")
		(net "GND")
	)
	(via
		(at 276.649434 -272.14957)
		(size 0.4064)
		(drill 0.2032)
		(layers "F.Cu" "B.Cu")
		(net "GND")
	)
	(via
		(at 365.05896 -304.373534)
		(size 0.508)
		(drill 0.254)
		(layers "F.Cu" "B.Cu")
		(net "GND")
	)
	(via
		(at 317.175134 -260.569456)
		(size 0.508)
		(drill 0.254)
		(layers "F.Cu" "B.Cu")
		(net "GND")
	)
	(via
		(at 52.85232 -109.644942)
		(size 0.508)
		(drill 0.254)
		(layers "F.Cu" "B.Cu")
		(net "GND")
	)
	(via
		(at 416.974782 -291.624766)
		(size 0.4064)
		(drill 0.2032)
		(layers "F.Cu" "B.Cu")
		(net "GND")
	)
	(via
		(at 447.613278 -31.118302)
		(size 0.508)
		(drill 0.254)
		(layers "F.Cu" "B.Cu")
		(net "GND")
	)
	(via
		(at 339.728048 -371.140228)
		(size 0.508)
		(drill 0.254)
		(layers "F.Cu" "B.Cu")
		(net "GND")
	)
	(via
		(at 451.459346 -291.546788)
		(size 0.508)
		(drill 0.254)
		(layers "F.Cu" "B.Cu")
		(net "GND")
	)
	(via
		(at 301.824898 -303.974754)
		(size 0.4064)
		(drill 0.2032)
		(layers "F.Cu" "B.Cu")
		(net "GND")
	)
	(via
		(at 416.024822 -287.824926)
		(size 0.4064)
		(drill 0.2032)
		(layers "F.Cu" "B.Cu")
		(net "GND")
	)
	(via
		(at 335.326736 -350.977454)
		(size 0.4572)
		(drill 0.254)
		(layers "F.Cu" "B.Cu")
		(net "GND")
	)
	(via
		(at 420.901114 -251.669042)
		(size 0.508)
		(drill 0.254)
		(layers "F.Cu" "B.Cu")
		(net "GND")
	)
	(via
		(at 273.324828 -285.924752)
		(size 0.4064)
		(drill 0.2032)
		(layers "F.Cu" "B.Cu")
		(net "GND")
	)
	(via
		(at 415.074862 -305.874928)
		(size 0.4064)
		(drill 0.2032)
		(layers "F.Cu" "B.Cu")
		(net "GND")
	)
	(via
		(at 126.347728 -404.838662)
		(size 0.508)
		(drill 0.254)
		(layers "F.Cu" "B.Cu")
		(net "GND")
	)
	(via
		(at 279.907746 -89.78773)
		(size 0.508)
		(drill 0.254)
		(layers "F.Cu" "B.Cu")
		(net "GND")
	)
	(via
		(at 187.149994 -274.999958)
		(size 0.4064)
		(drill 0.2032)
		(layers "F.Cu" "B.Cu")
		(net "GND")
	)
	(via
		(at 134.68604 -341.805514)
		(size 0.4572)
		(drill 0.254)
		(layers "F.Cu" "B.Cu")
		(net "GND")
	)
	(via
		(at 251.443744 -131.960874)
		(size 0.508)
		(drill 0.254)
		(layers "F.Cu" "B.Cu")
		(net "GND")
	)
	(via
		(at 440.202066 -58.096404)
		(size 0.508)
		(drill 0.254)
		(layers "F.Cu" "B.Cu")
		(net "GND")
	)
	(via
		(at 84.54771 -372.341902)
		(size 0.508)
		(drill 0.254)
		(layers "F.Cu" "B.Cu")
		(net "GND")
	)
	(via
		(at 79.59979 -304.449734)
		(size 0.4064)
		(drill 0.2032)
		(layers "F.Cu" "B.Cu")
		(net "GND")
	)
	(via
		(at 330.927964 -398.34185)
		(size 0.508)
		(drill 0.254)
		(layers "F.Cu" "B.Cu")
		(net "GND")
	)
	(via
		(at 32.6009 -31.390336)
		(size 0.508)
		(drill 0.254)
		(layers "F.Cu" "B.Cu")
		(net "GND")
	)
	(via
		(at 402.249894 -279.749758)
		(size 0.4064)
		(drill 0.2032)
		(layers "F.Cu" "B.Cu")
		(net "GND")
	)
	(via
		(at 139.440158 -74.58583)
		(size 0.508)
		(drill 0.254)
		(layers "F.Cu" "B.Cu")
		(net "GND")
	)
	(via
		(at 312.305192 -349.219774)
		(size 0.4572)
		(drill 0.254)
		(layers "F.Cu" "B.Cu")
		(net "GND")
	)
	(via
		(at 159.124904 -279.274778)
		(size 0.4064)
		(drill 0.2032)
		(layers "F.Cu" "B.Cu")
		(net "GND")
	)
	(via
		(at 277.124922 -289.724846)
		(size 0.4064)
		(drill 0.2032)
		(layers "F.Cu" "B.Cu")
		(net "GND")
	)
	(via
		(at 421.53332 -357.123746)
		(size 0.4572)
		(drill 0.254)
		(layers "F.Cu" "B.Cu")
		(net "GND")
	)
	(via
		(at 62.433454 -349.219774)
		(size 0.4572)
		(drill 0.254)
		(layers "F.Cu" "B.Cu")
		(net "GND")
	)
	(via
		(at 270.437102 -351.611438)
		(size 0.4064)
		(drill 0.2032)
		(layers "F.Cu" "B.Cu")
		(net "GND")
	)
	(via
		(at 372.249192 -344.831162)
		(size 0.4572)
		(drill 0.254)
		(layers "F.Cu" "B.Cu")
		(net "GND")
	)
	(via
		(at 315.414152 -346.09913)
		(size 0.4572)
		(drill 0.254)
		(layers "F.Cu" "B.Cu")
		(net "GND")
	)
	(via
		(at 40.649906 -319.65011)
		(size 0.4064)
		(drill 0.2032)
		(layers "F.Cu" "B.Cu")
		(net "GND")
	)
	(via
		(at 44.18457 -73.20026)
		(size 0.508)
		(drill 0.254)
		(layers "F.Cu" "B.Cu")
		(net "GND")
	)
	(via
		(at 448.384676 -400.160236)
		(size 0.508)
		(drill 0.254)
		(layers "F.Cu" "B.Cu")
		(net "GND")
	)
	(via
		(at 157.699964 -306.349908)
		(size 0.4064)
		(drill 0.2032)
		(layers "F.Cu" "B.Cu")
		(net "GND")
	)
	(via
		(at 199.500236 -285.450026)
		(size 0.4064)
		(drill 0.2032)
		(layers "F.Cu" "B.Cu")
		(net "GND")
	)
	(via
		(at 119.512588 -354.732082)
		(size 0.4064)
		(drill 0.2032)
		(layers "F.Cu" "B.Cu")
		(net "GND")
	)
	(via
		(at 27.668982 -292.732714)
		(size 0.508)
		(drill 0.254)
		(layers "F.Cu" "B.Cu")
		(net "GND")
	)
	(via
		(at 270.474948 -283.074872)
		(size 0.4064)
		(drill 0.2032)
		(layers "F.Cu" "B.Cu")
		(net "GND")
	)
	(via
		(at 191.440054 -73.87463)
		(size 0.508)
		(drill 0.254)
		(layers "F.Cu" "B.Cu")
		(net "GND")
	)
	(via
		(at 279.974802 -285.924752)
		(size 0.4064)
		(drill 0.2032)
		(layers "F.Cu" "B.Cu")
		(net "GND")
	)
	(via
		(at 408.424888 -294.4749)
		(size 0.4064)
		(drill 0.2032)
		(layers "F.Cu" "B.Cu")
		(net "GND")
	)
	(via
		(at 49.1998 -308.249828)
		(size 0.4064)
		(drill 0.2032)
		(layers "F.Cu" "B.Cu")
		(net "GND")
	)
	(via
		(at 200.908158 -123.904502)
		(size 0.508)
		(drill 0.254)
		(layers "F.Cu" "B.Cu")
		(net "GND")
	)
	(via
		(at 319.781936 -352.245422)
		(size 0.4572)
		(drill 0.254)
		(layers "F.Cu" "B.Cu")
		(net "GND")
	)
	(via
		(at 40.547798 -410.041852)
		(size 0.508)
		(drill 0.254)
		(layers "F.Cu" "B.Cu")
		(net "GND")
	)
	(via
		(at 39.224966 -273.574764)
		(size 0.4064)
		(drill 0.2032)
		(layers "F.Cu" "B.Cu")
		(net "GND")
	)
	(via
		(at 71.760334 -357.123746)
		(size 0.4572)
		(drill 0.254)
		(layers "F.Cu" "B.Cu")
		(net "GND")
	)
	(via
		(at 293.74973 -312.049922)
		(size 0.4064)
		(drill 0.2032)
		(layers "F.Cu" "B.Cu")
		(net "GND")
	)
	(via
		(at 188.039248 -28.05303)
		(size 0.508)
		(drill 0.254)
		(layers "F.Cu" "B.Cu")
		(net "GND")
	)
	(via
		(at 267.959586 -122.626628)
		(size 0.508)
		(drill 0.254)
		(layers "F.Cu" "B.Cu")
		(net "GND")
	)
	(via
		(at 415.85007 -109.879892)
		(size 0.508)
		(drill 0.254)
		(layers "F.Cu" "B.Cu")
		(net "GND")
	)
	(via
		(at 248.133108 -215.17229)
		(size 0.508)
		(drill 0.254)
		(layers "F.Cu" "B.Cu")
		(net "GND")
	)
	(via
		(at 241.251994 -13.613638)
		(size 0.508)
		(drill 0.254)
		(layers "F.Cu" "B.Cu")
		(net "GND")
	)
	(via
		(at 448.311524 -121.509028)
		(size 0.508)
		(drill 0.254)
		(layers "F.Cu" "B.Cu")
		(net "GND")
	)
	(via
		(at 418.399976 -277.849838)
		(size 0.4064)
		(drill 0.2032)
		(layers "F.Cu" "B.Cu")
		(net "GND")
	)
	(via
		(at 389.899906 -310.149748)
		(size 0.4064)
		(drill 0.2032)
		(layers "F.Cu" "B.Cu")
		(net "GND")
	)
	(via
		(at 123.728988 -351.611438)
		(size 0.4064)
		(drill 0.2032)
		(layers "F.Cu" "B.Cu")
		(net "GND")
	)
	(via
		(at 295.308782 -342.439498)
		(size 0.4064)
		(drill 0.2032)
		(layers "F.Cu" "B.Cu")
		(net "GND")
	)
	(via
		(at 164.349938 -316.799722)
		(size 0.4064)
		(drill 0.2032)
		(layers "F.Cu" "B.Cu")
		(net "GND")
	)
	(via
		(at 384.059684 -130.236722)
		(size 0.508)
		(drill 0.254)
		(layers "F.Cu" "B.Cu")
		(net "GND")
	)
	(via
		(at 440.18708 -347.951806)
		(size 0.4572)
		(drill 0.254)
		(layers "F.Cu" "B.Cu")
		(net "GND")
	)
	(via
		(at 406.050242 -319.65011)
		(size 0.4064)
		(drill 0.2032)
		(layers "F.Cu" "B.Cu")
		(net "GND")
	)
	(via
		(at 237.849918 -311.806082)
		(size 0.508)
		(drill 0.254)
		(layers "F.Cu" "B.Cu")
		(net "GND")
	)
	(via
		(at 346.465906 -86.341966)
		(size 0.508)
		(drill 0.254)
		(layers "F.Cu" "B.Cu")
		(net "GND")
	)
	(via
		(at 337.176872 -344.831162)
		(size 0.4572)
		(drill 0.254)
		(layers "F.Cu" "B.Cu")
		(net "GND")
	)
	(via
		(at 201.088244 -260.46176)
		(size 0.508)
		(drill 0.254)
		(layers "F.Cu" "B.Cu")
		(net "GND")
	)
	(via
		(at 294.69969 -312.999882)
		(size 0.4064)
		(drill 0.2032)
		(layers "F.Cu" "B.Cu")
		(net "GND")
	)
	(via
		(at 285.687262 -107.844844)
		(size 0.508)
		(drill 0.254)
		(layers "F.Cu" "B.Cu")
		(net "GND")
	)
	(via
		(at 408.120088 -31.390336)
		(size 0.508)
		(drill 0.254)
		(layers "F.Cu" "B.Cu")
		(net "GND")
	)
	(via
		(at 0.77089 -314.461144)
		(size 0.508)
		(drill 0.254)
		(layers "F.Cu" "B.Cu")
		(net "GND")
	)
	(via
		(at 81.499964 -282.599892)
		(size 0.4064)
		(drill 0.2032)
		(layers "F.Cu" "B.Cu")
		(net "GND")
	)
	(via
		(at 193.324988 -301.124874)
		(size 0.4064)
		(drill 0.2032)
		(layers "F.Cu" "B.Cu")
		(net "GND")
	)
	(via
		(at 296.124884 -284.974792)
		(size 0.4064)
		(drill 0.2032)
		(layers "F.Cu" "B.Cu")
		(net "GND")
	)
	(via
		(at 34.491676 -119.026686)
		(size 0.508)
		(drill 0.254)
		(layers "F.Cu" "B.Cu")
		(net "GND")
	)
	(via
		(at 173.375066 -287.824926)
		(size 0.4064)
		(drill 0.2032)
		(layers "F.Cu" "B.Cu")
		(net "GND")
	)
	(via
		(at 165.947852 -381.241808)
		(size 0.508)
		(drill 0.254)
		(layers "F.Cu" "B.Cu")
		(net "GND")
	)
	(via
		(at 69.624956 -298.27474)
		(size 0.4064)
		(drill 0.2032)
		(layers "F.Cu" "B.Cu")
		(net "GND")
	)
	(via
		(at 282.349702 -314.899802)
		(size 0.4064)
		(drill 0.2032)
		(layers "F.Cu" "B.Cu")
		(net "GND")
	)
	(via
		(at 302.78197 -58.873644)
		(size 0.508)
		(drill 0.254)
		(layers "F.Cu" "B.Cu")
		(net "GND")
	)
	(via
		(at 54.424834 -291.624766)
		(size 0.4064)
		(drill 0.2032)
		(layers "F.Cu" "B.Cu")
		(net "GND")
	)
	(via
		(at 295.68013 -358.391714)
		(size 0.4572)
		(drill 0.254)
		(layers "F.Cu" "B.Cu")
		(net "GND")
	)
	(via
		(at 86.04631 -341.805514)
		(size 0.4572)
		(drill 0.254)
		(layers "F.Cu" "B.Cu")
		(net "GND")
	)
	(via
		(at 26.61158 -344.831162)
		(size 0.4572)
		(drill 0.254)
		(layers "F.Cu" "B.Cu")
		(net "GND")
	)
	(via
		(at 78.551532 -102.088696)
		(size 0.508)
		(drill 0.254)
		(layers "F.Cu" "B.Cu")
		(net "GND")
	)
	(via
		(at 418.927788 -410.041852)
		(size 0.508)
		(drill 0.254)
		(layers "F.Cu" "B.Cu")
		(net "GND")
	)
	(via
		(at 151.838406 -136.241028)
		(size 0.508)
		(drill 0.254)
		(layers "F.Cu" "B.Cu")
		(net "GND")
	)
	(via
		(at 27.323288 -54.067456)
		(size 0.508)
		(drill 0.254)
		(layers "F.Cu" "B.Cu")
		(net "GND")
	)
	(via
		(at 169.587164 -131.76504)
		(size 0.508)
		(drill 0.254)
		(layers "F.Cu" "B.Cu")
		(net "GND")
	)
	(via
		(at 343.25687 -292.710108)
		(size 0.508)
		(drill 0.254)
		(layers "F.Cu" "B.Cu")
		(net "GND")
	)
	(via
		(at 42.15638 -341.805514)
		(size 0.4572)
		(drill 0.254)
		(layers "F.Cu" "B.Cu")
		(net "GND")
	)
	(via
		(at 182.547514 -120.035066)
		(size 0.508)
		(drill 0.254)
		(layers "F.Cu" "B.Cu")
		(net "GND")
	)
	(via
		(at 301.824898 -291.624766)
		(size 0.4064)
		(drill 0.2032)
		(layers "F.Cu" "B.Cu")
		(net "GND")
	)
	(via
		(at 124.642372 -285.953454)
		(size 0.508)
		(drill 0.254)
		(layers "F.Cu" "B.Cu")
		(net "GND")
	)
	(via
		(at 439.928 -417.82492)
		(size 0.508)
		(drill 0.254)
		(layers "F.Cu" "B.Cu")
		(net "GND")
	)
	(via
		(at 128.547622 -404.940262)
		(size 0.4572)
		(drill 0.254)
		(layers "F.Cu" "B.Cu")
		(net "GND")
	)
	(via
		(at 42.15638 -346.09913)
		(size 0.4572)
		(drill 0.254)
		(layers "F.Cu" "B.Cu")
		(net "GND")
	)
	(via
		(at 176.94783 -397.140176)
		(size 0.508)
		(drill 0.254)
		(layers "F.Cu" "B.Cu")
		(net "GND")
	)
	(via
		(at 68.651374 -343.073482)
		(size 0.4572)
		(drill 0.254)
		(layers "F.Cu" "B.Cu")
		(net "GND")
	)
	(via
		(at 62.804802 -342.439498)
		(size 0.4064)
		(drill 0.2032)
		(layers "F.Cu" "B.Cu")
		(net "GND")
	)
	(via
		(at 303.559972 -237.819184)
		(size 0.508)
		(drill 0.254)
		(layers "F.Cu" "B.Cu")
		(net "GND")
	)
	(via
		(at 298.78909 -358.391714)
		(size 0.4572)
		(drill 0.254)
		(layers "F.Cu" "B.Cu")
		(net "GND")
	)
	(via
		(at 388.127748 -376.241818)
		(size 0.508)
		(drill 0.254)
		(layers "F.Cu" "B.Cu")
		(net "GND")
	)
	(via
		(at 275.176234 -343.073482)
		(size 0.4572)
		(drill 0.254)
		(layers "F.Cu" "B.Cu")
		(net "GND")
	)
	(via
		(at 369.808506 -258.665472)
		(size 0.508)
		(drill 0.254)
		(layers "F.Cu" "B.Cu")
		(net "GND")
	)
	(via
		(at 392.52779 -395.938502)
		(size 0.508)
		(drill 0.254)
		(layers "F.Cu" "B.Cu")
		(net "GND")
	)
	(via
		(at 273.91741 -344.831162)
		(size 0.4572)
		(drill 0.254)
		(layers "F.Cu" "B.Cu")
		(net "GND")
	)
	(via
		(at 88.947752 -401.040092)
		(size 0.508)
		(drill 0.254)
		(layers "F.Cu" "B.Cu")
		(net "GND")
	)
	(via
		(at 39.90086 -142.748762)
		(size 0.508)
		(drill 0.254)
		(layers "F.Cu" "B.Cu")
		(net "GND")
	)
	(via
		(at 165.09746 -349.219774)
		(size 0.4572)
		(drill 0.254)
		(layers "F.Cu" "B.Cu")
		(net "GND")
	)
	(via
		(at 454.795382 -77.1525)
		(size 0.508)
		(drill 0.254)
		(layers "F.Cu" "B.Cu")
		(net "GND")
	)
	(via
		(at 387.525006 -292.574726)
		(size 0.4064)
		(drill 0.2032)
		(layers "F.Cu" "B.Cu")
		(net "GND")
	)
	(via
		(at 22.581362 -34.718498)
		(size 0.508)
		(drill 0.254)
		(layers "F.Cu" "B.Cu")
		(net "GND")
	)
	(via
		(at 444.97117 -28.05303)
		(size 0.508)
		(drill 0.254)
		(layers "F.Cu" "B.Cu")
		(net "GND")
	)
	(via
		(at 222.914464 -190.368936)
		(size 0.508)
		(drill 0.254)
		(layers "F.Cu" "B.Cu")
		(net "GND")
	)
	(via
		(at 417.450016 -319.65011)
		(size 0.4064)
		(drill 0.2032)
		(layers "F.Cu" "B.Cu")
		(net "GND")
	)
	(via
		(at 123.1392 -330.708)
		(size 0.508)
		(drill 0.254)
		(layers "F.Cu" "B.Cu")
		(net "GND")
	)
	(via
		(at 250.96343 -93.105986)
		(size 0.508)
		(drill 0.254)
		(layers "F.Cu" "B.Cu")
		(net "GND")
	)
	(via
		(at 126.89713 -244.846602)
		(size 0.508)
		(drill 0.254)
		(layers "F.Cu" "B.Cu")
		(net "GND")
	)
	(via
		(at 193.143378 -82.421476)
		(size 0.508)
		(drill 0.254)
		(layers "F.Cu" "B.Cu")
		(net "GND")
	)
	(via
		(at 360.959146 -138.89482)
		(size 0.508)
		(drill 0.254)
		(layers "F.Cu" "B.Cu")
		(net "GND")
	)
	(via
		(at 170.347894 -385.141978)
		(size 0.508)
		(drill 0.254)
		(layers "F.Cu" "B.Cu")
		(net "GND")
	)
	(via
		(at 180.270912 -351.611438)
		(size 0.4064)
		(drill 0.2032)
		(layers "F.Cu" "B.Cu")
		(net "GND")
	)
	(via
		(at 198.550022 -311.099962)
		(size 0.4064)
		(drill 0.2032)
		(layers "F.Cu" "B.Cu")
		(net "GND")
	)
	(via
		(at 18.367756 -173.585378)
		(size 0.508)
		(drill 0.254)
		(layers "F.Cu" "B.Cu")
		(net "GND")
	)
	(via
		(at 130.04546 -174.33671)
		(size 0.508)
		(drill 0.254)
		(layers "F.Cu" "B.Cu")
		(net "GND")
	)
	(via
		(at 362.458 -196.723)
		(size 0.508)
		(drill 0.254)
		(layers "F.Cu" "B.Cu")
		(net "GND")
	)
	(via
		(at 90.414094 -343.073482)
		(size 0.4572)
		(drill 0.254)
		(layers "F.Cu" "B.Cu")
		(net "GND")
	)
	(via
		(at 65.542414 -346.09913)
		(size 0.4572)
		(drill 0.254)
		(layers "F.Cu" "B.Cu")
		(net "GND")
	)
	(via
		(at 66.774822 -291.624766)
		(size 0.4064)
		(drill 0.2032)
		(layers "F.Cu" "B.Cu")
		(net "GND")
	)
	(via
		(at 45.87494 -283.074872)
		(size 0.4064)
		(drill 0.2032)
		(layers "F.Cu" "B.Cu")
		(net "GND")
	)
	(via
		(at 161.54781 -403.34184)
		(size 0.508)
		(drill 0.254)
		(layers "F.Cu" "B.Cu")
		(net "GND")
	)
	(via
		(at 429.927766 -381.241808)
		(size 0.508)
		(drill 0.254)
		(layers "F.Cu" "B.Cu")
		(net "GND")
	)
	(via
		(at 408.726132 -351.611438)
		(size 0.4064)
		(drill 0.2032)
		(layers "F.Cu" "B.Cu")
		(net "GND")
	)
	(via
		(at 466.835998 -247.203976)
		(size 0.508)
		(drill 0.254)
		(layers "F.Cu" "B.Cu")
		(net "GND")
	)
	(via
		(at 330.13904 -29.311854)
		(size 0.508)
		(drill 0.254)
		(layers "F.Cu" "B.Cu")
		(net "GND")
	)
	(via
		(at 300.48073 -25.990042)
		(size 0.508)
		(drill 0.254)
		(layers "F.Cu" "B.Cu")
		(net "GND")
	)
	(via
		(at 64.446912 -23.583646)
		(size 0.508)
		(drill 0.254)
		(layers "F.Cu" "B.Cu")
		(net "GND")
	)
	(via
		(at 122.477022 -121.103136)
		(size 0.508)
		(drill 0.254)
		(layers "F.Cu" "B.Cu")
		(net "GND")
	)
	(via
		(at 153.89987 -307.299868)
		(size 0.4064)
		(drill 0.2032)
		(layers "F.Cu" "B.Cu")
		(net "GND")
	)
	(via
		(at 374.927876 -371.140228)
		(size 0.508)
		(drill 0.254)
		(layers "F.Cu" "B.Cu")
		(net "GND")
	)
	(via
		(at 306.099718 -278.799798)
		(size 0.4064)
		(drill 0.2032)
		(layers "F.Cu" "B.Cu")
		(net "GND")
	)
	(via
		(at 319.781936 -347.951806)
		(size 0.4572)
		(drill 0.254)
		(layers "F.Cu" "B.Cu")
		(net "GND")
	)
	(via
		(at 296.255948 -33.19018)
		(size 0.508)
		(drill 0.254)
		(layers "F.Cu" "B.Cu")
		(net "GND")
	)
	(via
		(at 278.074882 -297.32478)
		(size 0.4064)
		(drill 0.2032)
		(layers "F.Cu" "B.Cu")
		(net "GND")
	)
	(via
		(at 434.327808 -377.341892)
		(size 0.508)
		(drill 0.254)
		(layers "F.Cu" "B.Cu")
		(net "GND")
	)
	(via
		(at 250.871228 -31.652972)
		(size 0.508)
		(drill 0.254)
		(layers "F.Cu" "B.Cu")
		(net "GND")
	)
	(via
		(at 290.42487 -298.27474)
		(size 0.4064)
		(drill 0.2032)
		(layers "F.Cu" "B.Cu")
		(net "GND")
	)
	(via
		(at 79.323184 -55.083456)
		(size 0.508)
		(drill 0.254)
		(layers "F.Cu" "B.Cu")
		(net "GND")
	)
	(via
		(at 176.94783 -403.738588)
		(size 0.508)
		(drill 0.254)
		(layers "F.Cu" "B.Cu")
		(net "GND")
	)
	(via
		(at 290.42487 -300.174914)
		(size 0.4064)
		(drill 0.2032)
		(layers "F.Cu" "B.Cu")
		(net "GND")
	)
	(via
		(at 60.803282 -342.439498)
		(size 0.4064)
		(drill 0.2032)
		(layers "F.Cu" "B.Cu")
		(net "GND")
	)
	(via
		(at 86.454996 -29.590238)
		(size 0.508)
		(drill 0.254)
		(layers "F.Cu" "B.Cu")
		(net "GND")
	)
	(via
		(at 184.77484 -288.774886)
		(size 0.4064)
		(drill 0.2032)
		(layers "F.Cu" "B.Cu")
		(net "GND")
	)
	(via
		(at 428.971964 -49.574704)
		(size 0.508)
		(drill 0.254)
		(layers "F.Cu" "B.Cu")
		(net "GND")
	)
	(via
		(at 229.150926 -105.537508)
		(size 0.508)
		(drill 0.254)
		(layers "F.Cu" "B.Cu")
		(net "GND")
	)
	(via
		(at 433.108354 -136.373362)
		(size 0.508)
		(drill 0.254)
		(layers "F.Cu" "B.Cu")
		(net "GND")
	)
	(via
		(at 136.536176 -355.366066)
		(size 0.4572)
		(drill 0.254)
		(layers "F.Cu" "B.Cu")
		(net "GND")
	)
	(via
		(at 260.332728 -182.335424)
		(size 0.508)
		(drill 0.254)
		(layers "F.Cu" "B.Cu")
		(net "GND")
	)
	(via
		(at 323.11848 -294.50157)
		(size 0.508)
		(drill 0.254)
		(layers "F.Cu" "B.Cu")
		(net "GND")
	)
	(via
		(at 354.499926 -259.918962)
		(size 0.508)
		(drill 0.254)
		(layers "F.Cu" "B.Cu")
		(net "GND")
	)
	(via
		(at 67.39255 -354.098098)
		(size 0.4572)
		(drill 0.254)
		(layers "F.Cu" "B.Cu")
		(net "GND")
	)
	(via
		(at 404.149814 -311.099962)
		(size 0.4064)
		(drill 0.2032)
		(layers "F.Cu" "B.Cu")
		(net "GND")
	)
	(via
		(at 175.749966 -319.65011)
		(size 0.4064)
		(drill 0.2032)
		(layers "F.Cu" "B.Cu")
		(net "GND")
	)
	(via
		(at 142.14475 -187.860686)
		(size 0.508)
		(drill 0.254)
		(layers "F.Cu" "B.Cu")
		(net "GND")
	)
	(via
		(at 401.78736 -98.844862)
		(size 0.508)
		(drill 0.254)
		(layers "F.Cu" "B.Cu")
		(net "GND")
	)
	(via
		(at 283.949902 -144.250156)
		(size 0.508)
		(drill 0.254)
		(layers "F.Cu" "B.Cu")
		(net "GND")
	)
	(via
		(at 265.675364 -88.089232)
		(size 0.508)
		(drill 0.254)
		(layers "F.Cu" "B.Cu")
		(net "GND")
	)
	(via
		(at 415.3154 -352.245422)
		(size 0.4572)
		(drill 0.254)
		(layers "F.Cu" "B.Cu")
		(net "GND")
	)
	(via
		(at 8.518144 -372.74119)
		(size 0.508)
		(drill 0.254)
		(layers "F.Cu" "B.Cu")
		(net "GND")
	)
	(via
		(at 269.333726 -125.692154)
		(size 0.508)
		(drill 0.254)
		(layers "F.Cu" "B.Cu")
		(net "GND")
	)
	(via
		(at 288.049716 -274.999958)
		(size 0.4064)
		(drill 0.2032)
		(layers "F.Cu" "B.Cu")
		(net "GND")
	)
	(via
		(at 408.424888 -284.974792)
		(size 0.4064)
		(drill 0.2032)
		(layers "F.Cu" "B.Cu")
		(net "GND")
	)
	(via
		(at 429.325024 -294.4749)
		(size 0.4064)
		(drill 0.2032)
		(layers "F.Cu" "B.Cu")
		(net "GND")
	)
	(via
		(at 166.249858 -310.149748)
		(size 0.4064)
		(drill 0.2032)
		(layers "F.Cu" "B.Cu")
		(net "GND")
	)
	(via
		(at 298.024804 -284.974792)
		(size 0.4064)
		(drill 0.2032)
		(layers "F.Cu" "B.Cu")
		(net "GND")
	)
	(via
		(at 46.349666 -272.14957)
		(size 0.4064)
		(drill 0.2032)
		(layers "F.Cu" "B.Cu")
		(net "GND")
	)
	(via
		(at 413.836612 -357.75773)
		(size 0.4064)
		(drill 0.2032)
		(layers "F.Cu" "B.Cu")
		(net "GND")
	)
	(via
		(at 23.97506 -73.23963)
		(size 0.508)
		(drill 0.254)
		(layers "F.Cu" "B.Cu")
		(net "GND")
	)
	(via
		(at 189.99962 -276.899878)
		(size 0.4064)
		(drill 0.2032)
		(layers "F.Cu" "B.Cu")
		(net "GND")
	)
	(via
		(at 304.199798 -317.749936)
		(size 0.4064)
		(drill 0.2032)
		(layers "F.Cu" "B.Cu")
		(net "GND")
	)
	(via
		(at 69.655182 -145.881852)
		(size 0.508)
		(drill 0.254)
		(layers "F.Cu" "B.Cu")
		(net "GND")
	)
	(via
		(at 41.124886 -291.624766)
		(size 0.4064)
		(drill 0.2032)
		(layers "F.Cu" "B.Cu")
		(net "GND")
	)
	(via
		(at 68.674742 -286.874966)
		(size 0.4064)
		(drill 0.2032)
		(layers "F.Cu" "B.Cu")
		(net "GND")
	)
	(via
		(at 251.16028 -218.161362)
		(size 0.508)
		(drill 0.254)
		(layers "F.Cu" "B.Cu")
		(net "GND")
	)
	(via
		(at 271.899888 -312.999882)
		(size 0.4064)
		(drill 0.2032)
		(layers "F.Cu" "B.Cu")
		(net "GND")
	)
	(via
		(at 430.274984 -291.624766)
		(size 0.4064)
		(drill 0.2032)
		(layers "F.Cu" "B.Cu")
		(net "GND")
	)
	(via
		(at 236.885988 -85.551518)
		(size 0.508)
		(drill 0.254)
		(layers "F.Cu" "B.Cu")
		(net "GND")
	)
	(via
		(at 185.010044 -354.074222)
		(size 0.4572)
		(drill 0.254)
		(layers "F.Cu" "B.Cu")
		(net "GND")
	)
	(via
		(at 170.772074 -49.574704)
		(size 0.508)
		(drill 0.254)
		(layers "F.Cu" "B.Cu")
		(net "GND")
	)
	(via
		(at 392.274806 -281.174952)
		(size 0.4064)
		(drill 0.2032)
		(layers "F.Cu" "B.Cu")
		(net "GND")
	)
	(via
		(at 413.174942 -285.924752)
		(size 0.4064)
		(drill 0.2032)
		(layers "F.Cu" "B.Cu")
		(net "GND")
	)
	(via
		(at 248.596658 -326.366632)
		(size 0.508)
		(drill 0.254)
		(layers "F.Cu" "B.Cu")
		(net "GND")
	)
	(via
		(at 452.775574 -309.0164)
		(size 0.508)
		(drill 0.254)
		(layers "F.Cu" "B.Cu")
		(net "GND")
	)
	(via
		(at 238.757968 -136.328404)
		(size 0.508)
		(drill 0.254)
		(layers "F.Cu" "B.Cu")
		(net "GND")
	)
	(via
		(at 332.589124 -345.465146)
		(size 0.4064)
		(drill 0.2032)
		(layers "F.Cu" "B.Cu")
		(net "GND")
	)
	(via
		(at 62.974982 -284.974792)
		(size 0.4064)
		(drill 0.2032)
		(layers "F.Cu" "B.Cu")
		(net "GND")
	)
	(via
		(at 446.238376 -115.732814)
		(size 0.508)
		(drill 0.254)
		(layers "F.Cu" "B.Cu")
		(net "GND")
	)
	(via
		(at 413.649922 -276.899878)
		(size 0.4064)
		(drill 0.2032)
		(layers "F.Cu" "B.Cu")
		(net "GND")
	)
	(via
		(at 13.953744 -114.135408)
		(size 0.508)
		(drill 0.254)
		(layers "F.Cu" "B.Cu")
		(net "GND")
	)
	(via
		(at 119.512588 -351.611438)
		(size 0.4064)
		(drill 0.2032)
		(layers "F.Cu" "B.Cu")
		(net "GND")
	)
	(via
		(at 425.04995 -275.949918)
		(size 0.4064)
		(drill 0.2032)
		(layers "F.Cu" "B.Cu")
		(net "GND")
	)
	(via
		(at 364.580932 -34.990024)
		(size 0.508)
		(drill 0.254)
		(layers "F.Cu" "B.Cu")
		(net "GND")
	)
	(via
		(at 219.288868 -284.641544)
		(size 0.508)
		(drill 0.254)
		(layers "F.Cu" "B.Cu")
		(net "GND")
	)
	(via
		(at 291.32784 -378.94006)
		(size 0.508)
		(drill 0.254)
		(layers "F.Cu" "B.Cu")
		(net "GND")
	)
	(via
		(at 78.551532 -103.104696)
		(size 0.508)
		(drill 0.254)
		(layers "F.Cu" "B.Cu")
		(net "GND")
	)
	(via
		(at 76.27493 -301.124874)
		(size 0.4064)
		(drill 0.2032)
		(layers "F.Cu" "B.Cu")
		(net "GND")
	)
	(via
		(at 205.585822 -301.562008)
		(size 0.508)
		(drill 0.254)
		(layers "F.Cu" "B.Cu")
		(net "GND")
	)
	(via
		(at 110.045246 -306.55387)
		(size 0.508)
		(drill 0.254)
		(layers "F.Cu" "B.Cu")
		(net "GND")
	)
	(via
		(at 140.90396 -357.123746)
		(size 0.4572)
		(drill 0.254)
		(layers "F.Cu" "B.Cu")
		(net "GND")
	)
	(via
		(at 412.699962 -276.899878)
		(size 0.4064)
		(drill 0.2032)
		(layers "F.Cu" "B.Cu")
		(net "GND")
	)
	(via
		(at 346.327984 -411.141926)
		(size 0.508)
		(drill 0.254)
		(layers "F.Cu" "B.Cu")
		(net "GND")
	)
	(via
		(at 240.655094 -27.79014)
		(size 0.508)
		(drill 0.254)
		(layers "F.Cu" "B.Cu")
		(net "GND")
	)
	(via
		(at 182.272432 -345.465146)
		(size 0.4064)
		(drill 0.2032)
		(layers "F.Cu" "B.Cu")
		(net "GND")
	)
	(via
		(at 399.400014 -276.899878)
		(size 0.4064)
		(drill 0.2032)
		(layers "F.Cu" "B.Cu")
		(net "GND")
	)
	(via
		(at 251.96546 -196.589396)
		(size 0.508)
		(drill 0.254)
		(layers "F.Cu" "B.Cu")
		(net "GND")
	)
	(via
		(at 0.766318 -416.424364)
		(size 0.508)
		(drill 0.254)
		(layers "F.Cu" "B.Cu")
		(net "GND")
	)
	(via
		(at 413.174942 -291.624766)
		(size 0.4064)
		(drill 0.2032)
		(layers "F.Cu" "B.Cu")
		(net "GND")
	)
	(via
		(at 388.949946 -319.65011)
		(size 0.4064)
		(drill 0.2032)
		(layers "F.Cu" "B.Cu")
		(net "GND")
	)
	(via
		(at 435.494938 -60.633356)
		(size 0.508)
		(drill 0.254)
		(layers "F.Cu" "B.Cu")
		(net "GND")
	)
	(via
		(at 419.05555 -63.218314)
		(size 0.508)
		(drill 0.254)
		(layers "F.Cu" "B.Cu")
		(net "GND")
	)
	(via
		(at 253.513336 -29.859478)
		(size 0.508)
		(drill 0.254)
		(layers "F.Cu" "B.Cu")
		(net "GND")
	)
	(via
		(at 463.037682 -174.257462)
		(size 0.508)
		(drill 0.254)
		(layers "F.Cu" "B.Cu")
		(net "GND")
	)
	(via
		(at 304.527712 -371.140482)
		(size 0.508)
		(drill 0.254)
		(layers "F.Cu" "B.Cu")
		(net "GND")
	)
	(via
		(at 123.266962 -173.187614)
		(size 0.508)
		(drill 0.254)
		(layers "F.Cu" "B.Cu")
		(net "GND")
	)
	(via
		(at 300.12767 -406.141936)
		(size 0.508)
		(drill 0.254)
		(layers "F.Cu" "B.Cu")
		(net "GND")
	)
	(via
		(at 394.649706 -272.14957)
		(size 0.4064)
		(drill 0.2032)
		(layers "F.Cu" "B.Cu")
		(net "GND")
	)
	(via
		(at 48.834548 -71.451978)
		(size 0.508)
		(drill 0.254)
		(layers "F.Cu" "B.Cu")
		(net "GND")
	)
	(via
		(at 318.523112 -358.391714)
		(size 0.4572)
		(drill 0.254)
		(layers "F.Cu" "B.Cu")
		(net "GND")
	)
	(via
		(at 355.6 -62.812168)
		(size 0.508)
		(drill 0.254)
		(layers "F.Cu" "B.Cu")
		(net "GND")
	)
	(via
		(at 65.81267 -120.035066)
		(size 0.508)
		(drill 0.254)
		(layers "F.Cu" "B.Cu")
		(net "GND")
	)
	(via
		(at 38.054788 -34.990024)
		(size 0.508)
		(drill 0.254)
		(layers "F.Cu" "B.Cu")
		(net "GND")
	)
	(via
		(at 17.794986 -272.200624)
		(size 0.508)
		(drill 0.254)
		(layers "F.Cu" "B.Cu")
		(net "GND")
	)
	(via
		(at 208.060036 -219.356178)
		(size 0.508)
		(drill 0.254)
		(layers "F.Cu" "B.Cu")
		(net "GND")
	)
	(via
		(at 189.999874 -303.499774)
		(size 0.4064)
		(drill 0.2032)
		(layers "F.Cu" "B.Cu")
		(net "GND")
	)
	(via
		(at 40.547798 -377.738386)
		(size 0.508)
		(drill 0.254)
		(layers "F.Cu" "B.Cu")
		(net "GND")
	)
	(via
		(at 175.749966 -279.749758)
		(size 0.4064)
		(drill 0.2032)
		(layers "F.Cu" "B.Cu")
		(net "GND")
	)
	(via
		(at 53.949854 -281.649932)
		(size 0.4064)
		(drill 0.2032)
		(layers "F.Cu" "B.Cu")
		(net "GND")
	)
	(via
		(at 271.424908 -284.974792)
		(size 0.4064)
		(drill 0.2032)
		(layers "F.Cu" "B.Cu")
		(net "GND")
	)
	(via
		(at 167.849804 -143.615156)
		(size 0.508)
		(drill 0.254)
		(layers "F.Cu" "B.Cu")
		(net "GND")
	)
	(via
		(at 314.649866 -275.949918)
		(size 0.4064)
		(drill 0.2032)
		(layers "F.Cu" "B.Cu")
		(net "GND")
	)
	(via
		(at 308.949852 -316.799722)
		(size 0.4064)
		(drill 0.2032)
		(layers "F.Cu" "B.Cu")
		(net "GND")
	)
	(via
		(at 363.63148 -285.267654)
		(size 0.508)
		(drill 0.254)
		(layers "F.Cu" "B.Cu")
		(net "GND")
	)
	(via
		(at 48.745648 -357.75773)
		(size 0.4064)
		(drill 0.2032)
		(layers "F.Cu" "B.Cu")
		(net "GND")
	)
	(via
		(at 37.798248 -19.757136)
		(size 0.508)
		(drill 0.254)
		(layers "F.Cu" "B.Cu")
		(net "GND")
	)
	(via
		(at 237.642654 -310.315356)
		(size 0.508)
		(drill 0.254)
		(layers "F.Cu" "B.Cu")
		(net "GND")
	)
	(via
		(at 337.176872 -352.245422)
		(size 0.4572)
		(drill 0.254)
		(layers "F.Cu" "B.Cu")
		(net "GND")
	)
	(via
		(at 170.049952 -311.099962)
		(size 0.4064)
		(drill 0.2032)
		(layers "F.Cu" "B.Cu")
		(net "GND")
	)
	(via
		(at 181.44998 -311.099962)
		(size 0.4064)
		(drill 0.2032)
		(layers "F.Cu" "B.Cu")
		(net "GND")
	)
	(via
		(at 344.093546 -220.38691)
		(size 0.4572)
		(drill 0.254)
		(layers "F.Cu" "B.Cu")
		(net "GND")
	)
	(via
		(at 35.759644 -123.885452)
		(size 0.508)
		(drill 0.254)
		(layers "F.Cu" "B.Cu")
		(net "GND")
	)
	(via
		(at 388.127748 -377.738386)
		(size 0.508)
		(drill 0.254)
		(layers "F.Cu" "B.Cu")
		(net "GND")
	)
	(via
		(at 412.699962 -314.899802)
		(size 0.4064)
		(drill 0.2032)
		(layers "F.Cu" "B.Cu")
		(net "GND")
	)
	(via
		(at 314.649866 -280.699718)
		(size 0.4064)
		(drill 0.2032)
		(layers "F.Cu" "B.Cu")
		(net "GND")
	)
	(via
		(at 403.00656 -124.154946)
		(size 0.508)
		(drill 0.254)
		(layers "F.Cu" "B.Cu")
		(net "GND")
	)
	(via
		(at 170.064684 -142.367)
		(size 0.508)
		(drill 0.254)
		(layers "F.Cu" "B.Cu")
		(net "GND")
	)
	(via
		(at 415.737802 -74.624184)
		(size 0.508)
		(drill 0.254)
		(layers "F.Cu" "B.Cu")
		(net "GND")
	)
	(via
		(at 250.512072 -135.369046)
		(size 0.508)
		(drill 0.254)
		(layers "F.Cu" "B.Cu")
		(net "GND")
	)
	(via
		(at 431.224944 -297.32478)
		(size 0.4064)
		(drill 0.2032)
		(layers "F.Cu" "B.Cu")
		(net "GND")
	)
	(via
		(at 313.564016 -347.951806)
		(size 0.4572)
		(drill 0.254)
		(layers "F.Cu" "B.Cu")
		(net "GND")
	)
	(via
		(at 299.866812 -134.845044)
		(size 0.508)
		(drill 0.254)
		(layers "F.Cu" "B.Cu")
		(net "GND")
	)
	(via
		(at 73.424796 -299.224954)
		(size 0.4064)
		(drill 0.2032)
		(layers "F.Cu" "B.Cu")
		(net "GND")
	)
	(via
		(at 144.01292 -350.977454)
		(size 0.4572)
		(drill 0.254)
		(layers "F.Cu" "B.Cu")
		(net "GND")
	)
	(via
		(at 275.699728 -303.499774)
		(size 0.4064)
		(drill 0.2032)
		(layers "F.Cu" "B.Cu")
		(net "GND")
	)
	(via
		(at 390.849866 -300.649894)
		(size 0.4064)
		(drill 0.2032)
		(layers "F.Cu" "B.Cu")
		(net "GND")
	)
	(via
		(at 233.924094 -139.71905)
		(size 0.508)
		(drill 0.254)
		(layers "F.Cu" "B.Cu")
		(net "GND")
	)
	(via
		(at 103.954072 -103.69296)
		(size 0.508)
		(drill 0.254)
		(layers "F.Cu" "B.Cu")
		(net "GND")
	)
	(via
		(at 408.899868 -314.899802)
		(size 0.4064)
		(drill 0.2032)
		(layers "F.Cu" "B.Cu")
		(net "GND")
	)
	(via
		(at 237.849918 -313.558682)
		(size 0.508)
		(drill 0.254)
		(layers "F.Cu" "B.Cu")
		(net "GND")
	)
	(via
		(at 65.824862 -294.4749)
		(size 0.4064)
		(drill 0.2032)
		(layers "F.Cu" "B.Cu")
		(net "GND")
	)
	(via
		(at 302.327818 -371.038628)
		(size 0.508)
		(drill 0.254)
		(layers "F.Cu" "B.Cu")
		(net "GND")
	)
	(via
		(at 290.42487 -305.874928)
		(size 0.4064)
		(drill 0.2032)
		(layers "F.Cu" "B.Cu")
		(net "GND")
	)
	(via
		(at 452.013574 -309.7276)
		(size 0.508)
		(drill 0.254)
		(layers "F.Cu" "B.Cu")
		(net "GND")
	)
	(via
		(at 159.599884 -305.399948)
		(size 0.4064)
		(drill 0.2032)
		(layers "F.Cu" "B.Cu")
		(net "GND")
	)
	(via
		(at 6.521196 -377.517914)
		(size 0.508)
		(drill 0.254)
		(layers "F.Cu" "B.Cu")
		(net "GND")
	)
	(via
		(at 332.12532 -251.539756)
		(size 0.508)
		(drill 0.254)
		(layers "F.Cu" "B.Cu")
		(net "GND")
	)
	(via
		(at 182.547514 -121.835164)
		(size 0.508)
		(drill 0.254)
		(layers "F.Cu" "B.Cu")
		(net "GND")
	)
	(via
		(at 215.413336 -33.459674)
		(size 0.508)
		(drill 0.254)
		(layers "F.Cu" "B.Cu")
		(net "GND")
	)
	(via
		(at 280.924762 -300.174914)
		(size 0.4064)
		(drill 0.2032)
		(layers "F.Cu" "B.Cu")
		(net "GND")
	)
	(via
		(at 258.657852 -353.465638)
		(size 0.508)
		(drill 0.254)
		(layers "F.Cu" "B.Cu")
		(net "GND")
	)
	(via
		(at 391.324846 -284.974792)
		(size 0.4064)
		(drill 0.2032)
		(layers "F.Cu" "B.Cu")
		(net "GND")
	)
	(via
		(at 432.12766 -375.040144)
		(size 0.508)
		(drill 0.254)
		(layers "F.Cu" "B.Cu")
		(net "GND")
	)
	(via
		(at 326.480678 -33.19018)
		(size 0.508)
		(drill 0.254)
		(layers "F.Cu" "B.Cu")
		(net "GND")
	)
	(via
		(at 326.515222 -226.61245)
		(size 0.508)
		(drill 0.254)
		(layers "F.Cu" "B.Cu")
		(net "GND")
	)
	(via
		(at 180.50002 -313.949842)
		(size 0.4064)
		(drill 0.2032)
		(layers "F.Cu" "B.Cu")
		(net "GND")
	)
	(via
		(at 107.409742 -78.731364)
		(size 0.508)
		(drill 0.254)
		(layers "F.Cu" "B.Cu")
		(net "GND")
	)
	(via
		(at 324.741032 -354.098098)
		(size 0.4572)
		(drill 0.254)
		(layers "F.Cu" "B.Cu")
		(net "GND")
	)
	(via
		(at 238.28375 -58.646314)
		(size 0.508)
		(drill 0.254)
		(layers "F.Cu" "B.Cu")
		(net "GND")
	)
	(via
		(at 418.869876 -25.832054)
		(size 0.508)
		(drill 0.254)
		(layers "F.Cu" "B.Cu")
		(net "GND")
	)
	(via
		(at 400.60118 -345.465146)
		(size 0.4064)
		(drill 0.2032)
		(layers "F.Cu" "B.Cu")
		(net "GND")
	)
	(via
		(at 340.285832 -343.073482)
		(size 0.4572)
		(drill 0.254)
		(layers "F.Cu" "B.Cu")
		(net "GND")
	)
	(via
		(at 384.685032 -355.366066)
		(size 0.4572)
		(drill 0.254)
		(layers "F.Cu" "B.Cu")
		(net "GND")
	)
	(via
		(at 135.920226 -121.560844)
		(size 0.508)
		(drill 0.254)
		(layers "F.Cu" "B.Cu")
		(net "GND")
	)
	(via
		(at 29.72054 -354.098098)
		(size 0.4572)
		(drill 0.254)
		(layers "F.Cu" "B.Cu")
		(net "GND")
	)
	(via
		(at 277.599902 -309.199788)
		(size 0.4064)
		(drill 0.2032)
		(layers "F.Cu" "B.Cu")
		(net "GND")
	)
	(via
		(at 330.927964 -395.938502)
		(size 0.508)
		(drill 0.254)
		(layers "F.Cu" "B.Cu")
		(net "GND")
	)
	(via
		(at 111.293148 -351.611438)
		(size 0.4064)
		(drill 0.2032)
		(layers "F.Cu" "B.Cu")
		(net "GND")
	)
	(via
		(at 169.836592 -345.465146)
		(size 0.4064)
		(drill 0.2032)
		(layers "F.Cu" "B.Cu")
		(net "GND")
	)
	(via
		(at 398.4498 -316.799722)
		(size 0.4064)
		(drill 0.2032)
		(layers "F.Cu" "B.Cu")
		(net "GND")
	)
	(via
		(at 430.749964 -288.299906)
		(size 0.4064)
		(drill 0.2032)
		(layers "F.Cu" "B.Cu")
		(net "GND")
	)
	(via
		(at 62.974982 -298.27474)
		(size 0.4064)
		(drill 0.2032)
		(layers "F.Cu" "B.Cu")
		(net "GND")
	)
	(via
		(at 397.646652 -110.857538)
		(size 0.508)
		(drill 0.254)
		(layers "F.Cu" "B.Cu")
		(net "GND")
	)
	(via
		(at 89.798144 -21.738336)
		(size 0.508)
		(drill 0.254)
		(layers "F.Cu" "B.Cu")
		(net "GND")
	)
	(via
		(at 437.12384 -291.592)
		(size 0.508)
		(drill 0.254)
		(layers "F.Cu" "B.Cu")
		(net "GND")
	)
	(via
		(at 279.356058 -140.429488)
		(size 0.508)
		(drill 0.254)
		(layers "F.Cu" "B.Cu")
		(net "GND")
	)
	(via
		(at 168.20642 -344.831162)
		(size 0.4572)
		(drill 0.254)
		(layers "F.Cu" "B.Cu")
		(net "GND")
	)
	(via
		(at 163.89223 -70.918832)
		(size 0.508)
		(drill 0.254)
		(layers "F.Cu" "B.Cu")
		(net "GND")
	)
	(via
		(at 402.724874 -305.874928)
		(size 0.4064)
		(drill 0.2032)
		(layers "F.Cu" "B.Cu")
		(net "GND")
	)
	(via
		(at 32.241998 -307.240178)
		(size 0.508)
		(drill 0.254)
		(layers "F.Cu" "B.Cu")
		(net "GND")
	)
	(via
		(at 82.449924 -311.099962)
		(size 0.4064)
		(drill 0.2032)
		(layers "F.Cu" "B.Cu")
		(net "GND")
	)
	(via
		(at 303.249838 -280.699718)
		(size 0.4064)
		(drill 0.2032)
		(layers "F.Cu" "B.Cu")
		(net "GND")
	)
	(via
		(at 279.513284 -33.459674)
		(size 0.508)
		(drill 0.254)
		(layers "F.Cu" "B.Cu")
		(net "GND")
	)
	(via
		(at 34.308288 -357.75773)
		(size 0.4064)
		(drill 0.2032)
		(layers "F.Cu" "B.Cu")
		(net "GND")
	)
	(via
		(at 172.547788 -372.341902)
		(size 0.508)
		(drill 0.254)
		(layers "F.Cu" "B.Cu")
		(net "GND")
	)
	(via
		(at 433.108354 -149.083522)
		(size 0.508)
		(drill 0.254)
		(layers "F.Cu" "B.Cu")
		(net "GND")
	)
	(via
		(at 178.479958 -195.874386)
		(size 0.508)
		(drill 0.254)
		(layers "F.Cu" "B.Cu")
		(net "GND")
	)
	(via
		(at 251.105924 -1.364996)
		(size 0.508)
		(drill 0.254)
		(layers "F.Cu" "B.Cu")
		(net "GND")
	)
	(via
		(at 75.79995 -288.299906)
		(size 0.4064)
		(drill 0.2032)
		(layers "F.Cu" "B.Cu")
		(net "GND")
	)
	(via
		(at 34.679636 -344.831162)
		(size 0.4572)
		(drill 0.254)
		(layers "F.Cu" "B.Cu")
		(net "GND")
	)
	(via
		(at 356.83063 -304.373534)
		(size 0.508)
		(drill 0.254)
		(layers "F.Cu" "B.Cu")
		(net "GND")
	)
	(via
		(at 377.12777 -373.441976)
		(size 0.508)
		(drill 0.254)
		(layers "F.Cu" "B.Cu")
		(net "GND")
	)
	(via
		(at 435.35219 -13.613892)
		(size 0.508)
		(drill 0.254)
		(layers "F.Cu" "B.Cu")
		(net "GND")
	)
	(via
		(at 225.467926 -222.703898)
		(size 0.4572)
		(drill 0.254)
		(layers "F.Cu" "B.Cu")
		(net "GND")
	)
	(via
		(at 408.899868 -278.799798)
		(size 0.4064)
		(drill 0.2032)
		(layers "F.Cu" "B.Cu")
		(net "GND")
	)
	(via
		(at 52.524914 -284.024832)
		(size 0.4064)
		(drill 0.2032)
		(layers "F.Cu" "B.Cu")
		(net "GND")
	)
	(via
		(at 11.680952 -25.990042)
		(size 0.508)
		(drill 0.254)
		(layers "F.Cu" "B.Cu")
		(net "GND")
	)
	(via
		(at 397.543528 -172.172122)
		(size 0.508)
		(drill 0.254)
		(layers "F.Cu" "B.Cu")
		(net "GND")
	)
	(via
		(at 66.44767 -120.035066)
		(size 0.508)
		(drill 0.254)
		(layers "F.Cu" "B.Cu")
		(net "GND")
	)
	(via
		(at 139.324334 -222.976186)
		(size 0.508)
		(drill 0.254)
		(layers "F.Cu" "B.Cu")
		(net "GND")
	)
	(via
		(at 94.767654 -198.020432)
		(size 0.508)
		(drill 0.254)
		(layers "F.Cu" "B.Cu")
		(net "GND")
	)
	(via
		(at 162.450018 -275.949918)
		(size 0.4064)
		(drill 0.2032)
		(layers "F.Cu" "B.Cu")
		(net "GND")
	)
	(via
		(at 19.134836 -341.805514)
		(size 0.4572)
		(drill 0.254)
		(layers "F.Cu" "B.Cu")
		(net "GND")
	)
	(via
		(at 67.437762 -74.624184)
		(size 0.508)
		(drill 0.254)
		(layers "F.Cu" "B.Cu")
		(net "GND")
	)
	(via
		(at 433.099972 -38.315138)
		(size 0.508)
		(drill 0.254)
		(layers "F.Cu" "B.Cu")
		(net "GND")
	)
	(via
		(at 216.681304 -29.859478)
		(size 0.508)
		(drill 0.254)
		(layers "F.Cu" "B.Cu")
		(net "GND")
	)
	(via
		(at 386.535168 -355.366066)
		(size 0.4572)
		(drill 0.254)
		(layers "F.Cu" "B.Cu")
		(net "GND")
	)
	(via
		(at 330.927964 -375.040144)
		(size 0.508)
		(drill 0.254)
		(layers "F.Cu" "B.Cu")
		(net "GND")
	)
	(via
		(at 417.653216 -226.403662)
		(size 0.508)
		(drill 0.254)
		(layers "F.Cu" "B.Cu")
		(net "GND")
	)
	(via
		(at 413.836612 -342.439498)
		(size 0.4064)
		(drill 0.2032)
		(layers "F.Cu" "B.Cu")
		(net "GND")
	)
	(via
		(at 414.124902 -306.824888)
		(size 0.4064)
		(drill 0.2032)
		(layers "F.Cu" "B.Cu")
		(net "GND")
	)
	(via
		(at 238.299752 -228.816662)
		(size 0.508)
		(drill 0.254)
		(layers "F.Cu" "B.Cu")
		(net "GND")
	)
	(via
		(at 249.413776 -359.120186)
		(size 0.508)
		(drill 0.254)
		(layers "F.Cu" "B.Cu")
		(net "GND")
	)
	(via
		(at 166.725092 -293.52494)
		(size 0.4064)
		(drill 0.2032)
		(layers "F.Cu" "B.Cu")
		(net "GND")
	)
	(via
		(at 44.210732 -57.439814)
		(size 0.508)
		(drill 0.254)
		(layers "F.Cu" "B.Cu")
		(net "GND")
	)
	(via
		(at 217.307668 -284.641544)
		(size 0.508)
		(drill 0.254)
		(layers "F.Cu" "B.Cu")
		(net "GND")
	)
	(via
		(at 130.710432 -113.251996)
		(size 0.508)
		(drill 0.254)
		(layers "F.Cu" "B.Cu")
		(net "GND")
	)
	(via
		(at 377.12777 -381.241808)
		(size 0.508)
		(drill 0.254)
		(layers "F.Cu" "B.Cu")
		(net "GND")
	)
	(via
		(at 130.74777 -406.040336)
		(size 0.4572)
		(drill 0.254)
		(layers "F.Cu" "B.Cu")
		(net "GND")
	)
	(via
		(at 141.275308 -342.439498)
		(size 0.4064)
		(drill 0.2032)
		(layers "F.Cu" "B.Cu")
		(net "GND")
	)
	(via
		(at 397.49222 -345.465146)
		(size 0.4064)
		(drill 0.2032)
		(layers "F.Cu" "B.Cu")
		(net "GND")
	)
	(via
		(at 19.134836 -350.977454)
		(size 0.4572)
		(drill 0.254)
		(layers "F.Cu" "B.Cu")
		(net "GND")
	)
	(via
		(at 48.72482 -285.924752)
		(size 0.4064)
		(drill 0.2032)
		(layers "F.Cu" "B.Cu")
		(net "GND")
	)
	(via
		(at 291.84981 -279.749758)
		(size 0.4064)
		(drill 0.2032)
		(layers "F.Cu" "B.Cu")
		(net "GND")
	)
	(via
		(at 56.552084 -154.315668)
		(size 0.508)
		(drill 0.254)
		(layers "F.Cu" "B.Cu")
		(net "GND")
	)
	(via
		(at 102.281228 -240.928144)
		(size 0.508)
		(drill 0.254)
		(layers "F.Cu" "B.Cu")
		(net "GND")
	)
	(via
		(at 59.649868 -275.949918)
		(size 0.4064)
		(drill 0.2032)
		(layers "F.Cu" "B.Cu")
		(net "GND")
	)
	(via
		(at 59.10326 -60.627006)
		(size 0.508)
		(drill 0.254)
		(layers "F.Cu" "B.Cu")
		(net "GND")
	)
	(via
		(at 133.674104 -183.220106)
		(size 0.508)
		(drill 0.254)
		(layers "F.Cu" "B.Cu")
		(net "GND")
	)
	(via
		(at 394.17498 -284.024832)
		(size 0.4064)
		(drill 0.2032)
		(layers "F.Cu" "B.Cu")
		(net "GND")
	)
	(via
		(at 178.599846 -274.049744)
		(size 0.4064)
		(drill 0.2032)
		(layers "F.Cu" "B.Cu")
		(net "GND")
	)
	(via
		(at 130.74777 -382.73863)
		(size 0.508)
		(drill 0.254)
		(layers "F.Cu" "B.Cu")
		(net "GND")
	)
	(via
		(at 161.500058 -276.899878)
		(size 0.4064)
		(drill 0.2032)
		(layers "F.Cu" "B.Cu")
		(net "GND")
	)
	(via
		(at 266.691618 -135.095488)
		(size 0.508)
		(drill 0.254)
		(layers "F.Cu" "B.Cu")
		(net "GND")
	)
	(via
		(at 302.341026 -38.49116)
		(size 0.508)
		(drill 0.254)
		(layers "F.Cu" "B.Cu")
		(net "GND")
	)
	(via
		(at 405.575008 -309.674768)
		(size 0.4064)
		(drill 0.2032)
		(layers "F.Cu" "B.Cu")
		(net "GND")
	)
	(via
		(at 154.501596 -107.57535)
		(size 0.508)
		(drill 0.254)
		(layers "F.Cu" "B.Cu")
		(net "GND")
	)
	(via
		(at 74.374756 -294.4749)
		(size 0.4064)
		(drill 0.2032)
		(layers "F.Cu" "B.Cu")
		(net "GND")
	)
	(via
		(at 158.658052 -56.809894)
		(size 0.508)
		(drill 0.254)
		(layers "F.Cu" "B.Cu")
		(net "GND")
	)
	(via
		(at 130.74777 -385.141978)
		(size 0.4572)
		(drill 0.254)
		(layers "F.Cu" "B.Cu")
		(net "GND")
	)
	(via
		(at 12.792964 -274.926552)
		(size 0.508)
		(drill 0.254)
		(layers "F.Cu" "B.Cu")
		(net "GND")
	)
	(via
		(at 82.566002 -348.58579)
		(size 0.4064)
		(drill 0.2032)
		(layers "F.Cu" "B.Cu")
		(net "GND")
	)
	(via
		(at 335.326736 -343.073482)
		(size 0.4572)
		(drill 0.254)
		(layers "F.Cu" "B.Cu")
		(net "GND")
	)
	(via
		(at 335.326736 -344.831162)
		(size 0.4572)
		(drill 0.254)
		(layers "F.Cu" "B.Cu")
		(net "GND")
	)
	(via
		(at 425.04995 -316.799722)
		(size 0.4064)
		(drill 0.2032)
		(layers "F.Cu" "B.Cu")
		(net "GND")
	)
	(via
		(at 273.799808 -317.749936)
		(size 0.4064)
		(drill 0.2032)
		(layers "F.Cu" "B.Cu")
		(net "GND")
	)
	(via
		(at 168.952164 -113.245138)
		(size 0.508)
		(drill 0.254)
		(layers "F.Cu" "B.Cu")
		(net "GND")
	)
	(via
		(at 0.940816 -1.364996)
		(size 0.508)
		(drill 0.254)
		(layers "F.Cu" "B.Cu")
		(net "GND")
	)
	(via
		(at 381.576072 -349.219774)
		(size 0.4572)
		(drill 0.254)
		(layers "F.Cu" "B.Cu")
		(net "GND")
	)
	(via
		(at 130.318256 -349.219774)
		(size 0.4572)
		(drill 0.254)
		(layers "F.Cu" "B.Cu")
		(net "GND")
	)
	(via
		(at 395.12494 -284.974792)
		(size 0.4064)
		(drill 0.2032)
		(layers "F.Cu" "B.Cu")
		(net "GND")
	)
	(via
		(at 386.575046 -289.724846)
		(size 0.4064)
		(drill 0.2032)
		(layers "F.Cu" "B.Cu")
		(net "GND")
	)
	(via
		(at 38.347904 -402.140166)
		(size 0.508)
		(drill 0.254)
		(layers "F.Cu" "B.Cu")
		(net "GND")
	)
	(via
		(at 305.624738 -296.37482)
		(size 0.4064)
		(drill 0.2032)
		(layers "F.Cu" "B.Cu")
		(net "GND")
	)
	(via
		(at 186.86018 -354.074222)
		(size 0.4572)
		(drill 0.254)
		(layers "F.Cu" "B.Cu")
		(net "GND")
	)
	(via
		(at 57.023 -140.97)
		(size 0.508)
		(drill 0.254)
		(layers "F.Cu" "B.Cu")
		(net "GND")
	)
	(via
		(at 168.625012 -284.974792)
		(size 0.4064)
		(drill 0.2032)
		(layers "F.Cu" "B.Cu")
		(net "GND")
	)
	(via
		(at 403.71014 -357.75773)
		(size 0.4064)
		(drill 0.2032)
		(layers "F.Cu" "B.Cu")
		(net "GND")
	)
	(via
		(at 82.347816 -409.940252)
		(size 0.508)
		(drill 0.254)
		(layers "F.Cu" "B.Cu")
		(net "GND")
	)
	(via
		(at 290.80079 -29.590238)
		(size 0.508)
		(drill 0.254)
		(layers "F.Cu" "B.Cu")
		(net "GND")
	)
	(via
		(at 117.210586 -289.41649)
		(size 0.508)
		(drill 0.254)
		(layers "F.Cu" "B.Cu")
		(net "GND")
	)
	(via
		(at 431.882296 -37.087048)
		(size 0.508)
		(drill 0.254)
		(layers "F.Cu" "B.Cu")
		(net "GND")
	)
	(via
		(at 453.623172 -54.067456)
		(size 0.508)
		(drill 0.254)
		(layers "F.Cu" "B.Cu")
		(net "GND")
	)
	(via
		(at 188.119004 -343.073482)
		(size 0.4572)
		(drill 0.254)
		(layers "F.Cu" "B.Cu")
		(net "GND")
	)
	(via
		(at 111.311182 -288.14649)
		(size 0.508)
		(drill 0.254)
		(layers "F.Cu" "B.Cu")
		(net "GND")
	)
	(via
		(at 316.6872 -254.4064)
		(size 0.508)
		(drill 0.254)
		(layers "F.Cu" "B.Cu")
		(net "GND")
	)
	(via
		(at 72.131682 -345.465146)
		(size 0.4064)
		(drill 0.2032)
		(layers "F.Cu" "B.Cu")
		(net "GND")
	)
	(via
		(at 308.474872 -292.574726)
		(size 0.4064)
		(drill 0.2032)
		(layers "F.Cu" "B.Cu")
		(net "GND")
	)
	(via
		(at 42.747946 -373.441976)
		(size 0.508)
		(drill 0.254)
		(layers "F.Cu" "B.Cu")
		(net "GND")
	)
	(via
		(at 357.909368 -287.51149)
		(size 0.508)
		(drill 0.254)
		(layers "F.Cu" "B.Cu")
		(net "GND")
	)
	(via
		(at 199.500236 -304.449734)
		(size 0.4064)
		(drill 0.2032)
		(layers "F.Cu" "B.Cu")
		(net "GND")
	)
	(via
		(at 183.75122 -343.073482)
		(size 0.4572)
		(drill 0.254)
		(layers "F.Cu" "B.Cu")
		(net "GND")
	)
	(via
		(at 293.527734 -407.24201)
		(size 0.508)
		(drill 0.254)
		(layers "F.Cu" "B.Cu")
		(net "GND")
	)
	(via
		(at 44.94784 -397.140176)
		(size 0.508)
		(drill 0.254)
		(layers "F.Cu" "B.Cu")
		(net "GND")
	)
	(via
		(at 161.025078 -288.774886)
		(size 0.4064)
		(drill 0.2032)
		(layers "F.Cu" "B.Cu")
		(net "GND")
	)
	(via
		(at 262.410448 -75.892406)
		(size 0.508)
		(drill 0.254)
		(layers "F.Cu" "B.Cu")
		(net "GND")
	)
	(via
		(at 408.424888 -285.924752)
		(size 0.4064)
		(drill 0.2032)
		(layers "F.Cu" "B.Cu")
		(net "GND")
	)
	(via
		(at 26.982928 -357.75773)
		(size 0.4064)
		(drill 0.2032)
		(layers "F.Cu" "B.Cu")
		(net "GND")
	)
	(via
		(at 151.859488 -131.495546)
		(size 0.508)
		(drill 0.254)
		(layers "F.Cu" "B.Cu")
		(net "GND")
	)
	(via
		(at 325.651368 -113.364772)
		(size 0.508)
		(drill 0.254)
		(layers "F.Cu" "B.Cu")
		(net "GND")
	)
	(via
		(at 89.788492 -31.642304)
		(size 0.508)
		(drill 0.254)
		(layers "F.Cu" "B.Cu")
		(net "GND")
	)
	(via
		(at 195.700142 -274.049744)
		(size 0.4064)
		(drill 0.2032)
		(layers "F.Cu" "B.Cu")
		(net "GND")
	)
	(via
		(at 72.949816 -280.699718)
		(size 0.4064)
		(drill 0.2032)
		(layers "F.Cu" "B.Cu")
		(net "GND")
	)
	(via
		(at 42.15638 -347.951806)
		(size 0.4572)
		(drill 0.254)
		(layers "F.Cu" "B.Cu")
		(net "GND")
	)
	(via
		(at 429.325024 -302.074834)
		(size 0.4064)
		(drill 0.2032)
		(layers "F.Cu" "B.Cu")
		(net "GND")
	)
	(via
		(at 190.950088 -288.299906)
		(size 0.4064)
		(drill 0.2032)
		(layers "F.Cu" "B.Cu")
		(net "GND")
	)
	(via
		(at 137.413492 -29.859478)
		(size 0.508)
		(drill 0.254)
		(layers "F.Cu" "B.Cu")
		(net "GND")
	)
	(via
		(at 429.325024 -292.574726)
		(size 0.4064)
		(drill 0.2032)
		(layers "F.Cu" "B.Cu")
		(net "GND")
	)
	(via
		(at 228.667818 -221.103952)
		(size 0.4572)
		(drill 0.254)
		(layers "F.Cu" "B.Cu")
		(net "GND")
	)
	(via
		(at 31.570676 -346.09913)
		(size 0.4572)
		(drill 0.254)
		(layers "F.Cu" "B.Cu")
		(net "GND")
	)
	(via
		(at 65.824862 -287.824926)
		(size 0.4064)
		(drill 0.2032)
		(layers "F.Cu" "B.Cu")
		(net "GND")
	)
	(via
		(at 333.127858 -378.83846)
		(size 0.508)
		(drill 0.254)
		(layers "F.Cu" "B.Cu")
		(net "GND")
	)
	(via
		(at 161.54781 -382.73863)
		(size 0.508)
		(drill 0.254)
		(layers "F.Cu" "B.Cu")
		(net "GND")
	)
	(via
		(at 293.527734 -399.441924)
		(size 0.508)
		(drill 0.254)
		(layers "F.Cu" "B.Cu")
		(net "GND")
	)
	(via
		(at 268.574774 -280.224738)
		(size 0.4064)
		(drill 0.2032)
		(layers "F.Cu" "B.Cu")
		(net "GND")
	)
	(via
		(at 127.840994 -181.775608)
		(size 0.508)
		(drill 0.254)
		(layers "F.Cu" "B.Cu")
		(net "GND")
	)
	(via
		(at 228.29901 -144.824704)
		(size 0.508)
		(drill 0.254)
		(layers "F.Cu" "B.Cu")
		(net "GND")
	)
	(via
		(at 173.850046 -314.899802)
		(size 0.4064)
		(drill 0.2032)
		(layers "F.Cu" "B.Cu")
		(net "GND")
	)
	(via
		(at 185.844688 -143.655796)
		(size 0.508)
		(drill 0.254)
		(layers "F.Cu" "B.Cu")
		(net "GND")
	)
	(via
		(at 174.079662 -102.798372)
		(size 0.508)
		(drill 0.254)
		(layers "F.Cu" "B.Cu")
		(net "GND")
	)
	(via
		(at 200.908158 -155.024582)
		(size 0.508)
		(drill 0.254)
		(layers "F.Cu" "B.Cu")
		(net "GND")
	)
	(via
		(at 122.2502 -347.951806)
		(size 0.4572)
		(drill 0.254)
		(layers "F.Cu" "B.Cu")
		(net "GND")
	)
	(via
		(at 154.37485 -298.27474)
		(size 0.4064)
		(drill 0.2032)
		(layers "F.Cu" "B.Cu")
		(net "GND")
	)
	(via
		(at 43.024806 -287.824926)
		(size 0.4064)
		(drill 0.2032)
		(layers "F.Cu" "B.Cu")
		(net "GND")
	)
	(via
		(at 463.037682 -164.097462)
		(size 0.508)
		(drill 0.254)
		(layers "F.Cu" "B.Cu")
		(net "GND")
	)
	(via
		(at 357.35514 -122.931428)
		(size 0.508)
		(drill 0.254)
		(layers "F.Cu" "B.Cu")
		(net "GND")
	)
	(via
		(at 309.02402 -113.229898)
		(size 0.508)
		(drill 0.254)
		(layers "F.Cu" "B.Cu")
		(net "GND")
	)
	(via
		(at 293.27475 -296.37482)
		(size 0.4064)
		(drill 0.2032)
		(layers "F.Cu" "B.Cu")
		(net "GND")
	)
	(via
		(at 162.924998 -309.674768)
		(size 0.4064)
		(drill 0.2032)
		(layers "F.Cu" "B.Cu")
		(net "GND")
	)
	(via
		(at 67.39255 -347.951806)
		(size 0.4572)
		(drill 0.254)
		(layers "F.Cu" "B.Cu")
		(net "GND")
	)
	(via
		(at 401.299934 -318.699896)
		(size 0.4064)
		(drill 0.2032)
		(layers "F.Cu" "B.Cu")
		(net "GND")
	)
	(via
		(at 395.862048 -357.123746)
		(size 0.4572)
		(drill 0.254)
		(layers "F.Cu" "B.Cu")
		(net "GND")
	)
	(via
		(at 397.49984 -278.799798)
		(size 0.4064)
		(drill 0.2032)
		(layers "F.Cu" "B.Cu")
		(net "GND")
	)
	(via
		(at 156.750004 -315.849762)
		(size 0.4064)
		(drill 0.2032)
		(layers "F.Cu" "B.Cu")
		(net "GND")
	)
	(via
		(at 65.824862 -300.174914)
		(size 0.4064)
		(drill 0.2032)
		(layers "F.Cu" "B.Cu")
		(net "GND")
	)
	(via
		(at 119.14124 -349.219774)
		(size 0.4572)
		(drill 0.254)
		(layers "F.Cu" "B.Cu")
		(net "GND")
	)
	(via
		(at 138.934698 -71.451978)
		(size 0.508)
		(drill 0.254)
		(layers "F.Cu" "B.Cu")
		(net "GND")
	)
	(via
		(at 163.457636 -102.847394)
		(size 0.508)
		(drill 0.254)
		(layers "F.Cu" "B.Cu")
		(net "GND")
	)
	(via
		(at 44.449746 -314.899802)
		(size 0.4064)
		(drill 0.2032)
		(layers "F.Cu" "B.Cu")
		(net "GND")
	)
	(via
		(at 279.024842 -303.024794)
		(size 0.4064)
		(drill 0.2032)
		(layers "F.Cu" "B.Cu")
		(net "GND")
	)
	(via
		(at 410.799788 -277.849838)
		(size 0.4064)
		(drill 0.2032)
		(layers "F.Cu" "B.Cu")
		(net "GND")
	)
	(via
		(at 70.671182 -31.652972)
		(size 0.508)
		(drill 0.254)
		(layers "F.Cu" "B.Cu")
		(net "GND")
	)
	(via
		(at 65.542414 -352.245422)
		(size 0.4572)
		(drill 0.254)
		(layers "F.Cu" "B.Cu")
		(net "GND")
	)
	(via
		(at 71.524876 -288.774886)
		(size 0.4064)
		(drill 0.2032)
		(layers "F.Cu" "B.Cu")
		(net "GND")
	)
	(via
		(at 109.457236 -305.008534)
		(size 0.508)
		(drill 0.254)
		(layers "F.Cu" "B.Cu")
		(net "GND")
	)
	(via
		(at 267.69949 -350.977454)
		(size 0.4572)
		(drill 0.254)
		(layers "F.Cu" "B.Cu")
		(net "GND")
	)
	(via
		(at 390.327896 -400.938492)
		(size 0.508)
		(drill 0.254)
		(layers "F.Cu" "B.Cu")
		(net "GND")
	)
	(via
		(at 461.017112 -283.105606)
		(size 0.508)
		(drill 0.254)
		(layers "F.Cu" "B.Cu")
		(net "GND")
	)
	(via
		(at 109.678216 -136.952228)
		(size 0.508)
		(drill 0.254)
		(layers "F.Cu" "B.Cu")
		(net "GND")
	)
	(via
		(at 425.04995 -272.14957)
		(size 0.4064)
		(drill 0.2032)
		(layers "F.Cu" "B.Cu")
		(net "GND")
	)
	(via
		(at 64.28359 -343.073482)
		(size 0.4572)
		(drill 0.254)
		(layers "F.Cu" "B.Cu")
		(net "GND")
	)
	(via
		(at 354.302568 -286.842454)
		(size 0.508)
		(drill 0.254)
		(layers "F.Cu" "B.Cu")
		(net "GND")
	)
	(via
		(at 82.166206 -129.707894)
		(size 0.508)
		(drill 0.254)
		(layers "F.Cu" "B.Cu")
		(net "GND")
	)
	(via
		(at 332.451202 -47.03191)
		(size 0.508)
		(drill 0.254)
		(layers "F.Cu" "B.Cu")
		(net "GND")
	)
	(via
		(at 76.27493 -299.224954)
		(size 0.4064)
		(drill 0.2032)
		(layers "F.Cu" "B.Cu")
		(net "GND")
	)
	(via
		(at 46.34992 -305.399948)
		(size 0.4064)
		(drill 0.2032)
		(layers "F.Cu" "B.Cu")
		(net "GND")
	)
	(via
		(at 306.099718 -274.049744)
		(size 0.4064)
		(drill 0.2032)
		(layers "F.Cu" "B.Cu")
		(net "GND")
	)
	(via
		(at 201.804524 -358.471978)
		(size 0.508)
		(drill 0.254)
		(layers "F.Cu" "B.Cu")
		(net "GND")
	)
	(via
		(at 148.342096 -307.240178)
		(size 0.508)
		(drill 0.254)
		(layers "F.Cu" "B.Cu")
		(net "GND")
	)
	(via
		(at 90.414094 -341.781638)
		(size 0.4572)
		(drill 0.254)
		(layers "F.Cu" "B.Cu")
		(net "GND")
	)
	(via
		(at 426.851572 -100.056696)
		(size 0.508)
		(drill 0.254)
		(layers "F.Cu" "B.Cu")
		(net "GND")
	)
	(via
		(at 285.674816 -297.32478)
		(size 0.4064)
		(drill 0.2032)
		(layers "F.Cu" "B.Cu")
		(net "GND")
	)
	(via
		(at 144.614646 -391.654538)
		(size 0.508)
		(drill 0.254)
		(layers "F.Cu" "B.Cu")
		(net "GND")
	)
	(via
		(at 54.899814 -314.899802)
		(size 0.4064)
		(drill 0.2032)
		(layers "F.Cu" "B.Cu")
		(net "GND")
	)
	(via
		(at 169.574972 -294.4749)
		(size 0.4064)
		(drill 0.2032)
		(layers "F.Cu" "B.Cu")
		(net "GND")
	)
	(via
		(at 333.629254 -47.020734)
		(size 0.508)
		(drill 0.254)
		(layers "F.Cu" "B.Cu")
		(net "GND")
	)
	(via
		(at 44.94784 -408.840178)
		(size 0.508)
		(drill 0.254)
		(layers "F.Cu" "B.Cu")
		(net "GND")
	)
	(via
		(at 267.848842 -29.589984)
		(size 0.508)
		(drill 0.254)
		(layers "F.Cu" "B.Cu")
		(net "GND")
	)
	(via
		(at 285.969456 -64.102234)
		(size 0.508)
		(drill 0.254)
		(layers "F.Cu" "B.Cu")
		(net "GND")
	)
	(via
		(at 198.26605 -153.218134)
		(size 0.508)
		(drill 0.254)
		(layers "F.Cu" "B.Cu")
		(net "GND")
	)
	(via
		(at 388.949946 -306.349908)
		(size 0.4064)
		(drill 0.2032)
		(layers "F.Cu" "B.Cu")
		(net "GND")
	)
	(via
		(at 99.530408 -65.15989)
		(size 0.508)
		(drill 0.254)
		(layers "F.Cu" "B.Cu")
		(net "GND")
	)
	(via
		(at 302.327818 -397.038576)
		(size 0.508)
		(drill 0.254)
		(layers "F.Cu" "B.Cu")
		(net "GND")
	)
	(via
		(at 247.662192 -285.445962)
		(size 0.508)
		(drill 0.254)
		(layers "F.Cu" "B.Cu")
		(net "GND")
	)
	(via
		(at 80.147922 -401.040092)
		(size 0.508)
		(drill 0.254)
		(layers "F.Cu" "B.Cu")
		(net "GND")
	)
	(via
		(at 180.975 -287.824926)
		(size 0.4064)
		(drill 0.2032)
		(layers "F.Cu" "B.Cu")
		(net "GND")
	)
	(via
		(at 82.93735 -343.073482)
		(size 0.4572)
		(drill 0.254)
		(layers "F.Cu" "B.Cu")
		(net "GND")
	)
	(via
		(at 433.599844 -62.812168)
		(size 0.508)
		(drill 0.254)
		(layers "F.Cu" "B.Cu")
		(net "GND")
	)
	(via
		(at 335.328006 -401.040092)
		(size 0.508)
		(drill 0.254)
		(layers "F.Cu" "B.Cu")
		(net "GND")
	)
	(via
		(at 73.239122 -351.611438)
		(size 0.4064)
		(drill 0.2032)
		(layers "F.Cu" "B.Cu")
		(net "GND")
	)
	(via
		(at 44.006516 -357.123746)
		(size 0.4572)
		(drill 0.254)
		(layers "F.Cu" "B.Cu")
		(net "GND")
	)
	(via
		(at 75.79995 -284.499812)
		(size 0.4064)
		(drill 0.2032)
		(layers "F.Cu" "B.Cu")
		(net "GND")
	)
	(via
		(at 36.14801 -380.141734)
		(size 0.508)
		(drill 0.254)
		(layers "F.Cu" "B.Cu")
		(net "GND")
	)
	(via
		(at 408.755088 -31.390082)
		(size 0.508)
		(drill 0.254)
		(layers "F.Cu" "B.Cu")
		(net "GND")
	)
	(via
		(at 82.166206 -122.098054)
		(size 0.508)
		(drill 0.254)
		(layers "F.Cu" "B.Cu")
		(net "GND")
	)
	(via
		(at 200.908158 -145.483326)
		(size 0.508)
		(drill 0.254)
		(layers "F.Cu" "B.Cu")
		(net "GND")
	)
	(via
		(at 120.815354 -60.601606)
		(size 0.508)
		(drill 0.254)
		(layers "F.Cu" "B.Cu")
		(net "GND")
	)
	(via
		(at 301.824898 -297.32478)
		(size 0.4064)
		(drill 0.2032)
		(layers "F.Cu" "B.Cu")
		(net "GND")
	)
	(via
		(at 72.949816 -274.999958)
		(size 0.4064)
		(drill 0.2032)
		(layers "F.Cu" "B.Cu")
		(net "GND")
	)
	(via
		(at 188.214 -195.8594)
		(size 0.508)
		(drill 0.254)
		(layers "F.Cu" "B.Cu")
		(net "GND")
	)
	(via
		(at 296.599864 -310.149748)
		(size 0.4064)
		(drill 0.2032)
		(layers "F.Cu" "B.Cu")
		(net "GND")
	)
	(via
		(at 385.624832 -275.474938)
		(size 0.4064)
		(drill 0.2032)
		(layers "F.Cu" "B.Cu")
		(net "GND")
	)
	(via
		(at 37.565584 -151.40813)
		(size 0.508)
		(drill 0.254)
		(layers "F.Cu" "B.Cu")
		(net "GND")
	)
	(via
		(at 32.6009 -34.990278)
		(size 0.508)
		(drill 0.254)
		(layers "F.Cu" "B.Cu")
		(net "GND")
	)
	(via
		(at 60.124848 -297.32478)
		(size 0.4064)
		(drill 0.2032)
		(layers "F.Cu" "B.Cu")
		(net "GND")
	)
	(via
		(at 196.649848 -308.249828)
		(size 0.4064)
		(drill 0.2032)
		(layers "F.Cu" "B.Cu")
		(net "GND")
	)
	(via
		(at 370.551456 -47.03191)
		(size 0.508)
		(drill 0.254)
		(layers "F.Cu" "B.Cu")
		(net "GND")
	)
	(via
		(at 272.374868 -296.37482)
		(size 0.4064)
		(drill 0.2032)
		(layers "F.Cu" "B.Cu")
		(net "GND")
	)
	(via
		(at 178.792124 -357.123746)
		(size 0.4572)
		(drill 0.254)
		(layers "F.Cu" "B.Cu")
		(net "GND")
	)
	(via
		(at 171.31538 -354.098098)
		(size 0.4572)
		(drill 0.254)
		(layers "F.Cu" "B.Cu")
		(net "GND")
	)
	(via
		(at 292.199822 -357.75773)
		(size 0.4064)
		(drill 0.2032)
		(layers "F.Cu" "B.Cu")
		(net "GND")
	)
	(via
		(at 18.763488 -348.58579)
		(size 0.4064)
		(drill 0.2032)
		(layers "F.Cu" "B.Cu")
		(net "GND")
	)
	(via
		(at 167.675052 -289.724846)
		(size 0.4064)
		(drill 0.2032)
		(layers "F.Cu" "B.Cu")
		(net "GND")
	)
	(via
		(at 3.048 -417.82492)
		(size 0.508)
		(drill 0.254)
		(layers "F.Cu" "B.Cu")
		(net "GND")
	)
	(via
		(at 64.399922 -276.899878)
		(size 0.4064)
		(drill 0.2032)
		(layers "F.Cu" "B.Cu")
		(net "GND")
	)
	(via
		(at 67.021202 -354.732082)
		(size 0.4064)
		(drill 0.2032)
		(layers "F.Cu" "B.Cu")
		(net "GND")
	)
	(via
		(at 160.844992 -11.400536)
		(size 0.508)
		(drill 0.254)
		(layers "F.Cu" "B.Cu")
		(net "GND")
	)
	(via
		(at 304.410872 -109.41304)
		(size 0.508)
		(drill 0.254)
		(layers "F.Cu" "B.Cu")
		(net "GND")
	)
	(via
		(at 196.649848 -274.999958)
		(size 0.4064)
		(drill 0.2032)
		(layers "F.Cu" "B.Cu")
		(net "GND")
	)
	(via
		(at 26.61158 -341.805514)
		(size 0.4572)
		(drill 0.254)
		(layers "F.Cu" "B.Cu")
		(net "GND")
	)
	(via
		(at 302.167544 -134.400544)
		(size 0.508)
		(drill 0.254)
		(layers "F.Cu" "B.Cu")
		(net "GND")
	)
	(via
		(at 314.649866 -309.199788)
		(size 0.4064)
		(drill 0.2032)
		(layers "F.Cu" "B.Cu")
		(net "GND")
	)
	(via
		(at 426.851572 -102.088696)
		(size 0.508)
		(drill 0.254)
		(layers "F.Cu" "B.Cu")
		(net "GND")
	)
	(via
		(at 120.991376 -349.219774)
		(size 0.4572)
		(drill 0.254)
		(layers "F.Cu" "B.Cu")
		(net "GND")
	)
	(via
		(at 174.747936 -385.141978)
		(size 0.508)
		(drill 0.254)
		(layers "F.Cu" "B.Cu")
		(net "GND")
	)
	(via
		(at 368.064288 -226.715574)
		(size 0.508)
		(drill 0.254)
		(layers "F.Cu" "B.Cu")
		(net "GND")
	)
	(via
		(at 76.27493 -298.27474)
		(size 0.4064)
		(drill 0.2032)
		(layers "F.Cu" "B.Cu")
		(net "GND")
	)
	(via
		(at 349.85706 -317.69304)
		(size 0.508)
		(drill 0.254)
		(layers "F.Cu" "B.Cu")
		(net "GND")
	)
	(via
		(at 291.84981 -280.699718)
		(size 0.4064)
		(drill 0.2032)
		(layers "F.Cu" "B.Cu")
		(net "GND")
	)
	(via
		(at 183.72201 -117.415056)
		(size 0.508)
		(drill 0.254)
		(layers "F.Cu" "B.Cu")
		(net "GND")
	)
	(via
		(at 71.347838 -375.040144)
		(size 0.508)
		(drill 0.254)
		(layers "F.Cu" "B.Cu")
		(net "GND")
	)
	(via
		(at 433.492656 -11.372596)
		(size 0.508)
		(drill 0.254)
		(layers "F.Cu" "B.Cu")
		(net "GND")
	)
	(via
		(at 62.024768 -305.874928)
		(size 0.4064)
		(drill 0.2032)
		(layers "F.Cu" "B.Cu")
		(net "GND")
	)
	(via
		(at 169.574972 -303.974754)
		(size 0.4064)
		(drill 0.2032)
		(layers "F.Cu" "B.Cu")
		(net "GND")
	)
	(via
		(at 111.664496 -341.805514)
		(size 0.4572)
		(drill 0.254)
		(layers "F.Cu" "B.Cu")
		(net "GND")
	)
	(via
		(at 333.127858 -398.24025)
		(size 0.508)
		(drill 0.254)
		(layers "F.Cu" "B.Cu")
		(net "GND")
	)
	(via
		(at 427.89983 -312.999882)
		(size 0.4064)
		(drill 0.2032)
		(layers "F.Cu" "B.Cu")
		(net "GND")
	)
	(via
		(at 398.971008 -357.123746)
		(size 0.4572)
		(drill 0.254)
		(layers "F.Cu" "B.Cu")
		(net "GND")
	)
	(via
		(at 249.627898 -228.538278)
		(size 0.508)
		(drill 0.254)
		(layers "F.Cu" "B.Cu")
		(net "GND")
	)
	(via
		(at 383.495042 -60.633356)
		(size 0.508)
		(drill 0.254)
		(layers "F.Cu" "B.Cu")
		(net "GND")
	)
	(via
		(at 156.750004 -308.249828)
		(size 0.4064)
		(drill 0.2032)
		(layers "F.Cu" "B.Cu")
		(net "GND")
	)
	(via
		(at 313.699906 -318.699896)
		(size 0.4064)
		(drill 0.2032)
		(layers "F.Cu" "B.Cu")
		(net "GND")
	)
	(via
		(at 419.683184 -344.831162)
		(size 0.4572)
		(drill 0.254)
		(layers "F.Cu" "B.Cu")
		(net "GND")
	)
	(via
		(at 165.299898 -277.849838)
		(size 0.4064)
		(drill 0.2032)
		(layers "F.Cu" "B.Cu")
		(net "GND")
	)
	(via
		(at 124.147834 -376.241818)
		(size 0.4572)
		(drill 0.254)
		(layers "F.Cu" "B.Cu")
		(net "GND")
	)
	(via
		(at 399.93316 -120.555004)
		(size 0.508)
		(drill 0.254)
		(layers "F.Cu" "B.Cu")
		(net "GND")
	)
	(via
		(at 194.749928 -310.149748)
		(size 0.4064)
		(drill 0.2032)
		(layers "F.Cu" "B.Cu")
		(net "GND")
	)
	(via
		(at 137.577576 -98.817938)
		(size 0.508)
		(drill 0.254)
		(layers "F.Cu" "B.Cu")
		(net "GND")
	)
	(via
		(at 362.548932 -27.79014)
		(size 0.508)
		(drill 0.254)
		(layers "F.Cu" "B.Cu")
		(net "GND")
	)
	(via
		(at 389.27278 -354.732082)
		(size 0.4064)
		(drill 0.2032)
		(layers "F.Cu" "B.Cu")
		(net "GND")
	)
	(via
		(at 70.50151 -358.391714)
		(size 0.4572)
		(drill 0.254)
		(layers "F.Cu" "B.Cu")
		(net "GND")
	)
	(via
		(at 440.18708 -343.073482)
		(size 0.4572)
		(drill 0.254)
		(layers "F.Cu" "B.Cu")
		(net "GND")
	)
	(via
		(at 169.423334 -51.019456)
		(size 0.508)
		(drill 0.254)
		(layers "F.Cu" "B.Cu")
		(net "GND")
	)
	(via
		(at 39.90213 -56.826404)
		(size 0.508)
		(drill 0.254)
		(layers "F.Cu" "B.Cu")
		(net "GND")
	)
	(via
		(at 274.749768 -311.099962)
		(size 0.4064)
		(drill 0.2032)
		(layers "F.Cu" "B.Cu")
		(net "GND")
	)
	(via
		(at 127.410972 -177.38217)
		(size 0.508)
		(drill 0.254)
		(layers "F.Cu" "B.Cu")
		(net "GND")
	)
	(via
		(at 179.55006 -312.049922)
		(size 0.4064)
		(drill 0.2032)
		(layers "F.Cu" "B.Cu")
		(net "GND")
	)
	(via
		(at 449.044822 -107.681776)
		(size 0.508)
		(drill 0.254)
		(layers "F.Cu" "B.Cu")
		(net "GND")
	)
	(via
		(at 86.747858 -397.038576)
		(size 0.508)
		(drill 0.254)
		(layers "F.Cu" "B.Cu")
		(net "GND")
	)
	(via
		(at 117.547644 -380.040134)
		(size 0.4572)
		(drill 0.254)
		(layers "F.Cu" "B.Cu")
		(net "GND")
	)
	(via
		(at 383.72796 -381.638556)
		(size 0.508)
		(drill 0.254)
		(layers "F.Cu" "B.Cu")
		(net "GND")
	)
	(via
		(at 26.193496 -286.331914)
		(size 0.508)
		(drill 0.254)
		(layers "F.Cu" "B.Cu")
		(net "GND")
	)
	(via
		(at 392.749532 -272.14957)
		(size 0.4064)
		(drill 0.2032)
		(layers "F.Cu" "B.Cu")
		(net "GND")
	)
	(via
		(at 421.127682 -406.040336)
		(size 0.508)
		(drill 0.254)
		(layers "F.Cu" "B.Cu")
		(net "GND")
	)
	(via
		(at 55.320946 -364.155736)
		(size 0.508)
		(drill 0.254)
		(layers "F.Cu" "B.Cu")
		(net "GND")
	)
	(via
		(at 441.73775 -74.624184)
		(size 0.508)
		(drill 0.254)
		(layers "F.Cu" "B.Cu")
		(net "GND")
	)
	(via
		(at 24.981408 -351.611438)
		(size 0.4064)
		(drill 0.2032)
		(layers "F.Cu" "B.Cu")
		(net "GND")
	)
	(via
		(at 159.599884 -300.649894)
		(size 0.4064)
		(drill 0.2032)
		(layers "F.Cu" "B.Cu")
		(net "GND")
	)
	(via
		(at 447.522092 -52.51704)
		(size 0.508)
		(drill 0.254)
		(layers "F.Cu" "B.Cu")
		(net "GND")
	)
	(via
		(at 342.876378 -289.41649)
		(size 0.508)
		(drill 0.254)
		(layers "F.Cu" "B.Cu")
		(net "GND")
	)
	(via
		(at 348.527878 -375.040398)
		(size 0.508)
		(drill 0.254)
		(layers "F.Cu" "B.Cu")
		(net "GND")
	)
	(via
		(at 58.799984 -38.315138)
		(size 0.508)
		(drill 0.254)
		(layers "F.Cu" "B.Cu")
		(net "GND")
	)
	(via
		(at 362.204 -180.086)
		(size 0.508)
		(drill 0.254)
		(layers "F.Cu" "B.Cu")
		(net "GND")
	)
	(via
		(at 73.547732 -373.441976)
		(size 0.508)
		(drill 0.254)
		(layers "F.Cu" "B.Cu")
		(net "GND")
	)
	(via
		(at 183.766714 -154.755088)
		(size 0.508)
		(drill 0.254)
		(layers "F.Cu" "B.Cu")
		(net "GND")
	)
	(via
		(at 410.356304 -347.951806)
		(size 0.4572)
		(drill 0.254)
		(layers "F.Cu" "B.Cu")
		(net "GND")
	)
	(via
		(at 425.527724 -409.940252)
		(size 0.508)
		(drill 0.254)
		(layers "F.Cu" "B.Cu")
		(net "GND")
	)
	(via
		(at 422.792144 -354.098098)
		(size 0.4572)
		(drill 0.254)
		(layers "F.Cu" "B.Cu")
		(net "GND")
	)
	(via
		(at 178.124866 -284.974792)
		(size 0.4064)
		(drill 0.2032)
		(layers "F.Cu" "B.Cu")
		(net "GND")
	)
	(via
		(at 168.20642 -352.245422)
		(size 0.4572)
		(drill 0.254)
		(layers "F.Cu" "B.Cu")
		(net "GND")
	)
	(via
		(at 393.351766 -137.16508)
		(size 0.508)
		(drill 0.254)
		(layers "F.Cu" "B.Cu")
		(net "GND")
	)
	(via
		(at 172.424852 -284.024832)
		(size 0.4064)
		(drill 0.2032)
		(layers "F.Cu" "B.Cu")
		(net "GND")
	)
	(via
		(at 279.974802 -284.024832)
		(size 0.4064)
		(drill 0.2032)
		(layers "F.Cu" "B.Cu")
		(net "GND")
	)
	(via
		(at 90.956384 -220.334586)
		(size 0.508)
		(drill 0.254)
		(layers "F.Cu" "B.Cu")
		(net "GND")
	)
	(via
		(at 81.499964 -286.399732)
		(size 0.4064)
		(drill 0.2032)
		(layers "F.Cu" "B.Cu")
		(net "GND")
	)
	(via
		(at 76.348082 -351.611438)
		(size 0.4064)
		(drill 0.2032)
		(layers "F.Cu" "B.Cu")
		(net "GND")
	)
	(via
		(at 18.763488 -342.439498)
		(size 0.4064)
		(drill 0.2032)
		(layers "F.Cu" "B.Cu")
		(net "GND")
	)
	(via
		(at 412.699962 -281.649932)
		(size 0.4064)
		(drill 0.2032)
		(layers "F.Cu" "B.Cu")
		(net "GND")
	)
	(via
		(at 365.138462 -73.20026)
		(size 0.508)
		(drill 0.254)
		(layers "F.Cu" "B.Cu")
		(net "GND")
	)
	(via
		(at 119.747792 -406.141936)
		(size 0.4572)
		(drill 0.254)
		(layers "F.Cu" "B.Cu")
		(net "GND")
	)
	(via
		(at 167.675052 -306.824888)
		(size 0.4064)
		(drill 0.2032)
		(layers "F.Cu" "B.Cu")
		(net "GND")
	)
	(via
		(at 191.900048 -301.599854)
		(size 0.4064)
		(drill 0.2032)
		(layers "F.Cu" "B.Cu")
		(net "GND")
	)
	(via
		(at 421.61333 -29.859478)
		(size 0.508)
		(drill 0.254)
		(layers "F.Cu" "B.Cu")
		(net "GND")
	)
	(via
		(at 285.052262 -107.844844)
		(size 0.508)
		(drill 0.254)
		(layers "F.Cu" "B.Cu")
		(net "GND")
	)
	(via
		(at 168.625012 -303.974754)
		(size 0.4064)
		(drill 0.2032)
		(layers "F.Cu" "B.Cu")
		(net "GND")
	)
	(via
		(at 120.991376 -358.391714)
		(size 0.4572)
		(drill 0.254)
		(layers "F.Cu" "B.Cu")
		(net "GND")
	)
	(via
		(at 128.638554 -307.18887)
		(size 0.508)
		(drill 0.254)
		(layers "F.Cu" "B.Cu")
		(net "GND")
	)
	(via
		(at 84.808314 -149.083522)
		(size 0.508)
		(drill 0.254)
		(layers "F.Cu" "B.Cu")
		(net "GND")
	)
	(via
		(at 289.46221 -349.219774)
		(size 0.4572)
		(drill 0.254)
		(layers "F.Cu" "B.Cu")
		(net "GND")
	)
	(via
		(at 61.648848 -29.589984)
		(size 0.508)
		(drill 0.254)
		(layers "F.Cu" "B.Cu")
		(net "GND")
	)
	(via
		(at 93.523054 -343.073482)
		(size 0.4572)
		(drill 0.254)
		(layers "F.Cu" "B.Cu")
		(net "GND")
	)
	(via
		(at 380.317248 -355.366066)
		(size 0.4572)
		(drill 0.254)
		(layers "F.Cu" "B.Cu")
		(net "GND")
	)
	(via
		(at 383.05486 -351.611438)
		(size 0.4064)
		(drill 0.2032)
		(layers "F.Cu" "B.Cu")
		(net "GND")
	)
	(via
		(at 460.248 -417.82492)
		(size 0.508)
		(drill 0.254)
		(layers "F.Cu" "B.Cu")
		(net "GND")
	)
	(via
		(at 273.799808 -302.549814)
		(size 0.4064)
		(drill 0.2032)
		(layers "F.Cu" "B.Cu")
		(net "GND")
	)
	(via
		(at 161.0868 -151.157432)
		(size 0.508)
		(drill 0.254)
		(layers "F.Cu" "B.Cu")
		(net "GND")
	)
	(via
		(at 427.75124 -341.805514)
		(size 0.4572)
		(drill 0.254)
		(layers "F.Cu" "B.Cu")
		(net "GND")
	)
	(via
		(at 107.860846 -216.063576)
		(size 0.508)
		(drill 0.254)
		(layers "F.Cu" "B.Cu")
		(net "GND")
	)
	(via
		(at 121.947686 -381.241808)
		(size 0.4572)
		(drill 0.254)
		(layers "F.Cu" "B.Cu")
		(net "GND")
	)
	(via
		(at 169.836592 -351.611438)
		(size 0.4064)
		(drill 0.2032)
		(layers "F.Cu" "B.Cu")
		(net "GND")
	)
	(via
		(at 142.382748 -354.732082)
		(size 0.4064)
		(drill 0.2032)
		(layers "F.Cu" "B.Cu")
		(net "GND")
	)
	(via
		(at 377.208288 -349.219774)
		(size 0.4572)
		(drill 0.254)
		(layers "F.Cu" "B.Cu")
		(net "GND")
	)
	(via
		(at 189.597792 -351.611438)
		(size 0.4064)
		(drill 0.2032)
		(layers "F.Cu" "B.Cu")
		(net "GND")
	)
	(via
		(at 395.59992 -274.049744)
		(size 0.4064)
		(drill 0.2032)
		(layers "F.Cu" "B.Cu")
		(net "GND")
	)
	(via
		(at 180.693314 -133.0452)
		(size 0.508)
		(drill 0.254)
		(layers "F.Cu" "B.Cu")
		(net "GND")
	)
	(via
		(at 416.974782 -284.024832)
		(size 0.4064)
		(drill 0.2032)
		(layers "F.Cu" "B.Cu")
		(net "GND")
	)
	(via
		(at 96.731074 -6.292342)
		(size 0.508)
		(drill 0.254)
		(layers "F.Cu" "B.Cu")
		(net "GND")
	)
	(via
		(at 289.127692 -406.040336)
		(size 0.508)
		(drill 0.254)
		(layers "F.Cu" "B.Cu")
		(net "GND")
	)
	(via
		(at 128.839468 -342.439498)
		(size 0.4064)
		(drill 0.2032)
		(layers "F.Cu" "B.Cu")
		(net "GND")
	)
	(via
		(at 216.934542 -71.451978)
		(size 0.508)
		(drill 0.254)
		(layers "F.Cu" "B.Cu")
		(net "GND")
	)
	(via
		(at 69.022722 -345.465146)
		(size 0.4064)
		(drill 0.2032)
		(layers "F.Cu" "B.Cu")
		(net "GND")
	)
	(via
		(at 199.64019 -156.283406)
		(size 0.508)
		(drill 0.254)
		(layers "F.Cu" "B.Cu")
		(net "GND")
	)
	(via
		(at 165.774878 -301.124874)
		(size 0.4064)
		(drill 0.2032)
		(layers "F.Cu" "B.Cu")
		(net "GND")
	)
	(via
		(at 280.13533 -344.831162)
		(size 0.4572)
		(drill 0.254)
		(layers "F.Cu" "B.Cu")
		(net "GND")
	)
	(via
		(at 146.473926 -25.971246)
		(size 0.508)
		(drill 0.254)
		(layers "F.Cu" "B.Cu")
		(net "GND")
	)
	(via
		(at 70.574916 -285.924752)
		(size 0.4064)
		(drill 0.2032)
		(layers "F.Cu" "B.Cu")
		(net "GND")
	)
	(via
		(at 7.934198 -389.152384)
		(size 0.508)
		(drill 0.254)
		(layers "F.Cu" "B.Cu")
		(net "GND")
	)
	(via
		(at 275.038312 -72.56526)
		(size 0.508)
		(drill 0.254)
		(layers "F.Cu" "B.Cu")
		(net "GND")
	)
	(via
		(at 108.668566 -78.731364)
		(size 0.508)
		(drill 0.254)
		(layers "F.Cu" "B.Cu")
		(net "GND")
	)
	(via
		(at 130.048 -417.82492)
		(size 0.508)
		(drill 0.254)
		(layers "F.Cu" "B.Cu")
		(net "GND")
	)
	(via
		(at 259.738876 -262.918956)
		(size 0.508)
		(drill 0.254)
		(layers "F.Cu" "B.Cu")
		(net "GND")
	)
	(via
		(at 279.232868 -131.76504)
		(size 0.508)
		(drill 0.254)
		(layers "F.Cu" "B.Cu")
		(net "GND")
	)
	(via
		(at 281.399742 -314.899802)
		(size 0.4064)
		(drill 0.2032)
		(layers "F.Cu" "B.Cu")
		(net "GND")
	)
	(via
		(at 60.599828 -318.699896)
		(size 0.4064)
		(drill 0.2032)
		(layers "F.Cu" "B.Cu")
		(net "GND")
	)
	(via
		(at 354.201984 -279.000712)
		(size 0.508)
		(drill 0.254)
		(layers "F.Cu" "B.Cu")
		(net "GND")
	)
	(via
		(at 51.74996 -143.615156)
		(size 0.508)
		(drill 0.254)
		(layers "F.Cu" "B.Cu")
		(net "GND")
	)
	(via
		(at 289.127692 -411.141926)
		(size 0.508)
		(drill 0.254)
		(layers "F.Cu" "B.Cu")
		(net "GND")
	)
	(via
		(at 66.44767 -143.955008)
		(size 0.508)
		(drill 0.254)
		(layers "F.Cu" "B.Cu")
		(net "GND")
	)
	(via
		(at 277.599902 -313.949842)
		(size 0.4064)
		(drill 0.2032)
		(layers "F.Cu" "B.Cu")
		(net "GND")
	)
	(via
		(at 194.749928 -279.749758)
		(size 0.4064)
		(drill 0.2032)
		(layers "F.Cu" "B.Cu")
		(net "GND")
	)
	(via
		(at 329.63739 -7.776972)
		(size 0.508)
		(drill 0.254)
		(layers "F.Cu" "B.Cu")
		(net "GND")
	)
	(via
		(at 132.270754 -307.877718)
		(size 0.508)
		(drill 0.254)
		(layers "F.Cu" "B.Cu")
		(net "GND")
	)
	(via
		(at 75.74788 -401.040092)
		(size 0.508)
		(drill 0.254)
		(layers "F.Cu" "B.Cu")
		(net "GND")
	)
	(via
		(at 46.8249 -286.874966)
		(size 0.4064)
		(drill 0.2032)
		(layers "F.Cu" "B.Cu")
		(net "GND")
	)
	(via
		(at 418.226748 -136.061958)
		(size 0.508)
		(drill 0.254)
		(layers "F.Cu" "B.Cu")
		(net "GND")
	)
	(via
		(at 401.15236 -106.045)
		(size 0.508)
		(drill 0.254)
		(layers "F.Cu" "B.Cu")
		(net "GND")
	)
	(via
		(at 75.240642 -357.75773)
		(size 0.4064)
		(drill 0.2032)
		(layers "F.Cu" "B.Cu")
		(net "GND")
	)
	(via
		(at 308.474872 -301.124874)
		(size 0.4064)
		(drill 0.2032)
		(layers "F.Cu" "B.Cu")
		(net "GND")
	)
	(via
		(at 381.527812 -398.24025)
		(size 0.508)
		(drill 0.254)
		(layers "F.Cu" "B.Cu")
		(net "GND")
	)
	(via
		(at 235.609892 -284.641544)
		(size 0.508)
		(drill 0.254)
		(layers "F.Cu" "B.Cu")
		(net "GND")
	)
	(via
		(at 417.138358 -72.56526)
		(size 0.508)
		(drill 0.254)
		(layers "F.Cu" "B.Cu")
		(net "GND")
	)
	(via
		(at 187.149994 -310.149748)
		(size 0.4064)
		(drill 0.2032)
		(layers "F.Cu" "B.Cu")
		(net "GND")
	)
	(via
		(at 133.427216 -349.219774)
		(size 0.4572)
		(drill 0.254)
		(layers "F.Cu" "B.Cu")
		(net "GND")
	)
	(via
		(at 231.067356 -217.104468)
		(size 0.4572)
		(drill 0.254)
		(layers "F.Cu" "B.Cu")
		(net "GND")
	)
	(via
		(at 388.54888 -31.390082)
		(size 0.508)
		(drill 0.254)
		(layers "F.Cu" "B.Cu")
		(net "GND")
	)
	(via
		(at 70.196202 -60.099194)
		(size 0.508)
		(drill 0.254)
		(layers "F.Cu" "B.Cu")
		(net "GND")
	)
	(via
		(at 181.92496 -306.824888)
		(size 0.4064)
		(drill 0.2032)
		(layers "F.Cu" "B.Cu")
		(net "GND")
	)
	(via
		(at 186.241182 -38.49116)
		(size 0.508)
		(drill 0.254)
		(layers "F.Cu" "B.Cu")
		(net "GND")
	)
	(via
		(at 377.12777 -372.240302)
		(size 0.508)
		(drill 0.254)
		(layers "F.Cu" "B.Cu")
		(net "GND")
	)
	(via
		(at 420.529004 -147.314412)
		(size 0.508)
		(drill 0.254)
		(layers "F.Cu" "B.Cu")
		(net "GND")
	)
	(via
		(at 277.720044 -56.441848)
		(size 0.508)
		(drill 0.254)
		(layers "F.Cu" "B.Cu")
		(net "GND")
	)
	(via
		(at 242.541552 -93.856302)
		(size 0.508)
		(drill 0.254)
		(layers "F.Cu" "B.Cu")
		(net "GND")
	)
	(via
		(at 174.052992 -351.611438)
		(size 0.4064)
		(drill 0.2032)
		(layers "F.Cu" "B.Cu")
		(net "GND")
	)
	(via
		(at 17.331944 -131.942332)
		(size 0.508)
		(drill 0.254)
		(layers "F.Cu" "B.Cu")
		(net "GND")
	)
	(via
		(at 103.15067 -288.78149)
		(size 0.508)
		(drill 0.254)
		(layers "F.Cu" "B.Cu")
		(net "GND")
	)
	(via
		(at 88.947752 -380.141988)
		(size 0.508)
		(drill 0.254)
		(layers "F.Cu" "B.Cu")
		(net "GND")
	)
	(via
		(at 374.927876 -395.938502)
		(size 0.508)
		(drill 0.254)
		(layers "F.Cu" "B.Cu")
		(net "GND")
	)
	(via
		(at 421.127682 -400.938492)
		(size 0.508)
		(drill 0.254)
		(layers "F.Cu" "B.Cu")
		(net "GND")
	)
	(via
		(at 360.86796 -254.194564)
		(size 0.508)
		(drill 0.254)
		(layers "F.Cu" "B.Cu")
		(net "GND")
	)
	(via
		(at 399.400014 -277.849838)
		(size 0.4064)
		(drill 0.2032)
		(layers "F.Cu" "B.Cu")
		(net "GND")
	)
	(via
		(at 305.376072 -257.441954)
		(size 0.508)
		(drill 0.254)
		(layers "F.Cu" "B.Cu")
		(net "GND")
	)
	(via
		(at 387.999986 -306.349908)
		(size 0.4064)
		(drill 0.2032)
		(layers "F.Cu" "B.Cu")
		(net "GND")
	)
	(via
		(at 121.798334 -307.82387)
		(size 0.508)
		(drill 0.254)
		(layers "F.Cu" "B.Cu")
		(net "GND")
	)
	(via
		(at 382.791716 -135.095488)
		(size 0.508)
		(drill 0.254)
		(layers "F.Cu" "B.Cu")
		(net "GND")
	)
	(via
		(at 45.051726 -109.644942)
		(size 0.508)
		(drill 0.254)
		(layers "F.Cu" "B.Cu")
		(net "GND")
	)
	(via
		(at 276.174708 -292.57498)
		(size 0.4064)
		(drill 0.2032)
		(layers "F.Cu" "B.Cu")
		(net "GND")
	)
	(via
		(at 110.034324 -269.366492)
		(size 0.508)
		(drill 0.254)
		(layers "F.Cu" "B.Cu")
		(net "GND")
	)
	(via
		(at 79.59979 -306.349908)
		(size 0.4064)
		(drill 0.2032)
		(layers "F.Cu" "B.Cu")
		(net "GND")
	)
	(via
		(at 433.108354 -120.30456)
		(size 0.508)
		(drill 0.254)
		(layers "F.Cu" "B.Cu")
		(net "GND")
	)
	(via
		(at 248.480834 -33.19018)
		(size 0.508)
		(drill 0.254)
		(layers "F.Cu" "B.Cu")
		(net "GND")
	)
	(via
		(at 249.822716 -23.880318)
		(size 0.508)
		(drill 0.254)
		(layers "F.Cu" "B.Cu")
		(net "GND")
	)
	(via
		(at 149.905212 -78.67904)
		(size 0.508)
		(drill 0.254)
		(layers "F.Cu" "B.Cu")
		(net "GND")
	)
	(via
		(at 76.749656 -276.899878)
		(size 0.4064)
		(drill 0.2032)
		(layers "F.Cu" "B.Cu")
		(net "GND")
	)
	(via
		(at 15.641574 -280.6954)
		(size 0.508)
		(drill 0.254)
		(layers "F.Cu" "B.Cu")
		(net "GND")
	)
	(via
		(at 401.615148 -45.88891)
		(size 0.508)
		(drill 0.254)
		(layers "F.Cu" "B.Cu")
		(net "GND")
	)
	(via
		(at 108.142786 -220.248734)
		(size 0.508)
		(drill 0.254)
		(layers "F.Cu" "B.Cu")
		(net "GND")
	)
	(via
		(at 187.168282 -48.753014)
		(size 0.508)
		(drill 0.254)
		(layers "F.Cu" "B.Cu")
		(net "GND")
	)
	(via
		(at 379.9459 -351.611438)
		(size 0.4064)
		(drill 0.2032)
		(layers "F.Cu" "B.Cu")
		(net "GND")
	)
	(via
		(at 424.57497 -294.4749)
		(size 0.4064)
		(drill 0.2032)
		(layers "F.Cu" "B.Cu")
		(net "GND")
	)
	(via
		(at 277.251668 -131.76504)
		(size 0.508)
		(drill 0.254)
		(layers "F.Cu" "B.Cu")
		(net "GND")
	)
	(via
		(at 331.384656 -259.959348)
		(size 0.508)
		(drill 0.254)
		(layers "F.Cu" "B.Cu")
		(net "GND")
	)
	(via
		(at 37.788596 -346.09913)
		(size 0.4572)
		(drill 0.254)
		(layers "F.Cu" "B.Cu")
		(net "GND")
	)
	(via
		(at 159.347916 -410.041852)
		(size 0.508)
		(drill 0.254)
		(layers "F.Cu" "B.Cu")
		(net "GND")
	)
	(via
		(at 356.87 -177.546)
		(size 0.508)
		(drill 0.254)
		(layers "F.Cu" "B.Cu")
		(net "GND")
	)
	(via
		(at 256.705862 -399.203926)
		(size 0.508)
		(drill 0.254)
		(layers "F.Cu" "B.Cu")
		(net "GND")
	)
	(via
		(at 280.13533 -350.977454)
		(size 0.4572)
		(drill 0.254)
		(layers "F.Cu" "B.Cu")
		(net "GND")
	)
	(via
		(at 33.947862 -402.140166)
		(size 0.508)
		(drill 0.254)
		(layers "F.Cu" "B.Cu")
		(net "GND")
	)
	(via
		(at 182.547514 -134.845044)
		(size 0.508)
		(drill 0.254)
		(layers "F.Cu" "B.Cu")
		(net "GND")
	)
	(via
		(at 412.991808 -109.481366)
		(size 0.508)
		(drill 0.254)
		(layers "F.Cu" "B.Cu")
		(net "GND")
	)
	(via
		(at 198.365872 -77.175106)
		(size 0.508)
		(drill 0.254)
		(layers "F.Cu" "B.Cu")
		(net "GND")
	)
	(via
		(at 296.654474 -110.497366)
		(size 0.508)
		(drill 0.254)
		(layers "F.Cu" "B.Cu")
		(net "GND")
	)
	(via
		(at 208.314798 -26.171398)
		(size 0.508)
		(drill 0.254)
		(layers "F.Cu" "B.Cu")
		(net "GND")
	)
	(via
		(at 269.049754 -303.499774)
		(size 0.4064)
		(drill 0.2032)
		(layers "F.Cu" "B.Cu")
		(net "GND")
	)
	(via
		(at 36.14801 -377.738386)
		(size 0.508)
		(drill 0.254)
		(layers "F.Cu" "B.Cu")
		(net "GND")
	)
	(via
		(at 199.500236 -312.049922)
		(size 0.4064)
		(drill 0.2032)
		(layers "F.Cu" "B.Cu")
		(net "GND")
	)
	(via
		(at 266.020042 -34.990278)
		(size 0.508)
		(drill 0.254)
		(layers "F.Cu" "B.Cu")
		(net "GND")
	)
	(via
		(at 117.882416 -347.951806)
		(size 0.4572)
		(drill 0.254)
		(layers "F.Cu" "B.Cu")
		(net "GND")
	)
	(via
		(at 40.174926 -285.924752)
		(size 0.4064)
		(drill 0.2032)
		(layers "F.Cu" "B.Cu")
		(net "GND")
	)
	(via
		(at 385.864862 -154.327352)
		(size 0.508)
		(drill 0.254)
		(layers "F.Cu" "B.Cu")
		(net "GND")
	)
	(via
		(at 181.92496 -285.924752)
		(size 0.4064)
		(drill 0.2032)
		(layers "F.Cu" "B.Cu")
		(net "GND")
	)
	(via
		(at 73.547732 -377.341892)
		(size 0.508)
		(drill 0.254)
		(layers "F.Cu" "B.Cu")
		(net "GND")
	)
	(via
		(at 264.800842 -31.390336)
		(size 0.508)
		(drill 0.254)
		(layers "F.Cu" "B.Cu")
		(net "GND")
	)
	(via
		(at 286.927798 -378.94006)
		(size 0.508)
		(drill 0.254)
		(layers "F.Cu" "B.Cu")
		(net "GND")
	)
	(via
		(at 272.332196 -13.613638)
		(size 0.508)
		(drill 0.254)
		(layers "F.Cu" "B.Cu")
		(net "GND")
	)
	(via
		(at 288.524696 -302.074834)
		(size 0.4064)
		(drill 0.2032)
		(layers "F.Cu" "B.Cu")
		(net "GND")
	)
	(via
		(at 89.15527 -357.123746)
		(size 0.4572)
		(drill 0.254)
		(layers "F.Cu" "B.Cu")
		(net "GND")
	)
	(via
		(at 268.099286 -316.799468)
		(size 0.4064)
		(drill 0.2032)
		(layers "F.Cu" "B.Cu")
		(net "GND")
	)
	(via
		(at 161.025078 -297.32478)
		(size 0.4064)
		(drill 0.2032)
		(layers "F.Cu" "B.Cu")
		(net "GND")
	)
	(via
		(at 164.645594 -156.0576)
		(size 0.508)
		(drill 0.254)
		(layers "F.Cu" "B.Cu")
		(net "GND")
	)
	(via
		(at 315.124846 -301.124874)
		(size 0.4064)
		(drill 0.2032)
		(layers "F.Cu" "B.Cu")
		(net "GND")
	)
	(via
		(at 402.249894 -316.799722)
		(size 0.4064)
		(drill 0.2032)
		(layers "F.Cu" "B.Cu")
		(net "GND")
	)
	(via
		(at 65.824862 -289.724846)
		(size 0.4064)
		(drill 0.2032)
		(layers "F.Cu" "B.Cu")
		(net "GND")
	)
	(via
		(at 399.874994 -306.824888)
		(size 0.4064)
		(drill 0.2032)
		(layers "F.Cu" "B.Cu")
		(net "GND")
	)
	(via
		(at 183.82488 -307.774848)
		(size 0.4064)
		(drill 0.2032)
		(layers "F.Cu" "B.Cu")
		(net "GND")
	)
	(via
		(at 251.050806 -330.849732)
		(size 0.508)
		(drill 0.254)
		(layers "F.Cu" "B.Cu")
		(net "GND")
	)
	(via
		(at 212.855556 -63.218314)
		(size 0.508)
		(drill 0.254)
		(layers "F.Cu" "B.Cu")
		(net "GND")
	)
	(via
		(at 181.901084 -349.219774)
		(size 0.4572)
		(drill 0.254)
		(layers "F.Cu" "B.Cu")
		(net "GND")
	)
	(via
		(at 337.5279 -403.34184)
		(size 0.508)
		(drill 0.254)
		(layers "F.Cu" "B.Cu")
		(net "GND")
	)
	(via
		(at 31.516066 -256.375916)
		(size 0.508)
		(drill 0.254)
		(layers "F.Cu" "B.Cu")
		(net "GND")
	)
	(via
		(at 372.249192 -352.245422)
		(size 0.4572)
		(drill 0.254)
		(layers "F.Cu" "B.Cu")
		(net "GND")
	)
	(via
		(at 61.074808 -285.924752)
		(size 0.4064)
		(drill 0.2032)
		(layers "F.Cu" "B.Cu")
		(net "GND")
	)
	(via
		(at 277.234396 -47.936658)
		(size 0.508)
		(drill 0.254)
		(layers "F.Cu" "B.Cu")
		(net "GND")
	)
	(via
		(at 160.074864 -288.774886)
		(size 0.4064)
		(drill 0.2032)
		(layers "F.Cu" "B.Cu")
		(net "GND")
	)
	(via
		(at 68.557902 -58.156094)
		(size 0.508)
		(drill 0.254)
		(layers "F.Cu" "B.Cu")
		(net "GND")
	)
	(via
		(at 59.820048 -34.990278)
		(size 0.508)
		(drill 0.254)
		(layers "F.Cu" "B.Cu")
		(net "GND")
	)
	(via
		(at 51.099974 -313.949842)
		(size 0.4064)
		(drill 0.2032)
		(layers "F.Cu" "B.Cu")
		(net "GND")
	)
	(via
		(at 163.618672 -354.732082)
		(size 0.4064)
		(drill 0.2032)
		(layers "F.Cu" "B.Cu")
		(net "GND")
	)
	(via
		(at 418.874956 -307.774848)
		(size 0.4064)
		(drill 0.2032)
		(layers "F.Cu" "B.Cu")
		(net "GND")
	)
	(via
		(at 325.999856 -355.366066)
		(size 0.4572)
		(drill 0.254)
		(layers "F.Cu" "B.Cu")
		(net "GND")
	)
	(via
		(at 95.529146 -117.426486)
		(size 0.508)
		(drill 0.254)
		(layers "F.Cu" "B.Cu")
		(net "GND")
	)
	(via
		(at 71.347838 -381.638556)
		(size 0.508)
		(drill 0.254)
		(layers "F.Cu" "B.Cu")
		(net "GND")
	)
	(via
		(at 193.0781 -344.831162)
		(size 0.4572)
		(drill 0.254)
		(layers "F.Cu" "B.Cu")
		(net "GND")
	)
	(via
		(at 0.77089 -350.021144)
		(size 0.508)
		(drill 0.254)
		(layers "F.Cu" "B.Cu")
		(net "GND")
	)
	(via
		(at 268.958314 -341.805514)
		(size 0.4572)
		(drill 0.254)
		(layers "F.Cu" "B.Cu")
		(net "GND")
	)
	(via
		(at 132.668264 -201.567796)
		(size 0.508)
		(drill 0.254)
		(layers "F.Cu" "B.Cu")
		(net "GND")
	)
	(via
		(at 18.671286 -31.652972)
		(size 0.508)
		(drill 0.254)
		(layers "F.Cu" "B.Cu")
		(net "GND")
	)
	(via
		(at 7.72414 -313.638438)
		(size 0.508)
		(drill 0.254)
		(layers "F.Cu" "B.Cu")
		(net "GND")
	)
	(via
		(at 86.454996 -33.19018)
		(size 0.508)
		(drill 0.254)
		(layers "F.Cu" "B.Cu")
		(net "GND")
	)
	(via
		(at 429.800004 -307.299868)
		(size 0.4064)
		(drill 0.2032)
		(layers "F.Cu" "B.Cu")
		(net "GND")
	)
	(via
		(at 93.457776 -240.304828)
		(size 0.508)
		(drill 0.254)
		(layers "F.Cu" "B.Cu")
		(net "GND")
	)
	(via
		(at 40.174926 -282.124912)
		(size 0.4064)
		(drill 0.2032)
		(layers "F.Cu" "B.Cu")
		(net "GND")
	)
	(via
		(at 308.949852 -314.899802)
		(size 0.4064)
		(drill 0.2032)
		(layers "F.Cu" "B.Cu")
		(net "GND")
	)
	(via
		(at 134.953502 -208.964022)
		(size 0.508)
		(drill 0.254)
		(layers "F.Cu" "B.Cu")
		(net "GND")
	)
	(via
		(at 125.709172 -290.68649)
		(size 0.508)
		(drill 0.254)
		(layers "F.Cu" "B.Cu")
		(net "GND")
	)
	(via
		(at 333.696564 -354.732082)
		(size 0.4064)
		(drill 0.2032)
		(layers "F.Cu" "B.Cu")
		(net "GND")
	)
	(via
		(at 330.958952 -344.831162)
		(size 0.4572)
		(drill 0.254)
		(layers "F.Cu" "B.Cu")
		(net "GND")
	)
	(via
		(at 106.544618 -386.005324)
		(size 0.508)
		(drill 0.254)
		(layers "F.Cu" "B.Cu")
		(net "GND")
	)
	(via
		(at 189.524894 -293.52494)
		(size 0.4064)
		(drill 0.2032)
		(layers "F.Cu" "B.Cu")
		(net "GND")
	)
	(via
		(at 397.02486 -285.924752)
		(size 0.4064)
		(drill 0.2032)
		(layers "F.Cu" "B.Cu")
		(net "GND")
	)
	(via
		(at 42.747946 -382.73863)
		(size 0.508)
		(drill 0.254)
		(layers "F.Cu" "B.Cu")
		(net "GND")
	)
	(via
		(at 188.099954 -276.899878)
		(size 0.4064)
		(drill 0.2032)
		(layers "F.Cu" "B.Cu")
		(net "GND")
	)
	(via
		(at 166.727632 -345.465146)
		(size 0.4064)
		(drill 0.2032)
		(layers "F.Cu" "B.Cu")
		(net "GND")
	)
	(via
		(at 418.053012 -357.75773)
		(size 0.4064)
		(drill 0.2032)
		(layers "F.Cu" "B.Cu")
		(net "GND")
	)
	(via
		(at 82.93735 -350.977454)
		(size 0.4572)
		(drill 0.254)
		(layers "F.Cu" "B.Cu")
		(net "GND")
	)
	(via
		(at 291.303202 -60.627006)
		(size 0.508)
		(drill 0.254)
		(layers "F.Cu" "B.Cu")
		(net "GND")
	)
	(via
		(at 249.37593 -145.501868)
		(size 0.508)
		(drill 0.254)
		(layers "F.Cu" "B.Cu")
		(net "GND")
	)
	(via
		(at 140.43787 -109.430566)
		(size 0.508)
		(drill 0.254)
		(layers "F.Cu" "B.Cu")
		(net "GND")
	)
	(via
		(at 65.81267 -149.355302)
		(size 0.508)
		(drill 0.254)
		(layers "F.Cu" "B.Cu")
		(net "GND")
	)
	(via
		(at 357.909368 -290.05149)
		(size 0.508)
		(drill 0.254)
		(layers "F.Cu" "B.Cu")
		(net "GND")
	)
	(via
		(at 286.149796 -310.149748)
		(size 0.4064)
		(drill 0.2032)
		(layers "F.Cu" "B.Cu")
		(net "GND")
	)
	(via
		(at 43.974766 -290.674806)
		(size 0.4064)
		(drill 0.2032)
		(layers "F.Cu" "B.Cu")
		(net "GND")
	)
	(via
		(at 302.327818 -381.241808)
		(size 0.508)
		(drill 0.254)
		(layers "F.Cu" "B.Cu")
		(net "GND")
	)
	(via
		(at 140.90396 -344.831162)
		(size 0.4572)
		(drill 0.254)
		(layers "F.Cu" "B.Cu")
		(net "GND")
	)
	(via
		(at 75.339956 -74.58583)
		(size 0.508)
		(drill 0.254)
		(layers "F.Cu" "B.Cu")
		(net "GND")
	)
	(via
		(at 387.793992 -343.073482)
		(size 0.4572)
		(drill 0.254)
		(layers "F.Cu" "B.Cu")
		(net "GND")
	)
	(via
		(at 54.899814 -273.099784)
		(size 0.4064)
		(drill 0.2032)
		(layers "F.Cu" "B.Cu")
		(net "GND")
	)
	(via
		(at 330.958952 -346.09913)
		(size 0.4572)
		(drill 0.254)
		(layers "F.Cu" "B.Cu")
		(net "GND")
	)
	(via
		(at 436.527702 -380.141988)
		(size 0.508)
		(drill 0.254)
		(layers "F.Cu" "B.Cu")
		(net "GND")
	)
	(via
		(at 333.248 -417.82492)
		(size 0.508)
		(drill 0.254)
		(layers "F.Cu" "B.Cu")
		(net "GND")
	)
	(via
		(at 271.424908 -300.174914)
		(size 0.4064)
		(drill 0.2032)
		(layers "F.Cu" "B.Cu")
		(net "GND")
	)
	(via
		(at 110.045246 -307.18887)
		(size 0.508)
		(drill 0.254)
		(layers "F.Cu" "B.Cu")
		(net "GND")
	)
	(via
		(at 135.926068 -100.978208)
		(size 0.508)
		(drill 0.254)
		(layers "F.Cu" "B.Cu")
		(net "GND")
	)
	(via
		(at 392.274806 -292.57498)
		(size 0.4064)
		(drill 0.2032)
		(layers "F.Cu" "B.Cu")
		(net "GND")
	)
	(via
		(at 233.336592 -245.038118)
		(size 0.508)
		(drill 0.254)
		(layers "F.Cu" "B.Cu")
		(net "GND")
	)
	(via
		(at 166.356284 -350.977454)
		(size 0.4572)
		(drill 0.254)
		(layers "F.Cu" "B.Cu")
		(net "GND")
	)
	(via
		(at 31.747968 -381.638556)
		(size 0.508)
		(drill 0.254)
		(layers "F.Cu" "B.Cu")
		(net "GND")
	)
	(via
		(at 41.124886 -289.724846)
		(size 0.4064)
		(drill 0.2032)
		(layers "F.Cu" "B.Cu")
		(net "GND")
	)
	(via
		(at 328.769726 -25.832054)
		(size 0.508)
		(drill 0.254)
		(layers "F.Cu" "B.Cu")
		(net "GND")
	)
	(via
		(at 152.94991 -315.849762)
		(size 0.4064)
		(drill 0.2032)
		(layers "F.Cu" "B.Cu")
		(net "GND")
	)
	(via
		(at 443.829186 -116.410486)
		(size 0.508)
		(drill 0.254)
		(layers "F.Cu" "B.Cu")
		(net "GND")
	)
	(via
		(at 180.50002 -278.799798)
		(size 0.4064)
		(drill 0.2032)
		(layers "F.Cu" "B.Cu")
		(net "GND")
	)
	(via
		(at 397.064992 -98.845116)
		(size 0.508)
		(drill 0.254)
		(layers "F.Cu" "B.Cu")
		(net "GND")
	)
	(via
		(at 82.166206 -143.676878)
		(size 0.508)
		(drill 0.254)
		(layers "F.Cu" "B.Cu")
		(net "GND")
	)
	(via
		(at 156.348938 -33.19018)
		(size 0.508)
		(drill 0.254)
		(layers "F.Cu" "B.Cu")
		(net "GND")
	)
	(via
		(at 330.587604 -351.611438)
		(size 0.4064)
		(drill 0.2032)
		(layers "F.Cu" "B.Cu")
		(net "GND")
	)
	(via
		(at 138.166348 -342.439498)
		(size 0.4064)
		(drill 0.2032)
		(layers "F.Cu" "B.Cu")
		(net "GND")
	)
	(via
		(at 8.17753 -383.864866)
		(size 0.508)
		(drill 0.254)
		(layers "F.Cu" "B.Cu")
		(net "GND")
	)
	(via
		(at 173.375066 -284.024832)
		(size 0.4064)
		(drill 0.2032)
		(layers "F.Cu" "B.Cu")
		(net "GND")
	)
	(via
		(at 297.074844 -303.974754)
		(size 0.4064)
		(drill 0.2032)
		(layers "F.Cu" "B.Cu")
		(net "GND")
	)
	(via
		(at 301.824898 -296.37482)
		(size 0.4064)
		(drill 0.2032)
		(layers "F.Cu" "B.Cu")
		(net "GND")
	)
	(via
		(at 108.634022 -128.65608)
		(size 0.508)
		(drill 0.254)
		(layers "F.Cu" "B.Cu")
		(net "GND")
	)
	(via
		(at 143.76908 -286.331914)
		(size 0.508)
		(drill 0.254)
		(layers "F.Cu" "B.Cu")
		(net "GND")
	)
	(via
		(at 187.467748 -136.645142)
		(size 0.508)
		(drill 0.254)
		(layers "F.Cu" "B.Cu")
		(net "GND")
	)
	(via
		(at 123.399296 -208.225898)
		(size 0.508)
		(drill 0.254)
		(layers "F.Cu" "B.Cu")
		(net "GND")
	)
	(via
		(at 190.934594 -71.451978)
		(size 0.508)
		(drill 0.254)
		(layers "F.Cu" "B.Cu")
		(net "GND")
	)
	(via
		(at 364.68177 -133.972046)
		(size 0.508)
		(drill 0.254)
		(layers "F.Cu" "B.Cu")
		(net "GND")
	)
	(via
		(at 178.792124 -346.09913)
		(size 0.4572)
		(drill 0.254)
		(layers "F.Cu" "B.Cu")
		(net "GND")
	)
	(via
		(at 400.229832 -354.074222)
		(size 0.4572)
		(drill 0.254)
		(layers "F.Cu" "B.Cu")
		(net "GND")
	)
	(via
		(at 65.542414 -341.805514)
		(size 0.4572)
		(drill 0.254)
		(layers "F.Cu" "B.Cu")
		(net "GND")
	)
	(via
		(at 170.806364 -120.555004)
		(size 0.508)
		(drill 0.254)
		(layers "F.Cu" "B.Cu")
		(net "GND")
	)
	(via
		(at 78.349602 -342.439498)
		(size 0.4064)
		(drill 0.2032)
		(layers "F.Cu" "B.Cu")
		(net "GND")
	)
	(via
		(at 40.174926 -293.52494)
		(size 0.4064)
		(drill 0.2032)
		(layers "F.Cu" "B.Cu")
		(net "GND")
	)
	(via
		(at 179.163472 -354.732082)
		(size 0.4064)
		(drill 0.2032)
		(layers "F.Cu" "B.Cu")
		(net "GND")
	)
	(via
		(at 133.427216 -350.977454)
		(size 0.4572)
		(drill 0.254)
		(layers "F.Cu" "B.Cu")
		(net "GND")
	)
	(via
		(at 83.400138 -279.750012)
		(size 0.4064)
		(drill 0.2032)
		(layers "F.Cu" "B.Cu")
		(net "GND")
	)
	(via
		(at 73.31329 -33.459674)
		(size 0.508)
		(drill 0.254)
		(layers "F.Cu" "B.Cu")
		(net "GND")
	)
	(via
		(at 31.747968 -407.638504)
		(size 0.508)
		(drill 0.254)
		(layers "F.Cu" "B.Cu")
		(net "GND")
	)
	(via
		(at 104.67213 -292.789102)
		(size 0.508)
		(drill 0.254)
		(layers "F.Cu" "B.Cu")
		(net "GND")
	)
	(via
		(at 251.830078 -416.508438)
		(size 0.508)
		(drill 0.254)
		(layers "F.Cu" "B.Cu")
		(net "GND")
	)
	(via
		(at 45.39996 -307.299868)
		(size 0.4064)
		(drill 0.2032)
		(layers "F.Cu" "B.Cu")
		(net "GND")
	)
	(via
		(at 290.42487 -306.824888)
		(size 0.4064)
		(drill 0.2032)
		(layers "F.Cu" "B.Cu")
		(net "GND")
	)
	(via
		(at 30.091888 -357.75773)
		(size 0.4064)
		(drill 0.2032)
		(layers "F.Cu" "B.Cu")
		(net "GND")
	)
	(via
		(at 12.659106 -138.89482)
		(size 0.508)
		(drill 0.254)
		(layers "F.Cu" "B.Cu")
		(net "GND")
	)
	(via
		(at 168.625012 -300.174914)
		(size 0.4064)
		(drill 0.2032)
		(layers "F.Cu" "B.Cu")
		(net "GND")
	)
	(via
		(at 300.48073 -29.589984)
		(size 0.508)
		(drill 0.254)
		(layers "F.Cu" "B.Cu")
		(net "GND")
	)
	(via
		(at 441.445904 -347.951806)
		(size 0.4572)
		(drill 0.254)
		(layers "F.Cu" "B.Cu")
		(net "GND")
	)
	(via
		(at 132.270754 -307.242718)
		(size 0.508)
		(drill 0.254)
		(layers "F.Cu" "B.Cu")
		(net "GND")
	)
	(via
		(at 71.760334 -341.805514)
		(size 0.4572)
		(drill 0.254)
		(layers "F.Cu" "B.Cu")
		(net "GND")
	)
	(via
		(at 428.37481 -302.074834)
		(size 0.4064)
		(drill 0.2032)
		(layers "F.Cu" "B.Cu")
		(net "GND")
	)
	(via
		(at 427.727872 -373.83847)
		(size 0.508)
		(drill 0.254)
		(layers "F.Cu" "B.Cu")
		(net "GND")
	)
	(via
		(at 295.727882 -397.140176)
		(size 0.508)
		(drill 0.254)
		(layers "F.Cu" "B.Cu")
		(net "GND")
	)
	(via
		(at 348.093538 -220.38691)
		(size 0.4572)
		(drill 0.254)
		(layers "F.Cu" "B.Cu")
		(net "GND")
	)
	(via
		(at 380.09195 -239.54105)
		(size 0.508)
		(drill 0.254)
		(layers "F.Cu" "B.Cu")
		(net "GND")
	)
	(via
		(at 45.051726 -122.355102)
		(size 0.508)
		(drill 0.254)
		(layers "F.Cu" "B.Cu")
		(net "GND")
	)
	(via
		(at 103.958136 -188.294264)
		(size 0.508)
		(drill 0.254)
		(layers "F.Cu" "B.Cu")
		(net "GND")
	)
	(via
		(at 174.747936 -411.141926)
		(size 0.508)
		(drill 0.254)
		(layers "F.Cu" "B.Cu")
		(net "GND")
	)
	(via
		(at 52.049934 -276.899878)
		(size 0.4064)
		(drill 0.2032)
		(layers "F.Cu" "B.Cu")
		(net "GND")
	)
	(via
		(at 79.270352 -28.802076)
		(size 0.508)
		(drill 0.254)
		(layers "F.Cu" "B.Cu")
		(net "GND")
	)
	(via
		(at 194.651376 -98.021648)
		(size 0.508)
		(drill 0.254)
		(layers "F.Cu" "B.Cu")
		(net "GND")
	)
	(via
		(at 212.682074 -58.873644)
		(size 0.508)
		(drill 0.254)
		(layers "F.Cu" "B.Cu")
		(net "GND")
	)
	(via
		(at 324.968108 -308.345332)
		(size 0.508)
		(drill 0.254)
		(layers "F.Cu" "B.Cu")
		(net "GND")
	)
	(via
		(at 178.599846 -314.899802)
		(size 0.4064)
		(drill 0.2032)
		(layers "F.Cu" "B.Cu")
		(net "GND")
	)
	(via
		(at 275.822664 -23.880318)
		(size 0.508)
		(drill 0.254)
		(layers "F.Cu" "B.Cu")
		(net "GND")
	)
	(via
		(at 306.019454 -38.701218)
		(size 0.508)
		(drill 0.254)
		(layers "F.Cu" "B.Cu")
		(net "GND")
	)
	(via
		(at 192.114932 -410.696918)
		(size 0.508)
		(drill 0.254)
		(layers "F.Cu" "B.Cu")
		(net "GND")
	)
	(via
		(at 404.624794 -291.624766)
		(size 0.4064)
		(drill 0.2032)
		(layers "F.Cu" "B.Cu")
		(net "GND")
	)
	(via
		(at 111.664496 -343.073482)
		(size 0.4572)
		(drill 0.254)
		(layers "F.Cu" "B.Cu")
		(net "GND")
	)
	(via
		(at 84.567522 -342.439498)
		(size 0.4064)
		(drill 0.2032)
		(layers "F.Cu" "B.Cu")
		(net "GND")
	)
	(via
		(at 67.249548 -272.14957)
		(size 0.4064)
		(drill 0.2032)
		(layers "F.Cu" "B.Cu")
		(net "GND")
	)
	(via
		(at 193.799968 -306.349908)
		(size 0.4064)
		(drill 0.2032)
		(layers "F.Cu" "B.Cu")
		(net "GND")
	)
	(via
		(at 285.199836 -276.899878)
		(size 0.4064)
		(drill 0.2032)
		(layers "F.Cu" "B.Cu")
		(net "GND")
	)
	(via
		(at 36.14801 -372.341902)
		(size 0.508)
		(drill 0.254)
		(layers "F.Cu" "B.Cu")
		(net "GND")
	)
	(via
		(at 86.04631 -343.073482)
		(size 0.4572)
		(drill 0.254)
		(layers "F.Cu" "B.Cu")
		(net "GND")
	)
	(via
		(at 414.74771 -154.755088)
		(size 0.508)
		(drill 0.254)
		(layers "F.Cu" "B.Cu")
		(net "GND")
	)
	(via
		(at 327.729088 -115.394486)
		(size 0.508)
		(drill 0.254)
		(layers "F.Cu" "B.Cu")
		(net "GND")
	)
	(via
		(at 311.933844 -351.611438)
		(size 0.4064)
		(drill 0.2032)
		(layers "F.Cu" "B.Cu")
		(net "GND")
	)
	(via
		(at 74.248264 -120.035066)
		(size 0.508)
		(drill 0.254)
		(layers "F.Cu" "B.Cu")
		(net "GND")
	)
	(via
		(at 399.874994 -284.024832)
		(size 0.4064)
		(drill 0.2032)
		(layers "F.Cu" "B.Cu")
		(net "GND")
	)
	(via
		(at 14.7955 -313.612784)
		(size 0.508)
		(drill 0.254)
		(layers "F.Cu" "B.Cu")
		(net "GND")
	)
	(via
		(at 264.102088 -27.729688)
		(size 0.508)
		(drill 0.254)
		(layers "F.Cu" "B.Cu")
		(net "GND")
	)
	(via
		(at 429.325024 -296.37482)
		(size 0.4064)
		(drill 0.2032)
		(layers "F.Cu" "B.Cu")
		(net "GND")
	)
	(via
		(at 412.224982 -300.174914)
		(size 0.4064)
		(drill 0.2032)
		(layers "F.Cu" "B.Cu")
		(net "GND")
	)
	(via
		(at 117.547644 -371.038628)
		(size 0.508)
		(drill 0.254)
		(layers "F.Cu" "B.Cu")
		(net "GND")
	)
	(via
		(at 188.993526 -189.640718)
		(size 0.508)
		(drill 0.254)
		(layers "F.Cu" "B.Cu")
		(net "GND")
	)
	(via
		(at 422.548304 -123.635008)
		(size 0.508)
		(drill 0.254)
		(layers "F.Cu" "B.Cu")
		(net "GND")
	)
	(via
		(at 335.350866 -287.51149)
		(size 0.508)
		(drill 0.254)
		(layers "F.Cu" "B.Cu")
		(net "GND")
	)
	(via
		(at 314.174886 -299.224954)
		(size 0.4064)
		(drill 0.2032)
		(layers "F.Cu" "B.Cu")
		(net "GND")
	)
	(via
		(at 284.18917 -179.080922)
		(size 0.508)
		(drill 0.254)
		(layers "F.Cu" "B.Cu")
		(net "GND")
	)
	(via
		(at 127.209296 -346.09913)
		(size 0.4572)
		(drill 0.254)
		(layers "F.Cu" "B.Cu")
		(net "GND")
	)
	(via
		(at 354.816664 -219.158566)
		(size 0.508)
		(drill 0.254)
		(layers "F.Cu" "B.Cu")
		(net "GND")
	)
	(via
		(at 419.683184 -354.098098)
		(size 0.4572)
		(drill 0.254)
		(layers "F.Cu" "B.Cu")
		(net "GND")
	)
	(via
		(at 176.054512 -345.465146)
		(size 0.4064)
		(drill 0.2032)
		(layers "F.Cu" "B.Cu")
		(net "GND")
	)
	(via
		(at 116.447316 -86.29777)
		(size 0.508)
		(drill 0.254)
		(layers "F.Cu" "B.Cu")
		(net "GND")
	)
	(via
		(at 207.425798 -34.990024)
		(size 0.508)
		(drill 0.254)
		(layers "F.Cu" "B.Cu")
		(net "GND")
	)
	(via
		(at 406.049988 -312.049922)
		(size 0.4064)
		(drill 0.2032)
		(layers "F.Cu" "B.Cu")
		(net "GND")
	)
	(via
		(at 397.97482 -292.574726)
		(size 0.4064)
		(drill 0.2032)
		(layers "F.Cu" "B.Cu")
		(net "GND")
	)
	(via
		(at 430.466246 -146.017996)
		(size 0.508)
		(drill 0.254)
		(layers "F.Cu" "B.Cu")
		(net "GND")
	)
	(via
		(at 82.93735 -358.391714)
		(size 0.4572)
		(drill 0.254)
		(layers "F.Cu" "B.Cu")
		(net "GND")
	)
	(via
		(at 304.428906 -147.314412)
		(size 0.508)
		(drill 0.254)
		(layers "F.Cu" "B.Cu")
		(net "GND")
	)
	(via
		(at 51.63312 -122.355102)
		(size 0.508)
		(drill 0.254)
		(layers "F.Cu" "B.Cu")
		(net "GND")
	)
	(via
		(at 286.624776 -305.874928)
		(size 0.4064)
		(drill 0.2032)
		(layers "F.Cu" "B.Cu")
		(net "GND")
	)
	(via
		(at 296.124884 -300.174914)
		(size 0.4064)
		(drill 0.2032)
		(layers "F.Cu" "B.Cu")
		(net "GND")
	)
	(via
		(at 306.099718 -313.949842)
		(size 0.4064)
		(drill 0.2032)
		(layers "F.Cu" "B.Cu")
		(net "GND")
	)
	(via
		(at 171.949618 -272.14957)
		(size 0.4064)
		(drill 0.2032)
		(layers "F.Cu" "B.Cu")
		(net "GND")
	)
	(via
		(at 410.356304 -346.09913)
		(size 0.4572)
		(drill 0.254)
		(layers "F.Cu" "B.Cu")
		(net "GND")
	)
	(via
		(at 134.181596 -292.781736)
		(size 0.508)
		(drill 0.254)
		(layers "F.Cu" "B.Cu")
		(net "GND")
	)
	(via
		(at 137.919714 -38.701218)
		(size 0.508)
		(drill 0.254)
		(layers "F.Cu" "B.Cu")
		(net "GND")
	)
	(via
		(at 132.69214 -176.499774)
		(size 0.508)
		(drill 0.254)
		(layers "F.Cu" "B.Cu")
		(net "GND")
	)
	(via
		(at 84.196174 -358.391714)
		(size 0.4572)
		(drill 0.254)
		(layers "F.Cu" "B.Cu")
		(net "GND")
	)
	(via
		(at 170.999912 -312.999882)
		(size 0.4064)
		(drill 0.2032)
		(layers "F.Cu" "B.Cu")
		(net "GND")
	)
	(via
		(at 289.94989 -281.649932)
		(size 0.4064)
		(drill 0.2032)
		(layers "F.Cu" "B.Cu")
		(net "GND")
	)
	(via
		(at 266.702286 -253.45644)
		(size 0.508)
		(drill 0.254)
		(layers "F.Cu" "B.Cu")
		(net "GND")
	)
	(via
		(at 9.358122 -145.083276)
		(size 0.508)
		(drill 0.254)
		(layers "F.Cu" "B.Cu")
		(net "GND")
	)
	(via
		(at 171.949872 -274.999958)
		(size 0.4064)
		(drill 0.2032)
		(layers "F.Cu" "B.Cu")
		(net "GND")
	)
	(via
		(at 384.199638 -308.250082)
		(size 0.4064)
		(drill 0.2032)
		(layers "F.Cu" "B.Cu")
		(net "GND")
	)
	(via
		(at 16.838422 -72.56526)
		(size 0.508)
		(drill 0.254)
		(layers "F.Cu" "B.Cu")
		(net "GND")
	)
	(via
		(at 339.09 -161.798)
		(size 0.508)
		(drill 0.254)
		(layers "F.Cu" "B.Cu")
		(net "GND")
	)
	(via
		(at 355.572568 -285.953454)
		(size 0.508)
		(drill 0.254)
		(layers "F.Cu" "B.Cu")
		(net "GND")
	)
	(via
		(at 220.268546 -241.140488)
		(size 0.508)
		(drill 0.254)
		(layers "F.Cu" "B.Cu")
		(net "GND")
	)
	(via
		(at 300.419262 -345.465146)
		(size 0.4064)
		(drill 0.2032)
		(layers "F.Cu" "B.Cu")
		(net "GND")
	)
	(via
		(at 283.299916 -278.799798)
		(size 0.4064)
		(drill 0.2032)
		(layers "F.Cu" "B.Cu")
		(net "GND")
	)
	(via
		(at 174.800006 -318.699896)
		(size 0.4064)
		(drill 0.2032)
		(layers "F.Cu" "B.Cu")
		(net "GND")
	)
	(via
		(at 178.124866 -294.4749)
		(size 0.4064)
		(drill 0.2032)
		(layers "F.Cu" "B.Cu")
		(net "GND")
	)
	(via
		(at 174.700946 -34.990278)
		(size 0.508)
		(drill 0.254)
		(layers "F.Cu" "B.Cu")
		(net "GND")
	)
	(via
		(at 188.119004 -354.074222)
		(size 0.4572)
		(drill 0.254)
		(layers "F.Cu" "B.Cu")
		(net "GND")
	)
	(via
		(at 183.766714 -131.245102)
		(size 0.508)
		(drill 0.254)
		(layers "F.Cu" "B.Cu")
		(net "GND")
	)
	(via
		(at 217.968068 -284.641544)
		(size 0.508)
		(drill 0.254)
		(layers "F.Cu" "B.Cu")
		(net "GND")
	)
	(via
		(at 42.747946 -403.34184)
		(size 0.508)
		(drill 0.254)
		(layers "F.Cu" "B.Cu")
		(net "GND")
	)
	(via
		(at 192.375028 -294.4749)
		(size 0.4064)
		(drill 0.2032)
		(layers "F.Cu" "B.Cu")
		(net "GND")
	)
	(via
		(at 154.375104 -294.4749)
		(size 0.4064)
		(drill 0.2032)
		(layers "F.Cu" "B.Cu")
		(net "GND")
	)
	(via
		(at 278.074882 -299.224954)
		(size 0.4064)
		(drill 0.2032)
		(layers "F.Cu" "B.Cu")
		(net "GND")
	)
	(via
		(at 325.99757 -118.183152)
		(size 0.508)
		(drill 0.254)
		(layers "F.Cu" "B.Cu")
		(net "GND")
	)
	(via
		(at 379.440186 -27.729688)
		(size 0.508)
		(drill 0.254)
		(layers "F.Cu" "B.Cu")
		(net "GND")
	)
	(via
		(at 272.196814 -268.739366)
		(size 0.508)
		(drill 0.254)
		(layers "F.Cu" "B.Cu")
		(net "GND")
	)
	(via
		(at 421.249856 -281.649932)
		(size 0.4064)
		(drill 0.2032)
		(layers "F.Cu" "B.Cu")
		(net "GND")
	)
	(via
		(at 397.49984 -314.899802)
		(size 0.4064)
		(drill 0.2032)
		(layers "F.Cu" "B.Cu")
		(net "GND")
	)
	(via
		(at 93.523054 -358.391714)
		(size 0.4572)
		(drill 0.254)
		(layers "F.Cu" "B.Cu")
		(net "GND")
	)
	(via
		(at 53.474874 -291.624766)
		(size 0.4064)
		(drill 0.2032)
		(layers "F.Cu" "B.Cu")
		(net "GND")
	)
	(via
		(at 364.947454 -398.475962)
		(size 0.508)
		(drill 0.254)
		(layers "F.Cu" "B.Cu")
		(net "GND")
	)
	(via
		(at 279.499822 -318.699896)
		(size 0.4064)
		(drill 0.2032)
		(layers "F.Cu" "B.Cu")
		(net "GND")
	)
	(via
		(at 167.732964 -109.644942)
		(size 0.508)
		(drill 0.254)
		(layers "F.Cu" "B.Cu")
		(net "GND")
	)
	(via
		(at 181.92496 -289.724846)
		(size 0.4064)
		(drill 0.2032)
		(layers "F.Cu" "B.Cu")
		(net "GND")
	)
	(via
		(at 17.966944 -131.942332)
		(size 0.508)
		(drill 0.254)
		(layers "F.Cu" "B.Cu")
		(net "GND")
	)
	(via
		(at 117.869716 -64.102234)
		(size 0.508)
		(drill 0.254)
		(layers "F.Cu" "B.Cu")
		(net "GND")
	)
	(via
		(at 119.174768 -291.32149)
		(size 0.508)
		(drill 0.254)
		(layers "F.Cu" "B.Cu")
		(net "GND")
	)
	(via
		(at 446.238376 -114.310414)
		(size 0.508)
		(drill 0.254)
		(layers "F.Cu" "B.Cu")
		(net "GND")
	)
	(via
		(at 75.429364 -47.020734)
		(size 0.508)
		(drill 0.254)
		(layers "F.Cu" "B.Cu")
		(net "GND")
	)
	(via
		(at 29.271468 -51.661822)
		(size 0.508)
		(drill 0.254)
		(layers "F.Cu" "B.Cu")
		(net "GND")
	)
	(via
		(at 110.713774 -354.313236)
		(size 0.4572)
		(drill 0.254)
		(layers "F.Cu" "B.Cu")
		(net "GND")
	)
	(via
		(at 448.260216 -20.35556)
		(size 0.508)
		(drill 0.254)
		(layers "F.Cu" "B.Cu")
		(net "GND")
	)
	(via
		(at 285.795212 -116.787168)
		(size 0.508)
		(drill 0.254)
		(layers "F.Cu" "B.Cu")
		(net "GND")
	)
	(via
		(at 211.599526 -57.439814)
		(size 0.508)
		(drill 0.254)
		(layers "F.Cu" "B.Cu")
		(net "GND")
	)
	(via
		(at 430.749964 -305.399948)
		(size 0.4064)
		(drill 0.2032)
		(layers "F.Cu" "B.Cu")
		(net "GND")
	)
	(via
		(at 4.562856 -159.841692)
		(size 0.508)
		(drill 0.254)
		(layers "F.Cu" "B.Cu")
		(net "GND")
	)
	(via
		(at 419.683184 -343.073482)
		(size 0.4572)
		(drill 0.254)
		(layers "F.Cu" "B.Cu")
		(net "GND")
	)
	(via
		(at 170.347894 -383.940304)
		(size 0.508)
		(drill 0.254)
		(layers "F.Cu" "B.Cu")
		(net "GND")
	)
	(via
		(at 442.85789 -58.791094)
		(size 0.508)
		(drill 0.254)
		(layers "F.Cu" "B.Cu")
		(net "GND")
	)
	(via
		(at 289.04311 -52.536852)
		(size 0.508)
		(drill 0.254)
		(layers "F.Cu" "B.Cu")
		(net "GND")
	)
	(via
		(at 54.98211 -370.24945)
		(size 0.4572)
		(drill 0.254)
		(layers "F.Cu" "B.Cu")
		(net "GND")
	)
	(via
		(at 54.70652 -124.154946)
		(size 0.508)
		(drill 0.254)
		(layers "F.Cu" "B.Cu")
		(net "GND")
	)
	(via
		(at 63.924942 -303.974754)
		(size 0.4064)
		(drill 0.2032)
		(layers "F.Cu" "B.Cu")
		(net "GND")
	)
	(via
		(at 267.959586 -131.495546)
		(size 0.508)
		(drill 0.254)
		(layers "F.Cu" "B.Cu")
		(net "GND")
	)
	(via
		(at 416.974782 -285.924752)
		(size 0.4064)
		(drill 0.2032)
		(layers "F.Cu" "B.Cu")
		(net "GND")
	)
	(via
		(at 63.924942 -287.824926)
		(size 0.4064)
		(drill 0.2032)
		(layers "F.Cu" "B.Cu")
		(net "GND")
	)
	(via
		(at 161.500058 -305.399948)
		(size 0.4064)
		(drill 0.2032)
		(layers "F.Cu" "B.Cu")
		(net "GND")
	)
	(via
		(at 37.324792 -274.524724)
		(size 0.4064)
		(drill 0.2032)
		(layers "F.Cu" "B.Cu")
		(net "GND")
	)
	(via
		(at 256.19329 -76.270104)
		(size 0.508)
		(drill 0.254)
		(layers "F.Cu" "B.Cu")
		(net "GND")
	)
	(via
		(at 411.67177 -200.03262)
		(size 0.508)
		(drill 0.254)
		(layers "F.Cu" "B.Cu")
		(net "GND")
	)
	(via
		(at 31.747968 -371.140228)
		(size 0.508)
		(drill 0.254)
		(layers "F.Cu" "B.Cu")
		(net "GND")
	)
	(via
		(at 126.347728 -409.940252)
		(size 0.4572)
		(drill 0.254)
		(layers "F.Cu" "B.Cu")
		(net "GND")
	)
	(via
		(at 321.260724 -348.58579)
		(size 0.4064)
		(drill 0.2032)
		(layers "F.Cu" "B.Cu")
		(net "GND")
	)
	(via
		(at 341.544656 -341.781638)
		(size 0.4572)
		(drill 0.254)
		(layers "F.Cu" "B.Cu")
		(net "GND")
	)
	(via
		(at 130.74777 -399.441924)
		(size 0.4572)
		(drill 0.254)
		(layers "F.Cu" "B.Cu")
		(net "GND")
	)
	(via
		(at 342.876378 -288.78149)
		(size 0.508)
		(drill 0.254)
		(layers "F.Cu" "B.Cu")
		(net "GND")
	)
	(via
		(at 188.366908 -143.955008)
		(size 0.508)
		(drill 0.254)
		(layers "F.Cu" "B.Cu")
		(net "GND")
	)
	(via
		(at 324.741032 -352.245422)
		(size 0.4572)
		(drill 0.254)
		(layers "F.Cu" "B.Cu")
		(net "GND")
	)
	(via
		(at 394.17498 -291.624766)
		(size 0.4064)
		(drill 0.2032)
		(layers "F.Cu" "B.Cu")
		(net "GND")
	)
	(via
		(at 26.982928 -345.465146)
		(size 0.4064)
		(drill 0.2032)
		(layers "F.Cu" "B.Cu")
		(net "GND")
	)
	(via
		(at 165.774878 -303.974754)
		(size 0.4064)
		(drill 0.2032)
		(layers "F.Cu" "B.Cu")
		(net "GND")
	)
	(via
		(at 140.647674 -98.675698)
		(size 0.508)
		(drill 0.254)
		(layers "F.Cu" "B.Cu")
		(net "GND")
	)
	(via
		(at 186.310778 -57.439814)
		(size 0.508)
		(drill 0.254)
		(layers "F.Cu" "B.Cu")
		(net "GND")
	)
	(via
		(at 113.608866 -161.005774)
		(size 0.508)
		(drill 0.254)
		(layers "F.Cu" "B.Cu")
		(net "GND")
	)
	(via
		(at 334.268318 -88.871806)
		(size 0.508)
		(drill 0.254)
		(layers "F.Cu" "B.Cu")
		(net "GND")
	)
	(via
		(at 174.747936 -383.940304)
		(size 0.508)
		(drill 0.254)
		(layers "F.Cu" "B.Cu")
		(net "GND")
	)
	(via
		(at 337.514946 -43.85691)
		(size 0.508)
		(drill 0.254)
		(layers "F.Cu" "B.Cu")
		(net "GND")
	)
	(via
		(at 400.349974 -314.899802)
		(size 0.4064)
		(drill 0.2032)
		(layers "F.Cu" "B.Cu")
		(net "GND")
	)
	(via
		(at 388.127748 -401.040092)
		(size 0.508)
		(drill 0.254)
		(layers "F.Cu" "B.Cu")
		(net "GND")
	)
	(via
		(at 425.52493 -299.224954)
		(size 0.4064)
		(drill 0.2032)
		(layers "F.Cu" "B.Cu")
		(net "GND")
	)
	(via
		(at 79.82839 -349.219774)
		(size 0.4572)
		(drill 0.254)
		(layers "F.Cu" "B.Cu")
		(net "GND")
	)
	(via
		(at 399.93316 -104.244902)
		(size 0.508)
		(drill 0.254)
		(layers "F.Cu" "B.Cu")
		(net "GND")
	)
	(via
		(at 169.587164 -107.844844)
		(size 0.508)
		(drill 0.254)
		(layers "F.Cu" "B.Cu")
		(net "GND")
	)
	(via
		(at 81.499964 -307.299868)
		(size 0.4064)
		(drill 0.2032)
		(layers "F.Cu" "B.Cu")
		(net "GND")
	)
	(via
		(at 72.216264 -110.12678)
		(size 0.508)
		(drill 0.254)
		(layers "F.Cu" "B.Cu")
		(net "GND")
	)
	(via
		(at 344.74531 -259.782564)
		(size 0.508)
		(drill 0.254)
		(layers "F.Cu" "B.Cu")
		(net "GND")
	)
	(via
		(at 176.94783 -399.838418)
		(size 0.508)
		(drill 0.254)
		(layers "F.Cu" "B.Cu")
		(net "GND")
	)
	(via
		(at 15.948406 -154.510994)
		(size 0.508)
		(drill 0.254)
		(layers "F.Cu" "B.Cu")
		(net "GND")
	)
	(via
		(at 29.357828 -25.971246)
		(size 0.508)
		(drill 0.254)
		(layers "F.Cu" "B.Cu")
		(net "GND")
	)
	(via
		(at 410.799788 -274.049744)
		(size 0.4064)
		(drill 0.2032)
		(layers "F.Cu" "B.Cu")
		(net "GND")
	)
	(via
		(at 160.549844 -316.799722)
		(size 0.4064)
		(drill 0.2032)
		(layers "F.Cu" "B.Cu")
		(net "GND")
	)
	(via
		(at 452.7804 -222.123)
		(size 0.508)
		(drill 0.254)
		(layers "F.Cu" "B.Cu")
		(net "GND")
	)
	(via
		(at 211.661248 -60.099194)
		(size 0.508)
		(drill 0.254)
		(layers "F.Cu" "B.Cu")
		(net "GND")
	)
	(via
		(at 321.632072 -346.09913)
		(size 0.4572)
		(drill 0.254)
		(layers "F.Cu" "B.Cu")
		(net "GND")
	)
	(via
		(at 115.34775 -398.34185)
		(size 0.4572)
		(drill 0.254)
		(layers "F.Cu" "B.Cu")
		(net "GND")
	)
	(via
		(at 382.791716 -119.026686)
		(size 0.508)
		(drill 0.254)
		(layers "F.Cu" "B.Cu")
		(net "GND")
	)
	(via
		(at 84.54771 -380.141734)
		(size 0.508)
		(drill 0.254)
		(layers "F.Cu" "B.Cu")
		(net "GND")
	)
	(via
		(at 252.91923 -46.893226)
		(size 0.508)
		(drill 0.254)
		(layers "F.Cu" "B.Cu")
		(net "GND")
	)
	(via
		(at 254.733298 -211.922868)
		(size 0.508)
		(drill 0.254)
		(layers "F.Cu" "B.Cu")
		(net "GND")
	)
	(via
		(at 295.727882 -381.638556)
		(size 0.508)
		(drill 0.254)
		(layers "F.Cu" "B.Cu")
		(net "GND")
	)
	(via
		(at 403.674834 -307.774848)
		(size 0.4064)
		(drill 0.2032)
		(layers "F.Cu" "B.Cu")
		(net "GND")
	)
	(via
		(at 73.960228 -20.35556)
		(size 0.508)
		(drill 0.254)
		(layers "F.Cu" "B.Cu")
		(net "GND")
	)
	(via
		(at 352.145346 -51.227482)
		(size 0.508)
		(drill 0.254)
		(layers "F.Cu" "B.Cu")
		(net "GND")
	)
	(via
		(at 42.747946 -377.341892)
		(size 0.508)
		(drill 0.254)
		(layers "F.Cu" "B.Cu")
		(net "GND")
	)
	(via
		(at 126.018544 -305.008534)
		(size 0.508)
		(drill 0.254)
		(layers "F.Cu" "B.Cu")
		(net "GND")
	)
	(via
		(at 47.77486 -289.724846)
		(size 0.4064)
		(drill 0.2032)
		(layers "F.Cu" "B.Cu")
		(net "GND")
	)
	(via
		(at 250.291854 -149.89683)
		(size 0.508)
		(drill 0.254)
		(layers "F.Cu" "B.Cu")
		(net "GND")
	)
	(via
		(at 351.423224 -153.628852)
		(size 0.508)
		(drill 0.254)
		(layers "F.Cu" "B.Cu")
		(net "GND")
	)
	(via
		(at 62.024768 -306.824888)
		(size 0.4064)
		(drill 0.2032)
		(layers "F.Cu" "B.Cu")
		(net "GND")
	)
	(via
		(at 93.894402 -357.75773)
		(size 0.4064)
		(drill 0.2032)
		(layers "F.Cu" "B.Cu")
		(net "GND")
	)
	(via
		(at 446.150238 -94.227904)
		(size 0.508)
		(drill 0.254)
		(layers "F.Cu" "B.Cu")
		(net "GND")
	)
	(via
		(at 170.524932 -300.174914)
		(size 0.4064)
		(drill 0.2032)
		(layers "F.Cu" "B.Cu")
		(net "GND")
	)
	(via
		(at 428.243238 -28.139136)
		(size 0.508)
		(drill 0.254)
		(layers "F.Cu" "B.Cu")
		(net "GND")
	)
	(via
		(at 64.28359 -344.831162)
		(size 0.4572)
		(drill 0.254)
		(layers "F.Cu" "B.Cu")
		(net "GND")
	)
	(via
		(at 168.952164 -135.364982)
		(size 0.508)
		(drill 0.254)
		(layers "F.Cu" "B.Cu")
		(net "GND")
	)
	(via
		(at 137.630662 -65.15989)
		(size 0.508)
		(drill 0.254)
		(layers "F.Cu" "B.Cu")
		(net "GND")
	)
	(via
		(at 195.224908 -300.174914)
		(size 0.4064)
		(drill 0.2032)
		(layers "F.Cu" "B.Cu")
		(net "GND")
	)
	(via
		(at 319.913 -83.82)
		(size 0.508)
		(drill 0.254)
		(layers "F.Cu" "B.Cu")
		(net "GND")
	)
	(via
		(at 385.433824 -109.916722)
		(size 0.508)
		(drill 0.254)
		(layers "F.Cu" "B.Cu")
		(net "GND")
	)
	(via
		(at 264.539984 -76.270104)
		(size 0.508)
		(drill 0.254)
		(layers "F.Cu" "B.Cu")
		(net "GND")
	)
	(via
		(at 81.024984 -289.724846)
		(size 0.4064)
		(drill 0.2032)
		(layers "F.Cu" "B.Cu")
		(net "GND")
	)
	(via
		(at 67.39255 -350.977454)
		(size 0.4572)
		(drill 0.254)
		(layers "F.Cu" "B.Cu")
		(net "GND")
	)
	(via
		(at 4.562856 -164.921692)
		(size 0.508)
		(drill 0.254)
		(layers "F.Cu" "B.Cu")
		(net "GND")
	)
	(via
		(at 432.12766 -402.241766)
		(size 0.508)
		(drill 0.254)
		(layers "F.Cu" "B.Cu")
		(net "GND")
	)
	(via
		(at 221.8055 -202.8825)
		(size 0.508)
		(drill 0.254)
		(layers "F.Cu" "B.Cu")
		(net "GND")
	)
	(via
		(at 6.755384 -222.12808)
		(size 0.508)
		(drill 0.254)
		(layers "F.Cu" "B.Cu")
		(net "GND")
	)
	(via
		(at 77.930248 -86.949026)
		(size 0.508)
		(drill 0.254)
		(layers "F.Cu" "B.Cu")
		(net "GND")
	)
	(via
		(at 322.890896 -355.366066)
		(size 0.4572)
		(drill 0.254)
		(layers "F.Cu" "B.Cu")
		(net "GND")
	)
	(via
		(at 43.499532 -57.439814)
		(size 0.508)
		(drill 0.254)
		(layers "F.Cu" "B.Cu")
		(net "GND")
	)
	(via
		(at 278.549862 -315.849762)
		(size 0.4064)
		(drill 0.2032)
		(layers "F.Cu" "B.Cu")
		(net "GND")
	)
	(via
		(at 406.049988 -275.949918)
		(size 0.4064)
		(drill 0.2032)
		(layers "F.Cu" "B.Cu")
		(net "GND")
	)
	(via
		(at 463.691986 -0.762254)
		(size 0.508)
		(drill 0.254)
		(layers "F.Cu" "B.Cu")
		(net "GND")
	)
	(via
		(at 163.13277 -129.964942)
		(size 0.508)
		(drill 0.254)
		(layers "F.Cu" "B.Cu")
		(net "GND")
	)
	(via
		(at 123.631452 -147.630388)
		(size 0.508)
		(drill 0.254)
		(layers "F.Cu" "B.Cu")
		(net "GND")
	)
	(via
		(at 400.229832 -347.951806)
		(size 0.4572)
		(drill 0.254)
		(layers "F.Cu" "B.Cu")
		(net "GND")
	)
	(via
		(at 282.349702 -279.749758)
		(size 0.4064)
		(drill 0.2032)
		(layers "F.Cu" "B.Cu")
		(net "GND")
	)
	(via
		(at 144.941036 -95.365062)
		(size 0.508)
		(drill 0.254)
		(layers "F.Cu" "B.Cu")
		(net "GND")
	)
	(via
		(at 104.905048 -393.683744)
		(size 0.508)
		(drill 0.254)
		(layers "F.Cu" "B.Cu")
		(net "GND")
	)
	(via
		(at 374.099328 -352.245422)
		(size 0.4572)
		(drill 0.254)
		(layers "F.Cu" "B.Cu")
		(net "GND")
	)
	(via
		(at 299.866812 -151.155146)
		(size 0.508)
		(drill 0.254)
		(layers "F.Cu" "B.Cu")
		(net "GND")
	)
	(via
		(at 416.024822 -291.624766)
		(size 0.4064)
		(drill 0.2032)
		(layers "F.Cu" "B.Cu")
		(net "GND")
	)
	(via
		(at 164.645594 -151.9936)
		(size 0.508)
		(drill 0.254)
		(layers "F.Cu" "B.Cu")
		(net "GND")
	)
	(via
		(at 313.224926 -300.174914)
		(size 0.4064)
		(drill 0.2032)
		(layers "F.Cu" "B.Cu")
		(net "GND")
	)
	(via
		(at 453.615044 -45.88891)
		(size 0.508)
		(drill 0.254)
		(layers "F.Cu" "B.Cu")
		(net "GND")
	)
	(via
		(at 375.910348 -184.785)
		(size 0.508)
		(drill 0.254)
		(layers "F.Cu" "B.Cu")
		(net "GND")
	)
	(via
		(at 296.793412 -152.955244)
		(size 0.508)
		(drill 0.254)
		(layers "F.Cu" "B.Cu")
		(net "GND")
	)
	(via
		(at 159.599884 -274.049744)
		(size 0.4064)
		(drill 0.2032)
		(layers "F.Cu" "B.Cu")
		(net "GND")
	)
	(via
		(at 296.599864 -313.949842)
		(size 0.4064)
		(drill 0.2032)
		(layers "F.Cu" "B.Cu")
		(net "GND")
	)
	(via
		(at 114.378486 -284.333188)
		(size 0.49022)
		(drill 0.254)
		(layers "F.Cu" "B.Cu")
		(net "GND")
	)
	(via
		(at 101.323902 -26.319734)
		(size 0.508)
		(drill 0.254)
		(layers "F.Cu" "B.Cu")
		(net "GND")
	)
	(via
		(at 398.4498 -276.899878)
		(size 0.4064)
		(drill 0.2032)
		(layers "F.Cu" "B.Cu")
		(net "GND")
	)
	(via
		(at 324.385432 -307.762656)
		(size 0.508)
		(drill 0.254)
		(layers "F.Cu" "B.Cu")
		(net "GND")
	)
	(via
		(at 185.725054 -294.4749)
		(size 0.4064)
		(drill 0.2032)
		(layers "F.Cu" "B.Cu")
		(net "GND")
	)
	(via
		(at 114.910616 -136.87806)
		(size 0.508)
		(drill 0.254)
		(layers "F.Cu" "B.Cu")
		(net "GND")
	)
	(via
		(at 45.051726 -124.154946)
		(size 0.508)
		(drill 0.254)
		(layers "F.Cu" "B.Cu")
		(net "GND")
	)
	(via
		(at 339.728048 -408.840178)
		(size 0.508)
		(drill 0.254)
		(layers "F.Cu" "B.Cu")
		(net "GND")
	)
	(via
		(at 272.173192 -141.029436)
		(size 0.508)
		(drill 0.254)
		(layers "F.Cu" "B.Cu")
		(net "GND")
	)
	(via
		(at 64.59347 -120.035066)
		(size 0.508)
		(drill 0.254)
		(layers "F.Cu" "B.Cu")
		(net "GND")
	)
	(via
		(at 154.501596 -120.833134)
		(size 0.508)
		(drill 0.254)
		(layers "F.Cu" "B.Cu")
		(net "GND")
	)
	(via
		(at 79.972916 -33.248092)
		(size 0.508)
		(drill 0.254)
		(layers "F.Cu" "B.Cu")
		(net "GND")
	)
	(via
		(at 131.021074 -277.639272)
		(size 0.508)
		(drill 0.254)
		(layers "F.Cu" "B.Cu")
		(net "GND")
	)
	(via
		(at 286.149796 -274.999958)
		(size 0.4064)
		(drill 0.2032)
		(layers "F.Cu" "B.Cu")
		(net "GND")
	)
	(via
		(at 347.708982 -286.842454)
		(size 0.508)
		(drill 0.254)
		(layers "F.Cu" "B.Cu")
		(net "GND")
	)
	(via
		(at 73.424796 -298.27474)
		(size 0.4064)
		(drill 0.2032)
		(layers "F.Cu" "B.Cu")
		(net "GND")
	)
	(via
		(at 422.792144 -346.09913)
		(size 0.4572)
		(drill 0.254)
		(layers "F.Cu" "B.Cu")
		(net "GND")
	)
	(via
		(at 170.806364 -102.444804)
		(size 0.508)
		(drill 0.254)
		(layers "F.Cu" "B.Cu")
		(net "GND")
	)
	(via
		(at 284.503114 -355.366066)
		(size 0.4572)
		(drill 0.254)
		(layers "F.Cu" "B.Cu")
		(net "GND")
	)
	(via
		(at 35.899598 -302.550068)
		(size 0.4064)
		(drill 0.2032)
		(layers "F.Cu" "B.Cu")
		(net "GND")
	)
	(via
		(at 215.7984 -232.477564)
		(size 0.508)
		(drill 0.254)
		(layers "F.Cu" "B.Cu")
		(net "GND")
	)
	(via
		(at 248.426986 -189.849252)
		(size 0.508)
		(drill 0.254)
		(layers "F.Cu" "B.Cu")
		(net "GND")
	)
	(via
		(at 277.599902 -281.649932)
		(size 0.4064)
		(drill 0.2032)
		(layers "F.Cu" "B.Cu")
		(net "GND")
	)
	(via
		(at 270.601694 -132.04317)
		(size 0.508)
		(drill 0.254)
		(layers "F.Cu" "B.Cu")
		(net "GND")
	)
	(via
		(at 42.549826 -315.849762)
		(size 0.4064)
		(drill 0.2032)
		(layers "F.Cu" "B.Cu")
		(net "GND")
	)
	(via
		(at 417.924996 -293.52494)
		(size 0.4064)
		(drill 0.2032)
		(layers "F.Cu" "B.Cu")
		(net "GND")
	)
	(via
		(at 186.200034 -278.799798)
		(size 0.4064)
		(drill 0.2032)
		(layers "F.Cu" "B.Cu")
		(net "GND")
	)
	(via
		(at 290.17976 -103.814372)
		(size 0.508)
		(drill 0.254)
		(layers "F.Cu" "B.Cu")
		(net "GND")
	)
	(via
		(at 84.54771 -403.738588)
		(size 0.508)
		(drill 0.254)
		(layers "F.Cu" "B.Cu")
		(net "GND")
	)
	(via
		(at 52.524914 -287.824926)
		(size 0.4064)
		(drill 0.2032)
		(layers "F.Cu" "B.Cu")
		(net "GND")
	)
	(via
		(at 44.006516 -354.098098)
		(size 0.4572)
		(drill 0.254)
		(layers "F.Cu" "B.Cu")
		(net "GND")
	)
	(via
		(at 330.927964 -403.738588)
		(size 0.508)
		(drill 0.254)
		(layers "F.Cu" "B.Cu")
		(net "GND")
	)
	(via
		(at 157.537912 -74.624184)
		(size 0.508)
		(drill 0.254)
		(layers "F.Cu" "B.Cu")
		(net "GND")
	)
	(via
		(at 231.067356 -214.704422)
		(size 0.4572)
		(drill 0.254)
		(layers "F.Cu" "B.Cu")
		(net "GND")
	)
	(via
		(at 317.008256 -149.083522)
		(size 0.508)
		(drill 0.254)
		(layers "F.Cu" "B.Cu")
		(net "GND")
	)
	(via
		(at 391.77341 -72.56526)
		(size 0.508)
		(drill 0.254)
		(layers "F.Cu" "B.Cu")
		(net "GND")
	)
	(via
		(at 9.1059 -395.248384)
		(size 0.508)
		(drill 0.254)
		(layers "F.Cu" "B.Cu")
		(net "GND")
	)
	(via
		(at 364.69574 -128.193546)
		(size 0.508)
		(drill 0.254)
		(layers "F.Cu" "B.Cu")
		(net "GND")
	)
	(via
		(at 323.701918 -218.938856)
		(size 0.508)
		(drill 0.254)
		(layers "F.Cu" "B.Cu")
		(net "GND")
	)
	(via
		(at 161.15157 -125.955044)
		(size 0.508)
		(drill 0.254)
		(layers "F.Cu" "B.Cu")
		(net "GND")
	)
	(via
		(at 461.22971 -287.872424)
		(size 0.508)
		(drill 0.254)
		(layers "F.Cu" "B.Cu")
		(net "GND")
	)
	(via
		(at 377.12777 -406.040336)
		(size 0.508)
		(drill 0.254)
		(layers "F.Cu" "B.Cu")
		(net "GND")
	)
	(via
		(at 276.174708 -299.224954)
		(size 0.4064)
		(drill 0.2032)
		(layers "F.Cu" "B.Cu")
		(net "GND")
	)
	(via
		(at 379.9459 -342.439498)
		(size 0.4064)
		(drill 0.2032)
		(layers "F.Cu" "B.Cu")
		(net "GND")
	)
	(via
		(at 398.450054 -319.65011)
		(size 0.4064)
		(drill 0.2032)
		(layers "F.Cu" "B.Cu")
		(net "GND")
	)
	(via
		(at 153.00579 -238.99368)
		(size 0.508)
		(drill 0.254)
		(layers "F.Cu" "B.Cu")
		(net "GND")
	)
	(via
		(at 260.181852 -353.465638)
		(size 0.508)
		(drill 0.254)
		(layers "F.Cu" "B.Cu")
		(net "GND")
	)
	(via
		(at 280.924762 -293.52494)
		(size 0.4064)
		(drill 0.2032)
		(layers "F.Cu" "B.Cu")
		(net "GND")
	)
	(via
		(at 274.749768 -299.699934)
		(size 0.4064)
		(drill 0.2032)
		(layers "F.Cu" "B.Cu")
		(net "GND")
	)
	(via
		(at 418.10432 -132.622036)
		(size 0.508)
		(drill 0.254)
		(layers "F.Cu" "B.Cu")
		(net "GND")
	)
	(via
		(at 304.199798 -274.049744)
		(size 0.4064)
		(drill 0.2032)
		(layers "F.Cu" "B.Cu")
		(net "GND")
	)
	(via
		(at 38.749986 -300.649894)
		(size 0.4064)
		(drill 0.2032)
		(layers "F.Cu" "B.Cu")
		(net "GND")
	)
	(via
		(at 186.86018 -350.977454)
		(size 0.4572)
		(drill 0.254)
		(layers "F.Cu" "B.Cu")
		(net "GND")
	)
	(via
		(at 423.62501 -294.4749)
		(size 0.4064)
		(drill 0.2032)
		(layers "F.Cu" "B.Cu")
		(net "GND")
	)
	(via
		(at 293.27475 -284.974792)
		(size 0.4064)
		(drill 0.2032)
		(layers "F.Cu" "B.Cu")
		(net "GND")
	)
	(via
		(at 310.849772 -314.899802)
		(size 0.4064)
		(drill 0.2032)
		(layers "F.Cu" "B.Cu")
		(net "GND")
	)
	(via
		(at 193.0781 -352.245422)
		(size 0.4572)
		(drill 0.254)
		(layers "F.Cu" "B.Cu")
		(net "GND")
	)
	(via
		(at 308.474872 -294.4749)
		(size 0.4064)
		(drill 0.2032)
		(layers "F.Cu" "B.Cu")
		(net "GND")
	)
	(via
		(at 22.314662 -228.40188)
		(size 0.508)
		(drill 0.254)
		(layers "F.Cu" "B.Cu")
		(net "GND")
	)
	(via
		(at 286.927798 -402.241766)
		(size 0.508)
		(drill 0.254)
		(layers "F.Cu" "B.Cu")
		(net "GND")
	)
	(via
		(at 456.949048 -278.356822)
		(size 0.508)
		(drill 0.254)
		(layers "F.Cu" "B.Cu")
		(net "GND")
	)
	(via
		(at 428.37481 -292.574726)
		(size 0.4064)
		(drill 0.2032)
		(layers "F.Cu" "B.Cu")
		(net "GND")
	)
	(via
		(at 364.551214 -150.824184)
		(size 0.508)
		(drill 0.254)
		(layers "F.Cu" "B.Cu")
		(net "GND")
	)
	(via
		(at 128.46812 -346.09913)
		(size 0.4572)
		(drill 0.254)
		(layers "F.Cu" "B.Cu")
		(net "GND")
	)
	(via
		(at 192.375028 -298.27474)
		(size 0.4064)
		(drill 0.2032)
		(layers "F.Cu" "B.Cu")
		(net "GND")
	)
	(via
		(at 388.54888 -27.79014)
		(size 0.508)
		(drill 0.254)
		(layers "F.Cu" "B.Cu")
		(net "GND")
	)
	(via
		(at 78.64983 -304.449734)
		(size 0.4064)
		(drill 0.2032)
		(layers "F.Cu" "B.Cu")
		(net "GND")
	)
	(via
		(at 163.874958 -290.674806)
		(size 0.4064)
		(drill 0.2032)
		(layers "F.Cu" "B.Cu")
		(net "GND")
	)
	(via
		(at 388.127748 -382.84023)
		(size 0.508)
		(drill 0.254)
		(layers "F.Cu" "B.Cu")
		(net "GND")
	)
	(via
		(at 304.45837 -116.9035)
		(size 0.508)
		(drill 0.254)
		(layers "F.Cu" "B.Cu")
		(net "GND")
	)
	(via
		(at 349.34525 -108.96473)
		(size 0.508)
		(drill 0.254)
		(layers "F.Cu" "B.Cu")
		(net "GND")
	)
	(via
		(at 63.449962 -319.65011)
		(size 0.4064)
		(drill 0.2032)
		(layers "F.Cu" "B.Cu")
		(net "GND")
	)
	(via
		(at 152.47493 -284.024832)
		(size 0.4064)
		(drill 0.2032)
		(layers "F.Cu" "B.Cu")
		(net "GND")
	)
	(via
		(at 142.004796 -177.034698)
		(size 0.508)
		(drill 0.254)
		(layers "F.Cu" "B.Cu")
		(net "GND")
	)
	(via
		(at 304.527712 -399.838418)
		(size 0.508)
		(drill 0.254)
		(layers "F.Cu" "B.Cu")
		(net "GND")
	)
	(via
		(at 445.031114 -6.292342)
		(size 0.508)
		(drill 0.254)
		(layers "F.Cu" "B.Cu")
		(net "GND")
	)
	(via
		(at 42.549826 -304.449734)
		(size 0.4064)
		(drill 0.2032)
		(layers "F.Cu" "B.Cu")
		(net "GND")
	)
	(via
		(at 310.849772 -285.449772)
		(size 0.4064)
		(drill 0.2032)
		(layers "F.Cu" "B.Cu")
		(net "GND")
	)
	(via
		(at 93.797628 -118.894352)
		(size 0.508)
		(drill 0.254)
		(layers "F.Cu" "B.Cu")
		(net "GND")
	)
	(via
		(at 289.47491 -305.874928)
		(size 0.4064)
		(drill 0.2032)
		(layers "F.Cu" "B.Cu")
		(net "GND")
	)
	(via
		(at 424.270932 -348.58579)
		(size 0.4064)
		(drill 0.2032)
		(layers "F.Cu" "B.Cu")
		(net "GND")
	)
	(via
		(at 164.726112 -345.465146)
		(size 0.4064)
		(drill 0.2032)
		(layers "F.Cu" "B.Cu")
		(net "GND")
	)
	(via
		(at 108.904786 -220.248734)
		(size 0.508)
		(drill 0.254)
		(layers "F.Cu" "B.Cu")
		(net "GND")
	)
	(via
		(at 310.13019 -86.949026)
		(size 0.508)
		(drill 0.254)
		(layers "F.Cu" "B.Cu")
		(net "GND")
	)
	(via
		(at 258.61137 -173.769528)
		(size 0.508)
		(drill 0.254)
		(layers "F.Cu" "B.Cu")
		(net "GND")
	)
	(via
		(at 398.4498 -274.999958)
		(size 0.4064)
		(drill 0.2032)
		(layers "F.Cu" "B.Cu")
		(net "GND")
	)
	(via
		(at 131.62534 -293.424102)
		(size 0.508)
		(drill 0.254)
		(layers "F.Cu" "B.Cu")
		(net "GND")
	)
	(via
		(at 66.774822 -289.724846)
		(size 0.4064)
		(drill 0.2032)
		(layers "F.Cu" "B.Cu")
		(net "GND")
	)
	(via
		(at 57.274968 -284.974792)
		(size 0.4064)
		(drill 0.2032)
		(layers "F.Cu" "B.Cu")
		(net "GND")
	)
	(via
		(at 420.299896 -276.899878)
		(size 0.4064)
		(drill 0.2032)
		(layers "F.Cu" "B.Cu")
		(net "GND")
	)
	(via
		(at 298.499784 -277.849838)
		(size 0.4064)
		(drill 0.2032)
		(layers "F.Cu" "B.Cu")
		(net "GND")
	)
	(via
		(at 392.274806 -293.52494)
		(size 0.4064)
		(drill 0.2032)
		(layers "F.Cu" "B.Cu")
		(net "GND")
	)
	(via
		(at 80.671924 -49.574704)
		(size 0.508)
		(drill 0.254)
		(layers "F.Cu" "B.Cu")
		(net "GND")
	)
	(via
		(at 146.727164 -256.375916)
		(size 0.508)
		(drill 0.254)
		(layers "F.Cu" "B.Cu")
		(net "GND")
	)
	(via
		(at 40.897556 -355.366066)
		(size 0.4572)
		(drill 0.254)
		(layers "F.Cu" "B.Cu")
		(net "GND")
	)
	(via
		(at 381.492506 -6.292342)
		(size 0.508)
		(drill 0.254)
		(layers "F.Cu" "B.Cu")
		(net "GND")
	)
	(via
		(at 99.0981 -243.81587)
		(size 0.508)
		(drill 0.254)
		(layers "F.Cu" "B.Cu")
		(net "GND")
	)
	(via
		(at 330.05014 -94.227904)
		(size 0.508)
		(drill 0.254)
		(layers "F.Cu" "B.Cu")
		(net "GND")
	)
	(via
		(at 395.59992 -281.649932)
		(size 0.4064)
		(drill 0.2032)
		(layers "F.Cu" "B.Cu")
		(net "GND")
	)
	(via
		(at 376.858022 -279.931114)
		(size 0.508)
		(drill 0.254)
		(layers "F.Cu" "B.Cu")
		(net "GND")
	)
	(via
		(at 103.338122 -102.021894)
		(size 0.508)
		(drill 0.254)
		(layers "F.Cu" "B.Cu")
		(net "GND")
	)
	(via
		(at 455.459846 -168.35374)
		(size 0.508)
		(drill 0.254)
		(layers "F.Cu" "B.Cu")
		(net "GND")
	)
	(via
		(at 299.866812 -131.245102)
		(size 0.508)
		(drill 0.254)
		(layers "F.Cu" "B.Cu")
		(net "GND")
	)
	(via
		(at 39.699946 -304.449734)
		(size 0.4064)
		(drill 0.2032)
		(layers "F.Cu" "B.Cu")
		(net "GND")
	)
	(via
		(at 344.127836 -404.940262)
		(size 0.508)
		(drill 0.254)
		(layers "F.Cu" "B.Cu")
		(net "GND")
	)
	(via
		(at 54.70652 -98.844862)
		(size 0.508)
		(drill 0.254)
		(layers "F.Cu" "B.Cu")
		(net "GND")
	)
	(via
		(at 131.667504 -282.910788)
		(size 0.49022)
		(drill 0.254)
		(layers "F.Cu" "B.Cu")
		(net "GND")
	)
	(via
		(at 191.440054 -74.58583)
		(size 0.508)
		(drill 0.254)
		(layers "F.Cu" "B.Cu")
		(net "GND")
	)
	(via
		(at 289.47491 -297.32478)
		(size 0.4064)
		(drill 0.2032)
		(layers "F.Cu" "B.Cu")
		(net "GND")
	)
	(via
		(at 276.174708 -300.174914)
		(size 0.4064)
		(drill 0.2032)
		(layers "F.Cu" "B.Cu")
		(net "GND")
	)
	(via
		(at 165.774878 -299.224954)
		(size 0.4064)
		(drill 0.2032)
		(layers "F.Cu" "B.Cu")
		(net "GND")
	)
	(via
		(at 271.899888 -318.699896)
		(size 0.4064)
		(drill 0.2032)
		(layers "F.Cu" "B.Cu")
		(net "GND")
	)
	(via
		(at 308.949852 -281.649932)
		(size 0.4064)
		(drill 0.2032)
		(layers "F.Cu" "B.Cu")
		(net "GND")
	)
	(via
		(at 120.197372 -286.842454)
		(size 0.508)
		(drill 0.254)
		(layers "F.Cu" "B.Cu")
		(net "GND")
	)
	(via
		(at 269.283688 -266.822174)
		(size 0.508)
		(drill 0.254)
		(layers "F.Cu" "B.Cu")
		(net "GND")
	)
	(via
		(at 293.629842 -172.329348)
		(size 0.508)
		(drill 0.254)
		(layers "F.Cu" "B.Cu")
		(net "GND")
	)
	(via
		(at 193.324988 -293.52494)
		(size 0.4064)
		(drill 0.2032)
		(layers "F.Cu" "B.Cu")
		(net "GND")
	)
	(via
		(at 313.699906 -282.599892)
		(size 0.4064)
		(drill 0.2032)
		(layers "F.Cu" "B.Cu")
		(net "GND")
	)
	(via
		(at 426.272452 -342.439498)
		(size 0.4064)
		(drill 0.2032)
		(layers "F.Cu" "B.Cu")
		(net "GND")
	)
	(via
		(at 191.425068 -302.074834)
		(size 0.4064)
		(drill 0.2032)
		(layers "F.Cu" "B.Cu")
		(net "GND")
	)
	(via
		(at 310.943244 -80.449674)
		(size 0.508)
		(drill 0.254)
		(layers "F.Cu" "B.Cu")
		(net "GND")
	)
	(via
		(at 90.95359 -234.525058)
		(size 0.508)
		(drill 0.254)
		(layers "F.Cu" "B.Cu")
		(net "GND")
	)
	(via
		(at 296.793412 -149.355302)
		(size 0.508)
		(drill 0.254)
		(layers "F.Cu" "B.Cu")
		(net "GND")
	)
	(via
		(at 295.998138 -19.757136)
		(size 0.508)
		(drill 0.254)
		(layers "F.Cu" "B.Cu")
		(net "GND")
	)
	(via
		(at 93.523054 -357.123746)
		(size 0.4572)
		(drill 0.254)
		(layers "F.Cu" "B.Cu")
		(net "GND")
	)
	(via
		(at 180.975 -307.774848)
		(size 0.4064)
		(drill 0.2032)
		(layers "F.Cu" "B.Cu")
		(net "GND")
	)
	(via
		(at 105.315004 -45.88891)
		(size 0.508)
		(drill 0.254)
		(layers "F.Cu" "B.Cu")
		(net "GND")
	)
	(via
		(at 420.299896 -277.849838)
		(size 0.4064)
		(drill 0.2032)
		(layers "F.Cu" "B.Cu")
		(net "GND")
	)
	(via
		(at 281.53995 -73.23963)
		(size 0.508)
		(drill 0.254)
		(layers "F.Cu" "B.Cu")
		(net "GND")
	)
	(via
		(at 119.174768 -288.78149)
		(size 0.508)
		(drill 0.254)
		(layers "F.Cu" "B.Cu")
		(net "GND")
	)
	(via
		(at 11.920474 -33.19018)
		(size 0.508)
		(drill 0.254)
		(layers "F.Cu" "B.Cu")
		(net "GND")
	)
	(via
		(at 54.70652 -133.564884)
		(size 0.508)
		(drill 0.254)
		(layers "F.Cu" "B.Cu")
		(net "GND")
	)
	(via
		(at 48.72482 -305.874928)
		(size 0.4064)
		(drill 0.2032)
		(layers "F.Cu" "B.Cu")
		(net "GND")
	)
	(via
		(at 441.445904 -352.245422)
		(size 0.4572)
		(drill 0.254)
		(layers "F.Cu" "B.Cu")
		(net "GND")
	)
	(via
		(at 283.833062 -152.96007)
		(size 0.508)
		(drill 0.254)
		(layers "F.Cu" "B.Cu")
		(net "GND")
	)
	(via
		(at 117.547644 -374.938544)
		(size 0.508)
		(drill 0.254)
		(layers "F.Cu" "B.Cu")
		(net "GND")
	)
	(via
		(at 221.392496 -311.026556)
		(size 0.508)
		(drill 0.254)
		(layers "F.Cu" "B.Cu")
		(net "GND")
	)
	(via
		(at 403.199854 -277.849838)
		(size 0.4064)
		(drill 0.2032)
		(layers "F.Cu" "B.Cu")
		(net "GND")
	)
	(via
		(at 385.927854 -372.240302)
		(size 0.508)
		(drill 0.254)
		(layers "F.Cu" "B.Cu")
		(net "GND")
	)
	(via
		(at 431.224944 -289.724846)
		(size 0.4064)
		(drill 0.2032)
		(layers "F.Cu" "B.Cu")
		(net "GND")
	)
	(via
		(at 273.324828 -290.674806)
		(size 0.4064)
		(drill 0.2032)
		(layers "F.Cu" "B.Cu")
		(net "GND")
	)
	(via
		(at 185.755026 -145.881852)
		(size 0.508)
		(drill 0.254)
		(layers "F.Cu" "B.Cu")
		(net "GND")
	)
	(via
		(at 42.15638 -357.123746)
		(size 0.4572)
		(drill 0.254)
		(layers "F.Cu" "B.Cu")
		(net "GND")
	)
	(via
		(at 311.523126 -51.019456)
		(size 0.508)
		(drill 0.254)
		(layers "F.Cu" "B.Cu")
		(net "GND")
	)
	(via
		(at 326.186292 -309.563516)
		(size 0.508)
		(drill 0.254)
		(layers "F.Cu" "B.Cu")
		(net "GND")
	)
	(via
		(at 188.099954 -281.649932)
		(size 0.4064)
		(drill 0.2032)
		(layers "F.Cu" "B.Cu")
		(net "GND")
	)
	(via
		(at 337.5279 -385.141978)
		(size 0.508)
		(drill 0.254)
		(layers "F.Cu" "B.Cu")
		(net "GND")
	)
	(via
		(at 112.92332 -347.951806)
		(size 0.4572)
		(drill 0.254)
		(layers "F.Cu" "B.Cu")
		(net "GND")
	)
	(via
		(at 73.61047 -357.123746)
		(size 0.4572)
		(drill 0.254)
		(layers "F.Cu" "B.Cu")
		(net "GND")
	)
	(via
		(at 291.32784 -404.940262)
		(size 0.508)
		(drill 0.254)
		(layers "F.Cu" "B.Cu")
		(net "GND")
	)
	(via
		(at 42.527728 -342.439498)
		(size 0.4064)
		(drill 0.2032)
		(layers "F.Cu" "B.Cu")
		(net "GND")
	)
	(via
		(at 0.77089 -319.541144)
		(size 0.508)
		(drill 0.254)
		(layers "F.Cu" "B.Cu")
		(net "GND")
	)
	(via
		(at 425.52493 -293.52494)
		(size 0.4064)
		(drill 0.2032)
		(layers "F.Cu" "B.Cu")
		(net "GND")
	)
	(via
		(at 429.702722 -89.790524)
		(size 0.508)
		(drill 0.254)
		(layers "F.Cu" "B.Cu")
		(net "GND")
	)
	(via
		(at 60.599828 -317.749936)
		(size 0.4064)
		(drill 0.2032)
		(layers "F.Cu" "B.Cu")
		(net "GND")
	)
	(via
		(at 303.724818 -294.4749)
		(size 0.4064)
		(drill 0.2032)
		(layers "F.Cu" "B.Cu")
		(net "GND")
	)
	(via
		(at 119.14124 -347.951806)
		(size 0.4572)
		(drill 0.254)
		(layers "F.Cu" "B.Cu")
		(net "GND")
	)
	(via
		(at 355.100128 -38.315138)
		(size 0.508)
		(drill 0.254)
		(layers "F.Cu" "B.Cu")
		(net "GND")
	)
	(via
		(at 164.349684 -272.14957)
		(size 0.4064)
		(drill 0.2032)
		(layers "F.Cu" "B.Cu")
		(net "GND")
	)
	(via
		(at 45.87494 -294.4749)
		(size 0.4064)
		(drill 0.2032)
		(layers "F.Cu" "B.Cu")
		(net "GND")
	)
	(via
		(at 141.369796 -183.130698)
		(size 0.508)
		(drill 0.254)
		(layers "F.Cu" "B.Cu")
		(net "GND")
	)
	(via
		(at 385.927854 -406.040336)
		(size 0.508)
		(drill 0.254)
		(layers "F.Cu" "B.Cu")
		(net "GND")
	)
	(via
		(at 238.404654 -311.026556)
		(size 0.508)
		(drill 0.254)
		(layers "F.Cu" "B.Cu")
		(net "GND")
	)
	(via
		(at 362.202222 -58.096404)
		(size 0.508)
		(drill 0.254)
		(layers "F.Cu" "B.Cu")
		(net "GND")
	)
	(via
		(at 232.083864 -203.40701)
		(size 0.508)
		(drill 0.254)
		(layers "F.Cu" "B.Cu")
		(net "GND")
	)
	(via
		(at 153.233628 -122.091958)
		(size 0.508)
		(drill 0.254)
		(layers "F.Cu" "B.Cu")
		(net "GND")
	)
	(via
		(at 37.798248 -21.077936)
		(size 0.508)
		(drill 0.254)
		(layers "F.Cu" "B.Cu")
		(net "GND")
	)
	(via
		(at 311.799732 -283.549852)
		(size 0.4064)
		(drill 0.2032)
		(layers "F.Cu" "B.Cu")
		(net "GND")
	)
	(via
		(at 393.351766 -100.64496)
		(size 0.508)
		(drill 0.254)
		(layers "F.Cu" "B.Cu")
		(net "GND")
	)
	(via
		(at 169.099992 -318.699896)
		(size 0.4064)
		(drill 0.2032)
		(layers "F.Cu" "B.Cu")
		(net "GND")
	)
	(via
		(at 129.217166 -119.35587)
		(size 0.508)
		(drill 0.254)
		(layers "F.Cu" "B.Cu")
		(net "GND")
	)
	(via
		(at 57.274968 -302.074834)
		(size 0.4064)
		(drill 0.2032)
		(layers "F.Cu" "B.Cu")
		(net "GND")
	)
	(via
		(at 417.924996 -291.624766)
		(size 0.4064)
		(drill 0.2032)
		(layers "F.Cu" "B.Cu")
		(net "GND")
	)
	(via
		(at 107.625134 -332.872842)
		(size 0.508)
		(drill 0.254)
		(layers "F.Cu" "B.Cu")
		(net "GND")
	)
	(via
		(at 272.067274 -358.391714)
		(size 0.4572)
		(drill 0.254)
		(layers "F.Cu" "B.Cu")
		(net "GND")
	)
	(via
		(at 423.32783 -373.83847)
		(size 0.508)
		(drill 0.254)
		(layers "F.Cu" "B.Cu")
		(net "GND")
	)
	(via
		(at 398.971008 -344.831162)
		(size 0.4572)
		(drill 0.254)
		(layers "F.Cu" "B.Cu")
		(net "GND")
	)
	(via
		(at 273.91741 -358.391714)
		(size 0.4572)
		(drill 0.254)
		(layers "F.Cu" "B.Cu")
		(net "GND")
	)
	(via
		(at 82.347816 -371.038628)
		(size 0.508)
		(drill 0.254)
		(layers "F.Cu" "B.Cu")
		(net "GND")
	)
	(via
		(at 438.708292 -357.75773)
		(size 0.4064)
		(drill 0.2032)
		(layers "F.Cu" "B.Cu")
		(net "GND")
	)
	(via
		(at 102.390194 -353.086162)
		(size 0.508)
		(drill 0.254)
		(layers "F.Cu" "B.Cu")
		(net "GND")
	)
	(via
		(at 433.96916 -346.09913)
		(size 0.4572)
		(drill 0.254)
		(layers "F.Cu" "B.Cu")
		(net "GND")
	)
	(via
		(at 434.327808 -402.140166)
		(size 0.508)
		(drill 0.254)
		(layers "F.Cu" "B.Cu")
		(net "GND")
	)
	(via
		(at 221.42323 -51.019456)
		(size 0.508)
		(drill 0.254)
		(layers "F.Cu" "B.Cu")
		(net "GND")
	)
	(via
		(at 163.874958 -301.124874)
		(size 0.4064)
		(drill 0.2032)
		(layers "F.Cu" "B.Cu")
		(net "GND")
	)
	(via
		(at 51.48326 -347.951806)
		(size 0.4572)
		(drill 0.254)
		(layers "F.Cu" "B.Cu")
		(net "GND")
	)
	(via
		(at 260.463792 -256.987548)
		(size 0.508)
		(drill 0.254)
		(layers "F.Cu" "B.Cu")
		(net "GND")
	)
	(via
		(at 297.549824 -312.049922)
		(size 0.4064)
		(drill 0.2032)
		(layers "F.Cu" "B.Cu")
		(net "GND")
	)
	(via
		(at 80.550004 -280.699718)
		(size 0.4064)
		(drill 0.2032)
		(layers "F.Cu" "B.Cu")
		(net "GND")
	)
	(via
		(at 404.953216 -49.574704)
		(size 0.508)
		(drill 0.254)
		(layers "F.Cu" "B.Cu")
		(net "GND")
	)
	(via
		(at 15.050008 -131.312666)
		(size 0.508)
		(drill 0.254)
		(layers "F.Cu" "B.Cu")
		(net "GND")
	)
	(via
		(at 411.370526 -202.19289)
		(size 0.508)
		(drill 0.254)
		(layers "F.Cu" "B.Cu")
		(net "GND")
	)
	(via
		(at 406.5778 -389.7122)
		(size 0.508)
		(drill 0.254)
		(layers "F.Cu" "B.Cu")
		(net "GND")
	)
	(via
		(at 418.42436 -349.219774)
		(size 0.4572)
		(drill 0.254)
		(layers "F.Cu" "B.Cu")
		(net "GND")
	)
	(via
		(at 348.527878 -377.73864)
		(size 0.508)
		(drill 0.254)
		(layers "F.Cu" "B.Cu")
		(net "GND")
	)
	(via
		(at 385.433824 -107.57535)
		(size 0.508)
		(drill 0.254)
		(layers "F.Cu" "B.Cu")
		(net "GND")
	)
	(via
		(at 312.305192 -343.073482)
		(size 0.4572)
		(drill 0.254)
		(layers "F.Cu" "B.Cu")
		(net "GND")
	)
	(via
		(at 406.049988 -274.999958)
		(size 0.4064)
		(drill 0.2032)
		(layers "F.Cu" "B.Cu")
		(net "GND")
	)
	(via
		(at 286.624776 -303.974754)
		(size 0.4064)
		(drill 0.2032)
		(layers "F.Cu" "B.Cu")
		(net "GND")
	)
	(via
		(at 273.77517 -83.179412)
		(size 0.508)
		(drill 0.254)
		(layers "F.Cu" "B.Cu")
		(net "GND")
	)
	(via
		(at 392.88212 -58.873644)
		(size 0.508)
		(drill 0.254)
		(layers "F.Cu" "B.Cu")
		(net "GND")
	)
	(via
		(at 29.72054 -341.805514)
		(size 0.4572)
		(drill 0.254)
		(layers "F.Cu" "B.Cu")
		(net "GND")
	)
	(via
		(at 58.699908 -313.949842)
		(size 0.4064)
		(drill 0.2032)
		(layers "F.Cu" "B.Cu")
		(net "GND")
	)
	(via
		(at 105.744772 -93.447362)
		(size 0.508)
		(drill 0.254)
		(layers "F.Cu" "B.Cu")
		(net "GND")
	)
	(via
		(at 298.78909 -357.123746)
		(size 0.4572)
		(drill 0.254)
		(layers "F.Cu" "B.Cu")
		(net "GND")
	)
	(via
		(at 159.347916 -372.341902)
		(size 0.508)
		(drill 0.254)
		(layers "F.Cu" "B.Cu")
		(net "GND")
	)
	(via
		(at 264.999978 -38.315138)
		(size 0.508)
		(drill 0.254)
		(layers "F.Cu" "B.Cu")
		(net "GND")
	)
	(via
		(at 204.923898 -291.592)
		(size 0.508)
		(drill 0.254)
		(layers "F.Cu" "B.Cu")
		(net "GND")
	)
	(via
		(at 409.374848 -285.924752)
		(size 0.4064)
		(drill 0.2032)
		(layers "F.Cu" "B.Cu")
		(net "GND")
	)
	(via
		(at 272.448782 -29.589984)
		(size 0.508)
		(drill 0.254)
		(layers "F.Cu" "B.Cu")
		(net "GND")
	)
	(via
		(at 297.310302 -348.58579)
		(size 0.4064)
		(drill 0.2032)
		(layers "F.Cu" "B.Cu")
		(net "GND")
	)
	(via
		(at 291.32784 -402.241766)
		(size 0.508)
		(drill 0.254)
		(layers "F.Cu" "B.Cu")
		(net "GND")
	)
	(via
		(at 154.805888 -161.276284)
		(size 0.508)
		(drill 0.254)
		(layers "F.Cu" "B.Cu")
		(net "GND")
	)
	(via
		(at 196.18706 -341.805514)
		(size 0.4572)
		(drill 0.254)
		(layers "F.Cu" "B.Cu")
		(net "GND")
	)
	(via
		(at 42.074846 -279.274778)
		(size 0.4064)
		(drill 0.2032)
		(layers "F.Cu" "B.Cu")
		(net "GND")
	)
	(via
		(at 436.527702 -381.63881)
		(size 0.508)
		(drill 0.254)
		(layers "F.Cu" "B.Cu")
		(net "GND")
	)
	(via
		(at 111.249714 -326.782176)
		(size 0.508)
		(drill 0.254)
		(layers "F.Cu" "B.Cu")
		(net "GND")
	)
	(via
		(at 49.853088 -357.75773)
		(size 0.4064)
		(drill 0.2032)
		(layers "F.Cu" "B.Cu")
		(net "GND")
	)
	(via
		(at 165.299898 -281.649932)
		(size 0.4064)
		(drill 0.2032)
		(layers "F.Cu" "B.Cu")
		(net "GND")
	)
	(via
		(at 380.361952 -221.955106)
		(size 0.508)
		(drill 0.254)
		(layers "F.Cu" "B.Cu")
		(net "GND")
	)
	(via
		(at 288.99993 -317.749936)
		(size 0.4064)
		(drill 0.2032)
		(layers "F.Cu" "B.Cu")
		(net "GND")
	)
	(via
		(at 68.674742 -284.974792)
		(size 0.4064)
		(drill 0.2032)
		(layers "F.Cu" "B.Cu")
		(net "GND")
	)
	(via
		(at 395.332966 -133.565138)
		(size 0.508)
		(drill 0.254)
		(layers "F.Cu" "B.Cu")
		(net "GND")
	)
	(via
		(at 400.289268 -179.080922)
		(size 0.508)
		(drill 0.254)
		(layers "F.Cu" "B.Cu")
		(net "GND")
	)
	(via
		(at 74.869294 -344.831162)
		(size 0.4572)
		(drill 0.254)
		(layers "F.Cu" "B.Cu")
		(net "GND")
	)
	(via
		(at 86.747858 -411.141926)
		(size 0.508)
		(drill 0.254)
		(layers "F.Cu" "B.Cu")
		(net "GND")
	)
	(via
		(at 114.590576 -120.093486)
		(size 0.508)
		(drill 0.254)
		(layers "F.Cu" "B.Cu")
		(net "GND")
	)
	(via
		(at 172.547788 -384.041904)
		(size 0.508)
		(drill 0.254)
		(layers "F.Cu" "B.Cu")
		(net "GND")
	)
	(via
		(at 3.131058 -385.877308)
		(size 0.508)
		(drill 0.254)
		(layers "F.Cu" "B.Cu")
		(net "GND")
	)
	(via
		(at 147.574254 -206.787242)
		(size 0.508)
		(drill 0.254)
		(layers "F.Cu" "B.Cu")
		(net "GND")
	)
	(via
		(at 379.327918 -378.94006)
		(size 0.508)
		(drill 0.254)
		(layers "F.Cu" "B.Cu")
		(net "GND")
	)
	(via
		(at 270.601694 -124.43333)
		(size 0.508)
		(drill 0.254)
		(layers "F.Cu" "B.Cu")
		(net "GND")
	)
	(via
		(at 184.29986 -313.949842)
		(size 0.4064)
		(drill 0.2032)
		(layers "F.Cu" "B.Cu")
		(net "GND")
	)
	(via
		(at 110.691422 -84.13877)
		(size 0.508)
		(drill 0.254)
		(layers "F.Cu" "B.Cu")
		(net "GND")
	)
	(via
		(at 57.749948 -311.099962)
		(size 0.4064)
		(drill 0.2032)
		(layers "F.Cu" "B.Cu")
		(net "GND")
	)
	(via
		(at 65.913762 -345.465146)
		(size 0.4064)
		(drill 0.2032)
		(layers "F.Cu" "B.Cu")
		(net "GND")
	)
	(via
		(at 100.581206 -29.859478)
		(size 0.508)
		(drill 0.254)
		(layers "F.Cu" "B.Cu")
		(net "GND")
	)
	(via
		(at 19.820382 -122.195844)
		(size 0.508)
		(drill 0.254)
		(layers "F.Cu" "B.Cu")
		(net "GND")
	)
	(via
		(at 128.667764 -258.131564)
		(size 0.508)
		(drill 0.254)
		(layers "F.Cu" "B.Cu")
		(net "GND")
	)
	(via
		(at 99.28987 -73.85177)
		(size 0.508)
		(drill 0.254)
		(layers "F.Cu" "B.Cu")
		(net "GND")
	)
	(via
		(at 428.37481 -294.4749)
		(size 0.4064)
		(drill 0.2032)
		(layers "F.Cu" "B.Cu")
		(net "GND")
	)
	(via
		(at 185.381392 -351.611438)
		(size 0.4064)
		(drill 0.2032)
		(layers "F.Cu" "B.Cu")
		(net "GND")
	)
	(via
		(at 137.413492 -31.118302)
		(size 0.508)
		(drill 0.254)
		(layers "F.Cu" "B.Cu")
		(net "GND")
	)
	(via
		(at 408.424888 -300.174914)
		(size 0.4064)
		(drill 0.2032)
		(layers "F.Cu" "B.Cu")
		(net "GND")
	)
	(via
		(at 381.527812 -402.140166)
		(size 0.508)
		(drill 0.254)
		(layers "F.Cu" "B.Cu")
		(net "GND")
	)
	(via
		(at 289.647884 -64.312292)
		(size 0.508)
		(drill 0.254)
		(layers "F.Cu" "B.Cu")
		(net "GND")
	)
	(via
		(at 138.166348 -345.465146)
		(size 0.4064)
		(drill 0.2032)
		(layers "F.Cu" "B.Cu")
		(net "GND")
	)
	(via
		(at 45.051726 -118.754906)
		(size 0.508)
		(drill 0.254)
		(layers "F.Cu" "B.Cu")
		(net "GND")
	)
	(via
		(at 117.209316 -84.297774)
		(size 0.508)
		(drill 0.254)
		(layers "F.Cu" "B.Cu")
		(net "GND")
	)
	(via
		(at 388.127748 -381.638556)
		(size 0.508)
		(drill 0.254)
		(layers "F.Cu" "B.Cu")
		(net "GND")
	)
	(via
		(at 293.527734 -374.938544)
		(size 0.508)
		(drill 0.254)
		(layers "F.Cu" "B.Cu")
		(net "GND")
	)
	(via
		(at 82.166206 -118.498112)
		(size 0.508)
		(drill 0.254)
		(layers "F.Cu" "B.Cu")
		(net "GND")
	)
	(via
		(at 9.052052 -13.613638)
		(size 0.508)
		(drill 0.254)
		(layers "F.Cu" "B.Cu")
		(net "GND")
	)
	(via
		(at 35.759644 -135.095488)
		(size 0.508)
		(drill 0.254)
		(layers "F.Cu" "B.Cu")
		(net "GND")
	)
	(via
		(at 303.457864 -73.85177)
		(size 0.508)
		(drill 0.254)
		(layers "F.Cu" "B.Cu")
		(net "GND")
	)
	(via
		(at 168.952164 -131.76504)
		(size 0.508)
		(drill 0.254)
		(layers "F.Cu" "B.Cu")
		(net "GND")
	)
	(via
		(at 231.337866 -119.73052)
		(size 0.508)
		(drill 0.254)
		(layers "F.Cu" "B.Cu")
		(net "GND")
	)
	(via
		(at 49.346612 -110.857538)
		(size 0.508)
		(drill 0.254)
		(layers "F.Cu" "B.Cu")
		(net "GND")
	)
	(via
		(at 181.901084 -355.366066)
		(size 0.4572)
		(drill 0.254)
		(layers "F.Cu" "B.Cu")
		(net "GND")
	)
	(via
		(at 315.740288 -145.483326)
		(size 0.508)
		(drill 0.254)
		(layers "F.Cu" "B.Cu")
		(net "GND")
	)
	(via
		(at 102.203504 -214.039958)
		(size 0.508)
		(drill 0.254)
		(layers "F.Cu" "B.Cu")
		(net "GND")
	)
	(via
		(at 197.125082 -292.574726)
		(size 0.4064)
		(drill 0.2032)
		(layers "F.Cu" "B.Cu")
		(net "GND")
	)
	(via
		(at 392.753088 -346.09913)
		(size 0.4572)
		(drill 0.254)
		(layers "F.Cu" "B.Cu")
		(net "GND")
	)
	(via
		(at 114.773456 -355.366066)
		(size 0.4572)
		(drill 0.254)
		(layers "F.Cu" "B.Cu")
		(net "GND")
	)
	(via
		(at 257.004566 -342.257634)
		(size 0.508)
		(drill 0.254)
		(layers "F.Cu" "B.Cu")
		(net "GND")
	)
	(via
		(at 131.532884 -285.953454)
		(size 0.508)
		(drill 0.254)
		(layers "F.Cu" "B.Cu")
		(net "GND")
	)
	(via
		(at 275.547582 -342.439498)
		(size 0.4064)
		(drill 0.2032)
		(layers "F.Cu" "B.Cu")
		(net "GND")
	)
	(via
		(at 0.766318 -31.692342)
		(size 0.508)
		(drill 0.254)
		(layers "F.Cu" "B.Cu")
		(net "GND")
	)
	(via
		(at 300.874684 -290.674806)
		(size 0.4064)
		(drill 0.2032)
		(layers "F.Cu" "B.Cu")
		(net "GND")
	)
	(via
		(at 387.999986 -312.999882)
		(size 0.4064)
		(drill 0.2032)
		(layers "F.Cu" "B.Cu")
		(net "GND")
	)
	(via
		(at 40.547798 -399.838418)
		(size 0.508)
		(drill 0.254)
		(layers "F.Cu" "B.Cu")
		(net "GND")
	)
	(via
		(at 303.249838 -315.849762)
		(size 0.4064)
		(drill 0.2032)
		(layers "F.Cu" "B.Cu")
		(net "GND")
	)
	(via
		(at 427.727872 -375.040144)
		(size 0.508)
		(drill 0.254)
		(layers "F.Cu" "B.Cu")
		(net "GND")
	)
	(via
		(at 22.251416 -47.03191)
		(size 0.508)
		(drill 0.254)
		(layers "F.Cu" "B.Cu")
		(net "GND")
	)
	(via
		(at 84.808314 -152.683464)
		(size 0.508)
		(drill 0.254)
		(layers "F.Cu" "B.Cu")
		(net "GND")
	)
	(via
		(at 193.799968 -283.549852)
		(size 0.4064)
		(drill 0.2032)
		(layers "F.Cu" "B.Cu")
		(net "GND")
	)
	(via
		(at 69.637402 -125.752352)
		(size 0.508)
		(drill 0.254)
		(layers "F.Cu" "B.Cu")
		(net "GND")
	)
	(via
		(at 111.293148 -345.465146)
		(size 0.4064)
		(drill 0.2032)
		(layers "F.Cu" "B.Cu")
		(net "GND")
	)
	(via
		(at 123.372372 -286.842454)
		(size 0.508)
		(drill 0.254)
		(layers "F.Cu" "B.Cu")
		(net "GND")
	)
	(via
		(at 389.128 -417.82492)
		(size 0.508)
		(drill 0.254)
		(layers "F.Cu" "B.Cu")
		(net "GND")
	)
	(via
		(at 77.947774 -404.838662)
		(size 0.508)
		(drill 0.254)
		(layers "F.Cu" "B.Cu")
		(net "GND")
	)
	(via
		(at 439.831226 -307.362606)
		(size 0.508)
		(drill 0.254)
		(layers "F.Cu" "B.Cu")
		(net "GND")
	)
	(via
		(at 425.04995 -283.549852)
		(size 0.4064)
		(drill 0.2032)
		(layers "F.Cu" "B.Cu")
		(net "GND")
	)
	(via
		(at 119.809768 -287.51149)
		(size 0.508)
		(drill 0.254)
		(layers "F.Cu" "B.Cu")
		(net "GND")
	)
	(via
		(at 23.97506 -74.58583)
		(size 0.508)
		(drill 0.254)
		(layers "F.Cu" "B.Cu")
		(net "GND")
	)
	(via
		(at 307.034438 -71.451978)
		(size 0.508)
		(drill 0.254)
		(layers "F.Cu" "B.Cu")
		(net "GND")
	)
	(via
		(at 93.523054 -352.245422)
		(size 0.4572)
		(drill 0.254)
		(layers "F.Cu" "B.Cu")
		(net "GND")
	)
	(via
		(at 340.285832 -350.977454)
		(size 0.4572)
		(drill 0.254)
		(layers "F.Cu" "B.Cu")
		(net "GND")
	)
	(via
		(at 78.17485 -293.52494)
		(size 0.4064)
		(drill 0.2032)
		(layers "F.Cu" "B.Cu")
		(net "GND")
	)
	(via
		(at 417.92271 -23.880318)
		(size 0.508)
		(drill 0.254)
		(layers "F.Cu" "B.Cu")
		(net "GND")
	)
	(via
		(at 377.933204 -88.236298)
		(size 0.508)
		(drill 0.254)
		(layers "F.Cu" "B.Cu")
		(net "GND")
	)
	(via
		(at 183.766714 -123.635008)
		(size 0.508)
		(drill 0.254)
		(layers "F.Cu" "B.Cu")
		(net "GND")
	)
	(via
		(at 218.486482 -48.874934)
		(size 0.508)
		(drill 0.254)
		(layers "F.Cu" "B.Cu")
		(net "GND")
	)
	(via
		(at 104.609138 -107.75696)
		(size 0.508)
		(drill 0.254)
		(layers "F.Cu" "B.Cu")
		(net "GND")
	)
	(via
		(at 29.872178 -33.857692)
		(size 0.508)
		(drill 0.254)
		(layers "F.Cu" "B.Cu")
		(net "GND")
	)
	(via
		(at 353.748086 -64.312292)
		(size 0.508)
		(drill 0.254)
		(layers "F.Cu" "B.Cu")
		(net "GND")
	)
	(via
		(at 376.706384 -253.45644)
		(size 0.508)
		(drill 0.254)
		(layers "F.Cu" "B.Cu")
		(net "GND")
	)
	(via
		(at 50.624994 -300.174914)
		(size 0.4064)
		(drill 0.2032)
		(layers "F.Cu" "B.Cu")
		(net "GND")
	)
	(via
		(at 76.71943 -355.366066)
		(size 0.4572)
		(drill 0.254)
		(layers "F.Cu" "B.Cu")
		(net "GND")
	)
	(via
		(at 204.352144 -112.137444)
		(size 0.508)
		(drill 0.254)
		(layers "F.Cu" "B.Cu")
		(net "GND")
	)
	(via
		(at 291.84981 -314.899802)
		(size 0.4064)
		(drill 0.2032)
		(layers "F.Cu" "B.Cu")
		(net "GND")
	)
	(via
		(at 295.988486 -31.642304)
		(size 0.508)
		(drill 0.254)
		(layers "F.Cu" "B.Cu")
		(net "GND")
	)
	(via
		(at 156.348938 -31.390082)
		(size 0.508)
		(drill 0.254)
		(layers "F.Cu" "B.Cu")
		(net "GND")
	)
	(via
		(at 93.939106 -309.61076)
		(size 0.508)
		(drill 0.254)
		(layers "F.Cu" "B.Cu")
		(net "GND")
	)
	(via
		(at 71.347838 -382.84023)
		(size 0.508)
		(drill 0.254)
		(layers "F.Cu" "B.Cu")
		(net "GND")
	)
	(via
		(at 374.27535 -180.353208)
		(size 0.508)
		(drill 0.254)
		(layers "F.Cu" "B.Cu")
		(net "GND")
	)
	(via
		(at 103.916734 -237.918244)
		(size 0.508)
		(drill 0.254)
		(layers "F.Cu" "B.Cu")
		(net "GND")
	)
	(via
		(at 186.682126 -58.873644)
		(size 0.508)
		(drill 0.254)
		(layers "F.Cu" "B.Cu")
		(net "GND")
	)
	(via
		(at 119.407178 -49.574704)
		(size 0.508)
		(drill 0.254)
		(layers "F.Cu" "B.Cu")
		(net "GND")
	)
	(via
		(at 161.975038 -287.824926)
		(size 0.4064)
		(drill 0.2032)
		(layers "F.Cu" "B.Cu")
		(net "GND")
	)
	(via
		(at 195.699888 -318.699896)
		(size 0.4064)
		(drill 0.2032)
		(layers "F.Cu" "B.Cu")
		(net "GND")
	)
	(via
		(at 186.77128 -28.05303)
		(size 0.508)
		(drill 0.254)
		(layers "F.Cu" "B.Cu")
		(net "GND")
	)
	(via
		(at 400.824954 -296.37482)
		(size 0.4064)
		(drill 0.2032)
		(layers "F.Cu" "B.Cu")
		(net "GND")
	)
	(via
		(at 168.148 -371.140228)
		(size 0.508)
		(drill 0.254)
		(layers "F.Cu" "B.Cu")
		(net "GND")
	)
	(via
		(at 88.783922 -357.75773)
		(size 0.4064)
		(drill 0.2032)
		(layers "F.Cu" "B.Cu")
		(net "GND")
	)
	(via
		(at 403.71014 -348.58579)
		(size 0.4064)
		(drill 0.2032)
		(layers "F.Cu" "B.Cu")
		(net "GND")
	)
	(via
		(at 378.927106 -259.576316)
		(size 0.508)
		(drill 0.254)
		(layers "F.Cu" "B.Cu")
		(net "GND")
	)
	(via
		(at 180.02504 -302.074834)
		(size 0.4064)
		(drill 0.2032)
		(layers "F.Cu" "B.Cu")
		(net "GND")
	)
	(via
		(at 426.194982 -106.384852)
		(size 0.508)
		(drill 0.254)
		(layers "F.Cu" "B.Cu")
		(net "GND")
	)
	(via
		(at 124.147834 -398.34185)
		(size 0.4572)
		(drill 0.254)
		(layers "F.Cu" "B.Cu")
		(net "GND")
	)
	(via
		(at 388.514844 -26.171398)
		(size 0.508)
		(drill 0.254)
		(layers "F.Cu" "B.Cu")
		(net "GND")
	)
	(via
		(at 312.585354 -34.183066)
		(size 0.508)
		(drill 0.254)
		(layers "F.Cu" "B.Cu")
		(net "GND")
	)
	(via
		(at 364.659672 -145.53565)
		(size 0.508)
		(drill 0.254)
		(layers "F.Cu" "B.Cu")
		(net "GND")
	)
	(via
		(at 374.099328 -344.831162)
		(size 0.4572)
		(drill 0.254)
		(layers "F.Cu" "B.Cu")
		(net "GND")
	)
	(via
		(at 437.07812 -350.977454)
		(size 0.4572)
		(drill 0.254)
		(layers "F.Cu" "B.Cu")
		(net "GND")
	)
	(via
		(at 335.350866 -289.41649)
		(size 0.508)
		(drill 0.254)
		(layers "F.Cu" "B.Cu")
		(net "GND")
	)
	(via
		(at 418.42436 -350.977454)
		(size 0.4572)
		(drill 0.254)
		(layers "F.Cu" "B.Cu")
		(net "GND")
	)
	(via
		(at 183.75122 -347.951806)
		(size 0.4572)
		(drill 0.254)
		(layers "F.Cu" "B.Cu")
		(net "GND")
	)
	(via
		(at 128.839468 -354.732082)
		(size 0.4064)
		(drill 0.2032)
		(layers "F.Cu" "B.Cu")
		(net "GND")
	)
	(via
		(at 81.087214 -352.245422)
		(size 0.4572)
		(drill 0.254)
		(layers "F.Cu" "B.Cu")
		(net "GND")
	)
	(via
		(at 168.089072 -179.080922)
		(size 0.508)
		(drill 0.254)
		(layers "F.Cu" "B.Cu")
		(net "GND")
	)
	(via
		(at 28.461716 -352.245422)
		(size 0.4572)
		(drill 0.254)
		(layers "F.Cu" "B.Cu")
		(net "GND")
	)
	(via
		(at 389.644128 -347.951806)
		(size 0.4572)
		(drill 0.254)
		(layers "F.Cu" "B.Cu")
		(net "GND")
	)
	(via
		(at 183.75122 -341.805514)
		(size 0.4572)
		(drill 0.254)
		(layers "F.Cu" "B.Cu")
		(net "GND")
	)
	(via
		(at 401.15236 -122.354848)
		(size 0.508)
		(drill 0.254)
		(layers "F.Cu" "B.Cu")
		(net "GND")
	)
	(via
		(at 409.374848 -284.974792)
		(size 0.4064)
		(drill 0.2032)
		(layers "F.Cu" "B.Cu")
		(net "GND")
	)
	(via
		(at 333.127858 -404.838662)
		(size 0.508)
		(drill 0.254)
		(layers "F.Cu" "B.Cu")
		(net "GND")
	)
	(via
		(at 319.252092 -13.613638)
		(size 0.508)
		(drill 0.254)
		(layers "F.Cu" "B.Cu")
		(net "GND")
	)
	(via
		(at 367.558066 -73.85177)
		(size 0.508)
		(drill 0.254)
		(layers "F.Cu" "B.Cu")
		(net "GND")
	)
	(via
		(at 61.074808 -293.52494)
		(size 0.4064)
		(drill 0.2032)
		(layers "F.Cu" "B.Cu")
		(net "GND")
	)
	(via
		(at 348.527878 -381.63881)
		(size 0.508)
		(drill 0.254)
		(layers "F.Cu" "B.Cu")
		(net "GND")
	)
	(via
		(at 398.925034 -285.924752)
		(size 0.4064)
		(drill 0.2032)
		(layers "F.Cu" "B.Cu")
		(net "GND")
	)
	(via
		(at 436.55234 -113.661444)
		(size 0.508)
		(drill 0.254)
		(layers "F.Cu" "B.Cu")
		(net "GND")
	)
	(via
		(at 377.208288 -343.073482)
		(size 0.4572)
		(drill 0.254)
		(layers "F.Cu" "B.Cu")
		(net "GND")
	)
	(via
		(at 61.19495 -60.633356)
		(size 0.508)
		(drill 0.254)
		(layers "F.Cu" "B.Cu")
		(net "GND")
	)
	(via
		(at 74.84999 -303.499774)
		(size 0.4064)
		(drill 0.2032)
		(layers "F.Cu" "B.Cu")
		(net "GND")
	)
	(via
		(at 168.625012 -289.724846)
		(size 0.4064)
		(drill 0.2032)
		(layers "F.Cu" "B.Cu")
		(net "GND")
	)
	(via
		(at 220.812868 -106.019346)
		(size 0.508)
		(drill 0.254)
		(layers "F.Cu" "B.Cu")
		(net "GND")
	)
	(via
		(at 161.9885 -350.977454)
		(size 0.4572)
		(drill 0.254)
		(layers "F.Cu" "B.Cu")
		(net "GND")
	)
	(via
		(at 412.20644 -354.074222)
		(size 0.4572)
		(drill 0.254)
		(layers "F.Cu" "B.Cu")
		(net "GND")
	)
	(via
		(at 76.74991 -316.799722)
		(size 0.4064)
		(drill 0.2032)
		(layers "F.Cu" "B.Cu")
		(net "GND")
	)
	(via
		(at 279.024842 -284.974792)
		(size 0.4064)
		(drill 0.2032)
		(layers "F.Cu" "B.Cu")
		(net "GND")
	)
	(via
		(at 160.682178 -58.238644)
		(size 0.508)
		(drill 0.254)
		(layers "F.Cu" "B.Cu")
		(net "GND")
	)
	(via
		(at 170.347894 -409.940252)
		(size 0.508)
		(drill 0.254)
		(layers "F.Cu" "B.Cu")
		(net "GND")
	)
	(via
		(at 51.63312 -138.964924)
		(size 0.508)
		(drill 0.254)
		(layers "F.Cu" "B.Cu")
		(net "GND")
	)
	(via
		(at 83.400138 -285.450026)
		(size 0.4064)
		(drill 0.2032)
		(layers "F.Cu" "B.Cu")
		(net "GND")
	)
	(via
		(at 246.750078 -416.508438)
		(size 0.508)
		(drill 0.254)
		(layers "F.Cu" "B.Cu")
		(net "GND")
	)
	(via
		(at 120.941592 -269.366492)
		(size 0.508)
		(drill 0.254)
		(layers "F.Cu" "B.Cu")
		(net "GND")
	)
	(via
		(at 382.791716 -109.382052)
		(size 0.508)
		(drill 0.254)
		(layers "F.Cu" "B.Cu")
		(net "GND")
	)
	(via
		(at 381.527812 -409.940252)
		(size 0.508)
		(drill 0.254)
		(layers "F.Cu" "B.Cu")
		(net "GND")
	)
	(via
		(at 38.347904 -398.24025)
		(size 0.508)
		(drill 0.254)
		(layers "F.Cu" "B.Cu")
		(net "GND")
	)
	(via
		(at 31.747968 -410.041852)
		(size 0.508)
		(drill 0.254)
		(layers "F.Cu" "B.Cu")
		(net "GND")
	)
	(via
		(at 420.299896 -313.949842)
		(size 0.4064)
		(drill 0.2032)
		(layers "F.Cu" "B.Cu")
		(net "GND")
	)
	(via
		(at 156.750004 -319.65011)
		(size 0.4064)
		(drill 0.2032)
		(layers "F.Cu" "B.Cu")
		(net "GND")
	)
	(via
		(at 288.049716 -281.649932)
		(size 0.4064)
		(drill 0.2032)
		(layers "F.Cu" "B.Cu")
		(net "GND")
	)
	(via
		(at 420.299896 -310.149748)
		(size 0.4064)
		(drill 0.2032)
		(layers "F.Cu" "B.Cu")
		(net "GND")
	)
	(via
		(at 374.927876 -369.938554)
		(size 0.508)
		(drill 0.254)
		(layers "F.Cu" "B.Cu")
		(net "GND")
	)
	(via
		(at 421.127682 -404.838662)
		(size 0.508)
		(drill 0.254)
		(layers "F.Cu" "B.Cu")
		(net "GND")
	)
	(via
		(at 426.851572 -99.037648)
		(size 0.508)
		(drill 0.254)
		(layers "F.Cu" "B.Cu")
		(net "GND")
	)
	(via
		(at 117.547644 -408.738578)
		(size 0.508)
		(drill 0.254)
		(layers "F.Cu" "B.Cu")
		(net "GND")
	)
	(via
		(at 279.499822 -277.849838)
		(size 0.4064)
		(drill 0.2032)
		(layers "F.Cu" "B.Cu")
		(net "GND")
	)
	(via
		(at 66.44767 -129.445004)
		(size 0.508)
		(drill 0.254)
		(layers "F.Cu" "B.Cu")
		(net "GND")
	)
	(via
		(at 381.100076 -38.315138)
		(size 0.508)
		(drill 0.254)
		(layers "F.Cu" "B.Cu")
		(net "GND")
	)
	(via
		(at 86.454996 -27.79014)
		(size 0.508)
		(drill 0.254)
		(layers "F.Cu" "B.Cu")
		(net "GND")
	)
	(via
		(at 73.899776 -288.299906)
		(size 0.4064)
		(drill 0.2032)
		(layers "F.Cu" "B.Cu")
		(net "GND")
	)
	(via
		(at 348.343982 -285.953454)
		(size 0.508)
		(drill 0.254)
		(layers "F.Cu" "B.Cu")
		(net "GND")
	)
	(via
		(at 236.214412 -46.749716)
		(size 0.508)
		(drill 0.254)
		(layers "F.Cu" "B.Cu")
		(net "GND")
	)
	(via
		(at 426.94987 -314.899802)
		(size 0.4064)
		(drill 0.2032)
		(layers "F.Cu" "B.Cu")
		(net "GND")
	)
	(via
		(at 377.208288 -355.366066)
		(size 0.4572)
		(drill 0.254)
		(layers "F.Cu" "B.Cu")
		(net "GND")
	)
	(via
		(at 400.349974 -275.949918)
		(size 0.4064)
		(drill 0.2032)
		(layers "F.Cu" "B.Cu")
		(net "GND")
	)
	(via
		(at 432.119024 -349.219774)
		(size 0.4572)
		(drill 0.254)
		(layers "F.Cu" "B.Cu")
		(net "GND")
	)
	(via
		(at 366.06988 -291.32149)
		(size 0.508)
		(drill 0.254)
		(layers "F.Cu" "B.Cu")
		(net "GND")
	)
	(via
		(at 87.676482 -357.75773)
		(size 0.4064)
		(drill 0.2032)
		(layers "F.Cu" "B.Cu")
		(net "GND")
	)
	(via
		(at 164.824918 -298.27474)
		(size 0.4064)
		(drill 0.2032)
		(layers "F.Cu" "B.Cu")
		(net "GND")
	)
	(via
		(at 31.516066 -259.576316)
		(size 0.508)
		(drill 0.254)
		(layers "F.Cu" "B.Cu")
		(net "GND")
	)
	(via
		(at 386.098288 -19.096736)
		(size 0.508)
		(drill 0.254)
		(layers "F.Cu" "B.Cu")
		(net "GND")
	)
	(via
		(at 16.89354 -159.573468)
		(size 0.508)
		(drill 0.254)
		(layers "F.Cu" "B.Cu")
		(net "GND")
	)
	(via
		(at 277.02637 -346.09913)
		(size 0.4572)
		(drill 0.254)
		(layers "F.Cu" "B.Cu")
		(net "GND")
	)
	(via
		(at 168.20642 -349.219774)
		(size 0.4572)
		(drill 0.254)
		(layers "F.Cu" "B.Cu")
		(net "GND")
	)
	(via
		(at 307.049678 -284.499812)
		(size 0.4064)
		(drill 0.2032)
		(layers "F.Cu" "B.Cu")
		(net "GND")
	)
	(via
		(at 284.874462 -342.439498)
		(size 0.4064)
		(drill 0.2032)
		(layers "F.Cu" "B.Cu")
		(net "GND")
	)
	(via
		(at 416.974782 -298.27474)
		(size 0.4064)
		(drill 0.2032)
		(layers "F.Cu" "B.Cu")
		(net "GND")
	)
	(via
		(at 161.9885 -358.391714)
		(size 0.4572)
		(drill 0.254)
		(layers "F.Cu" "B.Cu")
		(net "GND")
	)
	(via
		(at 199.64019 -155.024582)
		(size 0.508)
		(drill 0.254)
		(layers "F.Cu" "B.Cu")
		(net "GND")
	)
	(via
		(at 40.897556 -357.123746)
		(size 0.4572)
		(drill 0.254)
		(layers "F.Cu" "B.Cu")
		(net "GND")
	)
	(via
		(at 174.800006 -276.899878)
		(size 0.4064)
		(drill 0.2032)
		(layers "F.Cu" "B.Cu")
		(net "GND")
	)
	(via
		(at 190.348108 -121.83491)
		(size 0.508)
		(drill 0.254)
		(layers "F.Cu" "B.Cu")
		(net "GND")
	)
	(via
		(at 44.006516 -343.073482)
		(size 0.4572)
		(drill 0.254)
		(layers "F.Cu" "B.Cu")
		(net "GND")
	)
	(via
		(at 181.912514 -125.435106)
		(size 0.508)
		(drill 0.254)
		(layers "F.Cu" "B.Cu")
		(net "GND")
	)
	(via
		(at 303.724818 -303.024794)
		(size 0.4064)
		(drill 0.2032)
		(layers "F.Cu" "B.Cu")
		(net "GND")
	)
	(via
		(at 92.248736 -33.19018)
		(size 0.508)
		(drill 0.254)
		(layers "F.Cu" "B.Cu")
		(net "GND")
	)
	(via
		(at 375.358152 -346.09913)
		(size 0.4572)
		(drill 0.254)
		(layers "F.Cu" "B.Cu")
		(net "GND")
	)
	(via
		(at 415.96691 -142.15491)
		(size 0.508)
		(drill 0.254)
		(layers "F.Cu" "B.Cu")
		(net "GND")
	)
	(via
		(at 339.54847 -285.953454)
		(size 0.508)
		(drill 0.254)
		(layers "F.Cu" "B.Cu")
		(net "GND")
	)
	(via
		(at 431.840386 -131.514596)
		(size 0.508)
		(drill 0.254)
		(layers "F.Cu" "B.Cu")
		(net "GND")
	)
	(via
		(at 52.999894 -310.149748)
		(size 0.4064)
		(drill 0.2032)
		(layers "F.Cu" "B.Cu")
		(net "GND")
	)
	(via
		(at 383.426208 -358.391714)
		(size 0.4572)
		(drill 0.254)
		(layers "F.Cu" "B.Cu")
		(net "GND")
	)
	(via
		(at 382.868932 -231.07396)
		(size 0.508)
		(drill 0.254)
		(layers "F.Cu" "B.Cu")
		(net "GND")
	)
	(via
		(at 302.774858 -290.674806)
		(size 0.4064)
		(drill 0.2032)
		(layers "F.Cu" "B.Cu")
		(net "GND")
	)
	(via
		(at 181.44998 -312.049922)
		(size 0.4064)
		(drill 0.2032)
		(layers "F.Cu" "B.Cu")
		(net "GND")
	)
	(via
		(at 181.20995 -199.651366)
		(size 0.508)
		(drill 0.254)
		(layers "F.Cu" "B.Cu")
		(net "GND")
	)
	(via
		(at 379.8824 -37.087048)
		(size 0.508)
		(drill 0.254)
		(layers "F.Cu" "B.Cu")
		(net "GND")
	)
	(via
		(at 2.786634 -84.668868)
		(size 0.508)
		(drill 0.254)
		(layers "F.Cu" "B.Cu")
		(net "GND")
	)
	(via
		(at 51.63312 -107.844844)
		(size 0.508)
		(drill 0.254)
		(layers "F.Cu" "B.Cu")
		(net "GND")
	)
	(via
		(at 172.424852 -303.974754)
		(size 0.4064)
		(drill 0.2032)
		(layers "F.Cu" "B.Cu")
		(net "GND")
	)
	(via
		(at 427.623224 -55.083456)
		(size 0.508)
		(drill 0.254)
		(layers "F.Cu" "B.Cu")
		(net "GND")
	)
	(via
		(at 340.094062 -221.186756)
		(size 0.4572)
		(drill 0.254)
		(layers "F.Cu" "B.Cu")
		(net "GND")
	)
	(via
		(at 410.799788 -276.899878)
		(size 0.4064)
		(drill 0.2032)
		(layers "F.Cu" "B.Cu")
		(net "GND")
	)
	(via
		(at 2.378456 -27.305254)
		(size 0.508)
		(drill 0.254)
		(layers "F.Cu" "B.Cu")
		(net "GND")
	)
	(via
		(at 308.949852 -287.349946)
		(size 0.4064)
		(drill 0.2032)
		(layers "F.Cu" "B.Cu")
		(net "GND")
	)
	(via
		(at 77.947774 -373.441976)
		(size 0.508)
		(drill 0.254)
		(layers "F.Cu" "B.Cu")
		(net "GND")
	)
	(via
		(at 365.221266 -112.844326)
		(size 0.508)
		(drill 0.254)
		(layers "F.Cu" "B.Cu")
		(net "GND")
	)
	(via
		(at 412.89351 -151.155146)
		(size 0.508)
		(drill 0.254)
		(layers "F.Cu" "B.Cu")
		(net "GND")
	)
	(via
		(at 271.582896 -34.990024)
		(size 0.508)
		(drill 0.254)
		(layers "F.Cu" "B.Cu")
		(net "GND")
	)
	(via
		(at 180.975 -291.624766)
		(size 0.4064)
		(drill 0.2032)
		(layers "F.Cu" "B.Cu")
		(net "GND")
	)
	(via
		(at 437.844184 -294.682672)
		(size 0.508)
		(drill 0.254)
		(layers "F.Cu" "B.Cu")
		(net "GND")
	)
	(via
		(at 248.651776 -359.120186)
		(size 0.508)
		(drill 0.254)
		(layers "F.Cu" "B.Cu")
		(net "GND")
	)
	(via
		(at 45.87494 -298.27474)
		(size 0.4064)
		(drill 0.2032)
		(layers "F.Cu" "B.Cu")
		(net "GND")
	)
	(via
		(at 286.927798 -398.34185)
		(size 0.508)
		(drill 0.254)
		(layers "F.Cu" "B.Cu")
		(net "GND")
	)
	(via
		(at 286.927798 -399.838418)
		(size 0.508)
		(drill 0.254)
		(layers "F.Cu" "B.Cu")
		(net "GND")
	)
	(via
		(at 379.327918 -384.041904)
		(size 0.508)
		(drill 0.254)
		(layers "F.Cu" "B.Cu")
		(net "GND")
	)
	(via
		(at 231.48417 -240.006886)
		(size 0.508)
		(drill 0.254)
		(layers "F.Cu" "B.Cu")
		(net "GND")
	)
	(via
		(at 403.00656 -131.76504)
		(size 0.508)
		(drill 0.254)
		(layers "F.Cu" "B.Cu")
		(net "GND")
	)
	(via
		(at 388.949946 -311.099962)
		(size 0.4064)
		(drill 0.2032)
		(layers "F.Cu" "B.Cu")
		(net "GND")
	)
	(via
		(at 306.494942 -102.439978)
		(size 0.508)
		(drill 0.254)
		(layers "F.Cu" "B.Cu")
		(net "GND")
	)
	(via
		(at 81.974944 -296.37482)
		(size 0.4064)
		(drill 0.2032)
		(layers "F.Cu" "B.Cu")
		(net "GND")
	)
	(via
		(at 333.127858 -407.24201)
		(size 0.508)
		(drill 0.254)
		(layers "F.Cu" "B.Cu")
		(net "GND")
	)
	(via
		(at 272.849848 -316.799722)
		(size 0.4064)
		(drill 0.2032)
		(layers "F.Cu" "B.Cu")
		(net "GND")
	)
	(via
		(at 344.653616 -344.831162)
		(size 0.4572)
		(drill 0.254)
		(layers "F.Cu" "B.Cu")
		(net "GND")
	)
	(via
		(at 163.191952 -104.793034)
		(size 0.508)
		(drill 0.254)
		(layers "F.Cu" "B.Cu")
		(net "GND")
	)
	(via
		(at 13.220192 -395.239748)
		(size 0.508)
		(drill 0.254)
		(layers "F.Cu" "B.Cu")
		(net "GND")
	)
	(via
		(at 186.026552 -136.061958)
		(size 0.508)
		(drill 0.254)
		(layers "F.Cu" "B.Cu")
		(net "GND")
	)
	(via
		(at 303.10582 -1.364996)
		(size 0.508)
		(drill 0.254)
		(layers "F.Cu" "B.Cu")
		(net "GND")
	)
	(via
		(at 254.019558 -38.701218)
		(size 0.508)
		(drill 0.254)
		(layers "F.Cu" "B.Cu")
		(net "GND")
	)
	(via
		(at 179.898294 -19.096736)
		(size 0.508)
		(drill 0.254)
		(layers "F.Cu" "B.Cu")
		(net "GND")
	)
	(via
		(at 339.728048 -402.241766)
		(size 0.508)
		(drill 0.254)
		(layers "F.Cu" "B.Cu")
		(net "GND")
	)
	(via
		(at 402.26488 -142.367)
		(size 0.508)
		(drill 0.254)
		(layers "F.Cu" "B.Cu")
		(net "GND")
	)
	(via
		(at 170.347894 -371.038628)
		(size 0.508)
		(drill 0.254)
		(layers "F.Cu" "B.Cu")
		(net "GND")
	)
	(via
		(at 195.423282 -55.083456)
		(size 0.508)
		(drill 0.254)
		(layers "F.Cu" "B.Cu")
		(net "GND")
	)
	(via
		(at 40.174926 -286.874966)
		(size 0.4064)
		(drill 0.2032)
		(layers "F.Cu" "B.Cu")
		(net "GND")
	)
	(via
		(at 425.999656 -281.649678)
		(size 0.4064)
		(drill 0.2032)
		(layers "F.Cu" "B.Cu")
		(net "GND")
	)
	(via
		(at 289.127692 -376.140218)
		(size 0.508)
		(drill 0.254)
		(layers "F.Cu" "B.Cu")
		(net "GND")
	)
	(via
		(at 196.998082 -143.676878)
		(size 0.508)
		(drill 0.254)
		(layers "F.Cu" "B.Cu")
		(net "GND")
	)
	(via
		(at 71.760334 -358.391714)
		(size 0.4572)
		(drill 0.254)
		(layers "F.Cu" "B.Cu")
		(net "GND")
	)
	(via
		(at 80.54975 -316.799722)
		(size 0.4064)
		(drill 0.2032)
		(layers "F.Cu" "B.Cu")
		(net "GND")
	)
	(via
		(at 428.641764 -25.971246)
		(size 0.508)
		(drill 0.254)
		(layers "F.Cu" "B.Cu")
		(net "GND")
	)
	(via
		(at 406.999948 -317.749936)
		(size 0.4064)
		(drill 0.2032)
		(layers "F.Cu" "B.Cu")
		(net "GND")
	)
	(via
		(at 304.199798 -318.699896)
		(size 0.4064)
		(drill 0.2032)
		(layers "F.Cu" "B.Cu")
		(net "GND")
	)
	(via
		(at 55.845202 -50.516282)
		(size 0.508)
		(drill 0.254)
		(layers "F.Cu" "B.Cu")
		(net "GND")
	)
	(via
		(at 217.52941 -47.020734)
		(size 0.508)
		(drill 0.254)
		(layers "F.Cu" "B.Cu")
		(net "GND")
	)
	(via
		(at 442.85789 -56.809894)
		(size 0.508)
		(drill 0.254)
		(layers "F.Cu" "B.Cu")
		(net "GND")
	)
	(via
		(at 172.547788 -404.940262)
		(size 0.508)
		(drill 0.254)
		(layers "F.Cu" "B.Cu")
		(net "GND")
	)
	(via
		(at 387.759194 -234.046268)
		(size 0.508)
		(drill 0.254)
		(layers "F.Cu" "B.Cu")
		(net "GND")
	)
	(via
		(at 246.958612 -237.344966)
		(size 0.508)
		(drill 0.254)
		(layers "F.Cu" "B.Cu")
		(net "GND")
	)
	(via
		(at 41.663112 -264.532872)
		(size 0.508)
		(drill 0.254)
		(layers "F.Cu" "B.Cu")
		(net "GND")
	)
	(via
		(at 51.63312 -102.445058)
		(size 0.508)
		(drill 0.254)
		(layers "F.Cu" "B.Cu")
		(net "GND")
	)
	(via
		(at 139.273788 -345.465146)
		(size 0.4064)
		(drill 0.2032)
		(layers "F.Cu" "B.Cu")
		(net "GND")
	)
	(via
		(at 399.400014 -310.149748)
		(size 0.4064)
		(drill 0.2032)
		(layers "F.Cu" "B.Cu")
		(net "GND")
	)
	(via
		(at 461.702912 -285.569406)
		(size 0.508)
		(drill 0.254)
		(layers "F.Cu" "B.Cu")
		(net "GND")
	)
	(via
		(at 31.747968 -377.738386)
		(size 0.508)
		(drill 0.254)
		(layers "F.Cu" "B.Cu")
		(net "GND")
	)
	(via
		(at 70.099936 -274.049744)
		(size 0.4064)
		(drill 0.2032)
		(layers "F.Cu" "B.Cu")
		(net "GND")
	)
	(via
		(at 380.649734 -8.900922)
		(size 0.508)
		(drill 0.254)
		(layers "F.Cu" "B.Cu")
		(net "GND")
	)
	(via
		(at 53.474874 -289.724846)
		(size 0.4064)
		(drill 0.2032)
		(layers "F.Cu" "B.Cu")
		(net "GND")
	)
	(via
		(at 267.959586 -133.836664)
		(size 0.508)
		(drill 0.254)
		(layers "F.Cu" "B.Cu")
		(net "GND")
	)
	(via
		(at 409.849828 -275.949918)
		(size 0.4064)
		(drill 0.2032)
		(layers "F.Cu" "B.Cu")
		(net "GND")
	)
	(via
		(at 71.93915 -29.311854)
		(size 0.508)
		(drill 0.254)
		(layers "F.Cu" "B.Cu")
		(net "GND")
	)
	(via
		(at 275.224748 -279.274778)
		(size 0.4064)
		(drill 0.2032)
		(layers "F.Cu" "B.Cu")
		(net "GND")
	)
	(via
		(at 429.198278 -122.098054)
		(size 0.508)
		(drill 0.254)
		(layers "F.Cu" "B.Cu")
		(net "GND")
	)
	(via
		(at 332.23454 -118.467886)
		(size 0.508)
		(drill 0.254)
		(layers "F.Cu" "B.Cu")
		(net "GND")
	)
	(via
		(at 279.801574 -145.372836)
		(size 0.508)
		(drill 0.254)
		(layers "F.Cu" "B.Cu")
		(net "GND")
	)
	(via
		(at 325.999856 -357.123746)
		(size 0.4572)
		(drill 0.254)
		(layers "F.Cu" "B.Cu")
		(net "GND")
	)
	(via
		(at 452.725028 -14.100302)
		(size 0.508)
		(drill 0.254)
		(layers "F.Cu" "B.Cu")
		(net "GND")
	)
	(via
		(at 17.499584 -57.439814)
		(size 0.508)
		(drill 0.254)
		(layers "F.Cu" "B.Cu")
		(net "GND")
	)
	(via
		(at 448.334638 -118.467886)
		(size 0.508)
		(drill 0.254)
		(layers "F.Cu" "B.Cu")
		(net "GND")
	)
	(via
		(at 339.914484 -357.75773)
		(size 0.4064)
		(drill 0.2032)
		(layers "F.Cu" "B.Cu")
		(net "GND")
	)
	(via
		(at 413.649922 -275.949918)
		(size 0.4064)
		(drill 0.2032)
		(layers "F.Cu" "B.Cu")
		(net "GND")
	)
	(via
		(at 87.648796 -34.990024)
		(size 0.508)
		(drill 0.254)
		(layers "F.Cu" "B.Cu")
		(net "GND")
	)
	(via
		(at 384.674872 -277.374858)
		(size 0.4064)
		(drill 0.2032)
		(layers "F.Cu" "B.Cu")
		(net "GND")
	)
	(via
		(at 81.673446 -113.82121)
		(size 0.508)
		(drill 0.254)
		(layers "F.Cu" "B.Cu")
		(net "GND")
	)
	(via
		(at 378.83846 -345.465146)
		(size 0.4064)
		(drill 0.2032)
		(layers "F.Cu" "B.Cu")
		(net "GND")
	)
	(via
		(at 36.374832 -278.324818)
		(size 0.4064)
		(drill 0.2032)
		(layers "F.Cu" "B.Cu")
		(net "GND")
	)
	(via
		(at 266.691618 -105.78211)
		(size 0.508)
		(drill 0.254)
		(layers "F.Cu" "B.Cu")
		(net "GND")
	)
	(via
		(at 400.229832 -358.391714)
		(size 0.4572)
		(drill 0.254)
		(layers "F.Cu" "B.Cu")
		(net "GND")
	)
	(via
		(at 246.988838 -120.130316)
		(size 0.508)
		(drill 0.254)
		(layers "F.Cu" "B.Cu")
		(net "GND")
	)
	(via
		(at 236.620812 -150.029926)
		(size 0.508)
		(drill 0.254)
		(layers "F.Cu" "B.Cu")
		(net "GND")
	)
	(via
		(at 189.049914 -316.799722)
		(size 0.4064)
		(drill 0.2032)
		(layers "F.Cu" "B.Cu")
		(net "GND")
	)
	(via
		(at 182.39994 -281.649932)
		(size 0.4064)
		(drill 0.2032)
		(layers "F.Cu" "B.Cu")
		(net "GND")
	)
	(via
		(at 402.249894 -312.049922)
		(size 0.4064)
		(drill 0.2032)
		(layers "F.Cu" "B.Cu")
		(net "GND")
	)
	(via
		(at 114.83721 -279.023572)
		(size 0.508)
		(drill 0.254)
		(layers "F.Cu" "B.Cu")
		(net "GND")
	)
	(via
		(at 286.906462 -129.964942)
		(size 0.508)
		(drill 0.254)
		(layers "F.Cu" "B.Cu")
		(net "GND")
	)
	(via
		(at 394.011912 -350.977454)
		(size 0.4572)
		(drill 0.254)
		(layers "F.Cu" "B.Cu")
		(net "GND")
	)
	(via
		(at 128.46812 -354.098098)
		(size 0.4572)
		(drill 0.254)
		(layers "F.Cu" "B.Cu")
		(net "GND")
	)
	(via
		(at 418.927788 -402.241766)
		(size 0.508)
		(drill 0.254)
		(layers "F.Cu" "B.Cu")
		(net "GND")
	)
	(via
		(at 98.672904 -23.880318)
		(size 0.508)
		(drill 0.254)
		(layers "F.Cu" "B.Cu")
		(net "GND")
	)
	(via
		(at 402.724874 -284.024832)
		(size 0.4064)
		(drill 0.2032)
		(layers "F.Cu" "B.Cu")
		(net "GND")
	)
	(via
		(at 86.747858 -402.140166)
		(size 0.508)
		(drill 0.254)
		(layers "F.Cu" "B.Cu")
		(net "GND")
	)
	(via
		(at 384.674872 -285.924752)
		(size 0.4064)
		(drill 0.2032)
		(layers "F.Cu" "B.Cu")
		(net "GND")
	)
	(via
		(at 269.329662 -345.465146)
		(size 0.4064)
		(drill 0.2032)
		(layers "F.Cu" "B.Cu")
		(net "GND")
	)
	(via
		(at 400.229832 -349.219774)
		(size 0.4572)
		(drill 0.254)
		(layers "F.Cu" "B.Cu")
		(net "GND")
	)
	(via
		(at 190.348108 -133.044946)
		(size 0.508)
		(drill 0.254)
		(layers "F.Cu" "B.Cu")
		(net "GND")
	)
	(via
		(at 40.547798 -380.141734)
		(size 0.508)
		(drill 0.254)
		(layers "F.Cu" "B.Cu")
		(net "GND")
	)
	(via
		(at 288.049716 -314.899802)
		(size 0.4064)
		(drill 0.2032)
		(layers "F.Cu" "B.Cu")
		(net "GND")
	)
	(via
		(at 66.44767 -145.755106)
		(size 0.508)
		(drill 0.254)
		(layers "F.Cu" "B.Cu")
		(net "GND")
	)
	(via
		(at 322.548504 -287.609026)
		(size 0.508)
		(drill 0.254)
		(layers "F.Cu" "B.Cu")
		(net "GND")
	)
	(via
		(at 230.26751 -217.104468)
		(size 0.4572)
		(drill 0.254)
		(layers "F.Cu" "B.Cu")
		(net "GND")
	)
	(via
		(at 159.347916 -382.84023)
		(size 0.508)
		(drill 0.254)
		(layers "F.Cu" "B.Cu")
		(net "GND")
	)
	(via
		(at 163.874958 -289.724846)
		(size 0.4064)
		(drill 0.2032)
		(layers "F.Cu" "B.Cu")
		(net "GND")
	)
	(via
		(at 109.812328 -227.291646)
		(size 0.508)
		(drill 0.254)
		(layers "F.Cu" "B.Cu")
		(net "GND")
	)
	(via
		(at 425.04995 -312.049922)
		(size 0.4064)
		(drill 0.2032)
		(layers "F.Cu" "B.Cu")
		(net "GND")
	)
	(via
		(at 236.590078 -416.508438)
		(size 0.508)
		(drill 0.254)
		(layers "F.Cu" "B.Cu")
		(net "GND")
	)
	(via
		(at 385.433824 -125.692154)
		(size 0.508)
		(drill 0.254)
		(layers "F.Cu" "B.Cu")
		(net "GND")
	)
	(via
		(at 410.324808 -302.074834)
		(size 0.4064)
		(drill 0.2032)
		(layers "F.Cu" "B.Cu")
		(net "GND")
	)
	(via
		(at 17.323308 -133.255766)
		(size 0.508)
		(drill 0.254)
		(layers "F.Cu" "B.Cu")
		(net "GND")
	)
	(via
		(at 165.299898 -274.049744)
		(size 0.4064)
		(drill 0.2032)
		(layers "F.Cu" "B.Cu")
		(net "GND")
	)
	(via
		(at 97.938336 -115.021614)
		(size 0.508)
		(drill 0.254)
		(layers "F.Cu" "B.Cu")
		(net "GND")
	)
	(via
		(at 294.69969 -318.699896)
		(size 0.4064)
		(drill 0.2032)
		(layers "F.Cu" "B.Cu")
		(net "GND")
	)
	(via
		(at 135.168386 -48.753014)
		(size 0.508)
		(drill 0.254)
		(layers "F.Cu" "B.Cu")
		(net "GND")
	)
	(via
		(at 181.901084 -346.09913)
		(size 0.4572)
		(drill 0.254)
		(layers "F.Cu" "B.Cu")
		(net "GND")
	)
	(via
		(at 353.463098 -159.465518)
		(size 0.508)
		(drill 0.254)
		(layers "F.Cu" "B.Cu")
		(net "GND")
	)
	(via
		(at 380.542038 -307.240178)
		(size 0.508)
		(drill 0.254)
		(layers "F.Cu" "B.Cu")
		(net "GND")
	)
	(via
		(at 308.474872 -302.074834)
		(size 0.4064)
		(drill 0.2032)
		(layers "F.Cu" "B.Cu")
		(net "GND")
	)
	(via
		(at 199.64019 -132.77342)
		(size 0.508)
		(drill 0.254)
		(layers "F.Cu" "B.Cu")
		(net "GND")
	)
	(via
		(at 130.38074 -119.39143)
		(size 0.508)
		(drill 0.254)
		(layers "F.Cu" "B.Cu")
		(net "GND")
	)
	(via
		(at 38.275006 -294.4749)
		(size 0.4064)
		(drill 0.2032)
		(layers "F.Cu" "B.Cu")
		(net "GND")
	)
	(via
		(at 54.348126 -367.033302)
		(size 0.4064)
		(drill 0.2032)
		(layers "F.Cu" "B.Cu")
		(net "GND")
	)
	(via
		(at 105.409746 -77.969364)
		(size 0.508)
		(drill 0.254)
		(layers "F.Cu" "B.Cu")
		(net "GND")
	)
	(via
		(at 330.13904 -31.652972)
		(size 0.508)
		(drill 0.254)
		(layers "F.Cu" "B.Cu")
		(net "GND")
	)
	(via
		(at 335.026 -183.007)
		(size 0.508)
		(drill 0.254)
		(layers "F.Cu" "B.Cu")
		(net "GND")
	)
	(via
		(at 116.403628 -342.439498)
		(size 0.4064)
		(drill 0.2032)
		(layers "F.Cu" "B.Cu")
		(net "GND")
	)
	(via
		(at 351.374964 -288.14649)
		(size 0.508)
		(drill 0.254)
		(layers "F.Cu" "B.Cu")
		(net "GND")
	)
	(via
		(at 125.35916 -355.366066)
		(size 0.4572)
		(drill 0.254)
		(layers "F.Cu" "B.Cu")
		(net "GND")
	)
	(via
		(at 423.32783 -397.140176)
		(size 0.508)
		(drill 0.254)
		(layers "F.Cu" "B.Cu")
		(net "GND")
	)
	(via
		(at 319.848738 -33.19018)
		(size 0.508)
		(drill 0.254)
		(layers "F.Cu" "B.Cu")
		(net "GND")
	)
	(via
		(at 379.327918 -373.83847)
		(size 0.508)
		(drill 0.254)
		(layers "F.Cu" "B.Cu")
		(net "GND")
	)
	(via
		(at 81.306924 -49.574704)
		(size 0.508)
		(drill 0.254)
		(layers "F.Cu" "B.Cu")
		(net "GND")
	)
	(via
		(at 229.715822 -144.824704)
		(size 0.508)
		(drill 0.254)
		(layers "F.Cu" "B.Cu")
		(net "GND")
	)
	(via
		(at 384.674872 -289.724846)
		(size 0.4064)
		(drill 0.2032)
		(layers "F.Cu" "B.Cu")
		(net "GND")
	)
	(via
		(at 414.11271 -134.845044)
		(size 0.508)
		(drill 0.254)
		(layers "F.Cu" "B.Cu")
		(net "GND")
	)
	(via
		(at 137.364978 -207.405224)
		(size 0.508)
		(drill 0.254)
		(layers "F.Cu" "B.Cu")
		(net "GND")
	)
	(via
		(at 161.975038 -298.27474)
		(size 0.4064)
		(drill 0.2032)
		(layers "F.Cu" "B.Cu")
		(net "GND")
	)
	(via
		(at 382.12014 -29.590238)
		(size 0.508)
		(drill 0.254)
		(layers "F.Cu" "B.Cu")
		(net "GND")
	)
	(via
		(at 64.874902 -296.37482)
		(size 0.4064)
		(drill 0.2032)
		(layers "F.Cu" "B.Cu")
		(net "GND")
	)
	(via
		(at 159.599884 -303.499774)
		(size 0.4064)
		(drill 0.2032)
		(layers "F.Cu" "B.Cu")
		(net "GND")
	)
	(via
		(at 220.241622 -141.910562)
		(size 0.508)
		(drill 0.254)
		(layers "F.Cu" "B.Cu")
		(net "GND")
	)
	(via
		(at 433.597812 -351.611438)
		(size 0.4064)
		(drill 0.2032)
		(layers "F.Cu" "B.Cu")
		(net "GND")
	)
	(via
		(at 303.724818 -297.32478)
		(size 0.4064)
		(drill 0.2032)
		(layers "F.Cu" "B.Cu")
		(net "GND")
	)
	(via
		(at 34.491676 -108.123228)
		(size 0.508)
		(drill 0.254)
		(layers "F.Cu" "B.Cu")
		(net "GND")
	)
	(via
		(at 190.950088 -280.699718)
		(size 0.4064)
		(drill 0.2032)
		(layers "F.Cu" "B.Cu")
		(net "GND")
	)
	(via
		(at 118.45925 -93.05671)
		(size 0.508)
		(drill 0.254)
		(layers "F.Cu" "B.Cu")
		(net "GND")
	)
	(via
		(at 401.257262 -152.1714)
		(size 0.508)
		(drill 0.254)
		(layers "F.Cu" "B.Cu")
		(net "GND")
	)
	(via
		(at 186.682126 -58.238644)
		(size 0.508)
		(drill 0.254)
		(layers "F.Cu" "B.Cu")
		(net "GND")
	)
	(via
		(at 90.055954 -33.19018)
		(size 0.508)
		(drill 0.254)
		(layers "F.Cu" "B.Cu")
		(net "GND")
	)
	(via
		(at 248.480834 -25.990042)
		(size 0.508)
		(drill 0.254)
		(layers "F.Cu" "B.Cu")
		(net "GND")
	)
	(via
		(at 276.649688 -307.299868)
		(size 0.4064)
		(drill 0.2032)
		(layers "F.Cu" "B.Cu")
		(net "GND")
	)
	(via
		(at 172.547788 -371.140228)
		(size 0.508)
		(drill 0.254)
		(layers "F.Cu" "B.Cu")
		(net "GND")
	)
	(via
		(at 153.424636 -298.27474)
		(size 0.4064)
		(drill 0.2032)
		(layers "F.Cu" "B.Cu")
		(net "GND")
	)
	(via
		(at 283.774896 -303.974754)
		(size 0.4064)
		(drill 0.2032)
		(layers "F.Cu" "B.Cu")
		(net "GND")
	)
	(via
		(at 401.403058 -14.591792)
		(size 0.508)
		(drill 0.254)
		(layers "F.Cu" "B.Cu")
		(net "GND")
	)
	(via
		(at 161.500058 -304.449734)
		(size 0.4064)
		(drill 0.2032)
		(layers "F.Cu" "B.Cu")
		(net "GND")
	)
	(via
		(at 433.108354 -147.824698)
		(size 0.508)
		(drill 0.254)
		(layers "F.Cu" "B.Cu")
		(net "GND")
	)
	(via
		(at 304.919126 -46.893226)
		(size 0.508)
		(drill 0.254)
		(layers "F.Cu" "B.Cu")
		(net "GND")
	)
	(via
		(at 313.09818 -142.418054)
		(size 0.508)
		(drill 0.254)
		(layers "F.Cu" "B.Cu")
		(net "GND")
	)
	(via
		(at 122.615198 -136.45261)
		(size 0.508)
		(drill 0.254)
		(layers "F.Cu" "B.Cu")
		(net "GND")
	)
	(via
		(at 146.634962 -242.444778)
		(size 0.508)
		(drill 0.254)
		(layers "F.Cu" "B.Cu")
		(net "GND")
	)
	(via
		(at 348.527878 -378.940314)
		(size 0.508)
		(drill 0.254)
		(layers "F.Cu" "B.Cu")
		(net "GND")
	)
	(via
		(at 389.424926 -272.624804)
		(size 0.4064)
		(drill 0.2032)
		(layers "F.Cu" "B.Cu")
		(net "GND")
	)
	(via
		(at 411.750002 -319.65011)
		(size 0.4064)
		(drill 0.2032)
		(layers "F.Cu" "B.Cu")
		(net "GND")
	)
	(via
		(at 403.571456 -51.661822)
		(size 0.508)
		(drill 0.254)
		(layers "F.Cu" "B.Cu")
		(net "GND")
	)
	(via
		(at 4.675886 -394.767308)
		(size 0.508)
		(drill 0.254)
		(layers "F.Cu" "B.Cu")
		(net "GND")
	)
	(via
		(at 129.946908 -351.611438)
		(size 0.4064)
		(drill 0.2032)
		(layers "F.Cu" "B.Cu")
		(net "GND")
	)
	(via
		(at 33.947862 -409.940252)
		(size 0.508)
		(drill 0.254)
		(layers "F.Cu" "B.Cu")
		(net "GND")
	)
	(via
		(at 406.049988 -276.899878)
		(size 0.4064)
		(drill 0.2032)
		(layers "F.Cu" "B.Cu")
		(net "GND")
	)
	(via
		(at 427.727872 -380.141734)
		(size 0.508)
		(drill 0.254)
		(layers "F.Cu" "B.Cu")
		(net "GND")
	)
	(via
		(at 73.899776 -302.549814)
		(size 0.4064)
		(drill 0.2032)
		(layers "F.Cu" "B.Cu")
		(net "GND")
	)
	(via
		(at 159.124904 -276.424898)
		(size 0.4064)
		(drill 0.2032)
		(layers "F.Cu" "B.Cu")
		(net "GND")
	)
	(via
		(at 29.54782 -380.040134)
		(size 0.508)
		(drill 0.254)
		(layers "F.Cu" "B.Cu")
		(net "GND")
	)
	(via
		(at 307.523896 -26.319734)
		(size 0.508)
		(drill 0.254)
		(layers "F.Cu" "B.Cu")
		(net "GND")
	)
	(via
		(at 184.380886 -27.79014)
		(size 0.508)
		(drill 0.254)
		(layers "F.Cu" "B.Cu")
		(net "GND")
	)
	(via
		(at 67.39255 -341.805514)
		(size 0.4572)
		(drill 0.254)
		(layers "F.Cu" "B.Cu")
		(net "GND")
	)
	(via
		(at 69.967602 -134.400544)
		(size 0.508)
		(drill 0.254)
		(layers "F.Cu" "B.Cu")
		(net "GND")
	)
	(via
		(at 286.906462 -122.354848)
		(size 0.508)
		(drill 0.254)
		(layers "F.Cu" "B.Cu")
		(net "GND")
	)
	(via
		(at 29.307028 -49.574704)
		(size 0.508)
		(drill 0.254)
		(layers "F.Cu" "B.Cu")
		(net "GND")
	)
	(via
		(at 121.947686 -399.441924)
		(size 0.4572)
		(drill 0.254)
		(layers "F.Cu" "B.Cu")
		(net "GND")
	)
	(via
		(at 88.947752 -384.042158)
		(size 0.508)
		(drill 0.254)
		(layers "F.Cu" "B.Cu")
		(net "GND")
	)
	(via
		(at 384.669284 -102.181914)
		(size 0.508)
		(drill 0.254)
		(layers "F.Cu" "B.Cu")
		(net "GND")
	)
	(via
		(at 167.457628 -29.784294)
		(size 0.508)
		(drill 0.254)
		(layers "F.Cu" "B.Cu")
		(net "GND")
	)
	(via
		(at 29.54782 -397.038576)
		(size 0.508)
		(drill 0.254)
		(layers "F.Cu" "B.Cu")
		(net "GND")
	)
	(via
		(at 232.990644 -172.62475)
		(size 0.508)
		(drill 0.254)
		(layers "F.Cu" "B.Cu")
		(net "GND")
	)
	(via
		(at 421.249856 -319.65011)
		(size 0.4064)
		(drill 0.2032)
		(layers "F.Cu" "B.Cu")
		(net "GND")
	)
	(via
		(at 324.448678 -29.589984)
		(size 0.508)
		(drill 0.254)
		(layers "F.Cu" "B.Cu")
		(net "GND")
	)
	(via
		(at 276.838664 -23.880318)
		(size 0.508)
		(drill 0.254)
		(layers "F.Cu" "B.Cu")
		(net "GND")
	)
	(via
		(at 258.393438 -295.933114)
		(size 0.508)
		(drill 0.254)
		(layers "F.Cu" "B.Cu")
		(net "GND")
	)
	(via
		(at 81.458562 -342.439498)
		(size 0.4064)
		(drill 0.2032)
		(layers "F.Cu" "B.Cu")
		(net "GND")
	)
	(via
		(at 374.927876 -410.041852)
		(size 0.508)
		(drill 0.254)
		(layers "F.Cu" "B.Cu")
		(net "GND")
	)
	(via
		(at 52.999894 -318.699896)
		(size 0.4064)
		(drill 0.2032)
		(layers "F.Cu" "B.Cu")
		(net "GND")
	)
	(via
		(at 415.549842 -310.149748)
		(size 0.4064)
		(drill 0.2032)
		(layers "F.Cu" "B.Cu")
		(net "GND")
	)
	(via
		(at 91.892882 -345.465146)
		(size 0.4064)
		(drill 0.2032)
		(layers "F.Cu" "B.Cu")
		(net "GND")
	)
	(via
		(at 217.993468 -287.105344)
		(size 0.508)
		(drill 0.254)
		(layers "F.Cu" "B.Cu")
		(net "GND")
	)
	(via
		(at 443.799468 -57.439814)
		(size 0.508)
		(drill 0.254)
		(layers "F.Cu" "B.Cu")
		(net "GND")
	)
	(via
		(at 293.74973 -279.749758)
		(size 0.4064)
		(drill 0.2032)
		(layers "F.Cu" "B.Cu")
		(net "GND")
	)
	(via
		(at 269.412466 -92.526104)
		(size 0.508)
		(drill 0.254)
		(layers "F.Cu" "B.Cu")
		(net "GND")
	)
	(via
		(at 160.549844 -276.899878)
		(size 0.4064)
		(drill 0.2032)
		(layers "F.Cu" "B.Cu")
		(net "GND")
	)
	(via
		(at 276.174708 -297.32478)
		(size 0.4064)
		(drill 0.2032)
		(layers "F.Cu" "B.Cu")
		(net "GND")
	)
	(via
		(at 445.205612 -1.364996)
		(size 0.508)
		(drill 0.254)
		(layers "F.Cu" "B.Cu")
		(net "GND")
	)
	(via
		(at 229.069392 -79.435452)
		(size 0.508)
		(drill 0.254)
		(layers "F.Cu" "B.Cu")
		(net "GND")
	)
	(via
		(at 49.1998 -313.949842)
		(size 0.4064)
		(drill 0.2032)
		(layers "F.Cu" "B.Cu")
		(net "GND")
	)
	(via
		(at 423.32783 -376.241818)
		(size 0.508)
		(drill 0.254)
		(layers "F.Cu" "B.Cu")
		(net "GND")
	)
	(via
		(at 408.726132 -342.439498)
		(size 0.4064)
		(drill 0.2032)
		(layers "F.Cu" "B.Cu")
		(net "GND")
	)
	(via
		(at 269.999714 -303.499774)
		(size 0.4064)
		(drill 0.2032)
		(layers "F.Cu" "B.Cu")
		(net "GND")
	)
	(via
		(at 75.79995 -277.849838)
		(size 0.4064)
		(drill 0.2032)
		(layers "F.Cu" "B.Cu")
		(net "GND")
	)
	(via
		(at 292.57117 -354.098098)
		(size 0.4572)
		(drill 0.254)
		(layers "F.Cu" "B.Cu")
		(net "GND")
	)
	(via
		(at 441.445904 -358.391714)
		(size 0.4572)
		(drill 0.254)
		(layers "F.Cu" "B.Cu")
		(net "GND")
	)
	(via
		(at 431.859944 -288.774886)
		(size 0.4064)
		(drill 0.2032)
		(layers "F.Cu" "B.Cu")
		(net "GND")
	)
	(via
		(at 311.799732 -306.349908)
		(size 0.4064)
		(drill 0.2032)
		(layers "F.Cu" "B.Cu")
		(net "GND")
	)
	(via
		(at 426.94987 -310.149748)
		(size 0.4064)
		(drill 0.2032)
		(layers "F.Cu" "B.Cu")
		(net "GND")
	)
	(via
		(at 62.974982 -305.874928)
		(size 0.4064)
		(drill 0.2032)
		(layers "F.Cu" "B.Cu")
		(net "GND")
	)
	(via
		(at 282.349702 -315.849762)
		(size 0.4064)
		(drill 0.2032)
		(layers "F.Cu" "B.Cu")
		(net "GND")
	)
	(via
		(at 192.706752 -348.58579)
		(size 0.4064)
		(drill 0.2032)
		(layers "F.Cu" "B.Cu")
		(net "GND")
	)
	(via
		(at 141.369796 -177.807874)
		(size 0.508)
		(drill 0.254)
		(layers "F.Cu" "B.Cu")
		(net "GND")
	)
	(via
		(at 395.613382 -33.459674)
		(size 0.508)
		(drill 0.254)
		(layers "F.Cu" "B.Cu")
		(net "GND")
	)
	(via
		(at 5.472176 -378.370592)
		(size 0.508)
		(drill 0.254)
		(layers "F.Cu" "B.Cu")
		(net "GND")
	)
	(via
		(at 294.201342 -354.732082)
		(size 0.4064)
		(drill 0.2032)
		(layers "F.Cu" "B.Cu")
		(net "GND")
	)
	(via
		(at 156.750004 -304.449734)
		(size 0.4064)
		(drill 0.2032)
		(layers "F.Cu" "B.Cu")
		(net "GND")
	)
	(via
		(at 82.449924 -313.949842)
		(size 0.4064)
		(drill 0.2032)
		(layers "F.Cu" "B.Cu")
		(net "GND")
	)
	(via
		(at 351.649538 -90.645234)
		(size 0.508)
		(drill 0.254)
		(layers "F.Cu" "B.Cu")
		(net "GND")
	)
	(via
		(at 152.634442 -253.45644)
		(size 0.508)
		(drill 0.254)
		(layers "F.Cu" "B.Cu")
		(net "GND")
	)
	(via
		(at 261.963916 -82.778854)
		(size 0.508)
		(drill 0.254)
		(layers "F.Cu" "B.Cu")
		(net "GND")
	)
	(via
		(at 189.999874 -317.749936)
		(size 0.4064)
		(drill 0.2032)
		(layers "F.Cu" "B.Cu")
		(net "GND")
	)
	(via
		(at 221.392496 -309.604156)
		(size 0.508)
		(drill 0.254)
		(layers "F.Cu" "B.Cu")
		(net "GND")
	)
	(via
		(at 411.498288 -203.61402)
		(size 0.508)
		(drill 0.254)
		(layers "F.Cu" "B.Cu")
		(net "GND")
	)
	(via
		(at 291.32784 -410.041852)
		(size 0.508)
		(drill 0.254)
		(layers "F.Cu" "B.Cu")
		(net "GND")
	)
	(via
		(at 163.41344 -34.718498)
		(size 0.508)
		(drill 0.254)
		(layers "F.Cu" "B.Cu")
		(net "GND")
	)
	(via
		(at 417.773358 -73.20026)
		(size 0.508)
		(drill 0.254)
		(layers "F.Cu" "B.Cu")
		(net "GND")
	)
	(via
		(at 73.53046 -65.15989)
		(size 0.508)
		(drill 0.254)
		(layers "F.Cu" "B.Cu")
		(net "GND")
	)
	(via
		(at 306.16017 -21.37156)
		(size 0.508)
		(drill 0.254)
		(layers "F.Cu" "B.Cu")
		(net "GND")
	)
	(via
		(at 199.500236 -316.799722)
		(size 0.4064)
		(drill 0.2032)
		(layers "F.Cu" "B.Cu")
		(net "GND")
	)
	(via
		(at 16.558006 -58.791094)
		(size 0.508)
		(drill 0.254)
		(layers "F.Cu" "B.Cu")
		(net "GND")
	)
	(via
		(at 295.649904 -319.65011)
		(size 0.4064)
		(drill 0.2032)
		(layers "F.Cu" "B.Cu")
		(net "GND")
	)
	(via
		(at 297.927776 -403.34184)
		(size 0.508)
		(drill 0.254)
		(layers "F.Cu" "B.Cu")
		(net "GND")
	)
	(via
		(at 317.044324 -342.439498)
		(size 0.4064)
		(drill 0.2032)
		(layers "F.Cu" "B.Cu")
		(net "GND")
	)
	(via
		(at 96.184466 -73.20026)
		(size 0.508)
		(drill 0.254)
		(layers "F.Cu" "B.Cu")
		(net "GND")
	)
	(via
		(at 37.324792 -284.024832)
		(size 0.4064)
		(drill 0.2032)
		(layers "F.Cu" "B.Cu")
		(net "GND")
	)
	(via
		(at 170.806364 -124.154946)
		(size 0.508)
		(drill 0.254)
		(layers "F.Cu" "B.Cu")
		(net "GND")
	)
	(via
		(at 119.972328 -33.857692)
		(size 0.508)
		(drill 0.254)
		(layers "F.Cu" "B.Cu")
		(net "GND")
	)
	(via
		(at 376.578114 -244.324886)
		(size 0.508)
		(drill 0.254)
		(layers "F.Cu" "B.Cu")
		(net "GND")
	)
	(via
		(at 174.325026 -306.824888)
		(size 0.4064)
		(drill 0.2032)
		(layers "F.Cu" "B.Cu")
		(net "GND")
	)
	(via
		(at 297.333162 -181.681374)
		(size 0.508)
		(drill 0.254)
		(layers "F.Cu" "B.Cu")
		(net "GND")
	)
	(via
		(at 167.835072 -348.58579)
		(size 0.4064)
		(drill 0.2032)
		(layers "F.Cu" "B.Cu")
		(net "GND")
	)
	(via
		(at 161.54781 -383.940304)
		(size 0.508)
		(drill 0.254)
		(layers "F.Cu" "B.Cu")
		(net "GND")
	)
	(via
		(at 189.999874 -289.249866)
		(size 0.4064)
		(drill 0.2032)
		(layers "F.Cu" "B.Cu")
		(net "GND")
	)
	(via
		(at 421.127682 -403.34184)
		(size 0.508)
		(drill 0.254)
		(layers "F.Cu" "B.Cu")
		(net "GND")
	)
	(via
		(at 286.927798 -372.341902)
		(size 0.508)
		(drill 0.254)
		(layers "F.Cu" "B.Cu")
		(net "GND")
	)
	(via
		(at 166.249858 -281.649932)
		(size 0.4064)
		(drill 0.2032)
		(layers "F.Cu" "B.Cu")
		(net "GND")
	)
	(via
		(at 284.503114 -346.09913)
		(size 0.4572)
		(drill 0.254)
		(layers "F.Cu" "B.Cu")
		(net "GND")
	)
	(via
		(at 314.366148 -129.707894)
		(size 0.508)
		(drill 0.254)
		(layers "F.Cu" "B.Cu")
		(net "GND")
	)
	(via
		(at 124.147834 -382.84023)
		(size 0.4572)
		(drill 0.254)
		(layers "F.Cu" "B.Cu")
		(net "GND")
	)
	(via
		(at 430.8602 -344.831162)
		(size 0.4572)
		(drill 0.254)
		(layers "F.Cu" "B.Cu")
		(net "GND")
	)
	(via
		(at 81.974944 -303.024794)
		(size 0.4064)
		(drill 0.2032)
		(layers "F.Cu" "B.Cu")
		(net "GND")
	)
	(via
		(at 309.424832 -303.024794)
		(size 0.4064)
		(drill 0.2032)
		(layers "F.Cu" "B.Cu")
		(net "GND")
	)
	(via
		(at 81.84515 -51.227482)
		(size 0.508)
		(drill 0.254)
		(layers "F.Cu" "B.Cu")
		(net "GND")
	)
	(via
		(at 276.871176 -29.311854)
		(size 0.508)
		(drill 0.254)
		(layers "F.Cu" "B.Cu")
		(net "GND")
	)
	(via
		(at 4.562856 -220.801692)
		(size 0.508)
		(drill 0.254)
		(layers "F.Cu" "B.Cu")
		(net "GND")
	)
	(via
		(at 40.897556 -344.831162)
		(size 0.4572)
		(drill 0.254)
		(layers "F.Cu" "B.Cu")
		(net "GND")
	)
	(via
		(at 311.799732 -281.649932)
		(size 0.4064)
		(drill 0.2032)
		(layers "F.Cu" "B.Cu")
		(net "GND")
	)
	(via
		(at 375.7295 -354.732082)
		(size 0.4064)
		(drill 0.2032)
		(layers "F.Cu" "B.Cu")
		(net "GND")
	)
	(via
		(at 168.150032 -315.849762)
		(size 0.4064)
		(drill 0.2032)
		(layers "F.Cu" "B.Cu")
		(net "GND")
	)
	(via
		(at 333.127858 -372.240302)
		(size 0.508)
		(drill 0.254)
		(layers "F.Cu" "B.Cu")
		(net "GND")
	)
	(via
		(at 419.824916 -289.724846)
		(size 0.4064)
		(drill 0.2032)
		(layers "F.Cu" "B.Cu")
		(net "GND")
	)
	(via
		(at 128.440942 -195.062094)
		(size 0.508)
		(drill 0.254)
		(layers "F.Cu" "B.Cu")
		(net "GND")
	)
	(via
		(at 272.374868 -279.274778)
		(size 0.4064)
		(drill 0.2032)
		(layers "F.Cu" "B.Cu")
		(net "GND")
	)
	(via
		(at 302.774858 -303.024794)
		(size 0.4064)
		(drill 0.2032)
		(layers "F.Cu" "B.Cu")
		(net "GND")
	)
	(via
		(at 70.75551 -63.218314)
		(size 0.508)
		(drill 0.254)
		(layers "F.Cu" "B.Cu")
		(net "GND")
	)
	(via
		(at 365.190532 -92.096336)
		(size 0.508)
		(drill 0.254)
		(layers "F.Cu" "B.Cu")
		(net "GND")
	)
	(via
		(at 80.54975 -276.899878)
		(size 0.4064)
		(drill 0.2032)
		(layers "F.Cu" "B.Cu")
		(net "GND")
	)
	(via
		(at 274.749768 -312.049922)
		(size 0.4064)
		(drill 0.2032)
		(layers "F.Cu" "B.Cu")
		(net "GND")
	)
	(via
		(at 428.84979 -312.049922)
		(size 0.4064)
		(drill 0.2032)
		(layers "F.Cu" "B.Cu")
		(net "GND")
	)
	(via
		(at 135.920226 -120.925844)
		(size 0.508)
		(drill 0.254)
		(layers "F.Cu" "B.Cu")
		(net "GND")
	)
	(via
		(at 290.89985 -281.649932)
		(size 0.4064)
		(drill 0.2032)
		(layers "F.Cu" "B.Cu")
		(net "GND")
	)
	(via
		(at 171.31538 -357.123746)
		(size 0.4572)
		(drill 0.254)
		(layers "F.Cu" "B.Cu")
		(net "GND")
	)
	(via
		(at 440.18708 -346.09913)
		(size 0.4572)
		(drill 0.254)
		(layers "F.Cu" "B.Cu")
		(net "GND")
	)
	(via
		(at 368.6302 -84.38515)
		(size 0.508)
		(drill 0.254)
		(layers "F.Cu" "B.Cu")
		(net "GND")
	)
	(via
		(at 293.74973 -310.149748)
		(size 0.4064)
		(drill 0.2032)
		(layers "F.Cu" "B.Cu")
		(net "GND")
	)
	(via
		(at 157.518354 -264.252202)
		(size 0.508)
		(drill 0.254)
		(layers "F.Cu" "B.Cu")
		(net "GND")
	)
	(via
		(at 369.818666 -99.506024)
		(size 0.508)
		(drill 0.254)
		(layers "F.Cu" "B.Cu")
		(net "GND")
	)
	(via
		(at 69.022722 -351.611438)
		(size 0.4064)
		(drill 0.2032)
		(layers "F.Cu" "B.Cu")
		(net "GND")
	)
	(via
		(at 99.469956 -238.417354)
		(size 0.508)
		(drill 0.254)
		(layers "F.Cu" "B.Cu")
		(net "GND")
	)
	(via
		(at 438.336944 -355.366066)
		(size 0.4572)
		(drill 0.254)
		(layers "F.Cu" "B.Cu")
		(net "GND")
	)
	(via
		(at 289.94989 -316.799722)
		(size 0.4064)
		(drill 0.2032)
		(layers "F.Cu" "B.Cu")
		(net "GND")
	)
	(via
		(at 195.224908 -290.674806)
		(size 0.4064)
		(drill 0.2032)
		(layers "F.Cu" "B.Cu")
		(net "GND")
	)
	(via
		(at 393.7 -304.449734)
		(size 0.4064)
		(drill 0.2032)
		(layers "F.Cu" "B.Cu")
		(net "GND")
	)
	(via
		(at 81.087214 -355.366066)
		(size 0.4572)
		(drill 0.254)
		(layers "F.Cu" "B.Cu")
		(net "GND")
	)
	(via
		(at 117.547644 -383.940304)
		(size 0.4572)
		(drill 0.254)
		(layers "F.Cu" "B.Cu")
		(net "GND")
	)
	(via
		(at 125.053852 -150.16861)
		(size 0.508)
		(drill 0.254)
		(layers "F.Cu" "B.Cu")
		(net "GND")
	)
	(via
		(at 4.562856 -144.601692)
		(size 0.508)
		(drill 0.254)
		(layers "F.Cu" "B.Cu")
		(net "GND")
	)
	(via
		(at 63.798196 -21.077936)
		(size 0.508)
		(drill 0.254)
		(layers "F.Cu" "B.Cu")
		(net "GND")
	)
	(via
		(at 259.258562 -211.749386)
		(size 0.508)
		(drill 0.254)
		(layers "F.Cu" "B.Cu")
		(net "GND")
	)
	(via
		(at 354.9777 -99.182936)
		(size 0.508)
		(drill 0.254)
		(layers "F.Cu" "B.Cu")
		(net "GND")
	)
	(via
		(at 290.42487 -291.624766)
		(size 0.4064)
		(drill 0.2032)
		(layers "F.Cu" "B.Cu")
		(net "GND")
	)
	(via
		(at 390.58088 -33.19018)
		(size 0.508)
		(drill 0.254)
		(layers "F.Cu" "B.Cu")
		(net "GND")
	)
	(via
		(at 54.70652 -100.64496)
		(size 0.508)
		(drill 0.254)
		(layers "F.Cu" "B.Cu")
		(net "GND")
	)
	(via
		(at 287.099756 -274.049744)
		(size 0.4064)
		(drill 0.2032)
		(layers "F.Cu" "B.Cu")
		(net "GND")
	)
	(via
		(at 270.601694 -102.716584)
		(size 0.508)
		(drill 0.254)
		(layers "F.Cu" "B.Cu")
		(net "GND")
	)
	(via
		(at 117.547644 -397.038576)
		(size 0.508)
		(drill 0.254)
		(layers "F.Cu" "B.Cu")
		(net "GND")
	)
	(via
		(at 160.682178 -58.873644)
		(size 0.508)
		(drill 0.254)
		(layers "F.Cu" "B.Cu")
		(net "GND")
	)
	(via
		(at 429.198278 -118.498112)
		(size 0.508)
		(drill 0.254)
		(layers "F.Cu" "B.Cu")
		(net "GND")
	)
	(via
		(at 74.251312 -47.03191)
		(size 0.508)
		(drill 0.254)
		(layers "F.Cu" "B.Cu")
		(net "GND")
	)
	(via
		(at 45.87494 -290.674806)
		(size 0.4064)
		(drill 0.2032)
		(layers "F.Cu" "B.Cu")
		(net "GND")
	)
	(via
		(at 122.70105 -33.19018)
		(size 0.508)
		(drill 0.254)
		(layers "F.Cu" "B.Cu")
		(net "GND")
	)
	(via
		(at 297.927776 -408.738578)
		(size 0.508)
		(drill 0.254)
		(layers "F.Cu" "B.Cu")
		(net "GND")
	)
	(via
		(at 385.149852 -307.299868)
		(size 0.4064)
		(drill 0.2032)
		(layers "F.Cu" "B.Cu")
		(net "GND")
	)
	(via
		(at 158.87954 -354.098098)
		(size 0.4572)
		(drill 0.254)
		(layers "F.Cu" "B.Cu")
		(net "GND")
	)
	(via
		(at 7.857236 -307.317394)
		(size 0.508)
		(drill 0.254)
		(layers "F.Cu" "B.Cu")
		(net "GND")
	)
	(via
		(at 466.827616 -62.172596)
		(size 0.508)
		(drill 0.254)
		(layers "F.Cu" "B.Cu")
		(net "GND")
	)
	(via
		(at 276.655022 -357.75773)
		(size 0.4064)
		(drill 0.2032)
		(layers "F.Cu" "B.Cu")
		(net "GND")
	)
	(via
		(at 272.438622 -354.732082)
		(size 0.4064)
		(drill 0.2032)
		(layers "F.Cu" "B.Cu")
		(net "GND")
	)
	(via
		(at 231.388158 -67.799966)
		(size 0.508)
		(drill 0.254)
		(layers "F.Cu" "B.Cu")
		(net "GND")
	)
	(via
		(at 425.901104 -344.831162)
		(size 0.4572)
		(drill 0.254)
		(layers "F.Cu" "B.Cu")
		(net "GND")
	)
	(via
		(at 431.700178 -306.349908)
		(size 0.4064)
		(drill 0.2032)
		(layers "F.Cu" "B.Cu")
		(net "GND")
	)
	(via
		(at 94.280736 -25.990042)
		(size 0.508)
		(drill 0.254)
		(layers "F.Cu" "B.Cu")
		(net "GND")
	)
	(via
		(at 70.130162 -345.465146)
		(size 0.4064)
		(drill 0.2032)
		(layers "F.Cu" "B.Cu")
		(net "GND")
	)
	(via
		(at 294.69969 -277.849838)
		(size 0.4064)
		(drill 0.2032)
		(layers "F.Cu" "B.Cu")
		(net "GND")
	)
	(via
		(at 65.349882 -315.849762)
		(size 0.4064)
		(drill 0.2032)
		(layers "F.Cu" "B.Cu")
		(net "GND")
	)
	(via
		(at 184.77484 -290.674806)
		(size 0.4064)
		(drill 0.2032)
		(layers "F.Cu" "B.Cu")
		(net "GND")
	)
	(via
		(at 60.599828 -277.849838)
		(size 0.4064)
		(drill 0.2032)
		(layers "F.Cu" "B.Cu")
		(net "GND")
	)
	(via
		(at 231.571546 -286.889952)
		(size 0.508)
		(drill 0.254)
		(layers "F.Cu" "B.Cu")
		(net "GND")
	)
	(via
		(at 107.983274 -285.953454)
		(size 0.508)
		(drill 0.254)
		(layers "F.Cu" "B.Cu")
		(net "GND")
	)
	(via
		(at 76.27493 -292.574726)
		(size 0.4064)
		(drill 0.2032)
		(layers "F.Cu" "B.Cu")
		(net "GND")
	)
	(via
		(at 249.699526 -57.439814)
		(size 0.508)
		(drill 0.254)
		(layers "F.Cu" "B.Cu")
		(net "GND")
	)
	(via
		(at 286.927798 -395.938502)
		(size 0.508)
		(drill 0.254)
		(layers "F.Cu" "B.Cu")
		(net "GND")
	)
	(via
		(at 172.574204 -343.073482)
		(size 0.4572)
		(drill 0.254)
		(layers "F.Cu" "B.Cu")
		(net "GND")
	)
	(via
		(at 318.151764 -357.75773)
		(size 0.4064)
		(drill 0.2032)
		(layers "F.Cu" "B.Cu")
		(net "GND")
	)
	(via
		(at 244.256052 -33.19018)
		(size 0.508)
		(drill 0.254)
		(layers "F.Cu" "B.Cu")
		(net "GND")
	)
	(via
		(at 79.315056 -43.85691)
		(size 0.508)
		(drill 0.254)
		(layers "F.Cu" "B.Cu")
		(net "GND")
	)
	(via
		(at 91.1479 -385.141978)
		(size 0.508)
		(drill 0.254)
		(layers "F.Cu" "B.Cu")
		(net "GND")
	)
	(via
		(at 293.829994 -347.951806)
		(size 0.4572)
		(drill 0.254)
		(layers "F.Cu" "B.Cu")
		(net "GND")
	)
	(via
		(at 75.79995 -314.899802)
		(size 0.4064)
		(drill 0.2032)
		(layers "F.Cu" "B.Cu")
		(net "GND")
	)
	(via
		(at 65.349882 -312.049922)
		(size 0.4064)
		(drill 0.2032)
		(layers "F.Cu" "B.Cu")
		(net "GND")
	)
	(via
		(at 67.39255 -355.366066)
		(size 0.4572)
		(drill 0.254)
		(layers "F.Cu" "B.Cu")
		(net "GND")
	)
	(via
		(at 311.523126 -54.067456)
		(size 0.508)
		(drill 0.254)
		(layers "F.Cu" "B.Cu")
		(net "GND")
	)
	(via
		(at 389.644128 -352.245422)
		(size 0.4572)
		(drill 0.254)
		(layers "F.Cu" "B.Cu")
		(net "GND")
	)
	(via
		(at 269.333726 -135.643112)
		(size 0.508)
		(drill 0.254)
		(layers "F.Cu" "B.Cu")
		(net "GND")
	)
	(via
		(at 13.971016 -276.081998)
		(size 0.508)
		(drill 0.254)
		(layers "F.Cu" "B.Cu")
		(net "GND")
	)
	(via
		(at 425.527724 -407.24201)
		(size 0.508)
		(drill 0.254)
		(layers "F.Cu" "B.Cu")
		(net "GND")
	)
	(via
		(at 257.381502 -86.336886)
		(size 0.508)
		(drill 0.254)
		(layers "F.Cu" "B.Cu")
		(net "GND")
	)
	(via
		(at 64.28359 -349.219774)
		(size 0.4572)
		(drill 0.254)
		(layers "F.Cu" "B.Cu")
		(net "GND")
	)
	(via
		(at 80.07477 -288.774886)
		(size 0.4064)
		(drill 0.2032)
		(layers "F.Cu" "B.Cu")
		(net "GND")
	)
	(via
		(at 337.035648 -125.260862)
		(size 0.508)
		(drill 0.254)
		(layers "F.Cu" "B.Cu")
		(net "GND")
	)
	(via
		(at 63.924942 -294.4749)
		(size 0.4064)
		(drill 0.2032)
		(layers "F.Cu" "B.Cu")
		(net "GND")
	)
	(via
		(at 314.366148 -142.418054)
		(size 0.508)
		(drill 0.254)
		(layers "F.Cu" "B.Cu")
		(net "GND")
	)
	(via
		(at 183.649874 -110.514892)
		(size 0.508)
		(drill 0.254)
		(layers "F.Cu" "B.Cu")
		(net "GND")
	)
	(via
		(at 458.468222 -75.588114)
		(size 0.508)
		(drill 0.254)
		(layers "F.Cu" "B.Cu")
		(net "GND")
	)
	(via
		(at 32.8295 -355.366066)
		(size 0.4572)
		(drill 0.254)
		(layers "F.Cu" "B.Cu")
		(net "GND")
	)
	(via
		(at 18.210784 -57.439814)
		(size 0.508)
		(drill 0.254)
		(layers "F.Cu" "B.Cu")
		(net "GND")
	)
	(via
		(at 169.217086 -14.553438)
		(size 0.508)
		(drill 0.254)
		(layers "F.Cu" "B.Cu")
		(net "GND")
	)
	(via
		(at 270.80845 -357.123746)
		(size 0.4572)
		(drill 0.254)
		(layers "F.Cu" "B.Cu")
		(net "GND")
	)
	(via
		(at 170.999912 -276.899878)
		(size 0.4064)
		(drill 0.2032)
		(layers "F.Cu" "B.Cu")
		(net "GND")
	)
	(via
		(at 58.35523 -367.45545)
		(size 0.4572)
		(drill 0.254)
		(layers "F.Cu" "B.Cu")
		(net "GND")
	)
	(via
		(at 384.199638 -302.550068)
		(size 0.4064)
		(drill 0.2032)
		(layers "F.Cu" "B.Cu")
		(net "GND")
	)
	(via
		(at 183.766714 -142.15491)
		(size 0.508)
		(drill 0.254)
		(layers "F.Cu" "B.Cu")
		(net "GND")
	)
	(via
		(at 401.78736 -135.364982)
		(size 0.508)
		(drill 0.254)
		(layers "F.Cu" "B.Cu")
		(net "GND")
	)
	(via
		(at 364.557564 -262.006588)
		(size 0.508)
		(drill 0.254)
		(layers "F.Cu" "B.Cu")
		(net "GND")
	)
	(via
		(at 236.63148 -148.441918)
		(size 0.508)
		(drill 0.254)
		(layers "F.Cu" "B.Cu")
		(net "GND")
	)
	(via
		(at 143.6624 -388.8232)
		(size 0.508)
		(drill 0.254)
		(layers "F.Cu" "B.Cu")
		(net "GND")
	)
	(via
		(at 401.623276 -54.067456)
		(size 0.508)
		(drill 0.254)
		(layers "F.Cu" "B.Cu")
		(net "GND")
	)
	(via
		(at 198.26605 -118.498112)
		(size 0.508)
		(drill 0.254)
		(layers "F.Cu" "B.Cu")
		(net "GND")
	)
	(via
		(at 55.35803 -361.676696)
		(size 0.508)
		(drill 0.254)
		(layers "F.Cu" "B.Cu")
		(net "GND")
	)
	(via
		(at 306.448206 -118.234968)
		(size 0.508)
		(drill 0.254)
		(layers "F.Cu" "B.Cu")
		(net "GND")
	)
	(via
		(at 44.45 -319.65011)
		(size 0.4064)
		(drill 0.2032)
		(layers "F.Cu" "B.Cu")
		(net "GND")
	)
	(via
		(at 163.399978 -313.949842)
		(size 0.4064)
		(drill 0.2032)
		(layers "F.Cu" "B.Cu")
		(net "GND")
	)
	(via
		(at 337.5279 -399.441924)
		(size 0.508)
		(drill 0.254)
		(layers "F.Cu" "B.Cu")
		(net "GND")
	)
	(via
		(at 95.483426 -114.075972)
		(size 0.508)
		(drill 0.254)
		(layers "F.Cu" "B.Cu")
		(net "GND")
	)
	(via
		(at 411.835092 -342.439498)
		(size 0.4064)
		(drill 0.2032)
		(layers "F.Cu" "B.Cu")
		(net "GND")
	)
	(via
		(at 368.120422 -121.560844)
		(size 0.508)
		(drill 0.254)
		(layers "F.Cu" "B.Cu")
		(net "GND")
	)
	(via
		(at 429.927766 -373.441976)
		(size 0.508)
		(drill 0.254)
		(layers "F.Cu" "B.Cu")
		(net "GND")
	)
	(via
		(at 346.578682 -284.333188)
		(size 0.49022)
		(drill 0.254)
		(layers "F.Cu" "B.Cu")
		(net "GND")
	)
	(via
		(at 317.008256 -132.77342)
		(size 0.508)
		(drill 0.254)
		(layers "F.Cu" "B.Cu")
		(net "GND")
	)
	(via
		(at 170.049952 -315.849762)
		(size 0.4064)
		(drill 0.2032)
		(layers "F.Cu" "B.Cu")
		(net "GND")
	)
	(via
		(at 38.347904 -411.141926)
		(size 0.508)
		(drill 0.254)
		(layers "F.Cu" "B.Cu")
		(net "GND")
	)
	(via
		(at 4.562856 -241.121692)
		(size 0.508)
		(drill 0.254)
		(layers "F.Cu" "B.Cu")
		(net "GND")
	)
	(via
		(at 339.728048 -403.738588)
		(size 0.508)
		(drill 0.254)
		(layers "F.Cu" "B.Cu")
		(net "GND")
	)
	(via
		(at 411.750002 -310.149748)
		(size 0.4064)
		(drill 0.2032)
		(layers "F.Cu" "B.Cu")
		(net "GND")
	)
	(via
		(at 432.900836 -31.390336)
		(size 0.508)
		(drill 0.254)
		(layers "F.Cu" "B.Cu")
		(net "GND")
	)
	(via
		(at 130.902964 -74.624184)
		(size 0.508)
		(drill 0.254)
		(layers "F.Cu" "B.Cu")
		(net "GND")
	)
	(via
		(at 40.174926 -283.074872)
		(size 0.4064)
		(drill 0.2032)
		(layers "F.Cu" "B.Cu")
		(net "GND")
	)
	(via
		(at 390.58088 -34.990024)
		(size 0.508)
		(drill 0.254)
		(layers "F.Cu" "B.Cu")
		(net "GND")
	)
	(via
		(at 38.749986 -316.799722)
		(size 0.4064)
		(drill 0.2032)
		(layers "F.Cu" "B.Cu")
		(net "GND")
	)
	(via
		(at 363.102906 -74.624184)
		(size 0.508)
		(drill 0.254)
		(layers "F.Cu" "B.Cu")
		(net "GND")
	)
	(via
		(at 15.67053 -133.972046)
		(size 0.508)
		(drill 0.254)
		(layers "F.Cu" "B.Cu")
		(net "GND")
	)
	(via
		(at 429.198278 -147.27682)
		(size 0.508)
		(drill 0.254)
		(layers "F.Cu" "B.Cu")
		(net "GND")
	)
	(via
		(at 416.024822 -307.774848)
		(size 0.4064)
		(drill 0.2032)
		(layers "F.Cu" "B.Cu")
		(net "GND")
	)
	(via
		(at 168.625012 -305.874928)
		(size 0.4064)
		(drill 0.2032)
		(layers "F.Cu" "B.Cu")
		(net "GND")
	)
	(via
		(at 114.910616 -134.87146)
		(size 0.508)
		(drill 0.254)
		(layers "F.Cu" "B.Cu")
		(net "GND")
	)
	(via
		(at 431.94986 -27.04973)
		(size 0.508)
		(drill 0.254)
		(layers "F.Cu" "B.Cu")
		(net "GND")
	)
	(via
		(at 97.03435 -47.936658)
		(size 0.508)
		(drill 0.254)
		(layers "F.Cu" "B.Cu")
		(net "GND")
	)
	(via
		(at 297.927776 -380.040134)
		(size 0.508)
		(drill 0.254)
		(layers "F.Cu" "B.Cu")
		(net "GND")
	)
	(via
		(at 42.747946 -378.83846)
		(size 0.508)
		(drill 0.254)
		(layers "F.Cu" "B.Cu")
		(net "GND")
	)
	(via
		(at 37.564822 -152.295352)
		(size 0.508)
		(drill 0.254)
		(layers "F.Cu" "B.Cu")
		(net "GND")
	)
	(via
		(at 215.464136 -185.719974)
		(size 0.508)
		(drill 0.254)
		(layers "F.Cu" "B.Cu")
		(net "GND")
	)
	(via
		(at 430.466246 -149.617938)
		(size 0.508)
		(drill 0.254)
		(layers "F.Cu" "B.Cu")
		(net "GND")
	)
	(via
		(at 169.574972 -306.824888)
		(size 0.4064)
		(drill 0.2032)
		(layers "F.Cu" "B.Cu")
		(net "GND")
	)
	(via
		(at 343.394792 -352.245422)
		(size 0.4572)
		(drill 0.254)
		(layers "F.Cu" "B.Cu")
		(net "GND")
	)
	(via
		(at 170.806364 -107.844844)
		(size 0.508)
		(drill 0.254)
		(layers "F.Cu" "B.Cu")
		(net "GND")
	)
	(via
		(at 136.306814 -213.016846)
		(size 0.508)
		(drill 0.254)
		(layers "F.Cu" "B.Cu")
		(net "GND")
	)
	(via
		(at 316.672976 -350.977454)
		(size 0.4572)
		(drill 0.254)
		(layers "F.Cu" "B.Cu")
		(net "GND")
	)
	(via
		(at 181.92496 -300.174914)
		(size 0.4064)
		(drill 0.2032)
		(layers "F.Cu" "B.Cu")
		(net "GND")
	)
	(via
		(at 424.57497 -291.624766)
		(size 0.4064)
		(drill 0.2032)
		(layers "F.Cu" "B.Cu")
		(net "GND")
	)
	(via
		(at 22.715728 -169.746422)
		(size 0.508)
		(drill 0.254)
		(layers "F.Cu" "B.Cu")
		(net "GND")
	)
	(via
		(at 338.27847 -285.953454)
		(size 0.508)
		(drill 0.254)
		(layers "F.Cu" "B.Cu")
		(net "GND")
	)
	(via
		(at 426.94987 -306.349908)
		(size 0.4064)
		(drill 0.2032)
		(layers "F.Cu" "B.Cu")
		(net "GND")
	)
	(via
		(at 252.020324 -122.907044)
		(size 0.508)
		(drill 0.254)
		(layers "F.Cu" "B.Cu")
		(net "GND")
	)
	(via
		(at 283.833062 -133.565138)
		(size 0.508)
		(drill 0.254)
		(layers "F.Cu" "B.Cu")
		(net "GND")
	)
	(via
		(at 101.333554 -84.762594)
		(size 0.508)
		(drill 0.254)
		(layers "F.Cu" "B.Cu")
		(net "GND")
	)
	(via
		(at 36.369244 -100.92309)
		(size 0.508)
		(drill 0.254)
		(layers "F.Cu" "B.Cu")
		(net "GND")
	)
	(via
		(at 258.993386 -398.467834)
		(size 0.508)
		(drill 0.254)
		(layers "F.Cu" "B.Cu")
		(net "GND")
	)
	(via
		(at 134.771384 -28.05303)
		(size 0.508)
		(drill 0.254)
		(layers "F.Cu" "B.Cu")
		(net "GND")
	)
	(via
		(at 53.270404 -28.040076)
		(size 0.508)
		(drill 0.254)
		(layers "F.Cu" "B.Cu")
		(net "GND")
	)
	(via
		(at 466.835998 -323.403976)
		(size 0.508)
		(drill 0.254)
		(layers "F.Cu" "B.Cu")
		(net "GND")
	)
	(via
		(at 292.199822 -354.732082)
		(size 0.4064)
		(drill 0.2032)
		(layers "F.Cu" "B.Cu")
		(net "GND")
	)
	(via
		(at 388.474966 -286.874966)
		(size 0.4064)
		(drill 0.2032)
		(layers "F.Cu" "B.Cu")
		(net "GND")
	)
	(via
		(at 42.747946 -404.838662)
		(size 0.508)
		(drill 0.254)
		(layers "F.Cu" "B.Cu")
		(net "GND")
	)
	(via
		(at 179.07508 -293.52494)
		(size 0.4064)
		(drill 0.2032)
		(layers "F.Cu" "B.Cu")
		(net "GND")
	)
	(via
		(at 134.296404 -60.099194)
		(size 0.508)
		(drill 0.254)
		(layers "F.Cu" "B.Cu")
		(net "GND")
	)
	(via
		(at 272.849848 -304.449734)
		(size 0.4064)
		(drill 0.2032)
		(layers "F.Cu" "B.Cu")
		(net "GND")
	)
	(via
		(at 307.049932 -281.649932)
		(size 0.4064)
		(drill 0.2032)
		(layers "F.Cu" "B.Cu")
		(net "GND")
	)
	(via
		(at 40.547798 -384.041904)
		(size 0.508)
		(drill 0.254)
		(layers "F.Cu" "B.Cu")
		(net "GND")
	)
	(via
		(at 159.599884 -312.999882)
		(size 0.4064)
		(drill 0.2032)
		(layers "F.Cu" "B.Cu")
		(net "GND")
	)
	(via
		(at 429.800004 -277.849838)
		(size 0.4064)
		(drill 0.2032)
		(layers "F.Cu" "B.Cu")
		(net "GND")
	)
	(via
		(at 50.14976 -275.949918)
		(size 0.4064)
		(drill 0.2032)
		(layers "F.Cu" "B.Cu")
		(net "GND")
	)
	(via
		(at 35.195002 -60.633356)
		(size 0.508)
		(drill 0.254)
		(layers "F.Cu" "B.Cu")
		(net "GND")
	)
	(via
		(at 64.59347 -133.0452)
		(size 0.508)
		(drill 0.254)
		(layers "F.Cu" "B.Cu")
		(net "GND")
	)
	(via
		(at 152.94991 -312.999882)
		(size 0.4064)
		(drill 0.2032)
		(layers "F.Cu" "B.Cu")
		(net "GND")
	)
	(via
		(at 360.83875 -306.55387)
		(size 0.508)
		(drill 0.254)
		(layers "F.Cu" "B.Cu")
		(net "GND")
	)
	(via
		(at 295.649904 -311.099962)
		(size 0.4064)
		(drill 0.2032)
		(layers "F.Cu" "B.Cu")
		(net "GND")
	)
	(via
		(at 269.524734 -284.024832)
		(size 0.4064)
		(drill 0.2032)
		(layers "F.Cu" "B.Cu")
		(net "GND")
	)
	(via
		(at 281.546554 -110.857538)
		(size 0.508)
		(drill 0.254)
		(layers "F.Cu" "B.Cu")
		(net "GND")
	)
	(via
		(at 114.238786 -285.953454)
		(size 0.508)
		(drill 0.254)
		(layers "F.Cu" "B.Cu")
		(net "GND")
	)
	(via
		(at 127.78105 -25.990042)
		(size 0.508)
		(drill 0.254)
		(layers "F.Cu" "B.Cu")
		(net "GND")
	)
	(via
		(at 33.947862 -398.24025)
		(size 0.508)
		(drill 0.254)
		(layers "F.Cu" "B.Cu")
		(net "GND")
	)
	(via
		(at 381.12192 -75.114658)
		(size 0.508)
		(drill 0.254)
		(layers "F.Cu" "B.Cu")
		(net "GND")
	)
	(via
		(at 388.16534 -345.465146)
		(size 0.4064)
		(drill 0.2032)
		(layers "F.Cu" "B.Cu")
		(net "GND")
	)
	(via
		(at 66.44767 -142.15491)
		(size 0.508)
		(drill 0.254)
		(layers "F.Cu" "B.Cu")
		(net "GND")
	)
	(via
		(at 388.20217 -58.096404)
		(size 0.508)
		(drill 0.254)
		(layers "F.Cu" "B.Cu")
		(net "GND")
	)
	(via
		(at 86.747858 -403.34184)
		(size 0.508)
		(drill 0.254)
		(layers "F.Cu" "B.Cu")
		(net "GND")
	)
	(via
		(at 139.645136 -349.219774)
		(size 0.4572)
		(drill 0.254)
		(layers "F.Cu" "B.Cu")
		(net "GND")
	)
	(via
		(at 421.724836 -303.024794)
		(size 0.4064)
		(drill 0.2032)
		(layers "F.Cu" "B.Cu")
		(net "GND")
	)
	(via
		(at 396.0749 -289.724846)
		(size 0.4064)
		(drill 0.2032)
		(layers "F.Cu" "B.Cu")
		(net "GND")
	)
	(via
		(at 161.54781 -408.738578)
		(size 0.508)
		(drill 0.254)
		(layers "F.Cu" "B.Cu")
		(net "GND")
	)
	(via
		(at 211.585556 -63.218314)
		(size 0.508)
		(drill 0.254)
		(layers "F.Cu" "B.Cu")
		(net "GND")
	)
	(via
		(at 109.409484 -93.424502)
		(size 0.508)
		(drill 0.254)
		(layers "F.Cu" "B.Cu")
		(net "GND")
	)
	(via
		(at 232.854246 -274.487386)
		(size 0.508)
		(drill 0.254)
		(layers "F.Cu" "B.Cu")
		(net "GND")
	)
	(via
		(at 282.58643 -48.874934)
		(size 0.508)
		(drill 0.254)
		(layers "F.Cu" "B.Cu")
		(net "GND")
	)
	(via
		(at 398.59966 -351.611438)
		(size 0.4064)
		(drill 0.2032)
		(layers "F.Cu" "B.Cu")
		(net "GND")
	)
	(via
		(at 288.524696 -285.924752)
		(size 0.4064)
		(drill 0.2032)
		(layers "F.Cu" "B.Cu")
		(net "GND")
	)
	(via
		(at 314.649866 -277.849838)
		(size 0.4064)
		(drill 0.2032)
		(layers "F.Cu" "B.Cu")
		(net "GND")
	)
	(via
		(at 67.66687 -131.245102)
		(size 0.508)
		(drill 0.254)
		(layers "F.Cu" "B.Cu")
		(net "GND")
	)
	(via
		(at 186.855608 -63.218314)
		(size 0.508)
		(drill 0.254)
		(layers "F.Cu" "B.Cu")
		(net "GND")
	)
	(via
		(at 29.54782 -374.938544)
		(size 0.508)
		(drill 0.254)
		(layers "F.Cu" "B.Cu")
		(net "GND")
	)
	(via
		(at 190.950088 -286.399732)
		(size 0.4064)
		(drill 0.2032)
		(layers "F.Cu" "B.Cu")
		(net "GND")
	)
	(via
		(at 129.946908 -342.439498)
		(size 0.4064)
		(drill 0.2032)
		(layers "F.Cu" "B.Cu")
		(net "GND")
	)
	(via
		(at 330.958952 -354.098098)
		(size 0.4572)
		(drill 0.254)
		(layers "F.Cu" "B.Cu")
		(net "GND")
	)
	(via
		(at 392.52779 -377.73864)
		(size 0.508)
		(drill 0.254)
		(layers "F.Cu" "B.Cu")
		(net "GND")
	)
	(via
		(at 285.523178 -56.353456)
		(size 0.508)
		(drill 0.254)
		(layers "F.Cu" "B.Cu")
		(net "GND")
	)
	(via
		(at 267.848842 -33.19018)
		(size 0.508)
		(drill 0.254)
		(layers "F.Cu" "B.Cu")
		(net "GND")
	)
	(via
		(at 441.10275 -74.624184)
		(size 0.508)
		(drill 0.254)
		(layers "F.Cu" "B.Cu")
		(net "GND")
	)
	(via
		(at 417.450016 -276.899878)
		(size 0.4064)
		(drill 0.2032)
		(layers "F.Cu" "B.Cu")
		(net "GND")
	)
	(via
		(at 394.64996 -314.899802)
		(size 0.4064)
		(drill 0.2032)
		(layers "F.Cu" "B.Cu")
		(net "GND")
	)
	(via
		(at 327.849992 -347.951806)
		(size 0.4572)
		(drill 0.254)
		(layers "F.Cu" "B.Cu")
		(net "GND")
	)
	(via
		(at 6.176264 -16.135858)
		(size 0.508)
		(drill 0.254)
		(layers "F.Cu" "B.Cu")
		(net "GND")
	)
	(via
		(at 418.882068 -58.873644)
		(size 0.508)
		(drill 0.254)
		(layers "F.Cu" "B.Cu")
		(net "GND")
	)
	(via
		(at 454.2282 -229.3112)
		(size 0.508)
		(drill 0.254)
		(layers "F.Cu" "B.Cu")
		(net "GND")
	)
	(via
		(at 140.442442 -253.45644)
		(size 0.508)
		(drill 0.254)
		(layers "F.Cu" "B.Cu")
		(net "GND")
	)
	(via
		(at 91.256612 -124.93498)
		(size 0.508)
		(drill 0.254)
		(layers "F.Cu" "B.Cu")
		(net "GND")
	)
	(via
		(at 183.75122 -349.219774)
		(size 0.4572)
		(drill 0.254)
		(layers "F.Cu" "B.Cu")
		(net "GND")
	)
	(via
		(at 359.639362 -325.77786)
		(size 0.508)
		(drill 0.254)
		(layers "F.Cu" "B.Cu")
		(net "GND")
	)
	(via
		(at 139.309856 -209.081624)
		(size 0.508)
		(drill 0.254)
		(layers "F.Cu" "B.Cu")
		(net "GND")
	)
	(via
		(at 375.6152 -45.88891)
		(size 0.508)
		(drill 0.254)
		(layers "F.Cu" "B.Cu")
		(net "GND")
	)
	(via
		(at 276.649688 -316.799722)
		(size 0.4064)
		(drill 0.2032)
		(layers "F.Cu" "B.Cu")
		(net "GND")
	)
	(via
		(at 368.55527 -236.689392)
		(size 0.508)
		(drill 0.254)
		(layers "F.Cu" "B.Cu")
		(net "GND")
	)
	(via
		(at 466.827616 -36.772596)
		(size 0.508)
		(drill 0.254)
		(layers "F.Cu" "B.Cu")
		(net "GND")
	)
	(via
		(at 398.925034 -291.624766)
		(size 0.4064)
		(drill 0.2032)
		(layers "F.Cu" "B.Cu")
		(net "GND")
	)
	(via
		(at 404.624794 -302.074834)
		(size 0.4064)
		(drill 0.2032)
		(layers "F.Cu" "B.Cu")
		(net "GND")
	)
	(via
		(at 270.905986 -161.276284)
		(size 0.508)
		(drill 0.254)
		(layers "F.Cu" "B.Cu")
		(net "GND")
	)
	(via
		(at 194.525138 -14.100302)
		(size 0.508)
		(drill 0.254)
		(layers "F.Cu" "B.Cu")
		(net "GND")
	)
	(via
		(at 242.269264 -143.051276)
		(size 0.508)
		(drill 0.254)
		(layers "F.Cu" "B.Cu")
		(net "GND")
	)
	(via
		(at 117.882416 -349.219774)
		(size 0.4572)
		(drill 0.254)
		(layers "F.Cu" "B.Cu")
		(net "GND")
	)
	(via
		(at 389.899906 -313.949842)
		(size 0.4064)
		(drill 0.2032)
		(layers "F.Cu" "B.Cu")
		(net "GND")
	)
	(via
		(at 152.94991 -305.399948)
		(size 0.4064)
		(drill 0.2032)
		(layers "F.Cu" "B.Cu")
		(net "GND")
	)
	(via
		(at 64.874902 -284.974792)
		(size 0.4064)
		(drill 0.2032)
		(layers "F.Cu" "B.Cu")
		(net "GND")
	)
	(via
		(at 273.546062 -342.439498)
		(size 0.4064)
		(drill 0.2032)
		(layers "F.Cu" "B.Cu")
		(net "GND")
	)
	(via
		(at 429.800004 -282.599892)
		(size 0.4064)
		(drill 0.2032)
		(layers "F.Cu" "B.Cu")
		(net "GND")
	)
	(via
		(at 6.846824 -1.135126)
		(size 0.508)
		(drill 0.254)
		(layers "F.Cu" "B.Cu")
		(net "GND")
	)
	(via
		(at 39.699946 -317.749936)
		(size 0.4064)
		(drill 0.2032)
		(layers "F.Cu" "B.Cu")
		(net "GND")
	)
	(via
		(at 396.62989 -165.902894)
		(size 0.508)
		(drill 0.254)
		(layers "F.Cu" "B.Cu")
		(net "GND")
	)
	(via
		(at 93.523054 -341.805514)
		(size 0.4572)
		(drill 0.254)
		(layers "F.Cu" "B.Cu")
		(net "GND")
	)
	(via
		(at 369.830604 -65.15989)
		(size 0.508)
		(drill 0.254)
		(layers "F.Cu" "B.Cu")
		(net "GND")
	)
	(via
		(at 151.999696 -306.350162)
		(size 0.4064)
		(drill 0.2032)
		(layers "F.Cu" "B.Cu")
		(net "GND")
	)
	(via
		(at 99.666298 -85.750146)
		(size 0.508)
		(drill 0.254)
		(layers "F.Cu" "B.Cu")
		(net "GND")
	)
	(via
		(at 256.693924 -393.147296)
		(size 0.508)
		(drill 0.254)
		(layers "F.Cu" "B.Cu")
		(net "GND")
	)
	(via
		(at 197.817232 -342.439498)
		(size 0.4064)
		(drill 0.2032)
		(layers "F.Cu" "B.Cu")
		(net "GND")
	)
	(via
		(at 183.649874 -111.149892)
		(size 0.508)
		(drill 0.254)
		(layers "F.Cu" "B.Cu")
		(net "GND")
	)
	(via
		(at 55.357776 -25.971246)
		(size 0.508)
		(drill 0.254)
		(layers "F.Cu" "B.Cu")
		(net "GND")
	)
	(via
		(at 132.958078 -123.097036)
		(size 0.508)
		(drill 0.254)
		(layers "F.Cu" "B.Cu")
		(net "GND")
	)
	(via
		(at 325.999856 -354.098098)
		(size 0.4572)
		(drill 0.254)
		(layers "F.Cu" "B.Cu")
		(net "GND")
	)
	(via
		(at 398.925034 -296.37482)
		(size 0.4064)
		(drill 0.2032)
		(layers "F.Cu" "B.Cu")
		(net "GND")
	)
	(via
		(at 299.866812 -142.15491)
		(size 0.508)
		(drill 0.254)
		(layers "F.Cu" "B.Cu")
		(net "GND")
	)
	(via
		(at 268.569186 -102.181914)
		(size 0.508)
		(drill 0.254)
		(layers "F.Cu" "B.Cu")
		(net "GND")
	)
	(via
		(at 427.89983 -314.899802)
		(size 0.4064)
		(drill 0.2032)
		(layers "F.Cu" "B.Cu")
		(net "GND")
	)
	(via
		(at 237.903512 -235.737654)
		(size 0.508)
		(drill 0.254)
		(layers "F.Cu" "B.Cu")
		(net "GND")
	)
	(via
		(at 330.958952 -355.366066)
		(size 0.4572)
		(drill 0.254)
		(layers "F.Cu" "B.Cu")
		(net "GND")
	)
	(via
		(at 395.657832 -102.847394)
		(size 0.508)
		(drill 0.254)
		(layers "F.Cu" "B.Cu")
		(net "GND")
	)
	(via
		(at 28.461716 -343.073482)
		(size 0.4572)
		(drill 0.254)
		(layers "F.Cu" "B.Cu")
		(net "GND")
	)
	(via
		(at 419.683184 -347.951806)
		(size 0.4572)
		(drill 0.254)
		(layers "F.Cu" "B.Cu")
		(net "GND")
	)
	(via
		(at 150.59152 -120.28551)
		(size 0.508)
		(drill 0.254)
		(layers "F.Cu" "B.Cu")
		(net "GND")
	)
	(via
		(at 157.224984 -299.224954)
		(size 0.4064)
		(drill 0.2032)
		(layers "F.Cu" "B.Cu")
		(net "GND")
	)
	(via
		(at 186.913012 -410.72054)
		(size 0.508)
		(drill 0.254)
		(layers "F.Cu" "B.Cu")
		(net "GND")
	)
	(via
		(at 50.224436 -344.831162)
		(size 0.4572)
		(drill 0.254)
		(layers "F.Cu" "B.Cu")
		(net "GND")
	)
	(via
		(at 15.437866 -74.624184)
		(size 0.508)
		(drill 0.254)
		(layers "F.Cu" "B.Cu")
		(net "GND")
	)
	(via
		(at 395.590014 -73.85177)
		(size 0.508)
		(drill 0.254)
		(layers "F.Cu" "B.Cu")
		(net "GND")
	)
	(via
		(at 114.873786 -286.842454)
		(size 0.508)
		(drill 0.254)
		(layers "F.Cu" "B.Cu")
		(net "GND")
	)
	(via
		(at 112.446816 -134.23646)
		(size 0.508)
		(drill 0.254)
		(layers "F.Cu" "B.Cu")
		(net "GND")
	)
	(via
		(at 83.400138 -281.650186)
		(size 0.4064)
		(drill 0.2032)
		(layers "F.Cu" "B.Cu")
		(net "GND")
	)
	(via
		(at 110.045246 -305.91887)
		(size 0.508)
		(drill 0.254)
		(layers "F.Cu" "B.Cu")
		(net "GND")
	)
	(via
		(at 74.84999 -275.949918)
		(size 0.4064)
		(drill 0.2032)
		(layers "F.Cu" "B.Cu")
		(net "GND")
	)
	(via
		(at 314.915042 -60.601606)
		(size 0.508)
		(drill 0.254)
		(layers "F.Cu" "B.Cu")
		(net "GND")
	)
	(via
		(at 70.099936 -310.149748)
		(size 0.4064)
		(drill 0.2032)
		(layers "F.Cu" "B.Cu")
		(net "GND")
	)
	(via
		(at 413.174942 -307.774848)
		(size 0.4064)
		(drill 0.2032)
		(layers "F.Cu" "B.Cu")
		(net "GND")
	)
	(via
		(at 6.444234 -249.096784)
		(size 0.508)
		(drill 0.254)
		(layers "F.Cu" "B.Cu")
		(net "GND")
	)
	(via
		(at 221.647512 -232.471468)
		(size 0.508)
		(drill 0.254)
		(layers "F.Cu" "B.Cu")
		(net "GND")
	)
	(via
		(at 17.098264 -219.930726)
		(size 0.508)
		(drill 0.254)
		(layers "F.Cu" "B.Cu")
		(net "GND")
	)
	(via
		(at 423.15003 -309.199788)
		(size 0.4064)
		(drill 0.2032)
		(layers "F.Cu" "B.Cu")
		(net "GND")
	)
	(via
		(at 435.948836 -27.79014)
		(size 0.508)
		(drill 0.254)
		(layers "F.Cu" "B.Cu")
		(net "GND")
	)
	(via
		(at 444.882016 -58.873644)
		(size 0.508)
		(drill 0.254)
		(layers "F.Cu" "B.Cu")
		(net "GND")
	)
	(via
		(at 42.527728 -351.611438)
		(size 0.4064)
		(drill 0.2032)
		(layers "F.Cu" "B.Cu")
		(net "GND")
	)
	(via
		(at 298.012612 -125.435106)
		(size 0.508)
		(drill 0.254)
		(layers "F.Cu" "B.Cu")
		(net "GND")
	)
	(via
		(at 387.050026 -302.549814)
		(size 0.4064)
		(drill 0.2032)
		(layers "F.Cu" "B.Cu")
		(net "GND")
	)
	(via
		(at 300.399704 -281.649932)
		(size 0.4064)
		(drill 0.2032)
		(layers "F.Cu" "B.Cu")
		(net "GND")
	)
	(via
		(at 269.524734 -282.124912)
		(size 0.4064)
		(drill 0.2032)
		(layers "F.Cu" "B.Cu")
		(net "GND")
	)
	(via
		(at 272.374868 -300.174914)
		(size 0.4064)
		(drill 0.2032)
		(layers "F.Cu" "B.Cu")
		(net "GND")
	)
	(via
		(at 234.347766 -85.498686)
		(size 0.508)
		(drill 0.254)
		(layers "F.Cu" "B.Cu")
		(net "GND")
	)
	(via
		(at 315.740288 -136.373362)
		(size 0.508)
		(drill 0.254)
		(layers "F.Cu" "B.Cu")
		(net "GND")
	)
	(via
		(at 261.95274 -85.823552)
		(size 0.508)
		(drill 0.254)
		(layers "F.Cu" "B.Cu")
		(net "GND")
	)
	(via
		(at 267.69949 -347.951806)
		(size 0.4572)
		(drill 0.254)
		(layers "F.Cu" "B.Cu")
		(net "GND")
	)
	(via
		(at 81.499964 -278.799798)
		(size 0.4064)
		(drill 0.2032)
		(layers "F.Cu" "B.Cu")
		(net "GND")
	)
	(via
		(at 318.523112 -341.805514)
		(size 0.4572)
		(drill 0.254)
		(layers "F.Cu" "B.Cu")
		(net "GND")
	)
	(via
		(at 440.18708 -352.245422)
		(size 0.4572)
		(drill 0.254)
		(layers "F.Cu" "B.Cu")
		(net "GND")
	)
	(via
		(at 185.010044 -346.09913)
		(size 0.4572)
		(drill 0.254)
		(layers "F.Cu" "B.Cu")
		(net "GND")
	)
	(via
		(at 307.999892 -284.499812)
		(size 0.4064)
		(drill 0.2032)
		(layers "F.Cu" "B.Cu")
		(net "GND")
	)
	(via
		(at 416.974782 -287.824926)
		(size 0.4064)
		(drill 0.2032)
		(layers "F.Cu" "B.Cu")
		(net "GND")
	)
	(via
		(at 60.803282 -348.58579)
		(size 0.4064)
		(drill 0.2032)
		(layers "F.Cu" "B.Cu")
		(net "GND")
	)
	(via
		(at 402.724874 -289.724846)
		(size 0.4064)
		(drill 0.2032)
		(layers "F.Cu" "B.Cu")
		(net "GND")
	)
	(via
		(at 124.147834 -371.140228)
		(size 0.4572)
		(drill 0.254)
		(layers "F.Cu" "B.Cu")
		(net "GND")
	)
	(via
		(at 180.02504 -306.824888)
		(size 0.4064)
		(drill 0.2032)
		(layers "F.Cu" "B.Cu")
		(net "GND")
	)
	(via
		(at 225.49358 -105.48366)
		(size 0.508)
		(drill 0.254)
		(layers "F.Cu" "B.Cu")
		(net "GND")
	)
	(via
		(at 119.174768 -287.51149)
		(size 0.508)
		(drill 0.254)
		(layers "F.Cu" "B.Cu")
		(net "GND")
	)
	(via
		(at 227.52812 -60.329318)
		(size 0.508)
		(drill 0.254)
		(layers "F.Cu" "B.Cu")
		(net "GND")
	)
	(via
		(at 311.324752 -296.37482)
		(size 0.4064)
		(drill 0.2032)
		(layers "F.Cu" "B.Cu")
		(net "GND")
	)
	(via
		(at 77.947774 -376.140218)
		(size 0.508)
		(drill 0.254)
		(layers "F.Cu" "B.Cu")
		(net "GND")
	)
	(via
		(at 260.54177 -25.971246)
		(size 0.508)
		(drill 0.254)
		(layers "F.Cu" "B.Cu")
		(net "GND")
	)
	(via
		(at 459.713838 -314.27039)
		(size 0.508)
		(drill 0.254)
		(layers "F.Cu" "B.Cu")
		(net "GND")
	)
	(via
		(at 300.874684 -293.52494)
		(size 0.4064)
		(drill 0.2032)
		(layers "F.Cu" "B.Cu")
		(net "GND")
	)
	(via
		(at 418.053012 -351.611438)
		(size 0.4064)
		(drill 0.2032)
		(layers "F.Cu" "B.Cu")
		(net "GND")
	)
	(via
		(at 290.721034 -344.831162)
		(size 0.4572)
		(drill 0.254)
		(layers "F.Cu" "B.Cu")
		(net "GND")
	)
	(via
		(at 191.900048 -305.399948)
		(size 0.4064)
		(drill 0.2032)
		(layers "F.Cu" "B.Cu")
		(net "GND")
	)
	(via
		(at 344.127836 -381.638556)
		(size 0.508)
		(drill 0.254)
		(layers "F.Cu" "B.Cu")
		(net "GND")
	)
	(via
		(at 120.30837 -52.536852)
		(size 0.508)
		(drill 0.254)
		(layers "F.Cu" "B.Cu")
		(net "GND")
	)
	(via
		(at 428.84979 -285.449772)
		(size 0.4064)
		(drill 0.2032)
		(layers "F.Cu" "B.Cu")
		(net "GND")
	)
	(via
		(at 150.555198 -31.390082)
		(size 0.508)
		(drill 0.254)
		(layers "F.Cu" "B.Cu")
		(net "GND")
	)
	(via
		(at 269.333726 -124.43333)
		(size 0.508)
		(drill 0.254)
		(layers "F.Cu" "B.Cu")
		(net "GND")
	)
	(via
		(at 399.93316 -129.964942)
		(size 0.508)
		(drill 0.254)
		(layers "F.Cu" "B.Cu")
		(net "GND")
	)
	(via
		(at 64.874902 -303.974754)
		(size 0.4064)
		(drill 0.2032)
		(layers "F.Cu" "B.Cu")
		(net "GND")
	)
	(via
		(at 389.644128 -355.366066)
		(size 0.4572)
		(drill 0.254)
		(layers "F.Cu" "B.Cu")
		(net "GND")
	)
	(via
		(at 258.393438 -292.732714)
		(size 0.508)
		(drill 0.254)
		(layers "F.Cu" "B.Cu")
		(net "GND")
	)
	(via
		(at 64.054736 -34.990024)
		(size 0.508)
		(drill 0.254)
		(layers "F.Cu" "B.Cu")
		(net "GND")
	)
	(via
		(at 72.131682 -354.732082)
		(size 0.4064)
		(drill 0.2032)
		(layers "F.Cu" "B.Cu")
		(net "GND")
	)
	(via
		(at 199.284844 -106.299)
		(size 0.508)
		(drill 0.254)
		(layers "F.Cu" "B.Cu")
		(net "GND")
	)
	(via
		(at 337.176872 -355.366066)
		(size 0.4572)
		(drill 0.254)
		(layers "F.Cu" "B.Cu")
		(net "GND")
	)
	(via
		(at 260.757924 -299.133514)
		(size 0.508)
		(drill 0.254)
		(layers "F.Cu" "B.Cu")
		(net "GND")
	)
	(via
		(at 341.544656 -347.951806)
		(size 0.4572)
		(drill 0.254)
		(layers "F.Cu" "B.Cu")
		(net "GND")
	)
	(via
		(at 384.199638 -306.350162)
		(size 0.4064)
		(drill 0.2032)
		(layers "F.Cu" "B.Cu")
		(net "GND")
	)
	(via
		(at 379.327918 -375.040144)
		(size 0.508)
		(drill 0.254)
		(layers "F.Cu" "B.Cu")
		(net "GND")
	)
	(via
		(at 114.910616 -136.21766)
		(size 0.508)
		(drill 0.254)
		(layers "F.Cu" "B.Cu")
		(net "GND")
	)
	(via
		(at 171.949872 -312.049922)
		(size 0.4064)
		(drill 0.2032)
		(layers "F.Cu" "B.Cu")
		(net "GND")
	)
	(via
		(at 415.3154 -354.098098)
		(size 0.4572)
		(drill 0.254)
		(layers "F.Cu" "B.Cu")
		(net "GND")
	)
	(via
		(at 421.127682 -372.240302)
		(size 0.508)
		(drill 0.254)
		(layers "F.Cu" "B.Cu")
		(net "GND")
	)
	(via
		(at 319.848738 -29.589984)
		(size 0.508)
		(drill 0.254)
		(layers "F.Cu" "B.Cu")
		(net "GND")
	)
	(via
		(at 131.948428 -345.465146)
		(size 0.4064)
		(drill 0.2032)
		(layers "F.Cu" "B.Cu")
		(net "GND")
	)
	(via
		(at 382.791716 -120.28551)
		(size 0.508)
		(drill 0.254)
		(layers "F.Cu" "B.Cu")
		(net "GND")
	)
	(via
		(at 330.927964 -401.040092)
		(size 0.508)
		(drill 0.254)
		(layers "F.Cu" "B.Cu")
		(net "GND")
	)
	(via
		(at 380.317248 -350.977454)
		(size 0.4572)
		(drill 0.254)
		(layers "F.Cu" "B.Cu")
		(net "GND")
	)
	(via
		(at 193.799968 -285.449772)
		(size 0.4064)
		(drill 0.2032)
		(layers "F.Cu" "B.Cu")
		(net "GND")
	)
	(via
		(at 281.874722 -287.824926)
		(size 0.4064)
		(drill 0.2032)
		(layers "F.Cu" "B.Cu")
		(net "GND")
	)
	(via
		(at 176.868074 -54.238906)
		(size 0.508)
		(drill 0.254)
		(layers "F.Cu" "B.Cu")
		(net "GND")
	)
	(via
		(at 333.696564 -348.58579)
		(size 0.4064)
		(drill 0.2032)
		(layers "F.Cu" "B.Cu")
		(net "GND")
	)
	(via
		(at 317.008256 -120.30456)
		(size 0.508)
		(drill 0.254)
		(layers "F.Cu" "B.Cu")
		(net "GND")
	)
	(via
		(at 270.601694 -120.833134)
		(size 0.508)
		(drill 0.254)
		(layers "F.Cu" "B.Cu")
		(net "GND")
	)
	(via
		(at 47.530512 -65.15989)
		(size 0.508)
		(drill 0.254)
		(layers "F.Cu" "B.Cu")
		(net "GND")
	)
	(via
		(at 407.949908 -274.999958)
		(size 0.4064)
		(drill 0.2032)
		(layers "F.Cu" "B.Cu")
		(net "GND")
	)
	(via
		(at 93.523054 -354.098098)
		(size 0.4572)
		(drill 0.254)
		(layers "F.Cu" "B.Cu")
		(net "GND")
	)
	(via
		(at 421.53332 -358.391714)
		(size 0.4572)
		(drill 0.254)
		(layers "F.Cu" "B.Cu")
		(net "GND")
	)
	(via
		(at 460.72679 -290.807648)
		(size 0.508)
		(drill 0.254)
		(layers "F.Cu" "B.Cu")
		(net "GND")
	)
	(via
		(at 201.214482 -338.84362)
		(size 0.508)
		(drill 0.254)
		(layers "F.Cu" "B.Cu")
		(net "GND")
	)
	(via
		(at 77.69987 -304.449734)
		(size 0.4064)
		(drill 0.2032)
		(layers "F.Cu" "B.Cu")
		(net "GND")
	)
	(via
		(at 178.792124 -343.073482)
		(size 0.4572)
		(drill 0.254)
		(layers "F.Cu" "B.Cu")
		(net "GND")
	)
	(via
		(at 96.4692 -197.612)
		(size 0.508)
		(drill 0.254)
		(layers "F.Cu" "B.Cu")
		(net "GND")
	)
	(via
		(at 107.980734 -237.918244)
		(size 0.508)
		(drill 0.254)
		(layers "F.Cu" "B.Cu")
		(net "GND")
	)
	(via
		(at 425.99991 -277.849838)
		(size 0.4064)
		(drill 0.2032)
		(layers "F.Cu" "B.Cu")
		(net "GND")
	)
	(via
		(at 180.64226 -350.977454)
		(size 0.4572)
		(drill 0.254)
		(layers "F.Cu" "B.Cu")
		(net "GND")
	)
	(via
		(at 313.224926 -299.224954)
		(size 0.4064)
		(drill 0.2032)
		(layers "F.Cu" "B.Cu")
		(net "GND")
	)
	(via
		(at 71.999856 -281.649932)
		(size 0.4064)
		(drill 0.2032)
		(layers "F.Cu" "B.Cu")
		(net "GND")
	)
	(via
		(at 125.709172 -287.51149)
		(size 0.508)
		(drill 0.254)
		(layers "F.Cu" "B.Cu")
		(net "GND")
	)
	(via
		(at 121.798334 -305.91887)
		(size 0.508)
		(drill 0.254)
		(layers "F.Cu" "B.Cu")
		(net "GND")
	)
	(via
		(at 185.725054 -284.974792)
		(size 0.4064)
		(drill 0.2032)
		(layers "F.Cu" "B.Cu")
		(net "GND")
	)
	(via
		(at 38.347904 -374.938544)
		(size 0.508)
		(drill 0.254)
		(layers "F.Cu" "B.Cu")
		(net "GND")
	)
	(via
		(at 116.03228 -354.074222)
		(size 0.4572)
		(drill 0.254)
		(layers "F.Cu" "B.Cu")
		(net "GND")
	)
	(via
		(at 193.799968 -310.149748)
		(size 0.4064)
		(drill 0.2032)
		(layers "F.Cu" "B.Cu")
		(net "GND")
	)
	(via
		(at 185.381392 -357.733854)
		(size 0.4064)
		(drill 0.2032)
		(layers "F.Cu" "B.Cu")
		(net "GND")
	)
	(via
		(at 196.998082 -142.418054)
		(size 0.508)
		(drill 0.254)
		(layers "F.Cu" "B.Cu")
		(net "GND")
	)
	(via
		(at 68.651374 -352.245422)
		(size 0.4572)
		(drill 0.254)
		(layers "F.Cu" "B.Cu")
		(net "GND")
	)
	(via
		(at 292.57117 -344.831162)
		(size 0.4572)
		(drill 0.254)
		(layers "F.Cu" "B.Cu")
		(net "GND")
	)
	(via
		(at 169.099992 -310.149748)
		(size 0.4064)
		(drill 0.2032)
		(layers "F.Cu" "B.Cu")
		(net "GND")
	)
	(via
		(at 187.624974 -288.774886)
		(size 0.4064)
		(drill 0.2032)
		(layers "F.Cu" "B.Cu")
		(net "GND")
	)
	(via
		(at 280.745692 -154.0256)
		(size 0.508)
		(drill 0.254)
		(layers "F.Cu" "B.Cu")
		(net "GND")
	)
	(via
		(at 77.947774 -403.34184)
		(size 0.508)
		(drill 0.254)
		(layers "F.Cu" "B.Cu")
		(net "GND")
	)
	(via
		(at 408.726132 -348.58579)
		(size 0.4064)
		(drill 0.2032)
		(layers "F.Cu" "B.Cu")
		(net "GND")
	)
	(via
		(at 135.620252 -57.076848)
		(size 0.508)
		(drill 0.254)
		(layers "F.Cu" "B.Cu")
		(net "GND")
	)
	(via
		(at 44.58208 -58.873644)
		(size 0.508)
		(drill 0.254)
		(layers "F.Cu" "B.Cu")
		(net "GND")
	)
	(via
		(at 292.57117 -350.977454)
		(size 0.4572)
		(drill 0.254)
		(layers "F.Cu" "B.Cu")
		(net "GND")
	)
	(via
		(at 74.374756 -298.27474)
		(size 0.4064)
		(drill 0.2032)
		(layers "F.Cu" "B.Cu")
		(net "GND")
	)
	(via
		(at 341.916004 -342.439498)
		(size 0.4064)
		(drill 0.2032)
		(layers "F.Cu" "B.Cu")
		(net "GND")
	)
	(via
		(at 196.18706 -343.073482)
		(size 0.4572)
		(drill 0.254)
		(layers "F.Cu" "B.Cu")
		(net "GND")
	)
	(via
		(at 418.927788 -384.041904)
		(size 0.508)
		(drill 0.254)
		(layers "F.Cu" "B.Cu")
		(net "GND")
	)
	(via
		(at 212.931248 -60.099194)
		(size 0.508)
		(drill 0.254)
		(layers "F.Cu" "B.Cu")
		(net "GND")
	)
	(via
		(at 283.774896 -306.824888)
		(size 0.4064)
		(drill 0.2032)
		(layers "F.Cu" "B.Cu")
		(net "GND")
	)
	(via
		(at 422.548304 -121.83491)
		(size 0.508)
		(drill 0.254)
		(layers "F.Cu" "B.Cu")
		(net "GND")
	)
	(via
		(at 346.327984 -371.038628)
		(size 0.508)
		(drill 0.254)
		(layers "F.Cu" "B.Cu")
		(net "GND")
	)
	(via
		(at 241.373914 -220.02496)
		(size 0.508)
		(drill 0.254)
		(layers "F.Cu" "B.Cu")
		(net "GND")
	)
	(via
		(at 425.901104 -341.805514)
		(size 0.4572)
		(drill 0.254)
		(layers "F.Cu" "B.Cu")
		(net "GND")
	)
	(via
		(at 101.884734 -237.918244)
		(size 0.508)
		(drill 0.254)
		(layers "F.Cu" "B.Cu")
		(net "GND")
	)
	(via
		(at 358.369362 -143.051276)
		(size 0.508)
		(drill 0.254)
		(layers "F.Cu" "B.Cu")
		(net "GND")
	)
	(via
		(at 45.87494 -299.224954)
		(size 0.4064)
		(drill 0.2032)
		(layers "F.Cu" "B.Cu")
		(net "GND")
	)
	(via
		(at 194.749928 -314.899802)
		(size 0.4064)
		(drill 0.2032)
		(layers "F.Cu" "B.Cu")
		(net "GND")
	)
	(via
		(at 169.574972 -300.174914)
		(size 0.4064)
		(drill 0.2032)
		(layers "F.Cu" "B.Cu")
		(net "GND")
	)
	(via
		(at 297.074844 -291.624766)
		(size 0.4064)
		(drill 0.2032)
		(layers "F.Cu" "B.Cu")
		(net "GND")
	)
	(via
		(at 318.523112 -347.951806)
		(size 0.4572)
		(drill 0.254)
		(layers "F.Cu" "B.Cu")
		(net "GND")
	)
	(via
		(at 188.099954 -312.999882)
		(size 0.4064)
		(drill 0.2032)
		(layers "F.Cu" "B.Cu")
		(net "GND")
	)
	(via
		(at 169.099992 -312.999882)
		(size 0.4064)
		(drill 0.2032)
		(layers "F.Cu" "B.Cu")
		(net "GND")
	)
	(via
		(at 409.948888 -29.589984)
		(size 0.508)
		(drill 0.254)
		(layers "F.Cu" "B.Cu")
		(net "GND")
	)
	(via
		(at 281.804872 -105.365042)
		(size 0.508)
		(drill 0.254)
		(layers "F.Cu" "B.Cu")
		(net "GND")
	)
	(via
		(at 368.239294 -28.05303)
		(size 0.508)
		(drill 0.254)
		(layers "F.Cu" "B.Cu")
		(net "GND")
	)
	(via
		(at 307.049932 -309.199788)
		(size 0.4064)
		(drill 0.2032)
		(layers "F.Cu" "B.Cu")
		(net "GND")
	)
	(via
		(at 37.799772 -309.199788)
		(size 0.4064)
		(drill 0.2032)
		(layers "F.Cu" "B.Cu")
		(net "GND")
	)
	(via
		(at 61.648848 -33.19018)
		(size 0.508)
		(drill 0.254)
		(layers "F.Cu" "B.Cu")
		(net "GND")
	)
	(via
		(at 301.944786 -143.655796)
		(size 0.508)
		(drill 0.254)
		(layers "F.Cu" "B.Cu")
		(net "GND")
	)
	(via
		(at 241.255042 -126.995428)
		(size 0.508)
		(drill 0.254)
		(layers "F.Cu" "B.Cu")
		(net "GND")
	)
	(via
		(at 75.74788 -377.738386)
		(size 0.508)
		(drill 0.254)
		(layers "F.Cu" "B.Cu")
		(net "GND")
	)
	(via
		(at 38.401752 -111.175546)
		(size 0.508)
		(drill 0.254)
		(layers "F.Cu" "B.Cu")
		(net "GND")
	)
	(via
		(at 312.274712 -303.974754)
		(size 0.4064)
		(drill 0.2032)
		(layers "F.Cu" "B.Cu")
		(net "GND")
	)
	(via
		(at 192.849754 -274.999958)
		(size 0.4064)
		(drill 0.2032)
		(layers "F.Cu" "B.Cu")
		(net "GND")
	)
	(via
		(at 188.366908 -123.635008)
		(size 0.508)
		(drill 0.254)
		(layers "F.Cu" "B.Cu")
		(net "GND")
	)
	(via
		(at 403.199854 -312.999882)
		(size 0.4064)
		(drill 0.2032)
		(layers "F.Cu" "B.Cu")
		(net "GND")
	)
	(via
		(at 286.149796 -314.899802)
		(size 0.4064)
		(drill 0.2032)
		(layers "F.Cu" "B.Cu")
		(net "GND")
	)
	(via
		(at 233.572558 -59.399932)
		(size 0.508)
		(drill 0.254)
		(layers "F.Cu" "B.Cu")
		(net "GND")
	)
	(via
		(at 277.251668 -124.154946)
		(size 0.508)
		(drill 0.254)
		(layers "F.Cu" "B.Cu")
		(net "GND")
	)
	(via
		(at 395.12494 -303.024794)
		(size 0.4064)
		(drill 0.2032)
		(layers "F.Cu" "B.Cu")
		(net "GND")
	)
	(via
		(at 123.372372 -285.953454)
		(size 0.508)
		(drill 0.254)
		(layers "F.Cu" "B.Cu")
		(net "GND")
	)
	(via
		(at 277.02637 -344.831162)
		(size 0.4572)
		(drill 0.254)
		(layers "F.Cu" "B.Cu")
		(net "GND")
	)
	(via
		(at 182.39994 -274.049744)
		(size 0.4064)
		(drill 0.2032)
		(layers "F.Cu" "B.Cu")
		(net "GND")
	)
	(via
		(at 293.74973 -311.099962)
		(size 0.4064)
		(drill 0.2032)
		(layers "F.Cu" "B.Cu")
		(net "GND")
	)
	(via
		(at 415.3154 -344.831162)
		(size 0.4572)
		(drill 0.254)
		(layers "F.Cu" "B.Cu")
		(net "GND")
	)
	(via
		(at 302.327818 -377.341892)
		(size 0.508)
		(drill 0.254)
		(layers "F.Cu" "B.Cu")
		(net "GND")
	)
	(via
		(at 366.938814 -23.880318)
		(size 0.508)
		(drill 0.254)
		(layers "F.Cu" "B.Cu")
		(net "GND")
	)
	(via
		(at 431.840386 -144.224502)
		(size 0.508)
		(drill 0.254)
		(layers "F.Cu" "B.Cu")
		(net "GND")
	)
	(via
		(at 16.280892 -25.990042)
		(size 0.508)
		(drill 0.254)
		(layers "F.Cu" "B.Cu")
		(net "GND")
	)
	(via
		(at 4.562856 -190.321692)
		(size 0.508)
		(drill 0.254)
		(layers "F.Cu" "B.Cu")
		(net "GND")
	)
	(via
		(at 171.31538 -349.219774)
		(size 0.4572)
		(drill 0.254)
		(layers "F.Cu" "B.Cu")
		(net "GND")
	)
	(via
		(at 97.908618 -243.8273)
		(size 0.508)
		(drill 0.254)
		(layers "F.Cu" "B.Cu")
		(net "GND")
	)
	(via
		(at 278.074882 -285.924752)
		(size 0.4064)
		(drill 0.2032)
		(layers "F.Cu" "B.Cu")
		(net "GND")
	)
	(via
		(at 125.35916 -352.245422)
		(size 0.4572)
		(drill 0.254)
		(layers "F.Cu" "B.Cu")
		(net "GND")
	)
	(via
		(at 391.2743 -342.439498)
		(size 0.4064)
		(drill 0.2032)
		(layers "F.Cu" "B.Cu")
		(net "GND")
	)
	(via
		(at 97.654618 -23.880318)
		(size 0.508)
		(drill 0.254)
		(layers "F.Cu" "B.Cu")
		(net "GND")
	)
	(via
		(at 388.127748 -406.141936)
		(size 0.508)
		(drill 0.254)
		(layers "F.Cu" "B.Cu")
		(net "GND")
	)
	(via
		(at 422.199816 -289.249866)
		(size 0.4064)
		(drill 0.2032)
		(layers "F.Cu" "B.Cu")
		(net "GND")
	)
	(via
		(at 77.978254 -354.098098)
		(size 0.4572)
		(drill 0.254)
		(layers "F.Cu" "B.Cu")
		(net "GND")
	)
	(via
		(at 148.700998 -31.390336)
		(size 0.508)
		(drill 0.254)
		(layers "F.Cu" "B.Cu")
		(net "GND")
	)
	(via
		(at 76.74991 -283.549852)
		(size 0.4064)
		(drill 0.2032)
		(layers "F.Cu" "B.Cu")
		(net "GND")
	)
	(via
		(at 127.97028 -287.51149)
		(size 0.508)
		(drill 0.254)
		(layers "F.Cu" "B.Cu")
		(net "GND")
	)
	(via
		(at 163.41344 -33.459674)
		(size 0.508)
		(drill 0.254)
		(layers "F.Cu" "B.Cu")
		(net "GND")
	)
	(via
		(at 285.052262 -100.64496)
		(size 0.508)
		(drill 0.254)
		(layers "F.Cu" "B.Cu")
		(net "GND")
	)
	(via
		(at 283.24429 -344.831162)
		(size 0.4572)
		(drill 0.254)
		(layers "F.Cu" "B.Cu")
		(net "GND")
	)
	(via
		(at 133.423152 -132.620766)
		(size 0.508)
		(drill 0.254)
		(layers "F.Cu" "B.Cu")
		(net "GND")
	)
	(via
		(at 2.273808 -284.818582)
		(size 0.508)
		(drill 0.254)
		(layers "F.Cu" "B.Cu")
		(net "GND")
	)
	(via
		(at 374.927876 -378.94006)
		(size 0.508)
		(drill 0.254)
		(layers "F.Cu" "B.Cu")
		(net "GND")
	)
	(via
		(at 362.548932 -29.589984)
		(size 0.508)
		(drill 0.254)
		(layers "F.Cu" "B.Cu")
		(net "GND")
	)
	(via
		(at 250.931426 -6.292342)
		(size 0.508)
		(drill 0.254)
		(layers "F.Cu" "B.Cu")
		(net "GND")
	)
	(via
		(at 161.975038 -282.124912)
		(size 0.4064)
		(drill 0.2032)
		(layers "F.Cu" "B.Cu")
		(net "GND")
	)
	(via
		(at 315.740288 -120.30456)
		(size 0.508)
		(drill 0.254)
		(layers "F.Cu" "B.Cu")
		(net "GND")
	)
	(via
		(at 221.415102 -45.88891)
		(size 0.508)
		(drill 0.254)
		(layers "F.Cu" "B.Cu")
		(net "GND")
	)
	(via
		(at 183.766714 -120.035066)
		(size 0.508)
		(drill 0.254)
		(layers "F.Cu" "B.Cu")
		(net "GND")
	)
	(via
		(at 65.542414 -350.977454)
		(size 0.4572)
		(drill 0.254)
		(layers "F.Cu" "B.Cu")
		(net "GND")
	)
	(via
		(at 453.615044 -43.85691)
		(size 0.508)
		(drill 0.254)
		(layers "F.Cu" "B.Cu")
		(net "GND")
	)
	(via
		(at 25.352756 -355.366066)
		(size 0.4572)
		(drill 0.254)
		(layers "F.Cu" "B.Cu")
		(net "GND")
	)
	(via
		(at 91.902026 -58.731404)
		(size 0.508)
		(drill 0.254)
		(layers "F.Cu" "B.Cu")
		(net "GND")
	)
	(via
		(at 116.910358 -277.639272)
		(size 0.508)
		(drill 0.254)
		(layers "F.Cu" "B.Cu")
		(net "GND")
	)
	(via
		(at 63.788544 -31.642304)
		(size 0.508)
		(drill 0.254)
		(layers "F.Cu" "B.Cu")
		(net "GND")
	)
	(via
		(at 70.671182 -32.911796)
		(size 0.508)
		(drill 0.254)
		(layers "F.Cu" "B.Cu")
		(net "GND")
	)
	(via
		(at 271.899888 -314.899802)
		(size 0.4064)
		(drill 0.2032)
		(layers "F.Cu" "B.Cu")
		(net "GND")
	)
	(via
		(at 378.83846 -357.75773)
		(size 0.4064)
		(drill 0.2032)
		(layers "F.Cu" "B.Cu")
		(net "GND")
	)
	(via
		(at 182.87492 -284.974792)
		(size 0.4064)
		(drill 0.2032)
		(layers "F.Cu" "B.Cu")
		(net "GND")
	)
	(via
		(at 112.225328 -159.053022)
		(size 0.508)
		(drill 0.254)
		(layers "F.Cu" "B.Cu")
		(net "GND")
	)
	(via
		(at 268.958314 -349.219774)
		(size 0.4572)
		(drill 0.254)
		(layers "F.Cu" "B.Cu")
		(net "GND")
	)
	(via
		(at 387.050026 -304.449734)
		(size 0.4064)
		(drill 0.2032)
		(layers "F.Cu" "B.Cu")
		(net "GND")
	)
	(via
		(at 230.896414 -286.087312)
		(size 0.508)
		(drill 0.254)
		(layers "F.Cu" "B.Cu")
		(net "GND")
	)
	(via
		(at 270.601694 -100.375466)
		(size 0.508)
		(drill 0.254)
		(layers "F.Cu" "B.Cu")
		(net "GND")
	)
	(via
		(at 422.792144 -357.123746)
		(size 0.4572)
		(drill 0.254)
		(layers "F.Cu" "B.Cu")
		(net "GND")
	)
	(via
		(at 60.599828 -278.799798)
		(size 0.4064)
		(drill 0.2032)
		(layers "F.Cu" "B.Cu")
		(net "GND")
	)
	(via
		(at 362.204 -191.262)
		(size 0.508)
		(drill 0.254)
		(layers "F.Cu" "B.Cu")
		(net "GND")
	)
	(via
		(at 386.575046 -288.774886)
		(size 0.4064)
		(drill 0.2032)
		(layers "F.Cu" "B.Cu")
		(net "GND")
	)
	(via
		(at 108.241338 -38.49116)
		(size 0.508)
		(drill 0.254)
		(layers "F.Cu" "B.Cu")
		(net "GND")
	)
	(via
		(at 281.874722 -290.674806)
		(size 0.4064)
		(drill 0.2032)
		(layers "F.Cu" "B.Cu")
		(net "GND")
	)
	(via
		(at 100.932996 -87.487506)
		(size 0.508)
		(drill 0.254)
		(layers "F.Cu" "B.Cu")
		(net "GND")
	)
	(via
		(at 22.581362 -33.459674)
		(size 0.508)
		(drill 0.254)
		(layers "F.Cu" "B.Cu")
		(net "GND")
	)
	(via
		(at 115.34775 -401.040092)
		(size 0.4572)
		(drill 0.254)
		(layers "F.Cu" "B.Cu")
		(net "GND")
	)
	(via
		(at 276.174708 -284.024832)
		(size 0.4064)
		(drill 0.2032)
		(layers "F.Cu" "B.Cu")
		(net "GND")
	)
	(via
		(at 64.399922 -314.899802)
		(size 0.4064)
		(drill 0.2032)
		(layers "F.Cu" "B.Cu")
		(net "GND")
	)
	(via
		(at 62.804802 -345.465146)
		(size 0.4064)
		(drill 0.2032)
		(layers "F.Cu" "B.Cu")
		(net "GND")
	)
	(via
		(at 318.523112 -346.09913)
		(size 0.4572)
		(drill 0.254)
		(layers "F.Cu" "B.Cu")
		(net "GND")
	)
	(via
		(at 344.653616 -357.123746)
		(size 0.4572)
		(drill 0.254)
		(layers "F.Cu" "B.Cu")
		(net "GND")
	)
	(via
		(at 197.445884 -346.09913)
		(size 0.4572)
		(drill 0.254)
		(layers "F.Cu" "B.Cu")
		(net "GND")
	)
	(via
		(at 270.949928 -312.049922)
		(size 0.4064)
		(drill 0.2032)
		(layers "F.Cu" "B.Cu")
		(net "GND")
	)
	(via
		(at 403.199854 -313.949842)
		(size 0.4064)
		(drill 0.2032)
		(layers "F.Cu" "B.Cu")
		(net "GND")
	)
	(via
		(at 37.324792 -277.374858)
		(size 0.4064)
		(drill 0.2032)
		(layers "F.Cu" "B.Cu")
		(net "GND")
	)
	(via
		(at 222.154496 -310.315356)
		(size 0.508)
		(drill 0.254)
		(layers "F.Cu" "B.Cu")
		(net "GND")
	)
	(via
		(at 161.975038 -288.774886)
		(size 0.4064)
		(drill 0.2032)
		(layers "F.Cu" "B.Cu")
		(net "GND")
	)
	(via
		(at 77.69987 -312.999882)
		(size 0.4064)
		(drill 0.2032)
		(layers "F.Cu" "B.Cu")
		(net "GND")
	)
	(via
		(at 231.286812 -139.747244)
		(size 0.508)
		(drill 0.254)
		(layers "F.Cu" "B.Cu")
		(net "GND")
	)
	(via
		(at 227.698046 -139.919202)
		(size 0.508)
		(drill 0.254)
		(layers "F.Cu" "B.Cu")
		(net "GND")
	)
	(via
		(at 172.547788 -403.738588)
		(size 0.508)
		(drill 0.254)
		(layers "F.Cu" "B.Cu")
		(net "GND")
	)
	(via
		(at 398.971008 -341.781638)
		(size 0.4572)
		(drill 0.254)
		(layers "F.Cu" "B.Cu")
		(net "GND")
	)
	(via
		(at 159.599884 -301.599854)
		(size 0.4064)
		(drill 0.2032)
		(layers "F.Cu" "B.Cu")
		(net "GND")
	)
	(via
		(at 299.866812 -143.955008)
		(size 0.508)
		(drill 0.254)
		(layers "F.Cu" "B.Cu")
		(net "GND")
	)
	(via
		(at 163.286948 -139.731242)
		(size 0.508)
		(drill 0.254)
		(layers "F.Cu" "B.Cu")
		(net "GND")
	)
	(via
		(at 414.548828 -31.390082)
		(size 0.508)
		(drill 0.254)
		(layers "F.Cu" "B.Cu")
		(net "GND")
	)
	(via
		(at 84.808314 -136.373362)
		(size 0.508)
		(drill 0.254)
		(layers "F.Cu" "B.Cu")
		(net "GND")
	)
	(via
		(at 290.89985 -273.099784)
		(size 0.4064)
		(drill 0.2032)
		(layers "F.Cu" "B.Cu")
		(net "GND")
	)
	(via
		(at 277.251668 -125.955044)
		(size 0.508)
		(drill 0.254)
		(layers "F.Cu" "B.Cu")
		(net "GND")
	)
	(via
		(at 54.424834 -303.974754)
		(size 0.4064)
		(drill 0.2032)
		(layers "F.Cu" "B.Cu")
		(net "GND")
	)
	(via
		(at 303.89068 -119.414544)
		(size 0.508)
		(drill 0.254)
		(layers "F.Cu" "B.Cu")
		(net "GND")
	)
	(via
		(at 329.71994 -56.441848)
		(size 0.508)
		(drill 0.254)
		(layers "F.Cu" "B.Cu")
		(net "GND")
	)
	(via
		(at 84.54771 -376.241818)
		(size 0.508)
		(drill 0.254)
		(layers "F.Cu" "B.Cu")
		(net "GND")
	)
	(via
		(at 278.656542 -354.732082)
		(size 0.4064)
		(drill 0.2032)
		(layers "F.Cu" "B.Cu")
		(net "GND")
	)
	(via
		(at 117.209316 -88.297766)
		(size 0.508)
		(drill 0.254)
		(layers "F.Cu" "B.Cu")
		(net "GND")
	)
	(via
		(at 7.29996 -62.812168)
		(size 0.508)
		(drill 0.254)
		(layers "F.Cu" "B.Cu")
		(net "GND")
	)
	(via
		(at 191.425068 -298.27474)
		(size 0.4064)
		(drill 0.2032)
		(layers "F.Cu" "B.Cu")
		(net "GND")
	)
	(via
		(at 251.720096 -56.441848)
		(size 0.508)
		(drill 0.254)
		(layers "F.Cu" "B.Cu")
		(net "GND")
	)
	(via
		(at 395.693646 -108.279946)
		(size 0.508)
		(drill 0.254)
		(layers "F.Cu" "B.Cu")
		(net "GND")
	)
	(via
		(at 52.949602 -24.503888)
		(size 0.508)
		(drill 0.254)
		(layers "F.Cu" "B.Cu")
		(net "GND")
	)
	(via
		(at 174.325026 -284.974792)
		(size 0.4064)
		(drill 0.2032)
		(layers "F.Cu" "B.Cu")
		(net "GND")
	)
	(via
		(at 178.792124 -344.831162)
		(size 0.4572)
		(drill 0.254)
		(layers "F.Cu" "B.Cu")
		(net "GND")
	)
	(via
		(at 121.576592 -268.096492)
		(size 0.508)
		(drill 0.254)
		(layers "F.Cu" "B.Cu")
		(net "GND")
	)
	(via
		(at 341.544656 -350.977454)
		(size 0.4572)
		(drill 0.254)
		(layers "F.Cu" "B.Cu")
		(net "GND")
	)
	(via
		(at 51.574954 -300.174914)
		(size 0.4064)
		(drill 0.2032)
		(layers "F.Cu" "B.Cu")
		(net "GND")
	)
	(via
		(at 339.728048 -410.041852)
		(size 0.508)
		(drill 0.254)
		(layers "F.Cu" "B.Cu")
		(net "GND")
	)
	(via
		(at 403.338792 -358.391714)
		(size 0.4572)
		(drill 0.254)
		(layers "F.Cu" "B.Cu")
		(net "GND")
	)
	(via
		(at 428.84979 -281.649932)
		(size 0.4064)
		(drill 0.2032)
		(layers "F.Cu" "B.Cu")
		(net "GND")
	)
	(via
		(at 296.901108 -109.481366)
		(size 0.508)
		(drill 0.254)
		(layers "F.Cu" "B.Cu")
		(net "GND")
	)
	(via
		(at 192.850008 -315.849762)
		(size 0.4064)
		(drill 0.2032)
		(layers "F.Cu" "B.Cu")
		(net "GND")
	)
	(via
		(at 64.874902 -285.924752)
		(size 0.4064)
		(drill 0.2032)
		(layers "F.Cu" "B.Cu")
		(net "GND")
	)
	(via
		(at 133.427216 -354.098098)
		(size 0.4572)
		(drill 0.254)
		(layers "F.Cu" "B.Cu")
		(net "GND")
	)
	(via
		(at 56.324754 -284.024832)
		(size 0.4064)
		(drill 0.2032)
		(layers "F.Cu" "B.Cu")
		(net "GND")
	)
	(via
		(at 332.217776 -346.09913)
		(size 0.4572)
		(drill 0.254)
		(layers "F.Cu" "B.Cu")
		(net "GND")
	)
	(via
		(at 446.072768 -253.017528)
		(size 0.508)
		(drill 0.254)
		(layers "F.Cu" "B.Cu")
		(net "GND")
	)
	(via
		(at 14.7955 -312.495184)
		(size 0.508)
		(drill 0.254)
		(layers "F.Cu" "B.Cu")
		(net "GND")
	)
	(via
		(at 423.15003 -303.499774)
		(size 0.4064)
		(drill 0.2032)
		(layers "F.Cu" "B.Cu")
		(net "GND")
	)
	(via
		(at 42.747946 -371.038628)
		(size 0.508)
		(drill 0.254)
		(layers "F.Cu" "B.Cu")
		(net "GND")
	)
	(via
		(at 114.779806 -330.471018)
		(size 0.508)
		(drill 0.254)
		(layers "F.Cu" "B.Cu")
		(net "GND")
	)
	(via
		(at 235.495084 -337.463638)
		(size 0.508)
		(drill 0.254)
		(layers "F.Cu" "B.Cu")
		(net "GND")
	)
	(via
		(at 239.73155 -147.630388)
		(size 0.508)
		(drill 0.254)
		(layers "F.Cu" "B.Cu")
		(net "GND")
	)
	(via
		(at 41.599866 -318.699896)
		(size 0.4064)
		(drill 0.2032)
		(layers "F.Cu" "B.Cu")
		(net "GND")
	)
	(via
		(at 238.994696 -83.555586)
		(size 0.508)
		(drill 0.254)
		(layers "F.Cu" "B.Cu")
		(net "GND")
	)
	(via
		(at 72.267064 -121.83491)
		(size 0.508)
		(drill 0.254)
		(layers "F.Cu" "B.Cu")
		(net "GND")
	)
	(via
		(at 424.09999 -273.099784)
		(size 0.4064)
		(drill 0.2032)
		(layers "F.Cu" "B.Cu")
		(net "GND")
	)
	(via
		(at 348.527878 -372.342156)
		(size 0.508)
		(drill 0.254)
		(layers "F.Cu" "B.Cu")
		(net "GND")
	)
	(via
		(at 142.293594 -292.732714)
		(size 0.508)
		(drill 0.254)
		(layers "F.Cu" "B.Cu")
		(net "GND")
	)
	(via
		(at 394.17498 -303.024794)
		(size 0.4064)
		(drill 0.2032)
		(layers "F.Cu" "B.Cu")
		(net "GND")
	)
	(via
		(at 103.685848 -353.081082)
		(size 0.508)
		(drill 0.254)
		(layers "F.Cu" "B.Cu")
		(net "GND")
	)
	(via
		(at 318.654938 -33.19018)
		(size 0.508)
		(drill 0.254)
		(layers "F.Cu" "B.Cu")
		(net "GND")
	)
	(via
		(at 409.948888 -25.990042)
		(size 0.508)
		(drill 0.254)
		(layers "F.Cu" "B.Cu")
		(net "GND")
	)
	(via
		(at 38.749986 -312.049922)
		(size 0.4064)
		(drill 0.2032)
		(layers "F.Cu" "B.Cu")
		(net "GND")
	)
	(via
		(at 389.424926 -293.52494)
		(size 0.4064)
		(drill 0.2032)
		(layers "F.Cu" "B.Cu")
		(net "GND")
	)
	(via
		(at 198.815198 -60.601606)
		(size 0.508)
		(drill 0.254)
		(layers "F.Cu" "B.Cu")
		(net "GND")
	)
	(via
		(at 391.799826 -312.999882)
		(size 0.4064)
		(drill 0.2032)
		(layers "F.Cu" "B.Cu")
		(net "GND")
	)
	(via
		(at 434.327808 -371.038628)
		(size 0.508)
		(drill 0.254)
		(layers "F.Cu" "B.Cu")
		(net "GND")
	)
	(via
		(at 77.947774 -398.24025)
		(size 0.508)
		(drill 0.254)
		(layers "F.Cu" "B.Cu")
		(net "GND")
	)
	(via
		(at 167.849804 -144.250156)
		(size 0.508)
		(drill 0.254)
		(layers "F.Cu" "B.Cu")
		(net "GND")
	)
	(via
		(at 400.229832 -346.09913)
		(size 0.4572)
		(drill 0.254)
		(layers "F.Cu" "B.Cu")
		(net "GND")
	)
	(via
		(at 423.15003 -310.149748)
		(size 0.4064)
		(drill 0.2032)
		(layers "F.Cu" "B.Cu")
		(net "GND")
	)
	(via
		(at 307.524912 -296.37482)
		(size 0.4064)
		(drill 0.2032)
		(layers "F.Cu" "B.Cu")
		(net "GND")
	)
	(via
		(at 388.474966 -282.124912)
		(size 0.4064)
		(drill 0.2032)
		(layers "F.Cu" "B.Cu")
		(net "GND")
	)
	(via
		(at 306.099718 -305.399948)
		(size 0.4064)
		(drill 0.2032)
		(layers "F.Cu" "B.Cu")
		(net "GND")
	)
	(via
		(at 229.069392 -78.176628)
		(size 0.508)
		(drill 0.254)
		(layers "F.Cu" "B.Cu")
		(net "GND")
	)
	(via
		(at 435.227984 -341.805514)
		(size 0.4572)
		(drill 0.254)
		(layers "F.Cu" "B.Cu")
		(net "GND")
	)
	(via
		(at 89.15527 -352.245422)
		(size 0.4572)
		(drill 0.254)
		(layers "F.Cu" "B.Cu")
		(net "GND")
	)
	(via
		(at 384.059684 -135.095488)
		(size 0.508)
		(drill 0.254)
		(layers "F.Cu" "B.Cu")
		(net "GND")
	)
	(via
		(at 42.28084 -33.19018)
		(size 0.508)
		(drill 0.254)
		(layers "F.Cu" "B.Cu")
		(net "GND")
	)
	(via
		(at 271.424908 -298.27474)
		(size 0.4064)
		(drill 0.2032)
		(layers "F.Cu" "B.Cu")
		(net "GND")
	)
	(via
		(at 113.677446 -306.607718)
		(size 0.508)
		(drill 0.254)
		(layers "F.Cu" "B.Cu")
		(net "GND")
	)
	(via
		(at 239.73155 -150.16861)
		(size 0.508)
		(drill 0.254)
		(layers "F.Cu" "B.Cu")
		(net "GND")
	)
	(via
		(at 112.92332 -350.977454)
		(size 0.4572)
		(drill 0.254)
		(layers "F.Cu" "B.Cu")
		(net "GND")
	)
	(via
		(at 47.092108 -104.793034)
		(size 0.508)
		(drill 0.254)
		(layers "F.Cu" "B.Cu")
		(net "GND")
	)
	(via
		(at 384.674872 -278.324818)
		(size 0.4064)
		(drill 0.2032)
		(layers "F.Cu" "B.Cu")
		(net "GND")
	)
	(via
		(at 365.99622 -160.83407)
		(size 0.508)
		(drill 0.254)
		(layers "F.Cu" "B.Cu")
		(net "GND")
	)
	(via
		(at 431.209704 -303.024794)
		(size 0.4064)
		(drill 0.2032)
		(layers "F.Cu" "B.Cu")
		(net "GND")
	)
	(via
		(at 339.20938 -329.564492)
		(size 0.508)
		(drill 0.254)
		(layers "F.Cu" "B.Cu")
		(net "GND")
	)
	(via
		(at 84.54771 -397.140176)
		(size 0.508)
		(drill 0.254)
		(layers "F.Cu" "B.Cu")
		(net "GND")
	)
	(via
		(at 7.417054 -38.519354)
		(size 0.508)
		(drill 0.254)
		(layers "F.Cu" "B.Cu")
		(net "GND")
	)
	(via
		(at 374.927876 -403.738588)
		(size 0.508)
		(drill 0.254)
		(layers "F.Cu" "B.Cu")
		(net "GND")
	)
	(via
		(at 183.82488 -284.974792)
		(size 0.4064)
		(drill 0.2032)
		(layers "F.Cu" "B.Cu")
		(net "GND")
	)
	(via
		(at 34.00298 -293.494714)
		(size 0.508)
		(drill 0.254)
		(layers "F.Cu" "B.Cu")
		(net "GND")
	)
	(via
		(at 268.569186 -100.92309)
		(size 0.508)
		(drill 0.254)
		(layers "F.Cu" "B.Cu")
		(net "GND")
	)
	(via
		(at 281.523948 -26.319734)
		(size 0.508)
		(drill 0.254)
		(layers "F.Cu" "B.Cu")
		(net "GND")
	)
	(via
		(at 156.275024 -279.274778)
		(size 0.4064)
		(drill 0.2032)
		(layers "F.Cu" "B.Cu")
		(net "GND")
	)
	(via
		(at 240.568226 -320.02349)
		(size 0.508)
		(drill 0.254)
		(layers "F.Cu" "B.Cu")
		(net "GND")
	)
	(via
		(at 331.663294 -228.386894)
		(size 0.4572)
		(drill 0.254)
		(layers "F.Cu" "B.Cu")
		(net "GND")
	)
	(via
		(at 394.17498 -292.57498)
		(size 0.4064)
		(drill 0.2032)
		(layers "F.Cu" "B.Cu")
		(net "GND")
	)
	(via
		(at 308.949852 -315.849762)
		(size 0.4064)
		(drill 0.2032)
		(layers "F.Cu" "B.Cu")
		(net "GND")
	)
	(via
		(at 160.931352 -60.099194)
		(size 0.508)
		(drill 0.254)
		(layers "F.Cu" "B.Cu")
		(net "GND")
	)
	(via
		(at 239.935512 -235.737654)
		(size 0.508)
		(drill 0.254)
		(layers "F.Cu" "B.Cu")
		(net "GND")
	)
	(via
		(at 5.660136 -372.011448)
		(size 0.508)
		(drill 0.254)
		(layers "F.Cu" "B.Cu")
		(net "GND")
	)
	(via
		(at 258.993386 -397.705834)
		(size 0.508)
		(drill 0.254)
		(layers "F.Cu" "B.Cu")
		(net "GND")
	)
	(via
		(at 415.3154 -350.977454)
		(size 0.4572)
		(drill 0.254)
		(layers "F.Cu" "B.Cu")
		(net "GND")
	)
	(via
		(at 172.424852 -300.174914)
		(size 0.4064)
		(drill 0.2032)
		(layers "F.Cu" "B.Cu")
		(net "GND")
	)
	(via
		(at 126.347728 -378.83846)
		(size 0.508)
		(drill 0.254)
		(layers "F.Cu" "B.Cu")
		(net "GND")
	)
	(via
		(at 430.488852 -354.732082)
		(size 0.4064)
		(drill 0.2032)
		(layers "F.Cu" "B.Cu")
		(net "GND")
	)
	(via
		(at 77.69987 -318.699896)
		(size 0.4064)
		(drill 0.2032)
		(layers "F.Cu" "B.Cu")
		(net "GND")
	)
	(via
		(at 426.47489 -297.32478)
		(size 0.4064)
		(drill 0.2032)
		(layers "F.Cu" "B.Cu")
		(net "GND")
	)
	(via
		(at 384.674872 -300.17466)
		(size 0.4064)
		(drill 0.2032)
		(layers "F.Cu" "B.Cu")
		(net "GND")
	)
	(via
		(at 157.224984 -292.57498)
		(size 0.4064)
		(drill 0.2032)
		(layers "F.Cu" "B.Cu")
		(net "GND")
	)
	(via
		(at 237.849918 -315.311282)
		(size 0.508)
		(drill 0.254)
		(layers "F.Cu" "B.Cu")
		(net "GND")
	)
	(via
		(at 64.874902 -291.624766)
		(size 0.4064)
		(drill 0.2032)
		(layers "F.Cu" "B.Cu")
		(net "GND")
	)
	(via
		(at 185.381392 -342.439498)
		(size 0.4064)
		(drill 0.2032)
		(layers "F.Cu" "B.Cu")
		(net "GND")
	)
	(via
		(at 319.848738 -34.990024)
		(size 0.508)
		(drill 0.254)
		(layers "F.Cu" "B.Cu")
		(net "GND")
	)
	(via
		(at 453.524112 -103.69296)
		(size 0.508)
		(drill 0.254)
		(layers "F.Cu" "B.Cu")
		(net "GND")
	)
	(via
		(at 197.125082 -301.124874)
		(size 0.4064)
		(drill 0.2032)
		(layers "F.Cu" "B.Cu")
		(net "GND")
	)
	(via
		(at 48.391572 -100.64496)
		(size 0.508)
		(drill 0.254)
		(layers "F.Cu" "B.Cu")
		(net "GND")
	)
	(via
		(at 269.333726 -103.975408)
		(size 0.508)
		(drill 0.254)
		(layers "F.Cu" "B.Cu")
		(net "GND")
	)
	(via
		(at 196.649848 -272.14957)
		(size 0.4064)
		(drill 0.2032)
		(layers "F.Cu" "B.Cu")
		(net "GND")
	)
	(via
		(at 189.597792 -348.58579)
		(size 0.4064)
		(drill 0.2032)
		(layers "F.Cu" "B.Cu")
		(net "GND")
	)
	(via
		(at 6.176264 -17.151858)
		(size 0.508)
		(drill 0.254)
		(layers "F.Cu" "B.Cu")
		(net "GND")
	)
	(via
		(at 332.589124 -342.439498)
		(size 0.4064)
		(drill 0.2032)
		(layers "F.Cu" "B.Cu")
		(net "GND")
	)
	(via
		(at 80.898238 -130.966718)
		(size 0.508)
		(drill 0.254)
		(layers "F.Cu" "B.Cu")
		(net "GND")
	)
	(via
		(at 227.852224 -278.379936)
		(size 0.508)
		(drill 0.254)
		(layers "F.Cu" "B.Cu")
		(net "GND")
	)
	(via
		(at 193.745104 -413.87141)
		(size 0.508)
		(drill 0.254)
		(layers "F.Cu" "B.Cu")
		(net "GND")
	)
	(via
		(at 291.32784 -407.638504)
		(size 0.508)
		(drill 0.254)
		(layers "F.Cu" "B.Cu")
		(net "GND")
	)
	(via
		(at 353.531424 -293.424102)
		(size 0.508)
		(drill 0.254)
		(layers "F.Cu" "B.Cu")
		(net "GND")
	)
	(via
		(at 362.578142 -245.267734)
		(size 0.508)
		(drill 0.254)
		(layers "F.Cu" "B.Cu")
		(net "GND")
	)
	(via
		(at 416.857942 -58.156094)
		(size 0.508)
		(drill 0.254)
		(layers "F.Cu" "B.Cu")
		(net "GND")
	)
	(via
		(at 250.173744 -131.960874)
		(size 0.508)
		(drill 0.254)
		(layers "F.Cu" "B.Cu")
		(net "GND")
	)
	(via
		(at 136.861804 -160.8963)
		(size 0.508)
		(drill 0.254)
		(layers "F.Cu" "B.Cu")
		(net "GND")
	)
	(via
		(at 341.927942 -383.940304)
		(size 0.508)
		(drill 0.254)
		(layers "F.Cu" "B.Cu")
		(net "GND")
	)
	(via
		(at 291.32784 -401.040092)
		(size 0.508)
		(drill 0.254)
		(layers "F.Cu" "B.Cu")
		(net "GND")
	)
	(via
		(at 123.506992 -284.333188)
		(size 0.49022)
		(drill 0.254)
		(layers "F.Cu" "B.Cu")
		(net "GND")
	)
	(via
		(at 302.327818 -404.838662)
		(size 0.508)
		(drill 0.254)
		(layers "F.Cu" "B.Cu")
		(net "GND")
	)
	(via
		(at 66.774822 -285.924752)
		(size 0.4064)
		(drill 0.2032)
		(layers "F.Cu" "B.Cu")
		(net "GND")
	)
	(via
		(at 403.199854 -281.649932)
		(size 0.4064)
		(drill 0.2032)
		(layers "F.Cu" "B.Cu")
		(net "GND")
	)
	(via
		(at 0.818134 -82.492342)
		(size 0.508)
		(drill 0.254)
		(layers "F.Cu" "B.Cu")
		(net "GND")
	)
	(via
		(at 57.274968 -289.724846)
		(size 0.4064)
		(drill 0.2032)
		(layers "F.Cu" "B.Cu")
		(net "GND")
	)
	(via
		(at 183.649874 -109.244892)
		(size 0.508)
		(drill 0.254)
		(layers "F.Cu" "B.Cu")
		(net "GND")
	)
	(via
		(at 133.57352 -73.20026)
		(size 0.508)
		(drill 0.254)
		(layers "F.Cu" "B.Cu")
		(net "GND")
	)
	(via
		(at 383.426208 -343.073482)
		(size 0.4572)
		(drill 0.254)
		(layers "F.Cu" "B.Cu")
		(net "GND")
	)
	(via
		(at 184.77484 -305.874928)
		(size 0.4064)
		(drill 0.2032)
		(layers "F.Cu" "B.Cu")
		(net "GND")
	)
	(via
		(at 351.293684 -210.787234)
		(size 0.4572)
		(drill 0.254)
		(layers "F.Cu" "B.Cu")
		(net "GND")
	)
	(via
		(at 419.03142 -6.292342)
		(size 0.508)
		(drill 0.254)
		(layers "F.Cu" "B.Cu")
		(net "GND")
	)
	(via
		(at 157.699964 -308.249828)
		(size 0.4064)
		(drill 0.2032)
		(layers "F.Cu" "B.Cu")
		(net "GND")
	)
	(via
		(at 313.09818 -150.876762)
		(size 0.508)
		(drill 0.254)
		(layers "F.Cu" "B.Cu")
		(net "GND")
	)
	(via
		(at 208.278222 -191.543686)
		(size 0.508)
		(drill 0.254)
		(layers "F.Cu" "B.Cu")
		(net "GND")
	)
	(via
		(at 57.274968 -300.174914)
		(size 0.4064)
		(drill 0.2032)
		(layers "F.Cu" "B.Cu")
		(net "GND")
	)
	(via
		(at 71.049896 -310.149748)
		(size 0.4064)
		(drill 0.2032)
		(layers "F.Cu" "B.Cu")
		(net "GND")
	)
	(via
		(at 385.149852 -317.749936)
		(size 0.4064)
		(drill 0.2032)
		(layers "F.Cu" "B.Cu")
		(net "GND")
	)
	(via
		(at 22.243796 -352.245422)
		(size 0.4572)
		(drill 0.254)
		(layers "F.Cu" "B.Cu")
		(net "GND")
	)
	(via
		(at 80.898238 -143.676878)
		(size 0.508)
		(drill 0.254)
		(layers "F.Cu" "B.Cu")
		(net "GND")
	)
	(via
		(at 51.574954 -287.824926)
		(size 0.4064)
		(drill 0.2032)
		(layers "F.Cu" "B.Cu")
		(net "GND")
	)
	(via
		(at 429.927766 -407.24201)
		(size 0.508)
		(drill 0.254)
		(layers "F.Cu" "B.Cu")
		(net "GND")
	)
	(via
		(at 355.535992 -279.023572)
		(size 0.508)
		(drill 0.254)
		(layers "F.Cu" "B.Cu")
		(net "GND")
	)
	(via
		(at 307.539898 -73.87463)
		(size 0.508)
		(drill 0.254)
		(layers "F.Cu" "B.Cu")
		(net "GND")
	)
	(via
		(at 187.754768 -23.880318)
		(size 0.508)
		(drill 0.254)
		(layers "F.Cu" "B.Cu")
		(net "GND")
	)
	(via
		(at 230.977948 -141.125956)
		(size 0.508)
		(drill 0.254)
		(layers "F.Cu" "B.Cu")
		(net "GND")
	)
	(via
		(at 71.049896 -274.999958)
		(size 0.4064)
		(drill 0.2032)
		(layers "F.Cu" "B.Cu")
		(net "GND")
	)
	(via
		(at 418.399976 -317.749936)
		(size 0.4064)
		(drill 0.2032)
		(layers "F.Cu" "B.Cu")
		(net "GND")
	)
	(via
		(at 30.438344 -253.45644)
		(size 0.508)
		(drill 0.254)
		(layers "F.Cu" "B.Cu")
		(net "GND")
	)
	(via
		(at 300.12767 -410.041852)
		(size 0.508)
		(drill 0.254)
		(layers "F.Cu" "B.Cu")
		(net "GND")
	)
	(via
		(at 245.280434 -278.36876)
		(size 0.508)
		(drill 0.254)
		(layers "F.Cu" "B.Cu")
		(net "GND")
	)
	(via
		(at 210.657948 -56.809894)
		(size 0.508)
		(drill 0.254)
		(layers "F.Cu" "B.Cu")
		(net "GND")
	)
	(via
		(at 429.198278 -153.218134)
		(size 0.508)
		(drill 0.254)
		(layers "F.Cu" "B.Cu")
		(net "GND")
	)
	(via
		(at 240.44275 -147.630388)
		(size 0.508)
		(drill 0.254)
		(layers "F.Cu" "B.Cu")
		(net "GND")
	)
	(via
		(at 270.437102 -345.465146)
		(size 0.4064)
		(drill 0.2032)
		(layers "F.Cu" "B.Cu")
		(net "GND")
	)
	(via
		(at 168.091104 -168.397174)
		(size 0.508)
		(drill 0.254)
		(layers "F.Cu" "B.Cu")
		(net "GND")
	)
	(via
		(at 189.049914 -280.699718)
		(size 0.4064)
		(drill 0.2032)
		(layers "F.Cu" "B.Cu")
		(net "GND")
	)
	(via
		(at 305.149758 -276.899878)
		(size 0.4064)
		(drill 0.2032)
		(layers "F.Cu" "B.Cu")
		(net "GND")
	)
	(via
		(at 34.679636 -341.805514)
		(size 0.4572)
		(drill 0.254)
		(layers "F.Cu" "B.Cu")
		(net "GND")
	)
	(via
		(at 9.0551 -126.995428)
		(size 0.508)
		(drill 0.254)
		(layers "F.Cu" "B.Cu")
		(net "GND")
	)
	(via
		(at 186.86018 -355.34219)
		(size 0.4572)
		(drill 0.254)
		(layers "F.Cu" "B.Cu")
		(net "GND")
	)
	(via
		(at 158.938468 -72.56526)
		(size 0.508)
		(drill 0.254)
		(layers "F.Cu" "B.Cu")
		(net "GND")
	)
	(via
		(at 0.766318 -11.372342)
		(size 0.508)
		(drill 0.254)
		(layers "F.Cu" "B.Cu")
		(net "GND")
	)
	(via
		(at 432.119024 -355.366066)
		(size 0.4572)
		(drill 0.254)
		(layers "F.Cu" "B.Cu")
		(net "GND")
	)
	(via
		(at 213.251542 -82.633058)
		(size 0.508)
		(drill 0.254)
		(layers "F.Cu" "B.Cu")
		(net "GND")
	)
	(via
		(at 230.26751 -220.303852)
		(size 0.4572)
		(drill 0.254)
		(layers "F.Cu" "B.Cu")
		(net "GND")
	)
	(via
		(at 75.339956 -73.87463)
		(size 0.508)
		(drill 0.254)
		(layers "F.Cu" "B.Cu")
		(net "GND")
	)
	(via
		(at 114.265456 -305.008534)
		(size 0.508)
		(drill 0.254)
		(layers "F.Cu" "B.Cu")
		(net "GND")
	)
	(via
		(at 275.176234 -344.831162)
		(size 0.4572)
		(drill 0.254)
		(layers "F.Cu" "B.Cu")
		(net "GND")
	)
	(via
		(at 34.491676 -109.382052)
		(size 0.508)
		(drill 0.254)
		(layers "F.Cu" "B.Cu")
		(net "GND")
	)
	(via
		(at 174.747936 -374.938544)
		(size 0.508)
		(drill 0.254)
		(layers "F.Cu" "B.Cu")
		(net "GND")
	)
	(via
		(at 83.540346 -121.563384)
		(size 0.508)
		(drill 0.254)
		(layers "F.Cu" "B.Cu")
		(net "GND")
	)
	(via
		(at 189.049914 -275.949918)
		(size 0.4064)
		(drill 0.2032)
		(layers "F.Cu" "B.Cu")
		(net "GND")
	)
	(via
		(at 329.108816 -349.219774)
		(size 0.4572)
		(drill 0.254)
		(layers "F.Cu" "B.Cu")
		(net "GND")
	)
	(via
		(at 306.448206 -129.445004)
		(size 0.508)
		(drill 0.254)
		(layers "F.Cu" "B.Cu")
		(net "GND")
	)
	(via
		(at 84.54771 -402.241766)
		(size 0.508)
		(drill 0.254)
		(layers "F.Cu" "B.Cu")
		(net "GND")
	)
	(via
		(at 371.446552 -255.66624)
		(size 0.508)
		(drill 0.254)
		(layers "F.Cu" "B.Cu")
		(net "GND")
	)
	(via
		(at 121.947686 -400.938492)
		(size 0.508)
		(drill 0.254)
		(layers "F.Cu" "B.Cu")
		(net "GND")
	)
	(via
		(at 270.601694 -99.116642)
		(size 0.508)
		(drill 0.254)
		(layers "F.Cu" "B.Cu")
		(net "GND")
	)
	(via
		(at 388.20217 -56.826404)
		(size 0.508)
		(drill 0.254)
		(layers "F.Cu" "B.Cu")
		(net "GND")
	)
	(via
		(at 296.793412 -143.955008)
		(size 0.508)
		(drill 0.254)
		(layers "F.Cu" "B.Cu")
		(net "GND")
	)
	(via
		(at 189.524894 -290.674806)
		(size 0.4064)
		(drill 0.2032)
		(layers "F.Cu" "B.Cu")
		(net "GND")
	)
	(via
		(at 348.527878 -376.242072)
		(size 0.508)
		(drill 0.254)
		(layers "F.Cu" "B.Cu")
		(net "GND")
	)
	(via
		(at 71.760334 -347.951806)
		(size 0.4572)
		(drill 0.254)
		(layers "F.Cu" "B.Cu")
		(net "GND")
	)
	(via
		(at 328.384408 -73.20026)
		(size 0.508)
		(drill 0.254)
		(layers "F.Cu" "B.Cu")
		(net "GND")
	)
	(via
		(at 185.010044 -350.977454)
		(size 0.4572)
		(drill 0.254)
		(layers "F.Cu" "B.Cu")
		(net "GND")
	)
	(via
		(at 225.050604 -88.032336)
		(size 0.508)
		(drill 0.254)
		(layers "F.Cu" "B.Cu")
		(net "GND")
	)
	(via
		(at 397.847566 -121.692416)
		(size 0.508)
		(drill 0.254)
		(layers "F.Cu" "B.Cu")
		(net "GND")
	)
	(via
		(at 22.243796 -349.219774)
		(size 0.4572)
		(drill 0.254)
		(layers "F.Cu" "B.Cu")
		(net "GND")
	)
	(via
		(at 415.96691 -152.95499)
		(size 0.508)
		(drill 0.254)
		(layers "F.Cu" "B.Cu")
		(net "GND")
	)
	(via
		(at 417.94811 -118.370858)
		(size 0.508)
		(drill 0.254)
		(layers "F.Cu" "B.Cu")
		(net "GND")
	)
	(via
		(at 438.336944 -347.951806)
		(size 0.4572)
		(drill 0.254)
		(layers "F.Cu" "B.Cu")
		(net "GND")
	)
	(via
		(at 379.327918 -372.341902)
		(size 0.508)
		(drill 0.254)
		(layers "F.Cu" "B.Cu")
		(net "GND")
	)
	(via
		(at 132.858764 -304.373534)
		(size 0.508)
		(drill 0.254)
		(layers "F.Cu" "B.Cu")
		(net "GND")
	)
	(via
		(at 429.927766 -409.940252)
		(size 0.508)
		(drill 0.254)
		(layers "F.Cu" "B.Cu")
		(net "GND")
	)
	(via
		(at 302.774858 -285.924752)
		(size 0.4064)
		(drill 0.2032)
		(layers "F.Cu" "B.Cu")
		(net "GND")
	)
	(via
		(at 85.674962 -354.732082)
		(size 0.4064)
		(drill 0.2032)
		(layers "F.Cu" "B.Cu")
		(net "GND")
	)
	(via
		(at 83.400138 -314.899548)
		(size 0.4064)
		(drill 0.2032)
		(layers "F.Cu" "B.Cu")
		(net "GND")
	)
	(via
		(at 267.959586 -119.026686)
		(size 0.508)
		(drill 0.254)
		(layers "F.Cu" "B.Cu")
		(net "GND")
	)
	(via
		(at 428.84979 -287.349946)
		(size 0.4064)
		(drill 0.2032)
		(layers "F.Cu" "B.Cu")
		(net "GND")
	)
	(via
		(at 164.824918 -293.52494)
		(size 0.4064)
		(drill 0.2032)
		(layers "F.Cu" "B.Cu")
		(net "GND")
	)
	(via
		(at 255.424178 -222.214186)
		(size 0.508)
		(drill 0.254)
		(layers "F.Cu" "B.Cu")
		(net "GND")
	)
	(via
		(at 169.099992 -313.949842)
		(size 0.4064)
		(drill 0.2032)
		(layers "F.Cu" "B.Cu")
		(net "GND")
	)
	(via
		(at 344.127836 -397.140176)
		(size 0.508)
		(drill 0.254)
		(layers "F.Cu" "B.Cu")
		(net "GND")
	)
	(via
		(at 332.781148 -31.118302)
		(size 0.508)
		(drill 0.254)
		(layers "F.Cu" "B.Cu")
		(net "GND")
	)
	(via
		(at 284.874462 -357.75773)
		(size 0.4064)
		(drill 0.2032)
		(layers "F.Cu" "B.Cu")
		(net "GND")
	)
	(via
		(at 261.47141 -51.661822)
		(size 0.508)
		(drill 0.254)
		(layers "F.Cu" "B.Cu")
		(net "GND")
	)
	(via
		(at 274.480782 -31.390082)
		(size 0.508)
		(drill 0.254)
		(layers "F.Cu" "B.Cu")
		(net "GND")
	)
	(via
		(at 80.54975 -274.999958)
		(size 0.4064)
		(drill 0.2032)
		(layers "F.Cu" "B.Cu")
		(net "GND")
	)
	(via
		(at 420.541958 -112.56772)
		(size 0.508)
		(drill 0.254)
		(layers "F.Cu" "B.Cu")
		(net "GND")
	)
	(via
		(at 300.419262 -348.58579)
		(size 0.4064)
		(drill 0.2032)
		(layers "F.Cu" "B.Cu")
		(net "GND")
	)
	(via
		(at 143.415258 -45.88891)
		(size 0.508)
		(drill 0.254)
		(layers "F.Cu" "B.Cu")
		(net "GND")
	)
	(via
		(at 227.682552 -111.153956)
		(size 0.508)
		(drill 0.254)
		(layers "F.Cu" "B.Cu")
		(net "GND")
	)
	(via
		(at 185.725054 -293.52494)
		(size 0.4064)
		(drill 0.2032)
		(layers "F.Cu" "B.Cu")
		(net "GND")
	)
	(via
		(at 107.860846 -218.095576)
		(size 0.508)
		(drill 0.254)
		(layers "F.Cu" "B.Cu")
		(net "GND")
	)
	(via
		(at 95.483426 -113.364772)
		(size 0.508)
		(drill 0.254)
		(layers "F.Cu" "B.Cu")
		(net "GND")
	)
	(via
		(at 69.624956 -300.174914)
		(size 0.4064)
		(drill 0.2032)
		(layers "F.Cu" "B.Cu")
		(net "GND")
	)
	(via
		(at 414.124902 -305.874928)
		(size 0.4064)
		(drill 0.2032)
		(layers "F.Cu" "B.Cu")
		(net "GND")
	)
	(via
		(at 105.224072 -103.69296)
		(size 0.508)
		(drill 0.254)
		(layers "F.Cu" "B.Cu")
		(net "GND")
	)
	(via
		(at 174.052992 -345.465146)
		(size 0.4064)
		(drill 0.2032)
		(layers "F.Cu" "B.Cu")
		(net "GND")
	)
	(via
		(at 298.647612 -147.555204)
		(size 0.508)
		(drill 0.254)
		(layers "F.Cu" "B.Cu")
		(net "GND")
	)
	(via
		(at 453.623172 -55.083456)
		(size 0.508)
		(drill 0.254)
		(layers "F.Cu" "B.Cu")
		(net "GND")
	)
	(via
		(at 445.954658 -23.880318)
		(size 0.508)
		(drill 0.254)
		(layers "F.Cu" "B.Cu")
		(net "GND")
	)
	(via
		(at 293.84879 -31.390082)
		(size 0.508)
		(drill 0.254)
		(layers "F.Cu" "B.Cu")
		(net "GND")
	)
	(via
		(at 86.747858 -385.141978)
		(size 0.508)
		(drill 0.254)
		(layers "F.Cu" "B.Cu")
		(net "GND")
	)
	(via
		(at 343.511378 -290.68649)
		(size 0.508)
		(drill 0.254)
		(layers "F.Cu" "B.Cu")
		(net "GND")
	)
	(via
		(at 71.049896 -280.699718)
		(size 0.4064)
		(drill 0.2032)
		(layers "F.Cu" "B.Cu")
		(net "GND")
	)
	(via
		(at 390.849866 -308.249828)
		(size 0.4064)
		(drill 0.2032)
		(layers "F.Cu" "B.Cu")
		(net "GND")
	)
	(via
		(at 206.453994 -230.673148)
		(size 0.508)
		(drill 0.254)
		(layers "F.Cu" "B.Cu")
		(net "GND")
	)
	(via
		(at 165.774878 -297.32478)
		(size 0.4064)
		(drill 0.2032)
		(layers "F.Cu" "B.Cu")
		(net "GND")
	)
	(via
		(at 66.44767 -151.155146)
		(size 0.508)
		(drill 0.254)
		(layers "F.Cu" "B.Cu")
		(net "GND")
	)
	(via
		(at 57.647078 -383.652268)
		(size 0.508)
		(drill 0.254)
		(layers "F.Cu" "B.Cu")
		(net "GND")
	)
	(via
		(at 314.408058 -52.536852)
		(size 0.508)
		(drill 0.254)
		(layers "F.Cu" "B.Cu")
		(net "GND")
	)
	(via
		(at 365.623348 -134.601966)
		(size 0.508)
		(drill 0.254)
		(layers "F.Cu" "B.Cu")
		(net "GND")
	)
	(via
		(at 62.024768 -284.974792)
		(size 0.4064)
		(drill 0.2032)
		(layers "F.Cu" "B.Cu")
		(net "GND")
	)
	(via
		(at 406.999948 -313.949842)
		(size 0.4064)
		(drill 0.2032)
		(layers "F.Cu" "B.Cu")
		(net "GND")
	)
	(via
		(at 388.127748 -395.938502)
		(size 0.508)
		(drill 0.254)
		(layers "F.Cu" "B.Cu")
		(net "GND")
	)
	(via
		(at 335.326736 -346.09913)
		(size 0.4572)
		(drill 0.254)
		(layers "F.Cu" "B.Cu")
		(net "GND")
	)
	(via
		(at 293.74973 -319.65011)
		(size 0.4064)
		(drill 0.2032)
		(layers "F.Cu" "B.Cu")
		(net "GND")
	)
	(via
		(at 397.120872 -344.831162)
		(size 0.4572)
		(drill 0.254)
		(layers "F.Cu" "B.Cu")
		(net "GND")
	)
	(via
		(at 206.645764 -189.023498)
		(size 0.508)
		(drill 0.254)
		(layers "F.Cu" "B.Cu")
		(net "GND")
	)
	(via
		(at 74.248264 -129.445004)
		(size 0.508)
		(drill 0.254)
		(layers "F.Cu" "B.Cu")
		(net "GND")
	)
	(via
		(at 44.449746 -279.749758)
		(size 0.4064)
		(drill 0.2032)
		(layers "F.Cu" "B.Cu")
		(net "GND")
	)
	(via
		(at 172.574204 -350.977454)
		(size 0.4572)
		(drill 0.254)
		(layers "F.Cu" "B.Cu")
		(net "GND")
	)
	(via
		(at 433.108354 -155.024582)
		(size 0.508)
		(drill 0.254)
		(layers "F.Cu" "B.Cu")
		(net "GND")
	)
	(via
		(at 466.835998 -379.283976)
		(size 0.508)
		(drill 0.254)
		(layers "F.Cu" "B.Cu")
		(net "GND")
	)
	(via
		(at 186.9313 -60.099194)
		(size 0.508)
		(drill 0.254)
		(layers "F.Cu" "B.Cu")
		(net "GND")
	)
	(via
		(at 311.799478 -276.899878)
		(size 0.4064)
		(drill 0.2032)
		(layers "F.Cu" "B.Cu")
		(net "GND")
	)
	(via
		(at 286.927798 -373.83847)
		(size 0.508)
		(drill 0.254)
		(layers "F.Cu" "B.Cu")
		(net "GND")
	)
	(via
		(at 375.59234 -174.15002)
		(size 0.508)
		(drill 0.254)
		(layers "F.Cu" "B.Cu")
		(net "GND")
	)
	(via
		(at 92.26423 -352.245422)
		(size 0.4572)
		(drill 0.254)
		(layers "F.Cu" "B.Cu")
		(net "GND")
	)
	(via
		(at 74.374756 -302.074834)
		(size 0.4064)
		(drill 0.2032)
		(layers "F.Cu" "B.Cu")
		(net "GND")
	)
	(via
		(at 165.774878 -307.774848)
		(size 0.4064)
		(drill 0.2032)
		(layers "F.Cu" "B.Cu")
		(net "GND")
	)
	(via
		(at 448.881246 -29.859478)
		(size 0.508)
		(drill 0.254)
		(layers "F.Cu" "B.Cu")
		(net "GND")
	)
	(via
		(at 318.654938 -31.390082)
		(size 0.508)
		(drill 0.254)
		(layers "F.Cu" "B.Cu")
		(net "GND")
	)
	(via
		(at 312.274712 -300.174914)
		(size 0.4064)
		(drill 0.2032)
		(layers "F.Cu" "B.Cu")
		(net "GND")
	)
	(via
		(at 275.547582 -357.75773)
		(size 0.4064)
		(drill 0.2032)
		(layers "F.Cu" "B.Cu")
		(net "GND")
	)
	(via
		(at 196.998082 -147.27682)
		(size 0.508)
		(drill 0.254)
		(layers "F.Cu" "B.Cu")
		(net "GND")
	)
	(via
		(at 286.35325 -352.245422)
		(size 0.4572)
		(drill 0.254)
		(layers "F.Cu" "B.Cu")
		(net "GND")
	)
	(via
		(at 331.73035 -65.15989)
		(size 0.508)
		(drill 0.254)
		(layers "F.Cu" "B.Cu")
		(net "GND")
	)
	(via
		(at 435.227984 -357.123746)
		(size 0.4572)
		(drill 0.254)
		(layers "F.Cu" "B.Cu")
		(net "GND")
	)
	(via
		(at 162.924998 -285.924752)
		(size 0.4064)
		(drill 0.2032)
		(layers "F.Cu" "B.Cu")
		(net "GND")
	)
	(via
		(at 8.954008 -147.630388)
		(size 0.508)
		(drill 0.254)
		(layers "F.Cu" "B.Cu")
		(net "GND")
	)
	(via
		(at 344.893646 -217.987372)
		(size 0.4572)
		(drill 0.254)
		(layers "F.Cu" "B.Cu")
		(net "GND")
	)
	(via
		(at 211.400136 -185.728864)
		(size 0.508)
		(drill 0.254)
		(layers "F.Cu" "B.Cu")
		(net "GND")
	)
	(via
		(at 168.952164 -111.44504)
		(size 0.508)
		(drill 0.254)
		(layers "F.Cu" "B.Cu")
		(net "GND")
	)
	(via
		(at 278.285194 -357.123746)
		(size 0.4572)
		(drill 0.254)
		(layers "F.Cu" "B.Cu")
		(net "GND")
	)
	(via
		(at 415.074862 -307.774848)
		(size 0.4064)
		(drill 0.2032)
		(layers "F.Cu" "B.Cu")
		(net "GND")
	)
	(via
		(at 390.902952 -358.391714)
		(size 0.4572)
		(drill 0.254)
		(layers "F.Cu" "B.Cu")
		(net "GND")
	)
	(via
		(at 418.874956 -288.774886)
		(size 0.4064)
		(drill 0.2032)
		(layers "F.Cu" "B.Cu")
		(net "GND")
	)
	(via
		(at 397.49222 -348.58579)
		(size 0.4064)
		(drill 0.2032)
		(layers "F.Cu" "B.Cu")
		(net "GND")
	)
	(via
		(at 298.974764 -287.824926)
		(size 0.4064)
		(drill 0.2032)
		(layers "F.Cu" "B.Cu")
		(net "GND")
	)
	(via
		(at 171.31538 -341.805514)
		(size 0.4572)
		(drill 0.254)
		(layers "F.Cu" "B.Cu")
		(net "GND")
	)
	(via
		(at 272.849848 -303.499774)
		(size 0.4064)
		(drill 0.2032)
		(layers "F.Cu" "B.Cu")
		(net "GND")
	)
	(via
		(at 301.349918 -315.849762)
		(size 0.4064)
		(drill 0.2032)
		(layers "F.Cu" "B.Cu")
		(net "GND")
	)
	(via
		(at 147.240244 -27.729688)
		(size 0.508)
		(drill 0.254)
		(layers "F.Cu" "B.Cu")
		(net "GND")
	)
	(via
		(at 108.828586 -84.13877)
		(size 0.508)
		(drill 0.254)
		(layers "F.Cu" "B.Cu")
		(net "GND")
	)
	(via
		(at 40.547798 -395.938502)
		(size 0.508)
		(drill 0.254)
		(layers "F.Cu" "B.Cu")
		(net "GND")
	)
	(via
		(at 344.127836 -373.83847)
		(size 0.508)
		(drill 0.254)
		(layers "F.Cu" "B.Cu")
		(net "GND")
	)
	(via
		(at 247.637808 -74.624184)
		(size 0.508)
		(drill 0.254)
		(layers "F.Cu" "B.Cu")
		(net "GND")
	)
	(via
		(at 300.12767 -373.83847)
		(size 0.508)
		(drill 0.254)
		(layers "F.Cu" "B.Cu")
		(net "GND")
	)
	(via
		(at 129.545588 -113.373408)
		(size 0.508)
		(drill 0.254)
		(layers "F.Cu" "B.Cu")
		(net "GND")
	)
	(via
		(at 381.527812 -397.038576)
		(size 0.508)
		(drill 0.254)
		(layers "F.Cu" "B.Cu")
		(net "GND")
	)
	(via
		(at 27.668982 -283.131514)
		(size 0.508)
		(drill 0.254)
		(layers "F.Cu" "B.Cu")
		(net "GND")
	)
	(via
		(at 435.78907 -83.487768)
		(size 0.508)
		(drill 0.254)
		(layers "F.Cu" "B.Cu")
		(net "GND")
	)
	(via
		(at 42.747946 -408.738578)
		(size 0.508)
		(drill 0.254)
		(layers "F.Cu" "B.Cu")
		(net "GND")
	)
	(via
		(at 181.44998 -316.799722)
		(size 0.4064)
		(drill 0.2032)
		(layers "F.Cu" "B.Cu")
		(net "GND")
	)
	(via
		(at 73.547732 -378.83846)
		(size 0.508)
		(drill 0.254)
		(layers "F.Cu" "B.Cu")
		(net "GND")
	)
	(via
		(at 160.549844 -309.199788)
		(size 0.4064)
		(drill 0.2032)
		(layers "F.Cu" "B.Cu")
		(net "GND")
	)
	(via
		(at 419.349936 -279.749758)
		(size 0.4064)
		(drill 0.2032)
		(layers "F.Cu" "B.Cu")
		(net "GND")
	)
	(via
		(at 193.799714 -281.649678)
		(size 0.4064)
		(drill 0.2032)
		(layers "F.Cu" "B.Cu")
		(net "GND")
	)
	(via
		(at 73.547732 -376.140218)
		(size 0.508)
		(drill 0.254)
		(layers "F.Cu" "B.Cu")
		(net "GND")
	)
	(via
		(at 207.899 -206.756)
		(size 0.508)
		(drill 0.254)
		(layers "F.Cu" "B.Cu")
		(net "GND")
	)
	(via
		(at 12.505944 -30.901132)
		(size 0.508)
		(drill 0.254)
		(layers "F.Cu" "B.Cu")
		(net "GND")
	)
	(via
		(at 406.524968 -302.074834)
		(size 0.4064)
		(drill 0.2032)
		(layers "F.Cu" "B.Cu")
		(net "GND")
	)
	(via
		(at 77.947774 -408.738578)
		(size 0.508)
		(drill 0.254)
		(layers "F.Cu" "B.Cu")
		(net "GND")
	)
	(via
		(at 311.523126 -56.353456)
		(size 0.508)
		(drill 0.254)
		(layers "F.Cu" "B.Cu")
		(net "GND")
	)
	(via
		(at 34.679636 -347.951806)
		(size 0.4572)
		(drill 0.254)
		(layers "F.Cu" "B.Cu")
		(net "GND")
	)
	(via
		(at 423.163492 -348.58579)
		(size 0.4064)
		(drill 0.2032)
		(layers "F.Cu" "B.Cu")
		(net "GND")
	)
	(via
		(at 313.564016 -349.219774)
		(size 0.4572)
		(drill 0.254)
		(layers "F.Cu" "B.Cu")
		(net "GND")
	)
	(via
		(at 134.191756 -149.89683)
		(size 0.508)
		(drill 0.254)
		(layers "F.Cu" "B.Cu")
		(net "GND")
	)
	(via
		(at 343.2937 -213.18728)
		(size 0.4572)
		(drill 0.254)
		(layers "F.Cu" "B.Cu")
		(net "GND")
	)
	(via
		(at 124.55525 -33.19018)
		(size 0.508)
		(drill 0.254)
		(layers "F.Cu" "B.Cu")
		(net "GND")
	)
	(via
		(at 324.448678 -31.390082)
		(size 0.508)
		(drill 0.254)
		(layers "F.Cu" "B.Cu")
		(net "GND")
	)
	(via
		(at 335.405222 -305.91887)
		(size 0.508)
		(drill 0.254)
		(layers "F.Cu" "B.Cu")
		(net "GND")
	)
	(via
		(at 380.111 -201.168)
		(size 0.508)
		(drill 0.254)
		(layers "F.Cu" "B.Cu")
		(net "GND")
	)
	(via
		(at 307.640736 -45.853858)
		(size 0.508)
		(drill 0.254)
		(layers "F.Cu" "B.Cu")
		(net "GND")
	)
	(via
		(at 98.566986 -0.762)
		(size 0.508)
		(drill 0.254)
		(layers "F.Cu" "B.Cu")
		(net "GND")
	)
	(via
		(at 42.527728 -345.465146)
		(size 0.4064)
		(drill 0.2032)
		(layers "F.Cu" "B.Cu")
		(net "GND")
	)
	(via
		(at 430.466246 -122.098054)
		(size 0.508)
		(drill 0.254)
		(layers "F.Cu" "B.Cu")
		(net "GND")
	)
	(via
		(at 161.500058 -314.899802)
		(size 0.4064)
		(drill 0.2032)
		(layers "F.Cu" "B.Cu")
		(net "GND")
	)
	(via
		(at 147.803362 -242.444778)
		(size 0.508)
		(drill 0.254)
		(layers "F.Cu" "B.Cu")
		(net "GND")
	)
	(via
		(at 116.03228 -344.831162)
		(size 0.4572)
		(drill 0.254)
		(layers "F.Cu" "B.Cu")
		(net "GND")
	)
	(via
		(at 270.437102 -357.75773)
		(size 0.4064)
		(drill 0.2032)
		(layers "F.Cu" "B.Cu")
		(net "GND")
	)
	(via
		(at 184.658 -58.156094)
		(size 0.508)
		(drill 0.254)
		(layers "F.Cu" "B.Cu")
		(net "GND")
	)
	(via
		(at 365.99622 -162.25647)
		(size 0.508)
		(drill 0.254)
		(layers "F.Cu" "B.Cu")
		(net "GND")
	)
	(via
		(at 344.127836 -375.040144)
		(size 0.508)
		(drill 0.254)
		(layers "F.Cu" "B.Cu")
		(net "GND")
	)
	(via
		(at 270.474948 -288.774886)
		(size 0.4064)
		(drill 0.2032)
		(layers "F.Cu" "B.Cu")
		(net "GND")
	)
	(via
		(at 376.858022 -289.532314)
		(size 0.508)
		(drill 0.254)
		(layers "F.Cu" "B.Cu")
		(net "GND")
	)
	(via
		(at 317.044324 -357.75773)
		(size 0.4064)
		(drill 0.2032)
		(layers "F.Cu" "B.Cu")
		(net "GND")
	)
	(via
		(at 47.032926 -133.565138)
		(size 0.508)
		(drill 0.254)
		(layers "F.Cu" "B.Cu")
		(net "GND")
	)
	(via
		(at 20.765008 -351.611438)
		(size 0.4064)
		(drill 0.2032)
		(layers "F.Cu" "B.Cu")
		(net "GND")
	)
	(via
		(at 73.61047 -358.391714)
		(size 0.4572)
		(drill 0.254)
		(layers "F.Cu" "B.Cu")
		(net "GND")
	)
	(via
		(at 190.949834 -272.14957)
		(size 0.4064)
		(drill 0.2032)
		(layers "F.Cu" "B.Cu")
		(net "GND")
	)
	(via
		(at 43.499786 -310.149748)
		(size 0.4064)
		(drill 0.2032)
		(layers "F.Cu" "B.Cu")
		(net "GND")
	)
	(via
		(at 421.127682 -397.038576)
		(size 0.508)
		(drill 0.254)
		(layers "F.Cu" "B.Cu")
		(net "GND")
	)
	(via
		(at 401.70862 -351.611438)
		(size 0.4064)
		(drill 0.2032)
		(layers "F.Cu" "B.Cu")
		(net "GND")
	)
	(via
		(at 231.55402 -138.175492)
		(size 0.508)
		(drill 0.254)
		(layers "F.Cu" "B.Cu")
		(net "GND")
	)
	(via
		(at 68.199762 -277.849838)
		(size 0.4064)
		(drill 0.2032)
		(layers "F.Cu" "B.Cu")
		(net "GND")
	)
	(via
		(at 47.313342 -31.118302)
		(size 0.508)
		(drill 0.254)
		(layers "F.Cu" "B.Cu")
		(net "GND")
	)
	(via
		(at 436.706772 -345.465146)
		(size 0.4064)
		(drill 0.2032)
		(layers "F.Cu" "B.Cu")
		(net "GND")
	)
	(via
		(at 187.35802 -73.85177)
		(size 0.508)
		(drill 0.254)
		(layers "F.Cu" "B.Cu")
		(net "GND")
	)
	(via
		(at 384.685032 -352.245422)
		(size 0.4572)
		(drill 0.254)
		(layers "F.Cu" "B.Cu")
		(net "GND")
	)
	(via
		(at 5.699506 -27.04973)
		(size 0.508)
		(drill 0.254)
		(layers "F.Cu" "B.Cu")
		(net "GND")
	)
	(via
		(at 309.899558 -276.899878)
		(size 0.4064)
		(drill 0.2032)
		(layers "F.Cu" "B.Cu")
		(net "GND")
	)
	(via
		(at 350.685608 -34.183066)
		(size 0.508)
		(drill 0.254)
		(layers "F.Cu" "B.Cu")
		(net "GND")
	)
	(via
		(at 264.89152 -201.910696)
		(size 0.508)
		(drill 0.254)
		(layers "F.Cu" "B.Cu")
		(net "GND")
	)
	(via
		(at 228.308154 -67.799966)
		(size 0.508)
		(drill 0.254)
		(layers "F.Cu" "B.Cu")
		(net "GND")
	)
	(via
		(at 388.474966 -281.174952)
		(size 0.4064)
		(drill 0.2032)
		(layers "F.Cu" "B.Cu")
		(net "GND")
	)
	(via
		(at 49.446942 -109.177328)
		(size 0.508)
		(drill 0.254)
		(layers "F.Cu" "B.Cu")
		(net "GND")
	)
	(via
		(at 122.621548 -357.75773)
		(size 0.4064)
		(drill 0.2032)
		(layers "F.Cu" "B.Cu")
		(net "GND")
	)
	(via
		(at 370.581428 -90.642694)
		(size 0.508)
		(drill 0.254)
		(layers "F.Cu" "B.Cu")
		(net "GND")
	)
	(via
		(at 425.527724 -385.141978)
		(size 0.508)
		(drill 0.254)
		(layers "F.Cu" "B.Cu")
		(net "GND")
	)
	(via
		(at 268.958314 -350.977454)
		(size 0.4572)
		(drill 0.254)
		(layers "F.Cu" "B.Cu")
		(net "GND")
	)
	(via
		(at 295.649904 -310.149748)
		(size 0.4064)
		(drill 0.2032)
		(layers "F.Cu" "B.Cu")
		(net "GND")
	)
	(via
		(at 396.54988 -316.799722)
		(size 0.4064)
		(drill 0.2032)
		(layers "F.Cu" "B.Cu")
		(net "GND")
	)
	(via
		(at 165.947852 -374.938544)
		(size 0.508)
		(drill 0.254)
		(layers "F.Cu" "B.Cu")
		(net "GND")
	)
	(via
		(at 313.224926 -290.674806)
		(size 0.4064)
		(drill 0.2032)
		(layers "F.Cu" "B.Cu")
		(net "GND")
	)
	(via
		(at 338.807044 -357.75773)
		(size 0.4064)
		(drill 0.2032)
		(layers "F.Cu" "B.Cu")
		(net "GND")
	)
	(via
		(at 303.249838 -281.649932)
		(size 0.4064)
		(drill 0.2032)
		(layers "F.Cu" "B.Cu")
		(net "GND")
	)
	(via
		(at 360.09834 -20.417536)
		(size 0.508)
		(drill 0.254)
		(layers "F.Cu" "B.Cu")
		(net "GND")
	)
	(via
		(at 400.05 -144.885156)
		(size 0.508)
		(drill 0.254)
		(layers "F.Cu" "B.Cu")
		(net "GND")
	)
	(via
		(at 58.224928 -306.824888)
		(size 0.4064)
		(drill 0.2032)
		(layers "F.Cu" "B.Cu")
		(net "GND")
	)
	(via
		(at 425.527724 -383.940304)
		(size 0.508)
		(drill 0.254)
		(layers "F.Cu" "B.Cu")
		(net "GND")
	)
	(via
		(at 128.547622 -399.838418)
		(size 0.508)
		(drill 0.254)
		(layers "F.Cu" "B.Cu")
		(net "GND")
	)
	(via
		(at 276.384512 -73.20026)
		(size 0.508)
		(drill 0.254)
		(layers "F.Cu" "B.Cu")
		(net "GND")
	)
	(via
		(at 130.318256 -343.073482)
		(size 0.4572)
		(drill 0.254)
		(layers "F.Cu" "B.Cu")
		(net "GND")
	)
	(via
		(at 190.348108 -147.55495)
		(size 0.508)
		(drill 0.254)
		(layers "F.Cu" "B.Cu")
		(net "GND")
	)
	(via
		(at 96.67113 -31.652972)
		(size 0.508)
		(drill 0.254)
		(layers "F.Cu" "B.Cu")
		(net "GND")
	)
	(via
		(at 176.94783 -410.041852)
		(size 0.508)
		(drill 0.254)
		(layers "F.Cu" "B.Cu")
		(net "GND")
	)
	(via
		(at 174.079662 -103.814372)
		(size 0.508)
		(drill 0.254)
		(layers "F.Cu" "B.Cu")
		(net "GND")
	)
	(via
		(at 187.149994 -276.899878)
		(size 0.4064)
		(drill 0.2032)
		(layers "F.Cu" "B.Cu")
		(net "GND")
	)
	(via
		(at 261.55777 -25.971246)
		(size 0.508)
		(drill 0.254)
		(layers "F.Cu" "B.Cu")
		(net "GND")
	)
	(via
		(at 212.682074 -58.238644)
		(size 0.508)
		(drill 0.254)
		(layers "F.Cu" "B.Cu")
		(net "GND")
	)
	(via
		(at 163.747958 -381.638556)
		(size 0.508)
		(drill 0.254)
		(layers "F.Cu" "B.Cu")
		(net "GND")
	)
	(via
		(at 92.26423 -344.831162)
		(size 0.4572)
		(drill 0.254)
		(layers "F.Cu" "B.Cu")
		(net "GND")
	)
	(via
		(at 396.0749 -292.57498)
		(size 0.4064)
		(drill 0.2032)
		(layers "F.Cu" "B.Cu")
		(net "GND")
	)
	(via
		(at 357.909368 -288.14649)
		(size 0.508)
		(drill 0.254)
		(layers "F.Cu" "B.Cu")
		(net "GND")
	)
	(via
		(at 100.476558 -115.021614)
		(size 0.508)
		(drill 0.254)
		(layers "F.Cu" "B.Cu")
		(net "GND")
	)
	(via
		(at 300.879764 -303.969928)
		(size 0.4064)
		(drill 0.2032)
		(layers "F.Cu" "B.Cu")
		(net "GND")
	)
	(via
		(at 294.201342 -348.58579)
		(size 0.4064)
		(drill 0.2032)
		(layers "F.Cu" "B.Cu")
		(net "GND")
	)
	(via
		(at 258.393438 -279.931114)
		(size 0.508)
		(drill 0.254)
		(layers "F.Cu" "B.Cu")
		(net "GND")
	)
	(via
		(at 181.92496 -284.974792)
		(size 0.4064)
		(drill 0.2032)
		(layers "F.Cu" "B.Cu")
		(net "GND")
	)
	(via
		(at 300.874684 -299.224954)
		(size 0.4064)
		(drill 0.2032)
		(layers "F.Cu" "B.Cu")
		(net "GND")
	)
	(via
		(at 258.231386 -397.705834)
		(size 0.508)
		(drill 0.254)
		(layers "F.Cu" "B.Cu")
		(net "GND")
	)
	(via
		(at 47.77486 -294.4749)
		(size 0.4064)
		(drill 0.2032)
		(layers "F.Cu" "B.Cu")
		(net "GND")
	)
	(via
		(at 448.776598 -114.310414)
		(size 0.508)
		(drill 0.254)
		(layers "F.Cu" "B.Cu")
		(net "GND")
	)
	(via
		(at 425.049696 -274.999958)
		(size 0.4064)
		(drill 0.2032)
		(layers "F.Cu" "B.Cu")
		(net "GND")
	)
	(via
		(at 375.372884 -306.052728)
		(size 0.508)
		(drill 0.254)
		(layers "F.Cu" "B.Cu")
		(net "GND")
	)
	(via
		(at 350.493584 -213.98738)
		(size 0.4572)
		(drill 0.254)
		(layers "F.Cu" "B.Cu")
		(net "GND")
	)
	(via
		(at 441.445904 -357.123746)
		(size 0.4572)
		(drill 0.254)
		(layers "F.Cu" "B.Cu")
		(net "GND")
	)
	(via
		(at 197.125082 -303.974754)
		(size 0.4064)
		(drill 0.2032)
		(layers "F.Cu" "B.Cu")
		(net "GND")
	)
	(via
		(at 64.28359 -358.391714)
		(size 0.4572)
		(drill 0.254)
		(layers "F.Cu" "B.Cu")
		(net "GND")
	)
	(via
		(at 72.241918 -112.56772)
		(size 0.508)
		(drill 0.254)
		(layers "F.Cu" "B.Cu")
		(net "GND")
	)
	(via
		(at 132.26288 -214.917782)
		(size 0.508)
		(drill 0.254)
		(layers "F.Cu" "B.Cu")
		(net "GND")
	)
	(via
		(at 132.36321 -227.965)
		(size 0.508)
		(drill 0.254)
		(layers "F.Cu" "B.Cu")
		(net "GND")
	)
	(via
		(at 38.347904 -404.838662)
		(size 0.508)
		(drill 0.254)
		(layers "F.Cu" "B.Cu")
		(net "GND")
	)
	(via
		(at 166.075106 -73.87463)
		(size 0.508)
		(drill 0.254)
		(layers "F.Cu" "B.Cu")
		(net "GND")
	)
	(via
		(at 406.524968 -289.724846)
		(size 0.4064)
		(drill 0.2032)
		(layers "F.Cu" "B.Cu")
		(net "GND")
	)
	(via
		(at 137.795 -344.831162)
		(size 0.4572)
		(drill 0.254)
		(layers "F.Cu" "B.Cu")
		(net "GND")
	)
	(via
		(at 193.799714 -276.899878)
		(size 0.4064)
		(drill 0.2032)
		(layers "F.Cu" "B.Cu")
		(net "GND")
	)
	(via
		(at 68.280788 -33.19018)
		(size 0.508)
		(drill 0.254)
		(layers "F.Cu" "B.Cu")
		(net "GND")
	)
	(via
		(at 109.812328 -228.714046)
		(size 0.508)
		(drill 0.254)
		(layers "F.Cu" "B.Cu")
		(net "GND")
	)
	(via
		(at 69.624956 -303.974754)
		(size 0.4064)
		(drill 0.2032)
		(layers "F.Cu" "B.Cu")
		(net "GND")
	)
	(via
		(at 5.183632 -13.029184)
		(size 0.508)
		(drill 0.254)
		(layers "F.Cu" "B.Cu")
		(net "GND")
	)
	(via
		(at 107.477814 -282.910788)
		(size 0.49022)
		(drill 0.254)
		(layers "F.Cu" "B.Cu")
		(net "GND")
	)
	(via
		(at 280.449782 -319.65011)
		(size 0.4064)
		(drill 0.2032)
		(layers "F.Cu" "B.Cu")
		(net "GND")
	)
	(via
		(at 296.124884 -303.974754)
		(size 0.4064)
		(drill 0.2032)
		(layers "F.Cu" "B.Cu")
		(net "GND")
	)
	(via
		(at 421.522144 -52.51704)
		(size 0.508)
		(drill 0.254)
		(layers "F.Cu" "B.Cu")
		(net "GND")
	)
	(via
		(at 343.023444 -345.465146)
		(size 0.4064)
		(drill 0.2032)
		(layers "F.Cu" "B.Cu")
		(net "GND")
	)
	(via
		(at 185.747914 -118.370858)
		(size 0.508)
		(drill 0.254)
		(layers "F.Cu" "B.Cu")
		(net "GND")
	)
	(via
		(at 59.649868 -315.849762)
		(size 0.4064)
		(drill 0.2032)
		(layers "F.Cu" "B.Cu")
		(net "GND")
	)
	(via
		(at 308.949852 -310.149748)
		(size 0.4064)
		(drill 0.2032)
		(layers "F.Cu" "B.Cu")
		(net "GND")
	)
	(via
		(at 387.525006 -298.27474)
		(size 0.4064)
		(drill 0.2032)
		(layers "F.Cu" "B.Cu")
		(net "GND")
	)
	(via
		(at 175.683164 -354.098098)
		(size 0.4572)
		(drill 0.254)
		(layers "F.Cu" "B.Cu")
		(net "GND")
	)
	(via
		(at 151.999696 -302.550068)
		(size 0.4064)
		(drill 0.2032)
		(layers "F.Cu" "B.Cu")
		(net "GND")
	)
	(via
		(at 395.862048 -349.219774)
		(size 0.4572)
		(drill 0.254)
		(layers "F.Cu" "B.Cu")
		(net "GND")
	)
	(via
		(at 276.649688 -279.749758)
		(size 0.4064)
		(drill 0.2032)
		(layers "F.Cu" "B.Cu")
		(net "GND")
	)
	(via
		(at 283.774896 -302.074834)
		(size 0.4064)
		(drill 0.2032)
		(layers "F.Cu" "B.Cu")
		(net "GND")
	)
	(via
		(at 400.824954 -284.974792)
		(size 0.4064)
		(drill 0.2032)
		(layers "F.Cu" "B.Cu")
		(net "GND")
	)
	(via
		(at 417.924996 -298.27474)
		(size 0.4064)
		(drill 0.2032)
		(layers "F.Cu" "B.Cu")
		(net "GND")
	)
	(via
		(at 296.124884 -306.824888)
		(size 0.4064)
		(drill 0.2032)
		(layers "F.Cu" "B.Cu")
		(net "GND")
	)
	(via
		(at 366.484662 -72.56526)
		(size 0.508)
		(drill 0.254)
		(layers "F.Cu" "B.Cu")
		(net "GND")
	)
	(via
		(at 338.435696 -341.805514)
		(size 0.4572)
		(drill 0.254)
		(layers "F.Cu" "B.Cu")
		(net "GND")
	)
	(via
		(at 257.895852 -353.465638)
		(size 0.508)
		(drill 0.254)
		(layers "F.Cu" "B.Cu")
		(net "GND")
	)
	(via
		(at 29.845254 -50.516282)
		(size 0.508)
		(drill 0.254)
		(layers "F.Cu" "B.Cu")
		(net "GND")
	)
	(via
		(at 287.612074 -358.391714)
		(size 0.4572)
		(drill 0.254)
		(layers "F.Cu" "B.Cu")
		(net "GND")
	)
	(via
		(at 57.749694 -272.14957)
		(size 0.4064)
		(drill 0.2032)
		(layers "F.Cu" "B.Cu")
		(net "GND")
	)
	(via
		(at 219.68968 -87.164672)
		(size 0.508)
		(drill 0.254)
		(layers "F.Cu" "B.Cu")
		(net "GND")
	)
	(via
		(at 115.34775 -371.140228)
		(size 0.4572)
		(drill 0.254)
		(layers "F.Cu" "B.Cu")
		(net "GND")
	)
	(via
		(at 56.324754 -293.52494)
		(size 0.4064)
		(drill 0.2032)
		(layers "F.Cu" "B.Cu")
		(net "GND")
	)
	(via
		(at 381.786384 -253.45644)
		(size 0.508)
		(drill 0.254)
		(layers "F.Cu" "B.Cu")
		(net "GND")
	)
	(via
		(at 414.124902 -287.824926)
		(size 0.4064)
		(drill 0.2032)
		(layers "F.Cu" "B.Cu")
		(net "GND")
	)
	(via
		(at 79.248 -417.82492)
		(size 0.508)
		(drill 0.254)
		(layers "F.Cu" "B.Cu")
		(net "GND")
	)
	(via
		(at 346.327984 -406.040336)
		(size 0.508)
		(drill 0.254)
		(layers "F.Cu" "B.Cu")
		(net "GND")
	)
	(via
		(at 201.478134 -35.635184)
		(size 0.508)
		(drill 0.254)
		(layers "F.Cu" "B.Cu")
		(net "GND")
	)
	(via
		(at 290.89985 -312.999882)
		(size 0.4064)
		(drill 0.2032)
		(layers "F.Cu" "B.Cu")
		(net "GND")
	)
	(via
		(at 329.045062 -239.002062)
		(size 0.508)
		(drill 0.254)
		(layers "F.Cu" "B.Cu")
		(net "GND")
	)
	(via
		(at 186.488832 -351.611438)
		(size 0.4064)
		(drill 0.2032)
		(layers "F.Cu" "B.Cu")
		(net "GND")
	)
	(via
		(at 277.02637 -343.073482)
		(size 0.4572)
		(drill 0.254)
		(layers "F.Cu" "B.Cu")
		(net "GND")
	)
	(via
		(at 390.902952 -346.09913)
		(size 0.4572)
		(drill 0.254)
		(layers "F.Cu" "B.Cu")
		(net "GND")
	)
	(via
		(at 132.38099 -25.990042)
		(size 0.508)
		(drill 0.254)
		(layers "F.Cu" "B.Cu")
		(net "GND")
	)
	(via
		(at 163.874958 -303.024794)
		(size 0.4064)
		(drill 0.2032)
		(layers "F.Cu" "B.Cu")
		(net "GND")
	)
	(via
		(at 188.119004 -344.831162)
		(size 0.4572)
		(drill 0.254)
		(layers "F.Cu" "B.Cu")
		(net "GND")
	)
	(via
		(at 272.102072 -57.461404)
		(size 0.508)
		(drill 0.254)
		(layers "F.Cu" "B.Cu")
		(net "GND")
	)
	(via
		(at 170.347894 -398.24025)
		(size 0.508)
		(drill 0.254)
		(layers "F.Cu" "B.Cu")
		(net "GND")
	)
	(via
		(at 166.356284 -341.805514)
		(size 0.4572)
		(drill 0.254)
		(layers "F.Cu" "B.Cu")
		(net "GND")
	)
	(via
		(at 420.054532 -351.611438)
		(size 0.4064)
		(drill 0.2032)
		(layers "F.Cu" "B.Cu")
		(net "GND")
	)
	(via
		(at 71.347838 -380.141734)
		(size 0.508)
		(drill 0.254)
		(layers "F.Cu" "B.Cu")
		(net "GND")
	)
	(via
		(at 130.34899 -33.19018)
		(size 0.508)
		(drill 0.254)
		(layers "F.Cu" "B.Cu")
		(net "GND")
	)
	(via
		(at 421.127682 -378.83846)
		(size 0.508)
		(drill 0.254)
		(layers "F.Cu" "B.Cu")
		(net "GND")
	)
	(via
		(at 98.866198 -94.25178)
		(size 0.508)
		(drill 0.254)
		(layers "F.Cu" "B.Cu")
		(net "GND")
	)
	(via
		(at 69.48551 -63.218314)
		(size 0.508)
		(drill 0.254)
		(layers "F.Cu" "B.Cu")
		(net "GND")
	)
	(via
		(at 153.233628 -120.833134)
		(size 0.508)
		(drill 0.254)
		(layers "F.Cu" "B.Cu")
		(net "GND")
	)
	(via
		(at 37.133784 -111.175546)
		(size 0.508)
		(drill 0.254)
		(layers "F.Cu" "B.Cu")
		(net "GND")
	)
	(via
		(at 172.547788 -397.140176)
		(size 0.508)
		(drill 0.254)
		(layers "F.Cu" "B.Cu")
		(net "GND")
	)
	(via
		(at 418.42436 -357.123746)
		(size 0.4572)
		(drill 0.254)
		(layers "F.Cu" "B.Cu")
		(net "GND")
	)
	(via
		(at 64.399922 -278.799798)
		(size 0.4064)
		(drill 0.2032)
		(layers "F.Cu" "B.Cu")
		(net "GND")
	)
	(via
		(at 205.932024 -124.108972)
		(size 0.508)
		(drill 0.254)
		(layers "F.Cu" "B.Cu")
		(net "GND")
	)
	(via
		(at 3.213608 -29.691076)
		(size 0.508)
		(drill 0.254)
		(layers "F.Cu" "B.Cu")
		(net "GND")
	)
	(via
		(at 148.94687 -1.135126)
		(size 0.508)
		(drill 0.254)
		(layers "F.Cu" "B.Cu")
		(net "GND")
	)
	(via
		(at 176.054512 -342.439498)
		(size 0.4064)
		(drill 0.2032)
		(layers "F.Cu" "B.Cu")
		(net "GND")
	)
	(via
		(at 409.849828 -311.099962)
		(size 0.4064)
		(drill 0.2032)
		(layers "F.Cu" "B.Cu")
		(net "GND")
	)
	(via
		(at 329.108816 -352.245422)
		(size 0.4572)
		(drill 0.254)
		(layers "F.Cu" "B.Cu")
		(net "GND")
	)
	(via
		(at 271.899888 -304.449734)
		(size 0.4064)
		(drill 0.2032)
		(layers "F.Cu" "B.Cu")
		(net "GND")
	)
	(via
		(at 266.020042 -33.19018)
		(size 0.508)
		(drill 0.254)
		(layers "F.Cu" "B.Cu")
		(net "GND")
	)
	(via
		(at 82.566002 -351.611438)
		(size 0.4064)
		(drill 0.2032)
		(layers "F.Cu" "B.Cu")
		(net "GND")
	)
	(via
		(at 267.017246 -327.733152)
		(size 0.508)
		(drill 0.254)
		(layers "F.Cu" "B.Cu")
		(net "GND")
	)
	(via
		(at 254.160274 -19.33956)
		(size 0.508)
		(drill 0.254)
		(layers "F.Cu" "B.Cu")
		(net "GND")
	)
	(via
		(at 306.049426 -259.55244)
		(size 0.508)
		(drill 0.254)
		(layers "F.Cu" "B.Cu")
		(net "GND")
	)
	(via
		(at 213.741 -197.144894)
		(size 0.508)
		(drill 0.254)
		(layers "F.Cu" "B.Cu")
		(net "GND")
	)
	(via
		(at 440.202066 -56.826404)
		(size 0.508)
		(drill 0.254)
		(layers "F.Cu" "B.Cu")
		(net "GND")
	)
	(via
		(at 164.349938 -276.899878)
		(size 0.4064)
		(drill 0.2032)
		(layers "F.Cu" "B.Cu")
		(net "GND")
	)
	(via
		(at 233.611166 -69.74332)
		(size 0.508)
		(drill 0.254)
		(layers "F.Cu" "B.Cu")
		(net "GND")
	)
	(via
		(at 335.326736 -341.805514)
		(size 0.4572)
		(drill 0.254)
		(layers "F.Cu" "B.Cu")
		(net "GND")
	)
	(via
		(at 182.348886 -29.589984)
		(size 0.508)
		(drill 0.254)
		(layers "F.Cu" "B.Cu")
		(net "GND")
	)
	(via
		(at 443.829186 -117.426486)
		(size 0.508)
		(drill 0.254)
		(layers "F.Cu" "B.Cu")
		(net "GND")
	)
	(via
		(at 187.790582 -119.414544)
		(size 0.508)
		(drill 0.254)
		(layers "F.Cu" "B.Cu")
		(net "GND")
	)
	(via
		(at 453.554084 -106.779822)
		(size 0.508)
		(drill 0.254)
		(layers "F.Cu" "B.Cu")
		(net "GND")
	)
	(via
		(at 82.924904 -296.37482)
		(size 0.4064)
		(drill 0.2032)
		(layers "F.Cu" "B.Cu")
		(net "GND")
	)
	(via
		(at 450.274944 -73.87463)
		(size 0.508)
		(drill 0.254)
		(layers "F.Cu" "B.Cu")
		(net "GND")
	)
	(via
		(at 72.267064 -145.755106)
		(size 0.508)
		(drill 0.254)
		(layers "F.Cu" "B.Cu")
		(net "GND")
	)
	(via
		(at 404.145242 -50.516282)
		(size 0.508)
		(drill 0.254)
		(layers "F.Cu" "B.Cu")
		(net "GND")
	)
	(via
		(at 414.74771 -129.445004)
		(size 0.508)
		(drill 0.254)
		(layers "F.Cu" "B.Cu")
		(net "GND")
	)
	(via
		(at 12.212066 -387.512814)
		(size 0.508)
		(drill 0.254)
		(layers "F.Cu" "B.Cu")
		(net "GND")
	)
	(via
		(at 272.849848 -309.199788)
		(size 0.4064)
		(drill 0.2032)
		(layers "F.Cu" "B.Cu")
		(net "GND")
	)
	(via
		(at 191.899794 -276.899878)
		(size 0.4064)
		(drill 0.2032)
		(layers "F.Cu" "B.Cu")
		(net "GND")
	)
	(via
		(at 192.375028 -293.52494)
		(size 0.4064)
		(drill 0.2032)
		(layers "F.Cu" "B.Cu")
		(net "GND")
	)
	(via
		(at 466.835998 -343.723976)
		(size 0.508)
		(drill 0.254)
		(layers "F.Cu" "B.Cu")
		(net "GND")
	)
	(via
		(at 286.927798 -384.041904)
		(size 0.508)
		(drill 0.254)
		(layers "F.Cu" "B.Cu")
		(net "GND")
	)
	(via
		(at 200.700894 -31.390336)
		(size 0.508)
		(drill 0.254)
		(layers "F.Cu" "B.Cu")
		(net "GND")
	)
	(via
		(at 68.199762 -273.099784)
		(size 0.4064)
		(drill 0.2032)
		(layers "F.Cu" "B.Cu")
		(net "GND")
	)
	(via
		(at 234.671108 -84.432394)
		(size 0.508)
		(drill 0.254)
		(layers "F.Cu" "B.Cu")
		(net "GND")
	)
	(via
		(at 355.492558 -6.292342)
		(size 0.508)
		(drill 0.254)
		(layers "F.Cu" "B.Cu")
		(net "GND")
	)
	(via
		(at 372.999 -247.441974)
		(size 0.508)
		(drill 0.254)
		(layers "F.Cu" "B.Cu")
		(net "GND")
	)
	(via
		(at 370.990368 -346.09913)
		(size 0.4572)
		(drill 0.254)
		(layers "F.Cu" "B.Cu")
		(net "GND")
	)
	(via
		(at 188.63437 -367.216182)
		(size 0.508)
		(drill 0.254)
		(layers "F.Cu" "B.Cu")
		(net "GND")
	)
	(via
		(at 398.971008 -354.074222)
		(size 0.4572)
		(drill 0.254)
		(layers "F.Cu" "B.Cu")
		(net "GND")
	)
	(via
		(at 385.927854 -382.73863)
		(size 0.508)
		(drill 0.254)
		(layers "F.Cu" "B.Cu")
		(net "GND")
	)
	(via
		(at 304.36947 -111.016288)
		(size 0.508)
		(drill 0.254)
		(layers "F.Cu" "B.Cu")
		(net "GND")
	)
	(via
		(at 71.65467 -23.880318)
		(size 0.508)
		(drill 0.254)
		(layers "F.Cu" "B.Cu")
		(net "GND")
	)
	(via
		(at 344.533982 -286.842454)
		(size 0.508)
		(drill 0.254)
		(layers "F.Cu" "B.Cu")
		(net "GND")
	)
	(via
		(at 75.79995 -278.799798)
		(size 0.4064)
		(drill 0.2032)
		(layers "F.Cu" "B.Cu")
		(net "GND")
	)
	(via
		(at 295.88079 -25.990042)
		(size 0.508)
		(drill 0.254)
		(layers "F.Cu" "B.Cu")
		(net "GND")
	)
	(via
		(at 398.4498 -314.899802)
		(size 0.4064)
		(drill 0.2032)
		(layers "F.Cu" "B.Cu")
		(net "GND")
	)
	(via
		(at 278.074882 -290.674806)
		(size 0.4064)
		(drill 0.2032)
		(layers "F.Cu" "B.Cu")
		(net "GND")
	)
	(via
		(at 29.72054 -346.09913)
		(size 0.4572)
		(drill 0.254)
		(layers "F.Cu" "B.Cu")
		(net "GND")
	)
	(via
		(at 144.772126 -49.574704)
		(size 0.508)
		(drill 0.254)
		(layers "F.Cu" "B.Cu")
		(net "GND")
	)
	(via
		(at 73.547732 -399.441924)
		(size 0.508)
		(drill 0.254)
		(layers "F.Cu" "B.Cu")
		(net "GND")
	)
	(via
		(at 276.649688 -315.849762)
		(size 0.4064)
		(drill 0.2032)
		(layers "F.Cu" "B.Cu")
		(net "GND")
	)
	(via
		(at 284.724856 -293.52494)
		(size 0.4064)
		(drill 0.2032)
		(layers "F.Cu" "B.Cu")
		(net "GND")
	)
	(via
		(at 303.719992 -57.076848)
		(size 0.508)
		(drill 0.254)
		(layers "F.Cu" "B.Cu")
		(net "GND")
	)
	(via
		(at 246.839232 -216.215468)
		(size 0.508)
		(drill 0.254)
		(layers "F.Cu" "B.Cu")
		(net "GND")
	)
	(via
		(at 184.034938 -243.404898)
		(size 0.508)
		(drill 0.254)
		(layers "F.Cu" "B.Cu")
		(net "GND")
	)
	(via
		(at 40.526208 -348.58579)
		(size 0.4064)
		(drill 0.2032)
		(layers "F.Cu" "B.Cu")
		(net "GND")
	)
	(via
		(at 300.12767 -397.140176)
		(size 0.508)
		(drill 0.254)
		(layers "F.Cu" "B.Cu")
		(net "GND")
	)
	(via
		(at 67.66687 -118.234968)
		(size 0.508)
		(drill 0.254)
		(layers "F.Cu" "B.Cu")
		(net "GND")
	)
	(via
		(at 194.651376 -103.104696)
		(size 0.508)
		(drill 0.254)
		(layers "F.Cu" "B.Cu")
		(net "GND")
	)
	(via
		(at 423.639996 -73.23963)
		(size 0.508)
		(drill 0.254)
		(layers "F.Cu" "B.Cu")
		(net "GND")
	)
	(via
		(at 183.766714 -151.155146)
		(size 0.508)
		(drill 0.254)
		(layers "F.Cu" "B.Cu")
		(net "GND")
	)
	(via
		(at 189.999874 -310.149748)
		(size 0.4064)
		(drill 0.2032)
		(layers "F.Cu" "B.Cu")
		(net "GND")
	)
	(via
		(at 221.350078 -416.508438)
		(size 0.508)
		(drill 0.254)
		(layers "F.Cu" "B.Cu")
		(net "GND")
	)
	(via
		(at 194.749928 -309.199788)
		(size 0.4064)
		(drill 0.2032)
		(layers "F.Cu" "B.Cu")
		(net "GND")
	)
	(via
		(at 385.284726 -151.045672)
		(size 0.508)
		(drill 0.254)
		(layers "F.Cu" "B.Cu")
		(net "GND")
	)
	(via
		(at 160.284668 -72.56526)
		(size 0.508)
		(drill 0.254)
		(layers "F.Cu" "B.Cu")
		(net "GND")
	)
	(via
		(at 100.68941 -278.708612)
		(size 0.508)
		(drill 0.254)
		(layers "F.Cu" "B.Cu")
		(net "GND")
	)
	(via
		(at 190.348108 -154.755088)
		(size 0.508)
		(drill 0.254)
		(layers "F.Cu" "B.Cu")
		(net "GND")
	)
	(via
		(at 397.02486 -305.874928)
		(size 0.4064)
		(drill 0.2032)
		(layers "F.Cu" "B.Cu")
		(net "GND")
	)
	(via
		(at 308.02072 -113.260632)
		(size 0.508)
		(drill 0.254)
		(layers "F.Cu" "B.Cu")
		(net "GND")
	)
	(via
		(at 137.446766 -213.07171)
		(size 0.508)
		(drill 0.254)
		(layers "F.Cu" "B.Cu")
		(net "GND")
	)
	(via
		(at 423.15003 -316.799722)
		(size 0.4064)
		(drill 0.2032)
		(layers "F.Cu" "B.Cu")
		(net "GND")
	)
	(via
		(at 300.874684 -289.724846)
		(size 0.4064)
		(drill 0.2032)
		(layers "F.Cu" "B.Cu")
		(net "GND")
	)
	(via
		(at 158.649924 -315.849762)
		(size 0.4064)
		(drill 0.2032)
		(layers "F.Cu" "B.Cu")
		(net "GND")
	)
	(via
		(at 129.23774 -293.424102)
		(size 0.508)
		(drill 0.254)
		(layers "F.Cu" "B.Cu")
		(net "GND")
	)
	(via
		(at 382.791716 -123.885452)
		(size 0.508)
		(drill 0.254)
		(layers "F.Cu" "B.Cu")
		(net "GND")
	)
	(via
		(at 130.26263 -110.365032)
		(size 0.508)
		(drill 0.254)
		(layers "F.Cu" "B.Cu")
		(net "GND")
	)
	(via
		(at 64.691768 -109.481366)
		(size 0.508)
		(drill 0.254)
		(layers "F.Cu" "B.Cu")
		(net "GND")
	)
	(via
		(at 126.347728 -397.038576)
		(size 0.508)
		(drill 0.254)
		(layers "F.Cu" "B.Cu")
		(net "GND")
	)
	(via
		(at 170.524932 -284.024832)
		(size 0.4064)
		(drill 0.2032)
		(layers "F.Cu" "B.Cu")
		(net "GND")
	)
	(via
		(at 71.049896 -281.649932)
		(size 0.4064)
		(drill 0.2032)
		(layers "F.Cu" "B.Cu")
		(net "GND")
	)
	(via
		(at 405.892 -377.444)
		(size 0.508)
		(drill 0.254)
		(layers "F.Cu" "B.Cu")
		(net "GND")
	)
	(via
		(at 297.927776 -402.140166)
		(size 0.508)
		(drill 0.254)
		(layers "F.Cu" "B.Cu")
		(net "GND")
	)
	(via
		(at 312.749692 -319.65011)
		(size 0.4064)
		(drill 0.2032)
		(layers "F.Cu" "B.Cu")
		(net "GND")
	)
	(via
		(at 119.25173 -259.918962)
		(size 0.508)
		(drill 0.254)
		(layers "F.Cu" "B.Cu")
		(net "GND")
	)
	(via
		(at 146.887692 -308.65953)
		(size 0.508)
		(drill 0.254)
		(layers "F.Cu" "B.Cu")
		(net "GND")
	)
	(via
		(at 137.795 -355.366066)
		(size 0.4572)
		(drill 0.254)
		(layers "F.Cu" "B.Cu")
		(net "GND")
	)
	(via
		(at 48.72482 -303.974754)
		(size 0.4064)
		(drill 0.2032)
		(layers "F.Cu" "B.Cu")
		(net "GND")
	)
	(via
		(at 114.966242 -293.424102)
		(size 0.508)
		(drill 0.254)
		(layers "F.Cu" "B.Cu")
		(net "GND")
	)
	(via
		(at 282.349702 -310.149748)
		(size 0.4064)
		(drill 0.2032)
		(layers "F.Cu" "B.Cu")
		(net "GND")
	)
	(via
		(at 243.944902 -29.589984)
		(size 0.508)
		(drill 0.254)
		(layers "F.Cu" "B.Cu")
		(net "GND")
	)
	(via
		(at 465.203794 -248.637552)
		(size 0.508)
		(drill 0.254)
		(layers "F.Cu" "B.Cu")
		(net "GND")
	)
	(via
		(at 335.350866 -288.14649)
		(size 0.508)
		(drill 0.254)
		(layers "F.Cu" "B.Cu")
		(net "GND")
	)
	(via
		(at 91.919298 -126.049532)
		(size 0.508)
		(drill 0.254)
		(layers "F.Cu" "B.Cu")
		(net "GND")
	)
	(via
		(at 64.59347 -131.245102)
		(size 0.508)
		(drill 0.254)
		(layers "F.Cu" "B.Cu")
		(net "GND")
	)
	(via
		(at 385.149852 -300.649894)
		(size 0.4064)
		(drill 0.2032)
		(layers "F.Cu" "B.Cu")
		(net "GND")
	)
	(via
		(at 279.499822 -273.099784)
		(size 0.4064)
		(drill 0.2032)
		(layers "F.Cu" "B.Cu")
		(net "GND")
	)
	(via
		(at 180.02504 -303.974754)
		(size 0.4064)
		(drill 0.2032)
		(layers "F.Cu" "B.Cu")
		(net "GND")
	)
	(via
		(at 314.174886 -303.024794)
		(size 0.4064)
		(drill 0.2032)
		(layers "F.Cu" "B.Cu")
		(net "GND")
	)
	(via
		(at 3.04673 -389.924036)
		(size 0.508)
		(drill 0.254)
		(layers "F.Cu" "B.Cu")
		(net "GND")
	)
	(via
		(at 413.649922 -280.699718)
		(size 0.4064)
		(drill 0.2032)
		(layers "F.Cu" "B.Cu")
		(net "GND")
	)
	(via
		(at 300.874684 -287.824926)
		(size 0.4064)
		(drill 0.2032)
		(layers "F.Cu" "B.Cu")
		(net "GND")
	)
	(via
		(at 105.22712 -346.090494)
		(size 0.508)
		(drill 0.254)
		(layers "F.Cu" "B.Cu")
		(net "GND")
	)
	(via
		(at 379.9459 -357.75773)
		(size 0.4064)
		(drill 0.2032)
		(layers "F.Cu" "B.Cu")
		(net "GND")
	)
	(via
		(at 68.199762 -317.749936)
		(size 0.4064)
		(drill 0.2032)
		(layers "F.Cu" "B.Cu")
		(net "GND")
	)
	(via
		(at 28.461716 -350.977454)
		(size 0.4572)
		(drill 0.254)
		(layers "F.Cu" "B.Cu")
		(net "GND")
	)
	(via
		(at 346.441014 -265.949938)
		(size 0.508)
		(drill 0.254)
		(layers "F.Cu" "B.Cu")
		(net "GND")
	)
	(via
		(at 288.049462 -272.14957)
		(size 0.4064)
		(drill 0.2032)
		(layers "F.Cu" "B.Cu")
		(net "GND")
	)
	(via
		(at 298.012612 -145.755106)
		(size 0.508)
		(drill 0.254)
		(layers "F.Cu" "B.Cu")
		(net "GND")
	)
	(via
		(at 302.774858 -301.124874)
		(size 0.4064)
		(drill 0.2032)
		(layers "F.Cu" "B.Cu")
		(net "GND")
	)
	(via
		(at 50.149506 -272.14957)
		(size 0.4064)
		(drill 0.2032)
		(layers "F.Cu" "B.Cu")
		(net "GND")
	)
	(via
		(at 310.849518 -276.899878)
		(size 0.4064)
		(drill 0.2032)
		(layers "F.Cu" "B.Cu")
		(net "GND")
	)
	(via
		(at 110.676182 -288.14649)
		(size 0.508)
		(drill 0.254)
		(layers "F.Cu" "B.Cu")
		(net "GND")
	)
	(via
		(at 395.332966 -98.845116)
		(size 0.508)
		(drill 0.254)
		(layers "F.Cu" "B.Cu")
		(net "GND")
	)
	(via
		(at 82.166206 -146.017996)
		(size 0.508)
		(drill 0.254)
		(layers "F.Cu" "B.Cu")
		(net "GND")
	)
	(via
		(at 433.108354 -135.114538)
		(size 0.508)
		(drill 0.254)
		(layers "F.Cu" "B.Cu")
		(net "GND")
	)
	(via
		(at 248.1961 -85.209888)
		(size 0.508)
		(drill 0.254)
		(layers "F.Cu" "B.Cu")
		(net "GND")
	)
	(via
		(at 269.524734 -275.474938)
		(size 0.4064)
		(drill 0.2032)
		(layers "F.Cu" "B.Cu")
		(net "GND")
	)
	(via
		(at 403.00656 -104.244902)
		(size 0.508)
		(drill 0.254)
		(layers "F.Cu" "B.Cu")
		(net "GND")
	)
	(via
		(at 61.549788 -276.899878)
		(size 0.4064)
		(drill 0.2032)
		(layers "F.Cu" "B.Cu")
		(net "GND")
	)
	(via
		(at 172.81525 -60.601606)
		(size 0.508)
		(drill 0.254)
		(layers "F.Cu" "B.Cu")
		(net "GND")
	)
	(via
		(at 418.124132 -130.710432)
		(size 0.508)
		(drill 0.254)
		(layers "F.Cu" "B.Cu")
		(net "GND")
	)
	(via
		(at 330.958952 -352.245422)
		(size 0.4572)
		(drill 0.254)
		(layers "F.Cu" "B.Cu")
		(net "GND")
	)
	(via
		(at 406.524968 -303.974754)
		(size 0.4064)
		(drill 0.2032)
		(layers "F.Cu" "B.Cu")
		(net "GND")
	)
	(via
		(at 261.666736 -73.332086)
		(size 0.508)
		(drill 0.254)
		(layers "F.Cu" "B.Cu")
		(net "GND")
	)
	(via
		(at 231.867456 -216.304368)
		(size 0.4572)
		(drill 0.254)
		(layers "F.Cu" "B.Cu")
		(net "GND")
	)
	(via
		(at 5.963666 -75.087226)
		(size 0.508)
		(drill 0.254)
		(layers "F.Cu" "B.Cu")
		(net "GND")
	)
	(via
		(at 346.493592 -212.38718)
		(size 0.4572)
		(drill 0.254)
		(layers "F.Cu" "B.Cu")
		(net "GND")
	)
	(via
		(at 199.284844 -105.029)
		(size 0.508)
		(drill 0.254)
		(layers "F.Cu" "B.Cu")
		(net "GND")
	)
	(via
		(at 431.840386 -120.30456)
		(size 0.508)
		(drill 0.254)
		(layers "F.Cu" "B.Cu")
		(net "GND")
	)
	(via
		(at 80.898238 -146.017996)
		(size 0.508)
		(drill 0.254)
		(layers "F.Cu" "B.Cu")
		(net "GND")
	)
	(via
		(at 17.473422 -72.56526)
		(size 0.508)
		(drill 0.254)
		(layers "F.Cu" "B.Cu")
		(net "GND")
	)
	(via
		(at 81.024984 -296.37482)
		(size 0.4064)
		(drill 0.2032)
		(layers "F.Cu" "B.Cu")
		(net "GND")
	)
	(via
		(at 281.765502 -342.439498)
		(size 0.4064)
		(drill 0.2032)
		(layers "F.Cu" "B.Cu")
		(net "GND")
	)
	(via
		(at 357.948992 -34.990024)
		(size 0.508)
		(drill 0.254)
		(layers "F.Cu" "B.Cu")
		(net "GND")
	)
	(via
		(at 390.902952 -343.073482)
		(size 0.4572)
		(drill 0.254)
		(layers "F.Cu" "B.Cu")
		(net "GND")
	)
	(via
		(at 54.348126 -369.136422)
		(size 0.4064)
		(drill 0.2032)
		(layers "F.Cu" "B.Cu")
		(net "GND")
	)
	(via
		(at 39.04742 -350.977454)
		(size 0.4572)
		(drill 0.254)
		(layers "F.Cu" "B.Cu")
		(net "GND")
	)
	(via
		(at 414.944052 -357.75773)
		(size 0.4064)
		(drill 0.2032)
		(layers "F.Cu" "B.Cu")
		(net "GND")
	)
	(via
		(at 154.501596 -106.316526)
		(size 0.508)
		(drill 0.254)
		(layers "F.Cu" "B.Cu")
		(net "GND")
	)
	(via
		(at 401.299934 -281.649932)
		(size 0.4064)
		(drill 0.2032)
		(layers "F.Cu" "B.Cu")
		(net "GND")
	)
	(via
		(at 127.209296 -347.951806)
		(size 0.4572)
		(drill 0.254)
		(layers "F.Cu" "B.Cu")
		(net "GND")
	)
	(via
		(at 294.69969 -278.799798)
		(size 0.4064)
		(drill 0.2032)
		(layers "F.Cu" "B.Cu")
		(net "GND")
	)
	(via
		(at 435.948836 -25.990042)
		(size 0.508)
		(drill 0.254)
		(layers "F.Cu" "B.Cu")
		(net "GND")
	)
	(via
		(at 63.449962 -281.649932)
		(size 0.4064)
		(drill 0.2032)
		(layers "F.Cu" "B.Cu")
		(net "GND")
	)
	(via
		(at 395.332966 -120.555004)
		(size 0.508)
		(drill 0.254)
		(layers "F.Cu" "B.Cu")
		(net "GND")
	)
	(via
		(at 263.854184 -193.871088)
		(size 0.508)
		(drill 0.254)
		(layers "F.Cu" "B.Cu")
		(net "GND")
	)
	(via
		(at 27.347926 -406.141936)
		(size 0.508)
		(drill 0.254)
		(layers "F.Cu" "B.Cu")
		(net "GND")
	)
	(via
		(at 17.398238 -114.351054)
		(size 0.508)
		(drill 0.254)
		(layers "F.Cu" "B.Cu")
		(net "GND")
	)
	(via
		(at 187.624974 -305.874928)
		(size 0.4064)
		(drill 0.2032)
		(layers "F.Cu" "B.Cu")
		(net "GND")
	)
	(via
		(at 163.63061 -65.15989)
		(size 0.508)
		(drill 0.254)
		(layers "F.Cu" "B.Cu")
		(net "GND")
	)
	(via
		(at 432.12766 -380.141734)
		(size 0.508)
		(drill 0.254)
		(layers "F.Cu" "B.Cu")
		(net "GND")
	)
	(via
		(at 48.72482 -306.824888)
		(size 0.4064)
		(drill 0.2032)
		(layers "F.Cu" "B.Cu")
		(net "GND")
	)
	(via
		(at 174.325026 -285.924752)
		(size 0.4064)
		(drill 0.2032)
		(layers "F.Cu" "B.Cu")
		(net "GND")
	)
	(via
		(at 192.075054 -73.23963)
		(size 0.508)
		(drill 0.254)
		(layers "F.Cu" "B.Cu")
		(net "GND")
	)
	(via
		(at 412.20644 -349.219774)
		(size 0.4572)
		(drill 0.254)
		(layers "F.Cu" "B.Cu")
		(net "GND")
	)
	(via
		(at 299.749972 -109.244892)
		(size 0.508)
		(drill 0.254)
		(layers "F.Cu" "B.Cu")
		(net "GND")
	)
	(via
		(at 339.037422 -306.607718)
		(size 0.508)
		(drill 0.254)
		(layers "F.Cu" "B.Cu")
		(net "GND")
	)
	(via
		(at 9.648952 -29.589984)
		(size 0.508)
		(drill 0.254)
		(layers "F.Cu" "B.Cu")
		(net "GND")
	)
	(via
		(at 161.6202 -57.076848)
		(size 0.508)
		(drill 0.254)
		(layers "F.Cu" "B.Cu")
		(net "GND")
	)
	(via
		(at 401.774914 -294.4749)
		(size 0.4064)
		(drill 0.2032)
		(layers "F.Cu" "B.Cu")
		(net "GND")
	)
	(via
		(at 139.645136 -350.977454)
		(size 0.4572)
		(drill 0.254)
		(layers "F.Cu" "B.Cu")
		(net "GND")
	)
	(via
		(at 293.527734 -382.73863)
		(size 0.508)
		(drill 0.254)
		(layers "F.Cu" "B.Cu")
		(net "GND")
	)
	(via
		(at 74.919586 -2.818638)
		(size 0.508)
		(drill 0.254)
		(layers "F.Cu" "B.Cu")
		(net "GND")
	)
	(via
		(at 86.767924 -54.238906)
		(size 0.508)
		(drill 0.254)
		(layers "F.Cu" "B.Cu")
		(net "GND")
	)
	(via
		(at 134.319264 -147.18665)
		(size 0.508)
		(drill 0.254)
		(layers "F.Cu" "B.Cu")
		(net "GND")
	)
	(via
		(at 53.840126 -33.857692)
		(size 0.508)
		(drill 0.254)
		(layers "F.Cu" "B.Cu")
		(net "GND")
	)
	(via
		(at 412.20644 -343.073482)
		(size 0.4572)
		(drill 0.254)
		(layers "F.Cu" "B.Cu")
		(net "GND")
	)
	(via
		(at 81.974944 -299.224954)
		(size 0.4064)
		(drill 0.2032)
		(layers "F.Cu" "B.Cu")
		(net "GND")
	)
	(via
		(at 450.4944 -229.3112)
		(size 0.508)
		(drill 0.254)
		(layers "F.Cu" "B.Cu")
		(net "GND")
	)
	(via
		(at 141.812264 -23.355554)
		(size 0.508)
		(drill 0.254)
		(layers "F.Cu" "B.Cu")
		(net "GND")
	)
	(via
		(at 103.658162 -172.22724)
		(size 0.508)
		(drill 0.254)
		(layers "F.Cu" "B.Cu")
		(net "GND")
	)
	(via
		(at 186.067446 -134.400544)
		(size 0.508)
		(drill 0.254)
		(layers "F.Cu" "B.Cu")
		(net "GND")
	)
	(via
		(at 284.610048 -156.802328)
		(size 0.508)
		(drill 0.254)
		(layers "F.Cu" "B.Cu")
		(net "GND")
	)
	(via
		(at 176.94783 -398.34185)
		(size 0.508)
		(drill 0.254)
		(layers "F.Cu" "B.Cu")
		(net "GND")
	)
	(via
		(at 421.127682 -382.73863)
		(size 0.508)
		(drill 0.254)
		(layers "F.Cu" "B.Cu")
		(net "GND")
	)
	(via
		(at 70.50151 -347.951806)
		(size 0.4572)
		(drill 0.254)
		(layers "F.Cu" "B.Cu")
		(net "GND")
	)
	(via
		(at 22.243796 -343.073482)
		(size 0.4572)
		(drill 0.254)
		(layers "F.Cu" "B.Cu")
		(net "GND")
	)
	(via
		(at 289.47491 -291.624766)
		(size 0.4064)
		(drill 0.2032)
		(layers "F.Cu" "B.Cu")
		(net "GND")
	)
	(via
		(at 410.356304 -350.977454)
		(size 0.4572)
		(drill 0.254)
		(layers "F.Cu" "B.Cu")
		(net "GND")
	)
	(via
		(at 85.192616 -6.292342)
		(size 0.508)
		(drill 0.254)
		(layers "F.Cu" "B.Cu")
		(net "GND")
	)
	(via
		(at 65.913762 -354.732082)
		(size 0.4064)
		(drill 0.2032)
		(layers "F.Cu" "B.Cu")
		(net "GND")
	)
	(via
		(at 380.90094 -34.990278)
		(size 0.508)
		(drill 0.254)
		(layers "F.Cu" "B.Cu")
		(net "GND")
	)
	(via
		(at 394.38326 -348.58579)
		(size 0.4064)
		(drill 0.2032)
		(layers "F.Cu" "B.Cu")
		(net "GND")
	)
	(via
		(at 43.635168 -348.58579)
		(size 0.4064)
		(drill 0.2032)
		(layers "F.Cu" "B.Cu")
		(net "GND")
	)
	(via
		(at 196.998082 -123.356878)
		(size 0.508)
		(drill 0.254)
		(layers "F.Cu" "B.Cu")
		(net "GND")
	)
	(via
		(at 40.24884 -29.589984)
		(size 0.508)
		(drill 0.254)
		(layers "F.Cu" "B.Cu")
		(net "GND")
	)
	(via
		(at 293.74973 -281.649932)
		(size 0.4064)
		(drill 0.2032)
		(layers "F.Cu" "B.Cu")
		(net "GND")
	)
	(via
		(at 31.570676 -341.805514)
		(size 0.4572)
		(drill 0.254)
		(layers "F.Cu" "B.Cu")
		(net "GND")
	)
	(via
		(at 132.459476 -145.53565)
		(size 0.508)
		(drill 0.254)
		(layers "F.Cu" "B.Cu")
		(net "GND")
	)
	(via
		(at 107.99445 -279.086818)
		(size 0.508)
		(drill 0.254)
		(layers "F.Cu" "B.Cu")
		(net "GND")
	)
	(via
		(at 399.400014 -317.749936)
		(size 0.4064)
		(drill 0.2032)
		(layers "F.Cu" "B.Cu")
		(net "GND")
	)
	(via
		(at 370.260372 -19.33956)
		(size 0.508)
		(drill 0.254)
		(layers "F.Cu" "B.Cu")
		(net "GND")
	)
	(via
		(at 297.927776 -376.140218)
		(size 0.508)
		(drill 0.254)
		(layers "F.Cu" "B.Cu")
		(net "GND")
	)
	(via
		(at 39.224966 -277.374858)
		(size 0.4064)
		(drill 0.2032)
		(layers "F.Cu" "B.Cu")
		(net "GND")
	)
	(via
		(at 278.87295 -23.880318)
		(size 0.508)
		(drill 0.254)
		(layers "F.Cu" "B.Cu")
		(net "GND")
	)
	(via
		(at 24.369522 -96.000062)
		(size 0.508)
		(drill 0.254)
		(layers "F.Cu" "B.Cu")
		(net "GND")
	)
	(via
		(at 209.679032 -232.122726)
		(size 0.508)
		(drill 0.254)
		(layers "F.Cu" "B.Cu")
		(net "GND")
	)
	(via
		(at 416.499802 -314.899802)
		(size 0.4064)
		(drill 0.2032)
		(layers "F.Cu" "B.Cu")
		(net "GND")
	)
	(via
		(at 78.64983 -283.549852)
		(size 0.4064)
		(drill 0.2032)
		(layers "F.Cu" "B.Cu")
		(net "GND")
	)
	(via
		(at 86.747858 -406.040336)
		(size 0.508)
		(drill 0.254)
		(layers "F.Cu" "B.Cu")
		(net "GND")
	)
	(via
		(at 22.243796 -347.92793)
		(size 0.4572)
		(drill 0.254)
		(layers "F.Cu" "B.Cu")
		(net "GND")
	)
	(via
		(at 451.638162 -102.021894)
		(size 0.508)
		(drill 0.254)
		(layers "F.Cu" "B.Cu")
		(net "GND")
	)
	(via
		(at 80.54975 -319.65011)
		(size 0.4064)
		(drill 0.2032)
		(layers "F.Cu" "B.Cu")
		(net "GND")
	)
	(via
		(at 174.349918 -287.699958)
		(size 0.4064)
		(drill 0.2032)
		(layers "F.Cu" "B.Cu")
		(net "GND")
	)
	(via
		(at 47.032926 -120.555004)
		(size 0.508)
		(drill 0.254)
		(layers "F.Cu" "B.Cu")
		(net "GND")
	)
	(via
		(at 314.045092 -51.227482)
		(size 0.508)
		(drill 0.254)
		(layers "F.Cu" "B.Cu")
		(net "GND")
	)
	(via
		(at 75.706986 -0.762)
		(size 0.508)
		(drill 0.254)
		(layers "F.Cu" "B.Cu")
		(net "GND")
	)
	(via
		(at 435.227984 -346.09913)
		(size 0.4572)
		(drill 0.254)
		(layers "F.Cu" "B.Cu")
		(net "GND")
	)
	(via
		(at 281.874722 -306.824888)
		(size 0.4064)
		(drill 0.2032)
		(layers "F.Cu" "B.Cu")
		(net "GND")
	)
	(via
		(at 171.9453 -50.516282)
		(size 0.508)
		(drill 0.254)
		(layers "F.Cu" "B.Cu")
		(net "GND")
	)
	(via
		(at 110.034324 -268.731492)
		(size 0.508)
		(drill 0.254)
		(layers "F.Cu" "B.Cu")
		(net "GND")
	)
	(via
		(at 114.808 -417.82492)
		(size 0.508)
		(drill 0.254)
		(layers "F.Cu" "B.Cu")
		(net "GND")
	)
	(via
		(at 48.745648 -345.465146)
		(size 0.4064)
		(drill 0.2032)
		(layers "F.Cu" "B.Cu")
		(net "GND")
	)
	(via
		(at 47.77486 -301.124874)
		(size 0.4064)
		(drill 0.2032)
		(layers "F.Cu" "B.Cu")
		(net "GND")
	)
	(via
		(at 400.349974 -274.999958)
		(size 0.4064)
		(drill 0.2032)
		(layers "F.Cu" "B.Cu")
		(net "GND")
	)
	(via
		(at 330.927964 -384.041904)
		(size 0.508)
		(drill 0.254)
		(layers "F.Cu" "B.Cu")
		(net "GND")
	)
	(via
		(at 81.974944 -289.724846)
		(size 0.4064)
		(drill 0.2032)
		(layers "F.Cu" "B.Cu")
		(net "GND")
	)
	(via
		(at 389.424926 -299.224954)
		(size 0.4064)
		(drill 0.2032)
		(layers "F.Cu" "B.Cu")
		(net "GND")
	)
	(via
		(at 415.549842 -314.899802)
		(size 0.4064)
		(drill 0.2032)
		(layers "F.Cu" "B.Cu")
		(net "GND")
	)
	(via
		(at 77.978254 -349.219774)
		(size 0.4572)
		(drill 0.254)
		(layers "F.Cu" "B.Cu")
		(net "GND")
	)
	(via
		(at 281.399742 -274.049744)
		(size 0.4064)
		(drill 0.2032)
		(layers "F.Cu" "B.Cu")
		(net "GND")
	)
	(via
		(at 238.757968 -140.392404)
		(size 0.508)
		(drill 0.254)
		(layers "F.Cu" "B.Cu")
		(net "GND")
	)
	(via
		(at 169.587164 -133.564884)
		(size 0.508)
		(drill 0.254)
		(layers "F.Cu" "B.Cu")
		(net "GND")
	)
	(via
		(at 116.035328 -329.976734)
		(size 0.508)
		(drill 0.254)
		(layers "F.Cu" "B.Cu")
		(net "GND")
	)
	(via
		(at 117.882416 -355.366066)
		(size 0.4572)
		(drill 0.254)
		(layers "F.Cu" "B.Cu")
		(net "GND")
	)
	(via
		(at 186.200034 -314.899802)
		(size 0.4064)
		(drill 0.2032)
		(layers "F.Cu" "B.Cu")
		(net "GND")
	)
	(via
		(at 71.347838 -372.341902)
		(size 0.508)
		(drill 0.254)
		(layers "F.Cu" "B.Cu")
		(net "GND")
	)
	(via
		(at 229.794562 -329.539092)
		(size 0.508)
		(drill 0.254)
		(layers "F.Cu" "B.Cu")
		(net "GND")
	)
	(via
		(at 190.348108 -152.95499)
		(size 0.508)
		(drill 0.254)
		(layers "F.Cu" "B.Cu")
		(net "GND")
	)
	(via
		(at 72.267064 -143.955008)
		(size 0.508)
		(drill 0.254)
		(layers "F.Cu" "B.Cu")
		(net "GND")
	)
	(via
		(at 102.428802 -292.781736)
		(size 0.508)
		(drill 0.254)
		(layers "F.Cu" "B.Cu")
		(net "GND")
	)
	(via
		(at 35.6489 -27.79014)
		(size 0.508)
		(drill 0.254)
		(layers "F.Cu" "B.Cu")
		(net "GND")
	)
	(via
		(at 175.749966 -310.149748)
		(size 0.4064)
		(drill 0.2032)
		(layers "F.Cu" "B.Cu")
		(net "GND")
	)
	(via
		(at 83.540346 -136.373362)
		(size 0.508)
		(drill 0.254)
		(layers "F.Cu" "B.Cu")
		(net "GND")
	)
	(via
		(at 387.793992 -354.098098)
		(size 0.4572)
		(drill 0.254)
		(layers "F.Cu" "B.Cu")
		(net "GND")
	)
	(via
		(at 128.050544 -305.008534)
		(size 0.508)
		(drill 0.254)
		(layers "F.Cu" "B.Cu")
		(net "GND")
	)
	(via
		(at 407.100024 -38.315138)
		(size 0.508)
		(drill 0.254)
		(layers "F.Cu" "B.Cu")
		(net "GND")
	)
	(via
		(at 362.548932 -31.390082)
		(size 0.508)
		(drill 0.254)
		(layers "F.Cu" "B.Cu")
		(net "GND")
	)
	(via
		(at 449.21805 -121.80824)
		(size 0.508)
		(drill 0.254)
		(layers "F.Cu" "B.Cu")
		(net "GND")
	)
	(via
		(at 418.053012 -342.439498)
		(size 0.4064)
		(drill 0.2032)
		(layers "F.Cu" "B.Cu")
		(net "GND")
	)
	(via
		(at 270.437102 -354.732082)
		(size 0.4064)
		(drill 0.2032)
		(layers "F.Cu" "B.Cu")
		(net "GND")
	)
	(via
		(at 359.243884 -330.96708)
		(size 0.508)
		(drill 0.254)
		(layers "F.Cu" "B.Cu")
		(net "GND")
	)
	(via
		(at 277.02637 -347.951806)
		(size 0.4572)
		(drill 0.254)
		(layers "F.Cu" "B.Cu")
		(net "GND")
	)
	(via
		(at 368.239294 -32.911796)
		(size 0.508)
		(drill 0.254)
		(layers "F.Cu" "B.Cu")
		(net "GND")
	)
	(via
		(at 153.46172 -150.457916)
		(size 0.508)
		(drill 0.254)
		(layers "F.Cu" "B.Cu")
		(net "GND")
	)
	(via
		(at 425.99991 -278.799798)
		(size 0.4064)
		(drill 0.2032)
		(layers "F.Cu" "B.Cu")
		(net "GND")
	)
	(via
		(at 68.674742 -301.124874)
		(size 0.4064)
		(drill 0.2032)
		(layers "F.Cu" "B.Cu")
		(net "GND")
	)
	(via
		(at 219.520262 -232.471468)
		(size 0.508)
		(drill 0.254)
		(layers "F.Cu" "B.Cu")
		(net "GND")
	)
	(via
		(at 51.63312 -125.955044)
		(size 0.508)
		(drill 0.254)
		(layers "F.Cu" "B.Cu")
		(net "GND")
	)
	(via
		(at 65.824862 -284.974792)
		(size 0.4064)
		(drill 0.2032)
		(layers "F.Cu" "B.Cu")
		(net "GND")
	)
	(via
		(at 302.299878 -312.999882)
		(size 0.4064)
		(drill 0.2032)
		(layers "F.Cu" "B.Cu")
		(net "GND")
	)
	(via
		(at 71.347838 -373.83847)
		(size 0.508)
		(drill 0.254)
		(layers "F.Cu" "B.Cu")
		(net "GND")
	)
	(via
		(at 181.44998 -280.699718)
		(size 0.4064)
		(drill 0.2032)
		(layers "F.Cu" "B.Cu")
		(net "GND")
	)
	(via
		(at 283.24429 -354.098098)
		(size 0.4572)
		(drill 0.254)
		(layers "F.Cu" "B.Cu")
		(net "GND")
	)
	(via
		(at 42.747946 -376.140218)
		(size 0.508)
		(drill 0.254)
		(layers "F.Cu" "B.Cu")
		(net "GND")
	)
	(via
		(at 434.327808 -406.040336)
		(size 0.508)
		(drill 0.254)
		(layers "F.Cu" "B.Cu")
		(net "GND")
	)
	(via
		(at 418.927788 -395.938502)
		(size 0.508)
		(drill 0.254)
		(layers "F.Cu" "B.Cu")
		(net "GND")
	)
	(via
		(at 298.974764 -291.624766)
		(size 0.4064)
		(drill 0.2032)
		(layers "F.Cu" "B.Cu")
		(net "GND")
	)
	(via
		(at 0.77089 -268.741144)
		(size 0.508)
		(drill 0.254)
		(layers "F.Cu" "B.Cu")
		(net "GND")
	)
	(via
		(at 388.474966 -285.924752)
		(size 0.4064)
		(drill 0.2032)
		(layers "F.Cu" "B.Cu")
		(net "GND")
	)
	(via
		(at 69.684138 -122.597164)
		(size 0.508)
		(drill 0.254)
		(layers "F.Cu" "B.Cu")
		(net "GND")
	)
	(via
		(at 49.1998 -318.699896)
		(size 0.4064)
		(drill 0.2032)
		(layers "F.Cu" "B.Cu")
		(net "GND")
	)
	(via
		(at 316.672976 -343.073482)
		(size 0.4572)
		(drill 0.254)
		(layers "F.Cu" "B.Cu")
		(net "GND")
	)
	(via
		(at 38.274752 -299.224954)
		(size 0.4064)
		(drill 0.2032)
		(layers "F.Cu" "B.Cu")
		(net "GND")
	)
	(via
		(at 179.07508 -302.074834)
		(size 0.4064)
		(drill 0.2032)
		(layers "F.Cu" "B.Cu")
		(net "GND")
	)
	(via
		(at 116.03228 -352.245422)
		(size 0.4572)
		(drill 0.254)
		(layers "F.Cu" "B.Cu")
		(net "GND")
	)
	(via
		(at 21.530564 -65.15989)
		(size 0.508)
		(drill 0.254)
		(layers "F.Cu" "B.Cu")
		(net "GND")
	)
	(via
		(at 390.902952 -352.245422)
		(size 0.4572)
		(drill 0.254)
		(layers "F.Cu" "B.Cu")
		(net "GND")
	)
	(via
		(at 361.394502 -231.15651)
		(size 0.508)
		(drill 0.254)
		(layers "F.Cu" "B.Cu")
		(net "GND")
	)
	(via
		(at 49.707038 -0.762)
		(size 0.508)
		(drill 0.254)
		(layers "F.Cu" "B.Cu")
		(net "GND")
	)
	(via
		(at 433.96916 -355.366066)
		(size 0.4572)
		(drill 0.254)
		(layers "F.Cu" "B.Cu")
		(net "GND")
	)
	(via
		(at 238.757968 -137.344404)
		(size 0.508)
		(drill 0.254)
		(layers "F.Cu" "B.Cu")
		(net "GND")
	)
	(via
		(at 391.799826 -313.949842)
		(size 0.4064)
		(drill 0.2032)
		(layers "F.Cu" "B.Cu")
		(net "GND")
	)
	(via
		(at 304.139092 -32.911796)
		(size 0.508)
		(drill 0.254)
		(layers "F.Cu" "B.Cu")
		(net "GND")
	)
	(via
		(at 47.115476 -350.977454)
		(size 0.4572)
		(drill 0.254)
		(layers "F.Cu" "B.Cu")
		(net "GND")
	)
	(via
		(at 72.273922 -73.85177)
		(size 0.508)
		(drill 0.254)
		(layers "F.Cu" "B.Cu")
		(net "GND")
	)
	(via
		(at 267.959586 -112.981994)
		(size 0.508)
		(drill 0.254)
		(layers "F.Cu" "B.Cu")
		(net "GND")
	)
	(via
		(at 366.882172 -58.873644)
		(size 0.508)
		(drill 0.254)
		(layers "F.Cu" "B.Cu")
		(net "GND")
	)
	(via
		(at 300.419262 -357.75773)
		(size 0.4064)
		(drill 0.2032)
		(layers "F.Cu" "B.Cu")
		(net "GND")
	)
	(via
		(at 305.513232 -29.859478)
		(size 0.508)
		(drill 0.254)
		(layers "F.Cu" "B.Cu")
		(net "GND")
	)
	(via
		(at 207.428592 -349.912432)
		(size 0.508)
		(drill 0.254)
		(layers "F.Cu" "B.Cu")
		(net "GND")
	)
	(via
		(at 267.848842 -27.79014)
		(size 0.508)
		(drill 0.254)
		(layers "F.Cu" "B.Cu")
		(net "GND")
	)
	(via
		(at 176.699926 -274.049744)
		(size 0.4064)
		(drill 0.2032)
		(layers "F.Cu" "B.Cu")
		(net "GND")
	)
	(via
		(at 163.747958 -399.838418)
		(size 0.508)
		(drill 0.254)
		(layers "F.Cu" "B.Cu")
		(net "GND")
	)
	(via
		(at 318.523112 -357.123746)
		(size 0.4572)
		(drill 0.254)
		(layers "F.Cu" "B.Cu")
		(net "GND")
	)
	(via
		(at 117.656864 -318.557656)
		(size 0.508)
		(drill 0.254)
		(layers "F.Cu" "B.Cu")
		(net "GND")
	)
	(via
		(at 161.54781 -372.240302)
		(size 0.508)
		(drill 0.254)
		(layers "F.Cu" "B.Cu")
		(net "GND")
	)
	(via
		(at 76.693522 -84.332318)
		(size 0.508)
		(drill 0.254)
		(layers "F.Cu" "B.Cu")
		(net "GND")
	)
	(via
		(at 87.305134 -343.073482)
		(size 0.4572)
		(drill 0.254)
		(layers "F.Cu" "B.Cu")
		(net "GND")
	)
	(via
		(at 428.84979 -279.749758)
		(size 0.4064)
		(drill 0.2032)
		(layers "F.Cu" "B.Cu")
		(net "GND")
	)
	(via
		(at 176.699926 -312.999882)
		(size 0.4064)
		(drill 0.2032)
		(layers "F.Cu" "B.Cu")
		(net "GND")
	)
	(via
		(at 339.293962 -216.387172)
		(size 0.4572)
		(drill 0.254)
		(layers "F.Cu" "B.Cu")
		(net "GND")
	)
	(via
		(at 219.080588 -101.658166)
		(size 0.508)
		(drill 0.254)
		(layers "F.Cu" "B.Cu")
		(net "GND")
	)
	(via
		(at 351.010728 -183.526938)
		(size 0.508)
		(drill 0.254)
		(layers "F.Cu" "B.Cu")
		(net "GND")
	)
	(via
		(at 81.024984 -301.124874)
		(size 0.4064)
		(drill 0.2032)
		(layers "F.Cu" "B.Cu")
		(net "GND")
	)
	(via
		(at 64.59347 -125.435106)
		(size 0.508)
		(drill 0.254)
		(layers "F.Cu" "B.Cu")
		(net "GND")
	)
	(via
		(at 113.750344 -180.644546)
		(size 0.508)
		(drill 0.254)
		(layers "F.Cu" "B.Cu")
		(net "GND")
	)
	(via
		(at 101.531674 -366.45977)
		(size 0.508)
		(drill 0.254)
		(layers "F.Cu" "B.Cu")
		(net "GND")
	)
	(via
		(at 216.470738 -256.420366)
		(size 0.508)
		(drill 0.254)
		(layers "F.Cu" "B.Cu")
		(net "GND")
	)
	(via
		(at 109.050074 -289.41649)
		(size 0.508)
		(drill 0.254)
		(layers "F.Cu" "B.Cu")
		(net "GND")
	)
	(via
		(at 181.44998 -279.749758)
		(size 0.4064)
		(drill 0.2032)
		(layers "F.Cu" "B.Cu")
		(net "GND")
	)
	(via
		(at 392.274806 -282.124912)
		(size 0.4064)
		(drill 0.2032)
		(layers "F.Cu" "B.Cu")
		(net "GND")
	)
	(via
		(at 306.099718 -317.749936)
		(size 0.4064)
		(drill 0.2032)
		(layers "F.Cu" "B.Cu")
		(net "GND")
	)
	(via
		(at 55.849774 -316.799722)
		(size 0.4064)
		(drill 0.2032)
		(layers "F.Cu" "B.Cu")
		(net "GND")
	)
	(via
		(at 180.693314 -143.955008)
		(size 0.508)
		(drill 0.254)
		(layers "F.Cu" "B.Cu")
		(net "GND")
	)
	(via
		(at 19.236944 -131.942332)
		(size 0.508)
		(drill 0.254)
		(layers "F.Cu" "B.Cu")
		(net "GND")
	)
	(via
		(at 152.47493 -280.224738)
		(size 0.4064)
		(drill 0.2032)
		(layers "F.Cu" "B.Cu")
		(net "GND")
	)
	(via
		(at 246.561102 -134.970012)
		(size 0.508)
		(drill 0.254)
		(layers "F.Cu" "B.Cu")
		(net "GND")
	)
	(via
		(at 221.836742 -15.474188)
		(size 0.508)
		(drill 0.254)
		(layers "F.Cu" "B.Cu")
		(net "GND")
	)
	(via
		(at 42.549826 -308.249828)
		(size 0.4064)
		(drill 0.2032)
		(layers "F.Cu" "B.Cu")
		(net "GND")
	)
	(via
		(at 391.324846 -288.774886)
		(size 0.4064)
		(drill 0.2032)
		(layers "F.Cu" "B.Cu")
		(net "GND")
	)
	(via
		(at 114.773456 -346.09913)
		(size 0.4572)
		(drill 0.254)
		(layers "F.Cu" "B.Cu")
		(net "GND")
	)
	(via
		(at 322.239386 -95.801942)
		(size 0.508)
		(drill 0.254)
		(layers "F.Cu" "B.Cu")
		(net "GND")
	)
	(via
		(at 410.799788 -318.699896)
		(size 0.4064)
		(drill 0.2032)
		(layers "F.Cu" "B.Cu")
		(net "GND")
	)
	(via
		(at 285.687262 -124.154946)
		(size 0.508)
		(drill 0.254)
		(layers "F.Cu" "B.Cu")
		(net "GND")
	)
	(via
		(at 398.4498 -281.649932)
		(size 0.4064)
		(drill 0.2032)
		(layers "F.Cu" "B.Cu")
		(net "GND")
	)
	(via
		(at 210.419442 -245.041674)
		(size 0.508)
		(drill 0.254)
		(layers "F.Cu" "B.Cu")
		(net "GND")
	)
	(via
		(at 188.383164 -154.461718)
		(size 0.508)
		(drill 0.254)
		(layers "F.Cu" "B.Cu")
		(net "GND")
	)
	(via
		(at 336.14487 -285.953454)
		(size 0.508)
		(drill 0.254)
		(layers "F.Cu" "B.Cu")
		(net "GND")
	)
	(via
		(at 268.574774 -294.4749)
		(size 0.4064)
		(drill 0.2032)
		(layers "F.Cu" "B.Cu")
		(net "GND")
	)
	(via
		(at 168.150032 -274.999958)
		(size 0.4064)
		(drill 0.2032)
		(layers "F.Cu" "B.Cu")
		(net "GND")
	)
	(via
		(at 276.955504 -63.218314)
		(size 0.508)
		(drill 0.254)
		(layers "F.Cu" "B.Cu")
		(net "GND")
	)
	(via
		(at 215.006936 -189.662054)
		(size 0.508)
		(drill 0.254)
		(layers "F.Cu" "B.Cu")
		(net "GND")
	)
	(via
		(at 299.449744 -279.749758)
		(size 0.4064)
		(drill 0.2032)
		(layers "F.Cu" "B.Cu")
		(net "GND")
	)
	(via
		(at 272.849848 -308.249828)
		(size 0.4064)
		(drill 0.2032)
		(layers "F.Cu" "B.Cu")
		(net "GND")
	)
	(via
		(at 293.527734 -406.040336)
		(size 0.508)
		(drill 0.254)
		(layers "F.Cu" "B.Cu")
		(net "GND")
	)
	(via
		(at 188.099954 -273.099784)
		(size 0.4064)
		(drill 0.2032)
		(layers "F.Cu" "B.Cu")
		(net "GND")
	)
	(via
		(at 42.747946 -372.240302)
		(size 0.508)
		(drill 0.254)
		(layers "F.Cu" "B.Cu")
		(net "GND")
	)
	(via
		(at 127.845058 -27.79014)
		(size 0.508)
		(drill 0.254)
		(layers "F.Cu" "B.Cu")
		(net "GND")
	)
	(via
		(at 260.757924 -286.331914)
		(size 0.508)
		(drill 0.254)
		(layers "F.Cu" "B.Cu")
		(net "GND")
	)
	(via
		(at 80.147922 -399.838418)
		(size 0.508)
		(drill 0.254)
		(layers "F.Cu" "B.Cu")
		(net "GND")
	)
	(via
		(at 314.366148 -134.566914)
		(size 0.508)
		(drill 0.254)
		(layers "F.Cu" "B.Cu")
		(net "GND")
	)
	(via
		(at 165.608 -417.82492)
		(size 0.508)
		(drill 0.254)
		(layers "F.Cu" "B.Cu")
		(net "GND")
	)
	(via
		(at 67.55003 -111.149892)
		(size 0.508)
		(drill 0.254)
		(layers "F.Cu" "B.Cu")
		(net "GND")
	)
	(via
		(at 341.927942 -406.040336)
		(size 0.508)
		(drill 0.254)
		(layers "F.Cu" "B.Cu")
		(net "GND")
	)
	(via
		(at 140.90396 -343.073482)
		(size 0.4572)
		(drill 0.254)
		(layers "F.Cu" "B.Cu")
		(net "GND")
	)
	(via
		(at 96.905572 -1.364996)
		(size 0.508)
		(drill 0.254)
		(layers "F.Cu" "B.Cu")
		(net "GND")
	)
	(via
		(at 444.484506 -73.20026)
		(size 0.508)
		(drill 0.254)
		(layers "F.Cu" "B.Cu")
		(net "GND")
	)
	(via
		(at 58.224928 -293.52494)
		(size 0.4064)
		(drill 0.2032)
		(layers "F.Cu" "B.Cu")
		(net "GND")
	)
	(via
		(at 82.449924 -312.999882)
		(size 0.4064)
		(drill 0.2032)
		(layers "F.Cu" "B.Cu")
		(net "GND")
	)
	(via
		(at 35.899598 -304.449988)
		(size 0.4064)
		(drill 0.2032)
		(layers "F.Cu" "B.Cu")
		(net "GND")
	)
	(via
		(at 352.17227 -33.857692)
		(size 0.508)
		(drill 0.254)
		(layers "F.Cu" "B.Cu")
		(net "GND")
	)
	(via
		(at 418.927788 -376.241818)
		(size 0.508)
		(drill 0.254)
		(layers "F.Cu" "B.Cu")
		(net "GND")
	)
	(via
		(at 36.374832 -275.474938)
		(size 0.4064)
		(drill 0.2032)
		(layers "F.Cu" "B.Cu")
		(net "GND")
	)
	(via
		(at 228.308154 -66.000122)
		(size 0.508)
		(drill 0.254)
		(layers "F.Cu" "B.Cu")
		(net "GND")
	)
	(via
		(at 338.494116 -212.38718)
		(size 0.4572)
		(drill 0.254)
		(layers "F.Cu" "B.Cu")
		(net "GND")
	)
	(via
		(at 411.750002 -316.799722)
		(size 0.4064)
		(drill 0.2032)
		(layers "F.Cu" "B.Cu")
		(net "GND")
	)
	(via
		(at 344.127836 -372.341902)
		(size 0.508)
		(drill 0.254)
		(layers "F.Cu" "B.Cu")
		(net "GND")
	)
	(via
		(at 250.89866 -227.735384)
		(size 0.508)
		(drill 0.254)
		(layers "F.Cu" "B.Cu")
		(net "GND")
	)
	(via
		(at 135.388858 -89.366344)
		(size 0.508)
		(drill 0.254)
		(layers "F.Cu" "B.Cu")
		(net "GND")
	)
	(via
		(at 330.328016 -212.34019)
		(size 0.508)
		(drill 0.254)
		(layers "F.Cu" "B.Cu")
		(net "GND")
	)
	(via
		(at 228.962712 -288.652204)
		(size 0.508)
		(drill 0.254)
		(layers "F.Cu" "B.Cu")
		(net "GND")
	)
	(via
		(at 104.299004 -387.601714)
		(size 0.508)
		(drill 0.254)
		(layers "F.Cu" "B.Cu")
		(net "GND")
	)
	(via
		(at 156.275024 -293.52494)
		(size 0.4064)
		(drill 0.2032)
		(layers "F.Cu" "B.Cu")
		(net "GND")
	)
	(via
		(at 434.792882 -303.237392)
		(size 0.508)
		(drill 0.254)
		(layers "F.Cu" "B.Cu")
		(net "GND")
	)
	(via
		(at 122.29973 -259.918962)
		(size 0.508)
		(drill 0.254)
		(layers "F.Cu" "B.Cu")
		(net "GND")
	)
	(via
		(at 0.77089 -294.141144)
		(size 0.508)
		(drill 0.254)
		(layers "F.Cu" "B.Cu")
		(net "GND")
	)
	(via
		(at 56.799988 -273.099784)
		(size 0.4064)
		(drill 0.2032)
		(layers "F.Cu" "B.Cu")
		(net "GND")
	)
	(via
		(at 268.574774 -284.024832)
		(size 0.4064)
		(drill 0.2032)
		(layers "F.Cu" "B.Cu")
		(net "GND")
	)
	(via
		(at 383.426208 -341.805514)
		(size 0.4572)
		(drill 0.254)
		(layers "F.Cu" "B.Cu")
		(net "GND")
	)
	(via
		(at 48.470566 -131.277614)
		(size 0.508)
		(drill 0.254)
		(layers "F.Cu" "B.Cu")
		(net "GND")
	)
	(via
		(at 234.932728 -178.066954)
		(size 0.508)
		(drill 0.254)
		(layers "F.Cu" "B.Cu")
		(net "GND")
	)
	(via
		(at 412.699962 -278.799798)
		(size 0.4064)
		(drill 0.2032)
		(layers "F.Cu" "B.Cu")
		(net "GND")
	)
	(via
		(at 222.154496 -308.181756)
		(size 0.508)
		(drill 0.254)
		(layers "F.Cu" "B.Cu")
		(net "GND")
	)
	(via
		(at 54.70652 -104.244902)
		(size 0.508)
		(drill 0.254)
		(layers "F.Cu" "B.Cu")
		(net "GND")
	)
	(via
		(at 42.074846 -281.174952)
		(size 0.4064)
		(drill 0.2032)
		(layers "F.Cu" "B.Cu")
		(net "GND")
	)
	(via
		(at 291.092382 -354.732082)
		(size 0.4064)
		(drill 0.2032)
		(layers "F.Cu" "B.Cu")
		(net "GND")
	)
	(via
		(at 47.147988 -373.441976)
		(size 0.508)
		(drill 0.254)
		(layers "F.Cu" "B.Cu")
		(net "GND")
	)
	(via
		(at 58.699908 -276.899878)
		(size 0.4064)
		(drill 0.2032)
		(layers "F.Cu" "B.Cu")
		(net "GND")
	)
	(via
		(at 388.127748 -399.838418)
		(size 0.508)
		(drill 0.254)
		(layers "F.Cu" "B.Cu")
		(net "GND")
	)
	(via
		(at 20.39366 -349.219774)
		(size 0.4572)
		(drill 0.254)
		(layers "F.Cu" "B.Cu")
		(net "GND")
	)
	(via
		(at 174.42434 -349.219774)
		(size 0.4572)
		(drill 0.254)
		(layers "F.Cu" "B.Cu")
		(net "GND")
	)
	(via
		(at 337.453986 -106.779822)
		(size 0.508)
		(drill 0.254)
		(layers "F.Cu" "B.Cu")
		(net "GND")
	)
	(via
		(at 228.667818 -221.904052)
		(size 0.4572)
		(drill 0.254)
		(layers "F.Cu" "B.Cu")
		(net "GND")
	)
	(via
		(at 115.508786 -286.842454)
		(size 0.508)
		(drill 0.254)
		(layers "F.Cu" "B.Cu")
		(net "GND")
	)
	(via
		(at 305.513232 -31.118302)
		(size 0.508)
		(drill 0.254)
		(layers "F.Cu" "B.Cu")
		(net "GND")
	)
	(via
		(at 153.888694 -31.642304)
		(size 0.508)
		(drill 0.254)
		(layers "F.Cu" "B.Cu")
		(net "GND")
	)
	(via
		(at 197.600062 -315.849762)
		(size 0.4064)
		(drill 0.2032)
		(layers "F.Cu" "B.Cu")
		(net "GND")
	)
	(via
		(at 465.328 -417.82492)
		(size 0.508)
		(drill 0.254)
		(layers "F.Cu" "B.Cu")
		(net "GND")
	)
	(via
		(at 67.55003 -110.514892)
		(size 0.508)
		(drill 0.254)
		(layers "F.Cu" "B.Cu")
		(net "GND")
	)
	(via
		(at 199.64019 -131.514596)
		(size 0.508)
		(drill 0.254)
		(layers "F.Cu" "B.Cu")
		(net "GND")
	)
	(via
		(at 82.347816 -403.34184)
		(size 0.508)
		(drill 0.254)
		(layers "F.Cu" "B.Cu")
		(net "GND")
	)
	(via
		(at 37.324792 -285.924752)
		(size 0.4064)
		(drill 0.2032)
		(layers "F.Cu" "B.Cu")
		(net "GND")
	)
	(via
		(at 16.280892 -27.79014)
		(size 0.508)
		(drill 0.254)
		(layers "F.Cu" "B.Cu")
		(net "GND")
	)
	(via
		(at 127.950214 -215.09482)
		(size 0.508)
		(drill 0.254)
		(layers "F.Cu" "B.Cu")
		(net "GND")
	)
	(via
		(at 120.603772 -285.953454)
		(size 0.508)
		(drill 0.254)
		(layers "F.Cu" "B.Cu")
		(net "GND")
	)
	(via
		(at 206.154782 -34.990024)
		(size 0.508)
		(drill 0.254)
		(layers "F.Cu" "B.Cu")
		(net "GND")
	)
	(via
		(at 412.699962 -317.749936)
		(size 0.4064)
		(drill 0.2032)
		(layers "F.Cu" "B.Cu")
		(net "GND")
	)
	(via
		(at 153.42489 -273.574764)
		(size 0.4064)
		(drill 0.2032)
		(layers "F.Cu" "B.Cu")
		(net "GND")
	)
	(via
		(at 18.196306 -60.099194)
		(size 0.508)
		(drill 0.254)
		(layers "F.Cu" "B.Cu")
		(net "GND")
	)
	(via
		(at 315.414152 -341.805514)
		(size 0.4572)
		(drill 0.254)
		(layers "F.Cu" "B.Cu")
		(net "GND")
	)
	(via
		(at 405.575008 -291.624766)
		(size 0.4064)
		(drill 0.2032)
		(layers "F.Cu" "B.Cu")
		(net "GND")
	)
	(via
		(at 430.14519 -50.516282)
		(size 0.508)
		(drill 0.254)
		(layers "F.Cu" "B.Cu")
		(net "GND")
	)
	(via
		(at 263.669272 -75.892406)
		(size 0.508)
		(drill 0.254)
		(layers "F.Cu" "B.Cu")
		(net "GND")
	)
	(via
		(at 262.85317 -49.574704)
		(size 0.508)
		(drill 0.254)
		(layers "F.Cu" "B.Cu")
		(net "GND")
	)
	(via
		(at 48.249586 -272.14957)
		(size 0.4064)
		(drill 0.2032)
		(layers "F.Cu" "B.Cu")
		(net "GND")
	)
	(via
		(at 160.549844 -279.749758)
		(size 0.4064)
		(drill 0.2032)
		(layers "F.Cu" "B.Cu")
		(net "GND")
	)
	(via
		(at 374.50395 -181.88305)
		(size 0.508)
		(drill 0.254)
		(layers "F.Cu" "B.Cu")
		(net "GND")
	)
	(via
		(at 67.249802 -276.899878)
		(size 0.4064)
		(drill 0.2032)
		(layers "F.Cu" "B.Cu")
		(net "GND")
	)
	(via
		(at 90.922348 -228.2952)
		(size 0.508)
		(drill 0.254)
		(layers "F.Cu" "B.Cu")
		(net "GND")
	)
	(via
		(at 403.00656 -120.555004)
		(size 0.508)
		(drill 0.254)
		(layers "F.Cu" "B.Cu")
		(net "GND")
	)
	(via
		(at 418.991034 -249.899678)
		(size 0.508)
		(drill 0.254)
		(layers "F.Cu" "B.Cu")
		(net "GND")
	)
	(via
		(at 126.347728 -408.738578)
		(size 0.508)
		(drill 0.254)
		(layers "F.Cu" "B.Cu")
		(net "GND")
	)
	(via
		(at 308.949852 -312.049922)
		(size 0.4064)
		(drill 0.2032)
		(layers "F.Cu" "B.Cu")
		(net "GND")
	)
	(via
		(at 114.773456 -341.805514)
		(size 0.4572)
		(drill 0.254)
		(layers "F.Cu" "B.Cu")
		(net "GND")
	)
	(via
		(at 295.649904 -274.999958)
		(size 0.4064)
		(drill 0.2032)
		(layers "F.Cu" "B.Cu")
		(net "GND")
	)
	(via
		(at 260.849872 -310.832246)
		(size 0.508)
		(drill 0.254)
		(layers "F.Cu" "B.Cu")
		(net "GND")
	)
	(via
		(at 385.624832 -285.924752)
		(size 0.4064)
		(drill 0.2032)
		(layers "F.Cu" "B.Cu")
		(net "GND")
	)
	(via
		(at 254.451358 -45.865288)
		(size 0.508)
		(drill 0.254)
		(layers "F.Cu" "B.Cu")
		(net "GND")
	)
	(via
		(at 120.991376 -344.831162)
		(size 0.4572)
		(drill 0.254)
		(layers "F.Cu" "B.Cu")
		(net "GND")
	)
	(via
		(at 185.250074 -314.899802)
		(size 0.4064)
		(drill 0.2032)
		(layers "F.Cu" "B.Cu")
		(net "GND")
	)
	(via
		(at 73.547732 -400.938492)
		(size 0.508)
		(drill 0.254)
		(layers "F.Cu" "B.Cu")
		(net "GND")
	)
	(via
		(at 377.12777 -398.24025)
		(size 0.508)
		(drill 0.254)
		(layers "F.Cu" "B.Cu")
		(net "GND")
	)
	(via
		(at 283.833062 -151.159972)
		(size 0.508)
		(drill 0.254)
		(layers "F.Cu" "B.Cu")
		(net "GND")
	)
	(via
		(at 308.949852 -311.099962)
		(size 0.4064)
		(drill 0.2032)
		(layers "F.Cu" "B.Cu")
		(net "GND")
	)
	(via
		(at 406.999948 -314.899802)
		(size 0.4064)
		(drill 0.2032)
		(layers "F.Cu" "B.Cu")
		(net "GND")
	)
	(via
		(at 27.347926 -380.141734)
		(size 0.508)
		(drill 0.254)
		(layers "F.Cu" "B.Cu")
		(net "GND")
	)
	(via
		(at 3.845306 -51.227482)
		(size 0.508)
		(drill 0.254)
		(layers "F.Cu" "B.Cu")
		(net "GND")
	)
	(via
		(at 389.644128 -344.831162)
		(size 0.4572)
		(drill 0.254)
		(layers "F.Cu" "B.Cu")
		(net "GND")
	)
	(via
		(at 3.856736 -36.760912)
		(size 0.508)
		(drill 0.254)
		(layers "F.Cu" "B.Cu")
		(net "GND")
	)
	(via
		(at 159.599884 -313.949842)
		(size 0.4064)
		(drill 0.2032)
		(layers "F.Cu" "B.Cu")
		(net "GND")
	)
	(via
		(at 48.72482 -300.174914)
		(size 0.4064)
		(drill 0.2032)
		(layers "F.Cu" "B.Cu")
		(net "GND")
	)
	(via
		(at 27.347926 -384.041904)
		(size 0.508)
		(drill 0.254)
		(layers "F.Cu" "B.Cu")
		(net "GND")
	)
	(via
		(at 45.939202 -32.911796)
		(size 0.508)
		(drill 0.254)
		(layers "F.Cu" "B.Cu")
		(net "GND")
	)
	(via
		(at 185.010044 -344.831162)
		(size 0.4572)
		(drill 0.254)
		(layers "F.Cu" "B.Cu")
		(net "GND")
	)
	(via
		(at 118.441978 -25.971246)
		(size 0.508)
		(drill 0.254)
		(layers "F.Cu" "B.Cu")
		(net "GND")
	)
	(via
		(at 402.724874 -306.824888)
		(size 0.4064)
		(drill 0.2032)
		(layers "F.Cu" "B.Cu")
		(net "GND")
	)
	(via
		(at 76.27493 -294.4749)
		(size 0.4064)
		(drill 0.2032)
		(layers "F.Cu" "B.Cu")
		(net "GND")
	)
	(via
		(at 63.449708 -272.14957)
		(size 0.4064)
		(drill 0.2032)
		(layers "F.Cu" "B.Cu")
		(net "GND")
	)
	(via
		(at 71.257922 -73.85177)
		(size 0.508)
		(drill 0.254)
		(layers "F.Cu" "B.Cu")
		(net "GND")
	)
	(via
		(at 277.368 -417.82492)
		(size 0.508)
		(drill 0.254)
		(layers "F.Cu" "B.Cu")
		(net "GND")
	)
	(via
		(at 278.549862 -319.65011)
		(size 0.4064)
		(drill 0.2032)
		(layers "F.Cu" "B.Cu")
		(net "GND")
	)
	(via
		(at 30.002988 -189.88151)
		(size 0.508)
		(drill 0.254)
		(layers "F.Cu" "B.Cu")
		(net "GND")
	)
	(via
		(at 101.8286 -195.6054)
		(size 0.508)
		(drill 0.254)
		(layers "F.Cu" "B.Cu")
		(net "GND")
	)
	(via
		(at 62.024768 -302.074834)
		(size 0.4064)
		(drill 0.2032)
		(layers "F.Cu" "B.Cu")
		(net "GND")
	)
	(via
		(at 11.7983 -21.738336)
		(size 0.508)
		(drill 0.254)
		(layers "F.Cu" "B.Cu")
		(net "GND")
	)
	(via
		(at 65.81267 -152.955244)
		(size 0.508)
		(drill 0.254)
		(layers "F.Cu" "B.Cu")
		(net "GND")
	)
	(via
		(at 82.449924 -305.399948)
		(size 0.4064)
		(drill 0.2032)
		(layers "F.Cu" "B.Cu")
		(net "GND")
	)
	(via
		(at 312.749692 -304.449734)
		(size 0.4064)
		(drill 0.2032)
		(layers "F.Cu" "B.Cu")
		(net "GND")
	)
	(via
		(at 284.724856 -306.824888)
		(size 0.4064)
		(drill 0.2032)
		(layers "F.Cu" "B.Cu")
		(net "GND")
	)
	(via
		(at 409.09748 -347.951806)
		(size 0.4572)
		(drill 0.254)
		(layers "F.Cu" "B.Cu")
		(net "GND")
	)
	(via
		(at 207.268064 -212.861144)
		(size 0.508)
		(drill 0.254)
		(layers "F.Cu" "B.Cu")
		(net "GND")
	)
	(via
		(at 393.7 -308.249828)
		(size 0.4064)
		(drill 0.2032)
		(layers "F.Cu" "B.Cu")
		(net "GND")
	)
	(via
		(at 177.649886 -276.899878)
		(size 0.4064)
		(drill 0.2032)
		(layers "F.Cu" "B.Cu")
		(net "GND")
	)
	(via
		(at 428.84979 -308.249828)
		(size 0.4064)
		(drill 0.2032)
		(layers "F.Cu" "B.Cu")
		(net "GND")
	)
	(via
		(at 315.60008 -312.049922)
		(size 0.4064)
		(drill 0.2032)
		(layers "F.Cu" "B.Cu")
		(net "GND")
	)
	(via
		(at 342.876378 -287.51149)
		(size 0.508)
		(drill 0.254)
		(layers "F.Cu" "B.Cu")
		(net "GND")
	)
	(via
		(at 185.725054 -291.624766)
		(size 0.4064)
		(drill 0.2032)
		(layers "F.Cu" "B.Cu")
		(net "GND")
	)
	(via
		(at 190.950088 -316.799722)
		(size 0.4064)
		(drill 0.2032)
		(layers "F.Cu" "B.Cu")
		(net "GND")
	)
	(via
		(at 125.730508 -348.58579)
		(size 0.4064)
		(drill 0.2032)
		(layers "F.Cu" "B.Cu")
		(net "GND")
	)
	(via
		(at 159.347916 -378.94006)
		(size 0.508)
		(drill 0.254)
		(layers "F.Cu" "B.Cu")
		(net "GND")
	)
	(via
		(at 387.525006 -277.374858)
		(size 0.4064)
		(drill 0.2032)
		(layers "F.Cu" "B.Cu")
		(net "GND")
	)
	(via
		(at 414.944052 -351.611438)
		(size 0.4064)
		(drill 0.2032)
		(layers "F.Cu" "B.Cu")
		(net "GND")
	)
	(via
		(at 23.34006 -73.23963)
		(size 0.508)
		(drill 0.254)
		(layers "F.Cu" "B.Cu")
		(net "GND")
	)
	(via
		(at 87.676482 -354.732082)
		(size 0.4064)
		(drill 0.2032)
		(layers "F.Cu" "B.Cu")
		(net "GND")
	)
	(via
		(at 37.324792 -287.824926)
		(size 0.4064)
		(drill 0.2032)
		(layers "F.Cu" "B.Cu")
		(net "GND")
	)
	(via
		(at 184.29986 -274.049744)
		(size 0.4064)
		(drill 0.2032)
		(layers "F.Cu" "B.Cu")
		(net "GND")
	)
	(via
		(at 393.979146 -243.610384)
		(size 0.508)
		(drill 0.254)
		(layers "F.Cu" "B.Cu")
		(net "GND")
	)
	(via
		(at 306.099718 -288.299906)
		(size 0.4064)
		(drill 0.2032)
		(layers "F.Cu" "B.Cu")
		(net "GND")
	)
	(via
		(at 341.916004 -354.732082)
		(size 0.4064)
		(drill 0.2032)
		(layers "F.Cu" "B.Cu")
		(net "GND")
	)
	(via
		(at 352.041968 -326.508364)
		(size 0.508)
		(drill 0.254)
		(layers "F.Cu" "B.Cu")
		(net "GND")
	)
	(via
		(at 234.13466 -205.98511)
		(size 0.508)
		(drill 0.254)
		(layers "F.Cu" "B.Cu")
		(net "GND")
	)
	(via
		(at 346.327984 -373.441976)
		(size 0.508)
		(drill 0.254)
		(layers "F.Cu" "B.Cu")
		(net "GND")
	)
	(via
		(at 172.945552 -357.75773)
		(size 0.4064)
		(drill 0.2032)
		(layers "F.Cu" "B.Cu")
		(net "GND")
	)
	(via
		(at 185.722768 -23.880318)
		(size 0.508)
		(drill 0.254)
		(layers "F.Cu" "B.Cu")
		(net "GND")
	)
	(via
		(at 109.399324 -268.731492)
		(size 0.508)
		(drill 0.254)
		(layers "F.Cu" "B.Cu")
		(net "GND")
	)
	(via
		(at 115.34775 -377.738386)
		(size 0.508)
		(drill 0.254)
		(layers "F.Cu" "B.Cu")
		(net "GND")
	)
	(via
		(at 78.17485 -299.224954)
		(size 0.4064)
		(drill 0.2032)
		(layers "F.Cu" "B.Cu")
		(net "GND")
	)
	(via
		(at 304.527712 -406.141936)
		(size 0.508)
		(drill 0.254)
		(layers "F.Cu" "B.Cu")
		(net "GND")
	)
	(via
		(at 159.347916 -376.241818)
		(size 0.508)
		(drill 0.254)
		(layers "F.Cu" "B.Cu")
		(net "GND")
	)
	(via
		(at 84.196174 -341.805514)
		(size 0.4572)
		(drill 0.254)
		(layers "F.Cu" "B.Cu")
		(net "GND")
	)
	(via
		(at 399.874994 -287.824926)
		(size 0.4064)
		(drill 0.2032)
		(layers "F.Cu" "B.Cu")
		(net "GND")
	)
	(via
		(at 189.91961 -38.701218)
		(size 0.508)
		(drill 0.254)
		(layers "F.Cu" "B.Cu")
		(net "GND")
	)
	(via
		(at 107.225846 -216.063576)
		(size 0.508)
		(drill 0.254)
		(layers "F.Cu" "B.Cu")
		(net "GND")
	)
	(via
		(at 73.61047 -347.951806)
		(size 0.4572)
		(drill 0.254)
		(layers "F.Cu" "B.Cu")
		(net "GND")
	)
	(via
		(at 157.224984 -286.874966)
		(size 0.4064)
		(drill 0.2032)
		(layers "F.Cu" "B.Cu")
		(net "GND")
	)
	(via
		(at 213.005924 -1.364996)
		(size 0.508)
		(drill 0.254)
		(layers "F.Cu" "B.Cu")
		(net "GND")
	)
	(via
		(at 302.327818 -372.240302)
		(size 0.508)
		(drill 0.254)
		(layers "F.Cu" "B.Cu")
		(net "GND")
	)
	(via
		(at 276.649688 -310.149748)
		(size 0.4064)
		(drill 0.2032)
		(layers "F.Cu" "B.Cu")
		(net "GND")
	)
	(via
		(at 272.067274 -346.09913)
		(size 0.4572)
		(drill 0.254)
		(layers "F.Cu" "B.Cu")
		(net "GND")
	)
	(via
		(at 301.03826 -72.56526)
		(size 0.508)
		(drill 0.254)
		(layers "F.Cu" "B.Cu")
		(net "GND")
	)
	(via
		(at 107.31373 -292.789102)
		(size 0.508)
		(drill 0.254)
		(layers "F.Cu" "B.Cu")
		(net "GND")
	)
	(via
		(at 438.31764 -303.026826)
		(size 0.508)
		(drill 0.254)
		(layers "F.Cu" "B.Cu")
		(net "GND")
	)
	(via
		(at 280.13533 -346.09913)
		(size 0.4572)
		(drill 0.254)
		(layers "F.Cu" "B.Cu")
		(net "GND")
	)
	(via
		(at 44.92498 -301.124874)
		(size 0.4064)
		(drill 0.2032)
		(layers "F.Cu" "B.Cu")
		(net "GND")
	)
	(via
		(at 430.466246 -134.566914)
		(size 0.508)
		(drill 0.254)
		(layers "F.Cu" "B.Cu")
		(net "GND")
	)
	(via
		(at 115.52301 -247.553988)
		(size 0.508)
		(drill 0.254)
		(layers "F.Cu" "B.Cu")
		(net "GND")
	)
	(via
		(at 289.94989 -280.699718)
		(size 0.4064)
		(drill 0.2032)
		(layers "F.Cu" "B.Cu")
		(net "GND")
	)
	(via
		(at 128.547114 -23.583646)
		(size 0.508)
		(drill 0.254)
		(layers "F.Cu" "B.Cu")
		(net "GND")
	)
	(via
		(at 267.959586 -109.382052)
		(size 0.508)
		(drill 0.254)
		(layers "F.Cu" "B.Cu")
		(net "GND")
	)
	(via
		(at 386.575046 -279.274778)
		(size 0.4064)
		(drill 0.2032)
		(layers "F.Cu" "B.Cu")
		(net "GND")
	)
	(via
		(at 39.224966 -283.074872)
		(size 0.4064)
		(drill 0.2032)
		(layers "F.Cu" "B.Cu")
		(net "GND")
	)
	(via
		(at 306.099718 -310.149748)
		(size 0.4064)
		(drill 0.2032)
		(layers "F.Cu" "B.Cu")
		(net "GND")
	)
	(via
		(at 226.572826 -108.445808)
		(size 0.508)
		(drill 0.254)
		(layers "F.Cu" "B.Cu")
		(net "GND")
	)
	(via
		(at 69.149976 -311.099962)
		(size 0.4064)
		(drill 0.2032)
		(layers "F.Cu" "B.Cu")
		(net "GND")
	)
	(via
		(at 330.927964 -371.140228)
		(size 0.508)
		(drill 0.254)
		(layers "F.Cu" "B.Cu")
		(net "GND")
	)
	(via
		(at 38.566344 -253.45644)
		(size 0.508)
		(drill 0.254)
		(layers "F.Cu" "B.Cu")
		(net "GND")
	)
	(via
		(at 0.77089 -278.901144)
		(size 0.508)
		(drill 0.254)
		(layers "F.Cu" "B.Cu")
		(net "GND")
	)
	(via
		(at 418.927788 -380.141734)
		(size 0.508)
		(drill 0.254)
		(layers "F.Cu" "B.Cu")
		(net "GND")
	)
	(via
		(at 47.09922 -122.130312)
		(size 0.508)
		(drill 0.254)
		(layers "F.Cu" "B.Cu")
		(net "GND")
	)
	(via
		(at 394.208 -417.82492)
		(size 0.508)
		(drill 0.254)
		(layers "F.Cu" "B.Cu")
		(net "GND")
	)
	(via
		(at 340.285832 -352.245422)
		(size 0.4572)
		(drill 0.254)
		(layers "F.Cu" "B.Cu")
		(net "GND")
	)
	(via
		(at 107.881674 -130.416808)
		(size 0.508)
		(drill 0.254)
		(layers "F.Cu" "B.Cu")
		(net "GND")
	)
	(via
		(at 399.400014 -273.099784)
		(size 0.4064)
		(drill 0.2032)
		(layers "F.Cu" "B.Cu")
		(net "GND")
	)
	(via
		(at 267.959586 -135.095488)
		(size 0.508)
		(drill 0.254)
		(layers "F.Cu" "B.Cu")
		(net "GND")
	)
	(via
		(at 125.154944 -126.995428)
		(size 0.508)
		(drill 0.254)
		(layers "F.Cu" "B.Cu")
		(net "GND")
	)
	(via
		(at 405.948642 -89.154762)
		(size 0.508)
		(drill 0.254)
		(layers "F.Cu" "B.Cu")
		(net "GND")
	)
	(via
		(at 392.753088 -344.831162)
		(size 0.4572)
		(drill 0.254)
		(layers "F.Cu" "B.Cu")
		(net "GND")
	)
	(via
		(at 171.474892 -294.4749)
		(size 0.4064)
		(drill 0.2032)
		(layers "F.Cu" "B.Cu")
		(net "GND")
	)
	(via
		(at 139.324334 -222.214186)
		(size 0.508)
		(drill 0.254)
		(layers "F.Cu" "B.Cu")
		(net "GND")
	)
	(via
		(at 77.947774 -385.141978)
		(size 0.508)
		(drill 0.254)
		(layers "F.Cu" "B.Cu")
		(net "GND")
	)
	(via
		(at 200.700894 -33.19018)
		(size 0.508)
		(drill 0.254)
		(layers "F.Cu" "B.Cu")
		(net "GND")
	)
	(via
		(at 401.774914 -305.874928)
		(size 0.4064)
		(drill 0.2032)
		(layers "F.Cu" "B.Cu")
		(net "GND")
	)
	(via
		(at 314.853066 -49.574704)
		(size 0.508)
		(drill 0.254)
		(layers "F.Cu" "B.Cu")
		(net "GND")
	)
	(via
		(at 293.829994 -344.831162)
		(size 0.4572)
		(drill 0.254)
		(layers "F.Cu" "B.Cu")
		(net "GND")
	)
	(via
		(at 128.547622 -403.738588)
		(size 0.508)
		(drill 0.254)
		(layers "F.Cu" "B.Cu")
		(net "GND")
	)
	(via
		(at 397.120872 -355.366066)
		(size 0.4572)
		(drill 0.254)
		(layers "F.Cu" "B.Cu")
		(net "GND")
	)
	(via
		(at 309.424832 -291.624766)
		(size 0.4064)
		(drill 0.2032)
		(layers "F.Cu" "B.Cu")
		(net "GND")
	)
	(via
		(at 229.26929 -149.42947)
		(size 0.508)
		(drill 0.254)
		(layers "F.Cu" "B.Cu")
		(net "GND")
	)
	(via
		(at 425.527724 -402.140166)
		(size 0.508)
		(drill 0.254)
		(layers "F.Cu" "B.Cu")
		(net "GND")
	)
	(via
		(at 265.046968 -1.135126)
		(size 0.508)
		(drill 0.254)
		(layers "F.Cu" "B.Cu")
		(net "GND")
	)
	(via
		(at 259.390134 -215.572848)
		(size 0.508)
		(drill 0.254)
		(layers "F.Cu" "B.Cu")
		(net "GND")
	)
	(via
		(at 295.727882 -380.141734)
		(size 0.508)
		(drill 0.254)
		(layers "F.Cu" "B.Cu")
		(net "GND")
	)
	(via
		(at 124.630434 -304.373534)
		(size 0.508)
		(drill 0.254)
		(layers "F.Cu" "B.Cu")
		(net "GND")
	)
	(via
		(at 343.511378 -289.41649)
		(size 0.508)
		(drill 0.254)
		(layers "F.Cu" "B.Cu")
		(net "GND")
	)
	(via
		(at 127.209296 -349.219774)
		(size 0.4572)
		(drill 0.254)
		(layers "F.Cu" "B.Cu")
		(net "GND")
	)
	(via
		(at 183.379872 -342.439498)
		(size 0.4064)
		(drill 0.2032)
		(layers "F.Cu" "B.Cu")
		(net "GND")
	)
	(via
		(at 169.465244 -344.831162)
		(size 0.4572)
		(drill 0.254)
		(layers "F.Cu" "B.Cu")
		(net "GND")
	)
	(via
		(at 72.258428 -116.9035)
		(size 0.508)
		(drill 0.254)
		(layers "F.Cu" "B.Cu")
		(net "GND")
	)
	(via
		(at 205.932024 -124.743972)
		(size 0.508)
		(drill 0.254)
		(layers "F.Cu" "B.Cu")
		(net "GND")
	)
	(via
		(at 51.48326 -343.073482)
		(size 0.4572)
		(drill 0.254)
		(layers "F.Cu" "B.Cu")
		(net "GND")
	)
	(via
		(at 297.549824 -314.899802)
		(size 0.4064)
		(drill 0.2032)
		(layers "F.Cu" "B.Cu")
		(net "GND")
	)
	(via
		(at 193.0781 -347.951806)
		(size 0.4572)
		(drill 0.254)
		(layers "F.Cu" "B.Cu")
		(net "GND")
	)
	(via
		(at 229.405434 -285.445962)
		(size 0.508)
		(drill 0.254)
		(layers "F.Cu" "B.Cu")
		(net "GND")
	)
	(via
		(at 82.93735 -354.098098)
		(size 0.4572)
		(drill 0.254)
		(layers "F.Cu" "B.Cu")
		(net "GND")
	)
	(via
		(at 238.404654 -308.181756)
		(size 0.508)
		(drill 0.254)
		(layers "F.Cu" "B.Cu")
		(net "GND")
	)
	(via
		(at 375.7295 -357.75773)
		(size 0.4064)
		(drill 0.2032)
		(layers "F.Cu" "B.Cu")
		(net "GND")
	)
	(via
		(at 234.924092 -284.641544)
		(size 0.508)
		(drill 0.254)
		(layers "F.Cu" "B.Cu")
		(net "GND")
	)
	(via
		(at 82.924904 -293.52494)
		(size 0.4064)
		(drill 0.2032)
		(layers "F.Cu" "B.Cu")
		(net "GND")
	)
	(via
		(at 120.991376 -346.09913)
		(size 0.4572)
		(drill 0.254)
		(layers "F.Cu" "B.Cu")
		(net "GND")
	)
	(via
		(at 35.6489 -33.19018)
		(size 0.508)
		(drill 0.254)
		(layers "F.Cu" "B.Cu")
		(net "GND")
	)
	(via
		(at 415.549842 -316.799722)
		(size 0.4064)
		(drill 0.2032)
		(layers "F.Cu" "B.Cu")
		(net "GND")
	)
	(via
		(at 289.090862 -345.465146)
		(size 0.4064)
		(drill 0.2032)
		(layers "F.Cu" "B.Cu")
		(net "GND")
	)
	(via
		(at 37.788596 -347.951806)
		(size 0.4572)
		(drill 0.254)
		(layers "F.Cu" "B.Cu")
		(net "GND")
	)
	(via
		(at 156.275024 -282.124912)
		(size 0.4064)
		(drill 0.2032)
		(layers "F.Cu" "B.Cu")
		(net "GND")
	)
	(via
		(at 255.17729 -76.270104)
		(size 0.508)
		(drill 0.254)
		(layers "F.Cu" "B.Cu")
		(net "GND")
	)
	(via
		(at 430.749964 -286.399732)
		(size 0.4064)
		(drill 0.2032)
		(layers "F.Cu" "B.Cu")
		(net "GND")
	)
	(via
		(at 137.820146 -198.726806)
		(size 0.508)
		(drill 0.254)
		(layers "F.Cu" "B.Cu")
		(net "GND")
	)
	(via
		(at 174.325026 -303.974754)
		(size 0.4064)
		(drill 0.2032)
		(layers "F.Cu" "B.Cu")
		(net "GND")
	)
	(via
		(at 281.53995 -74.58583)
		(size 0.508)
		(drill 0.254)
		(layers "F.Cu" "B.Cu")
		(net "GND")
	)
	(via
		(at 302.299878 -313.949842)
		(size 0.4064)
		(drill 0.2032)
		(layers "F.Cu" "B.Cu")
		(net "GND")
	)
	(via
		(at 167.675052 -291.624766)
		(size 0.4064)
		(drill 0.2032)
		(layers "F.Cu" "B.Cu")
		(net "GND")
	)
	(via
		(at 351.374964 -290.68649)
		(size 0.508)
		(drill 0.254)
		(layers "F.Cu" "B.Cu")
		(net "GND")
	)
	(via
		(at 374.927876 -402.241766)
		(size 0.508)
		(drill 0.254)
		(layers "F.Cu" "B.Cu")
		(net "GND")
	)
	(via
		(at 119.945404 -51.227482)
		(size 0.508)
		(drill 0.254)
		(layers "F.Cu" "B.Cu")
		(net "GND")
	)
	(via
		(at 377.208288 -352.245422)
		(size 0.4572)
		(drill 0.254)
		(layers "F.Cu" "B.Cu")
		(net "GND")
	)
	(via
		(at 69.149976 -279.749758)
		(size 0.4064)
		(drill 0.2032)
		(layers "F.Cu" "B.Cu")
		(net "GND")
	)
	(via
		(at 144.01292 -352.245422)
		(size 0.4572)
		(drill 0.254)
		(layers "F.Cu" "B.Cu")
		(net "GND")
	)
	(via
		(at 237.859062 -87.715344)
		(size 0.508)
		(drill 0.254)
		(layers "F.Cu" "B.Cu")
		(net "GND")
	)
	(via
		(at 49.67478 -284.024832)
		(size 0.4064)
		(drill 0.2032)
		(layers "F.Cu" "B.Cu")
		(net "GND")
	)
	(via
		(at 76.348082 -342.439498)
		(size 0.4064)
		(drill 0.2032)
		(layers "F.Cu" "B.Cu")
		(net "GND")
	)
	(via
		(at 72.474836 -292.574726)
		(size 0.4064)
		(drill 0.2032)
		(layers "F.Cu" "B.Cu")
		(net "GND")
	)
	(via
		(at 165.396164 -129.68351)
		(size 0.508)
		(drill 0.254)
		(layers "F.Cu" "B.Cu")
		(net "GND")
	)
	(via
		(at 155.325064 -273.574764)
		(size 0.4064)
		(drill 0.2032)
		(layers "F.Cu" "B.Cu")
		(net "GND")
	)
	(via
		(at 430.466246 -129.707894)
		(size 0.508)
		(drill 0.254)
		(layers "F.Cu" "B.Cu")
		(net "GND")
	)
	(via
		(at 134.68604 -352.245422)
		(size 0.4572)
		(drill 0.254)
		(layers "F.Cu" "B.Cu")
		(net "GND")
	)
	(via
		(at 73.79208 -70.918832)
		(size 0.508)
		(drill 0.254)
		(layers "F.Cu" "B.Cu")
		(net "GND")
	)
	(via
		(at 198.550022 -274.049744)
		(size 0.4064)
		(drill 0.2032)
		(layers "F.Cu" "B.Cu")
		(net "GND")
	)
	(via
		(at 119.747792 -382.84023)
		(size 0.4572)
		(drill 0.254)
		(layers "F.Cu" "B.Cu")
		(net "GND")
	)
	(via
		(at 161.15157 -107.845098)
		(size 0.508)
		(drill 0.254)
		(layers "F.Cu" "B.Cu")
		(net "GND")
	)
	(via
		(at 374.927876 -401.040092)
		(size 0.508)
		(drill 0.254)
		(layers "F.Cu" "B.Cu")
		(net "GND")
	)
	(via
		(at 16.30045 -227.965)
		(size 0.508)
		(drill 0.254)
		(layers "F.Cu" "B.Cu")
		(net "GND")
	)
	(via
		(at 348.343982 -286.842454)
		(size 0.508)
		(drill 0.254)
		(layers "F.Cu" "B.Cu")
		(net "GND")
	)
	(via
		(at 40.174926 -284.974792)
		(size 0.4064)
		(drill 0.2032)
		(layers "F.Cu" "B.Cu")
		(net "GND")
	)
	(via
		(at 12.608052 -305.786536)
		(size 0.508)
		(drill 0.254)
		(layers "F.Cu" "B.Cu")
		(net "GND")
	)
	(via
		(at 357.35514 -121.661428)
		(size 0.508)
		(drill 0.254)
		(layers "F.Cu" "B.Cu")
		(net "GND")
	)
	(via
		(at 297.074844 -307.774848)
		(size 0.4064)
		(drill 0.2032)
		(layers "F.Cu" "B.Cu")
		(net "GND")
	)
	(via
		(at 414.548828 -33.19018)
		(size 0.508)
		(drill 0.254)
		(layers "F.Cu" "B.Cu")
		(net "GND")
	)
	(via
		(at 25.352756 -347.951806)
		(size 0.4572)
		(drill 0.254)
		(layers "F.Cu" "B.Cu")
		(net "GND")
	)
	(via
		(at 413.465264 -349.219774)
		(size 0.4572)
		(drill 0.254)
		(layers "F.Cu" "B.Cu")
		(net "GND")
	)
	(via
		(at 310.849772 -304.449734)
		(size 0.4064)
		(drill 0.2032)
		(layers "F.Cu" "B.Cu")
		(net "GND")
	)
	(via
		(at 165.947852 -382.73863)
		(size 0.508)
		(drill 0.254)
		(layers "F.Cu" "B.Cu")
		(net "GND")
	)
	(via
		(at 360.09834 -21.077936)
		(size 0.508)
		(drill 0.254)
		(layers "F.Cu" "B.Cu")
		(net "GND")
	)
	(via
		(at 62.024768 -294.4749)
		(size 0.4064)
		(drill 0.2032)
		(layers "F.Cu" "B.Cu")
		(net "GND")
	)
	(via
		(at 385.927854 -383.940304)
		(size 0.508)
		(drill 0.254)
		(layers "F.Cu" "B.Cu")
		(net "GND")
	)
	(via
		(at 252.283722 -81.61655)
		(size 0.508)
		(drill 0.254)
		(layers "F.Cu" "B.Cu")
		(net "GND")
	)
	(via
		(at 130.74777 -381.241808)
		(size 0.4572)
		(drill 0.254)
		(layers "F.Cu" "B.Cu")
		(net "GND")
	)
	(via
		(at 121.798334 -306.55387)
		(size 0.508)
		(drill 0.254)
		(layers "F.Cu" "B.Cu")
		(net "GND")
	)
	(via
		(at 430.274984 -303.024794)
		(size 0.4064)
		(drill 0.2032)
		(layers "F.Cu" "B.Cu")
		(net "GND")
	)
	(via
		(at 74.374756 -290.674806)
		(size 0.4064)
		(drill 0.2032)
		(layers "F.Cu" "B.Cu")
		(net "GND")
	)
	(via
		(at 40.214804 -26.171398)
		(size 0.508)
		(drill 0.254)
		(layers "F.Cu" "B.Cu")
		(net "GND")
	)
	(via
		(at 119.747792 -401.040092)
		(size 0.4572)
		(drill 0.254)
		(layers "F.Cu" "B.Cu")
		(net "GND")
	)
	(via
		(at 403.674834 -284.024832)
		(size 0.4064)
		(drill 0.2032)
		(layers "F.Cu" "B.Cu")
		(net "GND")
	)
	(via
		(at 67.249802 -310.149748)
		(size 0.4064)
		(drill 0.2032)
		(layers "F.Cu" "B.Cu")
		(net "GND")
	)
	(via
		(at 463.037682 -87.897462)
		(size 0.508)
		(drill 0.254)
		(layers "F.Cu" "B.Cu")
		(net "GND")
	)
	(via
		(at 341.694008 -226.786948)
		(size 0.4572)
		(drill 0.254)
		(layers "F.Cu" "B.Cu")
		(net "GND")
	)
	(via
		(at 183.379872 -354.708206)
		(size 0.4064)
		(drill 0.2032)
		(layers "F.Cu" "B.Cu")
		(net "GND")
	)
	(via
		(at 401.774914 -287.824926)
		(size 0.4064)
		(drill 0.2032)
		(layers "F.Cu" "B.Cu")
		(net "GND")
	)
	(via
		(at 133.427216 -343.073482)
		(size 0.4572)
		(drill 0.254)
		(layers "F.Cu" "B.Cu")
		(net "GND")
	)
	(via
		(at 166.725092 -296.37482)
		(size 0.4064)
		(drill 0.2032)
		(layers "F.Cu" "B.Cu")
		(net "GND")
	)
	(via
		(at 311.324752 -298.27474)
		(size 0.4064)
		(drill 0.2032)
		(layers "F.Cu" "B.Cu")
		(net "GND")
	)
	(via
		(at 87.676482 -342.439498)
		(size 0.4064)
		(drill 0.2032)
		(layers "F.Cu" "B.Cu")
		(net "GND")
	)
	(via
		(at 125.709172 -291.32149)
		(size 0.508)
		(drill 0.254)
		(layers "F.Cu" "B.Cu")
		(net "GND")
	)
	(via
		(at 190.474854 -292.574726)
		(size 0.4064)
		(drill 0.2032)
		(layers "F.Cu" "B.Cu")
		(net "GND")
	)
	(via
		(at 390.374886 -297.32478)
		(size 0.4064)
		(drill 0.2032)
		(layers "F.Cu" "B.Cu")
		(net "GND")
	)
	(via
		(at 400.012154 -23.355554)
		(size 0.508)
		(drill 0.254)
		(layers "F.Cu" "B.Cu")
		(net "GND")
	)
	(via
		(at 237.849918 -27.04973)
		(size 0.508)
		(drill 0.254)
		(layers "F.Cu" "B.Cu")
		(net "GND")
	)
	(via
		(at 301.824898 -294.4749)
		(size 0.4064)
		(drill 0.2032)
		(layers "F.Cu" "B.Cu")
		(net "GND")
	)
	(via
		(at 192.850008 -272.14957)
		(size 0.4064)
		(drill 0.2032)
		(layers "F.Cu" "B.Cu")
		(net "GND")
	)
	(via
		(at 31.570676 -349.219774)
		(size 0.4572)
		(drill 0.254)
		(layers "F.Cu" "B.Cu")
		(net "GND")
	)
	(via
		(at 388.474966 -298.27474)
		(size 0.4064)
		(drill 0.2032)
		(layers "F.Cu" "B.Cu")
		(net "GND")
	)
	(via
		(at 287.574736 -307.774848)
		(size 0.4064)
		(drill 0.2032)
		(layers "F.Cu" "B.Cu")
		(net "GND")
	)
	(via
		(at 297.582844 -34.990024)
		(size 0.508)
		(drill 0.254)
		(layers "F.Cu" "B.Cu")
		(net "GND")
	)
	(via
		(at 133.427216 -344.831162)
		(size 0.4572)
		(drill 0.254)
		(layers "F.Cu" "B.Cu")
		(net "GND")
	)
	(via
		(at 28.090368 -342.439498)
		(size 0.4064)
		(drill 0.2032)
		(layers "F.Cu" "B.Cu")
		(net "GND")
	)
	(via
		(at 77.69987 -313.949842)
		(size 0.4064)
		(drill 0.2032)
		(layers "F.Cu" "B.Cu")
		(net "GND")
	)
	(via
		(at 200.503282 -338.84362)
		(size 0.508)
		(drill 0.254)
		(layers "F.Cu" "B.Cu")
		(net "GND")
	)
	(via
		(at 431.700178 -279.750012)
		(size 0.4064)
		(drill 0.2032)
		(layers "F.Cu" "B.Cu")
		(net "GND")
	)
	(via
		(at 286.906462 -102.444804)
		(size 0.508)
		(drill 0.254)
		(layers "F.Cu" "B.Cu")
		(net "GND")
	)
	(via
		(at 355.470968 -285.267654)
		(size 0.508)
		(drill 0.254)
		(layers "F.Cu" "B.Cu")
		(net "GND")
	)
	(via
		(at 69.49948 -57.439814)
		(size 0.508)
		(drill 0.254)
		(layers "F.Cu" "B.Cu")
		(net "GND")
	)
	(via
		(at 393.286996 -151.157432)
		(size 0.508)
		(drill 0.254)
		(layers "F.Cu" "B.Cu")
		(net "GND")
	)
	(via
		(at 263.340088 -27.729688)
		(size 0.508)
		(drill 0.254)
		(layers "F.Cu" "B.Cu")
		(net "GND")
	)
	(via
		(at 189.999874 -308.249828)
		(size 0.4064)
		(drill 0.2032)
		(layers "F.Cu" "B.Cu")
		(net "GND")
	)
	(via
		(at 416.974782 -307.774848)
		(size 0.4064)
		(drill 0.2032)
		(layers "F.Cu" "B.Cu")
		(net "GND")
	)
	(via
		(at 434.327808 -408.738578)
		(size 0.508)
		(drill 0.254)
		(layers "F.Cu" "B.Cu")
		(net "GND")
	)
	(via
		(at 147.568666 -59.974734)
		(size 0.508)
		(drill 0.254)
		(layers "F.Cu" "B.Cu")
		(net "GND")
	)
	(via
		(at 346.562172 -277.639272)
		(size 0.508)
		(drill 0.254)
		(layers "F.Cu" "B.Cu")
		(net "GND")
	)
	(via
		(at 273.324828 -287.824926)
		(size 0.4064)
		(drill 0.2032)
		(layers "F.Cu" "B.Cu")
		(net "GND")
	)
	(via
		(at 0.77089 -334.781144)
		(size 0.508)
		(drill 0.254)
		(layers "F.Cu" "B.Cu")
		(net "GND")
	)
	(via
		(at 270.474948 -294.4749)
		(size 0.4064)
		(drill 0.2032)
		(layers "F.Cu" "B.Cu")
		(net "GND")
	)
	(via
		(at 176.94783 -382.840484)
		(size 0.508)
		(drill 0.254)
		(layers "F.Cu" "B.Cu")
		(net "GND")
	)
	(via
		(at 148.166582 -35.871912)
		(size 0.508)
		(drill 0.254)
		(layers "F.Cu" "B.Cu")
		(net "GND")
	)
	(via
		(at 402.249894 -280.699718)
		(size 0.4064)
		(drill 0.2032)
		(layers "F.Cu" "B.Cu")
		(net "GND")
	)
	(via
		(at 38.347904 -371.038628)
		(size 0.508)
		(drill 0.254)
		(layers "F.Cu" "B.Cu")
		(net "GND")
	)
	(via
		(at 364.580932 -29.589984)
		(size 0.508)
		(drill 0.254)
		(layers "F.Cu" "B.Cu")
		(net "GND")
	)
	(via
		(at 142.306802 -210.817206)
		(size 0.508)
		(drill 0.254)
		(layers "F.Cu" "B.Cu")
		(net "GND")
	)
	(via
		(at 379.9459 -345.465146)
		(size 0.4064)
		(drill 0.2032)
		(layers "F.Cu" "B.Cu")
		(net "GND")
	)
	(via
		(at 335.538064 -102.021894)
		(size 0.508)
		(drill 0.254)
		(layers "F.Cu" "B.Cu")
		(net "GND")
	)
	(via
		(at 122.477022 -119.071136)
		(size 0.508)
		(drill 0.254)
		(layers "F.Cu" "B.Cu")
		(net "GND")
	)
	(via
		(at 71.347838 -401.040092)
		(size 0.508)
		(drill 0.254)
		(layers "F.Cu" "B.Cu")
		(net "GND")
	)
	(via
		(at 191.227964 -352.245422)
		(size 0.4572)
		(drill 0.254)
		(layers "F.Cu" "B.Cu")
		(net "GND")
	)
	(via
		(at 297.549824 -310.149748)
		(size 0.4064)
		(drill 0.2032)
		(layers "F.Cu" "B.Cu")
		(net "GND")
	)
	(via
		(at 398.275048 -74.58583)
		(size 0.508)
		(drill 0.254)
		(layers "F.Cu" "B.Cu")
		(net "GND")
	)
	(via
		(at 50.386488 -48.874934)
		(size 0.508)
		(drill 0.254)
		(layers "F.Cu" "B.Cu")
		(net "GND")
	)
	(via
		(at 269.049754 -305.399948)
		(size 0.4064)
		(drill 0.2032)
		(layers "F.Cu" "B.Cu")
		(net "GND")
	)
	(via
		(at 53.949854 -310.149748)
		(size 0.4064)
		(drill 0.2032)
		(layers "F.Cu" "B.Cu")
		(net "GND")
	)
	(via
		(at 70.50151 -355.366066)
		(size 0.4572)
		(drill 0.254)
		(layers "F.Cu" "B.Cu")
		(net "GND")
	)
	(via
		(at 65.349882 -314.899802)
		(size 0.4064)
		(drill 0.2032)
		(layers "F.Cu" "B.Cu")
		(net "GND")
	)
	(via
		(at 466.827616 -26.612596)
		(size 0.508)
		(drill 0.254)
		(layers "F.Cu" "B.Cu")
		(net "GND")
	)
	(via
		(at 270.474948 -292.57498)
		(size 0.4064)
		(drill 0.2032)
		(layers "F.Cu" "B.Cu")
		(net "GND")
	)
	(via
		(at 191.227964 -344.831162)
		(size 0.4572)
		(drill 0.254)
		(layers "F.Cu" "B.Cu")
		(net "GND")
	)
	(via
		(at 35.759644 -109.382052)
		(size 0.508)
		(drill 0.254)
		(layers "F.Cu" "B.Cu")
		(net "GND")
	)
	(via
		(at 133.423152 -133.890766)
		(size 0.508)
		(drill 0.254)
		(layers "F.Cu" "B.Cu")
		(net "GND")
	)
	(via
		(at 29.72054 -347.951806)
		(size 0.4572)
		(drill 0.254)
		(layers "F.Cu" "B.Cu")
		(net "GND")
	)
	(via
		(at 27.668982 -295.933114)
		(size 0.508)
		(drill 0.254)
		(layers "F.Cu" "B.Cu")
		(net "GND")
	)
	(via
		(at 338.435696 -354.098098)
		(size 0.4572)
		(drill 0.254)
		(layers "F.Cu" "B.Cu")
		(net "GND")
	)
	(via
		(at 211.573364 -73.20026)
		(size 0.508)
		(drill 0.254)
		(layers "F.Cu" "B.Cu")
		(net "GND")
	)
	(via
		(at 392.753088 -355.366066)
		(size 0.4572)
		(drill 0.254)
		(layers "F.Cu" "B.Cu")
		(net "GND")
	)
	(via
		(at 165.947852 -378.83846)
		(size 0.508)
		(drill 0.254)
		(layers "F.Cu" "B.Cu")
		(net "GND")
	)
	(via
		(at 360.09834 -19.096736)
		(size 0.508)
		(drill 0.254)
		(layers "F.Cu" "B.Cu")
		(net "GND")
	)
	(via
		(at 421.724836 -293.52494)
		(size 0.4064)
		(drill 0.2032)
		(layers "F.Cu" "B.Cu")
		(net "GND")
	)
	(via
		(at 74.869294 -355.366066)
		(size 0.4572)
		(drill 0.254)
		(layers "F.Cu" "B.Cu")
		(net "GND")
	)
	(via
		(at 403.71014 -354.732082)
		(size 0.4064)
		(drill 0.2032)
		(layers "F.Cu" "B.Cu")
		(net "GND")
	)
	(via
		(at 9.470136 -72.459088)
		(size 0.508)
		(drill 0.254)
		(layers "F.Cu" "B.Cu")
		(net "GND")
	)
	(via
		(at 179.07508 -305.874928)
		(size 0.4064)
		(drill 0.2032)
		(layers "F.Cu" "B.Cu")
		(net "GND")
	)
	(via
		(at 389.899906 -304.449734)
		(size 0.4064)
		(drill 0.2032)
		(layers "F.Cu" "B.Cu")
		(net "GND")
	)
	(via
		(at 289.127692 -402.140166)
		(size 0.508)
		(drill 0.254)
		(layers "F.Cu" "B.Cu")
		(net "GND")
	)
	(via
		(at 333.539846 -73.87463)
		(size 0.508)
		(drill 0.254)
		(layers "F.Cu" "B.Cu")
		(net "GND")
	)
	(via
		(at 337.725004 -115.579906)
		(size 0.508)
		(drill 0.254)
		(layers "F.Cu" "B.Cu")
		(net "GND")
	)
	(via
		(at 395.59992 -310.149748)
		(size 0.4064)
		(drill 0.2032)
		(layers "F.Cu" "B.Cu")
		(net "GND")
	)
	(via
		(at 210.03895 -204.47)
		(size 0.508)
		(drill 0.254)
		(layers "F.Cu" "B.Cu")
		(net "GND")
	)
	(via
		(at 429.606964 -49.574704)
		(size 0.508)
		(drill 0.254)
		(layers "F.Cu" "B.Cu")
		(net "GND")
	)
	(via
		(at 275.224748 -281.174952)
		(size 0.4064)
		(drill 0.2032)
		(layers "F.Cu" "B.Cu")
		(net "GND")
	)
	(via
		(at 55.374794 -302.074834)
		(size 0.4064)
		(drill 0.2032)
		(layers "F.Cu" "B.Cu")
		(net "GND")
	)
	(via
		(at 425.049696 -276.899878)
		(size 0.4064)
		(drill 0.2032)
		(layers "F.Cu" "B.Cu")
		(net "GND")
	)
	(via
		(at 335.326736 -349.219774)
		(size 0.4572)
		(drill 0.254)
		(layers "F.Cu" "B.Cu")
		(net "GND")
	)
	(via
		(at 425.527724 -398.24025)
		(size 0.508)
		(drill 0.254)
		(layers "F.Cu" "B.Cu")
		(net "GND")
	)
	(via
		(at 108.89996 -136.21766)
		(size 0.508)
		(drill 0.254)
		(layers "F.Cu" "B.Cu")
		(net "GND")
	)
	(via
		(at 345.168982 -286.842454)
		(size 0.508)
		(drill 0.254)
		(layers "F.Cu" "B.Cu")
		(net "GND")
	)
	(via
		(at 169.099992 -273.099784)
		(size 0.4064)
		(drill 0.2032)
		(layers "F.Cu" "B.Cu")
		(net "GND")
	)
	(via
		(at 132.802884 -285.953454)
		(size 0.508)
		(drill 0.254)
		(layers "F.Cu" "B.Cu")
		(net "GND")
	)
	(via
		(at 50.624994 -306.824888)
		(size 0.4064)
		(drill 0.2032)
		(layers "F.Cu" "B.Cu")
		(net "GND")
	)
	(via
		(at 241.193066 -83.951318)
		(size 0.508)
		(drill 0.254)
		(layers "F.Cu" "B.Cu")
		(net "GND")
	)
	(via
		(at 116.403628 -345.465146)
		(size 0.4064)
		(drill 0.2032)
		(layers "F.Cu" "B.Cu")
		(net "GND")
	)
	(via
		(at 391.324846 -286.874712)
		(size 0.4064)
		(drill 0.2032)
		(layers "F.Cu" "B.Cu")
		(net "GND")
	)
	(via
		(at 189.999874 -288.299906)
		(size 0.4064)
		(drill 0.2032)
		(layers "F.Cu" "B.Cu")
		(net "GND")
	)
	(via
		(at 431.840386 -147.824698)
		(size 0.508)
		(drill 0.254)
		(layers "F.Cu" "B.Cu")
		(net "GND")
	)
	(via
		(at 368.601244 -89.013538)
		(size 0.508)
		(drill 0.254)
		(layers "F.Cu" "B.Cu")
		(net "GND")
	)
	(via
		(at 426.272452 -357.75773)
		(size 0.4064)
		(drill 0.2032)
		(layers "F.Cu" "B.Cu")
		(net "GND")
	)
	(via
		(at 437.07812 -358.391714)
		(size 0.4572)
		(drill 0.254)
		(layers "F.Cu" "B.Cu")
		(net "GND")
	)
	(via
		(at 233.572558 -64.799972)
		(size 0.508)
		(drill 0.254)
		(layers "F.Cu" "B.Cu")
		(net "GND")
	)
	(via
		(at 158.649924 -311.099962)
		(size 0.4064)
		(drill 0.2032)
		(layers "F.Cu" "B.Cu")
		(net "GND")
	)
	(via
		(at 229.949502 -180.151786)
		(size 0.508)
		(drill 0.254)
		(layers "F.Cu" "B.Cu")
		(net "GND")
	)
	(via
		(at 166.381684 -358.391714)
		(size 0.4572)
		(drill 0.254)
		(layers "F.Cu" "B.Cu")
		(net "GND")
	)
	(via
		(at 67.724782 -287.824926)
		(size 0.4064)
		(drill 0.2032)
		(layers "F.Cu" "B.Cu")
		(net "GND")
	)
	(via
		(at 374.927876 -376.241818)
		(size 0.508)
		(drill 0.254)
		(layers "F.Cu" "B.Cu")
		(net "GND")
	)
	(via
		(at 48.24984 -316.799722)
		(size 0.4064)
		(drill 0.2032)
		(layers "F.Cu" "B.Cu")
		(net "GND")
	)
	(via
		(at 163.49345 -108.279946)
		(size 0.508)
		(drill 0.254)
		(layers "F.Cu" "B.Cu")
		(net "GND")
	)
	(via
		(at 295.944798 -29.589984)
		(size 0.508)
		(drill 0.254)
		(layers "F.Cu" "B.Cu")
		(net "GND")
	)
	(via
		(at 423.32783 -407.638504)
		(size 0.508)
		(drill 0.254)
		(layers "F.Cu" "B.Cu")
		(net "GND")
	)
	(via
		(at 220.241622 -143.942562)
		(size 0.508)
		(drill 0.254)
		(layers "F.Cu" "B.Cu")
		(net "GND")
	)
	(via
		(at 338.892642 -8.48995)
		(size 0.508)
		(drill 0.254)
		(layers "F.Cu" "B.Cu")
		(net "GND")
	)
	(via
		(at 59.192668 -11.372342)
		(size 0.508)
		(drill 0.254)
		(layers "F.Cu" "B.Cu")
		(net "GND")
	)
	(via
		(at 58.699908 -310.149748)
		(size 0.4064)
		(drill 0.2032)
		(layers "F.Cu" "B.Cu")
		(net "GND")
	)
	(via
		(at 174.747936 -400.938492)
		(size 0.508)
		(drill 0.254)
		(layers "F.Cu" "B.Cu")
		(net "GND")
	)
	(via
		(at 301.88408 -120.716548)
		(size 0.508)
		(drill 0.254)
		(layers "F.Cu" "B.Cu")
		(net "GND")
	)
	(via
		(at 16.74876 -307.183028)
		(size 0.508)
		(drill 0.254)
		(layers "F.Cu" "B.Cu")
		(net "GND")
	)
	(via
		(at 103.15067 -290.05149)
		(size 0.508)
		(drill 0.254)
		(layers "F.Cu" "B.Cu")
		(net "GND")
	)
	(via
		(at 66.44767 -147.555204)
		(size 0.508)
		(drill 0.254)
		(layers "F.Cu" "B.Cu")
		(net "GND")
	)
	(via
		(at 295.592754 -182.752492)
		(size 0.508)
		(drill 0.254)
		(layers "F.Cu" "B.Cu")
		(net "GND")
	)
	(via
		(at 419.683184 -358.391714)
		(size 0.4572)
		(drill 0.254)
		(layers "F.Cu" "B.Cu")
		(net "GND")
	)
	(via
		(at 286.149796 -279.749758)
		(size 0.4064)
		(drill 0.2032)
		(layers "F.Cu" "B.Cu")
		(net "GND")
	)
	(via
		(at 185.381392 -345.465146)
		(size 0.4064)
		(drill 0.2032)
		(layers "F.Cu" "B.Cu")
		(net "GND")
	)
	(via
		(at 390.374886 -274.524978)
		(size 0.4064)
		(drill 0.2032)
		(layers "F.Cu" "B.Cu")
		(net "GND")
	)
	(via
		(at 321.998086 -19.096736)
		(size 0.508)
		(drill 0.254)
		(layers "F.Cu" "B.Cu")
		(net "GND")
	)
	(via
		(at 208.231994 -13.613638)
		(size 0.508)
		(drill 0.254)
		(layers "F.Cu" "B.Cu")
		(net "GND")
	)
	(via
		(at 429.010064 -358.391714)
		(size 0.4572)
		(drill 0.254)
		(layers "F.Cu" "B.Cu")
		(net "GND")
	)
	(via
		(at 430.8602 -352.245422)
		(size 0.4572)
		(drill 0.254)
		(layers "F.Cu" "B.Cu")
		(net "GND")
	)
	(via
		(at 9.0551 -121.661428)
		(size 0.508)
		(drill 0.254)
		(layers "F.Cu" "B.Cu")
		(net "GND")
	)
	(via
		(at 381.94742 -357.75773)
		(size 0.4064)
		(drill 0.2032)
		(layers "F.Cu" "B.Cu")
		(net "GND")
	)
	(via
		(at 155.325064 -296.37482)
		(size 0.4064)
		(drill 0.2032)
		(layers "F.Cu" "B.Cu")
		(net "GND")
	)
	(via
		(at 27.668982 -299.133514)
		(size 0.508)
		(drill 0.254)
		(layers "F.Cu" "B.Cu")
		(net "GND")
	)
	(via
		(at 330.587604 -342.439498)
		(size 0.4064)
		(drill 0.2032)
		(layers "F.Cu" "B.Cu")
		(net "GND")
	)
	(via
		(at 388.949946 -299.699934)
		(size 0.4064)
		(drill 0.2032)
		(layers "F.Cu" "B.Cu")
		(net "GND")
	)
	(via
		(at 275.547582 -351.611438)
		(size 0.4064)
		(drill 0.2032)
		(layers "F.Cu" "B.Cu")
		(net "GND")
	)
	(via
		(at 44.006516 -350.977454)
		(size 0.4572)
		(drill 0.254)
		(layers "F.Cu" "B.Cu")
		(net "GND")
	)
	(via
		(at 109.812328 -226.580446)
		(size 0.508)
		(drill 0.254)
		(layers "F.Cu" "B.Cu")
		(net "GND")
	)
	(via
		(at 20.39366 -347.951806)
		(size 0.4572)
		(drill 0.254)
		(layers "F.Cu" "B.Cu")
		(net "GND")
	)
	(via
		(at 33.947862 -371.038628)
		(size 0.508)
		(drill 0.254)
		(layers "F.Cu" "B.Cu")
		(net "GND")
	)
	(via
		(at 7.820152 -33.19018)
		(size 0.508)
		(drill 0.254)
		(layers "F.Cu" "B.Cu")
		(net "GND")
	)
	(via
		(at 414.74771 -123.635008)
		(size 0.508)
		(drill 0.254)
		(layers "F.Cu" "B.Cu")
		(net "GND")
	)
	(via
		(at 157.224984 -289.724846)
		(size 0.4064)
		(drill 0.2032)
		(layers "F.Cu" "B.Cu")
		(net "GND")
	)
	(via
		(at 422.792144 -341.805514)
		(size 0.4572)
		(drill 0.254)
		(layers "F.Cu" "B.Cu")
		(net "GND")
	)
	(via
		(at 377.181872 -82.55635)
		(size 0.508)
		(drill 0.254)
		(layers "F.Cu" "B.Cu")
		(net "GND")
	)
	(via
		(at 166.249858 -279.749758)
		(size 0.4064)
		(drill 0.2032)
		(layers "F.Cu" "B.Cu")
		(net "GND")
	)
	(via
		(at 428.84979 -319.65011)
		(size 0.4064)
		(drill 0.2032)
		(layers "F.Cu" "B.Cu")
		(net "GND")
	)
	(via
		(at 63.449962 -316.799722)
		(size 0.4064)
		(drill 0.2032)
		(layers "F.Cu" "B.Cu")
		(net "GND")
	)
	(via
		(at 306.099718 -309.199788)
		(size 0.4064)
		(drill 0.2032)
		(layers "F.Cu" "B.Cu")
		(net "GND")
	)
	(via
		(at 372.249192 -347.951806)
		(size 0.4572)
		(drill 0.254)
		(layers "F.Cu" "B.Cu")
		(net "GND")
	)
	(via
		(at 45.051726 -135.364982)
		(size 0.508)
		(drill 0.254)
		(layers "F.Cu" "B.Cu")
		(net "GND")
	)
	(via
		(at 416.974782 -288.774886)
		(size 0.4064)
		(drill 0.2032)
		(layers "F.Cu" "B.Cu")
		(net "GND")
	)
	(via
		(at 335.698084 -351.611438)
		(size 0.4064)
		(drill 0.2032)
		(layers "F.Cu" "B.Cu")
		(net "GND")
	)
	(via
		(at 446.680082 -401.580858)
		(size 0.508)
		(drill 0.254)
		(layers "F.Cu" "B.Cu")
		(net "GND")
	)
	(via
		(at 260.460236 -335.433924)
		(size 0.508)
		(drill 0.254)
		(layers "F.Cu" "B.Cu")
		(net "GND")
	)
	(via
		(at 369.070128 -195.334128)
		(size 0.508)
		(drill 0.254)
		(layers "F.Cu" "B.Cu")
		(net "GND")
	)
	(via
		(at 463.037682 -133.617462)
		(size 0.508)
		(drill 0.254)
		(layers "F.Cu" "B.Cu")
		(net "GND")
	)
	(via
		(at 420.261288 -196.012308)
		(size 0.508)
		(drill 0.254)
		(layers "F.Cu" "B.Cu")
		(net "GND")
	)
	(via
		(at 429.800004 -317.749936)
		(size 0.4064)
		(drill 0.2032)
		(layers "F.Cu" "B.Cu")
		(net "GND")
	)
	(via
		(at 387.525006 -283.074872)
		(size 0.4064)
		(drill 0.2032)
		(layers "F.Cu" "B.Cu")
		(net "GND")
	)
	(via
		(at 305.149758 -319.65011)
		(size 0.4064)
		(drill 0.2032)
		(layers "F.Cu" "B.Cu")
		(net "GND")
	)
	(via
		(at 310.751474 -104.120696)
		(size 0.508)
		(drill 0.254)
		(layers "F.Cu" "B.Cu")
		(net "GND")
	)
	(via
		(at 402.079968 -355.366066)
		(size 0.4572)
		(drill 0.254)
		(layers "F.Cu" "B.Cu")
		(net "GND")
	)
	(via
		(at 357.948992 -33.19018)
		(size 0.508)
		(drill 0.254)
		(layers "F.Cu" "B.Cu")
		(net "GND")
	)
	(via
		(at 27.323288 -56.353456)
		(size 0.508)
		(drill 0.254)
		(layers "F.Cu" "B.Cu")
		(net "GND")
	)
	(via
		(at 339.728048 -381.638556)
		(size 0.508)
		(drill 0.254)
		(layers "F.Cu" "B.Cu")
		(net "GND")
	)
	(via
		(at 401.78736 -133.564884)
		(size 0.508)
		(drill 0.254)
		(layers "F.Cu" "B.Cu")
		(net "GND")
	)
	(via
		(at 398.971008 -349.219774)
		(size 0.4572)
		(drill 0.254)
		(layers "F.Cu" "B.Cu")
		(net "GND")
	)
	(via
		(at 365.299752 -220.378782)
		(size 0.508)
		(drill 0.254)
		(layers "F.Cu" "B.Cu")
		(net "GND")
	)
	(via
		(at 48.3743 -352.245422)
		(size 0.4572)
		(drill 0.254)
		(layers "F.Cu" "B.Cu")
		(net "GND")
	)
	(via
		(at 169.465244 -352.245422)
		(size 0.4572)
		(drill 0.254)
		(layers "F.Cu" "B.Cu")
		(net "GND")
	)
	(via
		(at 161.975038 -303.024794)
		(size 0.4064)
		(drill 0.2032)
		(layers "F.Cu" "B.Cu")
		(net "GND")
	)
	(via
		(at 19.939254 -28.05303)
		(size 0.508)
		(drill 0.254)
		(layers "F.Cu" "B.Cu")
		(net "GND")
	)
	(via
		(at 386.701792 -136.901936)
		(size 0.508)
		(drill 0.254)
		(layers "F.Cu" "B.Cu")
		(net "GND")
	)
	(via
		(at 53.315108 -45.88891)
		(size 0.508)
		(drill 0.254)
		(layers "F.Cu" "B.Cu")
		(net "GND")
	)
	(via
		(at 241.558064 -145.083276)
		(size 0.508)
		(drill 0.254)
		(layers "F.Cu" "B.Cu")
		(net "GND")
	)
	(via
		(at 452.220838 -315.434726)
		(size 0.508)
		(drill 0.254)
		(layers "F.Cu" "B.Cu")
		(net "GND")
	)
	(via
		(at 149.759162 -242.038378)
		(size 0.508)
		(drill 0.254)
		(layers "F.Cu" "B.Cu")
		(net "GND")
	)
	(via
		(at 161.500058 -318.699896)
		(size 0.4064)
		(drill 0.2032)
		(layers "F.Cu" "B.Cu")
		(net "GND")
	)
	(via
		(at 384.998722 -225.585782)
		(size 0.508)
		(drill 0.254)
		(layers "F.Cu" "B.Cu")
		(net "GND")
	)
	(via
		(at 184.29986 -312.999882)
		(size 0.4064)
		(drill 0.2032)
		(layers "F.Cu" "B.Cu")
		(net "GND")
	)
	(via
		(at 198.26605 -150.876762)
		(size 0.508)
		(drill 0.254)
		(layers "F.Cu" "B.Cu")
		(net "GND")
	)
	(via
		(at 29.54782 -377.341892)
		(size 0.508)
		(drill 0.254)
		(layers "F.Cu" "B.Cu")
		(net "GND")
	)
	(via
		(at 197.835774 -113.41354)
		(size 0.508)
		(drill 0.254)
		(layers "F.Cu" "B.Cu")
		(net "GND")
	)
	(via
		(at 389.27278 -351.611438)
		(size 0.4064)
		(drill 0.2032)
		(layers "F.Cu" "B.Cu")
		(net "GND")
	)
	(via
		(at 275.176234 -349.219774)
		(size 0.4572)
		(drill 0.254)
		(layers "F.Cu" "B.Cu")
		(net "GND")
	)
	(via
		(at 132.29463 -110.365032)
		(size 0.508)
		(drill 0.254)
		(layers "F.Cu" "B.Cu")
		(net "GND")
	)
	(via
		(at 385.135882 -231.70896)
		(size 0.508)
		(drill 0.254)
		(layers "F.Cu" "B.Cu")
		(net "GND")
	)
	(via
		(at 283.833062 -140.765022)
		(size 0.508)
		(drill 0.254)
		(layers "F.Cu" "B.Cu")
		(net "GND")
	)
	(via
		(at 392.274806 -289.724846)
		(size 0.4064)
		(drill 0.2032)
		(layers "F.Cu" "B.Cu")
		(net "GND")
	)
	(via
		(at 30.091888 -348.58579)
		(size 0.4064)
		(drill 0.2032)
		(layers "F.Cu" "B.Cu")
		(net "GND")
	)
	(via
		(at 82.909664 -303.024794)
		(size 0.4064)
		(drill 0.2032)
		(layers "F.Cu" "B.Cu")
		(net "GND")
	)
	(via
		(at 114.889026 -254.210312)
		(size 0.508)
		(drill 0.254)
		(layers "F.Cu" "B.Cu")
		(net "GND")
	)
	(via
		(at 154.850084 -316.799722)
		(size 0.4064)
		(drill 0.2032)
		(layers "F.Cu" "B.Cu")
		(net "GND")
	)
	(via
		(at 431.840386 -125.163326)
		(size 0.508)
		(drill 0.254)
		(layers "F.Cu" "B.Cu")
		(net "GND")
	)
	(via
		(at 122.70105 -31.390336)
		(size 0.508)
		(drill 0.254)
		(layers "F.Cu" "B.Cu")
		(net "GND")
	)
	(via
		(at 298.499784 -273.099784)
		(size 0.4064)
		(drill 0.2032)
		(layers "F.Cu" "B.Cu")
		(net "GND")
	)
	(via
		(at 159.599884 -277.849838)
		(size 0.4064)
		(drill 0.2032)
		(layers "F.Cu" "B.Cu")
		(net "GND")
	)
	(via
		(at 133.869684 -290.05149)
		(size 0.508)
		(drill 0.254)
		(layers "F.Cu" "B.Cu")
		(net "GND")
	)
	(via
		(at 269.329662 -351.611438)
		(size 0.4064)
		(drill 0.2032)
		(layers "F.Cu" "B.Cu")
		(net "GND")
	)
	(via
		(at 128.357884 -286.842454)
		(size 0.508)
		(drill 0.254)
		(layers "F.Cu" "B.Cu")
		(net "GND")
	)
	(via
		(at 199.682354 -37.087048)
		(size 0.508)
		(drill 0.254)
		(layers "F.Cu" "B.Cu")
		(net "GND")
	)
	(via
		(at 106.837226 -306.607718)
		(size 0.508)
		(drill 0.254)
		(layers "F.Cu" "B.Cu")
		(net "GND")
	)
	(via
		(at 55.849774 -280.699718)
		(size 0.4064)
		(drill 0.2032)
		(layers "F.Cu" "B.Cu")
		(net "GND")
	)
	(via
		(at 425.527724 -382.73863)
		(size 0.508)
		(drill 0.254)
		(layers "F.Cu" "B.Cu")
		(net "GND")
	)
	(via
		(at 175.749966 -314.899802)
		(size 0.4064)
		(drill 0.2032)
		(layers "F.Cu" "B.Cu")
		(net "GND")
	)
	(via
		(at 289.94989 -314.899802)
		(size 0.4064)
		(drill 0.2032)
		(layers "F.Cu" "B.Cu")
		(net "GND")
	)
	(via
		(at 228.308154 -58.799984)
		(size 0.508)
		(drill 0.254)
		(layers "F.Cu" "B.Cu")
		(net "GND")
	)
	(via
		(at 87.305134 -350.977454)
		(size 0.4572)
		(drill 0.254)
		(layers "F.Cu" "B.Cu")
		(net "GND")
	)
	(via
		(at 411.750002 -280.699718)
		(size 0.4064)
		(drill 0.2032)
		(layers "F.Cu" "B.Cu")
		(net "GND")
	)
	(via
		(at 53.48732 -129.964942)
		(size 0.508)
		(drill 0.254)
		(layers "F.Cu" "B.Cu")
		(net "GND")
	)
	(via
		(at 61.074808 -307.774848)
		(size 0.4064)
		(drill 0.2032)
		(layers "F.Cu" "B.Cu")
		(net "GND")
	)
	(via
		(at 120.77573 -259.918962)
		(size 0.508)
		(drill 0.254)
		(layers "F.Cu" "B.Cu")
		(net "GND")
	)
	(via
		(at 189.413388 -29.859478)
		(size 0.508)
		(drill 0.254)
		(layers "F.Cu" "B.Cu")
		(net "GND")
	)
	(via
		(at 231.388158 -64.200024)
		(size 0.508)
		(drill 0.254)
		(layers "F.Cu" "B.Cu")
		(net "GND")
	)
	(via
		(at 235.722922 -172.15993)
		(size 0.508)
		(drill 0.254)
		(layers "F.Cu" "B.Cu")
		(net "GND")
	)
	(via
		(at 55.849774 -311.099962)
		(size 0.4064)
		(drill 0.2032)
		(layers "F.Cu" "B.Cu")
		(net "GND")
	)
	(via
		(at 152.94991 -303.499774)
		(size 0.4064)
		(drill 0.2032)
		(layers "F.Cu" "B.Cu")
		(net "GND")
	)
	(via
		(at 261.965948 -83.634072)
		(size 0.508)
		(drill 0.254)
		(layers "F.Cu" "B.Cu")
		(net "GND")
	)
	(via
		(at 165.299898 -310.149748)
		(size 0.4064)
		(drill 0.2032)
		(layers "F.Cu" "B.Cu")
		(net "GND")
	)
	(via
		(at 275.547582 -348.58579)
		(size 0.4064)
		(drill 0.2032)
		(layers "F.Cu" "B.Cu")
		(net "GND")
	)
	(via
		(at 103.390192 -393.683744)
		(size 0.508)
		(drill 0.254)
		(layers "F.Cu" "B.Cu")
		(net "GND")
	)
	(via
		(at 20.274026 -73.85177)
		(size 0.508)
		(drill 0.254)
		(layers "F.Cu" "B.Cu")
		(net "GND")
	)
	(via
		(at 362.202222 -56.826404)
		(size 0.508)
		(drill 0.254)
		(layers "F.Cu" "B.Cu")
		(net "GND")
	)
	(via
		(at 133.423152 -133.255766)
		(size 0.508)
		(drill 0.254)
		(layers "F.Cu" "B.Cu")
		(net "GND")
	)
	(via
		(at 174.325026 -305.874928)
		(size 0.4064)
		(drill 0.2032)
		(layers "F.Cu" "B.Cu")
		(net "GND")
	)
	(via
		(at 415.074862 -306.824888)
		(size 0.4064)
		(drill 0.2032)
		(layers "F.Cu" "B.Cu")
		(net "GND")
	)
	(via
		(at 131.412996 -326.954388)
		(size 0.508)
		(drill 0.254)
		(layers "F.Cu" "B.Cu")
		(net "GND")
	)
	(via
		(at 304.199798 -276.899878)
		(size 0.4064)
		(drill 0.2032)
		(layers "F.Cu" "B.Cu")
		(net "GND")
	)
	(via
		(at 170.806364 -111.44504)
		(size 0.508)
		(drill 0.254)
		(layers "F.Cu" "B.Cu")
		(net "GND")
	)
	(via
		(at 298.10202 -58.731404)
		(size 0.508)
		(drill 0.254)
		(layers "F.Cu" "B.Cu")
		(net "GND")
	)
	(via
		(at 150.59152 -131.495546)
		(size 0.508)
		(drill 0.254)
		(layers "F.Cu" "B.Cu")
		(net "GND")
	)
	(via
		(at 446.239138 -31.652972)
		(size 0.508)
		(drill 0.254)
		(layers "F.Cu" "B.Cu")
		(net "GND")
	)
	(via
		(at 268.958314 -344.831162)
		(size 0.4572)
		(drill 0.254)
		(layers "F.Cu" "B.Cu")
		(net "GND")
	)
	(via
		(at 128.992884 -286.842454)
		(size 0.508)
		(drill 0.254)
		(layers "F.Cu" "B.Cu")
		(net "GND")
	)
	(via
		(at 378.968 -417.82492)
		(size 0.508)
		(drill 0.254)
		(layers "F.Cu" "B.Cu")
		(net "GND")
	)
	(via
		(at 40.897556 -349.219774)
		(size 0.4572)
		(drill 0.254)
		(layers "F.Cu" "B.Cu")
		(net "GND")
	)
	(via
		(at 295.649904 -315.849762)
		(size 0.4064)
		(drill 0.2032)
		(layers "F.Cu" "B.Cu")
		(net "GND")
	)
	(via
		(at 405.100028 -274.049744)
		(size 0.4064)
		(drill 0.2032)
		(layers "F.Cu" "B.Cu")
		(net "GND")
	)
	(via
		(at 88.947752 -403.738588)
		(size 0.508)
		(drill 0.254)
		(layers "F.Cu" "B.Cu")
		(net "GND")
	)
	(via
		(at 172.424852 -309.674768)
		(size 0.4064)
		(drill 0.2032)
		(layers "F.Cu" "B.Cu")
		(net "GND")
	)
	(via
		(at 155.800044 -313.949842)
		(size 0.4064)
		(drill 0.2032)
		(layers "F.Cu" "B.Cu")
		(net "GND")
	)
	(via
		(at 36.14801 -404.940262)
		(size 0.508)
		(drill 0.254)
		(layers "F.Cu" "B.Cu")
		(net "GND")
	)
	(via
		(at 412.044896 -29.589984)
		(size 0.508)
		(drill 0.254)
		(layers "F.Cu" "B.Cu")
		(net "GND")
	)
	(via
		(at 335.328006 -375.040144)
		(size 0.508)
		(drill 0.254)
		(layers "F.Cu" "B.Cu")
		(net "GND")
	)
	(via
		(at 247.24995 -131.312666)
		(size 0.508)
		(drill 0.254)
		(layers "F.Cu" "B.Cu")
		(net "GND")
	)
	(via
		(at 270.949928 -306.349908)
		(size 0.4064)
		(drill 0.2032)
		(layers "F.Cu" "B.Cu")
		(net "GND")
	)
	(via
		(at 326.371204 -342.439498)
		(size 0.4064)
		(drill 0.2032)
		(layers "F.Cu" "B.Cu")
		(net "GND")
	)
	(via
		(at 183.766714 -152.95499)
		(size 0.508)
		(drill 0.254)
		(layers "F.Cu" "B.Cu")
		(net "GND")
	)
	(via
		(at 73.899776 -306.349908)
		(size 0.4064)
		(drill 0.2032)
		(layers "F.Cu" "B.Cu")
		(net "GND")
	)
	(via
		(at 419.683184 -355.366066)
		(size 0.4572)
		(drill 0.254)
		(layers "F.Cu" "B.Cu")
		(net "GND")
	)
	(via
		(at 441.445904 -343.073482)
		(size 0.4572)
		(drill 0.254)
		(layers "F.Cu" "B.Cu")
		(net "GND")
	)
	(via
		(at 178.599846 -278.799798)
		(size 0.4064)
		(drill 0.2032)
		(layers "F.Cu" "B.Cu")
		(net "GND")
	)
	(via
		(at 279.557734 -102.847394)
		(size 0.508)
		(drill 0.254)
		(layers "F.Cu" "B.Cu")
		(net "GND")
	)
	(via
		(at 94.341696 -238.04499)
		(size 0.508)
		(drill 0.254)
		(layers "F.Cu" "B.Cu")
		(net "GND")
	)
	(via
		(at 339.728048 -382.84023)
		(size 0.508)
		(drill 0.254)
		(layers "F.Cu" "B.Cu")
		(net "GND")
	)
	(via
		(at 129.880868 -79.025496)
		(size 0.508)
		(drill 0.254)
		(layers "F.Cu" "B.Cu")
		(net "GND")
	)
	(via
		(at 45.26534 -349.219774)
		(size 0.4572)
		(drill 0.254)
		(layers "F.Cu" "B.Cu")
		(net "GND")
	)
	(via
		(at 19.820382 -122.830844)
		(size 0.508)
		(drill 0.254)
		(layers "F.Cu" "B.Cu")
		(net "GND")
	)
	(via
		(at 189.999874 -282.599892)
		(size 0.4064)
		(drill 0.2032)
		(layers "F.Cu" "B.Cu")
		(net "GND")
	)
	(via
		(at 231.067356 -213.104476)
		(size 0.4572)
		(drill 0.254)
		(layers "F.Cu" "B.Cu")
		(net "GND")
	)
	(via
		(at 416.974782 -305.874928)
		(size 0.4064)
		(drill 0.2032)
		(layers "F.Cu" "B.Cu")
		(net "GND")
	)
	(via
		(at 195.86956 -64.102234)
		(size 0.508)
		(drill 0.254)
		(layers "F.Cu" "B.Cu")
		(net "GND")
	)
	(via
		(at 88.783922 -351.611438)
		(size 0.4064)
		(drill 0.2032)
		(layers "F.Cu" "B.Cu")
		(net "GND")
	)
	(via
		(at 119.371618 -51.661822)
		(size 0.508)
		(drill 0.254)
		(layers "F.Cu" "B.Cu")
		(net "GND")
	)
	(via
		(at 327.82256 -23.880318)
		(size 0.508)
		(drill 0.254)
		(layers "F.Cu" "B.Cu")
		(net "GND")
	)
	(via
		(at 31.570676 -357.123746)
		(size 0.4572)
		(drill 0.254)
		(layers "F.Cu" "B.Cu")
		(net "GND")
	)
	(via
		(at 289.950144 -319.65011)
		(size 0.4064)
		(drill 0.2032)
		(layers "F.Cu" "B.Cu")
		(net "GND")
	)
	(via
		(at 63.449962 -310.149748)
		(size 0.4064)
		(drill 0.2032)
		(layers "F.Cu" "B.Cu")
		(net "GND")
	)
	(via
		(at 343.023444 -351.611438)
		(size 0.4064)
		(drill 0.2032)
		(layers "F.Cu" "B.Cu")
		(net "GND")
	)
	(via
		(at 303.249838 -312.049922)
		(size 0.4064)
		(drill 0.2032)
		(layers "F.Cu" "B.Cu")
		(net "GND")
	)
	(via
		(at 424.270932 -342.439498)
		(size 0.4064)
		(drill 0.2032)
		(layers "F.Cu" "B.Cu")
		(net "GND")
	)
	(via
		(at 183.649874 -111.784892)
		(size 0.508)
		(drill 0.254)
		(layers "F.Cu" "B.Cu")
		(net "GND")
	)
	(via
		(at 346.327984 -383.940304)
		(size 0.508)
		(drill 0.254)
		(layers "F.Cu" "B.Cu")
		(net "GND")
	)
	(via
		(at 346.327984 -378.83846)
		(size 0.508)
		(drill 0.254)
		(layers "F.Cu" "B.Cu")
		(net "GND")
	)
	(via
		(at 210.380834 -25.990042)
		(size 0.508)
		(drill 0.254)
		(layers "F.Cu" "B.Cu")
		(net "GND")
	)
	(via
		(at 69.022722 -354.732082)
		(size 0.4064)
		(drill 0.2032)
		(layers "F.Cu" "B.Cu")
		(net "GND")
	)
	(via
		(at 335.026 -167.005)
		(size 0.508)
		(drill 0.254)
		(layers "F.Cu" "B.Cu")
		(net "GND")
	)
	(via
		(at 47.147988 -372.240302)
		(size 0.508)
		(drill 0.254)
		(layers "F.Cu" "B.Cu")
		(net "GND")
	)
	(via
		(at 425.527724 -380.040134)
		(size 0.508)
		(drill 0.254)
		(layers "F.Cu" "B.Cu")
		(net "GND")
	)
	(via
		(at 89.15527 -341.781638)
		(size 0.4572)
		(drill 0.254)
		(layers "F.Cu" "B.Cu")
		(net "GND")
	)
	(via
		(at 283.24429 -357.123746)
		(size 0.4572)
		(drill 0.254)
		(layers "F.Cu" "B.Cu")
		(net "GND")
	)
	(via
		(at 174.325026 -289.724846)
		(size 0.4064)
		(drill 0.2032)
		(layers "F.Cu" "B.Cu")
		(net "GND")
	)
	(via
		(at 37.417248 -348.58579)
		(size 0.4064)
		(drill 0.2032)
		(layers "F.Cu" "B.Cu")
		(net "GND")
	)
	(via
		(at 316.672976 -341.805514)
		(size 0.4572)
		(drill 0.254)
		(layers "F.Cu" "B.Cu")
		(net "GND")
	)
	(via
		(at 46.8249 -284.024832)
		(size 0.4064)
		(drill 0.2032)
		(layers "F.Cu" "B.Cu")
		(net "GND")
	)
	(via
		(at 95.499428 -57.439814)
		(size 0.508)
		(drill 0.254)
		(layers "F.Cu" "B.Cu")
		(net "GND")
	)
	(via
		(at 51.63312 -151.159972)
		(size 0.508)
		(drill 0.254)
		(layers "F.Cu" "B.Cu")
		(net "GND")
	)
	(via
		(at 301.824898 -306.824888)
		(size 0.4064)
		(drill 0.2032)
		(layers "F.Cu" "B.Cu")
		(net "GND")
	)
	(via
		(at 110.744508 -351.092008)
		(size 0.508)
		(drill 0.254)
		(layers "F.Cu" "B.Cu")
		(net "GND")
	)
	(via
		(at 46.8249 -284.974792)
		(size 0.4064)
		(drill 0.2032)
		(layers "F.Cu" "B.Cu")
		(net "GND")
	)
	(via
		(at 375.969022 -299.133514)
		(size 0.508)
		(drill 0.254)
		(layers "F.Cu" "B.Cu")
		(net "GND")
	)
	(via
		(at 270.949928 -300.649894)
		(size 0.4064)
		(drill 0.2032)
		(layers "F.Cu" "B.Cu")
		(net "GND")
	)
	(via
		(at 459.662784 -277.325328)
		(size 0.508)
		(drill 0.254)
		(layers "F.Cu" "B.Cu")
		(net "GND")
	)
	(via
		(at 365.623348 -132.620766)
		(size 0.508)
		(drill 0.254)
		(layers "F.Cu" "B.Cu")
		(net "GND")
	)
	(via
		(at 221.42323 -55.083456)
		(size 0.508)
		(drill 0.254)
		(layers "F.Cu" "B.Cu")
		(net "GND")
	)
	(via
		(at 338.435696 -358.391714)
		(size 0.4572)
		(drill 0.254)
		(layers "F.Cu" "B.Cu")
		(net "GND")
	)
	(via
		(at 34.491676 -122.626628)
		(size 0.508)
		(drill 0.254)
		(layers "F.Cu" "B.Cu")
		(net "GND")
	)
	(via
		(at 278.074882 -286.874966)
		(size 0.4064)
		(drill 0.2032)
		(layers "F.Cu" "B.Cu")
		(net "GND")
	)
	(via
		(at 317.044324 -351.611438)
		(size 0.4064)
		(drill 0.2032)
		(layers "F.Cu" "B.Cu")
		(net "GND")
	)
	(via
		(at 233.599228 -60.177934)
		(size 0.508)
		(drill 0.254)
		(layers "F.Cu" "B.Cu")
		(net "GND")
	)
	(via
		(at 61.549788 -281.649932)
		(size 0.4064)
		(drill 0.2032)
		(layers "F.Cu" "B.Cu")
		(net "GND")
	)
	(via
		(at 18.367756 -172.772578)
		(size 0.508)
		(drill 0.254)
		(layers "F.Cu" "B.Cu")
		(net "GND")
	)
	(via
		(at 296.599864 -318.699896)
		(size 0.4064)
		(drill 0.2032)
		(layers "F.Cu" "B.Cu")
		(net "GND")
	)
	(via
		(at 177.5333 -344.831162)
		(size 0.4572)
		(drill 0.254)
		(layers "F.Cu" "B.Cu")
		(net "GND")
	)
	(via
		(at 391.799826 -301.599854)
		(size 0.4064)
		(drill 0.2032)
		(layers "F.Cu" "B.Cu")
		(net "GND")
	)
	(via
		(at 453.709024 -235.617004)
		(size 0.508)
		(drill 0.254)
		(layers "F.Cu" "B.Cu")
		(net "GND")
	)
	(via
		(at 353.568 -417.82492)
		(size 0.508)
		(drill 0.254)
		(layers "F.Cu" "B.Cu")
		(net "GND")
	)
	(via
		(at 233.716068 -78.359254)
		(size 0.508)
		(drill 0.254)
		(layers "F.Cu" "B.Cu")
		(net "GND")
	)
	(via
		(at 329.382882 -130.036824)
		(size 0.508)
		(drill 0.254)
		(layers "F.Cu" "B.Cu")
		(net "GND")
	)
	(via
		(at 275.176234 -352.245422)
		(size 0.4572)
		(drill 0.254)
		(layers "F.Cu" "B.Cu")
		(net "GND")
	)
	(via
		(at 40.897556 -341.805514)
		(size 0.4572)
		(drill 0.254)
		(layers "F.Cu" "B.Cu")
		(net "GND")
	)
	(via
		(at 466.827616 -21.532596)
		(size 0.508)
		(drill 0.254)
		(layers "F.Cu" "B.Cu")
		(net "GND")
	)
	(via
		(at 241.558064 -143.051276)
		(size 0.508)
		(drill 0.254)
		(layers "F.Cu" "B.Cu")
		(net "GND")
	)
	(via
		(at 49.67478 -302.074834)
		(size 0.4064)
		(drill 0.2032)
		(layers "F.Cu" "B.Cu")
		(net "GND")
	)
	(via
		(at 49.67478 -301.124874)
		(size 0.4064)
		(drill 0.2032)
		(layers "F.Cu" "B.Cu")
		(net "GND")
	)
	(via
		(at 39.224966 -292.574726)
		(size 0.4064)
		(drill 0.2032)
		(layers "F.Cu" "B.Cu")
		(net "GND")
	)
	(via
		(at 279.024842 -309.674768)
		(size 0.4064)
		(drill 0.2032)
		(layers "F.Cu" "B.Cu")
		(net "GND")
	)
	(via
		(at 26.61158 -349.219774)
		(size 0.4572)
		(drill 0.254)
		(layers "F.Cu" "B.Cu")
		(net "GND")
	)
	(via
		(at 448.978782 -104.115616)
		(size 0.508)
		(drill 0.254)
		(layers "F.Cu" "B.Cu")
		(net "GND")
	)
	(via
		(at 412.044896 -27.79014)
		(size 0.508)
		(drill 0.254)
		(layers "F.Cu" "B.Cu")
		(net "GND")
	)
	(via
		(at 173.850046 -311.099962)
		(size 0.4064)
		(drill 0.2032)
		(layers "F.Cu" "B.Cu")
		(net "GND")
	)
	(via
		(at 186.86018 -358.367838)
		(size 0.4572)
		(drill 0.254)
		(layers "F.Cu" "B.Cu")
		(net "GND")
	)
	(via
		(at 80.07477 -298.27474)
		(size 0.4064)
		(drill 0.2032)
		(layers "F.Cu" "B.Cu")
		(net "GND")
	)
	(via
		(at 177.5333 -355.366066)
		(size 0.4572)
		(drill 0.254)
		(layers "F.Cu" "B.Cu")
		(net "GND")
	)
	(via
		(at 163.874958 -304.924714)
		(size 0.4064)
		(drill 0.2032)
		(layers "F.Cu" "B.Cu")
		(net "GND")
	)
	(via
		(at 49.340008 -74.58583)
		(size 0.508)
		(drill 0.254)
		(layers "F.Cu" "B.Cu")
		(net "GND")
	)
	(via
		(at 383.72796 -410.041852)
		(size 0.508)
		(drill 0.254)
		(layers "F.Cu" "B.Cu")
		(net "GND")
	)
	(via
		(at 227.867972 -217.104468)
		(size 0.4572)
		(drill 0.254)
		(layers "F.Cu" "B.Cu")
		(net "GND")
	)
	(via
		(at 164.349938 -279.749758)
		(size 0.4064)
		(drill 0.2032)
		(layers "F.Cu" "B.Cu")
		(net "GND")
	)
	(via
		(at 380.317248 -352.245422)
		(size 0.4572)
		(drill 0.254)
		(layers "F.Cu" "B.Cu")
		(net "GND")
	)
	(via
		(at 50.14976 -281.649932)
		(size 0.4064)
		(drill 0.2032)
		(layers "F.Cu" "B.Cu")
		(net "GND")
	)
	(via
		(at 106.6927 -8.48995)
		(size 0.508)
		(drill 0.254)
		(layers "F.Cu" "B.Cu")
		(net "GND")
	)
	(via
		(at 446.131188 -416.636962)
		(size 0.508)
		(drill 0.254)
		(layers "F.Cu" "B.Cu")
		(net "GND")
	)
	(via
		(at 95.485458 -63.218314)
		(size 0.508)
		(drill 0.254)
		(layers "F.Cu" "B.Cu")
		(net "GND")
	)
	(via
		(at 90.621612 -124.93498)
		(size 0.508)
		(drill 0.254)
		(layers "F.Cu" "B.Cu")
		(net "GND")
	)
	(via
		(at 188.099954 -277.849838)
		(size 0.4064)
		(drill 0.2032)
		(layers "F.Cu" "B.Cu")
		(net "GND")
	)
	(via
		(at 171.371514 -51.661822)
		(size 0.508)
		(drill 0.254)
		(layers "F.Cu" "B.Cu")
		(net "GND")
	)
	(via
		(at 7.725156 -170.563032)
		(size 0.508)
		(drill 0.254)
		(layers "F.Cu" "B.Cu")
		(net "GND")
	)
	(via
		(at 386.855462 -231.714548)
		(size 0.508)
		(drill 0.254)
		(layers "F.Cu" "B.Cu")
		(net "GND")
	)
	(via
		(at 76.71943 -354.098098)
		(size 0.4572)
		(drill 0.254)
		(layers "F.Cu" "B.Cu")
		(net "GND")
	)
	(via
		(at 71.93915 -28.05303)
		(size 0.508)
		(drill 0.254)
		(layers "F.Cu" "B.Cu")
		(net "GND")
	)
	(via
		(at 406.049988 -310.149748)
		(size 0.4064)
		(drill 0.2032)
		(layers "F.Cu" "B.Cu")
		(net "GND")
	)
	(via
		(at 158.380938 -25.990042)
		(size 0.508)
		(drill 0.254)
		(layers "F.Cu" "B.Cu")
		(net "GND")
	)
	(via
		(at 125.35916 -341.805514)
		(size 0.4572)
		(drill 0.254)
		(layers "F.Cu" "B.Cu")
		(net "GND")
	)
	(via
		(at 329.480164 -345.465146)
		(size 0.4064)
		(drill 0.2032)
		(layers "F.Cu" "B.Cu")
		(net "GND")
	)
	(via
		(at 16.702786 -111.127032)
		(size 0.508)
		(drill 0.254)
		(layers "F.Cu" "B.Cu")
		(net "GND")
	)
	(via
		(at 384.685032 -349.219774)
		(size 0.4572)
		(drill 0.254)
		(layers "F.Cu" "B.Cu")
		(net "GND")
	)
	(via
		(at 238.716058 -134.900416)
		(size 0.508)
		(drill 0.254)
		(layers "F.Cu" "B.Cu")
		(net "GND")
	)
	(via
		(at 15.299182 -133.173216)
		(size 0.508)
		(drill 0.254)
		(layers "F.Cu" "B.Cu")
		(net "GND")
	)
	(via
		(at 333.696564 -351.611438)
		(size 0.4064)
		(drill 0.2032)
		(layers "F.Cu" "B.Cu")
		(net "GND")
	)
	(via
		(at 401.15236 -107.844844)
		(size 0.508)
		(drill 0.254)
		(layers "F.Cu" "B.Cu")
		(net "GND")
	)
	(via
		(at 425.527724 -381.241808)
		(size 0.508)
		(drill 0.254)
		(layers "F.Cu" "B.Cu")
		(net "GND")
	)
	(via
		(at 152.94991 -317.749936)
		(size 0.4064)
		(drill 0.2032)
		(layers "F.Cu" "B.Cu")
		(net "GND")
	)
	(via
		(at 42.549826 -316.799722)
		(size 0.4064)
		(drill 0.2032)
		(layers "F.Cu" "B.Cu")
		(net "GND")
	)
	(via
		(at 328.871072 -31.652972)
		(size 0.508)
		(drill 0.254)
		(layers "F.Cu" "B.Cu")
		(net "GND")
	)
	(via
		(at 47.77486 -304.924714)
		(size 0.4064)
		(drill 0.2032)
		(layers "F.Cu" "B.Cu")
		(net "GND")
	)
	(via
		(at 308.586378 -48.874934)
		(size 0.508)
		(drill 0.254)
		(layers "F.Cu" "B.Cu")
		(net "GND")
	)
	(via
		(at 421.724836 -299.224954)
		(size 0.4064)
		(drill 0.2032)
		(layers "F.Cu" "B.Cu")
		(net "GND")
	)
	(via
		(at 139.645136 -344.831162)
		(size 0.4572)
		(drill 0.254)
		(layers "F.Cu" "B.Cu")
		(net "GND")
	)
	(via
		(at 440.18708 -357.123746)
		(size 0.4572)
		(drill 0.254)
		(layers "F.Cu" "B.Cu")
		(net "GND")
	)
	(via
		(at 241.38001 -118.072154)
		(size 0.508)
		(drill 0.254)
		(layers "F.Cu" "B.Cu")
		(net "GND")
	)
	(via
		(at 414.202118 -58.096404)
		(size 0.508)
		(drill 0.254)
		(layers "F.Cu" "B.Cu")
		(net "GND")
	)
	(via
		(at 272.067274 -352.245422)
		(size 0.4572)
		(drill 0.254)
		(layers "F.Cu" "B.Cu")
		(net "GND")
	)
	(via
		(at 29.72054 -358.391714)
		(size 0.4572)
		(drill 0.254)
		(layers "F.Cu" "B.Cu")
		(net "GND")
	)
	(via
		(at 401.78736 -129.964942)
		(size 0.508)
		(drill 0.254)
		(layers "F.Cu" "B.Cu")
		(net "GND")
	)
	(via
		(at 381.576072 -350.977454)
		(size 0.4572)
		(drill 0.254)
		(layers "F.Cu" "B.Cu")
		(net "GND")
	)
	(via
		(at 389.27278 -345.465146)
		(size 0.4064)
		(drill 0.2032)
		(layers "F.Cu" "B.Cu")
		(net "GND")
	)
	(via
		(at 18.21942 -147.18665)
		(size 0.508)
		(drill 0.254)
		(layers "F.Cu" "B.Cu")
		(net "GND")
	)
	(via
		(at 144.384268 -354.732082)
		(size 0.4064)
		(drill 0.2032)
		(layers "F.Cu" "B.Cu")
		(net "GND")
	)
	(via
		(at 60.124848 -305.874928)
		(size 0.4064)
		(drill 0.2032)
		(layers "F.Cu" "B.Cu")
		(net "GND")
	)
	(via
		(at 394.239242 -29.311854)
		(size 0.508)
		(drill 0.254)
		(layers "F.Cu" "B.Cu")
		(net "GND")
	)
	(via
		(at 384.674872 -292.57498)
		(size 0.4064)
		(drill 0.2032)
		(layers "F.Cu" "B.Cu")
		(net "GND")
	)
	(via
		(at 47.115476 -358.391714)
		(size 0.4572)
		(drill 0.254)
		(layers "F.Cu" "B.Cu")
		(net "GND")
	)
	(via
		(at 135.87476 -173.860206)
		(size 0.508)
		(drill 0.254)
		(layers "F.Cu" "B.Cu")
		(net "GND")
	)
	(via
		(at 315.042804 -348.58579)
		(size 0.4064)
		(drill 0.2032)
		(layers "F.Cu" "B.Cu")
		(net "GND")
	)
	(via
		(at 42.747946 -385.141978)
		(size 0.508)
		(drill 0.254)
		(layers "F.Cu" "B.Cu")
		(net "GND")
	)
	(via
		(at 4.562856 -88.721692)
		(size 0.508)
		(drill 0.254)
		(layers "F.Cu" "B.Cu")
		(net "GND")
	)
	(via
		(at 125.430534 -307.877718)
		(size 0.508)
		(drill 0.254)
		(layers "F.Cu" "B.Cu")
		(net "GND")
	)
	(via
		(at 158.938468 -73.20026)
		(size 0.508)
		(drill 0.254)
		(layers "F.Cu" "B.Cu")
		(net "GND")
	)
	(via
		(at 131.306062 -187.59805)
		(size 0.508)
		(drill 0.254)
		(layers "F.Cu" "B.Cu")
		(net "GND")
	)
	(via
		(at 285.687262 -111.44504)
		(size 0.508)
		(drill 0.254)
		(layers "F.Cu" "B.Cu")
		(net "GND")
	)
	(via
		(at 441.751466 -114.075972)
		(size 0.508)
		(drill 0.254)
		(layers "F.Cu" "B.Cu")
		(net "GND")
	)
	(via
		(at 272.374868 -284.024832)
		(size 0.4064)
		(drill 0.2032)
		(layers "F.Cu" "B.Cu")
		(net "GND")
	)
	(via
		(at 80.147922 -378.94006)
		(size 0.508)
		(drill 0.254)
		(layers "F.Cu" "B.Cu")
		(net "GND")
	)
	(via
		(at 300.874684 -304.924714)
		(size 0.4064)
		(drill 0.2032)
		(layers "F.Cu" "B.Cu")
		(net "GND")
	)
	(via
		(at 286.927798 -369.938554)
		(size 0.508)
		(drill 0.254)
		(layers "F.Cu" "B.Cu")
		(net "GND")
	)
	(via
		(at 46.744128 -357.75773)
		(size 0.4064)
		(drill 0.2032)
		(layers "F.Cu" "B.Cu")
		(net "GND")
	)
	(via
		(at 383.72796 -375.040144)
		(size 0.508)
		(drill 0.254)
		(layers "F.Cu" "B.Cu")
		(net "GND")
	)
	(via
		(at 58.35523 -371.508274)
		(size 0.4572)
		(drill 0.254)
		(layers "F.Cu" "B.Cu")
		(net "GND")
	)
	(via
		(at 64.28359 -357.123746)
		(size 0.4572)
		(drill 0.254)
		(layers "F.Cu" "B.Cu")
		(net "GND")
	)
	(via
		(at 193.799968 -314.899802)
		(size 0.4064)
		(drill 0.2032)
		(layers "F.Cu" "B.Cu")
		(net "GND")
	)
	(via
		(at 52.524914 -293.52494)
		(size 0.4064)
		(drill 0.2032)
		(layers "F.Cu" "B.Cu")
		(net "GND")
	)
	(via
		(at 335.328006 -408.840178)
		(size 0.508)
		(drill 0.254)
		(layers "F.Cu" "B.Cu")
		(net "GND")
	)
	(via
		(at 298.499784 -281.649932)
		(size 0.4064)
		(drill 0.2032)
		(layers "F.Cu" "B.Cu")
		(net "GND")
	)
	(via
		(at 368.60861 -82.091022)
		(size 0.508)
		(drill 0.254)
		(layers "F.Cu" "B.Cu")
		(net "GND")
	)
	(via
		(at 154.375104 -275.474938)
		(size 0.4064)
		(drill 0.2032)
		(layers "F.Cu" "B.Cu")
		(net "GND")
	)
	(via
		(at 198.550022 -278.799798)
		(size 0.4064)
		(drill 0.2032)
		(layers "F.Cu" "B.Cu")
		(net "GND")
	)
	(via
		(at 425.124118 -113.229898)
		(size 0.508)
		(drill 0.254)
		(layers "F.Cu" "B.Cu")
		(net "GND")
	)
	(via
		(at 148.249894 -388.402068)
		(size 0.508)
		(drill 0.254)
		(layers "F.Cu" "B.Cu")
		(net "GND")
	)
	(via
		(at 428.936404 -51.661822)
		(size 0.508)
		(drill 0.254)
		(layers "F.Cu" "B.Cu")
		(net "GND")
	)
	(via
		(at 292.32479 -306.824888)
		(size 0.4064)
		(drill 0.2032)
		(layers "F.Cu" "B.Cu")
		(net "GND")
	)
	(via
		(at 444.97117 -32.911796)
		(size 0.508)
		(drill 0.254)
		(layers "F.Cu" "B.Cu")
		(net "GND")
	)
	(via
		(at 410.799788 -314.899802)
		(size 0.4064)
		(drill 0.2032)
		(layers "F.Cu" "B.Cu")
		(net "GND")
	)
	(via
		(at 444.056008 -100.392992)
		(size 0.508)
		(drill 0.254)
		(layers "F.Cu" "B.Cu")
		(net "GND")
	)
	(via
		(at 335.328006 -406.141936)
		(size 0.508)
		(drill 0.254)
		(layers "F.Cu" "B.Cu")
		(net "GND")
	)
	(via
		(at 421.53332 -352.245422)
		(size 0.4572)
		(drill 0.254)
		(layers "F.Cu" "B.Cu")
		(net "GND")
	)
	(via
		(at 338.91347 -285.953454)
		(size 0.508)
		(drill 0.254)
		(layers "F.Cu" "B.Cu")
		(net "GND")
	)
	(via
		(at 420.054532 -348.58579)
		(size 0.4064)
		(drill 0.2032)
		(layers "F.Cu" "B.Cu")
		(net "GND")
	)
	(via
		(at 262.07212 -33.857692)
		(size 0.508)
		(drill 0.254)
		(layers "F.Cu" "B.Cu")
		(net "GND")
	)
	(via
		(at 436.706772 -351.611438)
		(size 0.4064)
		(drill 0.2032)
		(layers "F.Cu" "B.Cu")
		(net "GND")
	)
	(via
		(at 177.649886 -275.949918)
		(size 0.4064)
		(drill 0.2032)
		(layers "F.Cu" "B.Cu")
		(net "GND")
	)
	(via
		(at 142.293594 -286.331914)
		(size 0.508)
		(drill 0.254)
		(layers "F.Cu" "B.Cu")
		(net "GND")
	)
	(via
		(at 199.025002 -297.32478)
		(size 0.4064)
		(drill 0.2032)
		(layers "F.Cu" "B.Cu")
		(net "GND")
	)
	(via
		(at 353.41052 -304.373534)
		(size 0.508)
		(drill 0.254)
		(layers "F.Cu" "B.Cu")
		(net "GND")
	)
	(via
		(at 124.147834 -381.638556)
		(size 0.508)
		(drill 0.254)
		(layers "F.Cu" "B.Cu")
		(net "GND")
	)
	(via
		(at 151.748998 -27.79014)
		(size 0.508)
		(drill 0.254)
		(layers "F.Cu" "B.Cu")
		(net "GND")
	)
	(via
		(at 121.947686 -377.341892)
		(size 0.4572)
		(drill 0.254)
		(layers "F.Cu" "B.Cu")
		(net "GND")
	)
	(via
		(at 295.174924 -305.874928)
		(size 0.4064)
		(drill 0.2032)
		(layers "F.Cu" "B.Cu")
		(net "GND")
	)
	(via
		(at 402.641816 -25.971246)
		(size 0.508)
		(drill 0.254)
		(layers "F.Cu" "B.Cu")
		(net "GND")
	)
	(via
		(at 197.600062 -277.849838)
		(size 0.4064)
		(drill 0.2032)
		(layers "F.Cu" "B.Cu")
		(net "GND")
	)
	(via
		(at 7.531608 -147.630388)
		(size 0.508)
		(drill 0.254)
		(layers "F.Cu" "B.Cu")
		(net "GND")
	)
	(via
		(at 314.366148 -122.098054)
		(size 0.508)
		(drill 0.254)
		(layers "F.Cu" "B.Cu")
		(net "GND")
	)
	(via
		(at 287.612074 -352.245422)
		(size 0.4572)
		(drill 0.254)
		(layers "F.Cu" "B.Cu")
		(net "GND")
	)
	(via
		(at 288.99993 -281.649932)
		(size 0.4064)
		(drill 0.2032)
		(layers "F.Cu" "B.Cu")
		(net "GND")
	)
	(via
		(at 448.5513 -47.03191)
		(size 0.508)
		(drill 0.254)
		(layers "F.Cu" "B.Cu")
		(net "GND")
	)
	(via
		(at 305.730402 -65.15989)
		(size 0.508)
		(drill 0.254)
		(layers "F.Cu" "B.Cu")
		(net "GND")
	)
	(via
		(at 106.66857 -77.969364)
		(size 0.508)
		(drill 0.254)
		(layers "F.Cu" "B.Cu")
		(net "GND")
	)
	(via
		(at 422.199816 -281.649932)
		(size 0.4064)
		(drill 0.2032)
		(layers "F.Cu" "B.Cu")
		(net "GND")
	)
	(via
		(at 58.699908 -318.699896)
		(size 0.4064)
		(drill 0.2032)
		(layers "F.Cu" "B.Cu")
		(net "GND")
	)
	(via
		(at 399.93316 -125.955044)
		(size 0.508)
		(drill 0.254)
		(layers "F.Cu" "B.Cu")
		(net "GND")
	)
	(via
		(at 325.999856 -347.951806)
		(size 0.4572)
		(drill 0.254)
		(layers "F.Cu" "B.Cu")
		(net "GND")
	)
	(via
		(at 463.037682 -199.657462)
		(size 0.508)
		(drill 0.254)
		(layers "F.Cu" "B.Cu")
		(net "GND")
	)
	(via
		(at 71.347838 -395.938502)
		(size 0.508)
		(drill 0.254)
		(layers "F.Cu" "B.Cu")
		(net "GND")
	)
	(via
		(at 144.65808 -299.133514)
		(size 0.508)
		(drill 0.254)
		(layers "F.Cu" "B.Cu")
		(net "GND")
	)
	(via
		(at 98.702622 -168.714928)
		(size 0.508)
		(drill 0.254)
		(layers "F.Cu" "B.Cu")
		(net "GND")
	)
	(via
		(at 325.999856 -344.831162)
		(size 0.4572)
		(drill 0.254)
		(layers "F.Cu" "B.Cu")
		(net "GND")
	)
	(via
		(at 303.234344 -47.936658)
		(size 0.508)
		(drill 0.254)
		(layers "F.Cu" "B.Cu")
		(net "GND")
	)
	(via
		(at 54.385464 -34.183066)
		(size 0.508)
		(drill 0.254)
		(layers "F.Cu" "B.Cu")
		(net "GND")
	)
	(via
		(at 143.624554 -262.915908)
		(size 0.508)
		(drill 0.254)
		(layers "F.Cu" "B.Cu")
		(net "GND")
	)
	(via
		(at 44.449746 -303.499774)
		(size 0.4064)
		(drill 0.2032)
		(layers "F.Cu" "B.Cu")
		(net "GND")
	)
	(via
		(at 305.624738 -293.52494)
		(size 0.4064)
		(drill 0.2032)
		(layers "F.Cu" "B.Cu")
		(net "GND")
	)
	(via
		(at 146.943318 -52.536852)
		(size 0.508)
		(drill 0.254)
		(layers "F.Cu" "B.Cu")
		(net "GND")
	)
	(via
		(at 269.200122 -151.78532)
		(size 0.508)
		(drill 0.254)
		(layers "F.Cu" "B.Cu")
		(net "GND")
	)
	(via
		(at 194.749928 -319.65011)
		(size 0.4064)
		(drill 0.2032)
		(layers "F.Cu" "B.Cu")
		(net "GND")
	)
	(via
		(at 176.054512 -354.732082)
		(size 0.4064)
		(drill 0.2032)
		(layers "F.Cu" "B.Cu")
		(net "GND")
	)
	(via
		(at 340.094062 -217.987372)
		(size 0.4572)
		(drill 0.254)
		(layers "F.Cu" "B.Cu")
		(net "GND")
	)
	(via
		(at 299.866812 -125.435106)
		(size 0.508)
		(drill 0.254)
		(layers "F.Cu" "B.Cu")
		(net "GND")
	)
	(via
		(at 189.39002 -73.85177)
		(size 0.508)
		(drill 0.254)
		(layers "F.Cu" "B.Cu")
		(net "GND")
	)
	(via
		(at 410.799788 -273.099784)
		(size 0.4064)
		(drill 0.2032)
		(layers "F.Cu" "B.Cu")
		(net "GND")
	)
	(via
		(at 390.849866 -312.049922)
		(size 0.4064)
		(drill 0.2032)
		(layers "F.Cu" "B.Cu")
		(net "GND")
	)
	(via
		(at 371.51945 -3.640836)
		(size 0.508)
		(drill 0.254)
		(layers "F.Cu" "B.Cu")
		(net "GND")
	)
	(via
		(at 75.74788 -381.638556)
		(size 0.508)
		(drill 0.254)
		(layers "F.Cu" "B.Cu")
		(net "GND")
	)
	(via
		(at 302.327818 -383.940304)
		(size 0.508)
		(drill 0.254)
		(layers "F.Cu" "B.Cu")
		(net "GND")
	)
	(via
		(at 429.325024 -301.124874)
		(size 0.4064)
		(drill 0.2032)
		(layers "F.Cu" "B.Cu")
		(net "GND")
	)
	(via
		(at 139.645136 -352.245422)
		(size 0.4572)
		(drill 0.254)
		(layers "F.Cu" "B.Cu")
		(net "GND")
	)
	(via
		(at 129.302002 -198.848218)
		(size 0.508)
		(drill 0.254)
		(layers "F.Cu" "B.Cu")
		(net "GND")
	)
	(via
		(at 195.815712 -345.465146)
		(size 0.4064)
		(drill 0.2032)
		(layers "F.Cu" "B.Cu")
		(net "GND")
	)
	(via
		(at 337.5279 -372.240302)
		(size 0.508)
		(drill 0.254)
		(layers "F.Cu" "B.Cu")
		(net "GND")
	)
	(via
		(at 37.744908 -29.589984)
		(size 0.508)
		(drill 0.254)
		(layers "F.Cu" "B.Cu")
		(net "GND")
	)
	(via
		(at 114.265456 -304.373534)
		(size 0.508)
		(drill 0.254)
		(layers "F.Cu" "B.Cu")
		(net "GND")
	)
	(via
		(at 278.074882 -298.27474)
		(size 0.4064)
		(drill 0.2032)
		(layers "F.Cu" "B.Cu")
		(net "GND")
	)
	(via
		(at 203.151994 -13.613638)
		(size 0.508)
		(drill 0.254)
		(layers "F.Cu" "B.Cu")
		(net "GND")
	)
	(via
		(at 283.299916 -317.749936)
		(size 0.4064)
		(drill 0.2032)
		(layers "F.Cu" "B.Cu")
		(net "GND")
	)
	(via
		(at 115.87734 -255.18872)
		(size 0.508)
		(drill 0.254)
		(layers "F.Cu" "B.Cu")
		(net "GND")
	)
	(via
		(at 297.688 -417.82492)
		(size 0.508)
		(drill 0.254)
		(layers "F.Cu" "B.Cu")
		(net "GND")
	)
	(via
		(at 89.15527 -350.977454)
		(size 0.4572)
		(drill 0.254)
		(layers "F.Cu" "B.Cu")
		(net "GND")
	)
	(via
		(at 82.924904 -289.724846)
		(size 0.4064)
		(drill 0.2032)
		(layers "F.Cu" "B.Cu")
		(net "GND")
	)
	(via
		(at 365.05896 -305.008534)
		(size 0.508)
		(drill 0.254)
		(layers "F.Cu" "B.Cu")
		(net "GND")
	)
	(via
		(at 426.94987 -275.949918)
		(size 0.4064)
		(drill 0.2032)
		(layers "F.Cu" "B.Cu")
		(net "GND")
	)
	(via
		(at 392.749786 -310.149748)
		(size 0.4064)
		(drill 0.2032)
		(layers "F.Cu" "B.Cu")
		(net "GND")
	)
	(via
		(at 76.27493 -296.37482)
		(size 0.4064)
		(drill 0.2032)
		(layers "F.Cu" "B.Cu")
		(net "GND")
	)
	(via
		(at 73.899776 -317.749936)
		(size 0.4064)
		(drill 0.2032)
		(layers "F.Cu" "B.Cu")
		(net "GND")
	)
	(via
		(at 73.424796 -290.674806)
		(size 0.4064)
		(drill 0.2032)
		(layers "F.Cu" "B.Cu")
		(net "GND")
	)
	(via
		(at 31.747968 -384.041904)
		(size 0.508)
		(drill 0.254)
		(layers "F.Cu" "B.Cu")
		(net "GND")
	)
	(via
		(at 344.127836 -376.241818)
		(size 0.508)
		(drill 0.254)
		(layers "F.Cu" "B.Cu")
		(net "GND")
	)
	(via
		(at 75.974956 -74.58583)
		(size 0.508)
		(drill 0.254)
		(layers "F.Cu" "B.Cu")
		(net "GND")
	)
	(via
		(at 196.174868 -298.27474)
		(size 0.4064)
		(drill 0.2032)
		(layers "F.Cu" "B.Cu")
		(net "GND")
	)
	(via
		(at 374.493536 -279.931114)
		(size 0.508)
		(drill 0.254)
		(layers "F.Cu" "B.Cu")
		(net "GND")
	)
	(via
		(at 371.624098 -26.319734)
		(size 0.508)
		(drill 0.254)
		(layers "F.Cu" "B.Cu")
		(net "GND")
	)
	(via
		(at 166.356284 -343.073482)
		(size 0.4572)
		(drill 0.254)
		(layers "F.Cu" "B.Cu")
		(net "GND")
	)
	(via
		(at 82.347816 -398.24025)
		(size 0.508)
		(drill 0.254)
		(layers "F.Cu" "B.Cu")
		(net "GND")
	)
	(via
		(at 289.127692 -372.240302)
		(size 0.508)
		(drill 0.254)
		(layers "F.Cu" "B.Cu")
		(net "GND")
	)
	(via
		(at 400.984466 -155.713938)
		(size 0.508)
		(drill 0.254)
		(layers "F.Cu" "B.Cu")
		(net "GND")
	)
	(via
		(at 411.750002 -274.999958)
		(size 0.4064)
		(drill 0.2032)
		(layers "F.Cu" "B.Cu")
		(net "GND")
	)
	(via
		(at 178.124866 -307.774848)
		(size 0.4064)
		(drill 0.2032)
		(layers "F.Cu" "B.Cu")
		(net "GND")
	)
	(via
		(at 195.224908 -298.27474)
		(size 0.4064)
		(drill 0.2032)
		(layers "F.Cu" "B.Cu")
		(net "GND")
	)
	(via
		(at 326.480678 -27.79014)
		(size 0.508)
		(drill 0.254)
		(layers "F.Cu" "B.Cu")
		(net "GND")
	)
	(via
		(at 344.127836 -403.738588)
		(size 0.508)
		(drill 0.254)
		(layers "F.Cu" "B.Cu")
		(net "GND")
	)
	(via
		(at 423.62501 -300.174914)
		(size 0.4064)
		(drill 0.2032)
		(layers "F.Cu" "B.Cu")
		(net "GND")
	)
	(via
		(at 422.792144 -350.977454)
		(size 0.4572)
		(drill 0.254)
		(layers "F.Cu" "B.Cu")
		(net "GND")
	)
	(via
		(at 245.342918 -316.534546)
		(size 0.508)
		(drill 0.254)
		(layers "F.Cu" "B.Cu")
		(net "GND")
	)
	(via
		(at 403.71014 -342.439498)
		(size 0.4064)
		(drill 0.2032)
		(layers "F.Cu" "B.Cu")
		(net "GND")
	)
	(via
		(at 38.749986 -306.349908)
		(size 0.4064)
		(drill 0.2032)
		(layers "F.Cu" "B.Cu")
		(net "GND")
	)
	(via
		(at 401.15236 -137.16508)
		(size 0.508)
		(drill 0.254)
		(layers "F.Cu" "B.Cu")
		(net "GND")
	)
	(via
		(at 235.867448 -212.304376)
		(size 0.4572)
		(drill 0.254)
		(layers "F.Cu" "B.Cu")
		(net "GND")
	)
	(via
		(at 236.887512 -235.737654)
		(size 0.508)
		(drill 0.254)
		(layers "F.Cu" "B.Cu")
		(net "GND")
	)
	(via
		(at 432.12766 -410.041852)
		(size 0.508)
		(drill 0.254)
		(layers "F.Cu" "B.Cu")
		(net "GND")
	)
	(via
		(at 31.747968 -398.34185)
		(size 0.508)
		(drill 0.254)
		(layers "F.Cu" "B.Cu")
		(net "GND")
	)
	(via
		(at 312.749692 -272.14957)
		(size 0.4064)
		(drill 0.2032)
		(layers "F.Cu" "B.Cu")
		(net "GND")
	)
	(via
		(at 311.799732 -304.449734)
		(size 0.4064)
		(drill 0.2032)
		(layers "F.Cu" "B.Cu")
		(net "GND")
	)
	(via
		(at 185.010044 -347.951806)
		(size 0.4572)
		(drill 0.254)
		(layers "F.Cu" "B.Cu")
		(net "GND")
	)
	(via
		(at 170.347894 -378.83846)
		(size 0.508)
		(drill 0.254)
		(layers "F.Cu" "B.Cu")
		(net "GND")
	)
	(via
		(at 393.351766 -109.644942)
		(size 0.508)
		(drill 0.254)
		(layers "F.Cu" "B.Cu")
		(net "GND")
	)
	(via
		(at 61.074808 -300.174914)
		(size 0.4064)
		(drill 0.2032)
		(layers "F.Cu" "B.Cu")
		(net "GND")
	)
	(via
		(at 117.456458 -261.675372)
		(size 0.508)
		(drill 0.254)
		(layers "F.Cu" "B.Cu")
		(net "GND")
	)
	(via
		(at 354.900992 -33.19018)
		(size 0.508)
		(drill 0.254)
		(layers "F.Cu" "B.Cu")
		(net "GND")
	)
	(via
		(at 168.625012 -306.824888)
		(size 0.4064)
		(drill 0.2032)
		(layers "F.Cu" "B.Cu")
		(net "GND")
	)
	(via
		(at 109.050074 -288.78149)
		(size 0.508)
		(drill 0.254)
		(layers "F.Cu" "B.Cu")
		(net "GND")
	)
	(via
		(at 190.950088 -315.849762)
		(size 0.4064)
		(drill 0.2032)
		(layers "F.Cu" "B.Cu")
		(net "GND")
	)
	(via
		(at 386.535168 -344.831162)
		(size 0.4572)
		(drill 0.254)
		(layers "F.Cu" "B.Cu")
		(net "GND")
	)
	(via
		(at 81.024984 -290.674806)
		(size 0.4064)
		(drill 0.2032)
		(layers "F.Cu" "B.Cu")
		(net "GND")
	)
	(via
		(at 130.796284 -285.267654)
		(size 0.508)
		(drill 0.254)
		(layers "F.Cu" "B.Cu")
		(net "GND")
	)
	(via
		(at 112.578642 -292.789102)
		(size 0.508)
		(drill 0.254)
		(layers "F.Cu" "B.Cu")
		(net "GND")
	)
	(via
		(at 59.649614 -272.149316)
		(size 0.4064)
		(drill 0.2032)
		(layers "F.Cu" "B.Cu")
		(net "GND")
	)
	(via
		(at 101.884734 -238.553244)
		(size 0.508)
		(drill 0.254)
		(layers "F.Cu" "B.Cu")
		(net "GND")
	)
	(via
		(at 133.335014 -167.992298)
		(size 0.508)
		(drill 0.254)
		(layers "F.Cu" "B.Cu")
		(net "GND")
	)
	(via
		(at 385.30022 -151.78532)
		(size 0.508)
		(drill 0.254)
		(layers "F.Cu" "B.Cu")
		(net "GND")
	)
	(via
		(at 169.465244 -355.366066)
		(size 0.4572)
		(drill 0.254)
		(layers "F.Cu" "B.Cu")
		(net "GND")
	)
	(via
		(at 454.663556 -119.026178)
		(size 0.508)
		(drill 0.254)
		(layers "F.Cu" "B.Cu")
		(net "GND")
	)
	(via
		(at 352.009964 -289.41649)
		(size 0.508)
		(drill 0.254)
		(layers "F.Cu" "B.Cu")
		(net "GND")
	)
	(via
		(at 99.386136 -332.038452)
		(size 0.508)
		(drill 0.254)
		(layers "F.Cu" "B.Cu")
		(net "GND")
	)
	(via
		(at 167.200072 -274.049744)
		(size 0.4064)
		(drill 0.2032)
		(layers "F.Cu" "B.Cu")
		(net "GND")
	)
	(via
		(at 362.6612 -134.970012)
		(size 0.508)
		(drill 0.254)
		(layers "F.Cu" "B.Cu")
		(net "GND")
	)
	(via
		(at 38.401752 -125.692154)
		(size 0.508)
		(drill 0.254)
		(layers "F.Cu" "B.Cu")
		(net "GND")
	)
	(via
		(at 392.749786 -279.749758)
		(size 0.4064)
		(drill 0.2032)
		(layers "F.Cu" "B.Cu")
		(net "GND")
	)
	(via
		(at 429.927766 -378.83846)
		(size 0.508)
		(drill 0.254)
		(layers "F.Cu" "B.Cu")
		(net "GND")
	)
	(via
		(at 351.38995 -162.57905)
		(size 0.508)
		(drill 0.254)
		(layers "F.Cu" "B.Cu")
		(net "GND")
	)
	(via
		(at 180.50002 -312.999882)
		(size 0.4064)
		(drill 0.2032)
		(layers "F.Cu" "B.Cu")
		(net "GND")
	)
	(via
		(at 297.927776 -407.24201)
		(size 0.508)
		(drill 0.254)
		(layers "F.Cu" "B.Cu")
		(net "GND")
	)
	(via
		(at 44.006516 -349.219774)
		(size 0.4572)
		(drill 0.254)
		(layers "F.Cu" "B.Cu")
		(net "GND")
	)
	(via
		(at 219.457524 -29.784294)
		(size 0.508)
		(drill 0.254)
		(layers "F.Cu" "B.Cu")
		(net "GND")
	)
	(via
		(at 48.3743 -350.977454)
		(size 0.4572)
		(drill 0.254)
		(layers "F.Cu" "B.Cu")
		(net "GND")
	)
	(via
		(at 51.099974 -317.749936)
		(size 0.4064)
		(drill 0.2032)
		(layers "F.Cu" "B.Cu")
		(net "GND")
	)
	(via
		(at 174.800006 -317.749936)
		(size 0.4064)
		(drill 0.2032)
		(layers "F.Cu" "B.Cu")
		(net "GND")
	)
	(via
		(at 284.724856 -285.924752)
		(size 0.4064)
		(drill 0.2032)
		(layers "F.Cu" "B.Cu")
		(net "GND")
	)
	(via
		(at 375.969022 -295.933114)
		(size 0.508)
		(drill 0.254)
		(layers "F.Cu" "B.Cu")
		(net "GND")
	)
	(via
		(at 180.693314 -136.645142)
		(size 0.508)
		(drill 0.254)
		(layers "F.Cu" "B.Cu")
		(net "GND")
	)
	(via
		(at 37.133784 -135.643112)
		(size 0.508)
		(drill 0.254)
		(layers "F.Cu" "B.Cu")
		(net "GND")
	)
	(via
		(at 310.374792 -293.52494)
		(size 0.4064)
		(drill 0.2032)
		(layers "F.Cu" "B.Cu")
		(net "GND")
	)
	(via
		(at 452.220838 -317.822326)
		(size 0.508)
		(drill 0.254)
		(layers "F.Cu" "B.Cu")
		(net "GND")
	)
	(via
		(at 205.844902 -27.79014)
		(size 0.508)
		(drill 0.254)
		(layers "F.Cu" "B.Cu")
		(net "GND")
	)
	(via
		(at 195.699888 -277.849838)
		(size 0.4064)
		(drill 0.2032)
		(layers "F.Cu" "B.Cu")
		(net "GND")
	)
	(via
		(at 31.570676 -344.831162)
		(size 0.4572)
		(drill 0.254)
		(layers "F.Cu" "B.Cu")
		(net "GND")
	)
	(via
		(at 127.182118 -195.062094)
		(size 0.508)
		(drill 0.254)
		(layers "F.Cu" "B.Cu")
		(net "GND")
	)
	(via
		(at 427.570392 -28.802076)
		(size 0.508)
		(drill 0.254)
		(layers "F.Cu" "B.Cu")
		(net "GND")
	)
	(via
		(at 352.036634 -85.544914)
		(size 0.508)
		(drill 0.254)
		(layers "F.Cu" "B.Cu")
		(net "GND")
	)
	(via
		(at 418.93871 -23.880318)
		(size 0.508)
		(drill 0.254)
		(layers "F.Cu" "B.Cu")
		(net "GND")
	)
	(via
		(at 405.100028 -278.799798)
		(size 0.4064)
		(drill 0.2032)
		(layers "F.Cu" "B.Cu")
		(net "GND")
	)
	(via
		(at 428.84979 -316.799722)
		(size 0.4064)
		(drill 0.2032)
		(layers "F.Cu" "B.Cu")
		(net "GND")
	)
	(via
		(at 287.574736 -284.974792)
		(size 0.4064)
		(drill 0.2032)
		(layers "F.Cu" "B.Cu")
		(net "GND")
	)
	(via
		(at 339.948012 -88.60282)
		(size 0.508)
		(drill 0.254)
		(layers "F.Cu" "B.Cu")
		(net "GND")
	)
	(via
		(at 230.961184 -259.136896)
		(size 0.508)
		(drill 0.254)
		(layers "F.Cu" "B.Cu")
		(net "GND")
	)
	(via
		(at 412.224982 -306.824888)
		(size 0.4064)
		(drill 0.2032)
		(layers "F.Cu" "B.Cu")
		(net "GND")
	)
	(via
		(at 427.379892 -354.732082)
		(size 0.4064)
		(drill 0.2032)
		(layers "F.Cu" "B.Cu")
		(net "GND")
	)
	(via
		(at 15.380716 -409.448508)
		(size 0.508)
		(drill 0.254)
		(layers "F.Cu" "B.Cu")
		(net "GND")
	)
	(via
		(at 461.677512 -283.105606)
		(size 0.508)
		(drill 0.254)
		(layers "F.Cu" "B.Cu")
		(net "GND")
	)
	(via
		(at 188.119004 -341.805514)
		(size 0.4572)
		(drill 0.254)
		(layers "F.Cu" "B.Cu")
		(net "GND")
	)
	(via
		(at 144.65808 -295.933114)
		(size 0.508)
		(drill 0.254)
		(layers "F.Cu" "B.Cu")
		(net "GND")
	)
	(via
		(at 107.881674 -129.070608)
		(size 0.508)
		(drill 0.254)
		(layers "F.Cu" "B.Cu")
		(net "GND")
	)
	(via
		(at 76.71943 -344.831162)
		(size 0.4572)
		(drill 0.254)
		(layers "F.Cu" "B.Cu")
		(net "GND")
	)
	(via
		(at 198.550022 -305.399948)
		(size 0.4064)
		(drill 0.2032)
		(layers "F.Cu" "B.Cu")
		(net "GND")
	)
	(via
		(at 357.948992 -31.390082)
		(size 0.508)
		(drill 0.254)
		(layers "F.Cu" "B.Cu")
		(net "GND")
	)
	(via
		(at 390.902952 -355.366066)
		(size 0.4572)
		(drill 0.254)
		(layers "F.Cu" "B.Cu")
		(net "GND")
	)
	(via
		(at 397.97482 -305.874928)
		(size 0.4064)
		(drill 0.2032)
		(layers "F.Cu" "B.Cu")
		(net "GND")
	)
	(via
		(at 81.872074 -33.857692)
		(size 0.508)
		(drill 0.254)
		(layers "F.Cu" "B.Cu")
		(net "GND")
	)
	(via
		(at 425.527724 -374.938544)
		(size 0.508)
		(drill 0.254)
		(layers "F.Cu" "B.Cu")
		(net "GND")
	)
	(via
		(at 184.29986 -310.149748)
		(size 0.4064)
		(drill 0.2032)
		(layers "F.Cu" "B.Cu")
		(net "GND")
	)
	(via
		(at 283.299916 -276.899878)
		(size 0.4064)
		(drill 0.2032)
		(layers "F.Cu" "B.Cu")
		(net "GND")
	)
	(via
		(at 267.070078 -416.508438)
		(size 0.508)
		(drill 0.254)
		(layers "F.Cu" "B.Cu")
		(net "GND")
	)
	(via
		(at 392.52779 -375.040398)
		(size 0.508)
		(drill 0.254)
		(layers "F.Cu" "B.Cu")
		(net "GND")
	)
	(via
		(at 310.849772 -307.299868)
		(size 0.4064)
		(drill 0.2032)
		(layers "F.Cu" "B.Cu")
		(net "GND")
	)
	(via
		(at 68.679822 -303.969928)
		(size 0.4064)
		(drill 0.2032)
		(layers "F.Cu" "B.Cu")
		(net "GND")
	)
	(via
		(at 368.808 -417.82492)
		(size 0.508)
		(drill 0.254)
		(layers "F.Cu" "B.Cu")
		(net "GND")
	)
	(via
		(at 11.74496 -27.79014)
		(size 0.508)
		(drill 0.254)
		(layers "F.Cu" "B.Cu")
		(net "GND")
	)
	(via
		(at 63.449962 -311.099962)
		(size 0.4064)
		(drill 0.2032)
		(layers "F.Cu" "B.Cu")
		(net "GND")
	)
	(via
		(at 314.46597 -77.175106)
		(size 0.508)
		(drill 0.254)
		(layers "F.Cu" "B.Cu")
		(net "GND")
	)
	(via
		(at 449.75272 -235.285788)
		(size 0.508)
		(drill 0.254)
		(layers "F.Cu" "B.Cu")
		(net "GND")
	)
	(via
		(at 423.15003 -281.649932)
		(size 0.4064)
		(drill 0.2032)
		(layers "F.Cu" "B.Cu")
		(net "GND")
	)
	(via
		(at 80.147922 -404.940262)
		(size 0.508)
		(drill 0.254)
		(layers "F.Cu" "B.Cu")
		(net "GND")
	)
	(via
		(at 293.527734 -376.140218)
		(size 0.508)
		(drill 0.254)
		(layers "F.Cu" "B.Cu")
		(net "GND")
	)
	(via
		(at 383.426208 -346.09913)
		(size 0.4572)
		(drill 0.254)
		(layers "F.Cu" "B.Cu")
		(net "GND")
	)
	(via
		(at 60.599828 -310.149748)
		(size 0.4064)
		(drill 0.2032)
		(layers "F.Cu" "B.Cu")
		(net "GND")
	)
	(via
		(at 344.893646 -218.787218)
		(size 0.4572)
		(drill 0.254)
		(layers "F.Cu" "B.Cu")
		(net "GND")
	)
	(via
		(at 160.074864 -293.52494)
		(size 0.4064)
		(drill 0.2032)
		(layers "F.Cu" "B.Cu")
		(net "GND")
	)
	(via
		(at 291.32784 -375.040144)
		(size 0.508)
		(drill 0.254)
		(layers "F.Cu" "B.Cu")
		(net "GND")
	)
	(via
		(at 61.648848 -27.79014)
		(size 0.508)
		(drill 0.254)
		(layers "F.Cu" "B.Cu")
		(net "GND")
	)
	(via
		(at 415.074862 -296.37482)
		(size 0.4064)
		(drill 0.2032)
		(layers "F.Cu" "B.Cu")
		(net "GND")
	)
	(via
		(at 45.26534 -344.831162)
		(size 0.4572)
		(drill 0.254)
		(layers "F.Cu" "B.Cu")
		(net "GND")
	)
	(via
		(at 71.367904 -136.645142)
		(size 0.508)
		(drill 0.254)
		(layers "F.Cu" "B.Cu")
		(net "GND")
	)
	(via
		(at 153.89987 -318.699896)
		(size 0.4064)
		(drill 0.2032)
		(layers "F.Cu" "B.Cu")
		(net "GND")
	)
	(via
		(at 438.336944 -349.219774)
		(size 0.4572)
		(drill 0.254)
		(layers "F.Cu" "B.Cu")
		(net "GND")
	)
	(via
		(at 281.399742 -313.949842)
		(size 0.4064)
		(drill 0.2032)
		(layers "F.Cu" "B.Cu")
		(net "GND")
	)
	(via
		(at 182.002176 -58.731404)
		(size 0.508)
		(drill 0.254)
		(layers "F.Cu" "B.Cu")
		(net "GND")
	)
	(via
		(at 172.547788 -369.938554)
		(size 0.508)
		(drill 0.254)
		(layers "F.Cu" "B.Cu")
		(net "GND")
	)
	(via
		(at 377.12777 -400.938492)
		(size 0.508)
		(drill 0.254)
		(layers "F.Cu" "B.Cu")
		(net "GND")
	)
	(via
		(at 67.66687 -156.554932)
		(size 0.508)
		(drill 0.254)
		(layers "F.Cu" "B.Cu")
		(net "GND")
	)
	(via
		(at 164.824918 -304.924714)
		(size 0.4064)
		(drill 0.2032)
		(layers "F.Cu" "B.Cu")
		(net "GND")
	)
	(via
		(at 387.050026 -312.049922)
		(size 0.4064)
		(drill 0.2032)
		(layers "F.Cu" "B.Cu")
		(net "GND")
	)
	(via
		(at 153.665428 -151.40813)
		(size 0.508)
		(drill 0.254)
		(layers "F.Cu" "B.Cu")
		(net "GND")
	)
	(via
		(at 221.308676 -196.039486)
		(size 0.508)
		(drill 0.254)
		(layers "F.Cu" "B.Cu")
		(net "GND")
	)
	(via
		(at 137.413492 -34.718498)
		(size 0.508)
		(drill 0.254)
		(layers "F.Cu" "B.Cu")
		(net "GND")
	)
	(via
		(at 392.749786 -311.099962)
		(size 0.4064)
		(drill 0.2032)
		(layers "F.Cu" "B.Cu")
		(net "GND")
	)
	(via
		(at 227.867972 -217.904314)
		(size 0.4572)
		(drill 0.254)
		(layers "F.Cu" "B.Cu")
		(net "GND")
	)
	(via
		(at 415.662872 -87.78113)
		(size 0.508)
		(drill 0.254)
		(layers "F.Cu" "B.Cu")
		(net "GND")
	)
	(via
		(at 295.727882 -376.241818)
		(size 0.508)
		(drill 0.254)
		(layers "F.Cu" "B.Cu")
		(net "GND")
	)
	(via
		(at 192.793366 -84.332318)
		(size 0.508)
		(drill 0.254)
		(layers "F.Cu" "B.Cu")
		(net "GND")
	)
	(via
		(at 270.474694 -298.27474)
		(size 0.4064)
		(drill 0.2032)
		(layers "F.Cu" "B.Cu")
		(net "GND")
	)
	(via
		(at 245.291864 -277.201884)
		(size 0.508)
		(drill 0.254)
		(layers "F.Cu" "B.Cu")
		(net "GND")
	)
	(via
		(at 138.68146 -29.859478)
		(size 0.508)
		(drill 0.254)
		(layers "F.Cu" "B.Cu")
		(net "GND")
	)
	(via
		(at 73.960228 -19.33956)
		(size 0.508)
		(drill 0.254)
		(layers "F.Cu" "B.Cu")
		(net "GND")
	)
	(via
		(at 201.311256 -103.22814)
		(size 0.508)
		(drill 0.254)
		(layers "F.Cu" "B.Cu")
		(net "GND")
	)
	(via
		(at 342.876378 -290.68649)
		(size 0.508)
		(drill 0.254)
		(layers "F.Cu" "B.Cu")
		(net "GND")
	)
	(via
		(at 394.239242 -31.652972)
		(size 0.508)
		(drill 0.254)
		(layers "F.Cu" "B.Cu")
		(net "GND")
	)
	(via
		(at 218.080844 -97.79)
		(size 0.508)
		(drill 0.254)
		(layers "F.Cu" "B.Cu")
		(net "GND")
	)
	(via
		(at 378.50826 -52.536852)
		(size 0.508)
		(drill 0.254)
		(layers "F.Cu" "B.Cu")
		(net "GND")
	)
	(via
		(at 39.04742 -355.366066)
		(size 0.4572)
		(drill 0.254)
		(layers "F.Cu" "B.Cu")
		(net "GND")
	)
	(via
		(at 329.234292 -47.936658)
		(size 0.508)
		(drill 0.254)
		(layers "F.Cu" "B.Cu")
		(net "GND")
	)
	(via
		(at 156.750004 -303.499774)
		(size 0.4064)
		(drill 0.2032)
		(layers "F.Cu" "B.Cu")
		(net "GND")
	)
	(via
		(at 82.347816 -400.938492)
		(size 0.508)
		(drill 0.254)
		(layers "F.Cu" "B.Cu")
		(net "GND")
	)
	(via
		(at 279.513284 -31.118302)
		(size 0.508)
		(drill 0.254)
		(layers "F.Cu" "B.Cu")
		(net "GND")
	)
	(via
		(at 134.68604 -349.219774)
		(size 0.4572)
		(drill 0.254)
		(layers "F.Cu" "B.Cu")
		(net "GND")
	)
	(via
		(at 335.328006 -397.140176)
		(size 0.508)
		(drill 0.254)
		(layers "F.Cu" "B.Cu")
		(net "GND")
	)
	(via
		(at 53.474874 -284.024832)
		(size 0.4064)
		(drill 0.2032)
		(layers "F.Cu" "B.Cu")
		(net "GND")
	)
	(via
		(at 335.557368 -29.784294)
		(size 0.508)
		(drill 0.254)
		(layers "F.Cu" "B.Cu")
		(net "GND")
	)
	(via
		(at 164.351462 -45.865288)
		(size 0.508)
		(drill 0.254)
		(layers "F.Cu" "B.Cu")
		(net "GND")
	)
	(via
		(at 177.649886 -279.749758)
		(size 0.4064)
		(drill 0.2032)
		(layers "F.Cu" "B.Cu")
		(net "GND")
	)
	(via
		(at 450.088 -417.82492)
		(size 0.508)
		(drill 0.254)
		(layers "F.Cu" "B.Cu")
		(net "GND")
	)
	(via
		(at 155.483052 -34.990024)
		(size 0.508)
		(drill 0.254)
		(layers "F.Cu" "B.Cu")
		(net "GND")
	)
	(via
		(at 410.799788 -281.649932)
		(size 0.4064)
		(drill 0.2032)
		(layers "F.Cu" "B.Cu")
		(net "GND")
	)
	(via
		(at 231.407462 -203.32954)
		(size 0.508)
		(drill 0.254)
		(layers "F.Cu" "B.Cu")
		(net "GND")
	)
	(via
		(at 304.199798 -313.949842)
		(size 0.4064)
		(drill 0.2032)
		(layers "F.Cu" "B.Cu")
		(net "GND")
	)
	(via
		(at 310.849772 -319.65011)
		(size 0.4064)
		(drill 0.2032)
		(layers "F.Cu" "B.Cu")
		(net "GND")
	)
	(via
		(at 101.831394 -390.627108)
		(size 0.508)
		(drill 0.254)
		(layers "F.Cu" "B.Cu")
		(net "GND")
	)
	(via
		(at 307.999892 -288.299906)
		(size 0.4064)
		(drill 0.2032)
		(layers "F.Cu" "B.Cu")
		(net "GND")
	)
	(via
		(at 329.480164 -357.75773)
		(size 0.4064)
		(drill 0.2032)
		(layers "F.Cu" "B.Cu")
		(net "GND")
	)
	(via
		(at 311.799986 -274.049744)
		(size 0.4064)
		(drill 0.2032)
		(layers "F.Cu" "B.Cu")
		(net "GND")
	)
	(via
		(at 44.449746 -316.799722)
		(size 0.4064)
		(drill 0.2032)
		(layers "F.Cu" "B.Cu")
		(net "GND")
	)
	(via
		(at 341.927942 -398.24025)
		(size 0.508)
		(drill 0.254)
		(layers "F.Cu" "B.Cu")
		(net "GND")
	)
	(via
		(at 352.88093 -103.744522)
		(size 0.508)
		(drill 0.254)
		(layers "F.Cu" "B.Cu")
		(net "GND")
	)
	(via
		(at 157.66161 -265.88339)
		(size 0.508)
		(drill 0.254)
		(layers "F.Cu" "B.Cu")
		(net "GND")
	)
	(via
		(at 74.84999 -305.399948)
		(size 0.4064)
		(drill 0.2032)
		(layers "F.Cu" "B.Cu")
		(net "GND")
	)
	(via
		(at 396.551404 -45.865288)
		(size 0.508)
		(drill 0.254)
		(layers "F.Cu" "B.Cu")
		(net "GND")
	)
	(via
		(at 153.898346 -21.077936)
		(size 0.508)
		(drill 0.254)
		(layers "F.Cu" "B.Cu")
		(net "GND")
	)
	(via
		(at 169.587164 -102.444804)
		(size 0.508)
		(drill 0.254)
		(layers "F.Cu" "B.Cu")
		(net "GND")
	)
	(via
		(at 337.176872 -357.123746)
		(size 0.4572)
		(drill 0.254)
		(layers "F.Cu" "B.Cu")
		(net "GND")
	)
	(via
		(at 175.683164 -343.073482)
		(size 0.4572)
		(drill 0.254)
		(layers "F.Cu" "B.Cu")
		(net "GND")
	)
	(via
		(at 412.699962 -274.049744)
		(size 0.4064)
		(drill 0.2032)
		(layers "F.Cu" "B.Cu")
		(net "GND")
	)
	(via
		(at 432.12766 -371.140228)
		(size 0.508)
		(drill 0.254)
		(layers "F.Cu" "B.Cu")
		(net "GND")
	)
	(via
		(at 80.898238 -122.098054)
		(size 0.508)
		(drill 0.254)
		(layers "F.Cu" "B.Cu")
		(net "GND")
	)
	(via
		(at 424.57497 -296.37482)
		(size 0.4064)
		(drill 0.2032)
		(layers "F.Cu" "B.Cu")
		(net "GND")
	)
	(via
		(at 377.12777 -383.940304)
		(size 0.508)
		(drill 0.254)
		(layers "F.Cu" "B.Cu")
		(net "GND")
	)
	(via
		(at 150.616412 -384.762248)
		(size 0.508)
		(drill 0.254)
		(layers "F.Cu" "B.Cu")
		(net "GND")
	)
	(via
		(at 140.683234 -206.069692)
		(size 0.508)
		(drill 0.254)
		(layers "F.Cu" "B.Cu")
		(net "GND")
	)
	(via
		(at 135.806688 -199.399398)
		(size 0.508)
		(drill 0.254)
		(layers "F.Cu" "B.Cu")
		(net "GND")
	)
	(via
		(at 116.95557 -220.2307)
		(size 0.508)
		(drill 0.254)
		(layers "F.Cu" "B.Cu")
		(net "GND")
	)
	(via
		(at 112.105186 -285.267654)
		(size 0.508)
		(drill 0.254)
		(layers "F.Cu" "B.Cu")
		(net "GND")
	)
	(via
		(at 47.59452 -126.703836)
		(size 0.508)
		(drill 0.254)
		(layers "F.Cu" "B.Cu")
		(net "GND")
	)
	(via
		(at 348.527878 -399.838418)
		(size 0.508)
		(drill 0.254)
		(layers "F.Cu" "B.Cu")
		(net "GND")
	)
	(via
		(at 289.94989 -274.999958)
		(size 0.4064)
		(drill 0.2032)
		(layers "F.Cu" "B.Cu")
		(net "GND")
	)
	(via
		(at 3.45821 -38.928802)
		(size 0.508)
		(drill 0.254)
		(layers "F.Cu" "B.Cu")
		(net "GND")
	)
	(via
		(at 144.159986 -206.4639)
		(size 0.508)
		(drill 0.254)
		(layers "F.Cu" "B.Cu")
		(net "GND")
	)
	(via
		(at 423.15003 -319.65011)
		(size 0.4064)
		(drill 0.2032)
		(layers "F.Cu" "B.Cu")
		(net "GND")
	)
	(via
		(at 178.124866 -300.174914)
		(size 0.4064)
		(drill 0.2032)
		(layers "F.Cu" "B.Cu")
		(net "GND")
	)
	(via
		(at 14.070838 -287.956752)
		(size 0.508)
		(drill 0.254)
		(layers "F.Cu" "B.Cu")
		(net "GND")
	)
	(via
		(at 71.524876 -293.52494)
		(size 0.4064)
		(drill 0.2032)
		(layers "F.Cu" "B.Cu")
		(net "GND")
	)
	(via
		(at 185.250074 -312.049922)
		(size 0.4064)
		(drill 0.2032)
		(layers "F.Cu" "B.Cu")
		(net "GND")
	)
	(via
		(at 160.074864 -291.624766)
		(size 0.4064)
		(drill 0.2032)
		(layers "F.Cu" "B.Cu")
		(net "GND")
	)
	(via
		(at 394.17498 -288.774886)
		(size 0.4064)
		(drill 0.2032)
		(layers "F.Cu" "B.Cu")
		(net "GND")
	)
	(via
		(at 145.945352 -51.227482)
		(size 0.508)
		(drill 0.254)
		(layers "F.Cu" "B.Cu")
		(net "GND")
	)
	(via
		(at 123.728988 -345.465146)
		(size 0.4064)
		(drill 0.2032)
		(layers "F.Cu" "B.Cu")
		(net "GND")
	)
	(via
		(at 194.749674 -274.999958)
		(size 0.4064)
		(drill 0.2032)
		(layers "F.Cu" "B.Cu")
		(net "GND")
	)
	(via
		(at 64.874902 -289.724846)
		(size 0.4064)
		(drill 0.2032)
		(layers "F.Cu" "B.Cu")
		(net "GND")
	)
	(via
		(at 44.569888 -25.832054)
		(size 0.508)
		(drill 0.254)
		(layers "F.Cu" "B.Cu")
		(net "GND")
	)
	(via
		(at 406.524968 -300.174914)
		(size 0.4064)
		(drill 0.2032)
		(layers "F.Cu" "B.Cu")
		(net "GND")
	)
	(via
		(at 286.149796 -276.899878)
		(size 0.4064)
		(drill 0.2032)
		(layers "F.Cu" "B.Cu")
		(net "GND")
	)
	(via
		(at 388.127748 -375.040144)
		(size 0.508)
		(drill 0.254)
		(layers "F.Cu" "B.Cu")
		(net "GND")
	)
	(via
		(at 362.598462 -238.5568)
		(size 0.508)
		(drill 0.254)
		(layers "F.Cu" "B.Cu")
		(net "GND")
	)
	(via
		(at 408.899868 -273.099784)
		(size 0.4064)
		(drill 0.2032)
		(layers "F.Cu" "B.Cu")
		(net "GND")
	)
	(via
		(at 422.792144 -343.073482)
		(size 0.4572)
		(drill 0.254)
		(layers "F.Cu" "B.Cu")
		(net "GND")
	)
	(via
		(at 425.52493 -289.724846)
		(size 0.4064)
		(drill 0.2032)
		(layers "F.Cu" "B.Cu")
		(net "GND")
	)
	(via
		(at 270.474948 -276.424898)
		(size 0.4064)
		(drill 0.2032)
		(layers "F.Cu" "B.Cu")
		(net "GND")
	)
	(via
		(at 77.947774 -382.73863)
		(size 0.508)
		(drill 0.254)
		(layers "F.Cu" "B.Cu")
		(net "GND")
	)
	(via
		(at 81.024984 -288.774886)
		(size 0.4064)
		(drill 0.2032)
		(layers "F.Cu" "B.Cu")
		(net "GND")
	)
	(via
		(at 213.598506 -65.15989)
		(size 0.508)
		(drill 0.254)
		(layers "F.Cu" "B.Cu")
		(net "GND")
	)
	(via
		(at 111.311182 -287.51149)
		(size 0.508)
		(drill 0.254)
		(layers "F.Cu" "B.Cu")
		(net "GND")
	)
	(via
		(at 418.267642 -134.400544)
		(size 0.508)
		(drill 0.254)
		(layers "F.Cu" "B.Cu")
		(net "GND")
	)
	(via
		(at 25.352756 -349.219774)
		(size 0.4572)
		(drill 0.254)
		(layers "F.Cu" "B.Cu")
		(net "GND")
	)
	(via
		(at 45.39996 -312.999882)
		(size 0.4064)
		(drill 0.2032)
		(layers "F.Cu" "B.Cu")
		(net "GND")
	)
	(via
		(at 37.133784 -120.833134)
		(size 0.508)
		(drill 0.254)
		(layers "F.Cu" "B.Cu")
		(net "GND")
	)
	(via
		(at 277.251668 -111.44504)
		(size 0.508)
		(drill 0.254)
		(layers "F.Cu" "B.Cu")
		(net "GND")
	)
	(via
		(at 341.927942 -382.73863)
		(size 0.508)
		(drill 0.254)
		(layers "F.Cu" "B.Cu")
		(net "GND")
	)
	(via
		(at 27.31516 -43.85691)
		(size 0.508)
		(drill 0.254)
		(layers "F.Cu" "B.Cu")
		(net "GND")
	)
	(via
		(at 4.872736 -36.760912)
		(size 0.508)
		(drill 0.254)
		(layers "F.Cu" "B.Cu")
		(net "GND")
	)
	(via
		(at 302.774858 -302.074834)
		(size 0.4064)
		(drill 0.2032)
		(layers "F.Cu" "B.Cu")
		(net "GND")
	)
	(via
		(at 205.101698 -303.026826)
		(size 0.508)
		(drill 0.254)
		(layers "F.Cu" "B.Cu")
		(net "GND")
	)
	(via
		(at 154.850084 -311.099962)
		(size 0.4064)
		(drill 0.2032)
		(layers "F.Cu" "B.Cu")
		(net "GND")
	)
	(via
		(at 298.44873 -33.19018)
		(size 0.508)
		(drill 0.254)
		(layers "F.Cu" "B.Cu")
		(net "GND")
	)
	(via
		(at 105.323132 -51.019456)
		(size 0.508)
		(drill 0.254)
		(layers "F.Cu" "B.Cu")
		(net "GND")
	)
	(via
		(at 400.824954 -293.52494)
		(size 0.4064)
		(drill 0.2032)
		(layers "F.Cu" "B.Cu")
		(net "GND")
	)
	(via
		(at 366.033304 -121.525284)
		(size 0.508)
		(drill 0.254)
		(layers "F.Cu" "B.Cu")
		(net "GND")
	)
	(via
		(at 39.224966 -286.874966)
		(size 0.4064)
		(drill 0.2032)
		(layers "F.Cu" "B.Cu")
		(net "GND")
	)
	(via
		(at 4.562856 -236.041692)
		(size 0.508)
		(drill 0.254)
		(layers "F.Cu" "B.Cu")
		(net "GND")
	)
	(via
		(at 339.728048 -384.041904)
		(size 0.508)
		(drill 0.254)
		(layers "F.Cu" "B.Cu")
		(net "GND")
	)
	(via
		(at 383.05486 -357.75773)
		(size 0.4064)
		(drill 0.2032)
		(layers "F.Cu" "B.Cu")
		(net "GND")
	)
	(via
		(at 156.750004 -312.049922)
		(size 0.4064)
		(drill 0.2032)
		(layers "F.Cu" "B.Cu")
		(net "GND")
	)
	(via
		(at 93.425264 -332.888844)
		(size 0.508)
		(drill 0.254)
		(layers "F.Cu" "B.Cu")
		(net "GND")
	)
	(via
		(at 344.23477 -165.616128)
		(size 0.508)
		(drill 0.254)
		(layers "F.Cu" "B.Cu")
		(net "GND")
	)
	(via
		(at 98.199956 -220.544644)
		(size 0.508)
		(drill 0.254)
		(layers "F.Cu" "B.Cu")
		(net "GND")
	)
	(via
		(at 124.147834 -384.041904)
		(size 0.4572)
		(drill 0.254)
		(layers "F.Cu" "B.Cu")
		(net "GND")
	)
	(via
		(at 383.05486 -354.732082)
		(size 0.4064)
		(drill 0.2032)
		(layers "F.Cu" "B.Cu")
		(net "GND")
	)
	(via
		(at 67.249802 -281.649932)
		(size 0.4064)
		(drill 0.2032)
		(layers "F.Cu" "B.Cu")
		(net "GND")
	)
	(via
		(at 256.118868 -193.48069)
		(size 0.508)
		(drill 0.254)
		(layers "F.Cu" "B.Cu")
		(net "GND")
	)
	(via
		(at 284.724856 -287.824926)
		(size 0.4064)
		(drill 0.2032)
		(layers "F.Cu" "B.Cu")
		(net "GND")
	)
	(via
		(at 182.39994 -310.149748)
		(size 0.4064)
		(drill 0.2032)
		(layers "F.Cu" "B.Cu")
		(net "GND")
	)
	(via
		(at 22.243796 -357.123746)
		(size 0.4572)
		(drill 0.254)
		(layers "F.Cu" "B.Cu")
		(net "GND")
	)
	(via
		(at 62.499748 -314.899802)
		(size 0.4064)
		(drill 0.2032)
		(layers "F.Cu" "B.Cu")
		(net "GND")
	)
	(via
		(at 324.369684 -345.465146)
		(size 0.4064)
		(drill 0.2032)
		(layers "F.Cu" "B.Cu")
		(net "GND")
	)
	(via
		(at 47.147988 -374.938798)
		(size 0.508)
		(drill 0.254)
		(layers "F.Cu" "B.Cu")
		(net "GND")
	)
	(via
		(at 403.674834 -303.974754)
		(size 0.4064)
		(drill 0.2032)
		(layers "F.Cu" "B.Cu")
		(net "GND")
	)
	(via
		(at 119.0879 -136.526778)
		(size 0.508)
		(drill 0.254)
		(layers "F.Cu" "B.Cu")
		(net "GND")
	)
	(via
		(at 440.18708 -354.098098)
		(size 0.4572)
		(drill 0.254)
		(layers "F.Cu" "B.Cu")
		(net "GND")
	)
	(via
		(at 293.527734 -400.938492)
		(size 0.508)
		(drill 0.254)
		(layers "F.Cu" "B.Cu")
		(net "GND")
	)
	(via
		(at 428.84979 -315.849762)
		(size 0.4064)
		(drill 0.2032)
		(layers "F.Cu" "B.Cu")
		(net "GND")
	)
	(via
		(at 304.473864 -73.85177)
		(size 0.508)
		(drill 0.254)
		(layers "F.Cu" "B.Cu")
		(net "GND")
	)
	(via
		(at 194.749928 -308.249828)
		(size 0.4064)
		(drill 0.2032)
		(layers "F.Cu" "B.Cu")
		(net "GND")
	)
	(via
		(at 292.424358 -200.912984)
		(size 0.508)
		(drill 0.254)
		(layers "F.Cu" "B.Cu")
		(net "GND")
	)
	(via
		(at 37.133784 -133.301994)
		(size 0.508)
		(drill 0.254)
		(layers "F.Cu" "B.Cu")
		(net "GND")
	)
	(via
		(at 76.71943 -357.123746)
		(size 0.4572)
		(drill 0.254)
		(layers "F.Cu" "B.Cu")
		(net "GND")
	)
	(via
		(at 35.738562 -136.241028)
		(size 0.508)
		(drill 0.254)
		(layers "F.Cu" "B.Cu")
		(net "GND")
	)
	(via
		(at 279.974802 -290.674806)
		(size 0.4064)
		(drill 0.2032)
		(layers "F.Cu" "B.Cu")
		(net "GND")
	)
	(via
		(at 40.547798 -398.34185)
		(size 0.508)
		(drill 0.254)
		(layers "F.Cu" "B.Cu")
		(net "GND")
	)
	(via
		(at 161.975038 -283.074872)
		(size 0.4064)
		(drill 0.2032)
		(layers "F.Cu" "B.Cu")
		(net "GND")
	)
	(via
		(at 83.540346 -131.514596)
		(size 0.508)
		(drill 0.254)
		(layers "F.Cu" "B.Cu")
		(net "GND")
	)
	(via
		(at 180.02504 -300.174914)
		(size 0.4064)
		(drill 0.2032)
		(layers "F.Cu" "B.Cu")
		(net "GND")
	)
	(via
		(at 255.933194 -395.794738)
		(size 0.508)
		(drill 0.254)
		(layers "F.Cu" "B.Cu")
		(net "GND")
	)
	(via
		(at 171.474892 -307.774848)
		(size 0.4064)
		(drill 0.2032)
		(layers "F.Cu" "B.Cu")
		(net "GND")
	)
	(via
		(at 128.46812 -349.219774)
		(size 0.4572)
		(drill 0.254)
		(layers "F.Cu" "B.Cu")
		(net "GND")
	)
	(via
		(at 422.548304 -120.035066)
		(size 0.508)
		(drill 0.254)
		(layers "F.Cu" "B.Cu")
		(net "GND")
	)
	(via
		(at 249.391678 -345.68003)
		(size 0.508)
		(drill 0.254)
		(layers "F.Cu" "B.Cu")
		(net "GND")
	)
	(via
		(at 119.14124 -355.366066)
		(size 0.4572)
		(drill 0.254)
		(layers "F.Cu" "B.Cu")
		(net "GND")
	)
	(via
		(at 49.60493 -105.365042)
		(size 0.508)
		(drill 0.254)
		(layers "F.Cu" "B.Cu")
		(net "GND")
	)
	(via
		(at 348.093538 -225.186748)
		(size 0.4572)
		(drill 0.254)
		(layers "F.Cu" "B.Cu")
		(net "GND")
	)
	(via
		(at 73.899776 -309.199788)
		(size 0.4064)
		(drill 0.2032)
		(layers "F.Cu" "B.Cu")
		(net "GND")
	)
	(via
		(at 304.432208 -114.812572)
		(size 0.508)
		(drill 0.254)
		(layers "F.Cu" "B.Cu")
		(net "GND")
	)
	(via
		(at 260.379464 -177.376328)
		(size 0.508)
		(drill 0.254)
		(layers "F.Cu" "B.Cu")
		(net "GND")
	)
	(via
		(at 407.492454 -11.372342)
		(size 0.508)
		(drill 0.254)
		(layers "F.Cu" "B.Cu")
		(net "GND")
	)
	(via
		(at 31.747968 -408.840178)
		(size 0.508)
		(drill 0.254)
		(layers "F.Cu" "B.Cu")
		(net "GND")
	)
	(via
		(at 389.899906 -312.999882)
		(size 0.4064)
		(drill 0.2032)
		(layers "F.Cu" "B.Cu")
		(net "GND")
	)
	(via
		(at 203.294996 -60.633356)
		(size 0.508)
		(drill 0.254)
		(layers "F.Cu" "B.Cu")
		(net "GND")
	)
	(via
		(at 163.13277 -98.845116)
		(size 0.508)
		(drill 0.254)
		(layers "F.Cu" "B.Cu")
		(net "GND")
	)
	(via
		(at 463.023712 -283.105606)
		(size 0.508)
		(drill 0.254)
		(layers "F.Cu" "B.Cu")
		(net "GND")
	)
	(via
		(at 324.332092 -13.613638)
		(size 0.508)
		(drill 0.254)
		(layers "F.Cu" "B.Cu")
		(net "GND")
	)
	(via
		(at 221.747334 -181.795166)
		(size 0.508)
		(drill 0.254)
		(layers "F.Cu" "B.Cu")
		(net "GND")
	)
	(via
		(at 49.853088 -342.439498)
		(size 0.4064)
		(drill 0.2032)
		(layers "F.Cu" "B.Cu")
		(net "GND")
	)
	(via
		(at 342.876378 -291.32149)
		(size 0.508)
		(drill 0.254)
		(layers "F.Cu" "B.Cu")
		(net "GND")
	)
	(via
		(at 73.61047 -352.245422)
		(size 0.4572)
		(drill 0.254)
		(layers "F.Cu" "B.Cu")
		(net "GND")
	)
	(via
		(at 273.324828 -283.074872)
		(size 0.4064)
		(drill 0.2032)
		(layers "F.Cu" "B.Cu")
		(net "GND")
	)
	(via
		(at 313.699906 -286.399732)
		(size 0.4064)
		(drill 0.2032)
		(layers "F.Cu" "B.Cu")
		(net "GND")
	)
	(via
		(at 88.947752 -395.938502)
		(size 0.508)
		(drill 0.254)
		(layers "F.Cu" "B.Cu")
		(net "GND")
	)
	(via
		(at 276.655022 -345.465146)
		(size 0.4064)
		(drill 0.2032)
		(layers "F.Cu" "B.Cu")
		(net "GND")
	)
	(via
		(at 336.805524 -342.439498)
		(size 0.4064)
		(drill 0.2032)
		(layers "F.Cu" "B.Cu")
		(net "GND")
	)
	(via
		(at 197.600062 -311.099962)
		(size 0.4064)
		(drill 0.2032)
		(layers "F.Cu" "B.Cu")
		(net "GND")
	)
	(via
		(at 463.037682 -209.817462)
		(size 0.508)
		(drill 0.254)
		(layers "F.Cu" "B.Cu")
		(net "GND")
	)
	(via
		(at 118.743476 -234.831128)
		(size 0.508)
		(drill 0.254)
		(layers "F.Cu" "B.Cu")
		(net "GND")
	)
	(via
		(at 29.54782 -373.441976)
		(size 0.508)
		(drill 0.254)
		(layers "F.Cu" "B.Cu")
		(net "GND")
	)
	(via
		(at 183.75122 -344.831162)
		(size 0.4572)
		(drill 0.254)
		(layers "F.Cu" "B.Cu")
		(net "GND")
	)
	(via
		(at 74.248264 -125.435106)
		(size 0.508)
		(drill 0.254)
		(layers "F.Cu" "B.Cu")
		(net "GND")
	)
	(via
		(at 345.703906 -83.083146)
		(size 0.508)
		(drill 0.254)
		(layers "F.Cu" "B.Cu")
		(net "GND")
	)
	(via
		(at 275.224748 -273.574764)
		(size 0.4064)
		(drill 0.2032)
		(layers "F.Cu" "B.Cu")
		(net "GND")
	)
	(via
		(at 420.51097 -109.41304)
		(size 0.508)
		(drill 0.254)
		(layers "F.Cu" "B.Cu")
		(net "GND")
	)
	(via
		(at 463.037682 -169.177462)
		(size 0.508)
		(drill 0.254)
		(layers "F.Cu" "B.Cu")
		(net "GND")
	)
	(via
		(at 237.561374 -172.15993)
		(size 0.508)
		(drill 0.254)
		(layers "F.Cu" "B.Cu")
		(net "GND")
	)
	(via
		(at 153.89987 -313.949842)
		(size 0.4064)
		(drill 0.2032)
		(layers "F.Cu" "B.Cu")
		(net "GND")
	)
	(via
		(at 283.912056 -23.355554)
		(size 0.508)
		(drill 0.254)
		(layers "F.Cu" "B.Cu")
		(net "GND")
	)
	(via
		(at 65.824862 -306.824888)
		(size 0.4064)
		(drill 0.2032)
		(layers "F.Cu" "B.Cu")
		(net "GND")
	)
	(via
		(at 390.327896 -411.141926)
		(size 0.508)
		(drill 0.254)
		(layers "F.Cu" "B.Cu")
		(net "GND")
	)
	(via
		(at 392.52779 -399.838418)
		(size 0.508)
		(drill 0.254)
		(layers "F.Cu" "B.Cu")
		(net "GND")
	)
	(via
		(at 289.94989 -311.099962)
		(size 0.4064)
		(drill 0.2032)
		(layers "F.Cu" "B.Cu")
		(net "GND")
	)
	(via
		(at 14.36116 -134.970012)
		(size 0.508)
		(drill 0.254)
		(layers "F.Cu" "B.Cu")
		(net "GND")
	)
	(via
		(at 426.94987 -319.65011)
		(size 0.4064)
		(drill 0.2032)
		(layers "F.Cu" "B.Cu")
		(net "GND")
	)
	(via
		(at 297.927776 -400.938492)
		(size 0.508)
		(drill 0.254)
		(layers "F.Cu" "B.Cu")
		(net "GND")
	)
	(via
		(at 130.74777 -408.738578)
		(size 0.508)
		(drill 0.254)
		(layers "F.Cu" "B.Cu")
		(net "GND")
	)
	(via
		(at 182.547514 -152.95499)
		(size 0.508)
		(drill 0.254)
		(layers "F.Cu" "B.Cu")
		(net "GND")
	)
	(via
		(at 151.670766 -232.000044)
		(size 0.508)
		(drill 0.254)
		(layers "F.Cu" "B.Cu")
		(net "GND")
	)
	(via
		(at 290.42487 -303.974754)
		(size 0.4064)
		(drill 0.2032)
		(layers "F.Cu" "B.Cu")
		(net "GND")
	)
	(via
		(at 333.127858 -371.038628)
		(size 0.508)
		(drill 0.254)
		(layers "F.Cu" "B.Cu")
		(net "GND")
	)
	(via
		(at 174.079662 -104.830372)
		(size 0.508)
		(drill 0.254)
		(layers "F.Cu" "B.Cu")
		(net "GND")
	)
	(via
		(at 293.829994 -349.219774)
		(size 0.4572)
		(drill 0.254)
		(layers "F.Cu" "B.Cu")
		(net "GND")
	)
	(via
		(at 28.461716 -344.831162)
		(size 0.4572)
		(drill 0.254)
		(layers "F.Cu" "B.Cu")
		(net "GND")
	)
	(via
		(at 305.149504 -272.14957)
		(size 0.4064)
		(drill 0.2032)
		(layers "F.Cu" "B.Cu")
		(net "GND")
	)
	(via
		(at 73.899776 -303.499774)
		(size 0.4064)
		(drill 0.2032)
		(layers "F.Cu" "B.Cu")
		(net "GND")
	)
	(via
		(at 405.575008 -303.974754)
		(size 0.4064)
		(drill 0.2032)
		(layers "F.Cu" "B.Cu")
		(net "GND")
	)
	(via
		(at 93.425264 -334.147668)
		(size 0.508)
		(drill 0.254)
		(layers "F.Cu" "B.Cu")
		(net "GND")
	)
	(via
		(at 177.5333 -341.781638)
		(size 0.4572)
		(drill 0.254)
		(layers "F.Cu" "B.Cu")
		(net "GND")
	)
	(via
		(at 189.049914 -312.049922)
		(size 0.4064)
		(drill 0.2032)
		(layers "F.Cu" "B.Cu")
		(net "GND")
	)
	(via
		(at 23.50262 -357.123746)
		(size 0.4572)
		(drill 0.254)
		(layers "F.Cu" "B.Cu")
		(net "GND")
	)
	(via
		(at 183.766714 -147.555204)
		(size 0.508)
		(drill 0.254)
		(layers "F.Cu" "B.Cu")
		(net "GND")
	)
	(via
		(at 239.39246 -6.292342)
		(size 0.508)
		(drill 0.254)
		(layers "F.Cu" "B.Cu")
		(net "GND")
	)
	(via
		(at 110.713774 -355.2952)
		(size 0.4572)
		(drill 0.254)
		(layers "F.Cu" "B.Cu")
		(net "GND")
	)
	(via
		(at 80.07477 -302.074834)
		(size 0.4064)
		(drill 0.2032)
		(layers "F.Cu" "B.Cu")
		(net "GND")
	)
	(via
		(at 296.938954 -355.366066)
		(size 0.4572)
		(drill 0.254)
		(layers "F.Cu" "B.Cu")
		(net "GND")
	)
	(via
		(at 423.62501 -292.574726)
		(size 0.4064)
		(drill 0.2032)
		(layers "F.Cu" "B.Cu")
		(net "GND")
	)
	(via
		(at 37.417248 -357.75773)
		(size 0.4064)
		(drill 0.2032)
		(layers "F.Cu" "B.Cu")
		(net "GND")
	)
	(via
		(at 217.983308 -164.16782)
		(size 0.508)
		(drill 0.254)
		(layers "F.Cu" "B.Cu")
		(net "GND")
	)
	(via
		(at 135.001254 -201.252074)
		(size 0.508)
		(drill 0.254)
		(layers "F.Cu" "B.Cu")
		(net "GND")
	)
	(via
		(at 33.947862 -408.738578)
		(size 0.508)
		(drill 0.254)
		(layers "F.Cu" "B.Cu")
		(net "GND")
	)
	(via
		(at 427.043342 -80.449674)
		(size 0.508)
		(drill 0.254)
		(layers "F.Cu" "B.Cu")
		(net "GND")
	)
	(via
		(at 54.950868 -384.973068)
		(size 0.508)
		(drill 0.254)
		(layers "F.Cu" "B.Cu")
		(net "GND")
	)
	(via
		(at 406.524968 -283.074872)
		(size 0.4064)
		(drill 0.2032)
		(layers "F.Cu" "B.Cu")
		(net "GND")
	)
	(via
		(at 442.580776 -33.19018)
		(size 0.508)
		(drill 0.254)
		(layers "F.Cu" "B.Cu")
		(net "GND")
	)
	(via
		(at 352.397568 -286.842454)
		(size 0.508)
		(drill 0.254)
		(layers "F.Cu" "B.Cu")
		(net "GND")
	)
	(via
		(at 276.649688 -281.649932)
		(size 0.4064)
		(drill 0.2032)
		(layers "F.Cu" "B.Cu")
		(net "GND")
	)
	(via
		(at 123.92025 -33.19018)
		(size 0.508)
		(drill 0.254)
		(layers "F.Cu" "B.Cu")
		(net "GND")
	)
	(via
		(at 178.124866 -287.824926)
		(size 0.4064)
		(drill 0.2032)
		(layers "F.Cu" "B.Cu")
		(net "GND")
	)
	(via
		(at 208.348834 -27.79014)
		(size 0.508)
		(drill 0.254)
		(layers "F.Cu" "B.Cu")
		(net "GND")
	)
	(via
		(at 133.796024 -160.83407)
		(size 0.508)
		(drill 0.254)
		(layers "F.Cu" "B.Cu")
		(net "GND")
	)
	(via
		(at 174.052992 -357.75773)
		(size 0.4064)
		(drill 0.2032)
		(layers "F.Cu" "B.Cu")
		(net "GND")
	)
	(via
		(at 189.96914 -350.977454)
		(size 0.4572)
		(drill 0.254)
		(layers "F.Cu" "B.Cu")
		(net "GND")
	)
	(via
		(at 111.710216 -136.952228)
		(size 0.508)
		(drill 0.254)
		(layers "F.Cu" "B.Cu")
		(net "GND")
	)
	(via
		(at 251.4473 -148.718778)
		(size 0.508)
		(drill 0.254)
		(layers "F.Cu" "B.Cu")
		(net "GND")
	)
	(via
		(at 390.374886 -279.274778)
		(size 0.4064)
		(drill 0.2032)
		(layers "F.Cu" "B.Cu")
		(net "GND")
	)
	(via
		(at 127.209296 -350.977454)
		(size 0.4572)
		(drill 0.254)
		(layers "F.Cu" "B.Cu")
		(net "GND")
	)
	(via
		(at 140.90396 -347.951806)
		(size 0.4572)
		(drill 0.254)
		(layers "F.Cu" "B.Cu")
		(net "GND")
	)
	(via
		(at 53.48732 -102.444804)
		(size 0.508)
		(drill 0.254)
		(layers "F.Cu" "B.Cu")
		(net "GND")
	)
	(via
		(at 35.93846 -352.245422)
		(size 0.4572)
		(drill 0.254)
		(layers "F.Cu" "B.Cu")
		(net "GND")
	)
	(via
		(at 213.02599 -211.578698)
		(size 0.508)
		(drill 0.254)
		(layers "F.Cu" "B.Cu")
		(net "GND")
	)
	(via
		(at 403.674834 -294.4749)
		(size 0.4064)
		(drill 0.2032)
		(layers "F.Cu" "B.Cu")
		(net "GND")
	)
	(via
		(at 29.056838 -184.905396)
		(size 0.508)
		(drill 0.254)
		(layers "F.Cu" "B.Cu")
		(net "GND")
	)
	(via
		(at 277.02637 -354.098098)
		(size 0.4572)
		(drill 0.254)
		(layers "F.Cu" "B.Cu")
		(net "GND")
	)
	(via
		(at 295.174924 -298.27474)
		(size 0.4064)
		(drill 0.2032)
		(layers "F.Cu" "B.Cu")
		(net "GND")
	)
	(via
		(at 441.445904 -354.098098)
		(size 0.4572)
		(drill 0.254)
		(layers "F.Cu" "B.Cu")
		(net "GND")
	)
	(via
		(at 310.374792 -291.624766)
		(size 0.4064)
		(drill 0.2032)
		(layers "F.Cu" "B.Cu")
		(net "GND")
	)
	(via
		(at 63.924942 -285.924752)
		(size 0.4064)
		(drill 0.2032)
		(layers "F.Cu" "B.Cu")
		(net "GND")
	)
	(via
		(at 385.927854 -408.738578)
		(size 0.508)
		(drill 0.254)
		(layers "F.Cu" "B.Cu")
		(net "GND")
	)
	(via
		(at 168.148 -410.041852)
		(size 0.508)
		(drill 0.254)
		(layers "F.Cu" "B.Cu")
		(net "GND")
	)
	(via
		(at 330.189586 -89.269316)
		(size 0.508)
		(drill 0.254)
		(layers "F.Cu" "B.Cu")
		(net "GND")
	)
	(via
		(at 161.025078 -283.074872)
		(size 0.4064)
		(drill 0.2032)
		(layers "F.Cu" "B.Cu")
		(net "GND")
	)
	(via
		(at 180.02504 -297.32478)
		(size 0.4064)
		(drill 0.2032)
		(layers "F.Cu" "B.Cu")
		(net "GND")
	)
	(via
		(at 425.04995 -319.65011)
		(size 0.4064)
		(drill 0.2032)
		(layers "F.Cu" "B.Cu")
		(net "GND")
	)
	(via
		(at 63.449962 -279.749758)
		(size 0.4064)
		(drill 0.2032)
		(layers "F.Cu" "B.Cu")
		(net "GND")
	)
	(via
		(at 181.912514 -147.555204)
		(size 0.508)
		(drill 0.254)
		(layers "F.Cu" "B.Cu")
		(net "GND")
	)
	(via
		(at 80.147922 -381.638556)
		(size 0.508)
		(drill 0.254)
		(layers "F.Cu" "B.Cu")
		(net "GND")
	)
	(via
		(at 424.64228 -350.977454)
		(size 0.4572)
		(drill 0.254)
		(layers "F.Cu" "B.Cu")
		(net "GND")
	)
	(via
		(at 45.636688 -345.465146)
		(size 0.4064)
		(drill 0.2032)
		(layers "F.Cu" "B.Cu")
		(net "GND")
	)
	(via
		(at 82.7151 -60.601606)
		(size 0.508)
		(drill 0.254)
		(layers "F.Cu" "B.Cu")
		(net "GND")
	)
	(via
		(at 70.099936 -317.749936)
		(size 0.4064)
		(drill 0.2032)
		(layers "F.Cu" "B.Cu")
		(net "GND")
	)
	(via
		(at 302.871124 -28.05303)
		(size 0.508)
		(drill 0.254)
		(layers "F.Cu" "B.Cu")
		(net "GND")
	)
	(via
		(at 366.891062 -238.456724)
		(size 0.508)
		(drill 0.254)
		(layers "F.Cu" "B.Cu")
		(net "GND")
	)
	(via
		(at 154.501596 -135.643112)
		(size 0.508)
		(drill 0.254)
		(layers "F.Cu" "B.Cu")
		(net "GND")
	)
	(via
		(at 409.849828 -279.749758)
		(size 0.4064)
		(drill 0.2032)
		(layers "F.Cu" "B.Cu")
		(net "GND")
	)
	(via
		(at 324.741032 -349.219774)
		(size 0.4572)
		(drill 0.254)
		(layers "F.Cu" "B.Cu")
		(net "GND")
	)
	(via
		(at 143.326104 -197.282054)
		(size 0.508)
		(drill 0.254)
		(layers "F.Cu" "B.Cu")
		(net "GND")
	)
	(via
		(at 137.390124 -73.85177)
		(size 0.508)
		(drill 0.254)
		(layers "F.Cu" "B.Cu")
		(net "GND")
	)
	(via
		(at 385.624832 -277.374858)
		(size 0.4064)
		(drill 0.2032)
		(layers "F.Cu" "B.Cu")
		(net "GND")
	)
	(via
		(at 307.049932 -288.299906)
		(size 0.4064)
		(drill 0.2032)
		(layers "F.Cu" "B.Cu")
		(net "GND")
	)
	(via
		(at 136.039352 -28.05303)
		(size 0.508)
		(drill 0.254)
		(layers "F.Cu" "B.Cu")
		(net "GND")
	)
	(via
		(at 283.774896 -305.874928)
		(size 0.4064)
		(drill 0.2032)
		(layers "F.Cu" "B.Cu")
		(net "GND")
	)
	(via
		(at 259.868924 -299.133514)
		(size 0.508)
		(drill 0.254)
		(layers "F.Cu" "B.Cu")
		(net "GND")
	)
	(via
		(at 378.673868 -25.971246)
		(size 0.508)
		(drill 0.254)
		(layers "F.Cu" "B.Cu")
		(net "GND")
	)
	(via
		(at 68.838318 -72.56526)
		(size 0.508)
		(drill 0.254)
		(layers "F.Cu" "B.Cu")
		(net "GND")
	)
	(via
		(at 280.449782 -279.749758)
		(size 0.4064)
		(drill 0.2032)
		(layers "F.Cu" "B.Cu")
		(net "GND")
	)
	(via
		(at 154.37485 -296.37482)
		(size 0.4064)
		(drill 0.2032)
		(layers "F.Cu" "B.Cu")
		(net "GND")
	)
	(via
		(at 172.900086 -273.099784)
		(size 0.4064)
		(drill 0.2032)
		(layers "F.Cu" "B.Cu")
		(net "GND")
	)
	(via
		(at 190.394844 -102.439978)
		(size 0.508)
		(drill 0.254)
		(layers "F.Cu" "B.Cu")
		(net "GND")
	)
	(via
		(at 279.974802 -306.824888)
		(size 0.4064)
		(drill 0.2032)
		(layers "F.Cu" "B.Cu")
		(net "GND")
	)
	(via
		(at 52.85232 -102.445058)
		(size 0.508)
		(drill 0.254)
		(layers "F.Cu" "B.Cu")
		(net "GND")
	)
	(via
		(at 187.620148 -57.076848)
		(size 0.508)
		(drill 0.254)
		(layers "F.Cu" "B.Cu")
		(net "GND")
	)
	(via
		(at 233.572558 -66.000122)
		(size 0.508)
		(drill 0.254)
		(layers "F.Cu" "B.Cu")
		(net "GND")
	)
	(via
		(at 108.142786 -223.093534)
		(size 0.508)
		(drill 0.254)
		(layers "F.Cu" "B.Cu")
		(net "GND")
	)
	(via
		(at 281.874722 -292.574726)
		(size 0.4064)
		(drill 0.2032)
		(layers "F.Cu" "B.Cu")
		(net "GND")
	)
	(via
		(at 168.20642 -343.073482)
		(size 0.4572)
		(drill 0.254)
		(layers "F.Cu" "B.Cu")
		(net "GND")
	)
	(via
		(at 257.882644 -341.610696)
		(size 0.508)
		(drill 0.254)
		(layers "F.Cu" "B.Cu")
		(net "GND")
	)
	(via
		(at 177.748946 -33.19018)
		(size 0.508)
		(drill 0.254)
		(layers "F.Cu" "B.Cu")
		(net "GND")
	)
	(via
		(at 438.13222 -124.743972)
		(size 0.508)
		(drill 0.254)
		(layers "F.Cu" "B.Cu")
		(net "GND")
	)
	(via
		(at 396.84579 -156.0576)
		(size 0.508)
		(drill 0.254)
		(layers "F.Cu" "B.Cu")
		(net "GND")
	)
	(via
		(at 97.032318 -393.1158)
		(size 0.508)
		(drill 0.254)
		(layers "F.Cu" "B.Cu")
		(net "GND")
	)
	(via
		(at 40.598344 -253.45644)
		(size 0.508)
		(drill 0.254)
		(layers "F.Cu" "B.Cu")
		(net "GND")
	)
	(via
		(at 169.099992 -274.049744)
		(size 0.4064)
		(drill 0.2032)
		(layers "F.Cu" "B.Cu")
		(net "GND")
	)
	(via
		(at 415.96691 -154.755088)
		(size 0.508)
		(drill 0.254)
		(layers "F.Cu" "B.Cu")
		(net "GND")
	)
	(via
		(at 190.348108 -156.554932)
		(size 0.508)
		(drill 0.254)
		(layers "F.Cu" "B.Cu")
		(net "GND")
	)
	(via
		(at 179.163472 -351.611438)
		(size 0.4064)
		(drill 0.2032)
		(layers "F.Cu" "B.Cu")
		(net "GND")
	)
	(via
		(at 274.749768 -304.449734)
		(size 0.4064)
		(drill 0.2032)
		(layers "F.Cu" "B.Cu")
		(net "GND")
	)
	(via
		(at 414.599882 -313.949842)
		(size 0.4064)
		(drill 0.2032)
		(layers "F.Cu" "B.Cu")
		(net "GND")
	)
	(via
		(at 429.927766 -385.141978)
		(size 0.508)
		(drill 0.254)
		(layers "F.Cu" "B.Cu")
		(net "GND")
	)
	(via
		(at 193.799968 -302.549814)
		(size 0.4064)
		(drill 0.2032)
		(layers "F.Cu" "B.Cu")
		(net "GND")
	)
	(via
		(at 161.15157 -111.44504)
		(size 0.508)
		(drill 0.254)
		(layers "F.Cu" "B.Cu")
		(net "GND")
	)
	(via
		(at 88.48725 -81.860136)
		(size 0.508)
		(drill 0.254)
		(layers "F.Cu" "B.Cu")
		(net "GND")
	)
	(via
		(at 14.533372 -285.462218)
		(size 0.508)
		(drill 0.254)
		(layers "F.Cu" "B.Cu")
		(net "GND")
	)
	(via
		(at 355.707188 -282.910788)
		(size 0.49022)
		(drill 0.254)
		(layers "F.Cu" "B.Cu")
		(net "GND")
	)
	(via
		(at 291.092382 -357.75773)
		(size 0.4064)
		(drill 0.2032)
		(layers "F.Cu" "B.Cu")
		(net "GND")
	)
	(via
		(at 54.424834 -287.824926)
		(size 0.4064)
		(drill 0.2032)
		(layers "F.Cu" "B.Cu")
		(net "GND")
	)
	(via
		(at 44.006516 -355.366066)
		(size 0.4572)
		(drill 0.254)
		(layers "F.Cu" "B.Cu")
		(net "GND")
	)
	(via
		(at 115.179602 -94.156276)
		(size 0.508)
		(drill 0.254)
		(layers "F.Cu" "B.Cu")
		(net "GND")
	)
	(via
		(at 292.79977 -317.749936)
		(size 0.4064)
		(drill 0.2032)
		(layers "F.Cu" "B.Cu")
		(net "GND")
	)
	(via
		(at 78.349602 -345.465146)
		(size 0.4064)
		(drill 0.2032)
		(layers "F.Cu" "B.Cu")
		(net "GND")
	)
	(via
		(at 151.859488 -112.981994)
		(size 0.508)
		(drill 0.254)
		(layers "F.Cu" "B.Cu")
		(net "GND")
	)
	(via
		(at 385.149852 -312.999882)
		(size 0.4064)
		(drill 0.2032)
		(layers "F.Cu" "B.Cu")
		(net "GND")
	)
	(via
		(at 360.170476 -290.68649)
		(size 0.508)
		(drill 0.254)
		(layers "F.Cu" "B.Cu")
		(net "GND")
	)
	(via
		(at 164.349938 -311.099962)
		(size 0.4064)
		(drill 0.2032)
		(layers "F.Cu" "B.Cu")
		(net "GND")
	)
	(via
		(at 246.976392 -285.445962)
		(size 0.508)
		(drill 0.254)
		(layers "F.Cu" "B.Cu")
		(net "GND")
	)
	(via
		(at 429.325024 -299.224954)
		(size 0.4064)
		(drill 0.2032)
		(layers "F.Cu" "B.Cu")
		(net "GND")
	)
	(via
		(at 125.35916 -343.073482)
		(size 0.4572)
		(drill 0.254)
		(layers "F.Cu" "B.Cu")
		(net "GND")
	)
	(via
		(at 133.585712 -63.218314)
		(size 0.508)
		(drill 0.254)
		(layers "F.Cu" "B.Cu")
		(net "GND")
	)
	(via
		(at 44.94784 -404.940262)
		(size 0.508)
		(drill 0.254)
		(layers "F.Cu" "B.Cu")
		(net "GND")
	)
	(via
		(at 177.174906 -300.174914)
		(size 0.4064)
		(drill 0.2032)
		(layers "F.Cu" "B.Cu")
		(net "GND")
	)
	(via
		(at 70.671182 -28.05303)
		(size 0.508)
		(drill 0.254)
		(layers "F.Cu" "B.Cu")
		(net "GND")
	)
	(via
		(at 144.01292 -347.951806)
		(size 0.4572)
		(drill 0.254)
		(layers "F.Cu" "B.Cu")
		(net "GND")
	)
	(via
		(at 61.17463 -341.805514)
		(size 0.4572)
		(drill 0.254)
		(layers "F.Cu" "B.Cu")
		(net "GND")
	)
	(via
		(at 125.74905 -31.390082)
		(size 0.508)
		(drill 0.254)
		(layers "F.Cu" "B.Cu")
		(net "GND")
	)
	(via
		(at 373.657622 -29.784294)
		(size 0.508)
		(drill 0.254)
		(layers "F.Cu" "B.Cu")
		(net "GND")
	)
	(via
		(at 346.327984 -404.838662)
		(size 0.508)
		(drill 0.254)
		(layers "F.Cu" "B.Cu")
		(net "GND")
	)
	(via
		(at 130.34899 -31.390082)
		(size 0.508)
		(drill 0.254)
		(layers "F.Cu" "B.Cu")
		(net "GND")
	)
	(via
		(at 71.347838 -376.241818)
		(size 0.508)
		(drill 0.254)
		(layers "F.Cu" "B.Cu")
		(net "GND")
	)
	(via
		(at 69.926708 -136.061958)
		(size 0.508)
		(drill 0.254)
		(layers "F.Cu" "B.Cu")
		(net "GND")
	)
	(via
		(at 73.547732 -404.838662)
		(size 0.508)
		(drill 0.254)
		(layers "F.Cu" "B.Cu")
		(net "GND")
	)
	(via
		(at 168.952164 -137.16508)
		(size 0.508)
		(drill 0.254)
		(layers "F.Cu" "B.Cu")
		(net "GND")
	)
	(via
		(at 74.248264 -154.755088)
		(size 0.508)
		(drill 0.254)
		(layers "F.Cu" "B.Cu")
		(net "GND")
	)
	(via
		(at 140.90396 -341.781638)
		(size 0.4572)
		(drill 0.254)
		(layers "F.Cu" "B.Cu")
		(net "GND")
	)
	(via
		(at 126.347728 -400.938492)
		(size 0.508)
		(drill 0.254)
		(layers "F.Cu" "B.Cu")
		(net "GND")
	)
	(via
		(at 384.556 -246.059706)
		(size 0.508)
		(drill 0.254)
		(layers "F.Cu" "B.Cu")
		(net "GND")
	)
	(via
		(at 293.749476 -272.14957)
		(size 0.4064)
		(drill 0.2032)
		(layers "F.Cu" "B.Cu")
		(net "GND")
	)
	(via
		(at 67.66687 -121.83491)
		(size 0.508)
		(drill 0.254)
		(layers "F.Cu" "B.Cu")
		(net "GND")
	)
	(via
		(at 122.621548 -348.58579)
		(size 0.4064)
		(drill 0.2032)
		(layers "F.Cu" "B.Cu")
		(net "GND")
	)
	(via
		(at 381.576072 -346.09913)
		(size 0.4572)
		(drill 0.254)
		(layers "F.Cu" "B.Cu")
		(net "GND")
	)
	(via
		(at 194.89674 -406.187656)
		(size 0.508)
		(drill 0.254)
		(layers "F.Cu" "B.Cu")
		(net "GND")
	)
	(via
		(at 417.924996 -303.974754)
		(size 0.4064)
		(drill 0.2032)
		(layers "F.Cu" "B.Cu")
		(net "GND")
	)
	(via
		(at 20.39366 -352.245422)
		(size 0.4572)
		(drill 0.254)
		(layers "F.Cu" "B.Cu")
		(net "GND")
	)
	(via
		(at 119.14124 -350.977454)
		(size 0.4572)
		(drill 0.254)
		(layers "F.Cu" "B.Cu")
		(net "GND")
	)
	(via
		(at 29.72054 -349.219774)
		(size 0.4572)
		(drill 0.254)
		(layers "F.Cu" "B.Cu")
		(net "GND")
	)
	(via
		(at 51.574954 -297.32478)
		(size 0.4064)
		(drill 0.2032)
		(layers "F.Cu" "B.Cu")
		(net "GND")
	)
	(via
		(at 382.75514 -33.19018)
		(size 0.508)
		(drill 0.254)
		(layers "F.Cu" "B.Cu")
		(net "GND")
	)
	(via
		(at 446.57391 -73.85177)
		(size 0.508)
		(drill 0.254)
		(layers "F.Cu" "B.Cu")
		(net "GND")
	)
	(via
		(at 288.049716 -312.049922)
		(size 0.4064)
		(drill 0.2032)
		(layers "F.Cu" "B.Cu")
		(net "GND")
	)
	(via
		(at 427.900084 -273.099784)
		(size 0.4064)
		(drill 0.2032)
		(layers "F.Cu" "B.Cu")
		(net "GND")
	)
	(via
		(at 176.054512 -357.75773)
		(size 0.4064)
		(drill 0.2032)
		(layers "F.Cu" "B.Cu")
		(net "GND")
	)
	(via
		(at 419.824916 -301.124874)
		(size 0.4064)
		(drill 0.2032)
		(layers "F.Cu" "B.Cu")
		(net "GND")
	)
	(via
		(at 106.078274 -285.953454)
		(size 0.508)
		(drill 0.254)
		(layers "F.Cu" "B.Cu")
		(net "GND")
	)
	(via
		(at 257.382772 -84.63026)
		(size 0.508)
		(drill 0.254)
		(layers "F.Cu" "B.Cu")
		(net "GND")
	)
	(via
		(at 387.525006 -272.624804)
		(size 0.4064)
		(drill 0.2032)
		(layers "F.Cu" "B.Cu")
		(net "GND")
	)
	(via
		(at 162.450018 -316.799722)
		(size 0.4064)
		(drill 0.2032)
		(layers "F.Cu" "B.Cu")
		(net "GND")
	)
	(via
		(at 239.952276 -89.456768)
		(size 0.508)
		(drill 0.254)
		(layers "F.Cu" "B.Cu")
		(net "GND")
	)
	(via
		(at 293.27475 -306.824888)
		(size 0.4064)
		(drill 0.2032)
		(layers "F.Cu" "B.Cu")
		(net "GND")
	)
	(via
		(at 110.668562 -77.969364)
		(size 0.508)
		(drill 0.254)
		(layers "F.Cu" "B.Cu")
		(net "GND")
	)
	(via
		(at 107.425236 -305.008534)
		(size 0.508)
		(drill 0.254)
		(layers "F.Cu" "B.Cu")
		(net "GND")
	)
	(via
		(at 193.799968 -278.799798)
		(size 0.4064)
		(drill 0.2032)
		(layers "F.Cu" "B.Cu")
		(net "GND")
	)
	(via
		(at 416.945572 -354.732082)
		(size 0.4064)
		(drill 0.2032)
		(layers "F.Cu" "B.Cu")
		(net "GND")
	)
	(via
		(at 87.05215 -13.613638)
		(size 0.508)
		(drill 0.254)
		(layers "F.Cu" "B.Cu")
		(net "GND")
	)
	(via
		(at 382.791716 -104.523286)
		(size 0.508)
		(drill 0.254)
		(layers "F.Cu" "B.Cu")
		(net "GND")
	)
	(via
		(at 380.002288 -241.311176)
		(size 0.508)
		(drill 0.254)
		(layers "F.Cu" "B.Cu")
		(net "GND")
	)
	(via
		(at 294.22471 -287.824926)
		(size 0.4064)
		(drill 0.2032)
		(layers "F.Cu" "B.Cu")
		(net "GND")
	)
	(via
		(at 68.674742 -285.924752)
		(size 0.4064)
		(drill 0.2032)
		(layers "F.Cu" "B.Cu")
		(net "GND")
	)
	(via
		(at 81.974944 -297.32478)
		(size 0.4064)
		(drill 0.2032)
		(layers "F.Cu" "B.Cu")
		(net "GND")
	)
	(via
		(at 57.749948 -281.649932)
		(size 0.4064)
		(drill 0.2032)
		(layers "F.Cu" "B.Cu")
		(net "GND")
	)
	(via
		(at 3.455924 -375.083578)
		(size 0.508)
		(drill 0.254)
		(layers "F.Cu" "B.Cu")
		(net "GND")
	)
	(via
		(at 279.66416 -142.41145)
		(size 0.508)
		(drill 0.254)
		(layers "F.Cu" "B.Cu")
		(net "GND")
	)
	(via
		(at 307.999892 -303.499774)
		(size 0.4064)
		(drill 0.2032)
		(layers "F.Cu" "B.Cu")
		(net "GND")
	)
	(via
		(at 56.799988 -318.699896)
		(size 0.4064)
		(drill 0.2032)
		(layers "F.Cu" "B.Cu")
		(net "GND")
	)
	(via
		(at 51.099974 -310.149748)
		(size 0.4064)
		(drill 0.2032)
		(layers "F.Cu" "B.Cu")
		(net "GND")
	)
	(via
		(at 352.009964 -287.51149)
		(size 0.508)
		(drill 0.254)
		(layers "F.Cu" "B.Cu")
		(net "GND")
	)
	(via
		(at 282.448 -417.82492)
		(size 0.508)
		(drill 0.254)
		(layers "F.Cu" "B.Cu")
		(net "GND")
	)
	(via
		(at 14.214856 -26.171398)
		(size 0.508)
		(drill 0.254)
		(layers "F.Cu" "B.Cu")
		(net "GND")
	)
	(via
		(at 266.020042 -31.390336)
		(size 0.508)
		(drill 0.254)
		(layers "F.Cu" "B.Cu")
		(net "GND")
	)
	(via
		(at 64.59347 -134.845044)
		(size 0.508)
		(drill 0.254)
		(layers "F.Cu" "B.Cu")
		(net "GND")
	)
	(via
		(at 315.042804 -354.732082)
		(size 0.4064)
		(drill 0.2032)
		(layers "F.Cu" "B.Cu")
		(net "GND")
	)
	(via
		(at 22.37232 -26.315162)
		(size 0.508)
		(drill 0.254)
		(layers "F.Cu" "B.Cu")
		(net "GND")
	)
	(via
		(at 177.174906 -289.724846)
		(size 0.4064)
		(drill 0.2032)
		(layers "F.Cu" "B.Cu")
		(net "GND")
	)
	(via
		(at 386.16382 -342.439498)
		(size 0.4064)
		(drill 0.2032)
		(layers "F.Cu" "B.Cu")
		(net "GND")
	)
	(via
		(at 43.561254 -60.099194)
		(size 0.508)
		(drill 0.254)
		(layers "F.Cu" "B.Cu")
		(net "GND")
	)
	(via
		(at 159.347916 -408.840178)
		(size 0.508)
		(drill 0.254)
		(layers "F.Cu" "B.Cu")
		(net "GND")
	)
	(via
		(at 63.744856 -27.79014)
		(size 0.508)
		(drill 0.254)
		(layers "F.Cu" "B.Cu")
		(net "GND")
	)
	(via
		(at 332.781148 -33.459674)
		(size 0.508)
		(drill 0.254)
		(layers "F.Cu" "B.Cu")
		(net "GND")
	)
	(via
		(at 131.778248 -169.130218)
		(size 0.508)
		(drill 0.254)
		(layers "F.Cu" "B.Cu")
		(net "GND")
	)
	(via
		(at 359.535476 -291.32149)
		(size 0.508)
		(drill 0.254)
		(layers "F.Cu" "B.Cu")
		(net "GND")
	)
	(via
		(at 418.42055 -63.218314)
		(size 0.508)
		(drill 0.254)
		(layers "F.Cu" "B.Cu")
		(net "GND")
	)
	(via
		(at 12.24153 -383.864866)
		(size 0.508)
		(drill 0.254)
		(layers "F.Cu" "B.Cu")
		(net "GND")
	)
	(via
		(at 396.84579 -153.0096)
		(size 0.508)
		(drill 0.254)
		(layers "F.Cu" "B.Cu")
		(net "GND")
	)
	(via
		(at 300.874684 -292.574726)
		(size 0.4064)
		(drill 0.2032)
		(layers "F.Cu" "B.Cu")
		(net "GND")
	)
	(via
		(at 107.630214 -330.22921)
		(size 0.508)
		(drill 0.254)
		(layers "F.Cu" "B.Cu")
		(net "GND")
	)
	(via
		(at 187.624974 -292.574726)
		(size 0.4064)
		(drill 0.2032)
		(layers "F.Cu" "B.Cu")
		(net "GND")
	)
	(via
		(at 144.384268 -348.58579)
		(size 0.4064)
		(drill 0.2032)
		(layers "F.Cu" "B.Cu")
		(net "GND")
	)
	(via
		(at 293.27475 -287.824926)
		(size 0.4064)
		(drill 0.2032)
		(layers "F.Cu" "B.Cu")
		(net "GND")
	)
	(via
		(at 259.52323 -55.083456)
		(size 0.508)
		(drill 0.254)
		(layers "F.Cu" "B.Cu")
		(net "GND")
	)
	(via
		(at 288.049716 -310.149748)
		(size 0.4064)
		(drill 0.2032)
		(layers "F.Cu" "B.Cu")
		(net "GND")
	)
	(via
		(at 277.02637 -355.366066)
		(size 0.4572)
		(drill 0.254)
		(layers "F.Cu" "B.Cu")
		(net "GND")
	)
	(via
		(at 423.32783 -369.938554)
		(size 0.508)
		(drill 0.254)
		(layers "F.Cu" "B.Cu")
		(net "GND")
	)
	(via
		(at 206.548228 -216.6112)
		(size 0.508)
		(drill 0.254)
		(layers "F.Cu" "B.Cu")
		(net "GND")
	)
	(via
		(at 400.824954 -300.174914)
		(size 0.4064)
		(drill 0.2032)
		(layers "F.Cu" "B.Cu")
		(net "GND")
	)
	(via
		(at 56.70169 -382.71958)
		(size 0.508)
		(drill 0.254)
		(layers "F.Cu" "B.Cu")
		(net "GND")
	)
	(via
		(at 292.65499 -33.19018)
		(size 0.508)
		(drill 0.254)
		(layers "F.Cu" "B.Cu")
		(net "GND")
	)
	(via
		(at 127.650748 -293.424102)
		(size 0.508)
		(drill 0.254)
		(layers "F.Cu" "B.Cu")
		(net "GND")
	)
	(via
		(at 120.661684 -225.031808)
		(size 0.508)
		(drill 0.254)
		(layers "F.Cu" "B.Cu")
		(net "GND")
	)
	(via
		(at 120.991376 -341.805514)
		(size 0.4572)
		(drill 0.254)
		(layers "F.Cu" "B.Cu")
		(net "GND")
	)
	(via
		(at 291.32784 -377.738386)
		(size 0.508)
		(drill 0.254)
		(layers "F.Cu" "B.Cu")
		(net "GND")
	)
	(via
		(at 410.324808 -294.4749)
		(size 0.4064)
		(drill 0.2032)
		(layers "F.Cu" "B.Cu")
		(net "GND")
	)
	(via
		(at 376.83694 -357.75773)
		(size 0.4064)
		(drill 0.2032)
		(layers "F.Cu" "B.Cu")
		(net "GND")
	)
	(via
		(at 98.922332 -346.828364)
		(size 0.508)
		(drill 0.254)
		(layers "F.Cu" "B.Cu")
		(net "GND")
	)
	(via
		(at 103.7082 -191.893698)
		(size 0.508)
		(drill 0.254)
		(layers "F.Cu" "B.Cu")
		(net "GND")
	)
	(via
		(at 312.749692 -279.749758)
		(size 0.4064)
		(drill 0.2032)
		(layers "F.Cu" "B.Cu")
		(net "GND")
	)
	(via
		(at 345.024964 -342.439498)
		(size 0.4064)
		(drill 0.2032)
		(layers "F.Cu" "B.Cu")
		(net "GND")
	)
	(via
		(at 68.5038 -224.6884)
		(size 0.508)
		(drill 0.254)
		(layers "F.Cu" "B.Cu")
		(net "GND")
	)
	(via
		(at 281.874722 -303.024794)
		(size 0.4064)
		(drill 0.2032)
		(layers "F.Cu" "B.Cu")
		(net "GND")
	)
	(via
		(at 341.544656 -349.219774)
		(size 0.4572)
		(drill 0.254)
		(layers "F.Cu" "B.Cu")
		(net "GND")
	)
	(via
		(at 420.23919 -32.911796)
		(size 0.508)
		(drill 0.254)
		(layers "F.Cu" "B.Cu")
		(net "GND")
	)
	(via
		(at 315.740288 -149.083522)
		(size 0.508)
		(drill 0.254)
		(layers "F.Cu" "B.Cu")
		(net "GND")
	)
	(via
		(at 0.766318 -67.252342)
		(size 0.508)
		(drill 0.254)
		(layers "F.Cu" "B.Cu")
		(net "GND")
	)
	(via
		(at 334.214724 -107.681776)
		(size 0.508)
		(drill 0.254)
		(layers "F.Cu" "B.Cu")
		(net "GND")
	)
	(via
		(at 178.792124 -349.219774)
		(size 0.4572)
		(drill 0.254)
		(layers "F.Cu" "B.Cu")
		(net "GND")
	)
	(via
		(at 337.176872 -358.391714)
		(size 0.4572)
		(drill 0.254)
		(layers "F.Cu" "B.Cu")
		(net "GND")
	)
	(via
		(at 174.42434 -350.977454)
		(size 0.4572)
		(drill 0.254)
		(layers "F.Cu" "B.Cu")
		(net "GND")
	)
	(via
		(at 290.89985 -318.699896)
		(size 0.4064)
		(drill 0.2032)
		(layers "F.Cu" "B.Cu")
		(net "GND")
	)
	(via
		(at 151.999696 -304.449988)
		(size 0.4064)
		(drill 0.2032)
		(layers "F.Cu" "B.Cu")
		(net "GND")
	)
	(via
		(at 293.527734 -411.141926)
		(size 0.508)
		(drill 0.254)
		(layers "F.Cu" "B.Cu")
		(net "GND")
	)
	(via
		(at 286.927798 -375.040144)
		(size 0.508)
		(drill 0.254)
		(layers "F.Cu" "B.Cu")
		(net "GND")
	)
	(via
		(at 325.265542 -303.026826)
		(size 0.508)
		(drill 0.254)
		(layers "F.Cu" "B.Cu")
		(net "GND")
	)
	(via
		(at 81.087214 -343.073482)
		(size 0.4572)
		(drill 0.254)
		(layers "F.Cu" "B.Cu")
		(net "GND")
	)
	(via
		(at 266.202922 -293.494714)
		(size 0.508)
		(drill 0.254)
		(layers "F.Cu" "B.Cu")
		(net "GND")
	)
	(via
		(at 269.772892 -156.3624)
		(size 0.508)
		(drill 0.254)
		(layers "F.Cu" "B.Cu")
		(net "GND")
	)
	(via
		(at 76.71943 -349.219774)
		(size 0.4572)
		(drill 0.254)
		(layers "F.Cu" "B.Cu")
		(net "GND")
	)
	(via
		(at 161.500058 -309.199788)
		(size 0.4064)
		(drill 0.2032)
		(layers "F.Cu" "B.Cu")
		(net "GND")
	)
	(via
		(at 396.0749 -303.024794)
		(size 0.4064)
		(drill 0.2032)
		(layers "F.Cu" "B.Cu")
		(net "GND")
	)
	(via
		(at 338.807044 -345.465146)
		(size 0.4064)
		(drill 0.2032)
		(layers "F.Cu" "B.Cu")
		(net "GND")
	)
	(via
		(at 144.441926 -25.971246)
		(size 0.508)
		(drill 0.254)
		(layers "F.Cu" "B.Cu")
		(net "GND")
	)
	(via
		(at 259.144516 -24.655272)
		(size 0.508)
		(drill 0.254)
		(layers "F.Cu" "B.Cu")
		(net "GND")
	)
	(via
		(at 61.074808 -302.074834)
		(size 0.4064)
		(drill 0.2032)
		(layers "F.Cu" "B.Cu")
		(net "GND")
	)
	(via
		(at 52.425092 -14.100302)
		(size 0.508)
		(drill 0.254)
		(layers "F.Cu" "B.Cu")
		(net "GND")
	)
	(via
		(at 390.374886 -281.174952)
		(size 0.4064)
		(drill 0.2032)
		(layers "F.Cu" "B.Cu")
		(net "GND")
	)
	(via
		(at 161.15157 -104.244902)
		(size 0.508)
		(drill 0.254)
		(layers "F.Cu" "B.Cu")
		(net "GND")
	)
	(via
		(at 18.763488 -351.611438)
		(size 0.4064)
		(drill 0.2032)
		(layers "F.Cu" "B.Cu")
		(net "GND")
	)
	(via
		(at 186.675014 -290.674806)
		(size 0.4064)
		(drill 0.2032)
		(layers "F.Cu" "B.Cu")
		(net "GND")
	)
	(via
		(at 178.483514 -194.683634)
		(size 0.508)
		(drill 0.254)
		(layers "F.Cu" "B.Cu")
		(net "GND")
	)
	(via
		(at 286.35325 -354.098098)
		(size 0.4572)
		(drill 0.254)
		(layers "F.Cu" "B.Cu")
		(net "GND")
	)
	(via
		(at 288.99993 -273.099784)
		(size 0.4064)
		(drill 0.2032)
		(layers "F.Cu" "B.Cu")
		(net "GND")
	)
	(via
		(at 104.178608 -358.375712)
		(size 0.508)
		(drill 0.254)
		(layers "F.Cu" "B.Cu")
		(net "GND")
	)
	(via
		(at 128.764284 -285.953454)
		(size 0.508)
		(drill 0.254)
		(layers "F.Cu" "B.Cu")
		(net "GND")
	)
	(via
		(at 312.274712 -288.774886)
		(size 0.4064)
		(drill 0.2032)
		(layers "F.Cu" "B.Cu")
		(net "GND")
	)
	(via
		(at 64.28359 -347.92793)
		(size 0.4572)
		(drill 0.254)
		(layers "F.Cu" "B.Cu")
		(net "GND")
	)
	(via
		(at 176.224946 -305.874928)
		(size 0.4064)
		(drill 0.2032)
		(layers "F.Cu" "B.Cu")
		(net "GND")
	)
	(via
		(at 365.190278 -113.589054)
		(size 0.508)
		(drill 0.254)
		(layers "F.Cu" "B.Cu")
		(net "GND")
	)
	(via
		(at 330.927964 -381.638556)
		(size 0.508)
		(drill 0.254)
		(layers "F.Cu" "B.Cu")
		(net "GND")
	)
	(via
		(at 324.741032 -341.805514)
		(size 0.4572)
		(drill 0.254)
		(layers "F.Cu" "B.Cu")
		(net "GND")
	)
	(via
		(at 44.94784 -384.042158)
		(size 0.508)
		(drill 0.254)
		(layers "F.Cu" "B.Cu")
		(net "GND")
	)
	(via
		(at 42.527728 -357.75773)
		(size 0.4064)
		(drill 0.2032)
		(layers "F.Cu" "B.Cu")
		(net "GND")
	)
	(via
		(at 280.964894 -98.845116)
		(size 0.508)
		(drill 0.254)
		(layers "F.Cu" "B.Cu")
		(net "GND")
	)
	(via
		(at 80.147922 -397.140176)
		(size 0.508)
		(drill 0.254)
		(layers "F.Cu" "B.Cu")
		(net "GND")
	)
	(via
		(at 301.824898 -285.924752)
		(size 0.4064)
		(drill 0.2032)
		(layers "F.Cu" "B.Cu")
		(net "GND")
	)
	(via
		(at 47.464218 -142.41145)
		(size 0.508)
		(drill 0.254)
		(layers "F.Cu" "B.Cu")
		(net "GND")
	)
	(via
		(at 427.727872 -384.041904)
		(size 0.508)
		(drill 0.254)
		(layers "F.Cu" "B.Cu")
		(net "GND")
	)
	(via
		(at 195.699888 -289.249866)
		(size 0.4064)
		(drill 0.2032)
		(layers "F.Cu" "B.Cu")
		(net "GND")
	)
	(via
		(at 282.349956 -319.65011)
		(size 0.4064)
		(drill 0.2032)
		(layers "F.Cu" "B.Cu")
		(net "GND")
	)
	(via
		(at 401.774914 -289.724846)
		(size 0.4064)
		(drill 0.2032)
		(layers "F.Cu" "B.Cu")
		(net "GND")
	)
	(via
		(at 298.974764 -298.27474)
		(size 0.4064)
		(drill 0.2032)
		(layers "F.Cu" "B.Cu")
		(net "GND")
	)
	(via
		(at 190.474854 -290.674806)
		(size 0.4064)
		(drill 0.2032)
		(layers "F.Cu" "B.Cu")
		(net "GND")
	)
	(via
		(at 278.549862 -279.749758)
		(size 0.4064)
		(drill 0.2032)
		(layers "F.Cu" "B.Cu")
		(net "GND")
	)
	(via
		(at 407.949908 -315.849762)
		(size 0.4064)
		(drill 0.2032)
		(layers "F.Cu" "B.Cu")
		(net "GND")
	)
	(via
		(at 137.892282 -70.918832)
		(size 0.508)
		(drill 0.254)
		(layers "F.Cu" "B.Cu")
		(net "GND")
	)
	(via
		(at 135.505444 -168.669208)
		(size 0.508)
		(drill 0.254)
		(layers "F.Cu" "B.Cu")
		(net "GND")
	)
	(via
		(at 117.636036 -218.237562)
		(size 0.508)
		(drill 0.254)
		(layers "F.Cu" "B.Cu")
		(net "GND")
	)
	(via
		(at 173.850046 -280.699718)
		(size 0.4064)
		(drill 0.2032)
		(layers "F.Cu" "B.Cu")
		(net "GND")
	)
	(via
		(at 189.999874 -281.649932)
		(size 0.4064)
		(drill 0.2032)
		(layers "F.Cu" "B.Cu")
		(net "GND")
	)
	(via
		(at 230.726234 -285.445962)
		(size 0.508)
		(drill 0.254)
		(layers "F.Cu" "B.Cu")
		(net "GND")
	)
	(via
		(at 89.83218 -124.108972)
		(size 0.508)
		(drill 0.254)
		(layers "F.Cu" "B.Cu")
		(net "GND")
	)
	(via
		(at 133.945884 -231.510332)
		(size 0.508)
		(drill 0.254)
		(layers "F.Cu" "B.Cu")
		(net "GND")
	)
	(via
		(at 192.628774 -100.429314)
		(size 0.508)
		(drill 0.254)
		(layers "F.Cu" "B.Cu")
		(net "GND")
	)
	(via
		(at 392.274806 -291.624766)
		(size 0.4064)
		(drill 0.2032)
		(layers "F.Cu" "B.Cu")
		(net "GND")
	)
	(via
		(at 164.349938 -281.649932)
		(size 0.4064)
		(drill 0.2032)
		(layers "F.Cu" "B.Cu")
		(net "GND")
	)
	(via
		(at 429.381412 -342.439498)
		(size 0.4064)
		(drill 0.2032)
		(layers "F.Cu" "B.Cu")
		(net "GND")
	)
	(via
		(at 78.551532 -99.037648)
		(size 0.508)
		(drill 0.254)
		(layers "F.Cu" "B.Cu")
		(net "GND")
	)
	(via
		(at 176.699926 -276.899878)
		(size 0.4064)
		(drill 0.2032)
		(layers "F.Cu" "B.Cu")
		(net "GND")
	)
	(via
		(at 351.293684 -228.386894)
		(size 0.4572)
		(drill 0.254)
		(layers "F.Cu" "B.Cu")
		(net "GND")
	)
	(via
		(at 403.674834 -302.074834)
		(size 0.4064)
		(drill 0.2032)
		(layers "F.Cu" "B.Cu")
		(net "GND")
	)
	(via
		(at 416.945572 -357.75773)
		(size 0.4064)
		(drill 0.2032)
		(layers "F.Cu" "B.Cu")
		(net "GND")
	)
	(via
		(at 315.414152 -354.074222)
		(size 0.4572)
		(drill 0.254)
		(layers "F.Cu" "B.Cu")
		(net "GND")
	)
	(via
		(at 40.897556 -343.073482)
		(size 0.4572)
		(drill 0.254)
		(layers "F.Cu" "B.Cu")
		(net "GND")
	)
	(via
		(at 419.349936 -275.949918)
		(size 0.4064)
		(drill 0.2032)
		(layers "F.Cu" "B.Cu")
		(net "GND")
	)
	(via
		(at 210.662774 -88.401144)
		(size 0.508)
		(drill 0.254)
		(layers "F.Cu" "B.Cu")
		(net "GND")
	)
	(via
		(at 126.749048 -177.754026)
		(size 0.508)
		(drill 0.254)
		(layers "F.Cu" "B.Cu")
		(net "GND")
	)
	(via
		(at 227.734368 -93.057726)
		(size 0.508)
		(drill 0.254)
		(layers "F.Cu" "B.Cu")
		(net "GND")
	)
	(via
		(at 279.29205 -104.793034)
		(size 0.508)
		(drill 0.254)
		(layers "F.Cu" "B.Cu")
		(net "GND")
	)
	(via
		(at 378.467112 -344.831162)
		(size 0.4572)
		(drill 0.254)
		(layers "F.Cu" "B.Cu")
		(net "GND")
	)
	(via
		(at 189.999874 -284.499812)
		(size 0.4064)
		(drill 0.2032)
		(layers "F.Cu" "B.Cu")
		(net "GND")
	)
	(via
		(at 374.099328 -341.805514)
		(size 0.4572)
		(drill 0.254)
		(layers "F.Cu" "B.Cu")
		(net "GND")
	)
	(via
		(at 332.589124 -357.75773)
		(size 0.4064)
		(drill 0.2032)
		(layers "F.Cu" "B.Cu")
		(net "GND")
	)
	(via
		(at 176.94783 -377.73864)
		(size 0.508)
		(drill 0.254)
		(layers "F.Cu" "B.Cu")
		(net "GND")
	)
	(via
		(at 181.912514 -154.755088)
		(size 0.508)
		(drill 0.254)
		(layers "F.Cu" "B.Cu")
		(net "GND")
	)
	(via
		(at 415.3154 -341.805514)
		(size 0.4572)
		(drill 0.254)
		(layers "F.Cu" "B.Cu")
		(net "GND")
	)
	(via
		(at 286.927798 -381.638556)
		(size 0.508)
		(drill 0.254)
		(layers "F.Cu" "B.Cu")
		(net "GND")
	)
	(via
		(at 210.657948 -57.521094)
		(size 0.508)
		(drill 0.254)
		(layers "F.Cu" "B.Cu")
		(net "GND")
	)
	(via
		(at 395.59992 -317.749936)
		(size 0.4064)
		(drill 0.2032)
		(layers "F.Cu" "B.Cu")
		(net "GND")
	)
	(via
		(at 293.829994 -357.123746)
		(size 0.4572)
		(drill 0.254)
		(layers "F.Cu" "B.Cu")
		(net "GND")
	)
	(via
		(at 402.724874 -285.924752)
		(size 0.4064)
		(drill 0.2032)
		(layers "F.Cu" "B.Cu")
		(net "GND")
	)
	(via
		(at 129.946908 -357.75773)
		(size 0.4064)
		(drill 0.2032)
		(layers "F.Cu" "B.Cu")
		(net "GND")
	)
	(via
		(at 82.347816 -382.73863)
		(size 0.508)
		(drill 0.254)
		(layers "F.Cu" "B.Cu")
		(net "GND")
	)
	(via
		(at 414.11271 -151.155146)
		(size 0.508)
		(drill 0.254)
		(layers "F.Cu" "B.Cu")
		(net "GND")
	)
	(via
		(at 33.8201 -33.19018)
		(size 0.508)
		(drill 0.254)
		(layers "F.Cu" "B.Cu")
		(net "GND")
	)
	(via
		(at 459.651354 -278.492204)
		(size 0.508)
		(drill 0.254)
		(layers "F.Cu" "B.Cu")
		(net "GND")
	)
	(via
		(at 68.651374 -357.123746)
		(size 0.4572)
		(drill 0.254)
		(layers "F.Cu" "B.Cu")
		(net "GND")
	)
	(via
		(at 461.042512 -285.569406)
		(size 0.508)
		(drill 0.254)
		(layers "F.Cu" "B.Cu")
		(net "GND")
	)
	(via
		(at 210.657948 -58.156094)
		(size 0.508)
		(drill 0.254)
		(layers "F.Cu" "B.Cu")
		(net "GND")
	)
	(via
		(at 36.14801 -373.83847)
		(size 0.508)
		(drill 0.254)
		(layers "F.Cu" "B.Cu")
		(net "GND")
	)
	(via
		(at 389.424926 -290.674806)
		(size 0.4064)
		(drill 0.2032)
		(layers "F.Cu" "B.Cu")
		(net "GND")
	)
	(via
		(at 176.699926 -313.949842)
		(size 0.4064)
		(drill 0.2032)
		(layers "F.Cu" "B.Cu")
		(net "GND")
	)
	(via
		(at 78.64983 -280.699718)
		(size 0.4064)
		(drill 0.2032)
		(layers "F.Cu" "B.Cu")
		(net "GND")
	)
	(via
		(at 164.429694 -165.902894)
		(size 0.508)
		(drill 0.254)
		(layers "F.Cu" "B.Cu")
		(net "GND")
	)
	(via
		(at 49.67478 -305.874928)
		(size 0.4064)
		(drill 0.2032)
		(layers "F.Cu" "B.Cu")
		(net "GND")
	)
	(via
		(at 183.82488 -285.924752)
		(size 0.4064)
		(drill 0.2032)
		(layers "F.Cu" "B.Cu")
		(net "GND")
	)
	(via
		(at 64.28359 -346.09913)
		(size 0.4572)
		(drill 0.254)
		(layers "F.Cu" "B.Cu")
		(net "GND")
	)
	(via
		(at 385.927854 -374.938544)
		(size 0.508)
		(drill 0.254)
		(layers "F.Cu" "B.Cu")
		(net "GND")
	)
	(via
		(at 241.995452 -225.202496)
		(size 0.508)
		(drill 0.254)
		(layers "F.Cu" "B.Cu")
		(net "GND")
	)
	(via
		(at 27.340814 -219.766896)
		(size 0.508)
		(drill 0.254)
		(layers "F.Cu" "B.Cu")
		(net "GND")
	)
	(via
		(at 398.925034 -284.024832)
		(size 0.4064)
		(drill 0.2032)
		(layers "F.Cu" "B.Cu")
		(net "GND")
	)
	(via
		(at 330.331064 -211.339938)
		(size 0.508)
		(drill 0.254)
		(layers "F.Cu" "B.Cu")
		(net "GND")
	)
	(via
		(at 354.900992 -31.390336)
		(size 0.508)
		(drill 0.254)
		(layers "F.Cu" "B.Cu")
		(net "GND")
	)
	(via
		(at 223.679512 -232.471468)
		(size 0.508)
		(drill 0.254)
		(layers "F.Cu" "B.Cu")
		(net "GND")
	)
	(via
		(at 413.649922 -310.149748)
		(size 0.4064)
		(drill 0.2032)
		(layers "F.Cu" "B.Cu")
		(net "GND")
	)
	(via
		(at 271.977612 -257.112008)
		(size 0.508)
		(drill 0.254)
		(layers "F.Cu" "B.Cu")
		(net "GND")
	)
	(via
		(at 311.799732 -277.849838)
		(size 0.4064)
		(drill 0.2032)
		(layers "F.Cu" "B.Cu")
		(net "GND")
	)
	(via
		(at 385.624832 -290.674806)
		(size 0.4064)
		(drill 0.2032)
		(layers "F.Cu" "B.Cu")
		(net "GND")
	)
	(via
		(at 307.049678 -274.999958)
		(size 0.4064)
		(drill 0.2032)
		(layers "F.Cu" "B.Cu")
		(net "GND")
	)
	(via
		(at 97.032318 -395.1478)
		(size 0.508)
		(drill 0.254)
		(layers "F.Cu" "B.Cu")
		(net "GND")
	)
	(via
		(at 325.99757 -118.894352)
		(size 0.508)
		(drill 0.254)
		(layers "F.Cu" "B.Cu")
		(net "GND")
	)
	(via
		(at 432.12766 -398.34185)
		(size 0.508)
		(drill 0.254)
		(layers "F.Cu" "B.Cu")
		(net "GND")
	)
	(via
		(at 435.948836 -33.19018)
		(size 0.508)
		(drill 0.254)
		(layers "F.Cu" "B.Cu")
		(net "GND")
	)
	(via
		(at 260.757924 -292.732714)
		(size 0.508)
		(drill 0.254)
		(layers "F.Cu" "B.Cu")
		(net "GND")
	)
	(via
		(at 278.285194 -343.073482)
		(size 0.4572)
		(drill 0.254)
		(layers "F.Cu" "B.Cu")
		(net "GND")
	)
	(via
		(at 158.174944 -296.37482)
		(size 0.4064)
		(drill 0.2032)
		(layers "F.Cu" "B.Cu")
		(net "GND")
	)
	(via
		(at 66.44767 -154.755088)
		(size 0.508)
		(drill 0.254)
		(layers "F.Cu" "B.Cu")
		(net "GND")
	)
	(via
		(at 269.524988 -296.37482)
		(size 0.4064)
		(drill 0.2032)
		(layers "F.Cu" "B.Cu")
		(net "GND")
	)
	(via
		(at 256.542286 -253.5174)
		(size 0.508)
		(drill 0.254)
		(layers "F.Cu" "B.Cu")
		(net "GND")
	)
	(via
		(at 415.922206 -117.415056)
		(size 0.508)
		(drill 0.254)
		(layers "F.Cu" "B.Cu")
		(net "GND")
	)
	(via
		(at 322.032122 -124.108972)
		(size 0.508)
		(drill 0.254)
		(layers "F.Cu" "B.Cu")
		(net "GND")
	)
	(via
		(at 410.324808 -305.874928)
		(size 0.4064)
		(drill 0.2032)
		(layers "F.Cu" "B.Cu")
		(net "GND")
	)
	(via
		(at 306.099718 -287.349946)
		(size 0.4064)
		(drill 0.2032)
		(layers "F.Cu" "B.Cu")
		(net "GND")
	)
	(via
		(at 131.770374 -133.972046)
		(size 0.508)
		(drill 0.254)
		(layers "F.Cu" "B.Cu")
		(net "GND")
	)
	(via
		(at 198.473822 -25.971246)
		(size 0.508)
		(drill 0.254)
		(layers "F.Cu" "B.Cu")
		(net "GND")
	)
	(via
		(at 38.401752 -132.04317)
		(size 0.508)
		(drill 0.254)
		(layers "F.Cu" "B.Cu")
		(net "GND")
	)
	(via
		(at 417.924996 -305.874928)
		(size 0.4064)
		(drill 0.2032)
		(layers "F.Cu" "B.Cu")
		(net "GND")
	)
	(via
		(at 325.999856 -346.09913)
		(size 0.4572)
		(drill 0.254)
		(layers "F.Cu" "B.Cu")
		(net "GND")
	)
	(via
		(at 297.074844 -285.924752)
		(size 0.4064)
		(drill 0.2032)
		(layers "F.Cu" "B.Cu")
		(net "GND")
	)
	(via
		(at 221.392496 -308.181756)
		(size 0.508)
		(drill 0.254)
		(layers "F.Cu" "B.Cu")
		(net "GND")
	)
	(via
		(at 162.924998 -304.924714)
		(size 0.4064)
		(drill 0.2032)
		(layers "F.Cu" "B.Cu")
		(net "GND")
	)
	(via
		(at 252.255528 -78.979268)
		(size 0.508)
		(drill 0.254)
		(layers "F.Cu" "B.Cu")
		(net "GND")
	)
	(via
		(at 124.136912 -282.910788)
		(size 0.49022)
		(drill 0.254)
		(layers "F.Cu" "B.Cu")
		(net "GND")
	)
	(via
		(at 286.35325 -343.073482)
		(size 0.4572)
		(drill 0.254)
		(layers "F.Cu" "B.Cu")
		(net "GND")
	)
	(via
		(at 350.493584 -224.386902)
		(size 0.4572)
		(drill 0.254)
		(layers "F.Cu" "B.Cu")
		(net "GND")
	)
	(via
		(at 65.349882 -310.149748)
		(size 0.4064)
		(drill 0.2032)
		(layers "F.Cu" "B.Cu")
		(net "GND")
	)
	(via
		(at 98.675698 -6.113526)
		(size 0.508)
		(drill 0.254)
		(layers "F.Cu" "B.Cu")
		(net "GND")
	)
	(via
		(at 190.949834 -276.899878)
		(size 0.4064)
		(drill 0.2032)
		(layers "F.Cu" "B.Cu")
		(net "GND")
	)
	(via
		(at 310.374792 -289.724846)
		(size 0.4064)
		(drill 0.2032)
		(layers "F.Cu" "B.Cu")
		(net "GND")
	)
	(via
		(at 432.12766 -408.840178)
		(size 0.508)
		(drill 0.254)
		(layers "F.Cu" "B.Cu")
		(net "GND")
	)
	(via
		(at 466.835998 -369.123976)
		(size 0.508)
		(drill 0.254)
		(layers "F.Cu" "B.Cu")
		(net "GND")
	)
	(via
		(at 413.836612 -348.58579)
		(size 0.4064)
		(drill 0.2032)
		(layers "F.Cu" "B.Cu")
		(net "GND")
	)
	(via
		(at 186.644026 -164.192966)
		(size 0.508)
		(drill 0.254)
		(layers "F.Cu" "B.Cu")
		(net "GND")
	)
	(via
		(at 69.149976 -315.849762)
		(size 0.4064)
		(drill 0.2032)
		(layers "F.Cu" "B.Cu")
		(net "GND")
	)
	(via
		(at 240.447068 -251.805694)
		(size 0.508)
		(drill 0.254)
		(layers "F.Cu" "B.Cu")
		(net "GND")
	)
	(via
		(at 405.100028 -273.099784)
		(size 0.4064)
		(drill 0.2032)
		(layers "F.Cu" "B.Cu")
		(net "GND")
	)
	(via
		(at 441.445904 -349.219774)
		(size 0.4572)
		(drill 0.254)
		(layers "F.Cu" "B.Cu")
		(net "GND")
	)
	(via
		(at 276.649688 -312.049922)
		(size 0.4064)
		(drill 0.2032)
		(layers "F.Cu" "B.Cu")
		(net "GND")
	)
	(via
		(at 119.747792 -410.041852)
		(size 0.4572)
		(drill 0.254)
		(layers "F.Cu" "B.Cu")
		(net "GND")
	)
	(via
		(at 384.54457 -241.400584)
		(size 0.508)
		(drill 0.254)
		(layers "F.Cu" "B.Cu")
		(net "GND")
	)
	(via
		(at 35.93846 -357.123746)
		(size 0.4572)
		(drill 0.254)
		(layers "F.Cu" "B.Cu")
		(net "GND")
	)
	(via
		(at 305.489864 -73.85177)
		(size 0.508)
		(drill 0.254)
		(layers "F.Cu" "B.Cu")
		(net "GND")
	)
	(via
		(at 194.673982 -402.263102)
		(size 0.508)
		(drill 0.254)
		(layers "F.Cu" "B.Cu")
		(net "GND")
	)
	(via
		(at 266.691618 -119.026686)
		(size 0.508)
		(drill 0.254)
		(layers "F.Cu" "B.Cu")
		(net "GND")
	)
	(via
		(at 182.87492 -306.824888)
		(size 0.4064)
		(drill 0.2032)
		(layers "F.Cu" "B.Cu")
		(net "GND")
	)
	(via
		(at 189.96914 -344.831162)
		(size 0.4572)
		(drill 0.254)
		(layers "F.Cu" "B.Cu")
		(net "GND")
	)
	(via
		(at 194.843146 -80.449674)
		(size 0.508)
		(drill 0.254)
		(layers "F.Cu" "B.Cu")
		(net "GND")
	)
	(via
		(at 81.357724 -25.971246)
		(size 0.508)
		(drill 0.254)
		(layers "F.Cu" "B.Cu")
		(net "GND")
	)
	(via
		(at 403.00656 -122.354848)
		(size 0.508)
		(drill 0.254)
		(layers "F.Cu" "B.Cu")
		(net "GND")
	)
	(via
		(at 285.51505 -45.88891)
		(size 0.508)
		(drill 0.254)
		(layers "F.Cu" "B.Cu")
		(net "GND")
	)
	(via
		(at 405.575008 -287.824926)
		(size 0.4064)
		(drill 0.2032)
		(layers "F.Cu" "B.Cu")
		(net "GND")
	)
	(via
		(at 61.549534 -272.14957)
		(size 0.4064)
		(drill 0.2032)
		(layers "F.Cu" "B.Cu")
		(net "GND")
	)
	(via
		(at 298.44873 -27.79014)
		(size 0.508)
		(drill 0.254)
		(layers "F.Cu" "B.Cu")
		(net "GND")
	)
	(via
		(at 270.474948 -291.624766)
		(size 0.4064)
		(drill 0.2032)
		(layers "F.Cu" "B.Cu")
		(net "GND")
	)
	(via
		(at 145.74647 -184.988454)
		(size 0.508)
		(drill 0.254)
		(layers "F.Cu" "B.Cu")
		(net "GND")
	)
	(via
		(at 180.693314 -121.835164)
		(size 0.508)
		(drill 0.254)
		(layers "F.Cu" "B.Cu")
		(net "GND")
	)
	(via
		(at 131.948428 -357.75773)
		(size 0.4064)
		(drill 0.2032)
		(layers "F.Cu" "B.Cu")
		(net "GND")
	)
	(via
		(at 320.153284 -342.439498)
		(size 0.4064)
		(drill 0.2032)
		(layers "F.Cu" "B.Cu")
		(net "GND")
	)
	(via
		(at 313.224926 -288.774886)
		(size 0.4064)
		(drill 0.2032)
		(layers "F.Cu" "B.Cu")
		(net "GND")
	)
	(via
		(at 139.645136 -346.09913)
		(size 0.4572)
		(drill 0.254)
		(layers "F.Cu" "B.Cu")
		(net "GND")
	)
	(via
		(at 338.09559 -84.924138)
		(size 0.508)
		(drill 0.254)
		(layers "F.Cu" "B.Cu")
		(net "GND")
	)
	(via
		(at 318.151764 -348.58579)
		(size 0.4064)
		(drill 0.2032)
		(layers "F.Cu" "B.Cu")
		(net "GND")
	)
	(via
		(at 140.90396 -358.391714)
		(size 0.4572)
		(drill 0.254)
		(layers "F.Cu" "B.Cu")
		(net "GND")
	)
	(via
		(at 251.698506 -65.15989)
		(size 0.508)
		(drill 0.254)
		(layers "F.Cu" "B.Cu")
		(net "GND")
	)
	(via
		(at 398.971008 -355.366066)
		(size 0.4572)
		(drill 0.254)
		(layers "F.Cu" "B.Cu")
		(net "GND")
	)
	(via
		(at 51.574954 -284.024832)
		(size 0.4064)
		(drill 0.2032)
		(layers "F.Cu" "B.Cu")
		(net "GND")
	)
	(via
		(at 4.562856 -230.961692)
		(size 0.508)
		(drill 0.254)
		(layers "F.Cu" "B.Cu")
		(net "GND")
	)
	(via
		(at 394.011912 -354.098098)
		(size 0.4572)
		(drill 0.254)
		(layers "F.Cu" "B.Cu")
		(net "GND")
	)
	(via
		(at 296.254678 -34.990024)
		(size 0.508)
		(drill 0.254)
		(layers "F.Cu" "B.Cu")
		(net "GND")
	)
	(via
		(at 182.31485 -26.171398)
		(size 0.508)
		(drill 0.254)
		(layers "F.Cu" "B.Cu")
		(net "GND")
	)
	(via
		(at 48.3743 -343.073482)
		(size 0.4572)
		(drill 0.254)
		(layers "F.Cu" "B.Cu")
		(net "GND")
	)
	(via
		(at 110.676182 -290.68649)
		(size 0.508)
		(drill 0.254)
		(layers "F.Cu" "B.Cu")
		(net "GND")
	)
	(via
		(at 401.78736 -104.244902)
		(size 0.508)
		(drill 0.254)
		(layers "F.Cu" "B.Cu")
		(net "GND")
	)
	(via
		(at 388.949946 -308.249828)
		(size 0.4064)
		(drill 0.2032)
		(layers "F.Cu" "B.Cu")
		(net "GND")
	)
	(via
		(at 396.0749 -286.874966)
		(size 0.4064)
		(drill 0.2032)
		(layers "F.Cu" "B.Cu")
		(net "GND")
	)
	(via
		(at 358.14 -175.006)
		(size 0.508)
		(drill 0.254)
		(layers "F.Cu" "B.Cu")
		(net "GND")
	)
	(via
		(at 138.06043 -19.33956)
		(size 0.508)
		(drill 0.254)
		(layers "F.Cu" "B.Cu")
		(net "GND")
	)
	(via
		(at 296.124884 -287.824926)
		(size 0.4064)
		(drill 0.2032)
		(layers "F.Cu" "B.Cu")
		(net "GND")
	)
	(via
		(at 198.26605 -133.30809)
		(size 0.508)
		(drill 0.254)
		(layers "F.Cu" "B.Cu")
		(net "GND")
	)
	(via
		(at 414.198562 -89.06637)
		(size 0.508)
		(drill 0.254)
		(layers "F.Cu" "B.Cu")
		(net "GND")
	)
	(via
		(at 103.503222 -89.952068)
		(size 0.508)
		(drill 0.254)
		(layers "F.Cu" "B.Cu")
		(net "GND")
	)
	(via
		(at 395.4526 -145.821908)
		(size 0.508)
		(drill 0.254)
		(layers "F.Cu" "B.Cu")
		(net "GND")
	)
	(via
		(at 289.127692 -382.73863)
		(size 0.508)
		(drill 0.254)
		(layers "F.Cu" "B.Cu")
		(net "GND")
	)
	(via
		(at 76.74991 -311.099962)
		(size 0.4064)
		(drill 0.2032)
		(layers "F.Cu" "B.Cu")
		(net "GND")
	)
	(via
		(at 123.335796 -279.023572)
		(size 0.508)
		(drill 0.254)
		(layers "F.Cu" "B.Cu")
		(net "GND")
	)
	(via
		(at 293.27475 -307.774848)
		(size 0.4064)
		(drill 0.2032)
		(layers "F.Cu" "B.Cu")
		(net "GND")
	)
	(via
		(at 124.796296 -169.492422)
		(size 0.508)
		(drill 0.254)
		(layers "F.Cu" "B.Cu")
		(net "GND")
	)
	(via
		(at 133.427216 -358.391714)
		(size 0.4572)
		(drill 0.254)
		(layers "F.Cu" "B.Cu")
		(net "GND")
	)
	(via
		(at 90.405966 -287.538668)
		(size 0.508)
		(drill 0.254)
		(layers "F.Cu" "B.Cu")
		(net "GND")
	)
	(via
		(at 337.5279 -374.938544)
		(size 0.508)
		(drill 0.254)
		(layers "F.Cu" "B.Cu")
		(net "GND")
	)
	(via
		(at 312.928 -417.82492)
		(size 0.508)
		(drill 0.254)
		(layers "F.Cu" "B.Cu")
		(net "GND")
	)
	(via
		(at 429.800004 -286.399732)
		(size 0.4064)
		(drill 0.2032)
		(layers "F.Cu" "B.Cu")
		(net "GND")
	)
	(via
		(at 37.788596 -344.831162)
		(size 0.4572)
		(drill 0.254)
		(layers "F.Cu" "B.Cu")
		(net "GND")
	)
	(via
		(at 340.18347 -285.953454)
		(size 0.508)
		(drill 0.254)
		(layers "F.Cu" "B.Cu")
		(net "GND")
	)
	(via
		(at 303.031144 -60.099194)
		(size 0.508)
		(drill 0.254)
		(layers "F.Cu" "B.Cu")
		(net "GND")
	)
	(via
		(at 194.030092 -86.949026)
		(size 0.508)
		(drill 0.254)
		(layers "F.Cu" "B.Cu")
		(net "GND")
	)
	(via
		(at 208.741264 -308.472332)
		(size 0.508)
		(drill 0.254)
		(layers "F.Cu" "B.Cu")
		(net "GND")
	)
	(via
		(at 118.886986 -0.762)
		(size 0.508)
		(drill 0.254)
		(layers "F.Cu" "B.Cu")
		(net "GND")
	)
	(via
		(at 36.14801 -406.141936)
		(size 0.508)
		(drill 0.254)
		(layers "F.Cu" "B.Cu")
		(net "GND")
	)
	(via
		(at 107.348274 -285.953454)
		(size 0.508)
		(drill 0.254)
		(layers "F.Cu" "B.Cu")
		(net "GND")
	)
	(via
		(at 58.24982 -287.699958)
		(size 0.4064)
		(drill 0.2032)
		(layers "F.Cu" "B.Cu")
		(net "GND")
	)
	(via
		(at 185.725054 -296.37482)
		(size 0.4064)
		(drill 0.2032)
		(layers "F.Cu" "B.Cu")
		(net "GND")
	)
	(via
		(at 182.87492 -303.974754)
		(size 0.4064)
		(drill 0.2032)
		(layers "F.Cu" "B.Cu")
		(net "GND")
	)
	(via
		(at 79.660496 -15.474188)
		(size 0.508)
		(drill 0.254)
		(layers "F.Cu" "B.Cu")
		(net "GND")
	)
	(via
		(at 387.525006 -281.174952)
		(size 0.4064)
		(drill 0.2032)
		(layers "F.Cu" "B.Cu")
		(net "GND")
	)
	(via
		(at 337.428078 -243.836444)
		(size 0.508)
		(drill 0.254)
		(layers "F.Cu" "B.Cu")
		(net "GND")
	)
	(via
		(at 412.89351 -143.955008)
		(size 0.508)
		(drill 0.254)
		(layers "F.Cu" "B.Cu")
		(net "GND")
	)
	(via
		(at 283.833062 -100.64496)
		(size 0.508)
		(drill 0.254)
		(layers "F.Cu" "B.Cu")
		(net "GND")
	)
	(via
		(at 357.63073 -307.877718)
		(size 0.508)
		(drill 0.254)
		(layers "F.Cu" "B.Cu")
		(net "GND")
	)
	(via
		(at 436.527702 -404.940262)
		(size 0.508)
		(drill 0.254)
		(layers "F.Cu" "B.Cu")
		(net "GND")
	)
	(via
		(at 312.749692 -283.549852)
		(size 0.4064)
		(drill 0.2032)
		(layers "F.Cu" "B.Cu")
		(net "GND")
	)
	(via
		(at 241.268504 -121.535444)
		(size 0.508)
		(drill 0.254)
		(layers "F.Cu" "B.Cu")
		(net "GND")
	)
	(via
		(at 28.557982 -292.732714)
		(size 0.508)
		(drill 0.254)
		(layers "F.Cu" "B.Cu")
		(net "GND")
	)
	(via
		(at 45.39996 -302.549814)
		(size 0.4064)
		(drill 0.2032)
		(layers "F.Cu" "B.Cu")
		(net "GND")
	)
	(via
		(at 300.047914 -352.245422)
		(size 0.4572)
		(drill 0.254)
		(layers "F.Cu" "B.Cu")
		(net "GND")
	)
	(via
		(at 374.725184 -14.100302)
		(size 0.508)
		(drill 0.254)
		(layers "F.Cu" "B.Cu")
		(net "GND")
	)
	(via
		(at 298.647612 -145.755106)
		(size 0.508)
		(drill 0.254)
		(layers "F.Cu" "B.Cu")
		(net "GND")
	)
	(via
		(at 124.147834 -395.938502)
		(size 0.508)
		(drill 0.254)
		(layers "F.Cu" "B.Cu")
		(net "GND")
	)
	(via
		(at 27.347926 -398.34185)
		(size 0.508)
		(drill 0.254)
		(layers "F.Cu" "B.Cu")
		(net "GND")
	)
	(via
		(at 231.867456 -219.504006)
		(size 0.4572)
		(drill 0.254)
		(layers "F.Cu" "B.Cu")
		(net "GND")
	)
	(via
		(at 153.89987 -317.749936)
		(size 0.4064)
		(drill 0.2032)
		(layers "F.Cu" "B.Cu")
		(net "GND")
	)
	(via
		(at 101.753162 -172.22724)
		(size 0.508)
		(drill 0.254)
		(layers "F.Cu" "B.Cu")
		(net "GND")
	)
	(via
		(at 313.224926 -294.4749)
		(size 0.4064)
		(drill 0.2032)
		(layers "F.Cu" "B.Cu")
		(net "GND")
	)
	(via
		(at 47.77486 -292.57498)
		(size 0.4064)
		(drill 0.2032)
		(layers "F.Cu" "B.Cu")
		(net "GND")
	)
	(via
		(at 69.149976 -314.899802)
		(size 0.4064)
		(drill 0.2032)
		(layers "F.Cu" "B.Cu")
		(net "GND")
	)
	(via
		(at 209.101436 -220.39072)
		(size 0.508)
		(drill 0.254)
		(layers "F.Cu" "B.Cu")
		(net "GND")
	)
	(via
		(at 132.270754 -305.972718)
		(size 0.508)
		(drill 0.254)
		(layers "F.Cu" "B.Cu")
		(net "GND")
	)
	(via
		(at 413.465264 -358.391714)
		(size 0.4572)
		(drill 0.254)
		(layers "F.Cu" "B.Cu")
		(net "GND")
	)
	(via
		(at 276.871176 -31.652972)
		(size 0.508)
		(drill 0.254)
		(layers "F.Cu" "B.Cu")
		(net "GND")
	)
	(via
		(at 248.745502 -206.836264)
		(size 0.508)
		(drill 0.254)
		(layers "F.Cu" "B.Cu")
		(net "GND")
	)
	(via
		(at 385.927854 -378.83846)
		(size 0.508)
		(drill 0.254)
		(layers "F.Cu" "B.Cu")
		(net "GND")
	)
	(via
		(at 302.12665 -136.061958)
		(size 0.508)
		(drill 0.254)
		(layers "F.Cu" "B.Cu")
		(net "GND")
	)
	(via
		(at 190.348108 -151.155146)
		(size 0.508)
		(drill 0.254)
		(layers "F.Cu" "B.Cu")
		(net "GND")
	)
	(via
		(at 182.39994 -273.099784)
		(size 0.4064)
		(drill 0.2032)
		(layers "F.Cu" "B.Cu")
		(net "GND")
	)
	(via
		(at 372.249192 -349.219774)
		(size 0.4572)
		(drill 0.254)
		(layers "F.Cu" "B.Cu")
		(net "GND")
	)
	(via
		(at 389.424926 -298.27474)
		(size 0.4064)
		(drill 0.2032)
		(layers "F.Cu" "B.Cu")
		(net "GND")
	)
	(via
		(at 47.77486 -284.974792)
		(size 0.4064)
		(drill 0.2032)
		(layers "F.Cu" "B.Cu")
		(net "GND")
	)
	(via
		(at 248.480834 -29.589984)
		(size 0.508)
		(drill 0.254)
		(layers "F.Cu" "B.Cu")
		(net "GND")
	)
	(via
		(at 256.371852 -353.465638)
		(size 0.508)
		(drill 0.254)
		(layers "F.Cu" "B.Cu")
		(net "GND")
	)
	(via
		(at 413.649922 -311.099962)
		(size 0.4064)
		(drill 0.2032)
		(layers "F.Cu" "B.Cu")
		(net "GND")
	)
	(via
		(at 418.927788 -373.83847)
		(size 0.508)
		(drill 0.254)
		(layers "F.Cu" "B.Cu")
		(net "GND")
	)
	(via
		(at 186.675014 -301.124874)
		(size 0.4064)
		(drill 0.2032)
		(layers "F.Cu" "B.Cu")
		(net "GND")
	)
	(via
		(at 49.440846 -45.853858)
		(size 0.508)
		(drill 0.254)
		(layers "F.Cu" "B.Cu")
		(net "GND")
	)
	(via
		(at 79.323184 -56.353456)
		(size 0.508)
		(drill 0.254)
		(layers "F.Cu" "B.Cu")
		(net "GND")
	)
	(via
		(at 226.289362 -118.461028)
		(size 0.508)
		(drill 0.254)
		(layers "F.Cu" "B.Cu")
		(net "GND")
	)
	(via
		(at 226.289362 -119.172228)
		(size 0.508)
		(drill 0.254)
		(layers "F.Cu" "B.Cu")
		(net "GND")
	)
	(via
		(at 189.999874 -287.349946)
		(size 0.4064)
		(drill 0.2032)
		(layers "F.Cu" "B.Cu")
		(net "GND")
	)
	(via
		(at 300.12767 -380.141734)
		(size 0.508)
		(drill 0.254)
		(layers "F.Cu" "B.Cu")
		(net "GND")
	)
	(via
		(at 338.435696 -347.951806)
		(size 0.4572)
		(drill 0.254)
		(layers "F.Cu" "B.Cu")
		(net "GND")
	)
	(via
		(at 184.77484 -284.974792)
		(size 0.4064)
		(drill 0.2032)
		(layers "F.Cu" "B.Cu")
		(net "GND")
	)
	(via
		(at 262.14197 -49.574704)
		(size 0.508)
		(drill 0.254)
		(layers "F.Cu" "B.Cu")
		(net "GND")
	)
	(via
		(at 278.074882 -284.974792)
		(size 0.4064)
		(drill 0.2032)
		(layers "F.Cu" "B.Cu")
		(net "GND")
	)
	(via
		(at 327.478644 -354.732082)
		(size 0.4064)
		(drill 0.2032)
		(layers "F.Cu" "B.Cu")
		(net "GND")
	)
	(via
		(at 411.835092 -351.611438)
		(size 0.4064)
		(drill 0.2032)
		(layers "F.Cu" "B.Cu")
		(net "GND")
	)
	(via
		(at 385.98094 -25.990042)
		(size 0.508)
		(drill 0.254)
		(layers "F.Cu" "B.Cu")
		(net "GND")
	)
	(via
		(at 279.024842 -284.024832)
		(size 0.4064)
		(drill 0.2032)
		(layers "F.Cu" "B.Cu")
		(net "GND")
	)
	(via
		(at 45.636688 -351.611438)
		(size 0.4064)
		(drill 0.2032)
		(layers "F.Cu" "B.Cu")
		(net "GND")
	)
	(via
		(at 273.324828 -300.174914)
		(size 0.4064)
		(drill 0.2032)
		(layers "F.Cu" "B.Cu")
		(net "GND")
	)
	(via
		(at 58.699908 -314.899802)
		(size 0.4064)
		(drill 0.2032)
		(layers "F.Cu" "B.Cu")
		(net "GND")
	)
	(via
		(at 89.297002 -287.63214)
		(size 0.508)
		(drill 0.254)
		(layers "F.Cu" "B.Cu")
		(net "GND")
	)
	(via
		(at 159.124904 -281.174952)
		(size 0.4064)
		(drill 0.2032)
		(layers "F.Cu" "B.Cu")
		(net "GND")
	)
	(via
		(at 423.32783 -399.838418)
		(size 0.508)
		(drill 0.254)
		(layers "F.Cu" "B.Cu")
		(net "GND")
	)
	(via
		(at 43.635168 -342.439498)
		(size 0.4064)
		(drill 0.2032)
		(layers "F.Cu" "B.Cu")
		(net "GND")
	)
	(via
		(at 398.971008 -346.09913)
		(size 0.4572)
		(drill 0.254)
		(layers "F.Cu" "B.Cu")
		(net "GND")
	)
	(via
		(at 39.224966 -276.424898)
		(size 0.4064)
		(drill 0.2032)
		(layers "F.Cu" "B.Cu")
		(net "GND")
	)
	(via
		(at 318.151764 -351.611438)
		(size 0.4064)
		(drill 0.2032)
		(layers "F.Cu" "B.Cu")
		(net "GND")
	)
	(via
		(at 334.067912 -350.977454)
		(size 0.4572)
		(drill 0.254)
		(layers "F.Cu" "B.Cu")
		(net "GND")
	)
	(via
		(at 348.527878 -406.141936)
		(size 0.508)
		(drill 0.254)
		(layers "F.Cu" "B.Cu")
		(net "GND")
	)
	(via
		(at 170.524932 -303.974754)
		(size 0.4064)
		(drill 0.2032)
		(layers "F.Cu" "B.Cu")
		(net "GND")
	)
	(via
		(at 308.474872 -291.624766)
		(size 0.4064)
		(drill 0.2032)
		(layers "F.Cu" "B.Cu")
		(net "GND")
	)
	(via
		(at 46.744128 -348.58579)
		(size 0.4064)
		(drill 0.2032)
		(layers "F.Cu" "B.Cu")
		(net "GND")
	)
	(via
		(at 308.949598 -274.999958)
		(size 0.4064)
		(drill 0.2032)
		(layers "F.Cu" "B.Cu")
		(net "GND")
	)
	(via
		(at 79.59979 -283.549852)
		(size 0.4064)
		(drill 0.2032)
		(layers "F.Cu" "B.Cu")
		(net "GND")
	)
	(via
		(at 291.06114 -201.731118)
		(size 0.508)
		(drill 0.254)
		(layers "F.Cu" "B.Cu")
		(net "GND")
	)
	(via
		(at 53.48732 -135.364982)
		(size 0.508)
		(drill 0.254)
		(layers "F.Cu" "B.Cu")
		(net "GND")
	)
	(via
		(at 127.33528 -287.51149)
		(size 0.508)
		(drill 0.254)
		(layers "F.Cu" "B.Cu")
		(net "GND")
	)
	(via
		(at 146.753326 -49.574704)
		(size 0.508)
		(drill 0.254)
		(layers "F.Cu" "B.Cu")
		(net "GND")
	)
	(via
		(at 76.27493 -291.624766)
		(size 0.4064)
		(drill 0.2032)
		(layers "F.Cu" "B.Cu")
		(net "GND")
	)
	(via
		(at 89.15527 -346.09913)
		(size 0.4572)
		(drill 0.254)
		(layers "F.Cu" "B.Cu")
		(net "GND")
	)
	(via
		(at 418.971222 -31.652972)
		(size 0.508)
		(drill 0.254)
		(layers "F.Cu" "B.Cu")
		(net "GND")
	)
	(via
		(at 74.581258 -31.118302)
		(size 0.508)
		(drill 0.254)
		(layers "F.Cu" "B.Cu")
		(net "GND")
	)
	(via
		(at 201.857864 -301.262034)
		(size 0.508)
		(drill 0.254)
		(layers "F.Cu" "B.Cu")
		(net "GND")
	)
	(via
		(at 371.556026 -241.298984)
		(size 0.508)
		(drill 0.254)
		(layers "F.Cu" "B.Cu")
		(net "GND")
	)
	(via
		(at 70.130162 -342.439498)
		(size 0.4064)
		(drill 0.2032)
		(layers "F.Cu" "B.Cu")
		(net "GND")
	)
	(via
		(at 432.900836 -29.590238)
		(size 0.508)
		(drill 0.254)
		(layers "F.Cu" "B.Cu")
		(net "GND")
	)
	(via
		(at 57.582308 -37.087048)
		(size 0.508)
		(drill 0.254)
		(layers "F.Cu" "B.Cu")
		(net "GND")
	)
	(via
		(at 38.706044 -161.276284)
		(size 0.508)
		(drill 0.254)
		(layers "F.Cu" "B.Cu")
		(net "GND")
	)
	(via
		(at 37.799772 -318.699896)
		(size 0.4064)
		(drill 0.2032)
		(layers "F.Cu" "B.Cu")
		(net "GND")
	)
	(via
		(at 255.252982 -79.89189)
		(size 0.508)
		(drill 0.254)
		(layers "F.Cu" "B.Cu")
		(net "GND")
	)
	(via
		(at 317.577978 -35.635184)
		(size 0.508)
		(drill 0.254)
		(layers "F.Cu" "B.Cu")
		(net "GND")
	)
	(via
		(at 31.747968 -395.938502)
		(size 0.508)
		(drill 0.254)
		(layers "F.Cu" "B.Cu")
		(net "GND")
	)
	(via
		(at 293.527734 -385.141978)
		(size 0.508)
		(drill 0.254)
		(layers "F.Cu" "B.Cu")
		(net "GND")
	)
	(via
		(at 39.97325 -141.029436)
		(size 0.508)
		(drill 0.254)
		(layers "F.Cu" "B.Cu")
		(net "GND")
	)
	(via
		(at 186.86018 -346.09913)
		(size 0.4572)
		(drill 0.254)
		(layers "F.Cu" "B.Cu")
		(net "GND")
	)
	(via
		(at 195.224908 -296.37482)
		(size 0.4064)
		(drill 0.2032)
		(layers "F.Cu" "B.Cu")
		(net "GND")
	)
	(via
		(at 429.198278 -133.30809)
		(size 0.508)
		(drill 0.254)
		(layers "F.Cu" "B.Cu")
		(net "GND")
	)
	(via
		(at 194.274948 -301.124874)
		(size 0.4064)
		(drill 0.2032)
		(layers "F.Cu" "B.Cu")
		(net "GND")
	)
	(via
		(at 92.13215 -13.613638)
		(size 0.508)
		(drill 0.254)
		(layers "F.Cu" "B.Cu")
		(net "GND")
	)
	(via
		(at 156.750004 -311.099962)
		(size 0.4064)
		(drill 0.2032)
		(layers "F.Cu" "B.Cu")
		(net "GND")
	)
	(via
		(at 71.347838 -369.938554)
		(size 0.508)
		(drill 0.254)
		(layers "F.Cu" "B.Cu")
		(net "GND")
	)
	(via
		(at 309.424832 -297.32478)
		(size 0.4064)
		(drill 0.2032)
		(layers "F.Cu" "B.Cu")
		(net "GND")
	)
	(via
		(at 198.26605 -134.566914)
		(size 0.508)
		(drill 0.254)
		(layers "F.Cu" "B.Cu")
		(net "GND")
	)
	(via
		(at 31.649924 -27.04973)
		(size 0.508)
		(drill 0.254)
		(layers "F.Cu" "B.Cu")
		(net "GND")
	)
	(via
		(at 43.499786 -274.049744)
		(size 0.4064)
		(drill 0.2032)
		(layers "F.Cu" "B.Cu")
		(net "GND")
	)
	(via
		(at 96.869758 -254.764032)
		(size 0.508)
		(drill 0.254)
		(layers "F.Cu" "B.Cu")
		(net "GND")
	)
	(via
		(at 379.9459 -348.58579)
		(size 0.4064)
		(drill 0.2032)
		(layers "F.Cu" "B.Cu")
		(net "GND")
	)
	(via
		(at 53.660548 -15.474188)
		(size 0.508)
		(drill 0.254)
		(layers "F.Cu" "B.Cu")
		(net "GND")
	)
	(via
		(at 422.199816 -313.949842)
		(size 0.4064)
		(drill 0.2032)
		(layers "F.Cu" "B.Cu")
		(net "GND")
	)
	(via
		(at 238.800894 -29.590238)
		(size 0.508)
		(drill 0.254)
		(layers "F.Cu" "B.Cu")
		(net "GND")
	)
	(via
		(at 86.747858 -383.940304)
		(size 0.508)
		(drill 0.254)
		(layers "F.Cu" "B.Cu")
		(net "GND")
	)
	(via
		(at 148.900134 -38.315138)
		(size 0.508)
		(drill 0.254)
		(layers "F.Cu" "B.Cu")
		(net "GND")
	)
	(via
		(at 117.656864 -315.98997)
		(size 0.508)
		(drill 0.254)
		(layers "F.Cu" "B.Cu")
		(net "GND")
	)
	(via
		(at 100.581206 -34.718498)
		(size 0.508)
		(drill 0.254)
		(layers "F.Cu" "B.Cu")
		(net "GND")
	)
	(via
		(at 279.974802 -307.774848)
		(size 0.4064)
		(drill 0.2032)
		(layers "F.Cu" "B.Cu")
		(net "GND")
	)
	(via
		(at 94.838266 -72.56526)
		(size 0.508)
		(drill 0.254)
		(layers "F.Cu" "B.Cu")
		(net "GND")
	)
	(via
		(at 188.119004 -350.977454)
		(size 0.4572)
		(drill 0.254)
		(layers "F.Cu" "B.Cu")
		(net "GND")
	)
	(via
		(at 282.763976 -175.730154)
		(size 0.508)
		(drill 0.254)
		(layers "F.Cu" "B.Cu")
		(net "GND")
	)
	(via
		(at 419.349936 -312.049922)
		(size 0.4064)
		(drill 0.2032)
		(layers "F.Cu" "B.Cu")
		(net "GND")
	)
	(via
		(at 283.774896 -291.624766)
		(size 0.4064)
		(drill 0.2032)
		(layers "F.Cu" "B.Cu")
		(net "GND")
	)
	(via
		(at 393.334494 -47.936658)
		(size 0.508)
		(drill 0.254)
		(layers "F.Cu" "B.Cu")
		(net "GND")
	)
	(via
		(at 116.403628 -354.732082)
		(size 0.4064)
		(drill 0.2032)
		(layers "F.Cu" "B.Cu")
		(net "GND")
	)
	(via
		(at 156.750004 -316.799722)
		(size 0.4064)
		(drill 0.2032)
		(layers "F.Cu" "B.Cu")
		(net "GND")
	)
	(via
		(at 366.06988 -290.68649)
		(size 0.508)
		(drill 0.254)
		(layers "F.Cu" "B.Cu")
		(net "GND")
	)
	(via
		(at 163.572444 -113.245138)
		(size 0.508)
		(drill 0.254)
		(layers "F.Cu" "B.Cu")
		(net "GND")
	)
	(via
		(at 46.487588 -26.360882)
		(size 0.508)
		(drill 0.254)
		(layers "F.Cu" "B.Cu")
		(net "GND")
	)
	(via
		(at 160.074864 -286.874712)
		(size 0.4064)
		(drill 0.2032)
		(layers "F.Cu" "B.Cu")
		(net "GND")
	)
	(via
		(at 276.174708 -298.27474)
		(size 0.4064)
		(drill 0.2032)
		(layers "F.Cu" "B.Cu")
		(net "GND")
	)
	(via
		(at 22.243796 -346.09913)
		(size 0.4572)
		(drill 0.254)
		(layers "F.Cu" "B.Cu")
		(net "GND")
	)
	(via
		(at 385.850384 -253.45644)
		(size 0.508)
		(drill 0.254)
		(layers "F.Cu" "B.Cu")
		(net "GND")
	)
	(via
		(at 430.749964 -312.999882)
		(size 0.4064)
		(drill 0.2032)
		(layers "F.Cu" "B.Cu")
		(net "GND")
	)
	(via
		(at 14.050772 -159.857948)
		(size 0.508)
		(drill 0.254)
		(layers "F.Cu" "B.Cu")
		(net "GND")
	)
	(via
		(at 316.672976 -349.219774)
		(size 0.4572)
		(drill 0.254)
		(layers "F.Cu" "B.Cu")
		(net "GND")
	)
	(via
		(at 298.647612 -149.355048)
		(size 0.508)
		(drill 0.254)
		(layers "F.Cu" "B.Cu")
		(net "GND")
	)
	(via
		(at 280.745692 -150.9776)
		(size 0.508)
		(drill 0.254)
		(layers "F.Cu" "B.Cu")
		(net "GND")
	)
	(via
		(at 370.990368 -344.831162)
		(size 0.4572)
		(drill 0.254)
		(layers "F.Cu" "B.Cu")
		(net "GND")
	)
	(via
		(at 198.550022 -309.199788)
		(size 0.4064)
		(drill 0.2032)
		(layers "F.Cu" "B.Cu")
		(net "GND")
	)
	(via
		(at 44.18457 -72.56526)
		(size 0.508)
		(drill 0.254)
		(layers "F.Cu" "B.Cu")
		(net "GND")
	)
	(via
		(at 180.693314 -156.555186)
		(size 0.508)
		(drill 0.254)
		(layers "F.Cu" "B.Cu")
		(net "GND")
	)
	(via
		(at 239.246664 -205.47711)
		(size 0.508)
		(drill 0.254)
		(layers "F.Cu" "B.Cu")
		(net "GND")
	)
	(via
		(at 131.496308 -279.023572)
		(size 0.508)
		(drill 0.254)
		(layers "F.Cu" "B.Cu")
		(net "GND")
	)
	(via
		(at 284.249876 -275.949918)
		(size 0.4064)
		(drill 0.2032)
		(layers "F.Cu" "B.Cu")
		(net "GND")
	)
	(via
		(at 63.924942 -291.624766)
		(size 0.4064)
		(drill 0.2032)
		(layers "F.Cu" "B.Cu")
		(net "GND")
	)
	(via
		(at 12.212066 -388.528814)
		(size 0.508)
		(drill 0.254)
		(layers "F.Cu" "B.Cu")
		(net "GND")
	)
	(via
		(at 154.850084 -314.899802)
		(size 0.4064)
		(drill 0.2032)
		(layers "F.Cu" "B.Cu")
		(net "GND")
	)
	(via
		(at 425.527724 -406.040336)
		(size 0.508)
		(drill 0.254)
		(layers "F.Cu" "B.Cu")
		(net "GND")
	)
	(via
		(at 168.952164 -120.555004)
		(size 0.508)
		(drill 0.254)
		(layers "F.Cu" "B.Cu")
		(net "GND")
	)
	(via
		(at 196.998082 -154.476958)
		(size 0.508)
		(drill 0.254)
		(layers "F.Cu" "B.Cu")
		(net "GND")
	)
	(via
		(at 31.747968 -399.838418)
		(size 0.508)
		(drill 0.254)
		(layers "F.Cu" "B.Cu")
		(net "GND")
	)
	(via
		(at 161.500058 -308.249828)
		(size 0.4064)
		(drill 0.2032)
		(layers "F.Cu" "B.Cu")
		(net "GND")
	)
	(via
		(at 122.843544 -241.846608)
		(size 0.508)
		(drill 0.254)
		(layers "F.Cu" "B.Cu")
		(net "GND")
	)
	(via
		(at 307.524912 -294.4749)
		(size 0.4064)
		(drill 0.2032)
		(layers "F.Cu" "B.Cu")
		(net "GND")
	)
	(via
		(at 40.174926 -281.174952)
		(size 0.4064)
		(drill 0.2032)
		(layers "F.Cu" "B.Cu")
		(net "GND")
	)
	(via
		(at 321.988434 -31.642304)
		(size 0.508)
		(drill 0.254)
		(layers "F.Cu" "B.Cu")
		(net "GND")
	)
	(via
		(at 159.347916 -373.83847)
		(size 0.508)
		(drill 0.254)
		(layers "F.Cu" "B.Cu")
		(net "GND")
	)
	(via
		(at 180.154834 -34.990024)
		(size 0.508)
		(drill 0.254)
		(layers "F.Cu" "B.Cu")
		(net "GND")
	)
	(via
		(at 4.91871 -379.551692)
		(size 0.508)
		(drill 0.254)
		(layers "F.Cu" "B.Cu")
		(net "GND")
	)
	(via
		(at 58.066432 -35.871912)
		(size 0.508)
		(drill 0.254)
		(layers "F.Cu" "B.Cu")
		(net "GND")
	)
	(via
		(at 78.64983 -319.65011)
		(size 0.4064)
		(drill 0.2032)
		(layers "F.Cu" "B.Cu")
		(net "GND")
	)
	(via
		(at 144.01292 -346.09913)
		(size 0.4572)
		(drill 0.254)
		(layers "F.Cu" "B.Cu")
		(net "GND")
	)
	(via
		(at 418.053012 -345.465146)
		(size 0.4064)
		(drill 0.2032)
		(layers "F.Cu" "B.Cu")
		(net "GND")
	)
	(via
		(at 273.799808 -314.899802)
		(size 0.4064)
		(drill 0.2032)
		(layers "F.Cu" "B.Cu")
		(net "GND")
	)
	(via
		(at 380.290832 -231.07396)
		(size 0.508)
		(drill 0.254)
		(layers "F.Cu" "B.Cu")
		(net "GND")
	)
	(via
		(at 259.470398 -28.802076)
		(size 0.508)
		(drill 0.254)
		(layers "F.Cu" "B.Cu")
		(net "GND")
	)
	(via
		(at 388.20217 -57.461404)
		(size 0.508)
		(drill 0.254)
		(layers "F.Cu" "B.Cu")
		(net "GND")
	)
	(via
		(at 194.749928 -282.599892)
		(size 0.4064)
		(drill 0.2032)
		(layers "F.Cu" "B.Cu")
		(net "GND")
	)
	(via
		(at 413.174942 -303.974754)
		(size 0.4064)
		(drill 0.2032)
		(layers "F.Cu" "B.Cu")
		(net "GND")
	)
	(via
		(at 309.900066 -273.099784)
		(size 0.4064)
		(drill 0.2032)
		(layers "F.Cu" "B.Cu")
		(net "GND")
	)
	(via
		(at 108.142786 -222.382334)
		(size 0.508)
		(drill 0.254)
		(layers "F.Cu" "B.Cu")
		(net "GND")
	)
	(via
		(at 115.596416 -136.291828)
		(size 0.508)
		(drill 0.254)
		(layers "F.Cu" "B.Cu")
		(net "GND")
	)
	(via
		(at 71.760334 -343.073482)
		(size 0.4572)
		(drill 0.254)
		(layers "F.Cu" "B.Cu")
		(net "GND")
	)
	(via
		(at 279.763982 -348.58579)
		(size 0.4064)
		(drill 0.2032)
		(layers "F.Cu" "B.Cu")
		(net "GND")
	)
	(via
		(at 344.127836 -410.041852)
		(size 0.508)
		(drill 0.254)
		(layers "F.Cu" "B.Cu")
		(net "GND")
	)
	(via
		(at 322.890896 -350.977454)
		(size 0.4572)
		(drill 0.254)
		(layers "F.Cu" "B.Cu")
		(net "GND")
	)
	(via
		(at 215.93683 -0.762)
		(size 0.508)
		(drill 0.254)
		(layers "F.Cu" "B.Cu")
		(net "GND")
	)
	(via
		(at 15.15618 -127.021844)
		(size 0.508)
		(drill 0.254)
		(layers "F.Cu" "B.Cu")
		(net "GND")
	)
	(via
		(at 175.749966 -315.849762)
		(size 0.4064)
		(drill 0.2032)
		(layers "F.Cu" "B.Cu")
		(net "GND")
	)
	(via
		(at 308.474872 -299.224954)
		(size 0.4064)
		(drill 0.2032)
		(layers "F.Cu" "B.Cu")
		(net "GND")
	)
	(via
		(at 154.375104 -293.52494)
		(size 0.4064)
		(drill 0.2032)
		(layers "F.Cu" "B.Cu")
		(net "GND")
	)
	(via
		(at 49.863502 -113.780062)
		(size 0.508)
		(drill 0.254)
		(layers "F.Cu" "B.Cu")
		(net "GND")
	)
	(via
		(at 348.5642 -361.4166)
		(size 0.508)
		(drill 0.254)
		(layers "F.Cu" "B.Cu")
		(net "GND")
	)
	(via
		(at 159.347916 -402.241766)
		(size 0.508)
		(drill 0.254)
		(layers "F.Cu" "B.Cu")
		(net "GND")
	)
	(via
		(at 81.84515 -50.516282)
		(size 0.508)
		(drill 0.254)
		(layers "F.Cu" "B.Cu")
		(net "GND")
	)
	(via
		(at 300.757844 -56.809894)
		(size 0.508)
		(drill 0.254)
		(layers "F.Cu" "B.Cu")
		(net "GND")
	)
	(via
		(at 166.725092 -305.874928)
		(size 0.4064)
		(drill 0.2032)
		(layers "F.Cu" "B.Cu")
		(net "GND")
	)
	(via
		(at 8.455152 -33.19018)
		(size 0.508)
		(drill 0.254)
		(layers "F.Cu" "B.Cu")
		(net "GND")
	)
	(via
		(at 281.03449 -71.451978)
		(size 0.508)
		(drill 0.254)
		(layers "F.Cu" "B.Cu")
		(net "GND")
	)
	(via
		(at 18.184622 -73.20026)
		(size 0.508)
		(drill 0.254)
		(layers "F.Cu" "B.Cu")
		(net "GND")
	)
	(via
		(at 200.908158 -149.083522)
		(size 0.508)
		(drill 0.254)
		(layers "F.Cu" "B.Cu")
		(net "GND")
	)
	(via
		(at 295.174924 -293.52494)
		(size 0.4064)
		(drill 0.2032)
		(layers "F.Cu" "B.Cu")
		(net "GND")
	)
	(via
		(at 433.108354 -152.683464)
		(size 0.508)
		(drill 0.254)
		(layers "F.Cu" "B.Cu")
		(net "GND")
	)
	(via
		(at 136.536176 -354.098098)
		(size 0.4572)
		(drill 0.254)
		(layers "F.Cu" "B.Cu")
		(net "GND")
	)
	(via
		(at 248.1072 -212.854794)
		(size 0.508)
		(drill 0.254)
		(layers "F.Cu" "B.Cu")
		(net "GND")
	)
	(via
		(at 393.22502 -283.074872)
		(size 0.4064)
		(drill 0.2032)
		(layers "F.Cu" "B.Cu")
		(net "GND")
	)
	(via
		(at 386.535168 -358.391714)
		(size 0.4572)
		(drill 0.254)
		(layers "F.Cu" "B.Cu")
		(net "GND")
	)
	(via
		(at 395.59992 -278.799798)
		(size 0.4064)
		(drill 0.2032)
		(layers "F.Cu" "B.Cu")
		(net "GND")
	)
	(via
		(at 388.127748 -398.34185)
		(size 0.508)
		(drill 0.254)
		(layers "F.Cu" "B.Cu")
		(net "GND")
	)
	(via
		(at 377.12777 -409.940252)
		(size 0.508)
		(drill 0.254)
		(layers "F.Cu" "B.Cu")
		(net "GND")
	)
	(via
		(at 247.88495 -131.312666)
		(size 0.508)
		(drill 0.254)
		(layers "F.Cu" "B.Cu")
		(net "GND")
	)
	(via
		(at 245.342918 -312.394346)
		(size 0.508)
		(drill 0.254)
		(layers "F.Cu" "B.Cu")
		(net "GND")
	)
	(via
		(at 170.347894 -411.141926)
		(size 0.508)
		(drill 0.254)
		(layers "F.Cu" "B.Cu")
		(net "GND")
	)
	(via
		(at 415.96691 -118.234968)
		(size 0.508)
		(drill 0.254)
		(layers "F.Cu" "B.Cu")
		(net "GND")
	)
	(via
		(at 121.548144 -64.312292)
		(size 0.508)
		(drill 0.254)
		(layers "F.Cu" "B.Cu")
		(net "GND")
	)
	(via
		(at 82.449924 -307.299868)
		(size 0.4064)
		(drill 0.2032)
		(layers "F.Cu" "B.Cu")
		(net "GND")
	)
	(via
		(at 168.148 -372.341902)
		(size 0.508)
		(drill 0.254)
		(layers "F.Cu" "B.Cu")
		(net "GND")
	)
	(via
		(at 17.175988 -145.501868)
		(size 0.508)
		(drill 0.254)
		(layers "F.Cu" "B.Cu")
		(net "GND")
	)
	(via
		(at 90.414094 -358.391714)
		(size 0.4572)
		(drill 0.254)
		(layers "F.Cu" "B.Cu")
		(net "GND")
	)
	(via
		(at 348.077536 -255.18872)
		(size 0.508)
		(drill 0.254)
		(layers "F.Cu" "B.Cu")
		(net "GND")
	)
	(via
		(at 190.348108 -136.645142)
		(size 0.508)
		(drill 0.254)
		(layers "F.Cu" "B.Cu")
		(net "GND")
	)
	(via
		(at 333.127858 -374.938544)
		(size 0.508)
		(drill 0.254)
		(layers "F.Cu" "B.Cu")
		(net "GND")
	)
	(via
		(at 161.025078 -282.124912)
		(size 0.4064)
		(drill 0.2032)
		(layers "F.Cu" "B.Cu")
		(net "GND")
	)
	(via
		(at 49.1998 -273.099784)
		(size 0.4064)
		(drill 0.2032)
		(layers "F.Cu" "B.Cu")
		(net "GND")
	)
	(via
		(at 156.275024 -298.27474)
		(size 0.4064)
		(drill 0.2032)
		(layers "F.Cu" "B.Cu")
		(net "GND")
	)
	(via
		(at 84.54771 -382.84023)
		(size 0.508)
		(drill 0.254)
		(layers "F.Cu" "B.Cu")
		(net "GND")
	)
	(via
		(at 274.757896 -58.156094)
		(size 0.508)
		(drill 0.254)
		(layers "F.Cu" "B.Cu")
		(net "GND")
	)
	(via
		(at 36.14801 -403.738588)
		(size 0.508)
		(drill 0.254)
		(layers "F.Cu" "B.Cu")
		(net "GND")
	)
	(via
		(at 53.323236 -55.083456)
		(size 0.508)
		(drill 0.254)
		(layers "F.Cu" "B.Cu")
		(net "GND")
	)
	(via
		(at 47.29988 -281.649932)
		(size 0.4064)
		(drill 0.2032)
		(layers "F.Cu" "B.Cu")
		(net "GND")
	)
	(via
		(at 36.14801 -402.241766)
		(size 0.508)
		(drill 0.254)
		(layers "F.Cu" "B.Cu")
		(net "GND")
	)
	(via
		(at 433.108354 -123.904502)
		(size 0.508)
		(drill 0.254)
		(layers "F.Cu" "B.Cu")
		(net "GND")
	)
	(via
		(at 40.649906 -312.049922)
		(size 0.4064)
		(drill 0.2032)
		(layers "F.Cu" "B.Cu")
		(net "GND")
	)
	(via
		(at 49.975008 -74.58583)
		(size 0.508)
		(drill 0.254)
		(layers "F.Cu" "B.Cu")
		(net "GND")
	)
	(via
		(at 71.049642 -272.14957)
		(size 0.4064)
		(drill 0.2032)
		(layers "F.Cu" "B.Cu")
		(net "GND")
	)
	(via
		(at 64.874902 -307.774848)
		(size 0.4064)
		(drill 0.2032)
		(layers "F.Cu" "B.Cu")
		(net "GND")
	)
	(via
		(at 339.293708 -227.586794)
		(size 0.4572)
		(drill 0.254)
		(layers "F.Cu" "B.Cu")
		(net "GND")
	)
	(via
		(at 333.677514 -102.271068)
		(size 0.508)
		(drill 0.254)
		(layers "F.Cu" "B.Cu")
		(net "GND")
	)
	(via
		(at 341.927942 -407.24201)
		(size 0.508)
		(drill 0.254)
		(layers "F.Cu" "B.Cu")
		(net "GND")
	)
	(via
		(at 322.032122 -124.743972)
		(size 0.508)
		(drill 0.254)
		(layers "F.Cu" "B.Cu")
		(net "GND")
	)
	(via
		(at 196.174868 -290.674806)
		(size 0.4064)
		(drill 0.2032)
		(layers "F.Cu" "B.Cu")
		(net "GND")
	)
	(via
		(at 463.475324 -276.64283)
		(size 0.508)
		(drill 0.254)
		(layers "F.Cu" "B.Cu")
		(net "GND")
	)
	(via
		(at 391.324846 -290.674806)
		(size 0.4064)
		(drill 0.2032)
		(layers "F.Cu" "B.Cu")
		(net "GND")
	)
	(via
		(at 144.384268 -351.611438)
		(size 0.4064)
		(drill 0.2032)
		(layers "F.Cu" "B.Cu")
		(net "GND")
	)
	(via
		(at 306.574698 -288.774886)
		(size 0.4064)
		(drill 0.2032)
		(layers "F.Cu" "B.Cu")
		(net "GND")
	)
	(via
		(at 133.21665 -241.88166)
		(size 0.508)
		(drill 0.254)
		(layers "F.Cu" "B.Cu")
		(net "GND")
	)
	(via
		(at 79.12481 -298.27474)
		(size 0.4064)
		(drill 0.2032)
		(layers "F.Cu" "B.Cu")
		(net "GND")
	)
	(via
		(at 131.667504 -284.333188)
		(size 0.49022)
		(drill 0.254)
		(layers "F.Cu" "B.Cu")
		(net "GND")
	)
	(via
		(at 274.749768 -310.149748)
		(size 0.4064)
		(drill 0.2032)
		(layers "F.Cu" "B.Cu")
		(net "GND")
	)
	(via
		(at 444.67399 -411.100016)
		(size 0.508)
		(drill 0.254)
		(layers "F.Cu" "B.Cu")
		(net "GND")
	)
	(via
		(at 131.431284 -285.267654)
		(size 0.508)
		(drill 0.254)
		(layers "F.Cu" "B.Cu")
		(net "GND")
	)
	(via
		(at 458.473302 -278.50338)
		(size 0.508)
		(drill 0.254)
		(layers "F.Cu" "B.Cu")
		(net "GND")
	)
	(via
		(at 411.275022 -306.824888)
		(size 0.4064)
		(drill 0.2032)
		(layers "F.Cu" "B.Cu")
		(net "GND")
	)
	(via
		(at 180.50002 -281.649932)
		(size 0.4064)
		(drill 0.2032)
		(layers "F.Cu" "B.Cu")
		(net "GND")
	)
	(via
		(at 401.774914 -302.074834)
		(size 0.4064)
		(drill 0.2032)
		(layers "F.Cu" "B.Cu")
		(net "GND")
	)
	(via
		(at 246.315992 -285.445962)
		(size 0.508)
		(drill 0.254)
		(layers "F.Cu" "B.Cu")
		(net "GND")
	)
	(via
		(at 273.546062 -357.75773)
		(size 0.4064)
		(drill 0.2032)
		(layers "F.Cu" "B.Cu")
		(net "GND")
	)
	(via
		(at 426.230288 -86.949026)
		(size 0.508)
		(drill 0.254)
		(layers "F.Cu" "B.Cu")
		(net "GND")
	)
	(via
		(at 37.799772 -311.099962)
		(size 0.4064)
		(drill 0.2032)
		(layers "F.Cu" "B.Cu")
		(net "GND")
	)
	(via
		(at 266.655042 -27.79014)
		(size 0.508)
		(drill 0.254)
		(layers "F.Cu" "B.Cu")
		(net "GND")
	)
	(via
		(at 170.524932 -305.874928)
		(size 0.4064)
		(drill 0.2032)
		(layers "F.Cu" "B.Cu")
		(net "GND")
	)
	(via
		(at 126.347728 -398.24025)
		(size 0.4572)
		(drill 0.254)
		(layers "F.Cu" "B.Cu")
		(net "GND")
	)
	(via
		(at 250.782074 -58.238644)
		(size 0.508)
		(drill 0.254)
		(layers "F.Cu" "B.Cu")
		(net "GND")
	)
	(via
		(at 228.574092 -157.23616)
		(size 0.508)
		(drill 0.254)
		(layers "F.Cu" "B.Cu")
		(net "GND")
	)
	(via
		(at 267.959586 -123.885452)
		(size 0.508)
		(drill 0.254)
		(layers "F.Cu" "B.Cu")
		(net "GND")
	)
	(via
		(at 288.049716 -309.199788)
		(size 0.4064)
		(drill 0.2032)
		(layers "F.Cu" "B.Cu")
		(net "GND")
	)
	(via
		(at 415.074862 -293.52494)
		(size 0.4064)
		(drill 0.2032)
		(layers "F.Cu" "B.Cu")
		(net "GND")
	)
	(via
		(at 53.94325 -28.139136)
		(size 0.508)
		(drill 0.254)
		(layers "F.Cu" "B.Cu")
		(net "GND")
	)
	(via
		(at 74.84999 -309.199788)
		(size 0.4064)
		(drill 0.2032)
		(layers "F.Cu" "B.Cu")
		(net "GND")
	)
	(via
		(at 285.674816 -285.924752)
		(size 0.4064)
		(drill 0.2032)
		(layers "F.Cu" "B.Cu")
		(net "GND")
	)
	(via
		(at 185.923936 -130.710432)
		(size 0.508)
		(drill 0.254)
		(layers "F.Cu" "B.Cu")
		(net "GND")
	)
	(via
		(at 64.399922 -281.649932)
		(size 0.4064)
		(drill 0.2032)
		(layers "F.Cu" "B.Cu")
		(net "GND")
	)
	(via
		(at 292.79977 -276.899878)
		(size 0.4064)
		(drill 0.2032)
		(layers "F.Cu" "B.Cu")
		(net "GND")
	)
	(via
		(at 80.898238 -142.418054)
		(size 0.508)
		(drill 0.254)
		(layers "F.Cu" "B.Cu")
		(net "GND")
	)
	(via
		(at 181.92496 -291.624766)
		(size 0.4064)
		(drill 0.2032)
		(layers "F.Cu" "B.Cu")
		(net "GND")
	)
	(via
		(at 159.347916 -407.638504)
		(size 0.508)
		(drill 0.254)
		(layers "F.Cu" "B.Cu")
		(net "GND")
	)
	(via
		(at 401.78736 -107.844844)
		(size 0.508)
		(drill 0.254)
		(layers "F.Cu" "B.Cu")
		(net "GND")
	)
	(via
		(at 463.037682 -159.017462)
		(size 0.508)
		(drill 0.254)
		(layers "F.Cu" "B.Cu")
		(net "GND")
	)
	(via
		(at 40.649906 -302.549814)
		(size 0.4064)
		(drill 0.2032)
		(layers "F.Cu" "B.Cu")
		(net "GND")
	)
	(via
		(at 56.799988 -313.949842)
		(size 0.4064)
		(drill 0.2032)
		(layers "F.Cu" "B.Cu")
		(net "GND")
	)
	(via
		(at 295.68013 -352.245422)
		(size 0.4572)
		(drill 0.254)
		(layers "F.Cu" "B.Cu")
		(net "GND")
	)
	(via
		(at 442.580776 -31.390082)
		(size 0.508)
		(drill 0.254)
		(layers "F.Cu" "B.Cu")
		(net "GND")
	)
	(via
		(at 466.835998 -303.083976)
		(size 0.508)
		(drill 0.254)
		(layers "F.Cu" "B.Cu")
		(net "GND")
	)
	(via
		(at 291.092382 -342.439498)
		(size 0.4064)
		(drill 0.2032)
		(layers "F.Cu" "B.Cu")
		(net "GND")
	)
	(via
		(at 170.049698 -272.14957)
		(size 0.4064)
		(drill 0.2032)
		(layers "F.Cu" "B.Cu")
		(net "GND")
	)
	(via
		(at 170.347894 -406.040336)
		(size 0.508)
		(drill 0.254)
		(layers "F.Cu" "B.Cu")
		(net "GND")
	)
	(via
		(at 307.999892 -278.799798)
		(size 0.4064)
		(drill 0.2032)
		(layers "F.Cu" "B.Cu")
		(net "GND")
	)
	(via
		(at 236.25683 -0.762)
		(size 0.508)
		(drill 0.254)
		(layers "F.Cu" "B.Cu")
		(net "GND")
	)
	(via
		(at 380.317248 -341.805514)
		(size 0.4572)
		(drill 0.254)
		(layers "F.Cu" "B.Cu")
		(net "GND")
	)
	(via
		(at 421.249856 -316.799722)
		(size 0.4064)
		(drill 0.2032)
		(layers "F.Cu" "B.Cu")
		(net "GND")
	)
	(via
		(at 411.749748 -272.14957)
		(size 0.4064)
		(drill 0.2032)
		(layers "F.Cu" "B.Cu")
		(net "GND")
	)
	(via
		(at 168.148 -397.140176)
		(size 0.508)
		(drill 0.254)
		(layers "F.Cu" "B.Cu")
		(net "GND")
	)
	(via
		(at 435.948836 -29.589984)
		(size 0.508)
		(drill 0.254)
		(layers "F.Cu" "B.Cu")
		(net "GND")
	)
	(via
		(at 269.049754 -300.649894)
		(size 0.4064)
		(drill 0.2032)
		(layers "F.Cu" "B.Cu")
		(net "GND")
	)
	(via
		(at 220.241622 -146.990562)
		(size 0.508)
		(drill 0.254)
		(layers "F.Cu" "B.Cu")
		(net "GND")
	)
	(via
		(at 364.123732 -395.062964)
		(size 0.508)
		(drill 0.254)
		(layers "F.Cu" "B.Cu")
		(net "GND")
	)
	(via
		(at 40.649906 -316.799722)
		(size 0.4064)
		(drill 0.2032)
		(layers "F.Cu" "B.Cu")
		(net "GND")
	)
	(via
		(at 421.53332 -343.073482)
		(size 0.4572)
		(drill 0.254)
		(layers "F.Cu" "B.Cu")
		(net "GND")
	)
	(via
		(at 354.900992 -34.990278)
		(size 0.508)
		(drill 0.254)
		(layers "F.Cu" "B.Cu")
		(net "GND")
	)
	(via
		(at 341.59952 -269.366492)
		(size 0.508)
		(drill 0.254)
		(layers "F.Cu" "B.Cu")
		(net "GND")
	)
	(via
		(at 136.164828 -345.465146)
		(size 0.4064)
		(drill 0.2032)
		(layers "F.Cu" "B.Cu")
		(net "GND")
	)
	(via
		(at 403.338792 -349.219774)
		(size 0.4572)
		(drill 0.254)
		(layers "F.Cu" "B.Cu")
		(net "GND")
	)
	(via
		(at 385.865624 -151.40813)
		(size 0.508)
		(drill 0.254)
		(layers "F.Cu" "B.Cu")
		(net "GND")
	)
	(via
		(at 119.478806 -98.946462)
		(size 0.508)
		(drill 0.254)
		(layers "F.Cu" "B.Cu")
		(net "GND")
	)
	(via
		(at 150.59152 -104.523286)
		(size 0.508)
		(drill 0.254)
		(layers "F.Cu" "B.Cu")
		(net "GND")
	)
	(via
		(at 53.48732 -124.154946)
		(size 0.508)
		(drill 0.254)
		(layers "F.Cu" "B.Cu")
		(net "GND")
	)
	(via
		(at 374.927876 -375.040144)
		(size 0.508)
		(drill 0.254)
		(layers "F.Cu" "B.Cu")
		(net "GND")
	)
	(via
		(at 374.493536 -289.532314)
		(size 0.508)
		(drill 0.254)
		(layers "F.Cu" "B.Cu")
		(net "GND")
	)
	(via
		(at 427.727872 -397.140176)
		(size 0.508)
		(drill 0.254)
		(layers "F.Cu" "B.Cu")
		(net "GND")
	)
	(via
		(at 279.024842 -286.874966)
		(size 0.4064)
		(drill 0.2032)
		(layers "F.Cu" "B.Cu")
		(net "GND")
	)
	(via
		(at 275.176234 -350.977454)
		(size 0.4572)
		(drill 0.254)
		(layers "F.Cu" "B.Cu")
		(net "GND")
	)
	(via
		(at 119.013732 -128.947926)
		(size 0.508)
		(drill 0.254)
		(layers "F.Cu" "B.Cu")
		(net "GND")
	)
	(via
		(at 40.547798 -371.140228)
		(size 0.508)
		(drill 0.254)
		(layers "F.Cu" "B.Cu")
		(net "GND")
	)
	(via
		(at 358.14 -186.182)
		(size 0.508)
		(drill 0.254)
		(layers "F.Cu" "B.Cu")
		(net "GND")
	)
	(via
		(at 120.309132 -118.67261)
		(size 0.508)
		(drill 0.254)
		(layers "F.Cu" "B.Cu")
		(net "GND")
	)
	(via
		(at 199.025002 -301.124874)
		(size 0.4064)
		(drill 0.2032)
		(layers "F.Cu" "B.Cu")
		(net "GND")
	)
	(via
		(at 52.85232 -100.64496)
		(size 0.508)
		(drill 0.254)
		(layers "F.Cu" "B.Cu")
		(net "GND")
	)
	(via
		(at 408.49296 -83.566)
		(size 0.508)
		(drill 0.254)
		(layers "F.Cu" "B.Cu")
		(net "GND")
	)
	(via
		(at 352.058478 -86.6648)
		(size 0.508)
		(drill 0.254)
		(layers "F.Cu" "B.Cu")
		(net "GND")
	)
	(via
		(at 263.782302 -37.087048)
		(size 0.508)
		(drill 0.254)
		(layers "F.Cu" "B.Cu")
		(net "GND")
	)
	(via
		(at 181.912514 -123.635008)
		(size 0.508)
		(drill 0.254)
		(layers "F.Cu" "B.Cu")
		(net "GND")
	)
	(via
		(at 392.749786 -276.899878)
		(size 0.4064)
		(drill 0.2032)
		(layers "F.Cu" "B.Cu")
		(net "GND")
	)
	(via
		(at 344.8939 -217.187018)
		(size 0.4572)
		(drill 0.254)
		(layers "F.Cu" "B.Cu")
		(net "GND")
	)
	(via
		(at 422.674796 -298.27474)
		(size 0.4064)
		(drill 0.2032)
		(layers "F.Cu" "B.Cu")
		(net "GND")
	)
	(via
		(at 425.99991 -285.449772)
		(size 0.4064)
		(drill 0.2032)
		(layers "F.Cu" "B.Cu")
		(net "GND")
	)
	(via
		(at 87.676482 -348.58579)
		(size 0.4064)
		(drill 0.2032)
		(layers "F.Cu" "B.Cu")
		(net "GND")
	)
	(via
		(at 277.251668 -113.245138)
		(size 0.508)
		(drill 0.254)
		(layers "F.Cu" "B.Cu")
		(net "GND")
	)
	(via
		(at 291.84981 -316.799722)
		(size 0.4064)
		(drill 0.2032)
		(layers "F.Cu" "B.Cu")
		(net "GND")
	)
	(via
		(at 120.568212 -217.911426)
		(size 0.508)
		(drill 0.254)
		(layers "F.Cu" "B.Cu")
		(net "GND")
	)
	(via
		(at 154.850084 -304.449734)
		(size 0.4064)
		(drill 0.2032)
		(layers "F.Cu" "B.Cu")
		(net "GND")
	)
	(via
		(at 188.37402 -73.85177)
		(size 0.508)
		(drill 0.254)
		(layers "F.Cu" "B.Cu")
		(net "GND")
	)
	(via
		(at 82.449924 -317.749936)
		(size 0.4064)
		(drill 0.2032)
		(layers "F.Cu" "B.Cu")
		(net "GND")
	)
	(via
		(at 366.971326 -28.05303)
		(size 0.508)
		(drill 0.254)
		(layers "F.Cu" "B.Cu")
		(net "GND")
	)
	(via
		(at 49.429416 -47.020734)
		(size 0.508)
		(drill 0.254)
		(layers "F.Cu" "B.Cu")
		(net "GND")
	)
	(via
		(at 279.992074 -70.918832)
		(size 0.508)
		(drill 0.254)
		(layers "F.Cu" "B.Cu")
		(net "GND")
	)
	(via
		(at 300.047914 -350.977454)
		(size 0.4572)
		(drill 0.254)
		(layers "F.Cu" "B.Cu")
		(net "GND")
	)
	(via
		(at 334.067912 -347.951806)
		(size 0.4572)
		(drill 0.254)
		(layers "F.Cu" "B.Cu")
		(net "GND")
	)
	(via
		(at 158.380938 -29.589984)
		(size 0.508)
		(drill 0.254)
		(layers "F.Cu" "B.Cu")
		(net "GND")
	)
	(via
		(at 412.89351 -125.435106)
		(size 0.508)
		(drill 0.254)
		(layers "F.Cu" "B.Cu")
		(net "GND")
	)
	(via
		(at 130.318256 -357.123746)
		(size 0.4572)
		(drill 0.254)
		(layers "F.Cu" "B.Cu")
		(net "GND")
	)
	(via
		(at 272.849848 -310.149748)
		(size 0.4064)
		(drill 0.2032)
		(layers "F.Cu" "B.Cu")
		(net "GND")
	)
	(via
		(at 259.515102 -45.88891)
		(size 0.508)
		(drill 0.254)
		(layers "F.Cu" "B.Cu")
		(net "GND")
	)
	(via
		(at 315.414152 -355.366066)
		(size 0.4572)
		(drill 0.254)
		(layers "F.Cu" "B.Cu")
		(net "GND")
	)
	(via
		(at 153.42489 -290.674806)
		(size 0.4064)
		(drill 0.2032)
		(layers "F.Cu" "B.Cu")
		(net "GND")
	)
	(via
		(at 133.722872 -23.880318)
		(size 0.508)
		(drill 0.254)
		(layers "F.Cu" "B.Cu")
		(net "GND")
	)
	(via
		(at 359.535476 -290.05149)
		(size 0.508)
		(drill 0.254)
		(layers "F.Cu" "B.Cu")
		(net "GND")
	)
	(via
		(at 292.199822 -342.439498)
		(size 0.4064)
		(drill 0.2032)
		(layers "F.Cu" "B.Cu")
		(net "GND")
	)
	(via
		(at 383.068068 -54.238906)
		(size 0.508)
		(drill 0.254)
		(layers "F.Cu" "B.Cu")
		(net "GND")
	)
	(via
		(at 418.399976 -278.799798)
		(size 0.4064)
		(drill 0.2032)
		(layers "F.Cu" "B.Cu")
		(net "GND")
	)
	(via
		(at 115.34775 -382.84023)
		(size 0.4572)
		(drill 0.254)
		(layers "F.Cu" "B.Cu")
		(net "GND")
	)
	(via
		(at 353.667568 -286.842454)
		(size 0.508)
		(drill 0.254)
		(layers "F.Cu" "B.Cu")
		(net "GND")
	)
	(via
		(at 357.948992 -27.79014)
		(size 0.508)
		(drill 0.254)
		(layers "F.Cu" "B.Cu")
		(net "GND")
	)
	(via
		(at 128.547622 -377.738386)
		(size 0.508)
		(drill 0.254)
		(layers "F.Cu" "B.Cu")
		(net "GND")
	)
	(via
		(at 191.440054 -73.23963)
		(size 0.508)
		(drill 0.254)
		(layers "F.Cu" "B.Cu")
		(net "GND")
	)
	(via
		(at 205.844902 -29.589984)
		(size 0.508)
		(drill 0.254)
		(layers "F.Cu" "B.Cu")
		(net "GND")
	)
	(via
		(at 466.835998 -257.363976)
		(size 0.508)
		(drill 0.254)
		(layers "F.Cu" "B.Cu")
		(net "GND")
	)
	(via
		(at 64.874902 -293.52494)
		(size 0.4064)
		(drill 0.2032)
		(layers "F.Cu" "B.Cu")
		(net "GND")
	)
	(via
		(at 230.892096 -145.896076)
		(size 0.508)
		(drill 0.254)
		(layers "F.Cu" "B.Cu")
		(net "GND")
	)
	(via
		(at 196.649848 -276.899878)
		(size 0.4064)
		(drill 0.2032)
		(layers "F.Cu" "B.Cu")
		(net "GND")
	)
	(via
		(at 297.074844 -287.824926)
		(size 0.4064)
		(drill 0.2032)
		(layers "F.Cu" "B.Cu")
		(net "GND")
	)
	(via
		(at 421.127682 -398.24025)
		(size 0.508)
		(drill 0.254)
		(layers "F.Cu" "B.Cu")
		(net "GND")
	)
	(via
		(at 431.700178 -285.450026)
		(size 0.4064)
		(drill 0.2032)
		(layers "F.Cu" "B.Cu")
		(net "GND")
	)
	(via
		(at 22.251416 -45.865288)
		(size 0.508)
		(drill 0.254)
		(layers "F.Cu" "B.Cu")
		(net "GND")
	)
	(via
		(at 125.35916 -350.977454)
		(size 0.4572)
		(drill 0.254)
		(layers "F.Cu" "B.Cu")
		(net "GND")
	)
	(via
		(at 346.327984 -409.940252)
		(size 0.508)
		(drill 0.254)
		(layers "F.Cu" "B.Cu")
		(net "GND")
	)
	(via
		(at 380.317248 -357.123746)
		(size 0.4572)
		(drill 0.254)
		(layers "F.Cu" "B.Cu")
		(net "GND")
	)
	(via
		(at 182.87492 -305.874928)
		(size 0.4064)
		(drill 0.2032)
		(layers "F.Cu" "B.Cu")
		(net "GND")
	)
	(via
		(at 60.455048 -27.79014)
		(size 0.508)
		(drill 0.254)
		(layers "F.Cu" "B.Cu")
		(net "GND")
	)
	(via
		(at 282.349702 -281.649932)
		(size 0.4064)
		(drill 0.2032)
		(layers "F.Cu" "B.Cu")
		(net "GND")
	)
	(via
		(at 285.523178 -51.019456)
		(size 0.508)
		(drill 0.254)
		(layers "F.Cu" "B.Cu")
		(net "GND")
	)
	(via
		(at 424.100244 -274.049744)
		(size 0.4064)
		(drill 0.2032)
		(layers "F.Cu" "B.Cu")
		(net "GND")
	)
	(via
		(at 427.379892 -357.75773)
		(size 0.4064)
		(drill 0.2032)
		(layers "F.Cu" "B.Cu")
		(net "GND")
	)
	(via
		(at 65.349882 -274.999958)
		(size 0.4064)
		(drill 0.2032)
		(layers "F.Cu" "B.Cu")
		(net "GND")
	)
	(via
		(at 86.747858 -373.441976)
		(size 0.508)
		(drill 0.254)
		(layers "F.Cu" "B.Cu")
		(net "GND")
	)
	(via
		(at 289.076892 -138.15695)
		(size 0.508)
		(drill 0.254)
		(layers "F.Cu" "B.Cu")
		(net "GND")
	)
	(via
		(at 412.224982 -302.074834)
		(size 0.4064)
		(drill 0.2032)
		(layers "F.Cu" "B.Cu")
		(net "GND")
	)
	(via
		(at 415.96691 -143.955008)
		(size 0.508)
		(drill 0.254)
		(layers "F.Cu" "B.Cu")
		(net "GND")
	)
	(via
		(at 396.88135 -34.718498)
		(size 0.508)
		(drill 0.254)
		(layers "F.Cu" "B.Cu")
		(net "GND")
	)
	(via
		(at 54.899814 -312.999882)
		(size 0.4064)
		(drill 0.2032)
		(layers "F.Cu" "B.Cu")
		(net "GND")
	)
	(via
		(at 333.640684 -45.853858)
		(size 0.508)
		(drill 0.254)
		(layers "F.Cu" "B.Cu")
		(net "GND")
	)
	(via
		(at 347.089222 -254.210312)
		(size 0.508)
		(drill 0.254)
		(layers "F.Cu" "B.Cu")
		(net "GND")
	)
	(via
		(at 27.668982 -286.331914)
		(size 0.508)
		(drill 0.254)
		(layers "F.Cu" "B.Cu")
		(net "GND")
	)
	(via
		(at 105.948734 -237.918244)
		(size 0.508)
		(drill 0.254)
		(layers "F.Cu" "B.Cu")
		(net "GND")
	)
	(via
		(at 52.524914 -303.974754)
		(size 0.4064)
		(drill 0.2032)
		(layers "F.Cu" "B.Cu")
		(net "GND")
	)
	(via
		(at 49.975008 -73.23963)
		(size 0.508)
		(drill 0.254)
		(layers "F.Cu" "B.Cu")
		(net "GND")
	)
	(via
		(at 73.899776 -289.249866)
		(size 0.4064)
		(drill 0.2032)
		(layers "F.Cu" "B.Cu")
		(net "GND")
	)
	(via
		(at 185.780172 -156.554932)
		(size 0.508)
		(drill 0.254)
		(layers "F.Cu" "B.Cu")
		(net "GND")
	)
	(via
		(at 73.547732 -380.040134)
		(size 0.508)
		(drill 0.254)
		(layers "F.Cu" "B.Cu")
		(net "GND")
	)
	(via
		(at 417.924996 -300.174914)
		(size 0.4064)
		(drill 0.2032)
		(layers "F.Cu" "B.Cu")
		(net "GND")
	)
	(via
		(at 130.150616 -159.857948)
		(size 0.508)
		(drill 0.254)
		(layers "F.Cu" "B.Cu")
		(net "GND")
	)
	(via
		(at 254.29845 -37.201094)
		(size 0.508)
		(drill 0.254)
		(layers "F.Cu" "B.Cu")
		(net "GND")
	)
	(via
		(at 177.5333 -357.123746)
		(size 0.4572)
		(drill 0.254)
		(layers "F.Cu" "B.Cu")
		(net "GND")
	)
	(via
		(at 412.224982 -294.4749)
		(size 0.4064)
		(drill 0.2032)
		(layers "F.Cu" "B.Cu")
		(net "GND")
	)
	(via
		(at 395.59992 -276.899878)
		(size 0.4064)
		(drill 0.2032)
		(layers "F.Cu" "B.Cu")
		(net "GND")
	)
	(via
		(at 445.031114 -11.372342)
		(size 0.508)
		(drill 0.254)
		(layers "F.Cu" "B.Cu")
		(net "GND")
	)
	(via
		(at 0.77089 -258.581144)
		(size 0.508)
		(drill 0.254)
		(layers "F.Cu" "B.Cu")
		(net "GND")
	)
	(via
		(at 134.68604 -355.366066)
		(size 0.4572)
		(drill 0.254)
		(layers "F.Cu" "B.Cu")
		(net "GND")
	)
	(via
		(at 269.988538 -31.642304)
		(size 0.508)
		(drill 0.254)
		(layers "F.Cu" "B.Cu")
		(net "GND")
	)
	(via
		(at 345.024964 -354.732082)
		(size 0.4064)
		(drill 0.2032)
		(layers "F.Cu" "B.Cu")
		(net "GND")
	)
	(via
		(at 355.572568 -286.842454)
		(size 0.508)
		(drill 0.254)
		(layers "F.Cu" "B.Cu")
		(net "GND")
	)
	(via
		(at 415.3154 -357.123746)
		(size 0.4572)
		(drill 0.254)
		(layers "F.Cu" "B.Cu")
		(net "GND")
	)
	(via
		(at 351.328736 -149.263862)
		(size 0.508)
		(drill 0.254)
		(layers "F.Cu" "B.Cu")
		(net "GND")
	)
	(via
		(at 18.28673 -135.318246)
		(size 0.508)
		(drill 0.254)
		(layers "F.Cu" "B.Cu")
		(net "GND")
	)
	(via
		(at 361.45851 -383.115058)
		(size 0.508)
		(drill 0.254)
		(layers "F.Cu" "B.Cu")
		(net "GND")
	)
	(via
		(at 296.938954 -346.09913)
		(size 0.4572)
		(drill 0.254)
		(layers "F.Cu" "B.Cu")
		(net "GND")
	)
	(via
		(at 188.574934 -300.174914)
		(size 0.4064)
		(drill 0.2032)
		(layers "F.Cu" "B.Cu")
		(net "GND")
	)
	(via
		(at 78.17485 -297.32478)
		(size 0.4064)
		(drill 0.2032)
		(layers "F.Cu" "B.Cu")
		(net "GND")
	)
	(via
		(at 167.200072 -310.149748)
		(size 0.4064)
		(drill 0.2032)
		(layers "F.Cu" "B.Cu")
		(net "GND")
	)
	(via
		(at 31.199328 -354.732082)
		(size 0.4064)
		(drill 0.2032)
		(layers "F.Cu" "B.Cu")
		(net "GND")
	)
	(via
		(at 217.140028 -118.361714)
		(size 0.508)
		(drill 0.254)
		(layers "F.Cu" "B.Cu")
		(net "GND")
	)
	(via
		(at 235.676186 -45.808138)
		(size 0.508)
		(drill 0.254)
		(layers "F.Cu" "B.Cu")
		(net "GND")
	)
	(via
		(at 49.975008 -73.87463)
		(size 0.508)
		(drill 0.254)
		(layers "F.Cu" "B.Cu")
		(net "GND")
	)
	(via
		(at 405.575008 -285.924752)
		(size 0.4064)
		(drill 0.2032)
		(layers "F.Cu" "B.Cu")
		(net "GND")
	)
	(via
		(at 415.85007 -109.244892)
		(size 0.508)
		(drill 0.254)
		(layers "F.Cu" "B.Cu")
		(net "GND")
	)
	(via
		(at 22.8346 -71.451978)
		(size 0.508)
		(drill 0.254)
		(layers "F.Cu" "B.Cu")
		(net "GND")
	)
	(via
		(at 161.54781 -376.140218)
		(size 0.508)
		(drill 0.254)
		(layers "F.Cu" "B.Cu")
		(net "GND")
	)
	(via
		(at 67.249802 -315.849762)
		(size 0.4064)
		(drill 0.2032)
		(layers "F.Cu" "B.Cu")
		(net "GND")
	)
	(via
		(at 273.324828 -272.624804)
		(size 0.4064)
		(drill 0.2032)
		(layers "F.Cu" "B.Cu")
		(net "GND")
	)
	(via
		(at 41.599866 -317.749936)
		(size 0.4064)
		(drill 0.2032)
		(layers "F.Cu" "B.Cu")
		(net "GND")
	)
	(via
		(at 312.749946 -280.699718)
		(size 0.4064)
		(drill 0.2032)
		(layers "F.Cu" "B.Cu")
		(net "GND")
	)
	(via
		(at 192.850008 -316.799722)
		(size 0.4064)
		(drill 0.2032)
		(layers "F.Cu" "B.Cu")
		(net "GND")
	)
	(via
		(at 410.727652 -351.611438)
		(size 0.4064)
		(drill 0.2032)
		(layers "F.Cu" "B.Cu")
		(net "GND")
	)
	(via
		(at 205.898242 -21.077936)
		(size 0.508)
		(drill 0.254)
		(layers "F.Cu" "B.Cu")
		(net "GND")
	)
	(via
		(at 290.89985 -317.749936)
		(size 0.4064)
		(drill 0.2032)
		(layers "F.Cu" "B.Cu")
		(net "GND")
	)
	(via
		(at 336.805524 -345.465146)
		(size 0.4064)
		(drill 0.2032)
		(layers "F.Cu" "B.Cu")
		(net "GND")
	)
	(via
		(at 212.771228 -28.05303)
		(size 0.508)
		(drill 0.254)
		(layers "F.Cu" "B.Cu")
		(net "GND")
	)
	(via
		(at 418.874956 -301.124874)
		(size 0.4064)
		(drill 0.2032)
		(layers "F.Cu" "B.Cu")
		(net "GND")
	)
	(via
		(at 42.747946 -383.940304)
		(size 0.508)
		(drill 0.254)
		(layers "F.Cu" "B.Cu")
		(net "GND")
	)
	(via
		(at 128.547622 -402.241766)
		(size 0.4572)
		(drill 0.254)
		(layers "F.Cu" "B.Cu")
		(net "GND")
	)
	(via
		(at 112.333786 -286.842454)
		(size 0.508)
		(drill 0.254)
		(layers "F.Cu" "B.Cu")
		(net "GND")
	)
	(via
		(at 336.182716 -245.776242)
		(size 0.508)
		(drill 0.254)
		(layers "F.Cu" "B.Cu")
		(net "GND")
	)
	(via
		(at 197.817232 -345.465146)
		(size 0.4064)
		(drill 0.2032)
		(layers "F.Cu" "B.Cu")
		(net "GND")
	)
	(via
		(at 153.061162 -257.137916)
		(size 0.508)
		(drill 0.254)
		(layers "F.Cu" "B.Cu")
		(net "GND")
	)
	(via
		(at 9.648952 -27.79014)
		(size 0.508)
		(drill 0.254)
		(layers "F.Cu" "B.Cu")
		(net "GND")
	)
	(via
		(at 227.925376 -106.421682)
		(size 0.508)
		(drill 0.254)
		(layers "F.Cu" "B.Cu")
		(net "GND")
	)
	(via
		(at 101.01453 -326.916034)
		(size 0.508)
		(drill 0.254)
		(layers "F.Cu" "B.Cu")
		(net "GND")
	)
	(via
		(at 180.50002 -273.099784)
		(size 0.4064)
		(drill 0.2032)
		(layers "F.Cu" "B.Cu")
		(net "GND")
	)
	(via
		(at 133.833108 -120.890284)
		(size 0.508)
		(drill 0.254)
		(layers "F.Cu" "B.Cu")
		(net "GND")
	)
	(via
		(at 258.991862 -399.203926)
		(size 0.508)
		(drill 0.254)
		(layers "F.Cu" "B.Cu")
		(net "GND")
	)
	(via
		(at 178.792124 -347.951806)
		(size 0.4572)
		(drill 0.254)
		(layers "F.Cu" "B.Cu")
		(net "GND")
	)
	(via
		(at 385.149852 -315.849762)
		(size 0.4064)
		(drill 0.2032)
		(layers "F.Cu" "B.Cu")
		(net "GND")
	)
	(via
		(at 297.927776 -385.141978)
		(size 0.508)
		(drill 0.254)
		(layers "F.Cu" "B.Cu")
		(net "GND")
	)
	(via
		(at 174.800006 -312.999882)
		(size 0.4064)
		(drill 0.2032)
		(layers "F.Cu" "B.Cu")
		(net "GND")
	)
	(via
		(at 408.899868 -310.149748)
		(size 0.4064)
		(drill 0.2032)
		(layers "F.Cu" "B.Cu")
		(net "GND")
	)
	(via
		(at 242.269264 -145.083276)
		(size 0.508)
		(drill 0.254)
		(layers "F.Cu" "B.Cu")
		(net "GND")
	)
	(via
		(at 387.999986 -313.949842)
		(size 0.4064)
		(drill 0.2032)
		(layers "F.Cu" "B.Cu")
		(net "GND")
	)
	(via
		(at 302.396144 -60.099194)
		(size 0.508)
		(drill 0.254)
		(layers "F.Cu" "B.Cu")
		(net "GND")
	)
	(via
		(at 183.766714 -125.435106)
		(size 0.508)
		(drill 0.254)
		(layers "F.Cu" "B.Cu")
		(net "GND")
	)
	(via
		(at 100.476558 -115.732814)
		(size 0.508)
		(drill 0.254)
		(layers "F.Cu" "B.Cu")
		(net "GND")
	)
	(via
		(at 163.874958 -284.974792)
		(size 0.4064)
		(drill 0.2032)
		(layers "F.Cu" "B.Cu")
		(net "GND")
	)
	(via
		(at 269.999714 -301.599854)
		(size 0.4064)
		(drill 0.2032)
		(layers "F.Cu" "B.Cu")
		(net "GND")
	)
	(via
		(at 227.867972 -221.103952)
		(size 0.4572)
		(drill 0.254)
		(layers "F.Cu" "B.Cu")
		(net "GND")
	)
	(via
		(at 46.34992 -276.899878)
		(size 0.4064)
		(drill 0.2032)
		(layers "F.Cu" "B.Cu")
		(net "GND")
	)
	(via
		(at 23.737824 -165.058852)
		(size 0.508)
		(drill 0.254)
		(layers "F.Cu" "B.Cu")
		(net "GND")
	)
	(via
		(at 305.149758 -274.999958)
		(size 0.4064)
		(drill 0.2032)
		(layers "F.Cu" "B.Cu")
		(net "GND")
	)
	(via
		(at 259.923026 -238.232188)
		(size 0.508)
		(drill 0.254)
		(layers "F.Cu" "B.Cu")
		(net "GND")
	)
	(via
		(at 362.458 -207.899)
		(size 0.508)
		(drill 0.254)
		(layers "F.Cu" "B.Cu")
		(net "GND")
	)
	(via
		(at 152.47493 -287.824926)
		(size 0.4064)
		(drill 0.2032)
		(layers "F.Cu" "B.Cu")
		(net "GND")
	)
	(via
		(at 396.26032 -20.35556)
		(size 0.508)
		(drill 0.254)
		(layers "F.Cu" "B.Cu")
		(net "GND")
	)
	(via
		(at 267.328142 -342.439498)
		(size 0.4064)
		(drill 0.2032)
		(layers "F.Cu" "B.Cu")
		(net "GND")
	)
	(via
		(at 155.800044 -306.349908)
		(size 0.4064)
		(drill 0.2032)
		(layers "F.Cu" "B.Cu")
		(net "GND")
	)
	(via
		(at 103.427022 -224.425764)
		(size 0.508)
		(drill 0.254)
		(layers "F.Cu" "B.Cu")
		(net "GND")
	)
	(via
		(at 158.174944 -280.224738)
		(size 0.4064)
		(drill 0.2032)
		(layers "F.Cu" "B.Cu")
		(net "GND")
	)
	(via
		(at 414.548828 -27.79014)
		(size 0.508)
		(drill 0.254)
		(layers "F.Cu" "B.Cu")
		(net "GND")
	)
	(via
		(at 38.347904 -403.34184)
		(size 0.508)
		(drill 0.254)
		(layers "F.Cu" "B.Cu")
		(net "GND")
	)
	(via
		(at 83.540346 -155.024582)
		(size 0.508)
		(drill 0.254)
		(layers "F.Cu" "B.Cu")
		(net "GND")
	)
	(via
		(at 225.827082 -198.214234)
		(size 0.508)
		(drill 0.254)
		(layers "F.Cu" "B.Cu")
		(net "GND")
	)
	(via
		(at 277.02637 -352.245422)
		(size 0.4572)
		(drill 0.254)
		(layers "F.Cu" "B.Cu")
		(net "GND")
	)
	(via
		(at 275.699728 -314.899802)
		(size 0.4064)
		(drill 0.2032)
		(layers "F.Cu" "B.Cu")
		(net "GND")
	)
	(via
		(at 70.099936 -278.799798)
		(size 0.4064)
		(drill 0.2032)
		(layers "F.Cu" "B.Cu")
		(net "GND")
	)
	(via
		(at 388.949946 -301.599854)
		(size 0.4064)
		(drill 0.2032)
		(layers "F.Cu" "B.Cu")
		(net "GND")
	)
	(via
		(at 391.324846 -284.024832)
		(size 0.4064)
		(drill 0.2032)
		(layers "F.Cu" "B.Cu")
		(net "GND")
	)
	(via
		(at 377.12777 -404.838662)
		(size 0.508)
		(drill 0.254)
		(layers "F.Cu" "B.Cu")
		(net "GND")
	)
	(via
		(at 395.4907 -348.58579)
		(size 0.4064)
		(drill 0.2032)
		(layers "F.Cu" "B.Cu")
		(net "GND")
	)
	(via
		(at 36.374832 -277.374858)
		(size 0.4064)
		(drill 0.2032)
		(layers "F.Cu" "B.Cu")
		(net "GND")
	)
	(via
		(at 135.840978 -186.460638)
		(size 0.508)
		(drill 0.254)
		(layers "F.Cu" "B.Cu")
		(net "GND")
	)
	(via
		(at 40.174926 -280.224738)
		(size 0.4064)
		(drill 0.2032)
		(layers "F.Cu" "B.Cu")
		(net "GND")
	)
	(via
		(at 216.086182 -117.191028)
		(size 0.508)
		(drill 0.254)
		(layers "F.Cu" "B.Cu")
		(net "GND")
	)
	(via
		(at 177.161952 -348.58579)
		(size 0.4064)
		(drill 0.2032)
		(layers "F.Cu" "B.Cu")
		(net "GND")
	)
	(via
		(at 415.96691 -133.044946)
		(size 0.508)
		(drill 0.254)
		(layers "F.Cu" "B.Cu")
		(net "GND")
	)
	(via
		(at 406.279858 -101.782372)
		(size 0.508)
		(drill 0.254)
		(layers "F.Cu" "B.Cu")
		(net "GND")
	)
	(via
		(at 406.999948 -312.999882)
		(size 0.4064)
		(drill 0.2032)
		(layers "F.Cu" "B.Cu")
		(net "GND")
	)
	(via
		(at 344.093546 -221.986856)
		(size 0.4572)
		(drill 0.254)
		(layers "F.Cu" "B.Cu")
		(net "GND")
	)
	(via
		(at 283.299916 -277.849838)
		(size 0.4064)
		(drill 0.2032)
		(layers "F.Cu" "B.Cu")
		(net "GND")
	)
	(via
		(at 292.688264 -189.64275)
		(size 0.508)
		(drill 0.254)
		(layers "F.Cu" "B.Cu")
		(net "GND")
	)
	(via
		(at 57.749948 -274.999958)
		(size 0.4064)
		(drill 0.2032)
		(layers "F.Cu" "B.Cu")
		(net "GND")
	)
	(via
		(at 117.210586 -288.78149)
		(size 0.508)
		(drill 0.254)
		(layers "F.Cu" "B.Cu")
		(net "GND")
	)
	(via
		(at 412.89351 -136.645142)
		(size 0.508)
		(drill 0.254)
		(layers "F.Cu" "B.Cu")
		(net "GND")
	)
	(via
		(at 280.924762 -307.774848)
		(size 0.4064)
		(drill 0.2032)
		(layers "F.Cu" "B.Cu")
		(net "GND")
	)
	(via
		(at 466.835998 -328.483976)
		(size 0.508)
		(drill 0.254)
		(layers "F.Cu" "B.Cu")
		(net "GND")
	)
	(via
		(at 181.44998 -314.899802)
		(size 0.4064)
		(drill 0.2032)
		(layers "F.Cu" "B.Cu")
		(net "GND")
	)
	(via
		(at 182.348886 -31.390082)
		(size 0.508)
		(drill 0.254)
		(layers "F.Cu" "B.Cu")
		(net "GND")
	)
	(via
		(at 64.874902 -300.174914)
		(size 0.4064)
		(drill 0.2032)
		(layers "F.Cu" "B.Cu")
		(net "GND")
	)
	(via
		(at 309.900066 -274.049744)
		(size 0.4064)
		(drill 0.2032)
		(layers "F.Cu" "B.Cu")
		(net "GND")
	)
	(via
		(at 341.544656 -352.245422)
		(size 0.4572)
		(drill 0.254)
		(layers "F.Cu" "B.Cu")
		(net "GND")
	)
	(via
		(at 315.60008 -285.450026)
		(size 0.4064)
		(drill 0.2032)
		(layers "F.Cu" "B.Cu")
		(net "GND")
	)
	(via
		(at 329.108816 -347.951806)
		(size 0.4572)
		(drill 0.254)
		(layers "F.Cu" "B.Cu")
		(net "GND")
	)
	(via
		(at 51.63312 -131.76504)
		(size 0.508)
		(drill 0.254)
		(layers "F.Cu" "B.Cu")
		(net "GND")
	)
	(via
		(at 44.92498 -288.774886)
		(size 0.4064)
		(drill 0.2032)
		(layers "F.Cu" "B.Cu")
		(net "GND")
	)
	(via
		(at 96.569784 -25.832054)
		(size 0.508)
		(drill 0.254)
		(layers "F.Cu" "B.Cu")
		(net "GND")
	)
	(via
		(at 37.133784 -124.43333)
		(size 0.508)
		(drill 0.254)
		(layers "F.Cu" "B.Cu")
		(net "GND")
	)
	(via
		(at 280.924762 -296.37482)
		(size 0.4064)
		(drill 0.2032)
		(layers "F.Cu" "B.Cu")
		(net "GND")
	)
	(via
		(at 391.324846 -279.274778)
		(size 0.4064)
		(drill 0.2032)
		(layers "F.Cu" "B.Cu")
		(net "GND")
	)
	(via
		(at 392.496294 -60.099194)
		(size 0.508)
		(drill 0.254)
		(layers "F.Cu" "B.Cu")
		(net "GND")
	)
	(via
		(at 435.227984 -352.245422)
		(size 0.4572)
		(drill 0.254)
		(layers "F.Cu" "B.Cu")
		(net "GND")
	)
	(via
		(at 82.566002 -354.732082)
		(size 0.4064)
		(drill 0.2032)
		(layers "F.Cu" "B.Cu")
		(net "GND")
	)
	(via
		(at 390.849866 -299.699934)
		(size 0.4064)
		(drill 0.2032)
		(layers "F.Cu" "B.Cu")
		(net "GND")
	)
	(via
		(at 68.674742 -292.574726)
		(size 0.4064)
		(drill 0.2032)
		(layers "F.Cu" "B.Cu")
		(net "GND")
	)
	(via
		(at 343.25687 -293.345108)
		(size 0.508)
		(drill 0.254)
		(layers "F.Cu" "B.Cu")
		(net "GND")
	)
	(via
		(at 357.801164 -82.482182)
		(size 0.508)
		(drill 0.254)
		(layers "F.Cu" "B.Cu")
		(net "GND")
	)
	(via
		(at 77.22489 -303.024794)
		(size 0.4064)
		(drill 0.2032)
		(layers "F.Cu" "B.Cu")
		(net "GND")
	)
	(via
		(at 80.54975 -272.14957)
		(size 0.4064)
		(drill 0.2032)
		(layers "F.Cu" "B.Cu")
		(net "GND")
	)
	(via
		(at 70.50151 -357.123746)
		(size 0.4572)
		(drill 0.254)
		(layers "F.Cu" "B.Cu")
		(net "GND")
	)
	(via
		(at 174.42434 -358.391714)
		(size 0.4572)
		(drill 0.254)
		(layers "F.Cu" "B.Cu")
		(net "GND")
	)
	(via
		(at 137.795 -354.098098)
		(size 0.4572)
		(drill 0.254)
		(layers "F.Cu" "B.Cu")
		(net "GND")
	)
	(via
		(at 367.334546 -47.936658)
		(size 0.508)
		(drill 0.254)
		(layers "F.Cu" "B.Cu")
		(net "GND")
	)
	(via
		(at 40.547798 -378.94006)
		(size 0.508)
		(drill 0.254)
		(layers "F.Cu" "B.Cu")
		(net "GND")
	)
	(via
		(at 64.28359 -350.977454)
		(size 0.4572)
		(drill 0.254)
		(layers "F.Cu" "B.Cu")
		(net "GND")
	)
	(via
		(at 421.249856 -274.999958)
		(size 0.4064)
		(drill 0.2032)
		(layers "F.Cu" "B.Cu")
		(net "GND")
	)
	(via
		(at 80.147922 -406.141936)
		(size 0.508)
		(drill 0.254)
		(layers "F.Cu" "B.Cu")
		(net "GND")
	)
	(via
		(at 395.39926 -122.130312)
		(size 0.508)
		(drill 0.254)
		(layers "F.Cu" "B.Cu")
		(net "GND")
	)
	(via
		(at 398.971008 -358.391714)
		(size 0.4572)
		(drill 0.254)
		(layers "F.Cu" "B.Cu")
		(net "GND")
	)
	(via
		(at 78.743302 -80.449674)
		(size 0.508)
		(drill 0.254)
		(layers "F.Cu" "B.Cu")
		(net "GND")
	)
	(via
		(at 188.099954 -318.699896)
		(size 0.4064)
		(drill 0.2032)
		(layers "F.Cu" "B.Cu")
		(net "GND")
	)
	(via
		(at 111.293148 -342.439498)
		(size 0.4064)
		(drill 0.2032)
		(layers "F.Cu" "B.Cu")
		(net "GND")
	)
	(via
		(at 424.64228 -355.366066)
		(size 0.4572)
		(drill 0.254)
		(layers "F.Cu" "B.Cu")
		(net "GND")
	)
	(via
		(at 304.199798 -277.849838)
		(size 0.4064)
		(drill 0.2032)
		(layers "F.Cu" "B.Cu")
		(net "GND")
	)
	(via
		(at 369.613434 -29.859478)
		(size 0.508)
		(drill 0.254)
		(layers "F.Cu" "B.Cu")
		(net "GND")
	)
	(via
		(at 301.848012 -142.15491)
		(size 0.508)
		(drill 0.254)
		(layers "F.Cu" "B.Cu")
		(net "GND")
	)
	(via
		(at 421.724836 -297.32478)
		(size 0.4064)
		(drill 0.2032)
		(layers "F.Cu" "B.Cu")
		(net "GND")
	)
	(via
		(at 160.549844 -311.099962)
		(size 0.4064)
		(drill 0.2032)
		(layers "F.Cu" "B.Cu")
		(net "GND")
	)
	(via
		(at 206.415894 -205.748128)
		(size 0.508)
		(drill 0.254)
		(layers "F.Cu" "B.Cu")
		(net "GND")
	)
	(via
		(at 180.02504 -289.724846)
		(size 0.4064)
		(drill 0.2032)
		(layers "F.Cu" "B.Cu")
		(net "GND")
	)
	(via
		(at 285.981902 -348.58579)
		(size 0.4064)
		(drill 0.2032)
		(layers "F.Cu" "B.Cu")
		(net "GND")
	)
	(via
		(at 71.93915 -31.652972)
		(size 0.508)
		(drill 0.254)
		(layers "F.Cu" "B.Cu")
		(net "GND")
	)
	(via
		(at 139.645136 -341.781638)
		(size 0.4572)
		(drill 0.254)
		(layers "F.Cu" "B.Cu")
		(net "GND")
	)
	(via
		(at 388.2009 -142.748762)
		(size 0.508)
		(drill 0.254)
		(layers "F.Cu" "B.Cu")
		(net "GND")
	)
	(via
		(at 297.927776 -397.038576)
		(size 0.508)
		(drill 0.254)
		(layers "F.Cu" "B.Cu")
		(net "GND")
	)
	(via
		(at 38.347904 -377.341892)
		(size 0.508)
		(drill 0.254)
		(layers "F.Cu" "B.Cu")
		(net "GND")
	)
	(via
		(at 463.037682 -194.577462)
		(size 0.508)
		(drill 0.254)
		(layers "F.Cu" "B.Cu")
		(net "GND")
	)
	(via
		(at 392.38174 -354.732082)
		(size 0.4064)
		(drill 0.2032)
		(layers "F.Cu" "B.Cu")
		(net "GND")
	)
	(via
		(at 413.174942 -287.824926)
		(size 0.4064)
		(drill 0.2032)
		(layers "F.Cu" "B.Cu")
		(net "GND")
	)
	(via
		(at 276.649688 -274.999958)
		(size 0.4064)
		(drill 0.2032)
		(layers "F.Cu" "B.Cu")
		(net "GND")
	)
	(via
		(at 105.019094 -398.66824)
		(size 0.508)
		(drill 0.254)
		(layers "F.Cu" "B.Cu")
		(net "GND")
	)
	(via
		(at 81.673446 -113.11001)
		(size 0.508)
		(drill 0.254)
		(layers "F.Cu" "B.Cu")
		(net "GND")
	)
	(via
		(at 269.524734 -294.4749)
		(size 0.4064)
		(drill 0.2032)
		(layers "F.Cu" "B.Cu")
		(net "GND")
	)
	(via
		(at 378.3711 -212.59419)
		(size 0.508)
		(drill 0.254)
		(layers "F.Cu" "B.Cu")
		(net "GND")
	)
	(via
		(at 154.547062 -23.583646)
		(size 0.508)
		(drill 0.254)
		(layers "F.Cu" "B.Cu")
		(net "GND")
	)
	(via
		(at 40.526208 -357.75773)
		(size 0.4064)
		(drill 0.2032)
		(layers "F.Cu" "B.Cu")
		(net "GND")
	)
	(via
		(at 429.198278 -123.356878)
		(size 0.508)
		(drill 0.254)
		(layers "F.Cu" "B.Cu")
		(net "GND")
	)
	(via
		(at 185.725054 -300.174914)
		(size 0.4064)
		(drill 0.2032)
		(layers "F.Cu" "B.Cu")
		(net "GND")
	)
	(via
		(at 194.749928 -311.099962)
		(size 0.4064)
		(drill 0.2032)
		(layers "F.Cu" "B.Cu")
		(net "GND")
	)
	(via
		(at 260.410706 -214.64778)
		(size 0.508)
		(drill 0.254)
		(layers "F.Cu" "B.Cu")
		(net "GND")
	)
	(via
		(at 388.474966 -279.274778)
		(size 0.4064)
		(drill 0.2032)
		(layers "F.Cu" "B.Cu")
		(net "GND")
	)
	(via
		(at 414.74771 -142.15491)
		(size 0.508)
		(drill 0.254)
		(layers "F.Cu" "B.Cu")
		(net "GND")
	)
	(via
		(at 249.933206 -121.525284)
		(size 0.508)
		(drill 0.254)
		(layers "F.Cu" "B.Cu")
		(net "GND")
	)
	(via
		(at 356.755192 -31.390082)
		(size 0.508)
		(drill 0.254)
		(layers "F.Cu" "B.Cu")
		(net "GND")
	)
	(via
		(at 281.874722 -307.774848)
		(size 0.4064)
		(drill 0.2032)
		(layers "F.Cu" "B.Cu")
		(net "GND")
	)
	(via
		(at 387.050026 -311.099962)
		(size 0.4064)
		(drill 0.2032)
		(layers "F.Cu" "B.Cu")
		(net "GND")
	)
	(via
		(at 418.874956 -302.074834)
		(size 0.4064)
		(drill 0.2032)
		(layers "F.Cu" "B.Cu")
		(net "GND")
	)
	(via
		(at 238.9124 -94.1324)
		(size 0.508)
		(drill 0.254)
		(layers "F.Cu" "B.Cu")
		(net "GND")
	)
	(via
		(at 171.949872 -310.149748)
		(size 0.4064)
		(drill 0.2032)
		(layers "F.Cu" "B.Cu")
		(net "GND")
	)
	(via
		(at 97.032318 -394.1318)
		(size 0.508)
		(drill 0.254)
		(layers "F.Cu" "B.Cu")
		(net "GND")
	)
	(via
		(at 275.699728 -312.999882)
		(size 0.4064)
		(drill 0.2032)
		(layers "F.Cu" "B.Cu")
		(net "GND")
	)
	(via
		(at 131.57708 -347.951806)
		(size 0.4572)
		(drill 0.254)
		(layers "F.Cu" "B.Cu")
		(net "GND")
	)
	(via
		(at 291.32784 -382.84023)
		(size 0.508)
		(drill 0.254)
		(layers "F.Cu" "B.Cu")
		(net "GND")
	)
	(via
		(at 293.527734 -372.240302)
		(size 0.508)
		(drill 0.254)
		(layers "F.Cu" "B.Cu")
		(net "GND")
	)
	(via
		(at 296.793412 -151.155146)
		(size 0.508)
		(drill 0.254)
		(layers "F.Cu" "B.Cu")
		(net "GND")
	)
	(via
		(at 277.049738 -410.82341)
		(size 0.508)
		(drill 0.254)
		(layers "F.Cu" "B.Cu")
		(net "GND")
	)
	(via
		(at 291.32784 -369.938554)
		(size 0.508)
		(drill 0.254)
		(layers "F.Cu" "B.Cu")
		(net "GND")
	)
	(via
		(at 139.440158 -73.87463)
		(size 0.508)
		(drill 0.254)
		(layers "F.Cu" "B.Cu")
		(net "GND")
	)
	(via
		(at 159.599884 -318.699896)
		(size 0.4064)
		(drill 0.2032)
		(layers "F.Cu" "B.Cu")
		(net "GND")
	)
	(via
		(at 286.906462 -135.364982)
		(size 0.508)
		(drill 0.254)
		(layers "F.Cu" "B.Cu")
		(net "GND")
	)
	(via
		(at 414.124902 -302.074834)
		(size 0.4064)
		(drill 0.2032)
		(layers "F.Cu" "B.Cu")
		(net "GND")
	)
	(via
		(at 274.480782 -33.19018)
		(size 0.508)
		(drill 0.254)
		(layers "F.Cu" "B.Cu")
		(net "GND")
	)
	(via
		(at 199.025002 -291.624766)
		(size 0.4064)
		(drill 0.2032)
		(layers "F.Cu" "B.Cu")
		(net "GND")
	)
	(via
		(at 105.323132 -55.083456)
		(size 0.508)
		(drill 0.254)
		(layers "F.Cu" "B.Cu")
		(net "GND")
	)
	(via
		(at 116.03228 -349.219774)
		(size 0.4572)
		(drill 0.254)
		(layers "F.Cu" "B.Cu")
		(net "GND")
	)
	(via
		(at 266.691618 -122.626628)
		(size 0.508)
		(drill 0.254)
		(layers "F.Cu" "B.Cu")
		(net "GND")
	)
	(via
		(at 130.318256 -344.831162)
		(size 0.4572)
		(drill 0.254)
		(layers "F.Cu" "B.Cu")
		(net "GND")
	)
	(via
		(at 71.347838 -398.34185)
		(size 0.508)
		(drill 0.254)
		(layers "F.Cu" "B.Cu")
		(net "GND")
	)
	(via
		(at 177.174906 -303.974754)
		(size 0.4064)
		(drill 0.2032)
		(layers "F.Cu" "B.Cu")
		(net "GND")
	)
	(via
		(at 181.912514 -152.955244)
		(size 0.508)
		(drill 0.254)
		(layers "F.Cu" "B.Cu")
		(net "GND")
	)
	(via
		(at 136.536176 -343.073482)
		(size 0.4572)
		(drill 0.254)
		(layers "F.Cu" "B.Cu")
		(net "GND")
	)
	(via
		(at 44.94784 -382.840484)
		(size 0.508)
		(drill 0.254)
		(layers "F.Cu" "B.Cu")
		(net "GND")
	)
	(via
		(at 327.544938 -235.723938)
		(size 0.508)
		(drill 0.254)
		(layers "F.Cu" "B.Cu")
		(net "GND")
	)
	(via
		(at 267.69949 -352.245422)
		(size 0.4572)
		(drill 0.254)
		(layers "F.Cu" "B.Cu")
		(net "GND")
	)
	(via
		(at 350.64192 -25.971246)
		(size 0.508)
		(drill 0.254)
		(layers "F.Cu" "B.Cu")
		(net "GND")
	)
	(via
		(at 65.349882 -276.899878)
		(size 0.4064)
		(drill 0.2032)
		(layers "F.Cu" "B.Cu")
		(net "GND")
	)
	(via
		(at 407.949908 -310.149748)
		(size 0.4064)
		(drill 0.2032)
		(layers "F.Cu" "B.Cu")
		(net "GND")
	)
	(via
		(at 346.006928 -0.762)
		(size 0.508)
		(drill 0.254)
		(layers "F.Cu" "B.Cu")
		(net "GND")
	)
	(via
		(at 429.927766 -371.038628)
		(size 0.508)
		(drill 0.254)
		(layers "F.Cu" "B.Cu")
		(net "GND")
	)
	(via
		(at 159.599884 -307.299868)
		(size 0.4064)
		(drill 0.2032)
		(layers "F.Cu" "B.Cu")
		(net "GND")
	)
	(via
		(at 247.886728 -111.127032)
		(size 0.508)
		(drill 0.254)
		(layers "F.Cu" "B.Cu")
		(net "GND")
	)
	(via
		(at 376.56389 -254.623062)
		(size 0.508)
		(drill 0.254)
		(layers "F.Cu" "B.Cu")
		(net "GND")
	)
	(via
		(at 72.21093 -109.41304)
		(size 0.508)
		(drill 0.254)
		(layers "F.Cu" "B.Cu")
		(net "GND")
	)
	(via
		(at 188.119004 -358.367838)
		(size 0.4572)
		(drill 0.254)
		(layers "F.Cu" "B.Cu")
		(net "GND")
	)
	(via
		(at 328.15657 -228.92893)
		(size 0.508)
		(drill 0.254)
		(layers "F.Cu" "B.Cu")
		(net "GND")
	)
	(via
		(at 114.045746 -252.598682)
		(size 0.508)
		(drill 0.254)
		(layers "F.Cu" "B.Cu")
		(net "GND")
	)
	(via
		(at 60.599828 -273.099784)
		(size 0.4064)
		(drill 0.2032)
		(layers "F.Cu" "B.Cu")
		(net "GND")
	)
	(via
		(at 235.871512 -235.737654)
		(size 0.508)
		(drill 0.254)
		(layers "F.Cu" "B.Cu")
		(net "GND")
	)
	(via
		(at 71.524876 -302.074834)
		(size 0.4064)
		(drill 0.2032)
		(layers "F.Cu" "B.Cu")
		(net "GND")
	)
	(via
		(at 176.94783 -384.042158)
		(size 0.508)
		(drill 0.254)
		(layers "F.Cu" "B.Cu")
		(net "GND")
	)
	(via
		(at 185.725054 -284.024832)
		(size 0.4064)
		(drill 0.2032)
		(layers "F.Cu" "B.Cu")
		(net "GND")
	)
	(via
		(at 161.975038 -284.024832)
		(size 0.4064)
		(drill 0.2032)
		(layers "F.Cu" "B.Cu")
		(net "GND")
	)
	(via
		(at 427.42485 -294.4749)
		(size 0.4064)
		(drill 0.2032)
		(layers "F.Cu" "B.Cu")
		(net "GND")
	)
	(via
		(at 364.248446 -154.510994)
		(size 0.508)
		(drill 0.254)
		(layers "F.Cu" "B.Cu")
		(net "GND")
	)
	(via
		(at 367.37417 -135.369046)
		(size 0.508)
		(drill 0.254)
		(layers "F.Cu" "B.Cu")
		(net "GND")
	)
	(via
		(at 401.774914 -307.774848)
		(size 0.4064)
		(drill 0.2032)
		(layers "F.Cu" "B.Cu")
		(net "GND")
	)
	(via
		(at 431.01514 -60.601606)
		(size 0.508)
		(drill 0.254)
		(layers "F.Cu" "B.Cu")
		(net "GND")
	)
	(via
		(at 54.70652 -120.555004)
		(size 0.508)
		(drill 0.254)
		(layers "F.Cu" "B.Cu")
		(net "GND")
	)
	(via
		(at 198.075042 -293.52494)
		(size 0.4064)
		(drill 0.2032)
		(layers "F.Cu" "B.Cu")
		(net "GND")
	)
	(via
		(at 179.55006 -276.899878)
		(size 0.4064)
		(drill 0.2032)
		(layers "F.Cu" "B.Cu")
		(net "GND")
	)
	(via
		(at 300.12767 -369.938554)
		(size 0.508)
		(drill 0.254)
		(layers "F.Cu" "B.Cu")
		(net "GND")
	)
	(via
		(at 279.578562 -86.50224)
		(size 0.508)
		(drill 0.254)
		(layers "F.Cu" "B.Cu")
		(net "GND")
	)
	(via
		(at 300.48073 -31.390082)
		(size 0.508)
		(drill 0.254)
		(layers "F.Cu" "B.Cu")
		(net "GND")
	)
	(via
		(at 143.423386 -56.353456)
		(size 0.508)
		(drill 0.254)
		(layers "F.Cu" "B.Cu")
		(net "GND")
	)
	(via
		(at 420.299896 -278.799798)
		(size 0.4064)
		(drill 0.2032)
		(layers "F.Cu" "B.Cu")
		(net "GND")
	)
	(via
		(at 201.605642 -372.890034)
		(size 0.508)
		(drill 0.254)
		(layers "F.Cu" "B.Cu")
		(net "GND")
	)
	(via
		(at 353.776788 -268.096492)
		(size 0.508)
		(drill 0.254)
		(layers "F.Cu" "B.Cu")
		(net "GND")
	)
	(via
		(at 156.275024 -284.974792)
		(size 0.4064)
		(drill 0.2032)
		(layers "F.Cu" "B.Cu")
		(net "GND")
	)
	(via
		(at 272.849848 -306.349908)
		(size 0.4064)
		(drill 0.2032)
		(layers "F.Cu" "B.Cu")
		(net "GND")
	)
	(via
		(at 134.68223 -58.238644)
		(size 0.508)
		(drill 0.254)
		(layers "F.Cu" "B.Cu")
		(net "GND")
	)
	(via
		(at 383.94894 -25.990042)
		(size 0.508)
		(drill 0.254)
		(layers "F.Cu" "B.Cu")
		(net "GND")
	)
	(via
		(at 55.374794 -284.024832)
		(size 0.4064)
		(drill 0.2032)
		(layers "F.Cu" "B.Cu")
		(net "GND")
	)
	(via
		(at 38.347904 -408.738578)
		(size 0.508)
		(drill 0.254)
		(layers "F.Cu" "B.Cu")
		(net "GND")
	)
	(via
		(at 335.538064 -100.751894)
		(size 0.508)
		(drill 0.254)
		(layers "F.Cu" "B.Cu")
		(net "GND")
	)
	(via
		(at 304.199798 -310.149748)
		(size 0.4064)
		(drill 0.2032)
		(layers "F.Cu" "B.Cu")
		(net "GND")
	)
	(via
		(at 70.63867 -23.880318)
		(size 0.508)
		(drill 0.254)
		(layers "F.Cu" "B.Cu")
		(net "GND")
	)
	(via
		(at 256.910078 -416.508438)
		(size 0.508)
		(drill 0.254)
		(layers "F.Cu" "B.Cu")
		(net "GND")
	)
	(via
		(at 350.835976 -171.100242)
		(size 0.508)
		(drill 0.254)
		(layers "F.Cu" "B.Cu")
		(net "GND")
	)
	(via
		(at 273.324828 -291.624766)
		(size 0.4064)
		(drill 0.2032)
		(layers "F.Cu" "B.Cu")
		(net "GND")
	)
	(via
		(at 54.70652 -102.444804)
		(size 0.508)
		(drill 0.254)
		(layers "F.Cu" "B.Cu")
		(net "GND")
	)
	(via
		(at 47.115476 -354.074222)
		(size 0.4572)
		(drill 0.254)
		(layers "F.Cu" "B.Cu")
		(net "GND")
	)
	(via
		(at 48.24984 -307.299868)
		(size 0.4064)
		(drill 0.2032)
		(layers "F.Cu" "B.Cu")
		(net "GND")
	)
	(via
		(at 229.208838 -290.872926)
		(size 0.508)
		(drill 0.254)
		(layers "F.Cu" "B.Cu")
		(net "GND")
	)
	(via
		(at 299.866812 -133.044946)
		(size 0.508)
		(drill 0.254)
		(layers "F.Cu" "B.Cu")
		(net "GND")
	)
	(via
		(at 63.449962 -314.899802)
		(size 0.4064)
		(drill 0.2032)
		(layers "F.Cu" "B.Cu")
		(net "GND")
	)
	(via
		(at 161.59861 -65.15989)
		(size 0.508)
		(drill 0.254)
		(layers "F.Cu" "B.Cu")
		(net "GND")
	)
	(via
		(at 127.898398 -20.417536)
		(size 0.508)
		(drill 0.254)
		(layers "F.Cu" "B.Cu")
		(net "GND")
	)
	(via
		(at 428.84979 -276.899878)
		(size 0.4064)
		(drill 0.2032)
		(layers "F.Cu" "B.Cu")
		(net "GND")
	)
	(via
		(at 418.927788 -378.94006)
		(size 0.508)
		(drill 0.254)
		(layers "F.Cu" "B.Cu")
		(net "GND")
	)
	(via
		(at 283.833062 -120.555004)
		(size 0.508)
		(drill 0.254)
		(layers "F.Cu" "B.Cu")
		(net "GND")
	)
	(via
		(at 131.948428 -342.439498)
		(size 0.4064)
		(drill 0.2032)
		(layers "F.Cu" "B.Cu")
		(net "GND")
	)
	(via
		(at 52.524914 -305.874928)
		(size 0.4064)
		(drill 0.2032)
		(layers "F.Cu" "B.Cu")
		(net "GND")
	)
	(via
		(at 282.17495 -73.23963)
		(size 0.508)
		(drill 0.254)
		(layers "F.Cu" "B.Cu")
		(net "GND")
	)
	(via
		(at 65.902078 -57.461404)
		(size 0.508)
		(drill 0.254)
		(layers "F.Cu" "B.Cu")
		(net "GND")
	)
	(via
		(at 209.733134 -212.513164)
		(size 0.508)
		(drill 0.254)
		(layers "F.Cu" "B.Cu")
		(net "GND")
	)
	(via
		(at 289.47491 -287.824926)
		(size 0.4064)
		(drill 0.2032)
		(layers "F.Cu" "B.Cu")
		(net "GND")
	)
	(via
		(at 163.747958 -401.040092)
		(size 0.508)
		(drill 0.254)
		(layers "F.Cu" "B.Cu")
		(net "GND")
	)
	(via
		(at 156.275024 -296.37482)
		(size 0.4064)
		(drill 0.2032)
		(layers "F.Cu" "B.Cu")
		(net "GND")
	)
	(via
		(at 267.264134 -339.593936)
		(size 0.508)
		(drill 0.254)
		(layers "F.Cu" "B.Cu")
		(net "GND")
	)
	(via
		(at 307.999892 -313.949842)
		(size 0.4064)
		(drill 0.2032)
		(layers "F.Cu" "B.Cu")
		(net "GND")
	)
	(via
		(at 304.467006 -123.635008)
		(size 0.508)
		(drill 0.254)
		(layers "F.Cu" "B.Cu")
		(net "GND")
	)
	(via
		(at 61.074808 -305.874928)
		(size 0.4064)
		(drill 0.2032)
		(layers "F.Cu" "B.Cu")
		(net "GND")
	)
	(via
		(at 430.8602 -341.805514)
		(size 0.4572)
		(drill 0.254)
		(layers "F.Cu" "B.Cu")
		(net "GND")
	)
	(via
		(at 415.85007 -111.149892)
		(size 0.508)
		(drill 0.254)
		(layers "F.Cu" "B.Cu")
		(net "GND")
	)
	(via
		(at 26.61158 -357.123746)
		(size 0.4572)
		(drill 0.254)
		(layers "F.Cu" "B.Cu")
		(net "GND")
	)
	(via
		(at 283.24429 -341.805514)
		(size 0.4572)
		(drill 0.254)
		(layers "F.Cu" "B.Cu")
		(net "GND")
	)
	(via
		(at 149.920198 -33.19018)
		(size 0.508)
		(drill 0.254)
		(layers "F.Cu" "B.Cu")
		(net "GND")
	)
	(via
		(at 230.26751 -221.904052)
		(size 0.4572)
		(drill 0.254)
		(layers "F.Cu" "B.Cu")
		(net "GND")
	)
	(via
		(at 19.498564 -65.15989)
		(size 0.508)
		(drill 0.254)
		(layers "F.Cu" "B.Cu")
		(net "GND")
	)
	(via
		(at 133.846824 -176.519586)
		(size 0.508)
		(drill 0.254)
		(layers "F.Cu" "B.Cu")
		(net "GND")
	)
	(via
		(at 382.85547 -231.714548)
		(size 0.508)
		(drill 0.254)
		(layers "F.Cu" "B.Cu")
		(net "GND")
	)
	(via
		(at 302.895 -81.8896)
		(size 0.508)
		(drill 0.254)
		(layers "F.Cu" "B.Cu")
		(net "GND")
	)
	(via
		(at 153.845006 -29.589984)
		(size 0.508)
		(drill 0.254)
		(layers "F.Cu" "B.Cu")
		(net "GND")
	)
	(via
		(at 308.949852 -306.349908)
		(size 0.4064)
		(drill 0.2032)
		(layers "F.Cu" "B.Cu")
		(net "GND")
	)
	(via
		(at 364.494826 -110.365032)
		(size 0.508)
		(drill 0.254)
		(layers "F.Cu" "B.Cu")
		(net "GND")
	)
	(via
		(at 424.64228 -357.123746)
		(size 0.4572)
		(drill 0.254)
		(layers "F.Cu" "B.Cu")
		(net "GND")
	)
	(via
		(at 393.7 -306.349908)
		(size 0.4064)
		(drill 0.2032)
		(layers "F.Cu" "B.Cu")
		(net "GND")
	)
	(via
		(at 82.93735 -341.805514)
		(size 0.4572)
		(drill 0.254)
		(layers "F.Cu" "B.Cu")
		(net "GND")
	)
	(via
		(at 80.147922 -403.738588)
		(size 0.508)
		(drill 0.254)
		(layers "F.Cu" "B.Cu")
		(net "GND")
	)
	(via
		(at 44.449746 -315.849762)
		(size 0.4064)
		(drill 0.2032)
		(layers "F.Cu" "B.Cu")
		(net "GND")
	)
	(via
		(at 207.356456 -123.66498)
		(size 0.508)
		(drill 0.254)
		(layers "F.Cu" "B.Cu")
		(net "GND")
	)
	(via
		(at 339.728048 -380.141734)
		(size 0.508)
		(drill 0.254)
		(layers "F.Cu" "B.Cu")
		(net "GND")
	)
	(via
		(at 396.0749 -294.4749)
		(size 0.4064)
		(drill 0.2032)
		(layers "F.Cu" "B.Cu")
		(net "GND")
	)
	(via
		(at 49.67478 -303.024794)
		(size 0.4064)
		(drill 0.2032)
		(layers "F.Cu" "B.Cu")
		(net "GND")
	)
	(via
		(at 386.099812 -311.099962)
		(size 0.4064)
		(drill 0.2032)
		(layers "F.Cu" "B.Cu")
		(net "GND")
	)
	(via
		(at 279.499822 -317.749936)
		(size 0.4064)
		(drill 0.2032)
		(layers "F.Cu" "B.Cu")
		(net "GND")
	)
	(via
		(at 85.819996 -31.390336)
		(size 0.508)
		(drill 0.254)
		(layers "F.Cu" "B.Cu")
		(net "GND")
	)
	(via
		(at 142.754096 -352.245422)
		(size 0.4572)
		(drill 0.254)
		(layers "F.Cu" "B.Cu")
		(net "GND")
	)
	(via
		(at 424.09999 -314.899802)
		(size 0.4064)
		(drill 0.2032)
		(layers "F.Cu" "B.Cu")
		(net "GND")
	)
	(via
		(at 153.664666 -154.327352)
		(size 0.508)
		(drill 0.254)
		(layers "F.Cu" "B.Cu")
		(net "GND")
	)
	(via
		(at 193.0781 -349.219774)
		(size 0.4572)
		(drill 0.254)
		(layers "F.Cu" "B.Cu")
		(net "GND")
	)
	(via
		(at 277.124922 -287.824926)
		(size 0.4064)
		(drill 0.2032)
		(layers "F.Cu" "B.Cu")
		(net "GND")
	)
	(via
		(at 247.31853 -114.013996)
		(size 0.508)
		(drill 0.254)
		(layers "F.Cu" "B.Cu")
		(net "GND")
	)
	(via
		(at 117.209316 -85.556598)
		(size 0.508)
		(drill 0.254)
		(layers "F.Cu" "B.Cu")
		(net "GND")
	)
	(via
		(at 415.612834 -104.240076)
		(size 0.508)
		(drill 0.254)
		(layers "F.Cu" "B.Cu")
		(net "GND")
	)
	(via
		(at 427.75124 -343.073482)
		(size 0.4572)
		(drill 0.254)
		(layers "F.Cu" "B.Cu")
		(net "GND")
	)
	(via
		(at 183.766714 -145.755106)
		(size 0.508)
		(drill 0.254)
		(layers "F.Cu" "B.Cu")
		(net "GND")
	)
	(via
		(at 52.999894 -317.749936)
		(size 0.4064)
		(drill 0.2032)
		(layers "F.Cu" "B.Cu")
		(net "GND")
	)
	(via
		(at 295.727882 -384.041904)
		(size 0.508)
		(drill 0.254)
		(layers "F.Cu" "B.Cu")
		(net "GND")
	)
	(via
		(at 69.473318 -72.56526)
		(size 0.508)
		(drill 0.254)
		(layers "F.Cu" "B.Cu")
		(net "GND")
	)
	(via
		(at 237.642654 -309.604156)
		(size 0.508)
		(drill 0.254)
		(layers "F.Cu" "B.Cu")
		(net "GND")
	)
	(via
		(at 280.13533 -343.073482)
		(size 0.4572)
		(drill 0.254)
		(layers "F.Cu" "B.Cu")
		(net "GND")
	)
	(via
		(at 143.510762 -237.948978)
		(size 0.508)
		(drill 0.254)
		(layers "F.Cu" "B.Cu")
		(net "GND")
	)
	(via
		(at 330.927964 -399.838418)
		(size 0.508)
		(drill 0.254)
		(layers "F.Cu" "B.Cu")
		(net "GND")
	)
	(via
		(at 340.44128 -38.49116)
		(size 0.508)
		(drill 0.254)
		(layers "F.Cu" "B.Cu")
		(net "GND")
	)
	(via
		(at 189.524894 -297.32478)
		(size 0.4064)
		(drill 0.2032)
		(layers "F.Cu" "B.Cu")
		(net "GND")
	)
	(via
		(at 126.837948 -357.75773)
		(size 0.4064)
		(drill 0.2032)
		(layers "F.Cu" "B.Cu")
		(net "GND")
	)
	(via
		(at 356.120192 -29.590238)
		(size 0.508)
		(drill 0.254)
		(layers "F.Cu" "B.Cu")
		(net "GND")
	)
	(via
		(at 246.448834 -27.79014)
		(size 0.508)
		(drill 0.254)
		(layers "F.Cu" "B.Cu")
		(net "GND")
	)
	(via
		(at 379.327918 -404.940262)
		(size 0.508)
		(drill 0.254)
		(layers "F.Cu" "B.Cu")
		(net "GND")
	)
	(via
		(at 402.724874 -296.37482)
		(size 0.4064)
		(drill 0.2032)
		(layers "F.Cu" "B.Cu")
		(net "GND")
	)
	(via
		(at 190.348108 -120.035066)
		(size 0.508)
		(drill 0.254)
		(layers "F.Cu" "B.Cu")
		(net "GND")
	)
	(via
		(at 75.974956 -73.23963)
		(size 0.508)
		(drill 0.254)
		(layers "F.Cu" "B.Cu")
		(net "GND")
	)
	(via
		(at 436.706772 -354.732082)
		(size 0.4064)
		(drill 0.2032)
		(layers "F.Cu" "B.Cu")
		(net "GND")
	)
	(via
		(at 396.84579 -151.9936)
		(size 0.508)
		(drill 0.254)
		(layers "F.Cu" "B.Cu")
		(net "GND")
	)
	(via
		(at 38.275006 -280.224738)
		(size 0.4064)
		(drill 0.2032)
		(layers "F.Cu" "B.Cu")
		(net "GND")
	)
	(via
		(at 122.737372 -285.953454)
		(size 0.508)
		(drill 0.254)
		(layers "F.Cu" "B.Cu")
		(net "GND")
	)
	(via
		(at 286.149796 -316.799722)
		(size 0.4064)
		(drill 0.2032)
		(layers "F.Cu" "B.Cu")
		(net "GND")
	)
	(via
		(at 394.64996 -281.649932)
		(size 0.4064)
		(drill 0.2032)
		(layers "F.Cu" "B.Cu")
		(net "GND")
	)
	(via
		(at 293.74973 -280.699718)
		(size 0.4064)
		(drill 0.2032)
		(layers "F.Cu" "B.Cu")
		(net "GND")
	)
	(via
		(at 247.227852 -87.634572)
		(size 0.508)
		(drill 0.254)
		(layers "F.Cu" "B.Cu")
		(net "GND")
	)
	(via
		(at 429.087026 -0.762254)
		(size 0.508)
		(drill 0.254)
		(layers "F.Cu" "B.Cu")
		(net "GND")
	)
	(via
		(at 414.11271 -131.245102)
		(size 0.508)
		(drill 0.254)
		(layers "F.Cu" "B.Cu")
		(net "GND")
	)
	(via
		(at 278.074882 -283.074872)
		(size 0.4064)
		(drill 0.2032)
		(layers "F.Cu" "B.Cu")
		(net "GND")
	)
	(via
		(at 109.050074 -290.68649)
		(size 0.508)
		(drill 0.254)
		(layers "F.Cu" "B.Cu")
		(net "GND")
	)
	(via
		(at 277.251668 -138.964924)
		(size 0.508)
		(drill 0.254)
		(layers "F.Cu" "B.Cu")
		(net "GND")
	)
	(via
		(at 237.022386 -45.808138)
		(size 0.508)
		(drill 0.254)
		(layers "F.Cu" "B.Cu")
		(net "GND")
	)
	(via
		(at 431.700178 -276.900132)
		(size 0.4064)
		(drill 0.2032)
		(layers "F.Cu" "B.Cu")
		(net "GND")
	)
	(via
		(at 187.624974 -301.124874)
		(size 0.4064)
		(drill 0.2032)
		(layers "F.Cu" "B.Cu")
		(net "GND")
	)
	(via
		(at 293.527734 -408.738578)
		(size 0.508)
		(drill 0.254)
		(layers "F.Cu" "B.Cu")
		(net "GND")
	)
	(via
		(at 183.766714 -114.635026)
		(size 0.508)
		(drill 0.254)
		(layers "F.Cu" "B.Cu")
		(net "GND")
	)
	(via
		(at 297.54957 -272.14957)
		(size 0.4064)
		(drill 0.2032)
		(layers "F.Cu" "B.Cu")
		(net "GND")
	)
	(via
		(at 293.394892 -60.633356)
		(size 0.508)
		(drill 0.254)
		(layers "F.Cu" "B.Cu")
		(net "GND")
	)
	(via
		(at 27.323288 -51.019456)
		(size 0.508)
		(drill 0.254)
		(layers "F.Cu" "B.Cu")
		(net "GND")
	)
	(via
		(at 181.912514 -151.155146)
		(size 0.508)
		(drill 0.254)
		(layers "F.Cu" "B.Cu")
		(net "GND")
	)
	(via
		(at 152.0952 -392.7856)
		(size 0.508)
		(drill 0.254)
		(layers "F.Cu" "B.Cu")
		(net "GND")
	)
	(via
		(at 187.624974 -297.32478)
		(size 0.4064)
		(drill 0.2032)
		(layers "F.Cu" "B.Cu")
		(net "GND")
	)
	(via
		(at 62.822582 -152.274524)
		(size 0.508)
		(drill 0.254)
		(layers "F.Cu" "B.Cu")
		(net "GND")
	)
	(via
		(at 132.93852 -72.56526)
		(size 0.508)
		(drill 0.254)
		(layers "F.Cu" "B.Cu")
		(net "GND")
	)
	(via
		(at 25.550876 -262.912352)
		(size 0.508)
		(drill 0.254)
		(layers "F.Cu" "B.Cu")
		(net "GND")
	)
	(via
		(at 374.927876 -384.041904)
		(size 0.508)
		(drill 0.254)
		(layers "F.Cu" "B.Cu")
		(net "GND")
	)
	(via
		(at 49.1998 -310.149748)
		(size 0.4064)
		(drill 0.2032)
		(layers "F.Cu" "B.Cu")
		(net "GND")
	)
	(via
		(at 62.433454 -343.073482)
		(size 0.4572)
		(drill 0.254)
		(layers "F.Cu" "B.Cu")
		(net "GND")
	)
	(via
		(at 426.47489 -289.724846)
		(size 0.4064)
		(drill 0.2032)
		(layers "F.Cu" "B.Cu")
		(net "GND")
	)
	(via
		(at 100.678742 -103.404416)
		(size 0.508)
		(drill 0.254)
		(layers "F.Cu" "B.Cu")
		(net "GND")
	)
	(via
		(at 90.785442 -345.465146)
		(size 0.4064)
		(drill 0.2032)
		(layers "F.Cu" "B.Cu")
		(net "GND")
	)
	(via
		(at 401.299934 -278.799798)
		(size 0.4064)
		(drill 0.2032)
		(layers "F.Cu" "B.Cu")
		(net "GND")
	)
	(via
		(at 29.54782 -385.141978)
		(size 0.508)
		(drill 0.254)
		(layers "F.Cu" "B.Cu")
		(net "GND")
	)
	(via
		(at 362.115608 -329.542394)
		(size 0.508)
		(drill 0.254)
		(layers "F.Cu" "B.Cu")
		(net "GND")
	)
	(via
		(at 4.562856 -119.201692)
		(size 0.508)
		(drill 0.254)
		(layers "F.Cu" "B.Cu")
		(net "GND")
	)
	(via
		(at 252.139196 -28.05303)
		(size 0.508)
		(drill 0.254)
		(layers "F.Cu" "B.Cu")
		(net "GND")
	)
	(via
		(at 81.024984 -299.224954)
		(size 0.4064)
		(drill 0.2032)
		(layers "F.Cu" "B.Cu")
		(net "GND")
	)
	(via
		(at 252.873002 -23.880318)
		(size 0.508)
		(drill 0.254)
		(layers "F.Cu" "B.Cu")
		(net "GND")
	)
	(via
		(at 275.761196 -60.099194)
		(size 0.508)
		(drill 0.254)
		(layers "F.Cu" "B.Cu")
		(net "GND")
	)
	(via
		(at 181.44998 -319.65011)
		(size 0.4064)
		(drill 0.2032)
		(layers "F.Cu" "B.Cu")
		(net "GND")
	)
	(via
		(at 421.249856 -312.049922)
		(size 0.4064)
		(drill 0.2032)
		(layers "F.Cu" "B.Cu")
		(net "GND")
	)
	(via
		(at 417.924996 -285.924752)
		(size 0.4064)
		(drill 0.2032)
		(layers "F.Cu" "B.Cu")
		(net "GND")
	)
	(via
		(at 337.523074 -54.067456)
		(size 0.508)
		(drill 0.254)
		(layers "F.Cu" "B.Cu")
		(net "GND")
	)
	(via
		(at 281.851862 -125.955044)
		(size 0.508)
		(drill 0.254)
		(layers "F.Cu" "B.Cu")
		(net "GND")
	)
	(via
		(at 197.125082 -293.52494)
		(size 0.4064)
		(drill 0.2032)
		(layers "F.Cu" "B.Cu")
		(net "GND")
	)
	(via
		(at 49.67478 -287.824926)
		(size 0.4064)
		(drill 0.2032)
		(layers "F.Cu" "B.Cu")
		(net "GND")
	)
	(via
		(at 142.382748 -348.58579)
		(size 0.4064)
		(drill 0.2032)
		(layers "F.Cu" "B.Cu")
		(net "GND")
	)
	(via
		(at 47.115476 -355.366066)
		(size 0.4572)
		(drill 0.254)
		(layers "F.Cu" "B.Cu")
		(net "GND")
	)
	(via
		(at 406.524968 -306.824888)
		(size 0.4064)
		(drill 0.2032)
		(layers "F.Cu" "B.Cu")
		(net "GND")
	)
	(via
		(at 126.347728 -377.341892)
		(size 0.4572)
		(drill 0.254)
		(layers "F.Cu" "B.Cu")
		(net "GND")
	)
	(via
		(at 385.927854 -381.241808)
		(size 0.508)
		(drill 0.254)
		(layers "F.Cu" "B.Cu")
		(net "GND")
	)
	(via
		(at 421.53332 -350.977454)
		(size 0.4572)
		(drill 0.254)
		(layers "F.Cu" "B.Cu")
		(net "GND")
	)
	(via
		(at 337.5279 -397.038576)
		(size 0.508)
		(drill 0.254)
		(layers "F.Cu" "B.Cu")
		(net "GND")
	)
	(via
		(at 298.012612 -133.0452)
		(size 0.508)
		(drill 0.254)
		(layers "F.Cu" "B.Cu")
		(net "GND")
	)
	(via
		(at 277.720044 -57.076848)
		(size 0.508)
		(drill 0.254)
		(layers "F.Cu" "B.Cu")
		(net "GND")
	)
	(via
		(at 169.574972 -291.624766)
		(size 0.4064)
		(drill 0.2032)
		(layers "F.Cu" "B.Cu")
		(net "GND")
	)
	(via
		(at 126.347728 -374.938544)
		(size 0.508)
		(drill 0.254)
		(layers "F.Cu" "B.Cu")
		(net "GND")
	)
	(via
		(at 180.50002 -277.849838)
		(size 0.4064)
		(drill 0.2032)
		(layers "F.Cu" "B.Cu")
		(net "GND")
	)
	(via
		(at 198.26605 -119.756936)
		(size 0.508)
		(drill 0.254)
		(layers "F.Cu" "B.Cu")
		(net "GND")
	)
	(via
		(at 171.474892 -287.824926)
		(size 0.4064)
		(drill 0.2032)
		(layers "F.Cu" "B.Cu")
		(net "GND")
	)
	(via
		(at 410.324808 -287.824926)
		(size 0.4064)
		(drill 0.2032)
		(layers "F.Cu" "B.Cu")
		(net "GND")
	)
	(via
		(at 214.039196 -29.311854)
		(size 0.508)
		(drill 0.254)
		(layers "F.Cu" "B.Cu")
		(net "GND")
	)
	(via
		(at 409.849828 -310.149748)
		(size 0.4064)
		(drill 0.2032)
		(layers "F.Cu" "B.Cu")
		(net "GND")
	)
	(via
		(at 396.119604 -38.701218)
		(size 0.508)
		(drill 0.254)
		(layers "F.Cu" "B.Cu")
		(net "GND")
	)
	(via
		(at 35.759644 -130.236722)
		(size 0.508)
		(drill 0.254)
		(layers "F.Cu" "B.Cu")
		(net "GND")
	)
	(via
		(at 147.548092 -64.312292)
		(size 0.508)
		(drill 0.254)
		(layers "F.Cu" "B.Cu")
		(net "GND")
	)
	(via
		(at 21.917914 -414.985454)
		(size 0.508)
		(drill 0.254)
		(layers "F.Cu" "B.Cu")
		(net "GND")
	)
	(via
		(at 335.846928 -0.762)
		(size 0.508)
		(drill 0.254)
		(layers "F.Cu" "B.Cu")
		(net "GND")
	)
	(via
		(at 35.052 -13.613638)
		(size 0.508)
		(drill 0.254)
		(layers "F.Cu" "B.Cu")
		(net "GND")
	)
	(via
		(at 125.74905 -33.19018)
		(size 0.508)
		(drill 0.254)
		(layers "F.Cu" "B.Cu")
		(net "GND")
	)
	(via
		(at 93.486478 -89.962736)
		(size 0.508)
		(drill 0.254)
		(layers "F.Cu" "B.Cu")
		(net "GND")
	)
	(via
		(at 63.924942 -297.32478)
		(size 0.4064)
		(drill 0.2032)
		(layers "F.Cu" "B.Cu")
		(net "GND")
	)
	(via
		(at 189.999874 -278.799798)
		(size 0.4064)
		(drill 0.2032)
		(layers "F.Cu" "B.Cu")
		(net "GND")
	)
	(via
		(at 351.580196 -92.110814)
		(size 0.508)
		(drill 0.254)
		(layers "F.Cu" "B.Cu")
		(net "GND")
	)
	(via
		(at 119.14124 -343.073482)
		(size 0.4572)
		(drill 0.254)
		(layers "F.Cu" "B.Cu")
		(net "GND")
	)
	(via
		(at 260.568186 -203.77785)
		(size 0.508)
		(drill 0.254)
		(layers "F.Cu" "B.Cu")
		(net "GND")
	)
	(via
		(at 49.1998 -281.649932)
		(size 0.4064)
		(drill 0.2032)
		(layers "F.Cu" "B.Cu")
		(net "GND")
	)
	(via
		(at 403.674834 -284.974792)
		(size 0.4064)
		(drill 0.2032)
		(layers "F.Cu" "B.Cu")
		(net "GND")
	)
	(via
		(at 165.947852 -385.141978)
		(size 0.508)
		(drill 0.254)
		(layers "F.Cu" "B.Cu")
		(net "GND")
	)
	(via
		(at 81.499964 -274.049744)
		(size 0.4064)
		(drill 0.2032)
		(layers "F.Cu" "B.Cu")
		(net "GND")
	)
	(via
		(at 21.872448 -354.732082)
		(size 0.4064)
		(drill 0.2032)
		(layers "F.Cu" "B.Cu")
		(net "GND")
	)
	(via
		(at 45.939202 -31.652972)
		(size 0.508)
		(drill 0.254)
		(layers "F.Cu" "B.Cu")
		(net "GND")
	)
	(via
		(at 301.861474 -237.888272)
		(size 0.508)
		(drill 0.254)
		(layers "F.Cu" "B.Cu")
		(net "GND")
	)
	(via
		(at 191.227964 -350.977454)
		(size 0.4572)
		(drill 0.254)
		(layers "F.Cu" "B.Cu")
		(net "GND")
	)
	(via
		(at 33.947862 -381.241808)
		(size 0.508)
		(drill 0.254)
		(layers "F.Cu" "B.Cu")
		(net "GND")
	)
	(via
		(at 272.849848 -301.599854)
		(size 0.4064)
		(drill 0.2032)
		(layers "F.Cu" "B.Cu")
		(net "GND")
	)
	(via
		(at 42.747946 -402.140166)
		(size 0.508)
		(drill 0.254)
		(layers "F.Cu" "B.Cu")
		(net "GND")
	)
	(via
		(at 314.649866 -313.949842)
		(size 0.4064)
		(drill 0.2032)
		(layers "F.Cu" "B.Cu")
		(net "GND")
	)
	(via
		(at 411.835092 -357.75773)
		(size 0.4064)
		(drill 0.2032)
		(layers "F.Cu" "B.Cu")
		(net "GND")
	)
	(via
		(at 220.702632 -237.14456)
		(size 0.508)
		(drill 0.254)
		(layers "F.Cu" "B.Cu")
		(net "GND")
	)
	(via
		(at 424.57497 -288.774886)
		(size 0.4064)
		(drill 0.2032)
		(layers "F.Cu" "B.Cu")
		(net "GND")
	)
	(via
		(at 327.676764 -204.278484)
		(size 0.508)
		(drill 0.254)
		(layers "F.Cu" "B.Cu")
		(net "GND")
	)
	(via
		(at 133.427216 -346.09913)
		(size 0.4572)
		(drill 0.254)
		(layers "F.Cu" "B.Cu")
		(net "GND")
	)
	(via
		(at 377.247404 -247.367044)
		(size 0.508)
		(drill 0.254)
		(layers "F.Cu" "B.Cu")
		(net "GND")
	)
	(via
		(at 52.524914 -306.824888)
		(size 0.4064)
		(drill 0.2032)
		(layers "F.Cu" "B.Cu")
		(net "GND")
	)
	(via
		(at 167.835072 -354.732082)
		(size 0.4064)
		(drill 0.2032)
		(layers "F.Cu" "B.Cu")
		(net "GND")
	)
	(via
		(at 60.124848 -285.924752)
		(size 0.4064)
		(drill 0.2032)
		(layers "F.Cu" "B.Cu")
		(net "GND")
	)
	(via
		(at 68.199762 -281.649932)
		(size 0.4064)
		(drill 0.2032)
		(layers "F.Cu" "B.Cu")
		(net "GND")
	)
	(via
		(at 330.872846 -23.880318)
		(size 0.508)
		(drill 0.254)
		(layers "F.Cu" "B.Cu")
		(net "GND")
	)
	(via
		(at 422.674796 -296.37482)
		(size 0.4064)
		(drill 0.2032)
		(layers "F.Cu" "B.Cu")
		(net "GND")
	)
	(via
		(at 187.005468 -1.364996)
		(size 0.508)
		(drill 0.254)
		(layers "F.Cu" "B.Cu")
		(net "GND")
	)
	(via
		(at 125.430534 -306.607718)
		(size 0.508)
		(drill 0.254)
		(layers "F.Cu" "B.Cu")
		(net "GND")
	)
	(via
		(at 174.747936 -409.940252)
		(size 0.508)
		(drill 0.254)
		(layers "F.Cu" "B.Cu")
		(net "GND")
	)
	(via
		(at 182.002176 -56.826404)
		(size 0.508)
		(drill 0.254)
		(layers "F.Cu" "B.Cu")
		(net "GND")
	)
	(via
		(at 263.849866 -27.04973)
		(size 0.508)
		(drill 0.254)
		(layers "F.Cu" "B.Cu")
		(net "GND")
	)
	(via
		(at 154.501596 -99.116642)
		(size 0.508)
		(drill 0.254)
		(layers "F.Cu" "B.Cu")
		(net "GND")
	)
	(via
		(at 114.779806 -331.729842)
		(size 0.508)
		(drill 0.254)
		(layers "F.Cu" "B.Cu")
		(net "GND")
	)
	(via
		(at 209.165698 -303.026826)
		(size 0.508)
		(drill 0.254)
		(layers "F.Cu" "B.Cu")
		(net "GND")
	)
	(via
		(at 52.049934 -319.65011)
		(size 0.4064)
		(drill 0.2032)
		(layers "F.Cu" "B.Cu")
		(net "GND")
	)
	(via
		(at 21.313394 -34.718498)
		(size 0.508)
		(drill 0.254)
		(layers "F.Cu" "B.Cu")
		(net "GND")
	)
	(via
		(at 438.708292 -351.611438)
		(size 0.4064)
		(drill 0.2032)
		(layers "F.Cu" "B.Cu")
		(net "GND")
	)
	(via
		(at 189.049914 -310.149748)
		(size 0.4064)
		(drill 0.2032)
		(layers "F.Cu" "B.Cu")
		(net "GND")
	)
	(via
		(at 167.732964 -107.844844)
		(size 0.508)
		(drill 0.254)
		(layers "F.Cu" "B.Cu")
		(net "GND")
	)
	(via
		(at 313.09818 -129.707894)
		(size 0.508)
		(drill 0.254)
		(layers "F.Cu" "B.Cu")
		(net "GND")
	)
	(via
		(at 304.527712 -407.638504)
		(size 0.508)
		(drill 0.254)
		(layers "F.Cu" "B.Cu")
		(net "GND")
	)
	(via
		(at 122.102372 -286.842454)
		(size 0.508)
		(drill 0.254)
		(layers "F.Cu" "B.Cu")
		(net "GND")
	)
	(via
		(at 180.270912 -342.439498)
		(size 0.4064)
		(drill 0.2032)
		(layers "F.Cu" "B.Cu")
		(net "GND")
	)
	(via
		(at 384.674872 -294.4749)
		(size 0.4064)
		(drill 0.2032)
		(layers "F.Cu" "B.Cu")
		(net "GND")
	)
	(via
		(at 295.727882 -410.041852)
		(size 0.508)
		(drill 0.254)
		(layers "F.Cu" "B.Cu")
		(net "GND")
	)
	(via
		(at 429.800004 -312.999882)
		(size 0.4064)
		(drill 0.2032)
		(layers "F.Cu" "B.Cu")
		(net "GND")
	)
	(via
		(at 408.424888 -302.074834)
		(size 0.4064)
		(drill 0.2032)
		(layers "F.Cu" "B.Cu")
		(net "GND")
	)
	(via
		(at 249.058176 -122.462036)
		(size 0.508)
		(drill 0.254)
		(layers "F.Cu" "B.Cu")
		(net "GND")
	)
	(via
		(at 279.974802 -287.824926)
		(size 0.4064)
		(drill 0.2032)
		(layers "F.Cu" "B.Cu")
		(net "GND")
	)
	(via
		(at 288.524696 -284.024832)
		(size 0.4064)
		(drill 0.2032)
		(layers "F.Cu" "B.Cu")
		(net "GND")
	)
	(via
		(at 80.239616 -85.426296)
		(size 0.508)
		(drill 0.254)
		(layers "F.Cu" "B.Cu")
		(net "GND")
	)
	(via
		(at 47.77486 -299.224954)
		(size 0.4064)
		(drill 0.2032)
		(layers "F.Cu" "B.Cu")
		(net "GND")
	)
	(via
		(at 28.461716 -355.366066)
		(size 0.4572)
		(drill 0.254)
		(layers "F.Cu" "B.Cu")
		(net "GND")
	)
	(via
		(at 441.445904 -346.09913)
		(size 0.4572)
		(drill 0.254)
		(layers "F.Cu" "B.Cu")
		(net "GND")
	)
	(via
		(at 455.565002 -249.51944)
		(size 0.508)
		(drill 0.254)
		(layers "F.Cu" "B.Cu")
		(net "GND")
	)
	(via
		(at 419.349936 -319.65011)
		(size 0.4064)
		(drill 0.2032)
		(layers "F.Cu" "B.Cu")
		(net "GND")
	)
	(via
		(at 82.373724 -25.971246)
		(size 0.508)
		(drill 0.254)
		(layers "F.Cu" "B.Cu")
		(net "GND")
	)
	(via
		(at 392.52779 -401.040092)
		(size 0.508)
		(drill 0.254)
		(layers "F.Cu" "B.Cu")
		(net "GND")
	)
	(via
		(at 81.458562 -345.465146)
		(size 0.4064)
		(drill 0.2032)
		(layers "F.Cu" "B.Cu")
		(net "GND")
	)
	(via
		(at 315.124846 -296.37482)
		(size 0.4064)
		(drill 0.2032)
		(layers "F.Cu" "B.Cu")
		(net "GND")
	)
	(via
		(at 401.78736 -124.154946)
		(size 0.508)
		(drill 0.254)
		(layers "F.Cu" "B.Cu")
		(net "GND")
	)
	(via
		(at 395.59992 -312.999882)
		(size 0.4064)
		(drill 0.2032)
		(layers "F.Cu" "B.Cu")
		(net "GND")
	)
	(via
		(at 84.04987 -8.078724)
		(size 0.508)
		(drill 0.254)
		(layers "F.Cu" "B.Cu")
		(net "GND")
	)
	(via
		(at 387.525006 -276.424898)
		(size 0.4064)
		(drill 0.2032)
		(layers "F.Cu" "B.Cu")
		(net "GND")
	)
	(via
		(at 187.624974 -296.37482)
		(size 0.4064)
		(drill 0.2032)
		(layers "F.Cu" "B.Cu")
		(net "GND")
	)
	(via
		(at 170.999912 -281.649932)
		(size 0.4064)
		(drill 0.2032)
		(layers "F.Cu" "B.Cu")
		(net "GND")
	)
	(via
		(at 292.57117 -352.245422)
		(size 0.4572)
		(drill 0.254)
		(layers "F.Cu" "B.Cu")
		(net "GND")
	)
	(via
		(at 414.74771 -143.955008)
		(size 0.508)
		(drill 0.254)
		(layers "F.Cu" "B.Cu")
		(net "GND")
	)
	(via
		(at 265.686286 -253.45644)
		(size 0.508)
		(drill 0.254)
		(layers "F.Cu" "B.Cu")
		(net "GND")
	)
	(via
		(at 197.502526 -89.790524)
		(size 0.508)
		(drill 0.254)
		(layers "F.Cu" "B.Cu")
		(net "GND")
	)
	(via
		(at 248.097802 -78.054962)
		(size 0.508)
		(drill 0.254)
		(layers "F.Cu" "B.Cu")
		(net "GND")
	)
	(via
		(at 21.313394 -33.459674)
		(size 0.508)
		(drill 0.254)
		(layers "F.Cu" "B.Cu")
		(net "GND")
	)
	(via
		(at 302.327818 -380.040134)
		(size 0.508)
		(drill 0.254)
		(layers "F.Cu" "B.Cu")
		(net "GND")
	)
	(via
		(at 39.418768 -357.75773)
		(size 0.4064)
		(drill 0.2032)
		(layers "F.Cu" "B.Cu")
		(net "GND")
	)
	(via
		(at 70.099936 -276.899878)
		(size 0.4064)
		(drill 0.2032)
		(layers "F.Cu" "B.Cu")
		(net "GND")
	)
	(via
		(at 56.799988 -278.799798)
		(size 0.4064)
		(drill 0.2032)
		(layers "F.Cu" "B.Cu")
		(net "GND")
	)
	(via
		(at 420.054532 -354.732082)
		(size 0.4064)
		(drill 0.2032)
		(layers "F.Cu" "B.Cu")
		(net "GND")
	)
	(via
		(at 38.401752 -107.57535)
		(size 0.508)
		(drill 0.254)
		(layers "F.Cu" "B.Cu")
		(net "GND")
	)
	(via
		(at 346.578682 -282.910788)
		(size 0.49022)
		(drill 0.254)
		(layers "F.Cu" "B.Cu")
		(net "GND")
	)
	(via
		(at 419.334442 -47.936658)
		(size 0.508)
		(drill 0.254)
		(layers "F.Cu" "B.Cu")
		(net "GND")
	)
	(via
		(at 244.865144 -208.016094)
		(size 0.508)
		(drill 0.254)
		(layers "F.Cu" "B.Cu")
		(net "GND")
	)
	(via
		(at 130.897884 -286.842454)
		(size 0.508)
		(drill 0.254)
		(layers "F.Cu" "B.Cu")
		(net "GND")
	)
	(via
		(at 174.325026 -283.074872)
		(size 0.4064)
		(drill 0.2032)
		(layers "F.Cu" "B.Cu")
		(net "GND")
	)
	(via
		(at 349.85706 -318.557656)
		(size 0.508)
		(drill 0.254)
		(layers "F.Cu" "B.Cu")
		(net "GND")
	)
	(via
		(at 195.699634 -287.349946)
		(size 0.4064)
		(drill 0.2032)
		(layers "F.Cu" "B.Cu")
		(net "GND")
	)
	(via
		(at 386.701792 -124.43333)
		(size 0.508)
		(drill 0.254)
		(layers "F.Cu" "B.Cu")
		(net "GND")
	)
	(via
		(at 288.524696 -305.874928)
		(size 0.4064)
		(drill 0.2032)
		(layers "F.Cu" "B.Cu")
		(net "GND")
	)
	(via
		(at 67.724782 -306.824888)
		(size 0.4064)
		(drill 0.2032)
		(layers "F.Cu" "B.Cu")
		(net "GND")
	)
	(via
		(at 49.324006 -26.319734)
		(size 0.508)
		(drill 0.254)
		(layers "F.Cu" "B.Cu")
		(net "GND")
	)
	(via
		(at 270.474948 -284.974792)
		(size 0.4064)
		(drill 0.2032)
		(layers "F.Cu" "B.Cu")
		(net "GND")
	)
	(via
		(at 338.09559 -88.612472)
		(size 0.508)
		(drill 0.254)
		(layers "F.Cu" "B.Cu")
		(net "GND")
	)
	(via
		(at 151.859488 -135.095488)
		(size 0.508)
		(drill 0.254)
		(layers "F.Cu" "B.Cu")
		(net "GND")
	)
	(via
		(at 154.850084 -319.65011)
		(size 0.4064)
		(drill 0.2032)
		(layers "F.Cu" "B.Cu")
		(net "GND")
	)
	(via
		(at 39.04742 -357.123746)
		(size 0.4572)
		(drill 0.254)
		(layers "F.Cu" "B.Cu")
		(net "GND")
	)
	(via
		(at 427.727872 -369.938554)
		(size 0.508)
		(drill 0.254)
		(layers "F.Cu" "B.Cu")
		(net "GND")
	)
	(via
		(at 440.645804 -95.630746)
		(size 0.508)
		(drill 0.254)
		(layers "F.Cu" "B.Cu")
		(net "GND")
	)
	(via
		(at 272.102072 -58.731404)
		(size 0.508)
		(drill 0.254)
		(layers "F.Cu" "B.Cu")
		(net "GND")
	)
	(via
		(at 169.869612 -64.102234)
		(size 0.508)
		(drill 0.254)
		(layers "F.Cu" "B.Cu")
		(net "GND")
	)
	(via
		(at 178.483514 -191.381634)
		(size 0.508)
		(drill 0.254)
		(layers "F.Cu" "B.Cu")
		(net "GND")
	)
	(via
		(at 123.400058 -62.812168)
		(size 0.508)
		(drill 0.254)
		(layers "F.Cu" "B.Cu")
		(net "GND")
	)
	(via
		(at 62.499748 -277.849838)
		(size 0.4064)
		(drill 0.2032)
		(layers "F.Cu" "B.Cu")
		(net "GND")
	)
	(via
		(at 399.874994 -300.174914)
		(size 0.4064)
		(drill 0.2032)
		(layers "F.Cu" "B.Cu")
		(net "GND")
	)
	(via
		(at 250.367546 -122.09907)
		(size 0.508)
		(drill 0.254)
		(layers "F.Cu" "B.Cu")
		(net "GND")
	)
	(via
		(at 32.8295 -352.245422)
		(size 0.4572)
		(drill 0.254)
		(layers "F.Cu" "B.Cu")
		(net "GND")
	)
	(via
		(at 5.448046 -64.312292)
		(size 0.508)
		(drill 0.254)
		(layers "F.Cu" "B.Cu")
		(net "GND")
	)
	(via
		(at 167.200072 -281.649932)
		(size 0.4064)
		(drill 0.2032)
		(layers "F.Cu" "B.Cu")
		(net "GND")
	)
	(via
		(at 293.527734 -402.140166)
		(size 0.508)
		(drill 0.254)
		(layers "F.Cu" "B.Cu")
		(net "GND")
	)
	(via
		(at 54.70652 -131.76504)
		(size 0.508)
		(drill 0.254)
		(layers "F.Cu" "B.Cu")
		(net "GND")
	)
	(via
		(at 157.224984 -283.074872)
		(size 0.4064)
		(drill 0.2032)
		(layers "F.Cu" "B.Cu")
		(net "GND")
	)
	(via
		(at 304.527712 -408.840178)
		(size 0.508)
		(drill 0.254)
		(layers "F.Cu" "B.Cu")
		(net "GND")
	)
	(via
		(at 400.05 -146.155156)
		(size 0.508)
		(drill 0.254)
		(layers "F.Cu" "B.Cu")
		(net "GND")
	)
	(via
		(at 417.79952 -57.439814)
		(size 0.508)
		(drill 0.254)
		(layers "F.Cu" "B.Cu")
		(net "GND")
	)
	(via
		(at 122.166634 -35.871912)
		(size 0.508)
		(drill 0.254)
		(layers "F.Cu" "B.Cu")
		(net "GND")
	)
	(via
		(at 191.900048 -310.149748)
		(size 0.4064)
		(drill 0.2032)
		(layers "F.Cu" "B.Cu")
		(net "GND")
	)
	(via
		(at 420.567104 -129.445004)
		(size 0.508)
		(drill 0.254)
		(layers "F.Cu" "B.Cu")
		(net "GND")
	)
	(via
		(at 335.026 -178.943)
		(size 0.508)
		(drill 0.254)
		(layers "F.Cu" "B.Cu")
		(net "GND")
	)
	(via
		(at 218.653868 -284.641544)
		(size 0.508)
		(drill 0.254)
		(layers "F.Cu" "B.Cu")
		(net "GND")
	)
	(via
		(at 144.672558 -225.275902)
		(size 0.508)
		(drill 0.254)
		(layers "F.Cu" "B.Cu")
		(net "GND")
	)
	(via
		(at 303.698402 -65.15989)
		(size 0.508)
		(drill 0.254)
		(layers "F.Cu" "B.Cu")
		(net "GND")
	)
	(via
		(at 134.310882 -57.439814)
		(size 0.508)
		(drill 0.254)
		(layers "F.Cu" "B.Cu")
		(net "GND")
	)
	(via
		(at 134.738872 -23.880318)
		(size 0.508)
		(drill 0.254)
		(layers "F.Cu" "B.Cu")
		(net "GND")
	)
	(via
		(at 236.826552 -83.951318)
		(size 0.508)
		(drill 0.254)
		(layers "F.Cu" "B.Cu")
		(net "GND")
	)
	(via
		(at 66.132202 -13.613638)
		(size 0.508)
		(drill 0.254)
		(layers "F.Cu" "B.Cu")
		(net "GND")
	)
	(via
		(at 58.699908 -273.099784)
		(size 0.4064)
		(drill 0.2032)
		(layers "F.Cu" "B.Cu")
		(net "GND")
	)
	(via
		(at 135.057388 -354.732082)
		(size 0.4064)
		(drill 0.2032)
		(layers "F.Cu" "B.Cu")
		(net "GND")
	)
	(via
		(at 89.83218 -125.378972)
		(size 0.508)
		(drill 0.254)
		(layers "F.Cu" "B.Cu")
		(net "GND")
	)
	(via
		(at 151.748998 -34.990024)
		(size 0.508)
		(drill 0.254)
		(layers "F.Cu" "B.Cu")
		(net "GND")
	)
	(via
		(at 272.448782 -33.19018)
		(size 0.508)
		(drill 0.254)
		(layers "F.Cu" "B.Cu")
		(net "GND")
	)
	(via
		(at 432.119024 -346.09913)
		(size 0.4572)
		(drill 0.254)
		(layers "F.Cu" "B.Cu")
		(net "GND")
	)
	(via
		(at 360.045 -29.589984)
		(size 0.508)
		(drill 0.254)
		(layers "F.Cu" "B.Cu")
		(net "GND")
	)
	(via
		(at 420.972996 -23.880318)
		(size 0.508)
		(drill 0.254)
		(layers "F.Cu" "B.Cu")
		(net "GND")
	)
	(via
		(at 20.765008 -348.58579)
		(size 0.4064)
		(drill 0.2032)
		(layers "F.Cu" "B.Cu")
		(net "GND")
	)
	(via
		(at 427.75124 -352.245422)
		(size 0.4572)
		(drill 0.254)
		(layers "F.Cu" "B.Cu")
		(net "GND")
	)
	(via
		(at 346.327984 -380.040134)
		(size 0.508)
		(drill 0.254)
		(layers "F.Cu" "B.Cu")
		(net "GND")
	)
	(via
		(at 198.26605 -147.27682)
		(size 0.508)
		(drill 0.254)
		(layers "F.Cu" "B.Cu")
		(net "GND")
	)
	(via
		(at 40.174926 -279.274778)
		(size 0.4064)
		(drill 0.2032)
		(layers "F.Cu" "B.Cu")
		(net "GND")
	)
	(via
		(at 440.548776 -31.390082)
		(size 0.508)
		(drill 0.254)
		(layers "F.Cu" "B.Cu")
		(net "GND")
	)
	(via
		(at 289.47491 -303.974754)
		(size 0.4064)
		(drill 0.2032)
		(layers "F.Cu" "B.Cu")
		(net "GND")
	)
	(via
		(at 125.709172 -288.14649)
		(size 0.508)
		(drill 0.254)
		(layers "F.Cu" "B.Cu")
		(net "GND")
	)
	(via
		(at 318.019938 -31.390336)
		(size 0.508)
		(drill 0.254)
		(layers "F.Cu" "B.Cu")
		(net "GND")
	)
	(via
		(at 144.01292 -354.098098)
		(size 0.4572)
		(drill 0.254)
		(layers "F.Cu" "B.Cu")
		(net "GND")
	)
	(via
		(at 56.208168 -52.536852)
		(size 0.508)
		(drill 0.254)
		(layers "F.Cu" "B.Cu")
		(net "GND")
	)
	(via
		(at 221.204028 -119.072914)
		(size 0.508)
		(drill 0.254)
		(layers "F.Cu" "B.Cu")
		(net "GND")
	)
	(via
		(at 42.15638 -355.366066)
		(size 0.4572)
		(drill 0.254)
		(layers "F.Cu" "B.Cu")
		(net "GND")
	)
	(via
		(at 166.249858 -275.949918)
		(size 0.4064)
		(drill 0.2032)
		(layers "F.Cu" "B.Cu")
		(net "GND")
	)
	(via
		(at 374.493536 -292.732714)
		(size 0.508)
		(drill 0.254)
		(layers "F.Cu" "B.Cu")
		(net "GND")
	)
	(via
		(at 225.110294 -64.03086)
		(size 0.508)
		(drill 0.254)
		(layers "F.Cu" "B.Cu")
		(net "GND")
	)
	(via
		(at 282.824936 -305.874928)
		(size 0.4064)
		(drill 0.2032)
		(layers "F.Cu" "B.Cu")
		(net "GND")
	)
	(via
		(at 316.672976 -352.245422)
		(size 0.4572)
		(drill 0.254)
		(layers "F.Cu" "B.Cu")
		(net "GND")
	)
	(via
		(at 463.037682 -240.297462)
		(size 0.508)
		(drill 0.254)
		(layers "F.Cu" "B.Cu")
		(net "GND")
	)
	(via
		(at 327.849992 -357.123746)
		(size 0.4572)
		(drill 0.254)
		(layers "F.Cu" "B.Cu")
		(net "GND")
	)
	(via
		(at 293.74973 -275.949918)
		(size 0.4064)
		(drill 0.2032)
		(layers "F.Cu" "B.Cu")
		(net "GND")
	)
	(via
		(at 18.671286 -29.311854)
		(size 0.508)
		(drill 0.254)
		(layers "F.Cu" "B.Cu")
		(net "GND")
	)
	(via
		(at 182.547514 -149.355048)
		(size 0.508)
		(drill 0.254)
		(layers "F.Cu" "B.Cu")
		(net "GND")
	)
	(via
		(at 408.899868 -277.849838)
		(size 0.4064)
		(drill 0.2032)
		(layers "F.Cu" "B.Cu")
		(net "GND")
	)
	(via
		(at 168.150032 -312.049922)
		(size 0.4064)
		(drill 0.2032)
		(layers "F.Cu" "B.Cu")
		(net "GND")
	)
	(via
		(at 296.793412 -156.555186)
		(size 0.508)
		(drill 0.254)
		(layers "F.Cu" "B.Cu")
		(net "GND")
	)
	(via
		(at 60.599828 -313.949842)
		(size 0.4064)
		(drill 0.2032)
		(layers "F.Cu" "B.Cu")
		(net "GND")
	)
	(via
		(at 40.174926 -292.574726)
		(size 0.4064)
		(drill 0.2032)
		(layers "F.Cu" "B.Cu")
		(net "GND")
	)
	(via
		(at 84.04987 -2.998724)
		(size 0.508)
		(drill 0.254)
		(layers "F.Cu" "B.Cu")
		(net "GND")
	)
	(via
		(at 216.351358 -47.03191)
		(size 0.508)
		(drill 0.254)
		(layers "F.Cu" "B.Cu")
		(net "GND")
	)
	(via
		(at 255.933194 -396.556738)
		(size 0.508)
		(drill 0.254)
		(layers "F.Cu" "B.Cu")
		(net "GND")
	)
	(via
		(at 385.149852 -313.949842)
		(size 0.4064)
		(drill 0.2032)
		(layers "F.Cu" "B.Cu")
		(net "GND")
	)
	(via
		(at 308.474872 -293.52494)
		(size 0.4064)
		(drill 0.2032)
		(layers "F.Cu" "B.Cu")
		(net "GND")
	)
	(via
		(at 106.229404 -164.20592)
		(size 0.508)
		(drill 0.254)
		(layers "F.Cu" "B.Cu")
		(net "GND")
	)
	(via
		(at 429.768 -417.82492)
		(size 0.508)
		(drill 0.254)
		(layers "F.Cu" "B.Cu")
		(net "GND")
	)
	(via
		(at 434.848 -417.82492)
		(size 0.508)
		(drill 0.254)
		(layers "F.Cu" "B.Cu")
		(net "GND")
	)
	(via
		(at 134.730744 -131.964176)
		(size 0.508)
		(drill 0.254)
		(layers "F.Cu" "B.Cu")
		(net "GND")
	)
	(via
		(at 168.952164 -107.844844)
		(size 0.508)
		(drill 0.254)
		(layers "F.Cu" "B.Cu")
		(net "GND")
	)
	(via
		(at 163.747958 -375.040144)
		(size 0.508)
		(drill 0.254)
		(layers "F.Cu" "B.Cu")
		(net "GND")
	)
	(via
		(at 17.323308 -132.620766)
		(size 0.508)
		(drill 0.254)
		(layers "F.Cu" "B.Cu")
		(net "GND")
	)
	(via
		(at 419.683184 -352.245422)
		(size 0.4572)
		(drill 0.254)
		(layers "F.Cu" "B.Cu")
		(net "GND")
	)
	(via
		(at 155.800044 -299.699934)
		(size 0.4064)
		(drill 0.2032)
		(layers "F.Cu" "B.Cu")
		(net "GND")
	)
	(via
		(at 135.620252 -56.441848)
		(size 0.508)
		(drill 0.254)
		(layers "F.Cu" "B.Cu")
		(net "GND")
	)
	(via
		(at 92.26423 -354.098098)
		(size 0.4572)
		(drill 0.254)
		(layers "F.Cu" "B.Cu")
		(net "GND")
	)
	(via
		(at 12.212066 -386.496814)
		(size 0.508)
		(drill 0.254)
		(layers "F.Cu" "B.Cu")
		(net "GND")
	)
	(via
		(at 463.037682 -214.897462)
		(size 0.508)
		(drill 0.254)
		(layers "F.Cu" "B.Cu")
		(net "GND")
	)
	(via
		(at 310.751474 -103.104696)
		(size 0.508)
		(drill 0.254)
		(layers "F.Cu" "B.Cu")
		(net "GND")
	)
	(via
		(at 221.59976 -312.441082)
		(size 0.508)
		(drill 0.254)
		(layers "F.Cu" "B.Cu")
		(net "GND")
	)
	(via
		(at 290.17976 -101.782372)
		(size 0.508)
		(drill 0.254)
		(layers "F.Cu" "B.Cu")
		(net "GND")
	)
	(via
		(at 135.057388 -351.611438)
		(size 0.4064)
		(drill 0.2032)
		(layers "F.Cu" "B.Cu")
		(net "GND")
	)
	(via
		(at 319.781936 -346.09913)
		(size 0.4572)
		(drill 0.254)
		(layers "F.Cu" "B.Cu")
		(net "GND")
	)
	(via
		(at 402.079968 -346.09913)
		(size 0.4572)
		(drill 0.254)
		(layers "F.Cu" "B.Cu")
		(net "GND")
	)
	(via
		(at 416.580828 -25.990042)
		(size 0.508)
		(drill 0.254)
		(layers "F.Cu" "B.Cu")
		(net "GND")
	)
	(via
		(at 421.8305 -65.15989)
		(size 0.508)
		(drill 0.254)
		(layers "F.Cu" "B.Cu")
		(net "GND")
	)
	(via
		(at 389.644128 -350.977454)
		(size 0.4572)
		(drill 0.254)
		(layers "F.Cu" "B.Cu")
		(net "GND")
	)
	(via
		(at 170.736514 -51.661822)
		(size 0.508)
		(drill 0.254)
		(layers "F.Cu" "B.Cu")
		(net "GND")
	)
	(via
		(at 128.46812 -355.366066)
		(size 0.4572)
		(drill 0.254)
		(layers "F.Cu" "B.Cu")
		(net "GND")
	)
	(via
		(at 294.22471 -300.174914)
		(size 0.4064)
		(drill 0.2032)
		(layers "F.Cu" "B.Cu")
		(net "GND")
	)
	(via
		(at 346.327984 -402.140166)
		(size 0.508)
		(drill 0.254)
		(layers "F.Cu" "B.Cu")
		(net "GND")
	)
	(via
		(at 279.974802 -303.974754)
		(size 0.4064)
		(drill 0.2032)
		(layers "F.Cu" "B.Cu")
		(net "GND")
	)
	(via
		(at 383.35204 -13.613638)
		(size 0.508)
		(drill 0.254)
		(layers "F.Cu" "B.Cu")
		(net "GND")
	)
	(via
		(at 403.00656 -118.754906)
		(size 0.508)
		(drill 0.254)
		(layers "F.Cu" "B.Cu")
		(net "GND")
	)
	(via
		(at 163.747958 -406.141936)
		(size 0.508)
		(drill 0.254)
		(layers "F.Cu" "B.Cu")
		(net "GND")
	)
	(via
		(at 83.400138 -312.049922)
		(size 0.4064)
		(drill 0.2032)
		(layers "F.Cu" "B.Cu")
		(net "GND")
	)
	(via
		(at 376.641868 -25.971246)
		(size 0.508)
		(drill 0.254)
		(layers "F.Cu" "B.Cu")
		(net "GND")
	)
	(via
		(at 391.799826 -300.649894)
		(size 0.4064)
		(drill 0.2032)
		(layers "F.Cu" "B.Cu")
		(net "GND")
	)
	(via
		(at 195.699634 -276.899878)
		(size 0.4064)
		(drill 0.2032)
		(layers "F.Cu" "B.Cu")
		(net "GND")
	)
	(via
		(at 298.974764 -307.774848)
		(size 0.4064)
		(drill 0.2032)
		(layers "F.Cu" "B.Cu")
		(net "GND")
	)
	(via
		(at 7.480554 -160.92424)
		(size 0.508)
		(drill 0.254)
		(layers "F.Cu" "B.Cu")
		(net "GND")
	)
	(via
		(at 37.325046 -296.37482)
		(size 0.4064)
		(drill 0.2032)
		(layers "F.Cu" "B.Cu")
		(net "GND")
	)
	(via
		(at 425.99991 -306.349908)
		(size 0.4064)
		(drill 0.2032)
		(layers "F.Cu" "B.Cu")
		(net "GND")
	)
	(via
		(at 333.523844 -26.319734)
		(size 0.508)
		(drill 0.254)
		(layers "F.Cu" "B.Cu")
		(net "GND")
	)
	(via
		(at 16.280892 -34.990024)
		(size 0.508)
		(drill 0.254)
		(layers "F.Cu" "B.Cu")
		(net "GND")
	)
	(via
		(at 27.347926 -403.738588)
		(size 0.508)
		(drill 0.254)
		(layers "F.Cu" "B.Cu")
		(net "GND")
	)
	(via
		(at 437.886856 -94.21749)
		(size 0.508)
		(drill 0.254)
		(layers "F.Cu" "B.Cu")
		(net "GND")
	)
	(via
		(at 66.774822 -302.074834)
		(size 0.4064)
		(drill 0.2032)
		(layers "F.Cu" "B.Cu")
		(net "GND")
	)
	(via
		(at 160.074864 -298.27474)
		(size 0.4064)
		(drill 0.2032)
		(layers "F.Cu" "B.Cu")
		(net "GND")
	)
	(via
		(at 174.747936 -402.140166)
		(size 0.508)
		(drill 0.254)
		(layers "F.Cu" "B.Cu")
		(net "GND")
	)
	(via
		(at 59.649868 -280.699718)
		(size 0.4064)
		(drill 0.2032)
		(layers "F.Cu" "B.Cu")
		(net "GND")
	)
	(via
		(at 421.724836 -301.124874)
		(size 0.4064)
		(drill 0.2032)
		(layers "F.Cu" "B.Cu")
		(net "GND")
	)
	(via
		(at 113.976404 -164.84092)
		(size 0.508)
		(drill 0.254)
		(layers "F.Cu" "B.Cu")
		(net "GND")
	)
	(via
		(at 459.713838 -312.51779)
		(size 0.508)
		(drill 0.254)
		(layers "F.Cu" "B.Cu")
		(net "GND")
	)
	(via
		(at 379.11024 -247.562116)
		(size 0.508)
		(drill 0.254)
		(layers "F.Cu" "B.Cu")
		(net "GND")
	)
	(via
		(at 274.271486 -262.734044)
		(size 0.508)
		(drill 0.254)
		(layers "F.Cu" "B.Cu")
		(net "GND")
	)
	(via
		(at 241.56416 -56.86679)
		(size 0.508)
		(drill 0.254)
		(layers "F.Cu" "B.Cu")
		(net "GND")
	)
	(via
		(at 300.874684 -307.774848)
		(size 0.4064)
		(drill 0.2032)
		(layers "F.Cu" "B.Cu")
		(net "GND")
	)
	(via
		(at 124.147834 -401.040092)
		(size 0.4572)
		(drill 0.254)
		(layers "F.Cu" "B.Cu")
		(net "GND")
	)
	(via
		(at 387.53796 -235.89996)
		(size 0.508)
		(drill 0.254)
		(layers "F.Cu" "B.Cu")
		(net "GND")
	)
	(via
		(at 463.049112 -285.569406)
		(size 0.508)
		(drill 0.254)
		(layers "F.Cu" "B.Cu")
		(net "GND")
	)
	(via
		(at 389.644128 -346.09913)
		(size 0.4572)
		(drill 0.254)
		(layers "F.Cu" "B.Cu")
		(net "GND")
	)
	(via
		(at 423.32783 -395.938502)
		(size 0.508)
		(drill 0.254)
		(layers "F.Cu" "B.Cu")
		(net "GND")
	)
	(via
		(at 7.713726 -168.414192)
		(size 0.508)
		(drill 0.254)
		(layers "F.Cu" "B.Cu")
		(net "GND")
	)
	(via
		(at 61.741812 -161.667444)
		(size 0.508)
		(drill 0.254)
		(layers "F.Cu" "B.Cu")
		(net "GND")
	)
	(via
		(at 430.466246 -153.218134)
		(size 0.508)
		(drill 0.254)
		(layers "F.Cu" "B.Cu")
		(net "GND")
	)
	(via
		(at 229.09276 -316.534546)
		(size 0.508)
		(drill 0.254)
		(layers "F.Cu" "B.Cu")
		(net "GND")
	)
	(via
		(at 298.974764 -303.974754)
		(size 0.4064)
		(drill 0.2032)
		(layers "F.Cu" "B.Cu")
		(net "GND")
	)
	(via
		(at 376.972068 -49.574704)
		(size 0.508)
		(drill 0.254)
		(layers "F.Cu" "B.Cu")
		(net "GND")
	)
	(via
		(at 377.12777 -376.140218)
		(size 0.508)
		(drill 0.254)
		(layers "F.Cu" "B.Cu")
		(net "GND")
	)
	(via
		(at 74.869294 -352.245422)
		(size 0.4572)
		(drill 0.254)
		(layers "F.Cu" "B.Cu")
		(net "GND")
	)
	(via
		(at 391.2743 -348.58579)
		(size 0.4064)
		(drill 0.2032)
		(layers "F.Cu" "B.Cu")
		(net "GND")
	)
	(via
		(at 64.874902 -298.27474)
		(size 0.4064)
		(drill 0.2032)
		(layers "F.Cu" "B.Cu")
		(net "GND")
	)
	(via
		(at 336.872326 -292.789102)
		(size 0.508)
		(drill 0.254)
		(layers "F.Cu" "B.Cu")
		(net "GND")
	)
	(via
		(at 73.61047 -350.977454)
		(size 0.4572)
		(drill 0.254)
		(layers "F.Cu" "B.Cu")
		(net "GND")
	)
	(via
		(at 67.55003 -109.879892)
		(size 0.508)
		(drill 0.254)
		(layers "F.Cu" "B.Cu")
		(net "GND")
	)
	(via
		(at 315.740288 -151.42464)
		(size 0.508)
		(drill 0.254)
		(layers "F.Cu" "B.Cu")
		(net "GND")
	)
	(via
		(at 372.62054 -348.58579)
		(size 0.4064)
		(drill 0.2032)
		(layers "F.Cu" "B.Cu")
		(net "GND")
	)
	(via
		(at 178.599846 -317.749936)
		(size 0.4064)
		(drill 0.2032)
		(layers "F.Cu" "B.Cu")
		(net "GND")
	)
	(via
		(at 208.348834 -31.390082)
		(size 0.508)
		(drill 0.254)
		(layers "F.Cu" "B.Cu")
		(net "GND")
	)
	(via
		(at 237.898432 -82.818732)
		(size 0.508)
		(drill 0.254)
		(layers "F.Cu" "B.Cu")
		(net "GND")
	)
	(via
		(at 150.103078 -287.093914)
		(size 0.508)
		(drill 0.254)
		(layers "F.Cu" "B.Cu")
		(net "GND")
	)
	(via
		(at 156.275024 -280.224738)
		(size 0.4064)
		(drill 0.2032)
		(layers "F.Cu" "B.Cu")
		(net "GND")
	)
	(via
		(at 71.034402 -47.936658)
		(size 0.508)
		(drill 0.254)
		(layers "F.Cu" "B.Cu")
		(net "GND")
	)
	(via
		(at 180.54701 -23.583646)
		(size 0.508)
		(drill 0.254)
		(layers "F.Cu" "B.Cu")
		(net "GND")
	)
	(via
		(at 58.846974 -1.135126)
		(size 0.508)
		(drill 0.254)
		(layers "F.Cu" "B.Cu")
		(net "GND")
	)
	(via
		(at 132.658104 -57.521094)
		(size 0.508)
		(drill 0.254)
		(layers "F.Cu" "B.Cu")
		(net "GND")
	)
	(via
		(at 48.54575 -151.9936)
		(size 0.508)
		(drill 0.254)
		(layers "F.Cu" "B.Cu")
		(net "GND")
	)
	(via
		(at 331.51318 -29.859478)
		(size 0.508)
		(drill 0.254)
		(layers "F.Cu" "B.Cu")
		(net "GND")
	)
	(via
		(at 333.127858 -397.038576)
		(size 0.508)
		(drill 0.254)
		(layers "F.Cu" "B.Cu")
		(net "GND")
	)
	(via
		(at 69.624956 -297.32478)
		(size 0.4064)
		(drill 0.2032)
		(layers "F.Cu" "B.Cu")
		(net "GND")
	)
	(via
		(at 400.349974 -280.699718)
		(size 0.4064)
		(drill 0.2032)
		(layers "F.Cu" "B.Cu")
		(net "GND")
	)
	(via
		(at 344.127836 -377.738386)
		(size 0.508)
		(drill 0.254)
		(layers "F.Cu" "B.Cu")
		(net "GND")
	)
	(via
		(at 285.052262 -104.244902)
		(size 0.508)
		(drill 0.254)
		(layers "F.Cu" "B.Cu")
		(net "GND")
	)
	(via
		(at 393.351766 -118.754906)
		(size 0.508)
		(drill 0.254)
		(layers "F.Cu" "B.Cu")
		(net "GND")
	)
	(via
		(at 303.724818 -296.37482)
		(size 0.4064)
		(drill 0.2032)
		(layers "F.Cu" "B.Cu")
		(net "GND")
	)
	(via
		(at 185.381392 -354.708206)
		(size 0.4064)
		(drill 0.2032)
		(layers "F.Cu" "B.Cu")
		(net "GND")
	)
	(via
		(at 79.59979 -308.249828)
		(size 0.4064)
		(drill 0.2032)
		(layers "F.Cu" "B.Cu")
		(net "GND")
	)
	(via
		(at 436.527702 -401.040092)
		(size 0.508)
		(drill 0.254)
		(layers "F.Cu" "B.Cu")
		(net "GND")
	)
	(via
		(at 81.024984 -302.074834)
		(size 0.4064)
		(drill 0.2032)
		(layers "F.Cu" "B.Cu")
		(net "GND")
	)
	(via
		(at 256.175002 -73.23963)
		(size 0.508)
		(drill 0.254)
		(layers "F.Cu" "B.Cu")
		(net "GND")
	)
	(via
		(at 18.080736 -148.718778)
		(size 0.508)
		(drill 0.254)
		(layers "F.Cu" "B.Cu")
		(net "GND")
	)
	(via
		(at 41.437814 -74.624184)
		(size 0.508)
		(drill 0.254)
		(layers "F.Cu" "B.Cu")
		(net "GND")
	)
	(via
		(at 266.655042 -31.390082)
		(size 0.508)
		(drill 0.254)
		(layers "F.Cu" "B.Cu")
		(net "GND")
	)
	(via
		(at 65.349882 -279.749758)
		(size 0.4064)
		(drill 0.2032)
		(layers "F.Cu" "B.Cu")
		(net "GND")
	)
	(via
		(at 351.086928 -0.762)
		(size 0.508)
		(drill 0.254)
		(layers "F.Cu" "B.Cu")
		(net "GND")
	)
	(via
		(at 255.577594 -355.006148)
		(size 0.508)
		(drill 0.254)
		(layers "F.Cu" "B.Cu")
		(net "GND")
	)
	(via
		(at 397.120872 -347.951806)
		(size 0.4572)
		(drill 0.254)
		(layers "F.Cu" "B.Cu")
		(net "GND")
	)
	(via
		(at 287.574736 -287.824926)
		(size 0.4064)
		(drill 0.2032)
		(layers "F.Cu" "B.Cu")
		(net "GND")
	)
	(via
		(at 405.100028 -312.999882)
		(size 0.4064)
		(drill 0.2032)
		(layers "F.Cu" "B.Cu")
		(net "GND")
	)
	(via
		(at 424.09999 -313.949842)
		(size 0.4064)
		(drill 0.2032)
		(layers "F.Cu" "B.Cu")
		(net "GND")
	)
	(via
		(at 133.427216 -347.951806)
		(size 0.4572)
		(drill 0.254)
		(layers "F.Cu" "B.Cu")
		(net "GND")
	)
	(via
		(at 164.681408 -33.459674)
		(size 0.508)
		(drill 0.254)
		(layers "F.Cu" "B.Cu")
		(net "GND")
	)
	(via
		(at 232.459276 -169.334434)
		(size 0.508)
		(drill 0.254)
		(layers "F.Cu" "B.Cu")
		(net "GND")
	)
	(via
		(at 48.3743 -347.951806)
		(size 0.4572)
		(drill 0.254)
		(layers "F.Cu" "B.Cu")
		(net "GND")
	)
	(via
		(at 429.927766 -398.24025)
		(size 0.508)
		(drill 0.254)
		(layers "F.Cu" "B.Cu")
		(net "GND")
	)
	(via
		(at 276.649688 -303.499774)
		(size 0.4064)
		(drill 0.2032)
		(layers "F.Cu" "B.Cu")
		(net "GND")
	)
	(via
		(at 395.59992 -313.949842)
		(size 0.4064)
		(drill 0.2032)
		(layers "F.Cu" "B.Cu")
		(net "GND")
	)
	(via
		(at 393.558014 -73.85177)
		(size 0.508)
		(drill 0.254)
		(layers "F.Cu" "B.Cu")
		(net "GND")
	)
	(via
		(at 119.214646 -169.676064)
		(size 0.508)
		(drill 0.254)
		(layers "F.Cu" "B.Cu")
		(net "GND")
	)
	(via
		(at 129.946908 -345.465146)
		(size 0.4064)
		(drill 0.2032)
		(layers "F.Cu" "B.Cu")
		(net "GND")
	)
	(via
		(at 445.055498 -63.218314)
		(size 0.508)
		(drill 0.254)
		(layers "F.Cu" "B.Cu")
		(net "GND")
	)
	(via
		(at 396.54988 -280.699718)
		(size 0.4064)
		(drill 0.2032)
		(layers "F.Cu" "B.Cu")
		(net "GND")
	)
	(via
		(at 280.449528 -272.14957)
		(size 0.4064)
		(drill 0.2032)
		(layers "F.Cu" "B.Cu")
		(net "GND")
	)
	(via
		(at 47.77486 -303.974754)
		(size 0.4064)
		(drill 0.2032)
		(layers "F.Cu" "B.Cu")
		(net "GND")
	)
	(via
		(at 275.699728 -307.299868)
		(size 0.4064)
		(drill 0.2032)
		(layers "F.Cu" "B.Cu")
		(net "GND")
	)
	(via
		(at 287.099756 -277.849838)
		(size 0.4064)
		(drill 0.2032)
		(layers "F.Cu" "B.Cu")
		(net "GND")
	)
	(via
		(at 58.35523 -370.24945)
		(size 0.4572)
		(drill 0.254)
		(layers "F.Cu" "B.Cu")
		(net "GND")
	)
	(via
		(at 122.357896 -98.320606)
		(size 0.508)
		(drill 0.254)
		(layers "F.Cu" "B.Cu")
		(net "GND")
	)
	(via
		(at 168.150032 -316.799722)
		(size 0.4064)
		(drill 0.2032)
		(layers "F.Cu" "B.Cu")
		(net "GND")
	)
	(via
		(at 117.882416 -343.073482)
		(size 0.4572)
		(drill 0.254)
		(layers "F.Cu" "B.Cu")
		(net "GND")
	)
	(via
		(at 338.563458 -119.026178)
		(size 0.508)
		(drill 0.254)
		(layers "F.Cu" "B.Cu")
		(net "GND")
	)
	(via
		(at 67.66687 -151.155146)
		(size 0.508)
		(drill 0.254)
		(layers "F.Cu" "B.Cu")
		(net "GND")
	)
	(via
		(at 101.41839 -274.726146)
		(size 0.508)
		(drill 0.254)
		(layers "F.Cu" "B.Cu")
		(net "GND")
	)
	(via
		(at 337.5279 -407.24201)
		(size 0.508)
		(drill 0.254)
		(layers "F.Cu" "B.Cu")
		(net "GND")
	)
	(via
		(at 94.55785 -58.791094)
		(size 0.508)
		(drill 0.254)
		(layers "F.Cu" "B.Cu")
		(net "GND")
	)
	(via
		(at 184.29986 -314.899802)
		(size 0.4064)
		(drill 0.2032)
		(layers "F.Cu" "B.Cu")
		(net "GND")
	)
	(via
		(at 101.32441 -278.708612)
		(size 0.508)
		(drill 0.254)
		(layers "F.Cu" "B.Cu")
		(net "GND")
	)
	(via
		(at 146.538442 -253.45644)
		(size 0.508)
		(drill 0.254)
		(layers "F.Cu" "B.Cu")
		(net "GND")
	)
	(via
		(at 154.375104 -286.874966)
		(size 0.4064)
		(drill 0.2032)
		(layers "F.Cu" "B.Cu")
		(net "GND")
	)
	(via
		(at 42.747946 -399.441924)
		(size 0.508)
		(drill 0.254)
		(layers "F.Cu" "B.Cu")
		(net "GND")
	)
	(via
		(at 290.42487 -284.024832)
		(size 0.4064)
		(drill 0.2032)
		(layers "F.Cu" "B.Cu")
		(net "GND")
	)
	(via
		(at 22.243796 -344.831162)
		(size 0.4572)
		(drill 0.254)
		(layers "F.Cu" "B.Cu")
		(net "GND")
	)
	(via
		(at 243.217954 -177.355754)
		(size 0.508)
		(drill 0.254)
		(layers "F.Cu" "B.Cu")
		(net "GND")
	)
	(via
		(at 408.899868 -276.899878)
		(size 0.4064)
		(drill 0.2032)
		(layers "F.Cu" "B.Cu")
		(net "GND")
	)
	(via
		(at 339.09 -184.023)
		(size 0.508)
		(drill 0.254)
		(layers "F.Cu" "B.Cu")
		(net "GND")
	)
	(via
		(at 412.224982 -303.974754)
		(size 0.4064)
		(drill 0.2032)
		(layers "F.Cu" "B.Cu")
		(net "GND")
	)
	(via
		(at 152.94991 -309.199788)
		(size 0.4064)
		(drill 0.2032)
		(layers "F.Cu" "B.Cu")
		(net "GND")
	)
	(via
		(at 393.820142 -57.076848)
		(size 0.508)
		(drill 0.254)
		(layers "F.Cu" "B.Cu")
		(net "GND")
	)
	(via
		(at 309.899812 -285.449772)
		(size 0.4064)
		(drill 0.2032)
		(layers "F.Cu" "B.Cu")
		(net "GND")
	)
	(via
		(at 379.327918 -377.738386)
		(size 0.508)
		(drill 0.254)
		(layers "F.Cu" "B.Cu")
		(net "GND")
	)
	(via
		(at 161.15157 -113.245138)
		(size 0.508)
		(drill 0.254)
		(layers "F.Cu" "B.Cu")
		(net "GND")
	)
	(via
		(at 337.5279 -404.838662)
		(size 0.508)
		(drill 0.254)
		(layers "F.Cu" "B.Cu")
		(net "GND")
	)
	(via
		(at 282.872942 -354.732082)
		(size 0.4064)
		(drill 0.2032)
		(layers "F.Cu" "B.Cu")
		(net "GND")
	)
	(via
		(at 71.999856 -317.749936)
		(size 0.4064)
		(drill 0.2032)
		(layers "F.Cu" "B.Cu")
		(net "GND")
	)
	(via
		(at 466.827616 -31.692596)
		(size 0.508)
		(drill 0.254)
		(layers "F.Cu" "B.Cu")
		(net "GND")
	)
	(via
		(at 281.394154 -346.09913)
		(size 0.4572)
		(drill 0.254)
		(layers "F.Cu" "B.Cu")
		(net "GND")
	)
	(via
		(at 75.74788 -402.241766)
		(size 0.508)
		(drill 0.254)
		(layers "F.Cu" "B.Cu")
		(net "GND")
	)
	(via
		(at 401.70862 -354.732082)
		(size 0.4064)
		(drill 0.2032)
		(layers "F.Cu" "B.Cu")
		(net "GND")
	)
	(via
		(at 189.400942 -255.780286)
		(size 0.508)
		(drill 0.254)
		(layers "F.Cu" "B.Cu")
		(net "GND")
	)
	(via
		(at 269.049754 -313.949842)
		(size 0.4064)
		(drill 0.2032)
		(layers "F.Cu" "B.Cu")
		(net "GND")
	)
	(via
		(at 164.824918 -285.924752)
		(size 0.4064)
		(drill 0.2032)
		(layers "F.Cu" "B.Cu")
		(net "GND")
	)
	(via
		(at 436.527702 -397.140176)
		(size 0.508)
		(drill 0.254)
		(layers "F.Cu" "B.Cu")
		(net "GND")
	)
	(via
		(at 27.943302 -28.139136)
		(size 0.508)
		(drill 0.254)
		(layers "F.Cu" "B.Cu")
		(net "GND")
	)
	(via
		(at 349.410782 -289.41649)
		(size 0.508)
		(drill 0.254)
		(layers "F.Cu" "B.Cu")
		(net "GND")
	)
	(via
		(at 217.979244 -181.14518)
		(size 0.508)
		(drill 0.254)
		(layers "F.Cu" "B.Cu")
		(net "GND")
	)
	(via
		(at 59.649868 -274.999958)
		(size 0.4064)
		(drill 0.2032)
		(layers "F.Cu" "B.Cu")
		(net "GND")
	)
	(via
		(at 181.901084 -344.831162)
		(size 0.4572)
		(drill 0.254)
		(layers "F.Cu" "B.Cu")
		(net "GND")
	)
	(via
		(at 56.325008 -296.37482)
		(size 0.4064)
		(drill 0.2032)
		(layers "F.Cu" "B.Cu")
		(net "GND")
	)
	(via
		(at 134.978648 -122.09907)
		(size 0.508)
		(drill 0.254)
		(layers "F.Cu" "B.Cu")
		(net "GND")
	)
	(via
		(at 66.774822 -303.974754)
		(size 0.4064)
		(drill 0.2032)
		(layers "F.Cu" "B.Cu")
		(net "GND")
	)
	(via
		(at 78.551532 -100.056696)
		(size 0.508)
		(drill 0.254)
		(layers "F.Cu" "B.Cu")
		(net "GND")
	)
	(via
		(at 404.149814 -275.949918)
		(size 0.4064)
		(drill 0.2032)
		(layers "F.Cu" "B.Cu")
		(net "GND")
	)
	(via
		(at 345.877642 -305.972718)
		(size 0.508)
		(drill 0.254)
		(layers "F.Cu" "B.Cu")
		(net "GND")
	)
	(via
		(at 32.6009 -29.590238)
		(size 0.508)
		(drill 0.254)
		(layers "F.Cu" "B.Cu")
		(net "GND")
	)
	(via
		(at 65.349882 -311.099962)
		(size 0.4064)
		(drill 0.2032)
		(layers "F.Cu" "B.Cu")
		(net "GND")
	)
	(via
		(at 316.672976 -347.92793)
		(size 0.4572)
		(drill 0.254)
		(layers "F.Cu" "B.Cu")
		(net "GND")
	)
	(via
		(at 33.200848 -342.439498)
		(size 0.4064)
		(drill 0.2032)
		(layers "F.Cu" "B.Cu")
		(net "GND")
	)
	(via
		(at 382.30302 -280.693114)
		(size 0.508)
		(drill 0.254)
		(layers "F.Cu" "B.Cu")
		(net "GND")
	)
	(via
		(at 144.65808 -286.331914)
		(size 0.508)
		(drill 0.254)
		(layers "F.Cu" "B.Cu")
		(net "GND")
	)
	(via
		(at 336.249264 -88.612472)
		(size 0.508)
		(drill 0.254)
		(layers "F.Cu" "B.Cu")
		(net "GND")
	)
	(via
		(at 313.224926 -296.37482)
		(size 0.4064)
		(drill 0.2032)
		(layers "F.Cu" "B.Cu")
		(net "GND")
	)
	(via
		(at 349.85706 -315.98997)
		(size 0.508)
		(drill 0.254)
		(layers "F.Cu" "B.Cu")
		(net "GND")
	)
	(via
		(at 42.15638 -350.977454)
		(size 0.4572)
		(drill 0.254)
		(layers "F.Cu" "B.Cu")
		(net "GND")
	)
	(via
		(at 47.29988 -306.349908)
		(size 0.4064)
		(drill 0.2032)
		(layers "F.Cu" "B.Cu")
		(net "GND")
	)
	(via
		(at 174.747936 -382.73863)
		(size 0.508)
		(drill 0.254)
		(layers "F.Cu" "B.Cu")
		(net "GND")
	)
	(via
		(at 384.039872 -297.32478)
		(size 0.4064)
		(drill 0.2032)
		(layers "F.Cu" "B.Cu")
		(net "GND")
	)
	(via
		(at 322.890896 -347.951806)
		(size 0.4572)
		(drill 0.254)
		(layers "F.Cu" "B.Cu")
		(net "GND")
	)
	(via
		(at 363.854746 -384.09245)
		(size 0.508)
		(drill 0.254)
		(layers "F.Cu" "B.Cu")
		(net "GND")
	)
	(via
		(at 299.924724 -284.974792)
		(size 0.4064)
		(drill 0.2032)
		(layers "F.Cu" "B.Cu")
		(net "GND")
	)
	(via
		(at 86.04631 -357.123746)
		(size 0.4572)
		(drill 0.254)
		(layers "F.Cu" "B.Cu")
		(net "GND")
	)
	(via
		(at 153.89987 -303.499774)
		(size 0.4064)
		(drill 0.2032)
		(layers "F.Cu" "B.Cu")
		(net "GND")
	)
	(via
		(at 82.93735 -344.831162)
		(size 0.4572)
		(drill 0.254)
		(layers "F.Cu" "B.Cu")
		(net "GND")
	)
	(via
		(at 47.29988 -277.849838)
		(size 0.4064)
		(drill 0.2032)
		(layers "F.Cu" "B.Cu")
		(net "GND")
	)
	(via
		(at 31.747968 -372.341902)
		(size 0.508)
		(drill 0.254)
		(layers "F.Cu" "B.Cu")
		(net "GND")
	)
	(via
		(at 37.799772 -301.599854)
		(size 0.4064)
		(drill 0.2032)
		(layers "F.Cu" "B.Cu")
		(net "GND")
	)
	(via
		(at 194.336924 -347.951806)
		(size 0.4572)
		(drill 0.254)
		(layers "F.Cu" "B.Cu")
		(net "GND")
	)
	(via
		(at 49.67478 -292.574726)
		(size 0.4064)
		(drill 0.2032)
		(layers "F.Cu" "B.Cu")
		(net "GND")
	)
	(via
		(at 259.80263 -86.599776)
		(size 0.508)
		(drill 0.254)
		(layers "F.Cu" "B.Cu")
		(net "GND")
	)
	(via
		(at 172.900086 -313.949842)
		(size 0.4064)
		(drill 0.2032)
		(layers "F.Cu" "B.Cu")
		(net "GND")
	)
	(via
		(at 68.674742 -293.52494)
		(size 0.4064)
		(drill 0.2032)
		(layers "F.Cu" "B.Cu")
		(net "GND")
	)
	(via
		(at 190.950088 -275.949918)
		(size 0.4064)
		(drill 0.2032)
		(layers "F.Cu" "B.Cu")
		(net "GND")
	)
	(via
		(at 412.699962 -310.149748)
		(size 0.4064)
		(drill 0.2032)
		(layers "F.Cu" "B.Cu")
		(net "GND")
	)
	(via
		(at 348.527878 -384.042158)
		(size 0.508)
		(drill 0.254)
		(layers "F.Cu" "B.Cu")
		(net "GND")
	)
	(via
		(at 375.623328 -51.019456)
		(size 0.508)
		(drill 0.254)
		(layers "F.Cu" "B.Cu")
		(net "GND")
	)
	(via
		(at 17.429226 -113.606326)
		(size 0.508)
		(drill 0.254)
		(layers "F.Cu" "B.Cu")
		(net "GND")
	)
	(via
		(at 287.574736 -291.624766)
		(size 0.4064)
		(drill 0.2032)
		(layers "F.Cu" "B.Cu")
		(net "GND")
	)
	(via
		(at 46.34992 -310.149748)
		(size 0.4064)
		(drill 0.2032)
		(layers "F.Cu" "B.Cu")
		(net "GND")
	)
	(via
		(at 353.99853 -307.18887)
		(size 0.508)
		(drill 0.254)
		(layers "F.Cu" "B.Cu")
		(net "GND")
	)
	(via
		(at 334.067912 -352.245422)
		(size 0.4572)
		(drill 0.254)
		(layers "F.Cu" "B.Cu")
		(net "GND")
	)
	(via
		(at 265.392662 -11.372342)
		(size 0.508)
		(drill 0.254)
		(layers "F.Cu" "B.Cu")
		(net "GND")
	)
	(via
		(at 428.685452 -34.183066)
		(size 0.508)
		(drill 0.254)
		(layers "F.Cu" "B.Cu")
		(net "GND")
	)
	(via
		(at 35.759644 -133.836664)
		(size 0.508)
		(drill 0.254)
		(layers "F.Cu" "B.Cu")
		(net "GND")
	)
	(via
		(at 40.649906 -303.499774)
		(size 0.4064)
		(drill 0.2032)
		(layers "F.Cu" "B.Cu")
		(net "GND")
	)
	(via
		(at 466.827616 -72.332596)
		(size 0.508)
		(drill 0.254)
		(layers "F.Cu" "B.Cu")
		(net "GND")
	)
	(via
		(at 337.5279 -383.940304)
		(size 0.508)
		(drill 0.254)
		(layers "F.Cu" "B.Cu")
		(net "GND")
	)
	(via
		(at 459.713838 -314.90539)
		(size 0.508)
		(drill 0.254)
		(layers "F.Cu" "B.Cu")
		(net "GND")
	)
	(via
		(at 225.046794 -39.1414)
		(size 0.508)
		(drill 0.254)
		(layers "F.Cu" "B.Cu")
		(net "GND")
	)
	(via
		(at 106.363516 -119.026178)
		(size 0.508)
		(drill 0.254)
		(layers "F.Cu" "B.Cu")
		(net "GND")
	)
	(via
		(at 84.600796 -33.19018)
		(size 0.508)
		(drill 0.254)
		(layers "F.Cu" "B.Cu")
		(net "GND")
	)
	(via
		(at 198.26605 -154.476958)
		(size 0.508)
		(drill 0.254)
		(layers "F.Cu" "B.Cu")
		(net "GND")
	)
	(via
		(at 138.466576 -230.89235)
		(size 0.508)
		(drill 0.254)
		(layers "F.Cu" "B.Cu")
		(net "GND")
	)
	(via
		(at 379.015244 -60.601606)
		(size 0.508)
		(drill 0.254)
		(layers "F.Cu" "B.Cu")
		(net "GND")
	)
	(via
		(at 427.727872 -382.84023)
		(size 0.508)
		(drill 0.254)
		(layers "F.Cu" "B.Cu")
		(net "GND")
	)
	(via
		(at 356.337108 -284.333188)
		(size 0.49022)
		(drill 0.254)
		(layers "F.Cu" "B.Cu")
		(net "GND")
	)
	(via
		(at 50.14976 -315.849762)
		(size 0.4064)
		(drill 0.2032)
		(layers "F.Cu" "B.Cu")
		(net "GND")
	)
	(via
		(at 49.67478 -306.824888)
		(size 0.4064)
		(drill 0.2032)
		(layers "F.Cu" "B.Cu")
		(net "GND")
	)
	(via
		(at 383.94894 -34.990024)
		(size 0.508)
		(drill 0.254)
		(layers "F.Cu" "B.Cu")
		(net "GND")
	)
	(via
		(at 72.949816 -312.049922)
		(size 0.4064)
		(drill 0.2032)
		(layers "F.Cu" "B.Cu")
		(net "GND")
	)
	(via
		(at 439.556652 -124.93498)
		(size 0.508)
		(drill 0.254)
		(layers "F.Cu" "B.Cu")
		(net "GND")
	)
	(via
		(at 64.399922 -318.699896)
		(size 0.4064)
		(drill 0.2032)
		(layers "F.Cu" "B.Cu")
		(net "GND")
	)
	(via
		(at 125.34519 -111.735362)
		(size 0.508)
		(drill 0.254)
		(layers "F.Cu" "B.Cu")
		(net "GND")
	)
	(via
		(at 389.644128 -343.073482)
		(size 0.4572)
		(drill 0.254)
		(layers "F.Cu" "B.Cu")
		(net "GND")
	)
	(via
		(at 181.44998 -276.899878)
		(size 0.4064)
		(drill 0.2032)
		(layers "F.Cu" "B.Cu")
		(net "GND")
	)
	(via
		(at 394.17498 -282.124912)
		(size 0.4064)
		(drill 0.2032)
		(layers "F.Cu" "B.Cu")
		(net "GND")
	)
	(via
		(at 169.574972 -305.874928)
		(size 0.4064)
		(drill 0.2032)
		(layers "F.Cu" "B.Cu")
		(net "GND")
	)
	(via
		(at 181.901084 -350.977454)
		(size 0.4572)
		(drill 0.254)
		(layers "F.Cu" "B.Cu")
		(net "GND")
	)
	(via
		(at 284.503114 -344.831162)
		(size 0.4572)
		(drill 0.254)
		(layers "F.Cu" "B.Cu")
		(net "GND")
	)
	(via
		(at 264.800842 -34.990278)
		(size 0.508)
		(drill 0.254)
		(layers "F.Cu" "B.Cu")
		(net "GND")
	)
	(via
		(at 182.87492 -289.724846)
		(size 0.4064)
		(drill 0.2032)
		(layers "F.Cu" "B.Cu")
		(net "GND")
	)
	(via
		(at 395.12494 -305.874928)
		(size 0.4064)
		(drill 0.2032)
		(layers "F.Cu" "B.Cu")
		(net "GND")
	)
	(via
		(at 269.57655 -86.235286)
		(size 0.508)
		(drill 0.254)
		(layers "F.Cu" "B.Cu")
		(net "GND")
	)
	(via
		(at 36.849812 -300.649894)
		(size 0.4064)
		(drill 0.2032)
		(layers "F.Cu" "B.Cu")
		(net "GND")
	)
	(via
		(at 100.034598 -118.467886)
		(size 0.508)
		(drill 0.254)
		(layers "F.Cu" "B.Cu")
		(net "GND")
	)
	(via
		(at 65.81267 -121.835164)
		(size 0.508)
		(drill 0.254)
		(layers "F.Cu" "B.Cu")
		(net "GND")
	)
	(via
		(at 343.394792 -346.09913)
		(size 0.4572)
		(drill 0.254)
		(layers "F.Cu" "B.Cu")
		(net "GND")
	)
	(via
		(at 293.829994 -343.073482)
		(size 0.4572)
		(drill 0.254)
		(layers "F.Cu" "B.Cu")
		(net "GND")
	)
	(via
		(at 270.474694 -273.574764)
		(size 0.4064)
		(drill 0.2032)
		(layers "F.Cu" "B.Cu")
		(net "GND")
	)
	(via
		(at 412.088584 -31.642304)
		(size 0.508)
		(drill 0.254)
		(layers "F.Cu" "B.Cu")
		(net "GND")
	)
	(via
		(at 134.18058 -148.718778)
		(size 0.508)
		(drill 0.254)
		(layers "F.Cu" "B.Cu")
		(net "GND")
	)
	(via
		(at 191.425068 -290.674806)
		(size 0.4064)
		(drill 0.2032)
		(layers "F.Cu" "B.Cu")
		(net "GND")
	)
	(via
		(at 439.815732 -357.75773)
		(size 0.4064)
		(drill 0.2032)
		(layers "F.Cu" "B.Cu")
		(net "GND")
	)
	(via
		(at 434.327808 -383.940304)
		(size 0.508)
		(drill 0.254)
		(layers "F.Cu" "B.Cu")
		(net "GND")
	)
	(via
		(at 117.547644 -407.24201)
		(size 0.4572)
		(drill 0.254)
		(layers "F.Cu" "B.Cu")
		(net "GND")
	)
	(via
		(at 156.232098 -13.613638)
		(size 0.508)
		(drill 0.254)
		(layers "F.Cu" "B.Cu")
		(net "GND")
	)
	(via
		(at 428.850044 -275.949918)
		(size 0.4064)
		(drill 0.2032)
		(layers "F.Cu" "B.Cu")
		(net "GND")
	)
	(via
		(at 410.52877 -209.39887)
		(size 0.508)
		(drill 0.254)
		(layers "F.Cu" "B.Cu")
		(net "GND")
	)
	(via
		(at 403.607016 -49.574704)
		(size 0.508)
		(drill 0.254)
		(layers "F.Cu" "B.Cu")
		(net "GND")
	)
	(via
		(at 298.647612 -142.15491)
		(size 0.508)
		(drill 0.254)
		(layers "F.Cu" "B.Cu")
		(net "GND")
	)
	(via
		(at 393.7 -276.899878)
		(size 0.4064)
		(drill 0.2032)
		(layers "F.Cu" "B.Cu")
		(net "GND")
	)
	(via
		(at 36.309808 -357.75773)
		(size 0.4064)
		(drill 0.2032)
		(layers "F.Cu" "B.Cu")
		(net "GND")
	)
	(via
		(at 268.958314 -346.09913)
		(size 0.4572)
		(drill 0.254)
		(layers "F.Cu" "B.Cu")
		(net "GND")
	)
	(via
		(at 400.824954 -303.974754)
		(size 0.4064)
		(drill 0.2032)
		(layers "F.Cu" "B.Cu")
		(net "GND")
	)
	(via
		(at 333.127858 -376.140218)
		(size 0.508)
		(drill 0.254)
		(layers "F.Cu" "B.Cu")
		(net "GND")
	)
	(via
		(at 139.645136 -347.951806)
		(size 0.4572)
		(drill 0.254)
		(layers "F.Cu" "B.Cu")
		(net "GND")
	)
	(via
		(at 344.653616 -350.977454)
		(size 0.4572)
		(drill 0.254)
		(layers "F.Cu" "B.Cu")
		(net "GND")
	)
	(via
		(at 193.0781 -341.781638)
		(size 0.4572)
		(drill 0.254)
		(layers "F.Cu" "B.Cu")
		(net "GND")
	)
	(via
		(at 36.849812 -311.099962)
		(size 0.4064)
		(drill 0.2032)
		(layers "F.Cu" "B.Cu")
		(net "GND")
	)
	(via
		(at 291.32784 -371.140228)
		(size 0.508)
		(drill 0.254)
		(layers "F.Cu" "B.Cu")
		(net "GND")
	)
	(via
		(at 197.600062 -305.399948)
		(size 0.4064)
		(drill 0.2032)
		(layers "F.Cu" "B.Cu")
		(net "GND")
	)
	(via
		(at 75.79995 -305.399948)
		(size 0.4064)
		(drill 0.2032)
		(layers "F.Cu" "B.Cu")
		(net "GND")
	)
	(via
		(at 363.45622 -127.021844)
		(size 0.508)
		(drill 0.254)
		(layers "F.Cu" "B.Cu")
		(net "GND")
	)
	(via
		(at 430.749964 -277.849838)
		(size 0.4064)
		(drill 0.2032)
		(layers "F.Cu" "B.Cu")
		(net "GND")
	)
	(via
		(at 277.599902 -303.499774)
		(size 0.4064)
		(drill 0.2032)
		(layers "F.Cu" "B.Cu")
		(net "GND")
	)
	(via
		(at 24.38654 -48.874934)
		(size 0.508)
		(drill 0.254)
		(layers "F.Cu" "B.Cu")
		(net "GND")
	)
	(via
		(at 140.208 -417.82492)
		(size 0.508)
		(drill 0.254)
		(layers "F.Cu" "B.Cu")
		(net "GND")
	)
	(via
		(at 237.642654 -308.892956)
		(size 0.508)
		(drill 0.254)
		(layers "F.Cu" "B.Cu")
		(net "GND")
	)
	(via
		(at 54.424834 -289.724846)
		(size 0.4064)
		(drill 0.2032)
		(layers "F.Cu" "B.Cu")
		(net "GND")
	)
	(via
		(at 124.147834 -406.141936)
		(size 0.4572)
		(drill 0.254)
		(layers "F.Cu" "B.Cu")
		(net "GND")
	)
	(via
		(at 426.012102 -23.355554)
		(size 0.508)
		(drill 0.254)
		(layers "F.Cu" "B.Cu")
		(net "GND")
	)
	(via
		(at 308.474872 -290.674806)
		(size 0.4064)
		(drill 0.2032)
		(layers "F.Cu" "B.Cu")
		(net "GND")
	)
	(via
		(at 339.728048 -397.140176)
		(size 0.508)
		(drill 0.254)
		(layers "F.Cu" "B.Cu")
		(net "GND")
	)
	(via
		(at 190.198502 -37.201094)
		(size 0.508)
		(drill 0.254)
		(layers "F.Cu" "B.Cu")
		(net "GND")
	)
	(via
		(at 166.381684 -354.098098)
		(size 0.4572)
		(drill 0.254)
		(layers "F.Cu" "B.Cu")
		(net "GND")
	)
	(via
		(at 165.947852 -407.24201)
		(size 0.508)
		(drill 0.254)
		(layers "F.Cu" "B.Cu")
		(net "GND")
	)
	(via
		(at 67.66687 -120.035066)
		(size 0.508)
		(drill 0.254)
		(layers "F.Cu" "B.Cu")
		(net "GND")
	)
	(via
		(at 378.145294 -50.516282)
		(size 0.508)
		(drill 0.254)
		(layers "F.Cu" "B.Cu")
		(net "GND")
	)
	(via
		(at 392.749786 -309.199788)
		(size 0.4064)
		(drill 0.2032)
		(layers "F.Cu" "B.Cu")
		(net "GND")
	)
	(via
		(at 196.174868 -303.974754)
		(size 0.4064)
		(drill 0.2032)
		(layers "F.Cu" "B.Cu")
		(net "GND")
	)
	(via
		(at 198.26605 -130.966718)
		(size 0.508)
		(drill 0.254)
		(layers "F.Cu" "B.Cu")
		(net "GND")
	)
	(via
		(at 410.727652 -345.465146)
		(size 0.4064)
		(drill 0.2032)
		(layers "F.Cu" "B.Cu")
		(net "GND")
	)
	(via
		(at 289.94989 -310.149748)
		(size 0.4064)
		(drill 0.2032)
		(layers "F.Cu" "B.Cu")
		(net "GND")
	)
	(via
		(at 414.599882 -276.899878)
		(size 0.4064)
		(drill 0.2032)
		(layers "F.Cu" "B.Cu")
		(net "GND")
	)
	(via
		(at 221.822772 -189.127638)
		(size 0.508)
		(drill 0.254)
		(layers "F.Cu" "B.Cu")
		(net "GND")
	)
	(via
		(at 112.446816 -134.89686)
		(size 0.508)
		(drill 0.254)
		(layers "F.Cu" "B.Cu")
		(net "GND")
	)
	(via
		(at 338.594446 -101.414072)
		(size 0.508)
		(drill 0.254)
		(layers "F.Cu" "B.Cu")
		(net "GND")
	)
	(via
		(at 66.774822 -307.774848)
		(size 0.4064)
		(drill 0.2032)
		(layers "F.Cu" "B.Cu")
		(net "GND")
	)
	(via
		(at 362.517182 -159.558482)
		(size 0.508)
		(drill 0.254)
		(layers "F.Cu" "B.Cu")
		(net "GND")
	)
	(via
		(at 298.10202 -57.461404)
		(size 0.508)
		(drill 0.254)
		(layers "F.Cu" "B.Cu")
		(net "GND")
	)
	(via
		(at 415.85007 -111.784892)
		(size 0.508)
		(drill 0.254)
		(layers "F.Cu" "B.Cu")
		(net "GND")
	)
	(via
		(at 120.620028 -345.465146)
		(size 0.4064)
		(drill 0.2032)
		(layers "F.Cu" "B.Cu")
		(net "GND")
	)
	(via
		(at 285.822898 -150.595838)
		(size 0.508)
		(drill 0.254)
		(layers "F.Cu" "B.Cu")
		(net "GND")
	)
	(via
		(at 52.999894 -313.949842)
		(size 0.4064)
		(drill 0.2032)
		(layers "F.Cu" "B.Cu")
		(net "GND")
	)
	(via
		(at 300.419262 -342.439498)
		(size 0.4064)
		(drill 0.2032)
		(layers "F.Cu" "B.Cu")
		(net "GND")
	)
	(via
		(at 7.192518 -6.292342)
		(size 0.508)
		(drill 0.254)
		(layers "F.Cu" "B.Cu")
		(net "GND")
	)
	(via
		(at 102.388162 -169.68724)
		(size 0.508)
		(drill 0.254)
		(layers "F.Cu" "B.Cu")
		(net "GND")
	)
	(via
		(at 287.574736 -285.924752)
		(size 0.4064)
		(drill 0.2032)
		(layers "F.Cu" "B.Cu")
		(net "GND")
	)
	(via
		(at 270.474948 -293.52494)
		(size 0.4064)
		(drill 0.2032)
		(layers "F.Cu" "B.Cu")
		(net "GND")
	)
	(via
		(at 168.150032 -280.699718)
		(size 0.4064)
		(drill 0.2032)
		(layers "F.Cu" "B.Cu")
		(net "GND")
	)
	(via
		(at 131.225544 -128.193546)
		(size 0.508)
		(drill 0.254)
		(layers "F.Cu" "B.Cu")
		(net "GND")
	)
	(via
		(at 116.143786 -286.842454)
		(size 0.508)
		(drill 0.254)
		(layers "F.Cu" "B.Cu")
		(net "GND")
	)
	(via
		(at 432.12766 -395.938502)
		(size 0.508)
		(drill 0.254)
		(layers "F.Cu" "B.Cu")
		(net "GND")
	)
	(via
		(at 440.18708 -358.391714)
		(size 0.4572)
		(drill 0.254)
		(layers "F.Cu" "B.Cu")
		(net "GND")
	)
	(via
		(at 254.451358 -47.03191)
		(size 0.508)
		(drill 0.254)
		(layers "F.Cu" "B.Cu")
		(net "GND")
	)
	(via
		(at 402.724874 -293.52494)
		(size 0.4064)
		(drill 0.2032)
		(layers "F.Cu" "B.Cu")
		(net "GND")
	)
	(via
		(at 90.414094 -349.219774)
		(size 0.4572)
		(drill 0.254)
		(layers "F.Cu" "B.Cu")
		(net "GND")
	)
	(via
		(at 166.075106 -74.58583)
		(size 0.508)
		(drill 0.254)
		(layers "F.Cu" "B.Cu")
		(net "GND")
	)
	(via
		(at 453.825102 -115.579906)
		(size 0.508)
		(drill 0.254)
		(layers "F.Cu" "B.Cu")
		(net "GND")
	)
	(via
		(at 30.787594 -308.65953)
		(size 0.508)
		(drill 0.254)
		(layers "F.Cu" "B.Cu")
		(net "GND")
	)
	(via
		(at 161.500058 -278.799798)
		(size 0.4064)
		(drill 0.2032)
		(layers "F.Cu" "B.Cu")
		(net "GND")
	)
	(via
		(at 174.800006 -313.949842)
		(size 0.4064)
		(drill 0.2032)
		(layers "F.Cu" "B.Cu")
		(net "GND")
	)
	(via
		(at 285.687262 -120.555004)
		(size 0.508)
		(drill 0.254)
		(layers "F.Cu" "B.Cu")
		(net "GND")
	)
	(via
		(at 425.901104 -349.219774)
		(size 0.4572)
		(drill 0.254)
		(layers "F.Cu" "B.Cu")
		(net "GND")
	)
	(via
		(at 124.147834 -404.940262)
		(size 0.4572)
		(drill 0.254)
		(layers "F.Cu" "B.Cu")
		(net "GND")
	)
	(via
		(at 280.591514 -100.64496)
		(size 0.508)
		(drill 0.254)
		(layers "F.Cu" "B.Cu")
		(net "GND")
	)
	(via
		(at 70.574916 -299.224954)
		(size 0.4064)
		(drill 0.2032)
		(layers "F.Cu" "B.Cu")
		(net "GND")
	)
	(via
		(at 427.727872 -372.341902)
		(size 0.508)
		(drill 0.254)
		(layers "F.Cu" "B.Cu")
		(net "GND")
	)
	(via
		(at 282.349702 -280.699718)
		(size 0.4064)
		(drill 0.2032)
		(layers "F.Cu" "B.Cu")
		(net "GND")
	)
	(via
		(at 396.54988 -281.649932)
		(size 0.4064)
		(drill 0.2032)
		(layers "F.Cu" "B.Cu")
		(net "GND")
	)
	(via
		(at 117.547644 -373.441976)
		(size 0.4572)
		(drill 0.254)
		(layers "F.Cu" "B.Cu")
		(net "GND")
	)
	(via
		(at 466.827616 -67.252596)
		(size 0.508)
		(drill 0.254)
		(layers "F.Cu" "B.Cu")
		(net "GND")
	)
	(via
		(at 58.224928 -300.174914)
		(size 0.4064)
		(drill 0.2032)
		(layers "F.Cu" "B.Cu")
		(net "GND")
	)
	(via
		(at 410.799788 -312.999882)
		(size 0.4064)
		(drill 0.2032)
		(layers "F.Cu" "B.Cu")
		(net "GND")
	)
	(via
		(at 74.248264 -136.645142)
		(size 0.508)
		(drill 0.254)
		(layers "F.Cu" "B.Cu")
		(net "GND")
	)
	(via
		(at 175.683164 -341.805514)
		(size 0.4572)
		(drill 0.254)
		(layers "F.Cu" "B.Cu")
		(net "GND")
	)
	(via
		(at 194.336924 -349.219774)
		(size 0.4572)
		(drill 0.254)
		(layers "F.Cu" "B.Cu")
		(net "GND")
	)
	(via
		(at 356.87 -166.624)
		(size 0.508)
		(drill 0.254)
		(layers "F.Cu" "B.Cu")
		(net "GND")
	)
	(via
		(at 90.942668 -112.399572)
		(size 0.508)
		(drill 0.254)
		(layers "F.Cu" "B.Cu")
		(net "GND")
	)
	(via
		(at 196.772022 -49.574704)
		(size 0.508)
		(drill 0.254)
		(layers "F.Cu" "B.Cu")
		(net "GND")
	)
	(via
		(at 198.26605 -123.356878)
		(size 0.508)
		(drill 0.254)
		(layers "F.Cu" "B.Cu")
		(net "GND")
	)
	(via
		(at 313.699906 -277.849838)
		(size 0.4064)
		(drill 0.2032)
		(layers "F.Cu" "B.Cu")
		(net "GND")
	)
	(via
		(at 155.325064 -293.52494)
		(size 0.4064)
		(drill 0.2032)
		(layers "F.Cu" "B.Cu")
		(net "GND")
	)
	(via
		(at 46.34992 -312.049922)
		(size 0.4064)
		(drill 0.2032)
		(layers "F.Cu" "B.Cu")
		(net "GND")
	)
	(via
		(at 390.849866 -304.449734)
		(size 0.4064)
		(drill 0.2032)
		(layers "F.Cu" "B.Cu")
		(net "GND")
	)
	(via
		(at 190.78956 -401.65909)
		(size 0.508)
		(drill 0.254)
		(layers "F.Cu" "B.Cu")
		(net "GND")
	)
	(via
		(at 430.488852 -351.611438)
		(size 0.4064)
		(drill 0.2032)
		(layers "F.Cu" "B.Cu")
		(net "GND")
	)
	(via
		(at 376.56389 -256.098548)
		(size 0.508)
		(drill 0.254)
		(layers "F.Cu" "B.Cu")
		(net "GND")
	)
	(via
		(at 390.327896 -377.341892)
		(size 0.508)
		(drill 0.254)
		(layers "F.Cu" "B.Cu")
		(net "GND")
	)
	(via
		(at 273.324828 -281.174952)
		(size 0.4064)
		(drill 0.2032)
		(layers "F.Cu" "B.Cu")
		(net "GND")
	)
	(via
		(at 54.424834 -302.074834)
		(size 0.4064)
		(drill 0.2032)
		(layers "F.Cu" "B.Cu")
		(net "GND")
	)
	(via
		(at 357.658162 -143.051276)
		(size 0.508)
		(drill 0.254)
		(layers "F.Cu" "B.Cu")
		(net "GND")
	)
	(via
		(at 17.561306 -60.099194)
		(size 0.508)
		(drill 0.254)
		(layers "F.Cu" "B.Cu")
		(net "GND")
	)
	(via
		(at 281.399742 -317.749936)
		(size 0.4064)
		(drill 0.2032)
		(layers "F.Cu" "B.Cu")
		(net "GND")
	)
	(via
		(at 286.906462 -124.154946)
		(size 0.508)
		(drill 0.254)
		(layers "F.Cu" "B.Cu")
		(net "GND")
	)
	(via
		(at 3.746754 -15.844774)
		(size 0.508)
		(drill 0.254)
		(layers "F.Cu" "B.Cu")
		(net "GND")
	)
	(via
		(at 47.601632 -145.372836)
		(size 0.508)
		(drill 0.254)
		(layers "F.Cu" "B.Cu")
		(net "GND")
	)
	(via
		(at 384.685032 -343.073482)
		(size 0.4572)
		(drill 0.254)
		(layers "F.Cu" "B.Cu")
		(net "GND")
	)
	(via
		(at 23.50262 -341.805514)
		(size 0.4572)
		(drill 0.254)
		(layers "F.Cu" "B.Cu")
		(net "GND")
	)
	(via
		(at 385.927854 -404.838662)
		(size 0.508)
		(drill 0.254)
		(layers "F.Cu" "B.Cu")
		(net "GND")
	)
	(via
		(at 441.094368 -124.47778)
		(size 0.508)
		(drill 0.254)
		(layers "F.Cu" "B.Cu")
		(net "GND")
	)
	(via
		(at 432.490372 -351.611438)
		(size 0.4064)
		(drill 0.2032)
		(layers "F.Cu" "B.Cu")
		(net "GND")
	)
	(via
		(at 441.297822 -295.355518)
		(size 0.508)
		(drill 0.254)
		(layers "F.Cu" "B.Cu")
		(net "GND")
	)
	(via
		(at 54.70652 -107.844844)
		(size 0.508)
		(drill 0.254)
		(layers "F.Cu" "B.Cu")
		(net "GND")
	)
	(via
		(at 51.854608 -357.75773)
		(size 0.4064)
		(drill 0.2032)
		(layers "F.Cu" "B.Cu")
		(net "GND")
	)
	(via
		(at 196.174868 -300.174914)
		(size 0.4064)
		(drill 0.2032)
		(layers "F.Cu" "B.Cu")
		(net "GND")
	)
	(via
		(at 232.651046 -143.094202)
		(size 0.508)
		(drill 0.254)
		(layers "F.Cu" "B.Cu")
		(net "GND")
	)
	(via
		(at 412.098236 -19.096736)
		(size 0.508)
		(drill 0.254)
		(layers "F.Cu" "B.Cu")
		(net "GND")
	)
	(via
		(at 231.067356 -221.103952)
		(size 0.4572)
		(drill 0.254)
		(layers "F.Cu" "B.Cu")
		(net "GND")
	)
	(via
		(at 124.147834 -380.141734)
		(size 0.4572)
		(drill 0.254)
		(layers "F.Cu" "B.Cu")
		(net "GND")
	)
	(via
		(at 191.900048 -288.299906)
		(size 0.4064)
		(drill 0.2032)
		(layers "F.Cu" "B.Cu")
		(net "GND")
	)
	(via
		(at 124.630434 -305.008534)
		(size 0.508)
		(drill 0.254)
		(layers "F.Cu" "B.Cu")
		(net "GND")
	)
	(via
		(at 82.449924 -280.699718)
		(size 0.4064)
		(drill 0.2032)
		(layers "F.Cu" "B.Cu")
		(net "GND")
	)
	(via
		(at 122.2502 -352.245422)
		(size 0.4572)
		(drill 0.254)
		(layers "F.Cu" "B.Cu")
		(net "GND")
	)
	(via
		(at 279.974802 -289.724846)
		(size 0.4064)
		(drill 0.2032)
		(layers "F.Cu" "B.Cu")
		(net "GND")
	)
	(via
		(at 40.547798 -406.141936)
		(size 0.508)
		(drill 0.254)
		(layers "F.Cu" "B.Cu")
		(net "GND")
	)
	(via
		(at 161.54781 -371.038628)
		(size 0.508)
		(drill 0.254)
		(layers "F.Cu" "B.Cu")
		(net "GND")
	)
	(via
		(at 432.12766 -381.638556)
		(size 0.508)
		(drill 0.254)
		(layers "F.Cu" "B.Cu")
		(net "GND")
	)
	(via
		(at 150.103078 -280.693114)
		(size 0.508)
		(drill 0.254)
		(layers "F.Cu" "B.Cu")
		(net "GND")
	)
	(via
		(at 225.256344 -185.363612)
		(size 0.508)
		(drill 0.254)
		(layers "F.Cu" "B.Cu")
		(net "GND")
	)
	(via
		(at 423.163492 -342.439498)
		(size 0.4064)
		(drill 0.2032)
		(layers "F.Cu" "B.Cu")
		(net "GND")
	)
	(via
		(at 378.927106 -256.375916)
		(size 0.508)
		(drill 0.254)
		(layers "F.Cu" "B.Cu")
		(net "GND")
	)
	(via
		(at 225.861626 -108.445808)
		(size 0.508)
		(drill 0.254)
		(layers "F.Cu" "B.Cu")
		(net "GND")
	)
	(via
		(at 308.949852 -304.449734)
		(size 0.4064)
		(drill 0.2032)
		(layers "F.Cu" "B.Cu")
		(net "GND")
	)
	(via
		(at 138.351514 -45.865288)
		(size 0.508)
		(drill 0.254)
		(layers "F.Cu" "B.Cu")
		(net "GND")
	)
	(via
		(at 73.547732 -385.141978)
		(size 0.508)
		(drill 0.254)
		(layers "F.Cu" "B.Cu")
		(net "GND")
	)
	(via
		(at 172.900086 -312.999882)
		(size 0.4064)
		(drill 0.2032)
		(layers "F.Cu" "B.Cu")
		(net "GND")
	)
	(via
		(at 325.276464 -119.936006)
		(size 0.508)
		(drill 0.254)
		(layers "F.Cu" "B.Cu")
		(net "GND")
	)
	(via
		(at 197.125082 -303.024794)
		(size 0.4064)
		(drill 0.2032)
		(layers "F.Cu" "B.Cu")
		(net "GND")
	)
	(via
		(at 47.115476 -344.831162)
		(size 0.4572)
		(drill 0.254)
		(layers "F.Cu" "B.Cu")
		(net "GND")
	)
	(via
		(at 130.74777 -411.141926)
		(size 0.4572)
		(drill 0.254)
		(layers "F.Cu" "B.Cu")
		(net "GND")
	)
	(via
		(at 387.355588 -243.16436)
		(size 0.508)
		(drill 0.254)
		(layers "F.Cu" "B.Cu")
		(net "GND")
	)
	(via
		(at 150.59152 -111.72317)
		(size 0.508)
		(drill 0.254)
		(layers "F.Cu" "B.Cu")
		(net "GND")
	)
	(via
		(at 65.81267 -131.245102)
		(size 0.508)
		(drill 0.254)
		(layers "F.Cu" "B.Cu")
		(net "GND")
	)
	(via
		(at 346.438982 -286.842454)
		(size 0.508)
		(drill 0.254)
		(layers "F.Cu" "B.Cu")
		(net "GND")
	)
	(via
		(at 285.674816 -307.774848)
		(size 0.4064)
		(drill 0.2032)
		(layers "F.Cu" "B.Cu")
		(net "GND")
	)
	(via
		(at 38.749986 -315.849762)
		(size 0.4064)
		(drill 0.2032)
		(layers "F.Cu" "B.Cu")
		(net "GND")
	)
	(via
		(at 287.099756 -312.999882)
		(size 0.4064)
		(drill 0.2032)
		(layers "F.Cu" "B.Cu")
		(net "GND")
	)
	(via
		(at 359.535476 -288.14649)
		(size 0.508)
		(drill 0.254)
		(layers "F.Cu" "B.Cu")
		(net "GND")
	)
	(via
		(at 126.018544 -304.373534)
		(size 0.508)
		(drill 0.254)
		(layers "F.Cu" "B.Cu")
		(net "GND")
	)
	(via
		(at 295.727882 -375.040144)
		(size 0.508)
		(drill 0.254)
		(layers "F.Cu" "B.Cu")
		(net "GND")
	)
	(via
		(at 296.599864 -317.749936)
		(size 0.4064)
		(drill 0.2032)
		(layers "F.Cu" "B.Cu")
		(net "GND")
	)
	(via
		(at 272.374868 -274.524978)
		(size 0.4064)
		(drill 0.2032)
		(layers "F.Cu" "B.Cu")
		(net "GND")
	)
	(via
		(at 61.549788 -280.699718)
		(size 0.4064)
		(drill 0.2032)
		(layers "F.Cu" "B.Cu")
		(net "GND")
	)
	(via
		(at 289.46221 -357.123746)
		(size 0.4572)
		(drill 0.254)
		(layers "F.Cu" "B.Cu")
		(net "GND")
	)
	(via
		(at 127.17907 -179.203096)
		(size 0.508)
		(drill 0.254)
		(layers "F.Cu" "B.Cu")
		(net "GND")
	)
	(via
		(at 167.732964 -151.159972)
		(size 0.508)
		(drill 0.254)
		(layers "F.Cu" "B.Cu")
		(net "GND")
	)
	(via
		(at 321.201542 -303.026826)
		(size 0.508)
		(drill 0.254)
		(layers "F.Cu" "B.Cu")
		(net "GND")
	)
	(via
		(at 53.474874 -294.4749)
		(size 0.4064)
		(drill 0.2032)
		(layers "F.Cu" "B.Cu")
		(net "GND")
	)
	(via
		(at 45.26534 -347.951806)
		(size 0.4572)
		(drill 0.254)
		(layers "F.Cu" "B.Cu")
		(net "GND")
	)
	(via
		(at 169.099992 -317.749936)
		(size 0.4064)
		(drill 0.2032)
		(layers "F.Cu" "B.Cu")
		(net "GND")
	)
	(via
		(at 384.674872 -287.824926)
		(size 0.4064)
		(drill 0.2032)
		(layers "F.Cu" "B.Cu")
		(net "GND")
	)
	(via
		(at 73.239122 -354.732082)
		(size 0.4064)
		(drill 0.2032)
		(layers "F.Cu" "B.Cu")
		(net "GND")
	)
	(via
		(at 57.749948 -310.149748)
		(size 0.4064)
		(drill 0.2032)
		(layers "F.Cu" "B.Cu")
		(net "GND")
	)
	(via
		(at 283.949902 -145.520156)
		(size 0.508)
		(drill 0.254)
		(layers "F.Cu" "B.Cu")
		(net "GND")
	)
	(via
		(at 356.676706 -393.12977)
		(size 0.508)
		(drill 0.254)
		(layers "F.Cu" "B.Cu")
		(net "GND")
	)
	(via
		(at 48.3743 -346.09913)
		(size 0.4572)
		(drill 0.254)
		(layers "F.Cu" "B.Cu")
		(net "GND")
	)
	(via
		(at 123.728988 -357.75773)
		(size 0.4064)
		(drill 0.2032)
		(layers "F.Cu" "B.Cu")
		(net "GND")
	)
	(via
		(at 268.574774 -277.374858)
		(size 0.4064)
		(drill 0.2032)
		(layers "F.Cu" "B.Cu")
		(net "GND")
	)
	(via
		(at 61.078364 -381.979678)
		(size 0.508)
		(drill 0.254)
		(layers "F.Cu" "B.Cu")
		(net "GND")
	)
	(via
		(at 293.74973 -315.849762)
		(size 0.4064)
		(drill 0.2032)
		(layers "F.Cu" "B.Cu")
		(net "GND")
	)
	(via
		(at 159.124904 -289.724846)
		(size 0.4064)
		(drill 0.2032)
		(layers "F.Cu" "B.Cu")
		(net "GND")
	)
	(via
		(at 362.514896 -26.171398)
		(size 0.508)
		(drill 0.254)
		(layers "F.Cu" "B.Cu")
		(net "GND")
	)
	(via
		(at 177.649632 -272.14957)
		(size 0.4064)
		(drill 0.2032)
		(layers "F.Cu" "B.Cu")
		(net "GND")
	)
	(via
		(at 95.529146 -115.394486)
		(size 0.508)
		(drill 0.254)
		(layers "F.Cu" "B.Cu")
		(net "GND")
	)
	(via
		(at 284.724856 -284.024832)
		(size 0.4064)
		(drill 0.2032)
		(layers "F.Cu" "B.Cu")
		(net "GND")
	)
	(via
		(at 101.339904 -74.58583)
		(size 0.508)
		(drill 0.254)
		(layers "F.Cu" "B.Cu")
		(net "GND")
	)
	(via
		(at 418.927788 -397.140176)
		(size 0.508)
		(drill 0.254)
		(layers "F.Cu" "B.Cu")
		(net "GND")
	)
	(via
		(at 442.778896 -284.23997)
		(size 0.508)
		(drill 0.254)
		(layers "F.Cu" "B.Cu")
		(net "GND")
	)
	(via
		(at 415.549842 -281.649932)
		(size 0.4064)
		(drill 0.2032)
		(layers "F.Cu" "B.Cu")
		(net "GND")
	)
	(via
		(at 182.547514 -131.245102)
		(size 0.508)
		(drill 0.254)
		(layers "F.Cu" "B.Cu")
		(net "GND")
	)
	(via
		(at 344.23477 -154.313128)
		(size 0.508)
		(drill 0.254)
		(layers "F.Cu" "B.Cu")
		(net "GND")
	)
	(via
		(at 82.166206 -123.356878)
		(size 0.508)
		(drill 0.254)
		(layers "F.Cu" "B.Cu")
		(net "GND")
	)
	(via
		(at 425.901104 -358.391714)
		(size 0.4572)
		(drill 0.254)
		(layers "F.Cu" "B.Cu")
		(net "GND")
	)
	(via
		(at 333.127858 -402.140166)
		(size 0.508)
		(drill 0.254)
		(layers "F.Cu" "B.Cu")
		(net "GND")
	)
	(via
		(at 165.947852 -406.040336)
		(size 0.508)
		(drill 0.254)
		(layers "F.Cu" "B.Cu")
		(net "GND")
	)
	(via
		(at 313.564016 -352.245422)
		(size 0.4572)
		(drill 0.254)
		(layers "F.Cu" "B.Cu")
		(net "GND")
	)
	(via
		(at 257.912108 -23.355554)
		(size 0.508)
		(drill 0.254)
		(layers "F.Cu" "B.Cu")
		(net "GND")
	)
	(via
		(at 170.944032 -342.439498)
		(size 0.4064)
		(drill 0.2032)
		(layers "F.Cu" "B.Cu")
		(net "GND")
	)
	(via
		(at 400.349974 -281.649932)
		(size 0.4064)
		(drill 0.2032)
		(layers "F.Cu" "B.Cu")
		(net "GND")
	)
	(via
		(at 408.755088 -29.590238)
		(size 0.508)
		(drill 0.254)
		(layers "F.Cu" "B.Cu")
		(net "GND")
	)
	(via
		(at 122.2502 -350.977454)
		(size 0.4572)
		(drill 0.254)
		(layers "F.Cu" "B.Cu")
		(net "GND")
	)
	(via
		(at 315.849762 -27.04973)
		(size 0.508)
		(drill 0.254)
		(layers "F.Cu" "B.Cu")
		(net "GND")
	)
	(via
		(at 249.896122 -162.25647)
		(size 0.508)
		(drill 0.254)
		(layers "F.Cu" "B.Cu")
		(net "GND")
	)
	(via
		(at 16.858234 -122.462036)
		(size 0.508)
		(drill 0.254)
		(layers "F.Cu" "B.Cu")
		(net "GND")
	)
	(via
		(at 388.127748 -373.83847)
		(size 0.508)
		(drill 0.254)
		(layers "F.Cu" "B.Cu")
		(net "GND")
	)
	(via
		(at 267.394944 -60.633356)
		(size 0.508)
		(drill 0.254)
		(layers "F.Cu" "B.Cu")
		(net "GND")
	)
	(via
		(at 392.274806 -294.4749)
		(size 0.4064)
		(drill 0.2032)
		(layers "F.Cu" "B.Cu")
		(net "GND")
	)
	(via
		(at 165.774878 -292.574726)
		(size 0.4064)
		(drill 0.2032)
		(layers "F.Cu" "B.Cu")
		(net "GND")
	)
	(via
		(at 411.275022 -305.874928)
		(size 0.4064)
		(drill 0.2032)
		(layers "F.Cu" "B.Cu")
		(net "GND")
	)
	(via
		(at 327.849992 -358.391714)
		(size 0.4572)
		(drill 0.254)
		(layers "F.Cu" "B.Cu")
		(net "GND")
	)
	(via
		(at 37.798248 -19.096736)
		(size 0.508)
		(drill 0.254)
		(layers "F.Cu" "B.Cu")
		(net "GND")
	)
	(via
		(at 432.12766 -376.241818)
		(size 0.508)
		(drill 0.254)
		(layers "F.Cu" "B.Cu")
		(net "GND")
	)
	(via
		(at 37.324792 -273.574764)
		(size 0.4064)
		(drill 0.2032)
		(layers "F.Cu" "B.Cu")
		(net "GND")
	)
	(via
		(at 124.100336 -341.805514)
		(size 0.4572)
		(drill 0.254)
		(layers "F.Cu" "B.Cu")
		(net "GND")
	)
	(via
		(at 299.866812 -154.755088)
		(size 0.508)
		(drill 0.254)
		(layers "F.Cu" "B.Cu")
		(net "GND")
	)
	(via
		(at 122.70105 -29.590238)
		(size 0.508)
		(drill 0.254)
		(layers "F.Cu" "B.Cu")
		(net "GND")
	)
	(via
		(at 50.624994 -284.024832)
		(size 0.4064)
		(drill 0.2032)
		(layers "F.Cu" "B.Cu")
		(net "GND")
	)
	(via
		(at 353.141788 -270.001492)
		(size 0.508)
		(drill 0.254)
		(layers "F.Cu" "B.Cu")
		(net "GND")
	)
	(via
		(at 18.73123 -6.292342)
		(size 0.508)
		(drill 0.254)
		(layers "F.Cu" "B.Cu")
		(net "GND")
	)
	(via
		(at 378.83846 -348.58579)
		(size 0.4064)
		(drill 0.2032)
		(layers "F.Cu" "B.Cu")
		(net "GND")
	)
	(via
		(at 128.547622 -401.040092)
		(size 0.4572)
		(drill 0.254)
		(layers "F.Cu" "B.Cu")
		(net "GND")
	)
	(via
		(at 108.021882 -348.985332)
		(size 0.508)
		(drill 0.254)
		(layers "F.Cu" "B.Cu")
		(net "GND")
	)
	(via
		(at 110.676182 -288.78149)
		(size 0.508)
		(drill 0.254)
		(layers "F.Cu" "B.Cu")
		(net "GND")
	)
	(via
		(at 316.800738 -31.390336)
		(size 0.508)
		(drill 0.254)
		(layers "F.Cu" "B.Cu")
		(net "GND")
	)
	(via
		(at 288.04997 -319.65011)
		(size 0.4064)
		(drill 0.2032)
		(layers "F.Cu" "B.Cu")
		(net "GND")
	)
	(via
		(at 69.149976 -319.65011)
		(size 0.4064)
		(drill 0.2032)
		(layers "F.Cu" "B.Cu")
		(net "GND")
	)
	(via
		(at 350.97212 -49.574704)
		(size 0.508)
		(drill 0.254)
		(layers "F.Cu" "B.Cu")
		(net "GND")
	)
	(via
		(at 156.750004 -314.899802)
		(size 0.4064)
		(drill 0.2032)
		(layers "F.Cu" "B.Cu")
		(net "GND")
	)
	(via
		(at 221.59976 -311.806082)
		(size 0.508)
		(drill 0.254)
		(layers "F.Cu" "B.Cu")
		(net "GND")
	)
	(via
		(at 400.349974 -319.65011)
		(size 0.4064)
		(drill 0.2032)
		(layers "F.Cu" "B.Cu")
		(net "GND")
	)
	(via
		(at 57.749948 -276.899878)
		(size 0.4064)
		(drill 0.2032)
		(layers "F.Cu" "B.Cu")
		(net "GND")
	)
	(via
		(at 65.913762 -351.611438)
		(size 0.4064)
		(drill 0.2032)
		(layers "F.Cu" "B.Cu")
		(net "GND")
	)
	(via
		(at 309.899812 -310.149748)
		(size 0.4064)
		(drill 0.2032)
		(layers "F.Cu" "B.Cu")
		(net "GND")
	)
	(via
		(at 60.599828 -314.899802)
		(size 0.4064)
		(drill 0.2032)
		(layers "F.Cu" "B.Cu")
		(net "GND")
	)
	(via
		(at 422.199816 -286.399732)
		(size 0.4064)
		(drill 0.2032)
		(layers "F.Cu" "B.Cu")
		(net "GND")
	)
	(via
		(at 199.500236 -279.750012)
		(size 0.4064)
		(drill 0.2032)
		(layers "F.Cu" "B.Cu")
		(net "GND")
	)
	(via
		(at 332.589124 -354.732082)
		(size 0.4064)
		(drill 0.2032)
		(layers "F.Cu" "B.Cu")
		(net "GND")
	)
	(via
		(at 297.927776 -398.24025)
		(size 0.508)
		(drill 0.254)
		(layers "F.Cu" "B.Cu")
		(net "GND")
	)
	(via
		(at 190.949834 -284.499812)
		(size 0.4064)
		(drill 0.2032)
		(layers "F.Cu" "B.Cu")
		(net "GND")
	)
	(via
		(at 387.525006 -293.52494)
		(size 0.4064)
		(drill 0.2032)
		(layers "F.Cu" "B.Cu")
		(net "GND")
	)
	(via
		(at 333.127858 -400.938492)
		(size 0.508)
		(drill 0.254)
		(layers "F.Cu" "B.Cu")
		(net "GND")
	)
	(via
		(at 419.82009 -56.441848)
		(size 0.508)
		(drill 0.254)
		(layers "F.Cu" "B.Cu")
		(net "GND")
	)
	(via
		(at 16.280892 -33.19018)
		(size 0.508)
		(drill 0.254)
		(layers "F.Cu" "B.Cu")
		(net "GND")
	)
	(via
		(at 284.249876 -315.849762)
		(size 0.4064)
		(drill 0.2032)
		(layers "F.Cu" "B.Cu")
		(net "GND")
	)
	(via
		(at 55.374794 -307.774848)
		(size 0.4064)
		(drill 0.2032)
		(layers "F.Cu" "B.Cu")
		(net "GND")
	)
	(via
		(at 284.249876 -316.799722)
		(size 0.4064)
		(drill 0.2032)
		(layers "F.Cu" "B.Cu")
		(net "GND")
	)
	(via
		(at 256.707386 -398.467834)
		(size 0.508)
		(drill 0.254)
		(layers "F.Cu" "B.Cu")
		(net "GND")
	)
	(via
		(at 309.899812 -308.249828)
		(size 0.4064)
		(drill 0.2032)
		(layers "F.Cu" "B.Cu")
		(net "GND")
	)
	(via
		(at 83.400138 -274.999958)
		(size 0.4064)
		(drill 0.2032)
		(layers "F.Cu" "B.Cu")
		(net "GND")
	)
	(via
		(at 274.757896 -56.809894)
		(size 0.508)
		(drill 0.254)
		(layers "F.Cu" "B.Cu")
		(net "GND")
	)
	(via
		(at 261.811262 -185.982102)
		(size 0.508)
		(drill 0.254)
		(layers "F.Cu" "B.Cu")
		(net "GND")
	)
	(via
		(at 163.874958 -297.32478)
		(size 0.4064)
		(drill 0.2032)
		(layers "F.Cu" "B.Cu")
		(net "GND")
	)
	(via
		(at 429.198278 -150.876762)
		(size 0.508)
		(drill 0.254)
		(layers "F.Cu" "B.Cu")
		(net "GND")
	)
	(via
		(at 75.74788 -397.140176)
		(size 0.508)
		(drill 0.254)
		(layers "F.Cu" "B.Cu")
		(net "GND")
	)
	(via
		(at 249.761248 -60.099194)
		(size 0.508)
		(drill 0.254)
		(layers "F.Cu" "B.Cu")
		(net "GND")
	)
	(via
		(at 128.667764 -255.210564)
		(size 0.508)
		(drill 0.254)
		(layers "F.Cu" "B.Cu")
		(net "GND")
	)
	(via
		(at 128.547622 -373.83847)
		(size 0.508)
		(drill 0.254)
		(layers "F.Cu" "B.Cu")
		(net "GND")
	)
	(via
		(at 36.14801 -408.840178)
		(size 0.508)
		(drill 0.254)
		(layers "F.Cu" "B.Cu")
		(net "GND")
	)
	(via
		(at 407.416 -385.064)
		(size 0.508)
		(drill 0.254)
		(layers "F.Cu" "B.Cu")
		(net "GND")
	)
	(via
		(at 297.074844 -306.824888)
		(size 0.4064)
		(drill 0.2032)
		(layers "F.Cu" "B.Cu")
		(net "GND")
	)
	(via
		(at 327.849992 -354.098098)
		(size 0.4572)
		(drill 0.254)
		(layers "F.Cu" "B.Cu")
		(net "GND")
	)
	(via
		(at 120.941592 -270.001492)
		(size 0.508)
		(drill 0.254)
		(layers "F.Cu" "B.Cu")
		(net "GND")
	)
	(via
		(at 87.648796 -27.79014)
		(size 0.508)
		(drill 0.254)
		(layers "F.Cu" "B.Cu")
		(net "GND")
	)
	(via
		(at 188.490352 -345.465146)
		(size 0.4064)
		(drill 0.2032)
		(layers "F.Cu" "B.Cu")
		(net "GND")
	)
	(via
		(at 303.724818 -293.52494)
		(size 0.4064)
		(drill 0.2032)
		(layers "F.Cu" "B.Cu")
		(net "GND")
	)
	(via
		(at 312.749692 -285.449772)
		(size 0.4064)
		(drill 0.2032)
		(layers "F.Cu" "B.Cu")
		(net "GND")
	)
	(via
		(at 99.05619 -357.063548)
		(size 0.508)
		(drill 0.254)
		(layers "F.Cu" "B.Cu")
		(net "GND")
	)
	(via
		(at 294.69969 -310.149748)
		(size 0.4064)
		(drill 0.2032)
		(layers "F.Cu" "B.Cu")
		(net "GND")
	)
	(via
		(at 153.233628 -103.975408)
		(size 0.508)
		(drill 0.254)
		(layers "F.Cu" "B.Cu")
		(net "GND")
	)
	(via
		(at 145.371566 -51.661822)
		(size 0.508)
		(drill 0.254)
		(layers "F.Cu" "B.Cu")
		(net "GND")
	)
	(via
		(at 300.399704 -274.049744)
		(size 0.4064)
		(drill 0.2032)
		(layers "F.Cu" "B.Cu")
		(net "GND")
	)
	(via
		(at 261.50697 -49.574704)
		(size 0.508)
		(drill 0.254)
		(layers "F.Cu" "B.Cu")
		(net "GND")
	)
	(via
		(at 414.11271 -149.355302)
		(size 0.508)
		(drill 0.254)
		(layers "F.Cu" "B.Cu")
		(net "GND")
	)
	(via
		(at 270.949928 -311.099962)
		(size 0.4064)
		(drill 0.2032)
		(layers "F.Cu" "B.Cu")
		(net "GND")
	)
	(via
		(at 248.480834 -31.390082)
		(size 0.508)
		(drill 0.254)
		(layers "F.Cu" "B.Cu")
		(net "GND")
	)
	(via
		(at 424.57497 -298.27474)
		(size 0.4064)
		(drill 0.2032)
		(layers "F.Cu" "B.Cu")
		(net "GND")
	)
	(via
		(at 89.83218 -124.743972)
		(size 0.508)
		(drill 0.254)
		(layers "F.Cu" "B.Cu")
		(net "GND")
	)
	(via
		(at 116.674646 -169.676064)
		(size 0.508)
		(drill 0.254)
		(layers "F.Cu" "B.Cu")
		(net "GND")
	)
	(via
		(at 180.693314 -151.155146)
		(size 0.508)
		(drill 0.254)
		(layers "F.Cu" "B.Cu")
		(net "GND")
	)
	(via
		(at 165.774878 -290.674806)
		(size 0.4064)
		(drill 0.2032)
		(layers "F.Cu" "B.Cu")
		(net "GND")
	)
	(via
		(at 72.949816 -319.65011)
		(size 0.4064)
		(drill 0.2032)
		(layers "F.Cu" "B.Cu")
		(net "GND")
	)
	(via
		(at 7.103364 -60.627006)
		(size 0.508)
		(drill 0.254)
		(layers "F.Cu" "B.Cu")
		(net "GND")
	)
	(via
		(at 385.405376 -229.407466)
		(size 0.508)
		(drill 0.254)
		(layers "F.Cu" "B.Cu")
		(net "GND")
	)
	(via
		(at 403.199854 -282.599892)
		(size 0.4064)
		(drill 0.2032)
		(layers "F.Cu" "B.Cu")
		(net "GND")
	)
	(via
		(at 288.524696 -300.174914)
		(size 0.4064)
		(drill 0.2032)
		(layers "F.Cu" "B.Cu")
		(net "GND")
	)
	(via
		(at 325.999856 -352.245422)
		(size 0.4572)
		(drill 0.254)
		(layers "F.Cu" "B.Cu")
		(net "GND")
	)
	(via
		(at 304.199798 -281.649932)
		(size 0.4064)
		(drill 0.2032)
		(layers "F.Cu" "B.Cu")
		(net "GND")
	)
	(via
		(at 406.524968 -284.974792)
		(size 0.4064)
		(drill 0.2032)
		(layers "F.Cu" "B.Cu")
		(net "GND")
	)
	(via
		(at 295.174924 -284.974792)
		(size 0.4064)
		(drill 0.2032)
		(layers "F.Cu" "B.Cu")
		(net "GND")
	)
	(via
		(at 391.799826 -317.749936)
		(size 0.4064)
		(drill 0.2032)
		(layers "F.Cu" "B.Cu")
		(net "GND")
	)
	(via
		(at 57.750202 -319.65011)
		(size 0.4064)
		(drill 0.2032)
		(layers "F.Cu" "B.Cu")
		(net "GND")
	)
	(via
		(at 0.766318 -62.172342)
		(size 0.508)
		(drill 0.254)
		(layers "F.Cu" "B.Cu")
		(net "GND")
	)
	(via
		(at 53.474874 -284.974792)
		(size 0.4064)
		(drill 0.2032)
		(layers "F.Cu" "B.Cu")
		(net "GND")
	)
	(via
		(at 43.499786 -309.199788)
		(size 0.4064)
		(drill 0.2032)
		(layers "F.Cu" "B.Cu")
		(net "GND")
	)
	(via
		(at 64.874902 -305.874928)
		(size 0.4064)
		(drill 0.2032)
		(layers "F.Cu" "B.Cu")
		(net "GND")
	)
	(via
		(at 301.903892 -99.187)
		(size 0.508)
		(drill 0.254)
		(layers "F.Cu" "B.Cu")
		(net "GND")
	)
	(via
		(at 339.04809 -284.333188)
		(size 0.49022)
		(drill 0.254)
		(layers "F.Cu" "B.Cu")
		(net "GND")
	)
	(via
		(at 163.13277 -100.64496)
		(size 0.508)
		(drill 0.254)
		(layers "F.Cu" "B.Cu")
		(net "GND")
	)
	(via
		(at 272.438622 -348.58579)
		(size 0.4064)
		(drill 0.2032)
		(layers "F.Cu" "B.Cu")
		(net "GND")
	)
	(via
		(at 105.012998 -350.452944)
		(size 0.508)
		(drill 0.254)
		(layers "F.Cu" "B.Cu")
		(net "GND")
	)
	(via
		(at 186.200034 -274.049744)
		(size 0.4064)
		(drill 0.2032)
		(layers "F.Cu" "B.Cu")
		(net "GND")
	)
	(via
		(at 288.049716 -315.849762)
		(size 0.4064)
		(drill 0.2032)
		(layers "F.Cu" "B.Cu")
		(net "GND")
	)
	(via
		(at 172.424852 -302.074834)
		(size 0.4064)
		(drill 0.2032)
		(layers "F.Cu" "B.Cu")
		(net "GND")
	)
	(via
		(at 161.358072 -73.85177)
		(size 0.508)
		(drill 0.254)
		(layers "F.Cu" "B.Cu")
		(net "GND")
	)
	(via
		(at 96.78543 -256.398776)
		(size 0.508)
		(drill 0.254)
		(layers "F.Cu" "B.Cu")
		(net "GND")
	)
	(via
		(at 27.769566 -64.102234)
		(size 0.508)
		(drill 0.254)
		(layers "F.Cu" "B.Cu")
		(net "GND")
	)
	(via
		(at 387.682994 -34.990024)
		(size 0.508)
		(drill 0.254)
		(layers "F.Cu" "B.Cu")
		(net "GND")
	)
	(via
		(at 178.599846 -312.999882)
		(size 0.4064)
		(drill 0.2032)
		(layers "F.Cu" "B.Cu")
		(net "GND")
	)
	(via
		(at 81.087214 -349.219774)
		(size 0.4572)
		(drill 0.254)
		(layers "F.Cu" "B.Cu")
		(net "GND")
	)
	(via
		(at 250.782074 -58.873644)
		(size 0.508)
		(drill 0.254)
		(layers "F.Cu" "B.Cu")
		(net "GND")
	)
	(via
		(at 77.978254 -341.805514)
		(size 0.4572)
		(drill 0.254)
		(layers "F.Cu" "B.Cu")
		(net "GND")
	)
	(via
		(at 403.674834 -305.874928)
		(size 0.4064)
		(drill 0.2032)
		(layers "F.Cu" "B.Cu")
		(net "GND")
	)
	(via
		(at 314.649866 -312.999882)
		(size 0.4064)
		(drill 0.2032)
		(layers "F.Cu" "B.Cu")
		(net "GND")
	)
	(via
		(at 244.859048 -138.89482)
		(size 0.508)
		(drill 0.254)
		(layers "F.Cu" "B.Cu")
		(net "GND")
	)
	(via
		(at 2.042668 -386.638546)
		(size 0.508)
		(drill 0.254)
		(layers "F.Cu" "B.Cu")
		(net "GND")
	)
	(via
		(at 119.809768 -290.05149)
		(size 0.508)
		(drill 0.254)
		(layers "F.Cu" "B.Cu")
		(net "GND")
	)
	(via
		(at 148.570442 -253.45644)
		(size 0.508)
		(drill 0.254)
		(layers "F.Cu" "B.Cu")
		(net "GND")
	)
	(via
		(at 317.008256 -131.514596)
		(size 0.508)
		(drill 0.254)
		(layers "F.Cu" "B.Cu")
		(net "GND")
	)
	(via
		(at 125.730508 -357.75773)
		(size 0.4064)
		(drill 0.2032)
		(layers "F.Cu" "B.Cu")
		(net "GND")
	)
	(via
		(at 226.247452 -333.027528)
		(size 0.508)
		(drill 0.254)
		(layers "F.Cu" "B.Cu")
		(net "GND")
	)
	(via
		(at 70.130162 -348.58579)
		(size 0.4064)
		(drill 0.2032)
		(layers "F.Cu" "B.Cu")
		(net "GND")
	)
	(via
		(at 90.938096 -231.66959)
		(size 0.508)
		(drill 0.254)
		(layers "F.Cu" "B.Cu")
		(net "GND")
	)
	(via
		(at 45.39996 -273.099784)
		(size 0.4064)
		(drill 0.2032)
		(layers "F.Cu" "B.Cu")
		(net "GND")
	)
	(via
		(at 31.747968 -406.141936)
		(size 0.508)
		(drill 0.254)
		(layers "F.Cu" "B.Cu")
		(net "GND")
	)
	(via
		(at 156.348938 -27.79014)
		(size 0.508)
		(drill 0.254)
		(layers "F.Cu" "B.Cu")
		(net "GND")
	)
	(via
		(at 298.974764 -289.724846)
		(size 0.4064)
		(drill 0.2032)
		(layers "F.Cu" "B.Cu")
		(net "GND")
	)
	(via
		(at 31.747968 -403.738588)
		(size 0.508)
		(drill 0.254)
		(layers "F.Cu" "B.Cu")
		(net "GND")
	)
	(via
		(at 78.349602 -351.611438)
		(size 0.4064)
		(drill 0.2032)
		(layers "F.Cu" "B.Cu")
		(net "GND")
	)
	(via
		(at 403.71014 -351.611438)
		(size 0.4064)
		(drill 0.2032)
		(layers "F.Cu" "B.Cu")
		(net "GND")
	)
	(via
		(at 177.649886 -280.699718)
		(size 0.4064)
		(drill 0.2032)
		(layers "F.Cu" "B.Cu")
		(net "GND")
	)
	(via
		(at 386.747004 -23.583646)
		(size 0.508)
		(drill 0.254)
		(layers "F.Cu" "B.Cu")
		(net "GND")
	)
	(via
		(at 91.892882 -348.58579)
		(size 0.4064)
		(drill 0.2032)
		(layers "F.Cu" "B.Cu")
		(net "GND")
	)
	(via
		(at 53.323236 -54.067456)
		(size 0.508)
		(drill 0.254)
		(layers "F.Cu" "B.Cu")
		(net "GND")
	)
	(via
		(at 388.474966 -284.974792)
		(size 0.4064)
		(drill 0.2032)
		(layers "F.Cu" "B.Cu")
		(net "GND")
	)
	(via
		(at 425.04995 -280.699718)
		(size 0.4064)
		(drill 0.2032)
		(layers "F.Cu" "B.Cu")
		(net "GND")
	)
	(via
		(at 312.749692 -308.249828)
		(size 0.4064)
		(drill 0.2032)
		(layers "F.Cu" "B.Cu")
		(net "GND")
	)
	(via
		(at 413.37357 -192.910206)
		(size 0.508)
		(drill 0.254)
		(layers "F.Cu" "B.Cu")
		(net "GND")
	)
	(via
		(at 363.09808 -286.842454)
		(size 0.508)
		(drill 0.254)
		(layers "F.Cu" "B.Cu")
		(net "GND")
	)
	(via
		(at 333.694024 -210.787234)
		(size 0.4572)
		(drill 0.254)
		(layers "F.Cu" "B.Cu")
		(net "GND")
	)
	(via
		(at 162.819334 -46.893226)
		(size 0.508)
		(drill 0.254)
		(layers "F.Cu" "B.Cu")
		(net "GND")
	)
	(via
		(at 386.16382 -351.611438)
		(size 0.4064)
		(drill 0.2032)
		(layers "F.Cu" "B.Cu")
		(net "GND")
	)
	(via
		(at 286.624776 -293.52494)
		(size 0.4064)
		(drill 0.2032)
		(layers "F.Cu" "B.Cu")
		(net "GND")
	)
	(via
		(at 131.572254 -176.51476)
		(size 0.508)
		(drill 0.254)
		(layers "F.Cu" "B.Cu")
		(net "GND")
	)
	(via
		(at 342.245442 -307.82387)
		(size 0.508)
		(drill 0.254)
		(layers "F.Cu" "B.Cu")
		(net "GND")
	)
	(via
		(at 93.523054 -349.219774)
		(size 0.4572)
		(drill 0.254)
		(layers "F.Cu" "B.Cu")
		(net "GND")
	)
	(via
		(at 131.532884 -286.842454)
		(size 0.508)
		(drill 0.254)
		(layers "F.Cu" "B.Cu")
		(net "GND")
	)
	(via
		(at 193.800222 -273.099784)
		(size 0.4064)
		(drill 0.2032)
		(layers "F.Cu" "B.Cu")
		(net "GND")
	)
	(via
		(at 81.024984 -294.4749)
		(size 0.4064)
		(drill 0.2032)
		(layers "F.Cu" "B.Cu")
		(net "GND")
	)
	(via
		(at 74.869294 -354.098098)
		(size 0.4572)
		(drill 0.254)
		(layers "F.Cu" "B.Cu")
		(net "GND")
	)
	(via
		(at 27.347926 -378.94006)
		(size 0.508)
		(drill 0.254)
		(layers "F.Cu" "B.Cu")
		(net "GND")
	)
	(via
		(at 390.849866 -311.099962)
		(size 0.4064)
		(drill 0.2032)
		(layers "F.Cu" "B.Cu")
		(net "GND")
	)
	(via
		(at 45.87494 -297.32478)
		(size 0.4064)
		(drill 0.2032)
		(layers "F.Cu" "B.Cu")
		(net "GND")
	)
	(via
		(at 304.1777 -135.320024)
		(size 0.508)
		(drill 0.254)
		(layers "F.Cu" "B.Cu")
		(net "GND")
	)
	(via
		(at 125.457966 -143.051276)
		(size 0.508)
		(drill 0.254)
		(layers "F.Cu" "B.Cu")
		(net "GND")
	)
	(via
		(at 385.149852 -309.199788)
		(size 0.4064)
		(drill 0.2032)
		(layers "F.Cu" "B.Cu")
		(net "GND")
	)
	(via
		(at 415.3154 -347.951806)
		(size 0.4572)
		(drill 0.254)
		(layers "F.Cu" "B.Cu")
		(net "GND")
	)
	(via
		(at 429.927766 -411.141926)
		(size 0.508)
		(drill 0.254)
		(layers "F.Cu" "B.Cu")
		(net "GND")
	)
	(via
		(at 162.450018 -310.149748)
		(size 0.4064)
		(drill 0.2032)
		(layers "F.Cu" "B.Cu")
		(net "GND")
	)
	(via
		(at 392.48461 -72.56526)
		(size 0.508)
		(drill 0.254)
		(layers "F.Cu" "B.Cu")
		(net "GND")
	)
	(via
		(at 180.64226 -354.074222)
		(size 0.4572)
		(drill 0.254)
		(layers "F.Cu" "B.Cu")
		(net "GND")
	)
	(via
		(at 281.53995 -73.87463)
		(size 0.508)
		(drill 0.254)
		(layers "F.Cu" "B.Cu")
		(net "GND")
	)
	(via
		(at 44.58208 -58.238644)
		(size 0.508)
		(drill 0.254)
		(layers "F.Cu" "B.Cu")
		(net "GND")
	)
	(via
		(at 315.414152 -358.391714)
		(size 0.4572)
		(drill 0.254)
		(layers "F.Cu" "B.Cu")
		(net "GND")
	)
	(via
		(at 132.38099 -27.79014)
		(size 0.508)
		(drill 0.254)
		(layers "F.Cu" "B.Cu")
		(net "GND")
	)
	(via
		(at 197.371462 -51.661822)
		(size 0.508)
		(drill 0.254)
		(layers "F.Cu" "B.Cu")
		(net "GND")
	)
	(via
		(at 136.819386 -46.893226)
		(size 0.508)
		(drill 0.254)
		(layers "F.Cu" "B.Cu")
		(net "GND")
	)
	(via
		(at 115.34775 -410.041852)
		(size 0.4572)
		(drill 0.254)
		(layers "F.Cu" "B.Cu")
		(net "GND")
	)
	(via
		(at 252.961902 -160.8963)
		(size 0.508)
		(drill 0.254)
		(layers "F.Cu" "B.Cu")
		(net "GND")
	)
	(via
		(at 79.59979 -317.749936)
		(size 0.4064)
		(drill 0.2032)
		(layers "F.Cu" "B.Cu")
		(net "GND")
	)
	(via
		(at 8.715756 -308.712362)
		(size 0.508)
		(drill 0.254)
		(layers "F.Cu" "B.Cu")
		(net "GND")
	)
	(via
		(at 82.566002 -342.439498)
		(size 0.4064)
		(drill 0.2032)
		(layers "F.Cu" "B.Cu")
		(net "GND")
	)
	(via
		(at 276.384512 -72.56526)
		(size 0.508)
		(drill 0.254)
		(layers "F.Cu" "B.Cu")
		(net "GND")
	)
	(via
		(at 76.74991 -315.849762)
		(size 0.4064)
		(drill 0.2032)
		(layers "F.Cu" "B.Cu")
		(net "GND")
	)
	(via
		(at 392.52779 -397.140176)
		(size 0.508)
		(drill 0.254)
		(layers "F.Cu" "B.Cu")
		(net "GND")
	)
	(via
		(at 166.249858 -314.899802)
		(size 0.4064)
		(drill 0.2032)
		(layers "F.Cu" "B.Cu")
		(net "GND")
	)
	(via
		(at 41.124886 -273.574764)
		(size 0.4064)
		(drill 0.2032)
		(layers "F.Cu" "B.Cu")
		(net "GND")
	)
	(via
		(at 53.949854 -275.949918)
		(size 0.4064)
		(drill 0.2032)
		(layers "F.Cu" "B.Cu")
		(net "GND")
	)
	(via
		(at 367.368328 -48.753014)
		(size 0.508)
		(drill 0.254)
		(layers "F.Cu" "B.Cu")
		(net "GND")
	)
	(via
		(at 421.589962 -73.85177)
		(size 0.508)
		(drill 0.254)
		(layers "F.Cu" "B.Cu")
		(net "GND")
	)
	(via
		(at 423.32783 -382.84023)
		(size 0.508)
		(drill 0.254)
		(layers "F.Cu" "B.Cu")
		(net "GND")
	)
	(via
		(at 396.0749 -299.224954)
		(size 0.4064)
		(drill 0.2032)
		(layers "F.Cu" "B.Cu")
		(net "GND")
	)
	(via
		(at 379.327918 -407.638504)
		(size 0.508)
		(drill 0.254)
		(layers "F.Cu" "B.Cu")
		(net "GND")
	)
	(via
		(at 117.547644 -409.940252)
		(size 0.4572)
		(drill 0.254)
		(layers "F.Cu" "B.Cu")
		(net "GND")
	)
	(via
		(at 306.448206 -133.044946)
		(size 0.508)
		(drill 0.254)
		(layers "F.Cu" "B.Cu")
		(net "GND")
	)
	(via
		(at 34.491676 -133.836664)
		(size 0.508)
		(drill 0.254)
		(layers "F.Cu" "B.Cu")
		(net "GND")
	)
	(via
		(at 386.099812 -309.199788)
		(size 0.4064)
		(drill 0.2032)
		(layers "F.Cu" "B.Cu")
		(net "GND")
	)
	(via
		(at 272.374868 -298.27474)
		(size 0.4064)
		(drill 0.2032)
		(layers "F.Cu" "B.Cu")
		(net "GND")
	)
	(via
		(at 412.754572 -110.497366)
		(size 0.508)
		(drill 0.254)
		(layers "F.Cu" "B.Cu")
		(net "GND")
	)
	(via
		(at 302.327818 -407.24201)
		(size 0.508)
		(drill 0.254)
		(layers "F.Cu" "B.Cu")
		(net "GND")
	)
	(via
		(at 332.723998 -263.407652)
		(size 0.508)
		(drill 0.254)
		(layers "F.Cu" "B.Cu")
		(net "GND")
	)
	(via
		(at 232.94594 -279.883108)
		(size 0.508)
		(drill 0.254)
		(layers "F.Cu" "B.Cu")
		(net "GND")
	)
	(via
		(at 241.373914 -221.04096)
		(size 0.508)
		(drill 0.254)
		(layers "F.Cu" "B.Cu")
		(net "GND")
	)
	(via
		(at 34.152078 -299.886116)
		(size 0.508)
		(drill 0.254)
		(layers "F.Cu" "B.Cu")
		(net "GND")
	)
	(via
		(at 123.292616 -11.372342)
		(size 0.508)
		(drill 0.254)
		(layers "F.Cu" "B.Cu")
		(net "GND")
	)
	(via
		(at 77.947774 -371.038628)
		(size 0.508)
		(drill 0.254)
		(layers "F.Cu" "B.Cu")
		(net "GND")
	)
	(via
		(at 76.494132 -96.597978)
		(size 0.508)
		(drill 0.254)
		(layers "F.Cu" "B.Cu")
		(net "GND")
	)
	(via
		(at 36.14801 -381.638556)
		(size 0.508)
		(drill 0.254)
		(layers "F.Cu" "B.Cu")
		(net "GND")
	)
	(via
		(at 38.347904 -382.73863)
		(size 0.508)
		(drill 0.254)
		(layers "F.Cu" "B.Cu")
		(net "GND")
	)
	(via
		(at 314.649866 -274.049744)
		(size 0.4064)
		(drill 0.2032)
		(layers "F.Cu" "B.Cu")
		(net "GND")
	)
	(via
		(at 372.2751 -73.23963)
		(size 0.508)
		(drill 0.254)
		(layers "F.Cu" "B.Cu")
		(net "GND")
	)
	(via
		(at 408.424888 -297.32478)
		(size 0.4064)
		(drill 0.2032)
		(layers "F.Cu" "B.Cu")
		(net "GND")
	)
	(via
		(at 13.442188 -228.67493)
		(size 0.508)
		(drill 0.254)
		(layers "F.Cu" "B.Cu")
		(net "GND")
	)
	(via
		(at 2.934208 -284.818582)
		(size 0.508)
		(drill 0.254)
		(layers "F.Cu" "B.Cu")
		(net "GND")
	)
	(via
		(at 73.547732 -406.040336)
		(size 0.508)
		(drill 0.254)
		(layers "F.Cu" "B.Cu")
		(net "GND")
	)
	(via
		(at 299.866812 -149.355048)
		(size 0.508)
		(drill 0.254)
		(layers "F.Cu" "B.Cu")
		(net "GND")
	)
	(via
		(at 213.620096 -56.441848)
		(size 0.508)
		(drill 0.254)
		(layers "F.Cu" "B.Cu")
		(net "GND")
	)
	(via
		(at 179.07508 -296.37482)
		(size 0.4064)
		(drill 0.2032)
		(layers "F.Cu" "B.Cu")
		(net "GND")
	)
	(via
		(at 51.63312 -111.44504)
		(size 0.508)
		(drill 0.254)
		(layers "F.Cu" "B.Cu")
		(net "GND")
	)
	(via
		(at 175.203358 -60.627006)
		(size 0.508)
		(drill 0.254)
		(layers "F.Cu" "B.Cu")
		(net "GND")
	)
	(via
		(at 143.76908 -289.532314)
		(size 0.508)
		(drill 0.254)
		(layers "F.Cu" "B.Cu")
		(net "GND")
	)
	(via
		(at 327.761092 -60.099194)
		(size 0.508)
		(drill 0.254)
		(layers "F.Cu" "B.Cu")
		(net "GND")
	)
	(via
		(at 180.64226 -358.391714)
		(size 0.4572)
		(drill 0.254)
		(layers "F.Cu" "B.Cu")
		(net "GND")
	)
	(via
		(at 397.49984 -276.899878)
		(size 0.4064)
		(drill 0.2032)
		(layers "F.Cu" "B.Cu")
		(net "GND")
	)
	(via
		(at 107.29722 -212.0392)
		(size 0.508)
		(drill 0.254)
		(layers "F.Cu" "B.Cu")
		(net "GND")
	)
	(via
		(at 325.999856 -343.073482)
		(size 0.4572)
		(drill 0.254)
		(layers "F.Cu" "B.Cu")
		(net "GND")
	)
	(via
		(at 331.192378 -243.863622)
		(size 0.508)
		(drill 0.254)
		(layers "F.Cu" "B.Cu")
		(net "GND")
	)
	(via
		(at 189.524894 -292.574726)
		(size 0.4064)
		(drill 0.2032)
		(layers "F.Cu" "B.Cu")
		(net "GND")
	)
	(via
		(at 189.999874 -283.549852)
		(size 0.4064)
		(drill 0.2032)
		(layers "F.Cu" "B.Cu")
		(net "GND")
	)
	(via
		(at 169.587164 -129.964942)
		(size 0.508)
		(drill 0.254)
		(layers "F.Cu" "B.Cu")
		(net "GND")
	)
	(via
		(at 297.927776 -371.038628)
		(size 0.508)
		(drill 0.254)
		(layers "F.Cu" "B.Cu")
		(net "GND")
	)
	(via
		(at 397.90497 -105.365042)
		(size 0.508)
		(drill 0.254)
		(layers "F.Cu" "B.Cu")
		(net "GND")
	)
	(via
		(at 73.547732 -381.241808)
		(size 0.508)
		(drill 0.254)
		(layers "F.Cu" "B.Cu")
		(net "GND")
	)
	(via
		(at 427.727872 -395.938502)
		(size 0.508)
		(drill 0.254)
		(layers "F.Cu" "B.Cu")
		(net "GND")
	)
	(via
		(at 194.336924 -343.073482)
		(size 0.4572)
		(drill 0.254)
		(layers "F.Cu" "B.Cu")
		(net "GND")
	)
	(via
		(at 427.900084 -274.049744)
		(size 0.4064)
		(drill 0.2032)
		(layers "F.Cu" "B.Cu")
		(net "GND")
	)
	(via
		(at 246.102124 -58.096404)
		(size 0.508)
		(drill 0.254)
		(layers "F.Cu" "B.Cu")
		(net "GND")
	)
	(via
		(at 342.23452 -268.731492)
		(size 0.508)
		(drill 0.254)
		(layers "F.Cu" "B.Cu")
		(net "GND")
	)
	(via
		(at 415.96691 -123.635008)
		(size 0.508)
		(drill 0.254)
		(layers "F.Cu" "B.Cu")
		(net "GND")
	)
	(via
		(at 450.824346 -287.228788)
		(size 0.508)
		(drill 0.254)
		(layers "F.Cu" "B.Cu")
		(net "GND")
	)
	(via
		(at 171.474892 -303.974754)
		(size 0.4064)
		(drill 0.2032)
		(layers "F.Cu" "B.Cu")
		(net "GND")
	)
	(via
		(at 270.601694 -136.901936)
		(size 0.508)
		(drill 0.254)
		(layers "F.Cu" "B.Cu")
		(net "GND")
	)
	(via
		(at 357.35514 -123.947428)
		(size 0.508)
		(drill 0.254)
		(layers "F.Cu" "B.Cu")
		(net "GND")
	)
	(via
		(at 57.979818 -104.830372)
		(size 0.508)
		(drill 0.254)
		(layers "F.Cu" "B.Cu")
		(net "GND")
	)
	(via
		(at 170.806364 -133.564884)
		(size 0.508)
		(drill 0.254)
		(layers "F.Cu" "B.Cu")
		(net "GND")
	)
	(via
		(at 297.927776 -378.83846)
		(size 0.508)
		(drill 0.254)
		(layers "F.Cu" "B.Cu")
		(net "GND")
	)
	(via
		(at 124.88037 -210.609942)
		(size 0.508)
		(drill 0.254)
		(layers "F.Cu" "B.Cu")
		(net "GND")
	)
	(via
		(at 71.690738 -119.414544)
		(size 0.508)
		(drill 0.254)
		(layers "F.Cu" "B.Cu")
		(net "GND")
	)
	(via
		(at 432.119024 -357.123746)
		(size 0.4572)
		(drill 0.254)
		(layers "F.Cu" "B.Cu")
		(net "GND")
	)
	(via
		(at 52.049934 -314.899802)
		(size 0.4064)
		(drill 0.2032)
		(layers "F.Cu" "B.Cu")
		(net "GND")
	)
	(via
		(at 384.059684 -104.523286)
		(size 0.508)
		(drill 0.254)
		(layers "F.Cu" "B.Cu")
		(net "GND")
	)
	(via
		(at 80.54975 -285.449772)
		(size 0.4064)
		(drill 0.2032)
		(layers "F.Cu" "B.Cu")
		(net "GND")
	)
	(via
		(at 290.449762 -287.699958)
		(size 0.4064)
		(drill 0.2032)
		(layers "F.Cu" "B.Cu")
		(net "GND")
	)
	(via
		(at 23.50262 -343.073482)
		(size 0.4572)
		(drill 0.254)
		(layers "F.Cu" "B.Cu")
		(net "GND")
	)
	(via
		(at 341.927942 -371.038628)
		(size 0.508)
		(drill 0.254)
		(layers "F.Cu" "B.Cu")
		(net "GND")
	)
	(via
		(at 134.94004 -201.913236)
		(size 0.508)
		(drill 0.254)
		(layers "F.Cu" "B.Cu")
		(net "GND")
	)
	(via
		(at 130.318256 -346.09913)
		(size 0.4572)
		(drill 0.254)
		(layers "F.Cu" "B.Cu")
		(net "GND")
	)
	(via
		(at 390.857994 -57.521094)
		(size 0.508)
		(drill 0.254)
		(layers "F.Cu" "B.Cu")
		(net "GND")
	)
	(via
		(at 124.342652 -150.16861)
		(size 0.508)
		(drill 0.254)
		(layers "F.Cu" "B.Cu")
		(net "GND")
	)
	(via
		(at 188.574934 -303.024794)
		(size 0.4064)
		(drill 0.2032)
		(layers "F.Cu" "B.Cu")
		(net "GND")
	)
	(via
		(at 51.74996 -144.250156)
		(size 0.508)
		(drill 0.254)
		(layers "F.Cu" "B.Cu")
		(net "GND")
	)
	(via
		(at 39.04742 -347.951806)
		(size 0.4572)
		(drill 0.254)
		(layers "F.Cu" "B.Cu")
		(net "GND")
	)
	(via
		(at 313.224926 -289.724846)
		(size 0.4064)
		(drill 0.2032)
		(layers "F.Cu" "B.Cu")
		(net "GND")
	)
	(via
		(at 356.207568 -286.842454)
		(size 0.508)
		(drill 0.254)
		(layers "F.Cu" "B.Cu")
		(net "GND")
	)
	(via
		(at 39.418768 -354.732082)
		(size 0.4064)
		(drill 0.2032)
		(layers "F.Cu" "B.Cu")
		(net "GND")
	)
	(via
		(at 347.442536 -258.78155)
		(size 0.508)
		(drill 0.254)
		(layers "F.Cu" "B.Cu")
		(net "GND")
	)
	(via
		(at 155.800044 -308.249828)
		(size 0.4064)
		(drill 0.2032)
		(layers "F.Cu" "B.Cu")
		(net "GND")
	)
	(via
		(at 381.527812 -403.34184)
		(size 0.508)
		(drill 0.254)
		(layers "F.Cu" "B.Cu")
		(net "GND")
	)
	(via
		(at 161.54781 -409.940252)
		(size 0.508)
		(drill 0.254)
		(layers "F.Cu" "B.Cu")
		(net "GND")
	)
	(via
		(at 300.047914 -346.09913)
		(size 0.4572)
		(drill 0.254)
		(layers "F.Cu" "B.Cu")
		(net "GND")
	)
	(via
		(at 106.43616 -134.87146)
		(size 0.508)
		(drill 0.254)
		(layers "F.Cu" "B.Cu")
		(net "GND")
	)
	(via
		(at 154.375104 -281.174952)
		(size 0.4064)
		(drill 0.2032)
		(layers "F.Cu" "B.Cu")
		(net "GND")
	)
	(via
		(at 156.750004 -301.599854)
		(size 0.4064)
		(drill 0.2032)
		(layers "F.Cu" "B.Cu")
		(net "GND")
	)
	(via
		(at 423.32783 -401.040092)
		(size 0.508)
		(drill 0.254)
		(layers "F.Cu" "B.Cu")
		(net "GND")
	)
	(via
		(at 33.947862 -385.141978)
		(size 0.508)
		(drill 0.254)
		(layers "F.Cu" "B.Cu")
		(net "GND")
	)
	(via
		(at 250.955556 -63.218314)
		(size 0.508)
		(drill 0.254)
		(layers "F.Cu" "B.Cu")
		(net "GND")
	)
	(via
		(at 237.642654 -308.181756)
		(size 0.508)
		(drill 0.254)
		(layers "F.Cu" "B.Cu")
		(net "GND")
	)
	(via
		(at 287.612074 -341.805514)
		(size 0.4572)
		(drill 0.254)
		(layers "F.Cu" "B.Cu")
		(net "GND")
	)
	(via
		(at 109.678216 -136.317228)
		(size 0.508)
		(drill 0.254)
		(layers "F.Cu" "B.Cu")
		(net "GND")
	)
	(via
		(at 225.7171 -304.703988)
		(size 0.508)
		(drill 0.254)
		(layers "F.Cu" "B.Cu")
		(net "GND")
	)
	(via
		(at 128.839468 -351.611438)
		(size 0.4064)
		(drill 0.2032)
		(layers "F.Cu" "B.Cu")
		(net "GND")
	)
	(via
		(at 147.682458 -37.087048)
		(size 0.508)
		(drill 0.254)
		(layers "F.Cu" "B.Cu")
		(net "GND")
	)
	(via
		(at 306.574698 -302.074834)
		(size 0.4064)
		(drill 0.2032)
		(layers "F.Cu" "B.Cu")
		(net "GND")
	)
	(via
		(at 392.441176 -38.49116)
		(size 0.508)
		(drill 0.254)
		(layers "F.Cu" "B.Cu")
		(net "GND")
	)
	(via
		(at 427.89983 -313.949842)
		(size 0.4064)
		(drill 0.2032)
		(layers "F.Cu" "B.Cu")
		(net "GND")
	)
	(via
		(at 236.633258 -143.656812)
		(size 0.508)
		(drill 0.254)
		(layers "F.Cu" "B.Cu")
		(net "GND")
	)
	(via
		(at 50.224436 -358.391714)
		(size 0.4572)
		(drill 0.254)
		(layers "F.Cu" "B.Cu")
		(net "GND")
	)
	(via
		(at 422.199816 -314.899802)
		(size 0.4064)
		(drill 0.2032)
		(layers "F.Cu" "B.Cu")
		(net "GND")
	)
	(via
		(at 312.439558 -85.426296)
		(size 0.508)
		(drill 0.254)
		(layers "F.Cu" "B.Cu")
		(net "GND")
	)
	(via
		(at 17.733264 -120.890284)
		(size 0.508)
		(drill 0.254)
		(layers "F.Cu" "B.Cu")
		(net "GND")
	)
	(via
		(at 329.108816 -350.977454)
		(size 0.4572)
		(drill 0.254)
		(layers "F.Cu" "B.Cu")
		(net "GND")
	)
	(via
		(at 360.135424 -115.688364)
		(size 0.508)
		(drill 0.254)
		(layers "F.Cu" "B.Cu")
		(net "GND")
	)
	(via
		(at 378.01677 -87.101934)
		(size 0.508)
		(drill 0.254)
		(layers "F.Cu" "B.Cu")
		(net "GND")
	)
	(via
		(at 121.947686 -385.141978)
		(size 0.4572)
		(drill 0.254)
		(layers "F.Cu" "B.Cu")
		(net "GND")
	)
	(via
		(at 287.099756 -282.599892)
		(size 0.4064)
		(drill 0.2032)
		(layers "F.Cu" "B.Cu")
		(net "GND")
	)
	(via
		(at 187.631578 -250.939808)
		(size 0.508)
		(drill 0.254)
		(layers "F.Cu" "B.Cu")
		(net "GND")
	)
	(via
		(at 80.54975 -304.449734)
		(size 0.4064)
		(drill 0.2032)
		(layers "F.Cu" "B.Cu")
		(net "GND")
	)
	(via
		(at 368.239294 -31.652972)
		(size 0.508)
		(drill 0.254)
		(layers "F.Cu" "B.Cu")
		(net "GND")
	)
	(via
		(at 290.80079 -34.990278)
		(size 0.508)
		(drill 0.254)
		(layers "F.Cu" "B.Cu")
		(net "GND")
	)
	(via
		(at 297.49877 -115.896898)
		(size 0.508)
		(drill 0.254)
		(layers "F.Cu" "B.Cu")
		(net "GND")
	)
	(via
		(at 302.871124 -31.652972)
		(size 0.508)
		(drill 0.254)
		(layers "F.Cu" "B.Cu")
		(net "GND")
	)
	(via
		(at 455.234802 -244.59184)
		(size 0.508)
		(drill 0.254)
		(layers "F.Cu" "B.Cu")
		(net "GND")
	)
	(via
		(at 75.74788 -395.938502)
		(size 0.508)
		(drill 0.254)
		(layers "F.Cu" "B.Cu")
		(net "GND")
	)
	(via
		(at 453.709024 -236.379004)
		(size 0.508)
		(drill 0.254)
		(layers "F.Cu" "B.Cu")
		(net "GND")
	)
	(via
		(at 157.224984 -294.4749)
		(size 0.4064)
		(drill 0.2032)
		(layers "F.Cu" "B.Cu")
		(net "GND")
	)
	(via
		(at 289.94989 -275.949918)
		(size 0.4064)
		(drill 0.2032)
		(layers "F.Cu" "B.Cu")
		(net "GND")
	)
	(via
		(at 293.527734 -403.34184)
		(size 0.508)
		(drill 0.254)
		(layers "F.Cu" "B.Cu")
		(net "GND")
	)
	(via
		(at 366.420654 -63.218314)
		(size 0.508)
		(drill 0.254)
		(layers "F.Cu" "B.Cu")
		(net "GND")
	)
	(via
		(at 300.419262 -354.732082)
		(size 0.4064)
		(drill 0.2032)
		(layers "F.Cu" "B.Cu")
		(net "GND")
	)
	(via
		(at 84.567522 -354.732082)
		(size 0.4064)
		(drill 0.2032)
		(layers "F.Cu" "B.Cu")
		(net "GND")
	)
	(via
		(at 111.056674 -292.710108)
		(size 0.508)
		(drill 0.254)
		(layers "F.Cu" "B.Cu")
		(net "GND")
	)
	(via
		(at 171.31538 -358.391714)
		(size 0.4572)
		(drill 0.254)
		(layers "F.Cu" "B.Cu")
		(net "GND")
	)
	(via
		(at 154.375104 -276.424898)
		(size 0.4064)
		(drill 0.2032)
		(layers "F.Cu" "B.Cu")
		(net "GND")
	)
	(via
		(at 384.834384 -253.45644)
		(size 0.508)
		(drill 0.254)
		(layers "F.Cu" "B.Cu")
		(net "GND")
	)
	(via
		(at 338.435696 -355.366066)
		(size 0.4572)
		(drill 0.254)
		(layers "F.Cu" "B.Cu")
		(net "GND")
	)
	(via
		(at 192.850008 -279.749758)
		(size 0.4064)
		(drill 0.2032)
		(layers "F.Cu" "B.Cu")
		(net "GND")
	)
	(via
		(at 386.099812 -303.499774)
		(size 0.4064)
		(drill 0.2032)
		(layers "F.Cu" "B.Cu")
		(net "GND")
	)
	(via
		(at 70.50151 -346.09913)
		(size 0.4572)
		(drill 0.254)
		(layers "F.Cu" "B.Cu")
		(net "GND")
	)
	(via
		(at 151.859488 -109.382052)
		(size 0.508)
		(drill 0.254)
		(layers "F.Cu" "B.Cu")
		(net "GND")
	)
	(via
		(at 127.97028 -290.68649)
		(size 0.508)
		(drill 0.254)
		(layers "F.Cu" "B.Cu")
		(net "GND")
	)
	(via
		(at 179.07508 -291.624766)
		(size 0.4064)
		(drill 0.2032)
		(layers "F.Cu" "B.Cu")
		(net "GND")
	)
	(via
		(at 80.636364 -51.661822)
		(size 0.508)
		(drill 0.254)
		(layers "F.Cu" "B.Cu")
		(net "GND")
	)
	(via
		(at 69.561202 -60.099194)
		(size 0.508)
		(drill 0.254)
		(layers "F.Cu" "B.Cu")
		(net "GND")
	)
	(via
		(at 317.008256 -144.224502)
		(size 0.508)
		(drill 0.254)
		(layers "F.Cu" "B.Cu")
		(net "GND")
	)
	(via
		(at 224.722944 -97.31375)
		(size 0.508)
		(drill 0.254)
		(layers "F.Cu" "B.Cu")
		(net "GND")
	)
	(via
		(at 190.949834 -274.999958)
		(size 0.4064)
		(drill 0.2032)
		(layers "F.Cu" "B.Cu")
		(net "GND")
	)
	(via
		(at 169.587164 -135.364982)
		(size 0.508)
		(drill 0.254)
		(layers "F.Cu" "B.Cu")
		(net "GND")
	)
	(via
		(at 84.196174 -354.098098)
		(size 0.4572)
		(drill 0.254)
		(layers "F.Cu" "B.Cu")
		(net "GND")
	)
	(via
		(at 345.877642 -306.607718)
		(size 0.508)
		(drill 0.254)
		(layers "F.Cu" "B.Cu")
		(net "GND")
	)
	(via
		(at 126.347728 -402.140166)
		(size 0.4572)
		(drill 0.254)
		(layers "F.Cu" "B.Cu")
		(net "GND")
	)
	(via
		(at 51.48326 -346.09913)
		(size 0.4572)
		(drill 0.254)
		(layers "F.Cu" "B.Cu")
		(net "GND")
	)
	(via
		(at 125.154944 -121.661428)
		(size 0.508)
		(drill 0.254)
		(layers "F.Cu" "B.Cu")
		(net "GND")
	)
	(via
		(at 161.975038 -286.874966)
		(size 0.4064)
		(drill 0.2032)
		(layers "F.Cu" "B.Cu")
		(net "GND")
	)
	(via
		(at 53.323236 -56.353456)
		(size 0.508)
		(drill 0.254)
		(layers "F.Cu" "B.Cu")
		(net "GND")
	)
	(via
		(at 274.749768 -306.349908)
		(size 0.4064)
		(drill 0.2032)
		(layers "F.Cu" "B.Cu")
		(net "GND")
	)
	(via
		(at 389.424926 -283.074872)
		(size 0.4064)
		(drill 0.2032)
		(layers "F.Cu" "B.Cu")
		(net "GND")
	)
	(via
		(at 314.366148 -118.498112)
		(size 0.508)
		(drill 0.254)
		(layers "F.Cu" "B.Cu")
		(net "GND")
	)
	(via
		(at 252.139196 -32.911796)
		(size 0.508)
		(drill 0.254)
		(layers "F.Cu" "B.Cu")
		(net "GND")
	)
	(via
		(at 172.547788 -382.84023)
		(size 0.508)
		(drill 0.254)
		(layers "F.Cu" "B.Cu")
		(net "GND")
	)
	(via
		(at 421.161972 -351.611438)
		(size 0.4064)
		(drill 0.2032)
		(layers "F.Cu" "B.Cu")
		(net "GND")
	)
	(via
		(at 348.527878 -408.840178)
		(size 0.508)
		(drill 0.254)
		(layers "F.Cu" "B.Cu")
		(net "GND")
	)
	(via
		(at 32.8295 -344.831162)
		(size 0.4572)
		(drill 0.254)
		(layers "F.Cu" "B.Cu")
		(net "GND")
	)
	(via
		(at 267.939774 -297.32478)
		(size 0.4064)
		(drill 0.2032)
		(layers "F.Cu" "B.Cu")
		(net "GND")
	)
	(via
		(at 440.895994 -103.894128)
		(size 0.508)
		(drill 0.254)
		(layers "F.Cu" "B.Cu")
		(net "GND")
	)
	(via
		(at 383.94894 -33.19018)
		(size 0.508)
		(drill 0.254)
		(layers "F.Cu" "B.Cu")
		(net "GND")
	)
	(via
		(at 18.638774 -23.880318)
		(size 0.508)
		(drill 0.254)
		(layers "F.Cu" "B.Cu")
		(net "GND")
	)
	(via
		(at 319.39484 -60.633356)
		(size 0.508)
		(drill 0.254)
		(layers "F.Cu" "B.Cu")
		(net "GND")
	)
	(via
		(at 142.174214 -208.825846)
		(size 0.508)
		(drill 0.254)
		(layers "F.Cu" "B.Cu")
		(net "GND")
	)
	(via
		(at 164.060378 -20.35556)
		(size 0.508)
		(drill 0.254)
		(layers "F.Cu" "B.Cu")
		(net "GND")
	)
	(via
		(at 396.26032 -21.37156)
		(size 0.508)
		(drill 0.254)
		(layers "F.Cu" "B.Cu")
		(net "GND")
	)
	(via
		(at 159.124904 -288.774886)
		(size 0.4064)
		(drill 0.2032)
		(layers "F.Cu" "B.Cu")
		(net "GND")
	)
	(via
		(at 386.099812 -300.649894)
		(size 0.4064)
		(drill 0.2032)
		(layers "F.Cu" "B.Cu")
		(net "GND")
	)
	(via
		(at 166.663878 -175.730154)
		(size 0.508)
		(drill 0.254)
		(layers "F.Cu" "B.Cu")
		(net "GND")
	)
	(via
		(at 284.249876 -280.699718)
		(size 0.4064)
		(drill 0.2032)
		(layers "F.Cu" "B.Cu")
		(net "GND")
	)
	(via
		(at 325.002906 -197.250304)
		(size 0.508)
		(drill 0.254)
		(layers "F.Cu" "B.Cu")
		(net "GND")
	)
	(via
		(at 228.667818 -220.303852)
		(size 0.4572)
		(drill 0.254)
		(layers "F.Cu" "B.Cu")
		(net "GND")
	)
	(via
		(at 299.449744 -319.65011)
		(size 0.4064)
		(drill 0.2032)
		(layers "F.Cu" "B.Cu")
		(net "GND")
	)
	(via
		(at 2.426716 -244.336316)
		(size 0.508)
		(drill 0.254)
		(layers "F.Cu" "B.Cu")
		(net "GND")
	)
	(via
		(at 170.347894 -399.441924)
		(size 0.508)
		(drill 0.254)
		(layers "F.Cu" "B.Cu")
		(net "GND")
	)
	(via
		(at 188.077602 -135.320024)
		(size 0.508)
		(drill 0.254)
		(layers "F.Cu" "B.Cu")
		(net "GND")
	)
	(via
		(at 125.15215 -13.613638)
		(size 0.508)
		(drill 0.254)
		(layers "F.Cu" "B.Cu")
		(net "GND")
	)
	(via
		(at 34.00298 -296.695114)
		(size 0.508)
		(drill 0.254)
		(layers "F.Cu" "B.Cu")
		(net "GND")
	)
	(via
		(at 166.249858 -274.999958)
		(size 0.4064)
		(drill 0.2032)
		(layers "F.Cu" "B.Cu")
		(net "GND")
	)
	(via
		(at 344.653616 -352.245422)
		(size 0.4572)
		(drill 0.254)
		(layers "F.Cu" "B.Cu")
		(net "GND")
	)
	(via
		(at 437.07812 -347.951806)
		(size 0.4572)
		(drill 0.254)
		(layers "F.Cu" "B.Cu")
		(net "GND")
	)
	(via
		(at 386.575046 -294.4749)
		(size 0.4064)
		(drill 0.2032)
		(layers "F.Cu" "B.Cu")
		(net "GND")
	)
	(via
		(at 165.947852 -383.940304)
		(size 0.508)
		(drill 0.254)
		(layers "F.Cu" "B.Cu")
		(net "GND")
	)
	(via
		(at 168.148 -404.940262)
		(size 0.508)
		(drill 0.254)
		(layers "F.Cu" "B.Cu")
		(net "GND")
	)
	(via
		(at 34.4551 -31.390082)
		(size 0.508)
		(drill 0.254)
		(layers "F.Cu" "B.Cu")
		(net "GND")
	)
	(via
		(at 79.82839 -347.951806)
		(size 0.4572)
		(drill 0.254)
		(layers "F.Cu" "B.Cu")
		(net "GND")
	)
	(via
		(at 99.313238 -33.459674)
		(size 0.508)
		(drill 0.254)
		(layers "F.Cu" "B.Cu")
		(net "GND")
	)
	(via
		(at 37.788596 -343.073482)
		(size 0.4572)
		(drill 0.254)
		(layers "F.Cu" "B.Cu")
		(net "GND")
	)
	(via
		(at 303.724818 -288.774886)
		(size 0.4064)
		(drill 0.2032)
		(layers "F.Cu" "B.Cu")
		(net "GND")
	)
	(via
		(at 406.54986 -287.699958)
		(size 0.4064)
		(drill 0.2032)
		(layers "F.Cu" "B.Cu")
		(net "GND")
	)
	(via
		(at 54.899814 -274.049744)
		(size 0.4064)
		(drill 0.2032)
		(layers "F.Cu" "B.Cu")
		(net "GND")
	)
	(via
		(at 274.274788 -280.224738)
		(size 0.4064)
		(drill 0.2032)
		(layers "F.Cu" "B.Cu")
		(net "GND")
	)
	(via
		(at 250.871228 -32.911796)
		(size 0.508)
		(drill 0.254)
		(layers "F.Cu" "B.Cu")
		(net "GND")
	)
	(via
		(at 411.275022 -285.924752)
		(size 0.4064)
		(drill 0.2032)
		(layers "F.Cu" "B.Cu")
		(net "GND")
	)
	(via
		(at 269.52448 -298.27474)
		(size 0.4064)
		(drill 0.2032)
		(layers "F.Cu" "B.Cu")
		(net "GND")
	)
	(via
		(at 90.942668 -111.688372)
		(size 0.508)
		(drill 0.254)
		(layers "F.Cu" "B.Cu")
		(net "GND")
	)
	(via
		(at 114.361976 -276.928072)
		(size 0.508)
		(drill 0.254)
		(layers "F.Cu" "B.Cu")
		(net "GND")
	)
	(via
		(at 403.674834 -306.824888)
		(size 0.4064)
		(drill 0.2032)
		(layers "F.Cu" "B.Cu")
		(net "GND")
	)
	(via
		(at 379.327918 -397.140176)
		(size 0.508)
		(drill 0.254)
		(layers "F.Cu" "B.Cu")
		(net "GND")
	)
	(via
		(at 436.527702 -384.042158)
		(size 0.508)
		(drill 0.254)
		(layers "F.Cu" "B.Cu")
		(net "GND")
	)
	(via
		(at 190.474854 -296.37482)
		(size 0.4064)
		(drill 0.2032)
		(layers "F.Cu" "B.Cu")
		(net "GND")
	)
	(via
		(at 211.349336 -371.112288)
		(size 0.508)
		(drill 0.254)
		(layers "F.Cu" "B.Cu")
		(net "GND")
	)
	(via
		(at 290.80079 -33.19018)
		(size 0.508)
		(drill 0.254)
		(layers "F.Cu" "B.Cu")
		(net "GND")
	)
	(via
		(at 74.581258 -29.859478)
		(size 0.508)
		(drill 0.254)
		(layers "F.Cu" "B.Cu")
		(net "GND")
	)
	(via
		(at 289.94989 -279.749758)
		(size 0.4064)
		(drill 0.2032)
		(layers "F.Cu" "B.Cu")
		(net "GND")
	)
	(via
		(at 363.825536 -293.424102)
		(size 0.508)
		(drill 0.254)
		(layers "F.Cu" "B.Cu")
		(net "GND")
	)
	(via
		(at 133.055868 -345.465146)
		(size 0.4064)
		(drill 0.2032)
		(layers "F.Cu" "B.Cu")
		(net "GND")
	)
	(via
		(at 283.833062 -98.845116)
		(size 0.508)
		(drill 0.254)
		(layers "F.Cu" "B.Cu")
		(net "GND")
	)
	(via
		(at 88.783922 -345.465146)
		(size 0.4064)
		(drill 0.2032)
		(layers "F.Cu" "B.Cu")
		(net "GND")
	)
	(via
		(at 67.249802 -316.799722)
		(size 0.4064)
		(drill 0.2032)
		(layers "F.Cu" "B.Cu")
		(net "GND")
	)
	(via
		(at 4.562856 -215.721692)
		(size 0.508)
		(drill 0.254)
		(layers "F.Cu" "B.Cu")
		(net "GND")
	)
	(via
		(at 229.832916 -157.23616)
		(size 0.508)
		(drill 0.254)
		(layers "F.Cu" "B.Cu")
		(net "GND")
	)
	(via
		(at 191.425068 -294.4749)
		(size 0.4064)
		(drill 0.2032)
		(layers "F.Cu" "B.Cu")
		(net "GND")
	)
	(via
		(at 466.835998 -308.163976)
		(size 0.508)
		(drill 0.254)
		(layers "F.Cu" "B.Cu")
		(net "GND")
	)
	(via
		(at 246.448834 -31.390082)
		(size 0.508)
		(drill 0.254)
		(layers "F.Cu" "B.Cu")
		(net "GND")
	)
	(via
		(at 444.938658 -23.880318)
		(size 0.508)
		(drill 0.254)
		(layers "F.Cu" "B.Cu")
		(net "GND")
	)
	(via
		(at 35.759644 -122.626628)
		(size 0.508)
		(drill 0.254)
		(layers "F.Cu" "B.Cu")
		(net "GND")
	)
	(via
		(at 149.315932 -385.557268)
		(size 0.508)
		(drill 0.254)
		(layers "F.Cu" "B.Cu")
		(net "GND")
	)
	(via
		(at 75.240642 -348.58579)
		(size 0.4064)
		(drill 0.2032)
		(layers "F.Cu" "B.Cu")
		(net "GND")
	)
	(via
		(at 101.477572 -102.271068)
		(size 0.508)
		(drill 0.254)
		(layers "F.Cu" "B.Cu")
		(net "GND")
	)
	(via
		(at 235.005626 -47.895256)
		(size 0.508)
		(drill 0.254)
		(layers "F.Cu" "B.Cu")
		(net "GND")
	)
	(via
		(at 117.511068 -351.611438)
		(size 0.4064)
		(drill 0.2032)
		(layers "F.Cu" "B.Cu")
		(net "GND")
	)
	(via
		(at 454.2536 -225.5774)
		(size 0.508)
		(drill 0.254)
		(layers "F.Cu" "B.Cu")
		(net "GND")
	)
	(via
		(at 276.649688 -275.949918)
		(size 0.4064)
		(drill 0.2032)
		(layers "F.Cu" "B.Cu")
		(net "GND")
	)
	(via
		(at 160.549844 -314.899802)
		(size 0.4064)
		(drill 0.2032)
		(layers "F.Cu" "B.Cu")
		(net "GND")
	)
	(via
		(at 44.94784 -395.938502)
		(size 0.508)
		(drill 0.254)
		(layers "F.Cu" "B.Cu")
		(net "GND")
	)
	(via
		(at 291.32784 -403.738588)
		(size 0.508)
		(drill 0.254)
		(layers "F.Cu" "B.Cu")
		(net "GND")
	)
	(via
		(at 376.858022 -283.131514)
		(size 0.508)
		(drill 0.254)
		(layers "F.Cu" "B.Cu")
		(net "GND")
	)
	(via
		(at 170.043348 -28.139136)
		(size 0.508)
		(drill 0.254)
		(layers "F.Cu" "B.Cu")
		(net "GND")
	)
	(via
		(at 409.849828 -319.65011)
		(size 0.4064)
		(drill 0.2032)
		(layers "F.Cu" "B.Cu")
		(net "GND")
	)
	(via
		(at 435.599332 -354.732082)
		(size 0.4064)
		(drill 0.2032)
		(layers "F.Cu" "B.Cu")
		(net "GND")
	)
	(via
		(at 381.94742 -345.465146)
		(size 0.4064)
		(drill 0.2032)
		(layers "F.Cu" "B.Cu")
		(net "GND")
	)
	(via
		(at 36.849812 -313.949842)
		(size 0.4064)
		(drill 0.2032)
		(layers "F.Cu" "B.Cu")
		(net "GND")
	)
	(via
		(at 53.48732 -100.64496)
		(size 0.508)
		(drill 0.254)
		(layers "F.Cu" "B.Cu")
		(net "GND")
	)
	(via
		(at 280.924762 -305.874928)
		(size 0.4064)
		(drill 0.2032)
		(layers "F.Cu" "B.Cu")
		(net "GND")
	)
	(via
		(at 366.441228 -38.49116)
		(size 0.508)
		(drill 0.254)
		(layers "F.Cu" "B.Cu")
		(net "GND")
	)
	(via
		(at 297.310302 -342.439498)
		(size 0.4064)
		(drill 0.2032)
		(layers "F.Cu" "B.Cu")
		(net "GND")
	)
	(via
		(at 33.947862 -411.141926)
		(size 0.508)
		(drill 0.254)
		(layers "F.Cu" "B.Cu")
		(net "GND")
	)
	(via
		(at 378.467112 -354.098098)
		(size 0.4572)
		(drill 0.254)
		(layers "F.Cu" "B.Cu")
		(net "GND")
	)
	(via
		(at 30.627066 -259.576316)
		(size 0.508)
		(drill 0.254)
		(layers "F.Cu" "B.Cu")
		(net "GND")
	)
	(via
		(at 177.174906 -296.37482)
		(size 0.4064)
		(drill 0.2032)
		(layers "F.Cu" "B.Cu")
		(net "GND")
	)
	(via
		(at 36.14801 -397.140176)
		(size 0.508)
		(drill 0.254)
		(layers "F.Cu" "B.Cu")
		(net "GND")
	)
	(via
		(at 310.849772 -305.399948)
		(size 0.4064)
		(drill 0.2032)
		(layers "F.Cu" "B.Cu")
		(net "GND")
	)
	(via
		(at 161.975038 -284.974792)
		(size 0.4064)
		(drill 0.2032)
		(layers "F.Cu" "B.Cu")
		(net "GND")
	)
	(via
		(at 277.599902 -318.699896)
		(size 0.4064)
		(drill 0.2032)
		(layers "F.Cu" "B.Cu")
		(net "GND")
	)
	(via
		(at 290.721034 -354.098098)
		(size 0.4572)
		(drill 0.254)
		(layers "F.Cu" "B.Cu")
		(net "GND")
	)
	(via
		(at 279.974802 -294.4749)
		(size 0.4064)
		(drill 0.2032)
		(layers "F.Cu" "B.Cu")
		(net "GND")
	)
	(via
		(at 104.996996 -331.545692)
		(size 0.508)
		(drill 0.254)
		(layers "F.Cu" "B.Cu")
		(net "GND")
	)
	(via
		(at 261.963916 -82.01787)
		(size 0.508)
		(drill 0.254)
		(layers "F.Cu" "B.Cu")
		(net "GND")
	)
	(via
		(at 387.999986 -302.549814)
		(size 0.4064)
		(drill 0.2032)
		(layers "F.Cu" "B.Cu")
		(net "GND")
	)
	(via
		(at 296.599864 -312.999882)
		(size 0.4064)
		(drill 0.2032)
		(layers "F.Cu" "B.Cu")
		(net "GND")
	)
	(via
		(at 284.724856 -298.27474)
		(size 0.4064)
		(drill 0.2032)
		(layers "F.Cu" "B.Cu")
		(net "GND")
	)
	(via
		(at 53.270404 -28.802076)
		(size 0.508)
		(drill 0.254)
		(layers "F.Cu" "B.Cu")
		(net "GND")
	)
	(via
		(at 86.747858 -409.940252)
		(size 0.508)
		(drill 0.254)
		(layers "F.Cu" "B.Cu")
		(net "GND")
	)
	(via
		(at 14.670786 -111.127032)
		(size 0.508)
		(drill 0.254)
		(layers "F.Cu" "B.Cu")
		(net "GND")
	)
	(via
		(at 196.07784 -33.248092)
		(size 0.508)
		(drill 0.254)
		(layers "F.Cu" "B.Cu")
		(net "GND")
	)
	(via
		(at 61.549788 -315.849762)
		(size 0.4064)
		(drill 0.2032)
		(layers "F.Cu" "B.Cu")
		(net "GND")
	)
	(via
		(at 335.328006 -373.83847)
		(size 0.508)
		(drill 0.254)
		(layers "F.Cu" "B.Cu")
		(net "GND")
	)
	(via
		(at 166.075106 -73.23963)
		(size 0.508)
		(drill 0.254)
		(layers "F.Cu" "B.Cu")
		(net "GND")
	)
	(via
		(at 112.92332 -341.805514)
		(size 0.4572)
		(drill 0.254)
		(layers "F.Cu" "B.Cu")
		(net "GND")
	)
	(via
		(at 26.61158 -352.245422)
		(size 0.4572)
		(drill 0.254)
		(layers "F.Cu" "B.Cu")
		(net "GND")
	)
	(via
		(at 128.638554 -307.82387)
		(size 0.508)
		(drill 0.254)
		(layers "F.Cu" "B.Cu")
		(net "GND")
	)
	(via
		(at 163.247324 -358.391714)
		(size 0.4572)
		(drill 0.254)
		(layers "F.Cu" "B.Cu")
		(net "GND")
	)
	(via
		(at 357.658162 -145.083276)
		(size 0.508)
		(drill 0.254)
		(layers "F.Cu" "B.Cu")
		(net "GND")
	)
	(via
		(at 427.89983 -318.699896)
		(size 0.4064)
		(drill 0.2032)
		(layers "F.Cu" "B.Cu")
		(net "GND")
	)
	(via
		(at 22.243796 -350.977454)
		(size 0.4572)
		(drill 0.254)
		(layers "F.Cu" "B.Cu")
		(net "GND")
	)
	(via
		(at 383.94894 -27.79014)
		(size 0.508)
		(drill 0.254)
		(layers "F.Cu" "B.Cu")
		(net "GND")
	)
	(via
		(at 322.646802 -23.583646)
		(size 0.508)
		(drill 0.254)
		(layers "F.Cu" "B.Cu")
		(net "GND")
	)
	(via
		(at 132.027168 -261.942834)
		(size 0.508)
		(drill 0.254)
		(layers "F.Cu" "B.Cu")
		(net "GND")
	)
	(via
		(at 285.199836 -317.749936)
		(size 0.4064)
		(drill 0.2032)
		(layers "F.Cu" "B.Cu")
		(net "GND")
	)
	(via
		(at 393.22502 -285.924752)
		(size 0.4064)
		(drill 0.2032)
		(layers "F.Cu" "B.Cu")
		(net "GND")
	)
	(via
		(at 389.27278 -342.439498)
		(size 0.4064)
		(drill 0.2032)
		(layers "F.Cu" "B.Cu")
		(net "GND")
	)
	(via
		(at 163.747958 -403.738588)
		(size 0.508)
		(drill 0.254)
		(layers "F.Cu" "B.Cu")
		(net "GND")
	)
	(via
		(at 240.020094 -31.390336)
		(size 0.508)
		(drill 0.254)
		(layers "F.Cu" "B.Cu")
		(net "GND")
	)
	(via
		(at 351.57156 -51.661822)
		(size 0.508)
		(drill 0.254)
		(layers "F.Cu" "B.Cu")
		(net "GND")
	)
	(via
		(at 344.127836 -398.34185)
		(size 0.508)
		(drill 0.254)
		(layers "F.Cu" "B.Cu")
		(net "GND")
	)
	(via
		(at 86.747858 -407.24201)
		(size 0.508)
		(drill 0.254)
		(layers "F.Cu" "B.Cu")
		(net "GND")
	)
	(via
		(at 153.425144 -296.37482)
		(size 0.4064)
		(drill 0.2032)
		(layers "F.Cu" "B.Cu")
		(net "GND")
	)
	(via
		(at 268.574774 -292.57498)
		(size 0.4064)
		(drill 0.2032)
		(layers "F.Cu" "B.Cu")
		(net "GND")
	)
	(via
		(at 390.327896 -404.838662)
		(size 0.508)
		(drill 0.254)
		(layers "F.Cu" "B.Cu")
		(net "GND")
	)
	(via
		(at 380.90094 -33.19018)
		(size 0.508)
		(drill 0.254)
		(layers "F.Cu" "B.Cu")
		(net "GND")
	)
	(via
		(at 154.501596 -100.375466)
		(size 0.508)
		(drill 0.254)
		(layers "F.Cu" "B.Cu")
		(net "GND")
	)
	(via
		(at 292.79977 -277.849838)
		(size 0.4064)
		(drill 0.2032)
		(layers "F.Cu" "B.Cu")
		(net "GND")
	)
	(via
		(at 194.274948 -294.4749)
		(size 0.4064)
		(drill 0.2032)
		(layers "F.Cu" "B.Cu")
		(net "GND")
	)
	(via
		(at 297.549824 -319.65011)
		(size 0.4064)
		(drill 0.2032)
		(layers "F.Cu" "B.Cu")
		(net "GND")
	)
	(via
		(at 363.599222 -133.173216)
		(size 0.508)
		(drill 0.254)
		(layers "F.Cu" "B.Cu")
		(net "GND")
	)
	(via
		(at 253.513336 -33.459674)
		(size 0.508)
		(drill 0.254)
		(layers "F.Cu" "B.Cu")
		(net "GND")
	)
	(via
		(at 432.12766 -407.638504)
		(size 0.508)
		(drill 0.254)
		(layers "F.Cu" "B.Cu")
		(net "GND")
	)
	(via
		(at 31.747968 -373.83847)
		(size 0.508)
		(drill 0.254)
		(layers "F.Cu" "B.Cu")
		(net "GND")
	)
	(via
		(at 444.869824 -25.832054)
		(size 0.508)
		(drill 0.254)
		(layers "F.Cu" "B.Cu")
		(net "GND")
	)
	(via
		(at 439.584338 -34.990024)
		(size 0.508)
		(drill 0.254)
		(layers "F.Cu" "B.Cu")
		(net "GND")
	)
	(via
		(at 417.450016 -312.049922)
		(size 0.4064)
		(drill 0.2032)
		(layers "F.Cu" "B.Cu")
		(net "GND")
	)
	(via
		(at 383.05486 -342.439498)
		(size 0.4064)
		(drill 0.2032)
		(layers "F.Cu" "B.Cu")
		(net "GND")
	)
	(via
		(at 324.367906 -232.786936)
		(size 0.508)
		(drill 0.254)
		(layers "F.Cu" "B.Cu")
		(net "GND")
	)
	(via
		(at 52.999894 -277.849838)
		(size 0.4064)
		(drill 0.2032)
		(layers "F.Cu" "B.Cu")
		(net "GND")
	)
	(via
		(at 73.899776 -281.649932)
		(size 0.4064)
		(drill 0.2032)
		(layers "F.Cu" "B.Cu")
		(net "GND")
	)
	(via
		(at 291.84981 -311.099962)
		(size 0.4064)
		(drill 0.2032)
		(layers "F.Cu" "B.Cu")
		(net "GND")
	)
	(via
		(at 23.50262 -350.977454)
		(size 0.4572)
		(drill 0.254)
		(layers "F.Cu" "B.Cu")
		(net "GND")
	)
	(via
		(at 418.484558 -72.56526)
		(size 0.508)
		(drill 0.254)
		(layers "F.Cu" "B.Cu")
		(net "GND")
	)
	(via
		(at 354.472494 -222.555816)
		(size 0.508)
		(drill 0.254)
		(layers "F.Cu" "B.Cu")
		(net "GND")
	)
	(via
		(at 49.65192 -118.754906)
		(size 0.508)
		(drill 0.254)
		(layers "F.Cu" "B.Cu")
		(net "GND")
	)
	(via
		(at 339.728048 -395.938502)
		(size 0.508)
		(drill 0.254)
		(layers "F.Cu" "B.Cu")
		(net "GND")
	)
	(via
		(at 170.347894 -372.240302)
		(size 0.508)
		(drill 0.254)
		(layers "F.Cu" "B.Cu")
		(net "GND")
	)
	(via
		(at 84.808314 -145.483326)
		(size 0.508)
		(drill 0.254)
		(layers "F.Cu" "B.Cu")
		(net "GND")
	)
	(via
		(at 174.800006 -278.799798)
		(size 0.4064)
		(drill 0.2032)
		(layers "F.Cu" "B.Cu")
		(net "GND")
	)
	(via
		(at 421.127682 -376.140218)
		(size 0.508)
		(drill 0.254)
		(layers "F.Cu" "B.Cu")
		(net "GND")
	)
	(via
		(at 391.2743 -357.75773)
		(size 0.4064)
		(drill 0.2032)
		(layers "F.Cu" "B.Cu")
		(net "GND")
	)
	(via
		(at 448.009772 -235.265214)
		(size 0.508)
		(drill 0.254)
		(layers "F.Cu" "B.Cu")
		(net "GND")
	)
	(via
		(at 313.699906 -305.399948)
		(size 0.4064)
		(drill 0.2032)
		(layers "F.Cu" "B.Cu")
		(net "GND")
	)
	(via
		(at 281.874722 -297.32478)
		(size 0.4064)
		(drill 0.2032)
		(layers "F.Cu" "B.Cu")
		(net "GND")
	)
	(via
		(at 317.008256 -121.563384)
		(size 0.508)
		(drill 0.254)
		(layers "F.Cu" "B.Cu")
		(net "GND")
	)
	(via
		(at 385.624832 -294.4749)
		(size 0.4064)
		(drill 0.2032)
		(layers "F.Cu" "B.Cu")
		(net "GND")
	)
	(via
		(at 47.4726 -113.245138)
		(size 0.508)
		(drill 0.254)
		(layers "F.Cu" "B.Cu")
		(net "GND")
	)
	(via
		(at 79.59979 -310.149748)
		(size 0.4064)
		(drill 0.2032)
		(layers "F.Cu" "B.Cu")
		(net "GND")
	)
	(via
		(at 58.224928 -303.974754)
		(size 0.4064)
		(drill 0.2032)
		(layers "F.Cu" "B.Cu")
		(net "GND")
	)
	(via
		(at 413.465264 -352.245422)
		(size 0.4572)
		(drill 0.254)
		(layers "F.Cu" "B.Cu")
		(net "GND")
	)
	(via
		(at 291.32784 -397.140176)
		(size 0.508)
		(drill 0.254)
		(layers "F.Cu" "B.Cu")
		(net "GND")
	)
	(via
		(at 78.64983 -310.149748)
		(size 0.4064)
		(drill 0.2032)
		(layers "F.Cu" "B.Cu")
		(net "GND")
	)
	(via
		(at 47.29988 -314.899802)
		(size 0.4064)
		(drill 0.2032)
		(layers "F.Cu" "B.Cu")
		(net "GND")
	)
	(via
		(at 19.134836 -346.09913)
		(size 0.4572)
		(drill 0.254)
		(layers "F.Cu" "B.Cu")
		(net "GND")
	)
	(via
		(at 308.949852 -279.749758)
		(size 0.4064)
		(drill 0.2032)
		(layers "F.Cu" "B.Cu")
		(net "GND")
	)
	(via
		(at 59.649868 -316.799722)
		(size 0.4064)
		(drill 0.2032)
		(layers "F.Cu" "B.Cu")
		(net "GND")
	)
	(via
		(at 259.868924 -289.532314)
		(size 0.508)
		(drill 0.254)
		(layers "F.Cu" "B.Cu")
		(net "GND")
	)
	(via
		(at 317.499746 -62.812168)
		(size 0.508)
		(drill 0.254)
		(layers "F.Cu" "B.Cu")
		(net "GND")
	)
	(via
		(at 58.224928 -284.974792)
		(size 0.4064)
		(drill 0.2032)
		(layers "F.Cu" "B.Cu")
		(net "GND")
	)
	(via
		(at 200.908158 -125.163326)
		(size 0.508)
		(drill 0.254)
		(layers "F.Cu" "B.Cu")
		(net "GND")
	)
	(via
		(at 165.299898 -276.899878)
		(size 0.4064)
		(drill 0.2032)
		(layers "F.Cu" "B.Cu")
		(net "GND")
	)
	(via
		(at 115.34775 -403.738588)
		(size 0.508)
		(drill 0.254)
		(layers "F.Cu" "B.Cu")
		(net "GND")
	)
	(via
		(at 300.047914 -358.391714)
		(size 0.4572)
		(drill 0.254)
		(layers "F.Cu" "B.Cu")
		(net "GND")
	)
	(via
		(at 360.83875 -305.91887)
		(size 0.508)
		(drill 0.254)
		(layers "F.Cu" "B.Cu")
		(net "GND")
	)
	(via
		(at 126.90856 -218.830652)
		(size 0.508)
		(drill 0.254)
		(layers "F.Cu" "B.Cu")
		(net "GND")
	)
	(via
		(at 108.634022 -129.29108)
		(size 0.508)
		(drill 0.254)
		(layers "F.Cu" "B.Cu")
		(net "GND")
	)
	(via
		(at 79.457042 -354.732082)
		(size 0.4064)
		(drill 0.2032)
		(layers "F.Cu" "B.Cu")
		(net "GND")
	)
	(via
		(at 243.551456 -311.711086)
		(size 0.508)
		(drill 0.254)
		(layers "F.Cu" "B.Cu")
		(net "GND")
	)
	(via
		(at 169.587164 -100.64496)
		(size 0.508)
		(drill 0.254)
		(layers "F.Cu" "B.Cu")
		(net "GND")
	)
	(via
		(at 88.579198 -95.348044)
		(size 0.508)
		(drill 0.254)
		(layers "F.Cu" "B.Cu")
		(net "GND")
	)
	(via
		(at 159.124904 -290.674806)
		(size 0.4064)
		(drill 0.2032)
		(layers "F.Cu" "B.Cu")
		(net "GND")
	)
	(via
		(at 407.949908 -312.049922)
		(size 0.4064)
		(drill 0.2032)
		(layers "F.Cu" "B.Cu")
		(net "GND")
	)
	(via
		(at 175.683164 -355.366066)
		(size 0.4572)
		(drill 0.254)
		(layers "F.Cu" "B.Cu")
		(net "GND")
	)
	(via
		(at 119.25173 -258.394962)
		(size 0.508)
		(drill 0.254)
		(layers "F.Cu" "B.Cu")
		(net "GND")
	)
	(via
		(at 167.732964 -131.76504)
		(size 0.508)
		(drill 0.254)
		(layers "F.Cu" "B.Cu")
		(net "GND")
	)
	(via
		(at 133.055868 -354.732082)
		(size 0.4064)
		(drill 0.2032)
		(layers "F.Cu" "B.Cu")
		(net "GND")
	)
	(via
		(at 77.69987 -277.849838)
		(size 0.4064)
		(drill 0.2032)
		(layers "F.Cu" "B.Cu")
		(net "GND")
	)
	(via
		(at 48.58131 -33.459674)
		(size 0.508)
		(drill 0.254)
		(layers "F.Cu" "B.Cu")
		(net "GND")
	)
	(via
		(at 394.17498 -283.074872)
		(size 0.4064)
		(drill 0.2032)
		(layers "F.Cu" "B.Cu")
		(net "GND")
	)
	(via
		(at 163.247324 -357.123746)
		(size 0.4572)
		(drill 0.254)
		(layers "F.Cu" "B.Cu")
		(net "GND")
	)
	(via
		(at 367.523776 -153.782522)
		(size 0.508)
		(drill 0.254)
		(layers "F.Cu" "B.Cu")
		(net "GND")
	)
	(via
		(at 60.455048 -29.590238)
		(size 0.508)
		(drill 0.254)
		(layers "F.Cu" "B.Cu")
		(net "GND")
	)
	(via
		(at 167.200072 -278.799798)
		(size 0.4064)
		(drill 0.2032)
		(layers "F.Cu" "B.Cu")
		(net "GND")
	)
	(via
		(at 75.74788 -382.84023)
		(size 0.508)
		(drill 0.254)
		(layers "F.Cu" "B.Cu")
		(net "GND")
	)
	(via
		(at 38.347904 -406.040336)
		(size 0.508)
		(drill 0.254)
		(layers "F.Cu" "B.Cu")
		(net "GND")
	)
	(via
		(at 386.574792 -299.224954)
		(size 0.4064)
		(drill 0.2032)
		(layers "F.Cu" "B.Cu")
		(net "GND")
	)
	(via
		(at 323.262244 -345.465146)
		(size 0.4064)
		(drill 0.2032)
		(layers "F.Cu" "B.Cu")
		(net "GND")
	)
	(via
		(at 418.874956 -285.924752)
		(size 0.4064)
		(drill 0.2032)
		(layers "F.Cu" "B.Cu")
		(net "GND")
	)
	(via
		(at 117.370606 -28.802076)
		(size 0.508)
		(drill 0.254)
		(layers "F.Cu" "B.Cu")
		(net "GND")
	)
	(via
		(at 327.849992 -344.831162)
		(size 0.4572)
		(drill 0.254)
		(layers "F.Cu" "B.Cu")
		(net "GND")
	)
	(via
		(at 63.798196 -19.096736)
		(size 0.508)
		(drill 0.254)
		(layers "F.Cu" "B.Cu")
		(net "GND")
	)
	(via
		(at 326.757792 -57.521094)
		(size 0.508)
		(drill 0.254)
		(layers "F.Cu" "B.Cu")
		(net "GND")
	)
	(via
		(at 418.496242 -60.099194)
		(size 0.508)
		(drill 0.254)
		(layers "F.Cu" "B.Cu")
		(net "GND")
	)
	(via
		(at 121.947686 -371.038628)
		(size 0.508)
		(drill 0.254)
		(layers "F.Cu" "B.Cu")
		(net "GND")
	)
	(via
		(at 399.400014 -314.899802)
		(size 0.4064)
		(drill 0.2032)
		(layers "F.Cu" "B.Cu")
		(net "GND")
	)
	(via
		(at 237.849918 -317.698882)
		(size 0.508)
		(drill 0.254)
		(layers "F.Cu" "B.Cu")
		(net "GND")
	)
	(via
		(at 437.980836 -25.990042)
		(size 0.508)
		(drill 0.254)
		(layers "F.Cu" "B.Cu")
		(net "GND")
	)
	(via
		(at 418.927788 -369.938554)
		(size 0.508)
		(drill 0.254)
		(layers "F.Cu" "B.Cu")
		(net "GND")
	)
	(via
		(at 330.958952 -343.073482)
		(size 0.4572)
		(drill 0.254)
		(layers "F.Cu" "B.Cu")
		(net "GND")
	)
	(via
		(at 397.49222 -342.439498)
		(size 0.4064)
		(drill 0.2032)
		(layers "F.Cu" "B.Cu")
		(net "GND")
	)
	(via
		(at 274.274788 -289.724846)
		(size 0.4064)
		(drill 0.2032)
		(layers "F.Cu" "B.Cu")
		(net "GND")
	)
	(via
		(at 178.124866 -302.074834)
		(size 0.4064)
		(drill 0.2032)
		(layers "F.Cu" "B.Cu")
		(net "GND")
	)
	(via
		(at 77.22489 -293.52494)
		(size 0.4064)
		(drill 0.2032)
		(layers "F.Cu" "B.Cu")
		(net "GND")
	)
	(via
		(at 315.740288 -156.283406)
		(size 0.508)
		(drill 0.254)
		(layers "F.Cu" "B.Cu")
		(net "GND")
	)
	(via
		(at 68.651374 -341.805514)
		(size 0.4572)
		(drill 0.254)
		(layers "F.Cu" "B.Cu")
		(net "GND")
	)
	(via
		(at 104.619044 -106.779822)
		(size 0.508)
		(drill 0.254)
		(layers "F.Cu" "B.Cu")
		(net "GND")
	)
	(via
		(at 157.224984 -290.674806)
		(size 0.4064)
		(drill 0.2032)
		(layers "F.Cu" "B.Cu")
		(net "GND")
	)
	(via
		(at 55.84952 -272.14957)
		(size 0.4064)
		(drill 0.2032)
		(layers "F.Cu" "B.Cu")
		(net "GND")
	)
	(via
		(at 69.149722 -272.14957)
		(size 0.4064)
		(drill 0.2032)
		(layers "F.Cu" "B.Cu")
		(net "GND")
	)
	(via
		(at 132.219192 -326.943974)
		(size 0.508)
		(drill 0.254)
		(layers "F.Cu" "B.Cu")
		(net "GND")
	)
	(via
		(at 268.574774 -289.724846)
		(size 0.4064)
		(drill 0.2032)
		(layers "F.Cu" "B.Cu")
		(net "GND")
	)
	(via
		(at 182.87492 -285.924752)
		(size 0.4064)
		(drill 0.2032)
		(layers "F.Cu" "B.Cu")
		(net "GND")
	)
	(via
		(at 38.749986 -319.65011)
		(size 0.4064)
		(drill 0.2032)
		(layers "F.Cu" "B.Cu")
		(net "GND")
	)
	(via
		(at 54.787038 -0.762)
		(size 0.508)
		(drill 0.254)
		(layers "F.Cu" "B.Cu")
		(net "GND")
	)
	(via
		(at 168.625012 -298.27474)
		(size 0.4064)
		(drill 0.2032)
		(layers "F.Cu" "B.Cu")
		(net "GND")
	)
	(via
		(at 355.154738 -235.270294)
		(size 0.508)
		(drill 0.254)
		(layers "F.Cu" "B.Cu")
		(net "GND")
	)
	(via
		(at 54.424834 -285.924752)
		(size 0.4064)
		(drill 0.2032)
		(layers "F.Cu" "B.Cu")
		(net "GND")
	)
	(via
		(at 37.133784 -99.116642)
		(size 0.508)
		(drill 0.254)
		(layers "F.Cu" "B.Cu")
		(net "GND")
	)
	(via
		(at 394.011912 -343.073482)
		(size 0.4572)
		(drill 0.254)
		(layers "F.Cu" "B.Cu")
		(net "GND")
	)
	(via
		(at 312.274712 -294.4749)
		(size 0.4064)
		(drill 0.2032)
		(layers "F.Cu" "B.Cu")
		(net "GND")
	)
	(via
		(at 86.747858 -400.938492)
		(size 0.508)
		(drill 0.254)
		(layers "F.Cu" "B.Cu")
		(net "GND")
	)
	(via
		(at 156.002228 -58.731404)
		(size 0.508)
		(drill 0.254)
		(layers "F.Cu" "B.Cu")
		(net "GND")
	)
	(via
		(at 170.999912 -274.049744)
		(size 0.4064)
		(drill 0.2032)
		(layers "F.Cu" "B.Cu")
		(net "GND")
	)
	(via
		(at 202.555094 -33.19018)
		(size 0.508)
		(drill 0.254)
		(layers "F.Cu" "B.Cu")
		(net "GND")
	)
	(via
		(at 74.248264 -152.95499)
		(size 0.508)
		(drill 0.254)
		(layers "F.Cu" "B.Cu")
		(net "GND")
	)
	(via
		(at 85.942932 -140.934694)
		(size 0.508)
		(drill 0.254)
		(layers "F.Cu" "B.Cu")
		(net "GND")
	)
	(via
		(at 411.750002 -281.649932)
		(size 0.4064)
		(drill 0.2032)
		(layers "F.Cu" "B.Cu")
		(net "GND")
	)
	(via
		(at 203.742544 -114.892836)
		(size 0.508)
		(drill 0.254)
		(layers "F.Cu" "B.Cu")
		(net "GND")
	)
	(via
		(at 176.699926 -273.099784)
		(size 0.4064)
		(drill 0.2032)
		(layers "F.Cu" "B.Cu")
		(net "GND")
	)
	(via
		(at 97.939098 -29.311854)
		(size 0.508)
		(drill 0.254)
		(layers "F.Cu" "B.Cu")
		(net "GND")
	)
	(via
		(at 332.217776 -352.245422)
		(size 0.4572)
		(drill 0.254)
		(layers "F.Cu" "B.Cu")
		(net "GND")
	)
	(via
		(at 281.629358 -47.020734)
		(size 0.508)
		(drill 0.254)
		(layers "F.Cu" "B.Cu")
		(net "GND")
	)
	(via
		(at 45.87494 -285.924752)
		(size 0.4064)
		(drill 0.2032)
		(layers "F.Cu" "B.Cu")
		(net "GND")
	)
	(via
		(at 420.45509 -96.901)
		(size 0.508)
		(drill 0.254)
		(layers "F.Cu" "B.Cu")
		(net "GND")
	)
	(via
		(at 397.120872 -357.123746)
		(size 0.4572)
		(drill 0.254)
		(layers "F.Cu" "B.Cu")
		(net "GND")
	)
	(via
		(at 300.399704 -312.999882)
		(size 0.4064)
		(drill 0.2032)
		(layers "F.Cu" "B.Cu")
		(net "GND")
	)
	(via
		(at 11.22553 -383.864866)
		(size 0.508)
		(drill 0.254)
		(layers "F.Cu" "B.Cu")
		(net "GND")
	)
	(via
		(at 55.374794 -291.624766)
		(size 0.4064)
		(drill 0.2032)
		(layers "F.Cu" "B.Cu")
		(net "GND")
	)
	(via
		(at 429.010064 -344.831162)
		(size 0.4572)
		(drill 0.254)
		(layers "F.Cu" "B.Cu")
		(net "GND")
	)
	(via
		(at 229.09276 -313.029346)
		(size 0.508)
		(drill 0.254)
		(layers "F.Cu" "B.Cu")
		(net "GND")
	)
	(via
		(at 427.42485 -298.27474)
		(size 0.4064)
		(drill 0.2032)
		(layers "F.Cu" "B.Cu")
		(net "GND")
	)
	(via
		(at 124.147834 -372.341902)
		(size 0.4572)
		(drill 0.254)
		(layers "F.Cu" "B.Cu")
		(net "GND")
	)
	(via
		(at 153.233628 -102.716584)
		(size 0.508)
		(drill 0.254)
		(layers "F.Cu" "B.Cu")
		(net "GND")
	)
	(via
		(at 386.535168 -346.09913)
		(size 0.4572)
		(drill 0.254)
		(layers "F.Cu" "B.Cu")
		(net "GND")
	)
	(via
		(at 192.375028 -299.224954)
		(size 0.4064)
		(drill 0.2032)
		(layers "F.Cu" "B.Cu")
		(net "GND")
	)
	(via
		(at 275.685504 -63.218314)
		(size 0.508)
		(drill 0.254)
		(layers "F.Cu" "B.Cu")
		(net "GND")
	)
	(via
		(at 142.035784 -214.959184)
		(size 0.508)
		(drill 0.254)
		(layers "F.Cu" "B.Cu")
		(net "GND")
	)
	(via
		(at 77.700124 -274.049744)
		(size 0.4064)
		(drill 0.2032)
		(layers "F.Cu" "B.Cu")
		(net "GND")
	)
	(via
		(at 396.0749 -285.924752)
		(size 0.4064)
		(drill 0.2032)
		(layers "F.Cu" "B.Cu")
		(net "GND")
	)
	(via
		(at 289.47491 -284.024832)
		(size 0.4064)
		(drill 0.2032)
		(layers "F.Cu" "B.Cu")
		(net "GND")
	)
	(via
		(at 313.564016 -344.831162)
		(size 0.4572)
		(drill 0.254)
		(layers "F.Cu" "B.Cu")
		(net "GND")
	)
	(via
		(at 193.0781 -343.073482)
		(size 0.4572)
		(drill 0.254)
		(layers "F.Cu" "B.Cu")
		(net "GND")
	)
	(via
		(at 36.14801 -369.938554)
		(size 0.508)
		(drill 0.254)
		(layers "F.Cu" "B.Cu")
		(net "GND")
	)
	(via
		(at 110.165896 -110.22965)
		(size 0.508)
		(drill 0.254)
		(layers "F.Cu" "B.Cu")
		(net "GND")
	)
	(via
		(at 71.524876 -298.27474)
		(size 0.4064)
		(drill 0.2032)
		(layers "F.Cu" "B.Cu")
		(net "GND")
	)
	(via
		(at 348.330266 -250.626118)
		(size 0.508)
		(drill 0.254)
		(layers "F.Cu" "B.Cu")
		(net "GND")
	)
	(via
		(at 275.224748 -284.024832)
		(size 0.4064)
		(drill 0.2032)
		(layers "F.Cu" "B.Cu")
		(net "GND")
	)
	(via
		(at 300.48073 -27.79014)
		(size 0.508)
		(drill 0.254)
		(layers "F.Cu" "B.Cu")
		(net "GND")
	)
	(via
		(at 63.449962 -275.949918)
		(size 0.4064)
		(drill 0.2032)
		(layers "F.Cu" "B.Cu")
		(net "GND")
	)
	(via
		(at 420.299896 -314.899802)
		(size 0.4064)
		(drill 0.2032)
		(layers "F.Cu" "B.Cu")
		(net "GND")
	)
	(via
		(at 61.790072 -381.483362)
		(size 0.508)
		(drill 0.254)
		(layers "F.Cu" "B.Cu")
		(net "GND")
	)
	(via
		(at 364.858046 -58.156094)
		(size 0.508)
		(drill 0.254)
		(layers "F.Cu" "B.Cu")
		(net "GND")
	)
	(via
		(at 176.699926 -277.849838)
		(size 0.4064)
		(drill 0.2032)
		(layers "F.Cu" "B.Cu")
		(net "GND")
	)
	(via
		(at 379.327918 -381.638556)
		(size 0.508)
		(drill 0.254)
		(layers "F.Cu" "B.Cu")
		(net "GND")
	)
	(via
		(at 284.249876 -281.649932)
		(size 0.4064)
		(drill 0.2032)
		(layers "F.Cu" "B.Cu")
		(net "GND")
	)
	(via
		(at 170.347894 -374.938544)
		(size 0.508)
		(drill 0.254)
		(layers "F.Cu" "B.Cu")
		(net "GND")
	)
	(via
		(at 274.274788 -274.524978)
		(size 0.4064)
		(drill 0.2032)
		(layers "F.Cu" "B.Cu")
		(net "GND")
	)
	(via
		(at 185.599578 -57.439814)
		(size 0.508)
		(drill 0.254)
		(layers "F.Cu" "B.Cu")
		(net "GND")
	)
	(via
		(at 277.599902 -276.899878)
		(size 0.4064)
		(drill 0.2032)
		(layers "F.Cu" "B.Cu")
		(net "GND")
	)
	(via
		(at 169.587164 -120.555004)
		(size 0.508)
		(drill 0.254)
		(layers "F.Cu" "B.Cu")
		(net "GND")
	)
	(via
		(at 288.99993 -277.849838)
		(size 0.4064)
		(drill 0.2032)
		(layers "F.Cu" "B.Cu")
		(net "GND")
	)
	(via
		(at 29.54782 -376.140218)
		(size 0.508)
		(drill 0.254)
		(layers "F.Cu" "B.Cu")
		(net "GND")
	)
	(via
		(at 46.34992 -275.949918)
		(size 0.4064)
		(drill 0.2032)
		(layers "F.Cu" "B.Cu")
		(net "GND")
	)
	(via
		(at 232.51033 -92.255848)
		(size 0.508)
		(drill 0.254)
		(layers "F.Cu" "B.Cu")
		(net "GND")
	)
	(via
		(at 122.550936 -112.907318)
		(size 0.508)
		(drill 0.254)
		(layers "F.Cu" "B.Cu")
		(net "GND")
	)
	(via
		(at 260.83641 -51.661822)
		(size 0.508)
		(drill 0.254)
		(layers "F.Cu" "B.Cu")
		(net "GND")
	)
	(via
		(at 330.958952 -347.951806)
		(size 0.4572)
		(drill 0.254)
		(layers "F.Cu" "B.Cu")
		(net "GND")
	)
	(via
		(at 396.88135 -29.859478)
		(size 0.508)
		(drill 0.254)
		(layers "F.Cu" "B.Cu")
		(net "GND")
	)
	(via
		(at 169.836592 -354.732082)
		(size 0.4064)
		(drill 0.2032)
		(layers "F.Cu" "B.Cu")
		(net "GND")
	)
	(via
		(at 198.075042 -301.124874)
		(size 0.4064)
		(drill 0.2032)
		(layers "F.Cu" "B.Cu")
		(net "GND")
	)
	(via
		(at 8.455152 -27.79014)
		(size 0.508)
		(drill 0.254)
		(layers "F.Cu" "B.Cu")
		(net "GND")
	)
	(via
		(at 125.709172 -289.41649)
		(size 0.508)
		(drill 0.254)
		(layers "F.Cu" "B.Cu")
		(net "GND")
	)
	(via
		(at 313.699906 -284.499812)
		(size 0.4064)
		(drill 0.2032)
		(layers "F.Cu" "B.Cu")
		(net "GND")
	)
	(via
		(at 171.949872 -311.099962)
		(size 0.4064)
		(drill 0.2032)
		(layers "F.Cu" "B.Cu")
		(net "GND")
	)
	(via
		(at 35.6489 -29.589984)
		(size 0.508)
		(drill 0.254)
		(layers "F.Cu" "B.Cu")
		(net "GND")
	)
	(via
		(at 366.06988 -289.41649)
		(size 0.508)
		(drill 0.254)
		(layers "F.Cu" "B.Cu")
		(net "GND")
	)
	(via
		(at 222.576644 -174.49038)
		(size 0.508)
		(drill 0.254)
		(layers "F.Cu" "B.Cu")
		(net "GND")
	)
	(via
		(at 56.452262 -365.374682)
		(size 0.508)
		(drill 0.254)
		(layers "F.Cu" "B.Cu")
		(net "GND")
	)
	(via
		(at 396.88135 -33.459674)
		(size 0.508)
		(drill 0.254)
		(layers "F.Cu" "B.Cu")
		(net "GND")
	)
	(via
		(at 40.649906 -308.249828)
		(size 0.4064)
		(drill 0.2032)
		(layers "F.Cu" "B.Cu")
		(net "GND")
	)
	(via
		(at 466.827616 -6.292596)
		(size 0.508)
		(drill 0.254)
		(layers "F.Cu" "B.Cu")
		(net "GND")
	)
	(via
		(at 363.23778 -284.333188)
		(size 0.49022)
		(drill 0.254)
		(layers "F.Cu" "B.Cu")
		(net "GND")
	)
	(via
		(at 190.348108 -125.435106)
		(size 0.508)
		(drill 0.254)
		(layers "F.Cu" "B.Cu")
		(net "GND")
	)
	(via
		(at 270.646906 -23.583646)
		(size 0.508)
		(drill 0.254)
		(layers "F.Cu" "B.Cu")
		(net "GND")
	)
	(via
		(at 224.318068 -320.02349)
		(size 0.508)
		(drill 0.254)
		(layers "F.Cu" "B.Cu")
		(net "GND")
	)
	(via
		(at 380.649734 -3.820922)
		(size 0.508)
		(drill 0.254)
		(layers "F.Cu" "B.Cu")
		(net "GND")
	)
	(via
		(at 167.812212 -23.355554)
		(size 0.508)
		(drill 0.254)
		(layers "F.Cu" "B.Cu")
		(net "GND")
	)
	(via
		(at 354.625402 -220.623638)
		(size 0.508)
		(drill 0.254)
		(layers "F.Cu" "B.Cu")
		(net "GND")
	)
	(via
		(at 394.17498 -301.124874)
		(size 0.4064)
		(drill 0.2032)
		(layers "F.Cu" "B.Cu")
		(net "GND")
	)
	(via
		(at 183.75122 -354.074222)
		(size 0.4572)
		(drill 0.254)
		(layers "F.Cu" "B.Cu")
		(net "GND")
	)
	(via
		(at 375.623328 -54.067456)
		(size 0.508)
		(drill 0.254)
		(layers "F.Cu" "B.Cu")
		(net "GND")
	)
	(via
		(at 40.174926 -289.724846)
		(size 0.4064)
		(drill 0.2032)
		(layers "F.Cu" "B.Cu")
		(net "GND")
	)
	(via
		(at 422.199816 -284.499812)
		(size 0.4064)
		(drill 0.2032)
		(layers "F.Cu" "B.Cu")
		(net "GND")
	)
	(via
		(at 112.92332 -343.073482)
		(size 0.4572)
		(drill 0.254)
		(layers "F.Cu" "B.Cu")
		(net "GND")
	)
	(via
		(at 427.42485 -292.574726)
		(size 0.4064)
		(drill 0.2032)
		(layers "F.Cu" "B.Cu")
		(net "GND")
	)
	(via
		(at 174.325026 -293.52494)
		(size 0.4064)
		(drill 0.2032)
		(layers "F.Cu" "B.Cu")
		(net "GND")
	)
	(via
		(at 45.051726 -120.555004)
		(size 0.508)
		(drill 0.254)
		(layers "F.Cu" "B.Cu")
		(net "GND")
	)
	(via
		(at 120.991376 -355.366066)
		(size 0.4572)
		(drill 0.254)
		(layers "F.Cu" "B.Cu")
		(net "GND")
	)
	(via
		(at 61.17463 -344.831162)
		(size 0.4572)
		(drill 0.254)
		(layers "F.Cu" "B.Cu")
		(net "GND")
	)
	(via
		(at 214.773002 -23.880318)
		(size 0.508)
		(drill 0.254)
		(layers "F.Cu" "B.Cu")
		(net "GND")
	)
	(via
		(at 211.722716 -23.880318)
		(size 0.508)
		(drill 0.254)
		(layers "F.Cu" "B.Cu")
		(net "GND")
	)
	(via
		(at 285.93669 -15.474188)
		(size 0.508)
		(drill 0.254)
		(layers "F.Cu" "B.Cu")
		(net "GND")
	)
	(via
		(at 349.410782 -287.51149)
		(size 0.508)
		(drill 0.254)
		(layers "F.Cu" "B.Cu")
		(net "GND")
	)
	(via
		(at 231.067356 -219.504006)
		(size 0.4572)
		(drill 0.254)
		(layers "F.Cu" "B.Cu")
		(net "GND")
	)
	(via
		(at 7.72414 -309.498238)
		(size 0.508)
		(drill 0.254)
		(layers "F.Cu" "B.Cu")
		(net "GND")
	)
	(via
		(at 280.449782 -280.699718)
		(size 0.4064)
		(drill 0.2032)
		(layers "F.Cu" "B.Cu")
		(net "GND")
	)
	(via
		(at 359.535476 -289.41649)
		(size 0.508)
		(drill 0.254)
		(layers "F.Cu" "B.Cu")
		(net "GND")
	)
	(via
		(at 99.666298 -87.00897)
		(size 0.508)
		(drill 0.254)
		(layers "F.Cu" "B.Cu")
		(net "GND")
	)
	(via
		(at 191.900048 -303.499774)
		(size 0.4064)
		(drill 0.2032)
		(layers "F.Cu" "B.Cu")
		(net "GND")
	)
	(via
		(at 270.949928 -316.799722)
		(size 0.4064)
		(drill 0.2032)
		(layers "F.Cu" "B.Cu")
		(net "GND")
	)
	(via
		(at 175.399954 -62.812168)
		(size 0.508)
		(drill 0.254)
		(layers "F.Cu" "B.Cu")
		(net "GND")
	)
	(via
		(at 99.960176 -20.35556)
		(size 0.508)
		(drill 0.254)
		(layers "F.Cu" "B.Cu")
		(net "GND")
	)
	(via
		(at 62.974982 -302.074834)
		(size 0.4064)
		(drill 0.2032)
		(layers "F.Cu" "B.Cu")
		(net "GND")
	)
	(via
		(at 430.749964 -280.699718)
		(size 0.4064)
		(drill 0.2032)
		(layers "F.Cu" "B.Cu")
		(net "GND")
	)
	(via
		(at 115.878102 -326.841104)
		(size 0.508)
		(drill 0.254)
		(layers "F.Cu" "B.Cu")
		(net "GND")
	)
	(via
		(at 84.196174 -349.219774)
		(size 0.4572)
		(drill 0.254)
		(layers "F.Cu" "B.Cu")
		(net "GND")
	)
	(via
		(at 83.540346 -120.30456)
		(size 0.508)
		(drill 0.254)
		(layers "F.Cu" "B.Cu")
		(net "GND")
	)
	(via
		(at 80.147922 -377.738386)
		(size 0.508)
		(drill 0.254)
		(layers "F.Cu" "B.Cu")
		(net "GND")
	)
	(via
		(at 278.285194 -347.951806)
		(size 0.4572)
		(drill 0.254)
		(layers "F.Cu" "B.Cu")
		(net "GND")
	)
	(via
		(at 385.261104 -260.338316)
		(size 0.508)
		(drill 0.254)
		(layers "F.Cu" "B.Cu")
		(net "GND")
	)
	(via
		(at 154.850084 -302.549814)
		(size 0.4064)
		(drill 0.2032)
		(layers "F.Cu" "B.Cu")
		(net "GND")
	)
	(via
		(at 379.476 -224.536)
		(size 0.508)
		(drill 0.254)
		(layers "F.Cu" "B.Cu")
		(net "GND")
	)
	(via
		(at 437.07812 -349.219774)
		(size 0.4572)
		(drill 0.254)
		(layers "F.Cu" "B.Cu")
		(net "GND")
	)
	(via
		(at 162.924998 -305.874928)
		(size 0.4064)
		(drill 0.2032)
		(layers "F.Cu" "B.Cu")
		(net "GND")
	)
	(via
		(at 301.822612 -23.880318)
		(size 0.508)
		(drill 0.254)
		(layers "F.Cu" "B.Cu")
		(net "GND")
	)
	(via
		(at 420.567104 -125.435106)
		(size 0.508)
		(drill 0.254)
		(layers "F.Cu" "B.Cu")
		(net "GND")
	)
	(via
		(at 64.874902 -287.824926)
		(size 0.4064)
		(drill 0.2032)
		(layers "F.Cu" "B.Cu")
		(net "GND")
	)
	(via
		(at 408.899868 -317.749936)
		(size 0.4064)
		(drill 0.2032)
		(layers "F.Cu" "B.Cu")
		(net "GND")
	)
	(via
		(at 44.94784 -403.738588)
		(size 0.508)
		(drill 0.254)
		(layers "F.Cu" "B.Cu")
		(net "GND")
	)
	(via
		(at 15.118588 -114.013996)
		(size 0.508)
		(drill 0.254)
		(layers "F.Cu" "B.Cu")
		(net "GND")
	)
	(via
		(at 74.248264 -156.554932)
		(size 0.508)
		(drill 0.254)
		(layers "F.Cu" "B.Cu")
		(net "GND")
	)
	(via
		(at 271.899888 -317.749936)
		(size 0.4064)
		(drill 0.2032)
		(layers "F.Cu" "B.Cu")
		(net "GND")
	)
	(via
		(at 39.418768 -351.611438)
		(size 0.4064)
		(drill 0.2032)
		(layers "F.Cu" "B.Cu")
		(net "GND")
	)
	(via
		(at 409.09748 -352.245422)
		(size 0.4572)
		(drill 0.254)
		(layers "F.Cu" "B.Cu")
		(net "GND")
	)
	(via
		(at 438.098184 -19.757136)
		(size 0.508)
		(drill 0.254)
		(layers "F.Cu" "B.Cu")
		(net "GND")
	)
	(via
		(at 340.093808 -221.98711)
		(size 0.4572)
		(drill 0.254)
		(layers "F.Cu" "B.Cu")
		(net "GND")
	)
	(via
		(at 279.232868 -100.64496)
		(size 0.508)
		(drill 0.254)
		(layers "F.Cu" "B.Cu")
		(net "GND")
	)
	(via
		(at 216.681304 -33.459674)
		(size 0.508)
		(drill 0.254)
		(layers "F.Cu" "B.Cu")
		(net "GND")
	)
	(via
		(at 466.835998 -282.763976)
		(size 0.508)
		(drill 0.254)
		(layers "F.Cu" "B.Cu")
		(net "GND")
	)
	(via
		(at 348.527878 -404.940262)
		(size 0.508)
		(drill 0.254)
		(layers "F.Cu" "B.Cu")
		(net "GND")
	)
	(via
		(at 193.799968 -277.849838)
		(size 0.4064)
		(drill 0.2032)
		(layers "F.Cu" "B.Cu")
		(net "GND")
	)
	(via
		(at 422.551352 -47.03191)
		(size 0.508)
		(drill 0.254)
		(layers "F.Cu" "B.Cu")
		(net "GND")
	)
	(via
		(at 265.204448 -197.82409)
		(size 0.508)
		(drill 0.254)
		(layers "F.Cu" "B.Cu")
		(net "GND")
	)
	(via
		(at 65.349882 -319.65011)
		(size 0.4064)
		(drill 0.2032)
		(layers "F.Cu" "B.Cu")
		(net "GND")
	)
	(via
		(at 113.503202 -279.000712)
		(size 0.508)
		(drill 0.254)
		(layers "F.Cu" "B.Cu")
		(net "GND")
	)
	(via
		(at 274.274788 -296.37482)
		(size 0.4064)
		(drill 0.2032)
		(layers "F.Cu" "B.Cu")
		(net "GND")
	)
	(via
		(at 192.075054 -73.87463)
		(size 0.508)
		(drill 0.254)
		(layers "F.Cu" "B.Cu")
		(net "GND")
	)
	(via
		(at 275.224748 -272.624804)
		(size 0.4064)
		(drill 0.2032)
		(layers "F.Cu" "B.Cu")
		(net "GND")
	)
	(via
		(at 298.024804 -297.32478)
		(size 0.4064)
		(drill 0.2032)
		(layers "F.Cu" "B.Cu")
		(net "GND")
	)
	(via
		(at 29.72054 -350.977454)
		(size 0.4572)
		(drill 0.254)
		(layers "F.Cu" "B.Cu")
		(net "GND")
	)
	(via
		(at 414.944052 -342.439498)
		(size 0.4064)
		(drill 0.2032)
		(layers "F.Cu" "B.Cu")
		(net "GND")
	)
	(via
		(at 157.699964 -317.749936)
		(size 0.4064)
		(drill 0.2032)
		(layers "F.Cu" "B.Cu")
		(net "GND")
	)
	(via
		(at 75.32497 -296.37482)
		(size 0.4064)
		(drill 0.2032)
		(layers "F.Cu" "B.Cu")
		(net "GND")
	)
	(via
		(at 38.274752 -296.37482)
		(size 0.4064)
		(drill 0.2032)
		(layers "F.Cu" "B.Cu")
		(net "GND")
	)
	(via
		(at 128.547622 -382.84023)
		(size 0.4572)
		(drill 0.254)
		(layers "F.Cu" "B.Cu")
		(net "GND")
	)
	(via
		(at 289.47491 -302.074834)
		(size 0.4064)
		(drill 0.2032)
		(layers "F.Cu" "B.Cu")
		(net "GND")
	)
	(via
		(at 424.64228 -343.073482)
		(size 0.4572)
		(drill 0.254)
		(layers "F.Cu" "B.Cu")
		(net "GND")
	)
	(via
		(at 402.079968 -350.977454)
		(size 0.4572)
		(drill 0.254)
		(layers "F.Cu" "B.Cu")
		(net "GND")
	)
	(via
		(at 331.574648 -202.961494)
		(size 0.508)
		(drill 0.254)
		(layers "F.Cu" "B.Cu")
		(net "GND")
	)
	(via
		(at 140.075158 -74.58583)
		(size 0.508)
		(drill 0.254)
		(layers "F.Cu" "B.Cu")
		(net "GND")
	)
	(via
		(at 161.500058 -274.049744)
		(size 0.4064)
		(drill 0.2032)
		(layers "F.Cu" "B.Cu")
		(net "GND")
	)
	(via
		(at 68.674742 -284.024832)
		(size 0.4064)
		(drill 0.2032)
		(layers "F.Cu" "B.Cu")
		(net "GND")
	)
	(via
		(at 123.631452 -150.16861)
		(size 0.508)
		(drill 0.254)
		(layers "F.Cu" "B.Cu")
		(net "GND")
	)
	(via
		(at 251.234448 -47.936658)
		(size 0.508)
		(drill 0.254)
		(layers "F.Cu" "B.Cu")
		(net "GND")
	)
	(via
		(at 439.218578 -294.50157)
		(size 0.508)
		(drill 0.254)
		(layers "F.Cu" "B.Cu")
		(net "GND")
	)
	(via
		(at 261.929626 -241.280188)
		(size 0.508)
		(drill 0.254)
		(layers "F.Cu" "B.Cu")
		(net "GND")
	)
	(via
		(at 46.34992 -302.549814)
		(size 0.4064)
		(drill 0.2032)
		(layers "F.Cu" "B.Cu")
		(net "GND")
	)
	(via
		(at 297.927776 -373.441976)
		(size 0.508)
		(drill 0.254)
		(layers "F.Cu" "B.Cu")
		(net "GND")
	)
	(via
		(at 360.96448 -285.953454)
		(size 0.508)
		(drill 0.254)
		(layers "F.Cu" "B.Cu")
		(net "GND")
	)
	(via
		(at 131.589018 -177.642012)
		(size 0.508)
		(drill 0.254)
		(layers "F.Cu" "B.Cu")
		(net "GND")
	)
	(via
		(at 392.510772 -57.439814)
		(size 0.508)
		(drill 0.254)
		(layers "F.Cu" "B.Cu")
		(net "GND")
	)
	(via
		(at 298.44873 -31.390082)
		(size 0.508)
		(drill 0.254)
		(layers "F.Cu" "B.Cu")
		(net "GND")
	)
	(via
		(at 419.608 -417.82492)
		(size 0.508)
		(drill 0.254)
		(layers "F.Cu" "B.Cu")
		(net "GND")
	)
	(via
		(at 164.681408 -31.118302)
		(size 0.508)
		(drill 0.254)
		(layers "F.Cu" "B.Cu")
		(net "GND")
	)
	(via
		(at 68.674742 -302.074834)
		(size 0.4064)
		(drill 0.2032)
		(layers "F.Cu" "B.Cu")
		(net "GND")
	)
	(via
		(at 397.02486 -309.674768)
		(size 0.4064)
		(drill 0.2032)
		(layers "F.Cu" "B.Cu")
		(net "GND")
	)
	(via
		(at 71.347838 -377.738386)
		(size 0.508)
		(drill 0.254)
		(layers "F.Cu" "B.Cu")
		(net "GND")
	)
	(via
		(at 37.324792 -282.124912)
		(size 0.4064)
		(drill 0.2032)
		(layers "F.Cu" "B.Cu")
		(net "GND")
	)
	(via
		(at 245.342918 -315.899546)
		(size 0.508)
		(drill 0.254)
		(layers "F.Cu" "B.Cu")
		(net "GND")
	)
	(via
		(at 149.400006 -62.812168)
		(size 0.508)
		(drill 0.254)
		(layers "F.Cu" "B.Cu")
		(net "GND")
	)
	(via
		(at 261.6962 -223.8756)
		(size 0.508)
		(drill 0.254)
		(layers "F.Cu" "B.Cu")
		(net "GND")
	)
	(via
		(at 271.899888 -306.349908)
		(size 0.4064)
		(drill 0.2032)
		(layers "F.Cu" "B.Cu")
		(net "GND")
	)
	(via
		(at 227.008944 -97.31375)
		(size 0.508)
		(drill 0.254)
		(layers "F.Cu" "B.Cu")
		(net "GND")
	)
	(via
		(at 386.701792 -111.175546)
		(size 0.508)
		(drill 0.254)
		(layers "F.Cu" "B.Cu")
		(net "GND")
	)
	(via
		(at 28.448 -417.82492)
		(size 0.508)
		(drill 0.254)
		(layers "F.Cu" "B.Cu")
		(net "GND")
	)
	(via
		(at 47.115476 -352.245422)
		(size 0.4572)
		(drill 0.254)
		(layers "F.Cu" "B.Cu")
		(net "GND")
	)
	(via
		(at 414.74771 -118.234968)
		(size 0.508)
		(drill 0.254)
		(layers "F.Cu" "B.Cu")
		(net "GND")
	)
	(via
		(at 424.09999 -309.199788)
		(size 0.4064)
		(drill 0.2032)
		(layers "F.Cu" "B.Cu")
		(net "GND")
	)
	(via
		(at 306.448206 -121.83491)
		(size 0.508)
		(drill 0.254)
		(layers "F.Cu" "B.Cu")
		(net "GND")
	)
	(via
		(at 321.944746 -29.589984)
		(size 0.508)
		(drill 0.254)
		(layers "F.Cu" "B.Cu")
		(net "GND")
	)
	(via
		(at 190.681356 -29.859478)
		(size 0.508)
		(drill 0.254)
		(layers "F.Cu" "B.Cu")
		(net "GND")
	)
	(via
		(at 238.975392 -332.785974)
		(size 0.508)
		(drill 0.254)
		(layers "F.Cu" "B.Cu")
		(net "GND")
	)
	(via
		(at 143.76908 -299.133514)
		(size 0.508)
		(drill 0.254)
		(layers "F.Cu" "B.Cu")
		(net "GND")
	)
	(via
		(at 40.649906 -301.599854)
		(size 0.4064)
		(drill 0.2032)
		(layers "F.Cu" "B.Cu")
		(net "GND")
	)
	(via
		(at 452.885556 -120.526302)
		(size 0.508)
		(drill 0.254)
		(layers "F.Cu" "B.Cu")
		(net "GND")
	)
	(via
		(at 144.573244 -199.982328)
		(size 0.508)
		(drill 0.254)
		(layers "F.Cu" "B.Cu")
		(net "GND")
	)
	(via
		(at 115.008406 -282.910788)
		(size 0.49022)
		(drill 0.254)
		(layers "F.Cu" "B.Cu")
		(net "GND")
	)
	(via
		(at 199.64019 -135.114538)
		(size 0.508)
		(drill 0.254)
		(layers "F.Cu" "B.Cu")
		(net "GND")
	)
	(via
		(at 353.015296 -60.601606)
		(size 0.508)
		(drill 0.254)
		(layers "F.Cu" "B.Cu")
		(net "GND")
	)
	(via
		(at 283.833062 -106.045)
		(size 0.508)
		(drill 0.254)
		(layers "F.Cu" "B.Cu")
		(net "GND")
	)
	(via
		(at 177.174906 -287.824926)
		(size 0.4064)
		(drill 0.2032)
		(layers "F.Cu" "B.Cu")
		(net "GND")
	)
	(via
		(at 28.090368 -351.611438)
		(size 0.4064)
		(drill 0.2032)
		(layers "F.Cu" "B.Cu")
		(net "GND")
	)
	(via
		(at 100.011484 -121.509028)
		(size 0.508)
		(drill 0.254)
		(layers "F.Cu" "B.Cu")
		(net "GND")
	)
	(via
		(at 423.15003 -275.949918)
		(size 0.4064)
		(drill 0.2032)
		(layers "F.Cu" "B.Cu")
		(net "GND")
	)
	(via
		(at 397.97482 -302.074834)
		(size 0.4064)
		(drill 0.2032)
		(layers "F.Cu" "B.Cu")
		(net "GND")
	)
	(via
		(at 266.691618 -108.123228)
		(size 0.508)
		(drill 0.254)
		(layers "F.Cu" "B.Cu")
		(net "GND")
	)
	(via
		(at 313.935364 -348.58579)
		(size 0.4064)
		(drill 0.2032)
		(layers "F.Cu" "B.Cu")
		(net "GND")
	)
	(via
		(at 163.399978 -310.149748)
		(size 0.4064)
		(drill 0.2032)
		(layers "F.Cu" "B.Cu")
		(net "GND")
	)
	(via
		(at 381.403352 -60.627006)
		(size 0.508)
		(drill 0.254)
		(layers "F.Cu" "B.Cu")
		(net "GND")
	)
	(via
		(at 231.765348 -176.72558)
		(size 0.508)
		(drill 0.254)
		(layers "F.Cu" "B.Cu")
		(net "GND")
	)
	(via
		(at 409.374848 -289.724846)
		(size 0.4064)
		(drill 0.2032)
		(layers "F.Cu" "B.Cu")
		(net "GND")
	)
	(via
		(at 27.31516 -45.88891)
		(size 0.508)
		(drill 0.254)
		(layers "F.Cu" "B.Cu")
		(net "GND")
	)
	(via
		(at 44.94784 -369.938808)
		(size 0.508)
		(drill 0.254)
		(layers "F.Cu" "B.Cu")
		(net "GND")
	)
	(via
		(at 374.012206 -23.355554)
		(size 0.508)
		(drill 0.254)
		(layers "F.Cu" "B.Cu")
		(net "GND")
	)
	(via
		(at 292.57117 -349.219774)
		(size 0.4572)
		(drill 0.254)
		(layers "F.Cu" "B.Cu")
		(net "GND")
	)
	(via
		(at 130.74777 -402.140166)
		(size 0.4572)
		(drill 0.254)
		(layers "F.Cu" "B.Cu")
		(net "GND")
	)
	(via
		(at 271.424908 -272.624804)
		(size 0.4064)
		(drill 0.2032)
		(layers "F.Cu" "B.Cu")
		(net "GND")
	)
	(via
		(at 384.685032 -347.951806)
		(size 0.4572)
		(drill 0.254)
		(layers "F.Cu" "B.Cu")
		(net "GND")
	)
	(via
		(at 359.535476 -287.51149)
		(size 0.508)
		(drill 0.254)
		(layers "F.Cu" "B.Cu")
		(net "GND")
	)
	(via
		(at 86.747858 -381.241808)
		(size 0.508)
		(drill 0.254)
		(layers "F.Cu" "B.Cu")
		(net "GND")
	)
	(via
		(at 438.708292 -354.732082)
		(size 0.4064)
		(drill 0.2032)
		(layers "F.Cu" "B.Cu")
		(net "GND")
	)
	(via
		(at 278.549862 -280.699718)
		(size 0.4064)
		(drill 0.2032)
		(layers "F.Cu" "B.Cu")
		(net "GND")
	)
	(via
		(at 284.724856 -303.974754)
		(size 0.4064)
		(drill 0.2032)
		(layers "F.Cu" "B.Cu")
		(net "GND")
	)
	(via
		(at 416.574224 -354.098098)
		(size 0.4572)
		(drill 0.254)
		(layers "F.Cu" "B.Cu")
		(net "GND")
	)
	(via
		(at 175.749966 -312.049922)
		(size 0.4064)
		(drill 0.2032)
		(layers "F.Cu" "B.Cu")
		(net "GND")
	)
	(via
		(at 397.97482 -307.774848)
		(size 0.4064)
		(drill 0.2032)
		(layers "F.Cu" "B.Cu")
		(net "GND")
	)
	(via
		(at 175.683164 -358.391714)
		(size 0.4572)
		(drill 0.254)
		(layers "F.Cu" "B.Cu")
		(net "GND")
	)
	(via
		(at 371.00637 -244.920262)
		(size 0.508)
		(drill 0.254)
		(layers "F.Cu" "B.Cu")
		(net "GND")
	)
	(via
		(at 293.74973 -274.999958)
		(size 0.4064)
		(drill 0.2032)
		(layers "F.Cu" "B.Cu")
		(net "GND")
	)
	(via
		(at 411.381448 -198.920608)
		(size 0.508)
		(drill 0.254)
		(layers "F.Cu" "B.Cu")
		(net "GND")
	)
	(via
		(at 331.504036 -206.26451)
		(size 0.508)
		(drill 0.254)
		(layers "F.Cu" "B.Cu")
		(net "GND")
	)
	(via
		(at 62.804802 -351.611438)
		(size 0.4064)
		(drill 0.2032)
		(layers "F.Cu" "B.Cu")
		(net "GND")
	)
	(via
		(at 152.47493 -292.57498)
		(size 0.4064)
		(drill 0.2032)
		(layers "F.Cu" "B.Cu")
		(net "GND")
	)
	(via
		(at 36.849812 -307.299868)
		(size 0.4064)
		(drill 0.2032)
		(layers "F.Cu" "B.Cu")
		(net "GND")
	)
	(via
		(at 132.495544 -128.193546)
		(size 0.508)
		(drill 0.254)
		(layers "F.Cu" "B.Cu")
		(net "GND")
	)
	(via
		(at 151.83993 -297.32478)
		(size 0.4064)
		(drill 0.2032)
		(layers "F.Cu" "B.Cu")
		(net "GND")
	)
	(via
		(at 274.480782 -27.79014)
		(size 0.508)
		(drill 0.254)
		(layers "F.Cu" "B.Cu")
		(net "GND")
	)
	(via
		(at 92.717366 -308.396132)
		(size 0.508)
		(drill 0.254)
		(layers "F.Cu" "B.Cu")
		(net "GND")
	)
	(via
		(at 51.574954 -302.074834)
		(size 0.4064)
		(drill 0.2032)
		(layers "F.Cu" "B.Cu")
		(net "GND")
	)
	(via
		(at 281.874722 -286.874966)
		(size 0.4064)
		(drill 0.2032)
		(layers "F.Cu" "B.Cu")
		(net "GND")
	)
	(via
		(at 445.820038 -56.441848)
		(size 0.508)
		(drill 0.254)
		(layers "F.Cu" "B.Cu")
		(net "GND")
	)
	(via
		(at 366.033304 -120.890284)
		(size 0.508)
		(drill 0.254)
		(layers "F.Cu" "B.Cu")
		(net "GND")
	)
	(via
		(at 458.689202 -249.11304)
		(size 0.508)
		(drill 0.254)
		(layers "F.Cu" "B.Cu")
		(net "GND")
	)
	(via
		(at 154.850084 -315.849762)
		(size 0.4064)
		(drill 0.2032)
		(layers "F.Cu" "B.Cu")
		(net "GND")
	)
	(via
		(at 358.14 -190.246)
		(size 0.508)
		(drill 0.254)
		(layers "F.Cu" "B.Cu")
		(net "GND")
	)
	(via
		(at 160.549844 -280.699718)
		(size 0.4064)
		(drill 0.2032)
		(layers "F.Cu" "B.Cu")
		(net "GND")
	)
	(via
		(at 146.621246 -245.22303)
		(size 0.508)
		(drill 0.254)
		(layers "F.Cu" "B.Cu")
		(net "GND")
	)
	(via
		(at 435.227984 -344.831162)
		(size 0.4572)
		(drill 0.254)
		(layers "F.Cu" "B.Cu")
		(net "GND")
	)
	(via
		(at 52.049934 -281.649932)
		(size 0.4064)
		(drill 0.2032)
		(layers "F.Cu" "B.Cu")
		(net "GND")
	)
	(via
		(at 286.927798 -404.940262)
		(size 0.508)
		(drill 0.254)
		(layers "F.Cu" "B.Cu")
		(net "GND")
	)
	(via
		(at 25.352756 -343.073482)
		(size 0.4572)
		(drill 0.254)
		(layers "F.Cu" "B.Cu")
		(net "GND")
	)
	(via
		(at 430.673764 -25.971246)
		(size 0.508)
		(drill 0.254)
		(layers "F.Cu" "B.Cu")
		(net "GND")
	)
	(via
		(at 188.366908 -118.234968)
		(size 0.508)
		(drill 0.254)
		(layers "F.Cu" "B.Cu")
		(net "GND")
	)
	(via
		(at 287.528 -417.82492)
		(size 0.508)
		(drill 0.254)
		(layers "F.Cu" "B.Cu")
		(net "GND")
	)
	(via
		(at 400.60118 -357.75773)
		(size 0.4064)
		(drill 0.2032)
		(layers "F.Cu" "B.Cu")
		(net "GND")
	)
	(via
		(at 44.92498 -285.924752)
		(size 0.4064)
		(drill 0.2032)
		(layers "F.Cu" "B.Cu")
		(net "GND")
	)
	(via
		(at 412.699962 -273.099784)
		(size 0.4064)
		(drill 0.2032)
		(layers "F.Cu" "B.Cu")
		(net "GND")
	)
	(via
		(at 285.687262 -109.644942)
		(size 0.508)
		(drill 0.254)
		(layers "F.Cu" "B.Cu")
		(net "GND")
	)
	(via
		(at 419.7985 -65.15989)
		(size 0.508)
		(drill 0.254)
		(layers "F.Cu" "B.Cu")
		(net "GND")
	)
	(via
		(at 131.57708 -355.366066)
		(size 0.4572)
		(drill 0.254)
		(layers "F.Cu" "B.Cu")
		(net "GND")
	)
	(via
		(at 67.66687 -145.755106)
		(size 0.508)
		(drill 0.254)
		(layers "F.Cu" "B.Cu")
		(net "GND")
	)
	(via
		(at 37.361876 -150.457916)
		(size 0.508)
		(drill 0.254)
		(layers "F.Cu" "B.Cu")
		(net "GND")
	)
	(via
		(at 360.747056 -23.583646)
		(size 0.508)
		(drill 0.254)
		(layers "F.Cu" "B.Cu")
		(net "GND")
	)
	(via
		(at 3.94208 -49.574704)
		(size 0.508)
		(drill 0.254)
		(layers "F.Cu" "B.Cu")
		(net "GND")
	)
	(via
		(at 306.448206 -131.245102)
		(size 0.508)
		(drill 0.254)
		(layers "F.Cu" "B.Cu")
		(net "GND")
	)
	(via
		(at 396.549626 -272.14957)
		(size 0.4064)
		(drill 0.2032)
		(layers "F.Cu" "B.Cu")
		(net "GND")
	)
	(via
		(at 330.927964 -408.840178)
		(size 0.508)
		(drill 0.254)
		(layers "F.Cu" "B.Cu")
		(net "GND")
	)
	(via
		(at 51.099974 -278.799798)
		(size 0.4064)
		(drill 0.2032)
		(layers "F.Cu" "B.Cu")
		(net "GND")
	)
	(via
		(at 140.90396 -346.09913)
		(size 0.4572)
		(drill 0.254)
		(layers "F.Cu" "B.Cu")
		(net "GND")
	)
	(via
		(at 80.898238 -147.27682)
		(size 0.508)
		(drill 0.254)
		(layers "F.Cu" "B.Cu")
		(net "GND")
	)
	(via
		(at 22.243796 -355.366066)
		(size 0.4572)
		(drill 0.254)
		(layers "F.Cu" "B.Cu")
		(net "GND")
	)
	(via
		(at 224.765362 -176.306226)
		(size 0.508)
		(drill 0.254)
		(layers "F.Cu" "B.Cu")
		(net "GND")
	)
	(via
		(at 136.536176 -352.245422)
		(size 0.4572)
		(drill 0.254)
		(layers "F.Cu" "B.Cu")
		(net "GND")
	)
	(via
		(at 393.22502 -282.124912)
		(size 0.4064)
		(drill 0.2032)
		(layers "F.Cu" "B.Cu")
		(net "GND")
	)
	(via
		(at 385.05638 -342.439498)
		(size 0.4064)
		(drill 0.2032)
		(layers "F.Cu" "B.Cu")
		(net "GND")
	)
	(via
		(at 188.316108 -110.12678)
		(size 0.508)
		(drill 0.254)
		(layers "F.Cu" "B.Cu")
		(net "GND")
	)
	(via
		(at 124.100336 -354.098098)
		(size 0.4572)
		(drill 0.254)
		(layers "F.Cu" "B.Cu")
		(net "GND")
	)
	(via
		(at 54.98211 -367.45545)
		(size 0.4572)
		(drill 0.254)
		(layers "F.Cu" "B.Cu")
		(net "GND")
	)
	(via
		(at 335.92516 -79.516732)
		(size 0.508)
		(drill 0.254)
		(layers "F.Cu" "B.Cu")
		(net "GND")
	)
	(via
		(at 74.374756 -296.37482)
		(size 0.4064)
		(drill 0.2032)
		(layers "F.Cu" "B.Cu")
		(net "GND")
	)
	(via
		(at 388.949946 -300.649894)
		(size 0.4064)
		(drill 0.2032)
		(layers "F.Cu" "B.Cu")
		(net "GND")
	)
	(via
		(at 269.999714 -312.999882)
		(size 0.4064)
		(drill 0.2032)
		(layers "F.Cu" "B.Cu")
		(net "GND")
	)
	(via
		(at 37.133784 -132.04317)
		(size 0.508)
		(drill 0.254)
		(layers "F.Cu" "B.Cu")
		(net "GND")
	)
	(via
		(at 61.459618 -156.480002)
		(size 0.508)
		(drill 0.254)
		(layers "F.Cu" "B.Cu")
		(net "GND")
	)
	(via
		(at 76.74991 -285.449772)
		(size 0.4064)
		(drill 0.2032)
		(layers "F.Cu" "B.Cu")
		(net "GND")
	)
	(via
		(at 40.174926 -287.824926)
		(size 0.4064)
		(drill 0.2032)
		(layers "F.Cu" "B.Cu")
		(net "GND")
	)
	(via
		(at 344.127836 -369.938554)
		(size 0.508)
		(drill 0.254)
		(layers "F.Cu" "B.Cu")
		(net "GND")
	)
	(via
		(at 48.58131 -31.118302)
		(size 0.508)
		(drill 0.254)
		(layers "F.Cu" "B.Cu")
		(net "GND")
	)
	(via
		(at 269.99819 -19.757136)
		(size 0.508)
		(drill 0.254)
		(layers "F.Cu" "B.Cu")
		(net "GND")
	)
	(via
		(at 354.499926 -256.870962)
		(size 0.508)
		(drill 0.254)
		(layers "F.Cu" "B.Cu")
		(net "GND")
	)
	(via
		(at 241.15395 -147.630388)
		(size 0.508)
		(drill 0.254)
		(layers "F.Cu" "B.Cu")
		(net "GND")
	)
	(via
		(at 444.49619 -60.099194)
		(size 0.508)
		(drill 0.254)
		(layers "F.Cu" "B.Cu")
		(net "GND")
	)
	(via
		(at 128.547622 -371.140228)
		(size 0.4572)
		(drill 0.254)
		(layers "F.Cu" "B.Cu")
		(net "GND")
	)
	(via
		(at 395.12494 -303.974754)
		(size 0.4064)
		(drill 0.2032)
		(layers "F.Cu" "B.Cu")
		(net "GND")
	)
	(via
		(at 108.253784 -389.658098)
		(size 0.508)
		(drill 0.254)
		(layers "F.Cu" "B.Cu")
		(net "GND")
	)
	(via
		(at 290.17976 -102.798372)
		(size 0.508)
		(drill 0.254)
		(layers "F.Cu" "B.Cu")
		(net "GND")
	)
	(via
		(at 39.04742 -358.391714)
		(size 0.4572)
		(drill 0.254)
		(layers "F.Cu" "B.Cu")
		(net "GND")
	)
	(via
		(at 165.09746 -354.098098)
		(size 0.4572)
		(drill 0.254)
		(layers "F.Cu" "B.Cu")
		(net "GND")
	)
	(via
		(at 312.749692 -274.999958)
		(size 0.4064)
		(drill 0.2032)
		(layers "F.Cu" "B.Cu")
		(net "GND")
	)
	(via
		(at 432.119024 -344.831162)
		(size 0.4572)
		(drill 0.254)
		(layers "F.Cu" "B.Cu")
		(net "GND")
	)
	(via
		(at 115.34775 -380.141734)
		(size 0.4572)
		(drill 0.254)
		(layers "F.Cu" "B.Cu")
		(net "GND")
	)
	(via
		(at 34.679636 -346.09913)
		(size 0.4572)
		(drill 0.254)
		(layers "F.Cu" "B.Cu")
		(net "GND")
	)
	(via
		(at 178.715416 -177.711862)
		(size 0.508)
		(drill 0.254)
		(layers "F.Cu" "B.Cu")
		(net "GND")
	)
	(via
		(at 44.94784 -380.141988)
		(size 0.508)
		(drill 0.254)
		(layers "F.Cu" "B.Cu")
		(net "GND")
	)
	(via
		(at 173.375066 -294.4749)
		(size 0.4064)
		(drill 0.2032)
		(layers "F.Cu" "B.Cu")
		(net "GND")
	)
	(via
		(at 75.800204 -274.049744)
		(size 0.4064)
		(drill 0.2032)
		(layers "F.Cu" "B.Cu")
		(net "GND")
	)
	(via
		(at 448.792346 -284.764988)
		(size 0.508)
		(drill 0.254)
		(layers "F.Cu" "B.Cu")
		(net "GND")
	)
	(via
		(at 429.800004 -305.399948)
		(size 0.4064)
		(drill 0.2032)
		(layers "F.Cu" "B.Cu")
		(net "GND")
	)
	(via
		(at 240.06048 -82.916014)
		(size 0.508)
		(drill 0.254)
		(layers "F.Cu" "B.Cu")
		(net "GND")
	)
	(via
		(at 312.274712 -296.37482)
		(size 0.4064)
		(drill 0.2032)
		(layers "F.Cu" "B.Cu")
		(net "GND")
	)
	(via
		(at 420.277798 -135.320024)
		(size 0.508)
		(drill 0.254)
		(layers "F.Cu" "B.Cu")
		(net "GND")
	)
	(via
		(at 314.174886 -291.624766)
		(size 0.4064)
		(drill 0.2032)
		(layers "F.Cu" "B.Cu")
		(net "GND")
	)
	(via
		(at 191.900048 -318.699896)
		(size 0.4064)
		(drill 0.2032)
		(layers "F.Cu" "B.Cu")
		(net "GND")
	)
	(via
		(at 78.64983 -284.499812)
		(size 0.4064)
		(drill 0.2032)
		(layers "F.Cu" "B.Cu")
		(net "GND")
	)
	(via
		(at 321.632072 -347.951806)
		(size 0.4572)
		(drill 0.254)
		(layers "F.Cu" "B.Cu")
		(net "GND")
	)
	(via
		(at 409.09748 -350.977454)
		(size 0.4572)
		(drill 0.254)
		(layers "F.Cu" "B.Cu")
		(net "GND")
	)
	(via
		(at 221.415102 -43.85691)
		(size 0.508)
		(drill 0.254)
		(layers "F.Cu" "B.Cu")
		(net "GND")
	)
	(via
		(at 300.12767 -371.140228)
		(size 0.508)
		(drill 0.254)
		(layers "F.Cu" "B.Cu")
		(net "GND")
	)
	(via
		(at 163.399978 -276.899878)
		(size 0.4064)
		(drill 0.2032)
		(layers "F.Cu" "B.Cu")
		(net "GND")
	)
	(via
		(at 133.869684 -288.14649)
		(size 0.508)
		(drill 0.254)
		(layers "F.Cu" "B.Cu")
		(net "GND")
	)
	(via
		(at 296.818558 -186.388248)
		(size 0.508)
		(drill 0.254)
		(layers "F.Cu" "B.Cu")
		(net "GND")
	)
	(via
		(at 24.981408 -354.732082)
		(size 0.4064)
		(drill 0.2032)
		(layers "F.Cu" "B.Cu")
		(net "GND")
	)
	(via
		(at 269.999714 -318.699896)
		(size 0.4064)
		(drill 0.2032)
		(layers "F.Cu" "B.Cu")
		(net "GND")
	)
	(via
		(at 104.808274 -286.842454)
		(size 0.508)
		(drill 0.254)
		(layers "F.Cu" "B.Cu")
		(net "GND")
	)
	(via
		(at 410.932122 -168.94556)
		(size 0.508)
		(drill 0.254)
		(layers "F.Cu" "B.Cu")
		(net "GND")
	)
	(via
		(at 71.524876 -305.874928)
		(size 0.4064)
		(drill 0.2032)
		(layers "F.Cu" "B.Cu")
		(net "GND")
	)
	(via
		(at 292.01999 -31.390336)
		(size 0.508)
		(drill 0.254)
		(layers "F.Cu" "B.Cu")
		(net "GND")
	)
	(via
		(at 71.999856 -276.899878)
		(size 0.4064)
		(drill 0.2032)
		(layers "F.Cu" "B.Cu")
		(net "GND")
	)
	(via
		(at 344.69578 -329.564492)
		(size 0.508)
		(drill 0.254)
		(layers "F.Cu" "B.Cu")
		(net "GND")
	)
	(via
		(at 117.547644 -372.240302)
		(size 0.4572)
		(drill 0.254)
		(layers "F.Cu" "B.Cu")
		(net "GND")
	)
	(via
		(at 283.833062 -138.964924)
		(size 0.508)
		(drill 0.254)
		(layers "F.Cu" "B.Cu")
		(net "GND")
	)
	(via
		(at 441.751466 -113.364772)
		(size 0.508)
		(drill 0.254)
		(layers "F.Cu" "B.Cu")
		(net "GND")
	)
	(via
		(at 35.93846 -344.831162)
		(size 0.4572)
		(drill 0.254)
		(layers "F.Cu" "B.Cu")
		(net "GND")
	)
	(via
		(at 384.199638 -304.449988)
		(size 0.4064)
		(drill 0.2032)
		(layers "F.Cu" "B.Cu")
		(net "GND")
	)
	(via
		(at 192.850008 -306.349908)
		(size 0.4064)
		(drill 0.2032)
		(layers "F.Cu" "B.Cu")
		(net "GND")
	)
	(via
		(at 100.581206 -31.118302)
		(size 0.508)
		(drill 0.254)
		(layers "F.Cu" "B.Cu")
		(net "GND")
	)
	(via
		(at 94.280736 -31.390082)
		(size 0.508)
		(drill 0.254)
		(layers "F.Cu" "B.Cu")
		(net "GND")
	)
	(via
		(at 373.72798 -357.75773)
		(size 0.4064)
		(drill 0.2032)
		(layers "F.Cu" "B.Cu")
		(net "GND")
	)
	(via
		(at 305.149758 -315.849762)
		(size 0.4064)
		(drill 0.2032)
		(layers "F.Cu" "B.Cu")
		(net "GND")
	)
	(via
		(at 273.324828 -299.224954)
		(size 0.4064)
		(drill 0.2032)
		(layers "F.Cu" "B.Cu")
		(net "GND")
	)
	(via
		(at 168.149778 -272.14957)
		(size 0.4064)
		(drill 0.2032)
		(layers "F.Cu" "B.Cu")
		(net "GND")
	)
	(via
		(at 298.44873 -29.589984)
		(size 0.508)
		(drill 0.254)
		(layers "F.Cu" "B.Cu")
		(net "GND")
	)
	(via
		(at 230.26751 -221.103952)
		(size 0.4572)
		(drill 0.254)
		(layers "F.Cu" "B.Cu")
		(net "GND")
	)
	(via
		(at 277.854664 -23.880318)
		(size 0.508)
		(drill 0.254)
		(layers "F.Cu" "B.Cu")
		(net "GND")
	)
	(via
		(at 389.644128 -358.391714)
		(size 0.4572)
		(drill 0.254)
		(layers "F.Cu" "B.Cu")
		(net "GND")
	)
	(via
		(at 404.149814 -316.799722)
		(size 0.4064)
		(drill 0.2032)
		(layers "F.Cu" "B.Cu")
		(net "GND")
	)
	(via
		(at 258.217924 -393.147296)
		(size 0.508)
		(drill 0.254)
		(layers "F.Cu" "B.Cu")
		(net "GND")
	)
	(via
		(at 377.12777 -374.938544)
		(size 0.508)
		(drill 0.254)
		(layers "F.Cu" "B.Cu")
		(net "GND")
	)
	(via
		(at 313.699906 -273.099784)
		(size 0.4064)
		(drill 0.2032)
		(layers "F.Cu" "B.Cu")
		(net "GND")
	)
	(via
		(at 350.493584 -217.987372)
		(size 0.4572)
		(drill 0.254)
		(layers "F.Cu" "B.Cu")
		(net "GND")
	)
	(via
		(at 284.874462 -354.732082)
		(size 0.4064)
		(drill 0.2032)
		(layers "F.Cu" "B.Cu")
		(net "GND")
	)
	(via
		(at 139.24661 -255.66624)
		(size 0.508)
		(drill 0.254)
		(layers "F.Cu" "B.Cu")
		(net "GND")
	)
	(via
		(at 44.449746 -310.149748)
		(size 0.4064)
		(drill 0.2032)
		(layers "F.Cu" "B.Cu")
		(net "GND")
	)
	(via
		(at 430.466246 -119.756936)
		(size 0.508)
		(drill 0.254)
		(layers "F.Cu" "B.Cu")
		(net "GND")
	)
	(via
		(at 230.700834 -282.982162)
		(size 0.508)
		(drill 0.254)
		(layers "F.Cu" "B.Cu")
		(net "GND")
	)
	(via
		(at 318.654938 -27.79014)
		(size 0.508)
		(drill 0.254)
		(layers "F.Cu" "B.Cu")
		(net "GND")
	)
	(via
		(at 103.594916 -378.997972)
		(size 0.508)
		(drill 0.254)
		(layers "F.Cu" "B.Cu")
		(net "GND")
	)
	(via
		(at 399.93316 -135.364982)
		(size 0.508)
		(drill 0.254)
		(layers "F.Cu" "B.Cu")
		(net "GND")
	)
	(via
		(at 397.02486 -293.52494)
		(size 0.4064)
		(drill 0.2032)
		(layers "F.Cu" "B.Cu")
		(net "GND")
	)
	(via
		(at 398.275048 -73.23963)
		(size 0.508)
		(drill 0.254)
		(layers "F.Cu" "B.Cu")
		(net "GND")
	)
	(via
		(at 188.269372 -111.016288)
		(size 0.508)
		(drill 0.254)
		(layers "F.Cu" "B.Cu")
		(net "GND")
	)
	(via
		(at 97.068132 -48.753014)
		(size 0.508)
		(drill 0.254)
		(layers "F.Cu" "B.Cu")
		(net "GND")
	)
	(via
		(at 414.74771 -134.845044)
		(size 0.508)
		(drill 0.254)
		(layers "F.Cu" "B.Cu")
		(net "GND")
	)
	(via
		(at 214.587582 -26.360882)
		(size 0.508)
		(drill 0.254)
		(layers "F.Cu" "B.Cu")
		(net "GND")
	)
	(via
		(at 179.898294 -21.077936)
		(size 0.508)
		(drill 0.254)
		(layers "F.Cu" "B.Cu")
		(net "GND")
	)
	(via
		(at 351.451926 -258.394962)
		(size 0.508)
		(drill 0.254)
		(layers "F.Cu" "B.Cu")
		(net "GND")
	)
	(via
		(at 344.093546 -217.187272)
		(size 0.4572)
		(drill 0.254)
		(layers "F.Cu" "B.Cu")
		(net "GND")
	)
	(via
		(at 101.831394 -392.283696)
		(size 0.508)
		(drill 0.254)
		(layers "F.Cu" "B.Cu")
		(net "GND")
	)
	(via
		(at 127.33528 -288.78149)
		(size 0.508)
		(drill 0.254)
		(layers "F.Cu" "B.Cu")
		(net "GND")
	)
	(via
		(at 53.48732 -131.76504)
		(size 0.508)
		(drill 0.254)
		(layers "F.Cu" "B.Cu")
		(net "GND")
	)
	(via
		(at 145.95348 -196.271896)
		(size 0.508)
		(drill 0.254)
		(layers "F.Cu" "B.Cu")
		(net "GND")
	)
	(via
		(at 59.299856 -62.812168)
		(size 0.508)
		(drill 0.254)
		(layers "F.Cu" "B.Cu")
		(net "GND")
	)
	(via
		(at 296.793412 -120.035066)
		(size 0.508)
		(drill 0.254)
		(layers "F.Cu" "B.Cu")
		(net "GND")
	)
	(via
		(at 362.910628 -113.251996)
		(size 0.508)
		(drill 0.254)
		(layers "F.Cu" "B.Cu")
		(net "GND")
	)
	(via
		(at 139.769596 -167.303704)
		(size 0.508)
		(drill 0.254)
		(layers "F.Cu" "B.Cu")
		(net "GND")
	)
	(via
		(at 185.250074 -275.949918)
		(size 0.4064)
		(drill 0.2032)
		(layers "F.Cu" "B.Cu")
		(net "GND")
	)
	(via
		(at 277.599902 -310.149748)
		(size 0.4064)
		(drill 0.2032)
		(layers "F.Cu" "B.Cu")
		(net "GND")
	)
	(via
		(at 44.94784 -381.63881)
		(size 0.508)
		(drill 0.254)
		(layers "F.Cu" "B.Cu")
		(net "GND")
	)
	(via
		(at 228.522022 -227.382578)
		(size 0.508)
		(drill 0.254)
		(layers "F.Cu" "B.Cu")
		(net "GND")
	)
	(via
		(at 412.89351 -149.355302)
		(size 0.508)
		(drill 0.254)
		(layers "F.Cu" "B.Cu")
		(net "GND")
	)
	(via
		(at 362.92536 -357.56596)
		(size 0.508)
		(drill 0.254)
		(layers "F.Cu" "B.Cu")
		(net "GND")
	)
	(via
		(at 299.866812 -129.445004)
		(size 0.508)
		(drill 0.254)
		(layers "F.Cu" "B.Cu")
		(net "GND")
	)
	(via
		(at 136.536176 -349.219774)
		(size 0.4572)
		(drill 0.254)
		(layers "F.Cu" "B.Cu")
		(net "GND")
	)
	(via
		(at 72.949562 -272.14957)
		(size 0.4064)
		(drill 0.2032)
		(layers "F.Cu" "B.Cu")
		(net "GND")
	)
	(via
		(at 29.54782 -382.73863)
		(size 0.508)
		(drill 0.254)
		(layers "F.Cu" "B.Cu")
		(net "GND")
	)
	(via
		(at 47.032926 -118.754906)
		(size 0.508)
		(drill 0.254)
		(layers "F.Cu" "B.Cu")
		(net "GND")
	)
	(via
		(at 402.249894 -276.899878)
		(size 0.4064)
		(drill 0.2032)
		(layers "F.Cu" "B.Cu")
		(net "GND")
	)
	(via
		(at 37.324792 -289.724846)
		(size 0.4064)
		(drill 0.2032)
		(layers "F.Cu" "B.Cu")
		(net "GND")
	)
	(via
		(at 315.414152 -357.123746)
		(size 0.4572)
		(drill 0.254)
		(layers "F.Cu" "B.Cu")
		(net "GND")
	)
	(via
		(at 275.038312 -73.20026)
		(size 0.508)
		(drill 0.254)
		(layers "F.Cu" "B.Cu")
		(net "GND")
	)
	(via
		(at 385.149852 -303.499774)
		(size 0.4064)
		(drill 0.2032)
		(layers "F.Cu" "B.Cu")
		(net "GND")
	)
	(via
		(at 418.927788 -408.840178)
		(size 0.508)
		(drill 0.254)
		(layers "F.Cu" "B.Cu")
		(net "GND")
	)
	(via
		(at 54.70652 -109.644942)
		(size 0.508)
		(drill 0.254)
		(layers "F.Cu" "B.Cu")
		(net "GND")
	)
	(via
		(at 2.012188 -389.253476)
		(size 0.508)
		(drill 0.254)
		(layers "F.Cu" "B.Cu")
		(net "GND")
	)
	(via
		(at 189.524894 -296.37482)
		(size 0.4064)
		(drill 0.2032)
		(layers "F.Cu" "B.Cu")
		(net "GND")
	)
	(via
		(at 326.371204 -354.732082)
		(size 0.4064)
		(drill 0.2032)
		(layers "F.Cu" "B.Cu")
		(net "GND")
	)
	(via
		(at 289.222942 -140.97)
		(size 0.508)
		(drill 0.254)
		(layers "F.Cu" "B.Cu")
		(net "GND")
	)
	(via
		(at 199.64019 -151.42464)
		(size 0.508)
		(drill 0.254)
		(layers "F.Cu" "B.Cu")
		(net "GND")
	)
	(via
		(at 128.764284 -285.267654)
		(size 0.508)
		(drill 0.254)
		(layers "F.Cu" "B.Cu")
		(net "GND")
	)
	(via
		(at 396.54988 -276.899878)
		(size 0.4064)
		(drill 0.2032)
		(layers "F.Cu" "B.Cu")
		(net "GND")
	)
	(via
		(at 176.94783 -378.940314)
		(size 0.508)
		(drill 0.254)
		(layers "F.Cu" "B.Cu")
		(net "GND")
	)
	(via
		(at 339.728048 -404.940262)
		(size 0.508)
		(drill 0.254)
		(layers "F.Cu" "B.Cu")
		(net "GND")
	)
	(via
		(at 402.036788 -15.474188)
		(size 0.508)
		(drill 0.254)
		(layers "F.Cu" "B.Cu")
		(net "GND")
	)
	(via
		(at 359.87482 -103.412036)
		(size 0.508)
		(drill 0.254)
		(layers "F.Cu" "B.Cu")
		(net "GND")
	)
	(via
		(at 332.211426 -121.509028)
		(size 0.508)
		(drill 0.254)
		(layers "F.Cu" "B.Cu")
		(net "GND")
	)
	(via
		(at 397.97482 -297.32478)
		(size 0.4064)
		(drill 0.2032)
		(layers "F.Cu" "B.Cu")
		(net "GND")
	)
	(via
		(at 386.574792 -298.27474)
		(size 0.4064)
		(drill 0.2032)
		(layers "F.Cu" "B.Cu")
		(net "GND")
	)
	(via
		(at 334.494124 -220.38691)
		(size 0.4572)
		(drill 0.254)
		(layers "F.Cu" "B.Cu")
		(net "GND")
	)
	(via
		(at 420.774876 -300.174914)
		(size 0.4064)
		(drill 0.2032)
		(layers "F.Cu" "B.Cu")
		(net "GND")
	)
	(via
		(at 147.4978 -392.2014)
		(size 0.508)
		(drill 0.254)
		(layers "F.Cu" "B.Cu")
		(net "GND")
	)
	(via
		(at 437.07812 -354.074222)
		(size 0.4572)
		(drill 0.254)
		(layers "F.Cu" "B.Cu")
		(net "GND")
	)
	(via
		(at 277.251668 -129.964942)
		(size 0.508)
		(drill 0.254)
		(layers "F.Cu" "B.Cu")
		(net "GND")
	)
	(via
		(at 438.354724 -34.990024)
		(size 0.508)
		(drill 0.254)
		(layers "F.Cu" "B.Cu")
		(net "GND")
	)
	(via
		(at 421.724836 -296.37482)
		(size 0.4064)
		(drill 0.2032)
		(layers "F.Cu" "B.Cu")
		(net "GND")
	)
	(via
		(at 422.674796 -302.074834)
		(size 0.4064)
		(drill 0.2032)
		(layers "F.Cu" "B.Cu")
		(net "GND")
	)
	(via
		(at 45.39996 -276.899878)
		(size 0.4064)
		(drill 0.2032)
		(layers "F.Cu" "B.Cu")
		(net "GND")
	)
	(via
		(at 392.753088 -354.098098)
		(size 0.4572)
		(drill 0.254)
		(layers "F.Cu" "B.Cu")
		(net "GND")
	)
	(via
		(at 118.579646 -169.676064)
		(size 0.508)
		(drill 0.254)
		(layers "F.Cu" "B.Cu")
		(net "GND")
	)
	(via
		(at 208.019142 -124.779532)
		(size 0.508)
		(drill 0.254)
		(layers "F.Cu" "B.Cu")
		(net "GND")
	)
	(via
		(at 281.718766 -123.878594)
		(size 0.508)
		(drill 0.254)
		(layers "F.Cu" "B.Cu")
		(net "GND")
	)
	(via
		(at 142.754096 -350.977454)
		(size 0.4572)
		(drill 0.254)
		(layers "F.Cu" "B.Cu")
		(net "GND")
	)
	(via
		(at 35.101276 -100.92309)
		(size 0.508)
		(drill 0.254)
		(layers "F.Cu" "B.Cu")
		(net "GND")
	)
	(via
		(at 67.66687 -116.435124)
		(size 0.508)
		(drill 0.254)
		(layers "F.Cu" "B.Cu")
		(net "GND")
	)
	(via
		(at 73.424796 -292.574726)
		(size 0.4064)
		(drill 0.2032)
		(layers "F.Cu" "B.Cu")
		(net "GND")
	)
	(via
		(at 374.927876 -381.638556)
		(size 0.508)
		(drill 0.254)
		(layers "F.Cu" "B.Cu")
		(net "GND")
	)
	(via
		(at 285.523178 -54.067456)
		(size 0.508)
		(drill 0.254)
		(layers "F.Cu" "B.Cu")
		(net "GND")
	)
	(via
		(at 381.527812 -400.938492)
		(size 0.508)
		(drill 0.254)
		(layers "F.Cu" "B.Cu")
		(net "GND")
	)
	(via
		(at 270.474694 -299.224954)
		(size 0.4064)
		(drill 0.2032)
		(layers "F.Cu" "B.Cu")
		(net "GND")
	)
	(via
		(at 194.749928 -316.799722)
		(size 0.4064)
		(drill 0.2032)
		(layers "F.Cu" "B.Cu")
		(net "GND")
	)
	(via
		(at 187.149994 -312.049922)
		(size 0.4064)
		(drill 0.2032)
		(layers "F.Cu" "B.Cu")
		(net "GND")
	)
	(via
		(at 373.850916 -262.912352)
		(size 0.508)
		(drill 0.254)
		(layers "F.Cu" "B.Cu")
		(net "GND")
	)
	(via
		(at 346.327984 -407.24201)
		(size 0.508)
		(drill 0.254)
		(layers "F.Cu" "B.Cu")
		(net "GND")
	)
	(via
		(at 341.916004 -357.75773)
		(size 0.4064)
		(drill 0.2032)
		(layers "F.Cu" "B.Cu")
		(net "GND")
	)
	(via
		(at 61.17463 -350.977454)
		(size 0.4572)
		(drill 0.254)
		(layers "F.Cu" "B.Cu")
		(net "GND")
	)
	(via
		(at 272.374868 -283.074872)
		(size 0.4064)
		(drill 0.2032)
		(layers "F.Cu" "B.Cu")
		(net "GND")
	)
	(via
		(at 140.255752 -194.710558)
		(size 0.508)
		(drill 0.254)
		(layers "F.Cu" "B.Cu")
		(net "GND")
	)
	(via
		(at 427.727872 -381.638556)
		(size 0.508)
		(drill 0.254)
		(layers "F.Cu" "B.Cu")
		(net "GND")
	)
	(via
		(at 161.15157 -98.845116)
		(size 0.508)
		(drill 0.254)
		(layers "F.Cu" "B.Cu")
		(net "GND")
	)
	(via
		(at 415.3154 -346.09913)
		(size 0.4572)
		(drill 0.254)
		(layers "F.Cu" "B.Cu")
		(net "GND")
	)
	(via
		(at 183.766714 -149.355048)
		(size 0.508)
		(drill 0.254)
		(layers "F.Cu" "B.Cu")
		(net "GND")
	)
	(via
		(at 292.01999 -33.19018)
		(size 0.508)
		(drill 0.254)
		(layers "F.Cu" "B.Cu")
		(net "GND")
	)
	(via
		(at 144.399762 -237.948978)
		(size 0.508)
		(drill 0.254)
		(layers "F.Cu" "B.Cu")
		(net "GND")
	)
	(via
		(at 180.64226 -346.09913)
		(size 0.4572)
		(drill 0.254)
		(layers "F.Cu" "B.Cu")
		(net "GND")
	)
	(via
		(at 164.349938 -310.149748)
		(size 0.4064)
		(drill 0.2032)
		(layers "F.Cu" "B.Cu")
		(net "GND")
	)
	(via
		(at 379.327918 -399.838418)
		(size 0.508)
		(drill 0.254)
		(layers "F.Cu" "B.Cu")
		(net "GND")
	)
	(via
		(at 189.999874 -286.399732)
		(size 0.4064)
		(drill 0.2032)
		(layers "F.Cu" "B.Cu")
		(net "GND")
	)
	(via
		(at 69.64807 -118.370858)
		(size 0.508)
		(drill 0.254)
		(layers "F.Cu" "B.Cu")
		(net "GND")
	)
	(via
		(at 165.774878 -306.824888)
		(size 0.4064)
		(drill 0.2032)
		(layers "F.Cu" "B.Cu")
		(net "GND")
	)
	(via
		(at 76.74991 -306.349908)
		(size 0.4064)
		(drill 0.2032)
		(layers "F.Cu" "B.Cu")
		(net "GND")
	)
	(via
		(at 182.90286 -74.624184)
		(size 0.508)
		(drill 0.254)
		(layers "F.Cu" "B.Cu")
		(net "GND")
	)
	(via
		(at 388.127748 -371.140228)
		(size 0.508)
		(drill 0.254)
		(layers "F.Cu" "B.Cu")
		(net "GND")
	)
	(via
		(at 346.438982 -285.953454)
		(size 0.508)
		(drill 0.254)
		(layers "F.Cu" "B.Cu")
		(net "GND")
	)
	(via
		(at 172.424852 -293.52494)
		(size 0.4064)
		(drill 0.2032)
		(layers "F.Cu" "B.Cu")
		(net "GND")
	)
	(via
		(at 183.766714 -156.554932)
		(size 0.508)
		(drill 0.254)
		(layers "F.Cu" "B.Cu")
		(net "GND")
	)
	(via
		(at 79.82839 -355.366066)
		(size 0.4572)
		(drill 0.254)
		(layers "F.Cu" "B.Cu")
		(net "GND")
	)
	(via
		(at 299.866812 -120.035066)
		(size 0.508)
		(drill 0.254)
		(layers "F.Cu" "B.Cu")
		(net "GND")
	)
	(via
		(at 279.513284 -29.859478)
		(size 0.508)
		(drill 0.254)
		(layers "F.Cu" "B.Cu")
		(net "GND")
	)
	(via
		(at 392.749786 -307.299868)
		(size 0.4064)
		(drill 0.2032)
		(layers "F.Cu" "B.Cu")
		(net "GND")
	)
	(via
		(at 46.34992 -308.249828)
		(size 0.4064)
		(drill 0.2032)
		(layers "F.Cu" "B.Cu")
		(net "GND")
	)
	(via
		(at 151.859488 -111.72317)
		(size 0.508)
		(drill 0.254)
		(layers "F.Cu" "B.Cu")
		(net "GND")
	)
	(via
		(at 38.275006 -286.874966)
		(size 0.4064)
		(drill 0.2032)
		(layers "F.Cu" "B.Cu")
		(net "GND")
	)
	(via
		(at 258.0132 -205.11389)
		(size 0.508)
		(drill 0.254)
		(layers "F.Cu" "B.Cu")
		(net "GND")
	)
	(via
		(at 40.526208 -354.732082)
		(size 0.4064)
		(drill 0.2032)
		(layers "F.Cu" "B.Cu")
		(net "GND")
	)
	(via
		(at 341.916004 -348.58579)
		(size 0.4064)
		(drill 0.2032)
		(layers "F.Cu" "B.Cu")
		(net "GND")
	)
	(via
		(at 27.347926 -381.638556)
		(size 0.508)
		(drill 0.254)
		(layers "F.Cu" "B.Cu")
		(net "GND")
	)
	(via
		(at 43.024806 -290.674806)
		(size 0.4064)
		(drill 0.2032)
		(layers "F.Cu" "B.Cu")
		(net "GND")
	)
	(via
		(at 49.1998 -312.999882)
		(size 0.4064)
		(drill 0.2032)
		(layers "F.Cu" "B.Cu")
		(net "GND")
	)
	(via
		(at 374.927876 -373.83847)
		(size 0.508)
		(drill 0.254)
		(layers "F.Cu" "B.Cu")
		(net "GND")
	)
	(via
		(at 239.006888 -85.912452)
		(size 0.508)
		(drill 0.254)
		(layers "F.Cu" "B.Cu")
		(net "GND")
	)
	(via
		(at 283.299916 -314.899802)
		(size 0.4064)
		(drill 0.2032)
		(layers "F.Cu" "B.Cu")
		(net "GND")
	)
	(via
		(at 284.724856 -291.624766)
		(size 0.4064)
		(drill 0.2032)
		(layers "F.Cu" "B.Cu")
		(net "GND")
	)
	(via
		(at 419.990778 -119.414544)
		(size 0.508)
		(drill 0.254)
		(layers "F.Cu" "B.Cu")
		(net "GND")
	)
	(via
		(at 134.931404 -60.099194)
		(size 0.508)
		(drill 0.254)
		(layers "F.Cu" "B.Cu")
		(net "GND")
	)
	(via
		(at 422.199816 -287.349946)
		(size 0.4064)
		(drill 0.2032)
		(layers "F.Cu" "B.Cu")
		(net "GND")
	)
	(via
		(at 46.744128 -351.611438)
		(size 0.4064)
		(drill 0.2032)
		(layers "F.Cu" "B.Cu")
		(net "GND")
	)
	(via
		(at 52.049934 -311.099962)
		(size 0.4064)
		(drill 0.2032)
		(layers "F.Cu" "B.Cu")
		(net "GND")
	)
	(via
		(at 346.465652 -304.373534)
		(size 0.508)
		(drill 0.254)
		(layers "F.Cu" "B.Cu")
		(net "GND")
	)
	(via
		(at 216.270078 -416.508438)
		(size 0.508)
		(drill 0.254)
		(layers "F.Cu" "B.Cu")
		(net "GND")
	)
	(via
		(at 293.527734 -409.940252)
		(size 0.508)
		(drill 0.254)
		(layers "F.Cu" "B.Cu")
		(net "GND")
	)
	(via
		(at 122.65787 -137.344404)
		(size 0.508)
		(drill 0.254)
		(layers "F.Cu" "B.Cu")
		(net "GND")
	)
	(via
		(at 100.744782 -107.681776)
		(size 0.508)
		(drill 0.254)
		(layers "F.Cu" "B.Cu")
		(net "GND")
	)
	(via
		(at 207.018636 -294.50157)
		(size 0.508)
		(drill 0.254)
		(layers "F.Cu" "B.Cu")
		(net "GND")
	)
	(via
		(at 38.347904 -407.24201)
		(size 0.508)
		(drill 0.254)
		(layers "F.Cu" "B.Cu")
		(net "GND")
	)
	(via
		(at 160.074864 -297.32478)
		(size 0.4064)
		(drill 0.2032)
		(layers "F.Cu" "B.Cu")
		(net "GND")
	)
	(via
		(at 250.180602 -199.488298)
		(size 0.508)
		(drill 0.254)
		(layers "F.Cu" "B.Cu")
		(net "GND")
	)
	(via
		(at 196.33946 -85.426296)
		(size 0.508)
		(drill 0.254)
		(layers "F.Cu" "B.Cu")
		(net "GND")
	)
	(via
		(at 189.999874 -312.999882)
		(size 0.4064)
		(drill 0.2032)
		(layers "F.Cu" "B.Cu")
		(net "GND")
	)
	(via
		(at 299.924724 -287.824926)
		(size 0.4064)
		(drill 0.2032)
		(layers "F.Cu" "B.Cu")
		(net "GND")
	)
	(via
		(at 4.562856 -149.681692)
		(size 0.508)
		(drill 0.254)
		(layers "F.Cu" "B.Cu")
		(net "GND")
	)
	(via
		(at 387.793992 -349.219774)
		(size 0.4572)
		(drill 0.254)
		(layers "F.Cu" "B.Cu")
		(net "GND")
	)
	(via
		(at 177.295048 -60.633356)
		(size 0.508)
		(drill 0.254)
		(layers "F.Cu" "B.Cu")
		(net "GND")
	)
	(via
		(at 413.836612 -354.732082)
		(size 0.4064)
		(drill 0.2032)
		(layers "F.Cu" "B.Cu")
		(net "GND")
	)
	(via
		(at 194.651376 -104.120696)
		(size 0.508)
		(drill 0.254)
		(layers "F.Cu" "B.Cu")
		(net "GND")
	)
	(via
		(at 392.869928 -25.832054)
		(size 0.508)
		(drill 0.254)
		(layers "F.Cu" "B.Cu")
		(net "GND")
	)
	(via
		(at 418.971222 -28.05303)
		(size 0.508)
		(drill 0.254)
		(layers "F.Cu" "B.Cu")
		(net "GND")
	)
	(via
		(at 220.82506 -248.412762)
		(size 0.508)
		(drill 0.254)
		(layers "F.Cu" "B.Cu")
		(net "GND")
	)
	(via
		(at 422.792144 -358.391714)
		(size 0.4572)
		(drill 0.254)
		(layers "F.Cu" "B.Cu")
		(net "GND")
	)
	(via
		(at 71.049896 -279.749758)
		(size 0.4064)
		(drill 0.2032)
		(layers "F.Cu" "B.Cu")
		(net "GND")
	)
	(via
		(at 407.949908 -276.899878)
		(size 0.4064)
		(drill 0.2032)
		(layers "F.Cu" "B.Cu")
		(net "GND")
	)
	(via
		(at 48.24984 -279.749758)
		(size 0.4064)
		(drill 0.2032)
		(layers "F.Cu" "B.Cu")
		(net "GND")
	)
	(via
		(at 392.52779 -407.638504)
		(size 0.508)
		(drill 0.254)
		(layers "F.Cu" "B.Cu")
		(net "GND")
	)
	(via
		(at 345.877642 -307.877718)
		(size 0.508)
		(drill 0.254)
		(layers "F.Cu" "B.Cu")
		(net "GND")
	)
	(via
		(at 62.499748 -276.899878)
		(size 0.4064)
		(drill 0.2032)
		(layers "F.Cu" "B.Cu")
		(net "GND")
	)
	(via
		(at 327.038208 -72.56526)
		(size 0.508)
		(drill 0.254)
		(layers "F.Cu" "B.Cu")
		(net "GND")
	)
	(via
		(at 61.074808 -296.37482)
		(size 0.4064)
		(drill 0.2032)
		(layers "F.Cu" "B.Cu")
		(net "GND")
	)
	(via
		(at 422.260268 -21.37156)
		(size 0.508)
		(drill 0.254)
		(layers "F.Cu" "B.Cu")
		(net "GND")
	)
	(via
		(at 172.943266 -52.536852)
		(size 0.508)
		(drill 0.254)
		(layers "F.Cu" "B.Cu")
		(net "GND")
	)
	(via
		(at 50.224436 -352.245422)
		(size 0.4572)
		(drill 0.254)
		(layers "F.Cu" "B.Cu")
		(net "GND")
	)
	(via
		(at 163.13277 -120.555004)
		(size 0.508)
		(drill 0.254)
		(layers "F.Cu" "B.Cu")
		(net "GND")
	)
	(via
		(at 137.795 -349.219774)
		(size 0.4572)
		(drill 0.254)
		(layers "F.Cu" "B.Cu")
		(net "GND")
	)
	(via
		(at 259.190236 -306.217066)
		(size 0.508)
		(drill 0.254)
		(layers "F.Cu" "B.Cu")
		(net "GND")
	)
	(via
		(at 107.509564 -161.096452)
		(size 0.508)
		(drill 0.254)
		(layers "F.Cu" "B.Cu")
		(net "GND")
	)
	(via
		(at 121.947686 -411.141926)
		(size 0.4572)
		(drill 0.254)
		(layers "F.Cu" "B.Cu")
		(net "GND")
	)
	(via
		(at 419.349936 -311.099962)
		(size 0.4064)
		(drill 0.2032)
		(layers "F.Cu" "B.Cu")
		(net "GND")
	)
	(via
		(at 203.378562 -362.401866)
		(size 0.508)
		(drill 0.254)
		(layers "F.Cu" "B.Cu")
		(net "GND")
	)
	(via
		(at 122.324622 -209.902298)
		(size 0.508)
		(drill 0.254)
		(layers "F.Cu" "B.Cu")
		(net "GND")
	)
	(via
		(at 166.725092 -298.27474)
		(size 0.4064)
		(drill 0.2032)
		(layers "F.Cu" "B.Cu")
		(net "GND")
	)
	(via
		(at 32.275018 -226.43973)
		(size 0.508)
		(drill 0.254)
		(layers "F.Cu" "B.Cu")
		(net "GND")
	)
	(via
		(at 167.200072 -312.999882)
		(size 0.4064)
		(drill 0.2032)
		(layers "F.Cu" "B.Cu")
		(net "GND")
	)
	(via
		(at 307.999892 -317.749936)
		(size 0.4064)
		(drill 0.2032)
		(layers "F.Cu" "B.Cu")
		(net "GND")
	)
	(via
		(at 46.34992 -306.349908)
		(size 0.4064)
		(drill 0.2032)
		(layers "F.Cu" "B.Cu")
		(net "GND")
	)
	(via
		(at 130.318256 -355.366066)
		(size 0.4572)
		(drill 0.254)
		(layers "F.Cu" "B.Cu")
		(net "GND")
	)
	(via
		(at 393.22502 -287.824926)
		(size 0.4064)
		(drill 0.2032)
		(layers "F.Cu" "B.Cu")
		(net "GND")
	)
	(via
		(at 393.351766 -122.355102)
		(size 0.508)
		(drill 0.254)
		(layers "F.Cu" "B.Cu")
		(net "GND")
	)
	(via
		(at 363.8677 -282.910788)
		(size 0.49022)
		(drill 0.254)
		(layers "F.Cu" "B.Cu")
		(net "GND")
	)
	(via
		(at 359.04805 -232.457244)
		(size 0.508)
		(drill 0.254)
		(layers "F.Cu" "B.Cu")
		(net "GND")
	)
	(via
		(at 413.174942 -296.37482)
		(size 0.4064)
		(drill 0.2032)
		(layers "F.Cu" "B.Cu")
		(net "GND")
	)
	(via
		(at 415.549842 -276.899878)
		(size 0.4064)
		(drill 0.2032)
		(layers "F.Cu" "B.Cu")
		(net "GND")
	)
	(via
		(at 60.767976 -54.238906)
		(size 0.508)
		(drill 0.254)
		(layers "F.Cu" "B.Cu")
		(net "GND")
	)
	(via
		(at 248.098056 -199.787002)
		(size 0.508)
		(drill 0.254)
		(layers "F.Cu" "B.Cu")
		(net "GND")
	)
	(via
		(at 284.249876 -310.149748)
		(size 0.4064)
		(drill 0.2032)
		(layers "F.Cu" "B.Cu")
		(net "GND")
	)
	(via
		(at 384.685032 -341.805514)
		(size 0.4572)
		(drill 0.254)
		(layers "F.Cu" "B.Cu")
		(net "GND")
	)
	(via
		(at 433.96916 -343.073482)
		(size 0.4572)
		(drill 0.254)
		(layers "F.Cu" "B.Cu")
		(net "GND")
	)
	(via
		(at 298.974764 -284.974792)
		(size 0.4064)
		(drill 0.2032)
		(layers "F.Cu" "B.Cu")
		(net "GND")
	)
	(via
		(at 312.305192 -341.805514)
		(size 0.4572)
		(drill 0.254)
		(layers "F.Cu" "B.Cu")
		(net "GND")
	)
	(via
		(at 109.457236 -304.373534)
		(size 0.508)
		(drill 0.254)
		(layers "F.Cu" "B.Cu")
		(net "GND")
	)
	(via
		(at 299.866812 -121.83491)
		(size 0.508)
		(drill 0.254)
		(layers "F.Cu" "B.Cu")
		(net "GND")
	)
	(via
		(at 452.220838 -314.317126)
		(size 0.508)
		(drill 0.254)
		(layers "F.Cu" "B.Cu")
		(net "GND")
	)
	(via
		(at 162.924998 -307.774848)
		(size 0.4064)
		(drill 0.2032)
		(layers "F.Cu" "B.Cu")
		(net "GND")
	)
	(via
		(at 223.75114 -119.883428)
		(size 0.508)
		(drill 0.254)
		(layers "F.Cu" "B.Cu")
		(net "GND")
	)
	(via
		(at 212.310726 -57.439814)
		(size 0.508)
		(drill 0.254)
		(layers "F.Cu" "B.Cu")
		(net "GND")
	)
	(via
		(at 324.11924 -126.049532)
		(size 0.508)
		(drill 0.254)
		(layers "F.Cu" "B.Cu")
		(net "GND")
	)
	(via
		(at 383.72796 -408.840178)
		(size 0.508)
		(drill 0.254)
		(layers "F.Cu" "B.Cu")
		(net "GND")
	)
	(via
		(at 108.904786 -222.382334)
		(size 0.508)
		(drill 0.254)
		(layers "F.Cu" "B.Cu")
		(net "GND")
	)
	(via
		(at 61.074808 -289.724846)
		(size 0.4064)
		(drill 0.2032)
		(layers "F.Cu" "B.Cu")
		(net "GND")
	)
	(via
		(at 67.66687 -147.555204)
		(size 0.508)
		(drill 0.254)
		(layers "F.Cu" "B.Cu")
		(net "GND")
	)
	(via
		(at 130.74777 -404.838662)
		(size 0.508)
		(drill 0.254)
		(layers "F.Cu" "B.Cu")
		(net "GND")
	)
	(via
		(at 267.718286 -253.45644)
		(size 0.508)
		(drill 0.254)
		(layers "F.Cu" "B.Cu")
		(net "GND")
	)
	(via
		(at 51.63312 -100.64496)
		(size 0.508)
		(drill 0.254)
		(layers "F.Cu" "B.Cu")
		(net "GND")
	)
	(via
		(at 162.374072 -73.85177)
		(size 0.508)
		(drill 0.254)
		(layers "F.Cu" "B.Cu")
		(net "GND")
	)
	(via
		(at 131.784852 -131.312666)
		(size 0.508)
		(drill 0.254)
		(layers "F.Cu" "B.Cu")
		(net "GND")
	)
	(via
		(at 198.26605 -142.418054)
		(size 0.508)
		(drill 0.254)
		(layers "F.Cu" "B.Cu")
		(net "GND")
	)
	(via
		(at 170.806364 -129.964942)
		(size 0.508)
		(drill 0.254)
		(layers "F.Cu" "B.Cu")
		(net "GND")
	)
	(via
		(at 213.134448 -47.936658)
		(size 0.508)
		(drill 0.254)
		(layers "F.Cu" "B.Cu")
		(net "GND")
	)
	(via
		(at 200.503282 -338.13242)
		(size 0.508)
		(drill 0.254)
		(layers "F.Cu" "B.Cu")
		(net "GND")
	)
	(via
		(at 395.862048 -354.098098)
		(size 0.4572)
		(drill 0.254)
		(layers "F.Cu" "B.Cu")
		(net "GND")
	)
	(via
		(at 323.953378 -102.328218)
		(size 0.508)
		(drill 0.254)
		(layers "F.Cu" "B.Cu")
		(net "GND")
	)
	(via
		(at 119.747792 -399.838418)
		(size 0.508)
		(drill 0.254)
		(layers "F.Cu" "B.Cu")
		(net "GND")
	)
	(via
		(at 344.127836 -407.638504)
		(size 0.508)
		(drill 0.254)
		(layers "F.Cu" "B.Cu")
		(net "GND")
	)
	(via
		(at 119.512588 -357.75773)
		(size 0.4064)
		(drill 0.2032)
		(layers "F.Cu" "B.Cu")
		(net "GND")
	)
	(via
		(at 159.124904 -273.574764)
		(size 0.4064)
		(drill 0.2032)
		(layers "F.Cu" "B.Cu")
		(net "GND")
	)
	(via
		(at 182.348886 -27.79014)
		(size 0.508)
		(drill 0.254)
		(layers "F.Cu" "B.Cu")
		(net "GND")
	)
	(via
		(at 16.3957 -128.193546)
		(size 0.508)
		(drill 0.254)
		(layers "F.Cu" "B.Cu")
		(net "GND")
	)
	(via
		(at 421.127682 -385.141978)
		(size 0.508)
		(drill 0.254)
		(layers "F.Cu" "B.Cu")
		(net "GND")
	)
	(via
		(at 373.72798 -348.58579)
		(size 0.4064)
		(drill 0.2032)
		(layers "F.Cu" "B.Cu")
		(net "GND")
	)
	(via
		(at 434.327808 -397.038576)
		(size 0.508)
		(drill 0.254)
		(layers "F.Cu" "B.Cu")
		(net "GND")
	)
	(via
		(at 454.694544 -100.751894)
		(size 0.508)
		(drill 0.254)
		(layers "F.Cu" "B.Cu")
		(net "GND")
	)
	(via
		(at 189.04966 -272.14957)
		(size 0.4064)
		(drill 0.2032)
		(layers "F.Cu" "B.Cu")
		(net "GND")
	)
	(via
		(at 450.650864 -373.42191)
		(size 0.508)
		(drill 0.254)
		(layers "F.Cu" "B.Cu")
		(net "GND")
	)
	(via
		(at 70.12051 -63.218314)
		(size 0.508)
		(drill 0.254)
		(layers "F.Cu" "B.Cu")
		(net "GND")
	)
	(via
		(at 170.524932 -293.52494)
		(size 0.4064)
		(drill 0.2032)
		(layers "F.Cu" "B.Cu")
		(net "GND")
	)
	(via
		(at 65.349882 -280.699718)
		(size 0.4064)
		(drill 0.2032)
		(layers "F.Cu" "B.Cu")
		(net "GND")
	)
	(via
		(at 442.580776 -29.589984)
		(size 0.508)
		(drill 0.254)
		(layers "F.Cu" "B.Cu")
		(net "GND")
	)
	(via
		(at 182.39994 -318.699896)
		(size 0.4064)
		(drill 0.2032)
		(layers "F.Cu" "B.Cu")
		(net "GND")
	)
	(via
		(at 195.423282 -54.067456)
		(size 0.508)
		(drill 0.254)
		(layers "F.Cu" "B.Cu")
		(net "GND")
	)
	(via
		(at 304.527712 -369.938808)
		(size 0.508)
		(drill 0.254)
		(layers "F.Cu" "B.Cu")
		(net "GND")
	)
	(via
		(at 452.919084 -106.779822)
		(size 0.508)
		(drill 0.254)
		(layers "F.Cu" "B.Cu")
		(net "GND")
	)
	(via
		(at 44.94784 -371.140482)
		(size 0.508)
		(drill 0.254)
		(layers "F.Cu" "B.Cu")
		(net "GND")
	)
	(via
		(at 414.74771 -147.555204)
		(size 0.508)
		(drill 0.254)
		(layers "F.Cu" "B.Cu")
		(net "GND")
	)
	(via
		(at 302.838612 -23.880318)
		(size 0.508)
		(drill 0.254)
		(layers "F.Cu" "B.Cu")
		(net "GND")
	)
	(via
		(at 168.952164 -125.955044)
		(size 0.508)
		(drill 0.254)
		(layers "F.Cu" "B.Cu")
		(net "GND")
	)
	(via
		(at 319.781936 -357.123746)
		(size 0.4572)
		(drill 0.254)
		(layers "F.Cu" "B.Cu")
		(net "GND")
	)
	(via
		(at 158.658052 -58.156094)
		(size 0.508)
		(drill 0.254)
		(layers "F.Cu" "B.Cu")
		(net "GND")
	)
	(via
		(at 64.59347 -136.645142)
		(size 0.508)
		(drill 0.254)
		(layers "F.Cu" "B.Cu")
		(net "GND")
	)
	(via
		(at 403.00656 -135.364982)
		(size 0.508)
		(drill 0.254)
		(layers "F.Cu" "B.Cu")
		(net "GND")
	)
	(via
		(at 158.649924 -310.149748)
		(size 0.4064)
		(drill 0.2032)
		(layers "F.Cu" "B.Cu")
		(net "GND")
	)
	(via
		(at 22.243796 -341.805514)
		(size 0.4572)
		(drill 0.254)
		(layers "F.Cu" "B.Cu")
		(net "GND")
	)
	(via
		(at 128.102614 -206.25816)
		(size 0.508)
		(drill 0.254)
		(layers "F.Cu" "B.Cu")
		(net "GND")
	)
	(via
		(at 302.774858 -284.024832)
		(size 0.4064)
		(drill 0.2032)
		(layers "F.Cu" "B.Cu")
		(net "GND")
	)
	(via
		(at 269.999714 -309.199788)
		(size 0.4064)
		(drill 0.2032)
		(layers "F.Cu" "B.Cu")
		(net "GND")
	)
	(via
		(at 438.336944 -357.123746)
		(size 0.4572)
		(drill 0.254)
		(layers "F.Cu" "B.Cu")
		(net "GND")
	)
	(via
		(at 51.099974 -277.849838)
		(size 0.4064)
		(drill 0.2032)
		(layers "F.Cu" "B.Cu")
		(net "GND")
	)
	(via
		(at 286.906462 -104.244902)
		(size 0.508)
		(drill 0.254)
		(layers "F.Cu" "B.Cu")
		(net "GND")
	)
	(via
		(at 387.999986 -317.749936)
		(size 0.4064)
		(drill 0.2032)
		(layers "F.Cu" "B.Cu")
		(net "GND")
	)
	(via
		(at 105.43413 -381.6985)
		(size 0.508)
		(drill 0.254)
		(layers "F.Cu" "B.Cu")
		(net "GND")
	)
	(via
		(at 6.558026 -137.344404)
		(size 0.508)
		(drill 0.254)
		(layers "F.Cu" "B.Cu")
		(net "GND")
	)
	(via
		(at 380.317248 -343.073482)
		(size 0.4572)
		(drill 0.254)
		(layers "F.Cu" "B.Cu")
		(net "GND")
	)
	(via
		(at 291.092382 -345.465146)
		(size 0.4064)
		(drill 0.2032)
		(layers "F.Cu" "B.Cu")
		(net "GND")
	)
	(via
		(at 283.774896 -297.32478)
		(size 0.4064)
		(drill 0.2032)
		(layers "F.Cu" "B.Cu")
		(net "GND")
	)
	(via
		(at 215.668352 -241.574574)
		(size 0.508)
		(drill 0.254)
		(layers "F.Cu" "B.Cu")
		(net "GND")
	)
	(via
		(at 31.747968 -382.84023)
		(size 0.508)
		(drill 0.254)
		(layers "F.Cu" "B.Cu")
		(net "GND")
	)
	(via
		(at 393.351766 -98.845116)
		(size 0.508)
		(drill 0.254)
		(layers "F.Cu" "B.Cu")
		(net "GND")
	)
	(via
		(at 316.672976 -358.391714)
		(size 0.4572)
		(drill 0.254)
		(layers "F.Cu" "B.Cu")
		(net "GND")
	)
	(via
		(at 414.281874 -186.03722)
		(size 0.508)
		(drill 0.254)
		(layers "F.Cu" "B.Cu")
		(net "GND")
	)
	(via
		(at 300.874684 -303.024794)
		(size 0.4064)
		(drill 0.2032)
		(layers "F.Cu" "B.Cu")
		(net "GND")
	)
	(via
		(at 32.800036 -38.315138)
		(size 0.508)
		(drill 0.254)
		(layers "F.Cu" "B.Cu")
		(net "GND")
	)
	(via
		(at 182.39994 -313.949842)
		(size 0.4064)
		(drill 0.2032)
		(layers "F.Cu" "B.Cu")
		(net "GND")
	)
	(via
		(at 291.84981 -312.049922)
		(size 0.4064)
		(drill 0.2032)
		(layers "F.Cu" "B.Cu")
		(net "GND")
	)
	(via
		(at 418.42436 -354.098098)
		(size 0.4572)
		(drill 0.254)
		(layers "F.Cu" "B.Cu")
		(net "GND")
	)
	(via
		(at 364.858046 -56.809894)
		(size 0.508)
		(drill 0.254)
		(layers "F.Cu" "B.Cu")
		(net "GND")
	)
	(via
		(at 368.652298 -87.784686)
		(size 0.508)
		(drill 0.254)
		(layers "F.Cu" "B.Cu")
		(net "GND")
	)
	(via
		(at 327.6854 -63.218314)
		(size 0.508)
		(drill 0.254)
		(layers "F.Cu" "B.Cu")
		(net "GND")
	)
	(via
		(at 337.5279 -371.038628)
		(size 0.508)
		(drill 0.254)
		(layers "F.Cu" "B.Cu")
		(net "GND")
	)
	(via
		(at 379.327918 -403.738588)
		(size 0.508)
		(drill 0.254)
		(layers "F.Cu" "B.Cu")
		(net "GND")
	)
	(via
		(at 106.837226 -307.242718)
		(size 0.508)
		(drill 0.254)
		(layers "F.Cu" "B.Cu")
		(net "GND")
	)
	(via
		(at 190.348108 -123.635008)
		(size 0.508)
		(drill 0.254)
		(layers "F.Cu" "B.Cu")
		(net "GND")
	)
	(via
		(at 47.96028 -20.35556)
		(size 0.508)
		(drill 0.254)
		(layers "F.Cu" "B.Cu")
		(net "GND")
	)
	(via
		(at 130.00228 -57.461404)
		(size 0.508)
		(drill 0.254)
		(layers "F.Cu" "B.Cu")
		(net "GND")
	)
	(via
		(at 367.055654 -63.218314)
		(size 0.508)
		(drill 0.254)
		(layers "F.Cu" "B.Cu")
		(net "GND")
	)
	(via
		(at 313.224926 -298.27474)
		(size 0.4064)
		(drill 0.2032)
		(layers "F.Cu" "B.Cu")
		(net "GND")
	)
	(via
		(at 281.394154 -354.098098)
		(size 0.4572)
		(drill 0.254)
		(layers "F.Cu" "B.Cu")
		(net "GND")
	)
	(via
		(at 419.824916 -294.4749)
		(size 0.4064)
		(drill 0.2032)
		(layers "F.Cu" "B.Cu")
		(net "GND")
	)
	(via
		(at 165.299898 -273.099784)
		(size 0.4064)
		(drill 0.2032)
		(layers "F.Cu" "B.Cu")
		(net "GND")
	)
	(via
		(at 117.882416 -352.245422)
		(size 0.4572)
		(drill 0.254)
		(layers "F.Cu" "B.Cu")
		(net "GND")
	)
	(via
		(at 160.509712 -357.75773)
		(size 0.4064)
		(drill 0.2032)
		(layers "F.Cu" "B.Cu")
		(net "GND")
	)
	(via
		(at 308.474872 -303.024794)
		(size 0.4064)
		(drill 0.2032)
		(layers "F.Cu" "B.Cu")
		(net "GND")
	)
	(via
		(at 65.81267 -145.755106)
		(size 0.508)
		(drill 0.254)
		(layers "F.Cu" "B.Cu")
		(net "GND")
	)
	(via
		(at 56.87695 -138.15695)
		(size 0.508)
		(drill 0.254)
		(layers "F.Cu" "B.Cu")
		(net "GND")
	)
	(via
		(at 453.288908 -143.279368)
		(size 0.508)
		(drill 0.254)
		(layers "F.Cu" "B.Cu")
		(net "GND")
	)
	(via
		(at 286.871918 -49.574704)
		(size 0.508)
		(drill 0.254)
		(layers "F.Cu" "B.Cu")
		(net "GND")
	)
	(via
		(at 106.313732 -332.872842)
		(size 0.508)
		(drill 0.254)
		(layers "F.Cu" "B.Cu")
		(net "GND")
	)
	(via
		(at 272.374868 -281.174952)
		(size 0.4064)
		(drill 0.2032)
		(layers "F.Cu" "B.Cu")
		(net "GND")
	)
	(via
		(at 435.227984 -349.219774)
		(size 0.4572)
		(drill 0.254)
		(layers "F.Cu" "B.Cu")
		(net "GND")
	)
	(via
		(at 43.622722 -23.880318)
		(size 0.508)
		(drill 0.254)
		(layers "F.Cu" "B.Cu")
		(net "GND")
	)
	(via
		(at 360.35488 -34.990024)
		(size 0.508)
		(drill 0.254)
		(layers "F.Cu" "B.Cu")
		(net "GND")
	)
	(via
		(at 183.82488 -291.624766)
		(size 0.4064)
		(drill 0.2032)
		(layers "F.Cu" "B.Cu")
		(net "GND")
	)
	(via
		(at 287.612074 -357.123746)
		(size 0.4572)
		(drill 0.254)
		(layers "F.Cu" "B.Cu")
		(net "GND")
	)
	(via
		(at 382.12014 -33.19018)
		(size 0.508)
		(drill 0.254)
		(layers "F.Cu" "B.Cu")
		(net "GND")
	)
	(via
		(at 400.349974 -315.849762)
		(size 0.4064)
		(drill 0.2032)
		(layers "F.Cu" "B.Cu")
		(net "GND")
	)
	(via
		(at 450.682106 -365.24565)
		(size 0.508)
		(drill 0.254)
		(layers "F.Cu" "B.Cu")
		(net "GND")
	)
	(via
		(at 426.851572 -98.021648)
		(size 0.508)
		(drill 0.254)
		(layers "F.Cu" "B.Cu")
		(net "GND")
	)
	(via
		(at 106.308398 -330.250038)
		(size 0.508)
		(drill 0.254)
		(layers "F.Cu" "B.Cu")
		(net "GND")
	)
	(via
		(at 338.328 -417.82492)
		(size 0.508)
		(drill 0.254)
		(layers "F.Cu" "B.Cu")
		(net "GND")
	)
	(via
		(at 388.474966 -289.724846)
		(size 0.4064)
		(drill 0.2032)
		(layers "F.Cu" "B.Cu")
		(net "GND")
	)
	(via
		(at 68.674742 -303.024794)
		(size 0.4064)
		(drill 0.2032)
		(layers "F.Cu" "B.Cu")
		(net "GND")
	)
	(via
		(at 194.336924 -341.781638)
		(size 0.4572)
		(drill 0.254)
		(layers "F.Cu" "B.Cu")
		(net "GND")
	)
	(via
		(at 285.199836 -312.999882)
		(size 0.4064)
		(drill 0.2032)
		(layers "F.Cu" "B.Cu")
		(net "GND")
	)
	(via
		(at 35.739578 -299.2247)
		(size 0.4064)
		(drill 0.2032)
		(layers "F.Cu" "B.Cu")
		(net "GND")
	)
	(via
		(at 165.09746 -355.366066)
		(size 0.4572)
		(drill 0.254)
		(layers "F.Cu" "B.Cu")
		(net "GND")
	)
	(via
		(at 364.580932 -31.390082)
		(size 0.508)
		(drill 0.254)
		(layers "F.Cu" "B.Cu")
		(net "GND")
	)
	(via
		(at 185.725054 -292.574726)
		(size 0.4064)
		(drill 0.2032)
		(layers "F.Cu" "B.Cu")
		(net "GND")
	)
	(via
		(at 403.00656 -109.644942)
		(size 0.508)
		(drill 0.254)
		(layers "F.Cu" "B.Cu")
		(net "GND")
	)
	(via
		(at 142.474442 -253.45644)
		(size 0.508)
		(drill 0.254)
		(layers "F.Cu" "B.Cu")
		(net "GND")
	)
	(via
		(at 270.474948 -289.724846)
		(size 0.4064)
		(drill 0.2032)
		(layers "F.Cu" "B.Cu")
		(net "GND")
	)
	(via
		(at 161.500058 -306.349908)
		(size 0.4064)
		(drill 0.2032)
		(layers "F.Cu" "B.Cu")
		(net "GND")
	)
	(via
		(at 315.124846 -293.52494)
		(size 0.4064)
		(drill 0.2032)
		(layers "F.Cu" "B.Cu")
		(net "GND")
	)
	(via
		(at 80.54975 -283.549852)
		(size 0.4064)
		(drill 0.2032)
		(layers "F.Cu" "B.Cu")
		(net "GND")
	)
	(via
		(at 78.649576 -281.649932)
		(size 0.4064)
		(drill 0.2032)
		(layers "F.Cu" "B.Cu")
		(net "GND")
	)
	(via
		(at 387.999986 -308.249828)
		(size 0.4064)
		(drill 0.2032)
		(layers "F.Cu" "B.Cu")
		(net "GND")
	)
	(via
		(at 229.827582 -232.49636)
		(size 0.508)
		(drill 0.254)
		(layers "F.Cu" "B.Cu")
		(net "GND")
	)
	(via
		(at 395.613382 -34.718498)
		(size 0.508)
		(drill 0.254)
		(layers "F.Cu" "B.Cu")
		(net "GND")
	)
	(via
		(at 255.171194 -394.270738)
		(size 0.508)
		(drill 0.254)
		(layers "F.Cu" "B.Cu")
		(net "GND")
	)
	(via
		(at 322.933314 -100.803964)
		(size 0.508)
		(drill 0.254)
		(layers "F.Cu" "B.Cu")
		(net "GND")
	)
	(via
		(at 247.960642 -128.193546)
		(size 0.508)
		(drill 0.254)
		(layers "F.Cu" "B.Cu")
		(net "GND")
	)
	(via
		(at 16.558006 -57.521094)
		(size 0.508)
		(drill 0.254)
		(layers "F.Cu" "B.Cu")
		(net "GND")
	)
	(via
		(at 311.799478 -287.349946)
		(size 0.4064)
		(drill 0.2032)
		(layers "F.Cu" "B.Cu")
		(net "GND")
	)
	(via
		(at 287.983422 -348.58579)
		(size 0.4064)
		(drill 0.2032)
		(layers "F.Cu" "B.Cu")
		(net "GND")
	)
	(via
		(at 74.374756 -300.174914)
		(size 0.4064)
		(drill 0.2032)
		(layers "F.Cu" "B.Cu")
		(net "GND")
	)
	(via
		(at 161.6202 -56.441848)
		(size 0.508)
		(drill 0.254)
		(layers "F.Cu" "B.Cu")
		(net "GND")
	)
	(via
		(at 133.427216 -341.805514)
		(size 0.4572)
		(drill 0.254)
		(layers "F.Cu" "B.Cu")
		(net "GND")
	)
	(via
		(at 361.57281 -34.990024)
		(size 0.508)
		(drill 0.254)
		(layers "F.Cu" "B.Cu")
		(net "GND")
	)
	(via
		(at 61.17463 -343.073482)
		(size 0.4572)
		(drill 0.254)
		(layers "F.Cu" "B.Cu")
		(net "GND")
	)
	(via
		(at 280.451306 -45.865288)
		(size 0.508)
		(drill 0.254)
		(layers "F.Cu" "B.Cu")
		(net "GND")
	)
	(via
		(at 36.849812 -312.999882)
		(size 0.4064)
		(drill 0.2032)
		(layers "F.Cu" "B.Cu")
		(net "GND")
	)
	(via
		(at 314.366148 -133.30809)
		(size 0.508)
		(drill 0.254)
		(layers "F.Cu" "B.Cu")
		(net "GND")
	)
	(via
		(at 117.656864 -317.69304)
		(size 0.508)
		(drill 0.254)
		(layers "F.Cu" "B.Cu")
		(net "GND")
	)
	(via
		(at 365.158274 -123.097036)
		(size 0.508)
		(drill 0.254)
		(layers "F.Cu" "B.Cu")
		(net "GND")
	)
	(via
		(at 128.46812 -352.245422)
		(size 0.4572)
		(drill 0.254)
		(layers "F.Cu" "B.Cu")
		(net "GND")
	)
	(via
		(at 247.002808 -74.624184)
		(size 0.508)
		(drill 0.254)
		(layers "F.Cu" "B.Cu")
		(net "GND")
	)
	(via
		(at 405.639524 -73.765918)
		(size 0.508)
		(drill 0.254)
		(layers "F.Cu" "B.Cu")
		(net "GND")
	)
	(via
		(at 285.674816 -289.724846)
		(size 0.4064)
		(drill 0.2032)
		(layers "F.Cu" "B.Cu")
		(net "GND")
	)
	(via
		(at 117.511068 -348.58579)
		(size 0.4064)
		(drill 0.2032)
		(layers "F.Cu" "B.Cu")
		(net "GND")
	)
	(via
		(at 163.874958 -306.824888)
		(size 0.4064)
		(drill 0.2032)
		(layers "F.Cu" "B.Cu")
		(net "GND")
	)
	(via
		(at 401.774914 -306.824888)
		(size 0.4064)
		(drill 0.2032)
		(layers "F.Cu" "B.Cu")
		(net "GND")
	)
	(via
		(at 313.935364 -351.611438)
		(size 0.4064)
		(drill 0.2032)
		(layers "F.Cu" "B.Cu")
		(net "GND")
	)
	(via
		(at 183.766714 -129.445004)
		(size 0.508)
		(drill 0.254)
		(layers "F.Cu" "B.Cu")
		(net "GND")
	)
	(via
		(at 390.902952 -354.098098)
		(size 0.4572)
		(drill 0.254)
		(layers "F.Cu" "B.Cu")
		(net "GND")
	)
	(via
		(at 419.824916 -303.974754)
		(size 0.4064)
		(drill 0.2032)
		(layers "F.Cu" "B.Cu")
		(net "GND")
	)
	(via
		(at 137.446766 -210.39709)
		(size 0.508)
		(drill 0.254)
		(layers "F.Cu" "B.Cu")
		(net "GND")
	)
	(via
		(at 404.172166 -33.857692)
		(size 0.508)
		(drill 0.254)
		(layers "F.Cu" "B.Cu")
		(net "GND")
	)
	(via
		(at 73.819512 -38.701218)
		(size 0.508)
		(drill 0.254)
		(layers "F.Cu" "B.Cu")
		(net "GND")
	)
	(via
		(at 99.960176 -21.37156)
		(size 0.508)
		(drill 0.254)
		(layers "F.Cu" "B.Cu")
		(net "GND")
	)
	(via
		(at 121.947686 -408.738578)
		(size 0.508)
		(drill 0.254)
		(layers "F.Cu" "B.Cu")
		(net "GND")
	)
	(via
		(at 51.48326 -358.391714)
		(size 0.4572)
		(drill 0.254)
		(layers "F.Cu" "B.Cu")
		(net "GND")
	)
	(via
		(at 18.243804 -122.09907)
		(size 0.508)
		(drill 0.254)
		(layers "F.Cu" "B.Cu")
		(net "GND")
	)
	(via
		(at 161.15157 -137.16508)
		(size 0.508)
		(drill 0.254)
		(layers "F.Cu" "B.Cu")
		(net "GND")
	)
	(via
		(at 329.108816 -343.073482)
		(size 0.4572)
		(drill 0.254)
		(layers "F.Cu" "B.Cu")
		(net "GND")
	)
	(via
		(at 398.59966 -357.75773)
		(size 0.4064)
		(drill 0.2032)
		(layers "F.Cu" "B.Cu")
		(net "GND")
	)
	(via
		(at 447.536062 -179.534058)
		(size 0.508)
		(drill 0.254)
		(layers "F.Cu" "B.Cu")
		(net "GND")
	)
	(via
		(at 424.09999 -310.149748)
		(size 0.4064)
		(drill 0.2032)
		(layers "F.Cu" "B.Cu")
		(net "GND")
	)
	(via
		(at 286.149796 -312.049922)
		(size 0.4064)
		(drill 0.2032)
		(layers "F.Cu" "B.Cu")
		(net "GND")
	)
	(via
		(at 85.819996 -29.590238)
		(size 0.508)
		(drill 0.254)
		(layers "F.Cu" "B.Cu")
		(net "GND")
	)
	(via
		(at 43.499786 -318.699896)
		(size 0.4064)
		(drill 0.2032)
		(layers "F.Cu" "B.Cu")
		(net "GND")
	)
	(via
		(at 91.888818 -99.625912)
		(size 0.508)
		(drill 0.254)
		(layers "F.Cu" "B.Cu")
		(net "GND")
	)
	(via
		(at 4.562856 -124.281692)
		(size 0.508)
		(drill 0.254)
		(layers "F.Cu" "B.Cu")
		(net "GND")
	)
	(via
		(at 69.473318 -73.20026)
		(size 0.508)
		(drill 0.254)
		(layers "F.Cu" "B.Cu")
		(net "GND")
	)
	(via
		(at 431.840386 -152.683464)
		(size 0.508)
		(drill 0.254)
		(layers "F.Cu" "B.Cu")
		(net "GND")
	)
	(via
		(at 274.274788 -275.474938)
		(size 0.4064)
		(drill 0.2032)
		(layers "F.Cu" "B.Cu")
		(net "GND")
	)
	(via
		(at 286.585406 -34.183066)
		(size 0.508)
		(drill 0.254)
		(layers "F.Cu" "B.Cu")
		(net "GND")
	)
	(via
		(at 170.049952 -281.649932)
		(size 0.4064)
		(drill 0.2032)
		(layers "F.Cu" "B.Cu")
		(net "GND")
	)
	(via
		(at 51.63312 -135.364982)
		(size 0.508)
		(drill 0.254)
		(layers "F.Cu" "B.Cu")
		(net "GND")
	)
	(via
		(at 280.781252 -34.718498)
		(size 0.508)
		(drill 0.254)
		(layers "F.Cu" "B.Cu")
		(net "GND")
	)
	(via
		(at 340.285832 -346.09913)
		(size 0.4572)
		(drill 0.254)
		(layers "F.Cu" "B.Cu")
		(net "GND")
	)
	(via
		(at 278.451056 -396.82039)
		(size 0.508)
		(drill 0.254)
		(layers "F.Cu" "B.Cu")
		(net "GND")
	)
	(via
		(at 244.69344 -30.850586)
		(size 0.508)
		(drill 0.254)
		(layers "F.Cu" "B.Cu")
		(net "GND")
	)
	(via
		(at 123.292616 -6.292342)
		(size 0.508)
		(drill 0.254)
		(layers "F.Cu" "B.Cu")
		(net "GND")
	)
	(via
		(at 360.170476 -289.41649)
		(size 0.508)
		(drill 0.254)
		(layers "F.Cu" "B.Cu")
		(net "GND")
	)
	(via
		(at 65.542414 -355.366066)
		(size 0.4572)
		(drill 0.254)
		(layers "F.Cu" "B.Cu")
		(net "GND")
	)
	(via
		(at 143.370554 -28.802076)
		(size 0.508)
		(drill 0.254)
		(layers "F.Cu" "B.Cu")
		(net "GND")
	)
	(via
		(at 103.944674 -285.953454)
		(size 0.508)
		(drill 0.254)
		(layers "F.Cu" "B.Cu")
		(net "GND")
	)
	(via
		(at 401.15236 -131.76504)
		(size 0.508)
		(drill 0.254)
		(layers "F.Cu" "B.Cu")
		(net "GND")
	)
	(via
		(at 86.747858 -376.140218)
		(size 0.508)
		(drill 0.254)
		(layers "F.Cu" "B.Cu")
		(net "GND")
	)
	(via
		(at 186.200034 -317.749936)
		(size 0.4064)
		(drill 0.2032)
		(layers "F.Cu" "B.Cu")
		(net "GND")
	)
	(via
		(at 190.348108 -143.955008)
		(size 0.508)
		(drill 0.254)
		(layers "F.Cu" "B.Cu")
		(net "GND")
	)
	(via
		(at 270.601694 -111.175546)
		(size 0.508)
		(drill 0.254)
		(layers "F.Cu" "B.Cu")
		(net "GND")
	)
	(via
		(at 38.274752 -273.574764)
		(size 0.4064)
		(drill 0.2032)
		(layers "F.Cu" "B.Cu")
		(net "GND")
	)
	(via
		(at 17.69618 -161.54527)
		(size 0.508)
		(drill 0.254)
		(layers "F.Cu" "B.Cu")
		(net "GND")
	)
	(via
		(at 269.049754 -311.099962)
		(size 0.4064)
		(drill 0.2032)
		(layers "F.Cu" "B.Cu")
		(net "GND")
	)
	(via
		(at 275.224748 -300.174914)
		(size 0.4064)
		(drill 0.2032)
		(layers "F.Cu" "B.Cu")
		(net "GND")
	)
	(via
		(at 161.54781 -385.141978)
		(size 0.508)
		(drill 0.254)
		(layers "F.Cu" "B.Cu")
		(net "GND")
	)
	(via
		(at 114.402108 -342.439498)
		(size 0.4064)
		(drill 0.2032)
		(layers "F.Cu" "B.Cu")
		(net "GND")
	)
	(via
		(at 133.840982 -178.77028)
		(size 0.508)
		(drill 0.254)
		(layers "F.Cu" "B.Cu")
		(net "GND")
	)
	(via
		(at 332.781148 -29.859478)
		(size 0.508)
		(drill 0.254)
		(layers "F.Cu" "B.Cu")
		(net "GND")
	)
	(via
		(at 321.632072 -358.391714)
		(size 0.4572)
		(drill 0.254)
		(layers "F.Cu" "B.Cu")
		(net "GND")
	)
	(via
		(at 339.728048 -407.638504)
		(size 0.508)
		(drill 0.254)
		(layers "F.Cu" "B.Cu")
		(net "GND")
	)
	(via
		(at 376.858022 -299.133514)
		(size 0.508)
		(drill 0.254)
		(layers "F.Cu" "B.Cu")
		(net "GND")
	)
	(via
		(at 300.874684 -286.874966)
		(size 0.4064)
		(drill 0.2032)
		(layers "F.Cu" "B.Cu")
		(net "GND")
	)
	(via
		(at 77.947774 -383.940304)
		(size 0.508)
		(drill 0.254)
		(layers "F.Cu" "B.Cu")
		(net "GND")
	)
	(via
		(at 131.021074 -277.004272)
		(size 0.508)
		(drill 0.254)
		(layers "F.Cu" "B.Cu")
		(net "GND")
	)
	(via
		(at 412.89351 -147.555204)
		(size 0.508)
		(drill 0.254)
		(layers "F.Cu" "B.Cu")
		(net "GND")
	)
	(via
		(at 231.954324 -85.468206)
		(size 0.508)
		(drill 0.254)
		(layers "F.Cu" "B.Cu")
		(net "GND")
	)
	(via
		(at 378.467112 -347.951806)
		(size 0.4572)
		(drill 0.254)
		(layers "F.Cu" "B.Cu")
		(net "GND")
	)
	(via
		(at 151.999696 -312.049668)
		(size 0.4064)
		(drill 0.2032)
		(layers "F.Cu" "B.Cu")
		(net "GND")
	)
	(via
		(at 159.347916 -403.738588)
		(size 0.508)
		(drill 0.254)
		(layers "F.Cu" "B.Cu")
		(net "GND")
	)
	(via
		(at 278.074882 -300.174914)
		(size 0.4064)
		(drill 0.2032)
		(layers "F.Cu" "B.Cu")
		(net "GND")
	)
	(via
		(at 408.424888 -287.899856)
		(size 0.4064)
		(drill 0.2032)
		(layers "F.Cu" "B.Cu")
		(net "GND")
	)
	(via
		(at 272.067274 -354.074222)
		(size 0.4572)
		(drill 0.254)
		(layers "F.Cu" "B.Cu")
		(net "GND")
	)
	(via
		(at 313.564016 -341.805514)
		(size 0.4572)
		(drill 0.254)
		(layers "F.Cu" "B.Cu")
		(net "GND")
	)
	(via
		(at 39.90213 -57.461404)
		(size 0.508)
		(drill 0.254)
		(layers "F.Cu" "B.Cu")
		(net "GND")
	)
	(via
		(at 310.849772 -287.349946)
		(size 0.4064)
		(drill 0.2032)
		(layers "F.Cu" "B.Cu")
		(net "GND")
	)
	(via
		(at 416.580828 -31.390082)
		(size 0.508)
		(drill 0.254)
		(layers "F.Cu" "B.Cu")
		(net "GND")
	)
	(via
		(at 298.10202 -58.096404)
		(size 0.508)
		(drill 0.254)
		(layers "F.Cu" "B.Cu")
		(net "GND")
	)
	(via
		(at 181.901084 -343.073482)
		(size 0.4572)
		(drill 0.254)
		(layers "F.Cu" "B.Cu")
		(net "GND")
	)
	(via
		(at 170.347894 -400.938492)
		(size 0.508)
		(drill 0.254)
		(layers "F.Cu" "B.Cu")
		(net "GND")
	)
	(via
		(at 103.15067 -291.32149)
		(size 0.508)
		(drill 0.254)
		(layers "F.Cu" "B.Cu")
		(net "GND")
	)
	(via
		(at 36.849812 -303.499774)
		(size 0.4064)
		(drill 0.2032)
		(layers "F.Cu" "B.Cu")
		(net "GND")
	)
	(via
		(at 54.70652 -106.044746)
		(size 0.508)
		(drill 0.254)
		(layers "F.Cu" "B.Cu")
		(net "GND")
	)
	(via
		(at 74.849736 -274.999958)
		(size 0.4064)
		(drill 0.2032)
		(layers "F.Cu" "B.Cu")
		(net "GND")
	)
	(via
		(at 313.09818 -133.30809)
		(size 0.508)
		(drill 0.254)
		(layers "F.Cu" "B.Cu")
		(net "GND")
	)
	(via
		(at 156.750004 -302.549814)
		(size 0.4064)
		(drill 0.2032)
		(layers "F.Cu" "B.Cu")
		(net "GND")
	)
	(via
		(at 35.93846 -347.951806)
		(size 0.4572)
		(drill 0.254)
		(layers "F.Cu" "B.Cu")
		(net "GND")
	)
	(via
		(at 430.749964 -275.949918)
		(size 0.4064)
		(drill 0.2032)
		(layers "F.Cu" "B.Cu")
		(net "GND")
	)
	(via
		(at 281.44343 -172.172122)
		(size 0.508)
		(drill 0.254)
		(layers "F.Cu" "B.Cu")
		(net "GND")
	)
	(via
		(at 162.0393 -31.652972)
		(size 0.508)
		(drill 0.254)
		(layers "F.Cu" "B.Cu")
		(net "GND")
	)
	(via
		(at 314.366148 -123.356878)
		(size 0.508)
		(drill 0.254)
		(layers "F.Cu" "B.Cu")
		(net "GND")
	)
	(via
		(at 28.64993 -310.832246)
		(size 0.508)
		(drill 0.254)
		(layers "F.Cu" "B.Cu")
		(net "GND")
	)
	(via
		(at 20.39366 -344.831162)
		(size 0.4572)
		(drill 0.254)
		(layers "F.Cu" "B.Cu")
		(net "GND")
	)
	(via
		(at 449.623942 -26.319734)
		(size 0.508)
		(drill 0.254)
		(layers "F.Cu" "B.Cu")
		(net "GND")
	)
	(via
		(at 119.512588 -345.465146)
		(size 0.4064)
		(drill 0.2032)
		(layers "F.Cu" "B.Cu")
		(net "GND")
	)
	(via
		(at 158.05658 -219.654374)
		(size 0.508)
		(drill 0.254)
		(layers "F.Cu" "B.Cu")
		(net "GND")
	)
	(via
		(at 416.574224 -357.123746)
		(size 0.4572)
		(drill 0.254)
		(layers "F.Cu" "B.Cu")
		(net "GND")
	)
	(via
		(at 297.549824 -316.799722)
		(size 0.4064)
		(drill 0.2032)
		(layers "F.Cu" "B.Cu")
		(net "GND")
	)
	(via
		(at 432.490372 -357.75773)
		(size 0.4064)
		(drill 0.2032)
		(layers "F.Cu" "B.Cu")
		(net "GND")
	)
	(via
		(at 394.17498 -299.224954)
		(size 0.4064)
		(drill 0.2032)
		(layers "F.Cu" "B.Cu")
		(net "GND")
	)
	(via
		(at 394.17498 -285.924752)
		(size 0.4064)
		(drill 0.2032)
		(layers "F.Cu" "B.Cu")
		(net "GND")
	)
	(via
		(at 379.327918 -402.241766)
		(size 0.508)
		(drill 0.254)
		(layers "F.Cu" "B.Cu")
		(net "GND")
	)
	(via
		(at 221.59976 -315.311282)
		(size 0.508)
		(drill 0.254)
		(layers "F.Cu" "B.Cu")
		(net "GND")
	)
	(via
		(at 121.947686 -373.441976)
		(size 0.4572)
		(drill 0.254)
		(layers "F.Cu" "B.Cu")
		(net "GND")
	)
	(via
		(at 57.274968 -284.024832)
		(size 0.4064)
		(drill 0.2032)
		(layers "F.Cu" "B.Cu")
		(net "GND")
	)
	(via
		(at 168.148 -382.84023)
		(size 0.508)
		(drill 0.254)
		(layers "F.Cu" "B.Cu")
		(net "GND")
	)
	(via
		(at 129.946908 -354.732082)
		(size 0.4064)
		(drill 0.2032)
		(layers "F.Cu" "B.Cu")
		(net "GND")
	)
	(via
		(at 91.919298 -125.414532)
		(size 0.508)
		(drill 0.254)
		(layers "F.Cu" "B.Cu")
		(net "GND")
	)
	(via
		(at 393.22502 -284.024832)
		(size 0.4064)
		(drill 0.2032)
		(layers "F.Cu" "B.Cu")
		(net "GND")
	)
	(via
		(at 449.740782 -45.853858)
		(size 0.508)
		(drill 0.254)
		(layers "F.Cu" "B.Cu")
		(net "GND")
	)
	(via
		(at 424.688 -417.82492)
		(size 0.508)
		(drill 0.254)
		(layers "F.Cu" "B.Cu")
		(net "GND")
	)
	(via
		(at 286.624776 -284.974792)
		(size 0.4064)
		(drill 0.2032)
		(layers "F.Cu" "B.Cu")
		(net "GND")
	)
	(via
		(at 281.399742 -273.099784)
		(size 0.4064)
		(drill 0.2032)
		(layers "F.Cu" "B.Cu")
		(net "GND")
	)
	(via
		(at 357.63073 -305.972718)
		(size 0.508)
		(drill 0.254)
		(layers "F.Cu" "B.Cu")
		(net "GND")
	)
	(via
		(at 299.924724 -305.874928)
		(size 0.4064)
		(drill 0.2032)
		(layers "F.Cu" "B.Cu")
		(net "GND")
	)
	(via
		(at 165.64737 -121.692416)
		(size 0.508)
		(drill 0.254)
		(layers "F.Cu" "B.Cu")
		(net "GND")
	)
	(via
		(at 224.258378 -122.0089)
		(size 0.508)
		(drill 0.254)
		(layers "F.Cu" "B.Cu")
		(net "GND")
	)
	(via
		(at 43.635168 -357.75773)
		(size 0.4064)
		(drill 0.2032)
		(layers "F.Cu" "B.Cu")
		(net "GND")
	)
	(via
		(at 310.849772 -310.149748)
		(size 0.4064)
		(drill 0.2032)
		(layers "F.Cu" "B.Cu")
		(net "GND")
	)
	(via
		(at 174.42434 -341.805514)
		(size 0.4572)
		(drill 0.254)
		(layers "F.Cu" "B.Cu")
		(net "GND")
	)
	(via
		(at 229.09276 -315.899546)
		(size 0.508)
		(drill 0.254)
		(layers "F.Cu" "B.Cu")
		(net "GND")
	)
	(via
		(at 152.47493 -282.124912)
		(size 0.4064)
		(drill 0.2032)
		(layers "F.Cu" "B.Cu")
		(net "GND")
	)
	(via
		(at 395.77264 -113.245138)
		(size 0.508)
		(drill 0.254)
		(layers "F.Cu" "B.Cu")
		(net "GND")
	)
	(via
		(at 79.315056 -45.88891)
		(size 0.508)
		(drill 0.254)
		(layers "F.Cu" "B.Cu")
		(net "GND")
	)
	(via
		(at 156.002228 -56.826404)
		(size 0.508)
		(drill 0.254)
		(layers "F.Cu" "B.Cu")
		(net "GND")
	)
	(via
		(at 392.749786 -274.999958)
		(size 0.4064)
		(drill 0.2032)
		(layers "F.Cu" "B.Cu")
		(net "GND")
	)
	(via
		(at 127.33528 -288.14649)
		(size 0.508)
		(drill 0.254)
		(layers "F.Cu" "B.Cu")
		(net "GND")
	)
	(via
		(at 172.574204 -349.219774)
		(size 0.4572)
		(drill 0.254)
		(layers "F.Cu" "B.Cu")
		(net "GND")
	)
	(via
		(at 59.649868 -281.649932)
		(size 0.4064)
		(drill 0.2032)
		(layers "F.Cu" "B.Cu")
		(net "GND")
	)
	(via
		(at 215.389968 -73.85177)
		(size 0.508)
		(drill 0.254)
		(layers "F.Cu" "B.Cu")
		(net "GND")
	)
	(via
		(at 330.138278 -115.732814)
		(size 0.508)
		(drill 0.254)
		(layers "F.Cu" "B.Cu")
		(net "GND")
	)
	(via
		(at 312.21553 -33.248092)
		(size 0.508)
		(drill 0.254)
		(layers "F.Cu" "B.Cu")
		(net "GND")
	)
	(via
		(at 78.964028 -24.539702)
		(size 0.508)
		(drill 0.254)
		(layers "F.Cu" "B.Cu")
		(net "GND")
	)
	(via
		(at 34.679636 -343.073482)
		(size 0.4572)
		(drill 0.254)
		(layers "F.Cu" "B.Cu")
		(net "GND")
	)
	(via
		(at 339.728048 -376.241818)
		(size 0.508)
		(drill 0.254)
		(layers "F.Cu" "B.Cu")
		(net "GND")
	)
	(via
		(at 160.074864 -284.024832)
		(size 0.4064)
		(drill 0.2032)
		(layers "F.Cu" "B.Cu")
		(net "GND")
	)
	(via
		(at 288.99993 -318.699896)
		(size 0.4064)
		(drill 0.2032)
		(layers "F.Cu" "B.Cu")
		(net "GND")
	)
	(via
		(at 396.0749 -304.924714)
		(size 0.4064)
		(drill 0.2032)
		(layers "F.Cu" "B.Cu")
		(net "GND")
	)
	(via
		(at 225.539046 -154.651202)
		(size 0.508)
		(drill 0.254)
		(layers "F.Cu" "B.Cu")
		(net "GND")
	)
	(via
		(at 357.909368 -289.41649)
		(size 0.508)
		(drill 0.254)
		(layers "F.Cu" "B.Cu")
		(net "GND")
	)
	(via
		(at 298.647612 -120.035066)
		(size 0.508)
		(drill 0.254)
		(layers "F.Cu" "B.Cu")
		(net "GND")
	)
	(via
		(at 18.091912 -149.89683)
		(size 0.508)
		(drill 0.254)
		(layers "F.Cu" "B.Cu")
		(net "GND")
	)
	(via
		(at 63.002668 -389.3566)
		(size 0.508)
		(drill 0.254)
		(layers "F.Cu" "B.Cu")
		(net "GND")
	)
	(via
		(at 392.749786 -280.699718)
		(size 0.4064)
		(drill 0.2032)
		(layers "F.Cu" "B.Cu")
		(net "GND")
	)
	(via
		(at 124.968 -417.82492)
		(size 0.508)
		(drill 0.254)
		(layers "F.Cu" "B.Cu")
		(net "GND")
	)
	(via
		(at 267.328142 -345.465146)
		(size 0.4064)
		(drill 0.2032)
		(layers "F.Cu" "B.Cu")
		(net "GND")
	)
	(via
		(at 412.098236 -19.757136)
		(size 0.508)
		(drill 0.254)
		(layers "F.Cu" "B.Cu")
		(net "GND")
	)
	(via
		(at 51.63312 -120.555004)
		(size 0.508)
		(drill 0.254)
		(layers "F.Cu" "B.Cu")
		(net "GND")
	)
	(via
		(at 371.524276 -222.976186)
		(size 0.508)
		(drill 0.254)
		(layers "F.Cu" "B.Cu")
		(net "GND")
	)
	(via
		(at 212.471762 -169.63263)
		(size 0.508)
		(drill 0.254)
		(layers "F.Cu" "B.Cu")
		(net "GND")
	)
	(via
		(at 386.098288 -19.757136)
		(size 0.508)
		(drill 0.254)
		(layers "F.Cu" "B.Cu")
		(net "GND")
	)
	(via
		(at 128.547622 -378.94006)
		(size 0.4572)
		(drill 0.254)
		(layers "F.Cu" "B.Cu")
		(net "GND")
	)
	(via
		(at 82.166206 -142.418054)
		(size 0.508)
		(drill 0.254)
		(layers "F.Cu" "B.Cu")
		(net "GND")
	)
	(via
		(at 273.91741 -347.951806)
		(size 0.4572)
		(drill 0.254)
		(layers "F.Cu" "B.Cu")
		(net "GND")
	)
	(via
		(at 30.373828 -25.971246)
		(size 0.508)
		(drill 0.254)
		(layers "F.Cu" "B.Cu")
		(net "GND")
	)
	(via
		(at 47.115476 -357.123746)
		(size 0.4572)
		(drill 0.254)
		(layers "F.Cu" "B.Cu")
		(net "GND")
	)
	(via
		(at 125.35916 -347.951806)
		(size 0.4572)
		(drill 0.254)
		(layers "F.Cu" "B.Cu")
		(net "GND")
	)
	(via
		(at 136.536176 -341.805514)
		(size 0.4572)
		(drill 0.254)
		(layers "F.Cu" "B.Cu")
		(net "GND")
	)
	(via
		(at 181.92496 -294.4749)
		(size 0.4064)
		(drill 0.2032)
		(layers "F.Cu" "B.Cu")
		(net "GND")
	)
	(via
		(at 382.30302 -290.294314)
		(size 0.508)
		(drill 0.254)
		(layers "F.Cu" "B.Cu")
		(net "GND")
	)
	(via
		(at 236.311186 -45.808138)
		(size 0.508)
		(drill 0.254)
		(layers "F.Cu" "B.Cu")
		(net "GND")
	)
	(via
		(at 381.94742 -342.439498)
		(size 0.4064)
		(drill 0.2032)
		(layers "F.Cu" "B.Cu")
		(net "GND")
	)
	(via
		(at 82.166206 -154.476958)
		(size 0.508)
		(drill 0.254)
		(layers "F.Cu" "B.Cu")
		(net "GND")
	)
	(via
		(at 252.473968 -73.85177)
		(size 0.508)
		(drill 0.254)
		(layers "F.Cu" "B.Cu")
		(net "GND")
	)
	(via
		(at 82.166206 -119.756936)
		(size 0.508)
		(drill 0.254)
		(layers "F.Cu" "B.Cu")
		(net "GND")
	)
	(via
		(at 88.783922 -348.58579)
		(size 0.4064)
		(drill 0.2032)
		(layers "F.Cu" "B.Cu")
		(net "GND")
	)
	(via
		(at 130.318256 -358.391714)
		(size 0.4572)
		(drill 0.254)
		(layers "F.Cu" "B.Cu")
		(net "GND")
	)
	(via
		(at 307.999892 -281.649932)
		(size 0.4064)
		(drill 0.2032)
		(layers "F.Cu" "B.Cu")
		(net "GND")
	)
	(via
		(at 317.008256 -125.163326)
		(size 0.508)
		(drill 0.254)
		(layers "F.Cu" "B.Cu")
		(net "GND")
	)
	(via
		(at 161.15157 -118.754906)
		(size 0.508)
		(drill 0.254)
		(layers "F.Cu" "B.Cu")
		(net "GND")
	)
	(via
		(at 202.868022 -54.238906)
		(size 0.508)
		(drill 0.254)
		(layers "F.Cu" "B.Cu")
		(net "GND")
	)
	(via
		(at 387.999986 -299.699934)
		(size 0.4064)
		(drill 0.2032)
		(layers "F.Cu" "B.Cu")
		(net "GND")
	)
	(via
		(at 41.599866 -314.899802)
		(size 0.4064)
		(drill 0.2032)
		(layers "F.Cu" "B.Cu")
		(net "GND")
	)
	(via
		(at 433.597812 -342.439498)
		(size 0.4064)
		(drill 0.2032)
		(layers "F.Cu" "B.Cu")
		(net "GND")
	)
	(via
		(at 392.971274 -28.05303)
		(size 0.508)
		(drill 0.254)
		(layers "F.Cu" "B.Cu")
		(net "GND")
	)
	(via
		(at 329.71994 -57.076848)
		(size 0.508)
		(drill 0.254)
		(layers "F.Cu" "B.Cu")
		(net "GND")
	)
	(via
		(at 45.520102 -57.076848)
		(size 0.508)
		(drill 0.254)
		(layers "F.Cu" "B.Cu")
		(net "GND")
	)
	(via
		(at 151.999696 -308.250082)
		(size 0.4064)
		(drill 0.2032)
		(layers "F.Cu" "B.Cu")
		(net "GND")
	)
	(via
		(at 416.979862 -303.969928)
		(size 0.4064)
		(drill 0.2032)
		(layers "F.Cu" "B.Cu")
		(net "GND")
	)
	(via
		(at 419.683184 -350.977454)
		(size 0.4572)
		(drill 0.254)
		(layers "F.Cu" "B.Cu")
		(net "GND")
	)
	(via
		(at 196.649848 -314.899802)
		(size 0.4064)
		(drill 0.2032)
		(layers "F.Cu" "B.Cu")
		(net "GND")
	)
	(via
		(at 130.74777 -409.940252)
		(size 0.4572)
		(drill 0.254)
		(layers "F.Cu" "B.Cu")
		(net "GND")
	)
	(via
		(at 115.34775 -407.638504)
		(size 0.508)
		(drill 0.254)
		(layers "F.Cu" "B.Cu")
		(net "GND")
	)
	(via
		(at 168.148 -398.34185)
		(size 0.508)
		(drill 0.254)
		(layers "F.Cu" "B.Cu")
		(net "GND")
	)
	(via
		(at 124.147834 -402.241766)
		(size 0.4572)
		(drill 0.254)
		(layers "F.Cu" "B.Cu")
		(net "GND")
	)
	(via
		(at 156.002228 -58.096404)
		(size 0.508)
		(drill 0.254)
		(layers "F.Cu" "B.Cu")
		(net "GND")
	)
	(via
		(at 361.620054 -397.250412)
		(size 0.508)
		(drill 0.254)
		(layers "F.Cu" "B.Cu")
		(net "GND")
	)
	(via
		(at 119.174768 -290.05149)
		(size 0.508)
		(drill 0.254)
		(layers "F.Cu" "B.Cu")
		(net "GND")
	)
	(via
		(at 285.687262 -102.444804)
		(size 0.508)
		(drill 0.254)
		(layers "F.Cu" "B.Cu")
		(net "GND")
	)
	(via
		(at 26.982928 -348.58579)
		(size 0.4064)
		(drill 0.2032)
		(layers "F.Cu" "B.Cu")
		(net "GND")
	)
	(via
		(at 378.729748 -201.422762)
		(size 0.508)
		(drill 0.254)
		(layers "F.Cu" "B.Cu")
		(net "GND")
	)
	(via
		(at 9.706864 -277.814278)
		(size 0.508)
		(drill 0.254)
		(layers "F.Cu" "B.Cu")
		(net "GND")
	)
	(via
		(at 122.868944 -94.301564)
		(size 0.508)
		(drill 0.254)
		(layers "F.Cu" "B.Cu")
		(net "GND")
	)
	(via
		(at 114.402108 -351.611438)
		(size 0.4064)
		(drill 0.2032)
		(layers "F.Cu" "B.Cu")
		(net "GND")
	)
	(via
		(at 422.199816 -312.999882)
		(size 0.4064)
		(drill 0.2032)
		(layers "F.Cu" "B.Cu")
		(net "GND")
	)
	(via
		(at 3.27152 -51.661822)
		(size 0.508)
		(drill 0.254)
		(layers "F.Cu" "B.Cu")
		(net "GND")
	)
	(via
		(at 43.499786 -305.399948)
		(size 0.4064)
		(drill 0.2032)
		(layers "F.Cu" "B.Cu")
		(net "GND")
	)
	(via
		(at 31.199328 -342.439498)
		(size 0.4064)
		(drill 0.2032)
		(layers "F.Cu" "B.Cu")
		(net "GND")
	)
	(via
		(at 459.713838 -316.65799)
		(size 0.508)
		(drill 0.254)
		(layers "F.Cu" "B.Cu")
		(net "GND")
	)
	(via
		(at 197.600062 -275.949918)
		(size 0.4064)
		(drill 0.2032)
		(layers "F.Cu" "B.Cu")
		(net "GND")
	)
	(via
		(at 43.974766 -287.824926)
		(size 0.4064)
		(drill 0.2032)
		(layers "F.Cu" "B.Cu")
		(net "GND")
	)
	(via
		(at 45.39996 -313.949842)
		(size 0.4064)
		(drill 0.2032)
		(layers "F.Cu" "B.Cu")
		(net "GND")
	)
	(via
		(at 283.24429 -347.951806)
		(size 0.4572)
		(drill 0.254)
		(layers "F.Cu" "B.Cu")
		(net "GND")
	)
	(via
		(at 37.799772 -312.999882)
		(size 0.4064)
		(drill 0.2032)
		(layers "F.Cu" "B.Cu")
		(net "GND")
	)
	(via
		(at 33.528 -417.82492)
		(size 0.508)
		(drill 0.254)
		(layers "F.Cu" "B.Cu")
		(net "GND")
	)
	(via
		(at 120.620028 -351.611438)
		(size 0.4064)
		(drill 0.2032)
		(layers "F.Cu" "B.Cu")
		(net "GND")
	)
	(via
		(at 271.424908 -277.374858)
		(size 0.4064)
		(drill 0.2032)
		(layers "F.Cu" "B.Cu")
		(net "GND")
	)
	(via
		(at 84.196174 -352.245422)
		(size 0.4572)
		(drill 0.254)
		(layers "F.Cu" "B.Cu")
		(net "GND")
	)
	(via
		(at 365.19358 -159.573468)
		(size 0.508)
		(drill 0.254)
		(layers "F.Cu" "B.Cu")
		(net "GND")
	)
	(via
		(at 386.575046 -292.57498)
		(size 0.4064)
		(drill 0.2032)
		(layers "F.Cu" "B.Cu")
		(net "GND")
	)
	(via
		(at 386.574792 -297.32478)
		(size 0.4064)
		(drill 0.2032)
		(layers "F.Cu" "B.Cu")
		(net "GND")
	)
	(via
		(at 119.747792 -372.341902)
		(size 0.4572)
		(drill 0.254)
		(layers "F.Cu" "B.Cu")
		(net "GND")
	)
	(via
		(at 11.7983 -19.757136)
		(size 0.508)
		(drill 0.254)
		(layers "F.Cu" "B.Cu")
		(net "GND")
	)
	(via
		(at 43.974766 -301.124874)
		(size 0.4064)
		(drill 0.2032)
		(layers "F.Cu" "B.Cu")
		(net "GND")
	)
	(via
		(at 61.074808 -306.824888)
		(size 0.4064)
		(drill 0.2032)
		(layers "F.Cu" "B.Cu")
		(net "GND")
	)
	(via
		(at 385.433824 -124.43333)
		(size 0.508)
		(drill 0.254)
		(layers "F.Cu" "B.Cu")
		(net "GND")
	)
	(via
		(at 292.57117 -343.073482)
		(size 0.4572)
		(drill 0.254)
		(layers "F.Cu" "B.Cu")
		(net "GND")
	)
	(via
		(at 398.971008 -347.951806)
		(size 0.4572)
		(drill 0.254)
		(layers "F.Cu" "B.Cu")
		(net "GND")
	)
	(via
		(at 164.864796 -98.845116)
		(size 0.508)
		(drill 0.254)
		(layers "F.Cu" "B.Cu")
		(net "GND")
	)
	(via
		(at 171.31538 -355.366066)
		(size 0.4572)
		(drill 0.254)
		(layers "F.Cu" "B.Cu")
		(net "GND")
	)
	(via
		(at 19.258788 -149.90826)
		(size 0.508)
		(drill 0.254)
		(layers "F.Cu" "B.Cu")
		(net "GND")
	)
	(via
		(at 273.91741 -357.123746)
		(size 0.4572)
		(drill 0.254)
		(layers "F.Cu" "B.Cu")
		(net "GND")
	)
	(via
		(at 287.574736 -289.724846)
		(size 0.4064)
		(drill 0.2032)
		(layers "F.Cu" "B.Cu")
		(net "GND")
	)
	(via
		(at 272.122392 -266.827762)
		(size 0.508)
		(drill 0.254)
		(layers "F.Cu" "B.Cu")
		(net "GND")
	)
	(via
		(at 167.732964 -124.154946)
		(size 0.508)
		(drill 0.254)
		(layers "F.Cu" "B.Cu")
		(net "GND")
	)
	(via
		(at 402.079968 -354.098098)
		(size 0.4572)
		(drill 0.254)
		(layers "F.Cu" "B.Cu")
		(net "GND")
	)
	(via
		(at 89.744804 -27.79014)
		(size 0.508)
		(drill 0.254)
		(layers "F.Cu" "B.Cu")
		(net "GND")
	)
	(via
		(at 266.655042 -33.19018)
		(size 0.508)
		(drill 0.254)
		(layers "F.Cu" "B.Cu")
		(net "GND")
	)
	(via
		(at 81.499964 -318.699896)
		(size 0.4064)
		(drill 0.2032)
		(layers "F.Cu" "B.Cu")
		(net "GND")
	)
	(via
		(at 176.94783 -375.040398)
		(size 0.508)
		(drill 0.254)
		(layers "F.Cu" "B.Cu")
		(net "GND")
	)
	(via
		(at 279.024842 -285.924752)
		(size 0.4064)
		(drill 0.2032)
		(layers "F.Cu" "B.Cu")
		(net "GND")
	)
	(via
		(at 189.597792 -345.465146)
		(size 0.4064)
		(drill 0.2032)
		(layers "F.Cu" "B.Cu")
		(net "GND")
	)
	(via
		(at 390.849866 -314.899802)
		(size 0.4064)
		(drill 0.2032)
		(layers "F.Cu" "B.Cu")
		(net "GND")
	)
	(via
		(at 144.95653 -194.831208)
		(size 0.508)
		(drill 0.254)
		(layers "F.Cu" "B.Cu")
		(net "GND")
	)
	(via
		(at 348.527878 -401.040092)
		(size 0.508)
		(drill 0.254)
		(layers "F.Cu" "B.Cu")
		(net "GND")
	)
	(via
		(at 279.232868 -120.555004)
		(size 0.508)
		(drill 0.254)
		(layers "F.Cu" "B.Cu")
		(net "GND")
	)
	(via
		(at 8.242808 -147.630388)
		(size 0.508)
		(drill 0.254)
		(layers "F.Cu" "B.Cu")
		(net "GND")
	)
	(via
		(at 321.023742 -291.592)
		(size 0.508)
		(drill 0.254)
		(layers "F.Cu" "B.Cu")
		(net "GND")
	)
	(via
		(at 125.053852 -147.630388)
		(size 0.508)
		(drill 0.254)
		(layers "F.Cu" "B.Cu")
		(net "GND")
	)
	(via
		(at 152.47493 -285.924752)
		(size 0.4064)
		(drill 0.2032)
		(layers "F.Cu" "B.Cu")
		(net "GND")
	)
	(via
		(at 294.201342 -342.439498)
		(size 0.4064)
		(drill 0.2032)
		(layers "F.Cu" "B.Cu")
		(net "GND")
	)
	(via
		(at 163.747958 -372.341902)
		(size 0.508)
		(drill 0.254)
		(layers "F.Cu" "B.Cu")
		(net "GND")
	)
	(via
		(at 159.599884 -309.199788)
		(size 0.4064)
		(drill 0.2032)
		(layers "F.Cu" "B.Cu")
		(net "GND")
	)
	(via
		(at 237.849918 -312.441082)
		(size 0.508)
		(drill 0.254)
		(layers "F.Cu" "B.Cu")
		(net "GND")
	)
	(via
		(at 141.684502 -189.944756)
		(size 0.508)
		(drill 0.254)
		(layers "F.Cu" "B.Cu")
		(net "GND")
	)
	(via
		(at 415.074862 -291.624766)
		(size 0.4064)
		(drill 0.2032)
		(layers "F.Cu" "B.Cu")
		(net "GND")
	)
	(via
		(at 73.424796 -301.124874)
		(size 0.4064)
		(drill 0.2032)
		(layers "F.Cu" "B.Cu")
		(net "GND")
	)
	(via
		(at 154.501596 -125.692154)
		(size 0.508)
		(drill 0.254)
		(layers "F.Cu" "B.Cu")
		(net "GND")
	)
	(via
		(at 264.816844 -341.839296)
		(size 0.508)
		(drill 0.254)
		(layers "F.Cu" "B.Cu")
		(net "GND")
	)
	(via
		(at 312.749692 -310.149748)
		(size 0.4064)
		(drill 0.2032)
		(layers "F.Cu" "B.Cu")
		(net "GND")
	)
	(via
		(at 310.849518 -281.649932)
		(size 0.4064)
		(drill 0.2032)
		(layers "F.Cu" "B.Cu")
		(net "GND")
	)
	(via
		(at 432.119024 -350.977454)
		(size 0.4572)
		(drill 0.254)
		(layers "F.Cu" "B.Cu")
		(net "GND")
	)
	(via
		(at 35.899598 -306.350162)
		(size 0.4064)
		(drill 0.2032)
		(layers "F.Cu" "B.Cu")
		(net "GND")
	)
	(via
		(at 18.582132 -58.873644)
		(size 0.508)
		(drill 0.254)
		(layers "F.Cu" "B.Cu")
		(net "GND")
	)
	(via
		(at 406.366472 -35.871912)
		(size 0.508)
		(drill 0.254)
		(layers "F.Cu" "B.Cu")
		(net "GND")
	)
	(via
		(at 393.7 -317.749936)
		(size 0.4064)
		(drill 0.2032)
		(layers "F.Cu" "B.Cu")
		(net "GND")
	)
	(via
		(at 286.906462 -106.044746)
		(size 0.508)
		(drill 0.254)
		(layers "F.Cu" "B.Cu")
		(net "GND")
	)
	(via
		(at 131.529328 -211.977732)
		(size 0.508)
		(drill 0.254)
		(layers "F.Cu" "B.Cu")
		(net "GND")
	)
	(via
		(at 444.012574 -250.032266)
		(size 0.508)
		(drill 0.254)
		(layers "F.Cu" "B.Cu")
		(net "GND")
	)
	(via
		(at 120.620028 -342.439498)
		(size 0.4064)
		(drill 0.2032)
		(layers "F.Cu" "B.Cu")
		(net "GND")
	)
	(via
		(at 86.747858 -408.738578)
		(size 0.508)
		(drill 0.254)
		(layers "F.Cu" "B.Cu")
		(net "GND")
	)
	(via
		(at 438.708292 -348.58579)
		(size 0.4064)
		(drill 0.2032)
		(layers "F.Cu" "B.Cu")
		(net "GND")
	)
	(via
		(at 188.119004 -346.09913)
		(size 0.4572)
		(drill 0.254)
		(layers "F.Cu" "B.Cu")
		(net "GND")
	)
	(via
		(at 176.94783 -395.938502)
		(size 0.508)
		(drill 0.254)
		(layers "F.Cu" "B.Cu")
		(net "GND")
	)
	(via
		(at 36.14801 -399.838418)
		(size 0.508)
		(drill 0.254)
		(layers "F.Cu" "B.Cu")
		(net "GND")
	)
	(via
		(at 425.04995 -311.099962)
		(size 0.4064)
		(drill 0.2032)
		(layers "F.Cu" "B.Cu")
		(net "GND")
	)
	(via
		(at 418.42436 -343.073482)
		(size 0.4572)
		(drill 0.254)
		(layers "F.Cu" "B.Cu")
		(net "GND")
	)
	(via
		(at 240.72469 -217.15349)
		(size 0.508)
		(drill 0.254)
		(layers "F.Cu" "B.Cu")
		(net "GND")
	)
	(via
		(at 154.501596 -109.916722)
		(size 0.508)
		(drill 0.254)
		(layers "F.Cu" "B.Cu")
		(net "GND")
	)
	(via
		(at 421.724836 -306.824888)
		(size 0.4064)
		(drill 0.2032)
		(layers "F.Cu" "B.Cu")
		(net "GND")
	)
	(via
		(at 62.024768 -307.774848)
		(size 0.4064)
		(drill 0.2032)
		(layers "F.Cu" "B.Cu")
		(net "GND")
	)
	(via
		(at 425.527724 -404.838662)
		(size 0.508)
		(drill 0.254)
		(layers "F.Cu" "B.Cu")
		(net "GND")
	)
	(via
		(at 295.649904 -279.749758)
		(size 0.4064)
		(drill 0.2032)
		(layers "F.Cu" "B.Cu")
		(net "GND")
	)
	(via
		(at 383.72796 -382.84023)
		(size 0.508)
		(drill 0.254)
		(layers "F.Cu" "B.Cu")
		(net "GND")
	)
	(via
		(at 429.325024 -288.774886)
		(size 0.4064)
		(drill 0.2032)
		(layers "F.Cu" "B.Cu")
		(net "GND")
	)
	(via
		(at 177.161952 -357.75773)
		(size 0.4064)
		(drill 0.2032)
		(layers "F.Cu" "B.Cu")
		(net "GND")
	)
	(via
		(at 199.64019 -123.904502)
		(size 0.508)
		(drill 0.254)
		(layers "F.Cu" "B.Cu")
		(net "GND")
	)
	(via
		(at 75.74788 -373.83847)
		(size 0.508)
		(drill 0.254)
		(layers "F.Cu" "B.Cu")
		(net "GND")
	)
	(via
		(at 392.52779 -382.840484)
		(size 0.508)
		(drill 0.254)
		(layers "F.Cu" "B.Cu")
		(net "GND")
	)
	(via
		(at 281.765502 -348.58579)
		(size 0.4064)
		(drill 0.2032)
		(layers "F.Cu" "B.Cu")
		(net "GND")
	)
	(via
		(at 416.574224 -352.245422)
		(size 0.4572)
		(drill 0.254)
		(layers "F.Cu" "B.Cu")
		(net "GND")
	)
	(via
		(at 58.600848 -33.19018)
		(size 0.508)
		(drill 0.254)
		(layers "F.Cu" "B.Cu")
		(net "GND")
	)
	(via
		(at 133.427216 -352.245422)
		(size 0.4572)
		(drill 0.254)
		(layers "F.Cu" "B.Cu")
		(net "GND")
	)
	(via
		(at 181.912514 -131.245102)
		(size 0.508)
		(drill 0.254)
		(layers "F.Cu" "B.Cu")
		(net "GND")
	)
	(via
		(at 299.449744 -280.699718)
		(size 0.4064)
		(drill 0.2032)
		(layers "F.Cu" "B.Cu")
		(net "GND")
	)
	(via
		(at 186.488832 -354.708206)
		(size 0.4064)
		(drill 0.2032)
		(layers "F.Cu" "B.Cu")
		(net "GND")
	)
	(via
		(at 32.8295 -350.977454)
		(size 0.4572)
		(drill 0.254)
		(layers "F.Cu" "B.Cu")
		(net "GND")
	)
	(via
		(at 181.901084 -354.074222)
		(size 0.4572)
		(drill 0.254)
		(layers "F.Cu" "B.Cu")
		(net "GND")
	)
	(via
		(at 313.09818 -143.676878)
		(size 0.508)
		(drill 0.254)
		(layers "F.Cu" "B.Cu")
		(net "GND")
	)
	(via
		(at 324.08876 -99.625912)
		(size 0.508)
		(drill 0.254)
		(layers "F.Cu" "B.Cu")
		(net "GND")
	)
	(via
		(at 427.75124 -347.951806)
		(size 0.4572)
		(drill 0.254)
		(layers "F.Cu" "B.Cu")
		(net "GND")
	)
	(via
		(at 163.747958 -384.041904)
		(size 0.508)
		(drill 0.254)
		(layers "F.Cu" "B.Cu")
		(net "GND")
	)
	(via
		(at 394.17498 -286.874966)
		(size 0.4064)
		(drill 0.2032)
		(layers "F.Cu" "B.Cu")
		(net "GND")
	)
	(via
		(at 65.902078 -58.731404)
		(size 0.508)
		(drill 0.254)
		(layers "F.Cu" "B.Cu")
		(net "GND")
	)
	(via
		(at 245.21287 -288.652204)
		(size 0.508)
		(drill 0.254)
		(layers "F.Cu" "B.Cu")
		(net "GND")
	)
	(via
		(at 429.927766 -403.34184)
		(size 0.508)
		(drill 0.254)
		(layers "F.Cu" "B.Cu")
		(net "GND")
	)
	(via
		(at 234.052872 -93.77934)
		(size 0.508)
		(drill 0.254)
		(layers "F.Cu" "B.Cu")
		(net "GND")
	)
	(via
		(at 30.091888 -345.465146)
		(size 0.4064)
		(drill 0.2032)
		(layers "F.Cu" "B.Cu")
		(net "GND")
	)
	(via
		(at 290.80079 -31.390336)
		(size 0.508)
		(drill 0.254)
		(layers "F.Cu" "B.Cu")
		(net "GND")
	)
	(via
		(at 103.15067 -288.14649)
		(size 0.508)
		(drill 0.254)
		(layers "F.Cu" "B.Cu")
		(net "GND")
	)
	(via
		(at 338.807044 -348.58579)
		(size 0.4064)
		(drill 0.2032)
		(layers "F.Cu" "B.Cu")
		(net "GND")
	)
	(via
		(at 57.087262 -367.45545)
		(size 0.4572)
		(drill 0.254)
		(layers "F.Cu" "B.Cu")
		(net "GND")
	)
	(via
		(at 365.91494 -259.478018)
		(size 0.508)
		(drill 0.254)
		(layers "F.Cu" "B.Cu")
		(net "GND")
	)
	(via
		(at 181.44998 -315.849762)
		(size 0.4064)
		(drill 0.2032)
		(layers "F.Cu" "B.Cu")
		(net "GND")
	)
	(via
		(at 423.149776 -276.899878)
		(size 0.4064)
		(drill 0.2032)
		(layers "F.Cu" "B.Cu")
		(net "GND")
	)
	(via
		(at 357.254048 -150.16861)
		(size 0.508)
		(drill 0.254)
		(layers "F.Cu" "B.Cu")
		(net "GND")
	)
	(via
		(at 51.574954 -284.974792)
		(size 0.4064)
		(drill 0.2032)
		(layers "F.Cu" "B.Cu")
		(net "GND")
	)
	(via
		(at 273.324828 -286.874966)
		(size 0.4064)
		(drill 0.2032)
		(layers "F.Cu" "B.Cu")
		(net "GND")
	)
	(via
		(at 87.305134 -352.245422)
		(size 0.4572)
		(drill 0.254)
		(layers "F.Cu" "B.Cu")
		(net "GND")
	)
	(via
		(at 436.527702 -398.34185)
		(size 0.508)
		(drill 0.254)
		(layers "F.Cu" "B.Cu")
		(net "GND")
	)
	(via
		(at 14.252956 -395.239494)
		(size 0.508)
		(drill 0.254)
		(layers "F.Cu" "B.Cu")
		(net "GND")
	)
	(via
		(at 427.623224 -54.067456)
		(size 0.508)
		(drill 0.254)
		(layers "F.Cu" "B.Cu")
		(net "GND")
	)
	(via
		(at 416.974782 -289.724846)
		(size 0.4064)
		(drill 0.2032)
		(layers "F.Cu" "B.Cu")
		(net "GND")
	)
	(via
		(at 186.86018 -352.245422)
		(size 0.4572)
		(drill 0.254)
		(layers "F.Cu" "B.Cu")
		(net "GND")
	)
	(via
		(at 154.501596 -132.04317)
		(size 0.508)
		(drill 0.254)
		(layers "F.Cu" "B.Cu")
		(net "GND")
	)
	(via
		(at 273.622008 -80.91551)
		(size 0.508)
		(drill 0.254)
		(layers "F.Cu" "B.Cu")
		(net "GND")
	)
	(via
		(at 35.93846 -354.098098)
		(size 0.4572)
		(drill 0.254)
		(layers "F.Cu" "B.Cu")
		(net "GND")
	)
	(via
		(at 238.659924 -78.872334)
		(size 0.508)
		(drill 0.254)
		(layers "F.Cu" "B.Cu")
		(net "GND")
	)
	(via
		(at 203.748894 -33.19018)
		(size 0.508)
		(drill 0.254)
		(layers "F.Cu" "B.Cu")
		(net "GND")
	)
	(via
		(at 297.927776 -404.838662)
		(size 0.508)
		(drill 0.254)
		(layers "F.Cu" "B.Cu")
		(net "GND")
	)
	(via
		(at 121.750074 -27.04973)
		(size 0.508)
		(drill 0.254)
		(layers "F.Cu" "B.Cu")
		(net "GND")
	)
	(via
		(at 150.59152 -123.885452)
		(size 0.508)
		(drill 0.254)
		(layers "F.Cu" "B.Cu")
		(net "GND")
	)
	(via
		(at 39.224966 -284.974792)
		(size 0.4064)
		(drill 0.2032)
		(layers "F.Cu" "B.Cu")
		(net "GND")
	)
	(via
		(at 189.999874 -274.049744)
		(size 0.4064)
		(drill 0.2032)
		(layers "F.Cu" "B.Cu")
		(net "GND")
	)
	(via
		(at 453.634094 -311.122568)
		(size 0.508)
		(drill 0.254)
		(layers "F.Cu" "B.Cu")
		(net "GND")
	)
	(via
		(at 274.749768 -315.849762)
		(size 0.4064)
		(drill 0.2032)
		(layers "F.Cu" "B.Cu")
		(net "GND")
	)
	(via
		(at 379.327918 -410.041852)
		(size 0.508)
		(drill 0.254)
		(layers "F.Cu" "B.Cu")
		(net "GND")
	)
	(via
		(at 130.74777 -371.038628)
		(size 0.508)
		(drill 0.254)
		(layers "F.Cu" "B.Cu")
		(net "GND")
	)
	(via
		(at 185.585608 -63.218314)
		(size 0.508)
		(drill 0.254)
		(layers "F.Cu" "B.Cu")
		(net "GND")
	)
	(via
		(at 248.1961 -83.431888)
		(size 0.508)
		(drill 0.254)
		(layers "F.Cu" "B.Cu")
		(net "GND")
	)
	(via
		(at 237.18774 -246.997982)
		(size 0.508)
		(drill 0.254)
		(layers "F.Cu" "B.Cu")
		(net "GND")
	)
	(via
		(at 74.248264 -121.83491)
		(size 0.508)
		(drill 0.254)
		(layers "F.Cu" "B.Cu")
		(net "GND")
	)
	(via
		(at 269.524734 -292.57498)
		(size 0.4064)
		(drill 0.2032)
		(layers "F.Cu" "B.Cu")
		(net "GND")
	)
	(via
		(at 38.347904 -380.040134)
		(size 0.508)
		(drill 0.254)
		(layers "F.Cu" "B.Cu")
		(net "GND")
	)
	(via
		(at 328.78395 -81.64195)
		(size 0.508)
		(drill 0.254)
		(layers "F.Cu" "B.Cu")
		(net "GND")
	)
	(via
		(at 281.874722 -284.024832)
		(size 0.4064)
		(drill 0.2032)
		(layers "F.Cu" "B.Cu")
		(net "GND")
	)
	(via
		(at 285.052262 -135.364982)
		(size 0.508)
		(drill 0.254)
		(layers "F.Cu" "B.Cu")
		(net "GND")
	)
	(via
		(at 151.748998 -25.990042)
		(size 0.508)
		(drill 0.254)
		(layers "F.Cu" "B.Cu")
		(net "GND")
	)
	(via
		(at 435.227984 -343.073482)
		(size 0.4572)
		(drill 0.254)
		(layers "F.Cu" "B.Cu")
		(net "GND")
	)
	(via
		(at 53.474874 -300.174914)
		(size 0.4064)
		(drill 0.2032)
		(layers "F.Cu" "B.Cu")
		(net "GND")
	)
	(via
		(at 348.527878 -398.34185)
		(size 0.508)
		(drill 0.254)
		(layers "F.Cu" "B.Cu")
		(net "GND")
	)
	(via
		(at 196.998082 -130.966718)
		(size 0.508)
		(drill 0.254)
		(layers "F.Cu" "B.Cu")
		(net "GND")
	)
	(via
		(at 291.84981 -274.999958)
		(size 0.4064)
		(drill 0.2032)
		(layers "F.Cu" "B.Cu")
		(net "GND")
	)
	(via
		(at 71.999856 -313.949842)
		(size 0.4064)
		(drill 0.2032)
		(layers "F.Cu" "B.Cu")
		(net "GND")
	)
	(via
		(at 283.833062 -109.644942)
		(size 0.508)
		(drill 0.254)
		(layers "F.Cu" "B.Cu")
		(net "GND")
	)
	(via
		(at 360.170476 -288.78149)
		(size 0.508)
		(drill 0.254)
		(layers "F.Cu" "B.Cu")
		(net "GND")
	)
	(via
		(at 47.115476 -347.951806)
		(size 0.4572)
		(drill 0.254)
		(layers "F.Cu" "B.Cu")
		(net "GND")
	)
	(via
		(at 144.384268 -342.439498)
		(size 0.4064)
		(drill 0.2032)
		(layers "F.Cu" "B.Cu")
		(net "GND")
	)
	(via
		(at 353.882452 -37.087048)
		(size 0.508)
		(drill 0.254)
		(layers "F.Cu" "B.Cu")
		(net "GND")
	)
	(via
		(at 277.251668 -122.355102)
		(size 0.508)
		(drill 0.254)
		(layers "F.Cu" "B.Cu")
		(net "GND")
	)
	(via
		(at 141.275308 -351.611438)
		(size 0.4064)
		(drill 0.2032)
		(layers "F.Cu" "B.Cu")
		(net "GND")
	)
	(via
		(at 384.674872 -296.374566)
		(size 0.4064)
		(drill 0.2032)
		(layers "F.Cu" "B.Cu")
		(net "GND")
	)
	(via
		(at 221.59976 -314.193682)
		(size 0.508)
		(drill 0.254)
		(layers "F.Cu" "B.Cu")
		(net "GND")
	)
	(via
		(at 0.77089 -248.421144)
		(size 0.508)
		(drill 0.254)
		(layers "F.Cu" "B.Cu")
		(net "GND")
	)
	(via
		(at 212.771228 -31.652972)
		(size 0.508)
		(drill 0.254)
		(layers "F.Cu" "B.Cu")
		(net "GND")
	)
	(via
		(at 428.84979 -274.999958)
		(size 0.4064)
		(drill 0.2032)
		(layers "F.Cu" "B.Cu")
		(net "GND")
	)
	(via
		(at 69.088 -417.82492)
		(size 0.508)
		(drill 0.254)
		(layers "F.Cu" "B.Cu")
		(net "GND")
	)
	(via
		(at 262.638286 -253.45644)
		(size 0.508)
		(drill 0.254)
		(layers "F.Cu" "B.Cu")
		(net "GND")
	)
	(via
		(at 82.266028 -77.175106)
		(size 0.508)
		(drill 0.254)
		(layers "F.Cu" "B.Cu")
		(net "GND")
	)
	(via
		(at 271.424908 -296.37482)
		(size 0.4064)
		(drill 0.2032)
		(layers "F.Cu" "B.Cu")
		(net "GND")
	)
	(via
		(at 136.374124 -73.85177)
		(size 0.508)
		(drill 0.254)
		(layers "F.Cu" "B.Cu")
		(net "GND")
	)
	(via
		(at 31.747968 -401.040092)
		(size 0.508)
		(drill 0.254)
		(layers "F.Cu" "B.Cu")
		(net "GND")
	)
	(via
		(at 163.874958 -307.774848)
		(size 0.4064)
		(drill 0.2032)
		(layers "F.Cu" "B.Cu")
		(net "GND")
	)
	(via
		(at 429.198278 -130.966718)
		(size 0.508)
		(drill 0.254)
		(layers "F.Cu" "B.Cu")
		(net "GND")
	)
	(segment
		(start 340.493858 -221.58706)
		(end 340.42985 -221.58706)
		(width 0.254)
		(layer "B.Cu")
		(net "GND")
	)
	(segment
		(start 228.805486 -226.738688)
		(end 228.750368 -226.68357)
		(width 0.4572)
		(layer "B.Cu")
		(net "GND")
	)
	(segment
		(start 378.741178 -224.692718)
		(end 379.319282 -224.692718)
		(width 0.4572)
		(layer "B.Cu")
		(net "GND")
	)
	(segment
		(start 398.925034 -293.73322)
		(end 398.925034 -293.52494)
		(width 0.3048)
		(layer "B.Cu")
		(net "GND")
	)
	(segment
		(start 389.89 -237.12805)
		(end 388.850124 -237.12805)
		(width 0.4572)
		(layer "B.Cu")
		(net "GND")
	)
	(segment
		(start 68.883276 -302.074834)
		(end 68.674742 -302.074834)
		(width 0.3048)
		(layer "B.Cu")
		(net "GND")
	)
	(segment
		(start 353.822254 -221.238572)
		(end 353.822254 -222.552514)
		(width 0.3048)
		(layer "B.Cu")
		(net "GND")
	)
	(segment
		(start 338.893912 -227.187252)
		(end 338.894166 -227.187252)
		(width 0.254)
		(layer "B.Cu")
		(net "GND")
	)
	(segment
		(start 412.224982 -297.53306)
		(end 412.224982 -297.32478)
		(width 0.3048)
		(layer "B.Cu")
		(net "GND")
	)
	(segment
		(start 77.941932 -100.056696)
		(end 78.551532 -100.056696)
		(width 0.4572)
		(layer "B.Cu")
		(net "GND")
	)
	(segment
		(start 110.015782 -354.313236)
		(end 110.713774 -354.313236)
		(width 0.4572)
		(layer "B.Cu")
		(net "GND")
	)
	(segment
		(start 288.52495 -293.525194)
		(end 288.524696 -293.52494)
		(width 0.3048)
		(layer "B.Cu")
		(net "GND")
	)
	(segment
		(start 165.774878 -294.26662)
		(end 165.774878 -294.4749)
		(width 0.3048)
		(layer "B.Cu")
		(net "GND")
	)
	(segment
		(start 180.975 -298.06646)
		(end 180.975 -298.27474)
		(width 0.3048)
		(layer "B.Cu")
		(net "GND")
	)
	(segment
		(start 179.07508 -293.73322)
		(end 179.07508 -293.52494)
		(width 0.3048)
		(layer "B.Cu")
		(net "GND")
	)
	(segment
		(start 281.666442 -292.574726)
		(end 281.874722 -292.574726)
		(width 0.3048)
		(layer "B.Cu")
		(net "GND")
	)
	(segment
		(start 172.106844 -138.15695)
		(end 172.976794 -138.15695)
		(width 0.4572)
		(layer "B.Cu")
		(net "GND")
	)
	(segment
		(start 49.624234 -299.2755)
		(end 49.67478 -299.224954)
		(width 0.3048)
		(layer "B.Cu")
		(net "GND")
	)
	(segment
		(start 50.833274 -291.833046)
		(end 50.624994 -291.624766)
		(width 0.3048)
		(layer "B.Cu")
		(net "GND")
	)
	(segment
		(start 339.293962 -222.786956)
		(end 339.693758 -222.38716)
		(width 0.254)
		(layer "B.Cu")
		(net "GND")
	)
	(segment
		(start 56.883808 -309.124858)
		(end 56.712866 -309.2958)
		(width 0.4572)
		(layer "B.Cu")
		(net "GND")
	)
	(segment
		(start 210.309714 -218.937332)
		(end 210.045046 -219.202)
		(width 0.3048)
		(layer "B.Cu")
		(net "GND")
	)
	(segment
		(start 332.703424 -228.116638)
		(end 332.703424 -228.386894)
		(width 0.3048)
		(layer "B.Cu")
		(net "GND")
	)
	(segment
		(start 284.724856 -293.73322)
		(end 284.724856 -293.52494)
		(width 0.3048)
		(layer "B.Cu")
		(net "GND")
	)
	(segment
		(start 403.674834 -297.53306)
		(end 403.674834 -297.32478)
		(width 0.3048)
		(layer "B.Cu")
		(net "GND")
	)
	(segment
		(start 62.974728 -293.73322)
		(end 62.974728 -293.525194)
		(width 0.3048)
		(layer "B.Cu")
		(net "GND")
	)
	(segment
		(start 346.893896 -227.187252)
		(end 346.893134 -227.187252)
		(width 0.254)
		(layer "B.Cu")
		(net "GND")
	)
	(segment
		(start 255.725168 -80.364076)
		(end 256.315464 -80.364076)
		(width 0.4572)
		(layer "B.Cu")
		(net "GND")
	)
	(segment
		(start 288.52495 -298.06646)
		(end 288.52495 -298.274486)
		(width 0.3048)
		(layer "B.Cu")
		(net "GND")
	)
	(segment
		(start 426.241972 -104.120696)
		(end 426.851572 -104.120696)
		(width 0.4572)
		(layer "B.Cu")
		(net "GND")
	)
	(segment
		(start 110.744508 -350.568006)
		(end 110.744508 -351.092008)
		(width 0.4572)
		(layer "B.Cu")
		(net "GND")
	)
	(segment
		(start 110.021878 -355.2952)
		(end 110.713774 -355.2952)
		(width 0.4572)
		(layer "B.Cu")
		(net "GND")
	)
	(segment
		(start 370.240814 -228.85527)
		(end 370.69268 -228.403404)
		(width 0.254)
		(layer "B.Cu")
		(net "GND")
	)
	(segment
		(start 418.666676 -290.674806)
		(end 418.874956 -290.674806)
		(width 0.3048)
		(layer "B.Cu")
		(net "GND")
	)
	(segment
		(start 131.293108 -227.965)
		(end 132.36321 -227.965)
		(width 0.4572)
		(layer "B.Cu")
		(net "GND")
	)
	(segment
		(start 61.023246 -159.595312)
		(end 59.00039 -159.595312)
		(width 0.4572)
		(layer "B.Cu")
		(net "GND")
	)
	(segment
		(start 343.2937 -221.923356)
		(end 343.2937 -221.92361)
		(width 0.254)
		(layer "B.Cu")
		(net "GND")
	)
	(segment
		(start 231.81691 -89.797128)
		(end 231.15016 -89.797128)
		(width 0.254)
		(layer "B.Cu")
		(net "GND")
	)
	(segment
		(start 179.30368 -296.37482)
		(end 179.07508 -296.37482)
		(width 0.3048)
		(layer "B.Cu")
		(net "GND")
	)
	(segment
		(start 341.293704 -221.58706)
		(end 341.227918 -221.58706)
		(width 0.254)
		(layer "B.Cu")
		(net "GND")
	)
	(segment
		(start 172.424852 -293.73322)
		(end 172.424852 -293.52494)
		(width 0.3048)
		(layer "B.Cu")
		(net "GND")
	)
	(segment
		(start 422.674796 -298.27474)
		(end 422.326816 -298.62272)
		(width 0.4572)
		(layer "B.Cu")
		(net "GND")
	)
	(segment
		(start 265.93673 -85.713316)
		(end 265.93673 -86.28634)
		(width 0.4572)
		(layer "B.Cu")
		(net "GND")
	)
	(segment
		(start 332.862428 -227.957634)
		(end 332.703424 -228.116638)
		(width 0.3048)
		(layer "B.Cu")
		(net "GND")
	)
	(segment
		(start 303.89068 -118.711218)
		(end 303.89068 -119.414544)
		(width 0.4572)
		(layer "B.Cu")
		(net "GND")
	)
	(segment
		(start 171.474892 -297.53306)
		(end 171.474892 -297.32478)
		(width 0.3048)
		(layer "B.Cu")
		(net "GND")
	)
	(segment
		(start 383.667 -235.98505)
		(end 383.667 -236.601)
		(width 0.4572)
		(layer "B.Cu")
		(net "GND")
	)
	(segment
		(start 404.625048 -298.06646)
		(end 404.625048 -298.274486)
		(width 0.3048)
		(layer "B.Cu")
		(net "GND")
	)
	(segment
		(start 351.245932 -142.006828)
		(end 351.423224 -141.829536)
		(width 0.4572)
		(layer "B.Cu")
		(net "GND")
	)
	(segment
		(start 281.178762 -296.37482)
		(end 280.924762 -296.37482)
		(width 0.3048)
		(layer "B.Cu")
		(net "GND")
	)
	(segment
		(start 295.983406 -108.462318)
		(end 296.969942 -108.462318)
		(width 0.4572)
		(layer "B.Cu")
		(net "GND")
	)
	(segment
		(start 378.587 -240.89995)
		(end 377.93295 -240.89995)
		(width 0.4572)
		(layer "B.Cu")
		(net "GND")
	)
	(segment
		(start 216.194894 -217.22207)
		(end 216.259156 -217.286332)
		(width 0.3048)
		(layer "B.Cu")
		(net "GND")
	)
	(segment
		(start 141.631416 -203.552806)
		(end 141.946376 -203.552806)
		(width 0.4572)
		(layer "B.Cu")
		(net "GND")
	)
	(segment
		(start 396.0749 -295.1099)
		(end 396.0749 -294.4749)
		(width 0.3048)
		(layer "B.Cu")
		(net "GND")
	)
	(segment
		(start 415.07664 -293.73322)
		(end 415.07664 -293.526718)
		(width 0.3048)
		(layer "B.Cu")
		(net "GND")
	)
	(segment
		(start 286.624776 -293.73322)
		(end 286.624776 -293.52494)
		(width 0.3048)
		(layer "B.Cu")
		(net "GND")
	)
	(segment
		(start 225.539046 -153.863802)
		(end 225.539046 -154.651202)
		(width 0.4572)
		(layer "B.Cu")
		(net "GND")
	)
	(segment
		(start 16.19123 -223.537018)
		(end 16.850868 -223.537018)
		(width 0.4572)
		(layer "B.Cu")
		(net "GND")
	)
	(segment
		(start 345.23553 -217.587068)
		(end 344.8939 -217.245438)
		(width 0.254)
		(layer "B.Cu")
		(net "GND")
	)
	(segment
		(start 166.953692 -296.37482)
		(end 166.725092 -296.37482)
		(width 0.3048)
		(layer "B.Cu")
		(net "GND")
	)
	(segment
		(start 63.924942 -297.53306)
		(end 63.924942 -297.32478)
		(width 0.3048)
		(layer "B.Cu")
		(net "GND")
	)
	(segment
		(start 295.17467 -293.73322)
		(end 295.17467 -293.525194)
		(width 0.3048)
		(layer "B.Cu")
		(net "GND")
	)
	(segment
		(start 301.739554 -243.737384)
		(end 301.739554 -244.512846)
		(width 0.4572)
		(layer "B.Cu")
		(net "GND")
	)
	(segment
		(start 281.615642 -301.0154)
		(end 281.765248 -301.0154)
		(width 0.3048)
		(layer "B.Cu")
		(net "GND")
	)
	(segment
		(start 349.84182 -318.542416)
		(end 349.85706 -318.557656)
		(width 0.254)
		(layer "B.Cu")
		(net "GND")
	)
	(segment
		(start 340.894162 -217.187272)
		(end 340.894162 -217.246962)
		(width 0.254)
		(layer "B.Cu")
		(net "GND")
	)
	(segment
		(start 164.824918 -293.73322)
		(end 164.824918 -293.52494)
		(width 0.3048)
		(layer "B.Cu")
		(net "GND")
	)
	(segment
		(start 54.424834 -298.06646)
		(end 54.424834 -298.27474)
		(width 0.3048)
		(layer "B.Cu")
		(net "GND")
	)
	(segment
		(start 292.213284 -195.685664)
		(end 292.798246 -195.685664)
		(width 0.4572)
		(layer "B.Cu")
		(net "GND")
	)
	(segment
		(start 344.093546 -217.254328)
		(end 343.760806 -217.587068)
		(width 0.254)
		(layer "B.Cu")
		(net "GND")
	)
	(segment
		(start 386.842 -246.65305)
		(end 387.482588 -246.65305)
		(width 0.4572)
		(layer "B.Cu")
		(net "GND")
	)
	(segment
		(start 281.355292 -156.0576)
		(end 280.745692 -156.0576)
		(width 0.4572)
		(layer "B.Cu")
		(net "GND")
	)
	(segment
		(start 164.824918 -298.06646)
		(end 164.824918 -298.27474)
		(width 0.3048)
		(layer "B.Cu")
		(net "GND")
	)
	(segment
		(start 54.678834 -296.37482)
		(end 54.424834 -296.37482)
		(width 0.3048)
		(layer "B.Cu")
		(net "GND")
	)
	(segment
		(start 228.773482 -226.660456)
		(end 228.773482 -226.078034)
		(width 0.4572)
		(layer "B.Cu")
		(net "GND")
	)
	(segment
		(start 411.274768 -293.525194)
		(end 411.275022 -293.52494)
		(width 0.3048)
		(layer "B.Cu")
		(net "GND")
	)
	(segment
		(start 65.103502 -296.37482)
		(end 64.874902 -296.37482)
		(width 0.3048)
		(layer "B.Cu")
		(net "GND")
	)
	(segment
		(start 301.616618 -296.37482)
		(end 301.824898 -296.37482)
		(width 0.3048)
		(layer "B.Cu")
		(net "GND")
	)
	(segment
		(start 281.355292 -150.9776)
		(end 280.745692 -150.9776)
		(width 0.4572)
		(layer "B.Cu")
		(net "GND")
	)
	(segment
		(start 127.840994 -181.03977)
		(end 127.840994 -181.775608)
		(width 0.4572)
		(layer "B.Cu")
		(net "GND")
	)
	(segment
		(start 397.45539 -153.0096)
		(end 396.84579 -153.0096)
		(width 0.4572)
		(layer "B.Cu")
		(net "GND")
	)
	(segment
		(start 400.75231 -360.376724)
		(end 404.37308 -363.997494)
		(width 0.4572)
		(layer "B.Cu")
		(net "GND")
	)
	(segment
		(start 351.423224 -141.829536)
		(end 351.423224 -141.817852)
		(width 0.4572)
		(layer "B.Cu")
		(net "GND")
	)
	(segment
		(start 366.532414 -222.658432)
		(end 366.532414 -221.915482)
		(width 0.4572)
		(layer "B.Cu")
		(net "GND")
	)
	(segment
		(start 409.03652 -296.37482)
		(end 409.01874 -296.3926)
		(width 0.3048)
		(layer "B.Cu")
		(net "GND")
	)
	(segment
		(start 309.02402 -113.95202)
		(end 309.02402 -113.229898)
		(width 0.4572)
		(layer "B.Cu")
		(net "GND")
	)
	(segment
		(start 300.804072 -117.723666)
		(end 300.058836 -117.415056)
		(width 0.4572)
		(layer "B.Cu")
		(net "GND")
	)
	(segment
		(start 340.493858 -221.58706)
		(end 340.493858 -221.586552)
		(width 0.254)
		(layer "B.Cu")
		(net "GND")
	)
	(segment
		(start 231.52481 -215.047068)
		(end 231.46766 -215.104218)
		(width 0.3048)
		(layer "B.Cu")
		(net "GND")
	)
	(segment
		(start 426.241972 -102.088696)
		(end 426.851572 -102.088696)
		(width 0.4572)
		(layer "B.Cu")
		(net "GND")
	)
	(segment
		(start 49.565306 -301.0154)
		(end 49.67478 -301.124874)
		(width 0.3048)
		(layer "B.Cu")
		(net "GND")
	)
	(segment
		(start 165.255194 -156.0576)
		(end 164.645594 -156.0576)
		(width 0.4572)
		(layer "B.Cu")
		(net "GND")
	)
	(segment
		(start 70.366636 -289.724846)
		(end 70.574916 -289.724846)
		(width 0.3048)
		(layer "B.Cu")
		(net "GND")
	)
	(segment
		(start 237.903512 -235.128054)
		(end 237.903512 -235.737654)
		(width 0.4572)
		(layer "B.Cu")
		(net "GND")
	)
	(segment
		(start 231.129586 -256.18186)
		(end 231.143302 -256.168144)
		(width 0.254)
		(layer "B.Cu")
		(net "GND")
	)
	(segment
		(start 166.725092 -293.73322)
		(end 166.725092 -293.52494)
		(width 0.3048)
		(layer "B.Cu")
		(net "GND")
	)
	(segment
		(start 111.60633 -332.70571)
		(end 111.987584 -333.086964)
		(width 0.4572)
		(layer "B.Cu")
		(net "GND")
	)
	(segment
		(start 288.77895 -296.37482)
		(end 288.52495 -296.37482)
		(width 0.3048)
		(layer "B.Cu")
		(net "GND")
	)
	(segment
		(start 250.432316 -222.658432)
		(end 250.837446 -223.063562)
		(width 0.4572)
		(layer "B.Cu")
		(net "GND")
	)
	(segment
		(start 344.893646 -217.987372)
		(end 345.29395 -217.587068)
		(width 0.254)
		(layer "B.Cu")
		(net "GND")
	)
	(segment
		(start 254.140716 -230.378762)
		(end 254.312166 -230.550212)
		(width 0.254)
		(layer "B.Cu")
		(net "GND")
	)
	(segment
		(start 51.574954 -294.26662)
		(end 51.574954 -294.4749)
		(width 0.3048)
		(layer "B.Cu")
		(net "GND")
	)
	(segment
		(start 344.093546 -221.92234)
		(end 344.428826 -221.58706)
		(width 0.254)
		(layer "B.Cu")
		(net "GND")
	)
	(segment
		(start 295.174924 -298.06646)
		(end 295.174924 -298.27474)
		(width 0.3048)
		(layer "B.Cu")
		(net "GND")
	)
	(segment
		(start 165.566598 -290.674806)
		(end 165.774878 -290.674806)
		(width 0.3048)
		(layer "B.Cu")
		(net "GND")
	)
	(segment
		(start 49.67478 -297.53306)
		(end 49.67478 -297.32478)
		(width 0.3048)
		(layer "B.Cu")
		(net "GND")
	)
	(segment
		(start 62.024768 -294.26662)
		(end 62.024768 -294.4749)
		(width 0.3048)
		(layer "B.Cu")
		(net "GND")
	)
	(segment
		(start 74.026776 -298.62272)
		(end 74.026776 -298.82465)
		(width 0.4572)
		(layer "B.Cu")
		(net "GND")
	)
	(segment
		(start 344.093546 -217.187272)
		(end 344.093546 -217.254328)
		(width 0.254)
		(layer "B.Cu")
		(net "GND")
	)
	(segment
		(start 334.09382 -224.786952)
		(end 334.09382 -224.728786)
		(width 0.254)
		(layer "B.Cu")
		(net "GND")
	)
	(segment
		(start 344.8939 -217.245438)
		(end 344.8939 -217.187018)
		(width 0.254)
		(layer "B.Cu")
		(net "GND")
	)
	(segment
		(start 380.032514 -241.28095)
		(end 380.002288 -241.311176)
		(width 0.381)
		(layer "B.Cu")
		(net "GND")
	)
	(segment
		(start 210.349846 -218.308936)
		(end 210.309714 -218.349068)
		(width 0.3048)
		(layer "B.Cu")
		(net "GND")
	)
	(segment
		(start 346.093288 -222.386906)
		(end 346.093288 -222.387414)
		(width 0.254)
		(layer "B.Cu")
		(net "GND")
	)
	(segment
		(start 110.303564 -350.127062)
		(end 110.744508 -350.568006)
		(width 0.4572)
		(layer "B.Cu")
		(net "GND")
	)
	(segment
		(start 346.65031 -258.404614)
		(end 347.0656 -258.404614)
		(width 0.381)
		(layer "B.Cu")
		(net "GND")
	)
	(segment
		(start 61.074808 -293.73322)
		(end 61.074808 -293.52494)
		(width 0.3048)
		(layer "B.Cu")
		(net "GND")
	)
	(segment
		(start 201.088244 -259.711698)
		(end 201.088244 -260.46176)
		(width 0.4572)
		(layer "B.Cu")
		(net "GND")
	)
	(segment
		(start 68.466462 -293.52494)
		(end 68.674742 -293.52494)
		(width 0.3048)
		(layer "B.Cu")
		(net "GND")
	)
	(segment
		(start 406.540208 -298.2595)
		(end 406.524968 -298.27474)
		(width 0.3048)
		(layer "B.Cu")
		(net "GND")
	)
	(segment
		(start 184.599072 -114.713512)
		(end 183.8452 -114.713512)
		(width 0.4572)
		(layer "B.Cu")
		(net "GND")
	)
	(segment
		(start 305.128676 -249.628406)
		(end 305.255676 -249.755406)
		(width 0.4572)
		(layer "B.Cu")
		(net "GND")
	)
	(segment
		(start 57.274968 -297.53306)
		(end 57.274968 -297.32478)
		(width 0.3048)
		(layer "B.Cu")
		(net "GND")
	)
	(segment
		(start 253.918212 -84.301838)
		(end 253.471934 -84.748116)
		(width 0.4572)
		(layer "B.Cu")
		(net "GND")
	)
	(segment
		(start 281.824176 -299.2755)
		(end 281.874722 -299.224954)
		(width 0.3048)
		(layer "B.Cu")
		(net "GND")
	)
	(segment
		(start 237.475776 -225.111056)
		(end 237.1598 -225.427032)
		(width 0.3048)
		(layer "B.Cu")
		(net "GND")
	)
	(segment
		(start 75.820778 -113.95202)
		(end 75.820778 -113.260632)
		(width 0.4572)
		(layer "B.Cu")
		(net "GND")
	)
	(segment
		(start 370.240814 -229.827582)
		(end 370.240814 -228.85527)
		(width 0.254)
		(layer "B.Cu")
		(net "GND")
	)
	(segment
		(start 297.303444 -296.37482)
		(end 297.074844 -296.37482)
		(width 0.3048)
		(layer "B.Cu")
		(net "GND")
	)
	(segment
		(start 211.508594 -252.290072)
		(end 211.48294 -252.315726)
		(width 0.3048)
		(layer "B.Cu")
		(net "GND")
	)
	(segment
		(start 339.693758 -220.787214)
		(end 340.0933 -221.186756)
		(width 0.254)
		(layer "B.Cu")
		(net "GND")
	)
	(segment
		(start 100.311966 -332.038452)
		(end 99.386136 -332.038452)
		(width 0.508)
		(layer "B.Cu")
		(net "GND")
	)
	(segment
		(start 135.316214 -201.332846)
		(end 135.235442 -201.252074)
		(width 0.4572)
		(layer "B.Cu")
		(net "GND")
	)
	(segment
		(start 349.8723 -318.542416)
		(end 349.85706 -318.557656)
		(width 0.254)
		(layer "B.Cu")
		(net "GND")
	)
	(segment
		(start 62.024768 -297.53306)
		(end 62.024768 -297.32478)
		(width 0.3048)
		(layer "B.Cu")
		(net "GND")
	)
	(segment
		(start 167.189658 -138.421618)
		(end 167.732964 -138.964924)
		(width 0.4572)
		(layer "B.Cu")
		(net "GND")
	)
	(segment
		(start 48.9331 -291.624766)
		(end 48.72482 -291.624766)
		(width 0.3048)
		(layer "B.Cu")
		(net "GND")
	)
	(segment
		(start 184.56656 -298.27474)
		(end 184.77484 -298.27474)
		(width 0.3048)
		(layer "B.Cu")
		(net "GND")
	)
	(segment
		(start 303.01946 -231.220518)
		(end 303.01946 -232.377742)
		(width 0.3556)
		(layer "B.Cu")
		(net "GND")
	)
	(segment
		(start 184.983374 -303.024794)
		(end 184.77484 -303.024794)
		(width 0.3048)
		(layer "B.Cu")
		(net "GND")
	)
	(segment
		(start 422.326816 -298.62272)
		(end 422.326816 -298.82465)
		(width 0.4572)
		(layer "B.Cu")
		(net "GND")
	)
	(segment
		(start 102.782878 -337.881722)
		(end 102.782878 -338.573618)
		(width 0.4572)
		(layer "B.Cu")
		(net "GND")
	)
	(segment
		(start 418.00399 -98.552)
		(end 418.00399 -99.187)
		(width 0.4572)
		(layer "B.Cu")
		(net "GND")
	)
	(segment
		(start 61.092588 -296.3926)
		(end 61.074808 -296.37482)
		(width 0.3048)
		(layer "B.Cu")
		(net "GND")
	)
	(segment
		(start 404.625048 -298.274486)
		(end 404.624794 -298.27474)
		(width 0.3048)
		(layer "B.Cu")
		(net "GND")
	)
	(segment
		(start 57.274968 -294.640508)
		(end 57.274968 -294.4749)
		(width 0.3048)
		(layer "B.Cu")
		(net "GND")
	)
	(segment
		(start 115.466114 -255.826514)
		(end 115.466114 -255.599946)
		(width 0.381)
		(layer "B.Cu")
		(net "GND")
	)
	(segment
		(start 304.354992 -97.663)
		(end 304.354992 -96.901)
		(width 0.4572)
		(layer "B.Cu")
		(net "GND")
	)
	(segment
		(start 172.983906 -309.124858)
		(end 172.983906 -309.283608)
		(width 0.4572)
		(layer "B.Cu")
		(net "GND")
	)
	(segment
		(start 52.524914 -293.73322)
		(end 52.524914 -293.52494)
		(width 0.3048)
		(layer "B.Cu")
		(net "GND")
	)
	(segment
		(start 58.240168 -298.2595)
		(end 58.224928 -298.27474)
		(width 0.3048)
		(layer "B.Cu")
		(net "GND")
	)
	(segment
		(start 380.365 -233.68)
		(end 380.72695 -233.68)
		(width 0.4572)
		(layer "B.Cu")
		(net "GND")
	)
	(segment
		(start 231.867456 -214.704422)
		(end 231.753918 -214.704422)
		(width 0.3048)
		(layer "B.Cu")
		(net "GND")
	)
	(segment
		(start 388.850124 -237.12805)
		(end 388.134098 -237.844076)
		(width 0.4572)
		(layer "B.Cu")
		(net "GND")
	)
	(segment
		(start 340.42985 -221.58706)
		(end 340.093808 -221.923102)
		(width 0.254)
		(layer "B.Cu")
		(net "GND")
	)
	(segment
		(start 77.941932 -103.104696)
		(end 78.551532 -103.104696)
		(width 0.4572)
		(layer "B.Cu")
		(net "GND")
	)
	(segment
		(start 288.171128 -309.3212)
		(end 288.049716 -309.199788)
		(width 0.4572)
		(layer "B.Cu")
		(net "GND")
	)
	(segment
		(start 326.835008 -223.39427)
		(end 327.123806 -223.683068)
		(width 0.3048)
		(layer "B.Cu")
		(net "GND")
	)
	(segment
		(start 77.941932 -102.088696)
		(end 78.551532 -102.088696)
		(width 0.4572)
		(layer "B.Cu")
		(net "GND")
	)
	(segment
		(start 417.183316 -302.074834)
		(end 416.974782 -302.074834)
		(width 0.3048)
		(layer "B.Cu")
		(net "GND")
	)
	(segment
		(start 305.128676 -242.262406)
		(end 305.128676 -241.896646)
		(width 0.4572)
		(layer "B.Cu")
		(net "GND")
	)
	(segment
		(start 353.818952 -222.555816)
		(end 354.472494 -222.555816)
		(width 0.3048)
		(layer "B.Cu")
		(net "GND")
	)
	(segment
		(start 194.041776 -99.037648)
		(end 194.651376 -99.037648)
		(width 0.4572)
		(layer "B.Cu")
		(net "GND")
	)
	(segment
		(start 134.300214 -207.193896)
		(end 135.043164 -207.193896)
		(width 0.4572)
		(layer "B.Cu")
		(net "GND")
	)
	(segment
		(start 134.983728 -208.933796)
		(end 134.953502 -208.964022)
		(width 0.381)
		(layer "B.Cu")
		(net "GND")
	)
	(segment
		(start 397.865346 -301.0154)
		(end 397.97482 -301.124874)
		(width 0.3048)
		(layer "B.Cu")
		(net "GND")
	)
	(segment
		(start 177.823876 -194.683634)
		(end 178.483514 -194.683634)
		(width 0.4572)
		(layer "B.Cu")
		(net "GND")
	)
	(segment
		(start 135.697214 -208.933796)
		(end 134.983728 -208.933796)
		(width 0.381)
		(layer "B.Cu")
		(net "GND")
	)
	(segment
		(start 329.962256 -239.776)
		(end 329.71486 -239.528604)
		(width 0.4572)
		(layer "B.Cu")
		(net "GND")
	)
	(segment
		(start 165.566598 -288.774886)
		(end 165.774878 -288.774886)
		(width 0.3048)
		(layer "B.Cu")
		(net "GND")
	)
	(segment
		(start 173.375066 -297.53306)
		(end 173.375066 -297.32478)
		(width 0.3048)
		(layer "B.Cu")
		(net "GND")
	)
	(segment
		(start 184.703974 -117.723666)
		(end 183.958738 -117.415056)
		(width 0.4572)
		(layer "B.Cu")
		(net "GND")
	)
	(segment
		(start 281.874722 -297.53306)
		(end 281.874722 -297.32478)
		(width 0.3048)
		(layer "B.Cu")
		(net "GND")
	)
	(segment
		(start 345.693746 -222.786956)
		(end 345.693746 -222.78721)
		(width 0.254)
		(layer "B.Cu")
		(net "GND")
	)
	(segment
		(start 240.83772 -219.639134)
		(end 240.988088 -219.639134)
		(width 0.3048)
		(layer "B.Cu")
		(net "GND")
	)
	(segment
		(start 417.716716 -300.174914)
		(end 417.924996 -300.174914)
		(width 0.3048)
		(layer "B.Cu")
		(net "GND")
	)
	(segment
		(start 340.094062 -220.461078)
		(end 340.094062 -220.38691)
		(width 0.254)
		(layer "B.Cu")
		(net "GND")
	)
	(segment
		(start 292.918642 -296.3926)
		(end 293.25697 -296.3926)
		(width 0.3048)
		(layer "B.Cu")
		(net "GND")
	)
	(segment
		(start 331.008482 -212.34019)
		(end 330.328016 -212.34019)
		(width 0.3048)
		(layer "B.Cu")
		(net "GND")
	)
	(segment
		(start 60.511436 -162.113722)
		(end 61.235336 -162.113722)
		(width 0.4572)
		(layer "B.Cu")
		(net "GND")
	)
	(segment
		(start 209.101436 -220.39072)
		(end 208.449672 -220.39072)
		(width 0.4572)
		(layer "B.Cu")
		(net "GND")
	)
	(segment
		(start 396.315438 -360.376724)
		(end 400.75231 -360.376724)
		(width 0.4572)
		(layer "B.Cu")
		(net "GND")
	)
	(segment
		(start 284.978856 -296.37482)
		(end 284.724856 -296.37482)
		(width 0.3048)
		(layer "B.Cu")
		(net "GND")
	)
	(segment
		(start 210.82635 -226.70008)
		(end 210.82635 -226.124262)
		(width 0.3048)
		(layer "B.Cu")
		(net "GND")
	)
	(segment
		(start 300.666404 -293.52494)
		(end 300.874684 -293.52494)
		(width 0.3048)
		(layer "B.Cu")
		(net "GND")
	)
	(segment
		(start 294.22471 -297.53306)
		(end 294.22471 -297.32478)
		(width 0.3048)
		(layer "B.Cu")
		(net "GND")
	)
	(segment
		(start 172.424852 -298.06646)
		(end 172.424852 -298.27474)
		(width 0.3048)
		(layer "B.Cu")
		(net "GND")
	)
	(segment
		(start 286.878776 -296.37482)
		(end 286.624776 -296.37482)
		(width 0.3048)
		(layer "B.Cu")
		(net "GND")
	)
	(segment
		(start 56.325008 -298.274486)
		(end 56.324754 -298.27474)
		(width 0.3048)
		(layer "B.Cu")
		(net "GND")
	)
	(segment
		(start 49.4157 -301.0154)
		(end 49.565306 -301.0154)
		(width 0.3048)
		(layer "B.Cu")
		(net "GND")
	)
	(segment
		(start 165.665404 -301.0154)
		(end 165.774878 -301.124874)
		(width 0.3048)
		(layer "B.Cu")
		(net "GND")
	)
	(segment
		(start 63.924942 -294.26662)
		(end 63.924942 -294.4749)
		(width 0.3048)
		(layer "B.Cu")
		(net "GND")
	)
	(segment
		(start 410.324808 -294.26662)
		(end 410.324808 -294.4749)
		(width 0.3048)
		(layer "B.Cu")
		(net "GND")
	)
	(segment
		(start 350.376744 -317.69304)
		(end 349.85706 -317.69304)
		(width 0.254)
		(layer "B.Cu")
		(net "GND")
	)
	(segment
		(start 46.0883 -294.4749)
		(end 45.87494 -294.4749)
		(width 0.3048)
		(layer "B.Cu")
		(net "GND")
	)
	(segment
		(start 348.493842 -220.787214)
		(end 348.425262 -220.787214)
		(width 0.254)
		(layer "B.Cu")
		(net "GND")
	)
	(segment
		(start 69.70395 -98.552)
		(end 69.70395 -99.187)
		(width 0.4572)
		(layer "B.Cu")
		(net "GND")
	)
	(segment
		(start 306.574698 -298.27474)
		(end 306.226718 -298.62272)
		(width 0.4572)
		(layer "B.Cu")
		(net "GND")
	)
	(segment
		(start 114.450114 -258.404614)
		(end 114.865404 -258.404614)
		(width 0.381)
		(layer "B.Cu")
		(net "GND")
	)
	(segment
		(start 172.653706 -296.37482)
		(end 172.425106 -296.37482)
		(width 0.3048)
		(layer "B.Cu")
		(net "GND")
	)
	(segment
		(start 135.205216 -202.663806)
		(end 135.205216 -202.178412)
		(width 0.4572)
		(layer "B.Cu")
		(net "GND")
	)
	(segment
		(start 165.566598 -299.2755)
		(end 165.724332 -299.2755)
		(width 0.3048)
		(layer "B.Cu")
		(net "GND")
	)
	(segment
		(start 255.240282 -199.79005)
		(end 255.537462 -200.08723)
		(width 0.4572)
		(layer "B.Cu")
		(net "GND")
	)
	(segment
		(start 325.88327 -223.39427)
		(end 326.835008 -223.39427)
		(width 0.3048)
		(layer "B.Cu")
		(net "GND")
	)
	(segment
		(start 169.574972 -297.53306)
		(end 169.574972 -297.32478)
		(width 0.3048)
		(layer "B.Cu")
		(net "GND")
	)
	(segment
		(start 398.925034 -298.06646)
		(end 398.925034 -298.27474)
		(width 0.3048)
		(layer "B.Cu")
		(net "GND")
	)
	(segment
		(start 52.778914 -296.37482)
		(end 52.524914 -296.37482)
		(width 0.3048)
		(layer "B.Cu")
		(net "GND")
	)
	(segment
		(start 62.974982 -298.06646)
		(end 62.974982 -298.27474)
		(width 0.3048)
		(layer "B.Cu")
		(net "GND")
	)
	(segment
		(start 130.766058 -174.33671)
		(end 130.04546 -174.33671)
		(width 0.4572)
		(layer "B.Cu")
		(net "GND")
	)
	(segment
		(start 405.575008 -309.674768)
		(end 405.183848 -309.283608)
		(width 0.4572)
		(layer "B.Cu")
		(net "GND")
	)
	(segment
		(start 265.93673 -86.28634)
		(end 265.855196 -86.367874)
		(width 0.4572)
		(layer "B.Cu")
		(net "GND")
	)
	(segment
		(start 210.419442 -245.439184)
		(end 210.419442 -245.041674)
		(width 0.4572)
		(layer "B.Cu")
		(net "GND")
	)
	(segment
		(start 66.7766 -293.526718)
		(end 66.774822 -293.52494)
		(width 0.3048)
		(layer "B.Cu")
		(net "GND")
	)
	(segment
		(start 181.2036 -296.37482)
		(end 180.975 -296.37482)
		(width 0.3048)
		(layer "B.Cu")
		(net "GND")
	)
	(segment
		(start 60.124848 -297.53306)
		(end 60.124848 -297.32478)
		(width 0.3048)
		(layer "B.Cu")
		(net "GND")
	)
	(segment
		(start 350.079564 -214.381334)
		(end 350.09963 -214.381334)
		(width 0.254)
		(layer "B.Cu")
		(net "GND")
	)
	(segment
		(start 294.690038 -201.360024)
		(end 294.967914 -201.082148)
		(width 0.4572)
		(layer "B.Cu")
		(net "GND")
	)
	(segment
		(start 231.753918 -214.704422)
		(end 231.52481 -214.93353)
		(width 0.3048)
		(layer "B.Cu")
		(net "GND")
	)
	(segment
		(start 66.7766 -293.73322)
		(end 66.7766 -293.526718)
		(width 0.3048)
		(layer "B.Cu")
		(net "GND")
	)
	(segment
		(start 346.093796 -216.786968)
		(end 346.093542 -216.786968)
		(width 0.3048)
		(layer "B.Cu")
		(net "GND")
	)
	(segment
		(start 104.845866 -346.724986)
		(end 105.132378 -346.438474)
		(width 0.4572)
		(layer "B.Cu")
		(net "GND")
	)
	(segment
		(start 194.041776 -100.056696)
		(end 194.651376 -100.056696)
		(width 0.4572)
		(layer "B.Cu")
		(net "GND")
	)
	(segment
		(start 51.099974 -291.833046)
		(end 50.833274 -291.833046)
		(width 0.3048)
		(layer "B.Cu")
		(net "GND")
	)
	(segment
		(start 30.998668 -224.75063)
		(end 31.213298 -224.536)
		(width 0.4572)
		(layer "B.Cu")
		(net "GND")
	)
	(segment
		(start 108.021882 -348.985332)
		(end 108.021882 -348.226888)
		(width 0.508)
		(layer "B.Cu")
		(net "GND")
	)
	(segment
		(start 240.867438 -220.514672)
		(end 240.867438 -220.534484)
		(width 0.3048)
		(layer "B.Cu")
		(net "GND")
	)
	(segment
		(start 412.075376 -109.481366)
		(end 412.991808 -109.481366)
		(width 0.4572)
		(layer "B.Cu")
		(net "GND")
	)
	(segment
		(start 240.861088 -218.610434)
		(end 240.861088 -217.289888)
		(width 0.3048)
		(layer "B.Cu")
		(net "GND")
	)
	(segment
		(start 285.674816 -294.4749)
		(end 285.674816 -294.640508)
		(width 0.3048)
		(layer "B.Cu")
		(net "GND")
	)
	(segment
		(start 233.500422 -218.844114)
		(end 233.760518 -219.10421)
		(width 0.3048)
		(layer "B.Cu")
		(net "GND")
	)
	(segment
		(start 305.128676 -241.896646)
		(end 304.70221 -241.47018)
		(width 0.4572)
		(layer "B.Cu")
		(net "GND")
	)
	(segment
		(start 405.575008 -294.26662)
		(end 405.575008 -294.4749)
		(width 0.3048)
		(layer "B.Cu")
		(net "GND")
	)
	(segment
		(start 342.957404 -221.58706)
		(end 343.2937 -221.923356)
		(width 0.254)
		(layer "B.Cu")
		(net "GND")
	)
	(segment
		(start 330.90358 -217.125296)
		(end 330.223114 -217.125296)
		(width 0.3048)
		(layer "B.Cu")
		(net "GND")
	)
	(segment
		(start 296.124884 -294.26662)
		(end 296.124884 -294.4749)
		(width 0.3048)
		(layer "B.Cu")
		(net "GND")
	)
	(segment
		(start 340.094062 -218.787218)
		(end 340.094062 -218.725242)
		(width 0.254)
		(layer "B.Cu")
		(net "GND")
	)
	(segment
		(start 250.837446 -223.063562)
		(end 251.010674 -223.063562)
		(width 0.4572)
		(layer "B.Cu")
		(net "GND")
	)
	(segment
		(start 418.666676 -288.774886)
		(end 418.874956 -288.774886)
		(width 0.3048)
		(layer "B.Cu")
		(net "GND")
	)
	(segment
		(start 101.734874 -356.550214)
		(end 101.120448 -356.550214)
		(width 0.4572)
		(layer "B.Cu")
		(net "GND")
	)
	(segment
		(start 344.893646 -220.327728)
		(end 345.234514 -219.98686)
		(width 0.254)
		(layer "B.Cu")
		(net "GND")
	)
	(segment
		(start 426.241972 -100.056696)
		(end 426.851572 -100.056696)
		(width 0.4572)
		(layer "B.Cu")
		(net "GND")
	)
	(segment
		(start 350.112838 -319.633346)
		(end 350.158812 -319.633346)
		(width 0.4572)
		(layer "B.Cu")
		(net "GND")
	)
	(segment
		(start 170.064684 -141.6812)
		(end 170.064684 -142.367)
		(width 0.4572)
		(layer "B.Cu")
		(net "GND")
	)
	(segment
		(start 340.093808 -221.923102)
		(end 340.093808 -221.98711)
		(width 0.254)
		(layer "B.Cu")
		(net "GND")
	)
	(segment
		(start 414.124902 -294.26662)
		(end 414.124902 -294.4749)
		(width 0.3048)
		(layer "B.Cu")
		(net "GND")
	)
	(segment
		(start 228.358446 -139.919202)
		(end 227.698046 -139.919202)
		(width 0.4572)
		(layer "B.Cu")
		(net "GND")
	)
	(segment
		(start 404.879048 -296.37482)
		(end 404.625048 -296.37482)
		(width 0.3048)
		(layer "B.Cu")
		(net "GND")
	)
	(segment
		(start 347.66631 -255.826514)
		(end 347.66631 -255.599946)
		(width 0.381)
		(layer "B.Cu")
		(net "GND")
	)
	(segment
		(start 228.578664 -204.04201)
		(end 228.578664 -203.40701)
		(width 0.4572)
		(layer "B.Cu")
		(net "GND")
	)
	(segment
		(start 397.924274 -299.2755)
		(end 397.97482 -299.224954)
		(width 0.3048)
		(layer "B.Cu")
		(net "GND")
	)
	(segment
		(start 412.083504 -108.462318)
		(end 413.07004 -108.462318)
		(width 0.4572)
		(layer "B.Cu")
		(net "GND")
	)
	(segment
		(start 397.02486 -298.06646)
		(end 397.02486 -298.27474)
		(width 0.3048)
		(layer "B.Cu")
		(net "GND")
	)
	(segment
		(start 292.32479 -294.26662)
		(end 292.32479 -294.4749)
		(width 0.3048)
		(layer "B.Cu")
		(net "GND")
	)
	(segment
		(start 358.287574 -261.179818)
		(end 358.92232 -261.814564)
		(width 0.4572)
		(layer "B.Cu")
		(net "GND")
	)
	(segment
		(start 417.183316 -303.024794)
		(end 416.974782 -303.024794)
		(width 0.3048)
		(layer "B.Cu")
		(net "GND")
	)
	(segment
		(start 347.390974 -327.682098)
		(end 346.016326 -327.682098)
		(width 0.4572)
		(layer "B.Cu")
		(net "GND")
	)
	(segment
		(start 68.466462 -298.27474)
		(end 68.674742 -298.27474)
		(width 0.3048)
		(layer "B.Cu")
		(net "GND")
	)
	(segment
		(start 191.920622 -113.95202)
		(end 191.920622 -113.260632)
		(width 0.4572)
		(layer "B.Cu")
		(net "GND")
	)
	(segment
		(start 177.591466 -296.37482)
		(end 177.174906 -296.37482)
		(width 0.3048)
		(layer "B.Cu")
		(net "GND")
	)
	(segment
		(start 281.666442 -288.774886)
		(end 281.874722 -288.774886)
		(width 0.3048)
		(layer "B.Cu")
		(net "GND")
	)
	(segment
		(start 184.983374 -302.074834)
		(end 184.77484 -302.074834)
		(width 0.3048)
		(layer "B.Cu")
		(net "GND")
	)
	(segment
		(start 350.891094 -224.795334)
		(end 350.891094 -224.734628)
		(width 0.254)
		(layer "B.Cu")
		(net "GND")
	)
	(segment
		(start 53.194966 -158.8262)
		(end 53.678074 -158.343092)
		(width 0.4572)
		(layer "B.Cu")
		(net "GND")
	)
	(segment
		(start 287.574736 -294.26662)
		(end 287.574736 -294.4749)
		(width 0.3048)
		(layer "B.Cu")
		(net "GND")
	)
	(segment
		(start 342.093804 -226.387152)
		(end 341.694008 -226.786948)
		(width 0.254)
		(layer "B.Cu")
		(net "GND")
	)
	(segment
		(start 71.690738 -118.711218)
		(end 71.690738 -119.414544)
		(width 0.4572)
		(layer "B.Cu")
		(net "GND")
	)
	(segment
		(start 48.72482 -298.06646)
		(end 48.72482 -298.27474)
		(width 0.3048)
		(layer "B.Cu")
		(net "GND")
	)
	(segment
		(start 117.641624 -318.542416)
		(end 117.656864 -318.557656)
		(width 0.254)
		(layer "B.Cu")
		(net "GND")
	)
	(segment
		(start 332.940914 -324.03415)
		(end 332.485238 -324.03415)
		(width 0.254)
		(layer "B.Cu")
		(net "GND")
	)
	(segment
		(start 56.579008 -296.37482)
		(end 56.325008 -296.37482)
		(width 0.3048)
		(layer "B.Cu")
		(net "GND")
	)
	(segment
		(start 194.041776 -102.088696)
		(end 194.651376 -102.088696)
		(width 0.4572)
		(layer "B.Cu")
		(net "GND")
	)
	(segment
		(start 292.720268 -200.261474)
		(end 292.720268 -200.617074)
		(width 0.4572)
		(layer "B.Cu")
		(net "GND")
	)
	(segment
		(start 165.053518 -296.37482)
		(end 164.824918 -296.37482)
		(width 0.3048)
		(layer "B.Cu")
		(net "GND")
	)
	(segment
		(start 349.85706 -318.557656)
		(end 349.85706 -319.377568)
		(width 0.4572)
		(layer "B.Cu")
		(net "GND")
	)
	(segment
		(start 186.466734 -290.674806)
		(end 186.675014 -290.674806)
		(width 0.3048)
		(layer "B.Cu")
		(net "GND")
	)
	(segment
		(start 61.872622 -152.274524)
		(end 62.822582 -152.274524)
		(width 0.4572)
		(layer "B.Cu")
		(net "GND")
	)
	(segment
		(start 235.495846 -211.932774)
		(end 235.867448 -212.304376)
		(width 0.4572)
		(layer "B.Cu")
		(net "GND")
	)
	(segment
		(start 296.124884 -297.53306)
		(end 296.124884 -297.32478)
		(width 0.3048)
		(layer "B.Cu")
		(net "GND")
	)
	(segment
		(start 240.861088 -217.289888)
		(end 240.72469 -217.15349)
		(width 0.3048)
		(layer "B.Cu")
		(net "GND")
	)
	(segment
		(start 284.724856 -298.06646)
		(end 284.724856 -298.27474)
		(width 0.3048)
		(layer "B.Cu")
		(net "GND")
	)
	(segment
		(start 190.474854 -298.27474)
		(end 190.126874 -298.62272)
		(width 0.4572)
		(layer "B.Cu")
		(net "GND")
	)
	(segment
		(start 46.0883 -292.57498)
		(end 45.87494 -292.57498)
		(width 0.3048)
		(layer "B.Cu")
		(net "GND")
	)
	(segment
		(start 141.793214 -214.305896)
		(end 141.793214 -214.716614)
		(width 0.4572)
		(layer "B.Cu")
		(net "GND")
	)
	(segment
		(start 117.054884 -316.868048)
		(end 117.054884 -317.6778)
		(width 0.254)
		(layer "B.Cu")
		(net "GND")
	)
	(segment
		(start 280.924762 -293.73322)
		(end 280.924762 -293.52494)
		(width 0.3048)
		(layer "B.Cu")
		(net "GND")
	)
	(segment
		(start 286.164782 -141.6812)
		(end 286.164782 -142.367)
		(width 0.4572)
		(layer "B.Cu")
		(net "GND")
	)
	(segment
		(start 344.8939 -221.92234)
		(end 345.229434 -221.586806)
		(width 0.254)
		(layer "B.Cu")
		(net "GND")
	)
	(segment
		(start 295.975278 -110.497366)
		(end 296.654474 -110.497366)
		(width 0.4572)
		(layer "B.Cu")
		(net "GND")
	)
	(segment
		(start 50.624994 -293.73322)
		(end 50.624994 -293.52494)
		(width 0.3048)
		(layer "B.Cu")
		(net "GND")
	)
	(segment
		(start 46.08322 -290.674806)
		(end 45.87494 -290.674806)
		(width 0.3048)
		(layer "B.Cu")
		(net "GND")
	)
	(segment
		(start 294.22471 -294.640762)
		(end 294.22471 -294.4749)
		(width 0.3048)
		(layer "B.Cu")
		(net "GND")
	)
	(segment
		(start 339.694012 -216.786968)
		(end 339.753702 -216.786968)
		(width 0.254)
		(layer "B.Cu")
		(net "GND")
	)
	(segment
		(start 262.304276 -224.321878)
		(end 262.304276 -224.75063)
		(width 0.4572)
		(layer "B.Cu")
		(net "GND")
	)
	(segment
		(start 301.083218 -301.124874)
		(end 300.874684 -301.124874)
		(width 0.3048)
		(layer "B.Cu")
		(net "GND")
	)
	(segment
		(start 289.08375 -309.1434)
		(end 288.90595 -309.3212)
		(width 0.4572)
		(layer "B.Cu")
		(net "GND")
	)
	(segment
		(start 331.822298 -227.974906)
		(end 331.663294 -228.13391)
		(width 0.3048)
		(layer "B.Cu")
		(net "GND")
	)
	(segment
		(start 165.724332 -299.2755)
		(end 165.774878 -299.224954)
		(width 0.3048)
		(layer "B.Cu")
		(net "GND")
	)
	(segment
		(start 72.15505 -97.663)
		(end 72.15505 -96.901)
		(width 0.4572)
		(layer "B.Cu")
		(net "GND")
	)
	(segment
		(start 46.4693 -291.624766)
		(end 45.87494 -291.624766)
		(width 0.3048)
		(layer "B.Cu")
		(net "GND")
	)
	(segment
		(start 344.8939 -221.98711)
		(end 344.8939 -221.92234)
		(width 0.254)
		(layer "B.Cu")
		(net "GND")
	)
	(segment
		(start 334.09382 -224.728786)
		(end 334.435704 -224.386902)
		(width 0.254)
		(layer "B.Cu")
		(net "GND")
	)
	(segment
		(start 389.404606 -243.074444)
		(end 388.664196 -243.074444)
		(width 0.4572)
		(layer "B.Cu")
		(net "GND")
	)
	(segment
		(start 339.031834 -215.986868)
		(end 339.293962 -216.248996)
		(width 0.254)
		(layer "B.Cu")
		(net "GND")
	)
	(segment
		(start 402.724874 -298.06646)
		(end 402.724874 -298.27474)
		(width 0.3048)
		(layer "B.Cu")
		(net "GND")
	)
	(segment
		(start 351.245932 -153.817828)
		(end 351.423224 -153.640536)
		(width 0.4572)
		(layer "B.Cu")
		(net "GND")
	)
	(segment
		(start 231.129586 -256.9845)
		(end 231.129586 -256.18186)
		(width 0.254)
		(layer "B.Cu")
		(net "GND")
	)
	(segment
		(start 334.409542 -220.302328)
		(end 334.494124 -220.38691)
		(width 0.254)
		(layer "B.Cu")
		(net "GND")
	)
	(segment
		(start 210.055968 -227.470462)
		(end 210.82635 -226.70008)
		(width 0.3048)
		(layer "B.Cu")
		(net "GND")
	)
	(segment
		(start 290.65347 -296.37482)
		(end 290.42487 -296.37482)
		(width 0.3048)
		(layer "B.Cu")
		(net "GND")
	)
	(segment
		(start 69.416676 -296.37482)
		(end 69.624956 -296.37482)
		(width 0.3048)
		(layer "B.Cu")
		(net "GND")
	)
	(segment
		(start 344.493342 -221.58706)
		(end 344.893646 -221.186756)
		(width 0.254)
		(layer "B.Cu")
		(net "GND")
	)
	(segment
		(start 233.867706 -216.704164)
		(end 234.267502 -216.304368)
		(width 0.3048)
		(layer "B.Cu")
		(net "GND")
	)
	(segment
		(start 310.141874 -104.120696)
		(end 310.751474 -104.120696)
		(width 0.4572)
		(layer "B.Cu")
		(net "GND")
	)
	(segment
		(start 298.974764 -298.06646)
		(end 298.974764 -298.27474)
		(width 0.3048)
		(layer "B.Cu")
		(net "GND")
	)
	(segment
		(start 56.007 -138.15695)
		(end 56.87695 -138.15695)
		(width 0.4572)
		(layer "B.Cu")
		(net "GND")
	)
	(segment
		(start 425.124118 -113.95202)
		(end 425.124118 -113.229898)
		(width 0.4572)
		(layer "B.Cu")
		(net "GND")
	)
	(segment
		(start 301.739554 -244.512846)
		(end 301.5488 -244.7036)
		(width 0.4572)
		(layer "B.Cu")
		(net "GND")
	)
	(segment
		(start 285.674816 -294.26662)
		(end 285.674816 -294.4749)
		(width 0.3048)
		(layer "B.Cu")
		(net "GND")
	)
	(segment
		(start 170.524932 -298.06646)
		(end 170.524932 -298.27474)
		(width 0.3048)
		(layer "B.Cu")
		(net "GND")
	)
	(segment
		(start 397.76654 -290.674806)
		(end 397.97482 -290.674806)
		(width 0.3048)
		(layer "B.Cu")
		(net "GND")
	)
	(segment
		(start 186.466734 -288.774886)
		(end 186.675014 -288.774886)
		(width 0.3048)
		(layer "B.Cu")
		(net "GND")
	)
	(segment
		(start 183.0832 -296.37482)
		(end 182.87492 -296.37482)
		(width 0.3048)
		(layer "B.Cu")
		(net "GND")
	)
	(segment
		(start 310.141874 -102.088696)
		(end 310.751474 -102.088696)
		(width 0.4572)
		(layer "B.Cu")
		(net "GND")
	)
	(segment
		(start 53.474874 -294.26662)
		(end 53.474874 -294.4749)
		(width 0.3048)
		(layer "B.Cu")
		(net "GND")
	)
	(segment
		(start 344.093546 -220.30436)
		(end 344.411046 -219.98686)
		(width 0.254)
		(layer "B.Cu")
		(net "GND")
	)
	(segment
		(start 288.206942 -138.15695)
		(end 289.076892 -138.15695)
		(width 0.4572)
		(layer "B.Cu")
		(net "GND")
	)
	(segment
		(start 343.2937 -221.92361)
		(end 343.2937 -221.986856)
		(width 0.254)
		(layer "B.Cu")
		(net "GND")
	)
	(segment
		(start 267.41628 -80.506316)
		(end 272.975832 -80.506316)
		(width 0.4572)
		(layer "B.Cu")
		(net "GND")
	)
	(segment
		(start 342.024462 -217.587068)
		(end 342.094058 -217.587068)
		(width 0.254)
		(layer "B.Cu")
		(net "GND")
	)
	(segment
		(start 232.397046 -155.709366)
		(end 232.397046 -154.879802)
		(width 0.4572)
		(layer "B.Cu")
		(net "GND")
	)
	(segment
		(start 248.353834 -223.537018)
		(end 248.807986 -223.537018)
		(width 0.4572)
		(layer "B.Cu")
		(net "GND")
	)
	(segment
		(start 105.132378 -346.185236)
		(end 105.22712 -346.090494)
		(width 0.4572)
		(layer "B.Cu")
		(net "GND")
	)
	(segment
		(start 338.093812 -211.986876)
		(end 338.226908 -211.986876)
		(width 0.254)
		(layer "B.Cu")
		(net "GND")
	)
	(segment
		(start 334.435704 -224.386902)
		(end 334.494124 -224.386902)
		(width 0.254)
		(layer "B.Cu")
		(net "GND")
	)
	(segment
		(start 327.123806 -223.683068)
		(end 327.123806 -223.977708)
		(width 0.3048)
		(layer "B.Cu")
		(net "GND")
	)
	(segment
		(start 342.954356 -217.587068)
		(end 342.894158 -217.587068)
		(width 0.254)
		(layer "B.Cu")
		(net "GND")
	)
	(segment
		(start 167.675052 -297.53306)
		(end 167.675052 -297.32478)
		(width 0.3048)
		(layer "B.Cu")
		(net "GND")
	)
	(segment
		(start 344.8939 -217.254074)
		(end 344.560906 -217.587068)
		(width 0.254)
		(layer "B.Cu")
		(net "GND")
	)
	(segment
		(start 141.268196 -200.11136)
		(end 141.268196 -199.823324)
		(width 0.4572)
		(layer "B.Cu")
		(net "GND")
	)
	(segment
		(start 341.694008 -217.256614)
		(end 342.024462 -217.587068)
		(width 0.254)
		(layer "B.Cu")
		(net "GND")
	)
	(segment
		(start 169.574972 -294.26662)
		(end 169.574972 -294.4749)
		(width 0.3048)
		(layer "B.Cu")
		(net "GND")
	)
	(segment
		(start 327.544938 -236.396276)
		(end 326.416162 -237.525052)
		(width 0.4572)
		(layer "B.Cu")
		(net "GND")
	)
	(segment
		(start 208.449672 -220.39072)
		(end 208.094326 -220.746066)
		(width 0.4572)
		(layer "B.Cu")
		(net "GND")
	)
	(segment
		(start 252.70968 -84.290916)
		(end 252.45568 -84.544916)
		(width 0.4572)
		(layer "B.Cu")
		(net "GND")
	)
	(segment
		(start 411.503622 -296.37482)
		(end 411.275022 -296.37482)
		(width 0.3048)
		(layer "B.Cu")
		(net "GND")
	)
	(segment
		(start 350.543368 -224.386902)
		(end 350.493584 -224.386902)
		(width 0.254)
		(layer "B.Cu")
		(net "GND")
	)
	(segment
		(start 414.124902 -297.53306)
		(end 414.124902 -297.32478)
		(width 0.3048)
		(layer "B.Cu")
		(net "GND")
	)
	(segment
		(start 402.978874 -296.37482)
		(end 402.724874 -296.37482)
		(width 0.3048)
		(layer "B.Cu")
		(net "GND")
	)
	(segment
		(start 67.745356 -114.713512)
		(end 67.66687 -114.635026)
		(width 0.4572)
		(layer "B.Cu")
		(net "GND")
	)
	(segment
		(start 184.983374 -301.124874)
		(end 184.77484 -301.124874)
		(width 0.3048)
		(layer "B.Cu")
		(net "GND")
	)
	(segment
		(start 69.416676 -300.174914)
		(end 69.624956 -300.174914)
		(width 0.3048)
		(layer "B.Cu")
		(net "GND")
	)
	(segment
		(start 295.17467 -293.525194)
		(end 295.174924 -293.52494)
		(width 0.3048)
		(layer "B.Cu")
		(net "GND")
	)
	(segment
		(start 132.383022 -206.756254)
		(end 133.030214 -207.403446)
		(width 0.4572)
		(layer "B.Cu")
		(net "GND")
	)
	(segment
		(start 118.190264 -316.003686)
		(end 117.67058 -316.003686)
		(width 0.254)
		(layer "B.Cu")
		(net "GND")
	)
	(segment
		(start 405.575008 -297.53306)
		(end 405.575008 -297.32478)
		(width 0.3048)
		(layer "B.Cu")
		(net "GND")
	)
	(segment
		(start 133.411214 -201.567796)
		(end 132.668264 -201.567796)
		(width 0.381)
		(layer "B.Cu")
		(net "GND")
	)
	(segment
		(start 236.887512 -235.128054)
		(end 236.887512 -235.737654)
		(width 0.4572)
		(layer "B.Cu")
		(net "GND")
	)
	(segment
		(start 68.499228 -114.713512)
		(end 67.745356 -114.713512)
		(width 0.4572)
		(layer "B.Cu")
		(net "GND")
	)
	(segment
		(start 176.758346 -296.37482)
		(end 177.174906 -296.37482)
		(width 0.3048)
		(layer "B.Cu")
		(net "GND")
	)
	(segment
		(start 232.651046 -143.881602)
		(end 232.651046 -143.094202)
		(width 0.4572)
		(layer "B.Cu")
		(net "GND")
	)
	(segment
		(start 133.538214 -208.552796)
		(end 132.777738 -208.552796)
		(width 0.4572)
		(layer "B.Cu")
		(net "GND")
	)
	(segment
		(start 68.60413 -117.723666)
		(end 67.858894 -117.415056)
		(width 0.4572)
		(layer "B.Cu")
		(net "GND")
	)
	(segment
		(start 266.40028 -87.364316)
		(end 265.675364 -88.089232)
		(width 0.4572)
		(layer "B.Cu")
		(net "GND")
	)
	(segment
		(start 351.245932 -154.305)
		(end 351.245932 -153.817828)
		(width 0.4572)
		(layer "B.Cu")
		(net "GND")
	)
	(segment
		(start 346.093288 -222.387414)
		(end 345.693746 -222.786956)
		(width 0.254)
		(layer "B.Cu")
		(net "GND")
	)
	(segment
		(start 253.918212 -84.069428)
		(end 253.918212 -84.301838)
		(width 0.4572)
		(layer "B.Cu")
		(net "GND")
	)
	(segment
		(start 349.25508 -318.542416)
		(end 349.84182 -318.542416)
		(width 0.254)
		(layer "B.Cu")
		(net "GND")
	)
	(segment
		(start 165.033198 -300.174914)
		(end 164.824918 -300.174914)
		(width 0.3048)
		(layer "B.Cu")
		(net "GND")
	)
	(segment
		(start 281.765248 -301.0154)
		(end 281.874722 -301.124874)
		(width 0.3048)
		(layer "B.Cu")
		(net "GND")
	)
	(segment
		(start 103.764842 -337.875626)
		(end 103.764842 -338.573618)
		(width 0.4572)
		(layer "B.Cu")
		(net "GND")
	)
	(segment
		(start 289.462718 -196.960236)
		(end 290.938712 -196.960236)
		(width 0.4572)
		(layer "B.Cu")
		(net "GND")
	)
	(segment
		(start 224.269046 -142.357602)
		(end 224.269046 -141.570202)
		(width 0.4572)
		(layer "B.Cu")
		(net "GND")
	)
	(segment
		(start 141.793214 -214.716614)
		(end 142.035784 -214.959184)
		(width 0.4572)
		(layer "B.Cu")
		(net "GND")
	)
	(segment
		(start 213.654894 -211.807044)
		(end 214.054436 -212.206586)
		(width 0.4572)
		(layer "B.Cu")
		(net "GND")
	)
	(segment
		(start 347.66885 -361.4166)
		(end 348.5642 -361.4166)
		(width 0.4572)
		(layer "B.Cu")
		(net "GND")
	)
	(segment
		(start 240.867438 -220.534484)
		(end 241.373914 -221.04096)
		(width 0.3048)
		(layer "B.Cu")
		(net "GND")
	)
	(segment
		(start 413.403542 -296.37482)
		(end 413.174942 -296.37482)
		(width 0.3048)
		(layer "B.Cu")
		(net "GND")
	)
	(segment
		(start 136.233916 -180.012594)
		(end 136.233916 -180.7591)
		(width 0.4572)
		(layer "B.Cu")
		(net "GND")
	)
	(segment
		(start 49.4665 -299.2755)
		(end 49.624234 -299.2755)
		(width 0.3048)
		(layer "B.Cu")
		(net "GND")
	)
	(segment
		(start 326.416162 -237.525052)
		(end 324.116446 -237.525052)
		(width 0.4572)
		(layer "B.Cu")
		(net "GND")
	)
	(segment
		(start 62.024768 -294.4749)
		(end 62.024768 -294.640762)
		(width 0.3048)
		(layer "B.Cu")
		(net "GND")
	)
	(segment
		(start 331.663294 -228.13391)
		(end 331.663294 -228.386894)
		(width 0.3048)
		(layer "B.Cu")
		(net "GND")
	)
	(segment
		(start 208.094326 -220.746066)
		(end 207.510126 -220.746066)
		(width 0.4572)
		(layer "B.Cu")
		(net "GND")
	)
	(segment
		(start 346.093542 -216.786968)
		(end 345.693746 -216.387172)
		(width 0.3048)
		(layer "B.Cu")
		(net "GND")
	)
	(segment
		(start 338.494116 -212.254084)
		(end 338.494116 -212.38718)
		(width 0.254)
		(layer "B.Cu")
		(net "GND")
	)
	(segment
		(start 174.325026 -293.73322)
		(end 174.325026 -293.52494)
		(width 0.3048)
		(layer "B.Cu")
		(net "GND")
	)
	(segment
		(start 231.067356 -213.104476)
		(end 231.147366 -213.024466)
		(width 0.3048)
		(layer "B.Cu")
		(net "GND")
	)
	(segment
		(start 397.45539 -154.0256)
		(end 396.84579 -154.0256)
		(width 0.4572)
		(layer "B.Cu")
		(net "GND")
	)
	(segment
		(start 211.48294 -252.315726)
		(end 211.476082 -252.315726)
		(width 0.3048)
		(layer "B.Cu")
		(net "GND")
	)
	(segment
		(start 233.867706 -215.104472)
		(end 234.267502 -215.504268)
		(width 0.3048)
		(layer "B.Cu")
		(net "GND")
	)
	(segment
		(start 331.01153 -211.390738)
		(end 330.381864 -211.390738)
		(width 0.3048)
		(layer "B.Cu")
		(net "GND")
	)
	(segment
		(start 131.529328 -211.242148)
		(end 131.529328 -211.977732)
		(width 0.4572)
		(layer "B.Cu")
		(net "GND")
	)
	(segment
		(start 55.374794 -297.53306)
		(end 55.374794 -297.32478)
		(width 0.3048)
		(layer "B.Cu")
		(net "GND")
	)
	(segment
		(start 192.923922 -113.95202)
		(end 192.923922 -113.229898)
		(width 0.4572)
		(layer "B.Cu")
		(net "GND")
	)
	(segment
		(start 203.217018 -240.7539)
		(end 203.217018 -244.209062)
		(width 0.3556)
		(layer "B.Cu")
		(net "GND")
	)
	(segment
		(start 343.760806 -217.587068)
		(end 343.694004 -217.587068)
		(width 0.254)
		(layer "B.Cu")
		(net "GND")
	)
	(segment
		(start 163.874958 -290.883086)
		(end 163.874958 -290.674806)
		(width 0.3048)
		(layer "B.Cu")
		(net "GND")
	)
	(segment
		(start 141.946376 -203.552806)
		(end 142.509494 -204.115924)
		(width 0.4572)
		(layer "B.Cu")
		(net "GND")
	)
	(segment
		(start 234.267502 -215.504268)
		(end 234.267502 -216.304368)
		(width 0.3048)
		(layer "B.Cu")
		(net "GND")
	)
	(segment
		(start 290.42487 -293.73322)
		(end 290.42487 -293.52494)
		(width 0.3048)
		(layer "B.Cu")
		(net "GND")
	)
	(segment
		(start 399.179034 -296.37482)
		(end 398.925034 -296.37482)
		(width 0.3048)
		(layer "B.Cu")
		(net "GND")
	)
	(segment
		(start 291.06114 -206.138018)
		(end 291.33419 -206.411068)
		(width 0.4572)
		(layer "B.Cu")
		(net "GND")
	)
	(segment
		(start 405.575008 -294.4749)
		(end 405.575008 -294.640508)
		(width 0.3048)
		(layer "B.Cu")
		(net "GND")
	)
	(segment
		(start 167.675052 -294.26662)
		(end 167.675052 -294.4749)
		(width 0.3048)
		(layer "B.Cu")
		(net "GND")
	)
	(segment
		(start 299.005244 -237.136686)
		(end 299.005244 -237.664244)
		(width 0.4572)
		(layer "B.Cu")
		(net "GND")
	)
	(segment
		(start 301.083218 -302.074834)
		(end 300.874684 -302.074834)
		(width 0.3048)
		(layer "B.Cu")
		(net "GND")
	)
	(segment
		(start 397.76654 -288.774886)
		(end 397.97482 -288.774886)
		(width 0.3048)
		(layer "B.Cu")
		(net "GND")
	)
	(segment
		(start 419.990778 -118.711218)
		(end 419.990778 -119.414544)
		(width 0.4572)
		(layer "B.Cu")
		(net "GND")
	)
	(segment
		(start 182.87492 -293.73322)
		(end 182.87492 -293.52494)
		(width 0.3048)
		(layer "B.Cu")
		(net "GND")
	)
	(segment
		(start 165.774878 -297.53306)
		(end 165.774878 -297.32478)
		(width 0.3048)
		(layer "B.Cu")
		(net "GND")
	)
	(segment
		(start 400.824954 -293.73322)
		(end 400.824954 -293.52494)
		(width 0.3048)
		(layer "B.Cu")
		(net "GND")
	)
	(segment
		(start 187.790582 -118.711218)
		(end 187.790582 -119.414544)
		(width 0.4572)
		(layer "B.Cu")
		(net "GND")
	)
	(segment
		(start 115.466114 -255.599946)
		(end 115.87734 -255.18872)
		(width 0.381)
		(layer "B.Cu")
		(net "GND")
	)
	(segment
		(start 413.174942 -298.06646)
		(end 413.174942 -298.27474)
		(width 0.3048)
		(layer "B.Cu")
		(net "GND")
	)
	(segment
		(start 340.894162 -217.246962)
		(end 341.234268 -217.587068)
		(width 0.254)
		(layer "B.Cu")
		(net "GND")
	)
	(segment
		(start 137.446766 -211.045806)
		(end 137.446766 -210.39709)
		(width 0.4572)
		(layer "B.Cu")
		(net "GND")
	)
	(segment
		(start 104.178608 -357.766112)
		(end 104.178608 -358.375712)
		(width 0.3048)
		(layer "B.Cu")
		(net "GND")
	)
	(segment
		(start 228.800152 -226.051364)
		(end 228.800152 -225.72853)
		(width 0.4572)
		(layer "B.Cu")
		(net "GND")
	)
	(segment
		(start 417.716716 -294.4749)
		(end 417.924996 -294.4749)
		(width 0.3048)
		(layer "B.Cu")
		(net "GND")
	)
	(segment
		(start 310.141874 -98.021648)
		(end 310.751474 -98.021648)
		(width 0.4572)
		(layer "B.Cu")
		(net "GND")
	)
	(segment
		(start 408.424888 -297.53306)
		(end 408.424888 -297.32478)
		(width 0.3048)
		(layer "B.Cu")
		(net "GND")
	)
	(segment
		(start 402.724874 -293.73322)
		(end 402.724874 -293.52494)
		(width 0.3048)
		(layer "B.Cu")
		(net "GND")
	)
	(segment
		(start 341.234268 -217.587068)
		(end 341.294212 -217.587068)
		(width 0.254)
		(layer "B.Cu")
		(net "GND")
	)
	(segment
		(start 227.190046 -153.400252)
		(end 227.190046 -154.016202)
		(width 0.4572)
		(layer "B.Cu")
		(net "GND")
	)
	(segment
		(start 48.9331 -300.174914)
		(end 48.72482 -300.174914)
		(width 0.3048)
		(layer "B.Cu")
		(net "GND")
	)
	(segment
		(start 107.573318 -349.37192)
		(end 107.959906 -348.985332)
		(width 0.3048)
		(layer "B.Cu")
		(net "GND")
	)
	(segment
		(start 172.983906 -309.283608)
		(end 172.592746 -309.674768)
		(width 0.4572)
		(layer "B.Cu")
		(net "GND")
	)
	(segment
		(start 289.47491 -294.640508)
		(end 288.893504 -295.221914)
		(width 0.3048)
		(layer "B.Cu")
		(net "GND")
	)
	(segment
		(start 209.965036 -253.826772)
		(end 209.965036 -254.530606)
		(width 0.3048)
		(layer "B.Cu")
		(net "GND")
	)
	(segment
		(start 397.23314 -291.624766)
		(end 397.02486 -291.624766)
		(width 0.3048)
		(layer "B.Cu")
		(net "GND")
	)
	(segment
		(start 345.29395 -217.587068)
		(end 345.23553 -217.587068)
		(width 0.254)
		(layer "B.Cu")
		(net "GND")
	)
	(segment
		(start 349.135954 -260.800596)
		(end 349.135954 -261.154672)
		(width 0.4572)
		(layer "B.Cu")
		(net "GND")
	)
	(segment
		(start 229.434644 -232.103422)
		(end 229.827582 -232.49636)
		(width 0.4572)
		(layer "B.Cu")
		(net "GND")
	)
	(segment
		(start 56.325008 -293.525194)
		(end 56.324754 -293.52494)
		(width 0.3048)
		(layer "B.Cu")
		(net "GND")
	)
	(segment
		(start 232.590848 -155.903168)
		(end 232.397046 -155.709366)
		(width 0.4572)
		(layer "B.Cu")
		(net "GND")
	)
	(segment
		(start 109.274102 -335.881726)
		(end 109.85119 -335.881726)
		(width 0.508)
		(layer "B.Cu")
		(net "GND")
	)
	(segment
		(start 338.893912 -215.986868)
		(end 339.031834 -215.986868)
		(width 0.254)
		(layer "B.Cu")
		(net "GND")
	)
	(segment
		(start 174.553626 -296.37482)
		(end 174.325026 -296.37482)
		(width 0.3048)
		(layer "B.Cu")
		(net "GND")
	)
	(segment
		(start 293.643558 -295.221914)
		(end 294.22471 -294.640762)
		(width 0.3048)
		(layer "B.Cu")
		(net "GND")
	)
	(segment
		(start 99.506278 -349.98025)
		(end 100.242878 -349.98025)
		(width 0.4572)
		(layer "B.Cu")
		(net "GND")
	)
	(segment
		(start 207.487012 -221.671134)
		(end 207.510126 -221.694248)
		(width 0.4572)
		(layer "B.Cu")
		(net "GND")
	)
	(segment
		(start 300.058836 -117.415056)
		(end 299.822108 -117.415056)
		(width 0.4572)
		(layer "B.Cu")
		(net "GND")
	)
	(segment
		(start 426.241972 -103.104696)
		(end 426.851572 -103.104696)
		(width 0.4572)
		(layer "B.Cu")
		(net "GND")
	)
	(segment
		(start 232.823512 -235.128054)
		(end 232.823512 -235.737654)
		(width 0.4572)
		(layer "B.Cu")
		(net "GND")
	)
	(segment
		(start 190.126874 -302.422814)
		(end 190.126874 -301.524924)
		(width 0.381)
		(layer "B.Cu")
		(net "GND")
	)
	(segment
		(start 232.083864 -204.04201)
		(end 232.083864 -203.40701)
		(width 0.4572)
		(layer "B.Cu")
		(net "GND")
	)
	(segment
		(start 233.716068 -78.359254)
		(end 233.692192 -78.38313)
		(width 0.4572)
		(layer "B.Cu")
		(net "GND")
	)
	(segment
		(start 426.241972 -99.037648)
		(end 426.851572 -99.037648)
		(width 0.4572)
		(layer "B.Cu")
		(net "GND")
	)
	(segment
		(start 148.209254 -206.787242)
		(end 147.574254 -206.787242)
		(width 0.4572)
		(layer "B.Cu")
		(net "GND")
	)
	(segment
		(start 234.855512 -235.128054)
		(end 234.855512 -235.737654)
		(width 0.4572)
		(layer "B.Cu")
		(net "GND")
	)
	(segment
		(start 401.774914 -294.26662)
		(end 401.774914 -294.4749)
		(width 0.3048)
		(layer "B.Cu")
		(net "GND")
	)
	(segment
		(start 65.824862 -294.26662)
		(end 65.824862 -294.4749)
		(width 0.3048)
		(layer "B.Cu")
		(net "GND")
	)
	(segment
		(start 113.914174 -328.43343)
		(end 114.631216 -328.43343)
		(width 0.4572)
		(layer "B.Cu")
		(net "GND")
	)
	(segment
		(start 236.505496 -211.932774)
		(end 236.505496 -211.201)
		(width 0.4572)
		(layer "B.Cu")
		(net "GND")
	)
	(segment
		(start 292.798246 -195.685664)
		(end 292.971982 -195.8594)
		(width 0.4572)
		(layer "B.Cu")
		(net "GND")
	)
	(segment
		(start 302.566578 -289.724846)
		(end 302.774858 -289.724846)
		(width 0.3048)
		(layer "B.Cu")
		(net "GND")
	)
	(segment
		(start 241.281712 -235.46181)
		(end 241.444018 -235.624116)
		(width 0.4572)
		(layer "B.Cu")
		(net "GND")
	)
	(segment
		(start 404.30704 -138.15695)
		(end 405.17699 -138.15695)
		(width 0.4572)
		(layer "B.Cu")
		(net "GND")
	)
	(segment
		(start 342.893396 -221.58706)
		(end 342.957404 -221.58706)
		(width 0.254)
		(layer "B.Cu")
		(net "GND")
	)
	(segment
		(start 345.234514 -219.98686)
		(end 345.293442 -219.98686)
		(width 0.254)
		(layer "B.Cu")
		(net "GND")
	)
	(segment
		(start 403.674834 -294.26662)
		(end 403.674834 -294.4749)
		(width 0.3048)
		(layer "B.Cu")
		(net "GND")
	)
	(segment
		(start 141.040866 -202.282806)
		(end 141.793214 -202.282806)
		(width 0.4572)
		(layer "B.Cu")
		(net "GND")
	)
	(segment
		(start 68.883276 -303.024794)
		(end 68.674742 -303.024794)
		(width 0.3048)
		(layer "B.Cu")
		(net "GND")
	)
	(segment
		(start 310.141874 -103.104696)
		(end 310.751474 -103.104696)
		(width 0.4572)
		(layer "B.Cu")
		(net "GND")
	)
	(segment
		(start 232.355644 -218.986608)
		(end 232.498138 -218.844114)
		(width 0.3048)
		(layer "B.Cu")
		(net "GND")
	)
	(segment
		(start 298.024804 -297.53306)
		(end 298.024804 -297.32478)
		(width 0.3048)
		(layer "B.Cu")
		(net "GND")
	)
	(segment
		(start 60.7187 -296.3926)
		(end 61.057028 -296.3926)
		(width 0.3048)
		(layer "B.Cu")
		(net "GND")
	)
	(segment
		(start 117.054884 -318.542416)
		(end 117.641624 -318.542416)
		(width 0.254)
		(layer "B.Cu")
		(net "GND")
	)
	(segment
		(start 349.27032 -317.69304)
		(end 349.85706 -317.69304)
		(width 0.254)
		(layer "B.Cu")
		(net "GND")
	)
	(segment
		(start 228.805486 -227.001832)
		(end 228.805486 -226.738688)
		(width 0.4572)
		(layer "B.Cu")
		(net "GND")
	)
	(segment
		(start 350.39046 -316.003686)
		(end 350.376744 -315.98997)
		(width 0.254)
		(layer "B.Cu")
		(net "GND")
	)
	(segment
		(start 334.088994 -213.668102)
		(end 334.408272 -213.98738)
		(width 0.254)
		(layer "B.Cu")
		(net "GND")
	)
	(segment
		(start 290.938712 -196.960236)
		(end 291.93363 -195.965318)
		(width 0.4572)
		(layer "B.Cu")
		(net "GND")
	)
	(segment
		(start 354.06838 -219.158566)
		(end 354.816664 -219.158566)
		(width 0.3048)
		(layer "B.Cu")
		(net "GND")
	)
	(segment
		(start 422.326816 -301.726854)
		(end 422.326816 -301.524924)
		(width 0.381)
		(layer "B.Cu")
		(net "GND")
	)
	(segment
		(start 228.612446 -140.173202)
		(end 228.358446 -139.919202)
		(width 0.4572)
		(layer "B.Cu")
		(net "GND")
	)
	(segment
		(start 48.72482 -293.73322)
		(end 48.72482 -293.52494)
		(width 0.3048)
		(layer "B.Cu")
		(net "GND")
	)
	(segment
		(start 49.67478 -294.26662)
		(end 49.67478 -294.4749)
		(width 0.3048)
		(layer "B.Cu")
		(net "GND")
	)
	(segment
		(start 179.07508 -298.06646)
		(end 179.07508 -298.27474)
		(width 0.3048)
		(layer "B.Cu")
		(net "GND")
	)
	(segment
		(start 100.573586 -344.163904)
		(end 100.573586 -343.446862)
		(width 0.4572)
		(layer "B.Cu")
		(net "GND")
	)
	(segment
		(start 54.424834 -293.73322)
		(end 54.424834 -293.52494)
		(width 0.3048)
		(layer "B.Cu")
		(net "GND")
	)
	(segment
		(start 396.0749 -296.90822)
		(end 396.0749 -297.32478)
		(width 0.3048)
		(layer "B.Cu")
		(net "GND")
	)
	(segment
		(start 325.708518 -223.569022)
		(end 325.88327 -223.39427)
		(width 0.3048)
		(layer "B.Cu")
		(net "GND")
	)
	(segment
		(start 330.94295 -239.776)
		(end 329.962256 -239.776)
		(width 0.4572)
		(layer "B.Cu")
		(net "GND")
	)
	(segment
		(start 77.941932 -98.021648)
		(end 78.551532 -98.021648)
		(width 0.4572)
		(layer "B.Cu")
		(net "GND")
	)
	(segment
		(start 416.90417 -117.723666)
		(end 416.158934 -117.415056)
		(width 0.4572)
		(layer "B.Cu")
		(net "GND")
	)
	(segment
		(start 116.935758 -260.800596)
		(end 116.935758 -261.154672)
		(width 0.4572)
		(layer "B.Cu")
		(net "GND")
	)
	(segment
		(start 165.515798 -301.0154)
		(end 165.665404 -301.0154)
		(width 0.3048)
		(layer "B.Cu")
		(net "GND")
	)
	(segment
		(start 340.094062 -218.725242)
		(end 339.755988 -218.387168)
		(width 0.254)
		(layer "B.Cu")
		(net "GND")
	)
	(segment
		(start 297.074844 -298.06646)
		(end 297.074844 -298.27474)
		(width 0.3048)
		(layer "B.Cu")
		(net "GND")
	)
	(segment
		(start 70.366636 -288.774886)
		(end 70.574916 -288.774886)
		(width 0.3048)
		(layer "B.Cu")
		(net "GND")
	)
	(segment
		(start 165.255194 -150.9776)
		(end 164.645594 -150.9776)
		(width 0.4572)
		(layer "B.Cu")
		(net "GND")
	)
	(segment
		(start 203.976986 -363.00029)
		(end 203.378562 -362.401866)
		(width 0.4572)
		(layer "B.Cu")
		(net "GND")
	)
	(segment
		(start 135.806942 -173.792388)
		(end 135.87476 -173.860206)
		(width 0.4572)
		(layer "B.Cu")
		(net "GND")
	)
	(segment
		(start 399.874994 -294.26662)
		(end 399.874994 -294.4749)
		(width 0.3048)
		(layer "B.Cu")
		(net "GND")
	)
	(segment
		(start 163.874958 -297.0149)
		(end 163.874958 -297.32478)
		(width 0.3048)
		(layer "B.Cu")
		(net "GND")
	)
	(segment
		(start 291.06114 -202.474068)
		(end 291.06114 -201.731118)
		(width 0.4572)
		(layer "B.Cu")
		(net "GND")
	)
	(segment
		(start 426.241972 -98.021648)
		(end 426.851572 -98.021648)
		(width 0.4572)
		(layer "B.Cu")
		(net "GND")
	)
	(segment
		(start 232.498138 -218.844114)
		(end 233.500422 -218.844114)
		(width 0.3048)
		(layer "B.Cu")
		(net "GND")
	)
	(segment
		(start 416.799268 -114.713512)
		(end 416.045396 -114.713512)
		(width 0.4572)
		(layer "B.Cu")
		(net "GND")
	)
	(segment
		(start 302.566578 -288.774886)
		(end 302.774858 -288.774886)
		(width 0.3048)
		(layer "B.Cu")
		(net "GND")
	)
	(segment
		(start 293.29253 -296.3926)
		(end 293.27475 -296.37482)
		(width 0.3048)
		(layer "B.Cu")
		(net "GND")
	)
	(segment
		(start 65.824862 -297.53306)
		(end 65.824862 -297.32478)
		(width 0.3048)
		(layer "B.Cu")
		(net "GND")
	)
	(segment
		(start 117.67058 -316.003686)
		(end 117.656864 -315.98997)
		(width 0.254)
		(layer "B.Cu")
		(net "GND")
	)
	(segment
		(start 233.867706 -215.104218)
		(end 233.867706 -215.104472)
		(width 0.3048)
		(layer "B.Cu")
		(net "GND")
	)
	(segment
		(start 418.666676 -289.724846)
		(end 418.874956 -289.724846)
		(width 0.3048)
		(layer "B.Cu")
		(net "GND")
	)
	(segment
		(start 299.945298 -114.713512)
		(end 299.866812 -114.635026)
		(width 0.4572)
		(layer "B.Cu")
		(net "GND")
	)
	(segment
		(start 185.516774 -297.32478)
		(end 185.725054 -297.32478)
		(width 0.3048)
		(layer "B.Cu")
		(net "GND")
	)
	(segment
		(start 346.893134 -227.187252)
		(end 346.493592 -227.586794)
		(width 0.254)
		(layer "B.Cu")
		(net "GND")
	)
	(segment
		(start 185.516774 -296.37482)
		(end 185.725054 -296.37482)
		(width 0.3048)
		(layer "B.Cu")
		(net "GND")
	)
	(segment
		(start 339.767926 -220.787214)
		(end 340.094062 -220.461078)
		(width 0.254)
		(layer "B.Cu")
		(net "GND")
	)
	(segment
		(start 405.183848 -309.283608)
		(end 405.183848 -309.124858)
		(width 0.4572)
		(layer "B.Cu")
		(net "GND")
	)
	(segment
		(start 51.574954 -297.53306)
		(end 51.574954 -297.32478)
		(width 0.3048)
		(layer "B.Cu")
		(net "GND")
	)
	(segment
		(start 58.453528 -296.37482)
		(end 58.224928 -296.37482)
		(width 0.3048)
		(layer "B.Cu")
		(net "GND")
	)
	(segment
		(start 306.574698 -302.074834)
		(end 306.226718 -301.726854)
		(width 0.381)
		(layer "B.Cu")
		(net "GND")
	)
	(segment
		(start 53.35778 -294.757602)
		(end 53.474874 -294.4749)
		(width 0.3048)
		(layer "B.Cu")
		(net "GND")
	)
	(segment
		(start 340.493858 -221.586552)
		(end 340.094062 -221.186756)
		(width 0.254)
		(layer "B.Cu")
		(net "GND")
	)
	(segment
		(start 68.883276 -301.124874)
		(end 68.674742 -301.124874)
		(width 0.3048)
		(layer "B.Cu")
		(net "GND")
	)
	(segment
		(start 132.777738 -208.552796)
		(end 132.741416 -208.516474)
		(width 0.4572)
		(layer "B.Cu")
		(net "GND")
	)
	(segment
		(start 180.02504 -297.53306)
		(end 180.02504 -297.32478)
		(width 0.3048)
		(layer "B.Cu")
		(net "GND")
	)
	(segment
		(start 134.332472 -222.658432)
		(end 134.332472 -221.915482)
		(width 0.4572)
		(layer "B.Cu")
		(net "GND")
	)
	(segment
		(start 327.544938 -235.723938)
		(end 327.544938 -236.396276)
		(width 0.4572)
		(layer "B.Cu")
		(net "GND")
	)
	(segment
		(start 141.268196 -199.823324)
		(end 140.806678 -199.361806)
		(width 0.4572)
		(layer "B.Cu")
		(net "GND")
	)
	(segment
		(start 394.38326 -290.674806)
		(end 394.17498 -290.674806)
		(width 0.3048)
		(layer "B.Cu")
		(net "GND")
	)
	(segment
		(start 233.692192 -78.38313)
		(end 233.692192 -79.305912)
		(width 0.4572)
		(layer "B.Cu")
		(net "GND")
	)
	(segment
		(start 241.07902 -234.469432)
		(end 242.038124 -234.469432)
		(width 0.4572)
		(layer "B.Cu")
		(net "GND")
	)
	(segment
		(start 169.574972 -294.640508)
		(end 168.993566 -295.221914)
		(width 0.3048)
		(layer "B.Cu")
		(net "GND")
	)
	(segment
		(start 406.753568 -296.37482)
		(end 406.524968 -296.37482)
		(width 0.3048)
		(layer "B.Cu")
		(net "GND")
	)
	(segment
		(start 48.97882 -296.37482)
		(end 48.72482 -296.37482)
		(width 0.3048)
		(layer "B.Cu")
		(net "GND")
	)
	(segment
		(start 227.063046 -140.452602)
		(end 227.063046 -139.792202)
		(width 0.4572)
		(layer "B.Cu")
		(net "GND")
	)
	(segment
		(start 291.93363 -195.965318)
		(end 292.213284 -195.685664)
		(width 0.4572)
		(layer "B.Cu")
		(net "GND")
	)
	(segment
		(start 349.25508 -316.868048)
		(end 349.25508 -317.6778)
		(width 0.254)
		(layer "B.Cu")
		(net "GND")
	)
	(segment
		(start 338.226908 -211.986876)
		(end 338.494116 -212.254084)
		(width 0.254)
		(layer "B.Cu")
		(net "GND")
	)
	(segment
		(start 339.293962 -216.248996)
		(end 339.293962 -216.387172)
		(width 0.254)
		(layer "B.Cu")
		(net "GND")
	)
	(segment
		(start 397.27886 -296.37482)
		(end 397.02486 -296.37482)
		(width 0.3048)
		(layer "B.Cu")
		(net "GND")
	)
	(segment
		(start 306.226718 -298.62272)
		(end 306.226718 -298.82465)
		(width 0.4572)
		(layer "B.Cu")
		(net "GND")
	)
	(segment
		(start 129.366264 -202.221846)
		(end 129.366264 -201.478896)
		(width 0.4572)
		(layer "B.Cu")
		(net "GND")
	)
	(segment
		(start 288.52495 -293.73322)
		(end 288.52495 -293.525194)
		(width 0.3048)
		(layer "B.Cu")
		(net "GND")
	)
	(segment
		(start 415.283142 -296.37482)
		(end 415.074862 -296.37482)
		(width 0.3048)
		(layer "B.Cu")
		(net "GND")
	)
	(segment
		(start 344.8939 -217.245438)
		(end 344.8939 -217.254074)
		(width 0.254)
		(layer "B.Cu")
		(net "GND")
	)
	(segment
		(start 380.111 -233.426)
		(end 380.365 -233.68)
		(width 0.4572)
		(layer "B.Cu")
		(net "GND")
	)
	(segment
		(start 178.124866 -297.53306)
		(end 178.124866 -297.32478)
		(width 0.3048)
		(layer "B.Cu")
		(net "GND")
	)
	(segment
		(start 228.525578 -141.316202)
		(end 228.131624 -140.922248)
		(width 0.4572)
		(layer "B.Cu")
		(net "GND")
	)
	(segment
		(start 281.133042 -291.624766)
		(end 280.924762 -291.624766)
		(width 0.3048)
		(layer "B.Cu")
		(net "GND")
	)
	(segment
		(start 174.325026 -298.06646)
		(end 174.325026 -298.27474)
		(width 0.3048)
		(layer "B.Cu")
		(net "GND")
	)
	(segment
		(start 335.709514 -219.171774)
		(end 336.09407 -218.787218)
		(width 0.254)
		(layer "B.Cu")
		(net "GND")
	)
	(segment
		(start 177.174906 -298.06646)
		(end 177.174906 -298.27474)
		(width 0.3048)
		(layer "B.Cu")
		(net "GND")
	)
	(segment
		(start 242.038124 -234.469432)
		(end 242.051078 -234.456478)
		(width 0.4572)
		(layer "B.Cu")
		(net "GND")
	)
	(segment
		(start 343.63025 -221.58706)
		(end 343.2937 -221.92361)
		(width 0.254)
		(layer "B.Cu")
		(net "GND")
	)
	(segment
		(start 378.46 -233.91495)
		(end 377.71705 -233.91495)
		(width 0.381)
		(layer "B.Cu")
		(net "GND")
	)
	(segment
		(start 409.374848 -298.27474)
		(end 409.374848 -298.06646)
		(width 0.3048)
		(layer "B.Cu")
		(net "GND")
	)
	(segment
		(start 397.45539 -151.9936)
		(end 396.84579 -151.9936)
		(width 0.4572)
		(layer "B.Cu")
		(net "GND")
	)
	(segment
		(start 135.678164 -201.332846)
		(end 135.316214 -201.332846)
		(width 0.4572)
		(layer "B.Cu")
		(net "GND")
	)
	(segment
		(start 67.858894 -117.415056)
		(end 67.622166 -117.415056)
		(width 0.4572)
		(layer "B.Cu")
		(net "GND")
	)
	(segment
		(start 340.093808 -222.055182)
		(end 340.093808 -221.98711)
		(width 0.254)
		(layer "B.Cu")
		(net "GND")
	)
	(segment
		(start 287.574736 -297.53306)
		(end 287.574736 -297.32478)
		(width 0.3048)
		(layer "B.Cu")
		(net "GND")
	)
	(segment
		(start 339.76183 -222.38716)
		(end 340.093808 -222.055182)
		(width 0.254)
		(layer "B.Cu")
		(net "GND")
	)
	(segment
		(start 135.205216 -202.178412)
		(end 134.94004 -201.913236)
		(width 0.4572)
		(layer "B.Cu")
		(net "GND")
	)
	(segment
		(start 422.674796 -302.074834)
		(end 422.326816 -301.726854)
		(width 0.381)
		(layer "B.Cu")
		(net "GND")
	)
	(segment
		(start 247.499632 -227.965)
		(end 248.463054 -227.965)
		(width 0.4572)
		(layer "B.Cu")
		(net "GND")
	)
	(segment
		(start 56.611012 -154.374596)
		(end 56.552084 -154.315668)
		(width 0.4572)
		(layer "B.Cu")
		(net "GND")
	)
	(segment
		(start 344.411046 -219.98686)
		(end 344.493342 -219.98686)
		(width 0.254)
		(layer "B.Cu")
		(net "GND")
	)
	(segment
		(start 305.255676 -249.755406)
		(end 305.255676 -250.263406)
		(width 0.4572)
		(layer "B.Cu")
		(net "GND")
	)
	(segment
		(start 74.374756 -298.27474)
		(end 74.026776 -298.62272)
		(width 0.4572)
		(layer "B.Cu")
		(net "GND")
	)
	(segment
		(start 77.941932 -99.037648)
		(end 78.551532 -99.037648)
		(width 0.4572)
		(layer "B.Cu")
		(net "GND")
	)
	(segment
		(start 209.746596 -227.470462)
		(end 210.055968 -227.470462)
		(width 0.3048)
		(layer "B.Cu")
		(net "GND")
	)
	(segment
		(start 118.190264 -317.706756)
		(end 117.67058 -317.706756)
		(width 0.254)
		(layer "B.Cu")
		(net "GND")
	)
	(segment
		(start 117.672104 -318.542416)
		(end 117.656864 -318.557656)
		(width 0.254)
		(layer "B.Cu")
		(net "GND")
	)
	(segment
		(start 254.312166 -230.550212)
		(end 254.61722 -230.550212)
		(width 0.254)
		(layer "B.Cu")
		(net "GND")
	)
	(segment
		(start 397.45539 -150.9776)
		(end 396.84579 -150.9776)
		(width 0.4572)
		(layer "B.Cu")
		(net "GND")
	)
	(segment
		(start 349.135954 -261.154672)
		(end 349.656654 -261.675372)
		(width 0.4572)
		(layer "B.Cu")
		(net "GND")
	)
	(segment
		(start 126.986538 -215.09482)
		(end 127.950214 -215.09482)
		(width 0.3556)
		(layer "B.Cu")
		(net "GND")
	)
	(segment
		(start 410.324808 -297.53306)
		(end 410.324808 -297.32478)
		(width 0.3048)
		(layer "B.Cu")
		(net "GND")
	)
	(segment
		(start 49.15535 -153.0096)
		(end 48.54575 -153.0096)
		(width 0.4572)
		(layer "B.Cu")
		(net "GND")
	)
	(segment
		(start 58.240168 -298.06646)
		(end 58.240168 -298.2595)
		(width 0.3048)
		(layer "B.Cu")
		(net "GND")
	)
	(segment
		(start 207.291178 -239.4839)
		(end 204.487018 -239.4839)
		(width 0.3556)
		(layer "B.Cu")
		(net "GND")
	)
	(segment
		(start 291.06114 -205.776068)
		(end 291.06114 -206.138018)
		(width 0.4572)
		(layer "B.Cu")
		(net "GND")
	)
	(segment
		(start 231.93248 -218.986608)
		(end 232.355644 -218.986608)
		(width 0.3048)
		(layer "B.Cu")
		(net "GND")
	)
	(segment
		(start 404.625048 -293.73322)
		(end 404.625048 -293.525194)
		(width 0.3048)
		(layer "B.Cu")
		(net "GND")
	)
	(segment
		(start 350.09963 -214.381334)
		(end 350.493584 -213.98738)
		(width 0.254)
		(layer "B.Cu")
		(net "GND")
	)
	(segment
		(start 298.976542 -293.526718)
		(end 298.974764 -293.52494)
		(width 0.3048)
		(layer "B.Cu")
		(net "GND")
	)
	(segment
		(start 261.6962 -223.8756)
		(end 261.857998 -223.8756)
		(width 0.4572)
		(layer "B.Cu")
		(net "GND")
	)
	(segment
		(start 55.945786 -309.2958)
		(end 55.849774 -309.199788)
		(width 0.4572)
		(layer "B.Cu")
		(net "GND")
	)
	(segment
		(start 384.683 -222.590106)
		(end 385.842002 -222.590106)
		(width 0.381)
		(layer "B.Cu")
		(net "GND")
	)
	(segment
		(start 281.666442 -290.674806)
		(end 281.874722 -290.674806)
		(width 0.3048)
		(layer "B.Cu")
		(net "GND")
	)
	(segment
		(start 185.5343 -295.3512)
		(end 185.5343 -294.492426)
		(width 0.3048)
		(layer "B.Cu")
		(net "GND")
	)
	(segment
		(start 57.918096 -154.374596)
		(end 56.611012 -154.374596)
		(width 0.4572)
		(layer "B.Cu")
		(net "GND")
	)
	(segment
		(start 386.842 -241.554)
		(end 387.223 -241.173)
		(width 0.3048)
		(layer "B.Cu")
		(net "GND")
	)
	(segment
		(start 138.618214 -203.637896)
		(end 138.618214 -204.253846)
		(width 0.4572)
		(layer "B.Cu")
		(net "GND")
	)
	(segment
		(start 298.976542 -293.73322)
		(end 298.976542 -293.526718)
		(width 0.3048)
		(layer "B.Cu")
		(net "GND")
	)
	(segment
		(start 289.47491 -294.26662)
		(end 289.47491 -294.4749)
		(width 0.3048)
		(layer "B.Cu")
		(net "GND")
	)
	(segment
		(start 183.8452 -114.713512)
		(end 183.766714 -114.635026)
		(width 0.4572)
		(layer "B.Cu")
		(net "GND")
	)
	(segment
		(start 210.045046 -219.202)
		(end 209.84591 -219.202)
		(width 0.3048)
		(layer "B.Cu")
		(net "GND")
	)
	(segment
		(start 210.309714 -218.349068)
		(end 210.309714 -218.937332)
		(width 0.3048)
		(layer "B.Cu")
		(net "GND")
	)
	(segment
		(start 397.97482 -294.26662)
		(end 397.97482 -294.4749)
		(width 0.3048)
		(layer "B.Cu")
		(net "GND")
	)
	(segment
		(start 292.971982 -195.8594)
		(end 292.971982 -196.149722)
		(width 0.4572)
		(layer "B.Cu")
		(net "GND")
	)
	(segment
		(start 188.254894 -97.663)
		(end 188.254894 -96.901)
		(width 0.4572)
		(layer "B.Cu")
		(net "GND")
	)
	(segment
		(start 288.52495 -298.274486)
		(end 288.524696 -298.27474)
		(width 0.3048)
		(layer "B.Cu")
		(net "GND")
	)
	(segment
		(start 74.026776 -301.726854)
		(end 74.026776 -301.524924)
		(width 0.381)
		(layer "B.Cu")
		(net "GND")
	)
	(segment
		(start 58.224928 -293.73322)
		(end 58.224928 -293.52494)
		(width 0.3048)
		(layer "B.Cu")
		(net "GND")
	)
	(segment
		(start 165.566598 -292.574726)
		(end 165.774878 -292.574726)
		(width 0.3048)
		(layer "B.Cu")
		(net "GND")
	)
	(segment
		(start 301.903892 -98.552)
		(end 301.903892 -99.187)
		(width 0.4572)
		(layer "B.Cu")
		(net "GND")
	)
	(segment
		(start 358.92232 -261.814564)
		(end 360.86796 -261.814564)
		(width 0.4572)
		(layer "B.Cu")
		(net "GND")
	)
	(segment
		(start 114.865404 -258.404614)
		(end 115.24234 -258.78155)
		(width 0.381)
		(layer "B.Cu")
		(net "GND")
	)
	(segment
		(start 261.857998 -223.8756)
		(end 262.304276 -224.321878)
		(width 0.4572)
		(layer "B.Cu")
		(net "GND")
	)
	(segment
		(start 405.575008 -294.640508)
		(end 404.993602 -295.221914)
		(width 0.3048)
		(layer "B.Cu")
		(net "GND")
	)
	(segment
		(start 51.044094 -138.421618)
		(end 51.089814 -138.421618)
		(width 0.4572)
		(layer "B.Cu")
		(net "GND")
	)
	(segment
		(start 424.120818 -113.95202)
		(end 424.120818 -113.260632)
		(width 0.4572)
		(layer "B.Cu")
		(net "GND")
	)
	(segment
		(start 185.516774 -300.174914)
		(end 185.725054 -300.174914)
		(width 0.3048)
		(layer "B.Cu")
		(net "GND")
	)
	(segment
		(start 342.893904 -213.587076)
		(end 343.2937 -213.18728)
		(width 0.254)
		(layer "B.Cu")
		(net "GND")
	)
	(segment
		(start 350.39046 -317.706756)
		(end 350.376744 -317.69304)
		(width 0.254)
		(layer "B.Cu")
		(net "GND")
	)
	(segment
		(start 386.842 -242.205002)
		(end 386.842 -241.554)
		(width 0.3048)
		(layer "B.Cu")
		(net "GND")
	)
	(segment
		(start 52.524914 -298.06646)
		(end 52.524914 -298.27474)
		(width 0.3048)
		(layer "B.Cu")
		(net "GND")
	)
	(segment
		(start 141.793214 -209.857848)
		(end 141.793214 -209.206846)
		(width 0.3048)
		(layer "B.Cu")
		(net "GND")
	)
	(segment
		(start 216.847674 -216.388696)
		(end 216.835736 -216.400634)
		(width 0.3048)
		(layer "B.Cu")
		(net "GND")
	)
	(segment
		(start 409.743656 -295.221914)
		(end 410.324808 -294.640762)
		(width 0.3048)
		(layer "B.Cu")
		(net "GND")
	)
	(segment
		(start 286.624776 -298.06646)
		(end 286.624776 -298.27474)
		(width 0.3048)
		(layer "B.Cu")
		(net "GND")
	)
	(segment
		(start 340.093808 -217.247216)
		(end 340.43366 -217.587068)
		(width 0.254)
		(layer "B.Cu")
		(net "GND")
	)
	(segment
		(start 49.15535 -150.9776)
		(end 48.54575 -150.9776)
		(width 0.4572)
		(layer "B.Cu")
		(net "GND")
	)
	(segment
		(start 168.625012 -298.06646)
		(end 168.625012 -298.27474)
		(width 0.3048)
		(layer "B.Cu")
		(net "GND")
	)
	(segment
		(start 412.075376 -110.497366)
		(end 412.754572 -110.497366)
		(width 0.4572)
		(layer "B.Cu")
		(net "GND")
	)
	(segment
		(start 176.224946 -294.26662)
		(end 176.224946 -294.4749)
		(width 0.3048)
		(layer "B.Cu")
		(net "GND")
	)
	(segment
		(start 279.974802 -295.1099)
		(end 279.974802 -294.4749)
		(width 0.3048)
		(layer "B.Cu")
		(net "GND")
	)
	(segment
		(start 66.774822 -298.06646)
		(end 66.774822 -298.27474)
		(width 0.3048)
		(layer "B.Cu")
		(net "GND")
	)
	(segment
		(start 306.226718 -301.726854)
		(end 306.226718 -301.524924)
		(width 0.381)
		(layer "B.Cu")
		(net "GND")
	)
	(segment
		(start 299.183044 -296.37482)
		(end 298.974764 -296.37482)
		(width 0.3048)
		(layer "B.Cu")
		(net "GND")
	)
	(segment
		(start 397.97482 -297.53306)
		(end 397.97482 -297.32478)
		(width 0.3048)
		(layer "B.Cu")
		(net "GND")
	)
	(segment
		(start 282.824936 -293.73322)
		(end 282.824936 -293.52494)
		(width 0.3048)
		(layer "B.Cu")
		(net "GND")
	)
	(segment
		(start 253.24308 -85.586316)
		(end 252.98908 -85.840316)
		(width 0.4572)
		(layer "B.Cu")
		(net "GND")
	)
	(segment
		(start 190.126874 -298.62272)
		(end 190.126874 -298.82465)
		(width 0.4572)
		(layer "B.Cu")
		(net "GND")
	)
	(segment
		(start 132.379212 -206.756254)
		(end 132.383022 -206.756254)
		(width 0.4572)
		(layer "B.Cu")
		(net "GND")
	)
	(segment
		(start 51.089814 -138.421618)
		(end 51.63312 -138.964924)
		(width 0.4572)
		(layer "B.Cu")
		(net "GND")
	)
	(segment
		(start 379.319282 -224.692718)
		(end 379.476 -224.536)
		(width 0.4572)
		(layer "B.Cu")
		(net "GND")
	)
	(segment
		(start 416.158934 -117.415056)
		(end 415.922206 -117.415056)
		(width 0.4572)
		(layer "B.Cu")
		(net "GND")
	)
	(segment
		(start 254.61722 -230.550212)
		(end 254.74422 -230.423212)
		(width 0.254)
		(layer "B.Cu")
		(net "GND")
	)
	(segment
		(start 236.632496 -211.074)
		(end 236.728 -211.074)
		(width 0.4572)
		(layer "B.Cu")
		(net "GND")
	)
	(segment
		(start 111.353092 -332.70571)
		(end 111.60633 -332.70571)
		(width 0.4572)
		(layer "B.Cu")
		(net "GND")
	)
	(segment
		(start 278.283162 -290.466526)
		(end 278.074882 -290.674806)
		(width 0.3048)
		(layer "B.Cu")
		(net "GND")
	)
	(segment
		(start 117.054884 -317.6778)
		(end 117.641624 -317.6778)
		(width 0.254)
		(layer "B.Cu")
		(net "GND")
	)
	(segment
		(start 279.974802 -296.90822)
		(end 279.974802 -297.32478)
		(width 0.3048)
		(layer "B.Cu")
		(net "GND")
	)
	(segment
		(start 49.15535 -154.0256)
		(end 48.54575 -154.0256)
		(width 0.4572)
		(layer "B.Cu")
		(net "GND")
	)
	(segment
		(start 339.293962 -222.84944)
		(end 339.293962 -222.786956)
		(width 0.254)
		(layer "B.Cu")
		(net "GND")
	)
	(segment
		(start 235.871512 -235.128054)
		(end 235.871512 -235.737654)
		(width 0.4572)
		(layer "B.Cu")
		(net "GND")
	)
	(segment
		(start 60.124848 -294.26662)
		(end 60.124848 -294.4749)
		(width 0.3048)
		(layer "B.Cu")
		(net "GND")
	)
	(segment
		(start 386.316982 -232.458514)
		(end 386.316982 -232.253028)
		(width 0.4572)
		(layer "B.Cu")
		(net "GND")
	)
	(segment
		(start 290.44011 -298.2595)
		(end 290.42487 -298.27474)
		(width 0.3048)
		(layer "B.Cu")
		(net "GND")
	)
	(segment
		(start 211.476082 -252.315726)
		(end 209.965036 -253.826772)
		(width 0.3048)
		(layer "B.Cu")
		(net "GND")
	)
	(segment
		(start 209.587084 -246.271542)
		(end 210.419442 -245.439184)
		(width 0.4572)
		(layer "B.Cu")
		(net "GND")
	)
	(segment
		(start 178.124866 -294.4749)
		(end 178.124866 -294.640762)
		(width 0.3048)
		(layer "B.Cu")
		(net "GND")
	)
	(segment
		(start 332.862428 -227.73132)
		(end 332.862428 -227.957634)
		(width 0.3048)
		(layer "B.Cu")
		(net "GND")
	)
	(segment
		(start 59.00039 -159.595312)
		(end 58.611516 -159.984186)
		(width 0.4572)
		(layer "B.Cu")
		(net "GND")
	)
	(segment
		(start 302.566578 -290.674806)
		(end 302.774858 -290.674806)
		(width 0.3048)
		(layer "B.Cu")
		(net "GND")
	)
	(segment
		(start 147.061428 -224.75063)
		(end 146.204432 -224.75063)
		(width 0.4572)
		(layer "B.Cu")
		(net "GND")
	)
	(segment
		(start 207.860138 -238.91494)
		(end 207.291178 -239.4839)
		(width 0.3556)
		(layer "B.Cu")
		(net "GND")
	)
	(segment
		(start 147.276058 -224.536)
		(end 147.061428 -224.75063)
		(width 0.4572)
		(layer "B.Cu")
		(net "GND")
	)
	(segment
		(start 283.078936 -296.37482)
		(end 282.824936 -296.37482)
		(width 0.3048)
		(layer "B.Cu")
		(net "GND")
	)
	(segment
		(start 343.693242 -221.58706)
		(end 343.63025 -221.58706)
		(width 0.254)
		(layer "B.Cu")
		(net "GND")
	)
	(segment
		(start 101.823266 -356.461822)
		(end 101.734874 -356.550214)
		(width 0.4572)
		(layer "B.Cu")
		(net "GND")
	)
	(segment
		(start 339.693758 -222.38716)
		(end 339.76183 -222.38716)
		(width 0.254)
		(layer "B.Cu")
		(net "GND")
	)
	(segment
		(start 396.0749 -294.4749)
		(end 396.0749 -294.3987)
		(width 0.3048)
		(layer "B.Cu")
		(net "GND")
	)
	(segment
		(start 340.43366 -217.587068)
		(end 340.494112 -217.587068)
		(width 0.254)
		(layer "B.Cu")
		(net "GND")
	)
	(segment
		(start 229.434644 -231.625648)
		(end 229.434644 -232.103422)
		(width 0.4572)
		(layer "B.Cu")
		(net "GND")
	)
	(segment
		(start 255.252982 -79.89189)
		(end 255.725168 -80.364076)
		(width 0.4572)
		(layer "B.Cu")
		(net "GND")
	)
	(segment
		(start 417.716716 -297.32478)
		(end 417.924996 -297.32478)
		(width 0.3048)
		(layer "B.Cu")
		(net "GND")
	)
	(segment
		(start 170.753532 -296.37482)
		(end 170.524932 -296.37482)
		(width 0.3048)
		(layer "B.Cu")
		(net "GND")
	)
	(segment
		(start 230.9622 -257.718306)
		(end 230.9622 -257.373374)
		(width 0.254)
		(layer "B.Cu")
		(net "GND")
	)
	(segment
		(start 300.69917 -114.713512)
		(end 299.945298 -114.713512)
		(width 0.4572)
		(layer "B.Cu")
		(net "GND")
	)
	(segment
		(start 58.611516 -159.984186)
		(end 58.611516 -160.81375)
		(width 0.4572)
		(layer "B.Cu")
		(net "GND")
	)
	(segment
		(start 415.074862 -298.06646)
		(end 415.074862 -298.27474)
		(width 0.3048)
		(layer "B.Cu")
		(net "GND")
	)
	(segment
		(start 298.850558 -225.780346)
		(end 298.850558 -225.037396)
		(width 0.4572)
		(layer "B.Cu")
		(net "GND")
	)
	(segment
		(start 194.041776 -98.021648)
		(end 194.651376 -98.021648)
		(width 0.4572)
		(layer "B.Cu")
		(net "GND")
	)
	(segment
		(start 53.678074 -158.343092)
		(end 54.9021 -158.343092)
		(width 0.4572)
		(layer "B.Cu")
		(net "GND")
	)
	(segment
		(start 300.666404 -298.27474)
		(end 300.874684 -298.27474)
		(width 0.3048)
		(layer "B.Cu")
		(net "GND")
	)
	(segment
		(start 278.283162 -290.215066)
		(end 278.283162 -290.466526)
		(width 0.3048)
		(layer "B.Cu")
		(net "GND")
	)
	(segment
		(start 374.41505 -234.569)
		(end 374.41505 -233.82605)
		(width 0.4572)
		(layer "B.Cu")
		(net "GND")
	)
	(segment
		(start 53.96484 -141.6812)
		(end 53.96484 -142.367)
		(width 0.4572)
		(layer "B.Cu")
		(net "GND")
	)
	(segment
		(start 132.741416 -208.516474)
		(end 132.47751 -208.516474)
		(width 0.4572)
		(layer "B.Cu")
		(net "GND")
	)
	(segment
		(start 285.674816 -297.53306)
		(end 285.674816 -297.32478)
		(width 0.3048)
		(layer "B.Cu")
		(net "GND")
	)
	(segment
		(start 238.106712 -52.107592)
		(end 240.38179 -52.107592)
		(width 0.4572)
		(layer "B.Cu")
		(net "GND")
	)
	(segment
		(start 30.141672 -224.75063)
		(end 30.998668 -224.75063)
		(width 0.4572)
		(layer "B.Cu")
		(net "GND")
	)
	(segment
		(start 177.82032 -195.874386)
		(end 178.479958 -195.874386)
		(width 0.4572)
		(layer "B.Cu")
		(net "GND")
	)
	(segment
		(start 272.975832 -80.506316)
		(end 273.710908 -79.77124)
		(width 0.4572)
		(layer "B.Cu")
		(net "GND")
	)
	(segment
		(start 288.90595 -309.3212)
		(end 288.171128 -309.3212)
		(width 0.4572)
		(layer "B.Cu")
		(net "GND")
	)
	(segment
		(start 378.079 -239.7506)
		(end 377.2154 -239.7506)
		(width 0.4572)
		(layer "B.Cu")
		(net "GND")
	)
	(segment
		(start 254.89408 -88.634316)
		(end 254.10668 -88.634316)
		(width 0.4572)
		(layer "B.Cu")
		(net "GND")
	)
	(segment
		(start 233.839512 -235.128054)
		(end 233.839512 -235.737654)
		(width 0.4572)
		(layer "B.Cu")
		(net "GND")
	)
	(segment
		(start 222.482664 -205.47711)
		(end 222.482664 -206.62011)
		(width 0.4572)
		(layer "B.Cu")
		(net "GND")
	)
	(segment
		(start 417.716716 -296.37482)
		(end 417.924996 -296.37482)
		(width 0.3048)
		(layer "B.Cu")
		(net "GND")
	)
	(segment
		(start 332.485238 -324.03415)
		(end 332.302104 -324.217284)
		(width 0.254)
		(layer "B.Cu")
		(net "GND")
	)
	(segment
		(start 401.193508 -295.221914)
		(end 401.774914 -294.640508)
		(width 0.3048)
		(layer "B.Cu")
		(net "GND")
	)
	(segment
		(start 49.15535 -151.9936)
		(end 48.54575 -151.9936)
		(width 0.4572)
		(layer "B.Cu")
		(net "GND")
	)
	(segment
		(start 15.230348 -227.965)
		(end 16.30045 -227.965)
		(width 0.4572)
		(layer "B.Cu")
		(net "GND")
	)
	(segment
		(start 344.893646 -220.38691)
		(end 344.893646 -220.327728)
		(width 0.254)
		(layer "B.Cu")
		(net "GND")
	)
	(segment
		(start 292.32479 -297.53306)
		(end 292.32479 -297.32478)
		(width 0.3048)
		(layer "B.Cu")
		(net "GND")
	)
	(segment
		(start 168.853612 -296.37482)
		(end 168.625012 -296.37482)
		(width 0.3048)
		(layer "B.Cu")
		(net "GND")
	)
	(segment
		(start 396.0749 -297.74134)
		(end 396.0749 -297.32478)
		(width 0.3048)
		(layer "B.Cu")
		(net "GND")
	)
	(segment
		(start 180.02504 -294.26662)
		(end 180.02504 -294.4749)
		(width 0.3048)
		(layer "B.Cu")
		(net "GND")
	)
	(segment
		(start 416.045396 -114.713512)
		(end 415.96691 -114.635026)
		(width 0.4572)
		(layer "B.Cu")
		(net "GND")
	)
	(segment
		(start 118.190264 -318.542416)
		(end 117.672104 -318.542416)
		(width 0.254)
		(layer "B.Cu")
		(net "GND")
	)
	(segment
		(start 348.750128 -327.670922)
		(end 347.40215 -327.670922)
		(width 0.4572)
		(layer "B.Cu")
		(net "GND")
	)
	(segment
		(start 301.616618 -300.174914)
		(end 301.824898 -300.174914)
		(width 0.3048)
		(layer "B.Cu")
		(net "GND")
	)
	(segment
		(start 137.689336 -173.090586)
		(end 136.934194 -173.090586)
		(width 0.4572)
		(layer "B.Cu")
		(net "GND")
	)
	(segment
		(start 64.874902 -298.06646)
		(end 64.874902 -298.27474)
		(width 0.3048)
		(layer "B.Cu")
		(net "GND")
	)
	(segment
		(start 108.846112 -335.453736)
		(end 109.274102 -335.881726)
		(width 0.508)
		(layer "B.Cu")
		(net "GND")
	)
	(segment
		(start 144.841214 -204.780896)
		(end 144.098264 -204.780896)
		(width 0.4572)
		(layer "B.Cu")
		(net "GND")
	)
	(segment
		(start 135.235442 -201.252074)
		(end 135.001254 -201.252074)
		(width 0.4572)
		(layer "B.Cu")
		(net "GND")
	)
	(segment
		(start 372.035324 -247.441974)
		(end 372.999 -247.441974)
		(width 0.3556)
		(layer "B.Cu")
		(net "GND")
	)
	(segment
		(start 216.835482 -217.286332)
		(end 216.835736 -217.286586)
		(width 0.3048)
		(layer "B.Cu")
		(net "GND")
	)
	(segment
		(start 339.755988 -218.387168)
		(end 339.694012 -218.387168)
		(width 0.254)
		(layer "B.Cu")
		(net "GND")
	)
	(segment
		(start 338.893912 -223.18726)
		(end 338.956142 -223.18726)
		(width 0.254)
		(layer "B.Cu")
		(net "GND")
	)
	(segment
		(start 200.058274 -259.711698)
		(end 201.088244 -259.711698)
		(width 0.4572)
		(layer "B.Cu")
		(net "GND")
	)
	(segment
		(start 351.245932 -142.494)
		(end 351.245932 -142.006828)
		(width 0.4572)
		(layer "B.Cu")
		(net "GND")
	)
	(segment
		(start 168.625012 -293.73322)
		(end 168.625012 -293.52494)
		(width 0.3048)
		(layer "B.Cu")
		(net "GND")
	)
	(segment
		(start 228.773482 -226.078034)
		(end 228.800152 -226.051364)
		(width 0.4572)
		(layer "B.Cu")
		(net "GND")
	)
	(segment
		(start 228.821996 -141.316202)
		(end 228.525578 -141.316202)
		(width 0.4572)
		(layer "B.Cu")
		(net "GND")
	)
	(segment
		(start 369.521486 -236.689392)
		(end 368.55527 -236.689392)
		(width 0.4572)
		(layer "B.Cu")
		(net "GND")
	)
	(segment
		(start 416.766502 -298.27474)
		(end 416.974782 -298.27474)
		(width 0.3048)
		(layer "B.Cu")
		(net "GND")
	)
	(segment
		(start 173.375066 -294.640508)
		(end 172.79366 -295.221914)
		(width 0.3048)
		(layer "B.Cu")
		(net "GND")
	)
	(segment
		(start 339.693758 -223.187006)
		(end 339.693758 -223.186752)
		(width 0.254)
		(layer "B.Cu")
		(net "GND")
	)
	(segment
		(start 63.783464 -108.462318)
		(end 64.77 -108.462318)
		(width 0.4572)
		(layer "B.Cu")
		(net "GND")
	)
	(segment
		(start 397.71574 -301.0154)
		(end 397.865346 -301.0154)
		(width 0.3048)
		(layer "B.Cu")
		(net "GND")
	)
	(segment
		(start 406.524968 -293.73322)
		(end 406.524968 -293.52494)
		(width 0.3048)
		(layer "B.Cu")
		(net "GND")
	)
	(segment
		(start 289.47491 -294.4749)
		(end 289.47491 -294.640508)
		(width 0.3048)
		(layer "B.Cu")
		(net "GND")
	)
	(segment
		(start 380.746 -241.28095)
		(end 380.032514 -241.28095)
		(width 0.381)
		(layer "B.Cu")
		(net "GND")
	)
	(segment
		(start 254.140716 -229.827582)
		(end 254.140716 -230.378762)
		(width 0.254)
		(layer "B.Cu")
		(net "GND")
	)
	(segment
		(start 409.374848 -296.37482)
		(end 409.03652 -296.37482)
		(width 0.3048)
		(layer "B.Cu")
		(net "GND")
	)
	(segment
		(start 350.39046 -318.542416)
		(end 349.8723 -318.542416)
		(width 0.254)
		(layer "B.Cu")
		(net "GND")
	)
	(segment
		(start 56.693562 -295.221914)
		(end 57.274968 -294.640508)
		(width 0.3048)
		(layer "B.Cu")
		(net "GND")
	)
	(segment
		(start 165.255194 -154.0256)
		(end 164.645594 -154.0256)
		(width 0.4572)
		(layer "B.Cu")
		(net "GND")
	)
	(segment
		(start 281.355292 -151.9936)
		(end 280.745692 -151.9936)
		(width 0.4572)
		(layer "B.Cu")
		(net "GND")
	)
	(segment
		(start 49.4665 -292.574726)
		(end 49.67478 -292.574726)
		(width 0.3048)
		(layer "B.Cu")
		(net "GND")
	)
	(segment
		(start 117.67058 -317.706756)
		(end 117.656864 -317.69304)
		(width 0.254)
		(layer "B.Cu")
		(net "GND")
	)
	(segment
		(start 46.0883 -293.52494)
		(end 45.87494 -293.52494)
		(width 0.3048)
		(layer "B.Cu")
		(net "GND")
	)
	(segment
		(start 401.774914 -294.640508)
		(end 401.774914 -294.4749)
		(width 0.3048)
		(layer "B.Cu")
		(net "GND")
	)
	(segment
		(start 209.67446 -226.071938)
		(end 210.774026 -226.071938)
		(width 0.3048)
		(layer "B.Cu")
		(net "GND")
	)
	(segment
		(start 344.093546 -220.38691)
		(end 344.093546 -220.30436)
		(width 0.254)
		(layer "B.Cu")
		(net "GND")
	)
	(segment
		(start 224.76841 -176.303178)
		(end 224.765362 -176.306226)
		(width 0.2794)
		(layer "B.Cu")
		(net "GND")
	)
	(segment
		(start 109.85119 -335.881726)
		(end 109.85119 -336.749136)
		(width 0.508)
		(layer "B.Cu")
		(net "GND")
	)
	(segment
		(start 56.712866 -309.2958)
		(end 55.945786 -309.2958)
		(width 0.4572)
		(layer "B.Cu")
		(net "GND")
	)
	(segment
		(start 101.527864 -329.594718)
		(end 101.527864 -328.980292)
		(width 0.4572)
		(layer "B.Cu")
		(net "GND")
	)
	(segment
		(start 118.190264 -316.868048)
		(end 118.190264 -316.003686)
		(width 0.254)
		(layer "B.Cu")
		(net "GND")
	)
	(segment
		(start 124.4727 -204.342238)
		(end 123.506484 -204.342238)
		(width 0.4572)
		(layer "B.Cu")
		(net "GND")
	)
	(segment
		(start 281.355292 -153.0096)
		(end 280.745692 -153.0096)
		(width 0.4572)
		(layer "B.Cu")
		(net "GND")
	)
	(segment
		(start 173.375066 -294.26662)
		(end 173.375066 -294.4749)
		(width 0.3048)
		(layer "B.Cu")
		(net "GND")
	)
	(segment
		(start 56.325008 -293.73322)
		(end 56.325008 -293.525194)
		(width 0.3048)
		(layer "B.Cu")
		(net "GND")
	)
	(segment
		(start 298.119038 -201.76109)
		(end 298.119038 -201.145394)
		(width 0.4572)
		(layer "B.Cu")
		(net "GND")
	)
	(segment
		(start 330.932282 -218.208352)
		(end 330.251816 -218.208352)
		(width 0.3048)
		(layer "B.Cu")
		(net "GND")
	)
	(segment
		(start 334.408272 -213.98738)
		(end 334.494124 -213.98738)
		(width 0.254)
		(layer "B.Cu")
		(net "GND")
	)
	(segment
		(start 129.486914 -183.004714)
		(end 129.486914 -183.395874)
		(width 0.4572)
		(layer "B.Cu")
		(net "GND")
	)
	(segment
		(start 60.312046 -156.480002)
		(end 61.459618 -156.480002)
		(width 0.4572)
		(layer "B.Cu")
		(net "GND")
	)
	(segment
		(start 294.22471 -294.26662)
		(end 294.22471 -294.4749)
		(width 0.3048)
		(layer "B.Cu")
		(net "GND")
	)
	(segment
		(start 49.4665 -290.674806)
		(end 49.67478 -290.674806)
		(width 0.3048)
		(layer "B.Cu")
		(net "GND")
	)
	(segment
		(start 399.874994 -297.53306)
		(end 399.874994 -297.32478)
		(width 0.3048)
		(layer "B.Cu")
		(net "GND")
	)
	(segment
		(start 228.800152 -225.72853)
		(end 228.745034 -225.673412)
		(width 0.4572)
		(layer "B.Cu")
		(net "GND")
	)
	(segment
		(start 241.060732 -234.451144)
		(end 241.07902 -234.469432)
		(width 0.4572)
		(layer "B.Cu")
		(net "GND")
	)
	(segment
		(start 240.38179 -52.107592)
		(end 241.158522 -52.884324)
		(width 0.4572)
		(layer "B.Cu")
		(net "GND")
	)
	(segment
		(start 21.978112 -228.73843)
		(end 22.314662 -228.40188)
		(width 0.254)
		(layer "B.Cu")
		(net "GND")
	)
	(segment
		(start 207.860138 -238.66094)
		(end 207.860138 -238.91494)
		(width 0.3556)
		(layer "B.Cu")
		(net "GND")
	)
	(segment
		(start 63.775336 -109.481366)
		(end 64.691768 -109.481366)
		(width 0.4572)
		(layer "B.Cu")
		(net "GND")
	)
	(segment
		(start 339.753702 -216.786968)
		(end 340.093808 -217.127074)
		(width 0.254)
		(layer "B.Cu")
		(net "GND")
	)
	(segment
		(start 129.486914 -183.395874)
		(end 129.092198 -183.79059)
		(width 0.4572)
		(layer "B.Cu")
		(net "GND")
	)
	(segment
		(start 280.924762 -298.06646)
		(end 280.924762 -298.27474)
		(width 0.3048)
		(layer "B.Cu")
		(net "GND")
	)
	(segment
		(start 56.325008 -298.06646)
		(end 56.325008 -298.274486)
		(width 0.3048)
		(layer "B.Cu")
		(net "GND")
	)
	(segment
		(start 397.76654 -292.574726)
		(end 397.97482 -292.574726)
		(width 0.3048)
		(layer "B.Cu")
		(net "GND")
	)
	(segment
		(start 170.524932 -293.73322)
		(end 170.524932 -293.52494)
		(width 0.3048)
		(layer "B.Cu")
		(net "GND")
	)
	(segment
		(start 389.89 -242.58905)
		(end 389.404606 -243.074444)
		(width 0.4572)
		(layer "B.Cu")
		(net "GND")
	)
	(segment
		(start 364.453932 -223.537018)
		(end 365.176562 -223.537018)
		(width 0.4572)
		(layer "B.Cu")
		(net "GND")
	)
	(segment
		(start 167.143938 -138.421618)
		(end 167.189658 -138.421618)
		(width 0.4572)
		(layer "B.Cu")
		(net "GND")
	)
	(segment
		(start 231.918764 -218.972892)
		(end 231.93248 -218.986608)
		(width 0.3048)
		(layer "B.Cu")
		(net "GND")
	)
	(segment
		(start 343.2937 -217.187272)
		(end 343.2937 -217.247724)
		(width 0.254)
		(layer "B.Cu")
		(net "GND")
	)
	(segment
		(start 107.573318 -349.504508)
		(end 107.573318 -349.37192)
		(width 0.3048)
		(layer "B.Cu")
		(net "GND")
	)
	(segment
		(start 132.25399 -223.537018)
		(end 132.911088 -223.537018)
		(width 0.4572)
		(layer "B.Cu")
		(net "GND")
	)
	(segment
		(start 348.425262 -220.787214)
		(end 348.093538 -220.45549)
		(width 0.254)
		(layer "B.Cu")
		(net "GND")
	)
	(segment
		(start 165.033198 -291.624766)
		(end 164.824918 -291.624766)
		(width 0.3048)
		(layer "B.Cu")
		(net "GND")
	)
	(segment
		(start 138.040872 -229.827582)
		(end 138.040872 -228.73843)
		(width 0.254)
		(layer "B.Cu")
		(net "GND")
	)
	(segment
		(start 194.041776 -104.120696)
		(end 194.651376 -104.120696)
		(width 0.4572)
		(layer "B.Cu")
		(net "GND")
	)
	(segment
		(start 330.905104 -216.203022)
		(end 330.224638 -216.203022)
		(width 0.3048)
		(layer "B.Cu")
		(net "GND")
	)
	(segment
		(start 339.693758 -223.186752)
		(end 339.293962 -222.786956)
		(width 0.254)
		(layer "B.Cu")
		(net "GND")
	)
	(segment
		(start 386.089652 -234.62996)
		(end 386.842 -234.62996)
		(width 0.4572)
		(layer "B.Cu")
		(net "GND")
	)
	(segment
		(start 303.559972 -237.819184)
		(end 303.559972 -237.136686)
		(width 0.4572)
		(layer "B.Cu")
		(net "GND")
	)
	(segment
		(start 349.25508 -317.6778)
		(end 349.27032 -317.69304)
		(width 0.254)
		(layer "B.Cu")
		(net "GND")
	)
	(segment
		(start 379.349 -239.54105)
		(end 380.09195 -239.54105)
		(width 0.4572)
		(layer "B.Cu")
		(net "GND")
	)
	(segment
		(start 281.874722 -294.26662)
		(end 281.874722 -294.4749)
		(width 0.3048)
		(layer "B.Cu")
		(net "GND")
	)
	(segment
		(start 347.0656 -258.404614)
		(end 347.442536 -258.78155)
		(width 0.381)
		(layer "B.Cu")
		(net "GND")
	)
	(segment
		(start 397.02486 -293.73322)
		(end 397.02486 -293.52494)
		(width 0.3048)
		(layer "B.Cu")
		(net "GND")
	)
	(segment
		(start 411.275022 -298.06646)
		(end 411.275022 -298.27474)
		(width 0.3048)
		(layer "B.Cu")
		(net "GND")
	)
	(segment
		(start 189.999874 -302.549814)
		(end 190.126874 -302.422814)
		(width 0.381)
		(layer "B.Cu")
		(net "GND")
	)
	(segment
		(start 233.760518 -219.10421)
		(end 233.867706 -219.10421)
		(width 0.3048)
		(layer "B.Cu")
		(net "GND")
	)
	(segment
		(start 227.317046 -140.706602)
		(end 227.063046 -140.452602)
		(width 0.4572)
		(layer "B.Cu")
		(net "GND")
	)
	(segment
		(start 382.495552 -243.39296)
		(end 382.495552 -244.53596)
		(width 0.4572)
		(layer "B.Cu")
		(net "GND")
	)
	(segment
		(start 342.09355 -221.58706)
		(end 342.02878 -221.58706)
		(width 0.254)
		(layer "B.Cu")
		(net "GND")
	)
	(segment
		(start 299.005244 -237.664244)
		(end 299.212 -237.871)
		(width 0.4572)
		(layer "B.Cu")
		(net "GND")
	)
	(segment
		(start 238.443008 -224.824544)
		(end 237.475776 -224.824544)
		(width 0.3048)
		(layer "B.Cu")
		(net "GND")
	)
	(segment
		(start 386.316982 -232.253028)
		(end 386.855462 -231.714548)
		(width 0.4572)
		(layer "B.Cu")
		(net "GND")
	)
	(segment
		(start 107.959906 -348.985332)
		(end 108.021882 -348.985332)
		(width 0.3048)
		(layer "B.Cu")
		(net "GND")
	)
	(segment
		(start 135.190992 -173.792388)
		(end 135.806942 -173.792388)
		(width 0.4572)
		(layer "B.Cu")
		(net "GND")
	)
	(segment
		(start 293.27475 -298.06646)
		(end 293.27475 -298.27474)
		(width 0.3048)
		(layer "B.Cu")
		(net "GND")
	)
	(segment
		(start 281.133042 -300.174914)
		(end 280.924762 -300.174914)
		(width 0.3048)
		(layer "B.Cu")
		(net "GND")
	)
	(segment
		(start 181.92496 -294.26662)
		(end 181.92496 -294.4749)
		(width 0.3048)
		(layer "B.Cu")
		(net "GND")
	)
	(segment
		(start 47.77486 -295.1099)
		(end 47.77486 -294.4749)
		(width 0.3048)
		(layer "B.Cu")
		(net "GND")
	)
	(segment
		(start 130.906774 -174.195994)
		(end 130.766058 -174.33671)
		(width 0.4572)
		(layer "B.Cu")
		(net "GND")
	)
	(segment
		(start 144.841214 -210.241896)
		(end 144.098264 -210.241896)
		(width 0.4572)
		(layer "B.Cu")
		(net "GND")
	)
	(segment
		(start 21.978112 -229.827582)
		(end 21.978112 -228.73843)
		(width 0.254)
		(layer "B.Cu")
		(net "GND")
	)
	(segment
		(start 241.281712 -234.672124)
		(end 241.281712 -235.46181)
		(width 0.4572)
		(layer "B.Cu")
		(net "GND")
	)
	(segment
		(start 281.666442 -299.2755)
		(end 281.824176 -299.2755)
		(width 0.3048)
		(layer "B.Cu")
		(net "GND")
	)
	(segment
		(start 182.87492 -298.06646)
		(end 182.87492 -298.27474)
		(width 0.3048)
		(layer "B.Cu")
		(net "GND")
	)
	(segment
		(start 310.141874 -99.037648)
		(end 310.751474 -99.037648)
		(width 0.4572)
		(layer "B.Cu")
		(net "GND")
	)
	(segment
		(start 62.024768 -294.640762)
		(end 61.443616 -295.221914)
		(width 0.3048)
		(layer "B.Cu")
		(net "GND")
	)
	(segment
		(start 226.321874 -176.303178)
		(end 224.76841 -176.303178)
		(width 0.2794)
		(layer "B.Cu")
		(net "GND")
	)
	(segment
		(start 333.89824 -220.302328)
		(end 334.409542 -220.302328)
		(width 0.254)
		(layer "B.Cu")
		(net "GND")
	)
	(segment
		(start 169.574972 -294.4749)
		(end 169.574972 -294.640508)
		(width 0.3048)
		(layer "B.Cu")
		(net "GND")
	)
	(segment
		(start 341.694008 -217.187272)
		(end 341.694008 -217.256614)
		(width 0.254)
		(layer "B.Cu")
		(net "GND")
	)
	(segment
		(start 216.259156 -217.286332)
		(end 216.835482 -217.286332)
		(width 0.3048)
		(layer "B.Cu")
		(net "GND")
	)
	(segment
		(start 339.693758 -220.787214)
		(end 339.767926 -220.787214)
		(width 0.254)
		(layer "B.Cu")
		(net "GND")
	)
	(segment
		(start 55.374794 -294.26662)
		(end 55.374794 -294.4749)
		(width 0.3048)
		(layer "B.Cu")
		(net "GND")
	)
	(segment
		(start 180.975 -293.73322)
		(end 180.975 -293.52494)
		(width 0.3048)
		(layer "B.Cu")
		(net "GND")
	)
	(segment
		(start 410.324808 -294.640762)
		(end 410.324808 -294.4749)
		(width 0.3048)
		(layer "B.Cu")
		(net "GND")
	)
	(segment
		(start 301.616618 -297.32478)
		(end 301.824898 -297.32478)
		(width 0.3048)
		(layer "B.Cu")
		(net "GND")
	)
	(segment
		(start 116.935758 -261.154672)
		(end 117.456458 -261.675372)
		(width 0.4572)
		(layer "B.Cu")
		(net "GND")
	)
	(segment
		(start 162.183318 -290.674806)
		(end 161.975038 -290.674806)
		(width 0.3048)
		(layer "B.Cu")
		(net "GND")
	)
	(segment
		(start 411.274768 -293.73322)
		(end 411.274768 -293.525194)
		(width 0.3048)
		(layer "B.Cu")
		(net "GND")
	)
	(segment
		(start 380.254002 -234.458002)
		(end 379.984 -234.188)
		(width 0.4572)
		(layer "B.Cu")
		(net "GND")
	)
	(segment
		(start 47.77486 -296.90822)
		(end 47.77486 -297.32478)
		(width 0.3048)
		(layer "B.Cu")
		(net "GND")
	)
	(segment
		(start 301.616618 -294.4749)
		(end 301.824898 -294.4749)
		(width 0.3048)
		(layer "B.Cu")
		(net "GND")
	)
	(segment
		(start 380.254002 -235.01096)
		(end 380.254002 -234.458002)
		(width 0.4572)
		(layer "B.Cu")
		(net "GND")
	)
	(segment
		(start 237.475776 -224.824544)
		(end 237.475776 -225.111056)
		(width 0.3048)
		(layer "B.Cu")
		(net "GND")
	)
	(segment
		(start 353.822254 -222.552514)
		(end 353.818952 -222.555816)
		(width 0.3048)
		(layer "B.Cu")
		(net "GND")
	)
	(segment
		(start 344.560906 -217.587068)
		(end 344.49385 -217.587068)
		(width 0.254)
		(layer "B.Cu")
		(net "GND")
	)
	(segment
		(start 283.289756 -138.421618)
		(end 283.833062 -138.964924)
		(width 0.4572)
		(layer "B.Cu")
		(net "GND")
	)
	(segment
		(start 338.894166 -227.187252)
		(end 339.293708 -227.586794)
		(width 0.254)
		(layer "B.Cu")
		(net "GND")
	)
	(segment
		(start 241.07902 -234.469432)
		(end 241.281712 -234.672124)
		(width 0.4572)
		(layer "B.Cu")
		(net "GND")
	)
	(segment
		(start 184.56656 -293.52494)
		(end 184.77484 -293.52494)
		(width 0.3048)
		(layer "B.Cu")
		(net "GND")
	)
	(segment
		(start 340.093808 -217.127074)
		(end 340.093808 -217.187018)
		(width 0.254)
		(layer "B.Cu")
		(net "GND")
	)
	(segment
		(start 416.766502 -293.52494)
		(end 416.974782 -293.52494)
		(width 0.3048)
		(layer "B.Cu")
		(net "GND")
	)
	(segment
		(start 404.625048 -293.525194)
		(end 404.624794 -293.52494)
		(width 0.3048)
		(layer "B.Cu")
		(net "GND")
	)
	(segment
		(start 49.4665 -288.774886)
		(end 49.67478 -288.774886)
		(width 0.3048)
		(layer "B.Cu")
		(net "GND")
	)
	(segment
		(start 354.062538 -220.12148)
		(end 354.123244 -220.12148)
		(width 0.3048)
		(layer "B.Cu")
		(net "GND")
	)
	(segment
		(start 231.52481 -214.93353)
		(end 231.52481 -215.047068)
		(width 0.3048)
		(layer "B.Cu")
		(net "GND")
	)
	(segment
		(start 178.124866 -294.640762)
		(end 177.543714 -295.221914)
		(width 0.3048)
		(layer "B.Cu")
		(net "GND")
	)
	(segment
		(start 181.92496 -297.53306)
		(end 181.92496 -297.32478)
		(width 0.3048)
		(layer "B.Cu")
		(net "GND")
	)
	(segment
		(start 386.680202 -235.89996)
		(end 387.53796 -235.89996)
		(width 0.4572)
		(layer "B.Cu")
		(net "GND")
	)
	(segment
		(start 172.592746 -309.674768)
		(end 172.424852 -309.674768)
		(width 0.4572)
		(layer "B.Cu")
		(net "GND")
	)
	(segment
		(start 101.616256 -329.68311)
		(end 101.527864 -329.594718)
		(width 0.4572)
		(layer "B.Cu")
		(net "GND")
	)
	(segment
		(start 342.02878 -221.58706)
		(end 341.694008 -221.921832)
		(width 0.254)
		(layer "B.Cu")
		(net "GND")
	)
	(segment
		(start 63.203582 -296.37482)
		(end 62.974982 -296.37482)
		(width 0.3048)
		(layer "B.Cu")
		(net "GND")
	)
	(segment
		(start 117.054884 -316.017402)
		(end 117.054884 -316.868048)
		(width 0.254)
		(layer "B.Cu")
		(net "GND")
	)
	(segment
		(start 347.40215 -327.670922)
		(end 347.390974 -327.682098)
		(width 0.4572)
		(layer "B.Cu")
		(net "GND")
	)
	(segment
		(start 228.750368 -226.68357)
		(end 228.773482 -226.660456)
		(width 0.4572)
		(layer "B.Cu")
		(net "GND")
	)
	(segment
		(start 363.49305 -227.965)
		(end 364.563152 -227.965)
		(width 0.4572)
		(layer "B.Cu")
		(net "GND")
	)
	(segment
		(start 382.495552 -244.53596)
		(end 382.495552 -245.354856)
		(width 0.4572)
		(layer "B.Cu")
		(net "GND")
	)
	(segment
		(start 177.82032 -199.303386)
		(end 178.479958 -199.303386)
		(width 0.4572)
		(layer "B.Cu")
		(net "GND")
	)
	(segment
		(start 228.522022 -227.285296)
		(end 228.805486 -227.001832)
		(width 0.4572)
		(layer "B.Cu")
		(net "GND")
	)
	(segment
		(start 294.690038 -201.76109)
		(end 294.690038 -201.360024)
		(width 0.4572)
		(layer "B.Cu")
		(net "GND")
	)
	(segment
		(start 251.968 -199.79005)
		(end 255.240282 -199.79005)
		(width 0.4572)
		(layer "B.Cu")
		(net "GND")
	)
	(segment
		(start 420.45509 -97.663)
		(end 420.45509 -96.901)
		(width 0.4572)
		(layer "B.Cu")
		(net "GND")
	)
	(segment
		(start 354.123244 -220.12148)
		(end 354.625402 -220.623638)
		(width 0.3048)
		(layer "B.Cu")
		(net "GND")
	)
	(segment
		(start 409.75534 -296.3926)
		(end 409.392628 -296.3926)
		(width 0.3048)
		(layer "B.Cu")
		(net "GND")
	)
	(segment
		(start 18.269712 -222.658432)
		(end 18.269712 -221.915482)
		(width 0.4572)
		(layer "B.Cu")
		(net "GND")
	)
	(segment
		(start 77.941932 -104.120696)
		(end 78.551532 -104.120696)
		(width 0.4572)
		(layer "B.Cu")
		(net "GND")
	)
	(segment
		(start 301.083218 -303.024794)
		(end 300.874684 -303.024794)
		(width 0.3048)
		(layer "B.Cu")
		(net "GND")
	)
	(segment
		(start 350.376744 -315.98997)
		(end 349.85706 -315.98997)
		(width 0.254)
		(layer "B.Cu")
		(net "GND")
	)
	(segment
		(start 236.505496 -211.201)
		(end 236.632496 -211.074)
		(width 0.4572)
		(layer "B.Cu")
		(net "GND")
	)
	(segment
		(start 163.874958 -295.1861)
		(end 163.874958 -294.4749)
		(width 0.3048)
		(layer "B.Cu")
		(net "GND")
	)
	(segment
		(start 333.171546 -316.406784)
		(end 332.020418 -316.406784)
		(width 0.4572)
		(layer "B.Cu")
		(net "GND")
	)
	(segment
		(start 62.974728 -293.525194)
		(end 62.974982 -293.52494)
		(width 0.3048)
		(layer "B.Cu")
		(net "GND")
	)
	(segment
		(start 341.227918 -221.58706)
		(end 340.894162 -221.920816)
		(width 0.254)
		(layer "B.Cu")
		(net "GND")
	)
	(segment
		(start 350.891094 -224.734628)
		(end 350.543368 -224.386902)
		(width 0.254)
		(layer "B.Cu")
		(net "GND")
	)
	(segment
		(start 50.624994 -298.06646)
		(end 50.624994 -298.27474)
		(width 0.3048)
		(layer "B.Cu")
		(net "GND")
	)
	(segment
		(start 347.66631 -255.599946)
		(end 348.077536 -255.18872)
		(width 0.381)
		(layer "B.Cu")
		(net "GND")
	)
	(segment
		(start 308.02072 -113.95202)
		(end 308.02072 -113.260632)
		(width 0.4572)
		(layer "B.Cu")
		(net "GND")
	)
	(segment
		(start 408.424888 -294.26662)
		(end 408.424888 -294.4749)
		(width 0.3048)
		(layer "B.Cu")
		(net "GND")
	)
	(segment
		(start 298.024804 -294.26662)
		(end 298.024804 -294.4749)
		(width 0.3048)
		(layer "B.Cu")
		(net "GND")
	)
	(segment
		(start 346.093796 -212.786976)
		(end 346.493592 -212.38718)
		(width 0.254)
		(layer "B.Cu")
		(net "GND")
	)
	(segment
		(start 345.229434 -221.586806)
		(end 345.293442 -221.586806)
		(width 0.254)
		(layer "B.Cu")
		(net "GND")
	)
	(segment
		(start 163.874958 -297.74134)
		(end 163.874958 -297.32478)
		(width 0.3048)
		(layer "B.Cu")
		(net "GND")
	)
	(segment
		(start 214.054436 -213.222586)
		(end 214.054436 -212.206586)
		(width 0.4572)
		(layer "B.Cu")
		(net "GND")
	)
	(segment
		(start 340.093808 -217.187018)
		(end 340.093808 -217.247216)
		(width 0.254)
		(layer "B.Cu")
		(net "GND")
	)
	(segment
		(start 228.522022 -227.382578)
		(end 228.522022 -227.285296)
		(width 0.4572)
		(layer "B.Cu")
		(net "GND")
	)
	(segment
		(start 50.878994 -296.37482)
		(end 50.624994 -296.37482)
		(width 0.3048)
		(layer "B.Cu")
		(net "GND")
	)
	(segment
		(start 137.446766 -212.188806)
		(end 137.446766 -213.07171)
		(width 0.4572)
		(layer "B.Cu")
		(net "GND")
	)
	(segment
		(start 57.274968 -294.26662)
		(end 57.274968 -294.4749)
		(width 0.3048)
		(layer "B.Cu")
		(net "GND")
	)
	(segment
		(start 289.47491 -297.53306)
		(end 289.47491 -297.32478)
		(width 0.3048)
		(layer "B.Cu")
		(net "GND")
	)
	(segment
		(start 409.392628 -296.3926)
		(end 409.374848 -296.37482)
		(width 0.3048)
		(layer "B.Cu")
		(net "GND")
	)
	(segment
		(start 70.366636 -290.674806)
		(end 70.574916 -290.674806)
		(width 0.3048)
		(layer "B.Cu")
		(net "GND")
	)
	(segment
		(start 136.233916 -180.7591)
		(end 135.988298 -181.004718)
		(width 0.4572)
		(layer "B.Cu")
		(net "GND")
	)
	(segment
		(start 177.823876 -191.381634)
		(end 178.483514 -191.381634)
		(width 0.4572)
		(layer "B.Cu")
		(net "GND")
	)
	(segment
		(start 345.693746 -222.78721)
		(end 345.29395 -223.187006)
		(width 0.254)
		(layer "B.Cu")
		(net "GND")
	)
	(segment
		(start 344.093546 -221.986856)
		(end 344.093546 -221.92234)
		(width 0.254)
		(layer "B.Cu")
		(net "GND")
	)
	(segment
		(start 185.803794 -98.552)
		(end 185.803794 -99.187)
		(width 0.4572)
		(layer "B.Cu")
		(net "GND")
	)
	(segment
		(start 240.988088 -219.639134)
		(end 241.373914 -220.02496)
		(width 0.3048)
		(layer "B.Cu")
		(net "GND")
	)
	(segment
		(start 351.423224 -153.640536)
		(end 351.423224 -153.628852)
		(width 0.4572)
		(layer "B.Cu")
		(net "GND")
	)
	(segment
		(start 63.775336 -110.497366)
		(end 64.454532 -110.497366)
		(width 0.4572)
		(layer "B.Cu")
		(net "GND")
	)
	(segment
		(start 297.074844 -293.73322)
		(end 297.074844 -293.52494)
		(width 0.3048)
		(layer "B.Cu")
		(net "GND")
	)
	(segment
		(start 372.370604 -243.936012)
		(end 371.348 -243.936012)
		(width 0.3556)
		(layer "B.Cu")
		(net "GND")
	)
	(segment
		(start 177.174906 -293.73322)
		(end 177.174906 -293.52494)
		(width 0.3048)
		(layer "B.Cu")
		(net "GND")
	)
	(segment
		(start 293.25697 -296.3926)
		(end 293.27475 -296.37482)
		(width 0.3048)
		(layer "B.Cu")
		(net "GND")
	)
	(segment
		(start 108.097828 -327.366122)
		(end 108.097828 -328.102722)
		(width 0.4572)
		(layer "B.Cu")
		(net "GND")
	)
	(segment
		(start 126.770892 -261.814564)
		(end 128.667764 -261.814564)
		(width 0.381)
		(layer "B.Cu")
		(net "GND")
	)
	(segment
		(start 117.641624 -317.6778)
		(end 117.656864 -317.69304)
		(width 0.254)
		(layer "B.Cu")
		(net "GND")
	)
	(segment
		(start 61.4553 -296.3926)
		(end 61.092588 -296.3926)
		(width 0.3048)
		(layer "B.Cu")
		(net "GND")
	)
	(segment
		(start 343.2937 -217.247724)
		(end 342.954356 -217.587068)
		(width 0.254)
		(layer "B.Cu")
		(net "GND")
	)
	(segment
		(start 401.774914 -297.53306)
		(end 401.774914 -297.32478)
		(width 0.3048)
		(layer "B.Cu")
		(net "GND")
	)
	(segment
		(start 338.956142 -223.18726)
		(end 339.293962 -222.84944)
		(width 0.254)
		(layer "B.Cu")
		(net "GND")
	)
	(segment
		(start 252.98908 -85.840316)
		(end 252.32868 -85.840316)
		(width 0.4572)
		(layer "B.Cu")
		(net "GND")
	)
	(segment
		(start 285.674816 -294.640508)
		(end 285.09341 -295.221914)
		(width 0.3048)
		(layer "B.Cu")
		(net "GND")
	)
	(segment
		(start 295.975278 -109.481366)
		(end 296.901108 -109.481366)
		(width 0.4572)
		(layer "B.Cu")
		(net "GND")
	)
	(segment
		(start 252.45568 -84.544916)
		(end 252.45568 -85.205316)
		(width 0.4572)
		(layer "B.Cu")
		(net "GND")
	)
	(segment
		(start 278.669242 -291.624766)
		(end 278.074882 -291.624766)
		(width 0.3048)
		(layer "B.Cu")
		(net "GND")
	)
	(segment
		(start 283.774896 -294.26662)
		(end 283.774896 -294.4749)
		(width 0.3048)
		(layer "B.Cu")
		(net "GND")
	)
	(segment
		(start 334.088994 -213.593934)
		(end 334.088994 -213.668102)
		(width 0.254)
		(layer "B.Cu")
		(net "GND")
	)
	(segment
		(start 293.655242 -296.3926)
		(end 293.29253 -296.3926)
		(width 0.3048)
		(layer "B.Cu")
		(net "GND")
	)
	(segment
		(start 66.983102 -296.37482)
		(end 66.774822 -296.37482)
		(width 0.3048)
		(layer "B.Cu")
		(net "GND")
	)
	(segment
		(start 349.85706 -319.377568)
		(end 350.112838 -319.633346)
		(width 0.4572)
		(layer "B.Cu")
		(net "GND")
	)
	(segment
		(start 69.416676 -297.32478)
		(end 69.624956 -297.32478)
		(width 0.3048)
		(layer "B.Cu")
		(net "GND")
	)
	(segment
		(start 49.15535 -156.0576)
		(end 48.54575 -156.0576)
		(width 0.4572)
		(layer "B.Cu")
		(net "GND")
	)
	(segment
		(start 207.487012 -220.76918)
		(end 207.487012 -221.671134)
		(width 0.4572)
		(layer "B.Cu")
		(net "GND")
	)
	(segment
		(start 331.822298 -227.73132)
		(end 331.822298 -227.974906)
		(width 0.3048)
		(layer "B.Cu")
		(net "GND")
	)
	(segment
		(start 254.74422 -230.423212)
		(end 254.74422 -230.32339)
		(width 0.254)
		(layer "B.Cu")
		(net "GND")
	)
	(segment
		(start 417.183316 -301.124874)
		(end 416.974782 -301.124874)
		(width 0.3048)
		(layer "B.Cu")
		(net "GND")
	)
	(segment
		(start 415.07664 -293.526718)
		(end 415.074862 -293.52494)
		(width 0.3048)
		(layer "B.Cu")
		(net "GND")
	)
	(segment
		(start 204.487018 -239.4839)
		(end 203.217018 -240.7539)
		(width 0.3556)
		(layer "B.Cu")
		(net "GND")
	)
	(segment
		(start 290.44011 -298.06646)
		(end 290.44011 -298.2595)
		(width 0.3048)
		(layer "B.Cu")
		(net "GND")
	)
	(segment
		(start 348.093538 -220.45549)
		(end 348.093538 -220.38691)
		(width 0.254)
		(layer "B.Cu")
		(net "GND")
	)
	(segment
		(start 295.403524 -296.37482)
		(end 295.174924 -296.37482)
		(width 0.3048)
		(layer "B.Cu")
		(net "GND")
	)
	(segment
		(start 406.540208 -298.06646)
		(end 406.540208 -298.2595)
		(width 0.3048)
		(layer "B.Cu")
		(net "GND")
	)
	(segment
		(start 231.147366 -213.024466)
		(end 231.147366 -212.56625)
		(width 0.3048)
		(layer "B.Cu")
		(net "GND")
	)
	(segment
		(start 226.546664 -205.47711)
		(end 226.546664 -206.62011)
		(width 0.4572)
		(layer "B.Cu")
		(net "GND")
	)
	(segment
		(start 69.416676 -294.4749)
		(end 69.624956 -294.4749)
		(width 0.3048)
		(layer "B.Cu")
		(net "GND")
	)
	(segment
		(start 171.474892 -294.26662)
		(end 171.474892 -294.4749)
		(width 0.3048)
		(layer "B.Cu")
		(net "GND")
	)
	(segment
		(start 335.709514 -219.234512)
		(end 335.709514 -219.171774)
		(width 0.254)
		(layer "B.Cu")
		(net "GND")
	)
	(segment
		(start 350.39046 -316.868048)
		(end 350.39046 -316.003686)
		(width 0.254)
		(layer "B.Cu")
		(net "GND")
	)
	(segment
		(start 281.355292 -154.0256)
		(end 280.745692 -154.0256)
		(width 0.4572)
		(layer "B.Cu")
		(net "GND")
	)
	(segment
		(start 46.4693 -298.27474)
		(end 45.87494 -298.27474)
		(width 0.3048)
		(layer "B.Cu")
		(net "GND")
	)
	(segment
		(start 165.255194 -153.0096)
		(end 164.645594 -153.0096)
		(width 0.4572)
		(layer "B.Cu")
		(net "GND")
	)
	(segment
		(start 279.974802 -297.74134)
		(end 279.974802 -297.32478)
		(width 0.3048)
		(layer "B.Cu")
		(net "GND")
	)
	(segment
		(start 185.725054 -294.4749)
		(end 185.516774 -294.4749)
		(width 0.3048)
		(layer "B.Cu")
		(net "GND")
	)
	(segment
		(start 176.224946 -297.53306)
		(end 176.224946 -297.32478)
		(width 0.3048)
		(layer "B.Cu")
		(net "GND")
	)
	(segment
		(start 213.02599 -211.578698)
		(end 213.254336 -211.807044)
		(width 0.4572)
		(layer "B.Cu")
		(net "GND")
	)
	(segment
		(start 141.793214 -209.206846)
		(end 142.174214 -208.825846)
		(width 0.3048)
		(layer "B.Cu")
		(net "GND")
	)
	(segment
		(start 283.774896 -297.53306)
		(end 283.774896 -297.32478)
		(width 0.3048)
		(layer "B.Cu")
		(net "GND")
	)
	(segment
		(start 340.894162 -221.920816)
		(end 340.894162 -221.986856)
		(width 0.254)
		(layer "B.Cu")
		(net "GND")
	)
	(segment
		(start 329.71486 -239.528604)
		(end 329.71486 -238.976408)
		(width 0.4572)
		(layer "B.Cu")
		(net "GND")
	)
	(segment
		(start 282.824936 -298.06646)
		(end 282.824936 -298.27474)
		(width 0.3048)
		(layer "B.Cu")
		(net "GND")
	)
	(segment
		(start 399.389854 -138.421618)
		(end 399.93316 -138.964924)
		(width 0.4572)
		(layer "B.Cu")
		(net "GND")
	)
	(segment
		(start 327.123806 -224.955354)
		(end 327.123806 -223.977708)
		(width 0.4572)
		(layer "B.Cu")
		(net "GND")
	)
	(segment
		(start 397.76654 -299.2755)
		(end 397.924274 -299.2755)
		(width 0.3048)
		(layer "B.Cu")
		(net "GND")
	)
	(segment
		(start 166.725092 -298.06646)
		(end 166.725092 -298.27474)
		(width 0.3048)
		(layer "B.Cu")
		(net "GND")
	)
	(segment
		(start 310.141874 -100.056696)
		(end 310.751474 -100.056696)
		(width 0.4572)
		(layer "B.Cu")
		(net "GND")
	)
	(segment
		(start 61.057028 -296.3926)
		(end 61.074808 -296.37482)
		(width 0.3048)
		(layer "B.Cu")
		(net "GND")
	)
	(segment
		(start 148.209254 -203.411074)
		(end 148.209254 -202.466194)
		(width 0.381)
		(layer "B.Cu")
		(net "GND")
	)
	(segment
		(start 207.510126 -220.746066)
		(end 207.487012 -220.76918)
		(width 0.4572)
		(layer "B.Cu")
		(net "GND")
	)
	(segment
		(start 376.578114 -243.589302)
		(end 376.578114 -244.324886)
		(width 0.4572)
		(layer "B.Cu")
		(net "GND")
	)
	(segment
		(start 292.720268 -200.617074)
		(end 292.424358 -200.912984)
		(width 0.4572)
		(layer "B.Cu")
		(net "GND")
	)
	(segment
		(start 412.224982 -294.26662)
		(end 412.224982 -294.4749)
		(width 0.3048)
		(layer "B.Cu")
		(net "GND")
	)
	(segment
		(start 210.774026 -226.071938)
		(end 210.782408 -226.08032)
		(width 0.3048)
		(layer "B.Cu")
		(net "GND")
	)
	(segment
		(start 330.381864 -211.390738)
		(end 330.331064 -211.339938)
		(width 0.3048)
		(layer "B.Cu")
		(net "GND")
	)
	(segment
		(start 61.074808 -298.06646)
		(end 61.074808 -298.27474)
		(width 0.3048)
		(layer "B.Cu")
		(net "GND")
	)
	(segment
		(start 235.14177 -211.932774)
		(end 235.495846 -211.932774)
		(width 0.4572)
		(layer "B.Cu")
		(net "GND")
	)
	(segment
		(start 409.374848 -293.73322)
		(end 409.374848 -293.52494)
		(width 0.3048)
		(layer "B.Cu")
		(net "GND")
	)
	(segment
		(start 402.26488 -141.6812)
		(end 402.26488 -142.367)
		(width 0.4572)
		(layer "B.Cu")
		(net "GND")
	)
	(segment
		(start 194.041776 -103.104696)
		(end 194.651376 -103.104696)
		(width 0.4572)
		(layer "B.Cu")
		(net "GND")
	)
	(segment
		(start 127.321818 -211.588858)
		(end 126.356618 -211.588858)
		(width 0.3556)
		(layer "B.Cu")
		(net "GND")
	)
	(segment
		(start 105.132378 -346.438474)
		(end 105.132378 -346.185236)
		(width 0.4572)
		(layer "B.Cu")
		(net "GND")
	)
	(segment
		(start 400.824954 -298.06646)
		(end 400.824954 -298.27474)
		(width 0.3048)
		(layer "B.Cu")
		(net "GND")
	)
	(segment
		(start 341.694008 -221.921832)
		(end 341.694008 -221.986856)
		(width 0.254)
		(layer "B.Cu")
		(net "GND")
	)
	(segment
		(start 165.255194 -151.9936)
		(end 164.645594 -151.9936)
		(width 0.4572)
		(layer "B.Cu")
		(net "GND")
	)
	(segment
		(start 52.893468 -295.221914)
		(end 53.35778 -294.757602)
		(width 0.3048)
		(layer "B.Cu")
		(net "GND")
	)
	(segment
		(start 380.361952 -222.590106)
		(end 380.361952 -221.955106)
		(width 0.4572)
		(layer "B.Cu")
		(net "GND")
	)
	(segment
		(start 283.244036 -138.421618)
		(end 283.289756 -138.421618)
		(width 0.4572)
		(layer "B.Cu")
		(net "GND")
	)
	(segment
		(start 213.254336 -211.807044)
		(end 213.654894 -211.807044)
		(width 0.4572)
		(layer "B.Cu")
		(net "GND")
	)
	(segment
		(start 76.824078 -113.95202)
		(end 76.824078 -113.229898)
		(width 0.4572)
		(layer "B.Cu")
		(net "GND")
	)
	(segment
		(start 344.428826 -221.58706)
		(end 344.493342 -221.58706)
		(width 0.254)
		(layer "B.Cu")
		(net "GND")
	)
	(segment
		(start 293.27475 -293.73322)
		(end 293.27475 -293.52494)
		(width 0.3048)
		(layer "B.Cu")
		(net "GND")
	)
	(segment
		(start 216.835736 -216.400634)
		(end 216.835736 -217.286586)
		(width 0.3048)
		(layer "B.Cu")
		(net "GND")
	)
	(segment
		(start 210.82635 -226.124262)
		(end 210.782408 -226.08032)
		(width 0.3048)
		(layer "B.Cu")
		(net "GND")
	)
	(segment
		(start 300.591474 -221.294452)
		(end 300.591474 -220.55836)
		(width 0.4572)
		(layer "B.Cu")
		(net "GND")
	)
	(segment
		(start 186.466734 -289.724846)
		(end 186.675014 -289.724846)
		(width 0.3048)
		(layer "B.Cu")
		(net "GND")
	)
	(segment
		(start 178.124866 -294.26662)
		(end 178.124866 -294.4749)
		(width 0.3048)
		(layer "B.Cu")
		(net "GND")
	)
	(segment
		(start 185.5343 -294.492426)
		(end 185.516774 -294.4749)
		(width 0.3048)
		(layer "B.Cu")
		(net "GND")
	)
	(segment
		(start 397.23314 -300.174914)
		(end 397.02486 -300.174914)
		(width 0.3048)
		(layer "B.Cu")
		(net "GND")
	)
	(segment
		(start 340.0933 -221.186756)
		(end 340.094062 -221.186756)
		(width 0.254)
		(layer "B.Cu")
		(net "GND")
	)
	(segment
		(start 231.129586 -257.205988)
		(end 231.129586 -256.9845)
		(width 0.254)
		(layer "B.Cu")
		(net "GND")
	)
	(segment
		(start 173.375066 -294.4749)
		(end 173.375066 -294.640508)
		(width 0.3048)
		(layer "B.Cu")
		(net "GND")
	)
	(segment
		(start 230.9622 -257.373374)
		(end 231.129586 -257.205988)
		(width 0.254)
		(layer "B.Cu")
		(net "GND")
	)
	(segment
		(start 74.374756 -302.074834)
		(end 74.026776 -301.726854)
		(width 0.381)
		(layer "B.Cu")
		(net "GND")
	)
	(segment
		(start 399.344134 -138.421618)
		(end 399.389854 -138.421618)
		(width 0.4572)
		(layer "B.Cu")
		(net "GND")
	)
	(segment
		(start 401.078954 -296.37482)
		(end 400.824954 -296.37482)
		(width 0.3048)
		(layer "B.Cu")
		(net "GND")
	)
	(segment
		(start 413.174942 -293.73322)
		(end 413.174942 -293.52494)
		(width 0.3048)
		(layer "B.Cu")
		(net "GND")
	)
	(segment
		(start 64.874902 -293.73322)
		(end 64.874902 -293.52494)
		(width 0.3048)
		(layer "B.Cu")
		(net "GND")
	)
	(segment
		(start 138.040872 -228.73843)
		(end 138.377422 -228.40188)
		(width 0.254)
		(layer "B.Cu")
		(net "GND")
	)
	(segment
		(start 183.958738 -117.415056)
		(end 183.72201 -117.415056)
		(width 0.4572)
		(layer "B.Cu")
		(net "GND")
	)
	(segment
		(start 397.45539 -156.0576)
		(end 396.84579 -156.0576)
		(width 0.4572)
		(layer "B.Cu")
		(net "GND")
	)
	(segment
		(start 53.474874 -297.53306)
		(end 53.474874 -297.32478)
		(width 0.3048)
		(layer "B.Cu")
		(net "GND")
	)
	(segment
		(start 126.110238 -261.15391)
		(end 126.770892 -261.814564)
		(width 0.381)
		(layer "B.Cu")
		(net "GND")
	)
	(segment
		(start 377.93295 -240.89995)
		(end 377.571 -240.538)
		(width 0.4572)
		(layer "B.Cu")
		(net "GND")
	)
	(segment
		(start 47.77486 -297.74134)
		(end 47.77486 -297.32478)
		(width 0.3048)
		(layer "B.Cu")
		(net "GND")
	)
	(segment
		(start 248.807986 -223.537018)
		(end 249.054366 -223.290638)
		(width 0.4572)
		(layer "B.Cu")
		(net "GND")
	)
	(segment
		(start 289.08375 -309.124858)
		(end 289.08375 -309.1434)
		(width 0.4572)
		(layer "B.Cu")
		(net "GND")
	)
	(segment
		(start 29.225494 -302.20793)
		(end 29.225494 -296.447972)
		(width 0.254)
		(layer "In9.Cu")
		(net "GND")
	)
	(segment
		(start 30.851856 -294.82161)
		(end 35.010598 -294.82161)
		(width 0.254)
		(layer "In9.Cu")
		(net "GND")
	)
	(segment
		(start 29.020008 -302.413416)
		(end 29.225494 -302.20793)
		(width 0.254)
		(layer "In9.Cu")
		(net "GND")
	)
	(segment
		(start 18.305272 -305.482244)
		(end 22.070568 -305.482244)
		(width 0.254)
		(layer "In9.Cu")
		(net "GND")
	)
	(segment
		(start 263.051798 -294.82161)
		(end 262.177022 -295.696386)
		(width 0.254)
		(layer "In9.Cu")
		(net "GND")
	)
	(segment
		(start 29.225494 -296.447972)
		(end 30.851856 -294.82161)
		(width 0.254)
		(layer "In9.Cu")
		(net "GND")
	)
	(segment
		(start 59.596528 -302.074834)
		(end 60.124848 -302.074834)
		(width 0.254)
		(layer "In9.Cu")
		(net "GND")
	)
	(segment
		(start 59.436 -301.914306)
		(end 59.596528 -302.074834)
		(width 0.254)
		(layer "In9.Cu")
		(net "GND")
	)
	(segment
		(start 35.571938 -295.38295)
		(end 58.547254 -295.38295)
		(width 0.254)
		(layer "In9.Cu")
		(net "GND")
	)
	(segment
		(start 58.547254 -295.38295)
		(end 59.436 -296.271696)
		(width 0.254)
		(layer "In9.Cu")
		(net "GND")
	)
	(segment
		(start 267.21054 -294.82161)
		(end 263.051798 -294.82161)
		(width 0.254)
		(layer "In9.Cu")
		(net "GND")
	)
	(segment
		(start 290.742116 -295.38295)
		(end 267.77188 -295.38295)
		(width 0.254)
		(layer "In9.Cu")
		(net "GND")
	)
	(segment
		(start 254.515112 -307.809646)
		(end 248.89333 -307.809646)
		(width 0.254)
		(layer "In9.Cu")
		(net "GND")
	)
	(segment
		(start 248.89333 -307.809646)
		(end 248.567956 -307.484272)
		(width 0.254)
		(layer "In9.Cu")
		(net "GND")
	)
	(segment
		(start 25.139396 -302.413416)
		(end 29.020008 -302.413416)
		(width 0.254)
		(layer "In9.Cu")
		(net "GND")
	)
	(segment
		(start 292.32479 -303.974754)
		(end 291.66947 -303.319434)
		(width 0.254)
		(layer "In9.Cu")
		(net "GND")
	)
	(segment
		(start 291.66947 -303.319434)
		(end 291.66947 -296.310304)
		(width 0.254)
		(layer "In9.Cu")
		(net "GND")
	)
	(segment
		(start 59.436 -296.271696)
		(end 59.436 -301.914306)
		(width 0.254)
		(layer "In9.Cu")
		(net "GND")
	)
	(segment
		(start 262.177022 -300.147736)
		(end 254.515112 -307.809646)
		(width 0.254)
		(layer "In9.Cu")
		(net "GND")
	)
	(segment
		(start 262.177022 -295.696386)
		(end 262.177022 -300.147736)
		(width 0.254)
		(layer "In9.Cu")
		(net "GND")
	)
	(segment
		(start 291.66947 -296.310304)
		(end 290.742116 -295.38295)
		(width 0.254)
		(layer "In9.Cu")
		(net "GND")
	)
	(segment
		(start 18.020538 -305.19751)
		(end 18.305272 -305.482244)
		(width 0.254)
		(layer "In9.Cu")
		(net "GND")
	)
	(segment
		(start 267.77188 -295.38295)
		(end 267.21054 -294.82161)
		(width 0.254)
		(layer "In9.Cu")
		(net "GND")
	)
	(segment
		(start 22.070568 -305.482244)
		(end 25.139396 -302.413416)
		(width 0.254)
		(layer "In9.Cu")
		(net "GND")
	)
	(segment
		(start 35.010598 -294.82161)
		(end 35.571938 -295.38295)
		(width 0.254)
		(layer "In9.Cu")
		(net "GND")
	)
	(segment
		(start 437.072532 -293.566342)
		(end 434.404516 -293.566342)
		(width 0.254)
		(layer "In15.Cu")
		(net "GND")
	)
	(segment
		(start 419.709346 -295.730676)
		(end 419.535102 -295.90492)
		(width 0.254)
		(layer "In15.Cu")
		(net "GND")
	)
	(segment
		(start 187.33516 -296.085006)
		(end 187.624974 -296.37482)
		(width 0.254)
		(layer "In15.Cu")
		(net "GND")
	)
	(segment
		(start 206.451454 -293.442898)
		(end 205.245208 -293.442898)
		(width 0.254)
		(layer "In15.Cu")
		(net "GND")
	)
	(segment
		(start 201.424032 -293.924228)
		(end 199.617584 -295.730676)
		(width 0.254)
		(layer "In15.Cu")
		(net "GND")
	)
	(segment
		(start 232.835958 -307.748432)
		(end 233.089958 -307.494432)
		(width 0.254)
		(layer "In15.Cu")
		(net "GND")
	)
	(segment
		(start 463.711036 -307.617876)
		(end 463.711036 -288.097976)
		(width 0.254)
		(layer "In15.Cu")
		(net "GND")
	)
	(segment
		(start 210.58124 -290.200842)
		(end 209.69351 -290.200842)
		(width 0.254)
		(layer "In15.Cu")
		(net "GND")
	)
	(segment
		(start 233.089958 -307.494432)
		(end 233.089958 -290.359592)
		(width 0.254)
		(layer "In15.Cu")
		(net "GND")
	)
	(segment
		(start 419.535102 -296.085006)
		(end 419.824916 -296.37482)
		(width 0.254)
		(layer "In15.Cu")
		(net "GND")
	)
	(segment
		(start 199.617584 -295.730676)
		(end 187.509404 -295.730676)
		(width 0.254)
		(layer "In15.Cu")
		(net "GND")
	)
	(segment
		(start 448.48526 -286.590232)
		(end 445.083946 -289.991546)
		(width 0.254)
		(layer "In15.Cu")
		(net "GND")
	)
	(segment
		(start 214.38616 -286.395922)
		(end 210.58124 -290.200842)
		(width 0.254)
		(layer "In15.Cu")
		(net "GND")
	)
	(segment
		(start 419.535102 -295.90492)
		(end 419.535102 -296.085006)
		(width 0.254)
		(layer "In15.Cu")
		(net "GND")
	)
	(segment
		(start 232.581958 -307.748432)
		(end 232.835958 -307.748432)
		(width 0.254)
		(layer "In15.Cu")
		(net "GND")
	)
	(segment
		(start 440.647328 -289.991546)
		(end 437.072532 -293.566342)
		(width 0.254)
		(layer "In15.Cu")
		(net "GND")
	)
	(segment
		(start 187.33516 -295.90492)
		(end 187.33516 -296.085006)
		(width 0.254)
		(layer "In15.Cu")
		(net "GND")
	)
	(segment
		(start 229.559358 -286.828992)
		(end 224.592388 -286.828992)
		(width 0.254)
		(layer "In15.Cu")
		(net "GND")
	)
	(segment
		(start 204.763878 -293.924228)
		(end 201.424032 -293.924228)
		(width 0.254)
		(layer "In15.Cu")
		(net "GND")
	)
	(segment
		(start 456.444096 -287.07842)
		(end 455.955908 -286.590232)
		(width 0.254)
		(layer "In15.Cu")
		(net "GND")
	)
	(segment
		(start 462.69148 -287.07842)
		(end 456.444096 -287.07842)
		(width 0.254)
		(layer "In15.Cu")
		(net "GND")
	)
	(segment
		(start 463.457036 -307.871876)
		(end 463.711036 -307.617876)
		(width 0.254)
		(layer "In15.Cu")
		(net "GND")
	)
	(segment
		(start 463.203036 -307.871876)
		(end 463.457036 -307.871876)
		(width 0.254)
		(layer "In15.Cu")
		(net "GND")
	)
	(segment
		(start 232.317798 -307.484272)
		(end 232.581958 -307.748432)
		(width 0.254)
		(layer "In15.Cu")
		(net "GND")
	)
	(segment
		(start 445.083946 -289.991546)
		(end 440.647328 -289.991546)
		(width 0.254)
		(layer "In15.Cu")
		(net "GND")
	)
	(segment
		(start 205.245208 -293.442898)
		(end 204.763878 -293.924228)
		(width 0.254)
		(layer "In15.Cu")
		(net "GND")
	)
	(segment
		(start 209.69351 -290.200842)
		(end 206.451454 -293.442898)
		(width 0.254)
		(layer "In15.Cu")
		(net "GND")
	)
	(segment
		(start 224.592388 -286.828992)
		(end 224.159318 -286.395922)
		(width 0.254)
		(layer "In15.Cu")
		(net "GND")
	)
	(segment
		(start 224.159318 -286.395922)
		(end 214.38616 -286.395922)
		(width 0.254)
		(layer "In15.Cu")
		(net "GND")
	)
	(segment
		(start 233.089958 -290.359592)
		(end 229.559358 -286.828992)
		(width 0.254)
		(layer "In15.Cu")
		(net "GND")
	)
	(segment
		(start 455.955908 -286.590232)
		(end 448.48526 -286.590232)
		(width 0.254)
		(layer "In15.Cu")
		(net "GND")
	)
	(segment
		(start 463.711036 -288.097976)
		(end 462.69148 -287.07842)
		(width 0.254)
		(layer "In15.Cu")
		(net "GND")
	)
	(segment
		(start 462.938876 -307.607716)
		(end 463.203036 -307.871876)
		(width 0.254)
		(layer "In15.Cu")
		(net "GND")
	)
	(segment
		(start 432.240182 -295.730676)
		(end 419.709346 -295.730676)
		(width 0.254)
		(layer "In15.Cu")
		(net "GND")
	)
	(segment
		(start 187.509404 -295.730676)
		(end 187.33516 -295.90492)
		(width 0.254)
		(layer "In15.Cu")
		(net "GND")
	)
	(segment
		(start 434.404516 -293.566342)
		(end 432.240182 -295.730676)
		(width 0.254)
		(layer "In15.Cu")
		(net "GND")
	)
	(segment
		(start 390.410192 -355.657658)
		(end 390.410192 -355.02723)
		(width 0.13462)
		(layer "F.Cu")
		(net "P5E_PEX3_STN5_TX_DN<89>")
	)
	(segment
		(start 390.73074 -355.978206)
		(end 390.410192 -355.657658)
		(width 0.13462)
		(layer "F.Cu")
		(net "P5E_PEX3_STN5_TX_DN<89>")
	)
	(segment
		(start 390.410192 -355.02723)
		(end 390.70534 -354.732082)
		(width 0.13462)
		(layer "F.Cu")
		(net "P5E_PEX3_STN5_TX_DN<89>")
	)
	(segment
		(start 390.70534 -354.732082)
		(end 390.41451 -354.441252)
		(width 0.1651)
		(layer "In13.Cu")
		(net "P5E_PEX3_STN5_TX_DN<89>")
	)
	(segment
		(start 415.549842 -313.684412)
		(end 415.549842 -313.949842)
		(width 0.1143)
		(layer "In13.Cu")
		(net "P5E_PEX3_STN5_TX_DN<89>")
	)
	(segment
		(start 415.215832 -320.046096)
		(end 415.215832 -320.017648)
		(width 0.1143)
		(layer "In13.Cu")
		(net "P5E_PEX3_STN5_TX_DN<89>")
	)
	(segment
		(start 392.182858 -341.717376)
		(end 392.182604 -341.717122)
		(width 0.1651)
		(layer "In13.Cu")
		(net "P5E_PEX3_STN5_TX_DN<89>")
	)
	(segment
		(start 415.435542 -313.570112)
		(end 415.549842 -313.684412)
		(width 0.1143)
		(layer "In13.Cu")
		(net "P5E_PEX3_STN5_TX_DN<89>")
	)
	(segment
		(start 392.182604 -341.717122)
		(end 392.396726 -341.279226)
		(width 0.1651)
		(layer "In13.Cu")
		(net "P5E_PEX3_STN5_TX_DN<89>")
	)
	(segment
		(start 415.170112 -319.971928)
		(end 415.170112 -313.673744)
		(width 0.1143)
		(layer "In13.Cu")
		(net "P5E_PEX3_STN5_TX_DN<89>")
	)
	(segment
		(start 391.96899 -342.155526)
		(end 392.182858 -341.717376)
		(width 0.1651)
		(layer "In13.Cu")
		(net "P5E_PEX3_STN5_TX_DN<89>")
	)
	(segment
		(start 414.136332 -322.849748)
		(end 415.215832 -321.36969)
		(width 0.1651)
		(layer "In13.Cu")
		(net "P5E_PEX3_STN5_TX_DN<89>")
	)
	(segment
		(start 390.41451 -353.930966)
		(end 391.96899 -352.376486)
		(width 0.1651)
		(layer "In13.Cu")
		(net "P5E_PEX3_STN5_TX_DN<89>")
	)
	(segment
		(start 392.396726 -341.279226)
		(end 414.136332 -322.849748)
		(width 0.1651)
		(layer "In13.Cu")
		(net "P5E_PEX3_STN5_TX_DN<89>")
	)
	(segment
		(start 390.41451 -354.441252)
		(end 390.41451 -353.930966)
		(width 0.1651)
		(layer "In13.Cu")
		(net "P5E_PEX3_STN5_TX_DN<89>")
	)
	(segment
		(start 415.170112 -313.673744)
		(end 415.273744 -313.570112)
		(width 0.1143)
		(layer "In13.Cu")
		(net "P5E_PEX3_STN5_TX_DN<89>")
	)
	(segment
		(start 415.215832 -320.017648)
		(end 415.170112 -319.971928)
		(width 0.1143)
		(layer "In13.Cu")
		(net "P5E_PEX3_STN5_TX_DN<89>")
	)
	(segment
		(start 415.215832 -321.36969)
		(end 415.215832 -320.046096)
		(width 0.1651)
		(layer "In13.Cu")
		(net "P5E_PEX3_STN5_TX_DN<89>")
	)
	(segment
		(start 391.96899 -352.376486)
		(end 391.96899 -342.155526)
		(width 0.1651)
		(layer "In13.Cu")
		(net "P5E_PEX3_STN5_TX_DN<89>")
	)
	(segment
		(start 415.273744 -313.570112)
		(end 415.435542 -313.570112)
		(width 0.1143)
		(layer "In13.Cu")
		(net "P5E_PEX3_STN5_TX_DN<89>")
	)
	(segment
		(start 36.710112 -382.18999)
		(end 36.710112 -382.57226)
		(width 0.1651)
		(layer "In5.Cu")
		(net "P5E_PEX0_STN7_RX_DP<124>")
	)
	(segment
		(start 40.49903 -331.010768)
		(end 39.083996 -326.346312)
		(width 0.1651)
		(layer "In5.Cu")
		(net "P5E_PEX0_STN7_RX_DP<124>")
	)
	(segment
		(start 41.034208 -332.773274)
		(end 40.922956 -332.714092)
		(width 0.1651)
		(layer "In5.Cu")
		(net "P5E_PEX0_STN7_RX_DP<124>")
	)
	(segment
		(start 41.373552 -333.891382)
		(end 41.2623 -333.8322)
		(width 0.1651)
		(layer "In5.Cu")
		(net "P5E_PEX0_STN7_RX_DP<124>")
	)
	(segment
		(start 41.2623 -333.8322)
		(end 41.118536 -333.357982)
		(width 0.1651)
		(layer "In5.Cu")
		(net "P5E_PEX0_STN7_RX_DP<124>")
	)
	(segment
		(start 37.577014 -369.632484)
		(end 37.921946 -368.255042)
		(width 0.1651)
		(layer "In5.Cu")
		(net "P5E_PEX0_STN7_RX_DP<124>")
	)
	(segment
		(start 39.083996 -319.966848)
		(end 39.129716 -319.921128)
		(width 0.1143)
		(layer "In5.Cu")
		(net "P5E_PEX0_STN7_RX_DP<124>")
	)
	(segment
		(start 40.922956 -332.714092)
		(end 40.779192 -332.239874)
		(width 0.1651)
		(layer "In5.Cu")
		(net "P5E_PEX0_STN7_RX_DP<124>")
	)
	(segment
		(start 41.373044 -333.891382)
		(end 41.373552 -333.891382)
		(width 0.1651)
		(layer "In5.Cu")
		(net "P5E_PEX0_STN7_RX_DP<124>")
	)
	(segment
		(start 39.585646 -316.229492)
		(end 39.699946 -316.115192)
		(width 0.1143)
		(layer "In5.Cu")
		(net "P5E_PEX0_STN7_RX_DP<124>")
	)
	(segment
		(start 40.838628 -332.12913)
		(end 40.694864 -331.655166)
		(width 0.1651)
		(layer "In5.Cu")
		(net "P5E_PEX0_STN7_RX_DP<124>")
	)
	(segment
		(start 39.699946 -316.115192)
		(end 39.699946 -315.849762)
		(width 0.1143)
		(layer "In5.Cu")
		(net "P5E_PEX0_STN7_RX_DP<124>")
	)
	(segment
		(start 39.083996 -319.995296)
		(end 39.083996 -319.966848)
		(width 0.1143)
		(layer "In5.Cu")
		(net "P5E_PEX0_STN7_RX_DP<124>")
	)
	(segment
		(start 41.177972 -333.247238)
		(end 41.177718 -333.247238)
		(width 0.1651)
		(layer "In5.Cu")
		(net "P5E_PEX0_STN7_RX_DP<124>")
	)
	(segment
		(start 41.033954 -332.773274)
		(end 41.034208 -332.773274)
		(width 0.1651)
		(layer "In5.Cu")
		(net "P5E_PEX0_STN7_RX_DP<124>")
	)
	(segment
		(start 41.177718 -333.247238)
		(end 41.033954 -332.773274)
		(width 0.1651)
		(layer "In5.Cu")
		(net "P5E_PEX0_STN7_RX_DP<124>")
	)
	(segment
		(start 39.129716 -316.455298)
		(end 39.355522 -316.229492)
		(width 0.1143)
		(layer "In5.Cu")
		(net "P5E_PEX0_STN7_RX_DP<124>")
	)
	(segment
		(start 39.355522 -316.229492)
		(end 39.585646 -316.229492)
		(width 0.1143)
		(layer "In5.Cu")
		(net "P5E_PEX0_STN7_RX_DP<124>")
	)
	(segment
		(start 40.779192 -332.239874)
		(end 40.838628 -332.12913)
		(width 0.1651)
		(layer "In5.Cu")
		(net "P5E_PEX0_STN7_RX_DP<124>")
	)
	(segment
		(start 37.577014 -382.32969)
		(end 37.577014 -369.632484)
		(width 0.1651)
		(layer "In5.Cu")
		(net "P5E_PEX0_STN7_RX_DP<124>")
	)
	(segment
		(start 36.837112 -382.69926)
		(end 37.207444 -382.69926)
		(width 0.1651)
		(layer "In5.Cu")
		(net "P5E_PEX0_STN7_RX_DP<124>")
	)
	(segment
		(start 40.694864 -331.655166)
		(end 40.583612 -331.59573)
		(width 0.1651)
		(layer "In5.Cu")
		(net "P5E_PEX0_STN7_RX_DP<124>")
	)
	(segment
		(start 42.940478 -357.799386)
		(end 42.940478 -342.168734)
		(width 0.1651)
		(layer "In5.Cu")
		(net "P5E_PEX0_STN7_RX_DP<124>")
	)
	(segment
		(start 37.921946 -368.255042)
		(end 42.602658 -359.497376)
		(width 0.1651)
		(layer "In5.Cu")
		(net "P5E_PEX0_STN7_RX_DP<124>")
	)
	(segment
		(start 40.439848 -331.121512)
		(end 40.49903 -331.010768)
		(width 0.1651)
		(layer "In5.Cu")
		(net "P5E_PEX0_STN7_RX_DP<124>")
	)
	(segment
		(start 40.583612 -331.59573)
		(end 40.439848 -331.121512)
		(width 0.1651)
		(layer "In5.Cu")
		(net "P5E_PEX0_STN7_RX_DP<124>")
	)
	(segment
		(start 42.602658 -359.497376)
		(end 42.940478 -357.799386)
		(width 0.1651)
		(layer "In5.Cu")
		(net "P5E_PEX0_STN7_RX_DP<124>")
	)
	(segment
		(start 39.129716 -319.921128)
		(end 39.129716 -316.455298)
		(width 0.1143)
		(layer "In5.Cu")
		(net "P5E_PEX0_STN7_RX_DP<124>")
	)
	(segment
		(start 39.083996 -326.346312)
		(end 39.083996 -319.995296)
		(width 0.1651)
		(layer "In5.Cu")
		(net "P5E_PEX0_STN7_RX_DP<124>")
	)
	(segment
		(start 41.118536 -333.357982)
		(end 41.177972 -333.247238)
		(width 0.1651)
		(layer "In5.Cu")
		(net "P5E_PEX0_STN7_RX_DP<124>")
	)
	(segment
		(start 37.207444 -382.69926)
		(end 37.577014 -382.32969)
		(width 0.1651)
		(layer "In5.Cu")
		(net "P5E_PEX0_STN7_RX_DP<124>")
	)
	(segment
		(start 36.710112 -382.57226)
		(end 36.837112 -382.69926)
		(width 0.1651)
		(layer "In5.Cu")
		(net "P5E_PEX0_STN7_RX_DP<124>")
	)
	(segment
		(start 42.940478 -342.168734)
		(end 42.045636 -336.107532)
		(width 0.1651)
		(layer "In5.Cu")
		(net "P5E_PEX0_STN7_RX_DP<124>")
	)
	(segment
		(start 42.045636 -336.107532)
		(end 41.373044 -333.891382)
		(width 0.1651)
		(layer "In5.Cu")
		(net "P5E_PEX0_STN7_RX_DP<124>")
	)
	(segment
		(start 67.884802 -343.365582)
		(end 67.884802 -342.734138)
		(width 0.13462)
		(layer "F.Cu")
		(net "P5E_PEX0_STN6_TX_DP<109>")
	)
	(segment
		(start 67.564762 -343.685622)
		(end 67.884802 -343.365582)
		(width 0.13462)
		(layer "F.Cu")
		(net "P5E_PEX0_STN6_TX_DP<109>")
	)
	(segment
		(start 67.884802 -342.734138)
		(end 67.590162 -342.439498)
		(width 0.13462)
		(layer "F.Cu")
		(net "P5E_PEX0_STN6_TX_DP<109>")
	)
	(segment
		(start 45.068236 -311.479692)
		(end 45.31106 -311.479692)
		(width 0.1143)
		(layer "In13.Cu")
		(net "P5E_PEX0_STN6_TX_DP<109>")
	)
	(segment
		(start 67.880992 -341.546688)
		(end 67.640962 -341.146384)
		(width 0.1651)
		(layer "In13.Cu")
		(net "P5E_PEX0_STN6_TX_DP<109>")
	)
	(segment
		(start 44.78401 -320.133472)
		(end 44.82973 -320.087752)
		(width 0.1143)
		(layer "In13.Cu")
		(net "P5E_PEX0_STN6_TX_DP<109>")
	)
	(segment
		(start 44.82973 -320.087752)
		(end 44.82973 -311.718198)
		(width 0.1143)
		(layer "In13.Cu")
		(net "P5E_PEX0_STN6_TX_DP<109>")
	)
	(segment
		(start 44.82973 -311.718198)
		(end 45.068236 -311.479692)
		(width 0.1143)
		(layer "In13.Cu")
		(net "P5E_PEX0_STN6_TX_DP<109>")
	)
	(segment
		(start 50.160428 -331.974444)
		(end 46.43628 -328.250296)
		(width 0.1651)
		(layer "In13.Cu")
		(net "P5E_PEX0_STN6_TX_DP<109>")
	)
	(segment
		(start 45.39996 -311.390792)
		(end 45.39996 -311.099962)
		(width 0.1143)
		(layer "In13.Cu")
		(net "P5E_PEX0_STN6_TX_DP<109>")
	)
	(segment
		(start 44.78401 -324.26148)
		(end 44.78401 -320.15557)
		(width 0.1651)
		(layer "In13.Cu")
		(net "P5E_PEX0_STN6_TX_DP<109>")
	)
	(segment
		(start 44.78401 -320.15557)
		(end 44.78401 -320.133472)
		(width 0.1143)
		(layer "In13.Cu")
		(net "P5E_PEX0_STN6_TX_DP<109>")
	)
	(segment
		(start 67.880992 -342.148668)
		(end 67.880992 -341.546688)
		(width 0.1651)
		(layer "In13.Cu")
		(net "P5E_PEX0_STN6_TX_DP<109>")
	)
	(segment
		(start 67.640962 -341.146384)
		(end 51.59248 -332.567534)
		(width 0.1651)
		(layer "In13.Cu")
		(net "P5E_PEX0_STN6_TX_DP<109>")
	)
	(segment
		(start 46.43628 -328.250296)
		(end 44.78401 -324.26148)
		(width 0.1651)
		(layer "In13.Cu")
		(net "P5E_PEX0_STN6_TX_DP<109>")
	)
	(segment
		(start 67.590162 -342.439498)
		(end 67.880992 -342.148668)
		(width 0.1651)
		(layer "In13.Cu")
		(net "P5E_PEX0_STN6_TX_DP<109>")
	)
	(segment
		(start 51.59248 -332.567534)
		(end 50.160428 -331.974444)
		(width 0.1651)
		(layer "In13.Cu")
		(net "P5E_PEX0_STN6_TX_DP<109>")
	)
	(segment
		(start 45.31106 -311.479692)
		(end 45.39996 -311.390792)
		(width 0.1143)
		(layer "In13.Cu")
		(net "P5E_PEX0_STN6_TX_DP<109>")
	)
	(segment
		(start 393.244832 -343.36609)
		(end 393.244832 -342.73363)
		(width 0.13462)
		(layer "F.Cu")
		(net "P5E_PEX3_STN5_TX_DP<82>")
	)
	(segment
		(start 392.9253 -343.685622)
		(end 393.244832 -343.36609)
		(width 0.13462)
		(layer "F.Cu")
		(net "P5E_PEX3_STN5_TX_DP<82>")
	)
	(segment
		(start 393.244832 -342.73363)
		(end 392.9507 -342.439498)
		(width 0.13462)
		(layer "F.Cu")
		(net "P5E_PEX3_STN5_TX_DP<82>")
	)
	(segment
		(start 408.283918 -319.9892)
		(end 408.283918 -319.960752)
		(width 0.1143)
		(layer "In7.Cu")
		(net "P5E_PEX3_STN5_TX_DP<82>")
	)
	(segment
		(start 408.329638 -319.915032)
		(end 408.329638 -311.705498)
		(width 0.1143)
		(layer "In7.Cu")
		(net "P5E_PEX3_STN5_TX_DP<82>")
	)
	(segment
		(start 399.877026 -334.100678)
		(end 399.87728 -334.100678)
		(width 0.1651)
		(layer "In7.Cu")
		(net "P5E_PEX3_STN5_TX_DP<82>")
	)
	(segment
		(start 408.283918 -323.256148)
		(end 408.283918 -319.9892)
		(width 0.1651)
		(layer "In7.Cu")
		(net "P5E_PEX3_STN5_TX_DP<82>")
	)
	(segment
		(start 406.424384 -326.966072)
		(end 407.27376 -325.694802)
		(width 0.1651)
		(layer "In7.Cu")
		(net "P5E_PEX3_STN5_TX_DP<82>")
	)
	(segment
		(start 392.9507 -342.439498)
		(end 393.24153 -342.148668)
		(width 0.1651)
		(layer "In7.Cu")
		(net "P5E_PEX3_STN5_TX_DP<82>")
	)
	(segment
		(start 408.555444 -311.479692)
		(end 408.785568 -311.479692)
		(width 0.1143)
		(layer "In7.Cu")
		(net "P5E_PEX3_STN5_TX_DP<82>")
	)
	(segment
		(start 408.899868 -311.365392)
		(end 408.899868 -311.099962)
		(width 0.1143)
		(layer "In7.Cu")
		(net "P5E_PEX3_STN5_TX_DP<82>")
	)
	(segment
		(start 393.24153 -341.332312)
		(end 399.877026 -334.100678)
		(width 0.1651)
		(layer "In7.Cu")
		(net "P5E_PEX3_STN5_TX_DP<82>")
	)
	(segment
		(start 393.24153 -342.148668)
		(end 393.24153 -341.332312)
		(width 0.1651)
		(layer "In7.Cu")
		(net "P5E_PEX3_STN5_TX_DP<82>")
	)
	(segment
		(start 408.283918 -319.960752)
		(end 408.329638 -319.915032)
		(width 0.1143)
		(layer "In7.Cu")
		(net "P5E_PEX3_STN5_TX_DP<82>")
	)
	(segment
		(start 407.27376 -325.694802)
		(end 408.283918 -323.256148)
		(width 0.1651)
		(layer "In7.Cu")
		(net "P5E_PEX3_STN5_TX_DP<82>")
	)
	(segment
		(start 399.87728 -334.100678)
		(end 406.424384 -326.966072)
		(width 0.1651)
		(layer "In7.Cu")
		(net "P5E_PEX3_STN5_TX_DP<82>")
	)
	(segment
		(start 408.329638 -311.705498)
		(end 408.555444 -311.479692)
		(width 0.1143)
		(layer "In7.Cu")
		(net "P5E_PEX3_STN5_TX_DP<82>")
	)
	(segment
		(start 408.785568 -311.479692)
		(end 408.899868 -311.365392)
		(width 0.1143)
		(layer "In7.Cu")
		(net "P5E_PEX3_STN5_TX_DP<82>")
	)
	(segment
		(start 40.990266 -366.882426)
		(end 45.25137 -360.505248)
		(width 0.1651)
		(layer "In5.Cu")
		(net "P5E_PEX0_STN7_RX_DN<125>")
	)
	(segment
		(start 40.270176 -318.434466)
		(end 40.384476 -318.320166)
		(width 0.1143)
		(layer "In5.Cu")
		(net "P5E_PEX0_STN7_RX_DN<125>")
	)
	(segment
		(start 40.059102 -383.55778)
		(end 40.059102 -369.952016)
		(width 0.1651)
		(layer "In5.Cu")
		(net "P5E_PEX0_STN7_RX_DN<125>")
	)
	(segment
		(start 40.315896 -319.995296)
		(end 40.315896 -319.966848)
		(width 0.1143)
		(layer "In5.Cu")
		(net "P5E_PEX0_STN7_RX_DN<125>")
	)
	(segment
		(start 40.384476 -318.320166)
		(end 40.535606 -318.320166)
		(width 0.1143)
		(layer "In5.Cu")
		(net "P5E_PEX0_STN7_RX_DN<125>")
	)
	(segment
		(start 40.315896 -325.706486)
		(end 40.315896 -319.995296)
		(width 0.1651)
		(layer "In5.Cu")
		(net "P5E_PEX0_STN7_RX_DN<125>")
	)
	(segment
		(start 40.270176 -319.921128)
		(end 40.270176 -318.434466)
		(width 0.1143)
		(layer "In5.Cu")
		(net "P5E_PEX0_STN7_RX_DN<125>")
	)
	(segment
		(start 40.31615 -325.70674)
		(end 40.315896 -325.706486)
		(width 0.1651)
		(layer "In5.Cu")
		(net "P5E_PEX0_STN7_RX_DN<125>")
	)
	(segment
		(start 39.037006 -384.08102)
		(end 39.535862 -384.08102)
		(width 0.1651)
		(layer "In5.Cu")
		(net "P5E_PEX0_STN7_RX_DN<125>")
	)
	(segment
		(start 40.649906 -318.434466)
		(end 40.649906 -318.699896)
		(width 0.1143)
		(layer "In5.Cu")
		(net "P5E_PEX0_STN7_RX_DN<125>")
	)
	(segment
		(start 46.331378 -357.89616)
		(end 46.331378 -342.369648)
		(width 0.1651)
		(layer "In5.Cu")
		(net "P5E_PEX0_STN7_RX_DN<125>")
	)
	(segment
		(start 39.535862 -384.08102)
		(end 40.059102 -383.55778)
		(width 0.1651)
		(layer "In5.Cu")
		(net "P5E_PEX0_STN7_RX_DN<125>")
	)
	(segment
		(start 38.910006 -384.590036)
		(end 38.910006 -384.20802)
		(width 0.1651)
		(layer "In5.Cu")
		(net "P5E_PEX0_STN7_RX_DN<125>")
	)
	(segment
		(start 38.910006 -384.20802)
		(end 39.037006 -384.08102)
		(width 0.1651)
		(layer "In5.Cu")
		(net "P5E_PEX0_STN7_RX_DN<125>")
	)
	(segment
		(start 40.059102 -369.952016)
		(end 40.990266 -366.882426)
		(width 0.1651)
		(layer "In5.Cu")
		(net "P5E_PEX0_STN7_RX_DN<125>")
	)
	(segment
		(start 45.25137 -360.505248)
		(end 46.331378 -357.89616)
		(width 0.1651)
		(layer "In5.Cu")
		(net "P5E_PEX0_STN7_RX_DN<125>")
	)
	(segment
		(start 40.315896 -319.966848)
		(end 40.270176 -319.921128)
		(width 0.1143)
		(layer "In5.Cu")
		(net "P5E_PEX0_STN7_RX_DN<125>")
	)
	(segment
		(start 40.535606 -318.320166)
		(end 40.649906 -318.434466)
		(width 0.1143)
		(layer "In5.Cu")
		(net "P5E_PEX0_STN7_RX_DN<125>")
	)
	(segment
		(start 46.331378 -342.369648)
		(end 45.512482 -338.252308)
		(width 0.1651)
		(layer "In5.Cu")
		(net "P5E_PEX0_STN7_RX_DN<125>")
	)
	(segment
		(start 45.512482 -338.252308)
		(end 40.31615 -325.70674)
		(width 0.1651)
		(layer "In5.Cu")
		(net "P5E_PEX0_STN7_RX_DN<125>")
	)
	(segment
		(start 77.211682 -349.511874)
		(end 77.211682 -348.88043)
		(width 0.13462)
		(layer "F.Cu")
		(net "P5E_PEX0_STN6_TX_DP<104>")
	)
	(segment
		(start 77.211682 -348.88043)
		(end 76.917042 -348.58579)
		(width 0.13462)
		(layer "F.Cu")
		(net "P5E_PEX0_STN6_TX_DP<104>")
	)
	(segment
		(start 76.891642 -349.831914)
		(end 77.211682 -349.511874)
		(width 0.13462)
		(layer "F.Cu")
		(net "P5E_PEX0_STN6_TX_DP<104>")
	)
	(segment
		(start 78.18882 -341.225632)
		(end 54.820058 -328.734674)
		(width 0.1651)
		(layer "In13.Cu")
		(net "P5E_PEX0_STN6_TX_DP<104>")
	)
	(segment
		(start 78.762352 -346.045028)
		(end 78.762352 -342.181942)
		(width 0.1651)
		(layer "In13.Cu")
		(net "P5E_PEX0_STN6_TX_DP<104>")
	)
	(segment
		(start 50.794412 -325.854568)
		(end 49.53381 -322.81114)
		(width 0.1651)
		(layer "In13.Cu")
		(net "P5E_PEX0_STN6_TX_DP<104>")
	)
	(segment
		(start 49.840642 -313.379612)
		(end 50.06086 -313.379612)
		(width 0.1143)
		(layer "In13.Cu")
		(net "P5E_PEX0_STN6_TX_DP<104>")
	)
	(segment
		(start 77.207872 -347.599508)
		(end 78.762352 -346.045028)
		(width 0.1651)
		(layer "In13.Cu")
		(net "P5E_PEX0_STN6_TX_DP<104>")
	)
	(segment
		(start 49.53381 -320.14795)
		(end 49.53381 -320.125852)
		(width 0.1143)
		(layer "In13.Cu")
		(net "P5E_PEX0_STN6_TX_DP<104>")
	)
	(segment
		(start 54.820058 -328.734674)
		(end 52.864258 -327.924414)
		(width 0.1651)
		(layer "In13.Cu")
		(net "P5E_PEX0_STN6_TX_DP<104>")
	)
	(segment
		(start 49.57953 -320.080132)
		(end 49.57953 -313.640724)
		(width 0.1143)
		(layer "In13.Cu")
		(net "P5E_PEX0_STN6_TX_DP<104>")
	)
	(segment
		(start 52.864258 -327.924414)
		(end 50.794412 -325.854568)
		(width 0.1651)
		(layer "In13.Cu")
		(net "P5E_PEX0_STN6_TX_DP<104>")
	)
	(segment
		(start 49.53381 -322.81114)
		(end 49.53381 -320.14795)
		(width 0.1651)
		(layer "In13.Cu")
		(net "P5E_PEX0_STN6_TX_DP<104>")
	)
	(segment
		(start 50.06086 -313.379612)
		(end 50.14976 -313.290712)
		(width 0.1143)
		(layer "In13.Cu")
		(net "P5E_PEX0_STN6_TX_DP<104>")
	)
	(segment
		(start 76.917042 -348.58579)
		(end 77.207872 -348.29496)
		(width 0.1651)
		(layer "In13.Cu")
		(net "P5E_PEX0_STN6_TX_DP<104>")
	)
	(segment
		(start 49.57953 -313.640724)
		(end 49.840642 -313.379612)
		(width 0.1143)
		(layer "In13.Cu")
		(net "P5E_PEX0_STN6_TX_DP<104>")
	)
	(segment
		(start 50.14976 -313.290712)
		(end 50.14976 -312.999882)
		(width 0.1143)
		(layer "In13.Cu")
		(net "P5E_PEX0_STN6_TX_DP<104>")
	)
	(segment
		(start 78.762352 -342.181942)
		(end 78.18882 -341.225632)
		(width 0.1651)
		(layer "In13.Cu")
		(net "P5E_PEX0_STN6_TX_DP<104>")
	)
	(segment
		(start 49.53381 -320.125852)
		(end 49.57953 -320.080132)
		(width 0.1143)
		(layer "In13.Cu")
		(net "P5E_PEX0_STN6_TX_DP<104>")
	)
	(segment
		(start 77.207872 -348.29496)
		(end 77.207872 -347.599508)
		(width 0.1651)
		(layer "In13.Cu")
		(net "P5E_PEX0_STN6_TX_DP<104>")
	)
	(segment
		(start 447.958972 -30.6324)
		(end 447.314828 -30.6324)
		(width 0.13462)
		(layer "F.Cu")
		(net "P5E_PEX3_STN2_TX_DP<33>")
	)
	(segment
		(start 447.314828 -30.6324)
		(end 447.001138 -30.94609)
		(width 0.13462)
		(layer "F.Cu")
		(net "P5E_PEX3_STN2_TX_DP<33>")
	)
	(segment
		(start 448.247262 -30.92069)
		(end 447.958972 -30.6324)
		(width 0.13462)
		(layer "F.Cu")
		(net "P5E_PEX3_STN2_TX_DP<33>")
	)
	(segment
		(start 405.434038 -271.427448)
		(end 405.479758 -271.473168)
		(width 0.1143)
		(layer "In11.Cu")
		(net "P5E_PEX3_STN2_TX_DP<33>")
	)
	(segment
		(start 405.434038 -271.399)
		(end 405.434038 -271.427448)
		(width 0.1143)
		(layer "In11.Cu")
		(net "P5E_PEX3_STN2_TX_DP<33>")
	)
	(segment
		(start 435.913276 -93.315536)
		(end 435.91353 -93.315536)
		(width 0.1651)
		(layer "In11.Cu")
		(net "P5E_PEX3_STN2_TX_DP<33>")
	)
	(segment
		(start 426.41901 -141.840458)
		(end 426.14596 -148.226526)
		(width 0.1651)
		(layer "In11.Cu")
		(net "P5E_PEX3_STN2_TX_DP<33>")
	)
	(segment
		(start 451.203314 -75.784202)
		(end 444.63589 -79.352648)
		(width 0.1651)
		(layer "In11.Cu")
		(net "P5E_PEX3_STN2_TX_DP<33>")
	)
	(segment
		(start 426.760894 -133.834886)
		(end 426.760894 -140.36929)
		(width 0.1651)
		(layer "In11.Cu")
		(net "P5E_PEX3_STN2_TX_DP<33>")
	)
	(segment
		(start 427.413928 -118.530624)
		(end 426.760894 -133.834886)
		(width 0.1651)
		(layer "In11.Cu")
		(net "P5E_PEX3_STN2_TX_DP<33>")
	)
	(segment
		(start 435.91353 -93.315536)
		(end 429.037496 -105.463594)
		(width 0.1651)
		(layer "In11.Cu")
		(net "P5E_PEX3_STN2_TX_DP<33>")
	)
	(segment
		(start 406.049988 -278.534368)
		(end 406.049988 -278.799798)
		(width 0.1143)
		(layer "In11.Cu")
		(net "P5E_PEX3_STN2_TX_DP<33>")
	)
	(segment
		(start 424.700192 -161.016188)
		(end 405.434038 -265.833606)
		(width 0.1651)
		(layer "In11.Cu")
		(net "P5E_PEX3_STN2_TX_DP<33>")
	)
	(segment
		(start 405.434038 -265.833606)
		(end 405.434038 -271.399)
		(width 0.1651)
		(layer "In11.Cu")
		(net "P5E_PEX3_STN2_TX_DP<33>")
	)
	(segment
		(start 456.46086 -56.83631)
		(end 454.203562 -68.424552)
		(width 0.1651)
		(layer "In11.Cu")
		(net "P5E_PEX3_STN2_TX_DP<33>")
	)
	(segment
		(start 452.284592 -34.478468)
		(end 452.254366 -34.581846)
		(width 0.1651)
		(layer "In11.Cu")
		(net "P5E_PEX3_STN2_TX_DP<33>")
	)
	(segment
		(start 452.254366 -34.581846)
		(end 452.491856 -35.016948)
		(width 0.1651)
		(layer "In11.Cu")
		(net "P5E_PEX3_STN2_TX_DP<33>")
	)
	(segment
		(start 453.143112 -36.050474)
		(end 455.696574 -40.728392)
		(width 0.1651)
		(layer "In11.Cu")
		(net "P5E_PEX3_STN2_TX_DP<33>")
	)
	(segment
		(start 426.14596 -148.226526)
		(end 425.919138 -150.913846)
		(width 0.1651)
		(layer "In11.Cu")
		(net "P5E_PEX3_STN2_TX_DP<33>")
	)
	(segment
		(start 451.266306 -32.612838)
		(end 452.284592 -34.478468)
		(width 0.1651)
		(layer "In11.Cu")
		(net "P5E_PEX3_STN2_TX_DP<33>")
	)
	(segment
		(start 405.694896 -278.420068)
		(end 405.935688 -278.420068)
		(width 0.1143)
		(layer "In11.Cu")
		(net "P5E_PEX3_STN2_TX_DP<33>")
	)
	(segment
		(start 405.479758 -278.20493)
		(end 405.694896 -278.420068)
		(width 0.1143)
		(layer "In11.Cu")
		(net "P5E_PEX3_STN2_TX_DP<33>")
	)
	(segment
		(start 453.039734 -36.020248)
		(end 453.143112 -36.050474)
		(width 0.1651)
		(layer "In11.Cu")
		(net "P5E_PEX3_STN2_TX_DP<33>")
	)
	(segment
		(start 449.486782 -30.852618)
		(end 451.266306 -32.612838)
		(width 0.1651)
		(layer "In11.Cu")
		(net "P5E_PEX3_STN2_TX_DP<33>")
	)
	(segment
		(start 425.918884 -150.913846)
		(end 425.692316 -153.60142)
		(width 0.1651)
		(layer "In11.Cu")
		(net "P5E_PEX3_STN2_TX_DP<33>")
	)
	(segment
		(start 448.247262 -30.92069)
		(end 448.538092 -30.62986)
		(width 0.1651)
		(layer "In11.Cu")
		(net "P5E_PEX3_STN2_TX_DP<33>")
	)
	(segment
		(start 429.037496 -105.463594)
		(end 427.413928 -118.530624)
		(width 0.1651)
		(layer "In11.Cu")
		(net "P5E_PEX3_STN2_TX_DP<33>")
	)
	(segment
		(start 426.760894 -140.36929)
		(end 426.41901 -141.840458)
		(width 0.1651)
		(layer "In11.Cu")
		(net "P5E_PEX3_STN2_TX_DP<33>")
	)
	(segment
		(start 425.692316 -153.60142)
		(end 424.700192 -161.016188)
		(width 0.1651)
		(layer "In11.Cu")
		(net "P5E_PEX3_STN2_TX_DP<33>")
	)
	(segment
		(start 456.18908 -42.583862)
		(end 456.46086 -56.83631)
		(width 0.1651)
		(layer "In11.Cu")
		(net "P5E_PEX3_STN2_TX_DP<33>")
	)
	(segment
		(start 452.595234 -35.047174)
		(end 452.83247 -35.481768)
		(width 0.1651)
		(layer "In11.Cu")
		(net "P5E_PEX3_STN2_TX_DP<33>")
	)
	(segment
		(start 452.491856 -35.016948)
		(end 452.595234 -35.047174)
		(width 0.1651)
		(layer "In11.Cu")
		(net "P5E_PEX3_STN2_TX_DP<33>")
	)
	(segment
		(start 454.203562 -68.424552)
		(end 451.91807 -74.822304)
		(width 0.1651)
		(layer "In11.Cu")
		(net "P5E_PEX3_STN2_TX_DP<33>")
	)
	(segment
		(start 405.479758 -271.473168)
		(end 405.479758 -278.20493)
		(width 0.1143)
		(layer "In11.Cu")
		(net "P5E_PEX3_STN2_TX_DP<33>")
	)
	(segment
		(start 444.63589 -79.352648)
		(end 442.781436 -81.181702)
		(width 0.1651)
		(layer "In11.Cu")
		(net "P5E_PEX3_STN2_TX_DP<33>")
	)
	(segment
		(start 452.80199 -35.585146)
		(end 453.039734 -36.020248)
		(width 0.1651)
		(layer "In11.Cu")
		(net "P5E_PEX3_STN2_TX_DP<33>")
	)
	(segment
		(start 405.935688 -278.420068)
		(end 406.049988 -278.534368)
		(width 0.1143)
		(layer "In11.Cu")
		(net "P5E_PEX3_STN2_TX_DP<33>")
	)
	(segment
		(start 451.91807 -74.822304)
		(end 451.203314 -75.784202)
		(width 0.1651)
		(layer "In11.Cu")
		(net "P5E_PEX3_STN2_TX_DP<33>")
	)
	(segment
		(start 442.781436 -81.181702)
		(end 435.913276 -93.315536)
		(width 0.1651)
		(layer "In11.Cu")
		(net "P5E_PEX3_STN2_TX_DP<33>")
	)
	(segment
		(start 425.919138 -150.913846)
		(end 425.918884 -150.913846)
		(width 0.1651)
		(layer "In11.Cu")
		(net "P5E_PEX3_STN2_TX_DP<33>")
	)
	(segment
		(start 452.83247 -35.481768)
		(end 452.80199 -35.585146)
		(width 0.1651)
		(layer "In11.Cu")
		(net "P5E_PEX3_STN2_TX_DP<33>")
	)
	(segment
		(start 448.538092 -30.62986)
		(end 448.980052 -30.62986)
		(width 0.1651)
		(layer "In11.Cu")
		(net "P5E_PEX3_STN2_TX_DP<33>")
	)
	(segment
		(start 455.696574 -40.728392)
		(end 456.18908 -42.583862)
		(width 0.1651)
		(layer "In11.Cu")
		(net "P5E_PEX3_STN2_TX_DP<33>")
	)
	(segment
		(start 448.980052 -30.62986)
		(end 449.486782 -30.852618)
		(width 0.1651)
		(layer "In11.Cu")
		(net "P5E_PEX3_STN2_TX_DP<33>")
	)
	(segment
		(start 42.170096 -318.434466)
		(end 42.284396 -318.320166)
		(width 0.1143)
		(layer "In5.Cu")
		(net "P5E_PEX0_STN7_RX_DN<127>")
	)
	(segment
		(start 42.549826 -318.434466)
		(end 42.549826 -318.699896)
		(width 0.1143)
		(layer "In5.Cu")
		(net "P5E_PEX0_STN7_RX_DN<127>")
	)
	(segment
		(start 43.437048 -384.08102)
		(end 43.935904 -384.08102)
		(width 0.1651)
		(layer "In5.Cu")
		(net "P5E_PEX0_STN7_RX_DN<127>")
	)
	(segment
		(start 42.215816 -319.995296)
		(end 42.215816 -319.966848)
		(width 0.1143)
		(layer "In5.Cu")
		(net "P5E_PEX0_STN7_RX_DN<127>")
	)
	(segment
		(start 52.549298 -341.657178)
		(end 51.852322 -339.974174)
		(width 0.1651)
		(layer "In5.Cu")
		(net "P5E_PEX0_STN7_RX_DN<127>")
	)
	(segment
		(start 43.310048 -384.590036)
		(end 43.310048 -384.20802)
		(width 0.1651)
		(layer "In5.Cu")
		(net "P5E_PEX0_STN7_RX_DN<127>")
	)
	(segment
		(start 43.935904 -384.08102)
		(end 44.459144 -383.55778)
		(width 0.1651)
		(layer "In5.Cu")
		(net "P5E_PEX0_STN7_RX_DN<127>")
	)
	(segment
		(start 42.215816 -324.601332)
		(end 42.215816 -319.995296)
		(width 0.1651)
		(layer "In5.Cu")
		(net "P5E_PEX0_STN7_RX_DN<127>")
	)
	(segment
		(start 45.541692 -366.766602)
		(end 52.064666 -358.818688)
		(width 0.1651)
		(layer "In5.Cu")
		(net "P5E_PEX0_STN7_RX_DN<127>")
	)
	(segment
		(start 42.284396 -318.320166)
		(end 42.435526 -318.320166)
		(width 0.1143)
		(layer "In5.Cu")
		(net "P5E_PEX0_STN7_RX_DN<127>")
	)
	(segment
		(start 43.252644 -327.104756)
		(end 42.215816 -324.601332)
		(width 0.1651)
		(layer "In5.Cu")
		(net "P5E_PEX0_STN7_RX_DN<127>")
	)
	(segment
		(start 44.459144 -383.55778)
		(end 44.459144 -369.379754)
		(width 0.1651)
		(layer "In5.Cu")
		(net "P5E_PEX0_STN7_RX_DN<127>")
	)
	(segment
		(start 52.064666 -358.818688)
		(end 52.33543 -358.413304)
		(width 0.1651)
		(layer "In5.Cu")
		(net "P5E_PEX0_STN7_RX_DN<127>")
	)
	(segment
		(start 51.852322 -339.974174)
		(end 43.252644 -327.104756)
		(width 0.1651)
		(layer "In5.Cu")
		(net "P5E_PEX0_STN7_RX_DN<127>")
	)
	(segment
		(start 52.549298 -357.896668)
		(end 52.549298 -341.657178)
		(width 0.1651)
		(layer "In5.Cu")
		(net "P5E_PEX0_STN7_RX_DN<127>")
	)
	(segment
		(start 43.310048 -384.20802)
		(end 43.437048 -384.08102)
		(width 0.1651)
		(layer "In5.Cu")
		(net "P5E_PEX0_STN7_RX_DN<127>")
	)
	(segment
		(start 42.435526 -318.320166)
		(end 42.549826 -318.434466)
		(width 0.1143)
		(layer "In5.Cu")
		(net "P5E_PEX0_STN7_RX_DN<127>")
	)
	(segment
		(start 44.459144 -369.379754)
		(end 45.541692 -366.766602)
		(width 0.1651)
		(layer "In5.Cu")
		(net "P5E_PEX0_STN7_RX_DN<127>")
	)
	(segment
		(start 52.33543 -358.413304)
		(end 52.549298 -357.896668)
		(width 0.1651)
		(layer "In5.Cu")
		(net "P5E_PEX0_STN7_RX_DN<127>")
	)
	(segment
		(start 42.215816 -319.966848)
		(end 42.170096 -319.921128)
		(width 0.1143)
		(layer "In5.Cu")
		(net "P5E_PEX0_STN7_RX_DN<127>")
	)
	(segment
		(start 42.170096 -319.921128)
		(end 42.170096 -318.434466)
		(width 0.1143)
		(layer "In5.Cu")
		(net "P5E_PEX0_STN7_RX_DN<127>")
	)
	(segment
		(start 61.941202 -342.734138)
		(end 62.235842 -342.439498)
		(width 0.13462)
		(layer "F.Cu")
		(net "P5E_PEX0_STN6_TX_DN<111>")
	)
	(segment
		(start 61.941202 -343.365582)
		(end 61.941202 -342.734138)
		(width 0.13462)
		(layer "F.Cu")
		(net "P5E_PEX0_STN6_TX_DN<111>")
	)
	(segment
		(start 62.261242 -343.685622)
		(end 61.941202 -343.365582)
		(width 0.13462)
		(layer "F.Cu")
		(net "P5E_PEX0_STN6_TX_DN<111>")
	)
	(segment
		(start 43.259502 -311.670192)
		(end 43.410886 -311.670192)
		(width 0.1143)
		(layer "In13.Cu")
		(net "P5E_PEX0_STN6_TX_DN<111>")
	)
	(segment
		(start 49.370234 -333.487014)
		(end 44.962064 -329.078844)
		(width 0.1651)
		(layer "In13.Cu")
		(net "P5E_PEX0_STN6_TX_DN<111>")
	)
	(segment
		(start 61.945012 -341.148924)
		(end 54.90972 -336.448146)
		(width 0.1651)
		(layer "In13.Cu")
		(net "P5E_PEX0_STN6_TX_DN<111>")
	)
	(segment
		(start 43.410886 -311.670192)
		(end 43.499786 -311.759092)
		(width 0.1143)
		(layer "In13.Cu")
		(net "P5E_PEX0_STN6_TX_DN<111>")
	)
	(segment
		(start 43.120056 -320.113152)
		(end 43.120056 -311.809638)
		(width 0.1143)
		(layer "In13.Cu")
		(net "P5E_PEX0_STN6_TX_DN<111>")
	)
	(segment
		(start 54.90972 -336.448146)
		(end 49.370234 -333.487014)
		(width 0.1651)
		(layer "In13.Cu")
		(net "P5E_PEX0_STN6_TX_DN<111>")
	)
	(segment
		(start 43.499786 -311.759092)
		(end 43.499786 -312.049922)
		(width 0.1143)
		(layer "In13.Cu")
		(net "P5E_PEX0_STN6_TX_DN<111>")
	)
	(segment
		(start 61.945012 -342.148668)
		(end 61.945012 -341.148924)
		(width 0.1651)
		(layer "In13.Cu")
		(net "P5E_PEX0_STN6_TX_DN<111>")
	)
	(segment
		(start 62.235842 -342.439498)
		(end 61.945012 -342.148668)
		(width 0.1651)
		(layer "In13.Cu")
		(net "P5E_PEX0_STN6_TX_DN<111>")
	)
	(segment
		(start 43.165776 -320.18097)
		(end 43.165776 -320.158872)
		(width 0.1143)
		(layer "In13.Cu")
		(net "P5E_PEX0_STN6_TX_DN<111>")
	)
	(segment
		(start 43.165776 -324.742302)
		(end 43.165776 -320.18097)
		(width 0.1651)
		(layer "In13.Cu")
		(net "P5E_PEX0_STN6_TX_DN<111>")
	)
	(segment
		(start 44.962064 -329.078844)
		(end 43.165776 -324.742302)
		(width 0.1651)
		(layer "In13.Cu")
		(net "P5E_PEX0_STN6_TX_DN<111>")
	)
	(segment
		(start 43.120056 -311.809638)
		(end 43.259502 -311.670192)
		(width 0.1143)
		(layer "In13.Cu")
		(net "P5E_PEX0_STN6_TX_DN<111>")
	)
	(segment
		(start 43.165776 -320.158872)
		(end 43.120056 -320.113152)
		(width 0.1143)
		(layer "In13.Cu")
		(net "P5E_PEX0_STN6_TX_DN<111>")
	)
	(segment
		(start 399.14322 -343.685622)
		(end 399.462752 -343.36609)
		(width 0.13462)
		(layer "F.Cu")
		(net "P5E_PEX3_STN5_TX_DP<85>")
	)
	(segment
		(start 399.462752 -342.73363)
		(end 399.16862 -342.439498)
		(width 0.13462)
		(layer "F.Cu")
		(net "P5E_PEX3_STN5_TX_DP<85>")
	)
	(segment
		(start 399.462752 -343.36609)
		(end 399.462752 -342.73363)
		(width 0.13462)
		(layer "F.Cu")
		(net "P5E_PEX3_STN5_TX_DP<85>")
	)
	(segment
		(start 411.179772 -313.605418)
		(end 411.405578 -313.379612)
		(width 0.1143)
		(layer "In7.Cu")
		(net "P5E_PEX3_STN5_TX_DP<85>")
	)
	(segment
		(start 408.290268 -329.473814)
		(end 410.06903 -326.811894)
		(width 0.1651)
		(layer "In7.Cu")
		(net "P5E_PEX3_STN5_TX_DP<85>")
	)
	(segment
		(start 399.45945 -341.31758)
		(end 403.904704 -335.35493)
		(width 0.1651)
		(layer "In7.Cu")
		(net "P5E_PEX3_STN5_TX_DP<85>")
	)
	(segment
		(start 399.16862 -342.439498)
		(end 399.45945 -342.148668)
		(width 0.1651)
		(layer "In7.Cu")
		(net "P5E_PEX3_STN5_TX_DP<85>")
	)
	(segment
		(start 411.134052 -319.9892)
		(end 411.134052 -319.960752)
		(width 0.1143)
		(layer "In7.Cu")
		(net "P5E_PEX3_STN5_TX_DP<85>")
	)
	(segment
		(start 411.134052 -319.960752)
		(end 411.179772 -319.915032)
		(width 0.1143)
		(layer "In7.Cu")
		(net "P5E_PEX3_STN5_TX_DP<85>")
	)
	(segment
		(start 411.635702 -313.379612)
		(end 411.750002 -313.265312)
		(width 0.1143)
		(layer "In7.Cu")
		(net "P5E_PEX3_STN5_TX_DP<85>")
	)
	(segment
		(start 410.06903 -326.811894)
		(end 411.134052 -324.240906)
		(width 0.1651)
		(layer "In7.Cu")
		(net "P5E_PEX3_STN5_TX_DP<85>")
	)
	(segment
		(start 403.904704 -335.35493)
		(end 403.904704 -335.355184)
		(width 0.1651)
		(layer "In7.Cu")
		(net "P5E_PEX3_STN5_TX_DP<85>")
	)
	(segment
		(start 411.750002 -313.265312)
		(end 411.750002 -312.999882)
		(width 0.1143)
		(layer "In7.Cu")
		(net "P5E_PEX3_STN5_TX_DP<85>")
	)
	(segment
		(start 403.904704 -335.355184)
		(end 408.290268 -329.473814)
		(width 0.1651)
		(layer "In7.Cu")
		(net "P5E_PEX3_STN5_TX_DP<85>")
	)
	(segment
		(start 399.45945 -342.148668)
		(end 399.45945 -341.31758)
		(width 0.1651)
		(layer "In7.Cu")
		(net "P5E_PEX3_STN5_TX_DP<85>")
	)
	(segment
		(start 411.405578 -313.379612)
		(end 411.635702 -313.379612)
		(width 0.1143)
		(layer "In7.Cu")
		(net "P5E_PEX3_STN5_TX_DP<85>")
	)
	(segment
		(start 411.179772 -319.915032)
		(end 411.179772 -313.605418)
		(width 0.1143)
		(layer "In7.Cu")
		(net "P5E_PEX3_STN5_TX_DP<85>")
	)
	(segment
		(start 411.134052 -324.240906)
		(end 411.134052 -319.9892)
		(width 0.1651)
		(layer "In7.Cu")
		(net "P5E_PEX3_STN5_TX_DP<85>")
	)
	(segment
		(start 85.226398 -365.603028)
		(end 87.464392 -359.348278)
		(width 0.1651)
		(layer "In5.Cu")
		(net "P5E_PEX0_STN5_RX_DP<93>")
	)
	(segment
		(start 84.317586 -367.892584)
		(end 84.425282 -367.841784)
		(width 0.1651)
		(layer "In5.Cu")
		(net "P5E_PEX0_STN5_RX_DP<93>")
	)
	(segment
		(start 82.909918 -371.590062)
		(end 82.909918 -371.972078)
		(width 0.1651)
		(layer "In5.Cu")
		(net "P5E_PEX0_STN5_RX_DP<93>")
	)
	(segment
		(start 70.433946 -319.995296)
		(end 70.433946 -319.966848)
		(width 0.1143)
		(layer "In5.Cu")
		(net "P5E_PEX0_STN5_RX_DP<93>")
	)
	(segment
		(start 84.136484 -368.399314)
		(end 84.317586 -367.892584)
		(width 0.1651)
		(layer "In5.Cu")
		(net "P5E_PEX0_STN5_RX_DP<93>")
	)
	(segment
		(start 84.684616 -366.789208)
		(end 84.82584 -366.722406)
		(width 0.1651)
		(layer "In5.Cu")
		(net "P5E_PEX0_STN5_RX_DP<93>")
	)
	(segment
		(start 70.935596 -318.129666)
		(end 71.049896 -318.015366)
		(width 0.1143)
		(layer "In5.Cu")
		(net "P5E_PEX0_STN5_RX_DP<93>")
	)
	(segment
		(start 83.928204 -369.23091)
		(end 84.187284 -368.506756)
		(width 0.1651)
		(layer "In5.Cu")
		(net "P5E_PEX0_STN5_RX_DP<93>")
	)
	(segment
		(start 83.80222 -371.867684)
		(end 83.80222 -369.864894)
		(width 0.1651)
		(layer "In5.Cu")
		(net "P5E_PEX0_STN5_RX_DP<93>")
	)
	(segment
		(start 70.479666 -318.355472)
		(end 70.705472 -318.129666)
		(width 0.1143)
		(layer "In5.Cu")
		(net "P5E_PEX0_STN5_RX_DP<93>")
	)
	(segment
		(start 82.909918 -371.972078)
		(end 83.036918 -372.099078)
		(width 0.1651)
		(layer "In5.Cu")
		(net "P5E_PEX0_STN5_RX_DP<93>")
	)
	(segment
		(start 88.089232 -342.038686)
		(end 86.63559 -339.863176)
		(width 0.1651)
		(layer "In5.Cu")
		(net "P5E_PEX0_STN5_RX_DP<93>")
	)
	(segment
		(start 70.479666 -319.921128)
		(end 70.479666 -318.355472)
		(width 0.1143)
		(layer "In5.Cu")
		(net "P5E_PEX0_STN5_RX_DP<93>")
	)
	(segment
		(start 71.049896 -318.015366)
		(end 71.049896 -317.749936)
		(width 0.1143)
		(layer "In5.Cu")
		(net "P5E_PEX0_STN5_RX_DP<93>")
	)
	(segment
		(start 84.187284 -368.506756)
		(end 84.136484 -368.399314)
		(width 0.1651)
		(layer "In5.Cu")
		(net "P5E_PEX0_STN5_RX_DP<93>")
	)
	(segment
		(start 84.9884 -366.268254)
		(end 84.935568 -366.156494)
		(width 0.1651)
		(layer "In5.Cu")
		(net "P5E_PEX0_STN5_RX_DP<93>")
	)
	(segment
		(start 84.82584 -366.722406)
		(end 84.825586 -366.722406)
		(width 0.1651)
		(layer "In5.Cu")
		(net "P5E_PEX0_STN5_RX_DP<93>")
	)
	(segment
		(start 83.80222 -369.864894)
		(end 83.928204 -369.23091)
		(width 0.1651)
		(layer "In5.Cu")
		(net "P5E_PEX0_STN5_RX_DP<93>")
	)
	(segment
		(start 84.988146 -366.268254)
		(end 84.9884 -366.268254)
		(width 0.1651)
		(layer "In5.Cu")
		(net "P5E_PEX0_STN5_RX_DP<93>")
	)
	(segment
		(start 84.825586 -366.722406)
		(end 84.988146 -366.268254)
		(width 0.1651)
		(layer "In5.Cu")
		(net "P5E_PEX0_STN5_RX_DP<93>")
	)
	(segment
		(start 86.63559 -339.863176)
		(end 71.358252 -323.007228)
		(width 0.1651)
		(layer "In5.Cu")
		(net "P5E_PEX0_STN5_RX_DP<93>")
	)
	(segment
		(start 84.52104 -367.246408)
		(end 84.684616 -366.789208)
		(width 0.1651)
		(layer "In5.Cu")
		(net "P5E_PEX0_STN5_RX_DP<93>")
	)
	(segment
		(start 83.570826 -372.099078)
		(end 83.80222 -371.867684)
		(width 0.1651)
		(layer "In5.Cu")
		(net "P5E_PEX0_STN5_RX_DP<93>")
	)
	(segment
		(start 70.433946 -320.775838)
		(end 70.433946 -319.995296)
		(width 0.1651)
		(layer "In5.Cu")
		(net "P5E_PEX0_STN5_RX_DP<93>")
	)
	(segment
		(start 87.464392 -359.348278)
		(end 88.089232 -357.840026)
		(width 0.1651)
		(layer "In5.Cu")
		(net "P5E_PEX0_STN5_RX_DP<93>")
	)
	(segment
		(start 83.036918 -372.099078)
		(end 83.570826 -372.099078)
		(width 0.1651)
		(layer "In5.Cu")
		(net "P5E_PEX0_STN5_RX_DP<93>")
	)
	(segment
		(start 84.935568 -366.156494)
		(end 85.114638 -365.65586)
		(width 0.1651)
		(layer "In5.Cu")
		(net "P5E_PEX0_STN5_RX_DP<93>")
	)
	(segment
		(start 70.705472 -318.129666)
		(end 70.935596 -318.129666)
		(width 0.1143)
		(layer "In5.Cu")
		(net "P5E_PEX0_STN5_RX_DP<93>")
	)
	(segment
		(start 84.587842 -367.387632)
		(end 84.52104 -367.246408)
		(width 0.1651)
		(layer "In5.Cu")
		(net "P5E_PEX0_STN5_RX_DP<93>")
	)
	(segment
		(start 88.089232 -357.840026)
		(end 88.089232 -342.038686)
		(width 0.1651)
		(layer "In5.Cu")
		(net "P5E_PEX0_STN5_RX_DP<93>")
	)
	(segment
		(start 85.114638 -365.65586)
		(end 85.226398 -365.603028)
		(width 0.1651)
		(layer "In5.Cu")
		(net "P5E_PEX0_STN5_RX_DP<93>")
	)
	(segment
		(start 70.433946 -319.966848)
		(end 70.479666 -319.921128)
		(width 0.1143)
		(layer "In5.Cu")
		(net "P5E_PEX0_STN5_RX_DP<93>")
	)
	(segment
		(start 71.358252 -323.007228)
		(end 70.433946 -320.775838)
		(width 0.1651)
		(layer "In5.Cu")
		(net "P5E_PEX0_STN5_RX_DP<93>")
	)
	(segment
		(start 84.425282 -367.841784)
		(end 84.587842 -367.387632)
		(width 0.1651)
		(layer "In5.Cu")
		(net "P5E_PEX0_STN5_RX_DP<93>")
	)
	(segment
		(start 328.569828 -32.13608)
		(end 328.258932 -31.825184)
		(width 0.13462)
		(layer "F.Cu")
		(net "P5E_PEX2_STN2_TX_DN<34>")
	)
	(segment
		(start 329.21956 -32.13608)
		(end 328.569828 -32.13608)
		(width 0.13462)
		(layer "F.Cu")
		(net "P5E_PEX2_STN2_TX_DN<34>")
	)
	(segment
		(start 329.505056 -31.850584)
		(end 329.21956 -32.13608)
		(width 0.13462)
		(layer "F.Cu")
		(net "P5E_PEX2_STN2_TX_DN<34>")
	)
	(segment
		(start 339.180678 -41.785794)
		(end 339.409278 -42.652188)
		(width 0.1651)
		(layer "In11.Cu")
		(net "P5E_PEX2_STN2_TX_DN<34>")
	)
	(segment
		(start 288.619946 -280.025856)
		(end 288.723578 -280.129488)
		(width 0.1143)
		(layer "In11.Cu")
		(net "P5E_PEX2_STN2_TX_DN<34>")
	)
	(segment
		(start 310.603138 -118.379748)
		(end 309.987696 -132.513578)
		(width 0.1651)
		(layer "In11.Cu")
		(net "P5E_PEX2_STN2_TX_DN<34>")
	)
	(segment
		(start 335.217516 -74.425556)
		(end 334.626966 -75.263756)
		(width 0.1651)
		(layer "In11.Cu")
		(net "P5E_PEX2_STN2_TX_DN<34>")
	)
	(segment
		(start 288.665666 -271.427448)
		(end 288.619946 -271.473168)
		(width 0.1143)
		(layer "In11.Cu")
		(net "P5E_PEX2_STN2_TX_DN<34>")
	)
	(segment
		(start 309.987696 -132.513578)
		(end 309.987696 -140.132816)
		(width 0.1651)
		(layer "In11.Cu")
		(net "P5E_PEX2_STN2_TX_DN<34>")
	)
	(segment
		(start 309.251604 -149.41169)
		(end 309.251604 -149.413722)
		(width 0.1651)
		(layer "In11.Cu")
		(net "P5E_PEX2_STN2_TX_DN<34>")
	)
	(segment
		(start 309.579518 -141.883892)
		(end 309.251604 -149.41169)
		(width 0.1651)
		(layer "In11.Cu")
		(net "P5E_PEX2_STN2_TX_DN<34>")
	)
	(segment
		(start 309.987696 -140.132816)
		(end 309.579518 -141.883892)
		(width 0.1651)
		(layer "In11.Cu")
		(net "P5E_PEX2_STN2_TX_DN<34>")
	)
	(segment
		(start 334.872076 -33.86836)
		(end 339.180678 -41.785794)
		(width 0.1651)
		(layer "In11.Cu")
		(net "P5E_PEX2_STN2_TX_DN<34>")
	)
	(segment
		(start 307.832252 -161.43859)
		(end 288.665666 -265.666982)
		(width 0.1651)
		(layer "In11.Cu")
		(net "P5E_PEX2_STN2_TX_DN<34>")
	)
	(segment
		(start 288.999676 -280.015188)
		(end 288.999676 -279.749504)
		(width 0.1143)
		(layer "In11.Cu")
		(net "P5E_PEX2_STN2_TX_DN<34>")
	)
	(segment
		(start 334.626966 -75.263756)
		(end 328.113644 -78.775052)
		(width 0.1651)
		(layer "In11.Cu")
		(net "P5E_PEX2_STN2_TX_DN<34>")
	)
	(segment
		(start 328.113644 -78.775052)
		(end 326.16394 -80.722724)
		(width 0.1651)
		(layer "In11.Cu")
		(net "P5E_PEX2_STN2_TX_DN<34>")
	)
	(segment
		(start 339.409278 -42.652188)
		(end 339.660484 -56.75376)
		(width 0.1651)
		(layer "In11.Cu")
		(net "P5E_PEX2_STN2_TX_DN<34>")
	)
	(segment
		(start 309.250842 -149.418294)
		(end 307.832252 -161.43859)
		(width 0.1651)
		(layer "In11.Cu")
		(net "P5E_PEX2_STN2_TX_DN<34>")
	)
	(segment
		(start 288.619946 -271.473168)
		(end 288.619946 -280.025856)
		(width 0.1143)
		(layer "In11.Cu")
		(net "P5E_PEX2_STN2_TX_DN<34>")
	)
	(segment
		(start 288.665666 -271.399)
		(end 288.665666 -271.427448)
		(width 0.1143)
		(layer "In11.Cu")
		(net "P5E_PEX2_STN2_TX_DN<34>")
	)
	(segment
		(start 337.443064 -68.266056)
		(end 335.217516 -74.425556)
		(width 0.1651)
		(layer "In11.Cu")
		(net "P5E_PEX2_STN2_TX_DN<34>")
	)
	(segment
		(start 311.409588 -111.841534)
		(end 310.603138 -118.379748)
		(width 0.1651)
		(layer "In11.Cu")
		(net "P5E_PEX2_STN2_TX_DN<34>")
	)
	(segment
		(start 329.505056 -31.850584)
		(end 329.795886 -32.141414)
		(width 0.1651)
		(layer "In11.Cu")
		(net "P5E_PEX2_STN2_TX_DN<34>")
	)
	(segment
		(start 312.2168 -105.301288)
		(end 311.409842 -111.841534)
		(width 0.1651)
		(layer "In11.Cu")
		(net "P5E_PEX2_STN2_TX_DN<34>")
	)
	(segment
		(start 326.16394 -80.722724)
		(end 312.2168 -105.301288)
		(width 0.1651)
		(layer "In11.Cu")
		(net "P5E_PEX2_STN2_TX_DN<34>")
	)
	(segment
		(start 339.660484 -56.75376)
		(end 337.443064 -68.266056)
		(width 0.1651)
		(layer "In11.Cu")
		(net "P5E_PEX2_STN2_TX_DN<34>")
	)
	(segment
		(start 309.25135 -149.413976)
		(end 309.250842 -149.418294)
		(width 0.1651)
		(layer "In11.Cu")
		(net "P5E_PEX2_STN2_TX_DN<34>")
	)
	(segment
		(start 309.251604 -149.413722)
		(end 309.25135 -149.413976)
		(width 0.1651)
		(layer "In11.Cu")
		(net "P5E_PEX2_STN2_TX_DN<34>")
	)
	(segment
		(start 288.723578 -280.129488)
		(end 288.885376 -280.129488)
		(width 0.1143)
		(layer "In11.Cu")
		(net "P5E_PEX2_STN2_TX_DN<34>")
	)
	(segment
		(start 311.409842 -111.841534)
		(end 311.409588 -111.841534)
		(width 0.1651)
		(layer "In11.Cu")
		(net "P5E_PEX2_STN2_TX_DN<34>")
	)
	(segment
		(start 288.885376 -280.129488)
		(end 288.999676 -280.015188)
		(width 0.1143)
		(layer "In11.Cu")
		(net "P5E_PEX2_STN2_TX_DN<34>")
	)
	(segment
		(start 288.665666 -265.666982)
		(end 288.665666 -271.399)
		(width 0.1651)
		(layer "In11.Cu")
		(net "P5E_PEX2_STN2_TX_DN<34>")
	)
	(segment
		(start 329.795886 -32.141414)
		(end 333.163164 -32.141414)
		(width 0.1651)
		(layer "In11.Cu")
		(net "P5E_PEX2_STN2_TX_DN<34>")
	)
	(segment
		(start 333.163164 -32.141414)
		(end 334.872076 -33.86836)
		(width 0.1651)
		(layer "In11.Cu")
		(net "P5E_PEX2_STN2_TX_DN<34>")
	)
	(segment
		(start 402.571712 -355.026214)
		(end 402.27758 -354.732082)
		(width 0.13462)
		(layer "F.Cu")
		(net "P5E_PEX3_STN5_TX_DP<95>")
	)
	(segment
		(start 402.571712 -355.658674)
		(end 402.571712 -355.026214)
		(width 0.13462)
		(layer "F.Cu")
		(net "P5E_PEX3_STN5_TX_DP<95>")
	)
	(segment
		(start 402.25218 -355.978206)
		(end 402.571712 -355.658674)
		(width 0.13462)
		(layer "F.Cu")
		(net "P5E_PEX3_STN5_TX_DP<95>")
	)
	(segment
		(start 402.56841 -354.441252)
		(end 402.56841 -353.724464)
		(width 0.1651)
		(layer "In13.Cu")
		(net "P5E_PEX3_STN5_TX_DP<95>")
	)
	(segment
		(start 420.679626 -313.59475)
		(end 420.894764 -313.379612)
		(width 0.1143)
		(layer "In13.Cu")
		(net "P5E_PEX3_STN5_TX_DP<95>")
	)
	(segment
		(start 420.633906 -320.046096)
		(end 420.633906 -320.017648)
		(width 0.1143)
		(layer "In13.Cu")
		(net "P5E_PEX3_STN5_TX_DP<95>")
	)
	(segment
		(start 403.96414 -352.085656)
		(end 403.964394 -352.085402)
		(width 0.1651)
		(layer "In13.Cu")
		(net "P5E_PEX3_STN5_TX_DP<95>")
	)
	(segment
		(start 402.27758 -354.732082)
		(end 402.56841 -354.441252)
		(width 0.1651)
		(layer "In13.Cu")
		(net "P5E_PEX3_STN5_TX_DP<95>")
	)
	(segment
		(start 406.15997 -346.595446)
		(end 408.25547 -341.25154)
		(width 0.1651)
		(layer "In13.Cu")
		(net "P5E_PEX3_STN5_TX_DP<95>")
	)
	(segment
		(start 420.894764 -313.379612)
		(end 421.135556 -313.379612)
		(width 0.1143)
		(layer "In13.Cu")
		(net "P5E_PEX3_STN5_TX_DP<95>")
	)
	(segment
		(start 403.964394 -352.085402)
		(end 404.086568 -351.882456)
		(width 0.1651)
		(layer "In13.Cu")
		(net "P5E_PEX3_STN5_TX_DP<95>")
	)
	(segment
		(start 421.249856 -313.265312)
		(end 421.249856 -312.999882)
		(width 0.1143)
		(layer "In13.Cu")
		(net "P5E_PEX3_STN5_TX_DP<95>")
	)
	(segment
		(start 402.56841 -353.724464)
		(end 403.596856 -352.696018)
		(width 0.1651)
		(layer "In13.Cu")
		(net "P5E_PEX3_STN5_TX_DP<95>")
	)
	(segment
		(start 403.596856 -352.696018)
		(end 403.96414 -352.085656)
		(width 0.1651)
		(layer "In13.Cu")
		(net "P5E_PEX3_STN5_TX_DP<95>")
	)
	(segment
		(start 404.086568 -351.882456)
		(end 406.159716 -346.595446)
		(width 0.1651)
		(layer "In13.Cu")
		(net "P5E_PEX3_STN5_TX_DP<95>")
	)
	(segment
		(start 408.25547 -341.25154)
		(end 418.013134 -328.010012)
		(width 0.1651)
		(layer "In13.Cu")
		(net "P5E_PEX3_STN5_TX_DP<95>")
	)
	(segment
		(start 420.679626 -319.971928)
		(end 420.679626 -313.59475)
		(width 0.1143)
		(layer "In13.Cu")
		(net "P5E_PEX3_STN5_TX_DP<95>")
	)
	(segment
		(start 418.013134 -328.010012)
		(end 420.633906 -323.367654)
		(width 0.1651)
		(layer "In13.Cu")
		(net "P5E_PEX3_STN5_TX_DP<95>")
	)
	(segment
		(start 421.135556 -313.379612)
		(end 421.249856 -313.265312)
		(width 0.1143)
		(layer "In13.Cu")
		(net "P5E_PEX3_STN5_TX_DP<95>")
	)
	(segment
		(start 420.633906 -320.017648)
		(end 420.679626 -319.971928)
		(width 0.1143)
		(layer "In13.Cu")
		(net "P5E_PEX3_STN5_TX_DP<95>")
	)
	(segment
		(start 406.159716 -346.595446)
		(end 406.15997 -346.595446)
		(width 0.1651)
		(layer "In13.Cu")
		(net "P5E_PEX3_STN5_TX_DP<95>")
	)
	(segment
		(start 420.633906 -323.367654)
		(end 420.633906 -320.046096)
		(width 0.1651)
		(layer "In13.Cu")
		(net "P5E_PEX3_STN5_TX_DP<95>")
	)
	(segment
		(start 86.447884 -368.563398)
		(end 86.65464 -368.127026)
		(width 0.1651)
		(layer "In5.Cu")
		(net "P5E_PEX0_STN5_RX_DP<94>")
	)
	(segment
		(start 88.141048 -365.245396)
		(end 91.198192 -357.840026)
		(width 0.1651)
		(layer "In5.Cu")
		(net "P5E_PEX0_STN5_RX_DP<94>")
	)
	(segment
		(start 91.198192 -357.840026)
		(end 91.198192 -341.820754)
		(width 0.1651)
		(layer "In5.Cu")
		(net "P5E_PEX0_STN5_RX_DP<94>")
	)
	(segment
		(start 85.109812 -370.872258)
		(end 85.236812 -370.999258)
		(width 0.1651)
		(layer "In5.Cu")
		(net "P5E_PEX0_STN5_RX_DP<94>")
	)
	(segment
		(start 71.885556 -316.229492)
		(end 71.999856 -316.115192)
		(width 0.1143)
		(layer "In5.Cu")
		(net "P5E_PEX0_STN5_RX_DP<94>")
	)
	(segment
		(start 71.999856 -316.115192)
		(end 71.999856 -315.849762)
		(width 0.1143)
		(layer "In5.Cu")
		(net "P5E_PEX0_STN5_RX_DP<94>")
	)
	(segment
		(start 71.383906 -319.966848)
		(end 71.429626 -319.921128)
		(width 0.1143)
		(layer "In5.Cu")
		(net "P5E_PEX0_STN5_RX_DP<94>")
	)
	(segment
		(start 71.429626 -316.455298)
		(end 71.655432 -316.229492)
		(width 0.1143)
		(layer "In5.Cu")
		(net "P5E_PEX0_STN5_RX_DP<94>")
	)
	(segment
		(start 87.311738 -366.999012)
		(end 87.517986 -366.562894)
		(width 0.1651)
		(layer "In5.Cu")
		(net "P5E_PEX0_STN5_RX_DP<94>")
	)
	(segment
		(start 86.008718 -370.727478)
		(end 86.008718 -369.753642)
		(width 0.1651)
		(layer "In5.Cu")
		(net "P5E_PEX0_STN5_RX_DP<94>")
	)
	(segment
		(start 71.383906 -320.482468)
		(end 71.383906 -319.995296)
		(width 0.1651)
		(layer "In5.Cu")
		(net "P5E_PEX0_STN5_RX_DP<94>")
	)
	(segment
		(start 91.198192 -341.820754)
		(end 90.94089 -341.19947)
		(width 0.1651)
		(layer "In5.Cu")
		(net "P5E_PEX0_STN5_RX_DP<94>")
	)
	(segment
		(start 86.80323 -368.073686)
		(end 87.009478 -367.637568)
		(width 0.1651)
		(layer "In5.Cu")
		(net "P5E_PEX0_STN5_RX_DP<94>")
	)
	(segment
		(start 87.009478 -367.637568)
		(end 87.009732 -367.637568)
		(width 0.1651)
		(layer "In5.Cu")
		(net "P5E_PEX0_STN5_RX_DP<94>")
	)
	(segment
		(start 87.162894 -367.052098)
		(end 87.311738 -366.999012)
		(width 0.1651)
		(layer "In5.Cu")
		(net "P5E_PEX0_STN5_RX_DP<94>")
	)
	(segment
		(start 71.429626 -319.921128)
		(end 71.429626 -316.455298)
		(width 0.1143)
		(layer "In5.Cu")
		(net "P5E_PEX0_STN5_RX_DP<94>")
	)
	(segment
		(start 85.109812 -370.489988)
		(end 85.109812 -370.872258)
		(width 0.1651)
		(layer "In5.Cu")
		(net "P5E_PEX0_STN5_RX_DP<94>")
	)
	(segment
		(start 86.803484 -368.073686)
		(end 86.80323 -368.073686)
		(width 0.1651)
		(layer "In5.Cu")
		(net "P5E_PEX0_STN5_RX_DP<94>")
	)
	(segment
		(start 72.204072 -322.462652)
		(end 71.383906 -320.482468)
		(width 0.1651)
		(layer "In5.Cu")
		(net "P5E_PEX0_STN5_RX_DP<94>")
	)
	(segment
		(start 87.517986 -366.562894)
		(end 87.464646 -366.41405)
		(width 0.1651)
		(layer "In5.Cu")
		(net "P5E_PEX0_STN5_RX_DP<94>")
	)
	(segment
		(start 87.671148 -365.977424)
		(end 87.819992 -365.924338)
		(width 0.1651)
		(layer "In5.Cu")
		(net "P5E_PEX0_STN5_RX_DP<94>")
	)
	(segment
		(start 85.736938 -370.999258)
		(end 86.008718 -370.727478)
		(width 0.1651)
		(layer "In5.Cu")
		(net "P5E_PEX0_STN5_RX_DP<94>")
	)
	(segment
		(start 87.819992 -365.924338)
		(end 88.141048 -365.245396)
		(width 0.1651)
		(layer "In5.Cu")
		(net "P5E_PEX0_STN5_RX_DP<94>")
	)
	(segment
		(start 87.464646 -366.41405)
		(end 87.671148 -365.977424)
		(width 0.1651)
		(layer "In5.Cu")
		(net "P5E_PEX0_STN5_RX_DP<94>")
	)
	(segment
		(start 71.655432 -316.229492)
		(end 71.885556 -316.229492)
		(width 0.1143)
		(layer "In5.Cu")
		(net "P5E_PEX0_STN5_RX_DP<94>")
	)
	(segment
		(start 85.236812 -370.999258)
		(end 85.736938 -370.999258)
		(width 0.1651)
		(layer "In5.Cu")
		(net "P5E_PEX0_STN5_RX_DP<94>")
	)
	(segment
		(start 86.956392 -367.488724)
		(end 87.162894 -367.052098)
		(width 0.1651)
		(layer "In5.Cu")
		(net "P5E_PEX0_STN5_RX_DP<94>")
	)
	(segment
		(start 90.94089 -341.19947)
		(end 72.204072 -322.462652)
		(width 0.1651)
		(layer "In5.Cu")
		(net "P5E_PEX0_STN5_RX_DP<94>")
	)
	(segment
		(start 87.009732 -367.637568)
		(end 86.956392 -367.488724)
		(width 0.1651)
		(layer "In5.Cu")
		(net "P5E_PEX0_STN5_RX_DP<94>")
	)
	(segment
		(start 86.65464 -368.127026)
		(end 86.803484 -368.073686)
		(width 0.1651)
		(layer "In5.Cu")
		(net "P5E_PEX0_STN5_RX_DP<94>")
	)
	(segment
		(start 86.008718 -369.753642)
		(end 86.501224 -368.712242)
		(width 0.1651)
		(layer "In5.Cu")
		(net "P5E_PEX0_STN5_RX_DP<94>")
	)
	(segment
		(start 71.383906 -319.995296)
		(end 71.383906 -319.966848)
		(width 0.1143)
		(layer "In5.Cu")
		(net "P5E_PEX0_STN5_RX_DP<94>")
	)
	(segment
		(start 86.501224 -368.712242)
		(end 86.447884 -368.563398)
		(width 0.1651)
		(layer "In5.Cu")
		(net "P5E_PEX0_STN5_RX_DP<94>")
	)
	(segment
		(start 292.743382 -350.365314)
		(end 293.063422 -350.685354)
		(width 0.13462)
		(layer "F.Cu")
		(net "P5E_PEX2_STN7_TX_C_DP<124>")
	)
	(segment
		(start 293.063422 -351.316798)
		(end 292.768782 -351.611438)
		(width 0.13462)
		(layer "F.Cu")
		(net "P5E_PEX2_STN7_TX_C_DP<124>")
	)
	(segment
		(start 293.063422 -350.685354)
		(end 293.063422 -351.316798)
		(width 0.13462)
		(layer "F.Cu")
		(net "P5E_PEX2_STN7_TX_C_DP<124>")
	)
	(segment
		(start 293.059612 -352.356166)
		(end 291.505132 -353.910646)
		(width 0.1651)
		(layer "In7.Cu")
		(net "P5E_PEX2_STN7_TX_C_DP<124>")
	)
	(segment
		(start 297.134026 -368.779552)
		(end 297.134026 -374.612408)
		(width 0.1651)
		(layer "In7.Cu")
		(net "P5E_PEX2_STN7_TX_C_DP<124>")
	)
	(segment
		(start 296.417238 -367.488978)
		(end 296.382694 -367.609882)
		(width 0.1651)
		(layer "In7.Cu")
		(net "P5E_PEX2_STN7_TX_C_DP<124>")
	)
	(segment
		(start 295.042082 -365.012986)
		(end 295.282366 -365.445802)
		(width 0.1651)
		(layer "In7.Cu")
		(net "P5E_PEX2_STN7_TX_C_DP<124>")
	)
	(segment
		(start 296.176954 -367.056162)
		(end 296.417238 -367.488978)
		(width 0.1651)
		(layer "In7.Cu")
		(net "P5E_PEX2_STN7_TX_C_DP<124>")
	)
	(segment
		(start 291.505132 -358.644952)
		(end 294.71493 -364.424214)
		(width 0.1651)
		(layer "In7.Cu")
		(net "P5E_PEX2_STN7_TX_C_DP<124>")
	)
	(segment
		(start 295.282366 -365.445802)
		(end 295.247822 -365.566706)
		(width 0.1651)
		(layer "In7.Cu")
		(net "P5E_PEX2_STN7_TX_C_DP<124>")
	)
	(segment
		(start 294.680386 -364.545118)
		(end 294.921178 -364.978442)
		(width 0.1651)
		(layer "In7.Cu")
		(net "P5E_PEX2_STN7_TX_C_DP<124>")
	)
	(segment
		(start 295.849802 -366.46739)
		(end 295.815258 -366.588294)
		(width 0.1651)
		(layer "In7.Cu")
		(net "P5E_PEX2_STN7_TX_C_DP<124>")
	)
	(segment
		(start 291.505132 -353.910646)
		(end 291.505132 -358.644952)
		(width 0.1651)
		(layer "In7.Cu")
		(net "P5E_PEX2_STN7_TX_C_DP<124>")
	)
	(segment
		(start 294.921178 -364.978442)
		(end 295.042082 -365.012986)
		(width 0.1651)
		(layer "In7.Cu")
		(net "P5E_PEX2_STN7_TX_C_DP<124>")
	)
	(segment
		(start 296.382694 -367.609882)
		(end 296.623486 -368.043206)
		(width 0.1651)
		(layer "In7.Cu")
		(net "P5E_PEX2_STN7_TX_C_DP<124>")
	)
	(segment
		(start 295.815258 -366.588294)
		(end 296.05605 -367.021618)
		(width 0.1651)
		(layer "In7.Cu")
		(net "P5E_PEX2_STN7_TX_C_DP<124>")
	)
	(segment
		(start 294.71493 -364.424214)
		(end 294.680386 -364.545118)
		(width 0.1651)
		(layer "In7.Cu")
		(net "P5E_PEX2_STN7_TX_C_DP<124>")
	)
	(segment
		(start 293.059612 -351.902268)
		(end 293.059612 -352.356166)
		(width 0.1651)
		(layer "In7.Cu")
		(net "P5E_PEX2_STN7_TX_C_DP<124>")
	)
	(segment
		(start 296.05605 -367.021618)
		(end 296.176954 -367.056162)
		(width 0.1651)
		(layer "In7.Cu")
		(net "P5E_PEX2_STN7_TX_C_DP<124>")
	)
	(segment
		(start 296.289984 -374.772174)
		(end 296.289984 -374.390158)
		(width 0.1651)
		(layer "In7.Cu")
		(net "P5E_PEX2_STN7_TX_C_DP<124>")
	)
	(segment
		(start 295.488614 -366.00003)
		(end 295.609518 -366.034574)
		(width 0.1651)
		(layer "In7.Cu")
		(net "P5E_PEX2_STN7_TX_C_DP<124>")
	)
	(segment
		(start 296.416984 -374.899174)
		(end 296.289984 -374.772174)
		(width 0.1651)
		(layer "In7.Cu")
		(net "P5E_PEX2_STN7_TX_C_DP<124>")
	)
	(segment
		(start 295.247822 -365.566706)
		(end 295.488614 -366.00003)
		(width 0.1651)
		(layer "In7.Cu")
		(net "P5E_PEX2_STN7_TX_C_DP<124>")
	)
	(segment
		(start 297.134026 -374.612408)
		(end 296.84726 -374.899174)
		(width 0.1651)
		(layer "In7.Cu")
		(net "P5E_PEX2_STN7_TX_C_DP<124>")
	)
	(segment
		(start 295.609518 -366.034574)
		(end 295.849802 -366.46739)
		(width 0.1651)
		(layer "In7.Cu")
		(net "P5E_PEX2_STN7_TX_C_DP<124>")
	)
	(segment
		(start 296.623486 -368.043206)
		(end 296.74439 -368.07775)
		(width 0.1651)
		(layer "In7.Cu")
		(net "P5E_PEX2_STN7_TX_C_DP<124>")
	)
	(segment
		(start 292.768782 -351.611438)
		(end 293.059612 -351.902268)
		(width 0.1651)
		(layer "In7.Cu")
		(net "P5E_PEX2_STN7_TX_C_DP<124>")
	)
	(segment
		(start 296.84726 -374.899174)
		(end 296.416984 -374.899174)
		(width 0.1651)
		(layer "In7.Cu")
		(net "P5E_PEX2_STN7_TX_C_DP<124>")
	)
	(segment
		(start 296.74439 -368.07775)
		(end 297.134026 -368.779552)
		(width 0.1651)
		(layer "In7.Cu")
		(net "P5E_PEX2_STN7_TX_C_DP<124>")
	)
	(segment
		(start 341.052404 -355.026722)
		(end 341.347044 -354.732082)
		(width 0.13462)
		(layer "F.Cu")
		(net "P5E_PEX2_STN5_TX_DN<94>")
	)
	(segment
		(start 341.372444 -355.978206)
		(end 341.052404 -355.658166)
		(width 0.13462)
		(layer "F.Cu")
		(net "P5E_PEX2_STN5_TX_DN<94>")
	)
	(segment
		(start 341.052404 -355.658166)
		(end 341.052404 -355.026722)
		(width 0.13462)
		(layer "F.Cu")
		(net "P5E_PEX2_STN5_TX_DN<94>")
	)
	(segment
		(start 304.085498 -311.670192)
		(end 303.934368 -311.670192)
		(width 0.1143)
		(layer "In7.Cu")
		(net "P5E_PEX2_STN5_TX_DN<94>")
	)
	(segment
		(start 303.865788 -319.916048)
		(end 303.865788 -320.348864)
		(width 0.1651)
		(layer "In7.Cu")
		(net "P5E_PEX2_STN5_TX_DN<94>")
	)
	(segment
		(start 303.820068 -311.784492)
		(end 303.820068 -319.84188)
		(width 0.1143)
		(layer "In7.Cu")
		(net "P5E_PEX2_STN5_TX_DN<94>")
	)
	(segment
		(start 341.056214 -353.930966)
		(end 341.056214 -354.441252)
		(width 0.1651)
		(layer "In7.Cu")
		(net "P5E_PEX2_STN5_TX_DN<94>")
	)
	(segment
		(start 341.056214 -354.441252)
		(end 341.347044 -354.732082)
		(width 0.1651)
		(layer "In7.Cu")
		(net "P5E_PEX2_STN5_TX_DN<94>")
	)
	(segment
		(start 342.610694 -341.6554)
		(end 342.610694 -352.376486)
		(width 0.1651)
		(layer "In7.Cu")
		(net "P5E_PEX2_STN5_TX_DN<94>")
	)
	(segment
		(start 307.030628 -322.140072)
		(end 307.488844 -322.32854)
		(width 0.1651)
		(layer "In7.Cu")
		(net "P5E_PEX2_STN5_TX_DN<94>")
	)
	(segment
		(start 304.199798 -311.784492)
		(end 304.085498 -311.670192)
		(width 0.1143)
		(layer "In7.Cu")
		(net "P5E_PEX2_STN5_TX_DN<94>")
	)
	(segment
		(start 342.610694 -352.376486)
		(end 341.056214 -353.930966)
		(width 0.1651)
		(layer "In7.Cu")
		(net "P5E_PEX2_STN5_TX_DN<94>")
	)
	(segment
		(start 327.1266 -330.5302)
		(end 342.2142 -340.7156)
		(width 0.1651)
		(layer "In7.Cu")
		(net "P5E_PEX2_STN5_TX_DN<94>")
	)
	(segment
		(start 307.551074 -322.477892)
		(end 327.1266 -330.5302)
		(width 0.1651)
		(layer "In7.Cu")
		(net "P5E_PEX2_STN5_TX_DN<94>")
	)
	(segment
		(start 304.907188 -321.390264)
		(end 306.881276 -322.202302)
		(width 0.1651)
		(layer "In7.Cu")
		(net "P5E_PEX2_STN5_TX_DN<94>")
	)
	(segment
		(start 304.199798 -312.049922)
		(end 304.199798 -311.784492)
		(width 0.1143)
		(layer "In7.Cu")
		(net "P5E_PEX2_STN5_TX_DN<94>")
	)
	(segment
		(start 303.865788 -320.348864)
		(end 304.907188 -321.390264)
		(width 0.1651)
		(layer "In7.Cu")
		(net "P5E_PEX2_STN5_TX_DN<94>")
	)
	(segment
		(start 303.865788 -319.8876)
		(end 303.865788 -319.916048)
		(width 0.1143)
		(layer "In7.Cu")
		(net "P5E_PEX2_STN5_TX_DN<94>")
	)
	(segment
		(start 306.881276 -322.202302)
		(end 307.030628 -322.140072)
		(width 0.1651)
		(layer "In7.Cu")
		(net "P5E_PEX2_STN5_TX_DN<94>")
	)
	(segment
		(start 342.2142 -340.7156)
		(end 342.610694 -341.6554)
		(width 0.1651)
		(layer "In7.Cu")
		(net "P5E_PEX2_STN5_TX_DN<94>")
	)
	(segment
		(start 307.488844 -322.32854)
		(end 307.551074 -322.477892)
		(width 0.1651)
		(layer "In7.Cu")
		(net "P5E_PEX2_STN5_TX_DN<94>")
	)
	(segment
		(start 303.820068 -319.84188)
		(end 303.865788 -319.8876)
		(width 0.1143)
		(layer "In7.Cu")
		(net "P5E_PEX2_STN5_TX_DN<94>")
	)
	(segment
		(start 303.934368 -311.670192)
		(end 303.820068 -311.784492)
		(width 0.1143)
		(layer "In7.Cu")
		(net "P5E_PEX2_STN5_TX_DN<94>")
	)
	(segment
		(start 422.247314 -30.92069)
		(end 421.953944 -30.62732)
		(width 0.13462)
		(layer "F.Cu")
		(net "P5E_PEX3_STN2_TX_DP<37>")
	)
	(segment
		(start 421.31996 -30.62732)
		(end 421.00119 -30.94609)
		(width 0.13462)
		(layer "F.Cu")
		(net "P5E_PEX3_STN2_TX_DP<37>")
	)
	(segment
		(start 421.953944 -30.62732)
		(end 421.31996 -30.62732)
		(width 0.13462)
		(layer "F.Cu")
		(net "P5E_PEX3_STN2_TX_DP<37>")
	)
	(segment
		(start 425.770294 -33.089596)
		(end 430.493678 -40.682418)
		(width 0.1651)
		(layer "In11.Cu")
		(net "P5E_PEX3_STN2_TX_DP<37>")
	)
	(segment
		(start 409.812998 -115.227608)
		(end 409.132786 -120.737122)
		(width 0.1651)
		(layer "In11.Cu")
		(net "P5E_PEX3_STN2_TX_DP<37>")
	)
	(segment
		(start 436.776876 -64.465962)
		(end 414.571688 -93.486986)
		(width 0.1651)
		(layer "In11.Cu")
		(net "P5E_PEX3_STN2_TX_DP<37>")
	)
	(segment
		(start 424.706288 -32.15132)
		(end 425.056808 -32.50184)
		(width 0.1651)
		(layer "In11.Cu")
		(net "P5E_PEX3_STN2_TX_DP<37>")
	)
	(segment
		(start 411.26029 -107.821222)
		(end 411.07868 -108.750354)
		(width 0.1651)
		(layer "In11.Cu")
		(net "P5E_PEX3_STN2_TX_DP<37>")
	)
	(segment
		(start 425.056808 -32.50184)
		(end 425.182538 -32.50184)
		(width 0.1651)
		(layer "In11.Cu")
		(net "P5E_PEX3_STN2_TX_DP<37>")
	)
	(segment
		(start 423.880026 -31.325058)
		(end 424.230546 -31.675578)
		(width 0.1651)
		(layer "In11.Cu")
		(net "P5E_PEX3_STN2_TX_DP<37>")
	)
	(segment
		(start 424.356276 -31.675578)
		(end 424.706288 -32.02559)
		(width 0.1651)
		(layer "In11.Cu")
		(net "P5E_PEX3_STN2_TX_DP<37>")
	)
	(segment
		(start 409.132786 -120.737122)
		(end 401.633944 -263.298686)
		(width 0.1651)
		(layer "In11.Cu")
		(net "P5E_PEX3_STN2_TX_DP<37>")
	)
	(segment
		(start 437.233822 -48.152812)
		(end 438.289446 -58.547)
		(width 0.1651)
		(layer "In11.Cu")
		(net "P5E_PEX3_STN2_TX_DP<37>")
	)
	(segment
		(start 438.289446 -60.42152)
		(end 437.707278 -62.600586)
		(width 0.1651)
		(layer "In11.Cu")
		(net "P5E_PEX3_STN2_TX_DP<37>")
	)
	(segment
		(start 401.633944 -271.399)
		(end 401.633944 -271.427448)
		(width 0.1143)
		(layer "In11.Cu")
		(net "P5E_PEX3_STN2_TX_DP<37>")
	)
	(segment
		(start 425.182538 -32.50184)
		(end 425.770294 -33.089596)
		(width 0.1651)
		(layer "In11.Cu")
		(net "P5E_PEX3_STN2_TX_DP<37>")
	)
	(segment
		(start 401.894802 -278.420068)
		(end 402.135594 -278.420068)
		(width 0.1143)
		(layer "In11.Cu")
		(net "P5E_PEX3_STN2_TX_DP<37>")
	)
	(segment
		(start 402.135594 -278.420068)
		(end 402.249894 -278.534368)
		(width 0.1143)
		(layer "In11.Cu")
		(net "P5E_PEX3_STN2_TX_DP<37>")
	)
	(segment
		(start 411.07868 -108.750354)
		(end 411.078426 -108.750354)
		(width 0.1651)
		(layer "In11.Cu")
		(net "P5E_PEX3_STN2_TX_DP<37>")
	)
	(segment
		(start 422.247314 -30.92069)
		(end 422.538144 -30.62986)
		(width 0.1651)
		(layer "In11.Cu")
		(net "P5E_PEX3_STN2_TX_DP<37>")
	)
	(segment
		(start 430.493678 -40.682418)
		(end 437.233822 -48.152812)
		(width 0.1651)
		(layer "In11.Cu")
		(net "P5E_PEX3_STN2_TX_DP<37>")
	)
	(segment
		(start 401.633944 -263.298686)
		(end 401.633944 -271.399)
		(width 0.1651)
		(layer "In11.Cu")
		(net "P5E_PEX3_STN2_TX_DP<37>")
	)
	(segment
		(start 424.706288 -32.02559)
		(end 424.706288 -32.15132)
		(width 0.1651)
		(layer "In11.Cu")
		(net "P5E_PEX3_STN2_TX_DP<37>")
	)
	(segment
		(start 401.679664 -278.20493)
		(end 401.894802 -278.420068)
		(width 0.1143)
		(layer "In11.Cu")
		(net "P5E_PEX3_STN2_TX_DP<37>")
	)
	(segment
		(start 401.679664 -271.473168)
		(end 401.679664 -278.20493)
		(width 0.1143)
		(layer "In11.Cu")
		(net "P5E_PEX3_STN2_TX_DP<37>")
	)
	(segment
		(start 423.419778 -30.73908)
		(end 423.880026 -31.199328)
		(width 0.1651)
		(layer "In11.Cu")
		(net "P5E_PEX3_STN2_TX_DP<37>")
	)
	(segment
		(start 422.538144 -30.62986)
		(end 423.156126 -30.62986)
		(width 0.1651)
		(layer "In11.Cu")
		(net "P5E_PEX3_STN2_TX_DP<37>")
	)
	(segment
		(start 438.289446 -58.547)
		(end 438.289446 -60.42152)
		(width 0.1651)
		(layer "In11.Cu")
		(net "P5E_PEX3_STN2_TX_DP<37>")
	)
	(segment
		(start 410.898086 -109.674152)
		(end 410.717492 -110.598458)
		(width 0.1651)
		(layer "In11.Cu")
		(net "P5E_PEX3_STN2_TX_DP<37>")
	)
	(segment
		(start 402.249894 -278.534368)
		(end 402.249894 -278.799798)
		(width 0.1143)
		(layer "In11.Cu")
		(net "P5E_PEX3_STN2_TX_DP<37>")
	)
	(segment
		(start 410.897832 -109.674152)
		(end 410.898086 -109.674152)
		(width 0.1651)
		(layer "In11.Cu")
		(net "P5E_PEX3_STN2_TX_DP<37>")
	)
	(segment
		(start 424.230546 -31.675578)
		(end 424.356276 -31.675578)
		(width 0.1651)
		(layer "In11.Cu")
		(net "P5E_PEX3_STN2_TX_DP<37>")
	)
	(segment
		(start 414.571688 -93.486986)
		(end 411.26029 -107.821222)
		(width 0.1651)
		(layer "In11.Cu")
		(net "P5E_PEX3_STN2_TX_DP<37>")
	)
	(segment
		(start 437.707278 -62.600586)
		(end 436.776876 -64.465962)
		(width 0.1651)
		(layer "In11.Cu")
		(net "P5E_PEX3_STN2_TX_DP<37>")
	)
	(segment
		(start 423.156126 -30.62986)
		(end 423.419778 -30.73908)
		(width 0.1651)
		(layer "In11.Cu")
		(net "P5E_PEX3_STN2_TX_DP<37>")
	)
	(segment
		(start 410.717492 -110.598458)
		(end 409.812998 -115.227608)
		(width 0.1651)
		(layer "In11.Cu")
		(net "P5E_PEX3_STN2_TX_DP<37>")
	)
	(segment
		(start 423.880026 -31.199328)
		(end 423.880026 -31.325058)
		(width 0.1651)
		(layer "In11.Cu")
		(net "P5E_PEX3_STN2_TX_DP<37>")
	)
	(segment
		(start 401.633944 -271.427448)
		(end 401.679664 -271.473168)
		(width 0.1143)
		(layer "In11.Cu")
		(net "P5E_PEX3_STN2_TX_DP<37>")
	)
	(segment
		(start 411.078426 -108.750354)
		(end 410.897832 -109.674152)
		(width 0.1651)
		(layer "In11.Cu")
		(net "P5E_PEX3_STN2_TX_DP<37>")
	)
	(segment
		(start 81.89087 -370.844318)
		(end 81.89087 -369.89258)
		(width 0.1651)
		(layer "In5.Cu")
		(net "P5E_PEX0_STN5_RX_DN<92>")
	)
	(segment
		(start 80.710024 -371.790214)
		(end 80.710024 -371.408198)
		(width 0.1651)
		(layer "In5.Cu")
		(net "P5E_PEX0_STN5_RX_DN<92>")
	)
	(segment
		(start 69.985636 -316.419992)
		(end 70.099936 -316.534292)
		(width 0.1143)
		(layer "In5.Cu")
		(net "P5E_PEX0_STN5_RX_DN<92>")
	)
	(segment
		(start 84.98078 -359.706926)
		(end 85.262212 -357.8098)
		(width 0.1651)
		(layer "In5.Cu")
		(net "P5E_PEX0_STN5_RX_DN<92>")
	)
	(segment
		(start 85.262212 -357.8098)
		(end 85.262212 -341.96274)
		(width 0.1651)
		(layer "In5.Cu")
		(net "P5E_PEX0_STN5_RX_DN<92>")
	)
	(segment
		(start 80.837024 -371.281198)
		(end 81.45399 -371.281198)
		(width 0.1651)
		(layer "In5.Cu")
		(net "P5E_PEX0_STN5_RX_DN<92>")
	)
	(segment
		(start 70.780402 -323.407024)
		(end 69.765926 -320.95694)
		(width 0.1651)
		(layer "In5.Cu")
		(net "P5E_PEX0_STN5_RX_DN<92>")
	)
	(segment
		(start 84.501228 -340.12505)
		(end 70.780402 -323.407024)
		(width 0.1651)
		(layer "In5.Cu")
		(net "P5E_PEX0_STN5_RX_DN<92>")
	)
	(segment
		(start 85.262212 -341.96274)
		(end 84.501228 -340.12505)
		(width 0.1651)
		(layer "In5.Cu")
		(net "P5E_PEX0_STN5_RX_DN<92>")
	)
	(segment
		(start 69.765926 -319.995296)
		(end 69.765926 -319.966848)
		(width 0.1143)
		(layer "In5.Cu")
		(net "P5E_PEX0_STN5_RX_DN<92>")
	)
	(segment
		(start 83.161378 -365.704628)
		(end 83.161632 -365.703866)
		(width 0.1651)
		(layer "In5.Cu")
		(net "P5E_PEX0_STN5_RX_DN<92>")
	)
	(segment
		(start 81.89087 -369.89258)
		(end 83.161378 -365.704628)
		(width 0.1651)
		(layer "In5.Cu")
		(net "P5E_PEX0_STN5_RX_DN<92>")
	)
	(segment
		(start 70.099936 -316.534292)
		(end 70.099936 -316.799722)
		(width 0.1143)
		(layer "In5.Cu")
		(net "P5E_PEX0_STN5_RX_DN<92>")
	)
	(segment
		(start 81.45399 -371.281198)
		(end 81.89087 -370.844318)
		(width 0.1651)
		(layer "In5.Cu")
		(net "P5E_PEX0_STN5_RX_DN<92>")
	)
	(segment
		(start 69.720206 -316.534292)
		(end 69.834506 -316.419992)
		(width 0.1143)
		(layer "In5.Cu")
		(net "P5E_PEX0_STN5_RX_DN<92>")
	)
	(segment
		(start 80.710024 -371.408198)
		(end 80.837024 -371.281198)
		(width 0.1651)
		(layer "In5.Cu")
		(net "P5E_PEX0_STN5_RX_DN<92>")
	)
	(segment
		(start 83.161632 -365.703866)
		(end 84.98078 -359.706926)
		(width 0.1651)
		(layer "In5.Cu")
		(net "P5E_PEX0_STN5_RX_DN<92>")
	)
	(segment
		(start 69.765926 -319.966848)
		(end 69.720206 -319.921128)
		(width 0.1143)
		(layer "In5.Cu")
		(net "P5E_PEX0_STN5_RX_DN<92>")
	)
	(segment
		(start 69.720206 -319.921128)
		(end 69.720206 -316.534292)
		(width 0.1143)
		(layer "In5.Cu")
		(net "P5E_PEX0_STN5_RX_DN<92>")
	)
	(segment
		(start 69.834506 -316.419992)
		(end 69.985636 -316.419992)
		(width 0.1143)
		(layer "In5.Cu")
		(net "P5E_PEX0_STN5_RX_DN<92>")
	)
	(segment
		(start 69.765926 -320.95694)
		(end 69.765926 -319.995296)
		(width 0.1651)
		(layer "In5.Cu")
		(net "P5E_PEX0_STN5_RX_DN<92>")
	)
	(segment
		(start 296.766742 -356.511606)
		(end 296.446702 -356.831646)
		(width 0.13462)
		(layer "F.Cu")
		(net "P5E_PEX2_STN7_TX_C_DN<126>")
	)
	(segment
		(start 296.446702 -357.46309)
		(end 296.741342 -357.75773)
		(width 0.13462)
		(layer "F.Cu")
		(net "P5E_PEX2_STN7_TX_C_DN<126>")
	)
	(segment
		(start 296.446702 -356.831646)
		(end 296.446702 -357.46309)
		(width 0.13462)
		(layer "F.Cu")
		(net "P5E_PEX2_STN7_TX_C_DN<126>")
	)
	(segment
		(start 300.816772 -375.181114)
		(end 300.689772 -375.308114)
		(width 0.1651)
		(layer "In7.Cu")
		(net "P5E_PEX2_STN7_TX_C_DN<126>")
	)
	(segment
		(start 296.450512 -358.7242)
		(end 301.815754 -368.7572)
		(width 0.1651)
		(layer "In7.Cu")
		(net "P5E_PEX2_STN7_TX_C_DN<126>")
	)
	(segment
		(start 296.741342 -357.75773)
		(end 296.450512 -358.04856)
		(width 0.1651)
		(layer "In7.Cu")
		(net "P5E_PEX2_STN7_TX_C_DN<126>")
	)
	(segment
		(start 301.815754 -374.729248)
		(end 301.363888 -375.181114)
		(width 0.1651)
		(layer "In7.Cu")
		(net "P5E_PEX2_STN7_TX_C_DN<126>")
	)
	(segment
		(start 301.815754 -368.7572)
		(end 301.815754 -374.729248)
		(width 0.1651)
		(layer "In7.Cu")
		(net "P5E_PEX2_STN7_TX_C_DN<126>")
	)
	(segment
		(start 296.450512 -358.04856)
		(end 296.450512 -358.7242)
		(width 0.1651)
		(layer "In7.Cu")
		(net "P5E_PEX2_STN7_TX_C_DN<126>")
	)
	(segment
		(start 300.689772 -375.308114)
		(end 300.689772 -375.69013)
		(width 0.1651)
		(layer "In7.Cu")
		(net "P5E_PEX2_STN7_TX_C_DN<126>")
	)
	(segment
		(start 301.363888 -375.181114)
		(end 300.816772 -375.181114)
		(width 0.1651)
		(layer "In7.Cu")
		(net "P5E_PEX2_STN7_TX_C_DN<126>")
	)
	(segment
		(start 90.241882 -349.831914)
		(end 89.921842 -349.511874)
		(width 0.13462)
		(layer "F.Cu")
		(net "P5E_PEX0_STN6_TX_DN<98>")
	)
	(segment
		(start 89.921842 -349.511874)
		(end 89.921842 -348.88043)
		(width 0.13462)
		(layer "F.Cu")
		(net "P5E_PEX0_STN6_TX_DN<98>")
	)
	(segment
		(start 89.921842 -348.88043)
		(end 90.216482 -348.58579)
		(width 0.13462)
		(layer "F.Cu")
		(net "P5E_PEX0_STN6_TX_DN<98>")
	)
	(segment
		(start 89.925652 -348.29496)
		(end 89.925652 -347.716348)
		(width 0.1651)
		(layer "In13.Cu")
		(net "P5E_PEX0_STN6_TX_DN<98>")
	)
	(segment
		(start 55.515764 -320.114676)
		(end 55.470044 -320.068956)
		(width 0.1143)
		(layer "In13.Cu")
		(net "P5E_PEX0_STN6_TX_DN<98>")
	)
	(segment
		(start 91.480132 -341.670132)
		(end 89.003886 -339.193886)
		(width 0.1651)
		(layer "In13.Cu")
		(net "P5E_PEX0_STN6_TX_DN<98>")
	)
	(segment
		(start 56.587136 -322.956936)
		(end 55.92572 -322.29552)
		(width 0.1651)
		(layer "In13.Cu")
		(net "P5E_PEX0_STN6_TX_DN<98>")
	)
	(segment
		(start 91.480132 -346.161868)
		(end 91.480132 -341.670132)
		(width 0.1651)
		(layer "In13.Cu")
		(net "P5E_PEX0_STN6_TX_DN<98>")
	)
	(segment
		(start 88.967056 -339.174328)
		(end 65.649094 -326.710548)
		(width 0.1651)
		(layer "In13.Cu")
		(net "P5E_PEX0_STN6_TX_DN<98>")
	)
	(segment
		(start 55.515764 -320.136774)
		(end 55.515764 -320.114676)
		(width 0.1143)
		(layer "In13.Cu")
		(net "P5E_PEX0_STN6_TX_DN<98>")
	)
	(segment
		(start 89.003886 -339.193886)
		(end 88.967056 -339.174074)
		(width 0.1651)
		(layer "In13.Cu")
		(net "P5E_PEX0_STN6_TX_DN<98>")
	)
	(segment
		(start 55.760874 -313.570112)
		(end 55.849774 -313.659012)
		(width 0.1143)
		(layer "In13.Cu")
		(net "P5E_PEX0_STN6_TX_DN<98>")
	)
	(segment
		(start 65.649094 -326.710548)
		(end 56.587136 -322.956936)
		(width 0.1651)
		(layer "In13.Cu")
		(net "P5E_PEX0_STN6_TX_DN<98>")
	)
	(segment
		(start 55.92572 -322.29552)
		(end 55.515764 -321.305682)
		(width 0.1651)
		(layer "In13.Cu")
		(net "P5E_PEX0_STN6_TX_DN<98>")
	)
	(segment
		(start 88.967056 -339.174074)
		(end 88.967056 -339.174328)
		(width 0.1651)
		(layer "In13.Cu")
		(net "P5E_PEX0_STN6_TX_DN<98>")
	)
	(segment
		(start 55.849774 -313.659012)
		(end 55.849774 -313.949842)
		(width 0.1143)
		(layer "In13.Cu")
		(net "P5E_PEX0_STN6_TX_DN<98>")
	)
	(segment
		(start 89.925652 -347.716348)
		(end 91.480132 -346.161868)
		(width 0.1651)
		(layer "In13.Cu")
		(net "P5E_PEX0_STN6_TX_DN<98>")
	)
	(segment
		(start 90.216482 -348.58579)
		(end 89.925652 -348.29496)
		(width 0.1651)
		(layer "In13.Cu")
		(net "P5E_PEX0_STN6_TX_DN<98>")
	)
	(segment
		(start 55.470044 -313.697112)
		(end 55.597044 -313.570112)
		(width 0.1143)
		(layer "In13.Cu")
		(net "P5E_PEX0_STN6_TX_DN<98>")
	)
	(segment
		(start 55.597044 -313.570112)
		(end 55.760874 -313.570112)
		(width 0.1143)
		(layer "In13.Cu")
		(net "P5E_PEX0_STN6_TX_DN<98>")
	)
	(segment
		(start 55.470044 -320.068956)
		(end 55.470044 -313.697112)
		(width 0.1143)
		(layer "In13.Cu")
		(net "P5E_PEX0_STN6_TX_DN<98>")
	)
	(segment
		(start 55.515764 -321.305682)
		(end 55.515764 -320.136774)
		(width 0.1651)
		(layer "In13.Cu")
		(net "P5E_PEX0_STN6_TX_DN<98>")
	)
	(segment
		(start 162.480752 -357.46309)
		(end 162.480752 -356.831646)
		(width 0.13462)
		(layer "F.Cu")
		(net "P5E_PEX1_STN7_TX_C_DP<113>")
	)
	(segment
		(start 162.186112 -357.75773)
		(end 162.480752 -357.46309)
		(width 0.13462)
		(layer "F.Cu")
		(net "P5E_PEX1_STN7_TX_C_DP<113>")
	)
	(segment
		(start 162.480752 -356.831646)
		(end 162.160712 -356.511606)
		(width 0.13462)
		(layer "F.Cu")
		(net "P5E_PEX1_STN7_TX_C_DP<113>")
	)
	(segment
		(start 157.499558 -391.759694)
		(end 157.641798 -391.738612)
		(width 0.1651)
		(layer "In11.Cu")
		(net "P5E_PEX1_STN7_TX_C_DP<113>")
	)
	(segment
		(start 152.911048 -385.817618)
		(end 154.303222 -389.260842)
		(width 0.1651)
		(layer "In11.Cu")
		(net "P5E_PEX1_STN7_TX_C_DP<113>")
	)
	(segment
		(start 154.877516 -389.687054)
		(end 154.898598 -389.82904)
		(width 0.1651)
		(layer "In11.Cu")
		(net "P5E_PEX1_STN7_TX_C_DP<113>")
	)
	(segment
		(start 152.65146 -382.826514)
		(end 152.911048 -385.817618)
		(width 0.1651)
		(layer "In11.Cu")
		(net "P5E_PEX1_STN7_TX_C_DP<113>")
	)
	(segment
		(start 162.020758 -394.506958)
		(end 162.020758 -394.650722)
		(width 0.1651)
		(layer "In11.Cu")
		(net "P5E_PEX1_STN7_TX_C_DP<113>")
	)
	(segment
		(start 154.303222 -389.260842)
		(end 154.877516 -389.687054)
		(width 0.1651)
		(layer "In11.Cu")
		(net "P5E_PEX1_STN7_TX_C_DP<113>")
	)
	(segment
		(start 162.476942 -358.04856)
		(end 162.476942 -358.63784)
		(width 0.1651)
		(layer "In11.Cu")
		(net "P5E_PEX1_STN7_TX_C_DP<113>")
	)
	(segment
		(start 162.371278 -395.001242)
		(end 162.515042 -395.001242)
		(width 0.1651)
		(layer "In11.Cu")
		(net "P5E_PEX1_STN7_TX_C_DP<113>")
	)
	(segment
		(start 156.540962 -391.04824)
		(end 156.682948 -391.027158)
		(width 0.1651)
		(layer "In11.Cu")
		(net "P5E_PEX1_STN7_TX_C_DP<113>")
	)
	(segment
		(start 157.080458 -391.322052)
		(end 157.10154 -391.464292)
		(width 0.1651)
		(layer "In11.Cu")
		(net "P5E_PEX1_STN7_TX_C_DP<113>")
	)
	(segment
		(start 162.852608 -401.999196)
		(end 162.236912 -401.999196)
		(width 0.1651)
		(layer "In11.Cu")
		(net "P5E_PEX1_STN7_TX_C_DP<113>")
	)
	(segment
		(start 157.21457 -361.183428)
		(end 154.05735 -364.42396)
		(width 0.1651)
		(layer "In11.Cu")
		(net "P5E_PEX1_STN7_TX_C_DP<113>")
	)
	(segment
		(start 156.142944 -390.752838)
		(end 156.540962 -391.04824)
		(width 0.1651)
		(layer "In11.Cu")
		(net "P5E_PEX1_STN7_TX_C_DP<113>")
	)
	(segment
		(start 162.236912 -401.999196)
		(end 162.109912 -401.872196)
		(width 0.1651)
		(layer "In11.Cu")
		(net "P5E_PEX1_STN7_TX_C_DP<113>")
	)
	(segment
		(start 157.10154 -391.464292)
		(end 157.499558 -391.759694)
		(width 0.1651)
		(layer "In11.Cu")
		(net "P5E_PEX1_STN7_TX_C_DP<113>")
	)
	(segment
		(start 158.600648 -392.450066)
		(end 159.20847 -392.90117)
		(width 0.1651)
		(layer "In11.Cu")
		(net "P5E_PEX1_STN7_TX_C_DP<113>")
	)
	(segment
		(start 161.465006 -393.951206)
		(end 162.020758 -394.506958)
		(width 0.1651)
		(layer "In11.Cu")
		(net "P5E_PEX1_STN7_TX_C_DP<113>")
	)
	(segment
		(start 158.039308 -392.03376)
		(end 158.06039 -392.175746)
		(width 0.1651)
		(layer "In11.Cu")
		(net "P5E_PEX1_STN7_TX_C_DP<113>")
	)
	(segment
		(start 152.837134 -367.651284)
		(end 152.65146 -382.826514)
		(width 0.1651)
		(layer "In11.Cu")
		(net "P5E_PEX1_STN7_TX_C_DP<113>")
	)
	(segment
		(start 155.438602 -390.103614)
		(end 156.121862 -390.610598)
		(width 0.1651)
		(layer "In11.Cu")
		(net "P5E_PEX1_STN7_TX_C_DP<113>")
	)
	(segment
		(start 158.06039 -392.175746)
		(end 158.458408 -392.471148)
		(width 0.1651)
		(layer "In11.Cu")
		(net "P5E_PEX1_STN7_TX_C_DP<113>")
	)
	(segment
		(start 156.121862 -390.610598)
		(end 156.142944 -390.752838)
		(width 0.1651)
		(layer "In11.Cu")
		(net "P5E_PEX1_STN7_TX_C_DP<113>")
	)
	(segment
		(start 161.896044 -359.218738)
		(end 157.21457 -361.183428)
		(width 0.1651)
		(layer "In11.Cu")
		(net "P5E_PEX1_STN7_TX_C_DP<113>")
	)
	(segment
		(start 158.458408 -392.471148)
		(end 158.600648 -392.450066)
		(width 0.1651)
		(layer "In11.Cu")
		(net "P5E_PEX1_STN7_TX_C_DP<113>")
	)
	(segment
		(start 162.476942 -358.63784)
		(end 161.896044 -359.218738)
		(width 0.1651)
		(layer "In11.Cu")
		(net "P5E_PEX1_STN7_TX_C_DP<113>")
	)
	(segment
		(start 162.186112 -357.75773)
		(end 162.476942 -358.04856)
		(width 0.1651)
		(layer "In11.Cu")
		(net "P5E_PEX1_STN7_TX_C_DP<113>")
	)
	(segment
		(start 156.682948 -391.027158)
		(end 157.080458 -391.322052)
		(width 0.1651)
		(layer "In11.Cu")
		(net "P5E_PEX1_STN7_TX_C_DP<113>")
	)
	(segment
		(start 162.99307 -401.858734)
		(end 162.852608 -401.999196)
		(width 0.1651)
		(layer "In11.Cu")
		(net "P5E_PEX1_STN7_TX_C_DP<113>")
	)
	(segment
		(start 157.641798 -391.738612)
		(end 158.039308 -392.03376)
		(width 0.1651)
		(layer "In11.Cu")
		(net "P5E_PEX1_STN7_TX_C_DP<113>")
	)
	(segment
		(start 154.898598 -389.82904)
		(end 155.296616 -390.124696)
		(width 0.1651)
		(layer "In11.Cu")
		(net "P5E_PEX1_STN7_TX_C_DP<113>")
	)
	(segment
		(start 155.296616 -390.124696)
		(end 155.438602 -390.103614)
		(width 0.1651)
		(layer "In11.Cu")
		(net "P5E_PEX1_STN7_TX_C_DP<113>")
	)
	(segment
		(start 162.109912 -401.872196)
		(end 162.109912 -401.49018)
		(width 0.1651)
		(layer "In11.Cu")
		(net "P5E_PEX1_STN7_TX_C_DP<113>")
	)
	(segment
		(start 162.020758 -394.650722)
		(end 162.371278 -395.001242)
		(width 0.1651)
		(layer "In11.Cu")
		(net "P5E_PEX1_STN7_TX_C_DP<113>")
	)
	(segment
		(start 154.05735 -364.42396)
		(end 152.837134 -367.651284)
		(width 0.1651)
		(layer "In11.Cu")
		(net "P5E_PEX1_STN7_TX_C_DP<113>")
	)
	(segment
		(start 162.515042 -395.001242)
		(end 162.99307 -395.47927)
		(width 0.1651)
		(layer "In11.Cu")
		(net "P5E_PEX1_STN7_TX_C_DP<113>")
	)
	(segment
		(start 162.99307 -395.47927)
		(end 162.99307 -401.858734)
		(width 0.1651)
		(layer "In11.Cu")
		(net "P5E_PEX1_STN7_TX_C_DP<113>")
	)
	(segment
		(start 159.20847 -392.90117)
		(end 161.465006 -393.951206)
		(width 0.1651)
		(layer "In11.Cu")
		(net "P5E_PEX1_STN7_TX_C_DP<113>")
	)
	(segment
		(start 319.289684 -348.88043)
		(end 319.584324 -348.58579)
		(width 0.13462)
		(layer "F.Cu")
		(net "P5E_PEX2_STN5_TX_DN<83>")
	)
	(segment
		(start 319.289684 -349.511874)
		(end 319.289684 -348.88043)
		(width 0.13462)
		(layer "F.Cu")
		(net "P5E_PEX2_STN5_TX_DN<83>")
	)
	(segment
		(start 319.609724 -349.831914)
		(end 319.289684 -349.511874)
		(width 0.13462)
		(layer "F.Cu")
		(net "P5E_PEX2_STN5_TX_DN<83>")
	)
	(segment
		(start 293.74973 -313.684412)
		(end 293.74973 -313.949842)
		(width 0.1143)
		(layer "In7.Cu")
		(net "P5E_PEX2_STN5_TX_DN<83>")
	)
	(segment
		(start 293.37 -319.79108)
		(end 293.37 -313.684412)
		(width 0.1143)
		(layer "In7.Cu")
		(net "P5E_PEX2_STN5_TX_DN<83>")
	)
	(segment
		(start 319.584324 -348.58579)
		(end 319.293494 -348.29496)
		(width 0.1651)
		(layer "In7.Cu")
		(net "P5E_PEX2_STN5_TX_DN<83>")
	)
	(segment
		(start 304.328576 -333.575914)
		(end 298.801028 -331.186028)
		(width 0.1651)
		(layer "In7.Cu")
		(net "P5E_PEX2_STN5_TX_DN<83>")
	)
	(segment
		(start 298.801028 -331.186028)
		(end 295.64457 -328.02957)
		(width 0.1651)
		(layer "In7.Cu")
		(net "P5E_PEX2_STN5_TX_DN<83>")
	)
	(segment
		(start 295.64457 -328.02957)
		(end 293.41572 -322.64858)
		(width 0.1651)
		(layer "In7.Cu")
		(net "P5E_PEX2_STN5_TX_DN<83>")
	)
	(segment
		(start 319.293494 -348.29496)
		(end 319.293494 -347.784674)
		(width 0.1651)
		(layer "In7.Cu")
		(net "P5E_PEX2_STN5_TX_DN<83>")
	)
	(segment
		(start 320.847974 -346.230194)
		(end 320.847974 -342.265)
		(width 0.1651)
		(layer "In7.Cu")
		(net "P5E_PEX2_STN5_TX_DN<83>")
	)
	(segment
		(start 304.428652 -333.53629)
		(end 304.328576 -333.575914)
		(width 0.1651)
		(layer "In7.Cu")
		(net "P5E_PEX2_STN5_TX_DN<83>")
	)
	(segment
		(start 293.41572 -319.8368)
		(end 293.37 -319.79108)
		(width 0.1143)
		(layer "In7.Cu")
		(net "P5E_PEX2_STN5_TX_DN<83>")
	)
	(segment
		(start 320.3702 -341.0458)
		(end 319.4304 -340.106)
		(width 0.1651)
		(layer "In7.Cu")
		(net "P5E_PEX2_STN5_TX_DN<83>")
	)
	(segment
		(start 293.4843 -313.570112)
		(end 293.63543 -313.570112)
		(width 0.1143)
		(layer "In7.Cu")
		(net "P5E_PEX2_STN5_TX_DN<83>")
	)
	(segment
		(start 293.41572 -322.64858)
		(end 293.41572 -319.865248)
		(width 0.1651)
		(layer "In7.Cu")
		(net "P5E_PEX2_STN5_TX_DN<83>")
	)
	(segment
		(start 304.883566 -333.73314)
		(end 304.428652 -333.53629)
		(width 0.1651)
		(layer "In7.Cu")
		(net "P5E_PEX2_STN5_TX_DN<83>")
	)
	(segment
		(start 293.63543 -313.570112)
		(end 293.74973 -313.684412)
		(width 0.1143)
		(layer "In7.Cu")
		(net "P5E_PEX2_STN5_TX_DN<83>")
	)
	(segment
		(start 319.293494 -347.784674)
		(end 320.847974 -346.230194)
		(width 0.1651)
		(layer "In7.Cu")
		(net "P5E_PEX2_STN5_TX_DN<83>")
	)
	(segment
		(start 320.847974 -342.265)
		(end 320.3702 -341.0458)
		(width 0.1651)
		(layer "In7.Cu")
		(net "P5E_PEX2_STN5_TX_DN<83>")
	)
	(segment
		(start 293.41572 -319.865248)
		(end 293.41572 -319.8368)
		(width 0.1143)
		(layer "In7.Cu")
		(net "P5E_PEX2_STN5_TX_DN<83>")
	)
	(segment
		(start 293.37 -313.684412)
		(end 293.4843 -313.570112)
		(width 0.1143)
		(layer "In7.Cu")
		(net "P5E_PEX2_STN5_TX_DN<83>")
	)
	(segment
		(start 319.4304 -340.106)
		(end 304.92319 -333.833216)
		(width 0.1651)
		(layer "In7.Cu")
		(net "P5E_PEX2_STN5_TX_DN<83>")
	)
	(segment
		(start 304.92319 -333.833216)
		(end 304.883566 -333.73314)
		(width 0.1651)
		(layer "In7.Cu")
		(net "P5E_PEX2_STN5_TX_DN<83>")
	)
	(segment
		(start 445.312038 -32.1437)
		(end 444.677546 -32.1437)
		(width 0.13462)
		(layer "F.Cu")
		(net "P5E_PEX3_STN2_TX_DN<34>")
	)
	(segment
		(start 445.605154 -31.850584)
		(end 445.312038 -32.1437)
		(width 0.13462)
		(layer "F.Cu")
		(net "P5E_PEX3_STN2_TX_DN<34>")
	)
	(segment
		(start 444.677546 -32.1437)
		(end 444.35903 -31.825184)
		(width 0.13462)
		(layer "F.Cu")
		(net "P5E_PEX3_STN2_TX_DN<34>")
	)
	(segment
		(start 404.765764 -271.399)
		(end 404.765764 -271.427448)
		(width 0.1143)
		(layer "In11.Cu")
		(net "P5E_PEX3_STN2_TX_DN<34>")
	)
	(segment
		(start 423.93235 -161.43859)
		(end 404.765764 -265.666982)
		(width 0.1651)
		(layer "In11.Cu")
		(net "P5E_PEX3_STN2_TX_DN<34>")
	)
	(segment
		(start 455.280776 -41.785794)
		(end 455.509376 -42.652188)
		(width 0.1651)
		(layer "In11.Cu")
		(net "P5E_PEX3_STN2_TX_DN<34>")
	)
	(segment
		(start 425.35094 -149.418294)
		(end 423.93235 -161.43859)
		(width 0.1651)
		(layer "In11.Cu")
		(net "P5E_PEX3_STN2_TX_DN<34>")
	)
	(segment
		(start 455.509376 -42.652188)
		(end 455.760582 -56.75376)
		(width 0.1651)
		(layer "In11.Cu")
		(net "P5E_PEX3_STN2_TX_DN<34>")
	)
	(segment
		(start 426.087794 -140.132816)
		(end 425.679616 -141.883892)
		(width 0.1651)
		(layer "In11.Cu")
		(net "P5E_PEX3_STN2_TX_DN<34>")
	)
	(segment
		(start 445.895984 -32.141414)
		(end 449.263262 -32.141414)
		(width 0.1651)
		(layer "In11.Cu")
		(net "P5E_PEX3_STN2_TX_DN<34>")
	)
	(segment
		(start 450.727064 -75.263756)
		(end 444.213742 -78.775052)
		(width 0.1651)
		(layer "In11.Cu")
		(net "P5E_PEX3_STN2_TX_DN<34>")
	)
	(segment
		(start 450.972174 -33.86836)
		(end 455.280776 -41.785794)
		(width 0.1651)
		(layer "In11.Cu")
		(net "P5E_PEX3_STN2_TX_DN<34>")
	)
	(segment
		(start 455.760582 -56.75376)
		(end 453.543162 -68.266056)
		(width 0.1651)
		(layer "In11.Cu")
		(net "P5E_PEX3_STN2_TX_DN<34>")
	)
	(segment
		(start 442.264038 -80.722724)
		(end 428.316898 -105.301288)
		(width 0.1651)
		(layer "In11.Cu")
		(net "P5E_PEX3_STN2_TX_DN<34>")
	)
	(segment
		(start 425.351702 -149.41169)
		(end 425.351702 -149.413722)
		(width 0.1651)
		(layer "In11.Cu")
		(net "P5E_PEX3_STN2_TX_DN<34>")
	)
	(segment
		(start 449.263262 -32.141414)
		(end 450.972174 -33.86836)
		(width 0.1651)
		(layer "In11.Cu")
		(net "P5E_PEX3_STN2_TX_DN<34>")
	)
	(segment
		(start 426.703236 -118.379748)
		(end 426.087794 -132.513578)
		(width 0.1651)
		(layer "In11.Cu")
		(net "P5E_PEX3_STN2_TX_DN<34>")
	)
	(segment
		(start 426.087794 -132.513578)
		(end 426.087794 -140.132816)
		(width 0.1651)
		(layer "In11.Cu")
		(net "P5E_PEX3_STN2_TX_DN<34>")
	)
	(segment
		(start 404.720044 -271.473168)
		(end 404.720044 -280.025856)
		(width 0.1143)
		(layer "In11.Cu")
		(net "P5E_PEX3_STN2_TX_DN<34>")
	)
	(segment
		(start 404.823676 -280.129488)
		(end 404.985474 -280.129488)
		(width 0.1143)
		(layer "In11.Cu")
		(net "P5E_PEX3_STN2_TX_DN<34>")
	)
	(segment
		(start 445.605154 -31.850584)
		(end 445.895984 -32.141414)
		(width 0.1651)
		(layer "In11.Cu")
		(net "P5E_PEX3_STN2_TX_DN<34>")
	)
	(segment
		(start 428.316898 -105.301288)
		(end 427.50994 -111.841534)
		(width 0.1651)
		(layer "In11.Cu")
		(net "P5E_PEX3_STN2_TX_DN<34>")
	)
	(segment
		(start 425.351448 -149.413976)
		(end 425.35094 -149.418294)
		(width 0.1651)
		(layer "In11.Cu")
		(net "P5E_PEX3_STN2_TX_DN<34>")
	)
	(segment
		(start 425.351702 -149.413722)
		(end 425.351448 -149.413976)
		(width 0.1651)
		(layer "In11.Cu")
		(net "P5E_PEX3_STN2_TX_DN<34>")
	)
	(segment
		(start 444.213742 -78.775052)
		(end 442.264038 -80.722724)
		(width 0.1651)
		(layer "In11.Cu")
		(net "P5E_PEX3_STN2_TX_DN<34>")
	)
	(segment
		(start 451.317614 -74.425556)
		(end 450.727064 -75.263756)
		(width 0.1651)
		(layer "In11.Cu")
		(net "P5E_PEX3_STN2_TX_DN<34>")
	)
	(segment
		(start 404.765764 -271.427448)
		(end 404.720044 -271.473168)
		(width 0.1143)
		(layer "In11.Cu")
		(net "P5E_PEX3_STN2_TX_DN<34>")
	)
	(segment
		(start 425.679616 -141.883892)
		(end 425.351702 -149.41169)
		(width 0.1651)
		(layer "In11.Cu")
		(net "P5E_PEX3_STN2_TX_DN<34>")
	)
	(segment
		(start 404.985474 -280.129488)
		(end 405.099774 -280.015188)
		(width 0.1143)
		(layer "In11.Cu")
		(net "P5E_PEX3_STN2_TX_DN<34>")
	)
	(segment
		(start 427.509686 -111.841534)
		(end 426.703236 -118.379748)
		(width 0.1651)
		(layer "In11.Cu")
		(net "P5E_PEX3_STN2_TX_DN<34>")
	)
	(segment
		(start 405.099774 -280.015188)
		(end 405.099774 -279.749504)
		(width 0.1143)
		(layer "In11.Cu")
		(net "P5E_PEX3_STN2_TX_DN<34>")
	)
	(segment
		(start 404.720044 -280.025856)
		(end 404.823676 -280.129488)
		(width 0.1143)
		(layer "In11.Cu")
		(net "P5E_PEX3_STN2_TX_DN<34>")
	)
	(segment
		(start 404.765764 -265.666982)
		(end 404.765764 -271.399)
		(width 0.1651)
		(layer "In11.Cu")
		(net "P5E_PEX3_STN2_TX_DN<34>")
	)
	(segment
		(start 427.50994 -111.841534)
		(end 427.509686 -111.841534)
		(width 0.1651)
		(layer "In11.Cu")
		(net "P5E_PEX3_STN2_TX_DN<34>")
	)
	(segment
		(start 453.543162 -68.266056)
		(end 451.317614 -74.425556)
		(width 0.1651)
		(layer "In11.Cu")
		(net "P5E_PEX3_STN2_TX_DN<34>")
	)
	(segment
		(start 72.570086 -318.434466)
		(end 72.684386 -318.320166)
		(width 0.1143)
		(layer "In5.Cu")
		(net "P5E_PEX0_STN5_RX_DN<95>")
	)
	(segment
		(start 72.615806 -319.992248)
		(end 72.615806 -319.9638)
		(width 0.1143)
		(layer "In5.Cu")
		(net "P5E_PEX0_STN5_RX_DN<95>")
	)
	(segment
		(start 72.835516 -318.320166)
		(end 72.949816 -318.434466)
		(width 0.1143)
		(layer "In5.Cu")
		(net "P5E_PEX0_STN5_RX_DN<95>")
	)
	(segment
		(start 94.150434 -358.95534)
		(end 94.589092 -357.89616)
		(width 0.1651)
		(layer "In5.Cu")
		(net "P5E_PEX0_STN5_RX_DN<95>")
	)
	(segment
		(start 87.30996 -372.890034)
		(end 87.30996 -372.508018)
		(width 0.1651)
		(layer "In5.Cu")
		(net "P5E_PEX0_STN5_RX_DN<95>")
	)
	(segment
		(start 88.889586 -368.95151)
		(end 92.32646 -361.685078)
		(width 0.1651)
		(layer "In5.Cu")
		(net "P5E_PEX0_STN5_RX_DN<95>")
	)
	(segment
		(start 88.484456 -371.98427)
		(end 88.484456 -370.287296)
		(width 0.1651)
		(layer "In5.Cu")
		(net "P5E_PEX0_STN5_RX_DN<95>")
	)
	(segment
		(start 88.087708 -372.381018)
		(end 88.484456 -371.98427)
		(width 0.1651)
		(layer "In5.Cu")
		(net "P5E_PEX0_STN5_RX_DN<95>")
	)
	(segment
		(start 72.615806 -319.9638)
		(end 72.570086 -319.91808)
		(width 0.1143)
		(layer "In5.Cu")
		(net "P5E_PEX0_STN5_RX_DN<95>")
	)
	(segment
		(start 87.43696 -372.381018)
		(end 88.087708 -372.381018)
		(width 0.1651)
		(layer "In5.Cu")
		(net "P5E_PEX0_STN5_RX_DN<95>")
	)
	(segment
		(start 73.277476 -321.765676)
		(end 72.615806 -320.168524)
		(width 0.1651)
		(layer "In5.Cu")
		(net "P5E_PEX0_STN5_RX_DN<95>")
	)
	(segment
		(start 94.589092 -357.89616)
		(end 94.589092 -342.208358)
		(width 0.1651)
		(layer "In5.Cu")
		(net "P5E_PEX0_STN5_RX_DN<95>")
	)
	(segment
		(start 94.589092 -342.208358)
		(end 94.035626 -341.173054)
		(width 0.1651)
		(layer "In5.Cu")
		(net "P5E_PEX0_STN5_RX_DN<95>")
	)
	(segment
		(start 94.035626 -341.173054)
		(end 84.200238 -332.688438)
		(width 0.1651)
		(layer "In5.Cu")
		(net "P5E_PEX0_STN5_RX_DN<95>")
	)
	(segment
		(start 72.684386 -318.320166)
		(end 72.835516 -318.320166)
		(width 0.1143)
		(layer "In5.Cu")
		(net "P5E_PEX0_STN5_RX_DN<95>")
	)
	(segment
		(start 72.615806 -320.168524)
		(end 72.615806 -319.992248)
		(width 0.1651)
		(layer "In5.Cu")
		(net "P5E_PEX0_STN5_RX_DN<95>")
	)
	(segment
		(start 92.32646 -361.685078)
		(end 94.150434 -358.95534)
		(width 0.1651)
		(layer "In5.Cu")
		(net "P5E_PEX0_STN5_RX_DN<95>")
	)
	(segment
		(start 88.484456 -370.287296)
		(end 88.889586 -368.95151)
		(width 0.1651)
		(layer "In5.Cu")
		(net "P5E_PEX0_STN5_RX_DN<95>")
	)
	(segment
		(start 87.30996 -372.508018)
		(end 87.43696 -372.381018)
		(width 0.1651)
		(layer "In5.Cu")
		(net "P5E_PEX0_STN5_RX_DN<95>")
	)
	(segment
		(start 72.570086 -319.91808)
		(end 72.570086 -318.434466)
		(width 0.1143)
		(layer "In5.Cu")
		(net "P5E_PEX0_STN5_RX_DN<95>")
	)
	(segment
		(start 84.200238 -332.688438)
		(end 73.277476 -321.765676)
		(width 0.1651)
		(layer "In5.Cu")
		(net "P5E_PEX0_STN5_RX_DN<95>")
	)
	(segment
		(start 72.949816 -318.434466)
		(end 72.949816 -318.699896)
		(width 0.1143)
		(layer "In5.Cu")
		(net "P5E_PEX0_STN5_RX_DN<95>")
	)
	(segment
		(start 290.228782 -345.170506)
		(end 290.523422 -345.465146)
		(width 0.13462)
		(layer "F.Cu")
		(net "P5E_PEX2_STN7_TX_C_DP<122>")
	)
	(segment
		(start 290.548822 -344.219022)
		(end 290.228782 -344.539062)
		(width 0.13462)
		(layer "F.Cu")
		(net "P5E_PEX2_STN7_TX_C_DP<122>")
	)
	(segment
		(start 290.228782 -344.539062)
		(end 290.228782 -345.170506)
		(width 0.13462)
		(layer "F.Cu")
		(net "P5E_PEX2_STN7_TX_C_DP<122>")
	)
	(segment
		(start 293.015924 -368.6302)
		(end 293.015924 -374.729248)
		(width 0.1651)
		(layer "In7.Cu")
		(net "P5E_PEX2_STN7_TX_C_DP<122>")
	)
	(segment
		(start 288.678112 -347.881194)
		(end 288.678112 -358.5464)
		(width 0.1651)
		(layer "In7.Cu")
		(net "P5E_PEX2_STN7_TX_C_DP<122>")
	)
	(segment
		(start 291.889942 -375.308114)
		(end 291.889942 -375.69013)
		(width 0.1651)
		(layer "In7.Cu")
		(net "P5E_PEX2_STN7_TX_C_DP<122>")
	)
	(segment
		(start 292.564058 -375.181114)
		(end 292.016942 -375.181114)
		(width 0.1651)
		(layer "In7.Cu")
		(net "P5E_PEX2_STN7_TX_C_DP<122>")
	)
	(segment
		(start 290.232592 -346.326714)
		(end 288.678112 -347.881194)
		(width 0.1651)
		(layer "In7.Cu")
		(net "P5E_PEX2_STN7_TX_C_DP<122>")
	)
	(segment
		(start 292.016942 -375.181114)
		(end 291.889942 -375.308114)
		(width 0.1651)
		(layer "In7.Cu")
		(net "P5E_PEX2_STN7_TX_C_DP<122>")
	)
	(segment
		(start 290.232592 -345.755976)
		(end 290.232592 -346.326714)
		(width 0.1651)
		(layer "In7.Cu")
		(net "P5E_PEX2_STN7_TX_C_DP<122>")
	)
	(segment
		(start 290.523422 -345.465146)
		(end 290.232592 -345.755976)
		(width 0.1651)
		(layer "In7.Cu")
		(net "P5E_PEX2_STN7_TX_C_DP<122>")
	)
	(segment
		(start 288.678112 -358.5464)
		(end 293.015924 -368.6302)
		(width 0.1651)
		(layer "In7.Cu")
		(net "P5E_PEX2_STN7_TX_C_DP<122>")
	)
	(segment
		(start 293.015924 -374.729248)
		(end 292.564058 -375.181114)
		(width 0.1651)
		(layer "In7.Cu")
		(net "P5E_PEX2_STN7_TX_C_DP<122>")
	)
	(segment
		(start 74.697082 -355.978206)
		(end 74.377042 -355.658166)
		(width 0.13462)
		(layer "F.Cu")
		(net "P5E_PEX0_STN6_TX_DN<105>")
	)
	(segment
		(start 74.377042 -355.026722)
		(end 74.671682 -354.732082)
		(width 0.13462)
		(layer "F.Cu")
		(net "P5E_PEX0_STN6_TX_DN<105>")
	)
	(segment
		(start 74.377042 -355.658166)
		(end 74.377042 -355.026722)
		(width 0.13462)
		(layer "F.Cu")
		(net "P5E_PEX0_STN6_TX_DN<105>")
	)
	(segment
		(start 52.483258 -328.495406)
		(end 50.126138 -326.138286)
		(width 0.1651)
		(layer "In13.Cu")
		(net "P5E_PEX0_STN6_TX_DN<105>")
	)
	(segment
		(start 75.349862 -340.509352)
		(end 54.216808 -329.213464)
		(width 0.1651)
		(layer "In13.Cu")
		(net "P5E_PEX0_STN6_TX_DN<105>")
	)
	(segment
		(start 48.86579 -320.13017)
		(end 48.86579 -320.108072)
		(width 0.1143)
		(layer "In13.Cu")
		(net "P5E_PEX0_STN6_TX_DN<105>")
	)
	(segment
		(start 74.671682 -354.732082)
		(end 74.380852 -354.441252)
		(width 0.1651)
		(layer "In13.Cu")
		(net "P5E_PEX0_STN6_TX_DN<105>")
	)
	(segment
		(start 75.935332 -352.197924)
		(end 75.935332 -341.485982)
		(width 0.1651)
		(layer "In13.Cu")
		(net "P5E_PEX0_STN6_TX_DN<105>")
	)
	(segment
		(start 48.86579 -320.108072)
		(end 48.82007 -320.062352)
		(width 0.1143)
		(layer "In13.Cu")
		(net "P5E_PEX0_STN6_TX_DN<105>")
	)
	(segment
		(start 75.935332 -341.485982)
		(end 75.349862 -340.509352)
		(width 0.1651)
		(layer "In13.Cu")
		(net "P5E_PEX0_STN6_TX_DN<105>")
	)
	(segment
		(start 74.380852 -354.441252)
		(end 74.380852 -353.752404)
		(width 0.1651)
		(layer "In13.Cu")
		(net "P5E_PEX0_STN6_TX_DN<105>")
	)
	(segment
		(start 48.82007 -311.797192)
		(end 48.94707 -311.670192)
		(width 0.1143)
		(layer "In13.Cu")
		(net "P5E_PEX0_STN6_TX_DN<105>")
	)
	(segment
		(start 49.1109 -311.670192)
		(end 49.1998 -311.759092)
		(width 0.1143)
		(layer "In13.Cu")
		(net "P5E_PEX0_STN6_TX_DN<105>")
	)
	(segment
		(start 48.82007 -320.062352)
		(end 48.82007 -311.797192)
		(width 0.1143)
		(layer "In13.Cu")
		(net "P5E_PEX0_STN6_TX_DN<105>")
	)
	(segment
		(start 50.126138 -326.138286)
		(end 48.86579 -323.095366)
		(width 0.1651)
		(layer "In13.Cu")
		(net "P5E_PEX0_STN6_TX_DN<105>")
	)
	(segment
		(start 48.86579 -323.095366)
		(end 48.86579 -320.13017)
		(width 0.1651)
		(layer "In13.Cu")
		(net "P5E_PEX0_STN6_TX_DN<105>")
	)
	(segment
		(start 54.216808 -329.213464)
		(end 52.483258 -328.495406)
		(width 0.1651)
		(layer "In13.Cu")
		(net "P5E_PEX0_STN6_TX_DN<105>")
	)
	(segment
		(start 74.380852 -353.752404)
		(end 75.935332 -352.197924)
		(width 0.1651)
		(layer "In13.Cu")
		(net "P5E_PEX0_STN6_TX_DN<105>")
	)
	(segment
		(start 48.94707 -311.670192)
		(end 49.1109 -311.670192)
		(width 0.1143)
		(layer "In13.Cu")
		(net "P5E_PEX0_STN6_TX_DN<105>")
	)
	(segment
		(start 49.1998 -311.759092)
		(end 49.1998 -312.049922)
		(width 0.1143)
		(layer "In13.Cu")
		(net "P5E_PEX0_STN6_TX_DN<105>")
	)
	(segment
		(start 340.778084 -343.365582)
		(end 340.778084 -342.734138)
		(width 0.13462)
		(layer "F.Cu")
		(net "P5E_PEX2_STN5_TX_DP<93>")
	)
	(segment
		(start 340.458044 -343.685622)
		(end 340.778084 -343.365582)
		(width 0.13462)
		(layer "F.Cu")
		(net "P5E_PEX2_STN5_TX_DP<93>")
	)
	(segment
		(start 340.778084 -342.734138)
		(end 340.483444 -342.439498)
		(width 0.13462)
		(layer "F.Cu")
		(net "P5E_PEX2_STN5_TX_DP<93>")
	)
	(segment
		(start 302.679608 -313.605418)
		(end 302.905414 -313.379612)
		(width 0.1143)
		(layer "In7.Cu")
		(net "P5E_PEX2_STN5_TX_DP<93>")
	)
	(segment
		(start 303.249838 -313.265312)
		(end 303.249838 -312.999882)
		(width 0.1143)
		(layer "In7.Cu")
		(net "P5E_PEX2_STN5_TX_DP<93>")
	)
	(segment
		(start 340.774274 -342.148668)
		(end 340.774274 -341.699342)
		(width 0.1651)
		(layer "In7.Cu")
		(net "P5E_PEX2_STN5_TX_DP<93>")
	)
	(segment
		(start 340.77402 -341.699088)
		(end 340.47049 -341.085932)
		(width 0.1651)
		(layer "In7.Cu")
		(net "P5E_PEX2_STN5_TX_DP<93>")
	)
	(segment
		(start 302.633888 -320.50355)
		(end 302.633888 -319.868296)
		(width 0.1651)
		(layer "In7.Cu")
		(net "P5E_PEX2_STN5_TX_DP<93>")
	)
	(segment
		(start 302.633888 -319.839848)
		(end 302.679608 -319.794128)
		(width 0.1143)
		(layer "In7.Cu")
		(net "P5E_PEX2_STN5_TX_DP<93>")
	)
	(segment
		(start 304.380138 -322.660518)
		(end 302.92421 -321.20459)
		(width 0.1651)
		(layer "In7.Cu")
		(net "P5E_PEX2_STN5_TX_DP<93>")
	)
	(segment
		(start 302.633888 -319.868296)
		(end 302.633888 -319.839848)
		(width 0.1143)
		(layer "In7.Cu")
		(net "P5E_PEX2_STN5_TX_DP<93>")
	)
	(segment
		(start 302.905414 -313.379612)
		(end 303.135538 -313.379612)
		(width 0.1143)
		(layer "In7.Cu")
		(net "P5E_PEX2_STN5_TX_DP<93>")
	)
	(segment
		(start 340.774274 -341.699342)
		(end 340.77402 -341.699088)
		(width 0.1651)
		(layer "In7.Cu")
		(net "P5E_PEX2_STN5_TX_DP<93>")
	)
	(segment
		(start 302.92421 -321.20459)
		(end 302.633888 -320.50355)
		(width 0.1651)
		(layer "In7.Cu")
		(net "P5E_PEX2_STN5_TX_DP<93>")
	)
	(segment
		(start 303.135538 -313.379612)
		(end 303.249838 -313.265312)
		(width 0.1143)
		(layer "In7.Cu")
		(net "P5E_PEX2_STN5_TX_DP<93>")
	)
	(segment
		(start 340.483444 -342.439498)
		(end 340.774274 -342.148668)
		(width 0.1651)
		(layer "In7.Cu")
		(net "P5E_PEX2_STN5_TX_DP<93>")
	)
	(segment
		(start 302.679608 -319.794128)
		(end 302.679608 -313.605418)
		(width 0.1143)
		(layer "In7.Cu")
		(net "P5E_PEX2_STN5_TX_DP<93>")
	)
	(segment
		(start 340.47049 -341.085932)
		(end 326.231504 -331.542644)
		(width 0.1651)
		(layer "In7.Cu")
		(net "P5E_PEX2_STN5_TX_DP<93>")
	)
	(segment
		(start 326.231504 -331.542644)
		(end 304.380138 -322.660518)
		(width 0.1651)
		(layer "In7.Cu")
		(net "P5E_PEX2_STN5_TX_DP<93>")
	)
	(segment
		(start 393.244832 -349.512382)
		(end 393.244832 -348.879922)
		(width 0.13462)
		(layer "F.Cu")
		(net "P5E_PEX3_STN5_TX_DP<90>")
	)
	(segment
		(start 392.9253 -349.831914)
		(end 393.244832 -349.512382)
		(width 0.13462)
		(layer "F.Cu")
		(net "P5E_PEX3_STN5_TX_DP<90>")
	)
	(segment
		(start 393.244832 -348.879922)
		(end 392.9507 -348.58579)
		(width 0.13462)
		(layer "F.Cu")
		(net "P5E_PEX3_STN5_TX_DP<90>")
	)
	(segment
		(start 416.385502 -311.479692)
		(end 416.499802 -311.365392)
		(width 0.1143)
		(layer "In13.Cu")
		(net "P5E_PEX3_STN5_TX_DP<90>")
	)
	(segment
		(start 415.883852 -320.046096)
		(end 415.883852 -320.017648)
		(width 0.1143)
		(layer "In13.Cu")
		(net "P5E_PEX3_STN5_TX_DP<90>")
	)
	(segment
		(start 394.79601 -346.113354)
		(end 394.79601 -342.050624)
		(width 0.1651)
		(layer "In13.Cu")
		(net "P5E_PEX3_STN5_TX_DP<90>")
	)
	(segment
		(start 415.929572 -311.69483)
		(end 416.14471 -311.479692)
		(width 0.1143)
		(layer "In13.Cu")
		(net "P5E_PEX3_STN5_TX_DP<90>")
	)
	(segment
		(start 416.499802 -311.365392)
		(end 416.499802 -311.099962)
		(width 0.1143)
		(layer "In13.Cu")
		(net "P5E_PEX3_STN5_TX_DP<90>")
	)
	(segment
		(start 415.883852 -321.6148)
		(end 415.883852 -320.046096)
		(width 0.1651)
		(layer "In13.Cu")
		(net "P5E_PEX3_STN5_TX_DP<90>")
	)
	(segment
		(start 392.9507 -348.58579)
		(end 393.24153 -348.29496)
		(width 0.1651)
		(layer "In13.Cu")
		(net "P5E_PEX3_STN5_TX_DP<90>")
	)
	(segment
		(start 415.929572 -319.971928)
		(end 415.929572 -311.69483)
		(width 0.1143)
		(layer "In13.Cu")
		(net "P5E_PEX3_STN5_TX_DP<90>")
	)
	(segment
		(start 393.24153 -348.29496)
		(end 393.24153 -347.667834)
		(width 0.1651)
		(layer "In13.Cu")
		(net "P5E_PEX3_STN5_TX_DP<90>")
	)
	(segment
		(start 416.14471 -311.479692)
		(end 416.385502 -311.479692)
		(width 0.1143)
		(layer "In13.Cu")
		(net "P5E_PEX3_STN5_TX_DP<90>")
	)
	(segment
		(start 394.79601 -342.050624)
		(end 395.188186 -340.983824)
		(width 0.1651)
		(layer "In13.Cu")
		(net "P5E_PEX3_STN5_TX_DP<90>")
	)
	(segment
		(start 414.235138 -323.939662)
		(end 415.883852 -321.6148)
		(width 0.1651)
		(layer "In13.Cu")
		(net "P5E_PEX3_STN5_TX_DP<90>")
	)
	(segment
		(start 415.883852 -320.017648)
		(end 415.929572 -319.971928)
		(width 0.1143)
		(layer "In13.Cu")
		(net "P5E_PEX3_STN5_TX_DP<90>")
	)
	(segment
		(start 393.24153 -347.667834)
		(end 394.79601 -346.113354)
		(width 0.1651)
		(layer "In13.Cu")
		(net "P5E_PEX3_STN5_TX_DP<90>")
	)
	(segment
		(start 395.188186 -340.983824)
		(end 414.235138 -323.939662)
		(width 0.1651)
		(layer "In13.Cu")
		(net "P5E_PEX3_STN5_TX_DP<90>")
	)
	(segment
		(start 81.60893 -369.85067)
		(end 81.99628 -368.573558)
		(width 0.1651)
		(layer "In5.Cu")
		(net "P5E_PEX0_STN5_RX_DP<92>")
	)
	(segment
		(start 82.752184 -365.696754)
		(end 82.891884 -365.622332)
		(width 0.1651)
		(layer "In5.Cu")
		(net "P5E_PEX0_STN5_RX_DP<92>")
	)
	(segment
		(start 80.837024 -370.999258)
		(end 81.33715 -370.999258)
		(width 0.1651)
		(layer "In5.Cu")
		(net "P5E_PEX0_STN5_RX_DP<92>")
	)
	(segment
		(start 82.686652 -366.298226)
		(end 82.61223 -366.159034)
		(width 0.1651)
		(layer "In5.Cu")
		(net "P5E_PEX0_STN5_RX_DP<92>")
	)
	(segment
		(start 69.483986 -321.013074)
		(end 69.483986 -319.995296)
		(width 0.1651)
		(layer "In5.Cu")
		(net "P5E_PEX0_STN5_RX_DP<92>")
	)
	(segment
		(start 82.89163 -365.622332)
		(end 84.704936 -359.64495)
		(width 0.1651)
		(layer "In5.Cu")
		(net "P5E_PEX0_STN5_RX_DP<92>")
	)
	(segment
		(start 80.710024 -370.489988)
		(end 80.710024 -370.872258)
		(width 0.1651)
		(layer "In5.Cu")
		(net "P5E_PEX0_STN5_RX_DP<92>")
	)
	(segment
		(start 82.54619 -366.759998)
		(end 82.686398 -366.298226)
		(width 0.1651)
		(layer "In5.Cu")
		(net "P5E_PEX0_STN5_RX_DP<92>")
	)
	(segment
		(start 82.406998 -366.83442)
		(end 82.546698 -366.759998)
		(width 0.1651)
		(layer "In5.Cu")
		(net "P5E_PEX0_STN5_RX_DP<92>")
	)
	(segment
		(start 84.704936 -359.64495)
		(end 84.980272 -357.788972)
		(width 0.1651)
		(layer "In5.Cu")
		(net "P5E_PEX0_STN5_RX_DP<92>")
	)
	(segment
		(start 69.755512 -316.229492)
		(end 69.985636 -316.229492)
		(width 0.1143)
		(layer "In5.Cu")
		(net "P5E_PEX0_STN5_RX_DP<92>")
	)
	(segment
		(start 82.201258 -367.897664)
		(end 82.341466 -367.435892)
		(width 0.1651)
		(layer "In5.Cu")
		(net "P5E_PEX0_STN5_RX_DP<92>")
	)
	(segment
		(start 70.5358 -323.553582)
		(end 69.483986 -321.013074)
		(width 0.1651)
		(layer "In5.Cu")
		(net "P5E_PEX0_STN5_RX_DP<92>")
	)
	(segment
		(start 82.341466 -367.435892)
		(end 82.267044 -367.2967)
		(width 0.1651)
		(layer "In5.Cu")
		(net "P5E_PEX0_STN5_RX_DP<92>")
	)
	(segment
		(start 81.921858 -368.434112)
		(end 82.061812 -367.972086)
		(width 0.1651)
		(layer "In5.Cu")
		(net "P5E_PEX0_STN5_RX_DP<92>")
	)
	(segment
		(start 69.529706 -319.921128)
		(end 69.529706 -316.455298)
		(width 0.1143)
		(layer "In5.Cu")
		(net "P5E_PEX0_STN5_RX_DP<92>")
	)
	(segment
		(start 82.201512 -367.897664)
		(end 82.201258 -367.897664)
		(width 0.1651)
		(layer "In5.Cu")
		(net "P5E_PEX0_STN5_RX_DP<92>")
	)
	(segment
		(start 82.061812 -367.972086)
		(end 82.201512 -367.897664)
		(width 0.1651)
		(layer "In5.Cu")
		(net "P5E_PEX0_STN5_RX_DP<92>")
	)
	(segment
		(start 83.425538 -339.259418)
		(end 83.425792 -339.259418)
		(width 0.1651)
		(layer "In5.Cu")
		(net "P5E_PEX0_STN5_RX_DP<92>")
	)
	(segment
		(start 82.686398 -366.298226)
		(end 82.686652 -366.298226)
		(width 0.1651)
		(layer "In5.Cu")
		(net "P5E_PEX0_STN5_RX_DP<92>")
	)
	(segment
		(start 82.891884 -365.622332)
		(end 82.89163 -365.622332)
		(width 0.1651)
		(layer "In5.Cu")
		(net "P5E_PEX0_STN5_RX_DP<92>")
	)
	(segment
		(start 84.256626 -340.271608)
		(end 83.425538 -339.259418)
		(width 0.1651)
		(layer "In5.Cu")
		(net "P5E_PEX0_STN5_RX_DP<92>")
	)
	(segment
		(start 69.483986 -319.995296)
		(end 69.483986 -319.966848)
		(width 0.1143)
		(layer "In5.Cu")
		(net "P5E_PEX0_STN5_RX_DP<92>")
	)
	(segment
		(start 69.483986 -319.966848)
		(end 69.529706 -319.921128)
		(width 0.1143)
		(layer "In5.Cu")
		(net "P5E_PEX0_STN5_RX_DP<92>")
	)
	(segment
		(start 69.985636 -316.229492)
		(end 70.099936 -316.115192)
		(width 0.1143)
		(layer "In5.Cu")
		(net "P5E_PEX0_STN5_RX_DP<92>")
	)
	(segment
		(start 84.980272 -357.788972)
		(end 84.980272 -342.018874)
		(width 0.1651)
		(layer "In5.Cu")
		(net "P5E_PEX0_STN5_RX_DP<92>")
	)
	(segment
		(start 69.529706 -316.455298)
		(end 69.755512 -316.229492)
		(width 0.1143)
		(layer "In5.Cu")
		(net "P5E_PEX0_STN5_RX_DP<92>")
	)
	(segment
		(start 70.099936 -316.115192)
		(end 70.099936 -315.849762)
		(width 0.1143)
		(layer "In5.Cu")
		(net "P5E_PEX0_STN5_RX_DP<92>")
	)
	(segment
		(start 81.33715 -370.999258)
		(end 81.60893 -370.727478)
		(width 0.1651)
		(layer "In5.Cu")
		(net "P5E_PEX0_STN5_RX_DP<92>")
	)
	(segment
		(start 82.267044 -367.2967)
		(end 82.406998 -366.83442)
		(width 0.1651)
		(layer "In5.Cu")
		(net "P5E_PEX0_STN5_RX_DP<92>")
	)
	(segment
		(start 84.980272 -342.018874)
		(end 84.256626 -340.271608)
		(width 0.1651)
		(layer "In5.Cu")
		(net "P5E_PEX0_STN5_RX_DP<92>")
	)
	(segment
		(start 81.60893 -370.727478)
		(end 81.60893 -369.85067)
		(width 0.1651)
		(layer "In5.Cu")
		(net "P5E_PEX0_STN5_RX_DP<92>")
	)
	(segment
		(start 82.61223 -366.159034)
		(end 82.752184 -365.696754)
		(width 0.1651)
		(layer "In5.Cu")
		(net "P5E_PEX0_STN5_RX_DP<92>")
	)
	(segment
		(start 82.546698 -366.759998)
		(end 82.54619 -366.759998)
		(width 0.1651)
		(layer "In5.Cu")
		(net "P5E_PEX0_STN5_RX_DP<92>")
	)
	(segment
		(start 80.710024 -370.872258)
		(end 80.837024 -370.999258)
		(width 0.1651)
		(layer "In5.Cu")
		(net "P5E_PEX0_STN5_RX_DP<92>")
	)
	(segment
		(start 83.425792 -339.259418)
		(end 70.5358 -323.553582)
		(width 0.1651)
		(layer "In5.Cu")
		(net "P5E_PEX0_STN5_RX_DP<92>")
	)
	(segment
		(start 81.99628 -368.573558)
		(end 81.921858 -368.434112)
		(width 0.1651)
		(layer "In5.Cu")
		(net "P5E_PEX0_STN5_RX_DP<92>")
	)
	(segment
		(start 84.023962 -349.831914)
		(end 83.703922 -349.511874)
		(width 0.13462)
		(layer "F.Cu")
		(net "P5E_PEX0_STN6_TX_DN<101>")
	)
	(segment
		(start 83.703922 -349.511874)
		(end 83.703922 -348.88043)
		(width 0.13462)
		(layer "F.Cu")
		(net "P5E_PEX0_STN6_TX_DN<101>")
	)
	(segment
		(start 83.703922 -348.88043)
		(end 83.998562 -348.58579)
		(width 0.13462)
		(layer "F.Cu")
		(net "P5E_PEX0_STN6_TX_DN<101>")
	)
	(segment
		(start 84.466176 -340.614762)
		(end 59.464956 -327.25106)
		(width 0.1651)
		(layer "In13.Cu")
		(net "P5E_PEX0_STN6_TX_DN<101>")
	)
	(segment
		(start 52.999894 -311.759092)
		(end 52.999894 -312.049922)
		(width 0.1143)
		(layer "In13.Cu")
		(net "P5E_PEX0_STN6_TX_DN<101>")
	)
	(segment
		(start 59.464956 -327.25106)
		(end 54.646068 -325.255128)
		(width 0.1651)
		(layer "In13.Cu")
		(net "P5E_PEX0_STN6_TX_DN<101>")
	)
	(segment
		(start 52.910994 -311.670192)
		(end 52.999894 -311.759092)
		(width 0.1143)
		(layer "In13.Cu")
		(net "P5E_PEX0_STN6_TX_DN<101>")
	)
	(segment
		(start 52.620164 -311.797192)
		(end 52.747164 -311.670192)
		(width 0.1143)
		(layer "In13.Cu")
		(net "P5E_PEX0_STN6_TX_DN<101>")
	)
	(segment
		(start 83.707732 -348.29496)
		(end 83.707732 -347.716348)
		(width 0.1651)
		(layer "In13.Cu")
		(net "P5E_PEX0_STN6_TX_DN<101>")
	)
	(segment
		(start 85.262212 -346.161868)
		(end 85.262212 -341.942928)
		(width 0.1651)
		(layer "In13.Cu")
		(net "P5E_PEX0_STN6_TX_DN<101>")
	)
	(segment
		(start 52.620164 -320.226182)
		(end 52.620164 -311.797192)
		(width 0.1143)
		(layer "In13.Cu")
		(net "P5E_PEX0_STN6_TX_DN<101>")
	)
	(segment
		(start 85.262212 -341.942928)
		(end 84.466176 -340.614762)
		(width 0.1651)
		(layer "In13.Cu")
		(net "P5E_PEX0_STN6_TX_DN<101>")
	)
	(segment
		(start 83.998562 -348.58579)
		(end 83.707732 -348.29496)
		(width 0.1651)
		(layer "In13.Cu")
		(net "P5E_PEX0_STN6_TX_DN<101>")
	)
	(segment
		(start 53.666136 -324.275196)
		(end 52.665884 -321.860418)
		(width 0.1651)
		(layer "In13.Cu")
		(net "P5E_PEX0_STN6_TX_DN<101>")
	)
	(segment
		(start 52.665884 -320.271902)
		(end 52.620164 -320.226182)
		(width 0.1143)
		(layer "In13.Cu")
		(net "P5E_PEX0_STN6_TX_DN<101>")
	)
	(segment
		(start 52.665884 -321.860418)
		(end 52.665884 -320.294)
		(width 0.1651)
		(layer "In13.Cu")
		(net "P5E_PEX0_STN6_TX_DN<101>")
	)
	(segment
		(start 52.665884 -320.294)
		(end 52.665884 -320.271902)
		(width 0.1143)
		(layer "In13.Cu")
		(net "P5E_PEX0_STN6_TX_DN<101>")
	)
	(segment
		(start 54.646068 -325.255128)
		(end 53.666136 -324.275196)
		(width 0.1651)
		(layer "In13.Cu")
		(net "P5E_PEX0_STN6_TX_DN<101>")
	)
	(segment
		(start 52.747164 -311.670192)
		(end 52.910994 -311.670192)
		(width 0.1143)
		(layer "In13.Cu")
		(net "P5E_PEX0_STN6_TX_DN<101>")
	)
	(segment
		(start 83.707732 -347.716348)
		(end 85.262212 -346.161868)
		(width 0.1651)
		(layer "In13.Cu")
		(net "P5E_PEX0_STN6_TX_DN<101>")
	)
	(segment
		(start 305.221386 -33.95218)
		(end 304.901092 -33.631886)
		(width 0.13462)
		(layer "F.Cu")
		(net "P5E_PEX2_STN2_TX_DN<39>")
	)
	(segment
		(start 306.147216 -33.657286)
		(end 305.852322 -33.95218)
		(width 0.13462)
		(layer "F.Cu")
		(net "P5E_PEX2_STN2_TX_DN<39>")
	)
	(segment
		(start 305.852322 -33.95218)
		(end 305.221386 -33.95218)
		(width 0.13462)
		(layer "F.Cu")
		(net "P5E_PEX2_STN2_TX_DN<39>")
	)
	(segment
		(start 292.1254 -114.480086)
		(end 291.37864 -120.544336)
		(width 0.1651)
		(layer "In11.Cu")
		(net "P5E_PEX2_STN2_TX_DN<39>")
	)
	(segment
		(start 320.47688 -58.541412)
		(end 320.47688 -60.165234)
		(width 0.1651)
		(layer "In11.Cu")
		(net "P5E_PEX2_STN2_TX_DN<39>")
	)
	(segment
		(start 284.249876 -278.115268)
		(end 284.249876 -277.849838)
		(width 0.1143)
		(layer "In11.Cu")
		(net "P5E_PEX2_STN2_TX_DN<39>")
	)
	(segment
		(start 291.378132 -120.544336)
		(end 291.265864 -121.457974)
		(width 0.1651)
		(layer "In11.Cu")
		(net "P5E_PEX2_STN2_TX_DN<39>")
	)
	(segment
		(start 283.973778 -278.229568)
		(end 284.135576 -278.229568)
		(width 0.1143)
		(layer "In11.Cu")
		(net "P5E_PEX2_STN2_TX_DN<39>")
	)
	(segment
		(start 320.47688 -60.165234)
		(end 319.976246 -62.053724)
		(width 0.1651)
		(layer "In11.Cu")
		(net "P5E_PEX2_STN2_TX_DN<39>")
	)
	(segment
		(start 296.83075 -92.81541)
		(end 293.546022 -107.220512)
		(width 0.1651)
		(layer "In11.Cu")
		(net "P5E_PEX2_STN2_TX_DN<39>")
	)
	(segment
		(start 293.546022 -107.220512)
		(end 292.1254 -114.480086)
		(width 0.1651)
		(layer "In11.Cu")
		(net "P5E_PEX2_STN2_TX_DN<39>")
	)
	(segment
		(start 312.89498 -41.84396)
		(end 319.482216 -49.033938)
		(width 0.1651)
		(layer "In11.Cu")
		(net "P5E_PEX2_STN2_TX_DN<39>")
	)
	(segment
		(start 283.870146 -271.473168)
		(end 283.870146 -278.125936)
		(width 0.1143)
		(layer "In11.Cu")
		(net "P5E_PEX2_STN2_TX_DN<39>")
	)
	(segment
		(start 309.22595 -35.848798)
		(end 312.89498 -41.84396)
		(width 0.1651)
		(layer "In11.Cu")
		(net "P5E_PEX2_STN2_TX_DN<39>")
	)
	(segment
		(start 319.482216 -49.033938)
		(end 320.47688 -58.541412)
		(width 0.1651)
		(layer "In11.Cu")
		(net "P5E_PEX2_STN2_TX_DN<39>")
	)
	(segment
		(start 306.438046 -33.948116)
		(end 307.011832 -33.948116)
		(width 0.1651)
		(layer "In11.Cu")
		(net "P5E_PEX2_STN2_TX_DN<39>")
	)
	(segment
		(start 306.147216 -33.657286)
		(end 306.438046 -33.948116)
		(width 0.1651)
		(layer "In11.Cu")
		(net "P5E_PEX2_STN2_TX_DN<39>")
	)
	(segment
		(start 284.135576 -278.229568)
		(end 284.249876 -278.115268)
		(width 0.1143)
		(layer "In11.Cu")
		(net "P5E_PEX2_STN2_TX_DN<39>")
	)
	(segment
		(start 283.915866 -271.399)
		(end 283.915866 -271.427448)
		(width 0.1143)
		(layer "In11.Cu")
		(net "P5E_PEX2_STN2_TX_DN<39>")
	)
	(segment
		(start 307.57114 -34.181034)
		(end 309.22595 -35.848798)
		(width 0.1651)
		(layer "In11.Cu")
		(net "P5E_PEX2_STN2_TX_DN<39>")
	)
	(segment
		(start 283.915866 -262.799068)
		(end 283.915866 -271.399)
		(width 0.1651)
		(layer "In11.Cu")
		(net "P5E_PEX2_STN2_TX_DN<39>")
	)
	(segment
		(start 307.011832 -33.948116)
		(end 307.57114 -34.181034)
		(width 0.1651)
		(layer "In11.Cu")
		(net "P5E_PEX2_STN2_TX_DN<39>")
	)
	(segment
		(start 283.870146 -278.125936)
		(end 283.973778 -278.229568)
		(width 0.1143)
		(layer "In11.Cu")
		(net "P5E_PEX2_STN2_TX_DN<39>")
	)
	(segment
		(start 291.37864 -120.544336)
		(end 291.378132 -120.544336)
		(width 0.1651)
		(layer "In11.Cu")
		(net "P5E_PEX2_STN2_TX_DN<39>")
	)
	(segment
		(start 291.265864 -121.457974)
		(end 283.915866 -262.799068)
		(width 0.1651)
		(layer "In11.Cu")
		(net "P5E_PEX2_STN2_TX_DN<39>")
	)
	(segment
		(start 319.08242 -63.834518)
		(end 296.83075 -92.81541)
		(width 0.1651)
		(layer "In11.Cu")
		(net "P5E_PEX2_STN2_TX_DN<39>")
	)
	(segment
		(start 283.915866 -271.427448)
		(end 283.870146 -271.473168)
		(width 0.1143)
		(layer "In11.Cu")
		(net "P5E_PEX2_STN2_TX_DN<39>")
	)
	(segment
		(start 319.976246 -62.053724)
		(end 319.08242 -63.834518)
		(width 0.1651)
		(layer "In11.Cu")
		(net "P5E_PEX2_STN2_TX_DN<39>")
	)
	(segment
		(start 395.9606 -34.23412)
		(end 395.313408 -34.23412)
		(width 0.13462)
		(layer "F.Cu")
		(net "P5E_PEX3_STN2_TX_DP<43>")
	)
	(segment
		(start 395.313408 -34.23412)
		(end 395.001242 -34.546286)
		(width 0.13462)
		(layer "F.Cu")
		(net "P5E_PEX3_STN2_TX_DP<43>")
	)
	(segment
		(start 396.247366 -34.520886)
		(end 395.9606 -34.23412)
		(width 0.13462)
		(layer "F.Cu")
		(net "P5E_PEX3_STN2_TX_DP<43>")
	)
	(segment
		(start 392.642344 -112.80267)
		(end 391.097262 -115.113054)
		(width 0.1651)
		(layer "In11.Cu")
		(net "P5E_PEX3_STN2_TX_DP<43>")
	)
	(segment
		(start 410.344112 -60.343288)
		(end 408.8638 -68.413884)
		(width 0.1651)
		(layer "In11.Cu")
		(net "P5E_PEX3_STN2_TX_DP<43>")
	)
	(segment
		(start 395.93393 -269.63751)
		(end 395.93393 -271.399)
		(width 0.1651)
		(layer "In11.Cu")
		(net "P5E_PEX3_STN2_TX_DP<43>")
	)
	(segment
		(start 401.003008 -38.507924)
		(end 409.278328 -49.270158)
		(width 0.1651)
		(layer "In11.Cu")
		(net "P5E_PEX3_STN2_TX_DP<43>")
	)
	(segment
		(start 395.97965 -278.20493)
		(end 396.194788 -278.420068)
		(width 0.1143)
		(layer "In11.Cu")
		(net "P5E_PEX3_STN2_TX_DP<43>")
	)
	(segment
		(start 396.965424 -101.587808)
		(end 393.831064 -111.631222)
		(width 0.1651)
		(layer "In11.Cu")
		(net "P5E_PEX3_STN2_TX_DP<43>")
	)
	(segment
		(start 395.93393 -271.427448)
		(end 395.97965 -271.473168)
		(width 0.1143)
		(layer "In11.Cu")
		(net "P5E_PEX3_STN2_TX_DP<43>")
	)
	(segment
		(start 400.290792 -37.581586)
		(end 400.592544 -37.974016)
		(width 0.1651)
		(layer "In11.Cu")
		(net "P5E_PEX3_STN2_TX_DP<43>")
	)
	(segment
		(start 398.652492 -95.389446)
		(end 396.965424 -101.587808)
		(width 0.1651)
		(layer "In11.Cu")
		(net "P5E_PEX3_STN2_TX_DP<43>")
	)
	(segment
		(start 409.717494 -50.549048)
		(end 410.344112 -60.343288)
		(width 0.1651)
		(layer "In11.Cu")
		(net "P5E_PEX3_STN2_TX_DP<43>")
	)
	(segment
		(start 408.8638 -68.413884)
		(end 398.652492 -95.389446)
		(width 0.1651)
		(layer "In11.Cu")
		(net "P5E_PEX3_STN2_TX_DP<43>")
	)
	(segment
		(start 399.864072 -37.172392)
		(end 400.166078 -37.56533)
		(width 0.1651)
		(layer "In11.Cu")
		(net "P5E_PEX3_STN2_TX_DP<43>")
	)
	(segment
		(start 396.194788 -278.420068)
		(end 396.43558 -278.420068)
		(width 0.1143)
		(layer "In11.Cu")
		(net "P5E_PEX3_STN2_TX_DP<43>")
	)
	(segment
		(start 396.247366 -34.520886)
		(end 396.538196 -34.230056)
		(width 0.1651)
		(layer "In11.Cu")
		(net "P5E_PEX3_STN2_TX_DP<43>")
	)
	(segment
		(start 396.54988 -278.534368)
		(end 396.54988 -278.799798)
		(width 0.1143)
		(layer "In11.Cu")
		(net "P5E_PEX3_STN2_TX_DP<43>")
	)
	(segment
		(start 396.43558 -278.420068)
		(end 396.54988 -278.534368)
		(width 0.1143)
		(layer "In11.Cu")
		(net "P5E_PEX3_STN2_TX_DP<43>")
	)
	(segment
		(start 395.97965 -271.473168)
		(end 395.97965 -278.20493)
		(width 0.1143)
		(layer "In11.Cu")
		(net "P5E_PEX3_STN2_TX_DP<43>")
	)
	(segment
		(start 391.097262 -115.113054)
		(end 390.819386 -116.42979)
		(width 0.1651)
		(layer "In11.Cu")
		(net "P5E_PEX3_STN2_TX_DP<43>")
	)
	(segment
		(start 391.874756 -162.54476)
		(end 395.55293 -265.771376)
		(width 0.1651)
		(layer "In11.Cu")
		(net "P5E_PEX3_STN2_TX_DP<43>")
	)
	(segment
		(start 393.831064 -111.631222)
		(end 392.642344 -112.80267)
		(width 0.1651)
		(layer "In11.Cu")
		(net "P5E_PEX3_STN2_TX_DP<43>")
	)
	(segment
		(start 395.55293 -265.771376)
		(end 395.93393 -269.63751)
		(width 0.1651)
		(layer "In11.Cu")
		(net "P5E_PEX3_STN2_TX_DP<43>")
	)
	(segment
		(start 395.93393 -271.399)
		(end 395.93393 -271.427448)
		(width 0.1143)
		(layer "In11.Cu")
		(net "P5E_PEX3_STN2_TX_DP<43>")
	)
	(segment
		(start 409.278328 -49.270158)
		(end 409.717494 -50.549048)
		(width 0.1651)
		(layer "In11.Cu")
		(net "P5E_PEX3_STN2_TX_DP<43>")
	)
	(segment
		(start 397.34109 -34.230056)
		(end 399.039842 -35.954716)
		(width 0.1651)
		(layer "In11.Cu")
		(net "P5E_PEX3_STN2_TX_DP<43>")
	)
	(segment
		(start 400.878548 -38.491668)
		(end 401.003008 -38.507924)
		(width 0.1651)
		(layer "In11.Cu")
		(net "P5E_PEX3_STN2_TX_DP<43>")
	)
	(segment
		(start 400.592544 -37.974016)
		(end 400.576288 -38.09873)
		(width 0.1651)
		(layer "In11.Cu")
		(net "P5E_PEX3_STN2_TX_DP<43>")
	)
	(segment
		(start 399.880328 -37.047678)
		(end 399.864072 -37.172392)
		(width 0.1651)
		(layer "In11.Cu")
		(net "P5E_PEX3_STN2_TX_DP<43>")
	)
	(segment
		(start 390.819386 -116.42979)
		(end 390.811512 -146.815048)
		(width 0.1651)
		(layer "In11.Cu")
		(net "P5E_PEX3_STN2_TX_DP<43>")
	)
	(segment
		(start 400.576288 -38.09873)
		(end 400.878548 -38.491668)
		(width 0.1651)
		(layer "In11.Cu")
		(net "P5E_PEX3_STN2_TX_DP<43>")
	)
	(segment
		(start 400.166078 -37.56533)
		(end 400.290792 -37.581586)
		(width 0.1651)
		(layer "In11.Cu")
		(net "P5E_PEX3_STN2_TX_DP<43>")
	)
	(segment
		(start 399.039842 -35.954716)
		(end 399.880074 -37.047678)
		(width 0.1651)
		(layer "In11.Cu")
		(net "P5E_PEX3_STN2_TX_DP<43>")
	)
	(segment
		(start 390.811512 -146.815048)
		(end 391.874756 -162.54476)
		(width 0.1651)
		(layer "In11.Cu")
		(net "P5E_PEX3_STN2_TX_DP<43>")
	)
	(segment
		(start 399.880074 -37.047678)
		(end 399.880328 -37.047678)
		(width 0.1651)
		(layer "In11.Cu")
		(net "P5E_PEX3_STN2_TX_DP<43>")
	)
	(segment
		(start 396.538196 -34.230056)
		(end 397.34109 -34.230056)
		(width 0.1651)
		(layer "In11.Cu")
		(net "P5E_PEX3_STN2_TX_DP<43>")
	)
	(segment
		(start 38.280848 -351.316798)
		(end 38.280848 -350.685354)
		(width 0.13462)
		(layer "F.Cu")
		(net "P5E_PEX0_STN7_TX_C_DN<121>")
	)
	(segment
		(start 37.986208 -351.611438)
		(end 38.280848 -351.316798)
		(width 0.13462)
		(layer "F.Cu")
		(net "P5E_PEX0_STN7_TX_C_DN<121>")
	)
	(segment
		(start 38.280848 -350.685354)
		(end 37.960808 -350.365314)
		(width 0.13462)
		(layer "F.Cu")
		(net "P5E_PEX0_STN7_TX_C_DN<121>")
	)
	(segment
		(start 32.39897 -365.76254)
		(end 32.554926 -365.71936)
		(width 0.1651)
		(layer "In7.Cu")
		(net "P5E_PEX0_STN7_TX_C_DN<121>")
	)
	(segment
		(start 32.554926 -365.71936)
		(end 32.79902 -365.288576)
		(width 0.1651)
		(layer "In7.Cu")
		(net "P5E_PEX0_STN7_TX_C_DN<121>")
	)
	(segment
		(start 31.002478 -369.655598)
		(end 31.591758 -367.419382)
		(width 0.1651)
		(layer "In7.Cu")
		(net "P5E_PEX0_STN7_TX_C_DN<121>")
	)
	(segment
		(start 36.722558 -358.362504)
		(end 36.722558 -353.990402)
		(width 0.1651)
		(layer "In7.Cu")
		(net "P5E_PEX0_STN7_TX_C_DN<121>")
	)
	(segment
		(start 30.852618 -375.999248)
		(end 31.002478 -375.849388)
		(width 0.1651)
		(layer "In7.Cu")
		(net "P5E_PEX0_STN7_TX_C_DN<121>")
	)
	(segment
		(start 38.277038 -351.902268)
		(end 37.986208 -351.611438)
		(width 0.1651)
		(layer "In7.Cu")
		(net "P5E_PEX0_STN7_TX_C_DN<121>")
	)
	(segment
		(start 32.75584 -365.13262)
		(end 33.000188 -364.701582)
		(width 0.1651)
		(layer "In7.Cu")
		(net "P5E_PEX0_STN7_TX_C_DN<121>")
	)
	(segment
		(start 33.15589 -364.658402)
		(end 36.722558 -358.362504)
		(width 0.1651)
		(layer "In7.Cu")
		(net "P5E_PEX0_STN7_TX_C_DN<121>")
	)
	(segment
		(start 30.236922 -375.999248)
		(end 30.852618 -375.999248)
		(width 0.1651)
		(layer "In7.Cu")
		(net "P5E_PEX0_STN7_TX_C_DN<121>")
	)
	(segment
		(start 33.000188 -364.701582)
		(end 33.15589 -364.658402)
		(width 0.1651)
		(layer "In7.Cu")
		(net "P5E_PEX0_STN7_TX_C_DN<121>")
	)
	(segment
		(start 32.154622 -366.193832)
		(end 32.39897 -365.76254)
		(width 0.1651)
		(layer "In7.Cu")
		(net "P5E_PEX0_STN7_TX_C_DN<121>")
	)
	(segment
		(start 36.722558 -353.990402)
		(end 38.277038 -352.435922)
		(width 0.1651)
		(layer "In7.Cu")
		(net "P5E_PEX0_STN7_TX_C_DN<121>")
	)
	(segment
		(start 31.591758 -367.419382)
		(end 32.197802 -366.349534)
		(width 0.1651)
		(layer "In7.Cu")
		(net "P5E_PEX0_STN7_TX_C_DN<121>")
	)
	(segment
		(start 30.109922 -375.872248)
		(end 30.236922 -375.999248)
		(width 0.1651)
		(layer "In7.Cu")
		(net "P5E_PEX0_STN7_TX_C_DN<121>")
	)
	(segment
		(start 30.109922 -375.490232)
		(end 30.109922 -375.872248)
		(width 0.1651)
		(layer "In7.Cu")
		(net "P5E_PEX0_STN7_TX_C_DN<121>")
	)
	(segment
		(start 32.79902 -365.288576)
		(end 32.75584 -365.13262)
		(width 0.1651)
		(layer "In7.Cu")
		(net "P5E_PEX0_STN7_TX_C_DN<121>")
	)
	(segment
		(start 32.197802 -366.349534)
		(end 32.154622 -366.193832)
		(width 0.1651)
		(layer "In7.Cu")
		(net "P5E_PEX0_STN7_TX_C_DN<121>")
	)
	(segment
		(start 31.002478 -375.849388)
		(end 31.002478 -369.655598)
		(width 0.1651)
		(layer "In7.Cu")
		(net "P5E_PEX0_STN7_TX_C_DN<121>")
	)
	(segment
		(start 38.277038 -352.435922)
		(end 38.277038 -351.902268)
		(width 0.1651)
		(layer "In7.Cu")
		(net "P5E_PEX0_STN7_TX_C_DN<121>")
	)
	(segment
		(start 337.669124 -349.511874)
		(end 337.669124 -348.88043)
		(width 0.13462)
		(layer "F.Cu")
		(net "P5E_PEX2_STN5_TX_DP<92>")
	)
	(segment
		(start 337.349084 -349.831914)
		(end 337.669124 -349.511874)
		(width 0.13462)
		(layer "F.Cu")
		(net "P5E_PEX2_STN5_TX_DP<92>")
	)
	(segment
		(start 337.669124 -348.88043)
		(end 337.374484 -348.58579)
		(width 0.13462)
		(layer "F.Cu")
		(net "P5E_PEX2_STN5_TX_DP<92>")
	)
	(segment
		(start 301.729648 -311.705498)
		(end 301.955454 -311.479692)
		(width 0.1143)
		(layer "In7.Cu")
		(net "P5E_PEX2_STN5_TX_DP<92>")
	)
	(segment
		(start 337.374484 -348.58579)
		(end 337.665314 -348.29496)
		(width 0.1651)
		(layer "In7.Cu")
		(net "P5E_PEX2_STN5_TX_DP<92>")
	)
	(segment
		(start 339.219794 -342.14562)
		(end 338.977224 -341.583518)
		(width 0.1651)
		(layer "In7.Cu")
		(net "P5E_PEX2_STN5_TX_DP<92>")
	)
	(segment
		(start 337.665314 -347.667834)
		(end 339.219794 -346.113354)
		(width 0.1651)
		(layer "In7.Cu")
		(net "P5E_PEX2_STN5_TX_DP<92>")
	)
	(segment
		(start 337.665314 -348.29496)
		(end 337.665314 -347.667834)
		(width 0.1651)
		(layer "In7.Cu")
		(net "P5E_PEX2_STN5_TX_DP<92>")
	)
	(segment
		(start 302.288448 -321.948048)
		(end 301.683928 -320.488818)
		(width 0.1651)
		(layer "In7.Cu")
		(net "P5E_PEX2_STN5_TX_DP<92>")
	)
	(segment
		(start 338.322412 -340.882224)
		(end 325.421244 -332.434692)
		(width 0.1651)
		(layer "In7.Cu")
		(net "P5E_PEX2_STN5_TX_DP<92>")
	)
	(segment
		(start 301.955454 -311.479692)
		(end 302.185578 -311.479692)
		(width 0.1143)
		(layer "In7.Cu")
		(net "P5E_PEX2_STN5_TX_DP<92>")
	)
	(segment
		(start 338.977224 -341.583518)
		(end 338.322412 -340.882224)
		(width 0.1651)
		(layer "In7.Cu")
		(net "P5E_PEX2_STN5_TX_DP<92>")
	)
	(segment
		(start 301.729648 -319.84188)
		(end 301.729648 -311.705498)
		(width 0.1143)
		(layer "In7.Cu")
		(net "P5E_PEX2_STN5_TX_DP<92>")
	)
	(segment
		(start 301.683928 -319.8876)
		(end 301.729648 -319.84188)
		(width 0.1143)
		(layer "In7.Cu")
		(net "P5E_PEX2_STN5_TX_DP<92>")
	)
	(segment
		(start 325.421244 -332.434692)
		(end 304.076354 -323.736208)
		(width 0.1651)
		(layer "In7.Cu")
		(net "P5E_PEX2_STN5_TX_DP<92>")
	)
	(segment
		(start 301.683928 -320.488818)
		(end 301.683928 -319.916048)
		(width 0.1651)
		(layer "In7.Cu")
		(net "P5E_PEX2_STN5_TX_DP<92>")
	)
	(segment
		(start 339.219794 -346.113354)
		(end 339.219794 -342.14562)
		(width 0.1651)
		(layer "In7.Cu")
		(net "P5E_PEX2_STN5_TX_DP<92>")
	)
	(segment
		(start 302.299878 -311.365392)
		(end 302.299878 -311.099962)
		(width 0.1143)
		(layer "In7.Cu")
		(net "P5E_PEX2_STN5_TX_DP<92>")
	)
	(segment
		(start 302.185578 -311.479692)
		(end 302.299878 -311.365392)
		(width 0.1143)
		(layer "In7.Cu")
		(net "P5E_PEX2_STN5_TX_DP<92>")
	)
	(segment
		(start 301.683928 -319.916048)
		(end 301.683928 -319.8876)
		(width 0.1143)
		(layer "In7.Cu")
		(net "P5E_PEX2_STN5_TX_DP<92>")
	)
	(segment
		(start 304.076354 -323.736208)
		(end 302.288448 -321.948048)
		(width 0.1651)
		(layer "In7.Cu")
		(net "P5E_PEX2_STN5_TX_DP<92>")
	)
	(segment
		(start 395.959076 -30.6324)
		(end 395.314932 -30.6324)
		(width 0.13462)
		(layer "F.Cu")
		(net "P5E_PEX3_STN2_TX_DP<41>")
	)
	(segment
		(start 395.314932 -30.6324)
		(end 395.001242 -30.94609)
		(width 0.13462)
		(layer "F.Cu")
		(net "P5E_PEX3_STN2_TX_DP<41>")
	)
	(segment
		(start 396.247366 -30.92069)
		(end 395.959076 -30.6324)
		(width 0.13462)
		(layer "F.Cu")
		(net "P5E_PEX3_STN2_TX_DP<41>")
	)
	(segment
		(start 397.87957 -271.473168)
		(end 397.87957 -278.20493)
		(width 0.1143)
		(layer "In11.Cu")
		(net "P5E_PEX3_STN2_TX_DP<41>")
	)
	(segment
		(start 398.4498 -278.534368)
		(end 398.4498 -278.799798)
		(width 0.1143)
		(layer "In11.Cu")
		(net "P5E_PEX3_STN2_TX_DP<41>")
	)
	(segment
		(start 397.83385 -271.399)
		(end 397.83385 -271.427448)
		(width 0.1143)
		(layer "In11.Cu")
		(net "P5E_PEX3_STN2_TX_DP<41>")
	)
	(segment
		(start 410.971746 -48.194976)
		(end 411.639004 -50.122074)
		(width 0.1651)
		(layer "In11.Cu")
		(net "P5E_PEX3_STN2_TX_DP<41>")
	)
	(segment
		(start 396.932912 -30.62986)
		(end 397.260572 -30.764734)
		(width 0.1651)
		(layer "In11.Cu")
		(net "P5E_PEX3_STN2_TX_DP<41>")
	)
	(segment
		(start 397.607282 -31.10865)
		(end 397.60779 -31.10865)
		(width 0.1651)
		(layer "In11.Cu")
		(net "P5E_PEX3_STN2_TX_DP<41>")
	)
	(segment
		(start 398.789906 -32.406082)
		(end 398.915636 -32.405574)
		(width 0.1651)
		(layer "In11.Cu")
		(net "P5E_PEX3_STN2_TX_DP<41>")
	)
	(segment
		(start 397.87957 -278.20493)
		(end 398.094708 -278.420068)
		(width 0.1143)
		(layer "In11.Cu")
		(net "P5E_PEX3_STN2_TX_DP<41>")
	)
	(segment
		(start 404.767796 -119.906288)
		(end 404.741634 -120.218454)
		(width 0.1651)
		(layer "In11.Cu")
		(net "P5E_PEX3_STN2_TX_DP<41>")
	)
	(segment
		(start 398.437354 -31.931356)
		(end 398.437862 -32.057086)
		(width 0.1651)
		(layer "In11.Cu")
		(net "P5E_PEX3_STN2_TX_DP<41>")
	)
	(segment
		(start 397.83385 -271.427448)
		(end 397.87957 -271.473168)
		(width 0.1143)
		(layer "In11.Cu")
		(net "P5E_PEX3_STN2_TX_DP<41>")
	)
	(segment
		(start 411.778196 -69.600318)
		(end 404.820628 -119.281194)
		(width 0.1651)
		(layer "In11.Cu")
		(net "P5E_PEX3_STN2_TX_DP<41>")
	)
	(segment
		(start 398.085818 -31.582868)
		(end 398.437354 -31.931356)
		(width 0.1651)
		(layer "In11.Cu")
		(net "P5E_PEX3_STN2_TX_DP<41>")
	)
	(segment
		(start 404.820628 -119.281194)
		(end 404.794212 -119.593868)
		(width 0.1651)
		(layer "In11.Cu")
		(net "P5E_PEX3_STN2_TX_DP<41>")
	)
	(segment
		(start 397.260572 -30.764734)
		(end 397.607282 -31.10865)
		(width 0.1651)
		(layer "In11.Cu")
		(net "P5E_PEX3_STN2_TX_DP<41>")
	)
	(segment
		(start 397.469868 -266.144502)
		(end 397.83385 -269.841726)
		(width 0.1651)
		(layer "In11.Cu")
		(net "P5E_PEX3_STN2_TX_DP<41>")
	)
	(segment
		(start 411.639004 -50.122074)
		(end 412.289752 -60.55106)
		(width 0.1651)
		(layer "In11.Cu")
		(net "P5E_PEX3_STN2_TX_DP<41>")
	)
	(segment
		(start 412.289752 -60.55106)
		(end 411.778196 -69.600318)
		(width 0.1651)
		(layer "In11.Cu")
		(net "P5E_PEX3_STN2_TX_DP<41>")
	)
	(segment
		(start 396.247366 -30.92069)
		(end 396.538196 -30.62986)
		(width 0.1651)
		(layer "In11.Cu")
		(net "P5E_PEX3_STN2_TX_DP<41>")
	)
	(segment
		(start 397.608298 -31.23438)
		(end 397.960088 -31.583376)
		(width 0.1651)
		(layer "In11.Cu")
		(net "P5E_PEX3_STN2_TX_DP<41>")
	)
	(segment
		(start 397.60779 -31.10865)
		(end 397.608298 -31.23438)
		(width 0.1651)
		(layer "In11.Cu")
		(net "P5E_PEX3_STN2_TX_DP<41>")
	)
	(segment
		(start 404.794212 -119.593868)
		(end 404.76805 -119.906288)
		(width 0.1651)
		(layer "In11.Cu")
		(net "P5E_PEX3_STN2_TX_DP<41>")
	)
	(segment
		(start 398.915636 -32.405574)
		(end 399.766028 -33.2486)
		(width 0.1651)
		(layer "In11.Cu")
		(net "P5E_PEX3_STN2_TX_DP<41>")
	)
	(segment
		(start 399.766028 -33.2486)
		(end 401.094702 -35.429444)
		(width 0.1651)
		(layer "In11.Cu")
		(net "P5E_PEX3_STN2_TX_DP<41>")
	)
	(segment
		(start 398.094708 -278.420068)
		(end 398.3355 -278.420068)
		(width 0.1143)
		(layer "In11.Cu")
		(net "P5E_PEX3_STN2_TX_DP<41>")
	)
	(segment
		(start 403.49043 -135.143494)
		(end 397.11757 -252.658372)
		(width 0.1651)
		(layer "In11.Cu")
		(net "P5E_PEX3_STN2_TX_DP<41>")
	)
	(segment
		(start 404.76805 -119.906288)
		(end 404.767796 -119.906288)
		(width 0.1651)
		(layer "In11.Cu")
		(net "P5E_PEX3_STN2_TX_DP<41>")
	)
	(segment
		(start 397.960088 -31.583376)
		(end 398.085818 -31.582868)
		(width 0.1651)
		(layer "In11.Cu")
		(net "P5E_PEX3_STN2_TX_DP<41>")
	)
	(segment
		(start 404.741634 -120.219724)
		(end 403.49043 -135.143494)
		(width 0.1651)
		(layer "In11.Cu")
		(net "P5E_PEX3_STN2_TX_DP<41>")
	)
	(segment
		(start 397.83385 -269.841726)
		(end 397.83385 -271.399)
		(width 0.1651)
		(layer "In11.Cu")
		(net "P5E_PEX3_STN2_TX_DP<41>")
	)
	(segment
		(start 398.437862 -32.057086)
		(end 398.789906 -32.406082)
		(width 0.1651)
		(layer "In11.Cu")
		(net "P5E_PEX3_STN2_TX_DP<41>")
	)
	(segment
		(start 396.538196 -30.62986)
		(end 396.932912 -30.62986)
		(width 0.1651)
		(layer "In11.Cu")
		(net "P5E_PEX3_STN2_TX_DP<41>")
	)
	(segment
		(start 401.094702 -35.429444)
		(end 410.971746 -48.194976)
		(width 0.1651)
		(layer "In11.Cu")
		(net "P5E_PEX3_STN2_TX_DP<41>")
	)
	(segment
		(start 404.741634 -120.218454)
		(end 404.741634 -120.219724)
		(width 0.1651)
		(layer "In11.Cu")
		(net "P5E_PEX3_STN2_TX_DP<41>")
	)
	(segment
		(start 398.3355 -278.420068)
		(end 398.4498 -278.534368)
		(width 0.1143)
		(layer "In11.Cu")
		(net "P5E_PEX3_STN2_TX_DP<41>")
	)
	(segment
		(start 397.11757 -252.658372)
		(end 397.469868 -266.144502)
		(width 0.1651)
		(layer "In11.Cu")
		(net "P5E_PEX3_STN2_TX_DP<41>")
	)
	(segment
		(start 35.171888 -356.831646)
		(end 34.851848 -356.511606)
		(width 0.13462)
		(layer "F.Cu")
		(net "P5E_PEX0_STN7_TX_C_DP<120>")
	)
	(segment
		(start 34.877248 -357.75773)
		(end 35.171888 -357.46309)
		(width 0.13462)
		(layer "F.Cu")
		(net "P5E_PEX0_STN7_TX_C_DP<120>")
	)
	(segment
		(start 35.171888 -357.46309)
		(end 35.171888 -356.831646)
		(width 0.13462)
		(layer "F.Cu")
		(net "P5E_PEX0_STN7_TX_C_DP<120>")
	)
	(segment
		(start 28.80233 -374.490488)
		(end 28.393644 -374.899174)
		(width 0.1651)
		(layer "In7.Cu")
		(net "P5E_PEX0_STN7_TX_C_DP<120>")
	)
	(segment
		(start 27.910028 -374.772174)
		(end 27.910028 -374.390158)
		(width 0.1651)
		(layer "In7.Cu")
		(net "P5E_PEX0_STN7_TX_C_DP<120>")
	)
	(segment
		(start 35.168078 -358.795066)
		(end 28.80233 -368.321844)
		(width 0.1651)
		(layer "In7.Cu")
		(net "P5E_PEX0_STN7_TX_C_DP<120>")
	)
	(segment
		(start 28.393644 -374.899174)
		(end 28.037028 -374.899174)
		(width 0.1651)
		(layer "In7.Cu")
		(net "P5E_PEX0_STN7_TX_C_DP<120>")
	)
	(segment
		(start 34.877248 -357.75773)
		(end 35.168078 -358.04856)
		(width 0.1651)
		(layer "In7.Cu")
		(net "P5E_PEX0_STN7_TX_C_DP<120>")
	)
	(segment
		(start 28.037028 -374.899174)
		(end 27.910028 -374.772174)
		(width 0.1651)
		(layer "In7.Cu")
		(net "P5E_PEX0_STN7_TX_C_DP<120>")
	)
	(segment
		(start 35.168078 -358.04856)
		(end 35.168078 -358.795066)
		(width 0.1651)
		(layer "In7.Cu")
		(net "P5E_PEX0_STN7_TX_C_DP<120>")
	)
	(segment
		(start 28.80233 -368.321844)
		(end 28.80233 -374.490488)
		(width 0.1651)
		(layer "In7.Cu")
		(net "P5E_PEX0_STN7_TX_C_DP<120>")
	)
	(segment
		(start 303.505108 -32.714184)
		(end 303.201324 -32.4104)
		(width 0.13462)
		(layer "F.Cu")
		(net "P5E_PEX2_STN2_TX_DP<38>")
	)
	(segment
		(start 302.588168 -32.4104)
		(end 302.258984 -32.739584)
		(width 0.13462)
		(layer "F.Cu")
		(net "P5E_PEX2_STN2_TX_DP<38>")
	)
	(segment
		(start 303.201324 -32.4104)
		(end 302.588168 -32.4104)
		(width 0.13462)
		(layer "F.Cu")
		(net "P5E_PEX2_STN2_TX_DP<38>")
	)
	(segment
		(start 285.085536 -280.319988)
		(end 284.844744 -280.319988)
		(width 0.1143)
		(layer "In11.Cu")
		(net "P5E_PEX2_STN2_TX_DP<38>")
	)
	(segment
		(start 304.701194 -32.524954)
		(end 304.599594 -32.423354)
		(width 0.1651)
		(layer "In11.Cu")
		(net "P5E_PEX2_STN2_TX_DP<38>")
	)
	(segment
		(start 292.702742 -115.413282)
		(end 294.225472 -107.62107)
		(width 0.1651)
		(layer "In11.Cu")
		(net "P5E_PEX2_STN2_TX_DP<38>")
	)
	(segment
		(start 284.583886 -271.427448)
		(end 284.583886 -271.399)
		(width 0.1143)
		(layer "In11.Cu")
		(net "P5E_PEX2_STN2_TX_DP<38>")
	)
	(segment
		(start 284.583886 -263.176004)
		(end 292.00983 -121.034048)
		(width 0.1651)
		(layer "In11.Cu")
		(net "P5E_PEX2_STN2_TX_DP<38>")
	)
	(segment
		(start 284.583886 -271.399)
		(end 284.583886 -263.176004)
		(width 0.1651)
		(layer "In11.Cu")
		(net "P5E_PEX2_STN2_TX_DP<38>")
	)
	(segment
		(start 284.844744 -280.319988)
		(end 284.629606 -280.10485)
		(width 0.1143)
		(layer "In11.Cu")
		(net "P5E_PEX2_STN2_TX_DP<38>")
	)
	(segment
		(start 321.161664 -60.311792)
		(end 321.161664 -58.512202)
		(width 0.1651)
		(layer "In11.Cu")
		(net "P5E_PEX2_STN2_TX_DP<38>")
	)
	(segment
		(start 285.199836 -280.434288)
		(end 285.085536 -280.319988)
		(width 0.1143)
		(layer "In11.Cu")
		(net "P5E_PEX2_STN2_TX_DP<38>")
	)
	(segment
		(start 313.485784 -41.469818)
		(end 309.339996 -34.717736)
		(width 0.1651)
		(layer "In11.Cu")
		(net "P5E_PEX2_STN2_TX_DP<38>")
	)
	(segment
		(start 285.199836 -280.699718)
		(end 285.199836 -280.434288)
		(width 0.1143)
		(layer "In11.Cu")
		(net "P5E_PEX2_STN2_TX_DP<38>")
	)
	(segment
		(start 305.915314 -32.423354)
		(end 305.298094 -32.423354)
		(width 0.1651)
		(layer "In11.Cu")
		(net "P5E_PEX2_STN2_TX_DP<38>")
	)
	(segment
		(start 297.587416 -93.070426)
		(end 319.749678 -64.07023)
		(width 0.1651)
		(layer "In11.Cu")
		(net "P5E_PEX2_STN2_TX_DP<38>")
	)
	(segment
		(start 294.225472 -107.62107)
		(end 297.587416 -93.070426)
		(width 0.1651)
		(layer "In11.Cu")
		(net "P5E_PEX2_STN2_TX_DP<38>")
	)
	(segment
		(start 320.142362 -48.697642)
		(end 313.485784 -41.469818)
		(width 0.1651)
		(layer "In11.Cu")
		(net "P5E_PEX2_STN2_TX_DP<38>")
	)
	(segment
		(start 304.599594 -32.423354)
		(end 303.795938 -32.423354)
		(width 0.1651)
		(layer "In11.Cu")
		(net "P5E_PEX2_STN2_TX_DP<38>")
	)
	(segment
		(start 284.629606 -271.473168)
		(end 284.583886 -271.427448)
		(width 0.1143)
		(layer "In11.Cu")
		(net "P5E_PEX2_STN2_TX_DP<38>")
	)
	(segment
		(start 307.59781 -33.028636)
		(end 305.915314 -32.423354)
		(width 0.1651)
		(layer "In11.Cu")
		(net "P5E_PEX2_STN2_TX_DP<38>")
	)
	(segment
		(start 292.00983 -121.034048)
		(end 292.702742 -115.413282)
		(width 0.1651)
		(layer "In11.Cu")
		(net "P5E_PEX2_STN2_TX_DP<38>")
	)
	(segment
		(start 284.629606 -280.10485)
		(end 284.629606 -271.473168)
		(width 0.1143)
		(layer "In11.Cu")
		(net "P5E_PEX2_STN2_TX_DP<38>")
	)
	(segment
		(start 320.64071 -62.267338)
		(end 321.161664 -60.311792)
		(width 0.1651)
		(layer "In11.Cu")
		(net "P5E_PEX2_STN2_TX_DP<38>")
	)
	(segment
		(start 305.298094 -32.423354)
		(end 305.196494 -32.524954)
		(width 0.1651)
		(layer "In11.Cu")
		(net "P5E_PEX2_STN2_TX_DP<38>")
	)
	(segment
		(start 309.339996 -34.717736)
		(end 307.59781 -33.028636)
		(width 0.1651)
		(layer "In11.Cu")
		(net "P5E_PEX2_STN2_TX_DP<38>")
	)
	(segment
		(start 305.196494 -32.524954)
		(end 304.701194 -32.524954)
		(width 0.1651)
		(layer "In11.Cu")
		(net "P5E_PEX2_STN2_TX_DP<38>")
	)
	(segment
		(start 303.795938 -32.423354)
		(end 303.505108 -32.714184)
		(width 0.1651)
		(layer "In11.Cu")
		(net "P5E_PEX2_STN2_TX_DP<38>")
	)
	(segment
		(start 321.161664 -58.512202)
		(end 320.142362 -48.697642)
		(width 0.1651)
		(layer "In11.Cu")
		(net "P5E_PEX2_STN2_TX_DP<38>")
	)
	(segment
		(start 319.749678 -64.07023)
		(end 320.64071 -62.267338)
		(width 0.1651)
		(layer "In11.Cu")
		(net "P5E_PEX2_STN2_TX_DP<38>")
	)
	(segment
		(start 421.3225 -30.353)
		(end 421.00119 -30.03169)
		(width 0.13462)
		(layer "F.Cu")
		(net "P5E_PEX3_STN2_TX_DN<37>")
	)
	(segment
		(start 422.247314 -30.05709)
		(end 421.951404 -30.353)
		(width 0.13462)
		(layer "F.Cu")
		(net "P5E_PEX3_STN2_TX_DN<37>")
	)
	(segment
		(start 421.951404 -30.353)
		(end 421.3225 -30.353)
		(width 0.13462)
		(layer "F.Cu")
		(net "P5E_PEX3_STN2_TX_DN<37>")
	)
	(segment
		(start 409.413964 -120.76176)
		(end 401.915884 -263.306306)
		(width 0.1651)
		(layer "In11.Cu")
		(net "P5E_PEX3_STN2_TX_DN<37>")
	)
	(segment
		(start 401.915884 -271.399)
		(end 401.915884 -271.427448)
		(width 0.1143)
		(layer "In11.Cu")
		(net "P5E_PEX3_STN2_TX_DN<37>")
	)
	(segment
		(start 430.719992 -40.511984)
		(end 437.505094 -48.032416)
		(width 0.1651)
		(layer "In11.Cu")
		(net "P5E_PEX3_STN2_TX_DN<37>")
	)
	(segment
		(start 437.972454 -62.700916)
		(end 437.017414 -64.616076)
		(width 0.1651)
		(layer "In11.Cu")
		(net "P5E_PEX3_STN2_TX_DN<37>")
	)
	(segment
		(start 438.571386 -60.458604)
		(end 437.972454 -62.700916)
		(width 0.1651)
		(layer "In11.Cu")
		(net "P5E_PEX3_STN2_TX_DN<37>")
	)
	(segment
		(start 401.870164 -278.125936)
		(end 401.973796 -278.229568)
		(width 0.1143)
		(layer "In11.Cu")
		(net "P5E_PEX3_STN2_TX_DN<37>")
	)
	(segment
		(start 437.017414 -64.616076)
		(end 414.8328 -93.609922)
		(width 0.1651)
		(layer "In11.Cu")
		(net "P5E_PEX3_STN2_TX_DN<37>")
	)
	(segment
		(start 410.091636 -115.272058)
		(end 409.413964 -120.76176)
		(width 0.1651)
		(layer "In11.Cu")
		(net "P5E_PEX3_STN2_TX_DN<37>")
	)
	(segment
		(start 423.579544 -30.500066)
		(end 425.992544 -32.913066)
		(width 0.1651)
		(layer "In11.Cu")
		(net "P5E_PEX3_STN2_TX_DN<37>")
	)
	(segment
		(start 401.870164 -271.473168)
		(end 401.870164 -278.125936)
		(width 0.1143)
		(layer "In11.Cu")
		(net "P5E_PEX3_STN2_TX_DN<37>")
	)
	(segment
		(start 422.538144 -30.34792)
		(end 423.21226 -30.34792)
		(width 0.1651)
		(layer "In11.Cu")
		(net "P5E_PEX3_STN2_TX_DN<37>")
	)
	(segment
		(start 414.8328 -93.609922)
		(end 411.536134 -107.879896)
		(width 0.1651)
		(layer "In11.Cu")
		(net "P5E_PEX3_STN2_TX_DN<37>")
	)
	(segment
		(start 425.992544 -32.913066)
		(end 430.719992 -40.511984)
		(width 0.1651)
		(layer "In11.Cu")
		(net "P5E_PEX3_STN2_TX_DN<37>")
	)
	(segment
		(start 411.536134 -107.879896)
		(end 410.091636 -115.272058)
		(width 0.1651)
		(layer "In11.Cu")
		(net "P5E_PEX3_STN2_TX_DN<37>")
	)
	(segment
		(start 437.505094 -48.032416)
		(end 438.571386 -58.532522)
		(width 0.1651)
		(layer "In11.Cu")
		(net "P5E_PEX3_STN2_TX_DN<37>")
	)
	(segment
		(start 438.571386 -58.532522)
		(end 438.571386 -60.458604)
		(width 0.1651)
		(layer "In11.Cu")
		(net "P5E_PEX3_STN2_TX_DN<37>")
	)
	(segment
		(start 402.249894 -278.115268)
		(end 402.249894 -277.849838)
		(width 0.1143)
		(layer "In11.Cu")
		(net "P5E_PEX3_STN2_TX_DN<37>")
	)
	(segment
		(start 401.973796 -278.229568)
		(end 402.135594 -278.229568)
		(width 0.1143)
		(layer "In11.Cu")
		(net "P5E_PEX3_STN2_TX_DN<37>")
	)
	(segment
		(start 402.135594 -278.229568)
		(end 402.249894 -278.115268)
		(width 0.1143)
		(layer "In11.Cu")
		(net "P5E_PEX3_STN2_TX_DN<37>")
	)
	(segment
		(start 401.915884 -263.306306)
		(end 401.915884 -271.399)
		(width 0.1651)
		(layer "In11.Cu")
		(net "P5E_PEX3_STN2_TX_DN<37>")
	)
	(segment
		(start 423.21226 -30.34792)
		(end 423.579544 -30.500066)
		(width 0.1651)
		(layer "In11.Cu")
		(net "P5E_PEX3_STN2_TX_DN<37>")
	)
	(segment
		(start 401.915884 -271.427448)
		(end 401.870164 -271.473168)
		(width 0.1143)
		(layer "In11.Cu")
		(net "P5E_PEX3_STN2_TX_DN<37>")
	)
	(segment
		(start 422.247314 -30.05709)
		(end 422.538144 -30.34792)
		(width 0.1651)
		(layer "In11.Cu")
		(net "P5E_PEX3_STN2_TX_DN<37>")
	)
	(segment
		(start 83.134962 -345.465146)
		(end 83.429602 -345.170506)
		(width 0.13462)
		(layer "F.Cu")
		(net "P5E_PEX0_STN5_TX_C_DP<90>")
	)
	(segment
		(start 83.429602 -345.170506)
		(end 83.429602 -344.539062)
		(width 0.13462)
		(layer "F.Cu")
		(net "P5E_PEX0_STN5_TX_C_DP<90>")
	)
	(segment
		(start 83.429602 -344.539062)
		(end 83.109562 -344.219022)
		(width 0.13462)
		(layer "F.Cu")
		(net "P5E_PEX0_STN5_TX_C_DP<90>")
	)
	(segment
		(start 78.870048 -365.136938)
		(end 78.98638 -365.088932)
		(width 0.1651)
		(layer "In7.Cu")
		(net "P5E_PEX0_STN5_TX_C_DP<90>")
	)
	(segment
		(start 77.833982 -367.869978)
		(end 77.785976 -367.7539)
		(width 0.1651)
		(layer "In7.Cu")
		(net "P5E_PEX0_STN5_TX_C_DP<90>")
	)
	(segment
		(start 78.538832 -366.168432)
		(end 78.728316 -365.710978)
		(width 0.1651)
		(layer "In7.Cu")
		(net "P5E_PEX0_STN5_TX_C_DP<90>")
	)
	(segment
		(start 78.68031 -365.5949)
		(end 78.870048 -365.136938)
		(width 0.1651)
		(layer "In7.Cu")
		(net "P5E_PEX0_STN5_TX_C_DP<90>")
	)
	(segment
		(start 78.72857 -365.710978)
		(end 78.68031 -365.5949)
		(width 0.1651)
		(layer "In7.Cu")
		(net "P5E_PEX0_STN5_TX_C_DP<90>")
	)
	(segment
		(start 77.202284 -378.370084)
		(end 77.202284 -369.395248)
		(width 0.1651)
		(layer "In7.Cu")
		(net "P5E_PEX0_STN5_TX_C_DP<90>")
	)
	(segment
		(start 76.309982 -378.67209)
		(end 76.436982 -378.79909)
		(width 0.1651)
		(layer "In7.Cu")
		(net "P5E_PEX0_STN5_TX_C_DP<90>")
	)
	(segment
		(start 77.785976 -367.7539)
		(end 77.975714 -367.295938)
		(width 0.1651)
		(layer "In7.Cu")
		(net "P5E_PEX0_STN5_TX_C_DP<90>")
	)
	(segment
		(start 78.281022 -366.790478)
		(end 78.281276 -366.790478)
		(width 0.1651)
		(layer "In7.Cu")
		(net "P5E_PEX0_STN5_TX_C_DP<90>")
	)
	(segment
		(start 83.425792 -345.755976)
		(end 83.134962 -345.465146)
		(width 0.1651)
		(layer "In7.Cu")
		(net "P5E_PEX0_STN5_TX_C_DP<90>")
	)
	(segment
		(start 81.871312 -358.123236)
		(end 81.871312 -347.912182)
		(width 0.1651)
		(layer "In7.Cu")
		(net "P5E_PEX0_STN5_TX_C_DP<90>")
	)
	(segment
		(start 76.309982 -378.290074)
		(end 76.309982 -378.67209)
		(width 0.1651)
		(layer "In7.Cu")
		(net "P5E_PEX0_STN5_TX_C_DP<90>")
	)
	(segment
		(start 78.728316 -365.710978)
		(end 78.72857 -365.710978)
		(width 0.1651)
		(layer "In7.Cu")
		(net "P5E_PEX0_STN5_TX_C_DP<90>")
	)
	(segment
		(start 81.871312 -347.912182)
		(end 83.425792 -346.357702)
		(width 0.1651)
		(layer "In7.Cu")
		(net "P5E_PEX0_STN5_TX_C_DP<90>")
	)
	(segment
		(start 76.436982 -378.79909)
		(end 76.773278 -378.79909)
		(width 0.1651)
		(layer "In7.Cu")
		(net "P5E_PEX0_STN5_TX_C_DP<90>")
	)
	(segment
		(start 78.091538 -367.247932)
		(end 78.281022 -366.790478)
		(width 0.1651)
		(layer "In7.Cu")
		(net "P5E_PEX0_STN5_TX_C_DP<90>")
	)
	(segment
		(start 83.425792 -346.357702)
		(end 83.425792 -345.755976)
		(width 0.1651)
		(layer "In7.Cu")
		(net "P5E_PEX0_STN5_TX_C_DP<90>")
	)
	(segment
		(start 78.539086 -366.168432)
		(end 78.538832 -366.168432)
		(width 0.1651)
		(layer "In7.Cu")
		(net "P5E_PEX0_STN5_TX_C_DP<90>")
	)
	(segment
		(start 78.091792 -367.247932)
		(end 78.091538 -367.247932)
		(width 0.1651)
		(layer "In7.Cu")
		(net "P5E_PEX0_STN5_TX_C_DP<90>")
	)
	(segment
		(start 77.202284 -369.395248)
		(end 77.833982 -367.869978)
		(width 0.1651)
		(layer "In7.Cu")
		(net "P5E_PEX0_STN5_TX_C_DP<90>")
	)
	(segment
		(start 76.773278 -378.79909)
		(end 77.202284 -378.370084)
		(width 0.1651)
		(layer "In7.Cu")
		(net "P5E_PEX0_STN5_TX_C_DP<90>")
	)
	(segment
		(start 78.98638 -365.088932)
		(end 78.985872 -365.088932)
		(width 0.1651)
		(layer "In7.Cu")
		(net "P5E_PEX0_STN5_TX_C_DP<90>")
	)
	(segment
		(start 78.423008 -366.216438)
		(end 78.539086 -366.168432)
		(width 0.1651)
		(layer "In7.Cu")
		(net "P5E_PEX0_STN5_TX_C_DP<90>")
	)
	(segment
		(start 78.281276 -366.790478)
		(end 78.233016 -366.6744)
		(width 0.1651)
		(layer "In7.Cu")
		(net "P5E_PEX0_STN5_TX_C_DP<90>")
	)
	(segment
		(start 77.975714 -367.295938)
		(end 78.091792 -367.247932)
		(width 0.1651)
		(layer "In7.Cu")
		(net "P5E_PEX0_STN5_TX_C_DP<90>")
	)
	(segment
		(start 78.233016 -366.6744)
		(end 78.423008 -366.216438)
		(width 0.1651)
		(layer "In7.Cu")
		(net "P5E_PEX0_STN5_TX_C_DP<90>")
	)
	(segment
		(start 78.985872 -365.088932)
		(end 81.871312 -358.123236)
		(width 0.1651)
		(layer "In7.Cu")
		(net "P5E_PEX0_STN5_TX_C_DP<90>")
	)
	(segment
		(start 298.961302 -350.365314)
		(end 299.281342 -350.685354)
		(width 0.13462)
		(layer "F.Cu")
		(net "P5E_PEX2_STN7_TX_C_DP<127>")
	)
	(segment
		(start 299.281342 -350.685354)
		(end 299.281342 -351.316798)
		(width 0.13462)
		(layer "F.Cu")
		(net "P5E_PEX2_STN7_TX_C_DP<127>")
	)
	(segment
		(start 299.281342 -351.316798)
		(end 298.986702 -351.611438)
		(width 0.13462)
		(layer "F.Cu")
		(net "P5E_PEX2_STN7_TX_C_DP<127>")
	)
	(segment
		(start 302.184562 -366.429798)
		(end 302.221138 -366.284764)
		(width 0.1651)
		(layer "In7.Cu")
		(net "P5E_PEX2_STN7_TX_C_DP<127>")
	)
	(segment
		(start 299.277532 -352.356166)
		(end 299.277532 -351.902268)
		(width 0.1651)
		(layer "In7.Cu")
		(net "P5E_PEX2_STN7_TX_C_DP<127>")
	)
	(segment
		(start 302.88992 -375.872248)
		(end 303.01692 -375.999248)
		(width 0.1651)
		(layer "In7.Cu")
		(net "P5E_PEX2_STN7_TX_C_DP<127>")
	)
	(segment
		(start 302.422052 -366.826038)
		(end 302.184562 -366.429798)
		(width 0.1651)
		(layer "In7.Cu")
		(net "P5E_PEX2_STN7_TX_C_DP<127>")
	)
	(segment
		(start 297.723052 -353.910646)
		(end 299.277532 -352.356166)
		(width 0.1651)
		(layer "In7.Cu")
		(net "P5E_PEX2_STN7_TX_C_DP<127>")
	)
	(segment
		(start 302.56734 -366.862614)
		(end 302.422052 -366.826038)
		(width 0.1651)
		(layer "In7.Cu")
		(net "P5E_PEX2_STN7_TX_C_DP<127>")
	)
	(segment
		(start 303.733962 -375.712482)
		(end 303.733962 -368.810032)
		(width 0.1651)
		(layer "In7.Cu")
		(net "P5E_PEX2_STN7_TX_C_DP<127>")
	)
	(segment
		(start 302.221138 -366.284764)
		(end 297.723052 -358.777032)
		(width 0.1651)
		(layer "In7.Cu")
		(net "P5E_PEX2_STN7_TX_C_DP<127>")
	)
	(segment
		(start 303.01692 -375.999248)
		(end 303.447196 -375.999248)
		(width 0.1651)
		(layer "In7.Cu")
		(net "P5E_PEX2_STN7_TX_C_DP<127>")
	)
	(segment
		(start 303.447196 -375.999248)
		(end 303.733962 -375.712482)
		(width 0.1651)
		(layer "In7.Cu")
		(net "P5E_PEX2_STN7_TX_C_DP<127>")
	)
	(segment
		(start 302.88992 -375.490232)
		(end 302.88992 -375.872248)
		(width 0.1651)
		(layer "In7.Cu")
		(net "P5E_PEX2_STN7_TX_C_DP<127>")
	)
	(segment
		(start 297.723052 -358.777032)
		(end 297.723052 -353.910646)
		(width 0.1651)
		(layer "In7.Cu")
		(net "P5E_PEX2_STN7_TX_C_DP<127>")
	)
	(segment
		(start 299.277532 -351.902268)
		(end 298.986702 -351.611438)
		(width 0.1651)
		(layer "In7.Cu")
		(net "P5E_PEX2_STN7_TX_C_DP<127>")
	)
	(segment
		(start 303.733962 -368.810032)
		(end 302.56734 -366.862614)
		(width 0.1651)
		(layer "In7.Cu")
		(net "P5E_PEX2_STN7_TX_C_DP<127>")
	)
	(segment
		(start 159.371792 -357.46309)
		(end 159.371792 -356.831646)
		(width 0.13462)
		(layer "F.Cu")
		(net "P5E_PEX1_STN7_TX_C_DP<112>")
	)
	(segment
		(start 159.371792 -356.831646)
		(end 159.051752 -356.511606)
		(width 0.13462)
		(layer "F.Cu")
		(net "P5E_PEX1_STN7_TX_C_DP<112>")
	)
	(segment
		(start 159.077152 -357.75773)
		(end 159.371792 -357.46309)
		(width 0.13462)
		(layer "F.Cu")
		(net "P5E_PEX1_STN7_TX_C_DP<112>")
	)
	(segment
		(start 160.037018 -400.899122)
		(end 159.910018 -400.772122)
		(width 0.1651)
		(layer "In11.Cu")
		(net "P5E_PEX1_STN7_TX_C_DP<112>")
	)
	(segment
		(start 155.296108 -391.360152)
		(end 155.31719 -391.502392)
		(width 0.1651)
		(layer "In11.Cu")
		(net "P5E_PEX1_STN7_TX_C_DP<112>")
	)
	(segment
		(start 154.337258 -390.648698)
		(end 154.35834 -390.790938)
		(width 0.1651)
		(layer "In11.Cu")
		(net "P5E_PEX1_STN7_TX_C_DP<112>")
	)
	(segment
		(start 155.857194 -391.776712)
		(end 156.254958 -392.071606)
		(width 0.1651)
		(layer "In11.Cu")
		(net "P5E_PEX1_STN7_TX_C_DP<112>")
	)
	(segment
		(start 154.35834 -390.790938)
		(end 154.756358 -391.08634)
		(width 0.1651)
		(layer "In11.Cu")
		(net "P5E_PEX1_STN7_TX_C_DP<112>")
	)
	(segment
		(start 157.23489 -392.9253)
		(end 157.632908 -393.220448)
		(width 0.1651)
		(layer "In11.Cu")
		(net "P5E_PEX1_STN7_TX_C_DP<112>")
	)
	(segment
		(start 157.213808 -392.78306)
		(end 157.23489 -392.9253)
		(width 0.1651)
		(layer "In11.Cu")
		(net "P5E_PEX1_STN7_TX_C_DP<112>")
	)
	(segment
		(start 156.816044 -392.488166)
		(end 157.213808 -392.78306)
		(width 0.1651)
		(layer "In11.Cu")
		(net "P5E_PEX1_STN7_TX_C_DP<112>")
	)
	(segment
		(start 156.27604 -392.213846)
		(end 156.674058 -392.508994)
		(width 0.1651)
		(layer "In11.Cu")
		(net "P5E_PEX1_STN7_TX_C_DP<112>")
	)
	(segment
		(start 159.367982 -358.04856)
		(end 159.367982 -358.802178)
		(width 0.1651)
		(layer "In11.Cu")
		(net "P5E_PEX1_STN7_TX_C_DP<112>")
	)
	(segment
		(start 159.760158 -394.233654)
		(end 160.535112 -394.594334)
		(width 0.1651)
		(layer "In11.Cu")
		(net "P5E_PEX1_STN7_TX_C_DP<112>")
	)
	(segment
		(start 151.97201 -386.076952)
		(end 153.598372 -390.100566)
		(width 0.1651)
		(layer "In11.Cu")
		(net "P5E_PEX1_STN7_TX_C_DP<112>")
	)
	(segment
		(start 156.254958 -392.071606)
		(end 156.27604 -392.213846)
		(width 0.1651)
		(layer "In11.Cu")
		(net "P5E_PEX1_STN7_TX_C_DP<112>")
	)
	(segment
		(start 159.367982 -358.802178)
		(end 158.740094 -359.430066)
		(width 0.1651)
		(layer "In11.Cu")
		(net "P5E_PEX1_STN7_TX_C_DP<112>")
	)
	(segment
		(start 159.126682 -393.938506)
		(end 159.175958 -394.073634)
		(width 0.1651)
		(layer "In11.Cu")
		(net "P5E_PEX1_STN7_TX_C_DP<112>")
	)
	(segment
		(start 153.228294 -363.84611)
		(end 151.879808 -367.412524)
		(width 0.1651)
		(layer "In11.Cu")
		(net "P5E_PEX1_STN7_TX_C_DP<112>")
	)
	(segment
		(start 154.756358 -391.08634)
		(end 154.898344 -391.065258)
		(width 0.1651)
		(layer "In11.Cu")
		(net "P5E_PEX1_STN7_TX_C_DP<112>")
	)
	(segment
		(start 155.715208 -391.79754)
		(end 155.857194 -391.776712)
		(width 0.1651)
		(layer "In11.Cu")
		(net "P5E_PEX1_STN7_TX_C_DP<112>")
	)
	(segment
		(start 156.674058 -392.508994)
		(end 156.816044 -392.488166)
		(width 0.1651)
		(layer "In11.Cu")
		(net "P5E_PEX1_STN7_TX_C_DP<112>")
	)
	(segment
		(start 160.652714 -400.899122)
		(end 160.037018 -400.899122)
		(width 0.1651)
		(layer "In11.Cu")
		(net "P5E_PEX1_STN7_TX_C_DP<112>")
	)
	(segment
		(start 155.31719 -391.502392)
		(end 155.715208 -391.79754)
		(width 0.1651)
		(layer "In11.Cu")
		(net "P5E_PEX1_STN7_TX_C_DP<112>")
	)
	(segment
		(start 159.910018 -400.772122)
		(end 159.910018 -400.390106)
		(width 0.1651)
		(layer "In11.Cu")
		(net "P5E_PEX1_STN7_TX_C_DP<112>")
	)
	(segment
		(start 159.175958 -394.073634)
		(end 159.625284 -394.28293)
		(width 0.1651)
		(layer "In11.Cu")
		(net "P5E_PEX1_STN7_TX_C_DP<112>")
	)
	(segment
		(start 158.172658 -393.494514)
		(end 159.126682 -393.938506)
		(width 0.1651)
		(layer "In11.Cu")
		(net "P5E_PEX1_STN7_TX_C_DP<112>")
	)
	(segment
		(start 160.793176 -394.852398)
		(end 160.793176 -400.75866)
		(width 0.1651)
		(layer "In11.Cu")
		(net "P5E_PEX1_STN7_TX_C_DP<112>")
	)
	(segment
		(start 158.740094 -359.430066)
		(end 156.694124 -360.28884)
		(width 0.1651)
		(layer "In11.Cu")
		(net "P5E_PEX1_STN7_TX_C_DP<112>")
	)
	(segment
		(start 160.535112 -394.594334)
		(end 160.793176 -394.852398)
		(width 0.1651)
		(layer "In11.Cu")
		(net "P5E_PEX1_STN7_TX_C_DP<112>")
	)
	(segment
		(start 151.69134 -382.84277)
		(end 151.97201 -386.076952)
		(width 0.1651)
		(layer "In11.Cu")
		(net "P5E_PEX1_STN7_TX_C_DP<112>")
	)
	(segment
		(start 159.077152 -357.75773)
		(end 159.367982 -358.04856)
		(width 0.1651)
		(layer "In11.Cu")
		(net "P5E_PEX1_STN7_TX_C_DP<112>")
	)
	(segment
		(start 153.598372 -390.100566)
		(end 154.337258 -390.648698)
		(width 0.1651)
		(layer "In11.Cu")
		(net "P5E_PEX1_STN7_TX_C_DP<112>")
	)
	(segment
		(start 156.694124 -360.28884)
		(end 153.228294 -363.84611)
		(width 0.1651)
		(layer "In11.Cu")
		(net "P5E_PEX1_STN7_TX_C_DP<112>")
	)
	(segment
		(start 159.625284 -394.28293)
		(end 159.760158 -394.233654)
		(width 0.1651)
		(layer "In11.Cu")
		(net "P5E_PEX1_STN7_TX_C_DP<112>")
	)
	(segment
		(start 151.879808 -367.412524)
		(end 151.69134 -382.84277)
		(width 0.1651)
		(layer "In11.Cu")
		(net "P5E_PEX1_STN7_TX_C_DP<112>")
	)
	(segment
		(start 157.774894 -393.19962)
		(end 158.172658 -393.494514)
		(width 0.1651)
		(layer "In11.Cu")
		(net "P5E_PEX1_STN7_TX_C_DP<112>")
	)
	(segment
		(start 154.898344 -391.065258)
		(end 155.296108 -391.360152)
		(width 0.1651)
		(layer "In11.Cu")
		(net "P5E_PEX1_STN7_TX_C_DP<112>")
	)
	(segment
		(start 160.793176 -400.75866)
		(end 160.652714 -400.899122)
		(width 0.1651)
		(layer "In11.Cu")
		(net "P5E_PEX1_STN7_TX_C_DP<112>")
	)
	(segment
		(start 157.632908 -393.220448)
		(end 157.774894 -393.19962)
		(width 0.1651)
		(layer "In11.Cu")
		(net "P5E_PEX1_STN7_TX_C_DP<112>")
	)
	(segment
		(start 306.147216 -30.92069)
		(end 305.853846 -30.62732)
		(width 0.13462)
		(layer "F.Cu")
		(net "P5E_PEX2_STN2_TX_DP<37>")
	)
	(segment
		(start 305.219862 -30.62732)
		(end 304.901092 -30.94609)
		(width 0.13462)
		(layer "F.Cu")
		(net "P5E_PEX2_STN2_TX_DP<37>")
	)
	(segment
		(start 305.853846 -30.62732)
		(end 305.219862 -30.62732)
		(width 0.13462)
		(layer "F.Cu")
		(net "P5E_PEX2_STN2_TX_DP<37>")
	)
	(segment
		(start 307.779928 -31.199328)
		(end 307.779928 -31.325058)
		(width 0.1651)
		(layer "In11.Cu")
		(net "P5E_PEX2_STN2_TX_DP<37>")
	)
	(segment
		(start 294.797734 -109.674152)
		(end 294.797988 -109.674152)
		(width 0.1651)
		(layer "In11.Cu")
		(net "P5E_PEX2_STN2_TX_DP<37>")
	)
	(segment
		(start 294.617394 -110.598458)
		(end 293.7129 -115.227608)
		(width 0.1651)
		(layer "In11.Cu")
		(net "P5E_PEX2_STN2_TX_DP<37>")
	)
	(segment
		(start 308.60619 -32.15132)
		(end 308.95671 -32.50184)
		(width 0.1651)
		(layer "In11.Cu")
		(net "P5E_PEX2_STN2_TX_DP<37>")
	)
	(segment
		(start 286.149796 -278.534368)
		(end 286.149796 -278.799798)
		(width 0.1143)
		(layer "In11.Cu")
		(net "P5E_PEX2_STN2_TX_DP<37>")
	)
	(segment
		(start 285.579566 -278.20493)
		(end 285.794704 -278.420068)
		(width 0.1143)
		(layer "In11.Cu")
		(net "P5E_PEX2_STN2_TX_DP<37>")
	)
	(segment
		(start 285.794704 -278.420068)
		(end 286.035496 -278.420068)
		(width 0.1143)
		(layer "In11.Cu")
		(net "P5E_PEX2_STN2_TX_DP<37>")
	)
	(segment
		(start 286.035496 -278.420068)
		(end 286.149796 -278.534368)
		(width 0.1143)
		(layer "In11.Cu")
		(net "P5E_PEX2_STN2_TX_DP<37>")
	)
	(segment
		(start 308.60619 -32.02559)
		(end 308.60619 -32.15132)
		(width 0.1651)
		(layer "In11.Cu")
		(net "P5E_PEX2_STN2_TX_DP<37>")
	)
	(segment
		(start 293.7129 -115.227608)
		(end 293.032688 -120.737122)
		(width 0.1651)
		(layer "In11.Cu")
		(net "P5E_PEX2_STN2_TX_DP<37>")
	)
	(segment
		(start 309.670196 -33.089596)
		(end 314.39358 -40.682418)
		(width 0.1651)
		(layer "In11.Cu")
		(net "P5E_PEX2_STN2_TX_DP<37>")
	)
	(segment
		(start 320.676778 -64.465962)
		(end 298.47159 -93.486986)
		(width 0.1651)
		(layer "In11.Cu")
		(net "P5E_PEX2_STN2_TX_DP<37>")
	)
	(segment
		(start 308.256178 -31.675578)
		(end 308.60619 -32.02559)
		(width 0.1651)
		(layer "In11.Cu")
		(net "P5E_PEX2_STN2_TX_DP<37>")
	)
	(segment
		(start 298.47159 -93.486986)
		(end 295.160192 -107.821222)
		(width 0.1651)
		(layer "In11.Cu")
		(net "P5E_PEX2_STN2_TX_DP<37>")
	)
	(segment
		(start 285.579566 -271.473168)
		(end 285.579566 -278.20493)
		(width 0.1143)
		(layer "In11.Cu")
		(net "P5E_PEX2_STN2_TX_DP<37>")
	)
	(segment
		(start 322.189348 -58.547)
		(end 322.189348 -60.42152)
		(width 0.1651)
		(layer "In11.Cu")
		(net "P5E_PEX2_STN2_TX_DP<37>")
	)
	(segment
		(start 306.438046 -30.62986)
		(end 307.056028 -30.62986)
		(width 0.1651)
		(layer "In11.Cu")
		(net "P5E_PEX2_STN2_TX_DP<37>")
	)
	(segment
		(start 306.147216 -30.92069)
		(end 306.438046 -30.62986)
		(width 0.1651)
		(layer "In11.Cu")
		(net "P5E_PEX2_STN2_TX_DP<37>")
	)
	(segment
		(start 285.533846 -263.298686)
		(end 285.533846 -271.399)
		(width 0.1651)
		(layer "In11.Cu")
		(net "P5E_PEX2_STN2_TX_DP<37>")
	)
	(segment
		(start 307.779928 -31.325058)
		(end 308.130448 -31.675578)
		(width 0.1651)
		(layer "In11.Cu")
		(net "P5E_PEX2_STN2_TX_DP<37>")
	)
	(segment
		(start 295.160192 -107.821222)
		(end 294.978582 -108.750354)
		(width 0.1651)
		(layer "In11.Cu")
		(net "P5E_PEX2_STN2_TX_DP<37>")
	)
	(segment
		(start 308.130448 -31.675578)
		(end 308.256178 -31.675578)
		(width 0.1651)
		(layer "In11.Cu")
		(net "P5E_PEX2_STN2_TX_DP<37>")
	)
	(segment
		(start 314.39358 -40.682418)
		(end 321.133724 -48.152812)
		(width 0.1651)
		(layer "In11.Cu")
		(net "P5E_PEX2_STN2_TX_DP<37>")
	)
	(segment
		(start 285.533846 -271.399)
		(end 285.533846 -271.427448)
		(width 0.1143)
		(layer "In11.Cu")
		(net "P5E_PEX2_STN2_TX_DP<37>")
	)
	(segment
		(start 309.08244 -32.50184)
		(end 309.670196 -33.089596)
		(width 0.1651)
		(layer "In11.Cu")
		(net "P5E_PEX2_STN2_TX_DP<37>")
	)
	(segment
		(start 293.032688 -120.737122)
		(end 285.533846 -263.298686)
		(width 0.1651)
		(layer "In11.Cu")
		(net "P5E_PEX2_STN2_TX_DP<37>")
	)
	(segment
		(start 321.133724 -48.152812)
		(end 322.189348 -58.547)
		(width 0.1651)
		(layer "In11.Cu")
		(net "P5E_PEX2_STN2_TX_DP<37>")
	)
	(segment
		(start 285.533846 -271.427448)
		(end 285.579566 -271.473168)
		(width 0.1143)
		(layer "In11.Cu")
		(net "P5E_PEX2_STN2_TX_DP<37>")
	)
	(segment
		(start 294.978582 -108.750354)
		(end 294.978328 -108.750354)
		(width 0.1651)
		(layer "In11.Cu")
		(net "P5E_PEX2_STN2_TX_DP<37>")
	)
	(segment
		(start 322.189348 -60.42152)
		(end 321.60718 -62.600586)
		(width 0.1651)
		(layer "In11.Cu")
		(net "P5E_PEX2_STN2_TX_DP<37>")
	)
	(segment
		(start 308.95671 -32.50184)
		(end 309.08244 -32.50184)
		(width 0.1651)
		(layer "In11.Cu")
		(net "P5E_PEX2_STN2_TX_DP<37>")
	)
	(segment
		(start 307.31968 -30.73908)
		(end 307.779928 -31.199328)
		(width 0.1651)
		(layer "In11.Cu")
		(net "P5E_PEX2_STN2_TX_DP<37>")
	)
	(segment
		(start 307.056028 -30.62986)
		(end 307.31968 -30.73908)
		(width 0.1651)
		(layer "In11.Cu")
		(net "P5E_PEX2_STN2_TX_DP<37>")
	)
	(segment
		(start 294.978328 -108.750354)
		(end 294.797734 -109.674152)
		(width 0.1651)
		(layer "In11.Cu")
		(net "P5E_PEX2_STN2_TX_DP<37>")
	)
	(segment
		(start 294.797988 -109.674152)
		(end 294.617394 -110.598458)
		(width 0.1651)
		(layer "In11.Cu")
		(net "P5E_PEX2_STN2_TX_DP<37>")
	)
	(segment
		(start 321.60718 -62.600586)
		(end 320.676778 -64.465962)
		(width 0.1651)
		(layer "In11.Cu")
		(net "P5E_PEX2_STN2_TX_DP<37>")
	)
	(segment
		(start 396.628112 -355.657658)
		(end 396.628112 -355.02723)
		(width 0.13462)
		(layer "F.Cu")
		(net "P5E_PEX3_STN5_TX_DN<92>")
	)
	(segment
		(start 396.628112 -355.02723)
		(end 396.92326 -354.732082)
		(width 0.13462)
		(layer "F.Cu")
		(net "P5E_PEX3_STN5_TX_DN<92>")
	)
	(segment
		(start 396.94866 -355.978206)
		(end 396.628112 -355.657658)
		(width 0.13462)
		(layer "F.Cu")
		(net "P5E_PEX3_STN5_TX_DN<92>")
	)
	(segment
		(start 396.63243 -354.441252)
		(end 396.63243 -353.930966)
		(width 0.1651)
		(layer "In13.Cu")
		(net "P5E_PEX3_STN5_TX_DN<92>")
	)
	(segment
		(start 398.18691 -352.376486)
		(end 398.18691 -342.081358)
		(width 0.1651)
		(layer "In13.Cu")
		(net "P5E_PEX3_STN5_TX_DN<92>")
	)
	(segment
		(start 418.399976 -311.784492)
		(end 418.399976 -312.049922)
		(width 0.1143)
		(layer "In13.Cu")
		(net "P5E_PEX3_STN5_TX_DN<92>")
	)
	(segment
		(start 418.123878 -311.670192)
		(end 418.285676 -311.670192)
		(width 0.1143)
		(layer "In13.Cu")
		(net "P5E_PEX3_STN5_TX_DN<92>")
	)
	(segment
		(start 418.020246 -319.971928)
		(end 418.020246 -311.773824)
		(width 0.1143)
		(layer "In13.Cu")
		(net "P5E_PEX3_STN5_TX_DN<92>")
	)
	(segment
		(start 396.92326 -354.732082)
		(end 396.63243 -354.441252)
		(width 0.1651)
		(layer "In13.Cu")
		(net "P5E_PEX3_STN5_TX_DN<92>")
	)
	(segment
		(start 418.285676 -311.670192)
		(end 418.399976 -311.784492)
		(width 0.1143)
		(layer "In13.Cu")
		(net "P5E_PEX3_STN5_TX_DN<92>")
	)
	(segment
		(start 418.065966 -322.396612)
		(end 418.065966 -320.046096)
		(width 0.1651)
		(layer "In13.Cu")
		(net "P5E_PEX3_STN5_TX_DN<92>")
	)
	(segment
		(start 418.065966 -320.017648)
		(end 418.020246 -319.971928)
		(width 0.1143)
		(layer "In13.Cu")
		(net "P5E_PEX3_STN5_TX_DN<92>")
	)
	(segment
		(start 398.18691 -342.081358)
		(end 398.372076 -341.438992)
		(width 0.1651)
		(layer "In13.Cu")
		(net "P5E_PEX3_STN5_TX_DN<92>")
	)
	(segment
		(start 398.372076 -341.438992)
		(end 415.633408 -325.844408)
		(width 0.1651)
		(layer "In13.Cu")
		(net "P5E_PEX3_STN5_TX_DN<92>")
	)
	(segment
		(start 418.065966 -320.046096)
		(end 418.065966 -320.017648)
		(width 0.1143)
		(layer "In13.Cu")
		(net "P5E_PEX3_STN5_TX_DN<92>")
	)
	(segment
		(start 396.63243 -353.930966)
		(end 398.18691 -352.376486)
		(width 0.1651)
		(layer "In13.Cu")
		(net "P5E_PEX3_STN5_TX_DN<92>")
	)
	(segment
		(start 415.633408 -325.844408)
		(end 418.065966 -322.396612)
		(width 0.1651)
		(layer "In13.Cu")
		(net "P5E_PEX3_STN5_TX_DN<92>")
	)
	(segment
		(start 418.020246 -311.773824)
		(end 418.123878 -311.670192)
		(width 0.1143)
		(layer "In13.Cu")
		(net "P5E_PEX3_STN5_TX_DN<92>")
	)
	(segment
		(start 83.429602 -357.46309)
		(end 83.429602 -356.831646)
		(width 0.13462)
		(layer "F.Cu")
		(net "P5E_PEX0_STN5_TX_C_DP<91>")
	)
	(segment
		(start 83.429602 -356.831646)
		(end 83.109562 -356.511606)
		(width 0.13462)
		(layer "F.Cu")
		(net "P5E_PEX0_STN5_TX_C_DP<91>")
	)
	(segment
		(start 83.134962 -357.75773)
		(end 83.429602 -357.46309)
		(width 0.13462)
		(layer "F.Cu")
		(net "P5E_PEX0_STN5_TX_C_DP<91>")
	)
	(segment
		(start 79.886302 -367.364264)
		(end 79.402432 -368.532664)
		(width 0.1651)
		(layer "In7.Cu")
		(net "P5E_PEX0_STN5_TX_C_DP<91>")
	)
	(segment
		(start 80.028034 -366.790224)
		(end 79.838296 -367.248186)
		(width 0.1651)
		(layer "In7.Cu")
		(net "P5E_PEX0_STN5_TX_C_DP<91>")
	)
	(segment
		(start 80.144112 -366.742218)
		(end 80.028034 -366.790224)
		(width 0.1651)
		(layer "In7.Cu")
		(net "P5E_PEX0_STN5_TX_C_DP<91>")
	)
	(segment
		(start 83.134962 -357.75773)
		(end 83.425792 -358.04856)
		(width 0.1651)
		(layer "In7.Cu")
		(net "P5E_PEX0_STN5_TX_C_DP<91>")
	)
	(segment
		(start 79.838296 -367.248186)
		(end 79.886302 -367.364264)
		(width 0.1651)
		(layer "In7.Cu")
		(net "P5E_PEX0_STN5_TX_C_DP<91>")
	)
	(segment
		(start 78.636876 -379.899164)
		(end 78.509876 -379.772164)
		(width 0.1651)
		(layer "In7.Cu")
		(net "P5E_PEX0_STN5_TX_C_DP<91>")
	)
	(segment
		(start 79.402432 -368.532664)
		(end 79.402432 -379.547882)
		(width 0.1651)
		(layer "In7.Cu")
		(net "P5E_PEX0_STN5_TX_C_DP<91>")
	)
	(segment
		(start 83.425792 -358.819196)
		(end 80.144112 -366.742218)
		(width 0.1651)
		(layer "In7.Cu")
		(net "P5E_PEX0_STN5_TX_C_DP<91>")
	)
	(segment
		(start 79.402432 -379.547882)
		(end 79.05115 -379.899164)
		(width 0.1651)
		(layer "In7.Cu")
		(net "P5E_PEX0_STN5_TX_C_DP<91>")
	)
	(segment
		(start 79.05115 -379.899164)
		(end 78.636876 -379.899164)
		(width 0.1651)
		(layer "In7.Cu")
		(net "P5E_PEX0_STN5_TX_C_DP<91>")
	)
	(segment
		(start 83.425792 -358.04856)
		(end 83.425792 -358.819196)
		(width 0.1651)
		(layer "In7.Cu")
		(net "P5E_PEX0_STN5_TX_C_DP<91>")
	)
	(segment
		(start 78.509876 -379.772164)
		(end 78.509876 -379.390148)
		(width 0.1651)
		(layer "In7.Cu")
		(net "P5E_PEX0_STN5_TX_C_DP<91>")
	)
	(segment
		(start 64.455802 -349.831914)
		(end 64.775842 -349.511874)
		(width 0.13462)
		(layer "F.Cu")
		(net "P5E_PEX0_STN6_TX_DP<110>")
	)
	(segment
		(start 64.775842 -349.511874)
		(end 64.775842 -348.88043)
		(width 0.13462)
		(layer "F.Cu")
		(net "P5E_PEX0_STN6_TX_DP<110>")
	)
	(segment
		(start 64.775842 -348.88043)
		(end 64.481202 -348.58579)
		(width 0.13462)
		(layer "F.Cu")
		(net "P5E_PEX0_STN6_TX_DP<110>")
	)
	(segment
		(start 44.449746 -313.290712)
		(end 44.449746 -312.999882)
		(width 0.1143)
		(layer "In13.Cu")
		(net "P5E_PEX0_STN6_TX_DP<110>")
	)
	(segment
		(start 43.833796 -320.177922)
		(end 43.833796 -320.155824)
		(width 0.1143)
		(layer "In13.Cu")
		(net "P5E_PEX0_STN6_TX_DP<110>")
	)
	(segment
		(start 44.118022 -313.379612)
		(end 44.360846 -313.379612)
		(width 0.1143)
		(layer "In13.Cu")
		(net "P5E_PEX0_STN6_TX_DP<110>")
	)
	(segment
		(start 64.772032 -347.599508)
		(end 66.326512 -346.045028)
		(width 0.1651)
		(layer "In13.Cu")
		(net "P5E_PEX0_STN6_TX_DP<110>")
	)
	(segment
		(start 45.565568 -328.730356)
		(end 43.833796 -324.549262)
		(width 0.1651)
		(layer "In13.Cu")
		(net "P5E_PEX0_STN6_TX_DP<110>")
	)
	(segment
		(start 51.33594 -333.5528)
		(end 49.717706 -332.882494)
		(width 0.1651)
		(layer "In13.Cu")
		(net "P5E_PEX0_STN6_TX_DP<110>")
	)
	(segment
		(start 66.326512 -346.045028)
		(end 66.326512 -342.12276)
		(width 0.1651)
		(layer "In13.Cu")
		(net "P5E_PEX0_STN6_TX_DP<110>")
	)
	(segment
		(start 43.879516 -320.110104)
		(end 43.879516 -313.618118)
		(width 0.1143)
		(layer "In13.Cu")
		(net "P5E_PEX0_STN6_TX_DP<110>")
	)
	(segment
		(start 64.481202 -348.58579)
		(end 64.772032 -348.29496)
		(width 0.1651)
		(layer "In13.Cu")
		(net "P5E_PEX0_STN6_TX_DP<110>")
	)
	(segment
		(start 43.879516 -313.618118)
		(end 44.118022 -313.379612)
		(width 0.1143)
		(layer "In13.Cu")
		(net "P5E_PEX0_STN6_TX_DP<110>")
	)
	(segment
		(start 43.833796 -320.155824)
		(end 43.879516 -320.110104)
		(width 0.1143)
		(layer "In13.Cu")
		(net "P5E_PEX0_STN6_TX_DP<110>")
	)
	(segment
		(start 65.835022 -341.302848)
		(end 51.33594 -333.5528)
		(width 0.1651)
		(layer "In13.Cu")
		(net "P5E_PEX0_STN6_TX_DP<110>")
	)
	(segment
		(start 49.717706 -332.882494)
		(end 45.565568 -328.730356)
		(width 0.1651)
		(layer "In13.Cu")
		(net "P5E_PEX0_STN6_TX_DP<110>")
	)
	(segment
		(start 66.326512 -342.12276)
		(end 65.835022 -341.302848)
		(width 0.1651)
		(layer "In13.Cu")
		(net "P5E_PEX0_STN6_TX_DP<110>")
	)
	(segment
		(start 44.360846 -313.379612)
		(end 44.449746 -313.290712)
		(width 0.1143)
		(layer "In13.Cu")
		(net "P5E_PEX0_STN6_TX_DP<110>")
	)
	(segment
		(start 64.772032 -348.29496)
		(end 64.772032 -347.599508)
		(width 0.1651)
		(layer "In13.Cu")
		(net "P5E_PEX0_STN6_TX_DP<110>")
	)
	(segment
		(start 43.833796 -324.549262)
		(end 43.833796 -320.177922)
		(width 0.1651)
		(layer "In13.Cu")
		(net "P5E_PEX0_STN6_TX_DP<110>")
	)
	(segment
		(start 344.161364 -349.511874)
		(end 344.161364 -348.88043)
		(width 0.13462)
		(layer "F.Cu")
		(net "P5E_PEX2_STN5_TX_DN<95>")
	)
	(segment
		(start 344.481404 -349.831914)
		(end 344.161364 -349.511874)
		(width 0.13462)
		(layer "F.Cu")
		(net "P5E_PEX2_STN5_TX_DN<95>")
	)
	(segment
		(start 344.161364 -348.88043)
		(end 344.456004 -348.58579)
		(width 0.13462)
		(layer "F.Cu")
		(net "P5E_PEX2_STN5_TX_DN<95>")
	)
	(segment
		(start 309.102506 -321.79895)
		(end 308.953916 -321.862196)
		(width 0.1651)
		(layer "In7.Cu")
		(net "P5E_PEX2_STN5_TX_DN<95>")
	)
	(segment
		(start 304.815748 -319.97523)
		(end 304.815748 -319.890648)
		(width 0.1651)
		(layer "In7.Cu")
		(net "P5E_PEX2_STN5_TX_DN<95>")
	)
	(segment
		(start 344.165174 -348.29496)
		(end 344.165174 -347.784674)
		(width 0.1651)
		(layer "In7.Cu")
		(net "P5E_PEX2_STN5_TX_DN<95>")
	)
	(segment
		(start 345.719654 -342.011)
		(end 345.2876 -341.249)
		(width 0.1651)
		(layer "In7.Cu")
		(net "P5E_PEX2_STN5_TX_DN<95>")
	)
	(segment
		(start 345.2876 -341.249)
		(end 327.614026 -329.373484)
		(width 0.1651)
		(layer "In7.Cu")
		(net "P5E_PEX2_STN5_TX_DN<95>")
	)
	(segment
		(start 304.815748 -319.8622)
		(end 304.770028 -319.81648)
		(width 0.1143)
		(layer "In7.Cu")
		(net "P5E_PEX2_STN5_TX_DN<95>")
	)
	(segment
		(start 327.614026 -329.373484)
		(end 309.625746 -322.13296)
		(width 0.1651)
		(layer "In7.Cu")
		(net "P5E_PEX2_STN5_TX_DN<95>")
	)
	(segment
		(start 344.456004 -348.58579)
		(end 344.165174 -348.29496)
		(width 0.1651)
		(layer "In7.Cu")
		(net "P5E_PEX2_STN5_TX_DN<95>")
	)
	(segment
		(start 305.035458 -313.570112)
		(end 305.149758 -313.684412)
		(width 0.1143)
		(layer "In7.Cu")
		(net "P5E_PEX2_STN5_TX_DN<95>")
	)
	(segment
		(start 304.770028 -319.81648)
		(end 304.770028 -313.684412)
		(width 0.1143)
		(layer "In7.Cu")
		(net "P5E_PEX2_STN5_TX_DN<95>")
	)
	(segment
		(start 309.625746 -322.13296)
		(end 309.562246 -321.983862)
		(width 0.1651)
		(layer "In7.Cu")
		(net "P5E_PEX2_STN5_TX_DN<95>")
	)
	(segment
		(start 308.953916 -321.862196)
		(end 305.672236 -320.541396)
		(width 0.1651)
		(layer "In7.Cu")
		(net "P5E_PEX2_STN5_TX_DN<95>")
	)
	(segment
		(start 304.815748 -319.890648)
		(end 304.815748 -319.8622)
		(width 0.1143)
		(layer "In7.Cu")
		(net "P5E_PEX2_STN5_TX_DN<95>")
	)
	(segment
		(start 305.672236 -320.541396)
		(end 304.815748 -319.97523)
		(width 0.1651)
		(layer "In7.Cu")
		(net "P5E_PEX2_STN5_TX_DN<95>")
	)
	(segment
		(start 304.884328 -313.570112)
		(end 305.035458 -313.570112)
		(width 0.1143)
		(layer "In7.Cu")
		(net "P5E_PEX2_STN5_TX_DN<95>")
	)
	(segment
		(start 344.165174 -347.784674)
		(end 345.719654 -346.230194)
		(width 0.1651)
		(layer "In7.Cu")
		(net "P5E_PEX2_STN5_TX_DN<95>")
	)
	(segment
		(start 304.770028 -313.684412)
		(end 304.884328 -313.570112)
		(width 0.1143)
		(layer "In7.Cu")
		(net "P5E_PEX2_STN5_TX_DN<95>")
	)
	(segment
		(start 305.149758 -313.684412)
		(end 305.149758 -313.949842)
		(width 0.1143)
		(layer "In7.Cu")
		(net "P5E_PEX2_STN5_TX_DN<95>")
	)
	(segment
		(start 345.719654 -346.230194)
		(end 345.719654 -342.011)
		(width 0.1651)
		(layer "In7.Cu")
		(net "P5E_PEX2_STN5_TX_DN<95>")
	)
	(segment
		(start 309.562246 -321.983862)
		(end 309.102506 -321.79895)
		(width 0.1651)
		(layer "In7.Cu")
		(net "P5E_PEX2_STN5_TX_DN<95>")
	)
	(segment
		(start 402.846032 -342.734646)
		(end 403.14118 -342.439498)
		(width 0.13462)
		(layer "F.Cu")
		(net "P5E_PEX3_STN5_TX_DN<94>")
	)
	(segment
		(start 402.846032 -343.365074)
		(end 402.846032 -342.734646)
		(width 0.13462)
		(layer "F.Cu")
		(net "P5E_PEX3_STN5_TX_DN<94>")
	)
	(segment
		(start 403.16658 -343.685622)
		(end 402.846032 -343.365074)
		(width 0.13462)
		(layer "F.Cu")
		(net "P5E_PEX3_STN5_TX_DN<94>")
	)
	(segment
		(start 402.85035 -342.148668)
		(end 402.85035 -341.549228)
		(width 0.1651)
		(layer "In13.Cu")
		(net "P5E_PEX3_STN5_TX_DN<94>")
	)
	(segment
		(start 419.965886 -320.017648)
		(end 419.920166 -319.971928)
		(width 0.1143)
		(layer "In13.Cu")
		(net "P5E_PEX3_STN5_TX_DN<94>")
	)
	(segment
		(start 419.965886 -323.10197)
		(end 419.965886 -320.046096)
		(width 0.1651)
		(layer "In13.Cu")
		(net "P5E_PEX3_STN5_TX_DN<94>")
	)
	(segment
		(start 419.965886 -320.046096)
		(end 419.965886 -320.017648)
		(width 0.1143)
		(layer "In13.Cu")
		(net "P5E_PEX3_STN5_TX_DN<94>")
	)
	(segment
		(start 417.213796 -327.161398)
		(end 419.965886 -323.10197)
		(width 0.1651)
		(layer "In13.Cu")
		(net "P5E_PEX3_STN5_TX_DN<94>")
	)
	(segment
		(start 420.299896 -311.784492)
		(end 420.299896 -312.049922)
		(width 0.1143)
		(layer "In13.Cu")
		(net "P5E_PEX3_STN5_TX_DN<94>")
	)
	(segment
		(start 403.070822 -340.925912)
		(end 417.213796 -327.161398)
		(width 0.1651)
		(layer "In13.Cu")
		(net "P5E_PEX3_STN5_TX_DN<94>")
	)
	(segment
		(start 420.185596 -311.670192)
		(end 420.299896 -311.784492)
		(width 0.1143)
		(layer "In13.Cu")
		(net "P5E_PEX3_STN5_TX_DN<94>")
	)
	(segment
		(start 419.920166 -319.971928)
		(end 419.920166 -311.773824)
		(width 0.1143)
		(layer "In13.Cu")
		(net "P5E_PEX3_STN5_TX_DN<94>")
	)
	(segment
		(start 403.14118 -342.439498)
		(end 402.85035 -342.148668)
		(width 0.1651)
		(layer "In13.Cu")
		(net "P5E_PEX3_STN5_TX_DN<94>")
	)
	(segment
		(start 419.920166 -311.773824)
		(end 420.023798 -311.670192)
		(width 0.1143)
		(layer "In13.Cu")
		(net "P5E_PEX3_STN5_TX_DN<94>")
	)
	(segment
		(start 420.023798 -311.670192)
		(end 420.185596 -311.670192)
		(width 0.1143)
		(layer "In13.Cu")
		(net "P5E_PEX3_STN5_TX_DN<94>")
	)
	(segment
		(start 402.85035 -341.549228)
		(end 403.070822 -340.925912)
		(width 0.1651)
		(layer "In13.Cu")
		(net "P5E_PEX3_STN5_TX_DN<94>")
	)
	(segment
		(start 83.998562 -357.75773)
		(end 83.703922 -357.46309)
		(width 0.13462)
		(layer "F.Cu")
		(net "P5E_PEX0_STN5_TX_C_DN<91>")
	)
	(segment
		(start 83.703922 -357.46309)
		(end 83.703922 -356.831646)
		(width 0.13462)
		(layer "F.Cu")
		(net "P5E_PEX0_STN5_TX_C_DN<91>")
	)
	(segment
		(start 83.703922 -356.831646)
		(end 84.023962 -356.511606)
		(width 0.13462)
		(layer "F.Cu")
		(net "P5E_PEX0_STN5_TX_C_DN<91>")
	)
	(segment
		(start 83.707732 -358.04856)
		(end 83.707732 -358.87533)
		(width 0.1651)
		(layer "In7.Cu")
		(net "P5E_PEX0_STN5_TX_C_DN<91>")
	)
	(segment
		(start 78.509876 -380.308104)
		(end 78.509876 -380.69012)
		(width 0.1651)
		(layer "In7.Cu")
		(net "P5E_PEX0_STN5_TX_C_DN<91>")
	)
	(segment
		(start 83.707732 -358.87533)
		(end 79.684372 -368.588798)
		(width 0.1651)
		(layer "In7.Cu")
		(net "P5E_PEX0_STN5_TX_C_DN<91>")
	)
	(segment
		(start 78.636876 -380.181104)
		(end 78.509876 -380.308104)
		(width 0.1651)
		(layer "In7.Cu")
		(net "P5E_PEX0_STN5_TX_C_DN<91>")
	)
	(segment
		(start 79.684372 -379.664722)
		(end 79.16799 -380.181104)
		(width 0.1651)
		(layer "In7.Cu")
		(net "P5E_PEX0_STN5_TX_C_DN<91>")
	)
	(segment
		(start 79.684372 -368.588798)
		(end 79.684372 -379.664722)
		(width 0.1651)
		(layer "In7.Cu")
		(net "P5E_PEX0_STN5_TX_C_DN<91>")
	)
	(segment
		(start 79.16799 -380.181104)
		(end 78.636876 -380.181104)
		(width 0.1651)
		(layer "In7.Cu")
		(net "P5E_PEX0_STN5_TX_C_DN<91>")
	)
	(segment
		(start 83.998562 -357.75773)
		(end 83.707732 -358.04856)
		(width 0.1651)
		(layer "In7.Cu")
		(net "P5E_PEX0_STN5_TX_C_DN<91>")
	)
	(segment
		(start 86.218522 -343.685622)
		(end 86.538562 -343.365582)
		(width 0.13462)
		(layer "F.Cu")
		(net "P5E_PEX0_STN6_TX_DP<100>")
	)
	(segment
		(start 86.538562 -342.734138)
		(end 86.243922 -342.439498)
		(width 0.13462)
		(layer "F.Cu")
		(net "P5E_PEX0_STN6_TX_DP<100>")
	)
	(segment
		(start 86.538562 -343.365582)
		(end 86.538562 -342.734138)
		(width 0.13462)
		(layer "F.Cu")
		(net "P5E_PEX0_STN6_TX_DP<100>")
	)
	(segment
		(start 53.949854 -313.290712)
		(end 53.860954 -313.379612)
		(width 0.1143)
		(layer "In13.Cu")
		(net "P5E_PEX0_STN6_TX_DP<100>")
	)
	(segment
		(start 55.026814 -324.683882)
		(end 62.473332 -327.768204)
		(width 0.1651)
		(layer "In13.Cu")
		(net "P5E_PEX0_STN6_TX_DP<100>")
	)
	(segment
		(start 86.534752 -341.263986)
		(end 86.534752 -342.148668)
		(width 0.1651)
		(layer "In13.Cu")
		(net "P5E_PEX0_STN6_TX_DP<100>")
	)
	(segment
		(start 54.260242 -323.91731)
		(end 55.026814 -324.683882)
		(width 0.1651)
		(layer "In13.Cu")
		(net "P5E_PEX0_STN6_TX_DP<100>")
	)
	(segment
		(start 53.379624 -320.181478)
		(end 53.333904 -320.227198)
		(width 0.1143)
		(layer "In13.Cu")
		(net "P5E_PEX0_STN6_TX_DP<100>")
	)
	(segment
		(start 53.949854 -312.999882)
		(end 53.949854 -313.290712)
		(width 0.1143)
		(layer "In13.Cu")
		(net "P5E_PEX0_STN6_TX_DP<100>")
	)
	(segment
		(start 53.333904 -321.68084)
		(end 54.260242 -323.91731)
		(width 0.1651)
		(layer "In13.Cu")
		(net "P5E_PEX0_STN6_TX_DP<100>")
	)
	(segment
		(start 86.534752 -342.148668)
		(end 86.243922 -342.439498)
		(width 0.1651)
		(layer "In13.Cu")
		(net "P5E_PEX0_STN6_TX_DP<100>")
	)
	(segment
		(start 53.333904 -320.249296)
		(end 53.333904 -321.68084)
		(width 0.1651)
		(layer "In13.Cu")
		(net "P5E_PEX0_STN6_TX_DP<100>")
	)
	(segment
		(start 53.379624 -313.618372)
		(end 53.379624 -320.181478)
		(width 0.1143)
		(layer "In13.Cu")
		(net "P5E_PEX0_STN6_TX_DP<100>")
	)
	(segment
		(start 85.17128 -339.900768)
		(end 86.534752 -341.263986)
		(width 0.1651)
		(layer "In13.Cu")
		(net "P5E_PEX0_STN6_TX_DP<100>")
	)
	(segment
		(start 62.473332 -327.768204)
		(end 85.17128 -339.900768)
		(width 0.1651)
		(layer "In13.Cu")
		(net "P5E_PEX0_STN6_TX_DP<100>")
	)
	(segment
		(start 53.860954 -313.379612)
		(end 53.618384 -313.379612)
		(width 0.1143)
		(layer "In13.Cu")
		(net "P5E_PEX0_STN6_TX_DP<100>")
	)
	(segment
		(start 53.618384 -313.379612)
		(end 53.379624 -313.618372)
		(width 0.1143)
		(layer "In13.Cu")
		(net "P5E_PEX0_STN6_TX_DP<100>")
	)
	(segment
		(start 53.333904 -320.227198)
		(end 53.333904 -320.249296)
		(width 0.1143)
		(layer "In13.Cu")
		(net "P5E_PEX0_STN6_TX_DP<100>")
	)
	(segment
		(start 322.718684 -355.978206)
		(end 322.398644 -355.658166)
		(width 0.13462)
		(layer "F.Cu")
		(net "P5E_PEX2_STN5_TX_DN<85>")
	)
	(segment
		(start 322.398644 -355.026722)
		(end 322.693284 -354.732082)
		(width 0.13462)
		(layer "F.Cu")
		(net "P5E_PEX2_STN5_TX_DN<85>")
	)
	(segment
		(start 322.398644 -355.658166)
		(end 322.398644 -355.026722)
		(width 0.13462)
		(layer "F.Cu")
		(net "P5E_PEX2_STN5_TX_DN<85>")
	)
	(segment
		(start 323.956934 -341.6808)
		(end 323.1642 -340.4616)
		(width 0.1651)
		(layer "In7.Cu")
		(net "P5E_PEX2_STN5_TX_DN<85>")
	)
	(segment
		(start 303.522634 -330.824078)
		(end 303.422558 -330.863956)
		(width 0.1651)
		(layer "In7.Cu")
		(net "P5E_PEX2_STN5_TX_DN<85>")
	)
	(segment
		(start 303.97831 -331.01915)
		(end 303.522634 -330.824078)
		(width 0.1651)
		(layer "In7.Cu")
		(net "P5E_PEX2_STN5_TX_DN<85>")
	)
	(segment
		(start 299.872654 -329.344274)
		(end 297.213782 -326.685402)
		(width 0.1651)
		(layer "In7.Cu")
		(net "P5E_PEX2_STN5_TX_DN<85>")
	)
	(segment
		(start 304.018442 -331.119226)
		(end 303.97831 -331.01915)
		(width 0.1651)
		(layer "In7.Cu")
		(net "P5E_PEX2_STN5_TX_DN<85>")
	)
	(segment
		(start 322.693284 -354.732082)
		(end 322.402454 -354.441252)
		(width 0.1651)
		(layer "In7.Cu")
		(net "P5E_PEX2_STN5_TX_DN<85>")
	)
	(segment
		(start 295.649904 -313.684412)
		(end 295.649904 -313.949842)
		(width 0.1143)
		(layer "In7.Cu")
		(net "P5E_PEX2_STN5_TX_DN<85>")
	)
	(segment
		(start 320.819018 -338.311998)
		(end 304.018442 -331.119226)
		(width 0.1651)
		(layer "In7.Cu")
		(net "P5E_PEX2_STN5_TX_DN<85>")
	)
	(segment
		(start 295.315894 -319.8368)
		(end 295.270174 -319.79108)
		(width 0.1143)
		(layer "In7.Cu")
		(net "P5E_PEX2_STN5_TX_DN<85>")
	)
	(segment
		(start 295.384474 -313.570112)
		(end 295.535604 -313.570112)
		(width 0.1143)
		(layer "In7.Cu")
		(net "P5E_PEX2_STN5_TX_DN<85>")
	)
	(segment
		(start 322.402454 -354.441252)
		(end 322.402454 -353.930966)
		(width 0.1651)
		(layer "In7.Cu")
		(net "P5E_PEX2_STN5_TX_DN<85>")
	)
	(segment
		(start 323.956934 -352.376486)
		(end 323.956934 -341.6808)
		(width 0.1651)
		(layer "In7.Cu")
		(net "P5E_PEX2_STN5_TX_DN<85>")
	)
	(segment
		(start 297.213782 -326.685402)
		(end 295.315894 -322.10375)
		(width 0.1651)
		(layer "In7.Cu")
		(net "P5E_PEX2_STN5_TX_DN<85>")
	)
	(segment
		(start 295.315894 -322.10375)
		(end 295.315894 -319.865248)
		(width 0.1651)
		(layer "In7.Cu")
		(net "P5E_PEX2_STN5_TX_DN<85>")
	)
	(segment
		(start 322.15455 -339.492844)
		(end 321.149726 -338.52866)
		(width 0.1651)
		(layer "In7.Cu")
		(net "P5E_PEX2_STN5_TX_DN<85>")
	)
	(segment
		(start 303.422558 -330.863956)
		(end 299.872654 -329.344274)
		(width 0.1651)
		(layer "In7.Cu")
		(net "P5E_PEX2_STN5_TX_DN<85>")
	)
	(segment
		(start 322.402454 -353.930966)
		(end 323.956934 -352.376486)
		(width 0.1651)
		(layer "In7.Cu")
		(net "P5E_PEX2_STN5_TX_DN<85>")
	)
	(segment
		(start 295.535604 -313.570112)
		(end 295.649904 -313.684412)
		(width 0.1143)
		(layer "In7.Cu")
		(net "P5E_PEX2_STN5_TX_DN<85>")
	)
	(segment
		(start 295.270174 -313.684412)
		(end 295.384474 -313.570112)
		(width 0.1143)
		(layer "In7.Cu")
		(net "P5E_PEX2_STN5_TX_DN<85>")
	)
	(segment
		(start 323.1642 -340.4616)
		(end 322.15455 -339.492844)
		(width 0.1651)
		(layer "In7.Cu")
		(net "P5E_PEX2_STN5_TX_DN<85>")
	)
	(segment
		(start 295.270174 -319.79108)
		(end 295.270174 -313.684412)
		(width 0.1143)
		(layer "In7.Cu")
		(net "P5E_PEX2_STN5_TX_DN<85>")
	)
	(segment
		(start 295.315894 -319.865248)
		(end 295.315894 -319.8368)
		(width 0.1143)
		(layer "In7.Cu")
		(net "P5E_PEX2_STN5_TX_DN<85>")
	)
	(segment
		(start 321.149726 -338.52866)
		(end 320.819018 -338.311998)
		(width 0.1651)
		(layer "In7.Cu")
		(net "P5E_PEX2_STN5_TX_DN<85>")
	)
	(segment
		(start 386.70738 -355.978206)
		(end 387.026912 -355.658674)
		(width 0.13462)
		(layer "F.Cu")
		(net "P5E_PEX3_STN5_TX_DP<80>")
	)
	(segment
		(start 387.026912 -355.658674)
		(end 387.026912 -355.026214)
		(width 0.13462)
		(layer "F.Cu")
		(net "P5E_PEX3_STN5_TX_DP<80>")
	)
	(segment
		(start 387.026912 -355.026214)
		(end 386.73278 -354.732082)
		(width 0.13462)
		(layer "F.Cu")
		(net "P5E_PEX3_STN5_TX_DP<80>")
	)
	(segment
		(start 387.02361 -354.441252)
		(end 387.02361 -353.814126)
		(width 0.1651)
		(layer "In7.Cu")
		(net "P5E_PEX3_STN5_TX_DP<80>")
	)
	(segment
		(start 386.73278 -354.732082)
		(end 387.02361 -354.441252)
		(width 0.1651)
		(layer "In7.Cu")
		(net "P5E_PEX3_STN5_TX_DP<80>")
	)
	(segment
		(start 406.383998 -322.612004)
		(end 406.383998 -319.9892)
		(width 0.1651)
		(layer "In7.Cu")
		(net "P5E_PEX3_STN5_TX_DP<80>")
	)
	(segment
		(start 406.383998 -319.960752)
		(end 406.429718 -319.915032)
		(width 0.1143)
		(layer "In7.Cu")
		(net "P5E_PEX3_STN5_TX_DP<80>")
	)
	(segment
		(start 406.885648 -311.479692)
		(end 406.999948 -311.365392)
		(width 0.1143)
		(layer "In7.Cu")
		(net "P5E_PEX3_STN5_TX_DP<80>")
	)
	(segment
		(start 388.585202 -341.785956)
		(end 404.913846 -325.702676)
		(width 0.1651)
		(layer "In7.Cu")
		(net "P5E_PEX3_STN5_TX_DP<80>")
	)
	(segment
		(start 406.383998 -319.9892)
		(end 406.383998 -319.960752)
		(width 0.1143)
		(layer "In7.Cu")
		(net "P5E_PEX3_STN5_TX_DP<80>")
	)
	(segment
		(start 404.913846 -325.702676)
		(end 405.40305 -324.979792)
		(width 0.1651)
		(layer "In7.Cu")
		(net "P5E_PEX3_STN5_TX_DP<80>")
	)
	(segment
		(start 388.585202 -352.252534)
		(end 388.585202 -341.785956)
		(width 0.1651)
		(layer "In7.Cu")
		(net "P5E_PEX3_STN5_TX_DP<80>")
	)
	(segment
		(start 406.429718 -311.705498)
		(end 406.655524 -311.479692)
		(width 0.1143)
		(layer "In7.Cu")
		(net "P5E_PEX3_STN5_TX_DP<80>")
	)
	(segment
		(start 387.02361 -353.814126)
		(end 388.585202 -352.252534)
		(width 0.1651)
		(layer "In7.Cu")
		(net "P5E_PEX3_STN5_TX_DP<80>")
	)
	(segment
		(start 406.429718 -319.915032)
		(end 406.429718 -311.705498)
		(width 0.1143)
		(layer "In7.Cu")
		(net "P5E_PEX3_STN5_TX_DP<80>")
	)
	(segment
		(start 405.40305 -324.979792)
		(end 406.383998 -322.612004)
		(width 0.1651)
		(layer "In7.Cu")
		(net "P5E_PEX3_STN5_TX_DP<80>")
	)
	(segment
		(start 406.655524 -311.479692)
		(end 406.885648 -311.479692)
		(width 0.1143)
		(layer "In7.Cu")
		(net "P5E_PEX3_STN5_TX_DP<80>")
	)
	(segment
		(start 406.999948 -311.365392)
		(end 406.999948 -311.099962)
		(width 0.1143)
		(layer "In7.Cu")
		(net "P5E_PEX3_STN5_TX_DP<80>")
	)
	(segment
		(start 77.486002 -356.831646)
		(end 77.806042 -356.511606)
		(width 0.13462)
		(layer "F.Cu")
		(net "P5E_PEX0_STN5_TX_C_DN<88>")
	)
	(segment
		(start 77.486002 -357.46309)
		(end 77.486002 -356.831646)
		(width 0.13462)
		(layer "F.Cu")
		(net "P5E_PEX0_STN5_TX_C_DN<88>")
	)
	(segment
		(start 77.780642 -357.75773)
		(end 77.486002 -357.46309)
		(width 0.13462)
		(layer "F.Cu")
		(net "P5E_PEX0_STN5_TX_C_DN<88>")
	)
	(segment
		(start 72.490076 -379.08103)
		(end 73.084182 -378.486924)
		(width 0.1651)
		(layer "In7.Cu")
		(net "P5E_PEX0_STN5_TX_C_DN<88>")
	)
	(segment
		(start 73.084182 -368.192812)
		(end 77.489812 -358.883458)
		(width 0.1651)
		(layer "In7.Cu")
		(net "P5E_PEX0_STN5_TX_C_DN<88>")
	)
	(segment
		(start 77.489812 -358.883458)
		(end 77.489812 -358.04856)
		(width 0.1651)
		(layer "In7.Cu")
		(net "P5E_PEX0_STN5_TX_C_DN<88>")
	)
	(segment
		(start 77.489812 -358.04856)
		(end 77.780642 -357.75773)
		(width 0.1651)
		(layer "In7.Cu")
		(net "P5E_PEX0_STN5_TX_C_DN<88>")
	)
	(segment
		(start 71.90994 -379.590046)
		(end 71.90994 -379.20803)
		(width 0.1651)
		(layer "In7.Cu")
		(net "P5E_PEX0_STN5_TX_C_DN<88>")
	)
	(segment
		(start 72.03694 -379.08103)
		(end 72.490076 -379.08103)
		(width 0.1651)
		(layer "In7.Cu")
		(net "P5E_PEX0_STN5_TX_C_DN<88>")
	)
	(segment
		(start 71.90994 -379.20803)
		(end 72.03694 -379.08103)
		(width 0.1651)
		(layer "In7.Cu")
		(net "P5E_PEX0_STN5_TX_C_DN<88>")
	)
	(segment
		(start 73.084182 -378.486924)
		(end 73.084182 -368.192812)
		(width 0.1651)
		(layer "In7.Cu")
		(net "P5E_PEX0_STN5_TX_C_DN<88>")
	)
	(segment
		(start 67.884802 -355.026722)
		(end 67.590162 -354.732082)
		(width 0.13462)
		(layer "F.Cu")
		(net "P5E_PEX0_STN6_TX_DP<108>")
	)
	(segment
		(start 67.884802 -355.658166)
		(end 67.884802 -355.026722)
		(width 0.13462)
		(layer "F.Cu")
		(net "P5E_PEX0_STN6_TX_DP<108>")
	)
	(segment
		(start 67.564762 -355.978206)
		(end 67.884802 -355.658166)
		(width 0.13462)
		(layer "F.Cu")
		(net "P5E_PEX0_STN6_TX_DP<108>")
	)
	(segment
		(start 45.73397 -324.05193)
		(end 45.73397 -320.203322)
		(width 0.1651)
		(layer "In13.Cu")
		(net "P5E_PEX0_STN6_TX_DP<108>")
	)
	(segment
		(start 45.77969 -320.135504)
		(end 45.77969 -313.618118)
		(width 0.1143)
		(layer "In13.Cu")
		(net "P5E_PEX0_STN6_TX_DP<108>")
	)
	(segment
		(start 67.880992 -353.635564)
		(end 69.435472 -352.081084)
		(width 0.1651)
		(layer "In13.Cu")
		(net "P5E_PEX0_STN6_TX_DP<108>")
	)
	(segment
		(start 45.77969 -313.618118)
		(end 46.018196 -313.379612)
		(width 0.1143)
		(layer "In13.Cu")
		(net "P5E_PEX0_STN6_TX_DP<108>")
	)
	(segment
		(start 45.73397 -320.203322)
		(end 45.73397 -320.181224)
		(width 0.1143)
		(layer "In13.Cu")
		(net "P5E_PEX0_STN6_TX_DP<108>")
	)
	(segment
		(start 46.26102 -313.379612)
		(end 46.34992 -313.290712)
		(width 0.1143)
		(layer "In13.Cu")
		(net "P5E_PEX0_STN6_TX_DP<108>")
	)
	(segment
		(start 67.590162 -354.732082)
		(end 67.880992 -354.441252)
		(width 0.1651)
		(layer "In13.Cu")
		(net "P5E_PEX0_STN6_TX_DP<108>")
	)
	(segment
		(start 47.250858 -327.714102)
		(end 45.73397 -324.05193)
		(width 0.1651)
		(layer "In13.Cu")
		(net "P5E_PEX0_STN6_TX_DP<108>")
	)
	(segment
		(start 67.880992 -354.441252)
		(end 67.880992 -353.635564)
		(width 0.1651)
		(layer "In13.Cu")
		(net "P5E_PEX0_STN6_TX_DP<108>")
	)
	(segment
		(start 50.70094 -331.164184)
		(end 47.250858 -327.714102)
		(width 0.1651)
		(layer "In13.Cu")
		(net "P5E_PEX0_STN6_TX_DP<108>")
	)
	(segment
		(start 69.435472 -341.011256)
		(end 52.092098 -331.74051)
		(width 0.1651)
		(layer "In13.Cu")
		(net "P5E_PEX0_STN6_TX_DP<108>")
	)
	(segment
		(start 52.092098 -331.74051)
		(end 50.70094 -331.164184)
		(width 0.1651)
		(layer "In13.Cu")
		(net "P5E_PEX0_STN6_TX_DP<108>")
	)
	(segment
		(start 46.34992 -313.290712)
		(end 46.34992 -312.999882)
		(width 0.1143)
		(layer "In13.Cu")
		(net "P5E_PEX0_STN6_TX_DP<108>")
	)
	(segment
		(start 45.73397 -320.181224)
		(end 45.77969 -320.135504)
		(width 0.1143)
		(layer "In13.Cu")
		(net "P5E_PEX0_STN6_TX_DP<108>")
	)
	(segment
		(start 46.018196 -313.379612)
		(end 46.26102 -313.379612)
		(width 0.1143)
		(layer "In13.Cu")
		(net "P5E_PEX0_STN6_TX_DP<108>")
	)
	(segment
		(start 69.435472 -352.081084)
		(end 69.435472 -341.011256)
		(width 0.1651)
		(layer "In13.Cu")
		(net "P5E_PEX0_STN6_TX_DP<108>")
	)
	(segment
		(start 319.015364 -349.511874)
		(end 319.015364 -348.88043)
		(width 0.13462)
		(layer "F.Cu")
		(net "P5E_PEX2_STN5_TX_DP<83>")
	)
	(segment
		(start 319.015364 -348.88043)
		(end 318.720724 -348.58579)
		(width 0.13462)
		(layer "F.Cu")
		(net "P5E_PEX2_STN5_TX_DP<83>")
	)
	(segment
		(start 318.695324 -349.831914)
		(end 319.015364 -349.511874)
		(width 0.13462)
		(layer "F.Cu")
		(net "P5E_PEX2_STN5_TX_DP<83>")
	)
	(segment
		(start 293.13378 -322.704714)
		(end 293.13378 -319.865248)
		(width 0.1651)
		(layer "In7.Cu")
		(net "P5E_PEX2_STN5_TX_DP<83>")
	)
	(segment
		(start 293.74973 -313.265312)
		(end 293.74973 -312.999882)
		(width 0.1143)
		(layer "In7.Cu")
		(net "P5E_PEX2_STN5_TX_DP<83>")
	)
	(segment
		(start 319.011554 -348.29496)
		(end 319.011554 -347.667834)
		(width 0.1651)
		(layer "In7.Cu")
		(net "P5E_PEX2_STN5_TX_DP<83>")
	)
	(segment
		(start 320.129154 -341.203534)
		(end 319.26911 -340.34349)
		(width 0.1651)
		(layer "In7.Cu")
		(net "P5E_PEX2_STN5_TX_DP<83>")
	)
	(segment
		(start 319.011554 -347.667834)
		(end 320.566034 -346.113354)
		(width 0.1651)
		(layer "In7.Cu")
		(net "P5E_PEX2_STN5_TX_DP<83>")
	)
	(segment
		(start 293.13378 -319.8368)
		(end 293.1795 -319.79108)
		(width 0.1143)
		(layer "In7.Cu")
		(net "P5E_PEX2_STN5_TX_DP<83>")
	)
	(segment
		(start 293.405306 -313.379612)
		(end 293.63543 -313.379612)
		(width 0.1143)
		(layer "In7.Cu")
		(net "P5E_PEX2_STN5_TX_DP<83>")
	)
	(segment
		(start 320.566034 -346.113354)
		(end 320.566034 -342.31834)
		(width 0.1651)
		(layer "In7.Cu")
		(net "P5E_PEX2_STN5_TX_DP<83>")
	)
	(segment
		(start 293.1795 -319.79108)
		(end 293.1795 -313.605418)
		(width 0.1143)
		(layer "In7.Cu")
		(net "P5E_PEX2_STN5_TX_DP<83>")
	)
	(segment
		(start 293.63543 -313.379612)
		(end 293.74973 -313.265312)
		(width 0.1143)
		(layer "In7.Cu")
		(net "P5E_PEX2_STN5_TX_DP<83>")
	)
	(segment
		(start 293.13378 -319.865248)
		(end 293.13378 -319.8368)
		(width 0.1143)
		(layer "In7.Cu")
		(net "P5E_PEX2_STN5_TX_DP<83>")
	)
	(segment
		(start 295.405556 -328.189336)
		(end 293.13378 -322.704714)
		(width 0.1651)
		(layer "In7.Cu")
		(net "P5E_PEX2_STN5_TX_DP<83>")
	)
	(segment
		(start 319.26911 -340.34349)
		(end 298.639738 -331.423518)
		(width 0.1651)
		(layer "In7.Cu")
		(net "P5E_PEX2_STN5_TX_DP<83>")
	)
	(segment
		(start 298.639738 -331.423518)
		(end 295.405556 -328.189336)
		(width 0.1651)
		(layer "In7.Cu")
		(net "P5E_PEX2_STN5_TX_DP<83>")
	)
	(segment
		(start 318.720724 -348.58579)
		(end 319.011554 -348.29496)
		(width 0.1651)
		(layer "In7.Cu")
		(net "P5E_PEX2_STN5_TX_DP<83>")
	)
	(segment
		(start 293.1795 -313.605418)
		(end 293.405306 -313.379612)
		(width 0.1143)
		(layer "In7.Cu")
		(net "P5E_PEX2_STN5_TX_DP<83>")
	)
	(segment
		(start 320.566034 -342.31834)
		(end 320.129154 -341.203534)
		(width 0.1651)
		(layer "In7.Cu")
		(net "P5E_PEX2_STN5_TX_DP<83>")
	)
	(segment
		(start 389.81634 -349.831914)
		(end 390.135872 -349.512382)
		(width 0.13462)
		(layer "F.Cu")
		(net "P5E_PEX3_STN5_TX_DP<81>")
	)
	(segment
		(start 390.135872 -348.879922)
		(end 389.84174 -348.58579)
		(width 0.13462)
		(layer "F.Cu")
		(net "P5E_PEX3_STN5_TX_DP<81>")
	)
	(segment
		(start 390.135872 -349.512382)
		(end 390.135872 -348.879922)
		(width 0.13462)
		(layer "F.Cu")
		(net "P5E_PEX3_STN5_TX_DP<81>")
	)
	(segment
		(start 405.177752 -326.899016)
		(end 405.810974 -326.15378)
		(width 0.1651)
		(layer "In7.Cu")
		(net "P5E_PEX3_STN5_TX_DP<81>")
	)
	(segment
		(start 405.810974 -326.15378)
		(end 406.239218 -325.512938)
		(width 0.1651)
		(layer "In7.Cu")
		(net "P5E_PEX3_STN5_TX_DP<81>")
	)
	(segment
		(start 407.379678 -313.605418)
		(end 407.605484 -313.379612)
		(width 0.1143)
		(layer "In7.Cu")
		(net "P5E_PEX3_STN5_TX_DP<81>")
	)
	(segment
		(start 406.239218 -325.512938)
		(end 407.333958 -322.870068)
		(width 0.1651)
		(layer "In7.Cu")
		(net "P5E_PEX3_STN5_TX_DP<81>")
	)
	(segment
		(start 390.13257 -347.667834)
		(end 391.68705 -346.113354)
		(width 0.1651)
		(layer "In7.Cu")
		(net "P5E_PEX3_STN5_TX_DP<81>")
	)
	(segment
		(start 407.835608 -313.379612)
		(end 407.949908 -313.265312)
		(width 0.1143)
		(layer "In7.Cu")
		(net "P5E_PEX3_STN5_TX_DP<81>")
	)
	(segment
		(start 390.13257 -348.29496)
		(end 390.13257 -347.667834)
		(width 0.1651)
		(layer "In7.Cu")
		(net "P5E_PEX3_STN5_TX_DP<81>")
	)
	(segment
		(start 407.949908 -313.265312)
		(end 407.949908 -312.999882)
		(width 0.1143)
		(layer "In7.Cu")
		(net "P5E_PEX3_STN5_TX_DP<81>")
	)
	(segment
		(start 391.68705 -346.113354)
		(end 391.68705 -341.511636)
		(width 0.1651)
		(layer "In7.Cu")
		(net "P5E_PEX3_STN5_TX_DP<81>")
	)
	(segment
		(start 391.68705 -341.511636)
		(end 405.177752 -326.899016)
		(width 0.1651)
		(layer "In7.Cu")
		(net "P5E_PEX3_STN5_TX_DP<81>")
	)
	(segment
		(start 407.333958 -322.870068)
		(end 407.333958 -319.9892)
		(width 0.1651)
		(layer "In7.Cu")
		(net "P5E_PEX3_STN5_TX_DP<81>")
	)
	(segment
		(start 407.605484 -313.379612)
		(end 407.835608 -313.379612)
		(width 0.1143)
		(layer "In7.Cu")
		(net "P5E_PEX3_STN5_TX_DP<81>")
	)
	(segment
		(start 407.379678 -319.915032)
		(end 407.379678 -313.605418)
		(width 0.1143)
		(layer "In7.Cu")
		(net "P5E_PEX3_STN5_TX_DP<81>")
	)
	(segment
		(start 389.84174 -348.58579)
		(end 390.13257 -348.29496)
		(width 0.1651)
		(layer "In7.Cu")
		(net "P5E_PEX3_STN5_TX_DP<81>")
	)
	(segment
		(start 407.333958 -319.9892)
		(end 407.333958 -319.960752)
		(width 0.1143)
		(layer "In7.Cu")
		(net "P5E_PEX3_STN5_TX_DP<81>")
	)
	(segment
		(start 407.333958 -319.960752)
		(end 407.379678 -319.915032)
		(width 0.1143)
		(layer "In7.Cu")
		(net "P5E_PEX3_STN5_TX_DP<81>")
	)
	(segment
		(start 41.389808 -356.831646)
		(end 41.069768 -356.511606)
		(width 0.13462)
		(layer "F.Cu")
		(net "P5E_PEX0_STN7_TX_C_DP<123>")
	)
	(segment
		(start 41.095168 -357.75773)
		(end 41.389808 -357.46309)
		(width 0.13462)
		(layer "F.Cu")
		(net "P5E_PEX0_STN7_TX_C_DP<123>")
	)
	(segment
		(start 41.389808 -357.46309)
		(end 41.389808 -356.831646)
		(width 0.13462)
		(layer "F.Cu")
		(net "P5E_PEX0_STN7_TX_C_DP<123>")
	)
	(segment
		(start 38.768782 -362.981748)
		(end 38.645338 -363.006386)
		(width 0.1651)
		(layer "In7.Cu")
		(net "P5E_PEX0_STN7_TX_C_DP<123>")
	)
	(segment
		(start 37.342572 -365.11611)
		(end 35.40252 -369.21821)
		(width 0.1651)
		(layer "In7.Cu")
		(net "P5E_PEX0_STN7_TX_C_DP<123>")
	)
	(segment
		(start 35.40252 -375.849388)
		(end 35.25266 -375.999248)
		(width 0.1651)
		(layer "In7.Cu")
		(net "P5E_PEX0_STN7_TX_C_DP<123>")
	)
	(segment
		(start 35.40252 -369.21821)
		(end 35.40252 -375.849388)
		(width 0.1651)
		(layer "In7.Cu")
		(net "P5E_PEX0_STN7_TX_C_DP<123>")
	)
	(segment
		(start 34.636964 -375.999248)
		(end 34.509964 -375.872248)
		(width 0.1651)
		(layer "In7.Cu")
		(net "P5E_PEX0_STN7_TX_C_DP<123>")
	)
	(segment
		(start 41.385998 -358.427528)
		(end 41.031922 -359.594658)
		(width 0.1651)
		(layer "In7.Cu")
		(net "P5E_PEX0_STN7_TX_C_DP<123>")
	)
	(segment
		(start 41.385998 -358.04856)
		(end 41.385998 -358.427528)
		(width 0.1651)
		(layer "In7.Cu")
		(net "P5E_PEX0_STN7_TX_C_DP<123>")
	)
	(segment
		(start 38.645338 -363.006386)
		(end 38.370002 -363.418374)
		(width 0.1651)
		(layer "In7.Cu")
		(net "P5E_PEX0_STN7_TX_C_DP<123>")
	)
	(segment
		(start 41.031922 -359.594658)
		(end 38.768782 -362.981748)
		(width 0.1651)
		(layer "In7.Cu")
		(net "P5E_PEX0_STN7_TX_C_DP<123>")
	)
	(segment
		(start 41.095168 -357.75773)
		(end 41.385998 -358.04856)
		(width 0.1651)
		(layer "In7.Cu")
		(net "P5E_PEX0_STN7_TX_C_DP<123>")
	)
	(segment
		(start 38.370002 -363.418374)
		(end 38.39464 -363.541564)
		(width 0.1651)
		(layer "In7.Cu")
		(net "P5E_PEX0_STN7_TX_C_DP<123>")
	)
	(segment
		(start 38.39464 -363.541564)
		(end 37.342572 -365.11611)
		(width 0.1651)
		(layer "In7.Cu")
		(net "P5E_PEX0_STN7_TX_C_DP<123>")
	)
	(segment
		(start 35.25266 -375.999248)
		(end 34.636964 -375.999248)
		(width 0.1651)
		(layer "In7.Cu")
		(net "P5E_PEX0_STN7_TX_C_DP<123>")
	)
	(segment
		(start 34.509964 -375.872248)
		(end 34.509964 -375.490232)
		(width 0.1651)
		(layer "In7.Cu")
		(net "P5E_PEX0_STN7_TX_C_DP<123>")
	)
	(segment
		(start 287.439862 -350.365314)
		(end 287.119822 -350.685354)
		(width 0.13462)
		(layer "F.Cu")
		(net "P5E_PEX2_STN7_TX_C_DP<121>")
	)
	(segment
		(start 287.119822 -351.316798)
		(end 287.414462 -351.611438)
		(width 0.13462)
		(layer "F.Cu")
		(net "P5E_PEX2_STN7_TX_C_DP<121>")
	)
	(segment
		(start 287.119822 -350.685354)
		(end 287.119822 -351.316798)
		(width 0.13462)
		(layer "F.Cu")
		(net "P5E_PEX2_STN7_TX_C_DP<121>")
	)
	(segment
		(start 285.569152 -358.4956)
		(end 290.815776 -368.6556)
		(width 0.1651)
		(layer "In7.Cu")
		(net "P5E_PEX2_STN7_TX_C_DP<121>")
	)
	(segment
		(start 289.689794 -376.408188)
		(end 289.689794 -376.790204)
		(width 0.1651)
		(layer "In7.Cu")
		(net "P5E_PEX2_STN7_TX_C_DP<121>")
	)
	(segment
		(start 290.815776 -368.6556)
		(end 290.815776 -375.829322)
		(width 0.1651)
		(layer "In7.Cu")
		(net "P5E_PEX2_STN7_TX_C_DP<121>")
	)
	(segment
		(start 290.815776 -375.829322)
		(end 290.36391 -376.281188)
		(width 0.1651)
		(layer "In7.Cu")
		(net "P5E_PEX2_STN7_TX_C_DP<121>")
	)
	(segment
		(start 287.414462 -351.611438)
		(end 287.123632 -351.902268)
		(width 0.1651)
		(layer "In7.Cu")
		(net "P5E_PEX2_STN7_TX_C_DP<121>")
	)
	(segment
		(start 289.816794 -376.281188)
		(end 289.689794 -376.408188)
		(width 0.1651)
		(layer "In7.Cu")
		(net "P5E_PEX2_STN7_TX_C_DP<121>")
	)
	(segment
		(start 290.36391 -376.281188)
		(end 289.816794 -376.281188)
		(width 0.1651)
		(layer "In7.Cu")
		(net "P5E_PEX2_STN7_TX_C_DP<121>")
	)
	(segment
		(start 287.123632 -351.902268)
		(end 287.123632 -352.473006)
		(width 0.1651)
		(layer "In7.Cu")
		(net "P5E_PEX2_STN7_TX_C_DP<121>")
	)
	(segment
		(start 285.569152 -354.027486)
		(end 285.569152 -358.4956)
		(width 0.1651)
		(layer "In7.Cu")
		(net "P5E_PEX2_STN7_TX_C_DP<121>")
	)
	(segment
		(start 287.123632 -352.473006)
		(end 285.569152 -354.027486)
		(width 0.1651)
		(layer "In7.Cu")
		(net "P5E_PEX2_STN7_TX_C_DP<121>")
	)
	(segment
		(start 80.320642 -343.365582)
		(end 80.320642 -342.734138)
		(width 0.13462)
		(layer "F.Cu")
		(net "P5E_PEX0_STN6_TX_DP<103>")
	)
	(segment
		(start 80.000602 -343.685622)
		(end 80.320642 -343.365582)
		(width 0.13462)
		(layer "F.Cu")
		(net "P5E_PEX0_STN6_TX_DP<103>")
	)
	(segment
		(start 80.320642 -342.734138)
		(end 80.026002 -342.439498)
		(width 0.13462)
		(layer "F.Cu")
		(net "P5E_PEX0_STN6_TX_DP<103>")
	)
	(segment
		(start 50.484024 -320.158872)
		(end 50.529744 -320.113152)
		(width 0.1143)
		(layer "In13.Cu")
		(net "P5E_PEX0_STN6_TX_DP<103>")
	)
	(segment
		(start 50.529744 -320.113152)
		(end 50.529744 -311.718198)
		(width 0.1143)
		(layer "In13.Cu")
		(net "P5E_PEX0_STN6_TX_DP<103>")
	)
	(segment
		(start 50.484024 -320.18097)
		(end 50.484024 -320.158872)
		(width 0.1143)
		(layer "In13.Cu")
		(net "P5E_PEX0_STN6_TX_DP<103>")
	)
	(segment
		(start 80.316832 -342.148668)
		(end 80.316832 -341.656924)
		(width 0.1651)
		(layer "In13.Cu")
		(net "P5E_PEX0_STN6_TX_DP<103>")
	)
	(segment
		(start 56.486806 -328.390758)
		(end 53.40477 -327.114154)
		(width 0.1651)
		(layer "In13.Cu")
		(net "P5E_PEX0_STN6_TX_DP<103>")
	)
	(segment
		(start 80.316832 -341.656924)
		(end 79.850234 -340.879176)
		(width 0.1651)
		(layer "In13.Cu")
		(net "P5E_PEX0_STN6_TX_DP<103>")
	)
	(segment
		(start 79.850234 -340.879176)
		(end 56.486806 -328.390758)
		(width 0.1651)
		(layer "In13.Cu")
		(net "P5E_PEX0_STN6_TX_DP<103>")
	)
	(segment
		(start 50.529744 -311.718198)
		(end 50.76825 -311.479692)
		(width 0.1143)
		(layer "In13.Cu")
		(net "P5E_PEX0_STN6_TX_DP<103>")
	)
	(segment
		(start 80.026002 -342.439498)
		(end 80.316832 -342.148668)
		(width 0.1651)
		(layer "In13.Cu")
		(net "P5E_PEX0_STN6_TX_DP<103>")
	)
	(segment
		(start 53.40477 -327.114154)
		(end 51.683158 -325.392542)
		(width 0.1651)
		(layer "In13.Cu")
		(net "P5E_PEX0_STN6_TX_DP<103>")
	)
	(segment
		(start 51.011074 -311.479692)
		(end 51.099974 -311.390792)
		(width 0.1143)
		(layer "In13.Cu")
		(net "P5E_PEX0_STN6_TX_DP<103>")
	)
	(segment
		(start 50.76825 -311.479692)
		(end 51.011074 -311.479692)
		(width 0.1143)
		(layer "In13.Cu")
		(net "P5E_PEX0_STN6_TX_DP<103>")
	)
	(segment
		(start 50.484024 -322.49745)
		(end 50.484024 -320.18097)
		(width 0.1651)
		(layer "In13.Cu")
		(net "P5E_PEX0_STN6_TX_DP<103>")
	)
	(segment
		(start 51.683158 -325.392542)
		(end 50.484024 -322.49745)
		(width 0.1651)
		(layer "In13.Cu")
		(net "P5E_PEX0_STN6_TX_DP<103>")
	)
	(segment
		(start 51.099974 -311.390792)
		(end 51.099974 -311.099962)
		(width 0.1143)
		(layer "In13.Cu")
		(net "P5E_PEX0_STN6_TX_DP<103>")
	)
	(segment
		(start 332.147164 -30.92069)
		(end 331.853794 -30.62732)
		(width 0.13462)
		(layer "F.Cu")
		(net "P5E_PEX2_STN2_TX_DP<33>")
	)
	(segment
		(start 331.21981 -30.62732)
		(end 330.90104 -30.94609)
		(width 0.13462)
		(layer "F.Cu")
		(net "P5E_PEX2_STN2_TX_DP<33>")
	)
	(segment
		(start 331.853794 -30.62732)
		(end 331.21981 -30.62732)
		(width 0.13462)
		(layer "F.Cu")
		(net "P5E_PEX2_STN2_TX_DP<33>")
	)
	(segment
		(start 336.701892 -35.585146)
		(end 336.939636 -36.020248)
		(width 0.1651)
		(layer "In11.Cu")
		(net "P5E_PEX2_STN2_TX_DP<33>")
	)
	(segment
		(start 289.594798 -278.420068)
		(end 289.83559 -278.420068)
		(width 0.1143)
		(layer "In11.Cu")
		(net "P5E_PEX2_STN2_TX_DP<33>")
	)
	(segment
		(start 338.103464 -68.424552)
		(end 335.817972 -74.822304)
		(width 0.1651)
		(layer "In11.Cu")
		(net "P5E_PEX2_STN2_TX_DP<33>")
	)
	(segment
		(start 312.937398 -105.463594)
		(end 311.31383 -118.530624)
		(width 0.1651)
		(layer "In11.Cu")
		(net "P5E_PEX2_STN2_TX_DP<33>")
	)
	(segment
		(start 339.596476 -40.728392)
		(end 340.088982 -42.583862)
		(width 0.1651)
		(layer "In11.Cu")
		(net "P5E_PEX2_STN2_TX_DP<33>")
	)
	(segment
		(start 289.37966 -271.473168)
		(end 289.37966 -278.20493)
		(width 0.1143)
		(layer "In11.Cu")
		(net "P5E_PEX2_STN2_TX_DP<33>")
	)
	(segment
		(start 335.103216 -75.784202)
		(end 328.535792 -79.352648)
		(width 0.1651)
		(layer "In11.Cu")
		(net "P5E_PEX2_STN2_TX_DP<33>")
	)
	(segment
		(start 319.813432 -93.315536)
		(end 312.937398 -105.463594)
		(width 0.1651)
		(layer "In11.Cu")
		(net "P5E_PEX2_STN2_TX_DP<33>")
	)
	(segment
		(start 332.437994 -30.62986)
		(end 332.879954 -30.62986)
		(width 0.1651)
		(layer "In11.Cu")
		(net "P5E_PEX2_STN2_TX_DP<33>")
	)
	(segment
		(start 340.360762 -56.83631)
		(end 338.103464 -68.424552)
		(width 0.1651)
		(layer "In11.Cu")
		(net "P5E_PEX2_STN2_TX_DP<33>")
	)
	(segment
		(start 289.33394 -271.427448)
		(end 289.37966 -271.473168)
		(width 0.1143)
		(layer "In11.Cu")
		(net "P5E_PEX2_STN2_TX_DP<33>")
	)
	(segment
		(start 336.495136 -35.047174)
		(end 336.732372 -35.481768)
		(width 0.1651)
		(layer "In11.Cu")
		(net "P5E_PEX2_STN2_TX_DP<33>")
	)
	(segment
		(start 336.154268 -34.581846)
		(end 336.391758 -35.016948)
		(width 0.1651)
		(layer "In11.Cu")
		(net "P5E_PEX2_STN2_TX_DP<33>")
	)
	(segment
		(start 310.660796 -140.36929)
		(end 310.318912 -141.840458)
		(width 0.1651)
		(layer "In11.Cu")
		(net "P5E_PEX2_STN2_TX_DP<33>")
	)
	(segment
		(start 335.166208 -32.612838)
		(end 336.184494 -34.478468)
		(width 0.1651)
		(layer "In11.Cu")
		(net "P5E_PEX2_STN2_TX_DP<33>")
	)
	(segment
		(start 289.33394 -271.399)
		(end 289.33394 -271.427448)
		(width 0.1143)
		(layer "In11.Cu")
		(net "P5E_PEX2_STN2_TX_DP<33>")
	)
	(segment
		(start 311.31383 -118.530624)
		(end 310.660796 -133.834886)
		(width 0.1651)
		(layer "In11.Cu")
		(net "P5E_PEX2_STN2_TX_DP<33>")
	)
	(segment
		(start 337.043014 -36.050474)
		(end 339.596476 -40.728392)
		(width 0.1651)
		(layer "In11.Cu")
		(net "P5E_PEX2_STN2_TX_DP<33>")
	)
	(segment
		(start 310.045862 -148.226526)
		(end 309.81904 -150.913846)
		(width 0.1651)
		(layer "In11.Cu")
		(net "P5E_PEX2_STN2_TX_DP<33>")
	)
	(segment
		(start 332.879954 -30.62986)
		(end 333.386684 -30.852618)
		(width 0.1651)
		(layer "In11.Cu")
		(net "P5E_PEX2_STN2_TX_DP<33>")
	)
	(segment
		(start 289.94989 -278.534368)
		(end 289.94989 -278.799798)
		(width 0.1143)
		(layer "In11.Cu")
		(net "P5E_PEX2_STN2_TX_DP<33>")
	)
	(segment
		(start 335.817972 -74.822304)
		(end 335.103216 -75.784202)
		(width 0.1651)
		(layer "In11.Cu")
		(net "P5E_PEX2_STN2_TX_DP<33>")
	)
	(segment
		(start 336.184494 -34.478468)
		(end 336.154268 -34.581846)
		(width 0.1651)
		(layer "In11.Cu")
		(net "P5E_PEX2_STN2_TX_DP<33>")
	)
	(segment
		(start 326.681338 -81.181702)
		(end 319.813178 -93.315536)
		(width 0.1651)
		(layer "In11.Cu")
		(net "P5E_PEX2_STN2_TX_DP<33>")
	)
	(segment
		(start 336.732372 -35.481768)
		(end 336.701892 -35.585146)
		(width 0.1651)
		(layer "In11.Cu")
		(net "P5E_PEX2_STN2_TX_DP<33>")
	)
	(segment
		(start 309.592218 -153.60142)
		(end 308.600094 -161.016188)
		(width 0.1651)
		(layer "In11.Cu")
		(net "P5E_PEX2_STN2_TX_DP<33>")
	)
	(segment
		(start 310.660796 -133.834886)
		(end 310.660796 -140.36929)
		(width 0.1651)
		(layer "In11.Cu")
		(net "P5E_PEX2_STN2_TX_DP<33>")
	)
	(segment
		(start 289.37966 -278.20493)
		(end 289.594798 -278.420068)
		(width 0.1143)
		(layer "In11.Cu")
		(net "P5E_PEX2_STN2_TX_DP<33>")
	)
	(segment
		(start 309.818786 -150.913846)
		(end 309.592218 -153.60142)
		(width 0.1651)
		(layer "In11.Cu")
		(net "P5E_PEX2_STN2_TX_DP<33>")
	)
	(segment
		(start 333.386684 -30.852618)
		(end 335.166208 -32.612838)
		(width 0.1651)
		(layer "In11.Cu")
		(net "P5E_PEX2_STN2_TX_DP<33>")
	)
	(segment
		(start 332.147164 -30.92069)
		(end 332.437994 -30.62986)
		(width 0.1651)
		(layer "In11.Cu")
		(net "P5E_PEX2_STN2_TX_DP<33>")
	)
	(segment
		(start 336.391758 -35.016948)
		(end 336.495136 -35.047174)
		(width 0.1651)
		(layer "In11.Cu")
		(net "P5E_PEX2_STN2_TX_DP<33>")
	)
	(segment
		(start 308.600094 -161.016188)
		(end 289.33394 -265.833606)
		(width 0.1651)
		(layer "In11.Cu")
		(net "P5E_PEX2_STN2_TX_DP<33>")
	)
	(segment
		(start 289.33394 -265.833606)
		(end 289.33394 -271.399)
		(width 0.1651)
		(layer "In11.Cu")
		(net "P5E_PEX2_STN2_TX_DP<33>")
	)
	(segment
		(start 310.318912 -141.840458)
		(end 310.045862 -148.226526)
		(width 0.1651)
		(layer "In11.Cu")
		(net "P5E_PEX2_STN2_TX_DP<33>")
	)
	(segment
		(start 336.939636 -36.020248)
		(end 337.043014 -36.050474)
		(width 0.1651)
		(layer "In11.Cu")
		(net "P5E_PEX2_STN2_TX_DP<33>")
	)
	(segment
		(start 340.088982 -42.583862)
		(end 340.360762 -56.83631)
		(width 0.1651)
		(layer "In11.Cu")
		(net "P5E_PEX2_STN2_TX_DP<33>")
	)
	(segment
		(start 289.83559 -278.420068)
		(end 289.94989 -278.534368)
		(width 0.1143)
		(layer "In11.Cu")
		(net "P5E_PEX2_STN2_TX_DP<33>")
	)
	(segment
		(start 328.535792 -79.352648)
		(end 326.681338 -81.181702)
		(width 0.1651)
		(layer "In11.Cu")
		(net "P5E_PEX2_STN2_TX_DP<33>")
	)
	(segment
		(start 319.813178 -93.315536)
		(end 319.813432 -93.315536)
		(width 0.1651)
		(layer "In11.Cu")
		(net "P5E_PEX2_STN2_TX_DP<33>")
	)
	(segment
		(start 309.81904 -150.913846)
		(end 309.818786 -150.913846)
		(width 0.1651)
		(layer "In11.Cu")
		(net "P5E_PEX2_STN2_TX_DP<33>")
	)
	(segment
		(start 422.247314 -34.520886)
		(end 421.952928 -34.2265)
		(width 0.13462)
		(layer "F.Cu")
		(net "P5E_PEX3_STN2_TX_DP<39>")
	)
	(segment
		(start 421.320976 -34.2265)
		(end 421.00119 -34.546286)
		(width 0.13462)
		(layer "F.Cu")
		(net "P5E_PEX3_STN2_TX_DP<39>")
	)
	(segment
		(start 421.952928 -34.2265)
		(end 421.320976 -34.2265)
		(width 0.13462)
		(layer "F.Cu")
		(net "P5E_PEX3_STN2_TX_DP<39>")
	)
	(segment
		(start 423.51071 -34.419794)
		(end 425.102528 -36.024312)
		(width 0.1651)
		(layer "In11.Cu")
		(net "P5E_PEX3_STN2_TX_DP<39>")
	)
	(segment
		(start 425.818808 -37.36467)
		(end 425.940982 -37.394134)
		(width 0.1651)
		(layer "In11.Cu")
		(net "P5E_PEX3_STN2_TX_DP<39>")
	)
	(segment
		(start 399.779744 -278.20493)
		(end 399.994882 -278.420068)
		(width 0.1143)
		(layer "In11.Cu")
		(net "P5E_PEX3_STN2_TX_DP<39>")
	)
	(segment
		(start 399.734024 -271.427448)
		(end 399.779744 -271.473168)
		(width 0.1143)
		(layer "In11.Cu")
		(net "P5E_PEX3_STN2_TX_DP<39>")
	)
	(segment
		(start 409.370022 -107.162092)
		(end 407.94686 -114.435636)
		(width 0.1651)
		(layer "In11.Cu")
		(net "P5E_PEX3_STN2_TX_DP<39>")
	)
	(segment
		(start 425.559982 -36.942014)
		(end 425.818808 -37.36467)
		(width 0.1651)
		(layer "In11.Cu")
		(net "P5E_PEX3_STN2_TX_DP<39>")
	)
	(segment
		(start 436.295038 -58.556144)
		(end 436.295038 -60.128404)
		(width 0.1651)
		(layer "In11.Cu")
		(net "P5E_PEX3_STN2_TX_DP<39>")
	)
	(segment
		(start 407.22931 -120.262396)
		(end 407.228802 -120.262396)
		(width 0.1651)
		(layer "In11.Cu")
		(net "P5E_PEX3_STN2_TX_DP<39>")
	)
	(segment
		(start 434.942488 -63.68415)
		(end 412.669482 -92.692474)
		(width 0.1651)
		(layer "In11.Cu")
		(net "P5E_PEX3_STN2_TX_DP<39>")
	)
	(segment
		(start 422.247314 -34.520886)
		(end 422.538144 -34.230056)
		(width 0.1651)
		(layer "In11.Cu")
		(net "P5E_PEX3_STN2_TX_DP<39>")
	)
	(segment
		(start 426.55109 -38.39083)
		(end 428.768764 -42.014394)
		(width 0.1651)
		(layer "In11.Cu")
		(net "P5E_PEX3_STN2_TX_DP<39>")
	)
	(segment
		(start 400.349974 -278.534368)
		(end 400.349974 -278.799798)
		(width 0.1143)
		(layer "In11.Cu")
		(net "P5E_PEX3_STN2_TX_DP<39>")
	)
	(segment
		(start 426.1993 -37.816536)
		(end 426.17009 -37.93871)
		(width 0.1651)
		(layer "In11.Cu")
		(net "P5E_PEX3_STN2_TX_DP<39>")
	)
	(segment
		(start 399.994882 -278.420068)
		(end 400.235674 -278.420068)
		(width 0.1143)
		(layer "In11.Cu")
		(net "P5E_PEX3_STN2_TX_DP<39>")
	)
	(segment
		(start 425.102528 -36.024312)
		(end 425.589446 -36.819586)
		(width 0.1651)
		(layer "In11.Cu")
		(net "P5E_PEX3_STN2_TX_DP<39>")
	)
	(segment
		(start 435.811168 -61.953394)
		(end 434.942488 -63.68415)
		(width 0.1651)
		(layer "In11.Cu")
		(net "P5E_PEX3_STN2_TX_DP<39>")
	)
	(segment
		(start 400.235674 -278.420068)
		(end 400.349974 -278.534368)
		(width 0.1143)
		(layer "In11.Cu")
		(net "P5E_PEX3_STN2_TX_DP<39>")
	)
	(segment
		(start 407.94686 -114.435636)
		(end 407.22931 -120.262396)
		(width 0.1651)
		(layer "In11.Cu")
		(net "P5E_PEX3_STN2_TX_DP<39>")
	)
	(segment
		(start 407.084784 -121.433336)
		(end 399.734024 -262.791702)
		(width 0.1651)
		(layer "In11.Cu")
		(net "P5E_PEX3_STN2_TX_DP<39>")
	)
	(segment
		(start 407.228802 -120.262396)
		(end 407.206196 -120.44807)
		(width 0.1651)
		(layer "In11.Cu")
		(net "P5E_PEX3_STN2_TX_DP<39>")
	)
	(segment
		(start 412.669482 -92.692474)
		(end 409.370022 -107.162092)
		(width 0.1651)
		(layer "In11.Cu")
		(net "P5E_PEX3_STN2_TX_DP<39>")
	)
	(segment
		(start 425.589446 -36.819586)
		(end 425.559982 -36.942014)
		(width 0.1651)
		(layer "In11.Cu")
		(net "P5E_PEX3_STN2_TX_DP<39>")
	)
	(segment
		(start 399.734024 -271.399)
		(end 399.734024 -271.427448)
		(width 0.1143)
		(layer "In11.Cu")
		(net "P5E_PEX3_STN2_TX_DP<39>")
	)
	(segment
		(start 423.055542 -34.230056)
		(end 423.51071 -34.419794)
		(width 0.1651)
		(layer "In11.Cu")
		(net "P5E_PEX3_STN2_TX_DP<39>")
	)
	(segment
		(start 436.295038 -60.128404)
		(end 435.811168 -61.953394)
		(width 0.1651)
		(layer "In11.Cu")
		(net "P5E_PEX3_STN2_TX_DP<39>")
	)
	(segment
		(start 435.31155 -49.155858)
		(end 436.295038 -58.556144)
		(width 0.1651)
		(layer "In11.Cu")
		(net "P5E_PEX3_STN2_TX_DP<39>")
	)
	(segment
		(start 407.206196 -120.44807)
		(end 407.205942 -120.44807)
		(width 0.1651)
		(layer "In11.Cu")
		(net "P5E_PEX3_STN2_TX_DP<39>")
	)
	(segment
		(start 407.205942 -120.44807)
		(end 407.084784 -121.433336)
		(width 0.1651)
		(layer "In11.Cu")
		(net "P5E_PEX3_STN2_TX_DP<39>")
	)
	(segment
		(start 426.428916 -38.361366)
		(end 426.55109 -38.39083)
		(width 0.1651)
		(layer "In11.Cu")
		(net "P5E_PEX3_STN2_TX_DP<39>")
	)
	(segment
		(start 422.538144 -34.230056)
		(end 423.055542 -34.230056)
		(width 0.1651)
		(layer "In11.Cu")
		(net "P5E_PEX3_STN2_TX_DP<39>")
	)
	(segment
		(start 426.17009 -37.93871)
		(end 426.428916 -38.361366)
		(width 0.1651)
		(layer "In11.Cu")
		(net "P5E_PEX3_STN2_TX_DP<39>")
	)
	(segment
		(start 425.940982 -37.394134)
		(end 426.1993 -37.816536)
		(width 0.1651)
		(layer "In11.Cu")
		(net "P5E_PEX3_STN2_TX_DP<39>")
	)
	(segment
		(start 399.779744 -271.473168)
		(end 399.779744 -278.20493)
		(width 0.1143)
		(layer "In11.Cu")
		(net "P5E_PEX3_STN2_TX_DP<39>")
	)
	(segment
		(start 428.768764 -42.014394)
		(end 435.31155 -49.155858)
		(width 0.1651)
		(layer "In11.Cu")
		(net "P5E_PEX3_STN2_TX_DP<39>")
	)
	(segment
		(start 399.734024 -262.791702)
		(end 399.734024 -271.399)
		(width 0.1651)
		(layer "In11.Cu")
		(net "P5E_PEX3_STN2_TX_DP<39>")
	)
	(segment
		(start 80.026002 -351.611438)
		(end 80.320642 -351.316798)
		(width 0.13462)
		(layer "F.Cu")
		(net "P5E_PEX0_STN5_TX_C_DP<89>")
	)
	(segment
		(start 80.320642 -350.685354)
		(end 80.000602 -350.365314)
		(width 0.13462)
		(layer "F.Cu")
		(net "P5E_PEX0_STN5_TX_C_DP<89>")
	)
	(segment
		(start 80.320642 -351.316798)
		(end 80.320642 -350.685354)
		(width 0.13462)
		(layer "F.Cu")
		(net "P5E_PEX0_STN5_TX_C_DP<89>")
	)
	(segment
		(start 75.00239 -379.547882)
		(end 74.651108 -379.899164)
		(width 0.1651)
		(layer "In7.Cu")
		(net "P5E_PEX0_STN5_TX_C_DP<89>")
	)
	(segment
		(start 80.026002 -351.611438)
		(end 80.316832 -351.902268)
		(width 0.1651)
		(layer "In7.Cu")
		(net "P5E_PEX0_STN5_TX_C_DP<89>")
	)
	(segment
		(start 75.00239 -368.592608)
		(end 75.00239 -379.547882)
		(width 0.1651)
		(layer "In7.Cu")
		(net "P5E_PEX0_STN5_TX_C_DP<89>")
	)
	(segment
		(start 78.380082 -360.43743)
		(end 75.91679 -366.385094)
		(width 0.1651)
		(layer "In7.Cu")
		(net "P5E_PEX0_STN5_TX_C_DP<89>")
	)
	(segment
		(start 78.762352 -353.990402)
		(end 78.762352 -358.516936)
		(width 0.1651)
		(layer "In7.Cu")
		(net "P5E_PEX0_STN5_TX_C_DP<89>")
	)
	(segment
		(start 80.316832 -351.902268)
		(end 80.316832 -352.435922)
		(width 0.1651)
		(layer "In7.Cu")
		(net "P5E_PEX0_STN5_TX_C_DP<89>")
	)
	(segment
		(start 80.316832 -352.435922)
		(end 78.762352 -353.990402)
		(width 0.1651)
		(layer "In7.Cu")
		(net "P5E_PEX0_STN5_TX_C_DP<89>")
	)
	(segment
		(start 75.91679 -366.385094)
		(end 75.817222 -366.426496)
		(width 0.1651)
		(layer "In7.Cu")
		(net "P5E_PEX0_STN5_TX_C_DP<89>")
	)
	(segment
		(start 74.109834 -379.772164)
		(end 74.109834 -379.390148)
		(width 0.1651)
		(layer "In7.Cu")
		(net "P5E_PEX0_STN5_TX_C_DP<89>")
	)
	(segment
		(start 74.236834 -379.899164)
		(end 74.109834 -379.772164)
		(width 0.1651)
		(layer "In7.Cu")
		(net "P5E_PEX0_STN5_TX_C_DP<89>")
	)
	(segment
		(start 75.627484 -366.884204)
		(end 75.668632 -366.983772)
		(width 0.1651)
		(layer "In7.Cu")
		(net "P5E_PEX0_STN5_TX_C_DP<89>")
	)
	(segment
		(start 75.817222 -366.426496)
		(end 75.627484 -366.884204)
		(width 0.1651)
		(layer "In7.Cu")
		(net "P5E_PEX0_STN5_TX_C_DP<89>")
	)
	(segment
		(start 75.668632 -366.983772)
		(end 75.00239 -368.592608)
		(width 0.1651)
		(layer "In7.Cu")
		(net "P5E_PEX0_STN5_TX_C_DP<89>")
	)
	(segment
		(start 78.762352 -358.516936)
		(end 78.380082 -360.43743)
		(width 0.1651)
		(layer "In7.Cu")
		(net "P5E_PEX0_STN5_TX_C_DP<89>")
	)
	(segment
		(start 74.651108 -379.899164)
		(end 74.236834 -379.899164)
		(width 0.1651)
		(layer "In7.Cu")
		(net "P5E_PEX0_STN5_TX_C_DP<89>")
	)
	(segment
		(start 283.736542 -356.831646)
		(end 283.736542 -357.46309)
		(width 0.13462)
		(layer "F.Cu")
		(net "P5E_PEX2_STN7_TX_C_DP<120>")
	)
	(segment
		(start 283.736542 -357.46309)
		(end 283.441902 -357.75773)
		(width 0.13462)
		(layer "F.Cu")
		(net "P5E_PEX2_STN7_TX_C_DP<120>")
	)
	(segment
		(start 283.416502 -356.511606)
		(end 283.736542 -356.831646)
		(width 0.13462)
		(layer "F.Cu")
		(net "P5E_PEX2_STN7_TX_C_DP<120>")
	)
	(segment
		(start 287.36671 -366.604296)
		(end 287.574736 -367.053622)
		(width 0.1651)
		(layer "In7.Cu")
		(net "P5E_PEX2_STN7_TX_C_DP<120>")
	)
	(segment
		(start 283.732732 -358.76103)
		(end 286.101028 -363.873034)
		(width 0.1651)
		(layer "In7.Cu")
		(net "P5E_PEX2_STN7_TX_C_DP<120>")
	)
	(segment
		(start 286.592264 -364.93323)
		(end 286.54883 -365.051086)
		(width 0.1651)
		(layer "In7.Cu")
		(net "P5E_PEX2_STN7_TX_C_DP<120>")
	)
	(segment
		(start 287.857692 -367.664492)
		(end 288.333942 -368.69243)
		(width 0.1651)
		(layer "In7.Cu")
		(net "P5E_PEX2_STN7_TX_C_DP<120>")
	)
	(segment
		(start 287.0835 -365.993426)
		(end 287.040066 -366.111282)
		(width 0.1651)
		(layer "In7.Cu")
		(net "P5E_PEX2_STN7_TX_C_DP<120>")
	)
	(segment
		(start 286.057594 -363.99089)
		(end 286.266128 -364.440724)
		(width 0.1651)
		(layer "In7.Cu")
		(net "P5E_PEX2_STN7_TX_C_DP<120>")
	)
	(segment
		(start 286.384238 -364.483904)
		(end 286.592264 -364.93323)
		(width 0.1651)
		(layer "In7.Cu")
		(net "P5E_PEX2_STN7_TX_C_DP<120>")
	)
	(segment
		(start 286.101028 -363.873034)
		(end 286.057594 -363.99089)
		(width 0.1651)
		(layer "In7.Cu")
		(net "P5E_PEX2_STN7_TX_C_DP<120>")
	)
	(segment
		(start 283.441902 -357.75773)
		(end 283.732732 -358.04856)
		(width 0.1651)
		(layer "In7.Cu")
		(net "P5E_PEX2_STN7_TX_C_DP<120>")
	)
	(segment
		(start 287.4899 -374.772174)
		(end 287.4899 -374.390158)
		(width 0.1651)
		(layer "In7.Cu")
		(net "P5E_PEX2_STN7_TX_C_DP<120>")
	)
	(segment
		(start 287.574736 -367.053622)
		(end 287.531302 -367.171732)
		(width 0.1651)
		(layer "In7.Cu")
		(net "P5E_PEX2_STN7_TX_C_DP<120>")
	)
	(segment
		(start 286.54883 -365.051086)
		(end 286.757364 -365.50092)
		(width 0.1651)
		(layer "In7.Cu")
		(net "P5E_PEX2_STN7_TX_C_DP<120>")
	)
	(segment
		(start 286.875474 -365.5441)
		(end 287.0835 -365.993426)
		(width 0.1651)
		(layer "In7.Cu")
		(net "P5E_PEX2_STN7_TX_C_DP<120>")
	)
	(segment
		(start 287.040066 -366.111282)
		(end 287.2486 -366.561116)
		(width 0.1651)
		(layer "In7.Cu")
		(net "P5E_PEX2_STN7_TX_C_DP<120>")
	)
	(segment
		(start 288.333942 -374.612408)
		(end 288.047176 -374.899174)
		(width 0.1651)
		(layer "In7.Cu")
		(net "P5E_PEX2_STN7_TX_C_DP<120>")
	)
	(segment
		(start 283.732732 -358.04856)
		(end 283.732732 -358.76103)
		(width 0.1651)
		(layer "In7.Cu")
		(net "P5E_PEX2_STN7_TX_C_DP<120>")
	)
	(segment
		(start 287.2486 -366.561116)
		(end 287.36671 -366.604296)
		(width 0.1651)
		(layer "In7.Cu")
		(net "P5E_PEX2_STN7_TX_C_DP<120>")
	)
	(segment
		(start 287.531302 -367.171732)
		(end 287.739836 -367.621312)
		(width 0.1651)
		(layer "In7.Cu")
		(net "P5E_PEX2_STN7_TX_C_DP<120>")
	)
	(segment
		(start 288.047176 -374.899174)
		(end 287.6169 -374.899174)
		(width 0.1651)
		(layer "In7.Cu")
		(net "P5E_PEX2_STN7_TX_C_DP<120>")
	)
	(segment
		(start 286.757364 -365.50092)
		(end 286.875474 -365.5441)
		(width 0.1651)
		(layer "In7.Cu")
		(net "P5E_PEX2_STN7_TX_C_DP<120>")
	)
	(segment
		(start 286.266128 -364.440724)
		(end 286.384238 -364.483904)
		(width 0.1651)
		(layer "In7.Cu")
		(net "P5E_PEX2_STN7_TX_C_DP<120>")
	)
	(segment
		(start 287.739836 -367.621312)
		(end 287.857692 -367.664492)
		(width 0.1651)
		(layer "In7.Cu")
		(net "P5E_PEX2_STN7_TX_C_DP<120>")
	)
	(segment
		(start 287.6169 -374.899174)
		(end 287.4899 -374.772174)
		(width 0.1651)
		(layer "In7.Cu")
		(net "P5E_PEX2_STN7_TX_C_DP<120>")
	)
	(segment
		(start 288.333942 -368.69243)
		(end 288.333942 -374.612408)
		(width 0.1651)
		(layer "In7.Cu")
		(net "P5E_PEX2_STN7_TX_C_DP<120>")
	)
	(segment
		(start 89.327482 -349.831914)
		(end 89.647522 -349.511874)
		(width 0.13462)
		(layer "F.Cu")
		(net "P5E_PEX0_STN6_TX_DP<98>")
	)
	(segment
		(start 89.647522 -348.88043)
		(end 89.352882 -348.58579)
		(width 0.13462)
		(layer "F.Cu")
		(net "P5E_PEX0_STN6_TX_DP<98>")
	)
	(segment
		(start 89.647522 -349.511874)
		(end 89.647522 -348.88043)
		(width 0.13462)
		(layer "F.Cu")
		(net "P5E_PEX0_STN6_TX_DP<98>")
	)
	(segment
		(start 55.279544 -313.618118)
		(end 55.51805 -313.379612)
		(width 0.1143)
		(layer "In13.Cu")
		(net "P5E_PEX0_STN6_TX_DP<98>")
	)
	(segment
		(start 65.528444 -326.965818)
		(end 56.42737 -323.19595)
		(width 0.1651)
		(layer "In13.Cu")
		(net "P5E_PEX0_STN6_TX_DP<98>")
	)
	(segment
		(start 91.198192 -341.787226)
		(end 88.83396 -339.422994)
		(width 0.1651)
		(layer "In13.Cu")
		(net "P5E_PEX0_STN6_TX_DP<98>")
	)
	(segment
		(start 55.760874 -313.379612)
		(end 55.849774 -313.290712)
		(width 0.1143)
		(layer "In13.Cu")
		(net "P5E_PEX0_STN6_TX_DP<98>")
	)
	(segment
		(start 55.849774 -313.290712)
		(end 55.849774 -312.999882)
		(width 0.1143)
		(layer "In13.Cu")
		(net "P5E_PEX0_STN6_TX_DP<98>")
	)
	(segment
		(start 55.686706 -322.455286)
		(end 55.233824 -321.361816)
		(width 0.1651)
		(layer "In13.Cu")
		(net "P5E_PEX0_STN6_TX_DP<98>")
	)
	(segment
		(start 89.643712 -347.599508)
		(end 91.198192 -346.045028)
		(width 0.1651)
		(layer "In13.Cu")
		(net "P5E_PEX0_STN6_TX_DP<98>")
	)
	(segment
		(start 55.233824 -321.361816)
		(end 55.233824 -320.136774)
		(width 0.1651)
		(layer "In13.Cu")
		(net "P5E_PEX0_STN6_TX_DP<98>")
	)
	(segment
		(start 55.233824 -320.136774)
		(end 55.233824 -320.114676)
		(width 0.1143)
		(layer "In13.Cu")
		(net "P5E_PEX0_STN6_TX_DP<98>")
	)
	(segment
		(start 55.279544 -320.068956)
		(end 55.279544 -313.618118)
		(width 0.1143)
		(layer "In13.Cu")
		(net "P5E_PEX0_STN6_TX_DP<98>")
	)
	(segment
		(start 88.83396 -339.422994)
		(end 65.528444 -326.965818)
		(width 0.1651)
		(layer "In13.Cu")
		(net "P5E_PEX0_STN6_TX_DP<98>")
	)
	(segment
		(start 55.233824 -320.114676)
		(end 55.279544 -320.068956)
		(width 0.1143)
		(layer "In13.Cu")
		(net "P5E_PEX0_STN6_TX_DP<98>")
	)
	(segment
		(start 89.352882 -348.58579)
		(end 89.643712 -348.29496)
		(width 0.1651)
		(layer "In13.Cu")
		(net "P5E_PEX0_STN6_TX_DP<98>")
	)
	(segment
		(start 91.198192 -346.045028)
		(end 91.198192 -341.787226)
		(width 0.1651)
		(layer "In13.Cu")
		(net "P5E_PEX0_STN6_TX_DP<98>")
	)
	(segment
		(start 56.42737 -323.19595)
		(end 55.686706 -322.455286)
		(width 0.1651)
		(layer "In13.Cu")
		(net "P5E_PEX0_STN6_TX_DP<98>")
	)
	(segment
		(start 89.643712 -348.29496)
		(end 89.643712 -347.599508)
		(width 0.1651)
		(layer "In13.Cu")
		(net "P5E_PEX0_STN6_TX_DP<98>")
	)
	(segment
		(start 55.51805 -313.379612)
		(end 55.760874 -313.379612)
		(width 0.1143)
		(layer "In13.Cu")
		(net "P5E_PEX0_STN6_TX_DP<98>")
	)
	(segment
		(start 277.201376 -32.4104)
		(end 276.58822 -32.4104)
		(width 0.13462)
		(layer "F.Cu")
		(net "P5E_PEX2_STN2_TX_DP<42>")
	)
	(segment
		(start 277.50516 -32.714184)
		(end 277.201376 -32.4104)
		(width 0.13462)
		(layer "F.Cu")
		(net "P5E_PEX2_STN2_TX_DP<42>")
	)
	(segment
		(start 276.58822 -32.4104)
		(end 276.259036 -32.739584)
		(width 0.13462)
		(layer "F.Cu")
		(net "P5E_PEX2_STN2_TX_DP<42>")
	)
	(segment
		(start 280.829512 -280.10485)
		(end 280.829512 -271.473168)
		(width 0.1143)
		(layer "In11.Cu")
		(net "P5E_PEX2_STN2_TX_DP<42>")
	)
	(segment
		(start 280.829512 -271.473168)
		(end 280.783792 -271.427448)
		(width 0.1143)
		(layer "In11.Cu")
		(net "P5E_PEX2_STN2_TX_DP<42>")
	)
	(segment
		(start 295.22293 -60.449968)
		(end 294.589708 -50.426366)
		(width 0.1651)
		(layer "In11.Cu")
		(net "P5E_PEX2_STN2_TX_DP<42>")
	)
	(segment
		(start 280.624026 -32.423354)
		(end 279.326594 -32.423354)
		(width 0.1651)
		(layer "In11.Cu")
		(net "P5E_PEX2_STN2_TX_DP<42>")
	)
	(segment
		(start 281.11069 -32.568896)
		(end 280.624026 -32.423354)
		(width 0.1651)
		(layer "In11.Cu")
		(net "P5E_PEX2_STN2_TX_DP<42>")
	)
	(segment
		(start 281.399742 -280.699718)
		(end 281.399742 -280.434288)
		(width 0.1143)
		(layer "In11.Cu")
		(net "P5E_PEX2_STN2_TX_DP<42>")
	)
	(segment
		(start 281.399742 -280.434288)
		(end 281.285442 -280.319988)
		(width 0.1143)
		(layer "In11.Cu")
		(net "P5E_PEX2_STN2_TX_DP<42>")
	)
	(segment
		(start 283.284168 -34.785046)
		(end 281.11069 -32.568896)
		(width 0.1651)
		(layer "In11.Cu")
		(net "P5E_PEX2_STN2_TX_DP<42>")
	)
	(segment
		(start 280.783792 -271.427448)
		(end 280.783792 -271.399)
		(width 0.1143)
		(layer "In11.Cu")
		(net "P5E_PEX2_STN2_TX_DP<42>")
	)
	(segment
		(start 294.589708 -50.426366)
		(end 293.973504 -48.627538)
		(width 0.1651)
		(layer "In11.Cu")
		(net "P5E_PEX2_STN2_TX_DP<42>")
	)
	(segment
		(start 281.04465 -280.319988)
		(end 280.829512 -280.10485)
		(width 0.1143)
		(layer "In11.Cu")
		(net "P5E_PEX2_STN2_TX_DP<42>")
	)
	(segment
		(start 280.453084 -267.083794)
		(end 276.939248 -161.954718)
		(width 0.1651)
		(layer "In11.Cu")
		(net "P5E_PEX2_STN2_TX_DP<42>")
	)
	(segment
		(start 280.783792 -271.399)
		(end 280.783792 -270.440658)
		(width 0.1651)
		(layer "In11.Cu")
		(net "P5E_PEX2_STN2_TX_DP<42>")
	)
	(segment
		(start 279.237694 -32.512254)
		(end 278.742394 -32.512254)
		(width 0.1651)
		(layer "In11.Cu")
		(net "P5E_PEX2_STN2_TX_DP<42>")
	)
	(segment
		(start 293.737792 -68.584318)
		(end 295.22293 -60.449968)
		(width 0.1651)
		(layer "In11.Cu")
		(net "P5E_PEX2_STN2_TX_DP<42>")
	)
	(segment
		(start 281.285442 -280.319988)
		(end 281.04465 -280.319988)
		(width 0.1143)
		(layer "In11.Cu")
		(net "P5E_PEX2_STN2_TX_DP<42>")
	)
	(segment
		(start 278.300434 -141.878558)
		(end 278.039576 -115.996212)
		(width 0.1651)
		(layer "In11.Cu")
		(net "P5E_PEX2_STN2_TX_DP<42>")
	)
	(segment
		(start 278.742394 -32.512254)
		(end 278.653494 -32.423354)
		(width 0.1651)
		(layer "In11.Cu")
		(net "P5E_PEX2_STN2_TX_DP<42>")
	)
	(segment
		(start 278.039576 -115.996212)
		(end 283.464 -95.718122)
		(width 0.1651)
		(layer "In11.Cu")
		(net "P5E_PEX2_STN2_TX_DP<42>")
	)
	(segment
		(start 277.79599 -32.423354)
		(end 277.50516 -32.714184)
		(width 0.1651)
		(layer "In11.Cu")
		(net "P5E_PEX2_STN2_TX_DP<42>")
	)
	(segment
		(start 279.326594 -32.423354)
		(end 279.237694 -32.512254)
		(width 0.1651)
		(layer "In11.Cu")
		(net "P5E_PEX2_STN2_TX_DP<42>")
	)
	(segment
		(start 280.783792 -270.440658)
		(end 280.453084 -267.083794)
		(width 0.1651)
		(layer "In11.Cu")
		(net "P5E_PEX2_STN2_TX_DP<42>")
	)
	(segment
		(start 278.653494 -32.423354)
		(end 277.79599 -32.423354)
		(width 0.1651)
		(layer "In11.Cu")
		(net "P5E_PEX2_STN2_TX_DP<42>")
	)
	(segment
		(start 276.939248 -161.954718)
		(end 278.300434 -141.878558)
		(width 0.1651)
		(layer "In11.Cu")
		(net "P5E_PEX2_STN2_TX_DP<42>")
	)
	(segment
		(start 283.464 -95.718122)
		(end 293.737792 -68.584318)
		(width 0.1651)
		(layer "In11.Cu")
		(net "P5E_PEX2_STN2_TX_DP<42>")
	)
	(segment
		(start 293.973504 -48.627538)
		(end 283.284168 -34.785046)
		(width 0.1651)
		(layer "In11.Cu")
		(net "P5E_PEX2_STN2_TX_DP<42>")
	)
	(segment
		(start 393.8397 -343.685622)
		(end 393.519152 -343.365074)
		(width 0.13462)
		(layer "F.Cu")
		(net "P5E_PEX3_STN5_TX_DN<82>")
	)
	(segment
		(start 393.519152 -343.365074)
		(end 393.519152 -342.734646)
		(width 0.13462)
		(layer "F.Cu")
		(net "P5E_PEX3_STN5_TX_DN<82>")
	)
	(segment
		(start 393.519152 -342.734646)
		(end 393.8143 -342.439498)
		(width 0.13462)
		(layer "F.Cu")
		(net "P5E_PEX3_STN5_TX_DN<82>")
	)
	(segment
		(start 408.520138 -319.915032)
		(end 408.520138 -311.784492)
		(width 0.1143)
		(layer "In7.Cu")
		(net "P5E_PEX3_STN5_TX_DN<82>")
	)
	(segment
		(start 407.523696 -325.828406)
		(end 408.565858 -323.312282)
		(width 0.1651)
		(layer "In7.Cu")
		(net "P5E_PEX3_STN5_TX_DN<82>")
	)
	(segment
		(start 406.646888 -327.140824)
		(end 407.523696 -325.828406)
		(width 0.1651)
		(layer "In7.Cu")
		(net "P5E_PEX3_STN5_TX_DN<82>")
	)
	(segment
		(start 408.565858 -319.960752)
		(end 408.520138 -319.915032)
		(width 0.1143)
		(layer "In7.Cu")
		(net "P5E_PEX3_STN5_TX_DN<82>")
	)
	(segment
		(start 408.899868 -311.784492)
		(end 408.899868 -312.049922)
		(width 0.1143)
		(layer "In7.Cu")
		(net "P5E_PEX3_STN5_TX_DN<82>")
	)
	(segment
		(start 408.785568 -311.670192)
		(end 408.899868 -311.784492)
		(width 0.1143)
		(layer "In7.Cu")
		(net "P5E_PEX3_STN5_TX_DN<82>")
	)
	(segment
		(start 393.52347 -342.148668)
		(end 393.52347 -341.442294)
		(width 0.1651)
		(layer "In7.Cu")
		(net "P5E_PEX3_STN5_TX_DN<82>")
	)
	(segment
		(start 393.52347 -341.442294)
		(end 406.646888 -327.140824)
		(width 0.1651)
		(layer "In7.Cu")
		(net "P5E_PEX3_STN5_TX_DN<82>")
	)
	(segment
		(start 408.520138 -311.784492)
		(end 408.634438 -311.670192)
		(width 0.1143)
		(layer "In7.Cu")
		(net "P5E_PEX3_STN5_TX_DN<82>")
	)
	(segment
		(start 408.565858 -323.312282)
		(end 408.565858 -319.9892)
		(width 0.1651)
		(layer "In7.Cu")
		(net "P5E_PEX3_STN5_TX_DN<82>")
	)
	(segment
		(start 408.565858 -319.9892)
		(end 408.565858 -319.960752)
		(width 0.1143)
		(layer "In7.Cu")
		(net "P5E_PEX3_STN5_TX_DN<82>")
	)
	(segment
		(start 393.8143 -342.439498)
		(end 393.52347 -342.148668)
		(width 0.1651)
		(layer "In7.Cu")
		(net "P5E_PEX3_STN5_TX_DN<82>")
	)
	(segment
		(start 408.634438 -311.670192)
		(end 408.785568 -311.670192)
		(width 0.1143)
		(layer "In7.Cu")
		(net "P5E_PEX3_STN5_TX_DN<82>")
	)
	(segment
		(start 76.917042 -357.75773)
		(end 77.211682 -357.46309)
		(width 0.13462)
		(layer "F.Cu")
		(net "P5E_PEX0_STN5_TX_C_DP<88>")
	)
	(segment
		(start 77.211682 -356.831646)
		(end 76.891642 -356.511606)
		(width 0.13462)
		(layer "F.Cu")
		(net "P5E_PEX0_STN5_TX_C_DP<88>")
	)
	(segment
		(start 77.211682 -357.46309)
		(end 77.211682 -356.831646)
		(width 0.13462)
		(layer "F.Cu")
		(net "P5E_PEX0_STN5_TX_C_DP<88>")
	)
	(segment
		(start 77.207872 -358.819958)
		(end 77.207872 -358.04856)
		(width 0.1651)
		(layer "In7.Cu")
		(net "P5E_PEX0_STN5_TX_C_DP<88>")
	)
	(segment
		(start 72.802242 -368.129312)
		(end 73.252584 -367.177574)
		(width 0.1651)
		(layer "In7.Cu")
		(net "P5E_PEX0_STN5_TX_C_DP<88>")
	)
	(segment
		(start 74.210164 -364.946946)
		(end 74.422254 -364.49889)
		(width 0.1651)
		(layer "In7.Cu")
		(net "P5E_PEX0_STN5_TX_C_DP<88>")
	)
	(segment
		(start 73.540874 -366.56899)
		(end 73.54062 -366.56899)
		(width 0.1651)
		(layer "In7.Cu")
		(net "P5E_PEX0_STN5_TX_C_DP<88>")
	)
	(segment
		(start 71.90994 -378.290074)
		(end 71.90994 -378.67209)
		(width 0.1651)
		(layer "In7.Cu")
		(net "P5E_PEX0_STN5_TX_C_DP<88>")
	)
	(segment
		(start 72.03694 -378.79909)
		(end 72.373236 -378.79909)
		(width 0.1651)
		(layer "In7.Cu")
		(net "P5E_PEX0_STN5_TX_C_DP<88>")
	)
	(segment
		(start 73.210166 -367.05921)
		(end 73.42251 -366.611154)
		(width 0.1651)
		(layer "In7.Cu")
		(net "P5E_PEX0_STN5_TX_C_DP<88>")
	)
	(segment
		(start 77.207872 -358.04856)
		(end 76.917042 -357.75773)
		(width 0.1651)
		(layer "In7.Cu")
		(net "P5E_PEX0_STN5_TX_C_DP<88>")
	)
	(segment
		(start 74.422254 -364.49889)
		(end 74.540618 -364.456726)
		(width 0.1651)
		(layer "In7.Cu")
		(net "P5E_PEX0_STN5_TX_C_DP<88>")
	)
	(segment
		(start 73.752456 -366.121188)
		(end 73.75271 -366.121442)
		(width 0.1651)
		(layer "In7.Cu")
		(net "P5E_PEX0_STN5_TX_C_DP<88>")
	)
	(segment
		(start 72.802242 -378.370084)
		(end 72.802242 -368.129312)
		(width 0.1651)
		(layer "In7.Cu")
		(net "P5E_PEX0_STN5_TX_C_DP<88>")
	)
	(segment
		(start 74.540618 -364.456726)
		(end 74.540364 -364.456472)
		(width 0.1651)
		(layer "In7.Cu")
		(net "P5E_PEX0_STN5_TX_C_DP<88>")
	)
	(segment
		(start 73.75271 -366.121442)
		(end 73.710292 -366.003078)
		(width 0.1651)
		(layer "In7.Cu")
		(net "P5E_PEX0_STN5_TX_C_DP<88>")
	)
	(segment
		(start 73.252584 -367.177574)
		(end 73.210166 -367.05921)
		(width 0.1651)
		(layer "In7.Cu")
		(net "P5E_PEX0_STN5_TX_C_DP<88>")
	)
	(segment
		(start 72.373236 -378.79909)
		(end 72.802242 -378.370084)
		(width 0.1651)
		(layer "In7.Cu")
		(net "P5E_PEX0_STN5_TX_C_DP<88>")
	)
	(segment
		(start 73.54062 -366.56899)
		(end 73.752456 -366.121188)
		(width 0.1651)
		(layer "In7.Cu")
		(net "P5E_PEX0_STN5_TX_C_DP<88>")
	)
	(segment
		(start 73.710292 -366.003078)
		(end 73.922382 -365.555022)
		(width 0.1651)
		(layer "In7.Cu")
		(net "P5E_PEX0_STN5_TX_C_DP<88>")
	)
	(segment
		(start 74.040492 -365.512604)
		(end 74.252328 -365.065056)
		(width 0.1651)
		(layer "In7.Cu")
		(net "P5E_PEX0_STN5_TX_C_DP<88>")
	)
	(segment
		(start 71.90994 -378.67209)
		(end 72.03694 -378.79909)
		(width 0.1651)
		(layer "In7.Cu")
		(net "P5E_PEX0_STN5_TX_C_DP<88>")
	)
	(segment
		(start 74.040746 -365.512858)
		(end 74.040492 -365.512604)
		(width 0.1651)
		(layer "In7.Cu")
		(net "P5E_PEX0_STN5_TX_C_DP<88>")
	)
	(segment
		(start 73.922382 -365.555022)
		(end 74.040746 -365.512858)
		(width 0.1651)
		(layer "In7.Cu")
		(net "P5E_PEX0_STN5_TX_C_DP<88>")
	)
	(segment
		(start 74.252582 -365.06531)
		(end 74.210164 -364.946946)
		(width 0.1651)
		(layer "In7.Cu")
		(net "P5E_PEX0_STN5_TX_C_DP<88>")
	)
	(segment
		(start 74.252328 -365.065056)
		(end 74.252582 -365.06531)
		(width 0.1651)
		(layer "In7.Cu")
		(net "P5E_PEX0_STN5_TX_C_DP<88>")
	)
	(segment
		(start 73.42251 -366.611154)
		(end 73.540874 -366.56899)
		(width 0.1651)
		(layer "In7.Cu")
		(net "P5E_PEX0_STN5_TX_C_DP<88>")
	)
	(segment
		(start 74.540364 -364.456472)
		(end 77.207872 -358.819958)
		(width 0.1651)
		(layer "In7.Cu")
		(net "P5E_PEX0_STN5_TX_C_DP<88>")
	)
	(segment
		(start 70.993762 -348.88043)
		(end 70.699122 -348.58579)
		(width 0.13462)
		(layer "F.Cu")
		(net "P5E_PEX0_STN6_TX_DP<107>")
	)
	(segment
		(start 70.673722 -349.831914)
		(end 70.993762 -349.511874)
		(width 0.13462)
		(layer "F.Cu")
		(net "P5E_PEX0_STN6_TX_DP<107>")
	)
	(segment
		(start 70.993762 -349.511874)
		(end 70.993762 -348.88043)
		(width 0.13462)
		(layer "F.Cu")
		(net "P5E_PEX0_STN6_TX_DP<107>")
	)
	(segment
		(start 62.547754 -336.211418)
		(end 62.547754 -336.211672)
		(width 0.1651)
		(layer "In13.Cu")
		(net "P5E_PEX0_STN6_TX_DP<107>")
	)
	(segment
		(start 47.21098 -311.479692)
		(end 47.29988 -311.390792)
		(width 0.1143)
		(layer "In13.Cu")
		(net "P5E_PEX0_STN6_TX_DP<107>")
	)
	(segment
		(start 46.96841 -311.479692)
		(end 47.21098 -311.479692)
		(width 0.1143)
		(layer "In13.Cu")
		(net "P5E_PEX0_STN6_TX_DP<107>")
	)
	(segment
		(start 72.544432 -341.826342)
		(end 72.304656 -341.4268)
		(width 0.1651)
		(layer "In13.Cu")
		(net "P5E_PEX0_STN6_TX_DP<107>")
	)
	(segment
		(start 48.091852 -327.204324)
		(end 46.68393 -323.805296)
		(width 0.1651)
		(layer "In13.Cu")
		(net "P5E_PEX0_STN6_TX_DP<107>")
	)
	(segment
		(start 70.989952 -347.599508)
		(end 72.544432 -346.045028)
		(width 0.1651)
		(layer "In13.Cu")
		(net "P5E_PEX0_STN6_TX_DP<107>")
	)
	(segment
		(start 46.68393 -323.805296)
		(end 46.68393 -320.199258)
		(width 0.1651)
		(layer "In13.Cu")
		(net "P5E_PEX0_STN6_TX_DP<107>")
	)
	(segment
		(start 51.24196 -330.354432)
		(end 48.091852 -327.204324)
		(width 0.1651)
		(layer "In13.Cu")
		(net "P5E_PEX0_STN6_TX_DP<107>")
	)
	(segment
		(start 70.699122 -348.58579)
		(end 70.989952 -348.29496)
		(width 0.1651)
		(layer "In13.Cu")
		(net "P5E_PEX0_STN6_TX_DP<107>")
	)
	(segment
		(start 46.68393 -320.199258)
		(end 46.68393 -320.17716)
		(width 0.1143)
		(layer "In13.Cu")
		(net "P5E_PEX0_STN6_TX_DP<107>")
	)
	(segment
		(start 62.547754 -336.211672)
		(end 52.790852 -330.996036)
		(width 0.1651)
		(layer "In13.Cu")
		(net "P5E_PEX0_STN6_TX_DP<107>")
	)
	(segment
		(start 72.304656 -341.4268)
		(end 62.547754 -336.211418)
		(width 0.1651)
		(layer "In13.Cu")
		(net "P5E_PEX0_STN6_TX_DP<107>")
	)
	(segment
		(start 52.790852 -330.996036)
		(end 51.24196 -330.354432)
		(width 0.1651)
		(layer "In13.Cu")
		(net "P5E_PEX0_STN6_TX_DP<107>")
	)
	(segment
		(start 46.72965 -311.718452)
		(end 46.96841 -311.479692)
		(width 0.1143)
		(layer "In13.Cu")
		(net "P5E_PEX0_STN6_TX_DP<107>")
	)
	(segment
		(start 72.544432 -346.045028)
		(end 72.544432 -341.826342)
		(width 0.1651)
		(layer "In13.Cu")
		(net "P5E_PEX0_STN6_TX_DP<107>")
	)
	(segment
		(start 47.29988 -311.390792)
		(end 47.29988 -311.099962)
		(width 0.1143)
		(layer "In13.Cu")
		(net "P5E_PEX0_STN6_TX_DP<107>")
	)
	(segment
		(start 46.72965 -320.13144)
		(end 46.72965 -311.718452)
		(width 0.1143)
		(layer "In13.Cu")
		(net "P5E_PEX0_STN6_TX_DP<107>")
	)
	(segment
		(start 70.989952 -348.29496)
		(end 70.989952 -347.599508)
		(width 0.1651)
		(layer "In13.Cu")
		(net "P5E_PEX0_STN6_TX_DP<107>")
	)
	(segment
		(start 46.68393 -320.17716)
		(end 46.72965 -320.13144)
		(width 0.1143)
		(layer "In13.Cu")
		(net "P5E_PEX0_STN6_TX_DP<107>")
	)
	(segment
		(start 253.22149 -33.95218)
		(end 252.901196 -33.631886)
		(width 0.13462)
		(layer "F.Cu")
		(net "P5E_PEX2_STN2_TX_DN<47>")
	)
	(segment
		(start 253.852426 -33.95218)
		(end 253.22149 -33.95218)
		(width 0.13462)
		(layer "F.Cu")
		(net "P5E_PEX2_STN2_TX_DN<47>")
	)
	(segment
		(start 254.14732 -33.657286)
		(end 253.852426 -33.95218)
		(width 0.13462)
		(layer "F.Cu")
		(net "P5E_PEX2_STN2_TX_DN<47>")
	)
	(segment
		(start 264.0838 -138.226292)
		(end 275.282914 -264.507726)
		(width 0.1651)
		(layer "In11.Cu")
		(net "P5E_PEX2_STN2_TX_DN<47>")
	)
	(segment
		(start 255.396492 -34.151316)
		(end 256.694178 -35.183572)
		(width 0.1651)
		(layer "In11.Cu")
		(net "P5E_PEX2_STN2_TX_DN<47>")
	)
	(segment
		(start 267.445744 -49.197768)
		(end 267.940028 -50.623724)
		(width 0.1651)
		(layer "In11.Cu")
		(net "P5E_PEX2_STN2_TX_DN<47>")
	)
	(segment
		(start 254.57023 -33.948116)
		(end 254.973328 -33.948116)
		(width 0.1651)
		(layer "In11.Cu")
		(net "P5E_PEX2_STN2_TX_DN<47>")
	)
	(segment
		(start 275.282914 -264.507726)
		(end 276.315678 -270.728694)
		(width 0.1651)
		(layer "In11.Cu")
		(net "P5E_PEX2_STN2_TX_DN<47>")
	)
	(segment
		(start 263.570212 -117.07495)
		(end 264.0838 -138.226292)
		(width 0.1651)
		(layer "In11.Cu")
		(net "P5E_PEX2_STN2_TX_DN<47>")
	)
	(segment
		(start 254.973328 -33.948116)
		(end 255.396492 -34.151316)
		(width 0.1651)
		(layer "In11.Cu")
		(net "P5E_PEX2_STN2_TX_DN<47>")
	)
	(segment
		(start 276.535388 -278.229568)
		(end 276.649688 -278.115268)
		(width 0.1143)
		(layer "In11.Cu")
		(net "P5E_PEX2_STN2_TX_DN<47>")
	)
	(segment
		(start 276.37359 -278.229568)
		(end 276.535388 -278.229568)
		(width 0.1143)
		(layer "In11.Cu")
		(net "P5E_PEX2_STN2_TX_DN<47>")
	)
	(segment
		(start 268.618462 -62.636908)
		(end 267.758926 -78.909926)
		(width 0.1651)
		(layer "In11.Cu")
		(net "P5E_PEX2_STN2_TX_DN<47>")
	)
	(segment
		(start 267.940028 -50.623724)
		(end 268.618462 -62.636908)
		(width 0.1651)
		(layer "In11.Cu")
		(net "P5E_PEX2_STN2_TX_DN<47>")
	)
	(segment
		(start 276.269958 -278.125936)
		(end 276.37359 -278.229568)
		(width 0.1143)
		(layer "In11.Cu")
		(net "P5E_PEX2_STN2_TX_DN<47>")
	)
	(segment
		(start 254.344932 -33.854898)
		(end 254.57023 -33.948116)
		(width 0.1651)
		(layer "In11.Cu")
		(net "P5E_PEX2_STN2_TX_DN<47>")
	)
	(segment
		(start 276.315678 -271.427448)
		(end 276.269958 -271.473168)
		(width 0.1143)
		(layer "In11.Cu")
		(net "P5E_PEX2_STN2_TX_DN<47>")
	)
	(segment
		(start 254.14732 -33.657286)
		(end 254.344932 -33.854898)
		(width 0.1651)
		(layer "In11.Cu")
		(net "P5E_PEX2_STN2_TX_DN<47>")
	)
	(segment
		(start 256.694178 -35.183572)
		(end 266.421616 -47.342298)
		(width 0.1651)
		(layer "In11.Cu")
		(net "P5E_PEX2_STN2_TX_DN<47>")
	)
	(segment
		(start 276.315678 -271.399)
		(end 276.315678 -271.427448)
		(width 0.1143)
		(layer "In11.Cu")
		(net "P5E_PEX2_STN2_TX_DN<47>")
	)
	(segment
		(start 276.315678 -270.728694)
		(end 276.315678 -271.399)
		(width 0.1651)
		(layer "In11.Cu")
		(net "P5E_PEX2_STN2_TX_DN<47>")
	)
	(segment
		(start 267.758926 -78.909926)
		(end 264.243058 -104.589834)
		(width 0.1651)
		(layer "In11.Cu")
		(net "P5E_PEX2_STN2_TX_DN<47>")
	)
	(segment
		(start 264.243058 -104.589834)
		(end 263.570212 -117.07495)
		(width 0.1651)
		(layer "In11.Cu")
		(net "P5E_PEX2_STN2_TX_DN<47>")
	)
	(segment
		(start 266.421616 -47.342298)
		(end 267.445744 -49.197768)
		(width 0.1651)
		(layer "In11.Cu")
		(net "P5E_PEX2_STN2_TX_DN<47>")
	)
	(segment
		(start 276.269958 -271.473168)
		(end 276.269958 -278.125936)
		(width 0.1143)
		(layer "In11.Cu")
		(net "P5E_PEX2_STN2_TX_DN<47>")
	)
	(segment
		(start 276.649688 -278.115268)
		(end 276.649688 -277.849838)
		(width 0.1143)
		(layer "In11.Cu")
		(net "P5E_PEX2_STN2_TX_DN<47>")
	)
	(segment
		(start 367.60531 -29.114242)
		(end 367.307368 -28.8163)
		(width 0.13462)
		(layer "F.Cu")
		(net "P5E_PEX3_STN2_TX_DP<44>")
	)
	(segment
		(start 367.307368 -28.8163)
		(end 366.682528 -28.8163)
		(width 0.13462)
		(layer "F.Cu")
		(net "P5E_PEX3_STN2_TX_DP<44>")
	)
	(segment
		(start 366.682528 -28.8163)
		(end 366.359186 -29.139642)
		(width 0.13462)
		(layer "F.Cu")
		(net "P5E_PEX3_STN2_TX_DP<44>")
	)
	(segment
		(start 394.98397 -271.427448)
		(end 395.02969 -271.473168)
		(width 0.1143)
		(layer "In11.Cu")
		(net "P5E_PEX3_STN2_TX_DP<44>")
	)
	(segment
		(start 386.707126 -50.411126)
		(end 387.40588 -62.140338)
		(width 0.1651)
		(layer "In11.Cu")
		(net "P5E_PEX3_STN2_TX_DP<44>")
	)
	(segment
		(start 369.569492 -28.823412)
		(end 370.373402 -28.823412)
		(width 0.1651)
		(layer "In11.Cu")
		(net "P5E_PEX3_STN2_TX_DP<44>")
	)
	(segment
		(start 394.98397 -271.399)
		(end 394.98397 -271.427448)
		(width 0.1143)
		(layer "In11.Cu")
		(net "P5E_PEX3_STN2_TX_DP<44>")
	)
	(segment
		(start 387.763004 -135.957056)
		(end 386.83438 -145.379948)
		(width 0.1651)
		(layer "In11.Cu")
		(net "P5E_PEX3_STN2_TX_DP<44>")
	)
	(segment
		(start 372.415562 -29.996892)
		(end 372.401084 -30.121606)
		(width 0.1651)
		(layer "In11.Cu")
		(net "P5E_PEX3_STN2_TX_DP<44>")
	)
	(segment
		(start 372.02618 -29.505402)
		(end 372.415562 -29.996892)
		(width 0.1651)
		(layer "In11.Cu")
		(net "P5E_PEX3_STN2_TX_DP<44>")
	)
	(segment
		(start 385.979162 -48.256952)
		(end 386.707126 -50.411126)
		(width 0.1651)
		(layer "In11.Cu")
		(net "P5E_PEX3_STN2_TX_DP<44>")
	)
	(segment
		(start 395.02969 -271.473168)
		(end 395.02969 -280.10485)
		(width 0.1143)
		(layer "In11.Cu")
		(net "P5E_PEX3_STN2_TX_DP<44>")
	)
	(segment
		(start 369.480592 -28.912312)
		(end 369.569492 -28.823412)
		(width 0.1651)
		(layer "In11.Cu")
		(net "P5E_PEX3_STN2_TX_DP<44>")
	)
	(segment
		(start 368.896392 -28.823412)
		(end 368.985292 -28.912312)
		(width 0.1651)
		(layer "In11.Cu")
		(net "P5E_PEX3_STN2_TX_DP<44>")
	)
	(segment
		(start 367.60531 -29.114242)
		(end 367.898426 -28.821126)
		(width 0.1651)
		(layer "In11.Cu")
		(net "P5E_PEX3_STN2_TX_DP<44>")
	)
	(segment
		(start 387.40588 -62.140338)
		(end 387.763004 -135.957056)
		(width 0.1651)
		(layer "In11.Cu")
		(net "P5E_PEX3_STN2_TX_DP<44>")
	)
	(segment
		(start 386.83438 -145.379948)
		(end 394.09497 -264.61212)
		(width 0.1651)
		(layer "In11.Cu")
		(net "P5E_PEX3_STN2_TX_DP<44>")
	)
	(segment
		(start 372.8339 -30.52445)
		(end 383.991612 -44.601638)
		(width 0.1651)
		(layer "In11.Cu")
		(net "P5E_PEX3_STN2_TX_DP<44>")
	)
	(segment
		(start 395.244828 -280.319988)
		(end 395.48562 -280.319988)
		(width 0.1143)
		(layer "In11.Cu")
		(net "P5E_PEX3_STN2_TX_DP<44>")
	)
	(segment
		(start 367.898426 -28.821126)
		(end 367.904522 -28.823412)
		(width 0.1651)
		(layer "In11.Cu")
		(net "P5E_PEX3_STN2_TX_DP<44>")
	)
	(segment
		(start 367.904522 -28.823412)
		(end 368.896392 -28.823412)
		(width 0.1651)
		(layer "In11.Cu")
		(net "P5E_PEX3_STN2_TX_DP<44>")
	)
	(segment
		(start 383.991612 -44.601638)
		(end 385.979162 -48.256952)
		(width 0.1651)
		(layer "In11.Cu")
		(net "P5E_PEX3_STN2_TX_DP<44>")
	)
	(segment
		(start 395.59992 -280.434288)
		(end 395.59992 -280.699718)
		(width 0.1143)
		(layer "In11.Cu")
		(net "P5E_PEX3_STN2_TX_DP<44>")
	)
	(segment
		(start 395.02969 -280.10485)
		(end 395.244828 -280.319988)
		(width 0.1143)
		(layer "In11.Cu")
		(net "P5E_PEX3_STN2_TX_DP<44>")
	)
	(segment
		(start 394.09497 -264.61212)
		(end 394.98397 -270.748252)
		(width 0.1651)
		(layer "In11.Cu")
		(net "P5E_PEX3_STN2_TX_DP<44>")
	)
	(segment
		(start 372.709186 -30.510226)
		(end 372.8339 -30.52445)
		(width 0.1651)
		(layer "In11.Cu")
		(net "P5E_PEX3_STN2_TX_DP<44>")
	)
	(segment
		(start 372.401084 -30.121606)
		(end 372.709186 -30.510226)
		(width 0.1651)
		(layer "In11.Cu")
		(net "P5E_PEX3_STN2_TX_DP<44>")
	)
	(segment
		(start 394.98397 -270.748252)
		(end 394.98397 -271.399)
		(width 0.1651)
		(layer "In11.Cu")
		(net "P5E_PEX3_STN2_TX_DP<44>")
	)
	(segment
		(start 370.373402 -28.823412)
		(end 372.02618 -29.505402)
		(width 0.1651)
		(layer "In11.Cu")
		(net "P5E_PEX3_STN2_TX_DP<44>")
	)
	(segment
		(start 368.985292 -28.912312)
		(end 369.480592 -28.912312)
		(width 0.1651)
		(layer "In11.Cu")
		(net "P5E_PEX3_STN2_TX_DP<44>")
	)
	(segment
		(start 395.48562 -280.319988)
		(end 395.59992 -280.434288)
		(width 0.1143)
		(layer "In11.Cu")
		(net "P5E_PEX3_STN2_TX_DP<44>")
	)
	(segment
		(start 41.389808 -345.170506)
		(end 41.389808 -344.539062)
		(width 0.13462)
		(layer "F.Cu")
		(net "P5E_PEX0_STN7_TX_C_DN<122>")
	)
	(segment
		(start 41.095168 -345.465146)
		(end 41.389808 -345.170506)
		(width 0.13462)
		(layer "F.Cu")
		(net "P5E_PEX0_STN7_TX_C_DN<122>")
	)
	(segment
		(start 41.389808 -344.539062)
		(end 41.069768 -344.219022)
		(width 0.13462)
		(layer "F.Cu")
		(net "P5E_PEX0_STN7_TX_C_DN<122>")
	)
	(segment
		(start 33.88233 -367.685066)
		(end 39.406576 -359.417874)
		(width 0.1651)
		(layer "In7.Cu")
		(net "P5E_PEX0_STN7_TX_C_DN<122>")
	)
	(segment
		(start 32.793686 -374.899174)
		(end 33.202372 -374.490488)
		(width 0.1651)
		(layer "In7.Cu")
		(net "P5E_PEX0_STN7_TX_C_DN<122>")
	)
	(segment
		(start 33.202372 -374.490488)
		(end 33.202372 -369.927124)
		(width 0.1651)
		(layer "In7.Cu")
		(net "P5E_PEX0_STN7_TX_C_DN<122>")
	)
	(segment
		(start 39.831518 -347.912182)
		(end 41.385998 -346.357702)
		(width 0.1651)
		(layer "In7.Cu")
		(net "P5E_PEX0_STN7_TX_C_DN<122>")
	)
	(segment
		(start 41.385998 -345.755976)
		(end 41.095168 -345.465146)
		(width 0.1651)
		(layer "In7.Cu")
		(net "P5E_PEX0_STN7_TX_C_DN<122>")
	)
	(segment
		(start 32.43707 -374.899174)
		(end 32.793686 -374.899174)
		(width 0.1651)
		(layer "In7.Cu")
		(net "P5E_PEX0_STN7_TX_C_DN<122>")
	)
	(segment
		(start 41.385998 -346.357702)
		(end 41.385998 -345.755976)
		(width 0.1651)
		(layer "In7.Cu")
		(net "P5E_PEX0_STN7_TX_C_DN<122>")
	)
	(segment
		(start 39.406576 -359.417874)
		(end 39.831518 -358.017064)
		(width 0.1651)
		(layer "In7.Cu")
		(net "P5E_PEX0_STN7_TX_C_DN<122>")
	)
	(segment
		(start 32.31007 -374.390158)
		(end 32.31007 -374.772174)
		(width 0.1651)
		(layer "In7.Cu")
		(net "P5E_PEX0_STN7_TX_C_DN<122>")
	)
	(segment
		(start 32.31007 -374.772174)
		(end 32.43707 -374.899174)
		(width 0.1651)
		(layer "In7.Cu")
		(net "P5E_PEX0_STN7_TX_C_DN<122>")
	)
	(segment
		(start 33.202372 -369.927124)
		(end 33.88233 -367.685066)
		(width 0.1651)
		(layer "In7.Cu")
		(net "P5E_PEX0_STN7_TX_C_DN<122>")
	)
	(segment
		(start 39.831518 -358.017064)
		(end 39.831518 -347.912182)
		(width 0.1651)
		(layer "In7.Cu")
		(net "P5E_PEX0_STN7_TX_C_DN<122>")
	)
	(segment
		(start 80.000602 -355.978206)
		(end 80.320642 -355.658166)
		(width 0.13462)
		(layer "F.Cu")
		(net "P5E_PEX0_STN6_TX_DP<102>")
	)
	(segment
		(start 80.320642 -355.658166)
		(end 80.320642 -355.026722)
		(width 0.13462)
		(layer "F.Cu")
		(net "P5E_PEX0_STN6_TX_DP<102>")
	)
	(segment
		(start 80.320642 -355.026722)
		(end 80.026002 -354.732082)
		(width 0.13462)
		(layer "F.Cu")
		(net "P5E_PEX0_STN6_TX_DP<102>")
	)
	(segment
		(start 80.316832 -354.441252)
		(end 80.026002 -354.732082)
		(width 0.1651)
		(layer "In13.Cu")
		(net "P5E_PEX0_STN6_TX_DP<102>")
	)
	(segment
		(start 52.607464 -324.966076)
		(end 53.945536 -326.304148)
		(width 0.1651)
		(layer "In13.Cu")
		(net "P5E_PEX0_STN6_TX_DP<102>")
	)
	(segment
		(start 51.433984 -320.23431)
		(end 51.433984 -320.256408)
		(width 0.1143)
		(layer "In13.Cu")
		(net "P5E_PEX0_STN6_TX_DP<102>")
	)
	(segment
		(start 80.316832 -353.635564)
		(end 80.316832 -354.441252)
		(width 0.1651)
		(layer "In13.Cu")
		(net "P5E_PEX0_STN6_TX_DP<102>")
	)
	(segment
		(start 51.433984 -320.256408)
		(end 51.433984 -322.133214)
		(width 0.1651)
		(layer "In13.Cu")
		(net "P5E_PEX0_STN6_TX_DP<102>")
	)
	(segment
		(start 81.871312 -352.081084)
		(end 80.316832 -353.635564)
		(width 0.1651)
		(layer "In13.Cu")
		(net "P5E_PEX0_STN6_TX_DP<102>")
	)
	(segment
		(start 51.961034 -313.379612)
		(end 51.718464 -313.379612)
		(width 0.1143)
		(layer "In13.Cu")
		(net "P5E_PEX0_STN6_TX_DP<102>")
	)
	(segment
		(start 51.718464 -313.379612)
		(end 51.479704 -313.618372)
		(width 0.1143)
		(layer "In13.Cu")
		(net "P5E_PEX0_STN6_TX_DP<102>")
	)
	(segment
		(start 57.424574 -327.745344)
		(end 80.894936 -340.291166)
		(width 0.1651)
		(layer "In13.Cu")
		(net "P5E_PEX0_STN6_TX_DP<102>")
	)
	(segment
		(start 51.479704 -320.18859)
		(end 51.433984 -320.23431)
		(width 0.1143)
		(layer "In13.Cu")
		(net "P5E_PEX0_STN6_TX_DP<102>")
	)
	(segment
		(start 80.894936 -340.291166)
		(end 81.871312 -341.919814)
		(width 0.1651)
		(layer "In13.Cu")
		(net "P5E_PEX0_STN6_TX_DP<102>")
	)
	(segment
		(start 51.479704 -313.618372)
		(end 51.479704 -320.18859)
		(width 0.1143)
		(layer "In13.Cu")
		(net "P5E_PEX0_STN6_TX_DP<102>")
	)
	(segment
		(start 52.049934 -313.290712)
		(end 51.961034 -313.379612)
		(width 0.1143)
		(layer "In13.Cu")
		(net "P5E_PEX0_STN6_TX_DP<102>")
	)
	(segment
		(start 51.433984 -322.133214)
		(end 52.607464 -324.966076)
		(width 0.1651)
		(layer "In13.Cu")
		(net "P5E_PEX0_STN6_TX_DP<102>")
	)
	(segment
		(start 81.871312 -341.919814)
		(end 81.871312 -352.081084)
		(width 0.1651)
		(layer "In13.Cu")
		(net "P5E_PEX0_STN6_TX_DP<102>")
	)
	(segment
		(start 53.945536 -326.304148)
		(end 57.424574 -327.745344)
		(width 0.1651)
		(layer "In13.Cu")
		(net "P5E_PEX0_STN6_TX_DP<102>")
	)
	(segment
		(start 52.049934 -312.999882)
		(end 52.049934 -313.290712)
		(width 0.1143)
		(layer "In13.Cu")
		(net "P5E_PEX0_STN6_TX_DP<102>")
	)
	(segment
		(start 328.342244 -355.026722)
		(end 328.047604 -354.732082)
		(width 0.13462)
		(layer "F.Cu")
		(net "P5E_PEX2_STN5_TX_DP<88>")
	)
	(segment
		(start 328.022204 -355.978206)
		(end 328.342244 -355.658166)
		(width 0.13462)
		(layer "F.Cu")
		(net "P5E_PEX2_STN5_TX_DP<88>")
	)
	(segment
		(start 328.342244 -355.658166)
		(end 328.342244 -355.026722)
		(width 0.13462)
		(layer "F.Cu")
		(net "P5E_PEX2_STN5_TX_DP<88>")
	)
	(segment
		(start 329.892914 -352.259646)
		(end 329.892914 -342.142318)
		(width 0.1651)
		(layer "In7.Cu")
		(net "P5E_PEX2_STN5_TX_DP<88>")
	)
	(segment
		(start 297.883834 -321.257422)
		(end 297.883834 -319.916048)
		(width 0.1651)
		(layer "In7.Cu")
		(net "P5E_PEX2_STN5_TX_DP<88>")
	)
	(segment
		(start 297.883834 -319.916048)
		(end 297.883834 -319.8876)
		(width 0.1143)
		(layer "In7.Cu")
		(net "P5E_PEX2_STN5_TX_DP<88>")
	)
	(segment
		(start 298.385484 -311.479692)
		(end 298.499784 -311.365392)
		(width 0.1143)
		(layer "In7.Cu")
		(net "P5E_PEX2_STN5_TX_DP<88>")
	)
	(segment
		(start 329.393042 -340.905084)
		(end 329.392788 -340.905084)
		(width 0.1651)
		(layer "In7.Cu")
		(net "P5E_PEX2_STN5_TX_DP<88>")
	)
	(segment
		(start 328.755502 -340.041484)
		(end 328.11847 -339.178392)
		(width 0.1651)
		(layer "In7.Cu")
		(net "P5E_PEX2_STN5_TX_DP<88>")
	)
	(segment
		(start 297.883834 -319.8876)
		(end 297.929554 -319.84188)
		(width 0.1143)
		(layer "In7.Cu")
		(net "P5E_PEX2_STN5_TX_DP<88>")
	)
	(segment
		(start 323.643752 -336.13217)
		(end 301.604426 -327.055226)
		(width 0.1651)
		(layer "In7.Cu")
		(net "P5E_PEX2_STN5_TX_DP<88>")
	)
	(segment
		(start 328.338434 -353.814126)
		(end 329.892914 -352.259646)
		(width 0.1651)
		(layer "In7.Cu")
		(net "P5E_PEX2_STN5_TX_DP<88>")
	)
	(segment
		(start 299.352462 -324.803262)
		(end 297.883834 -321.257422)
		(width 0.1651)
		(layer "In7.Cu")
		(net "P5E_PEX2_STN5_TX_DP<88>")
	)
	(segment
		(start 329.392788 -340.905084)
		(end 328.755502 -340.041738)
		(width 0.1651)
		(layer "In7.Cu")
		(net "P5E_PEX2_STN5_TX_DP<88>")
	)
	(segment
		(start 298.499784 -311.365392)
		(end 298.499784 -311.099962)
		(width 0.1143)
		(layer "In7.Cu")
		(net "P5E_PEX2_STN5_TX_DP<88>")
	)
	(segment
		(start 329.892914 -342.142318)
		(end 329.89266 -342.142064)
		(width 0.1651)
		(layer "In7.Cu")
		(net "P5E_PEX2_STN5_TX_DP<88>")
	)
	(segment
		(start 297.929554 -311.705498)
		(end 298.15536 -311.479692)
		(width 0.1143)
		(layer "In7.Cu")
		(net "P5E_PEX2_STN5_TX_DP<88>")
	)
	(segment
		(start 297.929554 -319.84188)
		(end 297.929554 -311.705498)
		(width 0.1143)
		(layer "In7.Cu")
		(net "P5E_PEX2_STN5_TX_DP<88>")
	)
	(segment
		(start 301.604426 -327.055226)
		(end 299.352462 -324.803262)
		(width 0.1651)
		(layer "In7.Cu")
		(net "P5E_PEX2_STN5_TX_DP<88>")
	)
	(segment
		(start 328.755502 -340.041738)
		(end 328.755502 -340.041484)
		(width 0.1651)
		(layer "In7.Cu")
		(net "P5E_PEX2_STN5_TX_DP<88>")
	)
	(segment
		(start 298.15536 -311.479692)
		(end 298.385484 -311.479692)
		(width 0.1143)
		(layer "In7.Cu")
		(net "P5E_PEX2_STN5_TX_DP<88>")
	)
	(segment
		(start 328.11847 -339.178392)
		(end 323.643752 -336.13217)
		(width 0.1651)
		(layer "In7.Cu")
		(net "P5E_PEX2_STN5_TX_DP<88>")
	)
	(segment
		(start 328.047604 -354.732082)
		(end 328.338434 -354.441252)
		(width 0.1651)
		(layer "In7.Cu")
		(net "P5E_PEX2_STN5_TX_DP<88>")
	)
	(segment
		(start 328.338434 -354.441252)
		(end 328.338434 -353.814126)
		(width 0.1651)
		(layer "In7.Cu")
		(net "P5E_PEX2_STN5_TX_DP<88>")
	)
	(segment
		(start 329.89266 -342.142064)
		(end 329.393042 -340.905084)
		(width 0.1651)
		(layer "In7.Cu")
		(net "P5E_PEX2_STN5_TX_DP<88>")
	)
	(segment
		(start 393.8397 -355.978206)
		(end 393.519152 -355.657658)
		(width 0.13462)
		(layer "F.Cu")
		(net "P5E_PEX3_STN5_TX_DN<83>")
	)
	(segment
		(start 393.519152 -355.02723)
		(end 393.8143 -354.732082)
		(width 0.13462)
		(layer "F.Cu")
		(net "P5E_PEX3_STN5_TX_DN<83>")
	)
	(segment
		(start 393.519152 -355.657658)
		(end 393.519152 -355.02723)
		(width 0.13462)
		(layer "F.Cu")
		(net "P5E_PEX3_STN5_TX_DN<83>")
	)
	(segment
		(start 393.52347 -354.441252)
		(end 393.52347 -353.930966)
		(width 0.1651)
		(layer "In7.Cu")
		(net "P5E_PEX3_STN5_TX_DN<83>")
	)
	(segment
		(start 407.176732 -328.093832)
		(end 408.475688 -326.14997)
		(width 0.1651)
		(layer "In7.Cu")
		(net "P5E_PEX3_STN5_TX_DN<83>")
	)
	(segment
		(start 409.735528 -313.570112)
		(end 409.849828 -313.684412)
		(width 0.1143)
		(layer "In7.Cu")
		(net "P5E_PEX3_STN5_TX_DN<83>")
	)
	(segment
		(start 395.07795 -341.790274)
		(end 407.176732 -328.093832)
		(width 0.1651)
		(layer "In7.Cu")
		(net "P5E_PEX3_STN5_TX_DN<83>")
	)
	(segment
		(start 409.849828 -313.684412)
		(end 409.849828 -313.949842)
		(width 0.1143)
		(layer "In7.Cu")
		(net "P5E_PEX3_STN5_TX_DN<83>")
	)
	(segment
		(start 409.515818 -319.960752)
		(end 409.470098 -319.915032)
		(width 0.1143)
		(layer "In7.Cu")
		(net "P5E_PEX3_STN5_TX_DN<83>")
	)
	(segment
		(start 393.8143 -354.732082)
		(end 393.52347 -354.441252)
		(width 0.1651)
		(layer "In7.Cu")
		(net "P5E_PEX3_STN5_TX_DN<83>")
	)
	(segment
		(start 409.470098 -313.684412)
		(end 409.584398 -313.570112)
		(width 0.1143)
		(layer "In7.Cu")
		(net "P5E_PEX3_STN5_TX_DN<83>")
	)
	(segment
		(start 409.515818 -319.9892)
		(end 409.515818 -319.960752)
		(width 0.1143)
		(layer "In7.Cu")
		(net "P5E_PEX3_STN5_TX_DN<83>")
	)
	(segment
		(start 409.515818 -323.638672)
		(end 409.515818 -319.9892)
		(width 0.1651)
		(layer "In7.Cu")
		(net "P5E_PEX3_STN5_TX_DN<83>")
	)
	(segment
		(start 393.52347 -353.930966)
		(end 395.07795 -352.376486)
		(width 0.1651)
		(layer "In7.Cu")
		(net "P5E_PEX3_STN5_TX_DN<83>")
	)
	(segment
		(start 409.470098 -319.915032)
		(end 409.470098 -313.684412)
		(width 0.1143)
		(layer "In7.Cu")
		(net "P5E_PEX3_STN5_TX_DN<83>")
	)
	(segment
		(start 395.07795 -352.376486)
		(end 395.07795 -341.790274)
		(width 0.1651)
		(layer "In7.Cu")
		(net "P5E_PEX3_STN5_TX_DN<83>")
	)
	(segment
		(start 408.475688 -326.14997)
		(end 409.515818 -323.638672)
		(width 0.1651)
		(layer "In7.Cu")
		(net "P5E_PEX3_STN5_TX_DN<83>")
	)
	(segment
		(start 409.584398 -313.570112)
		(end 409.735528 -313.570112)
		(width 0.1143)
		(layer "In7.Cu")
		(net "P5E_PEX3_STN5_TX_DN<83>")
	)
	(segment
		(start 41.958768 -357.75773)
		(end 41.664128 -357.46309)
		(width 0.13462)
		(layer "F.Cu")
		(net "P5E_PEX0_STN7_TX_C_DN<123>")
	)
	(segment
		(start 41.664128 -357.46309)
		(end 41.664128 -356.831646)
		(width 0.13462)
		(layer "F.Cu")
		(net "P5E_PEX0_STN7_TX_C_DN<123>")
	)
	(segment
		(start 41.664128 -356.831646)
		(end 41.984168 -356.511606)
		(width 0.13462)
		(layer "F.Cu")
		(net "P5E_PEX0_STN7_TX_C_DN<123>")
	)
	(segment
		(start 35.68446 -375.966228)
		(end 35.68446 -369.28171)
		(width 0.1651)
		(layer "In7.Cu")
		(net "P5E_PEX0_STN7_TX_C_DN<123>")
	)
	(segment
		(start 35.3695 -376.281188)
		(end 35.68446 -375.966228)
		(width 0.1651)
		(layer "In7.Cu")
		(net "P5E_PEX0_STN7_TX_C_DN<123>")
	)
	(segment
		(start 41.667938 -358.469438)
		(end 41.667938 -358.04856)
		(width 0.1651)
		(layer "In7.Cu")
		(net "P5E_PEX0_STN7_TX_C_DN<123>")
	)
	(segment
		(start 37.588698 -365.255556)
		(end 41.289732 -359.716578)
		(width 0.1651)
		(layer "In7.Cu")
		(net "P5E_PEX0_STN7_TX_C_DN<123>")
	)
	(segment
		(start 41.667938 -358.04856)
		(end 41.958768 -357.75773)
		(width 0.1651)
		(layer "In7.Cu")
		(net "P5E_PEX0_STN7_TX_C_DN<123>")
	)
	(segment
		(start 34.509964 -376.408188)
		(end 34.636964 -376.281188)
		(width 0.1651)
		(layer "In7.Cu")
		(net "P5E_PEX0_STN7_TX_C_DN<123>")
	)
	(segment
		(start 35.68446 -369.28171)
		(end 37.588698 -365.255556)
		(width 0.1651)
		(layer "In7.Cu")
		(net "P5E_PEX0_STN7_TX_C_DN<123>")
	)
	(segment
		(start 41.289732 -359.716578)
		(end 41.667938 -358.469438)
		(width 0.1651)
		(layer "In7.Cu")
		(net "P5E_PEX0_STN7_TX_C_DN<123>")
	)
	(segment
		(start 34.509964 -376.790204)
		(end 34.509964 -376.408188)
		(width 0.1651)
		(layer "In7.Cu")
		(net "P5E_PEX0_STN7_TX_C_DN<123>")
	)
	(segment
		(start 34.636964 -376.281188)
		(end 35.3695 -376.281188)
		(width 0.1651)
		(layer "In7.Cu")
		(net "P5E_PEX0_STN7_TX_C_DN<123>")
	)
	(segment
		(start 337.943444 -349.511874)
		(end 337.943444 -348.88043)
		(width 0.13462)
		(layer "F.Cu")
		(net "P5E_PEX2_STN5_TX_DN<92>")
	)
	(segment
		(start 337.943444 -348.88043)
		(end 338.238084 -348.58579)
		(width 0.13462)
		(layer "F.Cu")
		(net "P5E_PEX2_STN5_TX_DN<92>")
	)
	(segment
		(start 338.263484 -349.831914)
		(end 337.943444 -349.511874)
		(width 0.13462)
		(layer "F.Cu")
		(net "P5E_PEX2_STN5_TX_DN<92>")
	)
	(segment
		(start 301.920148 -311.784492)
		(end 302.034448 -311.670192)
		(width 0.1143)
		(layer "In7.Cu")
		(net "P5E_PEX2_STN5_TX_DN<92>")
	)
	(segment
		(start 301.965868 -319.916048)
		(end 301.965868 -319.8876)
		(width 0.1143)
		(layer "In7.Cu")
		(net "P5E_PEX2_STN5_TX_DN<92>")
	)
	(segment
		(start 302.527462 -321.788282)
		(end 301.965868 -320.432684)
		(width 0.1651)
		(layer "In7.Cu")
		(net "P5E_PEX2_STN5_TX_DN<92>")
	)
	(segment
		(start 304.235612 -323.496432)
		(end 302.527462 -321.788282)
		(width 0.1651)
		(layer "In7.Cu")
		(net "P5E_PEX2_STN5_TX_DN<92>")
	)
	(segment
		(start 301.965868 -320.432684)
		(end 301.965868 -319.916048)
		(width 0.1651)
		(layer "In7.Cu")
		(net "P5E_PEX2_STN5_TX_DN<92>")
	)
	(segment
		(start 316.149482 -328.351642)
		(end 316.107572 -328.252328)
		(width 0.1651)
		(layer "In7.Cu")
		(net "P5E_PEX2_STN5_TX_DN<92>")
	)
	(segment
		(start 301.920148 -319.84188)
		(end 301.920148 -311.784492)
		(width 0.1143)
		(layer "In7.Cu")
		(net "P5E_PEX2_STN5_TX_DN<92>")
	)
	(segment
		(start 315.648594 -328.06513)
		(end 315.54928 -328.10704)
		(width 0.1651)
		(layer "In7.Cu")
		(net "P5E_PEX2_STN5_TX_DN<92>")
	)
	(segment
		(start 302.299878 -311.784492)
		(end 302.299878 -312.049922)
		(width 0.1143)
		(layer "In7.Cu")
		(net "P5E_PEX2_STN5_TX_DN<92>")
	)
	(segment
		(start 339.501734 -346.230194)
		(end 339.501734 -342.0872)
		(width 0.1651)
		(layer "In7.Cu")
		(net "P5E_PEX2_STN5_TX_DN<92>")
	)
	(segment
		(start 338.238084 -348.58579)
		(end 337.947254 -348.29496)
		(width 0.1651)
		(layer "In7.Cu")
		(net "P5E_PEX2_STN5_TX_DN<92>")
	)
	(segment
		(start 339.501734 -342.0872)
		(end 339.217 -341.4268)
		(width 0.1651)
		(layer "In7.Cu")
		(net "P5E_PEX2_STN5_TX_DN<92>")
	)
	(segment
		(start 325.55307 -332.18374)
		(end 316.149482 -328.351642)
		(width 0.1651)
		(layer "In7.Cu")
		(net "P5E_PEX2_STN5_TX_DN<92>")
	)
	(segment
		(start 339.217 -341.4268)
		(end 338.505546 -340.6648)
		(width 0.1651)
		(layer "In7.Cu")
		(net "P5E_PEX2_STN5_TX_DN<92>")
	)
	(segment
		(start 337.947254 -347.784674)
		(end 339.501734 -346.230194)
		(width 0.1651)
		(layer "In7.Cu")
		(net "P5E_PEX2_STN5_TX_DN<92>")
	)
	(segment
		(start 337.947254 -348.29496)
		(end 337.947254 -347.784674)
		(width 0.1651)
		(layer "In7.Cu")
		(net "P5E_PEX2_STN5_TX_DN<92>")
	)
	(segment
		(start 301.965868 -319.8876)
		(end 301.920148 -319.84188)
		(width 0.1143)
		(layer "In7.Cu")
		(net "P5E_PEX2_STN5_TX_DN<92>")
	)
	(segment
		(start 338.505546 -340.6648)
		(end 325.55307 -332.18374)
		(width 0.1651)
		(layer "In7.Cu")
		(net "P5E_PEX2_STN5_TX_DN<92>")
	)
	(segment
		(start 315.54928 -328.10704)
		(end 304.235612 -323.496432)
		(width 0.1651)
		(layer "In7.Cu")
		(net "P5E_PEX2_STN5_TX_DN<92>")
	)
	(segment
		(start 302.034448 -311.670192)
		(end 302.185578 -311.670192)
		(width 0.1143)
		(layer "In7.Cu")
		(net "P5E_PEX2_STN5_TX_DN<92>")
	)
	(segment
		(start 316.107572 -328.252328)
		(end 315.648594 -328.06513)
		(width 0.1651)
		(layer "In7.Cu")
		(net "P5E_PEX2_STN5_TX_DN<92>")
	)
	(segment
		(start 302.185578 -311.670192)
		(end 302.299878 -311.784492)
		(width 0.1143)
		(layer "In7.Cu")
		(net "P5E_PEX2_STN5_TX_DN<92>")
	)
	(segment
		(start 399.737072 -342.734646)
		(end 400.03222 -342.439498)
		(width 0.13462)
		(layer "F.Cu")
		(net "P5E_PEX3_STN5_TX_DN<85>")
	)
	(segment
		(start 400.05762 -343.685622)
		(end 399.737072 -343.365074)
		(width 0.13462)
		(layer "F.Cu")
		(net "P5E_PEX3_STN5_TX_DN<85>")
	)
	(segment
		(start 399.737072 -343.365074)
		(end 399.737072 -342.734646)
		(width 0.13462)
		(layer "F.Cu")
		(net "P5E_PEX3_STN5_TX_DN<85>")
	)
	(segment
		(start 411.415992 -319.960752)
		(end 411.370272 -319.915032)
		(width 0.1143)
		(layer "In7.Cu")
		(net "P5E_PEX3_STN5_TX_DN<85>")
	)
	(segment
		(start 399.74139 -341.411306)
		(end 408.520646 -329.636628)
		(width 0.1651)
		(layer "In7.Cu")
		(net "P5E_PEX3_STN5_TX_DN<85>")
	)
	(segment
		(start 400.03222 -342.439498)
		(end 399.74139 -342.148668)
		(width 0.1651)
		(layer "In7.Cu")
		(net "P5E_PEX3_STN5_TX_DN<85>")
	)
	(segment
		(start 410.318966 -326.945498)
		(end 411.415992 -324.29704)
		(width 0.1651)
		(layer "In7.Cu")
		(net "P5E_PEX3_STN5_TX_DN<85>")
	)
	(segment
		(start 408.520646 -329.636628)
		(end 410.318966 -326.945498)
		(width 0.1651)
		(layer "In7.Cu")
		(net "P5E_PEX3_STN5_TX_DN<85>")
	)
	(segment
		(start 411.370272 -319.915032)
		(end 411.370272 -313.684412)
		(width 0.1143)
		(layer "In7.Cu")
		(net "P5E_PEX3_STN5_TX_DN<85>")
	)
	(segment
		(start 399.74139 -342.148668)
		(end 399.74139 -341.411306)
		(width 0.1651)
		(layer "In7.Cu")
		(net "P5E_PEX3_STN5_TX_DN<85>")
	)
	(segment
		(start 411.750002 -313.684412)
		(end 411.750002 -313.949842)
		(width 0.1143)
		(layer "In7.Cu")
		(net "P5E_PEX3_STN5_TX_DN<85>")
	)
	(segment
		(start 411.415992 -319.9892)
		(end 411.415992 -319.960752)
		(width 0.1143)
		(layer "In7.Cu")
		(net "P5E_PEX3_STN5_TX_DN<85>")
	)
	(segment
		(start 411.370272 -313.684412)
		(end 411.484572 -313.570112)
		(width 0.1143)
		(layer "In7.Cu")
		(net "P5E_PEX3_STN5_TX_DN<85>")
	)
	(segment
		(start 411.415992 -324.29704)
		(end 411.415992 -319.9892)
		(width 0.1651)
		(layer "In7.Cu")
		(net "P5E_PEX3_STN5_TX_DN<85>")
	)
	(segment
		(start 411.635702 -313.570112)
		(end 411.750002 -313.684412)
		(width 0.1143)
		(layer "In7.Cu")
		(net "P5E_PEX3_STN5_TX_DN<85>")
	)
	(segment
		(start 411.484572 -313.570112)
		(end 411.635702 -313.570112)
		(width 0.1143)
		(layer "In7.Cu")
		(net "P5E_PEX3_STN5_TX_DN<85>")
	)
	(segment
		(start 35.740848 -357.75773)
		(end 35.446208 -357.46309)
		(width 0.13462)
		(layer "F.Cu")
		(net "P5E_PEX0_STN7_TX_C_DN<120>")
	)
	(segment
		(start 35.446208 -357.46309)
		(end 35.446208 -356.831646)
		(width 0.13462)
		(layer "F.Cu")
		(net "P5E_PEX0_STN7_TX_C_DN<120>")
	)
	(segment
		(start 35.446208 -356.831646)
		(end 35.766248 -356.511606)
		(width 0.13462)
		(layer "F.Cu")
		(net "P5E_PEX0_STN7_TX_C_DN<120>")
	)
	(segment
		(start 28.510484 -375.181114)
		(end 29.08427 -374.607328)
		(width 0.1651)
		(layer "In7.Cu")
		(net "P5E_PEX0_STN7_TX_C_DN<120>")
	)
	(segment
		(start 27.910028 -375.69013)
		(end 27.910028 -375.308114)
		(width 0.1651)
		(layer "In7.Cu")
		(net "P5E_PEX0_STN7_TX_C_DN<120>")
	)
	(segment
		(start 29.08427 -374.607328)
		(end 29.08427 -368.407442)
		(width 0.1651)
		(layer "In7.Cu")
		(net "P5E_PEX0_STN7_TX_C_DN<120>")
	)
	(segment
		(start 35.450018 -358.04856)
		(end 35.740848 -357.75773)
		(width 0.1651)
		(layer "In7.Cu")
		(net "P5E_PEX0_STN7_TX_C_DN<120>")
	)
	(segment
		(start 29.08427 -368.407442)
		(end 35.450018 -358.880664)
		(width 0.1651)
		(layer "In7.Cu")
		(net "P5E_PEX0_STN7_TX_C_DN<120>")
	)
	(segment
		(start 28.037028 -375.181114)
		(end 28.510484 -375.181114)
		(width 0.1651)
		(layer "In7.Cu")
		(net "P5E_PEX0_STN7_TX_C_DN<120>")
	)
	(segment
		(start 35.450018 -358.880664)
		(end 35.450018 -358.04856)
		(width 0.1651)
		(layer "In7.Cu")
		(net "P5E_PEX0_STN7_TX_C_DN<120>")
	)
	(segment
		(start 27.910028 -375.308114)
		(end 28.037028 -375.181114)
		(width 0.1651)
		(layer "In7.Cu")
		(net "P5E_PEX0_STN7_TX_C_DN<120>")
	)
	(segment
		(start 296.172382 -344.539062)
		(end 296.172382 -345.170506)
		(width 0.13462)
		(layer "F.Cu")
		(net "P5E_PEX2_STN7_TX_C_DP<125>")
	)
	(segment
		(start 295.852342 -344.219022)
		(end 296.172382 -344.539062)
		(width 0.13462)
		(layer "F.Cu")
		(net "P5E_PEX2_STN7_TX_C_DP<125>")
	)
	(segment
		(start 296.172382 -345.170506)
		(end 295.877742 -345.465146)
		(width 0.13462)
		(layer "F.Cu")
		(net "P5E_PEX2_STN7_TX_C_DP<125>")
	)
	(segment
		(start 298.478448 -366.971834)
		(end 298.268136 -366.523524)
		(width 0.1651)
		(layer "In7.Cu")
		(net "P5E_PEX2_STN7_TX_C_DP<125>")
	)
	(segment
		(start 298.435776 -367.089944)
		(end 298.478448 -366.971834)
		(width 0.1651)
		(layer "In7.Cu")
		(net "P5E_PEX2_STN7_TX_C_DP<125>")
	)
	(segment
		(start 298.185332 -366.493552)
		(end 297.930316 -365.951008)
		(width 0.1651)
		(layer "In7.Cu")
		(net "P5E_PEX2_STN7_TX_C_DP<125>")
	)
	(segment
		(start 298.646342 -367.538762)
		(end 298.435776 -367.089944)
		(width 0.1651)
		(layer "In7.Cu")
		(net "P5E_PEX2_STN7_TX_C_DP<125>")
	)
	(segment
		(start 298.616878 -375.999248)
		(end 299.047154 -375.999248)
		(width 0.1651)
		(layer "In7.Cu")
		(net "P5E_PEX2_STN7_TX_C_DP<125>")
	)
	(segment
		(start 299.047154 -375.999248)
		(end 299.33392 -375.712482)
		(width 0.1651)
		(layer "In7.Cu")
		(net "P5E_PEX2_STN7_TX_C_DP<125>")
	)
	(segment
		(start 299.33392 -375.712482)
		(end 299.33392 -368.794792)
		(width 0.1651)
		(layer "In7.Cu")
		(net "P5E_PEX2_STN7_TX_C_DP<125>")
	)
	(segment
		(start 298.489878 -375.490232)
		(end 298.489878 -375.872248)
		(width 0.1651)
		(layer "In7.Cu")
		(net "P5E_PEX2_STN7_TX_C_DP<125>")
	)
	(segment
		(start 298.764706 -367.581434)
		(end 298.646342 -367.538762)
		(width 0.1651)
		(layer "In7.Cu")
		(net "P5E_PEX2_STN7_TX_C_DP<125>")
	)
	(segment
		(start 297.960288 -365.86795)
		(end 294.614092 -358.736392)
		(width 0.1651)
		(layer "In7.Cu")
		(net "P5E_PEX2_STN7_TX_C_DP<125>")
	)
	(segment
		(start 298.268136 -366.523524)
		(end 298.185332 -366.493552)
		(width 0.1651)
		(layer "In7.Cu")
		(net "P5E_PEX2_STN7_TX_C_DP<125>")
	)
	(segment
		(start 294.614092 -358.736392)
		(end 294.614092 -347.764354)
		(width 0.1651)
		(layer "In7.Cu")
		(net "P5E_PEX2_STN7_TX_C_DP<125>")
	)
	(segment
		(start 296.168572 -346.209874)
		(end 296.168572 -345.755976)
		(width 0.1651)
		(layer "In7.Cu")
		(net "P5E_PEX2_STN7_TX_C_DP<125>")
	)
	(segment
		(start 297.930316 -365.951008)
		(end 297.960288 -365.86795)
		(width 0.1651)
		(layer "In7.Cu")
		(net "P5E_PEX2_STN7_TX_C_DP<125>")
	)
	(segment
		(start 296.168572 -345.755976)
		(end 295.877742 -345.465146)
		(width 0.1651)
		(layer "In7.Cu")
		(net "P5E_PEX2_STN7_TX_C_DP<125>")
	)
	(segment
		(start 298.489878 -375.872248)
		(end 298.616878 -375.999248)
		(width 0.1651)
		(layer "In7.Cu")
		(net "P5E_PEX2_STN7_TX_C_DP<125>")
	)
	(segment
		(start 299.33392 -368.794792)
		(end 298.764706 -367.581434)
		(width 0.1651)
		(layer "In7.Cu")
		(net "P5E_PEX2_STN7_TX_C_DP<125>")
	)
	(segment
		(start 294.614092 -347.764354)
		(end 296.168572 -346.209874)
		(width 0.1651)
		(layer "In7.Cu")
		(net "P5E_PEX2_STN7_TX_C_DP<125>")
	)
	(segment
		(start 83.429602 -355.026722)
		(end 83.134962 -354.732082)
		(width 0.13462)
		(layer "F.Cu")
		(net "P5E_PEX0_STN5_TX_DP<91>")
	)
	(segment
		(start 83.429602 -355.658166)
		(end 83.429602 -355.026722)
		(width 0.13462)
		(layer "F.Cu")
		(net "P5E_PEX0_STN5_TX_DP<91>")
	)
	(segment
		(start 83.109562 -355.978206)
		(end 83.429602 -355.658166)
		(width 0.13462)
		(layer "F.Cu")
		(net "P5E_PEX0_STN5_TX_DP<91>")
	)
	(segment
		(start 84.980272 -340.78799)
		(end 83.836002 -339.075522)
		(width 0.1651)
		(layer "In7.Cu")
		(net "P5E_PEX0_STN5_TX_DP<91>")
	)
	(segment
		(start 83.425792 -354.441252)
		(end 83.425792 -353.825302)
		(width 0.1651)
		(layer "In7.Cu")
		(net "P5E_PEX0_STN5_TX_DP<91>")
	)
	(segment
		(start 70.033896 -323.823076)
		(end 68.934584 -322.177918)
		(width 0.1651)
		(layer "In7.Cu")
		(net "P5E_PEX0_STN5_TX_DP<91>")
	)
	(segment
		(start 68.579746 -319.86728)
		(end 68.579746 -313.605418)
		(width 0.1143)
		(layer "In7.Cu")
		(net "P5E_PEX0_STN5_TX_DP<91>")
	)
	(segment
		(start 68.534026 -319.913)
		(end 68.579746 -319.86728)
		(width 0.1143)
		(layer "In7.Cu")
		(net "P5E_PEX0_STN5_TX_DP<91>")
	)
	(segment
		(start 83.425792 -353.825302)
		(end 84.980272 -352.270822)
		(width 0.1651)
		(layer "In7.Cu")
		(net "P5E_PEX0_STN5_TX_DP<91>")
	)
	(segment
		(start 69.149976 -313.265312)
		(end 69.149976 -312.999882)
		(width 0.1143)
		(layer "In7.Cu")
		(net "P5E_PEX0_STN5_TX_DP<91>")
	)
	(segment
		(start 77.198474 -330.987908)
		(end 70.033896 -323.823076)
		(width 0.1651)
		(layer "In7.Cu")
		(net "P5E_PEX0_STN5_TX_DP<91>")
	)
	(segment
		(start 69.035676 -313.379612)
		(end 69.149976 -313.265312)
		(width 0.1143)
		(layer "In7.Cu")
		(net "P5E_PEX0_STN5_TX_DP<91>")
	)
	(segment
		(start 68.805552 -313.379612)
		(end 69.035676 -313.379612)
		(width 0.1143)
		(layer "In7.Cu")
		(net "P5E_PEX0_STN5_TX_DP<91>")
	)
	(segment
		(start 68.934584 -322.177918)
		(end 68.534026 -321.21094)
		(width 0.1651)
		(layer "In7.Cu")
		(net "P5E_PEX0_STN5_TX_DP<91>")
	)
	(segment
		(start 68.534026 -321.21094)
		(end 68.534026 -319.941448)
		(width 0.1651)
		(layer "In7.Cu")
		(net "P5E_PEX0_STN5_TX_DP<91>")
	)
	(segment
		(start 83.134962 -354.732082)
		(end 83.425792 -354.441252)
		(width 0.1651)
		(layer "In7.Cu")
		(net "P5E_PEX0_STN5_TX_DP<91>")
	)
	(segment
		(start 68.534026 -319.941448)
		(end 68.534026 -319.913)
		(width 0.1143)
		(layer "In7.Cu")
		(net "P5E_PEX0_STN5_TX_DP<91>")
	)
	(segment
		(start 83.836002 -339.075522)
		(end 77.198474 -330.987908)
		(width 0.1651)
		(layer "In7.Cu")
		(net "P5E_PEX0_STN5_TX_DP<91>")
	)
	(segment
		(start 68.579746 -313.605418)
		(end 68.805552 -313.379612)
		(width 0.1143)
		(layer "In7.Cu")
		(net "P5E_PEX0_STN5_TX_DP<91>")
	)
	(segment
		(start 84.980272 -352.270822)
		(end 84.980272 -340.78799)
		(width 0.1651)
		(layer "In7.Cu")
		(net "P5E_PEX0_STN5_TX_DP<91>")
	)
	(segment
		(start 329.505056 -28.250642)
		(end 329.201018 -28.55468)
		(width 0.13462)
		(layer "F.Cu")
		(net "P5E_PEX2_STN2_TX_DN<32>")
	)
	(segment
		(start 328.58837 -28.55468)
		(end 328.258932 -28.225242)
		(width 0.13462)
		(layer "F.Cu")
		(net "P5E_PEX2_STN2_TX_DN<32>")
	)
	(segment
		(start 329.201018 -28.55468)
		(end 328.58837 -28.55468)
		(width 0.13462)
		(layer "F.Cu")
		(net "P5E_PEX2_STN2_TX_DN<32>")
	)
	(segment
		(start 336.893408 -75.5142)
		(end 335.93151 -76.754482)
		(width 0.1651)
		(layer "In11.Cu")
		(net "P5E_PEX2_STN2_TX_DN<32>")
	)
	(segment
		(start 329.966066 -28.541472)
		(end 331.613764 -28.541472)
		(width 0.1651)
		(layer "In11.Cu")
		(net "P5E_PEX2_STN2_TX_DN<32>")
	)
	(segment
		(start 311.897776 -140.798042)
		(end 311.635394 -141.928088)
		(width 0.1651)
		(layer "In11.Cu")
		(net "P5E_PEX2_STN2_TX_DN<32>")
	)
	(segment
		(start 311.897776 -135.769604)
		(end 311.897776 -140.798042)
		(width 0.1651)
		(layer "In11.Cu")
		(net "P5E_PEX2_STN2_TX_DN<32>")
	)
	(segment
		(start 329.505056 -28.250642)
		(end 329.675744 -28.42133)
		(width 0.1651)
		(layer "In11.Cu")
		(net "P5E_PEX2_STN2_TX_DN<32>")
	)
	(segment
		(start 341.333582 -42.446194)
		(end 341.622888 -56.971184)
		(width 0.1651)
		(layer "In11.Cu")
		(net "P5E_PEX2_STN2_TX_DN<32>")
	)
	(segment
		(start 329.281536 -80.362044)
		(end 327.658222 -81.985358)
		(width 0.1651)
		(layer "In11.Cu")
		(net "P5E_PEX2_STN2_TX_DN<32>")
	)
	(segment
		(start 290.56584 -271.427448)
		(end 290.52012 -271.473168)
		(width 0.1143)
		(layer "In11.Cu")
		(net "P5E_PEX2_STN2_TX_DN<32>")
	)
	(segment
		(start 290.52012 -280.025856)
		(end 290.623752 -280.129488)
		(width 0.1143)
		(layer "In11.Cu")
		(net "P5E_PEX2_STN2_TX_DN<32>")
	)
	(segment
		(start 335.93151 -76.754482)
		(end 329.281536 -80.362044)
		(width 0.1651)
		(layer "In11.Cu")
		(net "P5E_PEX2_STN2_TX_DN<32>")
	)
	(segment
		(start 329.675744 -28.42133)
		(end 329.966066 -28.541472)
		(width 0.1651)
		(layer "In11.Cu")
		(net "P5E_PEX2_STN2_TX_DN<32>")
	)
	(segment
		(start 340.63178 -39.806626)
		(end 341.333582 -42.446194)
		(width 0.1651)
		(layer "In11.Cu")
		(net "P5E_PEX2_STN2_TX_DN<32>")
	)
	(segment
		(start 334.011778 -29.49448)
		(end 336.187796 -31.675832)
		(width 0.1651)
		(layer "In11.Cu")
		(net "P5E_PEX2_STN2_TX_DN<32>")
	)
	(segment
		(start 327.658222 -81.985358)
		(end 314.14085 -106.033316)
		(width 0.1651)
		(layer "In11.Cu")
		(net "P5E_PEX2_STN2_TX_DN<32>")
	)
	(segment
		(start 339.313266 -68.765928)
		(end 336.893408 -75.5142)
		(width 0.1651)
		(layer "In11.Cu")
		(net "P5E_PEX2_STN2_TX_DN<32>")
	)
	(segment
		(start 310.824626 -153.867612)
		(end 309.870094 -161.05886)
		(width 0.1651)
		(layer "In11.Cu")
		(net "P5E_PEX2_STN2_TX_DN<32>")
	)
	(segment
		(start 311.450482 -146.260566)
		(end 310.824626 -153.867612)
		(width 0.1651)
		(layer "In11.Cu")
		(net "P5E_PEX2_STN2_TX_DN<32>")
	)
	(segment
		(start 314.14085 -106.033316)
		(end 312.65622 -117.98173)
		(width 0.1651)
		(layer "In11.Cu")
		(net "P5E_PEX2_STN2_TX_DN<32>")
	)
	(segment
		(start 290.56584 -266.089638)
		(end 290.56584 -271.399)
		(width 0.1651)
		(layer "In11.Cu")
		(net "P5E_PEX2_STN2_TX_DN<32>")
	)
	(segment
		(start 290.52012 -271.473168)
		(end 290.52012 -280.025856)
		(width 0.1143)
		(layer "In11.Cu")
		(net "P5E_PEX2_STN2_TX_DN<32>")
	)
	(segment
		(start 311.635394 -141.928088)
		(end 311.450482 -146.260566)
		(width 0.1651)
		(layer "In11.Cu")
		(net "P5E_PEX2_STN2_TX_DN<32>")
	)
	(segment
		(start 336.187796 -31.675832)
		(end 340.63178 -39.806626)
		(width 0.1651)
		(layer "In11.Cu")
		(net "P5E_PEX2_STN2_TX_DN<32>")
	)
	(segment
		(start 290.78555 -280.129488)
		(end 290.89985 -280.015188)
		(width 0.1143)
		(layer "In11.Cu")
		(net "P5E_PEX2_STN2_TX_DN<32>")
	)
	(segment
		(start 312.65622 -117.98173)
		(end 311.897776 -135.769604)
		(width 0.1651)
		(layer "In11.Cu")
		(net "P5E_PEX2_STN2_TX_DN<32>")
	)
	(segment
		(start 341.622888 -56.971184)
		(end 339.313266 -68.765928)
		(width 0.1651)
		(layer "In11.Cu")
		(net "P5E_PEX2_STN2_TX_DN<32>")
	)
	(segment
		(start 309.870094 -161.05886)
		(end 290.56584 -266.089638)
		(width 0.1651)
		(layer "In11.Cu")
		(net "P5E_PEX2_STN2_TX_DN<32>")
	)
	(segment
		(start 290.56584 -271.399)
		(end 290.56584 -271.427448)
		(width 0.1143)
		(layer "In11.Cu")
		(net "P5E_PEX2_STN2_TX_DN<32>")
	)
	(segment
		(start 290.89985 -280.015188)
		(end 290.89985 -279.749504)
		(width 0.1143)
		(layer "In11.Cu")
		(net "P5E_PEX2_STN2_TX_DN<32>")
	)
	(segment
		(start 331.613764 -28.541472)
		(end 334.011778 -29.49448)
		(width 0.1651)
		(layer "In11.Cu")
		(net "P5E_PEX2_STN2_TX_DN<32>")
	)
	(segment
		(start 290.623752 -280.129488)
		(end 290.78555 -280.129488)
		(width 0.1143)
		(layer "In11.Cu")
		(net "P5E_PEX2_STN2_TX_DN<32>")
	)
	(segment
		(start 447.320924 -34.2265)
		(end 447.001138 -34.546286)
		(width 0.13462)
		(layer "F.Cu")
		(net "P5E_PEX3_STN2_TX_DP<35>")
	)
	(segment
		(start 448.247262 -34.520886)
		(end 447.952876 -34.2265)
		(width 0.13462)
		(layer "F.Cu")
		(net "P5E_PEX3_STN2_TX_DP<35>")
	)
	(segment
		(start 447.952876 -34.2265)
		(end 447.320924 -34.2265)
		(width 0.13462)
		(layer "F.Cu")
		(net "P5E_PEX3_STN2_TX_DP<35>")
	)
	(segment
		(start 450.019166 -34.754058)
		(end 450.253608 -35.190176)
		(width 0.1651)
		(layer "In11.Cu")
		(net "P5E_PEX3_STN2_TX_DP<35>")
	)
	(segment
		(start 424.10634 -149.233636)
		(end 422.645586 -161.487866)
		(width 0.1651)
		(layer "In11.Cu")
		(net "P5E_PEX3_STN2_TX_DP<35>")
	)
	(segment
		(start 424.850814 -131.097782)
		(end 424.850814 -139.865608)
		(width 0.1651)
		(layer "In11.Cu")
		(net "P5E_PEX3_STN2_TX_DP<35>")
	)
	(segment
		(start 454.273666 -42.823892)
		(end 454.502012 -56.74106)
		(width 0.1651)
		(layer "In11.Cu")
		(net "P5E_PEX3_STN2_TX_DP<35>")
	)
	(segment
		(start 403.533864 -265.45286)
		(end 403.533864 -271.399)
		(width 0.1651)
		(layer "In11.Cu")
		(net "P5E_PEX3_STN2_TX_DP<35>")
	)
	(segment
		(start 424.413426 -141.757654)
		(end 424.10634 -149.233636)
		(width 0.1651)
		(layer "In11.Cu")
		(net "P5E_PEX3_STN2_TX_DP<35>")
	)
	(segment
		(start 425.380404 -118.187978)
		(end 424.850814 -131.097782)
		(width 0.1651)
		(layer "In11.Cu")
		(net "P5E_PEX3_STN2_TX_DP<35>")
	)
	(segment
		(start 454.194164 -42.518584)
		(end 454.273666 -42.823892)
		(width 0.1651)
		(layer "In11.Cu")
		(net "P5E_PEX3_STN2_TX_DP<35>")
	)
	(segment
		(start 403.794722 -278.420068)
		(end 404.035514 -278.420068)
		(width 0.1143)
		(layer "In11.Cu")
		(net "P5E_PEX3_STN2_TX_DP<35>")
	)
	(segment
		(start 403.579584 -278.20493)
		(end 403.794722 -278.420068)
		(width 0.1143)
		(layer "In11.Cu")
		(net "P5E_PEX3_STN2_TX_DP<35>")
	)
	(segment
		(start 403.579584 -271.473168)
		(end 403.579584 -278.20493)
		(width 0.1143)
		(layer "In11.Cu")
		(net "P5E_PEX3_STN2_TX_DP<35>")
	)
	(segment
		(start 448.160648 -74.041508)
		(end 443.478666 -77.73924)
		(width 0.1651)
		(layer "In11.Cu")
		(net "P5E_PEX3_STN2_TX_DP<35>")
	)
	(segment
		(start 450.441822 -35.781488)
		(end 450.596762 -35.82797)
		(width 0.1651)
		(layer "In11.Cu")
		(net "P5E_PEX3_STN2_TX_DP<35>")
	)
	(segment
		(start 449.562728 -34.336228)
		(end 450.019166 -34.754058)
		(width 0.1651)
		(layer "In11.Cu")
		(net "P5E_PEX3_STN2_TX_DP<35>")
	)
	(segment
		(start 452.369682 -67.800728)
		(end 450.264784 -70.921626)
		(width 0.1651)
		(layer "In11.Cu")
		(net "P5E_PEX3_STN2_TX_DP<35>")
	)
	(segment
		(start 403.533864 -271.399)
		(end 403.533864 -271.427448)
		(width 0.1143)
		(layer "In11.Cu")
		(net "P5E_PEX3_STN2_TX_DP<35>")
	)
	(segment
		(start 443.478666 -77.73924)
		(end 443.466728 -77.751178)
		(width 0.1651)
		(layer "In11.Cu")
		(net "P5E_PEX3_STN2_TX_DP<35>")
	)
	(segment
		(start 441.262516 -79.960724)
		(end 427.087284 -104.92359)
		(width 0.1651)
		(layer "In11.Cu")
		(net "P5E_PEX3_STN2_TX_DP<35>")
	)
	(segment
		(start 450.596762 -35.82797)
		(end 454.194164 -42.518584)
		(width 0.1651)
		(layer "In11.Cu")
		(net "P5E_PEX3_STN2_TX_DP<35>")
	)
	(segment
		(start 427.087284 -104.92359)
		(end 425.380404 -118.187978)
		(width 0.1651)
		(layer "In11.Cu")
		(net "P5E_PEX3_STN2_TX_DP<35>")
	)
	(segment
		(start 454.502012 -56.74106)
		(end 452.369682 -67.800728)
		(width 0.1651)
		(layer "In11.Cu")
		(net "P5E_PEX3_STN2_TX_DP<35>")
	)
	(segment
		(start 448.538092 -34.230056)
		(end 449.182744 -34.230056)
		(width 0.1651)
		(layer "In11.Cu")
		(net "P5E_PEX3_STN2_TX_DP<35>")
	)
	(segment
		(start 404.035514 -278.420068)
		(end 404.149814 -278.534368)
		(width 0.1143)
		(layer "In11.Cu")
		(net "P5E_PEX3_STN2_TX_DP<35>")
	)
	(segment
		(start 422.645586 -161.487866)
		(end 403.533864 -265.45286)
		(width 0.1651)
		(layer "In11.Cu")
		(net "P5E_PEX3_STN2_TX_DP<35>")
	)
	(segment
		(start 450.207126 -35.344862)
		(end 450.441822 -35.781488)
		(width 0.1651)
		(layer "In11.Cu")
		(net "P5E_PEX3_STN2_TX_DP<35>")
	)
	(segment
		(start 450.264784 -70.921626)
		(end 450.26453 -70.921626)
		(width 0.1651)
		(layer "In11.Cu")
		(net "P5E_PEX3_STN2_TX_DP<35>")
	)
	(segment
		(start 448.247262 -34.520886)
		(end 448.538092 -34.230056)
		(width 0.1651)
		(layer "In11.Cu")
		(net "P5E_PEX3_STN2_TX_DP<35>")
	)
	(segment
		(start 450.26453 -70.921626)
		(end 448.160648 -74.041508)
		(width 0.1651)
		(layer "In11.Cu")
		(net "P5E_PEX3_STN2_TX_DP<35>")
	)
	(segment
		(start 424.850814 -139.865608)
		(end 424.413426 -141.757654)
		(width 0.1651)
		(layer "In11.Cu")
		(net "P5E_PEX3_STN2_TX_DP<35>")
	)
	(segment
		(start 404.149814 -278.534368)
		(end 404.149814 -278.799798)
		(width 0.1143)
		(layer "In11.Cu")
		(net "P5E_PEX3_STN2_TX_DP<35>")
	)
	(segment
		(start 449.182744 -34.230056)
		(end 449.562728 -34.336228)
		(width 0.1651)
		(layer "In11.Cu")
		(net "P5E_PEX3_STN2_TX_DP<35>")
	)
	(segment
		(start 443.466728 -77.751178)
		(end 443.466982 -77.751178)
		(width 0.1651)
		(layer "In11.Cu")
		(net "P5E_PEX3_STN2_TX_DP<35>")
	)
	(segment
		(start 443.466982 -77.751178)
		(end 441.262516 -79.960724)
		(width 0.1651)
		(layer "In11.Cu")
		(net "P5E_PEX3_STN2_TX_DP<35>")
	)
	(segment
		(start 403.533864 -271.427448)
		(end 403.579584 -271.473168)
		(width 0.1143)
		(layer "In11.Cu")
		(net "P5E_PEX3_STN2_TX_DP<35>")
	)
	(segment
		(start 450.253608 -35.190176)
		(end 450.207126 -35.344862)
		(width 0.1651)
		(layer "In11.Cu")
		(net "P5E_PEX3_STN2_TX_DP<35>")
	)
	(segment
		(start 80.594962 -351.316798)
		(end 80.594962 -350.685354)
		(width 0.13462)
		(layer "F.Cu")
		(net "P5E_PEX0_STN5_TX_C_DN<89>")
	)
	(segment
		(start 80.594962 -350.685354)
		(end 80.915002 -350.365314)
		(width 0.13462)
		(layer "F.Cu")
		(net "P5E_PEX0_STN5_TX_C_DN<89>")
	)
	(segment
		(start 80.889602 -351.611438)
		(end 80.594962 -351.316798)
		(width 0.13462)
		(layer "F.Cu")
		(net "P5E_PEX0_STN5_TX_C_DN<89>")
	)
	(segment
		(start 78.651354 -360.519726)
		(end 79.044292 -358.544876)
		(width 0.1651)
		(layer "In7.Cu")
		(net "P5E_PEX0_STN5_TX_C_DN<89>")
	)
	(segment
		(start 80.598772 -351.902268)
		(end 80.889602 -351.611438)
		(width 0.1651)
		(layer "In7.Cu")
		(net "P5E_PEX0_STN5_TX_C_DN<89>")
	)
	(segment
		(start 74.109834 -380.308104)
		(end 74.236834 -380.181104)
		(width 0.1651)
		(layer "In7.Cu")
		(net "P5E_PEX0_STN5_TX_C_DN<89>")
	)
	(segment
		(start 79.044292 -354.107242)
		(end 80.598772 -352.552762)
		(width 0.1651)
		(layer "In7.Cu")
		(net "P5E_PEX0_STN5_TX_C_DN<89>")
	)
	(segment
		(start 74.236834 -380.181104)
		(end 74.767948 -380.181104)
		(width 0.1651)
		(layer "In7.Cu")
		(net "P5E_PEX0_STN5_TX_C_DN<89>")
	)
	(segment
		(start 79.044292 -358.544876)
		(end 79.044292 -354.107242)
		(width 0.1651)
		(layer "In7.Cu")
		(net "P5E_PEX0_STN5_TX_C_DN<89>")
	)
	(segment
		(start 74.109834 -380.69012)
		(end 74.109834 -380.308104)
		(width 0.1651)
		(layer "In7.Cu")
		(net "P5E_PEX0_STN5_TX_C_DN<89>")
	)
	(segment
		(start 75.28433 -368.648742)
		(end 78.651354 -360.519726)
		(width 0.1651)
		(layer "In7.Cu")
		(net "P5E_PEX0_STN5_TX_C_DN<89>")
	)
	(segment
		(start 80.598772 -352.552762)
		(end 80.598772 -351.902268)
		(width 0.1651)
		(layer "In7.Cu")
		(net "P5E_PEX0_STN5_TX_C_DN<89>")
	)
	(segment
		(start 74.767948 -380.181104)
		(end 75.28433 -379.664722)
		(width 0.1651)
		(layer "In7.Cu")
		(net "P5E_PEX0_STN5_TX_C_DN<89>")
	)
	(segment
		(start 75.28433 -379.664722)
		(end 75.28433 -368.648742)
		(width 0.1651)
		(layer "In7.Cu")
		(net "P5E_PEX0_STN5_TX_C_DN<89>")
	)
	(segment
		(start 77.486002 -349.511874)
		(end 77.486002 -348.88043)
		(width 0.13462)
		(layer "F.Cu")
		(net "P5E_PEX0_STN6_TX_DN<104>")
	)
	(segment
		(start 77.806042 -349.831914)
		(end 77.486002 -349.511874)
		(width 0.13462)
		(layer "F.Cu")
		(net "P5E_PEX0_STN6_TX_DN<104>")
	)
	(segment
		(start 77.486002 -348.88043)
		(end 77.780642 -348.58579)
		(width 0.13462)
		(layer "F.Cu")
		(net "P5E_PEX0_STN6_TX_DN<104>")
	)
	(segment
		(start 49.77003 -320.080132)
		(end 49.77003 -313.719718)
		(width 0.1143)
		(layer "In13.Cu")
		(net "P5E_PEX0_STN6_TX_DN<104>")
	)
	(segment
		(start 50.06086 -313.570112)
		(end 50.14976 -313.659012)
		(width 0.1143)
		(layer "In13.Cu")
		(net "P5E_PEX0_STN6_TX_DN<104>")
	)
	(segment
		(start 77.780642 -348.58579)
		(end 77.489812 -348.29496)
		(width 0.1651)
		(layer "In13.Cu")
		(net "P5E_PEX0_STN6_TX_DN<104>")
	)
	(segment
		(start 50.14976 -313.659012)
		(end 50.14976 -313.949842)
		(width 0.1143)
		(layer "In13.Cu")
		(net "P5E_PEX0_STN6_TX_DN<104>")
	)
	(segment
		(start 49.919636 -313.570112)
		(end 50.06086 -313.570112)
		(width 0.1143)
		(layer "In13.Cu")
		(net "P5E_PEX0_STN6_TX_DN<104>")
	)
	(segment
		(start 49.81575 -322.755006)
		(end 49.81575 -320.14795)
		(width 0.1651)
		(layer "In13.Cu")
		(net "P5E_PEX0_STN6_TX_DN<104>")
	)
	(segment
		(start 79.044292 -342.10371)
		(end 78.39075 -341.013542)
		(width 0.1651)
		(layer "In13.Cu")
		(net "P5E_PEX0_STN6_TX_DN<104>")
	)
	(segment
		(start 51.033426 -325.694802)
		(end 49.81575 -322.755006)
		(width 0.1651)
		(layer "In13.Cu")
		(net "P5E_PEX0_STN6_TX_DN<104>")
	)
	(segment
		(start 54.940708 -328.479404)
		(end 53.024024 -327.6854)
		(width 0.1651)
		(layer "In13.Cu")
		(net "P5E_PEX0_STN6_TX_DN<104>")
	)
	(segment
		(start 78.39075 -341.013542)
		(end 54.940708 -328.479404)
		(width 0.1651)
		(layer "In13.Cu")
		(net "P5E_PEX0_STN6_TX_DN<104>")
	)
	(segment
		(start 49.81575 -320.14795)
		(end 49.81575 -320.125852)
		(width 0.1143)
		(layer "In13.Cu")
		(net "P5E_PEX0_STN6_TX_DN<104>")
	)
	(segment
		(start 77.489812 -348.29496)
		(end 77.489812 -347.716348)
		(width 0.1651)
		(layer "In13.Cu")
		(net "P5E_PEX0_STN6_TX_DN<104>")
	)
	(segment
		(start 79.044292 -346.161868)
		(end 79.044292 -342.10371)
		(width 0.1651)
		(layer "In13.Cu")
		(net "P5E_PEX0_STN6_TX_DN<104>")
	)
	(segment
		(start 49.77003 -313.719718)
		(end 49.919636 -313.570112)
		(width 0.1143)
		(layer "In13.Cu")
		(net "P5E_PEX0_STN6_TX_DN<104>")
	)
	(segment
		(start 49.81575 -320.125852)
		(end 49.77003 -320.080132)
		(width 0.1143)
		(layer "In13.Cu")
		(net "P5E_PEX0_STN6_TX_DN<104>")
	)
	(segment
		(start 77.489812 -347.716348)
		(end 79.044292 -346.161868)
		(width 0.1651)
		(layer "In13.Cu")
		(net "P5E_PEX0_STN6_TX_DN<104>")
	)
	(segment
		(start 53.024024 -327.6854)
		(end 51.033426 -325.694802)
		(width 0.1651)
		(layer "In13.Cu")
		(net "P5E_PEX0_STN6_TX_DN<104>")
	)
	(segment
		(start 86.812882 -348.88043)
		(end 87.107522 -348.58579)
		(width 0.13462)
		(layer "F.Cu")
		(net "P5E_PEX0_STN5_TX_DN<92>")
	)
	(segment
		(start 86.812882 -349.511874)
		(end 86.812882 -348.88043)
		(width 0.13462)
		(layer "F.Cu")
		(net "P5E_PEX0_STN5_TX_DN<92>")
	)
	(segment
		(start 87.132922 -349.831914)
		(end 86.812882 -349.511874)
		(width 0.13462)
		(layer "F.Cu")
		(net "P5E_PEX0_STN5_TX_DN<92>")
	)
	(segment
		(start 69.765926 -320.850514)
		(end 69.765926 -319.941448)
		(width 0.1651)
		(layer "In7.Cu")
		(net "P5E_PEX0_STN5_TX_DN<92>")
	)
	(segment
		(start 69.765926 -319.913)
		(end 69.720206 -319.86728)
		(width 0.1143)
		(layer "In7.Cu")
		(net "P5E_PEX0_STN5_TX_DN<92>")
	)
	(segment
		(start 70.944994 -322.912994)
		(end 70.090538 -321.634104)
		(width 0.1651)
		(layer "In7.Cu")
		(net "P5E_PEX0_STN5_TX_DN<92>")
	)
	(segment
		(start 88.371172 -346.103702)
		(end 88.371172 -341.600028)
		(width 0.1651)
		(layer "In7.Cu")
		(net "P5E_PEX0_STN5_TX_DN<92>")
	)
	(segment
		(start 70.099936 -311.784492)
		(end 70.099936 -312.049922)
		(width 0.1143)
		(layer "In7.Cu")
		(net "P5E_PEX0_STN5_TX_DN<92>")
	)
	(segment
		(start 69.765926 -319.941448)
		(end 69.765926 -319.913)
		(width 0.1143)
		(layer "In7.Cu")
		(net "P5E_PEX0_STN5_TX_DN<92>")
	)
	(segment
		(start 87.107522 -348.58579)
		(end 86.816692 -348.29496)
		(width 0.1651)
		(layer "In7.Cu")
		(net "P5E_PEX0_STN5_TX_DN<92>")
	)
	(segment
		(start 69.834506 -311.670192)
		(end 69.985636 -311.670192)
		(width 0.1143)
		(layer "In7.Cu")
		(net "P5E_PEX0_STN5_TX_DN<92>")
	)
	(segment
		(start 70.090538 -321.634104)
		(end 69.765926 -320.850514)
		(width 0.1651)
		(layer "In7.Cu")
		(net "P5E_PEX0_STN5_TX_DN<92>")
	)
	(segment
		(start 69.985636 -311.670192)
		(end 70.099936 -311.784492)
		(width 0.1143)
		(layer "In7.Cu")
		(net "P5E_PEX0_STN5_TX_DN<92>")
	)
	(segment
		(start 69.720206 -311.784492)
		(end 69.834506 -311.670192)
		(width 0.1143)
		(layer "In7.Cu")
		(net "P5E_PEX0_STN5_TX_DN<92>")
	)
	(segment
		(start 86.816692 -347.658182)
		(end 88.371172 -346.103702)
		(width 0.1651)
		(layer "In7.Cu")
		(net "P5E_PEX0_STN5_TX_DN<92>")
	)
	(segment
		(start 87.479632 -339.447632)
		(end 70.944994 -322.912994)
		(width 0.1651)
		(layer "In7.Cu")
		(net "P5E_PEX0_STN5_TX_DN<92>")
	)
	(segment
		(start 69.720206 -319.86728)
		(end 69.720206 -311.784492)
		(width 0.1143)
		(layer "In7.Cu")
		(net "P5E_PEX0_STN5_TX_DN<92>")
	)
	(segment
		(start 86.816692 -348.29496)
		(end 86.816692 -347.658182)
		(width 0.1651)
		(layer "In7.Cu")
		(net "P5E_PEX0_STN5_TX_DN<92>")
	)
	(segment
		(start 88.371172 -341.600028)
		(end 87.479632 -339.447632)
		(width 0.1651)
		(layer "In7.Cu")
		(net "P5E_PEX0_STN5_TX_DN<92>")
	)
	(segment
		(start 312.502804 -348.58579)
		(end 312.797444 -348.88043)
		(width 0.13462)
		(layer "F.Cu")
		(net "P5E_PEX2_STN5_TX_DP<80>")
	)
	(segment
		(start 312.797444 -348.88043)
		(end 312.797444 -349.511874)
		(width 0.13462)
		(layer "F.Cu")
		(net "P5E_PEX2_STN5_TX_DP<80>")
	)
	(segment
		(start 312.797444 -349.511874)
		(end 312.477404 -349.831914)
		(width 0.13462)
		(layer "F.Cu")
		(net "P5E_PEX2_STN5_TX_DP<80>")
	)
	(segment
		(start 290.89985 -311.365392)
		(end 290.89985 -311.099962)
		(width 0.1143)
		(layer "In7.Cu")
		(net "P5E_PEX2_STN5_TX_DP<80>")
	)
	(segment
		(start 312.502804 -348.58579)
		(end 312.793634 -348.29496)
		(width 0.1651)
		(layer "In7.Cu")
		(net "P5E_PEX2_STN5_TX_DP<80>")
	)
	(segment
		(start 312.793634 -348.29496)
		(end 312.793634 -347.667834)
		(width 0.1651)
		(layer "In7.Cu")
		(net "P5E_PEX2_STN5_TX_DP<80>")
	)
	(segment
		(start 290.2839 -319.8368)
		(end 290.32962 -319.79108)
		(width 0.1143)
		(layer "In7.Cu")
		(net "P5E_PEX2_STN5_TX_DP<80>")
	)
	(segment
		(start 292.840156 -330.03617)
		(end 290.2839 -325.28891)
		(width 0.1651)
		(layer "In7.Cu")
		(net "P5E_PEX2_STN5_TX_DP<80>")
	)
	(segment
		(start 290.2839 -319.865248)
		(end 290.2839 -319.8368)
		(width 0.1143)
		(layer "In7.Cu")
		(net "P5E_PEX2_STN5_TX_DP<80>")
	)
	(segment
		(start 290.78555 -311.479692)
		(end 290.89985 -311.365392)
		(width 0.1143)
		(layer "In7.Cu")
		(net "P5E_PEX2_STN5_TX_DP<80>")
	)
	(segment
		(start 296.36212 -333.580994)
		(end 292.840156 -330.03617)
		(width 0.1651)
		(layer "In7.Cu")
		(net "P5E_PEX2_STN5_TX_DP<80>")
	)
	(segment
		(start 290.32962 -319.79108)
		(end 290.32962 -311.705498)
		(width 0.1143)
		(layer "In7.Cu")
		(net "P5E_PEX2_STN5_TX_DP<80>")
	)
	(segment
		(start 312.46953 -347.34373)
		(end 296.36212 -333.580994)
		(width 0.1651)
		(layer "In7.Cu")
		(net "P5E_PEX2_STN5_TX_DP<80>")
	)
	(segment
		(start 290.32962 -311.705498)
		(end 290.555426 -311.479692)
		(width 0.1143)
		(layer "In7.Cu")
		(net "P5E_PEX2_STN5_TX_DP<80>")
	)
	(segment
		(start 290.555426 -311.479692)
		(end 290.78555 -311.479692)
		(width 0.1143)
		(layer "In7.Cu")
		(net "P5E_PEX2_STN5_TX_DP<80>")
	)
	(segment
		(start 290.2839 -325.28891)
		(end 290.2839 -319.865248)
		(width 0.1651)
		(layer "In7.Cu")
		(net "P5E_PEX2_STN5_TX_DP<80>")
	)
	(segment
		(start 312.793634 -347.667834)
		(end 312.46953 -347.34373)
		(width 0.1651)
		(layer "In7.Cu")
		(net "P5E_PEX2_STN5_TX_DP<80>")
	)
	(segment
		(start 395.329156 -33.9598)
		(end 395.001242 -33.631886)
		(width 0.13462)
		(layer "F.Cu")
		(net "P5E_PEX3_STN2_TX_DN<43>")
	)
	(segment
		(start 396.247366 -33.657286)
		(end 395.944852 -33.9598)
		(width 0.13462)
		(layer "F.Cu")
		(net "P5E_PEX3_STN2_TX_DN<43>")
	)
	(segment
		(start 395.944852 -33.9598)
		(end 395.329156 -33.9598)
		(width 0.13462)
		(layer "F.Cu")
		(net "P5E_PEX3_STN2_TX_DN<43>")
	)
	(segment
		(start 394.079222 -111.782606)
		(end 392.860784 -112.983264)
		(width 0.1651)
		(layer "In11.Cu")
		(net "P5E_PEX3_STN2_TX_DN<43>")
	)
	(segment
		(start 391.101326 -116.459254)
		(end 391.093706 -146.80565)
		(width 0.1651)
		(layer "In11.Cu")
		(net "P5E_PEX3_STN2_TX_DN<43>")
	)
	(segment
		(start 395.834616 -265.75258)
		(end 396.21587 -269.62354)
		(width 0.1651)
		(layer "In11.Cu")
		(net "P5E_PEX3_STN2_TX_DN<43>")
	)
	(segment
		(start 396.21587 -271.399)
		(end 396.21587 -271.427448)
		(width 0.1143)
		(layer "In11.Cu")
		(net "P5E_PEX3_STN2_TX_DN<43>")
	)
	(segment
		(start 396.17015 -278.125936)
		(end 396.273782 -278.229568)
		(width 0.1143)
		(layer "In11.Cu")
		(net "P5E_PEX3_STN2_TX_DN<43>")
	)
	(segment
		(start 409.136596 -68.48983)
		(end 398.921224 -95.476568)
		(width 0.1651)
		(layer "In11.Cu")
		(net "P5E_PEX3_STN2_TX_DN<43>")
	)
	(segment
		(start 397.236188 -101.666802)
		(end 394.079222 -111.782606)
		(width 0.1651)
		(layer "In11.Cu")
		(net "P5E_PEX3_STN2_TX_DN<43>")
	)
	(segment
		(start 391.36193 -115.22456)
		(end 391.101326 -116.459254)
		(width 0.1651)
		(layer "In11.Cu")
		(net "P5E_PEX3_STN2_TX_DN<43>")
	)
	(segment
		(start 410.62783 -60.360052)
		(end 409.136596 -68.48983)
		(width 0.1651)
		(layer "In11.Cu")
		(net "P5E_PEX3_STN2_TX_DN<43>")
	)
	(segment
		(start 396.17015 -271.473168)
		(end 396.17015 -278.125936)
		(width 0.1143)
		(layer "In11.Cu")
		(net "P5E_PEX3_STN2_TX_DN<43>")
	)
	(segment
		(start 396.538196 -33.948116)
		(end 397.4592 -33.948116)
		(width 0.1651)
		(layer "In11.Cu")
		(net "P5E_PEX3_STN2_TX_DN<43>")
	)
	(segment
		(start 399.252948 -35.769296)
		(end 409.530296 -49.134776)
		(width 0.1651)
		(layer "In11.Cu")
		(net "P5E_PEX3_STN2_TX_DN<43>")
	)
	(segment
		(start 392.156442 -162.530282)
		(end 395.834616 -265.75258)
		(width 0.1651)
		(layer "In11.Cu")
		(net "P5E_PEX3_STN2_TX_DN<43>")
	)
	(segment
		(start 396.247366 -33.657286)
		(end 396.538196 -33.948116)
		(width 0.1651)
		(layer "In11.Cu")
		(net "P5E_PEX3_STN2_TX_DN<43>")
	)
	(segment
		(start 409.99664 -50.493168)
		(end 410.62783 -60.360052)
		(width 0.1651)
		(layer "In11.Cu")
		(net "P5E_PEX3_STN2_TX_DN<43>")
	)
	(segment
		(start 396.43558 -278.229568)
		(end 396.54988 -278.115268)
		(width 0.1143)
		(layer "In11.Cu")
		(net "P5E_PEX3_STN2_TX_DN<43>")
	)
	(segment
		(start 397.4592 -33.948116)
		(end 399.252948 -35.769296)
		(width 0.1651)
		(layer "In11.Cu")
		(net "P5E_PEX3_STN2_TX_DN<43>")
	)
	(segment
		(start 409.530296 -49.134776)
		(end 409.99664 -50.493168)
		(width 0.1651)
		(layer "In11.Cu")
		(net "P5E_PEX3_STN2_TX_DN<43>")
	)
	(segment
		(start 396.21587 -271.427448)
		(end 396.17015 -271.473168)
		(width 0.1143)
		(layer "In11.Cu")
		(net "P5E_PEX3_STN2_TX_DN<43>")
	)
	(segment
		(start 391.093706 -146.80565)
		(end 392.156442 -162.530282)
		(width 0.1651)
		(layer "In11.Cu")
		(net "P5E_PEX3_STN2_TX_DN<43>")
	)
	(segment
		(start 396.21587 -269.62354)
		(end 396.21587 -271.399)
		(width 0.1651)
		(layer "In11.Cu")
		(net "P5E_PEX3_STN2_TX_DN<43>")
	)
	(segment
		(start 398.921224 -95.476568)
		(end 397.236188 -101.666802)
		(width 0.1651)
		(layer "In11.Cu")
		(net "P5E_PEX3_STN2_TX_DN<43>")
	)
	(segment
		(start 396.54988 -278.115268)
		(end 396.54988 -277.849838)
		(width 0.1143)
		(layer "In11.Cu")
		(net "P5E_PEX3_STN2_TX_DN<43>")
	)
	(segment
		(start 392.860784 -112.983264)
		(end 391.36193 -115.22456)
		(width 0.1651)
		(layer "In11.Cu")
		(net "P5E_PEX3_STN2_TX_DN<43>")
	)
	(segment
		(start 396.273782 -278.229568)
		(end 396.43558 -278.229568)
		(width 0.1143)
		(layer "In11.Cu")
		(net "P5E_PEX3_STN2_TX_DN<43>")
	)
	(segment
		(start 41.664128 -344.539062)
		(end 41.984168 -344.219022)
		(width 0.13462)
		(layer "F.Cu")
		(net "P5E_PEX0_STN7_TX_C_DP<122>")
	)
	(segment
		(start 41.664128 -345.170506)
		(end 41.664128 -344.539062)
		(width 0.13462)
		(layer "F.Cu")
		(net "P5E_PEX0_STN7_TX_C_DP<122>")
	)
	(segment
		(start 41.958768 -345.465146)
		(end 41.664128 -345.170506)
		(width 0.13462)
		(layer "F.Cu")
		(net "P5E_PEX0_STN7_TX_C_DP<122>")
	)
	(segment
		(start 40.113458 -358.058974)
		(end 40.113458 -348.029022)
		(width 0.1651)
		(layer "In7.Cu")
		(net "P5E_PEX0_STN7_TX_C_DP<122>")
	)
	(segment
		(start 33.484312 -369.969034)
		(end 34.14014 -367.806986)
		(width 0.1651)
		(layer "In7.Cu")
		(net "P5E_PEX0_STN7_TX_C_DP<122>")
	)
	(segment
		(start 33.484312 -374.607328)
		(end 33.484312 -369.969034)
		(width 0.1651)
		(layer "In7.Cu")
		(net "P5E_PEX0_STN7_TX_C_DP<122>")
	)
	(segment
		(start 32.43707 -375.181114)
		(end 32.910526 -375.181114)
		(width 0.1651)
		(layer "In7.Cu")
		(net "P5E_PEX0_STN7_TX_C_DP<122>")
	)
	(segment
		(start 39.664386 -359.539794)
		(end 40.113458 -358.058974)
		(width 0.1651)
		(layer "In7.Cu")
		(net "P5E_PEX0_STN7_TX_C_DP<122>")
	)
	(segment
		(start 32.31007 -375.308114)
		(end 32.43707 -375.181114)
		(width 0.1651)
		(layer "In7.Cu")
		(net "P5E_PEX0_STN7_TX_C_DP<122>")
	)
	(segment
		(start 32.31007 -375.69013)
		(end 32.31007 -375.308114)
		(width 0.1651)
		(layer "In7.Cu")
		(net "P5E_PEX0_STN7_TX_C_DP<122>")
	)
	(segment
		(start 34.14014 -367.806986)
		(end 39.664386 -359.539794)
		(width 0.1651)
		(layer "In7.Cu")
		(net "P5E_PEX0_STN7_TX_C_DP<122>")
	)
	(segment
		(start 41.667938 -346.474542)
		(end 41.667938 -345.755976)
		(width 0.1651)
		(layer "In7.Cu")
		(net "P5E_PEX0_STN7_TX_C_DP<122>")
	)
	(segment
		(start 41.667938 -345.755976)
		(end 41.958768 -345.465146)
		(width 0.1651)
		(layer "In7.Cu")
		(net "P5E_PEX0_STN7_TX_C_DP<122>")
	)
	(segment
		(start 32.910526 -375.181114)
		(end 33.484312 -374.607328)
		(width 0.1651)
		(layer "In7.Cu")
		(net "P5E_PEX0_STN7_TX_C_DP<122>")
	)
	(segment
		(start 40.113458 -348.029022)
		(end 41.667938 -346.474542)
		(width 0.1651)
		(layer "In7.Cu")
		(net "P5E_PEX0_STN7_TX_C_DP<122>")
	)
	(segment
		(start 335.154524 -344.219022)
		(end 334.834484 -344.539062)
		(width 0.13462)
		(layer "F.Cu")
		(net "P5E_PEX2_STN5_TX_C_DN<90>")
	)
	(segment
		(start 334.834484 -345.170506)
		(end 335.129124 -345.465146)
		(width 0.13462)
		(layer "F.Cu")
		(net "P5E_PEX2_STN5_TX_C_DN<90>")
	)
	(segment
		(start 334.834484 -344.539062)
		(end 334.834484 -345.170506)
		(width 0.13462)
		(layer "F.Cu")
		(net "P5E_PEX2_STN5_TX_C_DN<90>")
	)
	(segment
		(start 337.01609 -378.629164)
		(end 336.564224 -379.08103)
		(width 0.1651)
		(layer "In7.Cu")
		(net "P5E_PEX2_STN5_TX_C_DN<90>")
	)
	(segment
		(start 336.017108 -379.08103)
		(end 335.890108 -379.20803)
		(width 0.1651)
		(layer "In7.Cu")
		(net "P5E_PEX2_STN5_TX_C_DN<90>")
	)
	(segment
		(start 335.890108 -379.20803)
		(end 335.890108 -379.590046)
		(width 0.1651)
		(layer "In7.Cu")
		(net "P5E_PEX2_STN5_TX_C_DN<90>")
	)
	(segment
		(start 337.01609 -368.593116)
		(end 337.01609 -378.629164)
		(width 0.1651)
		(layer "In7.Cu")
		(net "P5E_PEX2_STN5_TX_C_DN<90>")
	)
	(segment
		(start 335.129124 -345.465146)
		(end 334.838294 -345.755976)
		(width 0.1651)
		(layer "In7.Cu")
		(net "P5E_PEX2_STN5_TX_C_DN<90>")
	)
	(segment
		(start 336.564224 -379.08103)
		(end 336.017108 -379.08103)
		(width 0.1651)
		(layer "In7.Cu")
		(net "P5E_PEX2_STN5_TX_C_DN<90>")
	)
	(segment
		(start 334.838294 -346.326714)
		(end 333.283814 -347.881194)
		(width 0.1651)
		(layer "In7.Cu")
		(net "P5E_PEX2_STN5_TX_C_DN<90>")
	)
	(segment
		(start 334.838294 -345.755976)
		(end 334.838294 -346.326714)
		(width 0.1651)
		(layer "In7.Cu")
		(net "P5E_PEX2_STN5_TX_C_DN<90>")
	)
	(segment
		(start 333.283814 -358.161844)
		(end 337.01609 -368.593116)
		(width 0.1651)
		(layer "In7.Cu")
		(net "P5E_PEX2_STN5_TX_C_DN<90>")
	)
	(segment
		(start 333.283814 -347.881194)
		(end 333.283814 -358.161844)
		(width 0.1651)
		(layer "In7.Cu")
		(net "P5E_PEX2_STN5_TX_C_DN<90>")
	)
	(segment
		(start 21.022564 -30.353)
		(end 20.701254 -30.03169)
		(width 0.13462)
		(layer "F.Cu")
		(net "P5E_PEX0_STN2_TX_DN<45>")
	)
	(segment
		(start 21.651468 -30.353)
		(end 21.022564 -30.353)
		(width 0.13462)
		(layer "F.Cu")
		(net "P5E_PEX0_STN2_TX_DN<45>")
	)
	(segment
		(start 21.947378 -30.05709)
		(end 21.651468 -30.353)
		(width 0.13462)
		(layer "F.Cu")
		(net "P5E_PEX0_STN2_TX_DN<45>")
	)
	(segment
		(start 23.268178 -30.58795)
		(end 24.50338 -31.646114)
		(width 0.1651)
		(layer "In11.Cu")
		(net "P5E_PEX0_STN2_TX_DN<45>")
	)
	(segment
		(start 37.024818 -48.4632)
		(end 37.66312 -50.312828)
		(width 0.1651)
		(layer "In11.Cu")
		(net "P5E_PEX0_STN2_TX_DN<45>")
	)
	(segment
		(start 37.66312 -50.312828)
		(end 38.429438 -63.149734)
		(width 0.1651)
		(layer "In11.Cu")
		(net "P5E_PEX0_STN2_TX_DN<45>")
	)
	(segment
		(start 22.192996 -30.302708)
		(end 22.301962 -30.34792)
		(width 0.1651)
		(layer "In11.Cu")
		(net "P5E_PEX0_STN2_TX_DN<45>")
	)
	(segment
		(start 22.301962 -30.34792)
		(end 22.687788 -30.34792)
		(width 0.1651)
		(layer "In11.Cu")
		(net "P5E_PEX0_STN2_TX_DN<45>")
	)
	(segment
		(start 46.073822 -278.229568)
		(end 46.23562 -278.229568)
		(width 0.1143)
		(layer "In11.Cu")
		(net "P5E_PEX0_STN2_TX_DN<45>")
	)
	(segment
		(start 46.01591 -270.360902)
		(end 46.01591 -271.399)
		(width 0.1651)
		(layer "In11.Cu")
		(net "P5E_PEX0_STN2_TX_DN<45>")
	)
	(segment
		(start 38.429438 -63.149734)
		(end 37.554408 -78.912974)
		(width 0.1651)
		(layer "In11.Cu")
		(net "P5E_PEX0_STN2_TX_DN<45>")
	)
	(segment
		(start 22.687788 -30.34792)
		(end 23.268178 -30.58795)
		(width 0.1651)
		(layer "In11.Cu")
		(net "P5E_PEX0_STN2_TX_DN<45>")
	)
	(segment
		(start 33.420812 -116.209572)
		(end 33.822894 -137.972292)
		(width 0.1651)
		(layer "In11.Cu")
		(net "P5E_PEX0_STN2_TX_DN<45>")
	)
	(segment
		(start 33.822894 -137.972292)
		(end 44.98721 -264.159746)
		(width 0.1651)
		(layer "In11.Cu")
		(net "P5E_PEX0_STN2_TX_DN<45>")
	)
	(segment
		(start 21.947378 -30.05709)
		(end 22.192996 -30.302708)
		(width 0.1651)
		(layer "In11.Cu")
		(net "P5E_PEX0_STN2_TX_DN<45>")
	)
	(segment
		(start 45.97019 -271.473168)
		(end 45.97019 -278.125936)
		(width 0.1143)
		(layer "In11.Cu")
		(net "P5E_PEX0_STN2_TX_DN<45>")
	)
	(segment
		(start 46.34992 -278.115268)
		(end 46.34992 -277.849838)
		(width 0.1143)
		(layer "In11.Cu")
		(net "P5E_PEX0_STN2_TX_DN<45>")
	)
	(segment
		(start 35.07613 -44.917868)
		(end 37.024818 -48.4632)
		(width 0.1651)
		(layer "In11.Cu")
		(net "P5E_PEX0_STN2_TX_DN<45>")
	)
	(segment
		(start 46.01591 -271.399)
		(end 46.01591 -271.427448)
		(width 0.1143)
		(layer "In11.Cu")
		(net "P5E_PEX0_STN2_TX_DN<45>")
	)
	(segment
		(start 46.23562 -278.229568)
		(end 46.34992 -278.115268)
		(width 0.1143)
		(layer "In11.Cu")
		(net "P5E_PEX0_STN2_TX_DN<45>")
	)
	(segment
		(start 44.98721 -264.159746)
		(end 46.01591 -270.360902)
		(width 0.1651)
		(layer "In11.Cu")
		(net "P5E_PEX0_STN2_TX_DN<45>")
	)
	(segment
		(start 37.554408 -78.912974)
		(end 33.923732 -105.234486)
		(width 0.1651)
		(layer "In11.Cu")
		(net "P5E_PEX0_STN2_TX_DN<45>")
	)
	(segment
		(start 45.97019 -278.125936)
		(end 46.073822 -278.229568)
		(width 0.1143)
		(layer "In11.Cu")
		(net "P5E_PEX0_STN2_TX_DN<45>")
	)
	(segment
		(start 46.01591 -271.427448)
		(end 45.97019 -271.473168)
		(width 0.1143)
		(layer "In11.Cu")
		(net "P5E_PEX0_STN2_TX_DN<45>")
	)
	(segment
		(start 24.50338 -31.646114)
		(end 35.07613 -44.917868)
		(width 0.1651)
		(layer "In11.Cu")
		(net "P5E_PEX0_STN2_TX_DN<45>")
	)
	(segment
		(start 33.923732 -105.234486)
		(end 33.420812 -116.209572)
		(width 0.1651)
		(layer "In11.Cu")
		(net "P5E_PEX0_STN2_TX_DN<45>")
	)
	(segment
		(start 341.372444 -343.685622)
		(end 341.052404 -343.365582)
		(width 0.13462)
		(layer "F.Cu")
		(net "P5E_PEX2_STN5_TX_DN<93>")
	)
	(segment
		(start 341.052404 -343.365582)
		(end 341.052404 -342.734138)
		(width 0.13462)
		(layer "F.Cu")
		(net "P5E_PEX2_STN5_TX_DN<93>")
	)
	(segment
		(start 341.052404 -342.734138)
		(end 341.347044 -342.439498)
		(width 0.13462)
		(layer "F.Cu")
		(net "P5E_PEX2_STN5_TX_DN<93>")
	)
	(segment
		(start 302.870108 -313.684412)
		(end 302.984408 -313.570112)
		(width 0.1143)
		(layer "In7.Cu")
		(net "P5E_PEX2_STN5_TX_DN<93>")
	)
	(segment
		(start 333.508096 -336.079592)
		(end 333.508096 -336.079846)
		(width 0.1651)
		(layer "In7.Cu")
		(net "P5E_PEX2_STN5_TX_DN<93>")
	)
	(segment
		(start 302.915828 -319.839848)
		(end 302.870108 -319.794128)
		(width 0.1143)
		(layer "In7.Cu")
		(net "P5E_PEX2_STN5_TX_DN<93>")
	)
	(segment
		(start 311.671208 -325.319898)
		(end 311.622186 -325.204074)
		(width 0.1651)
		(layer "In7.Cu")
		(net "P5E_PEX2_STN5_TX_DN<93>")
	)
	(segment
		(start 302.984408 -313.570112)
		(end 303.135538 -313.570112)
		(width 0.1143)
		(layer "In7.Cu")
		(net "P5E_PEX2_STN5_TX_DN<93>")
	)
	(segment
		(start 341.056214 -342.148668)
		(end 341.056214 -341.633048)
		(width 0.1651)
		(layer "In7.Cu")
		(net "P5E_PEX2_STN5_TX_DN<93>")
	)
	(segment
		(start 341.347044 -342.439498)
		(end 341.056214 -342.148668)
		(width 0.1651)
		(layer "In7.Cu")
		(net "P5E_PEX2_STN5_TX_DN<93>")
	)
	(segment
		(start 326.3646 -331.2922)
		(end 311.671208 -325.319898)
		(width 0.1651)
		(layer "In7.Cu")
		(net "P5E_PEX2_STN5_TX_DN<93>")
	)
	(segment
		(start 311.047384 -325.066152)
		(end 304.539142 -322.420742)
		(width 0.1651)
		(layer "In7.Cu")
		(net "P5E_PEX2_STN5_TX_DN<93>")
	)
	(segment
		(start 303.163224 -321.044824)
		(end 302.915828 -320.447416)
		(width 0.1651)
		(layer "In7.Cu")
		(net "P5E_PEX2_STN5_TX_DN<93>")
	)
	(segment
		(start 311.163208 -325.01713)
		(end 311.047384 -325.066152)
		(width 0.1651)
		(layer "In7.Cu")
		(net "P5E_PEX2_STN5_TX_DN<93>")
	)
	(segment
		(start 304.539142 -322.420742)
		(end 303.163224 -321.044824)
		(width 0.1651)
		(layer "In7.Cu")
		(net "P5E_PEX2_STN5_TX_DN<93>")
	)
	(segment
		(start 302.870108 -319.794128)
		(end 302.870108 -313.684412)
		(width 0.1143)
		(layer "In7.Cu")
		(net "P5E_PEX2_STN5_TX_DN<93>")
	)
	(segment
		(start 303.249838 -313.684412)
		(end 303.249838 -313.949842)
		(width 0.1143)
		(layer "In7.Cu")
		(net "P5E_PEX2_STN5_TX_DN<93>")
	)
	(segment
		(start 340.6902 -340.8934)
		(end 333.508096 -336.079592)
		(width 0.1651)
		(layer "In7.Cu")
		(net "P5E_PEX2_STN5_TX_DN<93>")
	)
	(segment
		(start 341.056214 -341.633048)
		(end 340.6902 -340.8934)
		(width 0.1651)
		(layer "In7.Cu")
		(net "P5E_PEX2_STN5_TX_DN<93>")
	)
	(segment
		(start 311.622186 -325.204074)
		(end 311.163208 -325.01713)
		(width 0.1651)
		(layer "In7.Cu")
		(net "P5E_PEX2_STN5_TX_DN<93>")
	)
	(segment
		(start 302.915828 -319.868296)
		(end 302.915828 -319.839848)
		(width 0.1143)
		(layer "In7.Cu")
		(net "P5E_PEX2_STN5_TX_DN<93>")
	)
	(segment
		(start 333.508096 -336.079846)
		(end 326.3646 -331.2922)
		(width 0.1651)
		(layer "In7.Cu")
		(net "P5E_PEX2_STN5_TX_DN<93>")
	)
	(segment
		(start 303.135538 -313.570112)
		(end 303.249838 -313.684412)
		(width 0.1143)
		(layer "In7.Cu")
		(net "P5E_PEX2_STN5_TX_DN<93>")
	)
	(segment
		(start 302.915828 -320.447416)
		(end 302.915828 -319.868296)
		(width 0.1651)
		(layer "In7.Cu")
		(net "P5E_PEX2_STN5_TX_DN<93>")
	)
	(segment
		(start 392.680698 -32.41802)
		(end 392.359134 -32.739584)
		(width 0.13462)
		(layer "F.Cu")
		(net "P5E_PEX3_STN2_TX_DP<42>")
	)
	(segment
		(start 393.309094 -32.41802)
		(end 392.680698 -32.41802)
		(width 0.13462)
		(layer "F.Cu")
		(net "P5E_PEX3_STN2_TX_DP<42>")
	)
	(segment
		(start 393.605258 -32.714184)
		(end 393.309094 -32.41802)
		(width 0.13462)
		(layer "F.Cu")
		(net "P5E_PEX3_STN2_TX_DP<42>")
	)
	(segment
		(start 410.073602 -48.627538)
		(end 410.689806 -50.426366)
		(width 0.1651)
		(layer "In11.Cu")
		(net "P5E_PEX3_STN2_TX_DP<42>")
	)
	(segment
		(start 394.139674 -115.996212)
		(end 394.400532 -141.878558)
		(width 0.1651)
		(layer "In11.Cu")
		(net "P5E_PEX3_STN2_TX_DP<42>")
	)
	(segment
		(start 397.38554 -280.319988)
		(end 397.49984 -280.434288)
		(width 0.1143)
		(layer "In11.Cu")
		(net "P5E_PEX3_STN2_TX_DP<42>")
	)
	(segment
		(start 395.09065 -32.423354)
		(end 396.724124 -32.423354)
		(width 0.1651)
		(layer "In11.Cu")
		(net "P5E_PEX3_STN2_TX_DP<42>")
	)
	(segment
		(start 394.400532 -141.878558)
		(end 393.039346 -161.954718)
		(width 0.1651)
		(layer "In11.Cu")
		(net "P5E_PEX3_STN2_TX_DP<42>")
	)
	(segment
		(start 411.323028 -60.449968)
		(end 409.83789 -68.584318)
		(width 0.1651)
		(layer "In11.Cu")
		(net "P5E_PEX3_STN2_TX_DP<42>")
	)
	(segment
		(start 397.210788 -32.568896)
		(end 397.846296 -33.21685)
		(width 0.1651)
		(layer "In11.Cu")
		(net "P5E_PEX3_STN2_TX_DP<42>")
	)
	(segment
		(start 396.88389 -271.399)
		(end 396.88389 -271.427448)
		(width 0.1143)
		(layer "In11.Cu")
		(net "P5E_PEX3_STN2_TX_DP<42>")
	)
	(segment
		(start 396.553182 -267.083794)
		(end 396.88389 -270.440658)
		(width 0.1651)
		(layer "In11.Cu")
		(net "P5E_PEX3_STN2_TX_DP<42>")
	)
	(segment
		(start 394.51915 -32.499554)
		(end 395.01445 -32.499554)
		(width 0.1651)
		(layer "In11.Cu")
		(net "P5E_PEX3_STN2_TX_DP<42>")
	)
	(segment
		(start 399.384266 -34.785046)
		(end 410.073602 -48.627538)
		(width 0.1651)
		(layer "In11.Cu")
		(net "P5E_PEX3_STN2_TX_DP<42>")
	)
	(segment
		(start 396.88389 -271.427448)
		(end 396.92961 -271.473168)
		(width 0.1143)
		(layer "In11.Cu")
		(net "P5E_PEX3_STN2_TX_DP<42>")
	)
	(segment
		(start 409.83789 -68.584318)
		(end 399.564098 -95.718122)
		(width 0.1651)
		(layer "In11.Cu")
		(net "P5E_PEX3_STN2_TX_DP<42>")
	)
	(segment
		(start 397.846296 -33.21685)
		(end 397.845026 -33.324546)
		(width 0.1651)
		(layer "In11.Cu")
		(net "P5E_PEX3_STN2_TX_DP<42>")
	)
	(segment
		(start 396.92961 -271.473168)
		(end 396.92961 -280.10485)
		(width 0.1143)
		(layer "In11.Cu")
		(net "P5E_PEX3_STN2_TX_DP<42>")
	)
	(segment
		(start 398.192244 -33.678368)
		(end 398.29994 -33.679384)
		(width 0.1651)
		(layer "In11.Cu")
		(net "P5E_PEX3_STN2_TX_DP<42>")
	)
	(segment
		(start 397.49984 -280.434288)
		(end 397.49984 -280.699718)
		(width 0.1143)
		(layer "In11.Cu")
		(net "P5E_PEX3_STN2_TX_DP<42>")
	)
	(segment
		(start 396.92961 -280.10485)
		(end 397.144748 -280.319988)
		(width 0.1143)
		(layer "In11.Cu")
		(net "P5E_PEX3_STN2_TX_DP<42>")
	)
	(segment
		(start 394.44295 -32.423354)
		(end 394.51915 -32.499554)
		(width 0.1651)
		(layer "In11.Cu")
		(net "P5E_PEX3_STN2_TX_DP<42>")
	)
	(segment
		(start 399.564098 -95.718122)
		(end 394.139674 -115.996212)
		(width 0.1651)
		(layer "In11.Cu")
		(net "P5E_PEX3_STN2_TX_DP<42>")
	)
	(segment
		(start 397.845026 -33.324546)
		(end 398.192244 -33.678368)
		(width 0.1651)
		(layer "In11.Cu")
		(net "P5E_PEX3_STN2_TX_DP<42>")
	)
	(segment
		(start 393.605258 -32.714184)
		(end 393.896088 -32.423354)
		(width 0.1651)
		(layer "In11.Cu")
		(net "P5E_PEX3_STN2_TX_DP<42>")
	)
	(segment
		(start 396.88389 -270.440658)
		(end 396.88389 -271.399)
		(width 0.1651)
		(layer "In11.Cu")
		(net "P5E_PEX3_STN2_TX_DP<42>")
	)
	(segment
		(start 410.689806 -50.426366)
		(end 411.323028 -60.449968)
		(width 0.1651)
		(layer "In11.Cu")
		(net "P5E_PEX3_STN2_TX_DP<42>")
	)
	(segment
		(start 397.144748 -280.319988)
		(end 397.38554 -280.319988)
		(width 0.1143)
		(layer "In11.Cu")
		(net "P5E_PEX3_STN2_TX_DP<42>")
	)
	(segment
		(start 393.039346 -161.954718)
		(end 396.553182 -267.083794)
		(width 0.1651)
		(layer "In11.Cu")
		(net "P5E_PEX3_STN2_TX_DP<42>")
	)
	(segment
		(start 396.724124 -32.423354)
		(end 397.210788 -32.568896)
		(width 0.1651)
		(layer "In11.Cu")
		(net "P5E_PEX3_STN2_TX_DP<42>")
	)
	(segment
		(start 398.29994 -33.679384)
		(end 399.384266 -34.785046)
		(width 0.1651)
		(layer "In11.Cu")
		(net "P5E_PEX3_STN2_TX_DP<42>")
	)
	(segment
		(start 393.896088 -32.423354)
		(end 394.44295 -32.423354)
		(width 0.1651)
		(layer "In11.Cu")
		(net "P5E_PEX3_STN2_TX_DP<42>")
	)
	(segment
		(start 395.01445 -32.499554)
		(end 395.09065 -32.423354)
		(width 0.1651)
		(layer "In11.Cu")
		(net "P5E_PEX3_STN2_TX_DP<42>")
	)
	(segment
		(start 83.703922 -344.539062)
		(end 84.023962 -344.219022)
		(width 0.13462)
		(layer "F.Cu")
		(net "P5E_PEX0_STN5_TX_C_DN<90>")
	)
	(segment
		(start 83.998562 -345.465146)
		(end 83.703922 -345.170506)
		(width 0.13462)
		(layer "F.Cu")
		(net "P5E_PEX0_STN5_TX_C_DN<90>")
	)
	(segment
		(start 83.703922 -345.170506)
		(end 83.703922 -344.539062)
		(width 0.13462)
		(layer "F.Cu")
		(net "P5E_PEX0_STN5_TX_C_DN<90>")
	)
	(segment
		(start 76.309982 -379.20803)
		(end 76.436982 -379.08103)
		(width 0.1651)
		(layer "In7.Cu")
		(net "P5E_PEX0_STN5_TX_C_DN<90>")
	)
	(segment
		(start 83.707732 -346.474542)
		(end 83.707732 -345.755976)
		(width 0.1651)
		(layer "In7.Cu")
		(net "P5E_PEX0_STN5_TX_C_DN<90>")
	)
	(segment
		(start 76.309982 -379.590046)
		(end 76.309982 -379.20803)
		(width 0.1651)
		(layer "In7.Cu")
		(net "P5E_PEX0_STN5_TX_C_DN<90>")
	)
	(segment
		(start 82.153252 -348.029022)
		(end 83.707732 -346.474542)
		(width 0.1651)
		(layer "In7.Cu")
		(net "P5E_PEX0_STN5_TX_C_DN<90>")
	)
	(segment
		(start 83.707732 -345.755976)
		(end 83.998562 -345.465146)
		(width 0.1651)
		(layer "In7.Cu")
		(net "P5E_PEX0_STN5_TX_C_DN<90>")
	)
	(segment
		(start 77.484224 -378.486924)
		(end 77.484224 -369.451382)
		(width 0.1651)
		(layer "In7.Cu")
		(net "P5E_PEX0_STN5_TX_C_DN<90>")
	)
	(segment
		(start 76.436982 -379.08103)
		(end 76.890118 -379.08103)
		(width 0.1651)
		(layer "In7.Cu")
		(net "P5E_PEX0_STN5_TX_C_DN<90>")
	)
	(segment
		(start 77.484224 -369.451382)
		(end 82.153252 -358.17937)
		(width 0.1651)
		(layer "In7.Cu")
		(net "P5E_PEX0_STN5_TX_C_DN<90>")
	)
	(segment
		(start 76.890118 -379.08103)
		(end 77.484224 -378.486924)
		(width 0.1651)
		(layer "In7.Cu")
		(net "P5E_PEX0_STN5_TX_C_DN<90>")
	)
	(segment
		(start 82.153252 -358.17937)
		(end 82.153252 -348.029022)
		(width 0.1651)
		(layer "In7.Cu")
		(net "P5E_PEX0_STN5_TX_C_DN<90>")
	)
	(segment
		(start 341.052404 -345.170506)
		(end 341.347044 -345.465146)
		(width 0.13462)
		(layer "F.Cu")
		(net "P5E_PEX2_STN5_TX_C_DN<93>")
	)
	(segment
		(start 341.052404 -344.539062)
		(end 341.052404 -345.170506)
		(width 0.13462)
		(layer "F.Cu")
		(net "P5E_PEX2_STN5_TX_C_DN<93>")
	)
	(segment
		(start 341.372444 -344.219022)
		(end 341.052404 -344.539062)
		(width 0.13462)
		(layer "F.Cu")
		(net "P5E_PEX2_STN5_TX_C_DN<93>")
	)
	(segment
		(start 341.056214 -345.755976)
		(end 341.347044 -345.465146)
		(width 0.1651)
		(layer "In7.Cu")
		(net "P5E_PEX2_STN5_TX_C_DN<93>")
	)
	(segment
		(start 343.16416 -380.181104)
		(end 343.616026 -379.729238)
		(width 0.1651)
		(layer "In7.Cu")
		(net "P5E_PEX2_STN5_TX_C_DN<93>")
	)
	(segment
		(start 342.490044 -380.69012)
		(end 342.490044 -380.308104)
		(width 0.1651)
		(layer "In7.Cu")
		(net "P5E_PEX2_STN5_TX_C_DN<93>")
	)
	(segment
		(start 343.616026 -379.729238)
		(end 343.616026 -368.882422)
		(width 0.1651)
		(layer "In7.Cu")
		(net "P5E_PEX2_STN5_TX_C_DN<93>")
	)
	(segment
		(start 339.501734 -347.881194)
		(end 341.056214 -346.326714)
		(width 0.1651)
		(layer "In7.Cu")
		(net "P5E_PEX2_STN5_TX_C_DN<93>")
	)
	(segment
		(start 341.056214 -346.326714)
		(end 341.056214 -345.755976)
		(width 0.1651)
		(layer "In7.Cu")
		(net "P5E_PEX2_STN5_TX_C_DN<93>")
	)
	(segment
		(start 339.501734 -358.948736)
		(end 339.501734 -347.881194)
		(width 0.1651)
		(layer "In7.Cu")
		(net "P5E_PEX2_STN5_TX_C_DN<93>")
	)
	(segment
		(start 342.490044 -380.308104)
		(end 342.617044 -380.181104)
		(width 0.1651)
		(layer "In7.Cu")
		(net "P5E_PEX2_STN5_TX_C_DN<93>")
	)
	(segment
		(start 343.616026 -368.882422)
		(end 339.501734 -358.948736)
		(width 0.1651)
		(layer "In7.Cu")
		(net "P5E_PEX2_STN5_TX_C_DN<93>")
	)
	(segment
		(start 342.617044 -380.181104)
		(end 343.16416 -380.181104)
		(width 0.1651)
		(layer "In7.Cu")
		(net "P5E_PEX2_STN5_TX_C_DN<93>")
	)
	(segment
		(start 68.159122 -355.026722)
		(end 68.453762 -354.732082)
		(width 0.13462)
		(layer "F.Cu")
		(net "P5E_PEX0_STN6_TX_DN<108>")
	)
	(segment
		(start 68.479162 -355.978206)
		(end 68.159122 -355.658166)
		(width 0.13462)
		(layer "F.Cu")
		(net "P5E_PEX0_STN6_TX_DN<108>")
	)
	(segment
		(start 68.159122 -355.658166)
		(end 68.159122 -355.026722)
		(width 0.13462)
		(layer "F.Cu")
		(net "P5E_PEX0_STN6_TX_DN<108>")
	)
	(segment
		(start 69.717412 -340.842092)
		(end 52.212748 -331.48524)
		(width 0.1651)
		(layer "In13.Cu")
		(net "P5E_PEX0_STN6_TX_DN<108>")
	)
	(segment
		(start 68.453762 -354.732082)
		(end 68.162932 -354.441252)
		(width 0.1651)
		(layer "In13.Cu")
		(net "P5E_PEX0_STN6_TX_DN<108>")
	)
	(segment
		(start 68.162932 -354.441252)
		(end 68.162932 -353.752404)
		(width 0.1651)
		(layer "In13.Cu")
		(net "P5E_PEX0_STN6_TX_DN<108>")
	)
	(segment
		(start 47.489872 -327.554336)
		(end 46.01591 -323.995796)
		(width 0.1651)
		(layer "In13.Cu")
		(net "P5E_PEX0_STN6_TX_DN<108>")
	)
	(segment
		(start 45.97019 -320.135504)
		(end 45.97019 -313.697112)
		(width 0.1143)
		(layer "In13.Cu")
		(net "P5E_PEX0_STN6_TX_DN<108>")
	)
	(segment
		(start 46.34992 -313.659012)
		(end 46.34992 -313.949842)
		(width 0.1143)
		(layer "In13.Cu")
		(net "P5E_PEX0_STN6_TX_DN<108>")
	)
	(segment
		(start 52.212748 -331.48524)
		(end 50.860706 -330.92517)
		(width 0.1651)
		(layer "In13.Cu")
		(net "P5E_PEX0_STN6_TX_DN<108>")
	)
	(segment
		(start 46.01591 -320.181224)
		(end 45.97019 -320.135504)
		(width 0.1143)
		(layer "In13.Cu")
		(net "P5E_PEX0_STN6_TX_DN<108>")
	)
	(segment
		(start 69.717412 -352.197924)
		(end 69.717412 -340.842092)
		(width 0.1651)
		(layer "In13.Cu")
		(net "P5E_PEX0_STN6_TX_DN<108>")
	)
	(segment
		(start 46.26102 -313.570112)
		(end 46.34992 -313.659012)
		(width 0.1143)
		(layer "In13.Cu")
		(net "P5E_PEX0_STN6_TX_DN<108>")
	)
	(segment
		(start 46.01591 -320.203322)
		(end 46.01591 -320.181224)
		(width 0.1143)
		(layer "In13.Cu")
		(net "P5E_PEX0_STN6_TX_DN<108>")
	)
	(segment
		(start 68.162932 -353.752404)
		(end 69.717412 -352.197924)
		(width 0.1651)
		(layer "In13.Cu")
		(net "P5E_PEX0_STN6_TX_DN<108>")
	)
	(segment
		(start 46.01591 -323.995796)
		(end 46.01591 -320.203322)
		(width 0.1651)
		(layer "In13.Cu")
		(net "P5E_PEX0_STN6_TX_DN<108>")
	)
	(segment
		(start 46.09719 -313.570112)
		(end 46.26102 -313.570112)
		(width 0.1143)
		(layer "In13.Cu")
		(net "P5E_PEX0_STN6_TX_DN<108>")
	)
	(segment
		(start 50.860706 -330.92517)
		(end 47.489872 -327.554336)
		(width 0.1651)
		(layer "In13.Cu")
		(net "P5E_PEX0_STN6_TX_DN<108>")
	)
	(segment
		(start 45.97019 -313.697112)
		(end 46.09719 -313.570112)
		(width 0.1143)
		(layer "In13.Cu")
		(net "P5E_PEX0_STN6_TX_DN<108>")
	)
	(segment
		(start 70.993762 -343.365582)
		(end 70.993762 -342.734138)
		(width 0.13462)
		(layer "F.Cu")
		(net "P5E_PEX0_STN5_TX_DP<84>")
	)
	(segment
		(start 70.673722 -343.685622)
		(end 70.993762 -343.365582)
		(width 0.13462)
		(layer "F.Cu")
		(net "P5E_PEX0_STN5_TX_DP<84>")
	)
	(segment
		(start 70.993762 -342.734138)
		(end 70.699122 -342.439498)
		(width 0.13462)
		(layer "F.Cu")
		(net "P5E_PEX0_STN5_TX_DP<84>")
	)
	(segment
		(start 70.989952 -342.148668)
		(end 70.989952 -340.088728)
		(width 0.1651)
		(layer "In7.Cu")
		(net "P5E_PEX0_STN5_TX_DP<84>")
	)
	(segment
		(start 70.699122 -342.439498)
		(end 70.989952 -342.148668)
		(width 0.1651)
		(layer "In7.Cu")
		(net "P5E_PEX0_STN5_TX_DP<84>")
	)
	(segment
		(start 62.439042 -324.923404)
		(end 61.883798 -323.582792)
		(width 0.1651)
		(layer "In7.Cu")
		(net "P5E_PEX0_STN5_TX_DP<84>")
	)
	(segment
		(start 61.929518 -319.84188)
		(end 61.929518 -311.705498)
		(width 0.1143)
		(layer "In7.Cu")
		(net "P5E_PEX0_STN5_TX_DP<84>")
	)
	(segment
		(start 61.883798 -319.8876)
		(end 61.929518 -319.84188)
		(width 0.1143)
		(layer "In7.Cu")
		(net "P5E_PEX0_STN5_TX_DP<84>")
	)
	(segment
		(start 65.289938 -330.25715)
		(end 62.439042 -324.923404)
		(width 0.1651)
		(layer "In7.Cu")
		(net "P5E_PEX0_STN5_TX_DP<84>")
	)
	(segment
		(start 61.883798 -319.916048)
		(end 61.883798 -319.8876)
		(width 0.1143)
		(layer "In7.Cu")
		(net "P5E_PEX0_STN5_TX_DP<84>")
	)
	(segment
		(start 61.929518 -311.705498)
		(end 62.155324 -311.479692)
		(width 0.1143)
		(layer "In7.Cu")
		(net "P5E_PEX0_STN5_TX_DP<84>")
	)
	(segment
		(start 62.499748 -311.365392)
		(end 62.499748 -311.099962)
		(width 0.1143)
		(layer "In7.Cu")
		(net "P5E_PEX0_STN5_TX_DP<84>")
	)
	(segment
		(start 61.883798 -323.582792)
		(end 61.883798 -319.916048)
		(width 0.1651)
		(layer "In7.Cu")
		(net "P5E_PEX0_STN5_TX_DP<84>")
	)
	(segment
		(start 62.155324 -311.479692)
		(end 62.385448 -311.479692)
		(width 0.1143)
		(layer "In7.Cu")
		(net "P5E_PEX0_STN5_TX_DP<84>")
	)
	(segment
		(start 62.385448 -311.479692)
		(end 62.499748 -311.365392)
		(width 0.1143)
		(layer "In7.Cu")
		(net "P5E_PEX0_STN5_TX_DP<84>")
	)
	(segment
		(start 67.512946 -333.584296)
		(end 65.289938 -330.25715)
		(width 0.1651)
		(layer "In7.Cu")
		(net "P5E_PEX0_STN5_TX_DP<84>")
	)
	(segment
		(start 70.989952 -340.088728)
		(end 67.512946 -333.584296)
		(width 0.1651)
		(layer "In7.Cu")
		(net "P5E_PEX0_STN5_TX_DP<84>")
	)
	(segment
		(start 250.569984 -32.13608)
		(end 250.259088 -31.825184)
		(width 0.13462)
		(layer "F.Cu")
		(net "P5E_PEX2_STN2_TX_DN<46>")
	)
	(segment
		(start 251.219716 -32.13608)
		(end 250.569984 -32.13608)
		(width 0.13462)
		(layer "F.Cu")
		(net "P5E_PEX2_STN2_TX_DN<46>")
	)
	(segment
		(start 251.505212 -31.850584)
		(end 251.219716 -32.13608)
		(width 0.13462)
		(layer "F.Cu")
		(net "P5E_PEX2_STN2_TX_DN<46>")
	)
	(segment
		(start 268.757908 -78.771496)
		(end 265.17981 -104.96423)
		(width 0.1651)
		(layer "In11.Cu")
		(net "P5E_PEX2_STN2_TX_DN<46>")
	)
	(segment
		(start 256.596896 -33.387538)
		(end 266.993116 -46.401736)
		(width 0.1651)
		(layer "In11.Cu")
		(net "P5E_PEX2_STN2_TX_DN<46>")
	)
	(segment
		(start 277.265892 -271.399)
		(end 277.265892 -271.427448)
		(width 0.1143)
		(layer "In11.Cu")
		(net "P5E_PEX2_STN2_TX_DN<46>")
	)
	(segment
		(start 268.898878 -50.44821)
		(end 269.644114 -62.96533)
		(width 0.1651)
		(layer "In11.Cu")
		(net "P5E_PEX2_STN2_TX_DN<46>")
	)
	(segment
		(start 276.258274 -264.52195)
		(end 277.265892 -270.196056)
		(width 0.1651)
		(layer "In11.Cu")
		(net "P5E_PEX2_STN2_TX_DN<46>")
	)
	(segment
		(start 277.265892 -271.427448)
		(end 277.220172 -271.473168)
		(width 0.1143)
		(layer "In11.Cu")
		(net "P5E_PEX2_STN2_TX_DN<46>")
	)
	(segment
		(start 277.265892 -270.196056)
		(end 277.265892 -271.399)
		(width 0.1651)
		(layer "In11.Cu")
		(net "P5E_PEX2_STN2_TX_DN<46>")
	)
	(segment
		(start 277.599902 -280.015188)
		(end 277.599902 -279.749504)
		(width 0.1143)
		(layer "In11.Cu")
		(net "P5E_PEX2_STN2_TX_DN<46>")
	)
	(segment
		(start 265.040364 -138.163046)
		(end 276.258274 -264.52195)
		(width 0.1651)
		(layer "In11.Cu")
		(net "P5E_PEX2_STN2_TX_DN<46>")
	)
	(segment
		(start 269.644114 -62.96533)
		(end 268.757908 -78.771496)
		(width 0.1651)
		(layer "In11.Cu")
		(net "P5E_PEX2_STN2_TX_DN<46>")
	)
	(segment
		(start 264.57783 -116.822728)
		(end 265.040364 -138.163046)
		(width 0.1651)
		(layer "In11.Cu")
		(net "P5E_PEX2_STN2_TX_DN<46>")
	)
	(segment
		(start 251.505212 -31.850584)
		(end 251.796042 -32.141414)
		(width 0.1651)
		(layer "In11.Cu")
		(net "P5E_PEX2_STN2_TX_DN<46>")
	)
	(segment
		(start 253.585218 -32.141414)
		(end 256.596896 -33.387538)
		(width 0.1651)
		(layer "In11.Cu")
		(net "P5E_PEX2_STN2_TX_DN<46>")
	)
	(segment
		(start 266.993116 -46.401736)
		(end 268.325346 -48.810164)
		(width 0.1651)
		(layer "In11.Cu")
		(net "P5E_PEX2_STN2_TX_DN<46>")
	)
	(segment
		(start 277.485602 -280.129488)
		(end 277.599902 -280.015188)
		(width 0.1143)
		(layer "In11.Cu")
		(net "P5E_PEX2_STN2_TX_DN<46>")
	)
	(segment
		(start 277.220172 -271.473168)
		(end 277.220172 -280.025856)
		(width 0.1143)
		(layer "In11.Cu")
		(net "P5E_PEX2_STN2_TX_DN<46>")
	)
	(segment
		(start 277.220172 -280.025856)
		(end 277.323804 -280.129488)
		(width 0.1143)
		(layer "In11.Cu")
		(net "P5E_PEX2_STN2_TX_DN<46>")
	)
	(segment
		(start 277.323804 -280.129488)
		(end 277.485602 -280.129488)
		(width 0.1143)
		(layer "In11.Cu")
		(net "P5E_PEX2_STN2_TX_DN<46>")
	)
	(segment
		(start 251.796042 -32.141414)
		(end 253.585218 -32.141414)
		(width 0.1651)
		(layer "In11.Cu")
		(net "P5E_PEX2_STN2_TX_DN<46>")
	)
	(segment
		(start 265.17981 -104.96423)
		(end 264.57783 -116.822728)
		(width 0.1651)
		(layer "In11.Cu")
		(net "P5E_PEX2_STN2_TX_DN<46>")
	)
	(segment
		(start 268.325346 -48.810164)
		(end 268.898878 -50.44821)
		(width 0.1651)
		(layer "In11.Cu")
		(net "P5E_PEX2_STN2_TX_DN<46>")
	)
	(segment
		(start 445.605154 -32.714184)
		(end 445.30899 -32.41802)
		(width 0.13462)
		(layer "F.Cu")
		(net "P5E_PEX3_STN2_TX_DP<34>")
	)
	(segment
		(start 444.680594 -32.41802)
		(end 444.35903 -32.739584)
		(width 0.13462)
		(layer "F.Cu")
		(net "P5E_PEX3_STN2_TX_DP<34>")
	)
	(segment
		(start 445.30899 -32.41802)
		(end 444.680594 -32.41802)
		(width 0.13462)
		(layer "F.Cu")
		(net "P5E_PEX3_STN2_TX_DP<34>")
	)
	(segment
		(start 447.407792 -32.423354)
		(end 445.895984 -32.423354)
		(width 0.1651)
		(layer "In11.Cu")
		(net "P5E_PEX3_STN2_TX_DP<34>")
	)
	(segment
		(start 448.131692 -32.423354)
		(end 448.017392 -32.537654)
		(width 0.1651)
		(layer "In11.Cu")
		(net "P5E_PEX3_STN2_TX_DP<34>")
	)
	(segment
		(start 442.037724 -80.550258)
		(end 444.043562 -78.546452)
		(width 0.1651)
		(layer "In11.Cu")
		(net "P5E_PEX3_STN2_TX_DP<34>")
	)
	(segment
		(start 451.065138 -74.293984)
		(end 453.270366 -68.191126)
		(width 0.1651)
		(layer "In11.Cu")
		(net "P5E_PEX3_STN2_TX_DP<34>")
	)
	(segment
		(start 453.270366 -68.191126)
		(end 455.478134 -56.729376)
		(width 0.1651)
		(layer "In11.Cu")
		(net "P5E_PEX3_STN2_TX_DP<34>")
	)
	(segment
		(start 448.017392 -32.537654)
		(end 447.522092 -32.537654)
		(width 0.1651)
		(layer "In11.Cu")
		(net "P5E_PEX3_STN2_TX_DP<34>")
	)
	(segment
		(start 455.016616 -41.890696)
		(end 450.743574 -34.038286)
		(width 0.1651)
		(layer "In11.Cu")
		(net "P5E_PEX3_STN2_TX_DP<34>")
	)
	(segment
		(start 404.744682 -280.319988)
		(end 404.529544 -280.10485)
		(width 0.1143)
		(layer "In11.Cu")
		(net "P5E_PEX3_STN2_TX_DP<34>")
	)
	(segment
		(start 455.227944 -42.691304)
		(end 455.016616 -41.890696)
		(width 0.1651)
		(layer "In11.Cu")
		(net "P5E_PEX3_STN2_TX_DP<34>")
	)
	(segment
		(start 404.483824 -271.427448)
		(end 404.483824 -271.399)
		(width 0.1143)
		(layer "In11.Cu")
		(net "P5E_PEX3_STN2_TX_DP<34>")
	)
	(segment
		(start 404.483824 -265.641074)
		(end 423.653204 -161.396426)
		(width 0.1651)
		(layer "In11.Cu")
		(net "P5E_PEX3_STN2_TX_DP<34>")
	)
	(segment
		(start 450.534786 -75.047094)
		(end 451.065138 -74.293984)
		(width 0.1651)
		(layer "In11.Cu")
		(net "P5E_PEX3_STN2_TX_DP<34>")
	)
	(segment
		(start 425.398946 -141.845284)
		(end 425.805854 -140.100304)
		(width 0.1651)
		(layer "In11.Cu")
		(net "P5E_PEX3_STN2_TX_DP<34>")
	)
	(segment
		(start 449.145406 -32.423354)
		(end 448.131692 -32.423354)
		(width 0.1651)
		(layer "In11.Cu")
		(net "P5E_PEX3_STN2_TX_DP<34>")
	)
	(segment
		(start 425.07027 -149.389084)
		(end 425.398946 -141.845284)
		(width 0.1651)
		(layer "In11.Cu")
		(net "P5E_PEX3_STN2_TX_DP<34>")
	)
	(segment
		(start 425.805854 -140.100304)
		(end 425.805854 -132.507228)
		(width 0.1651)
		(layer "In11.Cu")
		(net "P5E_PEX3_STN2_TX_DP<34>")
	)
	(segment
		(start 444.043562 -78.546452)
		(end 450.534786 -75.047094)
		(width 0.1651)
		(layer "In11.Cu")
		(net "P5E_PEX3_STN2_TX_DP<34>")
	)
	(segment
		(start 405.099774 -280.434288)
		(end 404.985474 -280.319988)
		(width 0.1143)
		(layer "In11.Cu")
		(net "P5E_PEX3_STN2_TX_DP<34>")
	)
	(segment
		(start 447.522092 -32.537654)
		(end 447.407792 -32.423354)
		(width 0.1651)
		(layer "In11.Cu")
		(net "P5E_PEX3_STN2_TX_DP<34>")
	)
	(segment
		(start 428.043848 -105.211118)
		(end 435.04485 -92.873068)
		(width 0.1651)
		(layer "In11.Cu")
		(net "P5E_PEX3_STN2_TX_DP<34>")
	)
	(segment
		(start 427.229778 -111.806228)
		(end 427.230032 -111.806228)
		(width 0.1651)
		(layer "In11.Cu")
		(net "P5E_PEX3_STN2_TX_DP<34>")
	)
	(segment
		(start 455.478134 -56.729376)
		(end 455.227944 -42.691304)
		(width 0.1651)
		(layer "In11.Cu")
		(net "P5E_PEX3_STN2_TX_DP<34>")
	)
	(segment
		(start 427.230032 -111.806228)
		(end 428.043848 -105.211118)
		(width 0.1651)
		(layer "In11.Cu")
		(net "P5E_PEX3_STN2_TX_DP<34>")
	)
	(segment
		(start 435.04485 -92.873068)
		(end 435.045104 -92.873068)
		(width 0.1651)
		(layer "In11.Cu")
		(net "P5E_PEX3_STN2_TX_DP<34>")
	)
	(segment
		(start 445.895984 -32.423354)
		(end 445.605154 -32.714184)
		(width 0.1651)
		(layer "In11.Cu")
		(net "P5E_PEX3_STN2_TX_DP<34>")
	)
	(segment
		(start 423.653204 -161.396426)
		(end 425.07027 -149.389084)
		(width 0.1651)
		(layer "In11.Cu")
		(net "P5E_PEX3_STN2_TX_DP<34>")
	)
	(segment
		(start 450.743574 -34.038286)
		(end 449.145406 -32.423354)
		(width 0.1651)
		(layer "In11.Cu")
		(net "P5E_PEX3_STN2_TX_DP<34>")
	)
	(segment
		(start 404.529544 -271.473168)
		(end 404.483824 -271.427448)
		(width 0.1143)
		(layer "In11.Cu")
		(net "P5E_PEX3_STN2_TX_DP<34>")
	)
	(segment
		(start 426.421804 -118.35638)
		(end 427.229778 -111.806228)
		(width 0.1651)
		(layer "In11.Cu")
		(net "P5E_PEX3_STN2_TX_DP<34>")
	)
	(segment
		(start 435.045104 -92.873068)
		(end 442.037724 -80.550258)
		(width 0.1651)
		(layer "In11.Cu")
		(net "P5E_PEX3_STN2_TX_DP<34>")
	)
	(segment
		(start 404.529544 -280.10485)
		(end 404.529544 -271.473168)
		(width 0.1143)
		(layer "In11.Cu")
		(net "P5E_PEX3_STN2_TX_DP<34>")
	)
	(segment
		(start 404.985474 -280.319988)
		(end 404.744682 -280.319988)
		(width 0.1143)
		(layer "In11.Cu")
		(net "P5E_PEX3_STN2_TX_DP<34>")
	)
	(segment
		(start 405.099774 -280.699718)
		(end 405.099774 -280.434288)
		(width 0.1143)
		(layer "In11.Cu")
		(net "P5E_PEX3_STN2_TX_DP<34>")
	)
	(segment
		(start 425.805854 -132.507228)
		(end 426.421804 -118.35638)
		(width 0.1651)
		(layer "In11.Cu")
		(net "P5E_PEX3_STN2_TX_DP<34>")
	)
	(segment
		(start 404.483824 -271.399)
		(end 404.483824 -265.641074)
		(width 0.1651)
		(layer "In11.Cu")
		(net "P5E_PEX3_STN2_TX_DP<34>")
	)
	(segment
		(start 38.555168 -350.685354)
		(end 38.875208 -350.365314)
		(width 0.13462)
		(layer "F.Cu")
		(net "P5E_PEX0_STN7_TX_C_DP<121>")
	)
	(segment
		(start 38.849808 -351.611438)
		(end 38.555168 -351.316798)
		(width 0.13462)
		(layer "F.Cu")
		(net "P5E_PEX0_STN7_TX_C_DP<121>")
	)
	(segment
		(start 38.555168 -351.316798)
		(end 38.555168 -350.685354)
		(width 0.13462)
		(layer "F.Cu")
		(net "P5E_PEX0_STN7_TX_C_DP<121>")
	)
	(segment
		(start 37.004498 -358.436926)
		(end 37.004498 -354.107242)
		(width 0.1651)
		(layer "In7.Cu")
		(net "P5E_PEX0_STN7_TX_C_DP<121>")
	)
	(segment
		(start 38.558978 -352.552762)
		(end 38.558978 -351.902268)
		(width 0.1651)
		(layer "In7.Cu")
		(net "P5E_PEX0_STN7_TX_C_DP<121>")
	)
	(segment
		(start 30.109922 -376.408188)
		(end 30.236922 -376.281188)
		(width 0.1651)
		(layer "In7.Cu")
		(net "P5E_PEX0_STN7_TX_C_DP<121>")
	)
	(segment
		(start 38.558978 -351.902268)
		(end 38.849808 -351.611438)
		(width 0.1651)
		(layer "In7.Cu")
		(net "P5E_PEX0_STN7_TX_C_DP<121>")
	)
	(segment
		(start 30.109922 -376.790204)
		(end 30.109922 -376.408188)
		(width 0.1651)
		(layer "In7.Cu")
		(net "P5E_PEX0_STN7_TX_C_DP<121>")
	)
	(segment
		(start 30.969458 -376.281188)
		(end 31.284418 -375.966228)
		(width 0.1651)
		(layer "In7.Cu")
		(net "P5E_PEX0_STN7_TX_C_DP<121>")
	)
	(segment
		(start 31.284418 -369.692174)
		(end 31.855156 -367.52657)
		(width 0.1651)
		(layer "In7.Cu")
		(net "P5E_PEX0_STN7_TX_C_DP<121>")
	)
	(segment
		(start 30.236922 -376.281188)
		(end 30.969458 -376.281188)
		(width 0.1651)
		(layer "In7.Cu")
		(net "P5E_PEX0_STN7_TX_C_DP<121>")
	)
	(segment
		(start 37.004498 -354.107242)
		(end 38.558978 -352.552762)
		(width 0.1651)
		(layer "In7.Cu")
		(net "P5E_PEX0_STN7_TX_C_DP<121>")
	)
	(segment
		(start 31.284418 -375.966228)
		(end 31.284418 -369.692174)
		(width 0.1651)
		(layer "In7.Cu")
		(net "P5E_PEX0_STN7_TX_C_DP<121>")
	)
	(segment
		(start 31.855156 -367.52657)
		(end 37.004498 -358.436926)
		(width 0.1651)
		(layer "In7.Cu")
		(net "P5E_PEX0_STN7_TX_C_DP<121>")
	)
	(segment
		(start 47.653956 -30.62732)
		(end 47.019972 -30.62732)
		(width 0.13462)
		(layer "F.Cu")
		(net "P5E_PEX0_STN2_TX_DP<41>")
	)
	(segment
		(start 47.947326 -30.92069)
		(end 47.653956 -30.62732)
		(width 0.13462)
		(layer "F.Cu")
		(net "P5E_PEX0_STN2_TX_DP<41>")
	)
	(segment
		(start 47.019972 -30.62732)
		(end 46.701202 -30.94609)
		(width 0.13462)
		(layer "F.Cu")
		(net "P5E_PEX0_STN2_TX_DP<41>")
	)
	(segment
		(start 48.81753 -252.658372)
		(end 49.169828 -266.144502)
		(width 0.1651)
		(layer "In11.Cu")
		(net "P5E_PEX0_STN2_TX_DP<41>")
	)
	(segment
		(start 50.14976 -278.534368)
		(end 50.14976 -278.799798)
		(width 0.1143)
		(layer "In11.Cu")
		(net "P5E_PEX0_STN2_TX_DP<41>")
	)
	(segment
		(start 50.137822 -32.057086)
		(end 50.489866 -32.406082)
		(width 0.1651)
		(layer "In11.Cu")
		(net "P5E_PEX0_STN2_TX_DP<41>")
	)
	(segment
		(start 50.489866 -32.406082)
		(end 50.615596 -32.405574)
		(width 0.1651)
		(layer "In11.Cu")
		(net "P5E_PEX0_STN2_TX_DP<41>")
	)
	(segment
		(start 63.338964 -50.122074)
		(end 63.989712 -60.55106)
		(width 0.1651)
		(layer "In11.Cu")
		(net "P5E_PEX0_STN2_TX_DP<41>")
	)
	(segment
		(start 49.53381 -271.399)
		(end 49.53381 -271.427448)
		(width 0.1143)
		(layer "In11.Cu")
		(net "P5E_PEX0_STN2_TX_DP<41>")
	)
	(segment
		(start 56.441594 -120.219724)
		(end 55.19039 -135.143494)
		(width 0.1651)
		(layer "In11.Cu")
		(net "P5E_PEX0_STN2_TX_DP<41>")
	)
	(segment
		(start 49.57953 -278.20493)
		(end 49.794668 -278.420068)
		(width 0.1143)
		(layer "In11.Cu")
		(net "P5E_PEX0_STN2_TX_DP<41>")
	)
	(segment
		(start 48.960532 -30.764734)
		(end 49.307242 -31.10865)
		(width 0.1651)
		(layer "In11.Cu")
		(net "P5E_PEX0_STN2_TX_DP<41>")
	)
	(segment
		(start 56.467756 -119.906288)
		(end 56.441594 -120.218454)
		(width 0.1651)
		(layer "In11.Cu")
		(net "P5E_PEX0_STN2_TX_DP<41>")
	)
	(segment
		(start 56.441594 -120.218454)
		(end 56.441594 -120.219724)
		(width 0.1651)
		(layer "In11.Cu")
		(net "P5E_PEX0_STN2_TX_DP<41>")
	)
	(segment
		(start 50.615596 -32.405574)
		(end 51.465988 -33.2486)
		(width 0.1651)
		(layer "In11.Cu")
		(net "P5E_PEX0_STN2_TX_DP<41>")
	)
	(segment
		(start 49.660048 -31.583376)
		(end 49.785778 -31.582868)
		(width 0.1651)
		(layer "In11.Cu")
		(net "P5E_PEX0_STN2_TX_DP<41>")
	)
	(segment
		(start 49.794668 -278.420068)
		(end 50.03546 -278.420068)
		(width 0.1143)
		(layer "In11.Cu")
		(net "P5E_PEX0_STN2_TX_DP<41>")
	)
	(segment
		(start 49.30775 -31.10865)
		(end 49.308258 -31.23438)
		(width 0.1651)
		(layer "In11.Cu")
		(net "P5E_PEX0_STN2_TX_DP<41>")
	)
	(segment
		(start 56.520588 -119.281194)
		(end 56.494172 -119.593868)
		(width 0.1651)
		(layer "In11.Cu")
		(net "P5E_PEX0_STN2_TX_DP<41>")
	)
	(segment
		(start 49.53381 -269.841726)
		(end 49.53381 -271.399)
		(width 0.1651)
		(layer "In11.Cu")
		(net "P5E_PEX0_STN2_TX_DP<41>")
	)
	(segment
		(start 56.46801 -119.906288)
		(end 56.467756 -119.906288)
		(width 0.1651)
		(layer "In11.Cu")
		(net "P5E_PEX0_STN2_TX_DP<41>")
	)
	(segment
		(start 50.137314 -31.931356)
		(end 50.137822 -32.057086)
		(width 0.1651)
		(layer "In11.Cu")
		(net "P5E_PEX0_STN2_TX_DP<41>")
	)
	(segment
		(start 49.53381 -271.427448)
		(end 49.57953 -271.473168)
		(width 0.1143)
		(layer "In11.Cu")
		(net "P5E_PEX0_STN2_TX_DP<41>")
	)
	(segment
		(start 49.169828 -266.144502)
		(end 49.53381 -269.841726)
		(width 0.1651)
		(layer "In11.Cu")
		(net "P5E_PEX0_STN2_TX_DP<41>")
	)
	(segment
		(start 56.494172 -119.593868)
		(end 56.46801 -119.906288)
		(width 0.1651)
		(layer "In11.Cu")
		(net "P5E_PEX0_STN2_TX_DP<41>")
	)
	(segment
		(start 52.794662 -35.429444)
		(end 62.671706 -48.194976)
		(width 0.1651)
		(layer "In11.Cu")
		(net "P5E_PEX0_STN2_TX_DP<41>")
	)
	(segment
		(start 50.03546 -278.420068)
		(end 50.14976 -278.534368)
		(width 0.1143)
		(layer "In11.Cu")
		(net "P5E_PEX0_STN2_TX_DP<41>")
	)
	(segment
		(start 51.465988 -33.2486)
		(end 52.794662 -35.429444)
		(width 0.1651)
		(layer "In11.Cu")
		(net "P5E_PEX0_STN2_TX_DP<41>")
	)
	(segment
		(start 49.785778 -31.582868)
		(end 50.137314 -31.931356)
		(width 0.1651)
		(layer "In11.Cu")
		(net "P5E_PEX0_STN2_TX_DP<41>")
	)
	(segment
		(start 48.238156 -30.62986)
		(end 48.632872 -30.62986)
		(width 0.1651)
		(layer "In11.Cu")
		(net "P5E_PEX0_STN2_TX_DP<41>")
	)
	(segment
		(start 63.478156 -69.600318)
		(end 56.520588 -119.281194)
		(width 0.1651)
		(layer "In11.Cu")
		(net "P5E_PEX0_STN2_TX_DP<41>")
	)
	(segment
		(start 47.947326 -30.92069)
		(end 48.238156 -30.62986)
		(width 0.1651)
		(layer "In11.Cu")
		(net "P5E_PEX0_STN2_TX_DP<41>")
	)
	(segment
		(start 48.632872 -30.62986)
		(end 48.960532 -30.764734)
		(width 0.1651)
		(layer "In11.Cu")
		(net "P5E_PEX0_STN2_TX_DP<41>")
	)
	(segment
		(start 62.671706 -48.194976)
		(end 63.338964 -50.122074)
		(width 0.1651)
		(layer "In11.Cu")
		(net "P5E_PEX0_STN2_TX_DP<41>")
	)
	(segment
		(start 49.308258 -31.23438)
		(end 49.660048 -31.583376)
		(width 0.1651)
		(layer "In11.Cu")
		(net "P5E_PEX0_STN2_TX_DP<41>")
	)
	(segment
		(start 63.989712 -60.55106)
		(end 63.478156 -69.600318)
		(width 0.1651)
		(layer "In11.Cu")
		(net "P5E_PEX0_STN2_TX_DP<41>")
	)
	(segment
		(start 49.57953 -271.473168)
		(end 49.57953 -278.20493)
		(width 0.1143)
		(layer "In11.Cu")
		(net "P5E_PEX0_STN2_TX_DP<41>")
	)
	(segment
		(start 49.307242 -31.10865)
		(end 49.30775 -31.10865)
		(width 0.1651)
		(layer "In11.Cu")
		(net "P5E_PEX0_STN2_TX_DP<41>")
	)
	(segment
		(start 55.19039 -135.143494)
		(end 48.81753 -252.658372)
		(width 0.1651)
		(layer "In11.Cu")
		(net "P5E_PEX0_STN2_TX_DP<41>")
	)
	(segment
		(start 253.222506 -30.353)
		(end 252.901196 -30.03169)
		(width 0.13462)
		(layer "F.Cu")
		(net "P5E_PEX2_STN2_TX_DN<45>")
	)
	(segment
		(start 253.85141 -30.353)
		(end 253.222506 -30.353)
		(width 0.13462)
		(layer "F.Cu")
		(net "P5E_PEX2_STN2_TX_DN<45>")
	)
	(segment
		(start 254.14732 -30.05709)
		(end 253.85141 -30.353)
		(width 0.13462)
		(layer "F.Cu")
		(net "P5E_PEX2_STN2_TX_DN<45>")
	)
	(segment
		(start 269.22476 -48.4632)
		(end 269.863062 -50.312828)
		(width 0.1651)
		(layer "In11.Cu")
		(net "P5E_PEX2_STN2_TX_DN<45>")
	)
	(segment
		(start 266.123674 -105.234486)
		(end 265.620754 -116.209572)
		(width 0.1651)
		(layer "In11.Cu")
		(net "P5E_PEX2_STN2_TX_DN<45>")
	)
	(segment
		(start 265.620754 -116.209572)
		(end 266.022836 -137.972292)
		(width 0.1651)
		(layer "In11.Cu")
		(net "P5E_PEX2_STN2_TX_DN<45>")
	)
	(segment
		(start 254.501904 -30.34792)
		(end 254.88773 -30.34792)
		(width 0.1651)
		(layer "In11.Cu")
		(net "P5E_PEX2_STN2_TX_DN<45>")
	)
	(segment
		(start 254.14732 -30.05709)
		(end 254.392938 -30.302708)
		(width 0.1651)
		(layer "In11.Cu")
		(net "P5E_PEX2_STN2_TX_DN<45>")
	)
	(segment
		(start 278.170132 -271.473168)
		(end 278.170132 -278.125936)
		(width 0.1143)
		(layer "In11.Cu")
		(net "P5E_PEX2_STN2_TX_DN<45>")
	)
	(segment
		(start 266.022836 -137.972292)
		(end 277.187152 -264.159746)
		(width 0.1651)
		(layer "In11.Cu")
		(net "P5E_PEX2_STN2_TX_DN<45>")
	)
	(segment
		(start 254.88773 -30.34792)
		(end 255.46812 -30.58795)
		(width 0.1651)
		(layer "In11.Cu")
		(net "P5E_PEX2_STN2_TX_DN<45>")
	)
	(segment
		(start 256.703322 -31.646114)
		(end 267.276072 -44.917868)
		(width 0.1651)
		(layer "In11.Cu")
		(net "P5E_PEX2_STN2_TX_DN<45>")
	)
	(segment
		(start 278.273764 -278.229568)
		(end 278.435562 -278.229568)
		(width 0.1143)
		(layer "In11.Cu")
		(net "P5E_PEX2_STN2_TX_DN<45>")
	)
	(segment
		(start 269.75435 -78.912974)
		(end 266.123674 -105.234486)
		(width 0.1651)
		(layer "In11.Cu")
		(net "P5E_PEX2_STN2_TX_DN<45>")
	)
	(segment
		(start 278.215852 -271.427448)
		(end 278.170132 -271.473168)
		(width 0.1143)
		(layer "In11.Cu")
		(net "P5E_PEX2_STN2_TX_DN<45>")
	)
	(segment
		(start 255.46812 -30.58795)
		(end 256.703322 -31.646114)
		(width 0.1651)
		(layer "In11.Cu")
		(net "P5E_PEX2_STN2_TX_DN<45>")
	)
	(segment
		(start 278.215852 -271.399)
		(end 278.215852 -271.427448)
		(width 0.1143)
		(layer "In11.Cu")
		(net "P5E_PEX2_STN2_TX_DN<45>")
	)
	(segment
		(start 254.392938 -30.302708)
		(end 254.501904 -30.34792)
		(width 0.1651)
		(layer "In11.Cu")
		(net "P5E_PEX2_STN2_TX_DN<45>")
	)
	(segment
		(start 278.170132 -278.125936)
		(end 278.273764 -278.229568)
		(width 0.1143)
		(layer "In11.Cu")
		(net "P5E_PEX2_STN2_TX_DN<45>")
	)
	(segment
		(start 270.62938 -63.149734)
		(end 269.75435 -78.912974)
		(width 0.1651)
		(layer "In11.Cu")
		(net "P5E_PEX2_STN2_TX_DN<45>")
	)
	(segment
		(start 278.549862 -278.115268)
		(end 278.549862 -277.849838)
		(width 0.1143)
		(layer "In11.Cu")
		(net "P5E_PEX2_STN2_TX_DN<45>")
	)
	(segment
		(start 277.187152 -264.159746)
		(end 278.215852 -270.360902)
		(width 0.1651)
		(layer "In11.Cu")
		(net "P5E_PEX2_STN2_TX_DN<45>")
	)
	(segment
		(start 269.863062 -50.312828)
		(end 270.62938 -63.149734)
		(width 0.1651)
		(layer "In11.Cu")
		(net "P5E_PEX2_STN2_TX_DN<45>")
	)
	(segment
		(start 278.435562 -278.229568)
		(end 278.549862 -278.115268)
		(width 0.1143)
		(layer "In11.Cu")
		(net "P5E_PEX2_STN2_TX_DN<45>")
	)
	(segment
		(start 267.276072 -44.917868)
		(end 269.22476 -48.4632)
		(width 0.1651)
		(layer "In11.Cu")
		(net "P5E_PEX2_STN2_TX_DN<45>")
	)
	(segment
		(start 278.215852 -270.360902)
		(end 278.215852 -271.399)
		(width 0.1651)
		(layer "In11.Cu")
		(net "P5E_PEX2_STN2_TX_DN<45>")
	)
	(segment
		(start 390.410192 -348.880938)
		(end 390.70534 -348.58579)
		(width 0.13462)
		(layer "F.Cu")
		(net "P5E_PEX3_STN5_TX_DN<81>")
	)
	(segment
		(start 390.410192 -349.511366)
		(end 390.410192 -348.880938)
		(width 0.13462)
		(layer "F.Cu")
		(net "P5E_PEX3_STN5_TX_DN<81>")
	)
	(segment
		(start 390.73074 -349.831914)
		(end 390.410192 -349.511366)
		(width 0.13462)
		(layer "F.Cu")
		(net "P5E_PEX3_STN5_TX_DN<81>")
	)
	(segment
		(start 390.41451 -348.29496)
		(end 390.41451 -347.784674)
		(width 0.1651)
		(layer "In7.Cu")
		(net "P5E_PEX3_STN5_TX_DN<81>")
	)
	(segment
		(start 390.70534 -348.58579)
		(end 390.41451 -348.29496)
		(width 0.1651)
		(layer "In7.Cu")
		(net "P5E_PEX3_STN5_TX_DN<81>")
	)
	(segment
		(start 406.489154 -325.646542)
		(end 407.615898 -322.926202)
		(width 0.1651)
		(layer "In7.Cu")
		(net "P5E_PEX3_STN5_TX_DN<81>")
	)
	(segment
		(start 405.386286 -327.089262)
		(end 406.036526 -326.32396)
		(width 0.1651)
		(layer "In7.Cu")
		(net "P5E_PEX3_STN5_TX_DN<81>")
	)
	(segment
		(start 406.036526 -326.32396)
		(end 406.489154 -325.646542)
		(width 0.1651)
		(layer "In7.Cu")
		(net "P5E_PEX3_STN5_TX_DN<81>")
	)
	(segment
		(start 391.96899 -346.230194)
		(end 391.96899 -341.622126)
		(width 0.1651)
		(layer "In7.Cu")
		(net "P5E_PEX3_STN5_TX_DN<81>")
	)
	(segment
		(start 407.570178 -319.915032)
		(end 407.570178 -313.684412)
		(width 0.1143)
		(layer "In7.Cu")
		(net "P5E_PEX3_STN5_TX_DN<81>")
	)
	(segment
		(start 391.96899 -341.622126)
		(end 405.386286 -327.089262)
		(width 0.1651)
		(layer "In7.Cu")
		(net "P5E_PEX3_STN5_TX_DN<81>")
	)
	(segment
		(start 407.949908 -313.684412)
		(end 407.949908 -313.949842)
		(width 0.1143)
		(layer "In7.Cu")
		(net "P5E_PEX3_STN5_TX_DN<81>")
	)
	(segment
		(start 407.615898 -319.9892)
		(end 407.615898 -319.960752)
		(width 0.1143)
		(layer "In7.Cu")
		(net "P5E_PEX3_STN5_TX_DN<81>")
	)
	(segment
		(start 407.615898 -319.960752)
		(end 407.570178 -319.915032)
		(width 0.1143)
		(layer "In7.Cu")
		(net "P5E_PEX3_STN5_TX_DN<81>")
	)
	(segment
		(start 407.835608 -313.570112)
		(end 407.949908 -313.684412)
		(width 0.1143)
		(layer "In7.Cu")
		(net "P5E_PEX3_STN5_TX_DN<81>")
	)
	(segment
		(start 407.684478 -313.570112)
		(end 407.835608 -313.570112)
		(width 0.1143)
		(layer "In7.Cu")
		(net "P5E_PEX3_STN5_TX_DN<81>")
	)
	(segment
		(start 390.41451 -347.784674)
		(end 391.96899 -346.230194)
		(width 0.1651)
		(layer "In7.Cu")
		(net "P5E_PEX3_STN5_TX_DN<81>")
	)
	(segment
		(start 407.615898 -322.926202)
		(end 407.615898 -319.9892)
		(width 0.1651)
		(layer "In7.Cu")
		(net "P5E_PEX3_STN5_TX_DN<81>")
	)
	(segment
		(start 407.570178 -313.684412)
		(end 407.684478 -313.570112)
		(width 0.1143)
		(layer "In7.Cu")
		(net "P5E_PEX3_STN5_TX_DN<81>")
	)
	(segment
		(start 410.184092 -343.685622)
		(end 409.863544 -343.365074)
		(width 0.13462)
		(layer "F.Cu")
		(net "P5E_PEX3_STN7_TX_DN<112>")
	)
	(segment
		(start 409.863544 -343.365074)
		(end 409.863544 -342.734646)
		(width 0.13462)
		(layer "F.Cu")
		(net "P5E_PEX3_STN7_TX_DN<112>")
	)
	(segment
		(start 409.863544 -342.734646)
		(end 410.158692 -342.439498)
		(width 0.13462)
		(layer "F.Cu")
		(net "P5E_PEX3_STN7_TX_DN<112>")
	)
	(segment
		(start 373.62511 -303.962054)
		(end 373.62511 -303.81829)
		(width 0.1651)
		(layer "In11.Cu")
		(net "P5E_PEX3_STN7_TX_DN<112>")
	)
	(segment
		(start 368.337592 -310.892952)
		(end 368.337846 -310.892952)
		(width 0.1651)
		(layer "In11.Cu")
		(net "P5E_PEX3_STN7_TX_DN<112>")
	)
	(segment
		(start 369.911376 -308.538118)
		(end 369.911122 -308.538118)
		(width 0.1651)
		(layer "In11.Cu")
		(net "P5E_PEX3_STN7_TX_DN<112>")
	)
	(segment
		(start 373.130826 -304.312574)
		(end 373.27459 -304.312574)
		(width 0.1651)
		(layer "In11.Cu")
		(net "P5E_PEX3_STN7_TX_DN<112>")
	)
	(segment
		(start 410.158692 -342.439498)
		(end 409.867862 -342.148668)
		(width 0.1651)
		(layer "In11.Cu")
		(net "P5E_PEX3_STN7_TX_DN<112>")
	)
	(segment
		(start 368.612674 -310.481218)
		(end 368.735864 -310.456834)
		(width 0.1651)
		(layer "In11.Cu")
		(net "P5E_PEX3_STN7_TX_DN<112>")
	)
	(segment
		(start 366.652048 -328.097642)
		(end 366.652048 -328.097388)
		(width 0.1651)
		(layer "In11.Cu")
		(net "P5E_PEX3_STN7_TX_DN<112>")
	)
	(segment
		(start 390.165336 -301.599854)
		(end 389.899906 -301.599854)
		(width 0.1143)
		(layer "In11.Cu")
		(net "P5E_PEX3_STN7_TX_DN<112>")
	)
	(segment
		(start 370.560346 -307.566822)
		(end 370.560346 -307.566568)
		(width 0.1651)
		(layer "In11.Cu")
		(net "P5E_PEX3_STN7_TX_DN<112>")
	)
	(segment
		(start 369.63604 -308.950106)
		(end 369.911376 -308.538118)
		(width 0.1651)
		(layer "In11.Cu")
		(net "P5E_PEX3_STN7_TX_DN<112>")
	)
	(segment
		(start 370.309902 -308.101492)
		(end 370.285264 -307.978302)
		(width 0.1651)
		(layer "In11.Cu")
		(net "P5E_PEX3_STN7_TX_DN<112>")
	)
	(segment
		(start 373.258588 -333.104744)
		(end 369.730528 -331.176122)
		(width 0.1651)
		(layer "In11.Cu")
		(net "P5E_PEX3_STN7_TX_DN<112>")
	)
	(segment
		(start 368.986816 -309.921656)
		(end 369.262152 -309.509668)
		(width 0.1651)
		(layer "In11.Cu")
		(net "P5E_PEX3_STN7_TX_DN<112>")
	)
	(segment
		(start 384.72872 -301.220124)
		(end 390.176004 -301.220124)
		(width 0.1143)
		(layer "In11.Cu")
		(net "P5E_PEX3_STN7_TX_DN<112>")
	)
	(segment
		(start 370.285264 -307.978302)
		(end 370.560346 -307.566822)
		(width 0.1651)
		(layer "In11.Cu")
		(net "P5E_PEX3_STN7_TX_DN<112>")
	)
	(segment
		(start 369.911122 -308.538118)
		(end 370.034312 -308.513734)
		(width 0.1651)
		(layer "In11.Cu")
		(net "P5E_PEX3_STN7_TX_DN<112>")
	)
	(segment
		(start 372.780814 -304.80635)
		(end 372.780814 -304.662586)
		(width 0.1651)
		(layer "In11.Cu")
		(net "P5E_PEX3_STN7_TX_DN<112>")
	)
	(segment
		(start 374.937274 -302.506126)
		(end 377.93168 -301.265844)
		(width 0.1651)
		(layer "In11.Cu")
		(net "P5E_PEX3_STN7_TX_DN<112>")
	)
	(segment
		(start 364.51032 -318.352678)
		(end 366.397286 -313.797188)
		(width 0.1651)
		(layer "In11.Cu")
		(net "P5E_PEX3_STN7_TX_DN<112>")
	)
	(segment
		(start 369.262152 -309.509668)
		(end 369.261898 -309.509668)
		(width 0.1651)
		(layer "In11.Cu")
		(net "P5E_PEX3_STN7_TX_DN<112>")
	)
	(segment
		(start 369.011454 -310.044592)
		(end 368.986816 -309.921656)
		(width 0.1651)
		(layer "In11.Cu")
		(net "P5E_PEX3_STN7_TX_DN<112>")
	)
	(segment
		(start 390.279636 -301.485554)
		(end 390.165336 -301.599854)
		(width 0.1143)
		(layer "In11.Cu")
		(net "P5E_PEX3_STN7_TX_DN<112>")
	)
	(segment
		(start 369.730528 -331.176122)
		(end 366.652048 -328.097642)
		(width 0.1651)
		(layer "In11.Cu")
		(net "P5E_PEX3_STN7_TX_DN<112>")
	)
	(segment
		(start 370.683536 -307.542184)
		(end 370.959126 -307.129942)
		(width 0.1651)
		(layer "In11.Cu")
		(net "P5E_PEX3_STN7_TX_DN<112>")
	)
	(segment
		(start 390.176004 -301.220124)
		(end 390.279636 -301.323756)
		(width 0.1143)
		(layer "In11.Cu")
		(net "P5E_PEX3_STN7_TX_DN<112>")
	)
	(segment
		(start 368.086894 -311.428384)
		(end 368.36223 -311.016142)
		(width 0.1651)
		(layer "In11.Cu")
		(net "P5E_PEX3_STN7_TX_DN<112>")
	)
	(segment
		(start 368.612928 -310.481472)
		(end 368.612674 -310.481218)
		(width 0.1651)
		(layer "In11.Cu")
		(net "P5E_PEX3_STN7_TX_DN<112>")
	)
	(segment
		(start 364.51032 -322.92671)
		(end 364.51032 -318.352678)
		(width 0.1651)
		(layer "In11.Cu")
		(net "P5E_PEX3_STN7_TX_DN<112>")
	)
	(segment
		(start 409.867862 -342.148668)
		(end 409.867862 -341.633048)
		(width 0.1651)
		(layer "In11.Cu")
		(net "P5E_PEX3_STN7_TX_DN<112>")
	)
	(segment
		(start 366.397286 -313.797188)
		(end 367.963704 -311.453022)
		(width 0.1651)
		(layer "In11.Cu")
		(net "P5E_PEX3_STN7_TX_DN<112>")
	)
	(segment
		(start 371.936518 -305.506882)
		(end 372.28653 -305.15687)
		(width 0.1651)
		(layer "In11.Cu")
		(net "P5E_PEX3_STN7_TX_DN<112>")
	)
	(segment
		(start 369.385088 -309.485284)
		(end 369.660678 -309.073042)
		(width 0.1651)
		(layer "In11.Cu")
		(net "P5E_PEX3_STN7_TX_DN<112>")
	)
	(segment
		(start 367.96345 -311.452768)
		(end 368.086894 -311.428384)
		(width 0.1651)
		(layer "In11.Cu")
		(net "P5E_PEX3_STN7_TX_DN<112>")
	)
	(segment
		(start 384.654552 -301.265844)
		(end 384.683 -301.265844)
		(width 0.1143)
		(layer "In11.Cu")
		(net "P5E_PEX3_STN7_TX_DN<112>")
	)
	(segment
		(start 367.963704 -311.453022)
		(end 367.96345 -311.452768)
		(width 0.1651)
		(layer "In11.Cu")
		(net "P5E_PEX3_STN7_TX_DN<112>")
	)
	(segment
		(start 384.683 -301.265844)
		(end 384.72872 -301.220124)
		(width 0.1143)
		(layer "In11.Cu")
		(net "P5E_PEX3_STN7_TX_DN<112>")
	)
	(segment
		(start 370.934488 -307.006752)
		(end 371.936518 -305.506882)
		(width 0.1651)
		(layer "In11.Cu")
		(net "P5E_PEX3_STN7_TX_DN<112>")
	)
	(segment
		(start 372.28653 -305.15687)
		(end 372.430294 -305.15687)
		(width 0.1651)
		(layer "In11.Cu")
		(net "P5E_PEX3_STN7_TX_DN<112>")
	)
	(segment
		(start 409.867862 -341.633048)
		(end 409.605734 -341.046308)
		(width 0.1651)
		(layer "In11.Cu")
		(net "P5E_PEX3_STN7_TX_DN<112>")
	)
	(segment
		(start 370.560346 -307.566568)
		(end 370.683536 -307.542184)
		(width 0.1651)
		(layer "In11.Cu")
		(net "P5E_PEX3_STN7_TX_DN<112>")
	)
	(segment
		(start 368.735864 -310.456834)
		(end 369.011454 -310.044592)
		(width 0.1651)
		(layer "In11.Cu")
		(net "P5E_PEX3_STN7_TX_DN<112>")
	)
	(segment
		(start 372.430294 -305.15687)
		(end 372.780814 -304.80635)
		(width 0.1651)
		(layer "In11.Cu")
		(net "P5E_PEX3_STN7_TX_DN<112>")
	)
	(segment
		(start 368.36223 -311.016142)
		(end 368.337592 -310.892952)
		(width 0.1651)
		(layer "In11.Cu")
		(net "P5E_PEX3_STN7_TX_DN<112>")
	)
	(segment
		(start 370.959126 -307.129942)
		(end 370.934488 -307.006752)
		(width 0.1651)
		(layer "In11.Cu")
		(net "P5E_PEX3_STN7_TX_DN<112>")
	)
	(segment
		(start 377.93168 -301.265844)
		(end 384.654552 -301.265844)
		(width 0.1651)
		(layer "In11.Cu")
		(net "P5E_PEX3_STN7_TX_DN<112>")
	)
	(segment
		(start 373.27459 -304.312574)
		(end 373.62511 -303.962054)
		(width 0.1651)
		(layer "In11.Cu")
		(net "P5E_PEX3_STN7_TX_DN<112>")
	)
	(segment
		(start 370.034312 -308.513734)
		(end 370.309902 -308.101492)
		(width 0.1651)
		(layer "In11.Cu")
		(net "P5E_PEX3_STN7_TX_DN<112>")
	)
	(segment
		(start 409.605734 -341.046308)
		(end 373.258588 -333.104744)
		(width 0.1651)
		(layer "In11.Cu")
		(net "P5E_PEX3_STN7_TX_DN<112>")
	)
	(segment
		(start 369.660678 -309.073042)
		(end 369.63604 -308.950106)
		(width 0.1651)
		(layer "In11.Cu")
		(net "P5E_PEX3_STN7_TX_DN<112>")
	)
	(segment
		(start 373.62511 -303.81829)
		(end 374.937274 -302.506126)
		(width 0.1651)
		(layer "In11.Cu")
		(net "P5E_PEX3_STN7_TX_DN<112>")
	)
	(segment
		(start 369.261898 -309.509668)
		(end 369.385088 -309.485284)
		(width 0.1651)
		(layer "In11.Cu")
		(net "P5E_PEX3_STN7_TX_DN<112>")
	)
	(segment
		(start 372.780814 -304.662586)
		(end 373.130826 -304.312574)
		(width 0.1651)
		(layer "In11.Cu")
		(net "P5E_PEX3_STN7_TX_DN<112>")
	)
	(segment
		(start 390.279636 -301.323756)
		(end 390.279636 -301.485554)
		(width 0.1143)
		(layer "In11.Cu")
		(net "P5E_PEX3_STN7_TX_DN<112>")
	)
	(segment
		(start 366.652048 -328.097388)
		(end 364.51032 -322.92671)
		(width 0.1651)
		(layer "In11.Cu")
		(net "P5E_PEX3_STN7_TX_DN<112>")
	)
	(segment
		(start 368.337846 -310.892952)
		(end 368.612928 -310.481472)
		(width 0.1651)
		(layer "In11.Cu")
		(net "P5E_PEX3_STN7_TX_DN<112>")
	)
	(segment
		(start 331.451204 -350.685354)
		(end 331.451204 -351.316798)
		(width 0.13462)
		(layer "F.Cu")
		(net "P5E_PEX2_STN5_TX_C_DP<89>")
	)
	(segment
		(start 331.451204 -351.316798)
		(end 331.156564 -351.611438)
		(width 0.13462)
		(layer "F.Cu")
		(net "P5E_PEX2_STN5_TX_C_DP<89>")
	)
	(segment
		(start 331.131164 -350.365314)
		(end 331.451204 -350.685354)
		(width 0.13462)
		(layer "F.Cu")
		(net "P5E_PEX2_STN5_TX_C_DP<89>")
	)
	(segment
		(start 331.447394 -351.902268)
		(end 331.156564 -351.611438)
		(width 0.1651)
		(layer "In7.Cu")
		(net "P5E_PEX2_STN5_TX_C_DP<89>")
	)
	(segment
		(start 333.68996 -379.772164)
		(end 333.81696 -379.899164)
		(width 0.1651)
		(layer "In7.Cu")
		(net "P5E_PEX2_STN5_TX_C_DP<89>")
	)
	(segment
		(start 333.386938 -366.16005)
		(end 333.16164 -365.668306)
		(width 0.1651)
		(layer "In7.Cu")
		(net "P5E_PEX2_STN5_TX_C_DP<89>")
	)
	(segment
		(start 329.892914 -353.910646)
		(end 331.447394 -352.356166)
		(width 0.1651)
		(layer "In7.Cu")
		(net "P5E_PEX2_STN5_TX_C_DP<89>")
	)
	(segment
		(start 334.534002 -368.474498)
		(end 333.491586 -366.198912)
		(width 0.1651)
		(layer "In7.Cu")
		(net "P5E_PEX2_STN5_TX_C_DP<89>")
	)
	(segment
		(start 334.534002 -379.612398)
		(end 334.534002 -368.474498)
		(width 0.1651)
		(layer "In7.Cu")
		(net "P5E_PEX2_STN5_TX_C_DP<89>")
	)
	(segment
		(start 332.994254 -365.11357)
		(end 332.894432 -365.076486)
		(width 0.1651)
		(layer "In7.Cu")
		(net "P5E_PEX2_STN5_TX_C_DP<89>")
	)
	(segment
		(start 329.892914 -358.342692)
		(end 329.892914 -353.910646)
		(width 0.1651)
		(layer "In7.Cu")
		(net "P5E_PEX2_STN5_TX_C_DP<89>")
	)
	(segment
		(start 332.894432 -365.076486)
		(end 332.655672 -364.55477)
		(width 0.1651)
		(layer "In7.Cu")
		(net "P5E_PEX2_STN5_TX_C_DP<89>")
	)
	(segment
		(start 334.247236 -379.899164)
		(end 334.534002 -379.612398)
		(width 0.1651)
		(layer "In7.Cu")
		(net "P5E_PEX2_STN5_TX_C_DP<89>")
	)
	(segment
		(start 333.200502 -365.563658)
		(end 332.994254 -365.11357)
		(width 0.1651)
		(layer "In7.Cu")
		(net "P5E_PEX2_STN5_TX_C_DP<89>")
	)
	(segment
		(start 332.655672 -364.55477)
		(end 332.692756 -364.455202)
		(width 0.1651)
		(layer "In7.Cu")
		(net "P5E_PEX2_STN5_TX_C_DP<89>")
	)
	(segment
		(start 333.16164 -365.668306)
		(end 333.200502 -365.563658)
		(width 0.1651)
		(layer "In7.Cu")
		(net "P5E_PEX2_STN5_TX_C_DP<89>")
	)
	(segment
		(start 332.692756 -364.455202)
		(end 329.892914 -358.342692)
		(width 0.1651)
		(layer "In7.Cu")
		(net "P5E_PEX2_STN5_TX_C_DP<89>")
	)
	(segment
		(start 333.491586 -366.198912)
		(end 333.386938 -366.16005)
		(width 0.1651)
		(layer "In7.Cu")
		(net "P5E_PEX2_STN5_TX_C_DP<89>")
	)
	(segment
		(start 331.447394 -352.356166)
		(end 331.447394 -351.902268)
		(width 0.1651)
		(layer "In7.Cu")
		(net "P5E_PEX2_STN5_TX_C_DP<89>")
	)
	(segment
		(start 333.68996 -379.390148)
		(end 333.68996 -379.772164)
		(width 0.1651)
		(layer "In7.Cu")
		(net "P5E_PEX2_STN5_TX_C_DP<89>")
	)
	(segment
		(start 333.81696 -379.899164)
		(end 334.247236 -379.899164)
		(width 0.1651)
		(layer "In7.Cu")
		(net "P5E_PEX2_STN5_TX_C_DP<89>")
	)
	(segment
		(start 18.369788 -28.829)
		(end 18.059146 -29.139642)
		(width 0.13462)
		(layer "F.Cu")
		(net "P5E_PEX0_STN2_TX_DP<44>")
	)
	(segment
		(start 19.020028 -28.829)
		(end 18.369788 -28.829)
		(width 0.13462)
		(layer "F.Cu")
		(net "P5E_PEX0_STN2_TX_DP<44>")
	)
	(segment
		(start 19.30527 -29.114242)
		(end 19.020028 -28.829)
		(width 0.13462)
		(layer "F.Cu")
		(net "P5E_PEX0_STN2_TX_DP<44>")
	)
	(segment
		(start 46.68393 -271.427448)
		(end 46.72965 -271.473168)
		(width 0.1143)
		(layer "In11.Cu")
		(net "P5E_PEX0_STN2_TX_DP<44>")
	)
	(segment
		(start 46.944788 -280.319988)
		(end 47.18558 -280.319988)
		(width 0.1143)
		(layer "In11.Cu")
		(net "P5E_PEX0_STN2_TX_DP<44>")
	)
	(segment
		(start 35.691572 -44.601638)
		(end 37.679122 -48.256952)
		(width 0.1651)
		(layer "In11.Cu")
		(net "P5E_PEX0_STN2_TX_DP<44>")
	)
	(segment
		(start 22.073362 -28.823412)
		(end 23.72614 -29.505402)
		(width 0.1651)
		(layer "In11.Cu")
		(net "P5E_PEX0_STN2_TX_DP<44>")
	)
	(segment
		(start 24.40051 -30.499304)
		(end 24.525478 -30.513782)
		(width 0.1651)
		(layer "In11.Cu")
		(net "P5E_PEX0_STN2_TX_DP<44>")
	)
	(segment
		(start 38.53434 -145.379948)
		(end 45.79493 -264.61212)
		(width 0.1651)
		(layer "In11.Cu")
		(net "P5E_PEX0_STN2_TX_DP<44>")
	)
	(segment
		(start 46.68393 -270.748252)
		(end 46.68393 -271.399)
		(width 0.1651)
		(layer "In11.Cu")
		(net "P5E_PEX0_STN2_TX_DP<44>")
	)
	(segment
		(start 24.092662 -30.110938)
		(end 24.40051 -30.499304)
		(width 0.1651)
		(layer "In11.Cu")
		(net "P5E_PEX0_STN2_TX_DP<44>")
	)
	(segment
		(start 19.30527 -29.114242)
		(end 19.598386 -28.821126)
		(width 0.1651)
		(layer "In11.Cu")
		(net "P5E_PEX0_STN2_TX_DP<44>")
	)
	(segment
		(start 24.525478 -30.513782)
		(end 35.691572 -44.601638)
		(width 0.1651)
		(layer "In11.Cu")
		(net "P5E_PEX0_STN2_TX_DP<44>")
	)
	(segment
		(start 20.46605 -28.823412)
		(end 20.55495 -28.912312)
		(width 0.1651)
		(layer "In11.Cu")
		(net "P5E_PEX0_STN2_TX_DP<44>")
	)
	(segment
		(start 38.407086 -50.411126)
		(end 39.10584 -62.140338)
		(width 0.1651)
		(layer "In11.Cu")
		(net "P5E_PEX0_STN2_TX_DP<44>")
	)
	(segment
		(start 37.679122 -48.256952)
		(end 38.407086 -50.411126)
		(width 0.1651)
		(layer "In11.Cu")
		(net "P5E_PEX0_STN2_TX_DP<44>")
	)
	(segment
		(start 39.462964 -135.957056)
		(end 38.53434 -145.379948)
		(width 0.1651)
		(layer "In11.Cu")
		(net "P5E_PEX0_STN2_TX_DP<44>")
	)
	(segment
		(start 23.72614 -29.505402)
		(end 24.10714 -29.98597)
		(width 0.1651)
		(layer "In11.Cu")
		(net "P5E_PEX0_STN2_TX_DP<44>")
	)
	(segment
		(start 47.18558 -280.319988)
		(end 47.29988 -280.434288)
		(width 0.1143)
		(layer "In11.Cu")
		(net "P5E_PEX0_STN2_TX_DP<44>")
	)
	(segment
		(start 20.55495 -28.912312)
		(end 21.05025 -28.912312)
		(width 0.1651)
		(layer "In11.Cu")
		(net "P5E_PEX0_STN2_TX_DP<44>")
	)
	(segment
		(start 21.05025 -28.912312)
		(end 21.13915 -28.823412)
		(width 0.1651)
		(layer "In11.Cu")
		(net "P5E_PEX0_STN2_TX_DP<44>")
	)
	(segment
		(start 45.79493 -264.61212)
		(end 46.68393 -270.748252)
		(width 0.1651)
		(layer "In11.Cu")
		(net "P5E_PEX0_STN2_TX_DP<44>")
	)
	(segment
		(start 39.10584 -62.140338)
		(end 39.462964 -135.957056)
		(width 0.1651)
		(layer "In11.Cu")
		(net "P5E_PEX0_STN2_TX_DP<44>")
	)
	(segment
		(start 21.13915 -28.823412)
		(end 22.073362 -28.823412)
		(width 0.1651)
		(layer "In11.Cu")
		(net "P5E_PEX0_STN2_TX_DP<44>")
	)
	(segment
		(start 46.72965 -271.473168)
		(end 46.72965 -280.10485)
		(width 0.1143)
		(layer "In11.Cu")
		(net "P5E_PEX0_STN2_TX_DP<44>")
	)
	(segment
		(start 24.10714 -29.98597)
		(end 24.092662 -30.110938)
		(width 0.1651)
		(layer "In11.Cu")
		(net "P5E_PEX0_STN2_TX_DP<44>")
	)
	(segment
		(start 47.29988 -280.434288)
		(end 47.29988 -280.699718)
		(width 0.1143)
		(layer "In11.Cu")
		(net "P5E_PEX0_STN2_TX_DP<44>")
	)
	(segment
		(start 19.598386 -28.821126)
		(end 19.604482 -28.823412)
		(width 0.1651)
		(layer "In11.Cu")
		(net "P5E_PEX0_STN2_TX_DP<44>")
	)
	(segment
		(start 46.72965 -280.10485)
		(end 46.944788 -280.319988)
		(width 0.1143)
		(layer "In11.Cu")
		(net "P5E_PEX0_STN2_TX_DP<44>")
	)
	(segment
		(start 19.604482 -28.823412)
		(end 20.46605 -28.823412)
		(width 0.1651)
		(layer "In11.Cu")
		(net "P5E_PEX0_STN2_TX_DP<44>")
	)
	(segment
		(start 46.68393 -271.399)
		(end 46.68393 -271.427448)
		(width 0.1143)
		(layer "In11.Cu")
		(net "P5E_PEX0_STN2_TX_DP<44>")
	)
	(segment
		(start 316.180724 -355.026722)
		(end 316.475364 -354.732082)
		(width 0.13462)
		(layer "F.Cu")
		(net "P5E_PEX2_STN5_TX_DN<82>")
	)
	(segment
		(start 316.500764 -355.978206)
		(end 316.180724 -355.658166)
		(width 0.13462)
		(layer "F.Cu")
		(net "P5E_PEX2_STN5_TX_DN<82>")
	)
	(segment
		(start 316.180724 -355.658166)
		(end 316.180724 -355.026722)
		(width 0.13462)
		(layer "F.Cu")
		(net "P5E_PEX2_STN5_TX_DN<82>")
	)
	(segment
		(start 316.184534 -354.441252)
		(end 316.184534 -353.930966)
		(width 0.1651)
		(layer "In7.Cu")
		(net "P5E_PEX2_STN5_TX_DN<82>")
	)
	(segment
		(start 292.46576 -319.8368)
		(end 292.42004 -319.79108)
		(width 0.1143)
		(layer "In7.Cu")
		(net "P5E_PEX2_STN5_TX_DN<82>")
	)
	(segment
		(start 305.275742 -335.157826)
		(end 298.0563 -331.9399)
		(width 0.1651)
		(layer "In7.Cu")
		(net "P5E_PEX2_STN5_TX_DN<82>")
	)
	(segment
		(start 316.184534 -353.930966)
		(end 317.739014 -352.376486)
		(width 0.1651)
		(layer "In7.Cu")
		(net "P5E_PEX2_STN5_TX_DN<82>")
	)
	(segment
		(start 298.0563 -331.9399)
		(end 294.701468 -328.585068)
		(width 0.1651)
		(layer "In7.Cu")
		(net "P5E_PEX2_STN5_TX_DN<82>")
	)
	(segment
		(start 305.828954 -335.321148)
		(end 305.376326 -335.119218)
		(width 0.1651)
		(layer "In7.Cu")
		(net "P5E_PEX2_STN5_TX_DN<82>")
	)
	(segment
		(start 292.42004 -319.79108)
		(end 292.42004 -311.784492)
		(width 0.1143)
		(layer "In7.Cu")
		(net "P5E_PEX2_STN5_TX_DN<82>")
	)
	(segment
		(start 294.701468 -328.585068)
		(end 292.46576 -323.187314)
		(width 0.1651)
		(layer "In7.Cu")
		(net "P5E_PEX2_STN5_TX_DN<82>")
	)
	(segment
		(start 317.422276 -341.0331)
		(end 315.918088 -339.901784)
		(width 0.1651)
		(layer "In7.Cu")
		(net "P5E_PEX2_STN5_TX_DN<82>")
	)
	(segment
		(start 292.46576 -319.865248)
		(end 292.46576 -319.8368)
		(width 0.1143)
		(layer "In7.Cu")
		(net "P5E_PEX2_STN5_TX_DN<82>")
	)
	(segment
		(start 315.918088 -339.901784)
		(end 305.867562 -335.421732)
		(width 0.1651)
		(layer "In7.Cu")
		(net "P5E_PEX2_STN5_TX_DN<82>")
	)
	(segment
		(start 292.79977 -311.784492)
		(end 292.79977 -312.049922)
		(width 0.1143)
		(layer "In7.Cu")
		(net "P5E_PEX2_STN5_TX_DN<82>")
	)
	(segment
		(start 292.42004 -311.784492)
		(end 292.53434 -311.670192)
		(width 0.1143)
		(layer "In7.Cu")
		(net "P5E_PEX2_STN5_TX_DN<82>")
	)
	(segment
		(start 305.867562 -335.421732)
		(end 305.828954 -335.321148)
		(width 0.1651)
		(layer "In7.Cu")
		(net "P5E_PEX2_STN5_TX_DN<82>")
	)
	(segment
		(start 317.739014 -341.937594)
		(end 317.422276 -341.0331)
		(width 0.1651)
		(layer "In7.Cu")
		(net "P5E_PEX2_STN5_TX_DN<82>")
	)
	(segment
		(start 316.475364 -354.732082)
		(end 316.184534 -354.441252)
		(width 0.1651)
		(layer "In7.Cu")
		(net "P5E_PEX2_STN5_TX_DN<82>")
	)
	(segment
		(start 305.376326 -335.119218)
		(end 305.275742 -335.157826)
		(width 0.1651)
		(layer "In7.Cu")
		(net "P5E_PEX2_STN5_TX_DN<82>")
	)
	(segment
		(start 292.46576 -323.187314)
		(end 292.46576 -319.865248)
		(width 0.1651)
		(layer "In7.Cu")
		(net "P5E_PEX2_STN5_TX_DN<82>")
	)
	(segment
		(start 292.53434 -311.670192)
		(end 292.68547 -311.670192)
		(width 0.1143)
		(layer "In7.Cu")
		(net "P5E_PEX2_STN5_TX_DN<82>")
	)
	(segment
		(start 292.68547 -311.670192)
		(end 292.79977 -311.784492)
		(width 0.1143)
		(layer "In7.Cu")
		(net "P5E_PEX2_STN5_TX_DN<82>")
	)
	(segment
		(start 317.739014 -352.376486)
		(end 317.739014 -341.937594)
		(width 0.1651)
		(layer "In7.Cu")
		(net "P5E_PEX2_STN5_TX_DN<82>")
	)
	(segment
		(start 402.571712 -348.879922)
		(end 402.27758 -348.58579)
		(width 0.13462)
		(layer "F.Cu")
		(net "P5E_PEX3_STN5_TX_DP<87>")
	)
	(segment
		(start 402.571712 -349.512382)
		(end 402.571712 -348.879922)
		(width 0.13462)
		(layer "F.Cu")
		(net "P5E_PEX3_STN5_TX_DP<87>")
	)
	(segment
		(start 402.25218 -349.831914)
		(end 402.571712 -349.512382)
		(width 0.13462)
		(layer "F.Cu")
		(net "P5E_PEX3_STN5_TX_DP<87>")
	)
	(segment
		(start 413.033972 -320.04)
		(end 413.079692 -319.99428)
		(width 0.1143)
		(layer "In7.Cu")
		(net "P5E_PEX3_STN5_TX_DP<87>")
	)
	(segment
		(start 413.649922 -313.265312)
		(end 413.649922 -312.999882)
		(width 0.1143)
		(layer "In7.Cu")
		(net "P5E_PEX3_STN5_TX_DP<87>")
	)
	(segment
		(start 402.56841 -347.667834)
		(end 404.301452 -345.934792)
		(width 0.1651)
		(layer "In7.Cu")
		(net "P5E_PEX3_STN5_TX_DP<87>")
	)
	(segment
		(start 413.305498 -313.379612)
		(end 413.535622 -313.379612)
		(width 0.1143)
		(layer "In7.Cu")
		(net "P5E_PEX3_STN5_TX_DP<87>")
	)
	(segment
		(start 413.079692 -319.99428)
		(end 413.079692 -313.605418)
		(width 0.1143)
		(layer "In7.Cu")
		(net "P5E_PEX3_STN5_TX_DP<87>")
	)
	(segment
		(start 413.079692 -313.605418)
		(end 413.305498 -313.379612)
		(width 0.1143)
		(layer "In7.Cu")
		(net "P5E_PEX3_STN5_TX_DP<87>")
	)
	(segment
		(start 404.301452 -345.934792)
		(end 413.033972 -324.77456)
		(width 0.1651)
		(layer "In7.Cu")
		(net "P5E_PEX3_STN5_TX_DP<87>")
	)
	(segment
		(start 413.033972 -320.068448)
		(end 413.033972 -320.04)
		(width 0.1143)
		(layer "In7.Cu")
		(net "P5E_PEX3_STN5_TX_DP<87>")
	)
	(segment
		(start 402.27758 -348.58579)
		(end 402.56841 -348.29496)
		(width 0.1651)
		(layer "In7.Cu")
		(net "P5E_PEX3_STN5_TX_DP<87>")
	)
	(segment
		(start 413.033972 -324.77456)
		(end 413.033972 -320.068448)
		(width 0.1651)
		(layer "In7.Cu")
		(net "P5E_PEX3_STN5_TX_DP<87>")
	)
	(segment
		(start 402.56841 -348.29496)
		(end 402.56841 -347.667834)
		(width 0.1651)
		(layer "In7.Cu")
		(net "P5E_PEX3_STN5_TX_DP<87>")
	)
	(segment
		(start 413.535622 -313.379612)
		(end 413.649922 -313.265312)
		(width 0.1143)
		(layer "In7.Cu")
		(net "P5E_PEX3_STN5_TX_DP<87>")
	)
	(segment
		(start 384.192272 -343.365074)
		(end 384.192272 -342.734646)
		(width 0.13462)
		(layer "F.Cu")
		(net "P5E_PEX3_STN6_TX_DN<106>")
	)
	(segment
		(start 384.51282 -343.685622)
		(end 384.192272 -343.365074)
		(width 0.13462)
		(layer "F.Cu")
		(net "P5E_PEX3_STN6_TX_DN<106>")
	)
	(segment
		(start 384.192272 -342.734646)
		(end 384.48742 -342.439498)
		(width 0.13462)
		(layer "F.Cu")
		(net "P5E_PEX3_STN6_TX_DN<106>")
	)
	(segment
		(start 396.17015 -313.673744)
		(end 396.273782 -313.570112)
		(width 0.1143)
		(layer "In13.Cu")
		(net "P5E_PEX3_STN6_TX_DN<106>")
	)
	(segment
		(start 396.21587 -320.017648)
		(end 396.17015 -319.971928)
		(width 0.1143)
		(layer "In13.Cu")
		(net "P5E_PEX3_STN6_TX_DN<106>")
	)
	(segment
		(start 384.48742 -342.439498)
		(end 384.19659 -342.148668)
		(width 0.1651)
		(layer "In13.Cu")
		(net "P5E_PEX3_STN6_TX_DN<106>")
	)
	(segment
		(start 395.895322 -322.848478)
		(end 396.21587 -322.074794)
		(width 0.1651)
		(layer "In13.Cu")
		(net "P5E_PEX3_STN6_TX_DN<106>")
	)
	(segment
		(start 396.21587 -322.074794)
		(end 396.21587 -320.046096)
		(width 0.1651)
		(layer "In13.Cu")
		(net "P5E_PEX3_STN6_TX_DN<106>")
	)
	(segment
		(start 384.19659 -342.148668)
		(end 384.19659 -341.604092)
		(width 0.1651)
		(layer "In13.Cu")
		(net "P5E_PEX3_STN6_TX_DN<106>")
	)
	(segment
		(start 396.43558 -313.570112)
		(end 396.54988 -313.684412)
		(width 0.1143)
		(layer "In13.Cu")
		(net "P5E_PEX3_STN6_TX_DN<106>")
	)
	(segment
		(start 394.680186 -325.20509)
		(end 395.895322 -322.848478)
		(width 0.1651)
		(layer "In13.Cu")
		(net "P5E_PEX3_STN6_TX_DN<106>")
	)
	(segment
		(start 396.54988 -313.684412)
		(end 396.54988 -313.949842)
		(width 0.1143)
		(layer "In13.Cu")
		(net "P5E_PEX3_STN6_TX_DN<106>")
	)
	(segment
		(start 396.21587 -320.046096)
		(end 396.21587 -320.017648)
		(width 0.1143)
		(layer "In13.Cu")
		(net "P5E_PEX3_STN6_TX_DN<106>")
	)
	(segment
		(start 384.285998 -341.342472)
		(end 387.783324 -336.47126)
		(width 0.1651)
		(layer "In13.Cu")
		(net "P5E_PEX3_STN6_TX_DN<106>")
	)
	(segment
		(start 384.19659 -341.604092)
		(end 384.285998 -341.342472)
		(width 0.1651)
		(layer "In13.Cu")
		(net "P5E_PEX3_STN6_TX_DN<106>")
	)
	(segment
		(start 396.273782 -313.570112)
		(end 396.43558 -313.570112)
		(width 0.1143)
		(layer "In13.Cu")
		(net "P5E_PEX3_STN6_TX_DN<106>")
	)
	(segment
		(start 396.17015 -319.971928)
		(end 396.17015 -313.673744)
		(width 0.1143)
		(layer "In13.Cu")
		(net "P5E_PEX3_STN6_TX_DN<106>")
	)
	(segment
		(start 387.783324 -336.47126)
		(end 394.680186 -325.20509)
		(width 0.1651)
		(layer "In13.Cu")
		(net "P5E_PEX3_STN6_TX_DN<106>")
	)
	(segment
		(start 289.634422 -344.219022)
		(end 289.954462 -344.539062)
		(width 0.13462)
		(layer "F.Cu")
		(net "P5E_PEX2_STN7_TX_C_DN<122>")
	)
	(segment
		(start 289.954462 -345.170506)
		(end 289.659822 -345.465146)
		(width 0.13462)
		(layer "F.Cu")
		(net "P5E_PEX2_STN7_TX_C_DN<122>")
	)
	(segment
		(start 289.954462 -344.539062)
		(end 289.954462 -345.170506)
		(width 0.13462)
		(layer "F.Cu")
		(net "P5E_PEX2_STN7_TX_C_DN<122>")
	)
	(segment
		(start 291.889942 -374.390158)
		(end 291.889942 -374.772174)
		(width 0.1651)
		(layer "In7.Cu")
		(net "P5E_PEX2_STN7_TX_C_DN<122>")
	)
	(segment
		(start 292.156134 -367.634774)
		(end 291.9603 -367.179352)
		(width 0.1651)
		(layer "In7.Cu")
		(net "P5E_PEX2_STN7_TX_C_DN<122>")
	)
	(segment
		(start 289.950652 -346.209874)
		(end 289.950652 -345.755976)
		(width 0.1651)
		(layer "In7.Cu")
		(net "P5E_PEX2_STN7_TX_C_DN<122>")
	)
	(segment
		(start 289.601148 -361.598718)
		(end 289.641026 -361.498642)
		(width 0.1651)
		(layer "In7.Cu")
		(net "P5E_PEX2_STN7_TX_C_DN<122>")
	)
	(segment
		(start 291.9603 -367.179352)
		(end 292.020244 -367.029238)
		(width 0.1651)
		(layer "In7.Cu")
		(net "P5E_PEX2_STN7_TX_C_DN<122>")
	)
	(segment
		(start 289.897312 -362.093764)
		(end 289.797236 -362.053886)
		(width 0.1651)
		(layer "In7.Cu")
		(net "P5E_PEX2_STN7_TX_C_DN<122>")
	)
	(segment
		(start 292.016942 -374.899174)
		(end 292.447218 -374.899174)
		(width 0.1651)
		(layer "In7.Cu")
		(net "P5E_PEX2_STN7_TX_C_DN<122>")
	)
	(segment
		(start 291.824664 -366.574324)
		(end 291.674296 -366.514634)
		(width 0.1651)
		(layer "In7.Cu")
		(net "P5E_PEX2_STN7_TX_C_DN<122>")
	)
	(segment
		(start 290.860988 -364.334044)
		(end 290.71062 -364.274354)
		(width 0.1651)
		(layer "In7.Cu")
		(net "P5E_PEX2_STN7_TX_C_DN<122>")
	)
	(segment
		(start 291.192458 -365.394494)
		(end 290.996624 -364.939072)
		(width 0.1651)
		(layer "In7.Cu")
		(net "P5E_PEX2_STN7_TX_C_DN<122>")
	)
	(segment
		(start 290.71062 -364.274354)
		(end 290.514786 -363.818932)
		(width 0.1651)
		(layer "In7.Cu")
		(net "P5E_PEX2_STN7_TX_C_DN<122>")
	)
	(segment
		(start 291.342826 -365.454184)
		(end 291.192458 -365.394494)
		(width 0.1651)
		(layer "In7.Cu")
		(net "P5E_PEX2_STN7_TX_C_DN<122>")
	)
	(segment
		(start 290.57473 -363.668818)
		(end 290.37915 -363.213904)
		(width 0.1651)
		(layer "In7.Cu")
		(net "P5E_PEX2_STN7_TX_C_DN<122>")
	)
	(segment
		(start 291.674296 -366.514634)
		(end 291.478462 -366.059212)
		(width 0.1651)
		(layer "In7.Cu")
		(net "P5E_PEX2_STN7_TX_C_DN<122>")
	)
	(segment
		(start 288.396172 -358.604566)
		(end 288.396172 -347.764354)
		(width 0.1651)
		(layer "In7.Cu")
		(net "P5E_PEX2_STN7_TX_C_DN<122>")
	)
	(segment
		(start 291.056568 -364.788958)
		(end 290.860988 -364.334044)
		(width 0.1651)
		(layer "In7.Cu")
		(net "P5E_PEX2_STN7_TX_C_DN<122>")
	)
	(segment
		(start 291.538406 -365.909098)
		(end 291.342826 -365.454184)
		(width 0.1651)
		(layer "In7.Cu")
		(net "P5E_PEX2_STN7_TX_C_DN<122>")
	)
	(segment
		(start 292.733984 -374.612408)
		(end 292.733984 -368.688366)
		(width 0.1651)
		(layer "In7.Cu")
		(net "P5E_PEX2_STN7_TX_C_DN<122>")
	)
	(segment
		(start 290.37915 -363.213904)
		(end 290.228782 -363.154214)
		(width 0.1651)
		(layer "In7.Cu")
		(net "P5E_PEX2_STN7_TX_C_DN<122>")
	)
	(segment
		(start 291.889942 -374.772174)
		(end 292.016942 -374.899174)
		(width 0.1651)
		(layer "In7.Cu")
		(net "P5E_PEX2_STN7_TX_C_DN<122>")
	)
	(segment
		(start 289.797236 -362.053886)
		(end 289.601148 -361.598718)
		(width 0.1651)
		(layer "In7.Cu")
		(net "P5E_PEX2_STN7_TX_C_DN<122>")
	)
	(segment
		(start 290.514786 -363.818932)
		(end 290.57473 -363.668818)
		(width 0.1651)
		(layer "In7.Cu")
		(net "P5E_PEX2_STN7_TX_C_DN<122>")
	)
	(segment
		(start 290.092892 -362.548678)
		(end 289.897312 -362.093764)
		(width 0.1651)
		(layer "In7.Cu")
		(net "P5E_PEX2_STN7_TX_C_DN<122>")
	)
	(segment
		(start 288.396172 -347.764354)
		(end 289.950652 -346.209874)
		(width 0.1651)
		(layer "In7.Cu")
		(net "P5E_PEX2_STN7_TX_C_DN<122>")
	)
	(segment
		(start 292.447218 -374.899174)
		(end 292.733984 -374.612408)
		(width 0.1651)
		(layer "In7.Cu")
		(net "P5E_PEX2_STN7_TX_C_DN<122>")
	)
	(segment
		(start 291.478462 -366.059212)
		(end 291.538406 -365.909098)
		(width 0.1651)
		(layer "In7.Cu")
		(net "P5E_PEX2_STN7_TX_C_DN<122>")
	)
	(segment
		(start 290.228782 -363.154214)
		(end 290.032948 -362.698792)
		(width 0.1651)
		(layer "In7.Cu")
		(net "P5E_PEX2_STN7_TX_C_DN<122>")
	)
	(segment
		(start 289.950652 -345.755976)
		(end 289.659822 -345.465146)
		(width 0.1651)
		(layer "In7.Cu")
		(net "P5E_PEX2_STN7_TX_C_DN<122>")
	)
	(segment
		(start 290.032948 -362.698792)
		(end 290.092892 -362.548678)
		(width 0.1651)
		(layer "In7.Cu")
		(net "P5E_PEX2_STN7_TX_C_DN<122>")
	)
	(segment
		(start 292.306502 -367.694464)
		(end 292.156134 -367.634774)
		(width 0.1651)
		(layer "In7.Cu")
		(net "P5E_PEX2_STN7_TX_C_DN<122>")
	)
	(segment
		(start 292.733984 -368.688366)
		(end 292.306502 -367.694464)
		(width 0.1651)
		(layer "In7.Cu")
		(net "P5E_PEX2_STN7_TX_C_DN<122>")
	)
	(segment
		(start 292.020244 -367.029238)
		(end 291.824664 -366.574324)
		(width 0.1651)
		(layer "In7.Cu")
		(net "P5E_PEX2_STN7_TX_C_DN<122>")
	)
	(segment
		(start 289.641026 -361.498642)
		(end 288.396172 -358.604566)
		(width 0.1651)
		(layer "In7.Cu")
		(net "P5E_PEX2_STN7_TX_C_DN<122>")
	)
	(segment
		(start 290.996624 -364.939072)
		(end 291.056568 -364.788958)
		(width 0.1651)
		(layer "In7.Cu")
		(net "P5E_PEX2_STN7_TX_C_DN<122>")
	)
	(segment
		(start 89.647522 -355.026722)
		(end 89.352882 -354.732082)
		(width 0.13462)
		(layer "F.Cu")
		(net "P5E_PEX0_STN5_TX_DP<94>")
	)
	(segment
		(start 89.327482 -355.978206)
		(end 89.647522 -355.658166)
		(width 0.13462)
		(layer "F.Cu")
		(net "P5E_PEX0_STN5_TX_DP<94>")
	)
	(segment
		(start 89.647522 -355.658166)
		(end 89.647522 -355.026722)
		(width 0.13462)
		(layer "F.Cu")
		(net "P5E_PEX0_STN5_TX_DP<94>")
	)
	(segment
		(start 89.643712 -353.825302)
		(end 91.198192 -352.270822)
		(width 0.1651)
		(layer "In7.Cu")
		(net "P5E_PEX0_STN5_TX_DP<94>")
	)
	(segment
		(start 71.999856 -311.365392)
		(end 71.999856 -311.099962)
		(width 0.1143)
		(layer "In7.Cu")
		(net "P5E_PEX0_STN5_TX_DP<94>")
	)
	(segment
		(start 91.198192 -352.270822)
		(end 91.198192 -341.562436)
		(width 0.1651)
		(layer "In7.Cu")
		(net "P5E_PEX0_STN5_TX_DP<94>")
	)
	(segment
		(start 89.643712 -354.441252)
		(end 89.643712 -353.825302)
		(width 0.1651)
		(layer "In7.Cu")
		(net "P5E_PEX0_STN5_TX_DP<94>")
	)
	(segment
		(start 91.198192 -341.562436)
		(end 90.566748 -340.037928)
		(width 0.1651)
		(layer "In7.Cu")
		(net "P5E_PEX0_STN5_TX_DP<94>")
	)
	(segment
		(start 71.383906 -319.8876)
		(end 71.429626 -319.84188)
		(width 0.1143)
		(layer "In7.Cu")
		(net "P5E_PEX0_STN5_TX_DP<94>")
	)
	(segment
		(start 71.383906 -320.411094)
		(end 71.383906 -319.916048)
		(width 0.1651)
		(layer "In7.Cu")
		(net "P5E_PEX0_STN5_TX_DP<94>")
	)
	(segment
		(start 90.566748 -340.037928)
		(end 71.99503 -321.46621)
		(width 0.1651)
		(layer "In7.Cu")
		(net "P5E_PEX0_STN5_TX_DP<94>")
	)
	(segment
		(start 71.99503 -321.46621)
		(end 71.537322 -320.78168)
		(width 0.1651)
		(layer "In7.Cu")
		(net "P5E_PEX0_STN5_TX_DP<94>")
	)
	(segment
		(start 89.352882 -354.732082)
		(end 89.643712 -354.441252)
		(width 0.1651)
		(layer "In7.Cu")
		(net "P5E_PEX0_STN5_TX_DP<94>")
	)
	(segment
		(start 71.537322 -320.78168)
		(end 71.383906 -320.411094)
		(width 0.1651)
		(layer "In7.Cu")
		(net "P5E_PEX0_STN5_TX_DP<94>")
	)
	(segment
		(start 71.429626 -319.84188)
		(end 71.429626 -311.705498)
		(width 0.1143)
		(layer "In7.Cu")
		(net "P5E_PEX0_STN5_TX_DP<94>")
	)
	(segment
		(start 71.383906 -319.916048)
		(end 71.383906 -319.8876)
		(width 0.1143)
		(layer "In7.Cu")
		(net "P5E_PEX0_STN5_TX_DP<94>")
	)
	(segment
		(start 71.655432 -311.479692)
		(end 71.885556 -311.479692)
		(width 0.1143)
		(layer "In7.Cu")
		(net "P5E_PEX0_STN5_TX_DP<94>")
	)
	(segment
		(start 71.885556 -311.479692)
		(end 71.999856 -311.365392)
		(width 0.1143)
		(layer "In7.Cu")
		(net "P5E_PEX0_STN5_TX_DP<94>")
	)
	(segment
		(start 71.429626 -311.705498)
		(end 71.655432 -311.479692)
		(width 0.1143)
		(layer "In7.Cu")
		(net "P5E_PEX0_STN5_TX_DP<94>")
	)
	(segment
		(start 251.505212 -28.250642)
		(end 251.201174 -28.55468)
		(width 0.13462)
		(layer "F.Cu")
		(net "P5E_PEX2_STN2_TX_DN<44>")
	)
	(segment
		(start 251.201174 -28.55468)
		(end 250.588526 -28.55468)
		(width 0.13462)
		(layer "F.Cu")
		(net "P5E_PEX2_STN2_TX_DN<44>")
	)
	(segment
		(start 250.588526 -28.55468)
		(end 250.259088 -28.225242)
		(width 0.13462)
		(layer "F.Cu")
		(net "P5E_PEX2_STN2_TX_DN<44>")
	)
	(segment
		(start 251.505212 -28.250642)
		(end 251.750576 -28.496006)
		(width 0.1651)
		(layer "In11.Cu")
		(net "P5E_PEX2_STN2_TX_DN<44>")
	)
	(segment
		(start 271.9451 -135.970264)
		(end 271.017238 -145.385282)
		(width 0.1651)
		(layer "In11.Cu")
		(net "P5E_PEX2_STN2_TX_DN<44>")
	)
	(segment
		(start 279.165812 -271.399)
		(end 279.165812 -271.427448)
		(width 0.1143)
		(layer "In11.Cu")
		(net "P5E_PEX2_STN2_TX_DN<44>")
	)
	(segment
		(start 279.499822 -280.015188)
		(end 279.499822 -279.749504)
		(width 0.1143)
		(layer "In11.Cu")
		(net "P5E_PEX2_STN2_TX_DN<44>")
	)
	(segment
		(start 279.120092 -271.473168)
		(end 279.120092 -280.025856)
		(width 0.1143)
		(layer "In11.Cu")
		(net "P5E_PEX2_STN2_TX_DN<44>")
	)
	(segment
		(start 279.385522 -280.129488)
		(end 279.499822 -280.015188)
		(width 0.1143)
		(layer "In11.Cu")
		(net "P5E_PEX2_STN2_TX_DN<44>")
	)
	(segment
		(start 278.275796 -264.583164)
		(end 279.165812 -270.72717)
		(width 0.1651)
		(layer "In11.Cu")
		(net "P5E_PEX2_STN2_TX_DN<44>")
	)
	(segment
		(start 251.860558 -28.541472)
		(end 254.329184 -28.541472)
		(width 0.1651)
		(layer "In11.Cu")
		(net "P5E_PEX2_STN2_TX_DN<44>")
	)
	(segment
		(start 268.127734 -44.445428)
		(end 270.138398 -48.143668)
		(width 0.1651)
		(layer "In11.Cu")
		(net "P5E_PEX2_STN2_TX_DN<44>")
	)
	(segment
		(start 254.329184 -28.541472)
		(end 256.101596 -29.272484)
		(width 0.1651)
		(layer "In11.Cu")
		(net "P5E_PEX2_STN2_TX_DN<44>")
	)
	(segment
		(start 279.165812 -271.427448)
		(end 279.120092 -271.473168)
		(width 0.1143)
		(layer "In11.Cu")
		(net "P5E_PEX2_STN2_TX_DN<44>")
	)
	(segment
		(start 271.017238 -145.385282)
		(end 278.275796 -264.583164)
		(width 0.1651)
		(layer "In11.Cu")
		(net "P5E_PEX2_STN2_TX_DN<44>")
	)
	(segment
		(start 251.750576 -28.496006)
		(end 251.860558 -28.541472)
		(width 0.1651)
		(layer "In11.Cu")
		(net "P5E_PEX2_STN2_TX_DN<44>")
	)
	(segment
		(start 279.120092 -280.025856)
		(end 279.223724 -280.129488)
		(width 0.1143)
		(layer "In11.Cu")
		(net "P5E_PEX2_STN2_TX_DN<44>")
	)
	(segment
		(start 279.165812 -270.72717)
		(end 279.165812 -271.399)
		(width 0.1651)
		(layer "In11.Cu")
		(net "P5E_PEX2_STN2_TX_DN<44>")
	)
	(segment
		(start 271.587722 -62.131194)
		(end 271.9451 -135.970264)
		(width 0.1651)
		(layer "In11.Cu")
		(net "P5E_PEX2_STN2_TX_DN<44>")
	)
	(segment
		(start 279.223724 -280.129488)
		(end 279.385522 -280.129488)
		(width 0.1143)
		(layer "In11.Cu")
		(net "P5E_PEX2_STN2_TX_DN<44>")
	)
	(segment
		(start 256.101596 -29.272484)
		(end 268.127734 -44.445428)
		(width 0.1651)
		(layer "In11.Cu")
		(net "P5E_PEX2_STN2_TX_DN<44>")
	)
	(segment
		(start 270.138398 -48.143668)
		(end 270.886428 -50.356516)
		(width 0.1651)
		(layer "In11.Cu")
		(net "P5E_PEX2_STN2_TX_DN<44>")
	)
	(segment
		(start 270.886428 -50.356516)
		(end 271.587722 -62.131194)
		(width 0.1651)
		(layer "In11.Cu")
		(net "P5E_PEX2_STN2_TX_DN<44>")
	)
	(segment
		(start 396.353792 -348.879922)
		(end 396.05966 -348.58579)
		(width 0.13462)
		(layer "F.Cu")
		(net "P5E_PEX3_STN5_TX_DP<84>")
	)
	(segment
		(start 396.353792 -349.512382)
		(end 396.353792 -348.879922)
		(width 0.13462)
		(layer "F.Cu")
		(net "P5E_PEX3_STN5_TX_DP<84>")
	)
	(segment
		(start 396.03426 -349.831914)
		(end 396.353792 -349.512382)
		(width 0.13462)
		(layer "F.Cu")
		(net "P5E_PEX3_STN5_TX_DP<84>")
	)
	(segment
		(start 410.183838 -319.960752)
		(end 410.229558 -319.915032)
		(width 0.1143)
		(layer "In7.Cu")
		(net "P5E_PEX3_STN5_TX_DP<84>")
	)
	(segment
		(start 397.90497 -341.4014)
		(end 402.817838 -334.964786)
		(width 0.1651)
		(layer "In7.Cu")
		(net "P5E_PEX3_STN5_TX_DP<84>")
	)
	(segment
		(start 396.35049 -348.29496)
		(end 396.35049 -347.667834)
		(width 0.1651)
		(layer "In7.Cu")
		(net "P5E_PEX3_STN5_TX_DP<84>")
	)
	(segment
		(start 410.229558 -319.915032)
		(end 410.229558 -311.705498)
		(width 0.1143)
		(layer "In7.Cu")
		(net "P5E_PEX3_STN5_TX_DP<84>")
	)
	(segment
		(start 402.817838 -334.964786)
		(end 402.818346 -334.965294)
		(width 0.1651)
		(layer "In7.Cu")
		(net "P5E_PEX3_STN5_TX_DP<84>")
	)
	(segment
		(start 410.183838 -319.9892)
		(end 410.183838 -319.960752)
		(width 0.1143)
		(layer "In7.Cu")
		(net "P5E_PEX3_STN5_TX_DP<84>")
	)
	(segment
		(start 407.667968 -328.611992)
		(end 409.268676 -326.216518)
		(width 0.1651)
		(layer "In7.Cu")
		(net "P5E_PEX3_STN5_TX_DP<84>")
	)
	(segment
		(start 410.685488 -311.479692)
		(end 410.799788 -311.365392)
		(width 0.1143)
		(layer "In7.Cu")
		(net "P5E_PEX3_STN5_TX_DP<84>")
	)
	(segment
		(start 402.818346 -334.965294)
		(end 407.667968 -328.611992)
		(width 0.1651)
		(layer "In7.Cu")
		(net "P5E_PEX3_STN5_TX_DP<84>")
	)
	(segment
		(start 410.799788 -311.365392)
		(end 410.799788 -311.099962)
		(width 0.1143)
		(layer "In7.Cu")
		(net "P5E_PEX3_STN5_TX_DP<84>")
	)
	(segment
		(start 396.05966 -348.58579)
		(end 396.35049 -348.29496)
		(width 0.1651)
		(layer "In7.Cu")
		(net "P5E_PEX3_STN5_TX_DP<84>")
	)
	(segment
		(start 397.90497 -346.113354)
		(end 397.90497 -341.4014)
		(width 0.1651)
		(layer "In7.Cu")
		(net "P5E_PEX3_STN5_TX_DP<84>")
	)
	(segment
		(start 396.35049 -347.667834)
		(end 397.90497 -346.113354)
		(width 0.1651)
		(layer "In7.Cu")
		(net "P5E_PEX3_STN5_TX_DP<84>")
	)
	(segment
		(start 409.268676 -326.216518)
		(end 410.183838 -324.007226)
		(width 0.1651)
		(layer "In7.Cu")
		(net "P5E_PEX3_STN5_TX_DP<84>")
	)
	(segment
		(start 410.183838 -324.007226)
		(end 410.183838 -319.9892)
		(width 0.1651)
		(layer "In7.Cu")
		(net "P5E_PEX3_STN5_TX_DP<84>")
	)
	(segment
		(start 410.455364 -311.479692)
		(end 410.685488 -311.479692)
		(width 0.1143)
		(layer "In7.Cu")
		(net "P5E_PEX3_STN5_TX_DP<84>")
	)
	(segment
		(start 410.229558 -311.705498)
		(end 410.455364 -311.479692)
		(width 0.1143)
		(layer "In7.Cu")
		(net "P5E_PEX3_STN5_TX_DP<84>")
	)
	(segment
		(start 422.299384 -355.02723)
		(end 422.594532 -354.732082)
		(width 0.13462)
		(layer "F.Cu")
		(net "P5E_PEX3_STN7_TX_DN<118>")
	)
	(segment
		(start 422.619932 -355.978206)
		(end 422.299384 -355.657658)
		(width 0.13462)
		(layer "F.Cu")
		(net "P5E_PEX3_STN7_TX_DN<118>")
	)
	(segment
		(start 422.299384 -355.657658)
		(end 422.299384 -355.02723)
		(width 0.13462)
		(layer "F.Cu")
		(net "P5E_PEX3_STN7_TX_DN<118>")
	)
	(segment
		(start 390.165336 -307.299868)
		(end 389.899906 -307.299868)
		(width 0.1143)
		(layer "In11.Cu")
		(net "P5E_PEX3_STN7_TX_DN<118>")
	)
	(segment
		(start 374.792748 -314.073032)
		(end 374.936512 -314.073032)
		(width 0.1651)
		(layer "In11.Cu")
		(net "P5E_PEX3_STN7_TX_DN<118>")
	)
	(segment
		(start 378.751592 -310.257952)
		(end 379.102112 -309.907432)
		(width 0.1651)
		(layer "In11.Cu")
		(net "P5E_PEX3_STN7_TX_DN<118>")
	)
	(segment
		(start 380.440184 -308.56936)
		(end 380.790704 -308.21884)
		(width 0.1651)
		(layer "In11.Cu")
		(net "P5E_PEX3_STN7_TX_DN<118>")
	)
	(segment
		(start 370.8654 -322.123562)
		(end 370.8654 -319.42278)
		(width 0.1651)
		(layer "In11.Cu")
		(net "P5E_PEX3_STN7_TX_DN<118>")
	)
	(segment
		(start 376.131328 -312.878216)
		(end 376.131328 -312.734452)
		(width 0.1651)
		(layer "In11.Cu")
		(net "P5E_PEX3_STN7_TX_DN<118>")
	)
	(segment
		(start 371.944392 -324.728586)
		(end 370.8654 -322.123562)
		(width 0.1651)
		(layer "In11.Cu")
		(net "P5E_PEX3_STN7_TX_DN<118>")
	)
	(segment
		(start 381.140716 -307.725064)
		(end 382.973326 -306.965858)
		(width 0.1651)
		(layer "In11.Cu")
		(net "P5E_PEX3_STN7_TX_DN<118>")
	)
	(segment
		(start 390.279636 -307.185568)
		(end 390.165336 -307.299868)
		(width 0.1143)
		(layer "In11.Cu")
		(net "P5E_PEX3_STN7_TX_DN<118>")
	)
	(segment
		(start 376.48134 -312.38444)
		(end 376.625104 -312.38444)
		(width 0.1651)
		(layer "In11.Cu")
		(net "P5E_PEX3_STN7_TX_DN<118>")
	)
	(segment
		(start 377.4694 -311.540144)
		(end 377.81992 -311.189624)
		(width 0.1651)
		(layer "In11.Cu")
		(net "P5E_PEX3_STN7_TX_DN<118>")
	)
	(segment
		(start 383.921 -306.965858)
		(end 383.949448 -306.965858)
		(width 0.1143)
		(layer "In11.Cu")
		(net "P5E_PEX3_STN7_TX_DN<118>")
	)
	(segment
		(start 376.625104 -312.38444)
		(end 376.975624 -312.03392)
		(width 0.1651)
		(layer "In11.Cu")
		(net "P5E_PEX3_STN7_TX_DN<118>")
	)
	(segment
		(start 370.8654 -319.42278)
		(end 371.17655 -318.671448)
		(width 0.1651)
		(layer "In11.Cu")
		(net "P5E_PEX3_STN7_TX_DN<118>")
	)
	(segment
		(start 422.8592 -339.725)
		(end 419.381178 -337.29676)
		(width 0.1651)
		(layer "In11.Cu")
		(net "P5E_PEX3_STN7_TX_DN<118>")
	)
	(segment
		(start 378.607828 -310.257952)
		(end 378.751592 -310.257952)
		(width 0.1651)
		(layer "In11.Cu")
		(net "P5E_PEX3_STN7_TX_DN<118>")
	)
	(segment
		(start 380.790704 -308.075076)
		(end 381.140716 -307.725064)
		(width 0.1651)
		(layer "In11.Cu")
		(net "P5E_PEX3_STN7_TX_DN<118>")
	)
	(segment
		(start 376.975624 -311.890156)
		(end 377.325636 -311.540144)
		(width 0.1651)
		(layer "In11.Cu")
		(net "P5E_PEX3_STN7_TX_DN<118>")
	)
	(segment
		(start 375.637044 -313.228736)
		(end 375.780808 -313.228736)
		(width 0.1651)
		(layer "In11.Cu")
		(net "P5E_PEX3_STN7_TX_DN<118>")
	)
	(segment
		(start 423.858182 -352.376486)
		(end 423.858182 -341.6808)
		(width 0.1651)
		(layer "In11.Cu")
		(net "P5E_PEX3_STN7_TX_DN<118>")
	)
	(segment
		(start 376.975624 -312.03392)
		(end 376.975624 -311.890156)
		(width 0.1651)
		(layer "In11.Cu")
		(net "P5E_PEX3_STN7_TX_DN<118>")
	)
	(segment
		(start 377.81992 -311.189624)
		(end 377.81992 -311.04586)
		(width 0.1651)
		(layer "In11.Cu")
		(net "P5E_PEX3_STN7_TX_DN<118>")
	)
	(segment
		(start 375.287032 -313.578748)
		(end 375.637044 -313.228736)
		(width 0.1651)
		(layer "In11.Cu")
		(net "P5E_PEX3_STN7_TX_DN<118>")
	)
	(segment
		(start 379.595888 -309.413656)
		(end 379.946408 -309.063136)
		(width 0.1651)
		(layer "In11.Cu")
		(net "P5E_PEX3_STN7_TX_DN<118>")
	)
	(segment
		(start 380.29642 -308.56936)
		(end 380.440184 -308.56936)
		(width 0.1651)
		(layer "In11.Cu")
		(net "P5E_PEX3_STN7_TX_DN<118>")
	)
	(segment
		(start 422.594532 -354.732082)
		(end 422.303702 -354.441252)
		(width 0.1651)
		(layer "In11.Cu")
		(net "P5E_PEX3_STN7_TX_DN<118>")
	)
	(segment
		(start 374.936512 -314.073032)
		(end 375.287032 -313.722512)
		(width 0.1651)
		(layer "In11.Cu")
		(net "P5E_PEX3_STN7_TX_DN<118>")
	)
	(segment
		(start 422.303702 -353.930966)
		(end 423.858182 -352.376486)
		(width 0.1651)
		(layer "In11.Cu")
		(net "P5E_PEX3_STN7_TX_DN<118>")
	)
	(segment
		(start 371.17655 -318.671448)
		(end 373.154702 -315.711078)
		(width 0.1651)
		(layer "In11.Cu")
		(net "P5E_PEX3_STN7_TX_DN<118>")
	)
	(segment
		(start 376.131328 -312.734452)
		(end 376.48134 -312.38444)
		(width 0.1651)
		(layer "In11.Cu")
		(net "P5E_PEX3_STN7_TX_DN<118>")
	)
	(segment
		(start 380.790704 -308.21884)
		(end 380.790704 -308.075076)
		(width 0.1651)
		(layer "In11.Cu")
		(net "P5E_PEX3_STN7_TX_DN<118>")
	)
	(segment
		(start 383.949448 -306.965858)
		(end 383.995168 -306.920138)
		(width 0.1143)
		(layer "In11.Cu")
		(net "P5E_PEX3_STN7_TX_DN<118>")
	)
	(segment
		(start 379.946408 -308.919372)
		(end 380.29642 -308.56936)
		(width 0.1651)
		(layer "In11.Cu")
		(net "P5E_PEX3_STN7_TX_DN<118>")
	)
	(segment
		(start 375.287032 -313.722512)
		(end 375.287032 -313.578748)
		(width 0.1651)
		(layer "In11.Cu")
		(net "P5E_PEX3_STN7_TX_DN<118>")
	)
	(segment
		(start 390.279636 -307.02377)
		(end 390.279636 -307.185568)
		(width 0.1143)
		(layer "In11.Cu")
		(net "P5E_PEX3_STN7_TX_DN<118>")
	)
	(segment
		(start 377.81992 -311.04586)
		(end 378.607828 -310.257952)
		(width 0.1651)
		(layer "In11.Cu")
		(net "P5E_PEX3_STN7_TX_DN<118>")
	)
	(segment
		(start 373.154702 -315.711078)
		(end 374.792748 -314.073032)
		(width 0.1651)
		(layer "In11.Cu")
		(net "P5E_PEX3_STN7_TX_DN<118>")
	)
	(segment
		(start 379.452124 -309.413656)
		(end 379.595888 -309.413656)
		(width 0.1651)
		(layer "In11.Cu")
		(net "P5E_PEX3_STN7_TX_DN<118>")
	)
	(segment
		(start 419.381178 -337.29676)
		(end 375.77522 -327.464674)
		(width 0.1651)
		(layer "In11.Cu")
		(net "P5E_PEX3_STN7_TX_DN<118>")
	)
	(segment
		(start 423.858182 -341.6808)
		(end 422.8592 -339.725)
		(width 0.1651)
		(layer "In11.Cu")
		(net "P5E_PEX3_STN7_TX_DN<118>")
	)
	(segment
		(start 377.325636 -311.540144)
		(end 377.4694 -311.540144)
		(width 0.1651)
		(layer "In11.Cu")
		(net "P5E_PEX3_STN7_TX_DN<118>")
	)
	(segment
		(start 375.77522 -327.464674)
		(end 373.337328 -326.121522)
		(width 0.1651)
		(layer "In11.Cu")
		(net "P5E_PEX3_STN7_TX_DN<118>")
	)
	(segment
		(start 379.102112 -309.907432)
		(end 379.102112 -309.763668)
		(width 0.1651)
		(layer "In11.Cu")
		(net "P5E_PEX3_STN7_TX_DN<118>")
	)
	(segment
		(start 379.946408 -309.063136)
		(end 379.946408 -308.919372)
		(width 0.1651)
		(layer "In11.Cu")
		(net "P5E_PEX3_STN7_TX_DN<118>")
	)
	(segment
		(start 422.303702 -354.441252)
		(end 422.303702 -353.930966)
		(width 0.1651)
		(layer "In11.Cu")
		(net "P5E_PEX3_STN7_TX_DN<118>")
	)
	(segment
		(start 390.176004 -306.920138)
		(end 390.279636 -307.02377)
		(width 0.1143)
		(layer "In11.Cu")
		(net "P5E_PEX3_STN7_TX_DN<118>")
	)
	(segment
		(start 383.995168 -306.920138)
		(end 390.176004 -306.920138)
		(width 0.1143)
		(layer "In11.Cu")
		(net "P5E_PEX3_STN7_TX_DN<118>")
	)
	(segment
		(start 382.973326 -306.965858)
		(end 383.921 -306.965858)
		(width 0.1651)
		(layer "In11.Cu")
		(net "P5E_PEX3_STN7_TX_DN<118>")
	)
	(segment
		(start 373.337328 -326.121522)
		(end 371.944392 -324.728586)
		(width 0.1651)
		(layer "In11.Cu")
		(net "P5E_PEX3_STN7_TX_DN<118>")
	)
	(segment
		(start 375.780808 -313.228736)
		(end 376.131328 -312.878216)
		(width 0.1651)
		(layer "In11.Cu")
		(net "P5E_PEX3_STN7_TX_DN<118>")
	)
	(segment
		(start 379.102112 -309.763668)
		(end 379.452124 -309.413656)
		(width 0.1651)
		(layer "In11.Cu")
		(net "P5E_PEX3_STN7_TX_DN<118>")
	)
	(segment
		(start 61.346842 -343.685622)
		(end 61.666882 -343.365582)
		(width 0.13462)
		(layer "F.Cu")
		(net "P5E_PEX0_STN6_TX_DP<111>")
	)
	(segment
		(start 61.666882 -343.365582)
		(end 61.666882 -342.734138)
		(width 0.13462)
		(layer "F.Cu")
		(net "P5E_PEX0_STN6_TX_DP<111>")
	)
	(segment
		(start 61.666882 -342.734138)
		(end 61.372242 -342.439498)
		(width 0.13462)
		(layer "F.Cu")
		(net "P5E_PEX0_STN6_TX_DP<111>")
	)
	(segment
		(start 49.200308 -333.716122)
		(end 44.72305 -329.23861)
		(width 0.1651)
		(layer "In13.Cu")
		(net "P5E_PEX0_STN6_TX_DP<111>")
	)
	(segment
		(start 42.883836 -320.158872)
		(end 42.929556 -320.113152)
		(width 0.1143)
		(layer "In13.Cu")
		(net "P5E_PEX0_STN6_TX_DP<111>")
	)
	(segment
		(start 61.663072 -342.148668)
		(end 61.663072 -341.2998)
		(width 0.1651)
		(layer "In13.Cu")
		(net "P5E_PEX0_STN6_TX_DP<111>")
	)
	(segment
		(start 42.883836 -324.798436)
		(end 42.883836 -320.18097)
		(width 0.1651)
		(layer "In13.Cu")
		(net "P5E_PEX0_STN6_TX_DP<111>")
	)
	(segment
		(start 42.929556 -320.113152)
		(end 42.929556 -311.730644)
		(width 0.1143)
		(layer "In13.Cu")
		(net "P5E_PEX0_STN6_TX_DP<111>")
	)
	(segment
		(start 42.929556 -311.730644)
		(end 43.180508 -311.479692)
		(width 0.1143)
		(layer "In13.Cu")
		(net "P5E_PEX0_STN6_TX_DP<111>")
	)
	(segment
		(start 43.180508 -311.479692)
		(end 43.410886 -311.479692)
		(width 0.1143)
		(layer "In13.Cu")
		(net "P5E_PEX0_STN6_TX_DP<111>")
	)
	(segment
		(start 61.663072 -341.2998)
		(end 54.764432 -336.690462)
		(width 0.1651)
		(layer "In13.Cu")
		(net "P5E_PEX0_STN6_TX_DP<111>")
	)
	(segment
		(start 43.410886 -311.479692)
		(end 43.499786 -311.390792)
		(width 0.1143)
		(layer "In13.Cu")
		(net "P5E_PEX0_STN6_TX_DP<111>")
	)
	(segment
		(start 44.72305 -329.23861)
		(end 42.883836 -324.798436)
		(width 0.1651)
		(layer "In13.Cu")
		(net "P5E_PEX0_STN6_TX_DP<111>")
	)
	(segment
		(start 61.372242 -342.439498)
		(end 61.663072 -342.148668)
		(width 0.1651)
		(layer "In13.Cu")
		(net "P5E_PEX0_STN6_TX_DP<111>")
	)
	(segment
		(start 54.764432 -336.690462)
		(end 49.200308 -333.716122)
		(width 0.1651)
		(layer "In13.Cu")
		(net "P5E_PEX0_STN6_TX_DP<111>")
	)
	(segment
		(start 42.883836 -320.18097)
		(end 42.883836 -320.158872)
		(width 0.1143)
		(layer "In13.Cu")
		(net "P5E_PEX0_STN6_TX_DP<111>")
	)
	(segment
		(start 43.499786 -311.390792)
		(end 43.499786 -311.099962)
		(width 0.1143)
		(layer "In13.Cu")
		(net "P5E_PEX0_STN6_TX_DP<111>")
	)
	(segment
		(start 174.564294 -139.6238)
		(end 174.564294 -140.6398)
		(width 0.13208)
		(layer "F.Cu")
		(net "RST_SMB_NIC2_MUX_ISO_N")
	)
	(segment
		(start 174.564294 -141.6558)
		(end 174.564294 -142.57655)
		(width 0.13208)
		(layer "F.Cu")
		(net "RST_SMB_NIC2_MUX_ISO_N")
	)
	(segment
		(start 174.564294 -140.6398)
		(end 174.564294 -141.6558)
		(width 0.13208)
		(layer "F.Cu")
		(net "RST_SMB_NIC2_MUX_ISO_N")
	)
	(segment
		(start 174.564294 -142.57655)
		(end 172.868844 -144.272)
		(width 0.13208)
		(layer "F.Cu")
		(net "RST_SMB_NIC2_MUX_ISO_N")
	)
	(via
		(at 172.868844 -144.272)
		(size 0.508)
		(drill 0.254)
		(layers "F.Cu" "B.Cu")
		(net "RST_SMB_NIC2_MUX_ISO_N")
	)
	(segment
		(start 171.864528 -143.267684)
		(end 171.864528 -141.6812)
		(width 0.13208)
		(layer "B.Cu")
		(net "RST_SMB_NIC2_MUX_ISO_N")
	)
	(segment
		(start 172.868844 -144.272)
		(end 171.864528 -143.267684)
		(width 0.13208)
		(layer "B.Cu")
		(net "RST_SMB_NIC2_MUX_ISO_N")
	)
	(segment
		(start 64.775842 -343.365582)
		(end 64.775842 -342.734138)
		(width 0.13462)
		(layer "F.Cu")
		(net "P5E_PEX0_STN5_TX_DP<81>")
	)
	(segment
		(start 64.775842 -342.734138)
		(end 64.481202 -342.439498)
		(width 0.13462)
		(layer "F.Cu")
		(net "P5E_PEX0_STN5_TX_DP<81>")
	)
	(segment
		(start 64.455802 -343.685622)
		(end 64.775842 -343.365582)
		(width 0.13462)
		(layer "F.Cu")
		(net "P5E_PEX0_STN5_TX_DP<81>")
	)
	(segment
		(start 64.772032 -339.433408)
		(end 59.033918 -325.582026)
		(width 0.1651)
		(layer "In7.Cu")
		(net "P5E_PEX0_STN5_TX_DP<81>")
	)
	(segment
		(start 59.535568 -313.379612)
		(end 59.649868 -313.265312)
		(width 0.1143)
		(layer "In7.Cu")
		(net "P5E_PEX0_STN5_TX_DP<81>")
	)
	(segment
		(start 59.079638 -319.81648)
		(end 59.079638 -313.605418)
		(width 0.1143)
		(layer "In7.Cu")
		(net "P5E_PEX0_STN5_TX_DP<81>")
	)
	(segment
		(start 59.033918 -325.582026)
		(end 59.033918 -319.890648)
		(width 0.1651)
		(layer "In7.Cu")
		(net "P5E_PEX0_STN5_TX_DP<81>")
	)
	(segment
		(start 59.033918 -319.890648)
		(end 59.033918 -319.8622)
		(width 0.1143)
		(layer "In7.Cu")
		(net "P5E_PEX0_STN5_TX_DP<81>")
	)
	(segment
		(start 59.079638 -313.605418)
		(end 59.305444 -313.379612)
		(width 0.1143)
		(layer "In7.Cu")
		(net "P5E_PEX0_STN5_TX_DP<81>")
	)
	(segment
		(start 59.305444 -313.379612)
		(end 59.535568 -313.379612)
		(width 0.1143)
		(layer "In7.Cu")
		(net "P5E_PEX0_STN5_TX_DP<81>")
	)
	(segment
		(start 64.481202 -342.439498)
		(end 64.772032 -342.148668)
		(width 0.1651)
		(layer "In7.Cu")
		(net "P5E_PEX0_STN5_TX_DP<81>")
	)
	(segment
		(start 59.649868 -313.265312)
		(end 59.649868 -312.999882)
		(width 0.1143)
		(layer "In7.Cu")
		(net "P5E_PEX0_STN5_TX_DP<81>")
	)
	(segment
		(start 59.033918 -319.8622)
		(end 59.079638 -319.81648)
		(width 0.1143)
		(layer "In7.Cu")
		(net "P5E_PEX0_STN5_TX_DP<81>")
	)
	(segment
		(start 64.772032 -342.148668)
		(end 64.772032 -339.433408)
		(width 0.1651)
		(layer "In7.Cu")
		(net "P5E_PEX0_STN5_TX_DP<81>")
	)
	(segment
		(start 329.201272 -32.4104)
		(end 328.588116 -32.4104)
		(width 0.13462)
		(layer "F.Cu")
		(net "P5E_PEX2_STN2_TX_DP<34>")
	)
	(segment
		(start 329.505056 -32.714184)
		(end 329.201272 -32.4104)
		(width 0.13462)
		(layer "F.Cu")
		(net "P5E_PEX2_STN2_TX_DP<34>")
	)
	(segment
		(start 328.588116 -32.4104)
		(end 328.258932 -32.739584)
		(width 0.13462)
		(layer "F.Cu")
		(net "P5E_PEX2_STN2_TX_DP<34>")
	)
	(segment
		(start 334.643476 -34.038286)
		(end 333.045308 -32.423354)
		(width 0.1651)
		(layer "In11.Cu")
		(net "P5E_PEX2_STN2_TX_DP<34>")
	)
	(segment
		(start 332.031594 -32.423354)
		(end 331.917294 -32.537654)
		(width 0.1651)
		(layer "In11.Cu")
		(net "P5E_PEX2_STN2_TX_DP<34>")
	)
	(segment
		(start 311.12968 -111.806228)
		(end 311.129934 -111.806228)
		(width 0.1651)
		(layer "In11.Cu")
		(net "P5E_PEX2_STN2_TX_DP<34>")
	)
	(segment
		(start 318.945006 -92.873068)
		(end 325.937626 -80.550258)
		(width 0.1651)
		(layer "In11.Cu")
		(net "P5E_PEX2_STN2_TX_DP<34>")
	)
	(segment
		(start 334.96504 -74.293984)
		(end 337.170268 -68.191126)
		(width 0.1651)
		(layer "In11.Cu")
		(net "P5E_PEX2_STN2_TX_DP<34>")
	)
	(segment
		(start 288.999676 -280.434288)
		(end 288.885376 -280.319988)
		(width 0.1143)
		(layer "In11.Cu")
		(net "P5E_PEX2_STN2_TX_DP<34>")
	)
	(segment
		(start 333.045308 -32.423354)
		(end 332.031594 -32.423354)
		(width 0.1651)
		(layer "In11.Cu")
		(net "P5E_PEX2_STN2_TX_DP<34>")
	)
	(segment
		(start 331.917294 -32.537654)
		(end 331.421994 -32.537654)
		(width 0.1651)
		(layer "In11.Cu")
		(net "P5E_PEX2_STN2_TX_DP<34>")
	)
	(segment
		(start 337.170268 -68.191126)
		(end 339.378036 -56.729376)
		(width 0.1651)
		(layer "In11.Cu")
		(net "P5E_PEX2_STN2_TX_DP<34>")
	)
	(segment
		(start 307.553106 -161.396426)
		(end 308.970172 -149.389084)
		(width 0.1651)
		(layer "In11.Cu")
		(net "P5E_PEX2_STN2_TX_DP<34>")
	)
	(segment
		(start 288.383726 -265.641074)
		(end 307.553106 -161.396426)
		(width 0.1651)
		(layer "In11.Cu")
		(net "P5E_PEX2_STN2_TX_DP<34>")
	)
	(segment
		(start 309.298848 -141.845284)
		(end 309.705756 -140.100304)
		(width 0.1651)
		(layer "In11.Cu")
		(net "P5E_PEX2_STN2_TX_DP<34>")
	)
	(segment
		(start 318.944752 -92.873068)
		(end 318.945006 -92.873068)
		(width 0.1651)
		(layer "In11.Cu")
		(net "P5E_PEX2_STN2_TX_DP<34>")
	)
	(segment
		(start 329.795886 -32.423354)
		(end 329.505056 -32.714184)
		(width 0.1651)
		(layer "In11.Cu")
		(net "P5E_PEX2_STN2_TX_DP<34>")
	)
	(segment
		(start 288.383726 -271.427448)
		(end 288.383726 -271.399)
		(width 0.1143)
		(layer "In11.Cu")
		(net "P5E_PEX2_STN2_TX_DP<34>")
	)
	(segment
		(start 309.705756 -132.507228)
		(end 310.321706 -118.35638)
		(width 0.1651)
		(layer "In11.Cu")
		(net "P5E_PEX2_STN2_TX_DP<34>")
	)
	(segment
		(start 288.999676 -280.699718)
		(end 288.999676 -280.434288)
		(width 0.1143)
		(layer "In11.Cu")
		(net "P5E_PEX2_STN2_TX_DP<34>")
	)
	(segment
		(start 327.943464 -78.546452)
		(end 334.434688 -75.047094)
		(width 0.1651)
		(layer "In11.Cu")
		(net "P5E_PEX2_STN2_TX_DP<34>")
	)
	(segment
		(start 309.705756 -140.100304)
		(end 309.705756 -132.507228)
		(width 0.1651)
		(layer "In11.Cu")
		(net "P5E_PEX2_STN2_TX_DP<34>")
	)
	(segment
		(start 331.421994 -32.537654)
		(end 331.307694 -32.423354)
		(width 0.1651)
		(layer "In11.Cu")
		(net "P5E_PEX2_STN2_TX_DP<34>")
	)
	(segment
		(start 288.429446 -271.473168)
		(end 288.383726 -271.427448)
		(width 0.1143)
		(layer "In11.Cu")
		(net "P5E_PEX2_STN2_TX_DP<34>")
	)
	(segment
		(start 331.307694 -32.423354)
		(end 329.795886 -32.423354)
		(width 0.1651)
		(layer "In11.Cu")
		(net "P5E_PEX2_STN2_TX_DP<34>")
	)
	(segment
		(start 288.644584 -280.319988)
		(end 288.429446 -280.10485)
		(width 0.1143)
		(layer "In11.Cu")
		(net "P5E_PEX2_STN2_TX_DP<34>")
	)
	(segment
		(start 339.127846 -42.691304)
		(end 338.916518 -41.890696)
		(width 0.1651)
		(layer "In11.Cu")
		(net "P5E_PEX2_STN2_TX_DP<34>")
	)
	(segment
		(start 288.429446 -280.10485)
		(end 288.429446 -271.473168)
		(width 0.1143)
		(layer "In11.Cu")
		(net "P5E_PEX2_STN2_TX_DP<34>")
	)
	(segment
		(start 311.129934 -111.806228)
		(end 311.94375 -105.211118)
		(width 0.1651)
		(layer "In11.Cu")
		(net "P5E_PEX2_STN2_TX_DP<34>")
	)
	(segment
		(start 308.970172 -149.389084)
		(end 309.298848 -141.845284)
		(width 0.1651)
		(layer "In11.Cu")
		(net "P5E_PEX2_STN2_TX_DP<34>")
	)
	(segment
		(start 310.321706 -118.35638)
		(end 311.12968 -111.806228)
		(width 0.1651)
		(layer "In11.Cu")
		(net "P5E_PEX2_STN2_TX_DP<34>")
	)
	(segment
		(start 325.937626 -80.550258)
		(end 327.943464 -78.546452)
		(width 0.1651)
		(layer "In11.Cu")
		(net "P5E_PEX2_STN2_TX_DP<34>")
	)
	(segment
		(start 288.383726 -271.399)
		(end 288.383726 -265.641074)
		(width 0.1651)
		(layer "In11.Cu")
		(net "P5E_PEX2_STN2_TX_DP<34>")
	)
	(segment
		(start 311.94375 -105.211118)
		(end 318.944752 -92.873068)
		(width 0.1651)
		(layer "In11.Cu")
		(net "P5E_PEX2_STN2_TX_DP<34>")
	)
	(segment
		(start 334.434688 -75.047094)
		(end 334.96504 -74.293984)
		(width 0.1651)
		(layer "In11.Cu")
		(net "P5E_PEX2_STN2_TX_DP<34>")
	)
	(segment
		(start 288.885376 -280.319988)
		(end 288.644584 -280.319988)
		(width 0.1143)
		(layer "In11.Cu")
		(net "P5E_PEX2_STN2_TX_DP<34>")
	)
	(segment
		(start 338.916518 -41.890696)
		(end 334.643476 -34.038286)
		(width 0.1651)
		(layer "In11.Cu")
		(net "P5E_PEX2_STN2_TX_DP<34>")
	)
	(segment
		(start 339.378036 -56.729376)
		(end 339.127846 -42.691304)
		(width 0.1651)
		(layer "In11.Cu")
		(net "P5E_PEX2_STN2_TX_DP<34>")
	)
	(segment
		(start 444.683388 -28.5496)
		(end 444.35903 -28.225242)
		(width 0.13462)
		(layer "F.Cu")
		(net "P5E_PEX3_STN2_TX_DN<32>")
	)
	(segment
		(start 445.605154 -28.250642)
		(end 445.306196 -28.5496)
		(width 0.13462)
		(layer "F.Cu")
		(net "P5E_PEX3_STN2_TX_DN<32>")
	)
	(segment
		(start 445.306196 -28.5496)
		(end 444.683388 -28.5496)
		(width 0.13462)
		(layer "F.Cu")
		(net "P5E_PEX3_STN2_TX_DN<32>")
	)
	(segment
		(start 406.665938 -271.399)
		(end 406.665938 -271.427448)
		(width 0.1143)
		(layer "In11.Cu")
		(net "P5E_PEX3_STN2_TX_DN<32>")
	)
	(segment
		(start 427.735492 -141.928088)
		(end 427.55058 -146.260566)
		(width 0.1651)
		(layer "In11.Cu")
		(net "P5E_PEX3_STN2_TX_DN<32>")
	)
	(segment
		(start 452.031608 -76.754482)
		(end 445.381634 -80.362044)
		(width 0.1651)
		(layer "In11.Cu")
		(net "P5E_PEX3_STN2_TX_DN<32>")
	)
	(segment
		(start 406.620218 -271.473168)
		(end 406.620218 -280.025856)
		(width 0.1143)
		(layer "In11.Cu")
		(net "P5E_PEX3_STN2_TX_DN<32>")
	)
	(segment
		(start 406.665938 -271.427448)
		(end 406.620218 -271.473168)
		(width 0.1143)
		(layer "In11.Cu")
		(net "P5E_PEX3_STN2_TX_DN<32>")
	)
	(segment
		(start 452.993506 -75.5142)
		(end 452.031608 -76.754482)
		(width 0.1651)
		(layer "In11.Cu")
		(net "P5E_PEX3_STN2_TX_DN<32>")
	)
	(segment
		(start 430.240948 -106.033316)
		(end 428.756318 -117.98173)
		(width 0.1651)
		(layer "In11.Cu")
		(net "P5E_PEX3_STN2_TX_DN<32>")
	)
	(segment
		(start 445.381634 -80.362044)
		(end 443.75832 -81.985358)
		(width 0.1651)
		(layer "In11.Cu")
		(net "P5E_PEX3_STN2_TX_DN<32>")
	)
	(segment
		(start 406.665938 -266.089638)
		(end 406.665938 -271.399)
		(width 0.1651)
		(layer "In11.Cu")
		(net "P5E_PEX3_STN2_TX_DN<32>")
	)
	(segment
		(start 406.620218 -280.025856)
		(end 406.72385 -280.129488)
		(width 0.1143)
		(layer "In11.Cu")
		(net "P5E_PEX3_STN2_TX_DN<32>")
	)
	(segment
		(start 456.731878 -39.806626)
		(end 457.43368 -42.446194)
		(width 0.1651)
		(layer "In11.Cu")
		(net "P5E_PEX3_STN2_TX_DN<32>")
	)
	(segment
		(start 443.75832 -81.985358)
		(end 430.240948 -106.033316)
		(width 0.1651)
		(layer "In11.Cu")
		(net "P5E_PEX3_STN2_TX_DN<32>")
	)
	(segment
		(start 406.885648 -280.129488)
		(end 406.999948 -280.015188)
		(width 0.1143)
		(layer "In11.Cu")
		(net "P5E_PEX3_STN2_TX_DN<32>")
	)
	(segment
		(start 406.999948 -280.015188)
		(end 406.999948 -279.749504)
		(width 0.1143)
		(layer "In11.Cu")
		(net "P5E_PEX3_STN2_TX_DN<32>")
	)
	(segment
		(start 455.413364 -68.765928)
		(end 452.993506 -75.5142)
		(width 0.1651)
		(layer "In11.Cu")
		(net "P5E_PEX3_STN2_TX_DN<32>")
	)
	(segment
		(start 446.066164 -28.541472)
		(end 447.713862 -28.541472)
		(width 0.1651)
		(layer "In11.Cu")
		(net "P5E_PEX3_STN2_TX_DN<32>")
	)
	(segment
		(start 428.756318 -117.98173)
		(end 427.997874 -135.769604)
		(width 0.1651)
		(layer "In11.Cu")
		(net "P5E_PEX3_STN2_TX_DN<32>")
	)
	(segment
		(start 425.970192 -161.05886)
		(end 406.665938 -266.089638)
		(width 0.1651)
		(layer "In11.Cu")
		(net "P5E_PEX3_STN2_TX_DN<32>")
	)
	(segment
		(start 447.713862 -28.541472)
		(end 450.111876 -29.49448)
		(width 0.1651)
		(layer "In11.Cu")
		(net "P5E_PEX3_STN2_TX_DN<32>")
	)
	(segment
		(start 457.43368 -42.446194)
		(end 457.722986 -56.971184)
		(width 0.1651)
		(layer "In11.Cu")
		(net "P5E_PEX3_STN2_TX_DN<32>")
	)
	(segment
		(start 426.924724 -153.867612)
		(end 425.970192 -161.05886)
		(width 0.1651)
		(layer "In11.Cu")
		(net "P5E_PEX3_STN2_TX_DN<32>")
	)
	(segment
		(start 452.287894 -31.675832)
		(end 456.731878 -39.806626)
		(width 0.1651)
		(layer "In11.Cu")
		(net "P5E_PEX3_STN2_TX_DN<32>")
	)
	(segment
		(start 457.722986 -56.971184)
		(end 455.413364 -68.765928)
		(width 0.1651)
		(layer "In11.Cu")
		(net "P5E_PEX3_STN2_TX_DN<32>")
	)
	(segment
		(start 406.72385 -280.129488)
		(end 406.885648 -280.129488)
		(width 0.1143)
		(layer "In11.Cu")
		(net "P5E_PEX3_STN2_TX_DN<32>")
	)
	(segment
		(start 427.997874 -135.769604)
		(end 427.997874 -140.798042)
		(width 0.1651)
		(layer "In11.Cu")
		(net "P5E_PEX3_STN2_TX_DN<32>")
	)
	(segment
		(start 445.605154 -28.250642)
		(end 445.775842 -28.42133)
		(width 0.1651)
		(layer "In11.Cu")
		(net "P5E_PEX3_STN2_TX_DN<32>")
	)
	(segment
		(start 445.775842 -28.42133)
		(end 446.066164 -28.541472)
		(width 0.1651)
		(layer "In11.Cu")
		(net "P5E_PEX3_STN2_TX_DN<32>")
	)
	(segment
		(start 450.111876 -29.49448)
		(end 452.287894 -31.675832)
		(width 0.1651)
		(layer "In11.Cu")
		(net "P5E_PEX3_STN2_TX_DN<32>")
	)
	(segment
		(start 427.997874 -140.798042)
		(end 427.735492 -141.928088)
		(width 0.1651)
		(layer "In11.Cu")
		(net "P5E_PEX3_STN2_TX_DN<32>")
	)
	(segment
		(start 427.55058 -146.260566)
		(end 426.924724 -153.867612)
		(width 0.1651)
		(layer "In11.Cu")
		(net "P5E_PEX3_STN2_TX_DN<32>")
	)
	(segment
		(start 381.40386 -349.831914)
		(end 381.083312 -349.511366)
		(width 0.13462)
		(layer "F.Cu")
		(net "P5E_PEX3_STN6_TX_DN<107>")
	)
	(segment
		(start 381.083312 -349.511366)
		(end 381.083312 -348.880938)
		(width 0.13462)
		(layer "F.Cu")
		(net "P5E_PEX3_STN6_TX_DN<107>")
	)
	(segment
		(start 381.083312 -348.880938)
		(end 381.37846 -348.58579)
		(width 0.13462)
		(layer "F.Cu")
		(net "P5E_PEX3_STN6_TX_DN<107>")
	)
	(segment
		(start 382.878584 -341.223854)
		(end 386.826252 -335.838292)
		(width 0.1651)
		(layer "In13.Cu")
		(net "P5E_PEX3_STN6_TX_DN<107>")
	)
	(segment
		(start 395.26591 -321.6656)
		(end 395.26591 -320.046096)
		(width 0.1651)
		(layer "In13.Cu")
		(net "P5E_PEX3_STN6_TX_DN<107>")
	)
	(segment
		(start 395.22019 -311.773824)
		(end 395.323822 -311.670192)
		(width 0.1143)
		(layer "In13.Cu")
		(net "P5E_PEX3_STN6_TX_DN<107>")
	)
	(segment
		(start 382.64211 -346.230194)
		(end 382.64211 -342.155526)
		(width 0.1651)
		(layer "In13.Cu")
		(net "P5E_PEX3_STN6_TX_DN<107>")
	)
	(segment
		(start 395.48562 -311.670192)
		(end 395.59992 -311.784492)
		(width 0.1143)
		(layer "In13.Cu")
		(net "P5E_PEX3_STN6_TX_DN<107>")
	)
	(segment
		(start 395.26591 -320.046096)
		(end 395.26591 -320.017648)
		(width 0.1143)
		(layer "In13.Cu")
		(net "P5E_PEX3_STN6_TX_DN<107>")
	)
	(segment
		(start 395.323822 -311.670192)
		(end 395.48562 -311.670192)
		(width 0.1143)
		(layer "In13.Cu")
		(net "P5E_PEX3_STN6_TX_DN<107>")
	)
	(segment
		(start 394.997686 -322.313046)
		(end 395.26591 -321.6656)
		(width 0.1651)
		(layer "In13.Cu")
		(net "P5E_PEX3_STN6_TX_DN<107>")
	)
	(segment
		(start 381.37846 -348.58579)
		(end 381.08763 -348.29496)
		(width 0.1651)
		(layer "In13.Cu")
		(net "P5E_PEX3_STN6_TX_DN<107>")
	)
	(segment
		(start 381.08763 -347.784674)
		(end 382.64211 -346.230194)
		(width 0.1651)
		(layer "In13.Cu")
		(net "P5E_PEX3_STN6_TX_DN<107>")
	)
	(segment
		(start 395.26591 -320.017648)
		(end 395.22019 -319.971928)
		(width 0.1143)
		(layer "In13.Cu")
		(net "P5E_PEX3_STN6_TX_DN<107>")
	)
	(segment
		(start 386.826252 -335.838292)
		(end 393.696698 -324.804532)
		(width 0.1651)
		(layer "In13.Cu")
		(net "P5E_PEX3_STN6_TX_DN<107>")
	)
	(segment
		(start 382.64211 -342.155526)
		(end 382.878584 -341.223854)
		(width 0.1651)
		(layer "In13.Cu")
		(net "P5E_PEX3_STN6_TX_DN<107>")
	)
	(segment
		(start 393.696698 -324.804532)
		(end 394.997686 -322.313046)
		(width 0.1651)
		(layer "In13.Cu")
		(net "P5E_PEX3_STN6_TX_DN<107>")
	)
	(segment
		(start 381.08763 -348.29496)
		(end 381.08763 -347.784674)
		(width 0.1651)
		(layer "In13.Cu")
		(net "P5E_PEX3_STN6_TX_DN<107>")
	)
	(segment
		(start 395.59992 -311.784492)
		(end 395.59992 -312.049922)
		(width 0.1143)
		(layer "In13.Cu")
		(net "P5E_PEX3_STN6_TX_DN<107>")
	)
	(segment
		(start 395.22019 -319.971928)
		(end 395.22019 -311.773824)
		(width 0.1143)
		(layer "In13.Cu")
		(net "P5E_PEX3_STN6_TX_DN<107>")
	)
	(segment
		(start 343.887044 -350.685354)
		(end 343.887044 -351.316798)
		(width 0.13462)
		(layer "F.Cu")
		(net "P5E_PEX2_STN5_TX_C_DP<95>")
	)
	(segment
		(start 343.887044 -351.316798)
		(end 343.592404 -351.611438)
		(width 0.13462)
		(layer "F.Cu")
		(net "P5E_PEX2_STN5_TX_C_DP<95>")
	)
	(segment
		(start 343.567004 -350.365314)
		(end 343.887044 -350.685354)
		(width 0.13462)
		(layer "F.Cu")
		(net "P5E_PEX2_STN5_TX_C_DP<95>")
	)
	(segment
		(start 345.802204 -365.470948)
		(end 345.681808 -365.434372)
		(width 0.1651)
		(layer "In7.Cu")
		(net "P5E_PEX2_STN5_TX_C_DP<95>")
	)
	(segment
		(start 342.328754 -358.972866)
		(end 342.328754 -353.910646)
		(width 0.1651)
		(layer "In7.Cu")
		(net "P5E_PEX2_STN5_TX_C_DP<95>")
	)
	(segment
		(start 346.890086 -379.390148)
		(end 346.890086 -379.772164)
		(width 0.1651)
		(layer "In7.Cu")
		(net "P5E_PEX2_STN5_TX_C_DP<95>")
	)
	(segment
		(start 345.448128 -364.997238)
		(end 345.48445 -364.877096)
		(width 0.1651)
		(layer "In7.Cu")
		(net "P5E_PEX2_STN5_TX_C_DP<95>")
	)
	(segment
		(start 347.447362 -379.899164)
		(end 347.734128 -379.612398)
		(width 0.1651)
		(layer "In7.Cu")
		(net "P5E_PEX2_STN5_TX_C_DP<95>")
	)
	(segment
		(start 344.896948 -363.96676)
		(end 344.933524 -363.846618)
		(width 0.1651)
		(layer "In7.Cu")
		(net "P5E_PEX2_STN5_TX_C_DP<95>")
	)
	(segment
		(start 344.933524 -363.846618)
		(end 342.328754 -358.972866)
		(width 0.1651)
		(layer "In7.Cu")
		(net "P5E_PEX2_STN5_TX_C_DP<95>")
	)
	(segment
		(start 345.681808 -365.434372)
		(end 345.448128 -364.997238)
		(width 0.1651)
		(layer "In7.Cu")
		(net "P5E_PEX2_STN5_TX_C_DP<95>")
	)
	(segment
		(start 343.883234 -352.356166)
		(end 343.883234 -351.902268)
		(width 0.1651)
		(layer "In7.Cu")
		(net "P5E_PEX2_STN5_TX_C_DP<95>")
	)
	(segment
		(start 342.328754 -353.910646)
		(end 343.883234 -352.356166)
		(width 0.1651)
		(layer "In7.Cu")
		(net "P5E_PEX2_STN5_TX_C_DP<95>")
	)
	(segment
		(start 343.883234 -351.902268)
		(end 343.592404 -351.611438)
		(width 0.1651)
		(layer "In7.Cu")
		(net "P5E_PEX2_STN5_TX_C_DP<95>")
	)
	(segment
		(start 346.890086 -379.772164)
		(end 347.017086 -379.899164)
		(width 0.1651)
		(layer "In7.Cu")
		(net "P5E_PEX2_STN5_TX_C_DP<95>")
	)
	(segment
		(start 345.48445 -364.877096)
		(end 345.251024 -364.44047)
		(width 0.1651)
		(layer "In7.Cu")
		(net "P5E_PEX2_STN5_TX_C_DP<95>")
	)
	(segment
		(start 347.734128 -369.085622)
		(end 345.802204 -365.470948)
		(width 0.1651)
		(layer "In7.Cu")
		(net "P5E_PEX2_STN5_TX_C_DP<95>")
	)
	(segment
		(start 347.017086 -379.899164)
		(end 347.447362 -379.899164)
		(width 0.1651)
		(layer "In7.Cu")
		(net "P5E_PEX2_STN5_TX_C_DP<95>")
	)
	(segment
		(start 347.734128 -379.612398)
		(end 347.734128 -369.085622)
		(width 0.1651)
		(layer "In7.Cu")
		(net "P5E_PEX2_STN5_TX_C_DP<95>")
	)
	(segment
		(start 345.251024 -364.44047)
		(end 345.130882 -364.403894)
		(width 0.1651)
		(layer "In7.Cu")
		(net "P5E_PEX2_STN5_TX_C_DP<95>")
	)
	(segment
		(start 345.130882 -364.403894)
		(end 344.896948 -363.96676)
		(width 0.1651)
		(layer "In7.Cu")
		(net "P5E_PEX2_STN5_TX_C_DP<95>")
	)
	(via
		(at 170.836844 -138.176)
		(size 0.6604)
		(drill 0.3302)
		(layers "F.Cu" "B.Cu")
		(net "RST_SMB_NIC2_MUX_N")
	)
	(segment
		(start 171.198794 -137.05205)
		(end 172.106844 -137.05205)
		(width 0.13208)
		(layer "B.Cu")
		(net "RST_SMB_NIC2_MUX_N")
	)
	(segment
		(start 170.836844 -137.414)
		(end 171.198794 -137.05205)
		(width 0.13208)
		(layer "B.Cu")
		(net "RST_SMB_NIC2_MUX_N")
	)
	(segment
		(start 170.709844 -140.931138)
		(end 170.836844 -140.804138)
		(width 0.13208)
		(layer "B.Cu")
		(net "RST_SMB_NIC2_MUX_N")
	)
	(segment
		(start 170.836844 -140.804138)
		(end 170.836844 -138.176)
		(width 0.13208)
		(layer "B.Cu")
		(net "RST_SMB_NIC2_MUX_N")
	)
	(segment
		(start 170.836844 -138.176)
		(end 170.836844 -137.414)
		(width 0.13208)
		(layer "B.Cu")
		(net "RST_SMB_NIC2_MUX_N")
	)
	(segment
		(start 170.064684 -140.931138)
		(end 170.709844 -140.931138)
		(width 0.13208)
		(layer "B.Cu")
		(net "RST_SMB_NIC2_MUX_N")
	)
	(segment
		(start 97.00133 -32.4104)
		(end 96.388174 -32.4104)
		(width 0.13462)
		(layer "F.Cu")
		(net "P5E_PEX0_STN2_TX_DP<34>")
	)
	(segment
		(start 97.305114 -32.714184)
		(end 97.00133 -32.4104)
		(width 0.13462)
		(layer "F.Cu")
		(net "P5E_PEX0_STN2_TX_DP<34>")
	)
	(segment
		(start 96.388174 -32.4104)
		(end 96.05899 -32.739584)
		(width 0.13462)
		(layer "F.Cu")
		(net "P5E_PEX0_STN2_TX_DP<34>")
	)
	(segment
		(start 56.799734 -280.434288)
		(end 56.685434 -280.319988)
		(width 0.1143)
		(layer "In11.Cu")
		(net "P5E_PEX0_STN2_TX_DP<34>")
	)
	(segment
		(start 56.799734 -280.699718)
		(end 56.799734 -280.434288)
		(width 0.1143)
		(layer "In11.Cu")
		(net "P5E_PEX0_STN2_TX_DP<34>")
	)
	(segment
		(start 106.716576 -41.890696)
		(end 102.443534 -34.038286)
		(width 0.1651)
		(layer "In11.Cu")
		(net "P5E_PEX0_STN2_TX_DP<34>")
	)
	(segment
		(start 78.121764 -118.35638)
		(end 78.929738 -111.806228)
		(width 0.1651)
		(layer "In11.Cu")
		(net "P5E_PEX0_STN2_TX_DP<34>")
	)
	(segment
		(start 77.098906 -141.845284)
		(end 77.505814 -140.100304)
		(width 0.1651)
		(layer "In11.Cu")
		(net "P5E_PEX0_STN2_TX_DP<34>")
	)
	(segment
		(start 106.927904 -42.691304)
		(end 106.716576 -41.890696)
		(width 0.1651)
		(layer "In11.Cu")
		(net "P5E_PEX0_STN2_TX_DP<34>")
	)
	(segment
		(start 99.77755 -32.423354)
		(end 99.66325 -32.537654)
		(width 0.1651)
		(layer "In11.Cu")
		(net "P5E_PEX0_STN2_TX_DP<34>")
	)
	(segment
		(start 102.765098 -74.293984)
		(end 104.970326 -68.191126)
		(width 0.1651)
		(layer "In11.Cu")
		(net "P5E_PEX0_STN2_TX_DP<34>")
	)
	(segment
		(start 99.66325 -32.537654)
		(end 99.16795 -32.537654)
		(width 0.1651)
		(layer "In11.Cu")
		(net "P5E_PEX0_STN2_TX_DP<34>")
	)
	(segment
		(start 78.929738 -111.806228)
		(end 78.929992 -111.806228)
		(width 0.1651)
		(layer "In11.Cu")
		(net "P5E_PEX0_STN2_TX_DP<34>")
	)
	(segment
		(start 77.505814 -140.100304)
		(end 77.505814 -132.507228)
		(width 0.1651)
		(layer "In11.Cu")
		(net "P5E_PEX0_STN2_TX_DP<34>")
	)
	(segment
		(start 79.743808 -105.211118)
		(end 86.74481 -92.873068)
		(width 0.1651)
		(layer "In11.Cu")
		(net "P5E_PEX0_STN2_TX_DP<34>")
	)
	(segment
		(start 77.505814 -132.507228)
		(end 78.121764 -118.35638)
		(width 0.1651)
		(layer "In11.Cu")
		(net "P5E_PEX0_STN2_TX_DP<34>")
	)
	(segment
		(start 97.595944 -32.423354)
		(end 97.305114 -32.714184)
		(width 0.1651)
		(layer "In11.Cu")
		(net "P5E_PEX0_STN2_TX_DP<34>")
	)
	(segment
		(start 56.229504 -280.10485)
		(end 56.229504 -271.473168)
		(width 0.1143)
		(layer "In11.Cu")
		(net "P5E_PEX0_STN2_TX_DP<34>")
	)
	(segment
		(start 99.16795 -32.537654)
		(end 99.05365 -32.423354)
		(width 0.1651)
		(layer "In11.Cu")
		(net "P5E_PEX0_STN2_TX_DP<34>")
	)
	(segment
		(start 78.929992 -111.806228)
		(end 79.743808 -105.211118)
		(width 0.1651)
		(layer "In11.Cu")
		(net "P5E_PEX0_STN2_TX_DP<34>")
	)
	(segment
		(start 56.183784 -271.427448)
		(end 56.183784 -271.399)
		(width 0.1143)
		(layer "In11.Cu")
		(net "P5E_PEX0_STN2_TX_DP<34>")
	)
	(segment
		(start 102.443534 -34.038286)
		(end 100.845366 -32.423354)
		(width 0.1651)
		(layer "In11.Cu")
		(net "P5E_PEX0_STN2_TX_DP<34>")
	)
	(segment
		(start 56.229504 -271.473168)
		(end 56.183784 -271.427448)
		(width 0.1143)
		(layer "In11.Cu")
		(net "P5E_PEX0_STN2_TX_DP<34>")
	)
	(segment
		(start 100.845366 -32.423354)
		(end 99.77755 -32.423354)
		(width 0.1651)
		(layer "In11.Cu")
		(net "P5E_PEX0_STN2_TX_DP<34>")
	)
	(segment
		(start 56.183784 -271.399)
		(end 56.183784 -265.641074)
		(width 0.1651)
		(layer "In11.Cu")
		(net "P5E_PEX0_STN2_TX_DP<34>")
	)
	(segment
		(start 102.234746 -75.047094)
		(end 102.765098 -74.293984)
		(width 0.1651)
		(layer "In11.Cu")
		(net "P5E_PEX0_STN2_TX_DP<34>")
	)
	(segment
		(start 76.77023 -149.389084)
		(end 77.098906 -141.845284)
		(width 0.1651)
		(layer "In11.Cu")
		(net "P5E_PEX0_STN2_TX_DP<34>")
	)
	(segment
		(start 86.74481 -92.873068)
		(end 86.745064 -92.873068)
		(width 0.1651)
		(layer "In11.Cu")
		(net "P5E_PEX0_STN2_TX_DP<34>")
	)
	(segment
		(start 56.444642 -280.319988)
		(end 56.229504 -280.10485)
		(width 0.1143)
		(layer "In11.Cu")
		(net "P5E_PEX0_STN2_TX_DP<34>")
	)
	(segment
		(start 107.178094 -56.729376)
		(end 106.927904 -42.691304)
		(width 0.1651)
		(layer "In11.Cu")
		(net "P5E_PEX0_STN2_TX_DP<34>")
	)
	(segment
		(start 104.970326 -68.191126)
		(end 107.178094 -56.729376)
		(width 0.1651)
		(layer "In11.Cu")
		(net "P5E_PEX0_STN2_TX_DP<34>")
	)
	(segment
		(start 75.353164 -161.396426)
		(end 76.77023 -149.389084)
		(width 0.1651)
		(layer "In11.Cu")
		(net "P5E_PEX0_STN2_TX_DP<34>")
	)
	(segment
		(start 86.745064 -92.873068)
		(end 93.737684 -80.550258)
		(width 0.1651)
		(layer "In11.Cu")
		(net "P5E_PEX0_STN2_TX_DP<34>")
	)
	(segment
		(start 56.685434 -280.319988)
		(end 56.444642 -280.319988)
		(width 0.1143)
		(layer "In11.Cu")
		(net "P5E_PEX0_STN2_TX_DP<34>")
	)
	(segment
		(start 93.737684 -80.550258)
		(end 95.743522 -78.546452)
		(width 0.1651)
		(layer "In11.Cu")
		(net "P5E_PEX0_STN2_TX_DP<34>")
	)
	(segment
		(start 95.743522 -78.546452)
		(end 102.234746 -75.047094)
		(width 0.1651)
		(layer "In11.Cu")
		(net "P5E_PEX0_STN2_TX_DP<34>")
	)
	(segment
		(start 99.05365 -32.423354)
		(end 97.595944 -32.423354)
		(width 0.1651)
		(layer "In11.Cu")
		(net "P5E_PEX0_STN2_TX_DP<34>")
	)
	(segment
		(start 56.183784 -265.641074)
		(end 75.353164 -161.396426)
		(width 0.1651)
		(layer "In11.Cu")
		(net "P5E_PEX0_STN2_TX_DP<34>")
	)
	(segment
		(start 331.220826 -34.2265)
		(end 330.90104 -34.546286)
		(width 0.13462)
		(layer "F.Cu")
		(net "P5E_PEX2_STN2_TX_DP<35>")
	)
	(segment
		(start 332.147164 -34.520886)
		(end 331.852778 -34.2265)
		(width 0.13462)
		(layer "F.Cu")
		(net "P5E_PEX2_STN2_TX_DP<35>")
	)
	(segment
		(start 331.852778 -34.2265)
		(end 331.220826 -34.2265)
		(width 0.13462)
		(layer "F.Cu")
		(net "P5E_PEX2_STN2_TX_DP<35>")
	)
	(segment
		(start 333.082646 -34.230056)
		(end 333.46263 -34.336228)
		(width 0.1651)
		(layer "In11.Cu")
		(net "P5E_PEX2_STN2_TX_DP<35>")
	)
	(segment
		(start 332.06055 -74.041508)
		(end 327.378568 -77.73924)
		(width 0.1651)
		(layer "In11.Cu")
		(net "P5E_PEX2_STN2_TX_DP<35>")
	)
	(segment
		(start 308.750716 -131.097782)
		(end 308.750716 -139.865608)
		(width 0.1651)
		(layer "In11.Cu")
		(net "P5E_PEX2_STN2_TX_DP<35>")
	)
	(segment
		(start 287.479486 -278.20493)
		(end 287.694624 -278.420068)
		(width 0.1143)
		(layer "In11.Cu")
		(net "P5E_PEX2_STN2_TX_DP<35>")
	)
	(segment
		(start 327.36663 -77.751178)
		(end 327.366884 -77.751178)
		(width 0.1651)
		(layer "In11.Cu")
		(net "P5E_PEX2_STN2_TX_DP<35>")
	)
	(segment
		(start 332.147164 -34.520886)
		(end 332.437994 -34.230056)
		(width 0.1651)
		(layer "In11.Cu")
		(net "P5E_PEX2_STN2_TX_DP<35>")
	)
	(segment
		(start 334.341724 -35.781488)
		(end 334.496664 -35.82797)
		(width 0.1651)
		(layer "In11.Cu")
		(net "P5E_PEX2_STN2_TX_DP<35>")
	)
	(segment
		(start 334.164686 -70.921626)
		(end 334.164432 -70.921626)
		(width 0.1651)
		(layer "In11.Cu")
		(net "P5E_PEX2_STN2_TX_DP<35>")
	)
	(segment
		(start 333.46263 -34.336228)
		(end 333.919068 -34.754058)
		(width 0.1651)
		(layer "In11.Cu")
		(net "P5E_PEX2_STN2_TX_DP<35>")
	)
	(segment
		(start 287.433766 -271.427448)
		(end 287.479486 -271.473168)
		(width 0.1143)
		(layer "In11.Cu")
		(net "P5E_PEX2_STN2_TX_DP<35>")
	)
	(segment
		(start 287.433766 -271.399)
		(end 287.433766 -271.427448)
		(width 0.1143)
		(layer "In11.Cu")
		(net "P5E_PEX2_STN2_TX_DP<35>")
	)
	(segment
		(start 309.280306 -118.187978)
		(end 308.750716 -131.097782)
		(width 0.1651)
		(layer "In11.Cu")
		(net "P5E_PEX2_STN2_TX_DP<35>")
	)
	(segment
		(start 336.269584 -67.800728)
		(end 334.164686 -70.921626)
		(width 0.1651)
		(layer "In11.Cu")
		(net "P5E_PEX2_STN2_TX_DP<35>")
	)
	(segment
		(start 287.694624 -278.420068)
		(end 287.935416 -278.420068)
		(width 0.1143)
		(layer "In11.Cu")
		(net "P5E_PEX2_STN2_TX_DP<35>")
	)
	(segment
		(start 332.437994 -34.230056)
		(end 333.082646 -34.230056)
		(width 0.1651)
		(layer "In11.Cu")
		(net "P5E_PEX2_STN2_TX_DP<35>")
	)
	(segment
		(start 334.496664 -35.82797)
		(end 338.094066 -42.518584)
		(width 0.1651)
		(layer "In11.Cu")
		(net "P5E_PEX2_STN2_TX_DP<35>")
	)
	(segment
		(start 308.313328 -141.757654)
		(end 308.006242 -149.233636)
		(width 0.1651)
		(layer "In11.Cu")
		(net "P5E_PEX2_STN2_TX_DP<35>")
	)
	(segment
		(start 287.433766 -265.45286)
		(end 287.433766 -271.399)
		(width 0.1651)
		(layer "In11.Cu")
		(net "P5E_PEX2_STN2_TX_DP<35>")
	)
	(segment
		(start 306.545488 -161.487866)
		(end 287.433766 -265.45286)
		(width 0.1651)
		(layer "In11.Cu")
		(net "P5E_PEX2_STN2_TX_DP<35>")
	)
	(segment
		(start 308.006242 -149.233636)
		(end 306.545488 -161.487866)
		(width 0.1651)
		(layer "In11.Cu")
		(net "P5E_PEX2_STN2_TX_DP<35>")
	)
	(segment
		(start 338.401914 -56.74106)
		(end 336.269584 -67.800728)
		(width 0.1651)
		(layer "In11.Cu")
		(net "P5E_PEX2_STN2_TX_DP<35>")
	)
	(segment
		(start 327.378568 -77.73924)
		(end 327.36663 -77.751178)
		(width 0.1651)
		(layer "In11.Cu")
		(net "P5E_PEX2_STN2_TX_DP<35>")
	)
	(segment
		(start 308.750716 -139.865608)
		(end 308.313328 -141.757654)
		(width 0.1651)
		(layer "In11.Cu")
		(net "P5E_PEX2_STN2_TX_DP<35>")
	)
	(segment
		(start 327.366884 -77.751178)
		(end 325.162418 -79.960724)
		(width 0.1651)
		(layer "In11.Cu")
		(net "P5E_PEX2_STN2_TX_DP<35>")
	)
	(segment
		(start 287.935416 -278.420068)
		(end 288.049716 -278.534368)
		(width 0.1143)
		(layer "In11.Cu")
		(net "P5E_PEX2_STN2_TX_DP<35>")
	)
	(segment
		(start 288.049716 -278.534368)
		(end 288.049716 -278.799798)
		(width 0.1143)
		(layer "In11.Cu")
		(net "P5E_PEX2_STN2_TX_DP<35>")
	)
	(segment
		(start 334.164432 -70.921626)
		(end 332.06055 -74.041508)
		(width 0.1651)
		(layer "In11.Cu")
		(net "P5E_PEX2_STN2_TX_DP<35>")
	)
	(segment
		(start 338.173568 -42.823892)
		(end 338.401914 -56.74106)
		(width 0.1651)
		(layer "In11.Cu")
		(net "P5E_PEX2_STN2_TX_DP<35>")
	)
	(segment
		(start 325.162418 -79.960724)
		(end 310.987186 -104.92359)
		(width 0.1651)
		(layer "In11.Cu")
		(net "P5E_PEX2_STN2_TX_DP<35>")
	)
	(segment
		(start 334.107028 -35.344862)
		(end 334.341724 -35.781488)
		(width 0.1651)
		(layer "In11.Cu")
		(net "P5E_PEX2_STN2_TX_DP<35>")
	)
	(segment
		(start 334.15351 -35.190176)
		(end 334.107028 -35.344862)
		(width 0.1651)
		(layer "In11.Cu")
		(net "P5E_PEX2_STN2_TX_DP<35>")
	)
	(segment
		(start 310.987186 -104.92359)
		(end 309.280306 -118.187978)
		(width 0.1651)
		(layer "In11.Cu")
		(net "P5E_PEX2_STN2_TX_DP<35>")
	)
	(segment
		(start 333.919068 -34.754058)
		(end 334.15351 -35.190176)
		(width 0.1651)
		(layer "In11.Cu")
		(net "P5E_PEX2_STN2_TX_DP<35>")
	)
	(segment
		(start 338.094066 -42.518584)
		(end 338.173568 -42.823892)
		(width 0.1651)
		(layer "In11.Cu")
		(net "P5E_PEX2_STN2_TX_DP<35>")
	)
	(segment
		(start 287.479486 -271.473168)
		(end 287.479486 -278.20493)
		(width 0.1143)
		(layer "In11.Cu")
		(net "P5E_PEX2_STN2_TX_DP<35>")
	)
	(segment
		(start 402.846032 -349.511366)
		(end 402.846032 -348.880938)
		(width 0.13462)
		(layer "F.Cu")
		(net "P5E_PEX3_STN5_TX_DN<87>")
	)
	(segment
		(start 402.846032 -348.880938)
		(end 403.14118 -348.58579)
		(width 0.13462)
		(layer "F.Cu")
		(net "P5E_PEX3_STN5_TX_DN<87>")
	)
	(segment
		(start 403.16658 -349.831914)
		(end 402.846032 -349.511366)
		(width 0.13462)
		(layer "F.Cu")
		(net "P5E_PEX3_STN5_TX_DN<87>")
	)
	(segment
		(start 413.270192 -319.99428)
		(end 413.270192 -313.684412)
		(width 0.1143)
		(layer "In7.Cu")
		(net "P5E_PEX3_STN5_TX_DN<87>")
	)
	(segment
		(start 413.384492 -313.570112)
		(end 413.535622 -313.570112)
		(width 0.1143)
		(layer "In7.Cu")
		(net "P5E_PEX3_STN5_TX_DN<87>")
	)
	(segment
		(start 405.825198 -343.221564)
		(end 405.775668 -343.102184)
		(width 0.1651)
		(layer "In7.Cu")
		(net "P5E_PEX3_STN5_TX_DN<87>")
	)
	(segment
		(start 405.775668 -343.102184)
		(end 413.315912 -324.830694)
		(width 0.1651)
		(layer "In7.Cu")
		(net "P5E_PEX3_STN5_TX_DN<87>")
	)
	(segment
		(start 405.516588 -343.72931)
		(end 405.635968 -343.67978)
		(width 0.1651)
		(layer "In7.Cu")
		(net "P5E_PEX3_STN5_TX_DN<87>")
	)
	(segment
		(start 413.315912 -320.04)
		(end 413.270192 -319.99428)
		(width 0.1143)
		(layer "In7.Cu")
		(net "P5E_PEX3_STN5_TX_DN<87>")
	)
	(segment
		(start 402.85035 -347.784674)
		(end 404.54072 -346.094304)
		(width 0.1651)
		(layer "In7.Cu")
		(net "P5E_PEX3_STN5_TX_DN<87>")
	)
	(segment
		(start 413.270192 -313.684412)
		(end 413.384492 -313.570112)
		(width 0.1143)
		(layer "In7.Cu")
		(net "P5E_PEX3_STN5_TX_DN<87>")
	)
	(segment
		(start 413.315912 -320.068448)
		(end 413.315912 -320.04)
		(width 0.1143)
		(layer "In7.Cu")
		(net "P5E_PEX3_STN5_TX_DN<87>")
	)
	(segment
		(start 413.315912 -324.830694)
		(end 413.315912 -320.068448)
		(width 0.1651)
		(layer "In7.Cu")
		(net "P5E_PEX3_STN5_TX_DN<87>")
	)
	(segment
		(start 405.635968 -343.67978)
		(end 405.825198 -343.221564)
		(width 0.1651)
		(layer "In7.Cu")
		(net "P5E_PEX3_STN5_TX_DN<87>")
	)
	(segment
		(start 413.535622 -313.570112)
		(end 413.649922 -313.684412)
		(width 0.1143)
		(layer "In7.Cu")
		(net "P5E_PEX3_STN5_TX_DN<87>")
	)
	(segment
		(start 403.14118 -348.58579)
		(end 402.85035 -348.29496)
		(width 0.1651)
		(layer "In7.Cu")
		(net "P5E_PEX3_STN5_TX_DN<87>")
	)
	(segment
		(start 402.85035 -348.29496)
		(end 402.85035 -347.784674)
		(width 0.1651)
		(layer "In7.Cu")
		(net "P5E_PEX3_STN5_TX_DN<87>")
	)
	(segment
		(start 413.649922 -313.684412)
		(end 413.649922 -313.949842)
		(width 0.1143)
		(layer "In7.Cu")
		(net "P5E_PEX3_STN5_TX_DN<87>")
	)
	(segment
		(start 404.54072 -346.094304)
		(end 405.516588 -343.72931)
		(width 0.1651)
		(layer "In7.Cu")
		(net "P5E_PEX3_STN5_TX_DN<87>")
	)
	(segment
		(start 425.134024 -348.879922)
		(end 424.839892 -348.58579)
		(width 0.13462)
		(layer "F.Cu")
		(net "P5E_PEX3_STN7_TX_DP<119>")
	)
	(segment
		(start 424.814492 -349.831914)
		(end 425.134024 -349.512382)
		(width 0.13462)
		(layer "F.Cu")
		(net "P5E_PEX3_STN7_TX_DP<119>")
	)
	(segment
		(start 425.134024 -349.512382)
		(end 425.134024 -348.879922)
		(width 0.13462)
		(layer "F.Cu")
		(net "P5E_PEX3_STN7_TX_DP<119>")
	)
	(segment
		(start 383.968752 -307.633878)
		(end 383.9972 -307.633878)
		(width 0.1143)
		(layer "In11.Cu")
		(net "P5E_PEX3_STN7_TX_DP<119>")
	)
	(segment
		(start 384.04292 -307.679598)
		(end 392.154918 -307.679598)
		(width 0.1143)
		(layer "In11.Cu")
		(net "P5E_PEX3_STN7_TX_DP<119>")
	)
	(segment
		(start 419.748462 -336.689446)
		(end 376.056652 -326.838056)
		(width 0.1651)
		(layer "In11.Cu")
		(net "P5E_PEX3_STN7_TX_DP<119>")
	)
	(segment
		(start 371.999764 -318.746886)
		(end 373.470932 -316.545468)
		(width 0.1651)
		(layer "In11.Cu")
		(net "P5E_PEX3_STN7_TX_DP<119>")
	)
	(segment
		(start 376.056652 -326.838056)
		(end 373.785384 -325.586598)
		(width 0.1651)
		(layer "In11.Cu")
		(net "P5E_PEX3_STN7_TX_DP<119>")
	)
	(segment
		(start 373.470932 -316.545468)
		(end 381.805942 -308.210458)
		(width 0.1651)
		(layer "In11.Cu")
		(net "P5E_PEX3_STN7_TX_DP<119>")
	)
	(segment
		(start 371.65026 -322.216272)
		(end 371.65026 -319.591182)
		(width 0.1651)
		(layer "In11.Cu")
		(net "P5E_PEX3_STN7_TX_DP<119>")
	)
	(segment
		(start 426.685202 -341.799418)
		(end 426.165772 -341.099394)
		(width 0.1651)
		(layer "In11.Cu")
		(net "P5E_PEX3_STN7_TX_DP<119>")
	)
	(segment
		(start 426.165772 -341.099394)
		(end 419.748462 -336.689446)
		(width 0.1651)
		(layer "In11.Cu")
		(net "P5E_PEX3_STN7_TX_DP<119>")
	)
	(segment
		(start 392.370056 -307.894736)
		(end 392.370056 -308.135528)
		(width 0.1143)
		(layer "In11.Cu")
		(net "P5E_PEX3_STN7_TX_DP<119>")
	)
	(segment
		(start 381.805942 -308.210458)
		(end 383.197608 -307.633878)
		(width 0.1651)
		(layer "In11.Cu")
		(net "P5E_PEX3_STN7_TX_DP<119>")
	)
	(segment
		(start 392.370056 -308.135528)
		(end 392.484356 -308.249828)
		(width 0.1143)
		(layer "In11.Cu")
		(net "P5E_PEX3_STN7_TX_DP<119>")
	)
	(segment
		(start 383.9972 -307.633878)
		(end 384.04292 -307.679598)
		(width 0.1143)
		(layer "In11.Cu")
		(net "P5E_PEX3_STN7_TX_DP<119>")
	)
	(segment
		(start 372.523766 -324.32498)
		(end 371.65026 -322.216272)
		(width 0.1651)
		(layer "In11.Cu")
		(net "P5E_PEX3_STN7_TX_DP<119>")
	)
	(segment
		(start 425.130722 -347.667834)
		(end 426.685202 -346.113354)
		(width 0.1651)
		(layer "In11.Cu")
		(net "P5E_PEX3_STN7_TX_DP<119>")
	)
	(segment
		(start 392.484356 -308.249828)
		(end 392.749786 -308.249828)
		(width 0.1143)
		(layer "In11.Cu")
		(net "P5E_PEX3_STN7_TX_DP<119>")
	)
	(segment
		(start 383.197608 -307.633878)
		(end 383.968752 -307.633878)
		(width 0.1651)
		(layer "In11.Cu")
		(net "P5E_PEX3_STN7_TX_DP<119>")
	)
	(segment
		(start 425.130722 -348.29496)
		(end 425.130722 -347.667834)
		(width 0.1651)
		(layer "In11.Cu")
		(net "P5E_PEX3_STN7_TX_DP<119>")
	)
	(segment
		(start 426.685202 -346.113354)
		(end 426.685202 -341.799418)
		(width 0.1651)
		(layer "In11.Cu")
		(net "P5E_PEX3_STN7_TX_DP<119>")
	)
	(segment
		(start 392.154918 -307.679598)
		(end 392.370056 -307.894736)
		(width 0.1143)
		(layer "In11.Cu")
		(net "P5E_PEX3_STN7_TX_DP<119>")
	)
	(segment
		(start 424.839892 -348.58579)
		(end 425.130722 -348.29496)
		(width 0.1651)
		(layer "In11.Cu")
		(net "P5E_PEX3_STN7_TX_DP<119>")
	)
	(segment
		(start 373.785384 -325.586598)
		(end 372.523766 -324.32498)
		(width 0.1651)
		(layer "In11.Cu")
		(net "P5E_PEX3_STN7_TX_DP<119>")
	)
	(segment
		(start 371.65026 -319.591182)
		(end 371.999764 -318.746886)
		(width 0.1651)
		(layer "In11.Cu")
		(net "P5E_PEX3_STN7_TX_DP<119>")
	)
	(segment
		(start 80.71866 -363.127798)
		(end 80.83423 -363.050328)
		(width 0.1651)
		(layer "In5.Cu")
		(net "P5E_PEX0_STN5_RX_DP<91>")
	)
	(segment
		(start 80.697324 -363.743494)
		(end 80.619854 -363.628178)
		(width 0.1651)
		(layer "In5.Cu")
		(net "P5E_PEX0_STN5_RX_DP<91>")
	)
	(segment
		(start 68.579746 -318.355472)
		(end 68.805552 -318.129666)
		(width 0.1143)
		(layer "In5.Cu")
		(net "P5E_PEX0_STN5_RX_DP<91>")
	)
	(segment
		(start 78.636876 -372.099078)
		(end 79.170784 -372.099078)
		(width 0.1651)
		(layer "In5.Cu")
		(net "P5E_PEX0_STN5_RX_DP<91>")
	)
	(segment
		(start 81.871312 -342.320118)
		(end 81.562702 -341.327994)
		(width 0.1651)
		(layer "In5.Cu")
		(net "P5E_PEX0_STN5_RX_DP<91>")
	)
	(segment
		(start 68.534026 -319.966848)
		(end 68.579746 -319.921128)
		(width 0.1143)
		(layer "In5.Cu")
		(net "P5E_PEX0_STN5_RX_DP<91>")
	)
	(segment
		(start 78.509876 -371.590062)
		(end 78.509876 -371.972078)
		(width 0.1651)
		(layer "In5.Cu")
		(net "P5E_PEX0_STN5_RX_DP<91>")
	)
	(segment
		(start 68.534026 -321.28079)
		(end 68.534026 -319.995296)
		(width 0.1651)
		(layer "In5.Cu")
		(net "P5E_PEX0_STN5_RX_DP<91>")
	)
	(segment
		(start 69.035676 -318.129666)
		(end 69.149976 -318.015366)
		(width 0.1143)
		(layer "In5.Cu")
		(net "P5E_PEX0_STN5_RX_DP<91>")
	)
	(segment
		(start 78.509876 -371.972078)
		(end 78.636876 -372.099078)
		(width 0.1651)
		(layer "In5.Cu")
		(net "P5E_PEX0_STN5_RX_DP<91>")
	)
	(segment
		(start 81.871312 -357.799386)
		(end 81.871312 -342.320118)
		(width 0.1651)
		(layer "In5.Cu")
		(net "P5E_PEX0_STN5_RX_DP<91>")
	)
	(segment
		(start 80.83423 -363.050328)
		(end 81.871312 -357.799386)
		(width 0.1651)
		(layer "In5.Cu")
		(net "P5E_PEX0_STN5_RX_DP<91>")
	)
	(segment
		(start 80.496918 -364.288578)
		(end 80.604106 -364.216696)
		(width 0.1651)
		(layer "In5.Cu")
		(net "P5E_PEX0_STN5_RX_DP<91>")
	)
	(segment
		(start 69.149976 -318.015366)
		(end 69.149976 -317.749936)
		(width 0.1143)
		(layer "In5.Cu")
		(net "P5E_PEX0_STN5_RX_DP<91>")
	)
	(segment
		(start 68.579746 -319.921128)
		(end 68.579746 -318.355472)
		(width 0.1143)
		(layer "In5.Cu")
		(net "P5E_PEX0_STN5_RX_DP<91>")
	)
	(segment
		(start 80.604106 -364.216696)
		(end 80.697324 -363.743494)
		(width 0.1651)
		(layer "In5.Cu")
		(net "P5E_PEX0_STN5_RX_DP<91>")
	)
	(segment
		(start 81.562702 -341.327994)
		(end 69.677534 -324.042024)
		(width 0.1651)
		(layer "In5.Cu")
		(net "P5E_PEX0_STN5_RX_DP<91>")
	)
	(segment
		(start 79.402432 -371.86743)
		(end 79.402432 -369.883182)
		(width 0.1651)
		(layer "In5.Cu")
		(net "P5E_PEX0_STN5_RX_DP<91>")
	)
	(segment
		(start 79.53629 -368.980466)
		(end 80.14335 -366.549432)
		(width 0.1651)
		(layer "In5.Cu")
		(net "P5E_PEX0_STN5_RX_DP<91>")
	)
	(segment
		(start 80.14335 -366.549432)
		(end 80.236822 -366.075976)
		(width 0.1651)
		(layer "In5.Cu")
		(net "P5E_PEX0_STN5_RX_DP<91>")
	)
	(segment
		(start 80.395318 -364.802928)
		(end 80.496918 -364.288578)
		(width 0.1651)
		(layer "In5.Cu")
		(net "P5E_PEX0_STN5_RX_DP<91>")
	)
	(segment
		(start 80.373728 -365.383064)
		(end 80.4672 -364.909608)
		(width 0.1651)
		(layer "In5.Cu")
		(net "P5E_PEX0_STN5_RX_DP<91>")
	)
	(segment
		(start 68.534026 -319.995296)
		(end 68.534026 -319.966848)
		(width 0.1143)
		(layer "In5.Cu")
		(net "P5E_PEX0_STN5_RX_DP<91>")
	)
	(segment
		(start 69.677534 -324.042024)
		(end 68.534026 -321.28079)
		(width 0.1651)
		(layer "In5.Cu")
		(net "P5E_PEX0_STN5_RX_DP<91>")
	)
	(segment
		(start 79.170784 -372.099078)
		(end 79.402432 -371.86743)
		(width 0.1651)
		(layer "In5.Cu")
		(net "P5E_PEX0_STN5_RX_DP<91>")
	)
	(segment
		(start 68.805552 -318.129666)
		(end 69.035676 -318.129666)
		(width 0.1143)
		(layer "In5.Cu")
		(net "P5E_PEX0_STN5_RX_DP<91>")
	)
	(segment
		(start 80.4672 -364.909608)
		(end 80.395318 -364.802928)
		(width 0.1651)
		(layer "In5.Cu")
		(net "P5E_PEX0_STN5_RX_DP<91>")
	)
	(segment
		(start 80.619854 -363.628178)
		(end 80.71866 -363.127798)
		(width 0.1651)
		(layer "In5.Cu")
		(net "P5E_PEX0_STN5_RX_DP<91>")
	)
	(segment
		(start 80.15859 -365.959898)
		(end 80.257142 -365.461296)
		(width 0.1651)
		(layer "In5.Cu")
		(net "P5E_PEX0_STN5_RX_DP<91>")
	)
	(segment
		(start 80.257142 -365.461296)
		(end 80.373728 -365.383064)
		(width 0.1651)
		(layer "In5.Cu")
		(net "P5E_PEX0_STN5_RX_DP<91>")
	)
	(segment
		(start 79.402432 -369.883182)
		(end 79.53629 -368.980466)
		(width 0.1651)
		(layer "In5.Cu")
		(net "P5E_PEX0_STN5_RX_DP<91>")
	)
	(segment
		(start 80.236822 -366.075976)
		(end 80.15859 -365.959898)
		(width 0.1651)
		(layer "In5.Cu")
		(net "P5E_PEX0_STN5_RX_DP<91>")
	)
	(segment
		(start 293.657782 -350.365314)
		(end 293.337742 -350.685354)
		(width 0.13462)
		(layer "F.Cu")
		(net "P5E_PEX2_STN7_TX_C_DN<124>")
	)
	(segment
		(start 293.337742 -350.685354)
		(end 293.337742 -351.316798)
		(width 0.13462)
		(layer "F.Cu")
		(net "P5E_PEX2_STN7_TX_C_DN<124>")
	)
	(segment
		(start 293.337742 -351.316798)
		(end 293.632382 -351.611438)
		(width 0.13462)
		(layer "F.Cu")
		(net "P5E_PEX2_STN7_TX_C_DN<124>")
	)
	(segment
		(start 291.787072 -358.5718)
		(end 297.415966 -368.7064)
		(width 0.1651)
		(layer "In7.Cu")
		(net "P5E_PEX2_STN7_TX_C_DN<124>")
	)
	(segment
		(start 297.415966 -374.729248)
		(end 296.9641 -375.181114)
		(width 0.1651)
		(layer "In7.Cu")
		(net "P5E_PEX2_STN7_TX_C_DN<124>")
	)
	(segment
		(start 291.787072 -354.027486)
		(end 291.787072 -358.5718)
		(width 0.1651)
		(layer "In7.Cu")
		(net "P5E_PEX2_STN7_TX_C_DN<124>")
	)
	(segment
		(start 293.632382 -351.611438)
		(end 293.341552 -351.902268)
		(width 0.1651)
		(layer "In7.Cu")
		(net "P5E_PEX2_STN7_TX_C_DN<124>")
	)
	(segment
		(start 296.9641 -375.181114)
		(end 296.416984 -375.181114)
		(width 0.1651)
		(layer "In7.Cu")
		(net "P5E_PEX2_STN7_TX_C_DN<124>")
	)
	(segment
		(start 293.341552 -351.902268)
		(end 293.341552 -352.473006)
		(width 0.1651)
		(layer "In7.Cu")
		(net "P5E_PEX2_STN7_TX_C_DN<124>")
	)
	(segment
		(start 297.415966 -368.7064)
		(end 297.415966 -374.729248)
		(width 0.1651)
		(layer "In7.Cu")
		(net "P5E_PEX2_STN7_TX_C_DN<124>")
	)
	(segment
		(start 296.289984 -375.308114)
		(end 296.289984 -375.69013)
		(width 0.1651)
		(layer "In7.Cu")
		(net "P5E_PEX2_STN7_TX_C_DN<124>")
	)
	(segment
		(start 296.416984 -375.181114)
		(end 296.289984 -375.308114)
		(width 0.1651)
		(layer "In7.Cu")
		(net "P5E_PEX2_STN7_TX_C_DN<124>")
	)
	(segment
		(start 293.341552 -352.473006)
		(end 291.787072 -354.027486)
		(width 0.1651)
		(layer "In7.Cu")
		(net "P5E_PEX2_STN7_TX_C_DN<124>")
	)
	(segment
		(start 68.479162 -343.685622)
		(end 68.159122 -343.365582)
		(width 0.13462)
		(layer "F.Cu")
		(net "P5E_PEX0_STN6_TX_DN<109>")
	)
	(segment
		(start 68.159122 -343.365582)
		(end 68.159122 -342.734138)
		(width 0.13462)
		(layer "F.Cu")
		(net "P5E_PEX0_STN6_TX_DN<109>")
	)
	(segment
		(start 68.159122 -342.734138)
		(end 68.453762 -342.439498)
		(width 0.13462)
		(layer "F.Cu")
		(net "P5E_PEX0_STN6_TX_DN<109>")
	)
	(segment
		(start 45.14723 -311.670192)
		(end 45.31106 -311.670192)
		(width 0.1143)
		(layer "In13.Cu")
		(net "P5E_PEX0_STN6_TX_DN<109>")
	)
	(segment
		(start 45.02023 -311.797192)
		(end 45.14723 -311.670192)
		(width 0.1143)
		(layer "In13.Cu")
		(net "P5E_PEX0_STN6_TX_DN<109>")
	)
	(segment
		(start 45.06595 -320.133472)
		(end 45.02023 -320.087752)
		(width 0.1143)
		(layer "In13.Cu")
		(net "P5E_PEX0_STN6_TX_DN<109>")
	)
	(segment
		(start 51.71313 -332.312264)
		(end 50.320194 -331.73543)
		(width 0.1651)
		(layer "In13.Cu")
		(net "P5E_PEX0_STN6_TX_DN<109>")
	)
	(segment
		(start 45.06595 -320.15557)
		(end 45.06595 -320.133472)
		(width 0.1143)
		(layer "In13.Cu")
		(net "P5E_PEX0_STN6_TX_DN<109>")
	)
	(segment
		(start 45.31106 -311.670192)
		(end 45.39996 -311.759092)
		(width 0.1143)
		(layer "In13.Cu")
		(net "P5E_PEX0_STN6_TX_DN<109>")
	)
	(segment
		(start 68.162932 -341.468456)
		(end 67.842892 -340.934294)
		(width 0.1651)
		(layer "In13.Cu")
		(net "P5E_PEX0_STN6_TX_DN<109>")
	)
	(segment
		(start 50.320194 -331.73543)
		(end 46.675294 -328.09053)
		(width 0.1651)
		(layer "In13.Cu")
		(net "P5E_PEX0_STN6_TX_DN<109>")
	)
	(segment
		(start 45.06595 -324.205346)
		(end 45.06595 -320.15557)
		(width 0.1651)
		(layer "In13.Cu")
		(net "P5E_PEX0_STN6_TX_DN<109>")
	)
	(segment
		(start 46.675294 -328.09053)
		(end 45.06595 -324.205346)
		(width 0.1651)
		(layer "In13.Cu")
		(net "P5E_PEX0_STN6_TX_DN<109>")
	)
	(segment
		(start 45.39996 -311.759092)
		(end 45.39996 -312.049922)
		(width 0.1143)
		(layer "In13.Cu")
		(net "P5E_PEX0_STN6_TX_DN<109>")
	)
	(segment
		(start 68.162932 -342.148668)
		(end 68.162932 -341.468456)
		(width 0.1651)
		(layer "In13.Cu")
		(net "P5E_PEX0_STN6_TX_DN<109>")
	)
	(segment
		(start 45.02023 -320.087752)
		(end 45.02023 -311.797192)
		(width 0.1143)
		(layer "In13.Cu")
		(net "P5E_PEX0_STN6_TX_DN<109>")
	)
	(segment
		(start 67.842892 -340.934294)
		(end 51.71313 -332.312264)
		(width 0.1651)
		(layer "In13.Cu")
		(net "P5E_PEX0_STN6_TX_DN<109>")
	)
	(segment
		(start 68.453762 -342.439498)
		(end 68.162932 -342.148668)
		(width 0.1651)
		(layer "In13.Cu")
		(net "P5E_PEX0_STN6_TX_DN<109>")
	)
	(segment
		(start 295.477692 -114.267742)
		(end 295.477692 -113.251742)
		(width 0.13208)
		(layer "F.Cu")
		(net "RST_SMB_NIC5_MUX_ISO_N")
	)
	(segment
		(start 295.597072 -112.510824)
		(end 296.384472 -112.510824)
		(width 0.13208)
		(layer "F.Cu")
		(net "RST_SMB_NIC5_MUX_ISO_N")
	)
	(segment
		(start 295.477692 -112.630204)
		(end 295.597072 -112.510824)
		(width 0.13208)
		(layer "F.Cu")
		(net "RST_SMB_NIC5_MUX_ISO_N")
	)
	(segment
		(start 295.477692 -115.283742)
		(end 295.477692 -114.267742)
		(width 0.13208)
		(layer "F.Cu")
		(net "RST_SMB_NIC5_MUX_ISO_N")
	)
	(segment
		(start 295.477692 -113.251742)
		(end 295.477692 -112.630204)
		(width 0.13208)
		(layer "F.Cu")
		(net "RST_SMB_NIC5_MUX_ISO_N")
	)
	(via
		(at 296.384472 -112.510824)
		(size 0.508)
		(drill 0.254)
		(layers "F.Cu" "B.Cu")
		(net "RST_SMB_NIC5_MUX_ISO_N")
	)
	(segment
		(start 297.360594 -113.83645)
		(end 297.360594 -112.963706)
		(width 0.13208)
		(layer "B.Cu")
		(net "RST_SMB_NIC5_MUX_ISO_N")
	)
	(segment
		(start 300.57852 -115.816634)
		(end 299.340778 -115.816634)
		(width 0.13208)
		(layer "B.Cu")
		(net "RST_SMB_NIC5_MUX_ISO_N")
	)
	(segment
		(start 296.907712 -112.510824)
		(end 296.384472 -112.510824)
		(width 0.13208)
		(layer "B.Cu")
		(net "RST_SMB_NIC5_MUX_ISO_N")
	)
	(segment
		(start 297.360594 -112.963706)
		(end 296.907712 -112.510824)
		(width 0.13208)
		(layer "B.Cu")
		(net "RST_SMB_NIC5_MUX_ISO_N")
	)
	(segment
		(start 300.69917 -116.513356)
		(end 300.69917 -115.937284)
		(width 0.13208)
		(layer "B.Cu")
		(net "RST_SMB_NIC5_MUX_ISO_N")
	)
	(segment
		(start 300.69917 -115.937284)
		(end 300.57852 -115.816634)
		(width 0.13208)
		(layer "B.Cu")
		(net "RST_SMB_NIC5_MUX_ISO_N")
	)
	(segment
		(start 299.340778 -115.816634)
		(end 297.360594 -113.83645)
		(width 0.13208)
		(layer "B.Cu")
		(net "RST_SMB_NIC5_MUX_ISO_N")
	)
	(segment
		(start 195.414646 -80.95996)
		(end 195.414646 -79.98206)
		(width 0.13208)
		(layer "F.Cu")
		(net "HP_NIC3_PWRGD")
	)
	(segment
		(start 196.12991 -79.98206)
		(end 195.414646 -79.98206)
		(width 0.13208)
		(layer "F.Cu")
		(net "HP_NIC3_PWRGD")
	)
	(segment
		(start 197.234302 -79.463646)
		(end 196.648324 -79.463646)
		(width 0.13208)
		(layer "F.Cu")
		(net "HP_NIC3_PWRGD")
	)
	(segment
		(start 196.648324 -79.463646)
		(end 196.12991 -79.98206)
		(width 0.13208)
		(layer "F.Cu")
		(net "HP_NIC3_PWRGD")
	)
	(via
		(at 196.12991 -79.98206)
		(size 0.508)
		(drill 0.254)
		(layers "F.Cu" "B.Cu")
		(net "HP_NIC3_PWRGD")
	)
	(segment
		(start 47.65294 -34.2265)
		(end 47.020988 -34.2265)
		(width 0.13462)
		(layer "F.Cu")
		(net "P5E_PEX0_STN2_TX_DP<43>")
	)
	(segment
		(start 47.020988 -34.2265)
		(end 46.701202 -34.546286)
		(width 0.13462)
		(layer "F.Cu")
		(net "P5E_PEX0_STN2_TX_DP<43>")
	)
	(segment
		(start 47.947326 -34.520886)
		(end 47.65294 -34.2265)
		(width 0.13462)
		(layer "F.Cu")
		(net "P5E_PEX0_STN2_TX_DP<43>")
	)
	(segment
		(start 43.574716 -162.54476)
		(end 47.25289 -265.771376)
		(width 0.1651)
		(layer "In11.Cu")
		(net "P5E_PEX0_STN2_TX_DP<43>")
	)
	(segment
		(start 44.342304 -112.80267)
		(end 42.797222 -115.113054)
		(width 0.1651)
		(layer "In11.Cu")
		(net "P5E_PEX0_STN2_TX_DP<43>")
	)
	(segment
		(start 52.578508 -38.491668)
		(end 52.702968 -38.507924)
		(width 0.1651)
		(layer "In11.Cu")
		(net "P5E_PEX0_STN2_TX_DP<43>")
	)
	(segment
		(start 51.580288 -37.047678)
		(end 51.564032 -37.172392)
		(width 0.1651)
		(layer "In11.Cu")
		(net "P5E_PEX0_STN2_TX_DP<43>")
	)
	(segment
		(start 51.866038 -37.56533)
		(end 51.990752 -37.581586)
		(width 0.1651)
		(layer "In11.Cu")
		(net "P5E_PEX0_STN2_TX_DP<43>")
	)
	(segment
		(start 62.044072 -60.343288)
		(end 60.56376 -68.413884)
		(width 0.1651)
		(layer "In11.Cu")
		(net "P5E_PEX0_STN2_TX_DP<43>")
	)
	(segment
		(start 47.63389 -269.63751)
		(end 47.63389 -271.399)
		(width 0.1651)
		(layer "In11.Cu")
		(net "P5E_PEX0_STN2_TX_DP<43>")
	)
	(segment
		(start 52.702968 -38.507924)
		(end 60.978288 -49.270158)
		(width 0.1651)
		(layer "In11.Cu")
		(net "P5E_PEX0_STN2_TX_DP<43>")
	)
	(segment
		(start 48.13554 -278.420068)
		(end 48.24984 -278.534368)
		(width 0.1143)
		(layer "In11.Cu")
		(net "P5E_PEX0_STN2_TX_DP<43>")
	)
	(segment
		(start 42.519346 -116.42979)
		(end 42.511472 -146.815048)
		(width 0.1651)
		(layer "In11.Cu")
		(net "P5E_PEX0_STN2_TX_DP<43>")
	)
	(segment
		(start 50.739802 -35.954716)
		(end 51.580034 -37.047678)
		(width 0.1651)
		(layer "In11.Cu")
		(net "P5E_PEX0_STN2_TX_DP<43>")
	)
	(segment
		(start 48.24984 -278.534368)
		(end 48.24984 -278.799798)
		(width 0.1143)
		(layer "In11.Cu")
		(net "P5E_PEX0_STN2_TX_DP<43>")
	)
	(segment
		(start 48.665384 -101.587808)
		(end 45.531024 -111.631222)
		(width 0.1651)
		(layer "In11.Cu")
		(net "P5E_PEX0_STN2_TX_DP<43>")
	)
	(segment
		(start 60.978288 -49.270158)
		(end 61.417454 -50.549048)
		(width 0.1651)
		(layer "In11.Cu")
		(net "P5E_PEX0_STN2_TX_DP<43>")
	)
	(segment
		(start 42.511472 -146.815048)
		(end 43.574716 -162.54476)
		(width 0.1651)
		(layer "In11.Cu")
		(net "P5E_PEX0_STN2_TX_DP<43>")
	)
	(segment
		(start 42.797222 -115.113054)
		(end 42.519346 -116.42979)
		(width 0.1651)
		(layer "In11.Cu")
		(net "P5E_PEX0_STN2_TX_DP<43>")
	)
	(segment
		(start 47.67961 -278.20493)
		(end 47.894748 -278.420068)
		(width 0.1143)
		(layer "In11.Cu")
		(net "P5E_PEX0_STN2_TX_DP<43>")
	)
	(segment
		(start 47.947326 -34.520886)
		(end 48.238156 -34.230056)
		(width 0.1651)
		(layer "In11.Cu")
		(net "P5E_PEX0_STN2_TX_DP<43>")
	)
	(segment
		(start 61.417454 -50.549048)
		(end 62.044072 -60.343288)
		(width 0.1651)
		(layer "In11.Cu")
		(net "P5E_PEX0_STN2_TX_DP<43>")
	)
	(segment
		(start 47.25289 -265.771376)
		(end 47.63389 -269.63751)
		(width 0.1651)
		(layer "In11.Cu")
		(net "P5E_PEX0_STN2_TX_DP<43>")
	)
	(segment
		(start 50.352452 -95.389446)
		(end 48.665384 -101.587808)
		(width 0.1651)
		(layer "In11.Cu")
		(net "P5E_PEX0_STN2_TX_DP<43>")
	)
	(segment
		(start 51.580034 -37.047678)
		(end 51.580288 -37.047678)
		(width 0.1651)
		(layer "In11.Cu")
		(net "P5E_PEX0_STN2_TX_DP<43>")
	)
	(segment
		(start 52.276248 -38.09873)
		(end 52.578508 -38.491668)
		(width 0.1651)
		(layer "In11.Cu")
		(net "P5E_PEX0_STN2_TX_DP<43>")
	)
	(segment
		(start 47.894748 -278.420068)
		(end 48.13554 -278.420068)
		(width 0.1143)
		(layer "In11.Cu")
		(net "P5E_PEX0_STN2_TX_DP<43>")
	)
	(segment
		(start 51.564032 -37.172392)
		(end 51.866038 -37.56533)
		(width 0.1651)
		(layer "In11.Cu")
		(net "P5E_PEX0_STN2_TX_DP<43>")
	)
	(segment
		(start 49.04105 -34.230056)
		(end 50.739802 -35.954716)
		(width 0.1651)
		(layer "In11.Cu")
		(net "P5E_PEX0_STN2_TX_DP<43>")
	)
	(segment
		(start 47.63389 -271.427448)
		(end 47.67961 -271.473168)
		(width 0.1143)
		(layer "In11.Cu")
		(net "P5E_PEX0_STN2_TX_DP<43>")
	)
	(segment
		(start 60.56376 -68.413884)
		(end 50.352452 -95.389446)
		(width 0.1651)
		(layer "In11.Cu")
		(net "P5E_PEX0_STN2_TX_DP<43>")
	)
	(segment
		(start 51.990752 -37.581586)
		(end 52.292504 -37.974016)
		(width 0.1651)
		(layer "In11.Cu")
		(net "P5E_PEX0_STN2_TX_DP<43>")
	)
	(segment
		(start 47.63389 -271.399)
		(end 47.63389 -271.427448)
		(width 0.1143)
		(layer "In11.Cu")
		(net "P5E_PEX0_STN2_TX_DP<43>")
	)
	(segment
		(start 45.531024 -111.631222)
		(end 44.342304 -112.80267)
		(width 0.1651)
		(layer "In11.Cu")
		(net "P5E_PEX0_STN2_TX_DP<43>")
	)
	(segment
		(start 52.292504 -37.974016)
		(end 52.276248 -38.09873)
		(width 0.1651)
		(layer "In11.Cu")
		(net "P5E_PEX0_STN2_TX_DP<43>")
	)
	(segment
		(start 47.67961 -271.473168)
		(end 47.67961 -278.20493)
		(width 0.1143)
		(layer "In11.Cu")
		(net "P5E_PEX0_STN2_TX_DP<43>")
	)
	(segment
		(start 48.238156 -34.230056)
		(end 49.04105 -34.230056)
		(width 0.1651)
		(layer "In11.Cu")
		(net "P5E_PEX0_STN2_TX_DP<43>")
	)
	(segment
		(start 303.20107 -28.55468)
		(end 302.588422 -28.55468)
		(width 0.13462)
		(layer "F.Cu")
		(net "P5E_PEX2_STN2_TX_DN<36>")
	)
	(segment
		(start 302.588422 -28.55468)
		(end 302.258984 -28.225242)
		(width 0.13462)
		(layer "F.Cu")
		(net "P5E_PEX2_STN2_TX_DN<36>")
	)
	(segment
		(start 303.505108 -28.250642)
		(end 303.20107 -28.55468)
		(width 0.13462)
		(layer "F.Cu")
		(net "P5E_PEX2_STN2_TX_DN<36>")
	)
	(segment
		(start 310.453786 -31.885636)
		(end 315.447172 -39.727886)
		(width 0.1651)
		(layer "In11.Cu")
		(net "P5E_PEX2_STN2_TX_DN<36>")
	)
	(segment
		(start 323.47408 -58.438034)
		(end 323.47408 -60.59424)
		(width 0.1651)
		(layer "In11.Cu")
		(net "P5E_PEX2_STN2_TX_DN<36>")
	)
	(segment
		(start 286.985456 -280.129488)
		(end 287.099756 -280.015188)
		(width 0.1143)
		(layer "In11.Cu")
		(net "P5E_PEX2_STN2_TX_DN<36>")
	)
	(segment
		(start 286.765746 -271.399)
		(end 286.765746 -271.427448)
		(width 0.1143)
		(layer "In11.Cu")
		(net "P5E_PEX2_STN2_TX_DN<36>")
	)
	(segment
		(start 322.347082 -47.60849)
		(end 323.47408 -58.438034)
		(width 0.1651)
		(layer "In11.Cu")
		(net "P5E_PEX2_STN2_TX_DN<36>")
	)
	(segment
		(start 286.823658 -280.129488)
		(end 286.985456 -280.129488)
		(width 0.1143)
		(layer "In11.Cu")
		(net "P5E_PEX2_STN2_TX_DN<36>")
	)
	(segment
		(start 287.099756 -280.015188)
		(end 287.099756 -279.749504)
		(width 0.1143)
		(layer "In11.Cu")
		(net "P5E_PEX2_STN2_TX_DN<36>")
	)
	(segment
		(start 307.775356 -29.206952)
		(end 310.453786 -31.885636)
		(width 0.1651)
		(layer "In11.Cu")
		(net "P5E_PEX2_STN2_TX_DN<36>")
	)
	(segment
		(start 286.720026 -271.473168)
		(end 286.720026 -280.025856)
		(width 0.1143)
		(layer "In11.Cu")
		(net "P5E_PEX2_STN2_TX_DN<36>")
	)
	(segment
		(start 303.795938 -28.541472)
		(end 306.171854 -28.541472)
		(width 0.1651)
		(layer "In11.Cu")
		(net "P5E_PEX2_STN2_TX_DN<36>")
	)
	(segment
		(start 286.765746 -271.427448)
		(end 286.720026 -271.473168)
		(width 0.1143)
		(layer "In11.Cu")
		(net "P5E_PEX2_STN2_TX_DN<36>")
	)
	(segment
		(start 323.47408 -60.59424)
		(end 322.82765 -62.998604)
		(width 0.1651)
		(layer "In11.Cu")
		(net "P5E_PEX2_STN2_TX_DN<36>")
	)
	(segment
		(start 321.832478 -65.005458)
		(end 299.617892 -94.024958)
		(width 0.1651)
		(layer "In11.Cu")
		(net "P5E_PEX2_STN2_TX_DN<36>")
	)
	(segment
		(start 303.505108 -28.250642)
		(end 303.795938 -28.541472)
		(width 0.1651)
		(layer "In11.Cu")
		(net "P5E_PEX2_STN2_TX_DN<36>")
	)
	(segment
		(start 296.450512 -108.111798)
		(end 294.822118 -116.6876)
		(width 0.1651)
		(layer "In11.Cu")
		(net "P5E_PEX2_STN2_TX_DN<36>")
	)
	(segment
		(start 294.306498 -120.957594)
		(end 286.765746 -263.42467)
		(width 0.1651)
		(layer "In11.Cu")
		(net "P5E_PEX2_STN2_TX_DN<36>")
	)
	(segment
		(start 286.720026 -280.025856)
		(end 286.823658 -280.129488)
		(width 0.1143)
		(layer "In11.Cu")
		(net "P5E_PEX2_STN2_TX_DN<36>")
	)
	(segment
		(start 286.765746 -263.42467)
		(end 286.765746 -271.399)
		(width 0.1651)
		(layer "In11.Cu")
		(net "P5E_PEX2_STN2_TX_DN<36>")
	)
	(segment
		(start 315.447172 -39.727886)
		(end 322.347082 -47.60849)
		(width 0.1651)
		(layer "In11.Cu")
		(net "P5E_PEX2_STN2_TX_DN<36>")
	)
	(segment
		(start 322.82765 -62.998604)
		(end 321.832478 -65.005458)
		(width 0.1651)
		(layer "In11.Cu")
		(net "P5E_PEX2_STN2_TX_DN<36>")
	)
	(segment
		(start 306.171854 -28.541472)
		(end 307.775356 -29.206952)
		(width 0.1651)
		(layer "In11.Cu")
		(net "P5E_PEX2_STN2_TX_DN<36>")
	)
	(segment
		(start 299.617892 -94.024958)
		(end 296.450512 -108.111798)
		(width 0.1651)
		(layer "In11.Cu")
		(net "P5E_PEX2_STN2_TX_DN<36>")
	)
	(segment
		(start 294.822118 -116.6876)
		(end 294.306498 -120.957594)
		(width 0.1651)
		(layer "In11.Cu")
		(net "P5E_PEX2_STN2_TX_DN<36>")
	)
	(segment
		(start 399.14322 -355.978206)
		(end 399.462752 -355.658674)
		(width 0.13462)
		(layer "F.Cu")
		(net "P5E_PEX3_STN5_TX_DP<86>")
	)
	(segment
		(start 399.462752 -355.026214)
		(end 399.16862 -354.732082)
		(width 0.13462)
		(layer "F.Cu")
		(net "P5E_PEX3_STN5_TX_DP<86>")
	)
	(segment
		(start 399.462752 -355.658674)
		(end 399.462752 -355.026214)
		(width 0.13462)
		(layer "F.Cu")
		(net "P5E_PEX3_STN5_TX_DP<86>")
	)
	(segment
		(start 401.01393 -341.48522)
		(end 401.065238 -341.412322)
		(width 0.1651)
		(layer "In7.Cu")
		(net "P5E_PEX3_STN5_TX_DP<86>")
	)
	(segment
		(start 412.585662 -311.479692)
		(end 412.699962 -311.365392)
		(width 0.1143)
		(layer "In7.Cu")
		(net "P5E_PEX3_STN5_TX_DP<86>")
	)
	(segment
		(start 410.910532 -327.342754)
		(end 412.084012 -324.509892)
		(width 0.1651)
		(layer "In7.Cu")
		(net "P5E_PEX3_STN5_TX_DP<86>")
	)
	(segment
		(start 412.084012 -319.9892)
		(end 412.084012 -319.960752)
		(width 0.1143)
		(layer "In7.Cu")
		(net "P5E_PEX3_STN5_TX_DP<86>")
	)
	(segment
		(start 399.45945 -354.441252)
		(end 399.45945 -353.814126)
		(width 0.1651)
		(layer "In7.Cu")
		(net "P5E_PEX3_STN5_TX_DP<86>")
	)
	(segment
		(start 412.129732 -319.915032)
		(end 412.129732 -311.705498)
		(width 0.1143)
		(layer "In7.Cu")
		(net "P5E_PEX3_STN5_TX_DP<86>")
	)
	(segment
		(start 399.16862 -354.732082)
		(end 399.45945 -354.441252)
		(width 0.1651)
		(layer "In7.Cu")
		(net "P5E_PEX3_STN5_TX_DP<86>")
	)
	(segment
		(start 412.084012 -319.960752)
		(end 412.129732 -319.915032)
		(width 0.1143)
		(layer "In7.Cu")
		(net "P5E_PEX3_STN5_TX_DP<86>")
	)
	(segment
		(start 409.106624 -330.04252)
		(end 410.910532 -327.342754)
		(width 0.1651)
		(layer "In7.Cu")
		(net "P5E_PEX3_STN5_TX_DP<86>")
	)
	(segment
		(start 412.084012 -324.509892)
		(end 412.084012 -319.9892)
		(width 0.1651)
		(layer "In7.Cu")
		(net "P5E_PEX3_STN5_TX_DP<86>")
	)
	(segment
		(start 399.45945 -353.814126)
		(end 401.01393 -352.259646)
		(width 0.1651)
		(layer "In7.Cu")
		(net "P5E_PEX3_STN5_TX_DP<86>")
	)
	(segment
		(start 412.355538 -311.479692)
		(end 412.585662 -311.479692)
		(width 0.1143)
		(layer "In7.Cu")
		(net "P5E_PEX3_STN5_TX_DP<86>")
	)
	(segment
		(start 412.699962 -311.365392)
		(end 412.699962 -311.099962)
		(width 0.1143)
		(layer "In7.Cu")
		(net "P5E_PEX3_STN5_TX_DP<86>")
	)
	(segment
		(start 412.129732 -311.705498)
		(end 412.355538 -311.479692)
		(width 0.1143)
		(layer "In7.Cu")
		(net "P5E_PEX3_STN5_TX_DP<86>")
	)
	(segment
		(start 401.01393 -352.259646)
		(end 401.01393 -341.48522)
		(width 0.1651)
		(layer "In7.Cu")
		(net "P5E_PEX3_STN5_TX_DP<86>")
	)
	(segment
		(start 401.065238 -341.412322)
		(end 401.065492 -341.412322)
		(width 0.1651)
		(layer "In7.Cu")
		(net "P5E_PEX3_STN5_TX_DP<86>")
	)
	(segment
		(start 401.065492 -341.412322)
		(end 409.106624 -330.04252)
		(width 0.1651)
		(layer "In7.Cu")
		(net "P5E_PEX3_STN5_TX_DP<86>")
	)
	(segment
		(start 416.402012 -355.978206)
		(end 416.081464 -355.657658)
		(width 0.13462)
		(layer "F.Cu")
		(net "P5E_PEX3_STN7_TX_DN<115>")
	)
	(segment
		(start 416.081464 -355.657658)
		(end 416.081464 -355.02723)
		(width 0.13462)
		(layer "F.Cu")
		(net "P5E_PEX3_STN7_TX_DN<115>")
	)
	(segment
		(start 416.081464 -355.02723)
		(end 416.376612 -354.732082)
		(width 0.13462)
		(layer "F.Cu")
		(net "P5E_PEX3_STN7_TX_DN<115>")
	)
	(segment
		(start 416.376612 -354.732082)
		(end 416.085782 -354.441252)
		(width 0.1651)
		(layer "In11.Cu")
		(net "P5E_PEX3_STN7_TX_DN<115>")
	)
	(segment
		(start 372.153942 -311.546494)
		(end 372.13286 -311.44083)
		(width 0.1651)
		(layer "In11.Cu")
		(net "P5E_PEX3_STN7_TX_DN<115>")
	)
	(segment
		(start 369.867688 -314.830968)
		(end 369.973606 -314.809886)
		(width 0.1651)
		(layer "In11.Cu")
		(net "P5E_PEX3_STN7_TX_DN<115>")
	)
	(segment
		(start 379.745494 -304.305208)
		(end 380.202186 -304.115724)
		(width 0.1651)
		(layer "In11.Cu")
		(net "P5E_PEX3_STN7_TX_DN<115>")
	)
	(segment
		(start 369.333526 -326.382126)
		(end 367.64214 -322.298568)
		(width 0.1651)
		(layer "In11.Cu")
		(net "P5E_PEX3_STN7_TX_DN<115>")
	)
	(segment
		(start 417.640262 -352.376486)
		(end 417.640262 -341.7824)
		(width 0.1651)
		(layer "In11.Cu")
		(net "P5E_PEX3_STN7_TX_DN<115>")
	)
	(segment
		(start 378.689362 -304.74285)
		(end 379.146816 -304.553366)
		(width 0.1651)
		(layer "In11.Cu")
		(net "P5E_PEX3_STN7_TX_DN<115>")
	)
	(segment
		(start 377.528328 -305.223672)
		(end 378.090684 -304.990754)
		(width 0.1651)
		(layer "In11.Cu")
		(net "P5E_PEX3_STN7_TX_DN<115>")
	)
	(segment
		(start 373.043196 -310.078628)
		(end 373.14886 -310.057546)
		(width 0.1651)
		(layer "In11.Cu")
		(net "P5E_PEX3_STN7_TX_DN<115>")
	)
	(segment
		(start 379.246384 -304.594514)
		(end 379.704346 -304.404776)
		(width 0.1651)
		(layer "In11.Cu")
		(net "P5E_PEX3_STN7_TX_DN<115>")
	)
	(segment
		(start 371.772942 -311.979564)
		(end 371.878606 -311.958482)
		(width 0.1651)
		(layer "In11.Cu")
		(net "P5E_PEX3_STN7_TX_DN<115>")
	)
	(segment
		(start 373.424196 -309.645558)
		(end 373.403114 -309.53964)
		(width 0.1651)
		(layer "In11.Cu")
		(net "P5E_PEX3_STN7_TX_DN<115>")
	)
	(segment
		(start 371.518942 -312.496962)
		(end 371.49786 -312.391298)
		(width 0.1651)
		(layer "In11.Cu")
		(net "P5E_PEX3_STN7_TX_DN<115>")
	)
	(segment
		(start 417.640262 -341.7824)
		(end 416.222434 -339.557868)
		(width 0.1651)
		(layer "In11.Cu")
		(net "P5E_PEX3_STN7_TX_DN<115>")
	)
	(segment
		(start 369.592606 -315.242702)
		(end 369.867688 -314.830968)
		(width 0.1651)
		(layer "In11.Cu")
		(net "P5E_PEX3_STN7_TX_DN<115>")
	)
	(segment
		(start 392.065256 -304.449734)
		(end 391.799826 -304.449734)
		(width 0.1143)
		(layer "In11.Cu")
		(net "P5E_PEX3_STN7_TX_DN<115>")
	)
	(segment
		(start 370.608606 -313.859418)
		(end 370.883942 -313.44743)
		(width 0.1651)
		(layer "In11.Cu")
		(net "P5E_PEX3_STN7_TX_DN<115>")
	)
	(segment
		(start 367.64214 -322.298568)
		(end 367.64214 -318.993012)
		(width 0.1651)
		(layer "In11.Cu")
		(net "P5E_PEX3_STN7_TX_DN<115>")
	)
	(segment
		(start 379.146816 -304.553366)
		(end 379.246384 -304.594514)
		(width 0.1651)
		(layer "In11.Cu")
		(net "P5E_PEX3_STN7_TX_DN<115>")
	)
	(segment
		(start 416.085782 -353.930966)
		(end 417.640262 -352.376486)
		(width 0.1651)
		(layer "In11.Cu")
		(net "P5E_PEX3_STN7_TX_DN<115>")
	)
	(segment
		(start 369.973606 -314.809886)
		(end 370.248942 -314.397898)
		(width 0.1651)
		(layer "In11.Cu")
		(net "P5E_PEX3_STN7_TX_DN<115>")
	)
	(segment
		(start 369.338352 -315.760354)
		(end 369.613688 -315.348366)
		(width 0.1651)
		(layer "In11.Cu")
		(net "P5E_PEX3_STN7_TX_DN<115>")
	)
	(segment
		(start 369.613688 -315.348366)
		(end 369.592606 -315.242702)
		(width 0.1651)
		(layer "In11.Cu")
		(net "P5E_PEX3_STN7_TX_DN<115>")
	)
	(segment
		(start 392.179556 -304.173636)
		(end 392.179556 -304.335434)
		(width 0.1143)
		(layer "In11.Cu")
		(net "P5E_PEX3_STN7_TX_DN<115>")
	)
	(segment
		(start 372.51386 -311.008014)
		(end 372.789196 -310.596026)
		(width 0.1651)
		(layer "In11.Cu")
		(net "P5E_PEX3_STN7_TX_DN<115>")
	)
	(segment
		(start 368.548158 -316.806072)
		(end 369.232688 -315.781436)
		(width 0.1651)
		(layer "In11.Cu")
		(net "P5E_PEX3_STN7_TX_DN<115>")
	)
	(segment
		(start 371.243606 -312.90895)
		(end 371.518942 -312.496962)
		(width 0.1651)
		(layer "In11.Cu")
		(net "P5E_PEX3_STN7_TX_DN<115>")
	)
	(segment
		(start 370.22786 -314.292234)
		(end 370.502942 -313.8805)
		(width 0.1651)
		(layer "In11.Cu")
		(net "P5E_PEX3_STN7_TX_DN<115>")
	)
	(segment
		(start 392.075924 -304.070004)
		(end 392.179556 -304.173636)
		(width 0.1143)
		(layer "In11.Cu")
		(net "P5E_PEX3_STN7_TX_DN<115>")
	)
	(segment
		(start 374.56745 -330.224384)
		(end 371.474238 -328.522838)
		(width 0.1651)
		(layer "In11.Cu")
		(net "P5E_PEX3_STN7_TX_DN<115>")
	)
	(segment
		(start 372.789196 -310.596026)
		(end 372.768114 -310.490362)
		(width 0.1651)
		(layer "In11.Cu")
		(net "P5E_PEX3_STN7_TX_DN<115>")
	)
	(segment
		(start 370.502942 -313.8805)
		(end 370.608606 -313.859418)
		(width 0.1651)
		(layer "In11.Cu")
		(net "P5E_PEX3_STN7_TX_DN<115>")
	)
	(segment
		(start 371.49786 -312.391298)
		(end 371.772942 -311.979564)
		(width 0.1651)
		(layer "In11.Cu")
		(net "P5E_PEX3_STN7_TX_DN<115>")
	)
	(segment
		(start 371.878606 -311.958482)
		(end 372.153942 -311.546494)
		(width 0.1651)
		(layer "In11.Cu")
		(net "P5E_PEX3_STN7_TX_DN<115>")
	)
	(segment
		(start 370.248942 -314.397898)
		(end 370.22786 -314.292234)
		(width 0.1651)
		(layer "In11.Cu")
		(net "P5E_PEX3_STN7_TX_DN<115>")
	)
	(segment
		(start 370.86286 -313.341766)
		(end 371.137942 -312.930032)
		(width 0.1651)
		(layer "In11.Cu")
		(net "P5E_PEX3_STN7_TX_DN<115>")
	)
	(segment
		(start 383.921 -304.115724)
		(end 383.949448 -304.115724)
		(width 0.1143)
		(layer "In11.Cu")
		(net "P5E_PEX3_STN7_TX_DN<115>")
	)
	(segment
		(start 373.14886 -310.057546)
		(end 373.424196 -309.645558)
		(width 0.1651)
		(layer "In11.Cu")
		(net "P5E_PEX3_STN7_TX_DN<115>")
	)
	(segment
		(start 369.232688 -315.781436)
		(end 369.338352 -315.760354)
		(width 0.1651)
		(layer "In11.Cu")
		(net "P5E_PEX3_STN7_TX_DN<115>")
	)
	(segment
		(start 416.085782 -354.441252)
		(end 416.085782 -353.930966)
		(width 0.1651)
		(layer "In11.Cu")
		(net "P5E_PEX3_STN7_TX_DN<115>")
	)
	(segment
		(start 372.13286 -311.44083)
		(end 372.407942 -311.029096)
		(width 0.1651)
		(layer "In11.Cu")
		(net "P5E_PEX3_STN7_TX_DN<115>")
	)
	(segment
		(start 392.179556 -304.335434)
		(end 392.065256 -304.449734)
		(width 0.1143)
		(layer "In11.Cu")
		(net "P5E_PEX3_STN7_TX_DN<115>")
	)
	(segment
		(start 367.64214 -318.993012)
		(end 368.548158 -316.806072)
		(width 0.1651)
		(layer "In11.Cu")
		(net "P5E_PEX3_STN7_TX_DN<115>")
	)
	(segment
		(start 380.202186 -304.115724)
		(end 383.921 -304.115724)
		(width 0.1651)
		(layer "In11.Cu")
		(net "P5E_PEX3_STN7_TX_DN<115>")
	)
	(segment
		(start 372.768114 -310.490362)
		(end 373.043196 -310.078628)
		(width 0.1651)
		(layer "In11.Cu")
		(net "P5E_PEX3_STN7_TX_DN<115>")
	)
	(segment
		(start 370.883942 -313.44743)
		(end 370.86286 -313.341766)
		(width 0.1651)
		(layer "In11.Cu")
		(net "P5E_PEX3_STN7_TX_DN<115>")
	)
	(segment
		(start 373.78767 -308.96433)
		(end 377.528328 -305.223672)
		(width 0.1651)
		(layer "In11.Cu")
		(net "P5E_PEX3_STN7_TX_DN<115>")
	)
	(segment
		(start 371.137942 -312.930032)
		(end 371.243606 -312.90895)
		(width 0.1651)
		(layer "In11.Cu")
		(net "P5E_PEX3_STN7_TX_DN<115>")
	)
	(segment
		(start 378.648214 -304.842418)
		(end 378.689362 -304.74285)
		(width 0.1651)
		(layer "In11.Cu")
		(net "P5E_PEX3_STN7_TX_DN<115>")
	)
	(segment
		(start 371.474238 -328.522838)
		(end 369.333526 -326.382126)
		(width 0.1651)
		(layer "In11.Cu")
		(net "P5E_PEX3_STN7_TX_DN<115>")
	)
	(segment
		(start 373.403114 -309.53964)
		(end 373.78767 -308.96433)
		(width 0.1651)
		(layer "In11.Cu")
		(net "P5E_PEX3_STN7_TX_DN<115>")
	)
	(segment
		(start 416.222434 -339.557868)
		(end 374.56745 -330.224384)
		(width 0.1651)
		(layer "In11.Cu")
		(net "P5E_PEX3_STN7_TX_DN<115>")
	)
	(segment
		(start 379.704346 -304.404776)
		(end 379.745494 -304.305208)
		(width 0.1651)
		(layer "In11.Cu")
		(net "P5E_PEX3_STN7_TX_DN<115>")
	)
	(segment
		(start 378.090684 -304.990754)
		(end 378.190252 -305.032156)
		(width 0.1651)
		(layer "In11.Cu")
		(net "P5E_PEX3_STN7_TX_DN<115>")
	)
	(segment
		(start 372.407942 -311.029096)
		(end 372.51386 -311.008014)
		(width 0.1651)
		(layer "In11.Cu")
		(net "P5E_PEX3_STN7_TX_DN<115>")
	)
	(segment
		(start 383.995168 -304.070004)
		(end 392.075924 -304.070004)
		(width 0.1143)
		(layer "In11.Cu")
		(net "P5E_PEX3_STN7_TX_DN<115>")
	)
	(segment
		(start 383.949448 -304.115724)
		(end 383.995168 -304.070004)
		(width 0.1143)
		(layer "In11.Cu")
		(net "P5E_PEX3_STN7_TX_DN<115>")
	)
	(segment
		(start 378.190252 -305.032156)
		(end 378.648214 -304.842418)
		(width 0.1651)
		(layer "In11.Cu")
		(net "P5E_PEX3_STN7_TX_DN<115>")
	)
	(segment
		(start 39.606728 -360.375708)
		(end 40.113458 -357.827834)
		(width 0.1651)
		(layer "In5.Cu")
		(net "P5E_PEX0_STN7_RX_DN<123>")
	)
	(segment
		(start 35.13582 -384.08102)
		(end 35.65906 -383.55778)
		(width 0.1651)
		(layer "In5.Cu")
		(net "P5E_PEX0_STN7_RX_DN<123>")
	)
	(segment
		(start 34.509964 -384.590036)
		(end 34.509964 -384.20802)
		(width 0.1651)
		(layer "In5.Cu")
		(net "P5E_PEX0_STN7_RX_DN<123>")
	)
	(segment
		(start 38.749986 -318.434466)
		(end 38.749986 -318.699896)
		(width 0.1143)
		(layer "In5.Cu")
		(net "P5E_PEX0_STN7_RX_DN<123>")
	)
	(segment
		(start 38.635686 -318.320166)
		(end 38.749986 -318.434466)
		(width 0.1143)
		(layer "In5.Cu")
		(net "P5E_PEX0_STN7_RX_DN<123>")
	)
	(segment
		(start 40.113458 -341.383366)
		(end 38.415976 -332.849728)
		(width 0.1651)
		(layer "In5.Cu")
		(net "P5E_PEX0_STN7_RX_DN<123>")
	)
	(segment
		(start 34.509964 -384.20802)
		(end 34.636964 -384.08102)
		(width 0.1651)
		(layer "In5.Cu")
		(net "P5E_PEX0_STN7_RX_DN<123>")
	)
	(segment
		(start 38.415976 -332.849728)
		(end 38.415976 -319.995296)
		(width 0.1651)
		(layer "In5.Cu")
		(net "P5E_PEX0_STN7_RX_DN<123>")
	)
	(segment
		(start 35.65906 -370.01958)
		(end 35.70224 -369.802156)
		(width 0.1651)
		(layer "In5.Cu")
		(net "P5E_PEX0_STN7_RX_DN<123>")
	)
	(segment
		(start 38.415976 -319.995296)
		(end 38.415976 -319.966848)
		(width 0.1143)
		(layer "In5.Cu")
		(net "P5E_PEX0_STN7_RX_DN<123>")
	)
	(segment
		(start 35.70224 -369.802156)
		(end 39.606728 -360.375708)
		(width 0.1651)
		(layer "In5.Cu")
		(net "P5E_PEX0_STN7_RX_DN<123>")
	)
	(segment
		(start 34.636964 -384.08102)
		(end 35.13582 -384.08102)
		(width 0.1651)
		(layer "In5.Cu")
		(net "P5E_PEX0_STN7_RX_DN<123>")
	)
	(segment
		(start 38.415976 -319.966848)
		(end 38.370256 -319.921128)
		(width 0.1143)
		(layer "In5.Cu")
		(net "P5E_PEX0_STN7_RX_DN<123>")
	)
	(segment
		(start 38.370256 -319.921128)
		(end 38.370256 -318.434466)
		(width 0.1143)
		(layer "In5.Cu")
		(net "P5E_PEX0_STN7_RX_DN<123>")
	)
	(segment
		(start 38.370256 -318.434466)
		(end 38.484556 -318.320166)
		(width 0.1143)
		(layer "In5.Cu")
		(net "P5E_PEX0_STN7_RX_DN<123>")
	)
	(segment
		(start 35.65906 -383.55778)
		(end 35.65906 -370.01958)
		(width 0.1651)
		(layer "In5.Cu")
		(net "P5E_PEX0_STN7_RX_DN<123>")
	)
	(segment
		(start 38.484556 -318.320166)
		(end 38.635686 -318.320166)
		(width 0.1143)
		(layer "In5.Cu")
		(net "P5E_PEX0_STN7_RX_DN<123>")
	)
	(segment
		(start 40.113458 -357.827834)
		(end 40.113458 -341.383366)
		(width 0.1651)
		(layer "In5.Cu")
		(net "P5E_PEX0_STN7_RX_DN<123>")
	)
	(segment
		(start 64.775842 -356.831646)
		(end 64.455802 -356.511606)
		(width 0.13462)
		(layer "F.Cu")
		(net "P5E_PEX0_STN5_TX_C_DP<82>")
	)
	(segment
		(start 64.481202 -357.75773)
		(end 64.775842 -357.46309)
		(width 0.13462)
		(layer "F.Cu")
		(net "P5E_PEX0_STN5_TX_C_DP<82>")
	)
	(segment
		(start 64.775842 -357.46309)
		(end 64.775842 -356.831646)
		(width 0.13462)
		(layer "F.Cu")
		(net "P5E_PEX0_STN5_TX_C_DP<82>")
	)
	(segment
		(start 77.202284 -404.370032)
		(end 76.773278 -404.799038)
		(width 0.1651)
		(layer "In7.Cu")
		(net "P5E_PEX0_STN5_TX_C_DP<82>")
	)
	(segment
		(start 75.268582 -392.909552)
		(end 75.726036 -393.099036)
		(width 0.1651)
		(layer "In7.Cu")
		(net "P5E_PEX0_STN5_TX_C_DP<82>")
	)
	(segment
		(start 74.073004 -392.510518)
		(end 74.189082 -392.462258)
		(width 0.1651)
		(layer "In7.Cu")
		(net "P5E_PEX0_STN5_TX_C_DP<82>")
	)
	(segment
		(start 73.567036 -392.204448)
		(end 73.615042 -392.32078)
		(width 0.1651)
		(layer "In7.Cu")
		(net "P5E_PEX0_STN5_TX_C_DP<82>")
	)
	(segment
		(start 74.189082 -392.462258)
		(end 74.646536 -392.651742)
		(width 0.1651)
		(layer "In7.Cu")
		(net "P5E_PEX0_STN5_TX_C_DP<82>")
	)
	(segment
		(start 75.726036 -393.099036)
		(end 76.330302 -393.703302)
		(width 0.1651)
		(layer "In7.Cu")
		(net "P5E_PEX0_STN5_TX_C_DP<82>")
	)
	(segment
		(start 69.091556 -390.35101)
		(end 73.567036 -392.204448)
		(width 0.1651)
		(layer "In7.Cu")
		(net "P5E_PEX0_STN5_TX_C_DP<82>")
	)
	(segment
		(start 76.309982 -404.672038)
		(end 76.309982 -404.290022)
		(width 0.1651)
		(layer "In7.Cu")
		(net "P5E_PEX0_STN5_TX_C_DP<82>")
	)
	(segment
		(start 76.680568 -394.179298)
		(end 76.806298 -394.179298)
		(width 0.1651)
		(layer "In7.Cu")
		(net "P5E_PEX0_STN5_TX_C_DP<82>")
	)
	(segment
		(start 76.330302 -393.829032)
		(end 76.680568 -394.179298)
		(width 0.1651)
		(layer "In7.Cu")
		(net "P5E_PEX0_STN5_TX_C_DP<82>")
	)
	(segment
		(start 76.330302 -393.703302)
		(end 76.330302 -393.829032)
		(width 0.1651)
		(layer "In7.Cu")
		(net "P5E_PEX0_STN5_TX_C_DP<82>")
	)
	(segment
		(start 73.615042 -392.32078)
		(end 74.073004 -392.510518)
		(width 0.1651)
		(layer "In7.Cu")
		(net "P5E_PEX0_STN5_TX_C_DP<82>")
	)
	(segment
		(start 74.694542 -392.76782)
		(end 75.152504 -392.957812)
		(width 0.1651)
		(layer "In7.Cu")
		(net "P5E_PEX0_STN5_TX_C_DP<82>")
	)
	(segment
		(start 74.646536 -392.651742)
		(end 74.694542 -392.76782)
		(width 0.1651)
		(layer "In7.Cu")
		(net "P5E_PEX0_STN5_TX_C_DP<82>")
	)
	(segment
		(start 75.152504 -392.957812)
		(end 75.268582 -392.909552)
		(width 0.1651)
		(layer "In7.Cu")
		(net "P5E_PEX0_STN5_TX_C_DP<82>")
	)
	(segment
		(start 64.481202 -357.75773)
		(end 64.772032 -358.04856)
		(width 0.1651)
		(layer "In7.Cu")
		(net "P5E_PEX0_STN5_TX_C_DP<82>")
	)
	(segment
		(start 77.202284 -394.575284)
		(end 77.202284 -404.370032)
		(width 0.1651)
		(layer "In7.Cu")
		(net "P5E_PEX0_STN5_TX_C_DP<82>")
	)
	(segment
		(start 65.71996 -385.364228)
		(end 66.861944 -388.121398)
		(width 0.1651)
		(layer "In7.Cu")
		(net "P5E_PEX0_STN5_TX_C_DP<82>")
	)
	(segment
		(start 65.71996 -376.788426)
		(end 65.71996 -385.364228)
		(width 0.1651)
		(layer "In7.Cu")
		(net "P5E_PEX0_STN5_TX_C_DP<82>")
	)
	(segment
		(start 64.772032 -358.04856)
		(end 64.772032 -361.145328)
		(width 0.1651)
		(layer "In7.Cu")
		(net "P5E_PEX0_STN5_TX_C_DP<82>")
	)
	(segment
		(start 76.806298 -394.179298)
		(end 77.202284 -394.575284)
		(width 0.1651)
		(layer "In7.Cu")
		(net "P5E_PEX0_STN5_TX_C_DP<82>")
	)
	(segment
		(start 64.772032 -361.145328)
		(end 65.71996 -376.788426)
		(width 0.1651)
		(layer "In7.Cu")
		(net "P5E_PEX0_STN5_TX_C_DP<82>")
	)
	(segment
		(start 76.773278 -404.799038)
		(end 76.436982 -404.799038)
		(width 0.1651)
		(layer "In7.Cu")
		(net "P5E_PEX0_STN5_TX_C_DP<82>")
	)
	(segment
		(start 76.436982 -404.799038)
		(end 76.309982 -404.672038)
		(width 0.1651)
		(layer "In7.Cu")
		(net "P5E_PEX0_STN5_TX_C_DP<82>")
	)
	(segment
		(start 66.861944 -388.121398)
		(end 69.091556 -390.35101)
		(width 0.1651)
		(layer "In7.Cu")
		(net "P5E_PEX0_STN5_TX_C_DP<82>")
	)
	(via
		(at 298.268136 -112.67059)
		(size 0.6604)
		(drill 0.3302)
		(layers "F.Cu" "B.Cu")
		(net "RST_SMB_NIC5_MUX_N")
	)
	(segment
		(start 298.268136 -112.274858)
		(end 298.268136 -112.67059)
		(width 0.13208)
		(layer "B.Cu")
		(net "RST_SMB_NIC5_MUX_N")
	)
	(segment
		(start 298.268136 -113.265966)
		(end 299.023786 -114.021616)
		(width 0.13208)
		(layer "B.Cu")
		(net "RST_SMB_NIC5_MUX_N")
	)
	(segment
		(start 301.449232 -114.278664)
		(end 301.449232 -114.713512)
		(width 0.13208)
		(layer "B.Cu")
		(net "RST_SMB_NIC5_MUX_N")
	)
	(segment
		(start 298.676568 -111.334042)
		(end 298.676568 -111.866426)
		(width 0.13208)
		(layer "B.Cu")
		(net "RST_SMB_NIC5_MUX_N")
	)
	(segment
		(start 298.676568 -111.866426)
		(end 298.268136 -112.274858)
		(width 0.13208)
		(layer "B.Cu")
		(net "RST_SMB_NIC5_MUX_N")
	)
	(segment
		(start 301.192184 -114.021616)
		(end 301.449232 -114.278664)
		(width 0.13208)
		(layer "B.Cu")
		(net "RST_SMB_NIC5_MUX_N")
	)
	(segment
		(start 298.268136 -112.67059)
		(end 298.268136 -113.265966)
		(width 0.13208)
		(layer "B.Cu")
		(net "RST_SMB_NIC5_MUX_N")
	)
	(segment
		(start 299.023786 -114.021616)
		(end 301.192184 -114.021616)
		(width 0.13208)
		(layer "B.Cu")
		(net "RST_SMB_NIC5_MUX_N")
	)
	(segment
		(start 189.792356 -80.749394)
		(end 190.989458 -80.749394)
		(width 0.13208)
		(layer "F.Cu")
		(net "HP_NIC3_HSC_PWRGD_N")
	)
	(segment
		(start 191.289178 -80.449674)
		(end 192.257426 -80.449674)
		(width 0.13208)
		(layer "F.Cu")
		(net "HP_NIC3_HSC_PWRGD_N")
	)
	(segment
		(start 190.989458 -80.749394)
		(end 191.289178 -80.449674)
		(width 0.13208)
		(layer "F.Cu")
		(net "HP_NIC3_HSC_PWRGD_N")
	)
	(segment
		(start 189.782704 -80.739742)
		(end 189.792356 -80.749394)
		(width 0.13208)
		(layer "F.Cu")
		(net "HP_NIC3_HSC_PWRGD_N")
	)
	(segment
		(start 191.339724 -81.09966)
		(end 190.989458 -80.749394)
		(width 0.13208)
		(layer "F.Cu")
		(net "HP_NIC3_HSC_PWRGD_N")
	)
	(segment
		(start 192.257426 -81.09966)
		(end 191.339724 -81.09966)
		(width 0.13208)
		(layer "F.Cu")
		(net "HP_NIC3_HSC_PWRGD_N")
	)
	(via
		(at 190.989458 -80.749394)
		(size 0.762)
		(drill 0.381)
		(layers "F.Cu" "B.Cu")
		(net "HP_NIC3_HSC_PWRGD_N")
	)
	(segment
		(start 77.486002 -342.734138)
		(end 77.780642 -342.439498)
		(width 0.13462)
		(layer "F.Cu")
		(net "P5E_PEX0_STN5_TX_DN<87>")
	)
	(segment
		(start 77.486002 -343.365582)
		(end 77.486002 -342.734138)
		(width 0.13462)
		(layer "F.Cu")
		(net "P5E_PEX0_STN5_TX_DN<87>")
	)
	(segment
		(start 77.806042 -343.685622)
		(end 77.486002 -343.365582)
		(width 0.13462)
		(layer "F.Cu")
		(net "P5E_PEX0_STN5_TX_DN<87>")
	)
	(segment
		(start 65.084452 -313.570112)
		(end 65.235582 -313.570112)
		(width 0.1143)
		(layer "In7.Cu")
		(net "P5E_PEX0_STN5_TX_DN<87>")
	)
	(segment
		(start 77.489812 -342.148668)
		(end 77.489812 -341.265764)
		(width 0.1651)
		(layer "In7.Cu")
		(net "P5E_PEX0_STN5_TX_DN<87>")
	)
	(segment
		(start 65.015872 -319.916048)
		(end 65.015872 -319.8876)
		(width 0.1143)
		(layer "In7.Cu")
		(net "P5E_PEX0_STN5_TX_DN<87>")
	)
	(segment
		(start 64.970152 -313.684412)
		(end 65.084452 -313.570112)
		(width 0.1143)
		(layer "In7.Cu")
		(net "P5E_PEX0_STN5_TX_DN<87>")
	)
	(segment
		(start 67.09029 -326.160892)
		(end 65.402968 -323.345556)
		(width 0.1651)
		(layer "In7.Cu")
		(net "P5E_PEX0_STN5_TX_DN<87>")
	)
	(segment
		(start 65.015872 -322.41109)
		(end 65.015872 -319.916048)
		(width 0.1651)
		(layer "In7.Cu")
		(net "P5E_PEX0_STN5_TX_DN<87>")
	)
	(segment
		(start 76.737972 -338.989924)
		(end 68.47078 -327.843134)
		(width 0.1651)
		(layer "In7.Cu")
		(net "P5E_PEX0_STN5_TX_DN<87>")
	)
	(segment
		(start 65.235582 -313.570112)
		(end 65.349882 -313.684412)
		(width 0.1143)
		(layer "In7.Cu")
		(net "P5E_PEX0_STN5_TX_DN<87>")
	)
	(segment
		(start 65.402968 -323.345556)
		(end 65.015872 -322.41109)
		(width 0.1651)
		(layer "In7.Cu")
		(net "P5E_PEX0_STN5_TX_DN<87>")
	)
	(segment
		(start 65.349882 -313.684412)
		(end 65.349882 -313.949842)
		(width 0.1143)
		(layer "In7.Cu")
		(net "P5E_PEX0_STN5_TX_DN<87>")
	)
	(segment
		(start 77.780642 -342.439498)
		(end 77.489812 -342.148668)
		(width 0.1651)
		(layer "In7.Cu")
		(net "P5E_PEX0_STN5_TX_DN<87>")
	)
	(segment
		(start 65.015872 -319.8876)
		(end 64.970152 -319.84188)
		(width 0.1143)
		(layer "In7.Cu")
		(net "P5E_PEX0_STN5_TX_DN<87>")
	)
	(segment
		(start 68.47078 -327.843134)
		(end 67.09029 -326.160892)
		(width 0.1651)
		(layer "In7.Cu")
		(net "P5E_PEX0_STN5_TX_DN<87>")
	)
	(segment
		(start 77.489812 -341.265764)
		(end 76.737972 -338.989924)
		(width 0.1651)
		(layer "In7.Cu")
		(net "P5E_PEX0_STN5_TX_DN<87>")
	)
	(segment
		(start 64.970152 -319.84188)
		(end 64.970152 -313.684412)
		(width 0.1143)
		(layer "In7.Cu")
		(net "P5E_PEX0_STN5_TX_DN<87>")
	)
	(segment
		(start 328.342244 -343.365582)
		(end 328.342244 -342.734138)
		(width 0.13462)
		(layer "F.Cu")
		(net "P5E_PEX2_STN5_TX_DP<87>")
	)
	(segment
		(start 328.022204 -343.685622)
		(end 328.342244 -343.365582)
		(width 0.13462)
		(layer "F.Cu")
		(net "P5E_PEX2_STN5_TX_DP<87>")
	)
	(segment
		(start 328.342244 -342.734138)
		(end 328.047604 -342.439498)
		(width 0.13462)
		(layer "F.Cu")
		(net "P5E_PEX2_STN5_TX_DP<87>")
	)
	(segment
		(start 296.933874 -319.8622)
		(end 296.979594 -319.81648)
		(width 0.1143)
		(layer "In7.Cu")
		(net "P5E_PEX2_STN5_TX_DP<87>")
	)
	(segment
		(start 297.435524 -313.379612)
		(end 297.549824 -313.265312)
		(width 0.1143)
		(layer "In7.Cu")
		(net "P5E_PEX2_STN5_TX_DP<87>")
	)
	(segment
		(start 328.047604 -342.439498)
		(end 328.338434 -342.148668)
		(width 0.1651)
		(layer "In7.Cu")
		(net "P5E_PEX2_STN5_TX_DP<87>")
	)
	(segment
		(start 321.675252 -336.367882)
		(end 300.820836 -327.770236)
		(width 0.1651)
		(layer "In7.Cu")
		(net "P5E_PEX2_STN5_TX_DP<87>")
	)
	(segment
		(start 296.979594 -319.81648)
		(end 296.979594 -313.605418)
		(width 0.1143)
		(layer "In7.Cu")
		(net "P5E_PEX2_STN5_TX_DP<87>")
	)
	(segment
		(start 327.868026 -340.649814)
		(end 321.675252 -336.367882)
		(width 0.1651)
		(layer "In7.Cu")
		(net "P5E_PEX2_STN5_TX_DP<87>")
	)
	(segment
		(start 328.338434 -341.66683)
		(end 327.868026 -340.649814)
		(width 0.1651)
		(layer "In7.Cu")
		(net "P5E_PEX2_STN5_TX_DP<87>")
	)
	(segment
		(start 297.549824 -313.265312)
		(end 297.549824 -312.999882)
		(width 0.1143)
		(layer "In7.Cu")
		(net "P5E_PEX2_STN5_TX_DP<87>")
	)
	(segment
		(start 300.820836 -327.770236)
		(end 298.592748 -325.542148)
		(width 0.1651)
		(layer "In7.Cu")
		(net "P5E_PEX2_STN5_TX_DP<87>")
	)
	(segment
		(start 298.592748 -325.542148)
		(end 296.933874 -321.53733)
		(width 0.1651)
		(layer "In7.Cu")
		(net "P5E_PEX2_STN5_TX_DP<87>")
	)
	(segment
		(start 296.979594 -313.605418)
		(end 297.2054 -313.379612)
		(width 0.1143)
		(layer "In7.Cu")
		(net "P5E_PEX2_STN5_TX_DP<87>")
	)
	(segment
		(start 297.2054 -313.379612)
		(end 297.435524 -313.379612)
		(width 0.1143)
		(layer "In7.Cu")
		(net "P5E_PEX2_STN5_TX_DP<87>")
	)
	(segment
		(start 296.933874 -321.53733)
		(end 296.933874 -319.890648)
		(width 0.1651)
		(layer "In7.Cu")
		(net "P5E_PEX2_STN5_TX_DP<87>")
	)
	(segment
		(start 328.338434 -342.148668)
		(end 328.338434 -341.66683)
		(width 0.1651)
		(layer "In7.Cu")
		(net "P5E_PEX2_STN5_TX_DP<87>")
	)
	(segment
		(start 296.933874 -319.890648)
		(end 296.933874 -319.8622)
		(width 0.1143)
		(layer "In7.Cu")
		(net "P5E_PEX2_STN5_TX_DP<87>")
	)
	(segment
		(start 396.628112 -349.511366)
		(end 396.628112 -348.880938)
		(width 0.13462)
		(layer "F.Cu")
		(net "P5E_PEX3_STN5_TX_DN<84>")
	)
	(segment
		(start 396.628112 -348.880938)
		(end 396.92326 -348.58579)
		(width 0.13462)
		(layer "F.Cu")
		(net "P5E_PEX3_STN5_TX_DN<84>")
	)
	(segment
		(start 396.94866 -349.831914)
		(end 396.628112 -349.511366)
		(width 0.13462)
		(layer "F.Cu")
		(net "P5E_PEX3_STN5_TX_DN<84>")
	)
	(segment
		(start 398.18691 -346.230194)
		(end 398.18691 -341.496904)
		(width 0.1651)
		(layer "In7.Cu")
		(net "P5E_PEX3_STN5_TX_DN<84>")
	)
	(segment
		(start 410.534358 -311.670192)
		(end 410.685488 -311.670192)
		(width 0.1143)
		(layer "In7.Cu")
		(net "P5E_PEX3_STN5_TX_DN<84>")
	)
	(segment
		(start 396.63243 -347.784674)
		(end 398.18691 -346.230194)
		(width 0.1651)
		(layer "In7.Cu")
		(net "P5E_PEX3_STN5_TX_DN<84>")
	)
	(segment
		(start 410.799788 -311.784492)
		(end 410.799788 -312.049922)
		(width 0.1143)
		(layer "In7.Cu")
		(net "P5E_PEX3_STN5_TX_DN<84>")
	)
	(segment
		(start 410.465778 -324.06336)
		(end 410.465778 -319.9892)
		(width 0.1651)
		(layer "In7.Cu")
		(net "P5E_PEX3_STN5_TX_DN<84>")
	)
	(segment
		(start 396.63243 -348.29496)
		(end 396.63243 -347.784674)
		(width 0.1651)
		(layer "In7.Cu")
		(net "P5E_PEX3_STN5_TX_DN<84>")
	)
	(segment
		(start 410.420058 -311.784492)
		(end 410.534358 -311.670192)
		(width 0.1143)
		(layer "In7.Cu")
		(net "P5E_PEX3_STN5_TX_DN<84>")
	)
	(segment
		(start 409.518612 -326.350122)
		(end 410.465778 -324.06336)
		(width 0.1651)
		(layer "In7.Cu")
		(net "P5E_PEX3_STN5_TX_DN<84>")
	)
	(segment
		(start 398.18691 -341.496904)
		(end 407.897584 -328.776076)
		(width 0.1651)
		(layer "In7.Cu")
		(net "P5E_PEX3_STN5_TX_DN<84>")
	)
	(segment
		(start 410.420058 -319.915032)
		(end 410.420058 -311.784492)
		(width 0.1143)
		(layer "In7.Cu")
		(net "P5E_PEX3_STN5_TX_DN<84>")
	)
	(segment
		(start 407.897584 -328.776076)
		(end 409.518612 -326.350122)
		(width 0.1651)
		(layer "In7.Cu")
		(net "P5E_PEX3_STN5_TX_DN<84>")
	)
	(segment
		(start 410.465778 -319.9892)
		(end 410.465778 -319.960752)
		(width 0.1143)
		(layer "In7.Cu")
		(net "P5E_PEX3_STN5_TX_DN<84>")
	)
	(segment
		(start 410.685488 -311.670192)
		(end 410.799788 -311.784492)
		(width 0.1143)
		(layer "In7.Cu")
		(net "P5E_PEX3_STN5_TX_DN<84>")
	)
	(segment
		(start 410.465778 -319.960752)
		(end 410.420058 -319.915032)
		(width 0.1143)
		(layer "In7.Cu")
		(net "P5E_PEX3_STN5_TX_DN<84>")
	)
	(segment
		(start 396.92326 -348.58579)
		(end 396.63243 -348.29496)
		(width 0.1651)
		(layer "In7.Cu")
		(net "P5E_PEX3_STN5_TX_DN<84>")
	)
	(segment
		(start 374.865392 -348.880938)
		(end 375.16054 -348.58579)
		(width 0.13462)
		(layer "F.Cu")
		(net "P5E_PEX3_STN6_TX_DN<110>")
	)
	(segment
		(start 374.865392 -349.511366)
		(end 374.865392 -348.880938)
		(width 0.13462)
		(layer "F.Cu")
		(net "P5E_PEX3_STN6_TX_DN<110>")
	)
	(segment
		(start 375.18594 -349.831914)
		(end 374.865392 -349.511366)
		(width 0.13462)
		(layer "F.Cu")
		(net "P5E_PEX3_STN6_TX_DN<110>")
	)
	(segment
		(start 376.42419 -346.230194)
		(end 376.42419 -341.987124)
		(width 0.1651)
		(layer "In13.Cu")
		(net "P5E_PEX3_STN6_TX_DN<110>")
	)
	(segment
		(start 392.415776 -319.992248)
		(end 392.370056 -319.946528)
		(width 0.1143)
		(layer "In13.Cu")
		(net "P5E_PEX3_STN6_TX_DN<110>")
	)
	(segment
		(start 375.16054 -348.58579)
		(end 374.86971 -348.29496)
		(width 0.1651)
		(layer "In13.Cu")
		(net "P5E_PEX3_STN6_TX_DN<110>")
	)
	(segment
		(start 376.42419 -341.987124)
		(end 376.621548 -341.225632)
		(width 0.1651)
		(layer "In13.Cu")
		(net "P5E_PEX3_STN6_TX_DN<110>")
	)
	(segment
		(start 392.370056 -319.946528)
		(end 392.370056 -313.673744)
		(width 0.1143)
		(layer "In13.Cu")
		(net "P5E_PEX3_STN6_TX_DN<110>")
	)
	(segment
		(start 391.30605 -322.804282)
		(end 392.415776 -320.899028)
		(width 0.1651)
		(layer "In13.Cu")
		(net "P5E_PEX3_STN6_TX_DN<110>")
	)
	(segment
		(start 392.749786 -313.684412)
		(end 392.749786 -313.949842)
		(width 0.1143)
		(layer "In13.Cu")
		(net "P5E_PEX3_STN6_TX_DN<110>")
	)
	(segment
		(start 392.473688 -313.570112)
		(end 392.635486 -313.570112)
		(width 0.1143)
		(layer "In13.Cu")
		(net "P5E_PEX3_STN6_TX_DN<110>")
	)
	(segment
		(start 392.635486 -313.570112)
		(end 392.749786 -313.684412)
		(width 0.1143)
		(layer "In13.Cu")
		(net "P5E_PEX3_STN6_TX_DN<110>")
	)
	(segment
		(start 392.370056 -313.673744)
		(end 392.473688 -313.570112)
		(width 0.1143)
		(layer "In13.Cu")
		(net "P5E_PEX3_STN6_TX_DN<110>")
	)
	(segment
		(start 381.614426 -335.51622)
		(end 391.30605 -322.804282)
		(width 0.1651)
		(layer "In13.Cu")
		(net "P5E_PEX3_STN6_TX_DN<110>")
	)
	(segment
		(start 376.621548 -341.225632)
		(end 381.614426 -335.51622)
		(width 0.1651)
		(layer "In13.Cu")
		(net "P5E_PEX3_STN6_TX_DN<110>")
	)
	(segment
		(start 392.415776 -320.020696)
		(end 392.415776 -319.992248)
		(width 0.1143)
		(layer "In13.Cu")
		(net "P5E_PEX3_STN6_TX_DN<110>")
	)
	(segment
		(start 374.86971 -348.29496)
		(end 374.86971 -347.784674)
		(width 0.1651)
		(layer "In13.Cu")
		(net "P5E_PEX3_STN6_TX_DN<110>")
	)
	(segment
		(start 392.415776 -320.899028)
		(end 392.415776 -320.020696)
		(width 0.1651)
		(layer "In13.Cu")
		(net "P5E_PEX3_STN6_TX_DN<110>")
	)
	(segment
		(start 374.86971 -347.784674)
		(end 376.42419 -346.230194)
		(width 0.1651)
		(layer "In13.Cu")
		(net "P5E_PEX3_STN6_TX_DN<110>")
	)
	(segment
		(start 78.509876 -372.508018)
		(end 78.636876 -372.381018)
		(width 0.1651)
		(layer "In5.Cu")
		(net "P5E_PEX0_STN5_RX_DN<91>")
	)
	(segment
		(start 69.926708 -323.906642)
		(end 68.815966 -321.224656)
		(width 0.1651)
		(layer "In5.Cu")
		(net "P5E_PEX0_STN5_RX_DN<91>")
	)
	(segment
		(start 79.684372 -371.98427)
		(end 79.684372 -369.90401)
		(width 0.1651)
		(layer "In5.Cu")
		(net "P5E_PEX0_STN5_RX_DN<91>")
	)
	(segment
		(start 79.684372 -369.90401)
		(end 79.813404 -369.035584)
		(width 0.1651)
		(layer "In5.Cu")
		(net "P5E_PEX0_STN5_RX_DN<91>")
	)
	(segment
		(start 69.035676 -318.320166)
		(end 69.149976 -318.434466)
		(width 0.1143)
		(layer "In5.Cu")
		(net "P5E_PEX0_STN5_RX_DN<91>")
	)
	(segment
		(start 78.636876 -372.381018)
		(end 79.287624 -372.381018)
		(width 0.1651)
		(layer "In5.Cu")
		(net "P5E_PEX0_STN5_RX_DN<91>")
	)
	(segment
		(start 78.509876 -372.890034)
		(end 78.509876 -372.508018)
		(width 0.1651)
		(layer "In5.Cu")
		(net "P5E_PEX0_STN5_RX_DN<91>")
	)
	(segment
		(start 79.287624 -372.381018)
		(end 79.684372 -371.98427)
		(width 0.1651)
		(layer "In5.Cu")
		(net "P5E_PEX0_STN5_RX_DN<91>")
	)
	(segment
		(start 82.153252 -342.277192)
		(end 81.819496 -341.20328)
		(width 0.1651)
		(layer "In5.Cu")
		(net "P5E_PEX0_STN5_RX_DN<91>")
	)
	(segment
		(start 68.815966 -319.995296)
		(end 68.815966 -319.966848)
		(width 0.1143)
		(layer "In5.Cu")
		(net "P5E_PEX0_STN5_RX_DN<91>")
	)
	(segment
		(start 82.153252 -357.827072)
		(end 82.153252 -342.277192)
		(width 0.1651)
		(layer "In5.Cu")
		(net "P5E_PEX0_STN5_RX_DN<91>")
	)
	(segment
		(start 69.149976 -318.434466)
		(end 69.149976 -318.699896)
		(width 0.1143)
		(layer "In5.Cu")
		(net "P5E_PEX0_STN5_RX_DN<91>")
	)
	(segment
		(start 68.770246 -318.434466)
		(end 68.884546 -318.320166)
		(width 0.1143)
		(layer "In5.Cu")
		(net "P5E_PEX0_STN5_RX_DN<91>")
	)
	(segment
		(start 68.884546 -318.320166)
		(end 69.035676 -318.320166)
		(width 0.1143)
		(layer "In5.Cu")
		(net "P5E_PEX0_STN5_RX_DN<91>")
	)
	(segment
		(start 68.770246 -319.921128)
		(end 68.770246 -318.434466)
		(width 0.1143)
		(layer "In5.Cu")
		(net "P5E_PEX0_STN5_RX_DN<91>")
	)
	(segment
		(start 68.815966 -321.224656)
		(end 68.815966 -319.995296)
		(width 0.1651)
		(layer "In5.Cu")
		(net "P5E_PEX0_STN5_RX_DN<91>")
	)
	(segment
		(start 68.815966 -319.966848)
		(end 68.770246 -319.921128)
		(width 0.1143)
		(layer "In5.Cu")
		(net "P5E_PEX0_STN5_RX_DN<91>")
	)
	(segment
		(start 81.819496 -341.20328)
		(end 69.926708 -323.906642)
		(width 0.1651)
		(layer "In5.Cu")
		(net "P5E_PEX0_STN5_RX_DN<91>")
	)
	(segment
		(start 80.418686 -366.6109)
		(end 82.153252 -357.827072)
		(width 0.1651)
		(layer "In5.Cu")
		(net "P5E_PEX0_STN5_RX_DN<91>")
	)
	(segment
		(start 79.813404 -369.035584)
		(end 80.418686 -366.6109)
		(width 0.1651)
		(layer "In5.Cu")
		(net "P5E_PEX0_STN5_RX_DN<91>")
	)
	(segment
		(start 337.943444 -350.685354)
		(end 337.943444 -351.316798)
		(width 0.13462)
		(layer "F.Cu")
		(net "P5E_PEX2_STN5_TX_C_DN<92>")
	)
	(segment
		(start 338.263484 -350.365314)
		(end 337.943444 -350.685354)
		(width 0.13462)
		(layer "F.Cu")
		(net "P5E_PEX2_STN5_TX_C_DN<92>")
	)
	(segment
		(start 337.943444 -351.316798)
		(end 338.238084 -351.611438)
		(width 0.13462)
		(layer "F.Cu")
		(net "P5E_PEX2_STN5_TX_C_DN<92>")
	)
	(segment
		(start 340.964266 -379.08103)
		(end 341.416132 -378.629164)
		(width 0.1651)
		(layer "In7.Cu")
		(net "P5E_PEX2_STN5_TX_C_DN<92>")
	)
	(segment
		(start 340.29015 -379.20803)
		(end 340.41715 -379.08103)
		(width 0.1651)
		(layer "In7.Cu")
		(net "P5E_PEX2_STN5_TX_C_DN<92>")
	)
	(segment
		(start 341.416132 -368.582702)
		(end 336.392774 -358.75341)
		(width 0.1651)
		(layer "In7.Cu")
		(net "P5E_PEX2_STN5_TX_C_DN<92>")
	)
	(segment
		(start 336.392774 -358.75341)
		(end 336.392774 -354.027486)
		(width 0.1651)
		(layer "In7.Cu")
		(net "P5E_PEX2_STN5_TX_C_DN<92>")
	)
	(segment
		(start 340.41715 -379.08103)
		(end 340.964266 -379.08103)
		(width 0.1651)
		(layer "In7.Cu")
		(net "P5E_PEX2_STN5_TX_C_DN<92>")
	)
	(segment
		(start 337.947254 -351.902268)
		(end 338.238084 -351.611438)
		(width 0.1651)
		(layer "In7.Cu")
		(net "P5E_PEX2_STN5_TX_C_DN<92>")
	)
	(segment
		(start 341.416132 -378.629164)
		(end 341.416132 -368.582702)
		(width 0.1651)
		(layer "In7.Cu")
		(net "P5E_PEX2_STN5_TX_C_DN<92>")
	)
	(segment
		(start 340.29015 -379.590046)
		(end 340.29015 -379.20803)
		(width 0.1651)
		(layer "In7.Cu")
		(net "P5E_PEX2_STN5_TX_C_DN<92>")
	)
	(segment
		(start 336.392774 -354.027486)
		(end 337.947254 -352.473006)
		(width 0.1651)
		(layer "In7.Cu")
		(net "P5E_PEX2_STN5_TX_C_DN<92>")
	)
	(segment
		(start 337.947254 -352.473006)
		(end 337.947254 -351.902268)
		(width 0.1651)
		(layer "In7.Cu")
		(net "P5E_PEX2_STN5_TX_C_DN<92>")
	)
	(segment
		(start 65.050162 -356.831646)
		(end 65.370202 -356.511606)
		(width 0.13462)
		(layer "F.Cu")
		(net "P5E_PEX0_STN5_TX_C_DN<82>")
	)
	(segment
		(start 65.344802 -357.75773)
		(end 65.050162 -357.46309)
		(width 0.13462)
		(layer "F.Cu")
		(net "P5E_PEX0_STN5_TX_C_DN<82>")
	)
	(segment
		(start 65.050162 -357.46309)
		(end 65.050162 -356.831646)
		(width 0.13462)
		(layer "F.Cu")
		(net "P5E_PEX0_STN5_TX_C_DN<82>")
	)
	(segment
		(start 66.0019 -376.77979)
		(end 65.053972 -361.136692)
		(width 0.1651)
		(layer "In7.Cu")
		(net "P5E_PEX0_STN5_TX_C_DN<82>")
	)
	(segment
		(start 77.484224 -404.486872)
		(end 77.484224 -394.458444)
		(width 0.1651)
		(layer "In7.Cu")
		(net "P5E_PEX0_STN5_TX_C_DN<82>")
	)
	(segment
		(start 69.251322 -390.111996)
		(end 67.100958 -387.961632)
		(width 0.1651)
		(layer "In7.Cu")
		(net "P5E_PEX0_STN5_TX_C_DN<82>")
	)
	(segment
		(start 76.890118 -405.080978)
		(end 77.484224 -404.486872)
		(width 0.1651)
		(layer "In7.Cu")
		(net "P5E_PEX0_STN5_TX_C_DN<82>")
	)
	(segment
		(start 65.053972 -361.136692)
		(end 65.053972 -358.04856)
		(width 0.1651)
		(layer "In7.Cu")
		(net "P5E_PEX0_STN5_TX_C_DN<82>")
	)
	(segment
		(start 76.309982 -405.207978)
		(end 76.436982 -405.080978)
		(width 0.1651)
		(layer "In7.Cu")
		(net "P5E_PEX0_STN5_TX_C_DN<82>")
	)
	(segment
		(start 76.436982 -405.080978)
		(end 76.890118 -405.080978)
		(width 0.1651)
		(layer "In7.Cu")
		(net "P5E_PEX0_STN5_TX_C_DN<82>")
	)
	(segment
		(start 65.053972 -358.04856)
		(end 65.344802 -357.75773)
		(width 0.1651)
		(layer "In7.Cu")
		(net "P5E_PEX0_STN5_TX_C_DN<82>")
	)
	(segment
		(start 75.885802 -392.860022)
		(end 69.251322 -390.111996)
		(width 0.1651)
		(layer "In7.Cu")
		(net "P5E_PEX0_STN5_TX_C_DN<82>")
	)
	(segment
		(start 76.309982 -405.589994)
		(end 76.309982 -405.207978)
		(width 0.1651)
		(layer "In7.Cu")
		(net "P5E_PEX0_STN5_TX_C_DN<82>")
	)
	(segment
		(start 67.100958 -387.961632)
		(end 66.0019 -385.308094)
		(width 0.1651)
		(layer "In7.Cu")
		(net "P5E_PEX0_STN5_TX_C_DN<82>")
	)
	(segment
		(start 66.0019 -385.308094)
		(end 66.0019 -376.77979)
		(width 0.1651)
		(layer "In7.Cu")
		(net "P5E_PEX0_STN5_TX_C_DN<82>")
	)
	(segment
		(start 77.484224 -394.458444)
		(end 75.885802 -392.860022)
		(width 0.1651)
		(layer "In7.Cu")
		(net "P5E_PEX0_STN5_TX_C_DN<82>")
	)
	(segment
		(start 63.648082 -170.157902)
		(end 63.648082 -170.888152)
		(width 0.13208)
		(layer "F.Cu")
		(net "HP_NIC0_PWRGD")
	)
	(segment
		(start 63.648082 -167.729662)
		(end 64.182752 -167.194992)
		(width 0.13208)
		(layer "F.Cu")
		(net "HP_NIC0_PWRGD")
	)
	(segment
		(start 63.648082 -170.888152)
		(end 63.96736 -171.20743)
		(width 0.13208)
		(layer "F.Cu")
		(net "HP_NIC0_PWRGD")
	)
	(segment
		(start 63.648082 -170.157902)
		(end 63.648082 -167.729662)
		(width 0.13208)
		(layer "F.Cu")
		(net "HP_NIC0_PWRGD")
	)
	(segment
		(start 63.96736 -171.20743)
		(end 63.96736 -171.675806)
		(width 0.13208)
		(layer "F.Cu")
		(net "HP_NIC0_PWRGD")
	)
	(segment
		(start 64.182752 -167.194992)
		(end 64.182752 -161.636456)
		(width 0.13208)
		(layer "F.Cu")
		(net "HP_NIC0_PWRGD")
	)
	(via
		(at 64.182752 -161.636456)
		(size 0.508)
		(drill 0.254)
		(layers "F.Cu" "B.Cu")
		(net "HP_NIC0_PWRGD")
	)
	(segment
		(start 64.182752 -161.636456)
		(end 64.157352 -161.611056)
		(width 0.13208)
		(layer "B.Cu")
		(net "HP_NIC0_PWRGD")
	)
	(segment
		(start 64.157352 -161.611056)
		(end 62.66053 -161.611056)
		(width 0.13208)
		(layer "B.Cu")
		(net "HP_NIC0_PWRGD")
	)
	(segment
		(start 179.377594 -118.331996)
		(end 179.377594 -117.566186)
		(width 0.13208)
		(layer "F.Cu")
		(net "PRSNT_NIC3_N")
	)
	(segment
		(start 197.86092 -137.840212)
		(end 200.231502 -137.840212)
		(width 0.13208)
		(layer "F.Cu")
		(net "PRSNT_NIC3_N")
	)
	(segment
		(start 179.437792 -139.414504)
		(end 179.170584 -139.147296)
		(width 0.13208)
		(layer "F.Cu")
		(net "PRSNT_NIC3_N")
	)
	(segment
		(start 193.393568 -138.474958)
		(end 182.899812 -138.474958)
		(width 0.13208)
		(layer "F.Cu")
		(net "PRSNT_NIC3_N")
	)
	(segment
		(start 179.170584 -138.864848)
		(end 178.421792 -138.864848)
		(width 0.13208)
		(layer "F.Cu")
		(net "PRSNT_NIC3_N")
	)
	(segment
		(start 200.231502 -137.840212)
		(end 201.946256 -139.554966)
		(width 0.13208)
		(layer "F.Cu")
		(net "PRSNT_NIC3_N")
	)
	(segment
		(start 202.701144 -141.004798)
		(end 203.040234 -141.004798)
		(width 0.13208)
		(layer "F.Cu")
		(net "PRSNT_NIC3_N")
	)
	(segment
		(start 179.170584 -139.147296)
		(end 179.170584 -138.864848)
		(width 0.13208)
		(layer "F.Cu")
		(net "PRSNT_NIC3_N")
	)
	(segment
		(start 201.946256 -139.554966)
		(end 201.946256 -140.24991)
		(width 0.13208)
		(layer "F.Cu")
		(net "PRSNT_NIC3_N")
	)
	(segment
		(start 182.899812 -138.474958)
		(end 181.960266 -139.414504)
		(width 0.13208)
		(layer "F.Cu")
		(net "PRSNT_NIC3_N")
	)
	(segment
		(start 202.184 -140.487654)
		(end 202.701144 -141.004798)
		(width 0.13208)
		(layer "F.Cu")
		(net "PRSNT_NIC3_N")
	)
	(segment
		(start 181.960266 -139.414504)
		(end 179.437792 -139.414504)
		(width 0.13208)
		(layer "F.Cu")
		(net "PRSNT_NIC3_N")
	)
	(segment
		(start 197.039484 -139.045696)
		(end 196.899784 -139.185396)
		(width 0.13208)
		(layer "F.Cu")
		(net "PRSNT_NIC3_N")
	)
	(segment
		(start 196.899784 -139.185396)
		(end 194.104006 -139.185396)
		(width 0.13208)
		(layer "F.Cu")
		(net "PRSNT_NIC3_N")
	)
	(segment
		(start 197.039484 -138.661648)
		(end 197.039484 -139.045696)
		(width 0.13208)
		(layer "F.Cu")
		(net "PRSNT_NIC3_N")
	)
	(segment
		(start 197.83044 -159.235648)
		(end 197.039484 -159.235648)
		(width 0.13208)
		(layer "F.Cu")
		(net "PRSNT_NIC3_N")
	)
	(segment
		(start 194.104006 -139.185396)
		(end 193.393568 -138.474958)
		(width 0.13208)
		(layer "F.Cu")
		(net "PRSNT_NIC3_N")
	)
	(segment
		(start 197.039484 -138.661648)
		(end 197.86092 -137.840212)
		(width 0.13208)
		(layer "F.Cu")
		(net "PRSNT_NIC3_N")
	)
	(segment
		(start 201.946256 -140.24991)
		(end 202.184 -140.487654)
		(width 0.13208)
		(layer "F.Cu")
		(net "PRSNT_NIC3_N")
	)
	(via
		(at 178.421792 -138.864848)
		(size 0.508)
		(drill 0.254)
		(layers "F.Cu" "B.Cu")
		(net "PRSNT_NIC3_N")
	)
	(via
		(at 197.83044 -159.235648)
		(size 0.508)
		(drill 0.254)
		(layers "F.Cu" "B.Cu")
		(net "PRSNT_NIC3_N")
	)
	(via
		(at 179.377594 -118.331996)
		(size 0.508)
		(drill 0.254)
		(layers "F.Cu" "B.Cu")
		(net "PRSNT_NIC3_N")
	)
	(via
		(at 202.184 -140.487654)
		(size 0.508)
		(drill 0.254)
		(layers "F.Cu" "B.Cu")
		(net "PRSNT_NIC3_N")
	)
	(segment
		(start 202.21829 -156.35986)
		(end 199.342502 -159.235648)
		(width 0.15494)
		(layer "In7.Cu")
		(net "PRSNT_NIC3_N")
	)
	(segment
		(start 199.342502 -159.235648)
		(end 197.83044 -159.235648)
		(width 0.15494)
		(layer "In7.Cu")
		(net "PRSNT_NIC3_N")
	)
	(segment
		(start 202.184 -140.487654)
		(end 202.21829 -140.521944)
		(width 0.15494)
		(layer "In7.Cu")
		(net "PRSNT_NIC3_N")
	)
	(segment
		(start 202.21829 -140.521944)
		(end 202.21829 -156.35986)
		(width 0.15494)
		(layer "In7.Cu")
		(net "PRSNT_NIC3_N")
	)
	(segment
		(start 178.421792 -138.864848)
		(end 178.421792 -138.80973)
		(width 0.15494)
		(layer "In9.Cu")
		(net "PRSNT_NIC3_N")
	)
	(segment
		(start 178.421792 -138.80973)
		(end 179.377594 -137.853928)
		(width 0.15494)
		(layer "In9.Cu")
		(net "PRSNT_NIC3_N")
	)
	(segment
		(start 179.377594 -137.853928)
		(end 179.377594 -118.331996)
		(width 0.15494)
		(layer "In9.Cu")
		(net "PRSNT_NIC3_N")
	)
	(segment
		(start 92.756482 -348.88043)
		(end 92.461842 -348.58579)
		(width 0.13462)
		(layer "F.Cu")
		(net "P5E_PEX0_STN5_TX_DP<95>")
	)
	(segment
		(start 92.756482 -349.511874)
		(end 92.756482 -348.88043)
		(width 0.13462)
		(layer "F.Cu")
		(net "P5E_PEX0_STN5_TX_DP<95>")
	)
	(segment
		(start 92.436442 -349.831914)
		(end 92.756482 -349.511874)
		(width 0.13462)
		(layer "F.Cu")
		(net "P5E_PEX0_STN5_TX_DP<95>")
	)
	(segment
		(start 94.307152 -345.986862)
		(end 94.307152 -342.199468)
		(width 0.1651)
		(layer "In7.Cu")
		(net "P5E_PEX0_STN5_TX_DP<95>")
	)
	(segment
		(start 92.752672 -347.541342)
		(end 94.307152 -345.986862)
		(width 0.1651)
		(layer "In7.Cu")
		(net "P5E_PEX0_STN5_TX_DP<95>")
	)
	(segment
		(start 72.835516 -313.379612)
		(end 72.949816 -313.265312)
		(width 0.1143)
		(layer "In7.Cu")
		(net "P5E_PEX0_STN5_TX_DP<95>")
	)
	(segment
		(start 94.306898 -342.199468)
		(end 92.865702 -338.948522)
		(width 0.1651)
		(layer "In7.Cu")
		(net "P5E_PEX0_STN5_TX_DP<95>")
	)
	(segment
		(start 72.333866 -319.916048)
		(end 72.333866 -319.8876)
		(width 0.1143)
		(layer "In7.Cu")
		(net "P5E_PEX0_STN5_TX_DP<95>")
	)
	(segment
		(start 72.333866 -319.8876)
		(end 72.379586 -319.84188)
		(width 0.1143)
		(layer "In7.Cu")
		(net "P5E_PEX0_STN5_TX_DP<95>")
	)
	(segment
		(start 92.752672 -348.29496)
		(end 92.752672 -347.541342)
		(width 0.1651)
		(layer "In7.Cu")
		(net "P5E_PEX0_STN5_TX_DP<95>")
	)
	(segment
		(start 72.379586 -313.605418)
		(end 72.605392 -313.379612)
		(width 0.1143)
		(layer "In7.Cu")
		(net "P5E_PEX0_STN5_TX_DP<95>")
	)
	(segment
		(start 72.949816 -313.265312)
		(end 72.949816 -312.999882)
		(width 0.1143)
		(layer "In7.Cu")
		(net "P5E_PEX0_STN5_TX_DP<95>")
	)
	(segment
		(start 92.865702 -338.948522)
		(end 72.503538 -320.492628)
		(width 0.1651)
		(layer "In7.Cu")
		(net "P5E_PEX0_STN5_TX_DP<95>")
	)
	(segment
		(start 72.379586 -319.84188)
		(end 72.379586 -313.605418)
		(width 0.1143)
		(layer "In7.Cu")
		(net "P5E_PEX0_STN5_TX_DP<95>")
	)
	(segment
		(start 72.333866 -320.110104)
		(end 72.333866 -319.916048)
		(width 0.1651)
		(layer "In7.Cu")
		(net "P5E_PEX0_STN5_TX_DP<95>")
	)
	(segment
		(start 94.307152 -342.199468)
		(end 94.306898 -342.199468)
		(width 0.1651)
		(layer "In7.Cu")
		(net "P5E_PEX0_STN5_TX_DP<95>")
	)
	(segment
		(start 92.461842 -348.58579)
		(end 92.752672 -348.29496)
		(width 0.1651)
		(layer "In7.Cu")
		(net "P5E_PEX0_STN5_TX_DP<95>")
	)
	(segment
		(start 72.605392 -313.379612)
		(end 72.835516 -313.379612)
		(width 0.1143)
		(layer "In7.Cu")
		(net "P5E_PEX0_STN5_TX_DP<95>")
	)
	(segment
		(start 72.503538 -320.492628)
		(end 72.333866 -320.110104)
		(width 0.1651)
		(layer "In7.Cu")
		(net "P5E_PEX0_STN5_TX_DP<95>")
	)
	(segment
		(start 279.219914 -30.62732)
		(end 278.901144 -30.94609)
		(width 0.13462)
		(layer "F.Cu")
		(net "P5E_PEX2_STN2_TX_DP<41>")
	)
	(segment
		(start 280.147268 -30.92069)
		(end 279.853898 -30.62732)
		(width 0.13462)
		(layer "F.Cu")
		(net "P5E_PEX2_STN2_TX_DP<41>")
	)
	(segment
		(start 279.853898 -30.62732)
		(end 279.219914 -30.62732)
		(width 0.13462)
		(layer "F.Cu")
		(net "P5E_PEX2_STN2_TX_DP<41>")
	)
	(segment
		(start 280.438098 -30.62986)
		(end 280.832814 -30.62986)
		(width 0.1651)
		(layer "In11.Cu")
		(net "P5E_PEX2_STN2_TX_DP<41>")
	)
	(segment
		(start 281.99461 -278.420068)
		(end 282.235402 -278.420068)
		(width 0.1143)
		(layer "In11.Cu")
		(net "P5E_PEX2_STN2_TX_DP<41>")
	)
	(segment
		(start 287.390332 -135.143494)
		(end 281.017472 -252.658372)
		(width 0.1651)
		(layer "In11.Cu")
		(net "P5E_PEX2_STN2_TX_DP<41>")
	)
	(segment
		(start 288.694114 -119.593868)
		(end 288.667952 -119.906288)
		(width 0.1651)
		(layer "In11.Cu")
		(net "P5E_PEX2_STN2_TX_DP<41>")
	)
	(segment
		(start 288.72053 -119.281194)
		(end 288.694114 -119.593868)
		(width 0.1651)
		(layer "In11.Cu")
		(net "P5E_PEX2_STN2_TX_DP<41>")
	)
	(segment
		(start 281.98572 -31.582868)
		(end 282.337256 -31.931356)
		(width 0.1651)
		(layer "In11.Cu")
		(net "P5E_PEX2_STN2_TX_DP<41>")
	)
	(segment
		(start 281.733752 -269.841726)
		(end 281.733752 -271.399)
		(width 0.1651)
		(layer "In11.Cu")
		(net "P5E_PEX2_STN2_TX_DP<41>")
	)
	(segment
		(start 283.66593 -33.2486)
		(end 284.994604 -35.429444)
		(width 0.1651)
		(layer "In11.Cu")
		(net "P5E_PEX2_STN2_TX_DP<41>")
	)
	(segment
		(start 295.678098 -69.600318)
		(end 288.72053 -119.281194)
		(width 0.1651)
		(layer "In11.Cu")
		(net "P5E_PEX2_STN2_TX_DP<41>")
	)
	(segment
		(start 284.994604 -35.429444)
		(end 294.871648 -48.194976)
		(width 0.1651)
		(layer "In11.Cu")
		(net "P5E_PEX2_STN2_TX_DP<41>")
	)
	(segment
		(start 282.689808 -32.406082)
		(end 282.815538 -32.405574)
		(width 0.1651)
		(layer "In11.Cu")
		(net "P5E_PEX2_STN2_TX_DP<41>")
	)
	(segment
		(start 281.779472 -271.473168)
		(end 281.779472 -278.20493)
		(width 0.1143)
		(layer "In11.Cu")
		(net "P5E_PEX2_STN2_TX_DP<41>")
	)
	(segment
		(start 282.349702 -278.534368)
		(end 282.349702 -278.799798)
		(width 0.1143)
		(layer "In11.Cu")
		(net "P5E_PEX2_STN2_TX_DP<41>")
	)
	(segment
		(start 280.147268 -30.92069)
		(end 280.438098 -30.62986)
		(width 0.1651)
		(layer "In11.Cu")
		(net "P5E_PEX2_STN2_TX_DP<41>")
	)
	(segment
		(start 280.832814 -30.62986)
		(end 281.160474 -30.764734)
		(width 0.1651)
		(layer "In11.Cu")
		(net "P5E_PEX2_STN2_TX_DP<41>")
	)
	(segment
		(start 282.337764 -32.057086)
		(end 282.689808 -32.406082)
		(width 0.1651)
		(layer "In11.Cu")
		(net "P5E_PEX2_STN2_TX_DP<41>")
	)
	(segment
		(start 294.871648 -48.194976)
		(end 295.538906 -50.122074)
		(width 0.1651)
		(layer "In11.Cu")
		(net "P5E_PEX2_STN2_TX_DP<41>")
	)
	(segment
		(start 281.36977 -266.144502)
		(end 281.733752 -269.841726)
		(width 0.1651)
		(layer "In11.Cu")
		(net "P5E_PEX2_STN2_TX_DP<41>")
	)
	(segment
		(start 281.017472 -252.658372)
		(end 281.36977 -266.144502)
		(width 0.1651)
		(layer "In11.Cu")
		(net "P5E_PEX2_STN2_TX_DP<41>")
	)
	(segment
		(start 281.85999 -31.583376)
		(end 281.98572 -31.582868)
		(width 0.1651)
		(layer "In11.Cu")
		(net "P5E_PEX2_STN2_TX_DP<41>")
	)
	(segment
		(start 281.507184 -31.10865)
		(end 281.507692 -31.10865)
		(width 0.1651)
		(layer "In11.Cu")
		(net "P5E_PEX2_STN2_TX_DP<41>")
	)
	(segment
		(start 281.733752 -271.399)
		(end 281.733752 -271.427448)
		(width 0.1143)
		(layer "In11.Cu")
		(net "P5E_PEX2_STN2_TX_DP<41>")
	)
	(segment
		(start 281.779472 -278.20493)
		(end 281.99461 -278.420068)
		(width 0.1143)
		(layer "In11.Cu")
		(net "P5E_PEX2_STN2_TX_DP<41>")
	)
	(segment
		(start 282.815538 -32.405574)
		(end 283.66593 -33.2486)
		(width 0.1651)
		(layer "In11.Cu")
		(net "P5E_PEX2_STN2_TX_DP<41>")
	)
	(segment
		(start 288.641536 -120.219724)
		(end 287.390332 -135.143494)
		(width 0.1651)
		(layer "In11.Cu")
		(net "P5E_PEX2_STN2_TX_DP<41>")
	)
	(segment
		(start 288.667952 -119.906288)
		(end 288.667698 -119.906288)
		(width 0.1651)
		(layer "In11.Cu")
		(net "P5E_PEX2_STN2_TX_DP<41>")
	)
	(segment
		(start 282.235402 -278.420068)
		(end 282.349702 -278.534368)
		(width 0.1143)
		(layer "In11.Cu")
		(net "P5E_PEX2_STN2_TX_DP<41>")
	)
	(segment
		(start 295.538906 -50.122074)
		(end 296.189654 -60.55106)
		(width 0.1651)
		(layer "In11.Cu")
		(net "P5E_PEX2_STN2_TX_DP<41>")
	)
	(segment
		(start 288.667698 -119.906288)
		(end 288.641536 -120.218454)
		(width 0.1651)
		(layer "In11.Cu")
		(net "P5E_PEX2_STN2_TX_DP<41>")
	)
	(segment
		(start 296.189654 -60.55106)
		(end 295.678098 -69.600318)
		(width 0.1651)
		(layer "In11.Cu")
		(net "P5E_PEX2_STN2_TX_DP<41>")
	)
	(segment
		(start 288.641536 -120.218454)
		(end 288.641536 -120.219724)
		(width 0.1651)
		(layer "In11.Cu")
		(net "P5E_PEX2_STN2_TX_DP<41>")
	)
	(segment
		(start 281.507692 -31.10865)
		(end 281.5082 -31.23438)
		(width 0.1651)
		(layer "In11.Cu")
		(net "P5E_PEX2_STN2_TX_DP<41>")
	)
	(segment
		(start 282.337256 -31.931356)
		(end 282.337764 -32.057086)
		(width 0.1651)
		(layer "In11.Cu")
		(net "P5E_PEX2_STN2_TX_DP<41>")
	)
	(segment
		(start 281.5082 -31.23438)
		(end 281.85999 -31.583376)
		(width 0.1651)
		(layer "In11.Cu")
		(net "P5E_PEX2_STN2_TX_DP<41>")
	)
	(segment
		(start 281.733752 -271.427448)
		(end 281.779472 -271.473168)
		(width 0.1143)
		(layer "In11.Cu")
		(net "P5E_PEX2_STN2_TX_DP<41>")
	)
	(segment
		(start 281.160474 -30.764734)
		(end 281.507184 -31.10865)
		(width 0.1651)
		(layer "In11.Cu")
		(net "P5E_PEX2_STN2_TX_DP<41>")
	)
	(segment
		(start 390.73074 -343.685622)
		(end 390.410192 -343.365074)
		(width 0.13462)
		(layer "F.Cu")
		(net "P5E_PEX3_STN5_TX_DN<88>")
	)
	(segment
		(start 390.410192 -342.734646)
		(end 390.70534 -342.439498)
		(width 0.13462)
		(layer "F.Cu")
		(net "P5E_PEX3_STN5_TX_DN<88>")
	)
	(segment
		(start 390.410192 -343.365074)
		(end 390.410192 -342.734646)
		(width 0.13462)
		(layer "F.Cu")
		(net "P5E_PEX3_STN5_TX_DN<88>")
	)
	(segment
		(start 414.265872 -320.017648)
		(end 414.220152 -319.971928)
		(width 0.1143)
		(layer "In13.Cu")
		(net "P5E_PEX3_STN5_TX_DN<88>")
	)
	(segment
		(start 414.265872 -320.046096)
		(end 414.265872 -320.017648)
		(width 0.1143)
		(layer "In13.Cu")
		(net "P5E_PEX3_STN5_TX_DN<88>")
	)
	(segment
		(start 414.599882 -311.784492)
		(end 414.599882 -312.049922)
		(width 0.1143)
		(layer "In13.Cu")
		(net "P5E_PEX3_STN5_TX_DN<88>")
	)
	(segment
		(start 414.485582 -311.670192)
		(end 414.599882 -311.784492)
		(width 0.1143)
		(layer "In13.Cu")
		(net "P5E_PEX3_STN5_TX_DN<88>")
	)
	(segment
		(start 390.861042 -341.033862)
		(end 391.059162 -340.774782)
		(width 0.1651)
		(layer "In13.Cu")
		(net "P5E_PEX3_STN5_TX_DN<88>")
	)
	(segment
		(start 390.41451 -341.771732)
		(end 390.861042 -341.033862)
		(width 0.1651)
		(layer "In13.Cu")
		(net "P5E_PEX3_STN5_TX_DN<88>")
	)
	(segment
		(start 414.220152 -319.971928)
		(end 414.220152 -311.787794)
		(width 0.1143)
		(layer "In13.Cu")
		(net "P5E_PEX3_STN5_TX_DN<88>")
	)
	(segment
		(start 414.220152 -311.787794)
		(end 414.337754 -311.670192)
		(width 0.1143)
		(layer "In13.Cu")
		(net "P5E_PEX3_STN5_TX_DN<88>")
	)
	(segment
		(start 390.41451 -342.148668)
		(end 390.41451 -341.771732)
		(width 0.1651)
		(layer "In13.Cu")
		(net "P5E_PEX3_STN5_TX_DN<88>")
	)
	(segment
		(start 413.937196 -321.484752)
		(end 414.265872 -321.035172)
		(width 0.1651)
		(layer "In13.Cu")
		(net "P5E_PEX3_STN5_TX_DN<88>")
	)
	(segment
		(start 391.059162 -340.774782)
		(end 413.937196 -321.484752)
		(width 0.1651)
		(layer "In13.Cu")
		(net "P5E_PEX3_STN5_TX_DN<88>")
	)
	(segment
		(start 414.337754 -311.670192)
		(end 414.485582 -311.670192)
		(width 0.1143)
		(layer "In13.Cu")
		(net "P5E_PEX3_STN5_TX_DN<88>")
	)
	(segment
		(start 390.70534 -342.439498)
		(end 390.41451 -342.148668)
		(width 0.1651)
		(layer "In13.Cu")
		(net "P5E_PEX3_STN5_TX_DN<88>")
	)
	(segment
		(start 414.265872 -321.035172)
		(end 414.265872 -320.046096)
		(width 0.1651)
		(layer "In13.Cu")
		(net "P5E_PEX3_STN5_TX_DN<88>")
	)
	(segment
		(start 377.700032 -342.73363)
		(end 377.4059 -342.439498)
		(width 0.13462)
		(layer "F.Cu")
		(net "P5E_PEX3_STN6_TX_DP<109>")
	)
	(segment
		(start 377.3805 -343.685622)
		(end 377.700032 -343.36609)
		(width 0.13462)
		(layer "F.Cu")
		(net "P5E_PEX3_STN6_TX_DP<109>")
	)
	(segment
		(start 377.700032 -343.36609)
		(end 377.700032 -342.73363)
		(width 0.13462)
		(layer "F.Cu")
		(net "P5E_PEX3_STN6_TX_DP<109>")
	)
	(segment
		(start 393.5857 -311.479692)
		(end 393.7 -311.365392)
		(width 0.1143)
		(layer "In13.Cu")
		(net "P5E_PEX3_STN6_TX_DP<109>")
	)
	(segment
		(start 392.95705 -321.374262)
		(end 393.083796 -321.068446)
		(width 0.1651)
		(layer "In13.Cu")
		(net "P5E_PEX3_STN6_TX_DP<109>")
	)
	(segment
		(start 393.083796 -320.046096)
		(end 393.083796 -320.017648)
		(width 0.1143)
		(layer "In13.Cu")
		(net "P5E_PEX3_STN6_TX_DP<109>")
	)
	(segment
		(start 393.7 -311.365392)
		(end 393.7 -311.099962)
		(width 0.1143)
		(layer "In13.Cu")
		(net "P5E_PEX3_STN6_TX_DP<109>")
	)
	(segment
		(start 377.4059 -342.439498)
		(end 377.69673 -342.148668)
		(width 0.1651)
		(layer "In13.Cu")
		(net "P5E_PEX3_STN6_TX_DP<109>")
	)
	(segment
		(start 393.083796 -321.068446)
		(end 393.083796 -320.046096)
		(width 0.1651)
		(layer "In13.Cu")
		(net "P5E_PEX3_STN6_TX_DP<109>")
	)
	(segment
		(start 384.15976 -334.091534)
		(end 391.875518 -323.245734)
		(width 0.1651)
		(layer "In13.Cu")
		(net "P5E_PEX3_STN6_TX_DP<109>")
	)
	(segment
		(start 393.083796 -320.017648)
		(end 393.129516 -319.971928)
		(width 0.1143)
		(layer "In13.Cu")
		(net "P5E_PEX3_STN6_TX_DP<109>")
	)
	(segment
		(start 391.875518 -323.245734)
		(end 392.95705 -321.374262)
		(width 0.1651)
		(layer "In13.Cu")
		(net "P5E_PEX3_STN6_TX_DP<109>")
	)
	(segment
		(start 377.69673 -342.148668)
		(end 377.69673 -341.570818)
		(width 0.1651)
		(layer "In13.Cu")
		(net "P5E_PEX3_STN6_TX_DP<109>")
	)
	(segment
		(start 377.69673 -341.570818)
		(end 384.15976 -334.091534)
		(width 0.1651)
		(layer "In13.Cu")
		(net "P5E_PEX3_STN6_TX_DP<109>")
	)
	(segment
		(start 393.344908 -311.479692)
		(end 393.5857 -311.479692)
		(width 0.1143)
		(layer "In13.Cu")
		(net "P5E_PEX3_STN6_TX_DP<109>")
	)
	(segment
		(start 393.129516 -319.971928)
		(end 393.129516 -311.695084)
		(width 0.1143)
		(layer "In13.Cu")
		(net "P5E_PEX3_STN6_TX_DP<109>")
	)
	(segment
		(start 393.129516 -311.695084)
		(end 393.344908 -311.479692)
		(width 0.1143)
		(layer "In13.Cu")
		(net "P5E_PEX3_STN6_TX_DP<109>")
	)
	(segment
		(start 39.831518 -341.411306)
		(end 38.778434 -336.117946)
		(width 0.1651)
		(layer "In5.Cu")
		(net "P5E_PEX0_STN7_RX_DP<123>")
	)
	(segment
		(start 38.179756 -319.921128)
		(end 38.179756 -318.355472)
		(width 0.1143)
		(layer "In5.Cu")
		(net "P5E_PEX0_STN7_RX_DP<123>")
	)
	(segment
		(start 38.778434 -336.117946)
		(end 38.778688 -336.117946)
		(width 0.1651)
		(layer "In5.Cu")
		(net "P5E_PEX0_STN7_RX_DP<123>")
	)
	(segment
		(start 35.430968 -369.71986)
		(end 39.335456 -360.293412)
		(width 0.1651)
		(layer "In5.Cu")
		(net "P5E_PEX0_STN7_RX_DP<123>")
	)
	(segment
		(start 34.509964 -383.290064)
		(end 34.509964 -383.67208)
		(width 0.1651)
		(layer "In5.Cu")
		(net "P5E_PEX0_STN7_RX_DP<123>")
	)
	(segment
		(start 38.547294 -335.542128)
		(end 38.63721 -335.407762)
		(width 0.1651)
		(layer "In5.Cu")
		(net "P5E_PEX0_STN7_RX_DP<123>")
	)
	(segment
		(start 38.405562 -318.129666)
		(end 38.635686 -318.129666)
		(width 0.1143)
		(layer "In5.Cu")
		(net "P5E_PEX0_STN7_RX_DP<123>")
	)
	(segment
		(start 35.37712 -383.44094)
		(end 35.37712 -369.99164)
		(width 0.1651)
		(layer "In5.Cu")
		(net "P5E_PEX0_STN7_RX_DP<123>")
	)
	(segment
		(start 39.831518 -357.799894)
		(end 39.831518 -341.411306)
		(width 0.1651)
		(layer "In5.Cu")
		(net "P5E_PEX0_STN7_RX_DP<123>")
	)
	(segment
		(start 38.778688 -336.117946)
		(end 38.644068 -336.028284)
		(width 0.1651)
		(layer "In5.Cu")
		(net "P5E_PEX0_STN7_RX_DP<123>")
	)
	(segment
		(start 35.01898 -383.79908)
		(end 35.37712 -383.44094)
		(width 0.1651)
		(layer "In5.Cu")
		(net "P5E_PEX0_STN7_RX_DP<123>")
	)
	(segment
		(start 38.179756 -318.355472)
		(end 38.405562 -318.129666)
		(width 0.1143)
		(layer "In5.Cu")
		(net "P5E_PEX0_STN7_RX_DP<123>")
	)
	(segment
		(start 38.644068 -336.028284)
		(end 38.547294 -335.542128)
		(width 0.1651)
		(layer "In5.Cu")
		(net "P5E_PEX0_STN7_RX_DP<123>")
	)
	(segment
		(start 34.636964 -383.79908)
		(end 35.01898 -383.79908)
		(width 0.1651)
		(layer "In5.Cu")
		(net "P5E_PEX0_STN7_RX_DP<123>")
	)
	(segment
		(start 38.635686 -318.129666)
		(end 38.749986 -318.015366)
		(width 0.1143)
		(layer "In5.Cu")
		(net "P5E_PEX0_STN7_RX_DP<123>")
	)
	(segment
		(start 38.134036 -319.995296)
		(end 38.134036 -319.966848)
		(width 0.1143)
		(layer "In5.Cu")
		(net "P5E_PEX0_STN7_RX_DP<123>")
	)
	(segment
		(start 38.749986 -318.015366)
		(end 38.749986 -317.749936)
		(width 0.1143)
		(layer "In5.Cu")
		(net "P5E_PEX0_STN7_RX_DP<123>")
	)
	(segment
		(start 38.134036 -319.966848)
		(end 38.179756 -319.921128)
		(width 0.1143)
		(layer "In5.Cu")
		(net "P5E_PEX0_STN7_RX_DP<123>")
	)
	(segment
		(start 34.509964 -383.67208)
		(end 34.636964 -383.79908)
		(width 0.1651)
		(layer "In5.Cu")
		(net "P5E_PEX0_STN7_RX_DP<123>")
	)
	(segment
		(start 38.134036 -332.877668)
		(end 38.134036 -319.995296)
		(width 0.1651)
		(layer "In5.Cu")
		(net "P5E_PEX0_STN7_RX_DP<123>")
	)
	(segment
		(start 35.37712 -369.99164)
		(end 35.430968 -369.71986)
		(width 0.1651)
		(layer "In5.Cu")
		(net "P5E_PEX0_STN7_RX_DP<123>")
	)
	(segment
		(start 38.63721 -335.407762)
		(end 38.134036 -332.877668)
		(width 0.1651)
		(layer "In5.Cu")
		(net "P5E_PEX0_STN7_RX_DP<123>")
	)
	(segment
		(start 39.335456 -360.293412)
		(end 39.831518 -357.799894)
		(width 0.1651)
		(layer "In5.Cu")
		(net "P5E_PEX0_STN7_RX_DP<123>")
	)
	(via
		(at 57.35955 -161.463736)
		(size 0.6604)
		(drill 0.3302)
		(layers "F.Cu" "B.Cu")
		(net "HP_NIC0_HSC_PWRGD_N")
	)
	(segment
		(start 56.200802 -161.474912)
		(end 56.211978 -161.463736)
		(width 0.13208)
		(layer "B.Cu")
		(net "HP_NIC0_HSC_PWRGD_N")
	)
	(segment
		(start 56.211978 -161.463736)
		(end 57.35955 -161.463736)
		(width 0.13208)
		(layer "B.Cu")
		(net "HP_NIC0_HSC_PWRGD_N")
	)
	(segment
		(start 57.35955 -161.853372)
		(end 57.35955 -161.463736)
		(width 0.13208)
		(layer "B.Cu")
		(net "HP_NIC0_HSC_PWRGD_N")
	)
	(segment
		(start 57.35955 -161.463736)
		(end 58.611516 -161.463736)
		(width 0.13208)
		(layer "B.Cu")
		(net "HP_NIC0_HSC_PWRGD_N")
	)
	(segment
		(start 58.611516 -162.113722)
		(end 57.6199 -162.113722)
		(width 0.13208)
		(layer "B.Cu")
		(net "HP_NIC0_HSC_PWRGD_N")
	)
	(segment
		(start 57.6199 -162.113722)
		(end 57.35955 -161.853372)
		(width 0.13208)
		(layer "B.Cu")
		(net "HP_NIC0_HSC_PWRGD_N")
	)
	(segment
		(start 180.905658 -94.1578)
		(end 175.299624 -94.1578)
		(width 0.13208)
		(layer "F.Cu")
		(net "RST_HP_NIC3_BUF_N")
	)
	(segment
		(start 197.739508 -86.949026)
		(end 198.37146 -86.949026)
		(width 0.13208)
		(layer "F.Cu")
		(net "RST_HP_NIC3_BUF_N")
	)
	(segment
		(start 174.51197 -96.052132)
		(end 174.69485 -96.235012)
		(width 0.13208)
		(layer "F.Cu")
		(net "RST_HP_NIC3_BUF_N")
	)
	(segment
		(start 184.349644 -90.713814)
		(end 180.905658 -94.1578)
		(width 0.13208)
		(layer "F.Cu")
		(net "RST_HP_NIC3_BUF_N")
	)
	(segment
		(start 175.299624 -94.1578)
		(end 174.51197 -94.945454)
		(width 0.13208)
		(layer "F.Cu")
		(net "RST_HP_NIC3_BUF_N")
	)
	(segment
		(start 196.723508 -86.949026)
		(end 197.739508 -86.949026)
		(width 0.13208)
		(layer "F.Cu")
		(net "RST_HP_NIC3_BUF_N")
	)
	(segment
		(start 195.334382 -86.949026)
		(end 196.723508 -86.949026)
		(width 0.13208)
		(layer "F.Cu")
		(net "RST_HP_NIC3_BUF_N")
	)
	(segment
		(start 198.49846 -87.076026)
		(end 198.49846 -90.134694)
		(width 0.13208)
		(layer "F.Cu")
		(net "RST_HP_NIC3_BUF_N")
	)
	(segment
		(start 174.51197 -94.945454)
		(end 174.51197 -95.619824)
		(width 0.13208)
		(layer "F.Cu")
		(net "RST_HP_NIC3_BUF_N")
	)
	(segment
		(start 198.37146 -86.949026)
		(end 198.49846 -87.076026)
		(width 0.13208)
		(layer "F.Cu")
		(net "RST_HP_NIC3_BUF_N")
	)
	(segment
		(start 174.51197 -95.619824)
		(end 174.51197 -96.052132)
		(width 0.13208)
		(layer "F.Cu")
		(net "RST_HP_NIC3_BUF_N")
	)
	(segment
		(start 174.69485 -97.718372)
		(end 174.69485 -96.702372)
		(width 0.13208)
		(layer "F.Cu")
		(net "RST_HP_NIC3_BUF_N")
	)
	(segment
		(start 174.69485 -96.235012)
		(end 174.69485 -96.702372)
		(width 0.13208)
		(layer "F.Cu")
		(net "RST_HP_NIC3_BUF_N")
	)
	(segment
		(start 198.49846 -90.134694)
		(end 197.91934 -90.713814)
		(width 0.13208)
		(layer "F.Cu")
		(net "RST_HP_NIC3_BUF_N")
	)
	(segment
		(start 197.91934 -90.713814)
		(end 184.349644 -90.713814)
		(width 0.13208)
		(layer "F.Cu")
		(net "RST_HP_NIC3_BUF_N")
	)
	(via
		(at 174.51197 -95.619824)
		(size 0.508)
		(drill 0.254)
		(layers "F.Cu" "B.Cu")
		(net "RST_HP_NIC3_BUF_N")
	)
	(segment
		(start 89.921842 -343.365582)
		(end 89.921842 -342.734138)
		(width 0.13462)
		(layer "F.Cu")
		(net "P5E_PEX0_STN5_TX_DN<93>")
	)
	(segment
		(start 90.241882 -343.685622)
		(end 89.921842 -343.365582)
		(width 0.13462)
		(layer "F.Cu")
		(net "P5E_PEX0_STN5_TX_DN<93>")
	)
	(segment
		(start 89.921842 -342.734138)
		(end 90.216482 -342.439498)
		(width 0.13462)
		(layer "F.Cu")
		(net "P5E_PEX0_STN5_TX_DN<93>")
	)
	(segment
		(start 70.670166 -313.684412)
		(end 70.784466 -313.570112)
		(width 0.1143)
		(layer "In7.Cu")
		(net "P5E_PEX0_STN5_TX_DN<93>")
	)
	(segment
		(start 70.715886 -320.614294)
		(end 70.715886 -319.916048)
		(width 0.1651)
		(layer "In7.Cu")
		(net "P5E_PEX0_STN5_TX_DN<93>")
	)
	(segment
		(start 90.216482 -342.439498)
		(end 89.925652 -342.148668)
		(width 0.1651)
		(layer "In7.Cu")
		(net "P5E_PEX0_STN5_TX_DN<93>")
	)
	(segment
		(start 70.935596 -313.570112)
		(end 71.049896 -313.684412)
		(width 0.1143)
		(layer "In7.Cu")
		(net "P5E_PEX0_STN5_TX_DN<93>")
	)
	(segment
		(start 70.784466 -313.570112)
		(end 70.935596 -313.570112)
		(width 0.1143)
		(layer "In7.Cu")
		(net "P5E_PEX0_STN5_TX_DN<93>")
	)
	(segment
		(start 89.925652 -341.00516)
		(end 89.51214 -340.00694)
		(width 0.1651)
		(layer "In7.Cu")
		(net "P5E_PEX0_STN5_TX_DN<93>")
	)
	(segment
		(start 71.515986 -322.010786)
		(end 70.933056 -321.13855)
		(width 0.1651)
		(layer "In7.Cu")
		(net "P5E_PEX0_STN5_TX_DN<93>")
	)
	(segment
		(start 89.925652 -342.148668)
		(end 89.925652 -341.00516)
		(width 0.1651)
		(layer "In7.Cu")
		(net "P5E_PEX0_STN5_TX_DN<93>")
	)
	(segment
		(start 70.933056 -321.13855)
		(end 70.715886 -320.614294)
		(width 0.1651)
		(layer "In7.Cu")
		(net "P5E_PEX0_STN5_TX_DN<93>")
	)
	(segment
		(start 89.51214 -340.00694)
		(end 71.515986 -322.010786)
		(width 0.1651)
		(layer "In7.Cu")
		(net "P5E_PEX0_STN5_TX_DN<93>")
	)
	(segment
		(start 70.715886 -319.916048)
		(end 70.715886 -319.8876)
		(width 0.1143)
		(layer "In7.Cu")
		(net "P5E_PEX0_STN5_TX_DN<93>")
	)
	(segment
		(start 70.715886 -319.8876)
		(end 70.670166 -319.84188)
		(width 0.1143)
		(layer "In7.Cu")
		(net "P5E_PEX0_STN5_TX_DN<93>")
	)
	(segment
		(start 71.049896 -313.684412)
		(end 71.049896 -313.949842)
		(width 0.1143)
		(layer "In7.Cu")
		(net "P5E_PEX0_STN5_TX_DN<93>")
	)
	(segment
		(start 70.670166 -319.84188)
		(end 70.670166 -313.684412)
		(width 0.1143)
		(layer "In7.Cu")
		(net "P5E_PEX0_STN5_TX_DN<93>")
	)
	(segment
		(start 315.906404 -342.734138)
		(end 315.611764 -342.439498)
		(width 0.13462)
		(layer "F.Cu")
		(net "P5E_PEX2_STN5_TX_DP<81>")
	)
	(segment
		(start 315.586364 -343.685622)
		(end 315.906404 -343.365582)
		(width 0.13462)
		(layer "F.Cu")
		(net "P5E_PEX2_STN5_TX_DP<81>")
	)
	(segment
		(start 315.906404 -343.365582)
		(end 315.906404 -342.734138)
		(width 0.13462)
		(layer "F.Cu")
		(net "P5E_PEX2_STN5_TX_DP<81>")
	)
	(segment
		(start 291.27958 -313.605418)
		(end 291.505386 -313.379612)
		(width 0.1143)
		(layer "In7.Cu")
		(net "P5E_PEX2_STN5_TX_DP<81>")
	)
	(segment
		(start 293.554404 -329.24115)
		(end 291.23386 -323.638672)
		(width 0.1651)
		(layer "In7.Cu")
		(net "P5E_PEX2_STN5_TX_DP<81>")
	)
	(segment
		(start 291.505386 -313.379612)
		(end 291.73551 -313.379612)
		(width 0.1143)
		(layer "In7.Cu")
		(net "P5E_PEX2_STN5_TX_DP<81>")
	)
	(segment
		(start 291.23386 -319.865248)
		(end 291.23386 -319.8368)
		(width 0.1143)
		(layer "In7.Cu")
		(net "P5E_PEX2_STN5_TX_DP<81>")
	)
	(segment
		(start 315.7093 -341.415624)
		(end 297.278806 -332.965552)
		(width 0.1651)
		(layer "In7.Cu")
		(net "P5E_PEX2_STN5_TX_DP<81>")
	)
	(segment
		(start 291.23386 -323.638672)
		(end 291.23386 -319.865248)
		(width 0.1651)
		(layer "In7.Cu")
		(net "P5E_PEX2_STN5_TX_DP<81>")
	)
	(segment
		(start 291.73551 -313.379612)
		(end 291.84981 -313.265312)
		(width 0.1143)
		(layer "In7.Cu")
		(net "P5E_PEX2_STN5_TX_DP<81>")
	)
	(segment
		(start 315.902594 -341.716106)
		(end 315.7093 -341.415624)
		(width 0.1651)
		(layer "In7.Cu")
		(net "P5E_PEX2_STN5_TX_DP<81>")
	)
	(segment
		(start 291.84981 -313.265312)
		(end 291.84981 -312.999882)
		(width 0.1143)
		(layer "In7.Cu")
		(net "P5E_PEX2_STN5_TX_DP<81>")
	)
	(segment
		(start 291.23386 -319.8368)
		(end 291.27958 -319.79108)
		(width 0.1143)
		(layer "In7.Cu")
		(net "P5E_PEX2_STN5_TX_DP<81>")
	)
	(segment
		(start 315.611764 -342.439498)
		(end 315.902594 -342.148668)
		(width 0.1651)
		(layer "In7.Cu")
		(net "P5E_PEX2_STN5_TX_DP<81>")
	)
	(segment
		(start 291.27958 -319.79108)
		(end 291.27958 -313.605418)
		(width 0.1143)
		(layer "In7.Cu")
		(net "P5E_PEX2_STN5_TX_DP<81>")
	)
	(segment
		(start 315.902594 -342.148668)
		(end 315.902594 -341.716106)
		(width 0.1651)
		(layer "In7.Cu")
		(net "P5E_PEX2_STN5_TX_DP<81>")
	)
	(segment
		(start 297.278806 -332.965552)
		(end 293.554404 -329.24115)
		(width 0.1651)
		(layer "In7.Cu")
		(net "P5E_PEX2_STN5_TX_DP<81>")
	)
	(segment
		(start 366.675924 -28.54198)
		(end 366.359186 -28.225242)
		(width 0.13462)
		(layer "F.Cu")
		(net "P5E_PEX3_STN2_TX_DN<44>")
	)
	(segment
		(start 367.313972 -28.54198)
		(end 366.675924 -28.54198)
		(width 0.13462)
		(layer "F.Cu")
		(net "P5E_PEX3_STN2_TX_DN<44>")
	)
	(segment
		(start 367.60531 -28.250642)
		(end 367.313972 -28.54198)
		(width 0.13462)
		(layer "F.Cu")
		(net "P5E_PEX3_STN2_TX_DN<44>")
	)
	(segment
		(start 367.60531 -28.250642)
		(end 367.850674 -28.496006)
		(width 0.1651)
		(layer "In11.Cu")
		(net "P5E_PEX3_STN2_TX_DN<44>")
	)
	(segment
		(start 395.48562 -280.129488)
		(end 395.59992 -280.015188)
		(width 0.1143)
		(layer "In11.Cu")
		(net "P5E_PEX3_STN2_TX_DN<44>")
	)
	(segment
		(start 395.26591 -271.399)
		(end 395.26591 -271.427448)
		(width 0.1143)
		(layer "In11.Cu")
		(net "P5E_PEX3_STN2_TX_DN<44>")
	)
	(segment
		(start 387.117336 -145.385282)
		(end 394.375894 -264.583164)
		(width 0.1651)
		(layer "In11.Cu")
		(net "P5E_PEX3_STN2_TX_DN<44>")
	)
	(segment
		(start 386.986526 -50.356516)
		(end 387.68782 -62.131194)
		(width 0.1651)
		(layer "In11.Cu")
		(net "P5E_PEX3_STN2_TX_DN<44>")
	)
	(segment
		(start 395.26591 -271.427448)
		(end 395.22019 -271.473168)
		(width 0.1143)
		(layer "In11.Cu")
		(net "P5E_PEX3_STN2_TX_DN<44>")
	)
	(segment
		(start 387.68782 -62.131194)
		(end 388.045198 -135.970264)
		(width 0.1651)
		(layer "In11.Cu")
		(net "P5E_PEX3_STN2_TX_DN<44>")
	)
	(segment
		(start 395.59992 -280.015188)
		(end 395.59992 -279.749504)
		(width 0.1143)
		(layer "In11.Cu")
		(net "P5E_PEX3_STN2_TX_DN<44>")
	)
	(segment
		(start 388.045198 -135.970264)
		(end 387.117336 -145.385282)
		(width 0.1651)
		(layer "In11.Cu")
		(net "P5E_PEX3_STN2_TX_DN<44>")
	)
	(segment
		(start 395.323822 -280.129488)
		(end 395.48562 -280.129488)
		(width 0.1143)
		(layer "In11.Cu")
		(net "P5E_PEX3_STN2_TX_DN<44>")
	)
	(segment
		(start 395.22019 -271.473168)
		(end 395.22019 -280.025856)
		(width 0.1143)
		(layer "In11.Cu")
		(net "P5E_PEX3_STN2_TX_DN<44>")
	)
	(segment
		(start 370.429282 -28.541472)
		(end 372.201694 -29.272484)
		(width 0.1651)
		(layer "In11.Cu")
		(net "P5E_PEX3_STN2_TX_DN<44>")
	)
	(segment
		(start 384.227832 -44.445428)
		(end 386.238496 -48.143668)
		(width 0.1651)
		(layer "In11.Cu")
		(net "P5E_PEX3_STN2_TX_DN<44>")
	)
	(segment
		(start 367.850674 -28.496006)
		(end 367.960656 -28.541472)
		(width 0.1651)
		(layer "In11.Cu")
		(net "P5E_PEX3_STN2_TX_DN<44>")
	)
	(segment
		(start 394.375894 -264.583164)
		(end 395.26591 -270.72717)
		(width 0.1651)
		(layer "In11.Cu")
		(net "P5E_PEX3_STN2_TX_DN<44>")
	)
	(segment
		(start 386.238496 -48.143668)
		(end 386.986526 -50.356516)
		(width 0.1651)
		(layer "In11.Cu")
		(net "P5E_PEX3_STN2_TX_DN<44>")
	)
	(segment
		(start 395.26591 -270.72717)
		(end 395.26591 -271.399)
		(width 0.1651)
		(layer "In11.Cu")
		(net "P5E_PEX3_STN2_TX_DN<44>")
	)
	(segment
		(start 372.201694 -29.272484)
		(end 384.227832 -44.445428)
		(width 0.1651)
		(layer "In11.Cu")
		(net "P5E_PEX3_STN2_TX_DN<44>")
	)
	(segment
		(start 367.960656 -28.541472)
		(end 370.429282 -28.541472)
		(width 0.1651)
		(layer "In11.Cu")
		(net "P5E_PEX3_STN2_TX_DN<44>")
	)
	(segment
		(start 395.22019 -280.025856)
		(end 395.323822 -280.129488)
		(width 0.1143)
		(layer "In11.Cu")
		(net "P5E_PEX3_STN2_TX_DN<44>")
	)
	(segment
		(start 428.242984 -355.026214)
		(end 427.948852 -354.732082)
		(width 0.13462)
		(layer "F.Cu")
		(net "P5E_PEX3_STN7_TX_DN<121>")
	)
	(segment
		(start 427.923452 -355.978206)
		(end 428.242984 -355.658674)
		(width 0.13462)
		(layer "F.Cu")
		(net "P5E_PEX3_STN7_TX_DN<121>")
	)
	(segment
		(start 428.242984 -355.658674)
		(end 428.242984 -355.026214)
		(width 0.13462)
		(layer "F.Cu")
		(net "P5E_PEX3_STN7_TX_DN<121>")
	)
	(segment
		(start 384.861308 -323.792088)
		(end 384.53568 -323.006466)
		(width 0.1651)
		(layer "In11.Cu")
		(net "P5E_PEX3_STN7_TX_DN<121>")
	)
	(segment
		(start 385.415282 -312.049922)
		(end 385.149852 -312.049922)
		(width 0.1143)
		(layer "In11.Cu")
		(net "P5E_PEX3_STN7_TX_DN<121>")
	)
	(segment
		(start 384.53568 -318.008)
		(end 384.5814 -317.96228)
		(width 0.1143)
		(layer "In11.Cu")
		(net "P5E_PEX3_STN7_TX_DN<121>")
	)
	(segment
		(start 384.53568 -323.006466)
		(end 384.53568 -318.036448)
		(width 0.1651)
		(layer "In11.Cu")
		(net "P5E_PEX3_STN7_TX_DN<121>")
	)
	(segment
		(start 384.53568 -318.036448)
		(end 384.53568 -318.008)
		(width 0.1143)
		(layer "In11.Cu")
		(net "P5E_PEX3_STN7_TX_DN<121>")
	)
	(segment
		(start 421.248586 -335.065878)
		(end 412.748476 -332.821788)
		(width 0.1651)
		(layer "In11.Cu")
		(net "P5E_PEX3_STN7_TX_DN<121>")
	)
	(segment
		(start 429.793908 -342.00846)
		(end 428.893224 -340.40191)
		(width 0.1651)
		(layer "In11.Cu")
		(net "P5E_PEX3_STN7_TX_DN<121>")
	)
	(segment
		(start 384.5814 -317.96228)
		(end 384.5814 -312.77052)
		(width 0.1143)
		(layer "In11.Cu")
		(net "P5E_PEX3_STN7_TX_DN<121>")
	)
	(segment
		(start 385.415282 -312.44032)
		(end 385.529582 -312.32602)
		(width 0.1143)
		(layer "In11.Cu")
		(net "P5E_PEX3_STN7_TX_DN<121>")
	)
	(segment
		(start 412.748476 -332.822042)
		(end 387.125718 -326.056498)
		(width 0.1651)
		(layer "In11.Cu")
		(net "P5E_PEX3_STN7_TX_DN<121>")
	)
	(segment
		(start 427.948852 -354.732082)
		(end 428.239682 -354.441252)
		(width 0.1651)
		(layer "In11.Cu")
		(net "P5E_PEX3_STN7_TX_DN<121>")
	)
	(segment
		(start 429.794162 -352.259646)
		(end 429.794162 -342.008714)
		(width 0.1651)
		(layer "In11.Cu")
		(net "P5E_PEX3_STN7_TX_DN<121>")
	)
	(segment
		(start 384.5814 -312.77052)
		(end 384.9116 -312.44032)
		(width 0.1143)
		(layer "In11.Cu")
		(net "P5E_PEX3_STN7_TX_DN<121>")
	)
	(segment
		(start 428.239682 -354.441252)
		(end 428.239682 -353.814126)
		(width 0.1651)
		(layer "In11.Cu")
		(net "P5E_PEX3_STN7_TX_DN<121>")
	)
	(segment
		(start 428.893224 -340.40191)
		(end 421.248586 -335.065878)
		(width 0.1651)
		(layer "In11.Cu")
		(net "P5E_PEX3_STN7_TX_DN<121>")
	)
	(segment
		(start 385.529582 -312.164222)
		(end 385.415282 -312.049922)
		(width 0.1143)
		(layer "In11.Cu")
		(net "P5E_PEX3_STN7_TX_DN<121>")
	)
	(segment
		(start 384.9116 -312.44032)
		(end 385.415282 -312.44032)
		(width 0.1143)
		(layer "In11.Cu")
		(net "P5E_PEX3_STN7_TX_DN<121>")
	)
	(segment
		(start 385.529582 -312.32602)
		(end 385.529582 -312.164222)
		(width 0.1143)
		(layer "In11.Cu")
		(net "P5E_PEX3_STN7_TX_DN<121>")
	)
	(segment
		(start 412.748476 -332.821788)
		(end 412.748476 -332.822042)
		(width 0.1651)
		(layer "In11.Cu")
		(net "P5E_PEX3_STN7_TX_DN<121>")
	)
	(segment
		(start 387.125718 -326.056498)
		(end 384.861308 -323.792088)
		(width 0.1651)
		(layer "In11.Cu")
		(net "P5E_PEX3_STN7_TX_DN<121>")
	)
	(segment
		(start 428.239682 -353.814126)
		(end 429.794162 -352.259646)
		(width 0.1651)
		(layer "In11.Cu")
		(net "P5E_PEX3_STN7_TX_DN<121>")
	)
	(segment
		(start 429.794162 -342.008714)
		(end 429.793908 -342.00846)
		(width 0.1651)
		(layer "In11.Cu")
		(net "P5E_PEX3_STN7_TX_DN<121>")
	)
	(segment
		(start 286.845502 -350.685354)
		(end 286.845502 -351.316798)
		(width 0.13462)
		(layer "F.Cu")
		(net "P5E_PEX2_STN7_TX_C_DN<121>")
	)
	(segment
		(start 286.845502 -351.316798)
		(end 286.550862 -351.611438)
		(width 0.13462)
		(layer "F.Cu")
		(net "P5E_PEX2_STN7_TX_C_DN<121>")
	)
	(segment
		(start 286.525462 -350.365314)
		(end 286.845502 -350.685354)
		(width 0.13462)
		(layer "F.Cu")
		(net "P5E_PEX2_STN7_TX_C_DN<121>")
	)
	(segment
		(start 289.789616 -367.282984)
		(end 289.635692 -367.233708)
		(width 0.1651)
		(layer "In7.Cu")
		(net "P5E_PEX2_STN7_TX_C_DN<121>")
	)
	(segment
		(start 286.841692 -352.356166)
		(end 286.841692 -351.902268)
		(width 0.1651)
		(layer "In7.Cu")
		(net "P5E_PEX2_STN7_TX_C_DN<121>")
	)
	(segment
		(start 289.816794 -375.999248)
		(end 290.24707 -375.999248)
		(width 0.1651)
		(layer "In7.Cu")
		(net "P5E_PEX2_STN7_TX_C_DN<121>")
	)
	(segment
		(start 289.230054 -366.199674)
		(end 289.07613 -366.150398)
		(width 0.1651)
		(layer "In7.Cu")
		(net "P5E_PEX2_STN7_TX_C_DN<121>")
	)
	(segment
		(start 287.974024 -363.989112)
		(end 287.74644 -363.548676)
		(width 0.1651)
		(layer "In7.Cu")
		(net "P5E_PEX2_STN7_TX_C_DN<121>")
	)
	(segment
		(start 288.516568 -365.067088)
		(end 288.288984 -364.626906)
		(width 0.1651)
		(layer "In7.Cu")
		(net "P5E_PEX2_STN7_TX_C_DN<121>")
	)
	(segment
		(start 288.897568 -365.556292)
		(end 288.670492 -365.116364)
		(width 0.1651)
		(layer "In7.Cu")
		(net "P5E_PEX2_STN7_TX_C_DN<121>")
	)
	(segment
		(start 289.689794 -375.490232)
		(end 289.689794 -375.872248)
		(width 0.1651)
		(layer "In7.Cu")
		(net "P5E_PEX2_STN7_TX_C_DN<121>")
	)
	(segment
		(start 288.11093 -364.0328)
		(end 287.974024 -363.989112)
		(width 0.1651)
		(layer "In7.Cu")
		(net "P5E_PEX2_STN7_TX_C_DN<121>")
	)
	(segment
		(start 285.287212 -353.910646)
		(end 286.841692 -352.356166)
		(width 0.1651)
		(layer "In7.Cu")
		(net "P5E_PEX2_STN7_TX_C_DN<121>")
	)
	(segment
		(start 289.07613 -366.150398)
		(end 288.848546 -365.710216)
		(width 0.1651)
		(layer "In7.Cu")
		(net "P5E_PEX2_STN7_TX_C_DN<121>")
	)
	(segment
		(start 289.408108 -366.793526)
		(end 289.45713 -366.639602)
		(width 0.1651)
		(layer "In7.Cu")
		(net "P5E_PEX2_STN7_TX_C_DN<121>")
	)
	(segment
		(start 289.45713 -366.639602)
		(end 289.230054 -366.199674)
		(width 0.1651)
		(layer "In7.Cu")
		(net "P5E_PEX2_STN7_TX_C_DN<121>")
	)
	(segment
		(start 285.287212 -358.56418)
		(end 285.287212 -353.910646)
		(width 0.1651)
		(layer "In7.Cu")
		(net "P5E_PEX2_STN7_TX_C_DN<121>")
	)
	(segment
		(start 288.670492 -365.116364)
		(end 288.516568 -365.067088)
		(width 0.1651)
		(layer "In7.Cu")
		(net "P5E_PEX2_STN7_TX_C_DN<121>")
	)
	(segment
		(start 288.288984 -364.626906)
		(end 288.338006 -364.472728)
		(width 0.1651)
		(layer "In7.Cu")
		(net "P5E_PEX2_STN7_TX_C_DN<121>")
	)
	(segment
		(start 288.338006 -364.472728)
		(end 288.11093 -364.0328)
		(width 0.1651)
		(layer "In7.Cu")
		(net "P5E_PEX2_STN7_TX_C_DN<121>")
	)
	(segment
		(start 290.533836 -368.72418)
		(end 289.789616 -367.282984)
		(width 0.1651)
		(layer "In7.Cu")
		(net "P5E_PEX2_STN7_TX_C_DN<121>")
	)
	(segment
		(start 290.533836 -375.712482)
		(end 290.533836 -368.72418)
		(width 0.1651)
		(layer "In7.Cu")
		(net "P5E_PEX2_STN7_TX_C_DN<121>")
	)
	(segment
		(start 286.841692 -351.902268)
		(end 286.550862 -351.611438)
		(width 0.1651)
		(layer "In7.Cu")
		(net "P5E_PEX2_STN7_TX_C_DN<121>")
	)
	(segment
		(start 289.635692 -367.233708)
		(end 289.408108 -366.793526)
		(width 0.1651)
		(layer "In7.Cu")
		(net "P5E_PEX2_STN7_TX_C_DN<121>")
	)
	(segment
		(start 287.74644 -363.548676)
		(end 287.790128 -363.41177)
		(width 0.1651)
		(layer "In7.Cu")
		(net "P5E_PEX2_STN7_TX_C_DN<121>")
	)
	(segment
		(start 289.689794 -375.872248)
		(end 289.816794 -375.999248)
		(width 0.1651)
		(layer "In7.Cu")
		(net "P5E_PEX2_STN7_TX_C_DN<121>")
	)
	(segment
		(start 287.790128 -363.41177)
		(end 285.287212 -358.56418)
		(width 0.1651)
		(layer "In7.Cu")
		(net "P5E_PEX2_STN7_TX_C_DN<121>")
	)
	(segment
		(start 288.848546 -365.710216)
		(end 288.897568 -365.556292)
		(width 0.1651)
		(layer "In7.Cu")
		(net "P5E_PEX2_STN7_TX_C_DN<121>")
	)
	(segment
		(start 290.24707 -375.999248)
		(end 290.533836 -375.712482)
		(width 0.1651)
		(layer "In7.Cu")
		(net "P5E_PEX2_STN7_TX_C_DN<121>")
	)
	(segment
		(start 386.78739 -116.214652)
		(end 389.595868 -116.214652)
		(width 0.13208)
		(layer "F.Cu")
		(net "PRSNT_NIC6_N")
	)
	(segment
		(start 385.907534 -96.1644)
		(end 386.66039 -96.1644)
		(width 0.13208)
		(layer "F.Cu")
		(net "PRSNT_NIC6_N")
	)
	(segment
		(start 390.306306 -116.92509)
		(end 400.800062 -116.92509)
		(width 0.13208)
		(layer "F.Cu")
		(net "PRSNT_NIC6_N")
	)
	(segment
		(start 404.58009 -138.6332)
		(end 404.58009 -137.414)
		(width 0.13208)
		(layer "F.Cu")
		(net "PRSNT_NIC6_N")
	)
	(segment
		(start 385.936744 -116.512594)
		(end 385.936744 -116.536978)
		(width 0.13208)
		(layer "F.Cu")
		(net "PRSNT_NIC6_N")
	)
	(segment
		(start 386.66039 -116.341652)
		(end 386.78739 -116.214652)
		(width 0.13208)
		(layer "F.Cu")
		(net "PRSNT_NIC6_N")
	)
	(segment
		(start 401.923758 -115.801394)
		(end 404.52929 -115.801394)
		(width 0.13208)
		(layer "F.Cu")
		(net "PRSNT_NIC6_N")
	)
	(segment
		(start 386.66039 -116.7384)
		(end 386.66039 -116.341652)
		(width 0.13208)
		(layer "F.Cu")
		(net "PRSNT_NIC6_N")
	)
	(segment
		(start 400.800062 -116.92509)
		(end 401.923758 -115.801394)
		(width 0.13208)
		(layer "F.Cu")
		(net "PRSNT_NIC6_N")
	)
	(segment
		(start 381.270256 -118.023386)
		(end 380.61773 -117.37086)
		(width 0.13208)
		(layer "F.Cu")
		(net "PRSNT_NIC6_N")
	)
	(segment
		(start 404.58009 -137.414)
		(end 404.70709 -137.287)
		(width 0.13208)
		(layer "F.Cu")
		(net "PRSNT_NIC6_N")
	)
	(segment
		(start 385.585716 -116.888006)
		(end 385.585716 -117.09654)
		(width 0.13208)
		(layer "F.Cu")
		(net "PRSNT_NIC6_N")
	)
	(segment
		(start 404.52929 -115.801394)
		(end 404.52929 -116.5352)
		(width 0.13208)
		(layer "F.Cu")
		(net "PRSNT_NIC6_N")
	)
	(segment
		(start 384.65887 -118.023386)
		(end 381.270256 -118.023386)
		(width 0.13208)
		(layer "F.Cu")
		(net "PRSNT_NIC6_N")
	)
	(segment
		(start 385.585716 -117.09654)
		(end 384.65887 -118.023386)
		(width 0.13208)
		(layer "F.Cu")
		(net "PRSNT_NIC6_N")
	)
	(segment
		(start 385.936744 -116.512594)
		(end 386.16255 -116.7384)
		(width 0.13208)
		(layer "F.Cu")
		(net "PRSNT_NIC6_N")
	)
	(segment
		(start 385.936744 -116.536978)
		(end 385.585716 -116.888006)
		(width 0.13208)
		(layer "F.Cu")
		(net "PRSNT_NIC6_N")
	)
	(segment
		(start 386.16255 -116.7384)
		(end 386.66039 -116.7384)
		(width 0.13208)
		(layer "F.Cu")
		(net "PRSNT_NIC6_N")
	)
	(segment
		(start 380.61773 -117.37086)
		(end 380.61773 -115.736624)
		(width 0.13208)
		(layer "F.Cu")
		(net "PRSNT_NIC6_N")
	)
	(segment
		(start 389.595868 -116.214652)
		(end 390.306306 -116.92509)
		(width 0.13208)
		(layer "F.Cu")
		(net "PRSNT_NIC6_N")
	)
	(segment
		(start 404.70709 -137.287)
		(end 405.45004 -137.287)
		(width 0.13208)
		(layer "F.Cu")
		(net "PRSNT_NIC6_N")
	)
	(via
		(at 385.907534 -96.1644)
		(size 0.508)
		(drill 0.254)
		(layers "F.Cu" "B.Cu")
		(net "PRSNT_NIC6_N")
	)
	(via
		(at 404.52929 -115.801394)
		(size 0.508)
		(drill 0.254)
		(layers "F.Cu" "B.Cu")
		(net "PRSNT_NIC6_N")
	)
	(via
		(at 385.936744 -116.512594)
		(size 0.508)
		(drill 0.254)
		(layers "F.Cu" "B.Cu")
		(net "PRSNT_NIC6_N")
	)
	(via
		(at 405.45004 -137.287)
		(size 0.508)
		(drill 0.254)
		(layers "F.Cu" "B.Cu")
		(net "PRSNT_NIC6_N")
	)
	(segment
		(start 404.30704 -132.557774)
		(end 404.30704 -136.144)
		(width 0.15494)
		(layer "In9.Cu")
		(net "PRSNT_NIC6_N")
	)
	(segment
		(start 387.583426 -112.019334)
		(end 385.504182 -114.098578)
		(width 0.15494)
		(layer "In9.Cu")
		(net "PRSNT_NIC6_N")
	)
	(segment
		(start 404.99411 -131.870704)
		(end 404.30704 -132.557774)
		(width 0.15494)
		(layer "In9.Cu")
		(net "PRSNT_NIC6_N")
	)
	(segment
		(start 404.52929 -115.801394)
		(end 404.99411 -116.266214)
		(width 0.15494)
		(layer "In9.Cu")
		(net "PRSNT_NIC6_N")
	)
	(segment
		(start 387.583426 -97.840292)
		(end 387.583426 -112.019334)
		(width 0.15494)
		(layer "In9.Cu")
		(net "PRSNT_NIC6_N")
	)
	(segment
		(start 404.99411 -116.266214)
		(end 404.99411 -131.870704)
		(width 0.15494)
		(layer "In9.Cu")
		(net "PRSNT_NIC6_N")
	)
	(segment
		(start 385.907534 -96.1644)
		(end 387.583426 -97.840292)
		(width 0.15494)
		(layer "In9.Cu")
		(net "PRSNT_NIC6_N")
	)
	(segment
		(start 404.30704 -136.144)
		(end 405.45004 -137.287)
		(width 0.15494)
		(layer "In9.Cu")
		(net "PRSNT_NIC6_N")
	)
	(segment
		(start 385.504182 -114.098578)
		(end 385.504182 -116.080032)
		(width 0.15494)
		(layer "In9.Cu")
		(net "PRSNT_NIC6_N")
	)
	(segment
		(start 385.504182 -116.080032)
		(end 385.936744 -116.512594)
		(width 0.15494)
		(layer "In9.Cu")
		(net "PRSNT_NIC6_N")
	)
	(segment
		(start 55.964582 -156.95422)
		(end 56.38165 -157.371288)
		(width 0.13208)
		(layer "F.Cu")
		(net "RST_HP_NIC0_BUF_N")
	)
	(segment
		(start 56.38165 -157.371288)
		(end 56.38165 -157.8356)
		(width 0.13208)
		(layer "F.Cu")
		(net "RST_HP_NIC0_BUF_N")
	)
	(segment
		(start 56.339486 -156.222954)
		(end 55.359554 -156.222954)
		(width 0.13208)
		(layer "F.Cu")
		(net "RST_HP_NIC0_BUF_N")
	)
	(segment
		(start 56.38165 -158.8516)
		(end 56.38165 -157.8356)
		(width 0.13208)
		(layer "F.Cu")
		(net "RST_HP_NIC0_BUF_N")
	)
	(segment
		(start 56.339486 -156.222954)
		(end 56.339486 -156.579316)
		(width 0.13208)
		(layer "F.Cu")
		(net "RST_HP_NIC0_BUF_N")
	)
	(segment
		(start 55.359554 -156.222954)
		(end 55.356506 -156.219906)
		(width 0.13208)
		(layer "F.Cu")
		(net "RST_HP_NIC0_BUF_N")
	)
	(segment
		(start 56.339486 -156.579316)
		(end 55.964582 -156.95422)
		(width 0.13208)
		(layer "F.Cu")
		(net "RST_HP_NIC0_BUF_N")
	)
	(via
		(at 55.964582 -156.95422)
		(size 0.508)
		(drill 0.254)
		(layers "F.Cu" "B.Cu")
		(net "RST_HP_NIC0_BUF_N")
	)
	(segment
		(start 58.970418 -156.95422)
		(end 59.175904 -156.748734)
		(width 0.13208)
		(layer "B.Cu")
		(net "RST_HP_NIC0_BUF_N")
	)
	(segment
		(start 55.964582 -156.95422)
		(end 58.970418 -156.95422)
		(width 0.13208)
		(layer "B.Cu")
		(net "RST_HP_NIC0_BUF_N")
	)
	(segment
		(start 59.175904 -154.58567)
		(end 59.386978 -154.374596)
		(width 0.13208)
		(layer "B.Cu")
		(net "RST_HP_NIC0_BUF_N")
	)
	(segment
		(start 59.175904 -156.748734)
		(end 59.175904 -154.58567)
		(width 0.13208)
		(layer "B.Cu")
		(net "RST_HP_NIC0_BUF_N")
	)
	(segment
		(start 59.386978 -154.374596)
		(end 60.118244 -154.374596)
		(width 0.13208)
		(layer "B.Cu")
		(net "RST_HP_NIC0_BUF_N")
	)
	(segment
		(start 76.891642 -343.685622)
		(end 77.211682 -343.365582)
		(width 0.13462)
		(layer "F.Cu")
		(net "P5E_PEX0_STN5_TX_DP<87>")
	)
	(segment
		(start 77.211682 -342.734138)
		(end 76.917042 -342.439498)
		(width 0.13462)
		(layer "F.Cu")
		(net "P5E_PEX0_STN5_TX_DP<87>")
	)
	(segment
		(start 77.211682 -343.365582)
		(end 77.211682 -342.734138)
		(width 0.13462)
		(layer "F.Cu")
		(net "P5E_PEX0_STN5_TX_DP<87>")
	)
	(segment
		(start 76.917042 -342.439498)
		(end 77.207872 -342.148668)
		(width 0.1651)
		(layer "In7.Cu")
		(net "P5E_PEX0_STN5_TX_DP<87>")
	)
	(segment
		(start 64.733932 -322.467224)
		(end 64.733932 -319.916048)
		(width 0.1651)
		(layer "In7.Cu")
		(net "P5E_PEX0_STN5_TX_DP<87>")
	)
	(segment
		(start 64.779652 -313.605418)
		(end 65.005458 -313.379612)
		(width 0.1143)
		(layer "In7.Cu")
		(net "P5E_PEX0_STN5_TX_DP<87>")
	)
	(segment
		(start 65.005458 -313.379612)
		(end 65.235582 -313.379612)
		(width 0.1143)
		(layer "In7.Cu")
		(net "P5E_PEX0_STN5_TX_DP<87>")
	)
	(segment
		(start 77.207618 -341.31123)
		(end 76.48448 -339.121496)
		(width 0.1651)
		(layer "In7.Cu")
		(net "P5E_PEX0_STN5_TX_DP<87>")
	)
	(segment
		(start 66.85915 -326.323706)
		(end 65.150238 -323.47281)
		(width 0.1651)
		(layer "In7.Cu")
		(net "P5E_PEX0_STN5_TX_DP<87>")
	)
	(segment
		(start 77.207872 -341.311484)
		(end 77.207618 -341.31123)
		(width 0.1651)
		(layer "In7.Cu")
		(net "P5E_PEX0_STN5_TX_DP<87>")
	)
	(segment
		(start 64.733932 -319.916048)
		(end 64.733932 -319.8876)
		(width 0.1143)
		(layer "In7.Cu")
		(net "P5E_PEX0_STN5_TX_DP<87>")
	)
	(segment
		(start 65.235582 -313.379612)
		(end 65.349882 -313.265312)
		(width 0.1143)
		(layer "In7.Cu")
		(net "P5E_PEX0_STN5_TX_DP<87>")
	)
	(segment
		(start 64.733932 -319.8876)
		(end 64.779652 -319.84188)
		(width 0.1143)
		(layer "In7.Cu")
		(net "P5E_PEX0_STN5_TX_DP<87>")
	)
	(segment
		(start 68.248276 -328.01687)
		(end 66.85915 -326.323706)
		(width 0.1651)
		(layer "In7.Cu")
		(net "P5E_PEX0_STN5_TX_DP<87>")
	)
	(segment
		(start 65.150238 -323.47281)
		(end 64.733932 -322.467224)
		(width 0.1651)
		(layer "In7.Cu")
		(net "P5E_PEX0_STN5_TX_DP<87>")
	)
	(segment
		(start 65.349882 -313.265312)
		(end 65.349882 -312.999882)
		(width 0.1143)
		(layer "In7.Cu")
		(net "P5E_PEX0_STN5_TX_DP<87>")
	)
	(segment
		(start 77.207872 -342.148668)
		(end 77.207872 -341.311484)
		(width 0.1651)
		(layer "In7.Cu")
		(net "P5E_PEX0_STN5_TX_DP<87>")
	)
	(segment
		(start 76.48448 -339.121496)
		(end 68.248276 -328.01687)
		(width 0.1651)
		(layer "In7.Cu")
		(net "P5E_PEX0_STN5_TX_DP<87>")
	)
	(segment
		(start 64.779652 -319.84188)
		(end 64.779652 -313.605418)
		(width 0.1143)
		(layer "In7.Cu")
		(net "P5E_PEX0_STN5_TX_DP<87>")
	)
	(segment
		(start 279.221438 -33.95218)
		(end 278.901144 -33.631886)
		(width 0.13462)
		(layer "F.Cu")
		(net "P5E_PEX2_STN2_TX_DN<43>")
	)
	(segment
		(start 279.852374 -33.95218)
		(end 279.221438 -33.95218)
		(width 0.13462)
		(layer "F.Cu")
		(net "P5E_PEX2_STN2_TX_DN<43>")
	)
	(segment
		(start 280.147268 -33.657286)
		(end 279.852374 -33.95218)
		(width 0.13462)
		(layer "F.Cu")
		(net "P5E_PEX2_STN2_TX_DN<43>")
	)
	(segment
		(start 280.335482 -278.229568)
		(end 280.449782 -278.115268)
		(width 0.1143)
		(layer "In11.Cu")
		(net "P5E_PEX2_STN2_TX_DN<43>")
	)
	(segment
		(start 277.979124 -111.782606)
		(end 276.760686 -112.983264)
		(width 0.1651)
		(layer "In11.Cu")
		(net "P5E_PEX2_STN2_TX_DN<43>")
	)
	(segment
		(start 281.13609 -101.666802)
		(end 277.979124 -111.782606)
		(width 0.1651)
		(layer "In11.Cu")
		(net "P5E_PEX2_STN2_TX_DN<43>")
	)
	(segment
		(start 293.896542 -50.493168)
		(end 294.527732 -60.360052)
		(width 0.1651)
		(layer "In11.Cu")
		(net "P5E_PEX2_STN2_TX_DN<43>")
	)
	(segment
		(start 280.115772 -271.427448)
		(end 280.070052 -271.473168)
		(width 0.1143)
		(layer "In11.Cu")
		(net "P5E_PEX2_STN2_TX_DN<43>")
	)
	(segment
		(start 283.15285 -35.769296)
		(end 293.430198 -49.134776)
		(width 0.1651)
		(layer "In11.Cu")
		(net "P5E_PEX2_STN2_TX_DN<43>")
	)
	(segment
		(start 275.261832 -115.22456)
		(end 275.001228 -116.459254)
		(width 0.1651)
		(layer "In11.Cu")
		(net "P5E_PEX2_STN2_TX_DN<43>")
	)
	(segment
		(start 280.449782 -278.115268)
		(end 280.449782 -277.849838)
		(width 0.1143)
		(layer "In11.Cu")
		(net "P5E_PEX2_STN2_TX_DN<43>")
	)
	(segment
		(start 280.438098 -33.948116)
		(end 281.359102 -33.948116)
		(width 0.1651)
		(layer "In11.Cu")
		(net "P5E_PEX2_STN2_TX_DN<43>")
	)
	(segment
		(start 294.527732 -60.360052)
		(end 293.036498 -68.48983)
		(width 0.1651)
		(layer "In11.Cu")
		(net "P5E_PEX2_STN2_TX_DN<43>")
	)
	(segment
		(start 280.115772 -271.399)
		(end 280.115772 -271.427448)
		(width 0.1143)
		(layer "In11.Cu")
		(net "P5E_PEX2_STN2_TX_DN<43>")
	)
	(segment
		(start 274.993608 -146.80565)
		(end 276.056344 -162.530282)
		(width 0.1651)
		(layer "In11.Cu")
		(net "P5E_PEX2_STN2_TX_DN<43>")
	)
	(segment
		(start 280.147268 -33.657286)
		(end 280.438098 -33.948116)
		(width 0.1651)
		(layer "In11.Cu")
		(net "P5E_PEX2_STN2_TX_DN<43>")
	)
	(segment
		(start 276.056344 -162.530282)
		(end 279.734518 -265.75258)
		(width 0.1651)
		(layer "In11.Cu")
		(net "P5E_PEX2_STN2_TX_DN<43>")
	)
	(segment
		(start 280.070052 -278.125936)
		(end 280.173684 -278.229568)
		(width 0.1143)
		(layer "In11.Cu")
		(net "P5E_PEX2_STN2_TX_DN<43>")
	)
	(segment
		(start 281.359102 -33.948116)
		(end 283.15285 -35.769296)
		(width 0.1651)
		(layer "In11.Cu")
		(net "P5E_PEX2_STN2_TX_DN<43>")
	)
	(segment
		(start 279.734518 -265.75258)
		(end 280.115772 -269.62354)
		(width 0.1651)
		(layer "In11.Cu")
		(net "P5E_PEX2_STN2_TX_DN<43>")
	)
	(segment
		(start 276.760686 -112.983264)
		(end 275.261832 -115.22456)
		(width 0.1651)
		(layer "In11.Cu")
		(net "P5E_PEX2_STN2_TX_DN<43>")
	)
	(segment
		(start 282.821126 -95.476568)
		(end 281.13609 -101.666802)
		(width 0.1651)
		(layer "In11.Cu")
		(net "P5E_PEX2_STN2_TX_DN<43>")
	)
	(segment
		(start 280.115772 -269.62354)
		(end 280.115772 -271.399)
		(width 0.1651)
		(layer "In11.Cu")
		(net "P5E_PEX2_STN2_TX_DN<43>")
	)
	(segment
		(start 280.070052 -271.473168)
		(end 280.070052 -278.125936)
		(width 0.1143)
		(layer "In11.Cu")
		(net "P5E_PEX2_STN2_TX_DN<43>")
	)
	(segment
		(start 280.173684 -278.229568)
		(end 280.335482 -278.229568)
		(width 0.1143)
		(layer "In11.Cu")
		(net "P5E_PEX2_STN2_TX_DN<43>")
	)
	(segment
		(start 293.430198 -49.134776)
		(end 293.896542 -50.493168)
		(width 0.1651)
		(layer "In11.Cu")
		(net "P5E_PEX2_STN2_TX_DN<43>")
	)
	(segment
		(start 293.036498 -68.48983)
		(end 282.821126 -95.476568)
		(width 0.1651)
		(layer "In11.Cu")
		(net "P5E_PEX2_STN2_TX_DN<43>")
	)
	(segment
		(start 275.001228 -116.459254)
		(end 274.993608 -146.80565)
		(width 0.1651)
		(layer "In11.Cu")
		(net "P5E_PEX2_STN2_TX_DN<43>")
	)
	(segment
		(start 440.953144 -342.734646)
		(end 441.248292 -342.439498)
		(width 0.13462)
		(layer "F.Cu")
		(net "P5E_PEX3_STN7_TX_DN<126>")
	)
	(segment
		(start 440.953144 -343.365074)
		(end 440.953144 -342.734646)
		(width 0.13462)
		(layer "F.Cu")
		(net "P5E_PEX3_STN7_TX_DN<126>")
	)
	(segment
		(start 441.273692 -343.685622)
		(end 440.953144 -343.365074)
		(width 0.13462)
		(layer "F.Cu")
		(net "P5E_PEX3_STN7_TX_DN<126>")
	)
	(segment
		(start 389.519922 -311.774078)
		(end 389.623808 -311.670192)
		(width 0.1143)
		(layer "In11.Cu")
		(net "P5E_PEX3_STN7_TX_DN<126>")
	)
	(segment
		(start 389.565642 -320.056256)
		(end 389.565642 -320.034158)
		(width 0.1143)
		(layer "In11.Cu")
		(net "P5E_PEX3_STN7_TX_DN<126>")
	)
	(segment
		(start 394.88999 -322.519548)
		(end 394.88999 -322.520056)
		(width 0.1651)
		(layer "In11.Cu")
		(net "P5E_PEX3_STN7_TX_DN<126>")
	)
	(segment
		(start 392.629898 -321.924172)
		(end 392.566652 -321.815206)
		(width 0.1651)
		(layer "In11.Cu")
		(net "P5E_PEX3_STN7_TX_DN<126>")
	)
	(segment
		(start 426.9232 -330.962)
		(end 394.88999 -322.519548)
		(width 0.1651)
		(layer "In11.Cu")
		(net "P5E_PEX3_STN7_TX_DN<126>")
	)
	(segment
		(start 392.566652 -321.815206)
		(end 392.087354 -321.688968)
		(width 0.1651)
		(layer "In11.Cu")
		(net "P5E_PEX3_STN7_TX_DN<126>")
	)
	(segment
		(start 394.347446 -322.284852)
		(end 394.238734 -322.348098)
		(width 0.1651)
		(layer "In11.Cu")
		(net "P5E_PEX3_STN7_TX_DN<126>")
	)
	(segment
		(start 393.2174 -321.98691)
		(end 393.108688 -322.050156)
		(width 0.1651)
		(layer "In11.Cu")
		(net "P5E_PEX3_STN7_TX_DN<126>")
	)
	(segment
		(start 389.785606 -311.670192)
		(end 389.899906 -311.784492)
		(width 0.1143)
		(layer "In11.Cu")
		(net "P5E_PEX3_STN7_TX_DN<126>")
	)
	(segment
		(start 389.565642 -321.002914)
		(end 389.565642 -320.056256)
		(width 0.1651)
		(layer "In11.Cu")
		(net "P5E_PEX3_STN7_TX_DN<126>")
	)
	(segment
		(start 392.087354 -321.688968)
		(end 391.978896 -321.752468)
		(width 0.1651)
		(layer "In11.Cu")
		(net "P5E_PEX3_STN7_TX_DN<126>")
	)
	(segment
		(start 393.696444 -322.113148)
		(end 393.2174 -321.98691)
		(width 0.1651)
		(layer "In11.Cu")
		(net "P5E_PEX3_STN7_TX_DN<126>")
	)
	(segment
		(start 441.248292 -342.439498)
		(end 440.957462 -342.148668)
		(width 0.1651)
		(layer "In11.Cu")
		(net "P5E_PEX3_STN7_TX_DN<126>")
	)
	(segment
		(start 440.957462 -341.414862)
		(end 440.0804 -340.1568)
		(width 0.1651)
		(layer "In11.Cu")
		(net "P5E_PEX3_STN7_TX_DN<126>")
	)
	(segment
		(start 394.88999 -322.520056)
		(end 394.82649 -322.41109)
		(width 0.1651)
		(layer "In11.Cu")
		(net "P5E_PEX3_STN7_TX_DN<126>")
	)
	(segment
		(start 389.899906 -311.784492)
		(end 389.899906 -312.049922)
		(width 0.1143)
		(layer "In11.Cu")
		(net "P5E_PEX3_STN7_TX_DN<126>")
	)
	(segment
		(start 393.108688 -322.050156)
		(end 392.629898 -321.924172)
		(width 0.1651)
		(layer "In11.Cu")
		(net "P5E_PEX3_STN7_TX_DN<126>")
	)
	(segment
		(start 389.623808 -311.670192)
		(end 389.785606 -311.670192)
		(width 0.1143)
		(layer "In11.Cu")
		(net "P5E_PEX3_STN7_TX_DN<126>")
	)
	(segment
		(start 389.67537 -321.145408)
		(end 389.565642 -321.002914)
		(width 0.1651)
		(layer "In11.Cu")
		(net "P5E_PEX3_STN7_TX_DN<126>")
	)
	(segment
		(start 389.519922 -319.988438)
		(end 389.519922 -311.774078)
		(width 0.1143)
		(layer "In11.Cu")
		(net "P5E_PEX3_STN7_TX_DN<126>")
	)
	(segment
		(start 391.978896 -321.752468)
		(end 389.67537 -321.145408)
		(width 0.1651)
		(layer "In11.Cu")
		(net "P5E_PEX3_STN7_TX_DN<126>")
	)
	(segment
		(start 394.238734 -322.348098)
		(end 393.759944 -322.222114)
		(width 0.1651)
		(layer "In11.Cu")
		(net "P5E_PEX3_STN7_TX_DN<126>")
	)
	(segment
		(start 440.0804 -340.1568)
		(end 426.9232 -330.962)
		(width 0.1651)
		(layer "In11.Cu")
		(net "P5E_PEX3_STN7_TX_DN<126>")
	)
	(segment
		(start 389.565642 -320.034158)
		(end 389.519922 -319.988438)
		(width 0.1143)
		(layer "In11.Cu")
		(net "P5E_PEX3_STN7_TX_DN<126>")
	)
	(segment
		(start 440.957462 -342.148668)
		(end 440.957462 -341.414862)
		(width 0.1651)
		(layer "In11.Cu")
		(net "P5E_PEX3_STN7_TX_DN<126>")
	)
	(segment
		(start 394.82649 -322.41109)
		(end 394.347446 -322.284852)
		(width 0.1651)
		(layer "In11.Cu")
		(net "P5E_PEX3_STN7_TX_DN<126>")
	)
	(segment
		(start 393.759944 -322.222114)
		(end 393.696444 -322.113148)
		(width 0.1651)
		(layer "In11.Cu")
		(net "P5E_PEX3_STN7_TX_DN<126>")
	)
	(segment
		(start 290.228782 -356.831646)
		(end 290.228782 -357.46309)
		(width 0.13462)
		(layer "F.Cu")
		(net "P5E_PEX2_STN7_TX_C_DN<123>")
	)
	(segment
		(start 290.228782 -357.46309)
		(end 290.523422 -357.75773)
		(width 0.13462)
		(layer "F.Cu")
		(net "P5E_PEX2_STN7_TX_C_DN<123>")
	)
	(segment
		(start 290.548822 -356.511606)
		(end 290.228782 -356.831646)
		(width 0.13462)
		(layer "F.Cu")
		(net "P5E_PEX2_STN7_TX_C_DN<123>")
	)
	(segment
		(start 294.216836 -376.281188)
		(end 294.089836 -376.408188)
		(width 0.1651)
		(layer "In7.Cu")
		(net "P5E_PEX2_STN7_TX_C_DN<123>")
	)
	(segment
		(start 290.523422 -357.75773)
		(end 290.232592 -358.04856)
		(width 0.1651)
		(layer "In7.Cu")
		(net "P5E_PEX2_STN7_TX_C_DN<123>")
	)
	(segment
		(start 294.089836 -376.408188)
		(end 294.089836 -376.790204)
		(width 0.1651)
		(layer "In7.Cu")
		(net "P5E_PEX2_STN7_TX_C_DN<123>")
	)
	(segment
		(start 294.763952 -376.281188)
		(end 294.216836 -376.281188)
		(width 0.1651)
		(layer "In7.Cu")
		(net "P5E_PEX2_STN7_TX_C_DN<123>")
	)
	(segment
		(start 295.215818 -375.829322)
		(end 294.763952 -376.281188)
		(width 0.1651)
		(layer "In7.Cu")
		(net "P5E_PEX2_STN7_TX_C_DN<123>")
	)
	(segment
		(start 290.232592 -358.04856)
		(end 290.232592 -358.7242)
		(width 0.1651)
		(layer "In7.Cu")
		(net "P5E_PEX2_STN7_TX_C_DN<123>")
	)
	(segment
		(start 290.232592 -358.7242)
		(end 295.215818 -368.6556)
		(width 0.1651)
		(layer "In7.Cu")
		(net "P5E_PEX2_STN7_TX_C_DN<123>")
	)
	(segment
		(start 295.215818 -368.6556)
		(end 295.215818 -375.829322)
		(width 0.1651)
		(layer "In7.Cu")
		(net "P5E_PEX2_STN7_TX_C_DN<123>")
	)
	(segment
		(start 401.865592 -174.911766)
		(end 401.595082 -175.182276)
		(width 0.13208)
		(layer "F.Cu")
		(net "HP_NIC6_PWRGD")
	)
	(segment
		(start 400.838924 -172.409104)
		(end 401.865592 -173.435772)
		(width 0.13208)
		(layer "F.Cu")
		(net "HP_NIC6_PWRGD")
	)
	(segment
		(start 412.2674 -174.004732)
		(end 411.762194 -174.509938)
		(width 0.13208)
		(layer "F.Cu")
		(net "HP_NIC6_PWRGD")
	)
	(segment
		(start 411.948122 -170.157902)
		(end 411.948122 -170.920918)
		(width 0.13208)
		(layer "F.Cu")
		(net "HP_NIC6_PWRGD")
	)
	(segment
		(start 401.595082 -175.182276)
		(end 401.145248 -175.182276)
		(width 0.13208)
		(layer "F.Cu")
		(net "HP_NIC6_PWRGD")
	)
	(segment
		(start 400.812 -172.409104)
		(end 400.838924 -172.409104)
		(width 0.13208)
		(layer "F.Cu")
		(net "HP_NIC6_PWRGD")
	)
	(segment
		(start 412.2674 -171.240196)
		(end 412.2674 -171.675806)
		(width 0.13208)
		(layer "F.Cu")
		(net "HP_NIC6_PWRGD")
	)
	(segment
		(start 401.865592 -173.435772)
		(end 401.865592 -174.911766)
		(width 0.13208)
		(layer "F.Cu")
		(net "HP_NIC6_PWRGD")
	)
	(segment
		(start 412.2674 -171.675806)
		(end 412.2674 -174.004732)
		(width 0.13208)
		(layer "F.Cu")
		(net "HP_NIC6_PWRGD")
	)
	(segment
		(start 411.762194 -174.509938)
		(end 410.441902 -175.83023)
		(width 0.13208)
		(layer "F.Cu")
		(net "HP_NIC6_PWRGD")
	)
	(segment
		(start 411.948122 -170.920918)
		(end 412.2674 -171.240196)
		(width 0.13208)
		(layer "F.Cu")
		(net "HP_NIC6_PWRGD")
	)
	(via
		(at 410.441902 -175.83023)
		(size 0.508)
		(drill 0.254)
		(layers "F.Cu" "B.Cu")
		(net "HP_NIC6_PWRGD")
	)
	(via
		(at 411.762194 -174.509938)
		(size 0.762)
		(drill 0.381)
		(layers "F.Cu" "B.Cu")
		(net "HP_NIC6_PWRGD")
	)
	(via
		(at 400.812 -172.409104)
		(size 0.508)
		(drill 0.254)
		(layers "F.Cu" "B.Cu")
		(net "HP_NIC6_PWRGD")
	)
	(segment
		(start 408.868118 -175.83023)
		(end 405.446992 -172.409104)
		(width 0.15494)
		(layer "In13.Cu")
		(net "HP_NIC6_PWRGD")
	)
	(segment
		(start 410.441902 -175.83023)
		(end 408.868118 -175.83023)
		(width 0.15494)
		(layer "In13.Cu")
		(net "HP_NIC6_PWRGD")
	)
	(segment
		(start 405.446992 -172.409104)
		(end 400.812 -172.409104)
		(width 0.15494)
		(layer "In13.Cu")
		(net "HP_NIC6_PWRGD")
	)
	(segment
		(start 53.849016 -115.576096)
		(end 56.22925 -115.576096)
		(width 0.13208)
		(layer "F.Cu")
		(net "PRSNT_NIC0_N")
	)
	(segment
		(start 32.31769 -117.37086)
		(end 32.31769 -115.736624)
		(width 0.13208)
		(layer "F.Cu")
		(net "PRSNT_NIC0_N")
	)
	(segment
		(start 37.636704 -116.512594)
		(end 37.86251 -116.7384)
		(width 0.13208)
		(layer "F.Cu")
		(net "PRSNT_NIC0_N")
	)
	(segment
		(start 52.500022 -116.92509)
		(end 53.849016 -115.576096)
		(width 0.13208)
		(layer "F.Cu")
		(net "PRSNT_NIC0_N")
	)
	(segment
		(start 37.636704 -116.512594)
		(end 36.166298 -117.983)
		(width 0.13208)
		(layer "F.Cu")
		(net "PRSNT_NIC0_N")
	)
	(segment
		(start 42.006266 -116.92509)
		(end 52.500022 -116.92509)
		(width 0.13208)
		(layer "F.Cu")
		(net "PRSNT_NIC0_N")
	)
	(segment
		(start 37.86251 -116.7384)
		(end 38.36035 -116.7384)
		(width 0.13208)
		(layer "F.Cu")
		(net "PRSNT_NIC0_N")
	)
	(segment
		(start 56.40705 -137.287)
		(end 57.15 -137.287)
		(width 0.13208)
		(layer "F.Cu")
		(net "PRSNT_NIC0_N")
	)
	(segment
		(start 56.28005 -137.414)
		(end 56.40705 -137.287)
		(width 0.13208)
		(layer "F.Cu")
		(net "PRSNT_NIC0_N")
	)
	(segment
		(start 38.48735 -116.214652)
		(end 41.295828 -116.214652)
		(width 0.13208)
		(layer "F.Cu")
		(net "PRSNT_NIC0_N")
	)
	(segment
		(start 56.28005 -138.6332)
		(end 56.28005 -137.414)
		(width 0.13208)
		(layer "F.Cu")
		(net "PRSNT_NIC0_N")
	)
	(segment
		(start 36.166298 -117.983)
		(end 32.92983 -117.983)
		(width 0.13208)
		(layer "F.Cu")
		(net "PRSNT_NIC0_N")
	)
	(segment
		(start 37.607494 -96.1644)
		(end 38.36035 -96.1644)
		(width 0.13208)
		(layer "F.Cu")
		(net "PRSNT_NIC0_N")
	)
	(segment
		(start 32.92983 -117.983)
		(end 32.31769 -117.37086)
		(width 0.13208)
		(layer "F.Cu")
		(net "PRSNT_NIC0_N")
	)
	(segment
		(start 56.22925 -115.576096)
		(end 56.22925 -116.5352)
		(width 0.13208)
		(layer "F.Cu")
		(net "PRSNT_NIC0_N")
	)
	(segment
		(start 38.36035 -116.7384)
		(end 38.36035 -116.341652)
		(width 0.13208)
		(layer "F.Cu")
		(net "PRSNT_NIC0_N")
	)
	(segment
		(start 38.36035 -116.341652)
		(end 38.48735 -116.214652)
		(width 0.13208)
		(layer "F.Cu")
		(net "PRSNT_NIC0_N")
	)
	(segment
		(start 41.295828 -116.214652)
		(end 42.006266 -116.92509)
		(width 0.13208)
		(layer "F.Cu")
		(net "PRSNT_NIC0_N")
	)
	(via
		(at 37.636704 -116.512594)
		(size 0.508)
		(drill 0.254)
		(layers "F.Cu" "B.Cu")
		(net "PRSNT_NIC0_N")
	)
	(via
		(at 57.15 -137.287)
		(size 0.508)
		(drill 0.254)
		(layers "F.Cu" "B.Cu")
		(net "PRSNT_NIC0_N")
	)
	(via
		(at 37.607494 -96.1644)
		(size 0.508)
		(drill 0.254)
		(layers "F.Cu" "B.Cu")
		(net "PRSNT_NIC0_N")
	)
	(via
		(at 56.22925 -115.576096)
		(size 0.508)
		(drill 0.254)
		(layers "F.Cu" "B.Cu")
		(net "PRSNT_NIC0_N")
	)
	(segment
		(start 37.204142 -114.098578)
		(end 37.204142 -116.080032)
		(width 0.15494)
		(layer "In9.Cu")
		(net "PRSNT_NIC0_N")
	)
	(segment
		(start 56.632094 -133.61416)
		(end 57.742074 -132.50418)
		(width 0.15494)
		(layer "In9.Cu")
		(net "PRSNT_NIC0_N")
	)
	(segment
		(start 57.15 -137.287)
		(end 56.632094 -136.769094)
		(width 0.15494)
		(layer "In9.Cu")
		(net "PRSNT_NIC0_N")
	)
	(segment
		(start 39.283386 -112.019334)
		(end 37.204142 -114.098578)
		(width 0.15494)
		(layer "In9.Cu")
		(net "PRSNT_NIC0_N")
	)
	(segment
		(start 39.283386 -97.840292)
		(end 39.283386 -112.019334)
		(width 0.15494)
		(layer "In9.Cu")
		(net "PRSNT_NIC0_N")
	)
	(segment
		(start 56.632094 -136.769094)
		(end 56.632094 -133.61416)
		(width 0.15494)
		(layer "In9.Cu")
		(net "PRSNT_NIC0_N")
	)
	(segment
		(start 37.607494 -96.1644)
		(end 39.283386 -97.840292)
		(width 0.15494)
		(layer "In9.Cu")
		(net "PRSNT_NIC0_N")
	)
	(segment
		(start 37.204142 -116.080032)
		(end 37.636704 -116.512594)
		(width 0.15494)
		(layer "In9.Cu")
		(net "PRSNT_NIC0_N")
	)
	(segment
		(start 57.742074 -117.089428)
		(end 56.22925 -115.576604)
		(width 0.15494)
		(layer "In9.Cu")
		(net "PRSNT_NIC0_N")
	)
	(segment
		(start 57.742074 -132.50418)
		(end 57.742074 -117.089428)
		(width 0.15494)
		(layer "In9.Cu")
		(net "PRSNT_NIC0_N")
	)
	(segment
		(start 56.22925 -115.576604)
		(end 56.22925 -115.576096)
		(width 0.15494)
		(layer "In9.Cu")
		(net "PRSNT_NIC0_N")
	)
	(segment
		(start 71.268082 -342.734138)
		(end 71.562722 -342.439498)
		(width 0.13462)
		(layer "F.Cu")
		(net "P5E_PEX0_STN5_TX_DN<84>")
	)
	(segment
		(start 71.588122 -343.685622)
		(end 71.268082 -343.365582)
		(width 0.13462)
		(layer "F.Cu")
		(net "P5E_PEX0_STN5_TX_DN<84>")
	)
	(segment
		(start 71.268082 -343.365582)
		(end 71.268082 -342.734138)
		(width 0.13462)
		(layer "F.Cu")
		(net "P5E_PEX0_STN5_TX_DN<84>")
	)
	(segment
		(start 71.271892 -342.148668)
		(end 71.271892 -340.017862)
		(width 0.1651)
		(layer "In7.Cu")
		(net "P5E_PEX0_STN5_TX_DN<84>")
	)
	(segment
		(start 71.271892 -340.017862)
		(end 67.755262 -333.439008)
		(width 0.1651)
		(layer "In7.Cu")
		(net "P5E_PEX0_STN5_TX_DN<84>")
	)
	(segment
		(start 62.165738 -319.916048)
		(end 62.165738 -319.8876)
		(width 0.1143)
		(layer "In7.Cu")
		(net "P5E_PEX0_STN5_TX_DN<84>")
	)
	(segment
		(start 62.694312 -324.802754)
		(end 62.165738 -323.526658)
		(width 0.1651)
		(layer "In7.Cu")
		(net "P5E_PEX0_STN5_TX_DN<84>")
	)
	(segment
		(start 67.755262 -333.439008)
		(end 65.532254 -330.111862)
		(width 0.1651)
		(layer "In7.Cu")
		(net "P5E_PEX0_STN5_TX_DN<84>")
	)
	(segment
		(start 62.165738 -319.8876)
		(end 62.120018 -319.84188)
		(width 0.1143)
		(layer "In7.Cu")
		(net "P5E_PEX0_STN5_TX_DN<84>")
	)
	(segment
		(start 62.120018 -311.784492)
		(end 62.234318 -311.670192)
		(width 0.1143)
		(layer "In7.Cu")
		(net "P5E_PEX0_STN5_TX_DN<84>")
	)
	(segment
		(start 62.120018 -319.84188)
		(end 62.120018 -311.784492)
		(width 0.1143)
		(layer "In7.Cu")
		(net "P5E_PEX0_STN5_TX_DN<84>")
	)
	(segment
		(start 62.385448 -311.670192)
		(end 62.499748 -311.784492)
		(width 0.1143)
		(layer "In7.Cu")
		(net "P5E_PEX0_STN5_TX_DN<84>")
	)
	(segment
		(start 62.165738 -323.526658)
		(end 62.165738 -319.916048)
		(width 0.1651)
		(layer "In7.Cu")
		(net "P5E_PEX0_STN5_TX_DN<84>")
	)
	(segment
		(start 71.562722 -342.439498)
		(end 71.271892 -342.148668)
		(width 0.1651)
		(layer "In7.Cu")
		(net "P5E_PEX0_STN5_TX_DN<84>")
	)
	(segment
		(start 62.234318 -311.670192)
		(end 62.385448 -311.670192)
		(width 0.1143)
		(layer "In7.Cu")
		(net "P5E_PEX0_STN5_TX_DN<84>")
	)
	(segment
		(start 65.532254 -330.111862)
		(end 62.694312 -324.802754)
		(width 0.1651)
		(layer "In7.Cu")
		(net "P5E_PEX0_STN5_TX_DN<84>")
	)
	(segment
		(start 62.499748 -311.784492)
		(end 62.499748 -312.049922)
		(width 0.1143)
		(layer "In7.Cu")
		(net "P5E_PEX0_STN5_TX_DN<84>")
	)
	(segment
		(start 316.500764 -343.685622)
		(end 316.180724 -343.365582)
		(width 0.13462)
		(layer "F.Cu")
		(net "P5E_PEX2_STN5_TX_DN<81>")
	)
	(segment
		(start 316.180724 -343.365582)
		(end 316.180724 -342.734138)
		(width 0.13462)
		(layer "F.Cu")
		(net "P5E_PEX2_STN5_TX_DN<81>")
	)
	(segment
		(start 316.180724 -342.734138)
		(end 316.475364 -342.439498)
		(width 0.13462)
		(layer "F.Cu")
		(net "P5E_PEX2_STN5_TX_DN<81>")
	)
	(segment
		(start 291.5158 -323.582538)
		(end 291.5158 -319.865248)
		(width 0.1651)
		(layer "In7.Cu")
		(net "P5E_PEX2_STN5_TX_DN<81>")
	)
	(segment
		(start 291.47008 -313.684412)
		(end 291.58438 -313.570112)
		(width 0.1143)
		(layer "In7.Cu")
		(net "P5E_PEX2_STN5_TX_DN<81>")
	)
	(segment
		(start 316.184534 -342.148668)
		(end 316.184534 -341.633048)
		(width 0.1651)
		(layer "In7.Cu")
		(net "P5E_PEX2_STN5_TX_DN<81>")
	)
	(segment
		(start 293.793418 -329.081384)
		(end 291.5158 -323.582538)
		(width 0.1651)
		(layer "In7.Cu")
		(net "P5E_PEX2_STN5_TX_DN<81>")
	)
	(segment
		(start 291.5158 -319.865248)
		(end 291.5158 -319.8368)
		(width 0.1143)
		(layer "In7.Cu")
		(net "P5E_PEX2_STN5_TX_DN<81>")
	)
	(segment
		(start 291.58438 -313.570112)
		(end 291.73551 -313.570112)
		(width 0.1143)
		(layer "In7.Cu")
		(net "P5E_PEX2_STN5_TX_DN<81>")
	)
	(segment
		(start 316.184534 -341.633048)
		(end 315.901832 -341.193628)
		(width 0.1651)
		(layer "In7.Cu")
		(net "P5E_PEX2_STN5_TX_DN<81>")
	)
	(segment
		(start 291.47008 -319.79108)
		(end 291.47008 -313.684412)
		(width 0.1143)
		(layer "In7.Cu")
		(net "P5E_PEX2_STN5_TX_DN<81>")
	)
	(segment
		(start 305.924712 -336.535522)
		(end 305.82362 -336.57286)
		(width 0.1651)
		(layer "In7.Cu")
		(net "P5E_PEX2_STN5_TX_DN<81>")
	)
	(segment
		(start 297.442382 -332.730348)
		(end 293.793418 -329.081384)
		(width 0.1651)
		(layer "In7.Cu")
		(net "P5E_PEX2_STN5_TX_DN<81>")
	)
	(segment
		(start 315.901832 -341.193628)
		(end 306.412646 -336.843116)
		(width 0.1651)
		(layer "In7.Cu")
		(net "P5E_PEX2_STN5_TX_DN<81>")
	)
	(segment
		(start 291.84981 -313.684412)
		(end 291.84981 -313.949842)
		(width 0.1143)
		(layer "In7.Cu")
		(net "P5E_PEX2_STN5_TX_DN<81>")
	)
	(segment
		(start 291.73551 -313.570112)
		(end 291.84981 -313.684412)
		(width 0.1143)
		(layer "In7.Cu")
		(net "P5E_PEX2_STN5_TX_DN<81>")
	)
	(segment
		(start 306.412646 -336.843116)
		(end 306.375308 -336.742024)
		(width 0.1651)
		(layer "In7.Cu")
		(net "P5E_PEX2_STN5_TX_DN<81>")
	)
	(segment
		(start 306.375308 -336.742024)
		(end 305.924712 -336.535522)
		(width 0.1651)
		(layer "In7.Cu")
		(net "P5E_PEX2_STN5_TX_DN<81>")
	)
	(segment
		(start 305.82362 -336.57286)
		(end 297.442382 -332.730348)
		(width 0.1651)
		(layer "In7.Cu")
		(net "P5E_PEX2_STN5_TX_DN<81>")
	)
	(segment
		(start 291.5158 -319.8368)
		(end 291.47008 -319.79108)
		(width 0.1143)
		(layer "In7.Cu")
		(net "P5E_PEX2_STN5_TX_DN<81>")
	)
	(segment
		(start 316.475364 -342.439498)
		(end 316.184534 -342.148668)
		(width 0.1651)
		(layer "In7.Cu")
		(net "P5E_PEX2_STN5_TX_DN<81>")
	)
	(segment
		(start 372.07698 -343.685622)
		(end 371.756432 -343.365074)
		(width 0.13462)
		(layer "F.Cu")
		(net "P5E_PEX3_STN6_TX_DN<111>")
	)
	(segment
		(start 371.756432 -343.365074)
		(end 371.756432 -342.734646)
		(width 0.13462)
		(layer "F.Cu")
		(net "P5E_PEX3_STN6_TX_DN<111>")
	)
	(segment
		(start 371.756432 -342.734646)
		(end 372.05158 -342.439498)
		(width 0.13462)
		(layer "F.Cu")
		(net "P5E_PEX3_STN6_TX_DN<111>")
	)
	(segment
		(start 391.523728 -311.670192)
		(end 391.685526 -311.670192)
		(width 0.1143)
		(layer "In13.Cu")
		(net "P5E_PEX3_STN6_TX_DN<111>")
	)
	(segment
		(start 391.799826 -311.784492)
		(end 391.799826 -312.049922)
		(width 0.1143)
		(layer "In13.Cu")
		(net "P5E_PEX3_STN6_TX_DN<111>")
	)
	(segment
		(start 371.76075 -341.238332)
		(end 390.717786 -321.749166)
		(width 0.1651)
		(layer "In13.Cu")
		(net "P5E_PEX3_STN6_TX_DN<111>")
	)
	(segment
		(start 390.717786 -321.749166)
		(end 391.321798 -320.83121)
		(width 0.1651)
		(layer "In13.Cu")
		(net "P5E_PEX3_STN6_TX_DN<111>")
	)
	(segment
		(start 391.321798 -320.83121)
		(end 391.465816 -320.484246)
		(width 0.1651)
		(layer "In13.Cu")
		(net "P5E_PEX3_STN6_TX_DN<111>")
	)
	(segment
		(start 391.420096 -319.878202)
		(end 391.420096 -311.773824)
		(width 0.1143)
		(layer "In13.Cu")
		(net "P5E_PEX3_STN6_TX_DN<111>")
	)
	(segment
		(start 391.685526 -311.670192)
		(end 391.799826 -311.784492)
		(width 0.1143)
		(layer "In13.Cu")
		(net "P5E_PEX3_STN6_TX_DN<111>")
	)
	(segment
		(start 372.05158 -342.439498)
		(end 371.76075 -342.148668)
		(width 0.1651)
		(layer "In13.Cu")
		(net "P5E_PEX3_STN6_TX_DN<111>")
	)
	(segment
		(start 391.465816 -320.484246)
		(end 391.465816 -319.94602)
		(width 0.1651)
		(layer "In13.Cu")
		(net "P5E_PEX3_STN6_TX_DN<111>")
	)
	(segment
		(start 391.465816 -319.923922)
		(end 391.420096 -319.878202)
		(width 0.1143)
		(layer "In13.Cu")
		(net "P5E_PEX3_STN6_TX_DN<111>")
	)
	(segment
		(start 391.420096 -311.773824)
		(end 391.523728 -311.670192)
		(width 0.1143)
		(layer "In13.Cu")
		(net "P5E_PEX3_STN6_TX_DN<111>")
	)
	(segment
		(start 371.76075 -342.148668)
		(end 371.76075 -341.238332)
		(width 0.1651)
		(layer "In13.Cu")
		(net "P5E_PEX3_STN6_TX_DN<111>")
	)
	(segment
		(start 391.465816 -319.94602)
		(end 391.465816 -319.923922)
		(width 0.1143)
		(layer "In13.Cu")
		(net "P5E_PEX3_STN6_TX_DN<111>")
	)
	(segment
		(start 397.93037 -179.657756)
		(end 397.93037 -178.656996)
		(width 0.13208)
		(layer "F.Cu")
		(net "HP_NIC6_HSC_PWRGD_N")
	)
	(segment
		(start 399.298668 -180.372766)
		(end 398.64538 -180.372766)
		(width 0.13208)
		(layer "F.Cu")
		(net "HP_NIC6_HSC_PWRGD_N")
	)
	(segment
		(start 397.93037 -178.656996)
		(end 398.209008 -178.378358)
		(width 0.13208)
		(layer "F.Cu")
		(net "HP_NIC6_HSC_PWRGD_N")
	)
	(segment
		(start 399.298668 -179.588668)
		(end 399.298668 -180.372766)
		(width 0.13208)
		(layer "F.Cu")
		(net "HP_NIC6_HSC_PWRGD_N")
	)
	(segment
		(start 398.209008 -178.378358)
		(end 398.989296 -178.378358)
		(width 0.13208)
		(layer "F.Cu")
		(net "HP_NIC6_HSC_PWRGD_N")
	)
	(segment
		(start 398.64538 -180.372766)
		(end 397.93037 -179.657756)
		(width 0.13208)
		(layer "F.Cu")
		(net "HP_NIC6_HSC_PWRGD_N")
	)
	(segment
		(start 399.639282 -178.378358)
		(end 399.639282 -179.248054)
		(width 0.13208)
		(layer "F.Cu")
		(net "HP_NIC6_HSC_PWRGD_N")
	)
	(segment
		(start 399.639282 -179.248054)
		(end 399.298668 -179.588668)
		(width 0.13208)
		(layer "F.Cu")
		(net "HP_NIC6_HSC_PWRGD_N")
	)
	(via
		(at 397.93037 -179.657756)
		(size 0.762)
		(drill 0.381)
		(layers "F.Cu" "B.Cu")
		(net "HP_NIC6_HSC_PWRGD_N")
	)
	(segment
		(start 89.327482 -343.685622)
		(end 89.647522 -343.365582)
		(width 0.13462)
		(layer "F.Cu")
		(net "P5E_PEX0_STN5_TX_DP<93>")
	)
	(segment
		(start 89.647522 -342.734138)
		(end 89.352882 -342.439498)
		(width 0.13462)
		(layer "F.Cu")
		(net "P5E_PEX0_STN5_TX_DP<93>")
	)
	(segment
		(start 89.647522 -343.365582)
		(end 89.647522 -342.734138)
		(width 0.13462)
		(layer "F.Cu")
		(net "P5E_PEX0_STN5_TX_DP<93>")
	)
	(segment
		(start 89.273126 -340.166706)
		(end 71.297038 -322.190618)
		(width 0.1651)
		(layer "In7.Cu")
		(net "P5E_PEX0_STN5_TX_DP<93>")
	)
	(segment
		(start 89.643712 -341.061294)
		(end 89.273126 -340.166706)
		(width 0.1651)
		(layer "In7.Cu")
		(net "P5E_PEX0_STN5_TX_DP<93>")
	)
	(segment
		(start 70.68312 -321.272154)
		(end 70.433946 -320.670428)
		(width 0.1651)
		(layer "In7.Cu")
		(net "P5E_PEX0_STN5_TX_DP<93>")
	)
	(segment
		(start 71.297038 -322.190618)
		(end 70.68312 -321.272154)
		(width 0.1651)
		(layer "In7.Cu")
		(net "P5E_PEX0_STN5_TX_DP<93>")
	)
	(segment
		(start 70.433946 -319.8876)
		(end 70.479666 -319.84188)
		(width 0.1143)
		(layer "In7.Cu")
		(net "P5E_PEX0_STN5_TX_DP<93>")
	)
	(segment
		(start 89.352882 -342.439498)
		(end 89.643712 -342.148668)
		(width 0.1651)
		(layer "In7.Cu")
		(net "P5E_PEX0_STN5_TX_DP<93>")
	)
	(segment
		(start 89.643712 -342.148668)
		(end 89.643712 -341.061294)
		(width 0.1651)
		(layer "In7.Cu")
		(net "P5E_PEX0_STN5_TX_DP<93>")
	)
	(segment
		(start 70.433946 -320.670428)
		(end 70.433946 -319.916048)
		(width 0.1651)
		(layer "In7.Cu")
		(net "P5E_PEX0_STN5_TX_DP<93>")
	)
	(segment
		(start 71.049896 -313.265312)
		(end 71.049896 -312.999882)
		(width 0.1143)
		(layer "In7.Cu")
		(net "P5E_PEX0_STN5_TX_DP<93>")
	)
	(segment
		(start 70.705472 -313.379612)
		(end 70.935596 -313.379612)
		(width 0.1143)
		(layer "In7.Cu")
		(net "P5E_PEX0_STN5_TX_DP<93>")
	)
	(segment
		(start 70.479666 -319.84188)
		(end 70.479666 -313.605418)
		(width 0.1143)
		(layer "In7.Cu")
		(net "P5E_PEX0_STN5_TX_DP<93>")
	)
	(segment
		(start 70.479666 -313.605418)
		(end 70.705472 -313.379612)
		(width 0.1143)
		(layer "In7.Cu")
		(net "P5E_PEX0_STN5_TX_DP<93>")
	)
	(segment
		(start 70.433946 -319.916048)
		(end 70.433946 -319.8876)
		(width 0.1143)
		(layer "In7.Cu")
		(net "P5E_PEX0_STN5_TX_DP<93>")
	)
	(segment
		(start 70.935596 -313.379612)
		(end 71.049896 -313.265312)
		(width 0.1143)
		(layer "In7.Cu")
		(net "P5E_PEX0_STN5_TX_DP<93>")
	)
	(segment
		(start 251.21997 -28.829)
		(end 250.56973 -28.829)
		(width 0.13462)
		(layer "F.Cu")
		(net "P5E_PEX2_STN2_TX_DP<44>")
	)
	(segment
		(start 251.505212 -29.114242)
		(end 251.21997 -28.829)
		(width 0.13462)
		(layer "F.Cu")
		(net "P5E_PEX2_STN2_TX_DP<44>")
	)
	(segment
		(start 250.56973 -28.829)
		(end 250.259088 -29.139642)
		(width 0.13462)
		(layer "F.Cu")
		(net "P5E_PEX2_STN2_TX_DP<44>")
	)
	(segment
		(start 251.804424 -28.823412)
		(end 252.796294 -28.823412)
		(width 0.1651)
		(layer "In11.Cu")
		(net "P5E_PEX2_STN2_TX_DP<44>")
	)
	(segment
		(start 252.885194 -28.912312)
		(end 253.380494 -28.912312)
		(width 0.1651)
		(layer "In11.Cu")
		(net "P5E_PEX2_STN2_TX_DP<44>")
	)
	(segment
		(start 278.883872 -271.399)
		(end 278.883872 -271.427448)
		(width 0.1143)
		(layer "In11.Cu")
		(net "P5E_PEX2_STN2_TX_DP<44>")
	)
	(segment
		(start 278.883872 -270.748252)
		(end 278.883872 -271.399)
		(width 0.1651)
		(layer "In11.Cu")
		(net "P5E_PEX2_STN2_TX_DP<44>")
	)
	(segment
		(start 256.300986 -30.121606)
		(end 256.609088 -30.510226)
		(width 0.1651)
		(layer "In11.Cu")
		(net "P5E_PEX2_STN2_TX_DP<44>")
	)
	(segment
		(start 271.662906 -135.957056)
		(end 270.734282 -145.379948)
		(width 0.1651)
		(layer "In11.Cu")
		(net "P5E_PEX2_STN2_TX_DP<44>")
	)
	(segment
		(start 270.607028 -50.411126)
		(end 271.305782 -62.140338)
		(width 0.1651)
		(layer "In11.Cu")
		(net "P5E_PEX2_STN2_TX_DP<44>")
	)
	(segment
		(start 251.798328 -28.821126)
		(end 251.804424 -28.823412)
		(width 0.1651)
		(layer "In11.Cu")
		(net "P5E_PEX2_STN2_TX_DP<44>")
	)
	(segment
		(start 271.305782 -62.140338)
		(end 271.662906 -135.957056)
		(width 0.1651)
		(layer "In11.Cu")
		(net "P5E_PEX2_STN2_TX_DP<44>")
	)
	(segment
		(start 279.499822 -280.434288)
		(end 279.499822 -280.699718)
		(width 0.1143)
		(layer "In11.Cu")
		(net "P5E_PEX2_STN2_TX_DP<44>")
	)
	(segment
		(start 270.734282 -145.379948)
		(end 277.994872 -264.61212)
		(width 0.1651)
		(layer "In11.Cu")
		(net "P5E_PEX2_STN2_TX_DP<44>")
	)
	(segment
		(start 251.505212 -29.114242)
		(end 251.798328 -28.821126)
		(width 0.1651)
		(layer "In11.Cu")
		(net "P5E_PEX2_STN2_TX_DP<44>")
	)
	(segment
		(start 253.469394 -28.823412)
		(end 254.273304 -28.823412)
		(width 0.1651)
		(layer "In11.Cu")
		(net "P5E_PEX2_STN2_TX_DP<44>")
	)
	(segment
		(start 278.929592 -271.473168)
		(end 278.929592 -280.10485)
		(width 0.1143)
		(layer "In11.Cu")
		(net "P5E_PEX2_STN2_TX_DP<44>")
	)
	(segment
		(start 254.273304 -28.823412)
		(end 255.926082 -29.505402)
		(width 0.1651)
		(layer "In11.Cu")
		(net "P5E_PEX2_STN2_TX_DP<44>")
	)
	(segment
		(start 267.891514 -44.601638)
		(end 269.879064 -48.256952)
		(width 0.1651)
		(layer "In11.Cu")
		(net "P5E_PEX2_STN2_TX_DP<44>")
	)
	(segment
		(start 279.14473 -280.319988)
		(end 279.385522 -280.319988)
		(width 0.1143)
		(layer "In11.Cu")
		(net "P5E_PEX2_STN2_TX_DP<44>")
	)
	(segment
		(start 278.883872 -271.427448)
		(end 278.929592 -271.473168)
		(width 0.1143)
		(layer "In11.Cu")
		(net "P5E_PEX2_STN2_TX_DP<44>")
	)
	(segment
		(start 253.380494 -28.912312)
		(end 253.469394 -28.823412)
		(width 0.1651)
		(layer "In11.Cu")
		(net "P5E_PEX2_STN2_TX_DP<44>")
	)
	(segment
		(start 278.929592 -280.10485)
		(end 279.14473 -280.319988)
		(width 0.1143)
		(layer "In11.Cu")
		(net "P5E_PEX2_STN2_TX_DP<44>")
	)
	(segment
		(start 269.879064 -48.256952)
		(end 270.607028 -50.411126)
		(width 0.1651)
		(layer "In11.Cu")
		(net "P5E_PEX2_STN2_TX_DP<44>")
	)
	(segment
		(start 277.994872 -264.61212)
		(end 278.883872 -270.748252)
		(width 0.1651)
		(layer "In11.Cu")
		(net "P5E_PEX2_STN2_TX_DP<44>")
	)
	(segment
		(start 255.926082 -29.505402)
		(end 256.315464 -29.996892)
		(width 0.1651)
		(layer "In11.Cu")
		(net "P5E_PEX2_STN2_TX_DP<44>")
	)
	(segment
		(start 256.733802 -30.52445)
		(end 267.891514 -44.601638)
		(width 0.1651)
		(layer "In11.Cu")
		(net "P5E_PEX2_STN2_TX_DP<44>")
	)
	(segment
		(start 252.796294 -28.823412)
		(end 252.885194 -28.912312)
		(width 0.1651)
		(layer "In11.Cu")
		(net "P5E_PEX2_STN2_TX_DP<44>")
	)
	(segment
		(start 256.609088 -30.510226)
		(end 256.733802 -30.52445)
		(width 0.1651)
		(layer "In11.Cu")
		(net "P5E_PEX2_STN2_TX_DP<44>")
	)
	(segment
		(start 279.385522 -280.319988)
		(end 279.499822 -280.434288)
		(width 0.1143)
		(layer "In11.Cu")
		(net "P5E_PEX2_STN2_TX_DP<44>")
	)
	(segment
		(start 256.315464 -29.996892)
		(end 256.300986 -30.121606)
		(width 0.1651)
		(layer "In11.Cu")
		(net "P5E_PEX2_STN2_TX_DP<44>")
	)
	(segment
		(start 375.18594 -343.685622)
		(end 374.865392 -343.365074)
		(width 0.13462)
		(layer "F.Cu")
		(net "P5E_PEX3_STN6_TX_DN<102>")
	)
	(segment
		(start 374.865392 -342.734646)
		(end 375.16054 -342.439498)
		(width 0.13462)
		(layer "F.Cu")
		(net "P5E_PEX3_STN6_TX_DN<102>")
	)
	(segment
		(start 374.865392 -343.365074)
		(end 374.865392 -342.734646)
		(width 0.13462)
		(layer "F.Cu")
		(net "P5E_PEX3_STN6_TX_DN<102>")
	)
	(segment
		(start 400.015964 -320.645536)
		(end 400.015964 -319.9892)
		(width 0.1651)
		(layer "In7.Cu")
		(net "P5E_PEX3_STN6_TX_DN<102>")
	)
	(segment
		(start 400.235674 -313.570112)
		(end 400.349974 -313.684412)
		(width 0.1143)
		(layer "In7.Cu")
		(net "P5E_PEX3_STN6_TX_DN<102>")
	)
	(segment
		(start 399.970244 -313.684412)
		(end 400.084544 -313.570112)
		(width 0.1143)
		(layer "In7.Cu")
		(net "P5E_PEX3_STN6_TX_DN<102>")
	)
	(segment
		(start 400.015964 -319.960752)
		(end 399.970244 -319.915032)
		(width 0.1143)
		(layer "In7.Cu")
		(net "P5E_PEX3_STN6_TX_DN<102>")
	)
	(segment
		(start 398.586198 -322.075302)
		(end 400.015964 -320.645536)
		(width 0.1651)
		(layer "In7.Cu")
		(net "P5E_PEX3_STN6_TX_DN<102>")
	)
	(segment
		(start 374.86971 -341.37854)
		(end 398.586198 -322.075302)
		(width 0.1651)
		(layer "In7.Cu")
		(net "P5E_PEX3_STN6_TX_DN<102>")
	)
	(segment
		(start 375.16054 -342.439498)
		(end 374.86971 -342.148668)
		(width 0.1651)
		(layer "In7.Cu")
		(net "P5E_PEX3_STN6_TX_DN<102>")
	)
	(segment
		(start 374.86971 -342.148668)
		(end 374.86971 -341.37854)
		(width 0.1651)
		(layer "In7.Cu")
		(net "P5E_PEX3_STN6_TX_DN<102>")
	)
	(segment
		(start 399.970244 -319.915032)
		(end 399.970244 -313.684412)
		(width 0.1143)
		(layer "In7.Cu")
		(net "P5E_PEX3_STN6_TX_DN<102>")
	)
	(segment
		(start 400.349974 -313.684412)
		(end 400.349974 -313.949842)
		(width 0.1143)
		(layer "In7.Cu")
		(net "P5E_PEX3_STN6_TX_DN<102>")
	)
	(segment
		(start 400.015964 -319.9892)
		(end 400.015964 -319.960752)
		(width 0.1143)
		(layer "In7.Cu")
		(net "P5E_PEX3_STN6_TX_DN<102>")
	)
	(segment
		(start 400.084544 -313.570112)
		(end 400.235674 -313.570112)
		(width 0.1143)
		(layer "In7.Cu")
		(net "P5E_PEX3_STN6_TX_DN<102>")
	)
	(segment
		(start 403.092412 -165.709346)
		(end 404.68169 -164.120068)
		(width 0.13208)
		(layer "F.Cu")
		(net "RST_HP_NIC6_BUF_N")
	)
	(segment
		(start 400.364452 -166.702994)
		(end 399.348452 -166.702994)
		(width 0.13208)
		(layer "F.Cu")
		(net "RST_HP_NIC6_BUF_N")
	)
	(segment
		(start 398.698466 -166.538656)
		(end 398.698466 -166.053008)
		(width 0.13208)
		(layer "F.Cu")
		(net "RST_HP_NIC6_BUF_N")
	)
	(segment
		(start 400.364452 -166.702994)
		(end 402.098764 -166.702994)
		(width 0.13208)
		(layer "F.Cu")
		(net "RST_HP_NIC6_BUF_N")
	)
	(segment
		(start 404.68169 -164.120068)
		(end 404.68169 -158.8516)
		(width 0.13208)
		(layer "F.Cu")
		(net "RST_HP_NIC6_BUF_N")
	)
	(segment
		(start 398.862804 -166.702994)
		(end 398.698466 -166.538656)
		(width 0.13208)
		(layer "F.Cu")
		(net "RST_HP_NIC6_BUF_N")
	)
	(segment
		(start 398.698466 -166.053008)
		(end 398.548352 -165.902894)
		(width 0.13208)
		(layer "F.Cu")
		(net "RST_HP_NIC6_BUF_N")
	)
	(segment
		(start 399.348452 -166.702994)
		(end 398.862804 -166.702994)
		(width 0.13208)
		(layer "F.Cu")
		(net "RST_HP_NIC6_BUF_N")
	)
	(segment
		(start 398.548352 -165.902894)
		(end 397.959326 -165.902894)
		(width 0.13208)
		(layer "F.Cu")
		(net "RST_HP_NIC6_BUF_N")
	)
	(segment
		(start 404.68169 -157.8356)
		(end 404.68169 -158.8516)
		(width 0.13208)
		(layer "F.Cu")
		(net "RST_HP_NIC6_BUF_N")
	)
	(segment
		(start 402.098764 -166.702994)
		(end 403.092412 -165.709346)
		(width 0.13208)
		(layer "F.Cu")
		(net "RST_HP_NIC6_BUF_N")
	)
	(via
		(at 403.092412 -165.709346)
		(size 0.762)
		(drill 0.381)
		(layers "F.Cu" "B.Cu")
		(net "RST_HP_NIC6_BUF_N")
	)
	(segment
		(start 73.947274 -30.92069)
		(end 73.653904 -30.62732)
		(width 0.13462)
		(layer "F.Cu")
		(net "P5E_PEX0_STN2_TX_DP<37>")
	)
	(segment
		(start 73.653904 -30.62732)
		(end 73.01992 -30.62732)
		(width 0.13462)
		(layer "F.Cu")
		(net "P5E_PEX0_STN2_TX_DP<37>")
	)
	(segment
		(start 73.01992 -30.62732)
		(end 72.70115 -30.94609)
		(width 0.13462)
		(layer "F.Cu")
		(net "P5E_PEX0_STN2_TX_DP<37>")
	)
	(segment
		(start 62.417452 -110.598458)
		(end 61.512958 -115.227608)
		(width 0.1651)
		(layer "In11.Cu")
		(net "P5E_PEX0_STN2_TX_DP<37>")
	)
	(segment
		(start 53.835554 -278.420068)
		(end 53.949854 -278.534368)
		(width 0.1143)
		(layer "In11.Cu")
		(net "P5E_PEX0_STN2_TX_DP<37>")
	)
	(segment
		(start 75.579986 -31.325058)
		(end 75.930506 -31.675578)
		(width 0.1651)
		(layer "In11.Cu")
		(net "P5E_PEX0_STN2_TX_DP<37>")
	)
	(segment
		(start 62.597792 -109.674152)
		(end 62.598046 -109.674152)
		(width 0.1651)
		(layer "In11.Cu")
		(net "P5E_PEX0_STN2_TX_DP<37>")
	)
	(segment
		(start 77.470254 -33.089596)
		(end 82.193638 -40.682418)
		(width 0.1651)
		(layer "In11.Cu")
		(net "P5E_PEX0_STN2_TX_DP<37>")
	)
	(segment
		(start 53.379624 -271.473168)
		(end 53.379624 -278.20493)
		(width 0.1143)
		(layer "In11.Cu")
		(net "P5E_PEX0_STN2_TX_DP<37>")
	)
	(segment
		(start 76.406248 -32.02559)
		(end 76.406248 -32.15132)
		(width 0.1651)
		(layer "In11.Cu")
		(net "P5E_PEX0_STN2_TX_DP<37>")
	)
	(segment
		(start 74.238104 -30.62986)
		(end 74.856086 -30.62986)
		(width 0.1651)
		(layer "In11.Cu")
		(net "P5E_PEX0_STN2_TX_DP<37>")
	)
	(segment
		(start 88.933782 -48.152812)
		(end 89.989406 -58.547)
		(width 0.1651)
		(layer "In11.Cu")
		(net "P5E_PEX0_STN2_TX_DP<37>")
	)
	(segment
		(start 53.949854 -278.534368)
		(end 53.949854 -278.799798)
		(width 0.1143)
		(layer "In11.Cu")
		(net "P5E_PEX0_STN2_TX_DP<37>")
	)
	(segment
		(start 53.333904 -271.427448)
		(end 53.379624 -271.473168)
		(width 0.1143)
		(layer "In11.Cu")
		(net "P5E_PEX0_STN2_TX_DP<37>")
	)
	(segment
		(start 76.056236 -31.675578)
		(end 76.406248 -32.02559)
		(width 0.1651)
		(layer "In11.Cu")
		(net "P5E_PEX0_STN2_TX_DP<37>")
	)
	(segment
		(start 53.333904 -271.399)
		(end 53.333904 -271.427448)
		(width 0.1143)
		(layer "In11.Cu")
		(net "P5E_PEX0_STN2_TX_DP<37>")
	)
	(segment
		(start 61.512958 -115.227608)
		(end 60.832746 -120.737122)
		(width 0.1651)
		(layer "In11.Cu")
		(net "P5E_PEX0_STN2_TX_DP<37>")
	)
	(segment
		(start 76.756768 -32.50184)
		(end 76.882498 -32.50184)
		(width 0.1651)
		(layer "In11.Cu")
		(net "P5E_PEX0_STN2_TX_DP<37>")
	)
	(segment
		(start 75.579986 -31.199328)
		(end 75.579986 -31.325058)
		(width 0.1651)
		(layer "In11.Cu")
		(net "P5E_PEX0_STN2_TX_DP<37>")
	)
	(segment
		(start 75.930506 -31.675578)
		(end 76.056236 -31.675578)
		(width 0.1651)
		(layer "In11.Cu")
		(net "P5E_PEX0_STN2_TX_DP<37>")
	)
	(segment
		(start 62.778386 -108.750354)
		(end 62.597792 -109.674152)
		(width 0.1651)
		(layer "In11.Cu")
		(net "P5E_PEX0_STN2_TX_DP<37>")
	)
	(segment
		(start 76.406248 -32.15132)
		(end 76.756768 -32.50184)
		(width 0.1651)
		(layer "In11.Cu")
		(net "P5E_PEX0_STN2_TX_DP<37>")
	)
	(segment
		(start 53.333904 -263.298686)
		(end 53.333904 -271.399)
		(width 0.1651)
		(layer "In11.Cu")
		(net "P5E_PEX0_STN2_TX_DP<37>")
	)
	(segment
		(start 53.594762 -278.420068)
		(end 53.835554 -278.420068)
		(width 0.1143)
		(layer "In11.Cu")
		(net "P5E_PEX0_STN2_TX_DP<37>")
	)
	(segment
		(start 82.193638 -40.682418)
		(end 88.933782 -48.152812)
		(width 0.1651)
		(layer "In11.Cu")
		(net "P5E_PEX0_STN2_TX_DP<37>")
	)
	(segment
		(start 60.832746 -120.737122)
		(end 53.333904 -263.298686)
		(width 0.1651)
		(layer "In11.Cu")
		(net "P5E_PEX0_STN2_TX_DP<37>")
	)
	(segment
		(start 53.379624 -278.20493)
		(end 53.594762 -278.420068)
		(width 0.1143)
		(layer "In11.Cu")
		(net "P5E_PEX0_STN2_TX_DP<37>")
	)
	(segment
		(start 75.119738 -30.73908)
		(end 75.579986 -31.199328)
		(width 0.1651)
		(layer "In11.Cu")
		(net "P5E_PEX0_STN2_TX_DP<37>")
	)
	(segment
		(start 62.77864 -108.750354)
		(end 62.778386 -108.750354)
		(width 0.1651)
		(layer "In11.Cu")
		(net "P5E_PEX0_STN2_TX_DP<37>")
	)
	(segment
		(start 89.989406 -60.42152)
		(end 89.407238 -62.600586)
		(width 0.1651)
		(layer "In11.Cu")
		(net "P5E_PEX0_STN2_TX_DP<37>")
	)
	(segment
		(start 66.271648 -93.486986)
		(end 62.96025 -107.821222)
		(width 0.1651)
		(layer "In11.Cu")
		(net "P5E_PEX0_STN2_TX_DP<37>")
	)
	(segment
		(start 73.947274 -30.92069)
		(end 74.238104 -30.62986)
		(width 0.1651)
		(layer "In11.Cu")
		(net "P5E_PEX0_STN2_TX_DP<37>")
	)
	(segment
		(start 62.96025 -107.821222)
		(end 62.77864 -108.750354)
		(width 0.1651)
		(layer "In11.Cu")
		(net "P5E_PEX0_STN2_TX_DP<37>")
	)
	(segment
		(start 76.882498 -32.50184)
		(end 77.470254 -33.089596)
		(width 0.1651)
		(layer "In11.Cu")
		(net "P5E_PEX0_STN2_TX_DP<37>")
	)
	(segment
		(start 74.856086 -30.62986)
		(end 75.119738 -30.73908)
		(width 0.1651)
		(layer "In11.Cu")
		(net "P5E_PEX0_STN2_TX_DP<37>")
	)
	(segment
		(start 88.476836 -64.465962)
		(end 66.271648 -93.486986)
		(width 0.1651)
		(layer "In11.Cu")
		(net "P5E_PEX0_STN2_TX_DP<37>")
	)
	(segment
		(start 89.989406 -58.547)
		(end 89.989406 -60.42152)
		(width 0.1651)
		(layer "In11.Cu")
		(net "P5E_PEX0_STN2_TX_DP<37>")
	)
	(segment
		(start 89.407238 -62.600586)
		(end 88.476836 -64.465962)
		(width 0.1651)
		(layer "In11.Cu")
		(net "P5E_PEX0_STN2_TX_DP<37>")
	)
	(segment
		(start 62.598046 -109.674152)
		(end 62.417452 -110.598458)
		(width 0.1651)
		(layer "In11.Cu")
		(net "P5E_PEX0_STN2_TX_DP<37>")
	)
	(segment
		(start 253.85395 -30.62732)
		(end 253.219966 -30.62732)
		(width 0.13462)
		(layer "F.Cu")
		(net "P5E_PEX2_STN2_TX_DP<45>")
	)
	(segment
		(start 254.14732 -30.92069)
		(end 253.85395 -30.62732)
		(width 0.13462)
		(layer "F.Cu")
		(net "P5E_PEX2_STN2_TX_DP<45>")
	)
	(segment
		(start 253.219966 -30.62732)
		(end 252.901196 -30.94609)
		(width 0.13462)
		(layer "F.Cu")
		(net "P5E_PEX2_STN2_TX_DP<45>")
	)
	(segment
		(start 254.14732 -30.92069)
		(end 254.440182 -30.627828)
		(width 0.1651)
		(layer "In11.Cu")
		(net "P5E_PEX2_STN2_TX_DP<45>")
	)
	(segment
		(start 256.49936 -31.842964)
		(end 256.83464 -32.264096)
		(width 0.1651)
		(layer "In11.Cu")
		(net "P5E_PEX2_STN2_TX_DP<45>")
	)
	(segment
		(start 256.82067 -32.389064)
		(end 257.129534 -32.776668)
		(width 0.1651)
		(layer "In11.Cu")
		(net "P5E_PEX2_STN2_TX_DP<45>")
	)
	(segment
		(start 257.548888 -33.302956)
		(end 257.857752 -33.69056)
		(width 0.1651)
		(layer "In11.Cu")
		(net "P5E_PEX2_STN2_TX_DP<45>")
	)
	(segment
		(start 255.318768 -30.831536)
		(end 256.49936 -31.842964)
		(width 0.1651)
		(layer "In11.Cu")
		(net "P5E_PEX2_STN2_TX_DP<45>")
	)
	(segment
		(start 254.440182 -30.627828)
		(end 254.445516 -30.62986)
		(width 0.1651)
		(layer "In11.Cu")
		(net "P5E_PEX2_STN2_TX_DP<45>")
	)
	(segment
		(start 257.982466 -33.704784)
		(end 267.040614 -45.07484)
		(width 0.1651)
		(layer "In11.Cu")
		(net "P5E_PEX2_STN2_TX_DP<45>")
	)
	(segment
		(start 265.33856 -116.205762)
		(end 265.740896 -137.987278)
		(width 0.1651)
		(layer "In11.Cu")
		(net "P5E_PEX2_STN2_TX_DP<45>")
	)
	(segment
		(start 257.254502 -32.790638)
		(end 257.563112 -33.177988)
		(width 0.1651)
		(layer "In11.Cu")
		(net "P5E_PEX2_STN2_TX_DP<45>")
	)
	(segment
		(start 257.98272 -33.70453)
		(end 257.982466 -33.704784)
		(width 0.1651)
		(layer "In11.Cu")
		(net "P5E_PEX2_STN2_TX_DP<45>")
	)
	(segment
		(start 268.965934 -48.578008)
		(end 269.583662 -50.3682)
		(width 0.1651)
		(layer "In11.Cu")
		(net "P5E_PEX2_STN2_TX_DP<45>")
	)
	(segment
		(start 270.346932 -63.150242)
		(end 269.473426 -78.885796)
		(width 0.1651)
		(layer "In11.Cu")
		(net "P5E_PEX2_STN2_TX_DP<45>")
	)
	(segment
		(start 254.445516 -30.62986)
		(end 254.831596 -30.62986)
		(width 0.1651)
		(layer "In11.Cu")
		(net "P5E_PEX2_STN2_TX_DP<45>")
	)
	(segment
		(start 257.857752 -33.69056)
		(end 257.98272 -33.70453)
		(width 0.1651)
		(layer "In11.Cu")
		(net "P5E_PEX2_STN2_TX_DP<45>")
	)
	(segment
		(start 277.933912 -270.38427)
		(end 277.933912 -271.399)
		(width 0.1651)
		(layer "In11.Cu")
		(net "P5E_PEX2_STN2_TX_DP<45>")
	)
	(segment
		(start 265.840464 -105.23093)
		(end 265.84148 -105.23093)
		(width 0.1651)
		(layer "In11.Cu")
		(net "P5E_PEX2_STN2_TX_DP<45>")
	)
	(segment
		(start 277.933912 -271.399)
		(end 277.933912 -271.427448)
		(width 0.1143)
		(layer "In11.Cu")
		(net "P5E_PEX2_STN2_TX_DP<45>")
	)
	(segment
		(start 267.040614 -45.07484)
		(end 268.965934 -48.578008)
		(width 0.1651)
		(layer "In11.Cu")
		(net "P5E_PEX2_STN2_TX_DP<45>")
	)
	(segment
		(start 269.583662 -50.3682)
		(end 270.346932 -63.150242)
		(width 0.1651)
		(layer "In11.Cu")
		(net "P5E_PEX2_STN2_TX_DP<45>")
	)
	(segment
		(start 277.933912 -271.427448)
		(end 277.979632 -271.473168)
		(width 0.1143)
		(layer "In11.Cu")
		(net "P5E_PEX2_STN2_TX_DP<45>")
	)
	(segment
		(start 278.435562 -278.420068)
		(end 278.549862 -278.534368)
		(width 0.1143)
		(layer "In11.Cu")
		(net "P5E_PEX2_STN2_TX_DP<45>")
	)
	(segment
		(start 277.979632 -278.20493)
		(end 278.19477 -278.420068)
		(width 0.1143)
		(layer "In11.Cu")
		(net "P5E_PEX2_STN2_TX_DP<45>")
	)
	(segment
		(start 254.831596 -30.62986)
		(end 255.318768 -30.831536)
		(width 0.1651)
		(layer "In11.Cu")
		(net "P5E_PEX2_STN2_TX_DP<45>")
	)
	(segment
		(start 265.84148 -105.23093)
		(end 265.33856 -116.205762)
		(width 0.1651)
		(layer "In11.Cu")
		(net "P5E_PEX2_STN2_TX_DP<45>")
	)
	(segment
		(start 276.907244 -264.195306)
		(end 277.933912 -270.38427)
		(width 0.1651)
		(layer "In11.Cu")
		(net "P5E_PEX2_STN2_TX_DP<45>")
	)
	(segment
		(start 278.549862 -278.534368)
		(end 278.549862 -278.799798)
		(width 0.1143)
		(layer "In11.Cu")
		(net "P5E_PEX2_STN2_TX_DP<45>")
	)
	(segment
		(start 256.83464 -32.264096)
		(end 256.82067 -32.389064)
		(width 0.1651)
		(layer "In11.Cu")
		(net "P5E_PEX2_STN2_TX_DP<45>")
	)
	(segment
		(start 277.979632 -271.473168)
		(end 277.979632 -278.20493)
		(width 0.1143)
		(layer "In11.Cu")
		(net "P5E_PEX2_STN2_TX_DP<45>")
	)
	(segment
		(start 269.473426 -78.885796)
		(end 265.841226 -105.217976)
		(width 0.1651)
		(layer "In11.Cu")
		(net "P5E_PEX2_STN2_TX_DP<45>")
	)
	(segment
		(start 265.740896 -137.987278)
		(end 276.907244 -264.195306)
		(width 0.1651)
		(layer "In11.Cu")
		(net "P5E_PEX2_STN2_TX_DP<45>")
	)
	(segment
		(start 257.129534 -32.776668)
		(end 257.254502 -32.790638)
		(width 0.1651)
		(layer "In11.Cu")
		(net "P5E_PEX2_STN2_TX_DP<45>")
	)
	(segment
		(start 265.841226 -105.217976)
		(end 265.840464 -105.23093)
		(width 0.1651)
		(layer "In11.Cu")
		(net "P5E_PEX2_STN2_TX_DP<45>")
	)
	(segment
		(start 257.563112 -33.177988)
		(end 257.548888 -33.302956)
		(width 0.1651)
		(layer "In11.Cu")
		(net "P5E_PEX2_STN2_TX_DP<45>")
	)
	(segment
		(start 278.19477 -278.420068)
		(end 278.435562 -278.420068)
		(width 0.1143)
		(layer "In11.Cu")
		(net "P5E_PEX2_STN2_TX_DP<45>")
	)
	(segment
		(start 431.351944 -349.512382)
		(end 431.351944 -348.879922)
		(width 0.13462)
		(layer "F.Cu")
		(net "P5E_PEX3_STN7_TX_DN<122>")
	)
	(segment
		(start 431.351944 -348.879922)
		(end 431.057812 -348.58579)
		(width 0.13462)
		(layer "F.Cu")
		(net "P5E_PEX3_STN7_TX_DN<122>")
	)
	(segment
		(start 431.032412 -349.831914)
		(end 431.351944 -349.512382)
		(width 0.13462)
		(layer "F.Cu")
		(net "P5E_PEX3_STN7_TX_DN<122>")
	)
	(segment
		(start 385.529582 -315.014102)
		(end 385.415282 -314.899802)
		(width 0.1143)
		(layer "In11.Cu")
		(net "P5E_PEX3_STN7_TX_DN<122>")
	)
	(segment
		(start 385.483862 -319.006982)
		(end 385.529582 -318.961262)
		(width 0.1143)
		(layer "In11.Cu")
		(net "P5E_PEX3_STN7_TX_DN<122>")
	)
	(segment
		(start 423.323258 -334.625696)
		(end 387.681216 -325.214996)
		(width 0.1651)
		(layer "In11.Cu")
		(net "P5E_PEX3_STN7_TX_DN<122>")
	)
	(segment
		(start 385.529582 -318.961262)
		(end 385.529582 -315.014102)
		(width 0.1143)
		(layer "In11.Cu")
		(net "P5E_PEX3_STN7_TX_DN<122>")
	)
	(segment
		(start 387.681216 -325.214996)
		(end 385.75361 -323.28739)
		(width 0.1651)
		(layer "In11.Cu")
		(net "P5E_PEX3_STN7_TX_DN<122>")
	)
	(segment
		(start 432.903122 -342.269572)
		(end 431.819812 -340.533228)
		(width 0.1651)
		(layer "In11.Cu")
		(net "P5E_PEX3_STN7_TX_DN<122>")
	)
	(segment
		(start 431.348642 -348.29496)
		(end 431.348642 -347.667834)
		(width 0.1651)
		(layer "In11.Cu")
		(net "P5E_PEX3_STN7_TX_DN<122>")
	)
	(segment
		(start 385.75361 -323.28739)
		(end 385.483862 -322.636134)
		(width 0.1651)
		(layer "In11.Cu")
		(net "P5E_PEX3_STN7_TX_DN<122>")
	)
	(segment
		(start 385.415282 -314.899802)
		(end 385.149852 -314.899802)
		(width 0.1143)
		(layer "In11.Cu")
		(net "P5E_PEX3_STN7_TX_DN<122>")
	)
	(segment
		(start 431.348642 -347.667834)
		(end 432.903122 -346.113354)
		(width 0.1651)
		(layer "In11.Cu")
		(net "P5E_PEX3_STN7_TX_DN<122>")
	)
	(segment
		(start 431.057812 -348.58579)
		(end 431.348642 -348.29496)
		(width 0.1651)
		(layer "In11.Cu")
		(net "P5E_PEX3_STN7_TX_DN<122>")
	)
	(segment
		(start 385.483862 -319.03543)
		(end 385.483862 -319.006982)
		(width 0.1143)
		(layer "In11.Cu")
		(net "P5E_PEX3_STN7_TX_DN<122>")
	)
	(segment
		(start 431.819812 -340.533228)
		(end 423.323258 -334.625696)
		(width 0.1651)
		(layer "In11.Cu")
		(net "P5E_PEX3_STN7_TX_DN<122>")
	)
	(segment
		(start 385.483862 -322.636134)
		(end 385.483862 -319.03543)
		(width 0.1651)
		(layer "In11.Cu")
		(net "P5E_PEX3_STN7_TX_DN<122>")
	)
	(segment
		(start 432.903122 -346.113354)
		(end 432.903122 -342.269572)
		(width 0.1651)
		(layer "In11.Cu")
		(net "P5E_PEX3_STN7_TX_DN<122>")
	)
	(segment
		(start 36.803076 -324.128384)
		(end 36.72586 -324.02907)
		(width 0.1651)
		(layer "In5.Cu")
		(net "P5E_PEX0_STN7_RX_DN<122>")
	)
	(segment
		(start 32.31007 -382.18999)
		(end 32.31007 -382.57226)
		(width 0.1651)
		(layer "In5.Cu")
		(net "P5E_PEX0_STN7_RX_DN<122>")
	)
	(segment
		(start 36.16706 -333.17815)
		(end 36.05276 -333.06385)
		(width 0.1651)
		(layer "In5.Cu")
		(net "P5E_PEX0_STN7_RX_DN<122>")
	)
	(segment
		(start 36.16706 -333.67345)
		(end 36.16706 -333.17815)
		(width 0.1651)
		(layer "In5.Cu")
		(net "P5E_PEX0_STN7_RX_DN<122>")
	)
	(segment
		(start 36.16706 -336.021934)
		(end 36.16706 -334.39735)
		(width 0.1651)
		(layer "In5.Cu")
		(net "P5E_PEX0_STN7_RX_DN<122>")
	)
	(segment
		(start 36.05276 -333.78775)
		(end 36.16706 -333.67345)
		(width 0.1651)
		(layer "In5.Cu")
		(net "P5E_PEX0_STN7_RX_DN<122>")
	)
	(segment
		(start 36.05276 -332.56855)
		(end 36.16706 -332.45425)
		(width 0.1651)
		(layer "In5.Cu")
		(net "P5E_PEX0_STN7_RX_DN<122>")
	)
	(segment
		(start 36.722558 -341.661496)
		(end 36.16706 -336.021934)
		(width 0.1651)
		(layer "In5.Cu")
		(net "P5E_PEX0_STN7_RX_DN<122>")
	)
	(segment
		(start 36.05276 -331.34935)
		(end 36.16706 -331.23505)
		(width 0.1651)
		(layer "In5.Cu")
		(net "P5E_PEX0_STN7_RX_DN<122>")
	)
	(segment
		(start 37.229542 -319.05448)
		(end 37.229542 -316.914022)
		(width 0.1143)
		(layer "In5.Cu")
		(net "P5E_PEX0_STN7_RX_DN<122>")
	)
	(segment
		(start 36.932108 -322.37807)
		(end 37.031422 -322.300854)
		(width 0.1651)
		(layer "In5.Cu")
		(net "P5E_PEX0_STN7_RX_DN<122>")
	)
	(segment
		(start 36.05276 -331.84465)
		(end 36.05276 -331.34935)
		(width 0.1651)
		(layer "In5.Cu")
		(net "P5E_PEX0_STN7_RX_DN<122>")
	)
	(segment
		(start 36.722558 -357.789226)
		(end 36.722558 -341.661496)
		(width 0.1651)
		(layer "In5.Cu")
		(net "P5E_PEX0_STN7_RX_DN<122>")
	)
	(segment
		(start 36.655248 -325.31304)
		(end 36.566856 -325.199756)
		(width 0.1651)
		(layer "In5.Cu")
		(net "P5E_PEX0_STN7_RX_DN<122>")
	)
	(segment
		(start 36.72586 -324.02907)
		(end 36.787074 -323.537326)
		(width 0.1651)
		(layer "In5.Cu")
		(net "P5E_PEX0_STN7_RX_DN<122>")
	)
	(segment
		(start 37.183822 -321.079622)
		(end 37.183822 -319.128648)
		(width 0.1651)
		(layer "In5.Cu")
		(net "P5E_PEX0_STN7_RX_DN<122>")
	)
	(segment
		(start 36.471098 -359.48493)
		(end 36.722558 -357.789226)
		(width 0.1651)
		(layer "In5.Cu")
		(net "P5E_PEX0_STN7_RX_DN<122>")
	)
	(segment
		(start 36.05276 -334.28305)
		(end 36.05276 -333.78775)
		(width 0.1651)
		(layer "In5.Cu")
		(net "P5E_PEX0_STN7_RX_DN<122>")
	)
	(segment
		(start 36.947856 -322.968874)
		(end 36.87064 -322.869814)
		(width 0.1651)
		(layer "In5.Cu")
		(net "P5E_PEX0_STN7_RX_DN<122>")
	)
	(segment
		(start 32.807402 -382.69926)
		(end 33.176972 -382.32969)
		(width 0.1651)
		(layer "In5.Cu")
		(net "P5E_PEX0_STN7_RX_DN<122>")
	)
	(segment
		(start 36.16706 -334.39735)
		(end 36.05276 -334.28305)
		(width 0.1651)
		(layer "In5.Cu")
		(net "P5E_PEX0_STN7_RX_DN<122>")
	)
	(segment
		(start 36.566856 -325.199756)
		(end 36.628324 -324.708012)
		(width 0.1651)
		(layer "In5.Cu")
		(net "P5E_PEX0_STN7_RX_DN<122>")
	)
	(segment
		(start 36.16706 -331.23505)
		(end 36.16706 -329.22718)
		(width 0.1651)
		(layer "In5.Cu")
		(net "P5E_PEX0_STN7_RX_DN<122>")
	)
	(segment
		(start 36.87064 -322.869814)
		(end 36.932108 -322.37807)
		(width 0.1651)
		(layer "In5.Cu")
		(net "P5E_PEX0_STN7_RX_DN<122>")
	)
	(segment
		(start 37.115242 -316.799722)
		(end 36.849812 -316.799722)
		(width 0.1143)
		(layer "In5.Cu")
		(net "P5E_PEX0_STN7_RX_DN<122>")
	)
	(segment
		(start 37.229542 -316.914022)
		(end 37.115242 -316.799722)
		(width 0.1143)
		(layer "In5.Cu")
		(net "P5E_PEX0_STN7_RX_DN<122>")
	)
	(segment
		(start 36.741862 -324.619874)
		(end 36.803076 -324.128384)
		(width 0.1651)
		(layer "In5.Cu")
		(net "P5E_PEX0_STN7_RX_DN<122>")
	)
	(segment
		(start 36.05276 -333.06385)
		(end 36.05276 -332.56855)
		(width 0.1651)
		(layer "In5.Cu")
		(net "P5E_PEX0_STN7_RX_DN<122>")
	)
	(segment
		(start 33.176972 -382.32969)
		(end 33.176972 -370.343684)
		(width 0.1651)
		(layer "In5.Cu")
		(net "P5E_PEX0_STN7_RX_DN<122>")
	)
	(segment
		(start 37.031422 -322.300854)
		(end 37.183822 -321.079622)
		(width 0.1651)
		(layer "In5.Cu")
		(net "P5E_PEX0_STN7_RX_DN<122>")
	)
	(segment
		(start 37.183822 -319.128648)
		(end 37.183822 -319.1002)
		(width 0.1143)
		(layer "In5.Cu")
		(net "P5E_PEX0_STN7_RX_DN<122>")
	)
	(segment
		(start 36.16706 -331.95895)
		(end 36.05276 -331.84465)
		(width 0.1651)
		(layer "In5.Cu")
		(net "P5E_PEX0_STN7_RX_DN<122>")
	)
	(segment
		(start 36.628324 -324.708012)
		(end 36.741862 -324.619874)
		(width 0.1651)
		(layer "In5.Cu")
		(net "P5E_PEX0_STN7_RX_DN<122>")
	)
	(segment
		(start 36.787074 -323.537326)
		(end 36.886642 -323.46011)
		(width 0.1651)
		(layer "In5.Cu")
		(net "P5E_PEX0_STN7_RX_DN<122>")
	)
	(segment
		(start 32.43707 -382.69926)
		(end 32.807402 -382.69926)
		(width 0.1651)
		(layer "In5.Cu")
		(net "P5E_PEX0_STN7_RX_DN<122>")
	)
	(segment
		(start 33.176972 -370.343684)
		(end 36.471098 -359.48493)
		(width 0.1651)
		(layer "In5.Cu")
		(net "P5E_PEX0_STN7_RX_DN<122>")
	)
	(segment
		(start 32.31007 -382.57226)
		(end 32.43707 -382.69926)
		(width 0.1651)
		(layer "In5.Cu")
		(net "P5E_PEX0_STN7_RX_DN<122>")
	)
	(segment
		(start 36.16706 -332.45425)
		(end 36.16706 -331.95895)
		(width 0.1651)
		(layer "In5.Cu")
		(net "P5E_PEX0_STN7_RX_DN<122>")
	)
	(segment
		(start 37.183822 -319.1002)
		(end 37.229542 -319.05448)
		(width 0.1143)
		(layer "In5.Cu")
		(net "P5E_PEX0_STN7_RX_DN<122>")
	)
	(segment
		(start 36.16706 -329.22718)
		(end 36.655248 -325.31304)
		(width 0.1651)
		(layer "In5.Cu")
		(net "P5E_PEX0_STN7_RX_DN<122>")
	)
	(segment
		(start 36.886642 -323.46011)
		(end 36.947856 -322.968874)
		(width 0.1651)
		(layer "In5.Cu")
		(net "P5E_PEX0_STN7_RX_DN<122>")
	)
	(segment
		(start 70.993762 -355.658166)
		(end 70.993762 -355.026722)
		(width 0.13462)
		(layer "F.Cu")
		(net "P5E_PEX0_STN5_TX_DP<85>")
	)
	(segment
		(start 70.993762 -355.026722)
		(end 70.699122 -354.732082)
		(width 0.13462)
		(layer "F.Cu")
		(net "P5E_PEX0_STN5_TX_DP<85>")
	)
	(segment
		(start 70.673722 -355.978206)
		(end 70.993762 -355.658166)
		(width 0.13462)
		(layer "F.Cu")
		(net "P5E_PEX0_STN5_TX_DP<85>")
	)
	(segment
		(start 70.989952 -353.825302)
		(end 72.544432 -352.270822)
		(width 0.1651)
		(layer "In7.Cu")
		(net "P5E_PEX0_STN5_TX_DP<85>")
	)
	(segment
		(start 65.847976 -329.224132)
		(end 63.238126 -324.340982)
		(width 0.1651)
		(layer "In7.Cu")
		(net "P5E_PEX0_STN5_TX_DP<85>")
	)
	(segment
		(start 72.544432 -352.270822)
		(end 72.544432 -340.483698)
		(width 0.1651)
		(layer "In7.Cu")
		(net "P5E_PEX0_STN5_TX_DP<85>")
	)
	(segment
		(start 71.19493 -337.225894)
		(end 65.847976 -329.224132)
		(width 0.1651)
		(layer "In7.Cu")
		(net "P5E_PEX0_STN5_TX_DP<85>")
	)
	(segment
		(start 63.449962 -313.265312)
		(end 63.449962 -312.999882)
		(width 0.1143)
		(layer "In7.Cu")
		(net "P5E_PEX0_STN5_TX_DP<85>")
	)
	(segment
		(start 62.879732 -313.605418)
		(end 63.105538 -313.379612)
		(width 0.1143)
		(layer "In7.Cu")
		(net "P5E_PEX0_STN5_TX_DP<85>")
	)
	(segment
		(start 63.335662 -313.379612)
		(end 63.449962 -313.265312)
		(width 0.1143)
		(layer "In7.Cu")
		(net "P5E_PEX0_STN5_TX_DP<85>")
	)
	(segment
		(start 72.544432 -340.483698)
		(end 71.19493 -337.225894)
		(width 0.1651)
		(layer "In7.Cu")
		(net "P5E_PEX0_STN5_TX_DP<85>")
	)
	(segment
		(start 62.834012 -323.365114)
		(end 62.834012 -319.916048)
		(width 0.1651)
		(layer "In7.Cu")
		(net "P5E_PEX0_STN5_TX_DP<85>")
	)
	(segment
		(start 62.834012 -319.8876)
		(end 62.879732 -319.84188)
		(width 0.1143)
		(layer "In7.Cu")
		(net "P5E_PEX0_STN5_TX_DP<85>")
	)
	(segment
		(start 70.699122 -354.732082)
		(end 70.989952 -354.441252)
		(width 0.1651)
		(layer "In7.Cu")
		(net "P5E_PEX0_STN5_TX_DP<85>")
	)
	(segment
		(start 62.879732 -319.84188)
		(end 62.879732 -313.605418)
		(width 0.1143)
		(layer "In7.Cu")
		(net "P5E_PEX0_STN5_TX_DP<85>")
	)
	(segment
		(start 63.238126 -324.340982)
		(end 62.834012 -323.365114)
		(width 0.1651)
		(layer "In7.Cu")
		(net "P5E_PEX0_STN5_TX_DP<85>")
	)
	(segment
		(start 63.105538 -313.379612)
		(end 63.335662 -313.379612)
		(width 0.1143)
		(layer "In7.Cu")
		(net "P5E_PEX0_STN5_TX_DP<85>")
	)
	(segment
		(start 70.989952 -354.441252)
		(end 70.989952 -353.825302)
		(width 0.1651)
		(layer "In7.Cu")
		(net "P5E_PEX0_STN5_TX_DP<85>")
	)
	(segment
		(start 62.834012 -319.916048)
		(end 62.834012 -319.8876)
		(width 0.1143)
		(layer "In7.Cu")
		(net "P5E_PEX0_STN5_TX_DP<85>")
	)
	(segment
		(start 334.560164 -342.734138)
		(end 334.265524 -342.439498)
		(width 0.13462)
		(layer "F.Cu")
		(net "P5E_PEX2_STN5_TX_DP<90>")
	)
	(segment
		(start 334.560164 -343.365582)
		(end 334.560164 -342.734138)
		(width 0.13462)
		(layer "F.Cu")
		(net "P5E_PEX2_STN5_TX_DP<90>")
	)
	(segment
		(start 334.240124 -343.685622)
		(end 334.560164 -343.365582)
		(width 0.13462)
		(layer "F.Cu")
		(net "P5E_PEX2_STN5_TX_DP<90>")
	)
	(segment
		(start 332.66761 -339.592412)
		(end 325.092314 -334.564736)
		(width 0.1651)
		(layer "In7.Cu")
		(net "P5E_PEX2_STN5_TX_DP<90>")
	)
	(segment
		(start 334.265524 -342.439498)
		(end 334.556354 -342.148668)
		(width 0.1651)
		(layer "In7.Cu")
		(net "P5E_PEX2_STN5_TX_DP<90>")
	)
	(segment
		(start 299.783754 -319.941448)
		(end 299.783754 -319.913)
		(width 0.1143)
		(layer "In7.Cu")
		(net "P5E_PEX2_STN5_TX_DP<90>")
	)
	(segment
		(start 334.556354 -341.686388)
		(end 334.330294 -341.109046)
		(width 0.1651)
		(layer "In7.Cu")
		(net "P5E_PEX2_STN5_TX_DP<90>")
	)
	(segment
		(start 300.05528 -311.479692)
		(end 300.285404 -311.479692)
		(width 0.1143)
		(layer "In7.Cu")
		(net "P5E_PEX2_STN5_TX_DP<90>")
	)
	(segment
		(start 299.829474 -319.86728)
		(end 299.829474 -311.705498)
		(width 0.1143)
		(layer "In7.Cu")
		(net "P5E_PEX2_STN5_TX_DP<90>")
	)
	(segment
		(start 299.783754 -320.752216)
		(end 299.783754 -319.941448)
		(width 0.1651)
		(layer "In7.Cu")
		(net "P5E_PEX2_STN5_TX_DP<90>")
	)
	(segment
		(start 325.092314 -334.564736)
		(end 303.152048 -325.605648)
		(width 0.1651)
		(layer "In7.Cu")
		(net "P5E_PEX2_STN5_TX_DP<90>")
	)
	(segment
		(start 300.399704 -311.365392)
		(end 300.399704 -311.099962)
		(width 0.1143)
		(layer "In7.Cu")
		(net "P5E_PEX2_STN5_TX_DP<90>")
	)
	(segment
		(start 334.330294 -341.109046)
		(end 334.33004 -341.108284)
		(width 0.1651)
		(layer "In7.Cu")
		(net "P5E_PEX2_STN5_TX_DP<90>")
	)
	(segment
		(start 299.783754 -319.913)
		(end 299.829474 -319.86728)
		(width 0.1143)
		(layer "In7.Cu")
		(net "P5E_PEX2_STN5_TX_DP<90>")
	)
	(segment
		(start 300.834044 -323.287644)
		(end 299.783754 -320.752216)
		(width 0.1651)
		(layer "In7.Cu")
		(net "P5E_PEX2_STN5_TX_DP<90>")
	)
	(segment
		(start 299.829474 -311.705498)
		(end 300.05528 -311.479692)
		(width 0.1143)
		(layer "In7.Cu")
		(net "P5E_PEX2_STN5_TX_DP<90>")
	)
	(segment
		(start 334.556354 -342.148668)
		(end 334.556354 -341.686388)
		(width 0.1651)
		(layer "In7.Cu")
		(net "P5E_PEX2_STN5_TX_DP<90>")
	)
	(segment
		(start 334.33004 -341.108284)
		(end 332.66761 -339.592412)
		(width 0.1651)
		(layer "In7.Cu")
		(net "P5E_PEX2_STN5_TX_DP<90>")
	)
	(segment
		(start 303.152048 -325.605648)
		(end 300.834044 -323.287644)
		(width 0.1651)
		(layer "In7.Cu")
		(net "P5E_PEX2_STN5_TX_DP<90>")
	)
	(segment
		(start 300.285404 -311.479692)
		(end 300.399704 -311.365392)
		(width 0.1143)
		(layer "In7.Cu")
		(net "P5E_PEX2_STN5_TX_DP<90>")
	)
	(segment
		(start 422.299384 -343.365074)
		(end 422.299384 -342.734646)
		(width 0.13462)
		(layer "F.Cu")
		(net "P5E_PEX3_STN7_TX_DN<117>")
	)
	(segment
		(start 422.619932 -343.685622)
		(end 422.299384 -343.365074)
		(width 0.13462)
		(layer "F.Cu")
		(net "P5E_PEX3_STN7_TX_DN<117>")
	)
	(segment
		(start 422.299384 -342.734646)
		(end 422.594532 -342.439498)
		(width 0.13462)
		(layer "F.Cu")
		(net "P5E_PEX3_STN7_TX_DN<117>")
	)
	(segment
		(start 382.192276 -306.015898)
		(end 383.921 -306.015898)
		(width 0.1651)
		(layer "In11.Cu")
		(net "P5E_PEX3_STN7_TX_DN<117>")
	)
	(segment
		(start 372.748556 -326.949816)
		(end 371.124988 -325.326248)
		(width 0.1651)
		(layer "In11.Cu")
		(net "P5E_PEX3_STN7_TX_DN<117>")
	)
	(segment
		(start 392.179556 -306.235608)
		(end 392.065256 -306.349908)
		(width 0.1143)
		(layer "In11.Cu")
		(net "P5E_PEX3_STN7_TX_DN<117>")
	)
	(segment
		(start 376.52833 -310.507634)
		(end 376.87885 -310.157114)
		(width 0.1651)
		(layer "In11.Cu")
		(net "P5E_PEX3_STN7_TX_DN<117>")
	)
	(segment
		(start 392.065256 -306.349908)
		(end 391.799826 -306.349908)
		(width 0.1143)
		(layer "In11.Cu")
		(net "P5E_PEX3_STN7_TX_DN<117>")
	)
	(segment
		(start 377.723146 -309.312818)
		(end 377.723146 -309.169054)
		(width 0.1651)
		(layer "In11.Cu")
		(net "P5E_PEX3_STN7_TX_DN<117>")
	)
	(segment
		(start 379.945646 -306.946554)
		(end 380.988824 -306.5145)
		(width 0.1651)
		(layer "In11.Cu")
		(net "P5E_PEX3_STN7_TX_DN<117>")
	)
	(segment
		(start 422.303702 -341.633048)
		(end 421.6908 -340.2076)
		(width 0.1651)
		(layer "In11.Cu")
		(net "P5E_PEX3_STN7_TX_DN<117>")
	)
	(segment
		(start 379.494542 -307.541422)
		(end 379.494542 -307.397658)
		(width 0.1651)
		(layer "In11.Cu")
		(net "P5E_PEX3_STN7_TX_DN<117>")
	)
	(segment
		(start 371.124988 -325.326248)
		(end 369.7986 -322.12407)
		(width 0.1651)
		(layer "In11.Cu")
		(net "P5E_PEX3_STN7_TX_DN<117>")
	)
	(segment
		(start 381.579374 -306.379626)
		(end 381.634492 -306.247038)
		(width 0.1651)
		(layer "In11.Cu")
		(net "P5E_PEX3_STN7_TX_DN<117>")
	)
	(segment
		(start 377.723146 -309.169054)
		(end 378.073158 -308.819042)
		(width 0.1651)
		(layer "In11.Cu")
		(net "P5E_PEX3_STN7_TX_DN<117>")
	)
	(segment
		(start 376.384566 -310.507634)
		(end 376.52833 -310.507634)
		(width 0.1651)
		(layer "In11.Cu")
		(net "P5E_PEX3_STN7_TX_DN<117>")
	)
	(segment
		(start 376.87885 -310.01335)
		(end 377.228862 -309.663338)
		(width 0.1651)
		(layer "In11.Cu")
		(net "P5E_PEX3_STN7_TX_DN<117>")
	)
	(segment
		(start 374.695974 -312.196226)
		(end 374.839738 -312.196226)
		(width 0.1651)
		(layer "In11.Cu")
		(net "P5E_PEX3_STN7_TX_DN<117>")
	)
	(segment
		(start 379.494542 -307.397658)
		(end 379.945646 -306.946554)
		(width 0.1651)
		(layer "In11.Cu")
		(net "P5E_PEX3_STN7_TX_DN<117>")
	)
	(segment
		(start 369.7986 -322.12407)
		(end 369.7986 -319.279016)
		(width 0.1651)
		(layer "In11.Cu")
		(net "P5E_PEX3_STN7_TX_DN<117>")
	)
	(segment
		(start 376.034554 -310.857646)
		(end 376.384566 -310.507634)
		(width 0.1651)
		(layer "In11.Cu")
		(net "P5E_PEX3_STN7_TX_DN<117>")
	)
	(segment
		(start 369.7986 -319.279016)
		(end 370.167662 -318.38773)
		(width 0.1651)
		(layer "In11.Cu")
		(net "P5E_PEX3_STN7_TX_DN<117>")
	)
	(segment
		(start 383.995168 -305.970178)
		(end 392.075924 -305.970178)
		(width 0.1143)
		(layer "In11.Cu")
		(net "P5E_PEX3_STN7_TX_DN<117>")
	)
	(segment
		(start 375.190258 -311.845706)
		(end 375.190258 -311.701942)
		(width 0.1651)
		(layer "In11.Cu")
		(net "P5E_PEX3_STN7_TX_DN<117>")
	)
	(segment
		(start 370.167662 -318.38773)
		(end 373.517414 -313.374786)
		(width 0.1651)
		(layer "In11.Cu")
		(net "P5E_PEX3_STN7_TX_DN<117>")
	)
	(segment
		(start 421.6908 -340.2076)
		(end 418.72535 -338.138008)
		(width 0.1651)
		(layer "In11.Cu")
		(net "P5E_PEX3_STN7_TX_DN<117>")
	)
	(segment
		(start 418.72535 -338.138008)
		(end 375.472706 -328.448162)
		(width 0.1651)
		(layer "In11.Cu")
		(net "P5E_PEX3_STN7_TX_DN<117>")
	)
	(segment
		(start 383.949448 -306.015898)
		(end 383.995168 -305.970178)
		(width 0.1143)
		(layer "In11.Cu")
		(net "P5E_PEX3_STN7_TX_DN<117>")
	)
	(segment
		(start 376.87885 -310.157114)
		(end 376.87885 -310.01335)
		(width 0.1651)
		(layer "In11.Cu")
		(net "P5E_PEX3_STN7_TX_DN<117>")
	)
	(segment
		(start 376.034554 -311.00141)
		(end 376.034554 -310.857646)
		(width 0.1651)
		(layer "In11.Cu")
		(net "P5E_PEX3_STN7_TX_DN<117>")
	)
	(segment
		(start 392.179556 -306.07381)
		(end 392.179556 -306.235608)
		(width 0.1143)
		(layer "In11.Cu")
		(net "P5E_PEX3_STN7_TX_DN<117>")
	)
	(segment
		(start 378.073158 -308.819042)
		(end 378.216922 -308.819042)
		(width 0.1651)
		(layer "In11.Cu")
		(net "P5E_PEX3_STN7_TX_DN<117>")
	)
	(segment
		(start 383.921 -306.015898)
		(end 383.949448 -306.015898)
		(width 0.1143)
		(layer "In11.Cu")
		(net "P5E_PEX3_STN7_TX_DN<117>")
	)
	(segment
		(start 378.216922 -308.819042)
		(end 378.567442 -308.468522)
		(width 0.1651)
		(layer "In11.Cu")
		(net "P5E_PEX3_STN7_TX_DN<117>")
	)
	(segment
		(start 379.000258 -307.891942)
		(end 379.144022 -307.891942)
		(width 0.1651)
		(layer "In11.Cu")
		(net "P5E_PEX3_STN7_TX_DN<117>")
	)
	(segment
		(start 392.075924 -305.970178)
		(end 392.179556 -306.07381)
		(width 0.1143)
		(layer "In11.Cu")
		(net "P5E_PEX3_STN7_TX_DN<117>")
	)
	(segment
		(start 422.303702 -342.148668)
		(end 422.303702 -341.633048)
		(width 0.1651)
		(layer "In11.Cu")
		(net "P5E_PEX3_STN7_TX_DN<117>")
	)
	(segment
		(start 375.54027 -311.35193)
		(end 375.684034 -311.35193)
		(width 0.1651)
		(layer "In11.Cu")
		(net "P5E_PEX3_STN7_TX_DN<117>")
	)
	(segment
		(start 379.144022 -307.891942)
		(end 379.494542 -307.541422)
		(width 0.1651)
		(layer "In11.Cu")
		(net "P5E_PEX3_STN7_TX_DN<117>")
	)
	(segment
		(start 377.228862 -309.663338)
		(end 377.372626 -309.663338)
		(width 0.1651)
		(layer "In11.Cu")
		(net "P5E_PEX3_STN7_TX_DN<117>")
	)
	(segment
		(start 378.567442 -308.324758)
		(end 379.000258 -307.891942)
		(width 0.1651)
		(layer "In11.Cu")
		(net "P5E_PEX3_STN7_TX_DN<117>")
	)
	(segment
		(start 381.121666 -306.569364)
		(end 381.579374 -306.379626)
		(width 0.1651)
		(layer "In11.Cu")
		(net "P5E_PEX3_STN7_TX_DN<117>")
	)
	(segment
		(start 374.839738 -312.196226)
		(end 375.190258 -311.845706)
		(width 0.1651)
		(layer "In11.Cu")
		(net "P5E_PEX3_STN7_TX_DN<117>")
	)
	(segment
		(start 377.372626 -309.663338)
		(end 377.723146 -309.312818)
		(width 0.1651)
		(layer "In11.Cu")
		(net "P5E_PEX3_STN7_TX_DN<117>")
	)
	(segment
		(start 422.594532 -342.439498)
		(end 422.303702 -342.148668)
		(width 0.1651)
		(layer "In11.Cu")
		(net "P5E_PEX3_STN7_TX_DN<117>")
	)
	(segment
		(start 381.634492 -306.247038)
		(end 382.192276 -306.015898)
		(width 0.1651)
		(layer "In11.Cu")
		(net "P5E_PEX3_STN7_TX_DN<117>")
	)
	(segment
		(start 375.190258 -311.701942)
		(end 375.54027 -311.35193)
		(width 0.1651)
		(layer "In11.Cu")
		(net "P5E_PEX3_STN7_TX_DN<117>")
	)
	(segment
		(start 378.567442 -308.468522)
		(end 378.567442 -308.324758)
		(width 0.1651)
		(layer "In11.Cu")
		(net "P5E_PEX3_STN7_TX_DN<117>")
	)
	(segment
		(start 375.684034 -311.35193)
		(end 376.034554 -311.00141)
		(width 0.1651)
		(layer "In11.Cu")
		(net "P5E_PEX3_STN7_TX_DN<117>")
	)
	(segment
		(start 380.988824 -306.5145)
		(end 381.121666 -306.569364)
		(width 0.1651)
		(layer "In11.Cu")
		(net "P5E_PEX3_STN7_TX_DN<117>")
	)
	(segment
		(start 375.472706 -328.448162)
		(end 372.748556 -326.949816)
		(width 0.1651)
		(layer "In11.Cu")
		(net "P5E_PEX3_STN7_TX_DN<117>")
	)
	(segment
		(start 373.517414 -313.374786)
		(end 374.695974 -312.196226)
		(width 0.1651)
		(layer "In11.Cu")
		(net "P5E_PEX3_STN7_TX_DN<117>")
	)
	(segment
		(start 68.199762 -316.534292)
		(end 68.199762 -316.799722)
		(width 0.1143)
		(layer "In5.Cu")
		(net "P5E_PEX0_STN5_RX_DN<90>")
	)
	(segment
		(start 76.309982 -371.408198)
		(end 76.436982 -371.281198)
		(width 0.1651)
		(layer "In5.Cu")
		(net "P5E_PEX0_STN5_RX_DN<90>")
	)
	(segment
		(start 67.934332 -316.419992)
		(end 68.085462 -316.419992)
		(width 0.1143)
		(layer "In5.Cu")
		(net "P5E_PEX0_STN5_RX_DN<90>")
	)
	(segment
		(start 67.820032 -319.921128)
		(end 67.820032 -316.534292)
		(width 0.1143)
		(layer "In5.Cu")
		(net "P5E_PEX0_STN5_RX_DN<90>")
	)
	(segment
		(start 67.865752 -321.445128)
		(end 67.865752 -319.995296)
		(width 0.1651)
		(layer "In5.Cu")
		(net "P5E_PEX0_STN5_RX_DN<90>")
	)
	(segment
		(start 76.436982 -371.281198)
		(end 77.053948 -371.281198)
		(width 0.1651)
		(layer "In5.Cu")
		(net "P5E_PEX0_STN5_RX_DN<90>")
	)
	(segment
		(start 67.865752 -319.995296)
		(end 67.865752 -319.966848)
		(width 0.1143)
		(layer "In5.Cu")
		(net "P5E_PEX0_STN5_RX_DN<90>")
	)
	(segment
		(start 67.865752 -319.966848)
		(end 67.820032 -319.921128)
		(width 0.1143)
		(layer "In5.Cu")
		(net "P5E_PEX0_STN5_RX_DN<90>")
	)
	(segment
		(start 79.044292 -358.138222)
		(end 79.044292 -342.051894)
		(width 0.1651)
		(layer "In5.Cu")
		(net "P5E_PEX0_STN5_RX_DN<90>")
	)
	(segment
		(start 77.490828 -368.610388)
		(end 79.044292 -358.138222)
		(width 0.1651)
		(layer "In5.Cu")
		(net "P5E_PEX0_STN5_RX_DN<90>")
	)
	(segment
		(start 67.820032 -316.534292)
		(end 67.934332 -316.419992)
		(width 0.1143)
		(layer "In5.Cu")
		(net "P5E_PEX0_STN5_RX_DN<90>")
	)
	(segment
		(start 78.839568 -341.311738)
		(end 68.66636 -324.339204)
		(width 0.1651)
		(layer "In5.Cu")
		(net "P5E_PEX0_STN5_RX_DN<90>")
	)
	(segment
		(start 76.309982 -371.790214)
		(end 76.309982 -371.408198)
		(width 0.1651)
		(layer "In5.Cu")
		(net "P5E_PEX0_STN5_RX_DN<90>")
	)
	(segment
		(start 68.66636 -324.339204)
		(end 67.865752 -321.445128)
		(width 0.1651)
		(layer "In5.Cu")
		(net "P5E_PEX0_STN5_RX_DN<90>")
	)
	(segment
		(start 68.085462 -316.419992)
		(end 68.199762 -316.534292)
		(width 0.1143)
		(layer "In5.Cu")
		(net "P5E_PEX0_STN5_RX_DN<90>")
	)
	(segment
		(start 77.490828 -370.844318)
		(end 77.490828 -368.610388)
		(width 0.1651)
		(layer "In5.Cu")
		(net "P5E_PEX0_STN5_RX_DN<90>")
	)
	(segment
		(start 79.044292 -342.051894)
		(end 78.839568 -341.311738)
		(width 0.1651)
		(layer "In5.Cu")
		(net "P5E_PEX0_STN5_RX_DN<90>")
	)
	(segment
		(start 77.053948 -371.281198)
		(end 77.490828 -370.844318)
		(width 0.1651)
		(layer "In5.Cu")
		(net "P5E_PEX0_STN5_RX_DN<90>")
	)
	(segment
		(start 84.023962 -355.978206)
		(end 83.703922 -355.658166)
		(width 0.13462)
		(layer "F.Cu")
		(net "P5E_PEX0_STN5_TX_DN<91>")
	)
	(segment
		(start 83.703922 -355.658166)
		(end 83.703922 -355.026722)
		(width 0.13462)
		(layer "F.Cu")
		(net "P5E_PEX0_STN5_TX_DN<91>")
	)
	(segment
		(start 83.703922 -355.026722)
		(end 83.998562 -354.732082)
		(width 0.13462)
		(layer "F.Cu")
		(net "P5E_PEX0_STN5_TX_DN<91>")
	)
	(segment
		(start 69.035676 -313.570112)
		(end 69.149976 -313.684412)
		(width 0.1143)
		(layer "In7.Cu")
		(net "P5E_PEX0_STN5_TX_DN<91>")
	)
	(segment
		(start 68.770246 -313.684412)
		(end 68.884546 -313.570112)
		(width 0.1143)
		(layer "In7.Cu")
		(net "P5E_PEX0_STN5_TX_DN<91>")
	)
	(segment
		(start 85.262212 -340.702392)
		(end 84.062824 -338.907374)
		(width 0.1651)
		(layer "In7.Cu")
		(net "P5E_PEX0_STN5_TX_DN<91>")
	)
	(segment
		(start 83.998562 -354.732082)
		(end 83.707732 -354.441252)
		(width 0.1651)
		(layer "In7.Cu")
		(net "P5E_PEX0_STN5_TX_DN<91>")
	)
	(segment
		(start 69.18452 -322.044314)
		(end 68.815966 -321.154806)
		(width 0.1651)
		(layer "In7.Cu")
		(net "P5E_PEX0_STN5_TX_DN<91>")
	)
	(segment
		(start 68.815966 -319.941448)
		(end 68.815966 -319.913)
		(width 0.1143)
		(layer "In7.Cu")
		(net "P5E_PEX0_STN5_TX_DN<91>")
	)
	(segment
		(start 68.770246 -319.86728)
		(end 68.770246 -313.684412)
		(width 0.1143)
		(layer "In7.Cu")
		(net "P5E_PEX0_STN5_TX_DN<91>")
	)
	(segment
		(start 68.815966 -321.154806)
		(end 68.815966 -319.941448)
		(width 0.1651)
		(layer "In7.Cu")
		(net "P5E_PEX0_STN5_TX_DN<91>")
	)
	(segment
		(start 68.884546 -313.570112)
		(end 69.035676 -313.570112)
		(width 0.1143)
		(layer "In7.Cu")
		(net "P5E_PEX0_STN5_TX_DN<91>")
	)
	(segment
		(start 84.062824 -338.907374)
		(end 77.40777 -330.79817)
		(width 0.1651)
		(layer "In7.Cu")
		(net "P5E_PEX0_STN5_TX_DN<91>")
	)
	(segment
		(start 83.707732 -354.441252)
		(end 83.707732 -353.942142)
		(width 0.1651)
		(layer "In7.Cu")
		(net "P5E_PEX0_STN5_TX_DN<91>")
	)
	(segment
		(start 68.815966 -319.913)
		(end 68.770246 -319.86728)
		(width 0.1143)
		(layer "In7.Cu")
		(net "P5E_PEX0_STN5_TX_DN<91>")
	)
	(segment
		(start 83.707732 -353.942142)
		(end 85.262212 -352.387662)
		(width 0.1651)
		(layer "In7.Cu")
		(net "P5E_PEX0_STN5_TX_DN<91>")
	)
	(segment
		(start 85.262212 -352.387662)
		(end 85.262212 -340.702392)
		(width 0.1651)
		(layer "In7.Cu")
		(net "P5E_PEX0_STN5_TX_DN<91>")
	)
	(segment
		(start 77.40777 -330.79817)
		(end 70.252844 -323.643244)
		(width 0.1651)
		(layer "In7.Cu")
		(net "P5E_PEX0_STN5_TX_DN<91>")
	)
	(segment
		(start 69.149976 -313.684412)
		(end 69.149976 -313.949842)
		(width 0.1143)
		(layer "In7.Cu")
		(net "P5E_PEX0_STN5_TX_DN<91>")
	)
	(segment
		(start 70.252844 -323.643244)
		(end 69.18452 -322.044314)
		(width 0.1651)
		(layer "In7.Cu")
		(net "P5E_PEX0_STN5_TX_DN<91>")
	)
	(segment
		(start 322.398644 -343.365582)
		(end 322.398644 -342.734138)
		(width 0.13462)
		(layer "F.Cu")
		(net "P5E_PEX2_STN5_TX_DN<84>")
	)
	(segment
		(start 322.718684 -343.685622)
		(end 322.398644 -343.365582)
		(width 0.13462)
		(layer "F.Cu")
		(net "P5E_PEX2_STN5_TX_DN<84>")
	)
	(segment
		(start 322.398644 -342.734138)
		(end 322.693284 -342.439498)
		(width 0.13462)
		(layer "F.Cu")
		(net "P5E_PEX2_STN5_TX_DN<84>")
	)
	(segment
		(start 294.58539 -311.670192)
		(end 294.69969 -311.784492)
		(width 0.1143)
		(layer "In7.Cu")
		(net "P5E_PEX2_STN5_TX_DN<84>")
	)
	(segment
		(start 303.893474 -332.117954)
		(end 303.793398 -332.157832)
		(width 0.1651)
		(layer "In7.Cu")
		(net "P5E_PEX2_STN5_TX_DN<84>")
	)
	(segment
		(start 319.987676 -339.148674)
		(end 304.388266 -332.414626)
		(width 0.1651)
		(layer "In7.Cu")
		(net "P5E_PEX2_STN5_TX_DN<84>")
	)
	(segment
		(start 294.31996 -319.79108)
		(end 294.31996 -311.784492)
		(width 0.1143)
		(layer "In7.Cu")
		(net "P5E_PEX2_STN5_TX_DN<84>")
	)
	(segment
		(start 294.36568 -322.344796)
		(end 294.36568 -319.865248)
		(width 0.1651)
		(layer "In7.Cu")
		(net "P5E_PEX2_STN5_TX_DN<84>")
	)
	(segment
		(start 294.36568 -319.8368)
		(end 294.31996 -319.79108)
		(width 0.1143)
		(layer "In7.Cu")
		(net "P5E_PEX2_STN5_TX_DN<84>")
	)
	(segment
		(start 320.617596 -339.578188)
		(end 319.987676 -339.148674)
		(width 0.1651)
		(layer "In7.Cu")
		(net "P5E_PEX2_STN5_TX_DN<84>")
	)
	(segment
		(start 304.388266 -332.414626)
		(end 304.348388 -332.31455)
		(width 0.1651)
		(layer "In7.Cu")
		(net "P5E_PEX2_STN5_TX_DN<84>")
	)
	(segment
		(start 294.31996 -311.784492)
		(end 294.43426 -311.670192)
		(width 0.1143)
		(layer "In7.Cu")
		(net "P5E_PEX2_STN5_TX_DN<84>")
	)
	(segment
		(start 294.36568 -319.865248)
		(end 294.36568 -319.8368)
		(width 0.1143)
		(layer "In7.Cu")
		(net "P5E_PEX2_STN5_TX_DN<84>")
	)
	(segment
		(start 303.793398 -332.157832)
		(end 299.355764 -330.242164)
		(width 0.1651)
		(layer "In7.Cu")
		(net "P5E_PEX2_STN5_TX_DN<84>")
	)
	(segment
		(start 304.348388 -332.31455)
		(end 303.893474 -332.117954)
		(width 0.1651)
		(layer "In7.Cu")
		(net "P5E_PEX2_STN5_TX_DN<84>")
	)
	(segment
		(start 296.421302 -327.307702)
		(end 294.36568 -322.344796)
		(width 0.1651)
		(layer "In7.Cu")
		(net "P5E_PEX2_STN5_TX_DN<84>")
	)
	(segment
		(start 294.69969 -311.784492)
		(end 294.69969 -312.049922)
		(width 0.1143)
		(layer "In7.Cu")
		(net "P5E_PEX2_STN5_TX_DN<84>")
	)
	(segment
		(start 322.402454 -341.633048)
		(end 322.107306 -341.120476)
		(width 0.1651)
		(layer "In7.Cu")
		(net "P5E_PEX2_STN5_TX_DN<84>")
	)
	(segment
		(start 322.402454 -342.148668)
		(end 322.402454 -341.633048)
		(width 0.1651)
		(layer "In7.Cu")
		(net "P5E_PEX2_STN5_TX_DN<84>")
	)
	(segment
		(start 322.693284 -342.439498)
		(end 322.402454 -342.148668)
		(width 0.1651)
		(layer "In7.Cu")
		(net "P5E_PEX2_STN5_TX_DN<84>")
	)
	(segment
		(start 322.107306 -341.120476)
		(end 320.617596 -339.578188)
		(width 0.1651)
		(layer "In7.Cu")
		(net "P5E_PEX2_STN5_TX_DN<84>")
	)
	(segment
		(start 294.43426 -311.670192)
		(end 294.58539 -311.670192)
		(width 0.1143)
		(layer "In7.Cu")
		(net "P5E_PEX2_STN5_TX_DN<84>")
	)
	(segment
		(start 299.355764 -330.242164)
		(end 296.421302 -327.307702)
		(width 0.1651)
		(layer "In7.Cu")
		(net "P5E_PEX2_STN5_TX_DN<84>")
	)
	(segment
		(start 429.832262 -153.415746)
		(end 429.547528 -153.70048)
		(width 0.13462)
		(layer "F.Cu")
		(net "P5E_PEX3_STN0_TX_DP<14>")
	)
	(segment
		(start 428.896272 -153.70048)
		(end 428.586138 -153.390346)
		(width 0.13462)
		(layer "F.Cu")
		(net "P5E_PEX3_STN0_TX_DP<14>")
	)
	(segment
		(start 429.547528 -153.70048)
		(end 428.896272 -153.70048)
		(width 0.13462)
		(layer "F.Cu")
		(net "P5E_PEX3_STN0_TX_DP<14>")
	)
	(segment
		(start 424.093386 -269.222728)
		(end 423.994072 -269.263876)
		(width 0.1651)
		(layer "In9.Cu")
		(net "P5E_PEX3_STN0_TX_DP<14>")
	)
	(segment
		(start 433.23764 -153.706576)
		(end 434.626004 -155.09494)
		(width 0.1651)
		(layer "In9.Cu")
		(net "P5E_PEX3_STN0_TX_DP<14>")
	)
	(segment
		(start 423.823892 -280.129488)
		(end 423.98569 -280.129488)
		(width 0.1143)
		(layer "In9.Cu")
		(net "P5E_PEX3_STN0_TX_DP<14>")
	)
	(segment
		(start 423.994072 -269.263876)
		(end 423.76598 -269.814548)
		(width 0.1651)
		(layer "In9.Cu")
		(net "P5E_PEX3_STN0_TX_DP<14>")
	)
	(segment
		(start 421.210994 -221.249748)
		(end 424.658028 -260.666992)
		(width 0.1651)
		(layer "In9.Cu")
		(net "P5E_PEX3_STN0_TX_DP<14>")
	)
	(segment
		(start 429.832262 -153.415746)
		(end 430.123092 -153.706576)
		(width 0.1651)
		(layer "In9.Cu")
		(net "P5E_PEX3_STN0_TX_DP<14>")
	)
	(segment
		(start 426.58792 -171.27347)
		(end 426.58792 -171.273724)
		(width 0.1651)
		(layer "In9.Cu")
		(net "P5E_PEX3_STN0_TX_DP<14>")
	)
	(segment
		(start 424.658028 -260.666992)
		(end 424.658028 -267.660374)
		(width 0.1651)
		(layer "In9.Cu")
		(net "P5E_PEX3_STN0_TX_DP<14>")
	)
	(segment
		(start 426.58792 -171.273724)
		(end 425.09567 -176.843436)
		(width 0.1651)
		(layer "In9.Cu")
		(net "P5E_PEX3_STN0_TX_DP<14>")
	)
	(segment
		(start 430.123092 -153.706576)
		(end 433.23764 -153.706576)
		(width 0.1651)
		(layer "In9.Cu")
		(net "P5E_PEX3_STN0_TX_DP<14>")
	)
	(segment
		(start 423.98569 -280.129488)
		(end 424.09999 -280.015188)
		(width 0.1143)
		(layer "In9.Cu")
		(net "P5E_PEX3_STN0_TX_DP<14>")
	)
	(segment
		(start 424.241976 -268.665198)
		(end 424.283378 -268.764766)
		(width 0.1651)
		(layer "In9.Cu")
		(net "P5E_PEX3_STN0_TX_DP<14>")
	)
	(segment
		(start 423.76598 -271.554448)
		(end 423.72026 -271.600168)
		(width 0.1143)
		(layer "In9.Cu")
		(net "P5E_PEX3_STN0_TX_DP<14>")
	)
	(segment
		(start 423.76598 -271.526)
		(end 423.76598 -271.554448)
		(width 0.1143)
		(layer "In9.Cu")
		(net "P5E_PEX3_STN0_TX_DP<14>")
	)
	(segment
		(start 434.626004 -155.09494)
		(end 434.923184 -155.81249)
		(width 0.1651)
		(layer "In9.Cu")
		(net "P5E_PEX3_STN0_TX_DP<14>")
	)
	(segment
		(start 423.72026 -271.600168)
		(end 423.72026 -280.025856)
		(width 0.1143)
		(layer "In9.Cu")
		(net "P5E_PEX3_STN0_TX_DP<14>")
	)
	(segment
		(start 425.09567 -176.843436)
		(end 421.210994 -221.249748)
		(width 0.1651)
		(layer "In9.Cu")
		(net "P5E_PEX3_STN0_TX_DP<14>")
	)
	(segment
		(start 424.658028 -267.660374)
		(end 424.241976 -268.665198)
		(width 0.1651)
		(layer "In9.Cu")
		(net "P5E_PEX3_STN0_TX_DP<14>")
	)
	(segment
		(start 424.09999 -280.015188)
		(end 424.09999 -279.749504)
		(width 0.1143)
		(layer "In9.Cu")
		(net "P5E_PEX3_STN0_TX_DP<14>")
	)
	(segment
		(start 434.923184 -156.835856)
		(end 426.58792 -171.27347)
		(width 0.1651)
		(layer "In9.Cu")
		(net "P5E_PEX3_STN0_TX_DP<14>")
	)
	(segment
		(start 423.72026 -280.025856)
		(end 423.823892 -280.129488)
		(width 0.1143)
		(layer "In9.Cu")
		(net "P5E_PEX3_STN0_TX_DP<14>")
	)
	(segment
		(start 434.923184 -155.81249)
		(end 434.923184 -156.835856)
		(width 0.1651)
		(layer "In9.Cu")
		(net "P5E_PEX3_STN0_TX_DP<14>")
	)
	(segment
		(start 423.76598 -269.814548)
		(end 423.76598 -271.526)
		(width 0.1651)
		(layer "In9.Cu")
		(net "P5E_PEX3_STN0_TX_DP<14>")
	)
	(segment
		(start 424.283378 -268.764766)
		(end 424.093386 -269.222728)
		(width 0.1651)
		(layer "In9.Cu")
		(net "P5E_PEX3_STN0_TX_DP<14>")
	)
	(segment
		(start 437.569864 -349.512382)
		(end 437.569864 -348.879922)
		(width 0.13462)
		(layer "F.Cu")
		(net "P5E_PEX3_STN7_TX_DP<125>")
	)
	(segment
		(start 437.250332 -349.831914)
		(end 437.569864 -349.512382)
		(width 0.13462)
		(layer "F.Cu")
		(net "P5E_PEX3_STN7_TX_DP<125>")
	)
	(segment
		(start 437.569864 -348.879922)
		(end 437.275732 -348.58579)
		(width 0.13462)
		(layer "F.Cu")
		(net "P5E_PEX3_STN7_TX_DP<125>")
	)
	(segment
		(start 438.211214 -340.543896)
		(end 439.121042 -341.638636)
		(width 0.1651)
		(layer "In11.Cu")
		(net "P5E_PEX3_STN7_TX_DP<125>")
	)
	(segment
		(start 388.379462 -313.595004)
		(end 388.379462 -319.988438)
		(width 0.1143)
		(layer "In11.Cu")
		(net "P5E_PEX3_STN7_TX_DP<125>")
	)
	(segment
		(start 388.333742 -320.034158)
		(end 388.333742 -320.056256)
		(width 0.1143)
		(layer "In11.Cu")
		(net "P5E_PEX3_STN7_TX_DP<125>")
	)
	(segment
		(start 388.379462 -319.988438)
		(end 388.333742 -320.034158)
		(width 0.1143)
		(layer "In11.Cu")
		(net "P5E_PEX3_STN7_TX_DP<125>")
	)
	(segment
		(start 437.566562 -348.29496)
		(end 437.275732 -348.58579)
		(width 0.1651)
		(layer "In11.Cu")
		(net "P5E_PEX3_STN7_TX_DP<125>")
	)
	(segment
		(start 388.835646 -313.379612)
		(end 388.594854 -313.379612)
		(width 0.1143)
		(layer "In11.Cu")
		(net "P5E_PEX3_STN7_TX_DP<125>")
	)
	(segment
		(start 388.333742 -321.625722)
		(end 389.10387 -322.396104)
		(width 0.1651)
		(layer "In11.Cu")
		(net "P5E_PEX3_STN7_TX_DP<125>")
	)
	(segment
		(start 388.949946 -312.999882)
		(end 388.949946 -313.265312)
		(width 0.1143)
		(layer "In11.Cu")
		(net "P5E_PEX3_STN7_TX_DP<125>")
	)
	(segment
		(start 389.10387 -322.396104)
		(end 426.24375 -332.161896)
		(width 0.1651)
		(layer "In11.Cu")
		(net "P5E_PEX3_STN7_TX_DP<125>")
	)
	(segment
		(start 439.121042 -341.638636)
		(end 439.121042 -346.113354)
		(width 0.1651)
		(layer "In11.Cu")
		(net "P5E_PEX3_STN7_TX_DP<125>")
	)
	(segment
		(start 388.949946 -313.265312)
		(end 388.835646 -313.379612)
		(width 0.1143)
		(layer "In11.Cu")
		(net "P5E_PEX3_STN7_TX_DP<125>")
	)
	(segment
		(start 388.333742 -320.056256)
		(end 388.333742 -321.625722)
		(width 0.1651)
		(layer "In11.Cu")
		(net "P5E_PEX3_STN7_TX_DP<125>")
	)
	(segment
		(start 439.121042 -346.113354)
		(end 437.566562 -347.667834)
		(width 0.1651)
		(layer "In11.Cu")
		(net "P5E_PEX3_STN7_TX_DP<125>")
	)
	(segment
		(start 388.594854 -313.379612)
		(end 388.379462 -313.595004)
		(width 0.1143)
		(layer "In11.Cu")
		(net "P5E_PEX3_STN7_TX_DP<125>")
	)
	(segment
		(start 437.566562 -347.667834)
		(end 437.566562 -348.29496)
		(width 0.1651)
		(layer "In11.Cu")
		(net "P5E_PEX3_STN7_TX_DP<125>")
	)
	(segment
		(start 426.24375 -332.161896)
		(end 438.211214 -340.543896)
		(width 0.1651)
		(layer "In11.Cu")
		(net "P5E_PEX3_STN7_TX_DP<125>")
	)
	(segment
		(start 77.734414 -365.046006)
		(end 78.762352 -358.117394)
		(width 0.1651)
		(layer "In5.Cu")
		(net "P5E_PEX0_STN5_RX_DP<90>")
	)
	(segment
		(start 78.762352 -358.117394)
		(end 78.762352 -342.090248)
		(width 0.1651)
		(layer "In5.Cu")
		(net "P5E_PEX0_STN5_RX_DP<90>")
	)
	(segment
		(start 77.432916 -366.31626)
		(end 77.56017 -366.222026)
		(width 0.1651)
		(layer "In5.Cu")
		(net "P5E_PEX0_STN5_RX_DP<90>")
	)
	(segment
		(start 77.56017 -366.222026)
		(end 77.559916 -366.222026)
		(width 0.1651)
		(layer "In5.Cu")
		(net "P5E_PEX0_STN5_RX_DP<90>")
	)
	(segment
		(start 77.281786 -368.0968)
		(end 77.187806 -367.9698)
		(width 0.1651)
		(layer "In5.Cu")
		(net "P5E_PEX0_STN5_RX_DP<90>")
	)
	(segment
		(start 76.164948 -337.39836)
		(end 76.165202 -337.39836)
		(width 0.1651)
		(layer "In5.Cu")
		(net "P5E_PEX0_STN5_RX_DP<90>")
	)
	(segment
		(start 67.855338 -316.229492)
		(end 68.085462 -316.229492)
		(width 0.1143)
		(layer "In5.Cu")
		(net "P5E_PEX0_STN5_RX_DP<90>")
	)
	(segment
		(start 77.208888 -368.58956)
		(end 77.281786 -368.0968)
		(width 0.1651)
		(layer "In5.Cu")
		(net "P5E_PEX0_STN5_RX_DP<90>")
	)
	(segment
		(start 67.583812 -321.483482)
		(end 67.583812 -319.995296)
		(width 0.1651)
		(layer "In5.Cu")
		(net "P5E_PEX0_STN5_RX_DP<90>")
	)
	(segment
		(start 77.456284 -366.92078)
		(end 77.362304 -366.79378)
		(width 0.1651)
		(layer "In5.Cu")
		(net "P5E_PEX0_STN5_RX_DP<90>")
	)
	(segment
		(start 78.762352 -342.090248)
		(end 78.577948 -341.423752)
		(width 0.1651)
		(layer "In5.Cu")
		(net "P5E_PEX0_STN5_RX_DP<90>")
	)
	(segment
		(start 77.208888 -370.727478)
		(end 77.208888 -368.58956)
		(width 0.1651)
		(layer "In5.Cu")
		(net "P5E_PEX0_STN5_RX_DP<90>")
	)
	(segment
		(start 76.165202 -337.39836)
		(end 68.40474 -324.451218)
		(width 0.1651)
		(layer "In5.Cu")
		(net "P5E_PEX0_STN5_RX_DP<90>")
	)
	(segment
		(start 76.436982 -370.999258)
		(end 76.937108 -370.999258)
		(width 0.1651)
		(layer "In5.Cu")
		(net "P5E_PEX0_STN5_RX_DP<90>")
	)
	(segment
		(start 76.309982 -370.489988)
		(end 76.309982 -370.872258)
		(width 0.1651)
		(layer "In5.Cu")
		(net "P5E_PEX0_STN5_RX_DP<90>")
	)
	(segment
		(start 67.583812 -319.966848)
		(end 67.629532 -319.921128)
		(width 0.1143)
		(layer "In5.Cu")
		(net "P5E_PEX0_STN5_RX_DP<90>")
	)
	(segment
		(start 77.385672 -367.398046)
		(end 77.456284 -366.92078)
		(width 0.1651)
		(layer "In5.Cu")
		(net "P5E_PEX0_STN5_RX_DP<90>")
	)
	(segment
		(start 77.258672 -367.49228)
		(end 77.385672 -367.398046)
		(width 0.1651)
		(layer "In5.Cu")
		(net "P5E_PEX0_STN5_RX_DP<90>")
	)
	(segment
		(start 77.559916 -366.222026)
		(end 77.630782 -365.74476)
		(width 0.1651)
		(layer "In5.Cu")
		(net "P5E_PEX0_STN5_RX_DP<90>")
	)
	(segment
		(start 67.629532 -316.455298)
		(end 67.855338 -316.229492)
		(width 0.1143)
		(layer "In5.Cu")
		(net "P5E_PEX0_STN5_RX_DP<90>")
	)
	(segment
		(start 78.577948 -341.423752)
		(end 76.164948 -337.39836)
		(width 0.1651)
		(layer "In5.Cu")
		(net "P5E_PEX0_STN5_RX_DP<90>")
	)
	(segment
		(start 67.583812 -319.995296)
		(end 67.583812 -319.966848)
		(width 0.1143)
		(layer "In5.Cu")
		(net "P5E_PEX0_STN5_RX_DP<90>")
	)
	(segment
		(start 77.607414 -365.14024)
		(end 77.734668 -365.046006)
		(width 0.1651)
		(layer "In5.Cu")
		(net "P5E_PEX0_STN5_RX_DP<90>")
	)
	(segment
		(start 76.309982 -370.872258)
		(end 76.436982 -370.999258)
		(width 0.1651)
		(layer "In5.Cu")
		(net "P5E_PEX0_STN5_RX_DP<90>")
	)
	(segment
		(start 68.40474 -324.451218)
		(end 67.583812 -321.483482)
		(width 0.1651)
		(layer "In5.Cu")
		(net "P5E_PEX0_STN5_RX_DP<90>")
	)
	(segment
		(start 76.937108 -370.999258)
		(end 77.208888 -370.727478)
		(width 0.1651)
		(layer "In5.Cu")
		(net "P5E_PEX0_STN5_RX_DP<90>")
	)
	(segment
		(start 77.362304 -366.79378)
		(end 77.432916 -366.31626)
		(width 0.1651)
		(layer "In5.Cu")
		(net "P5E_PEX0_STN5_RX_DP<90>")
	)
	(segment
		(start 68.085462 -316.229492)
		(end 68.199762 -316.115192)
		(width 0.1143)
		(layer "In5.Cu")
		(net "P5E_PEX0_STN5_RX_DP<90>")
	)
	(segment
		(start 77.734668 -365.046006)
		(end 77.734414 -365.046006)
		(width 0.1651)
		(layer "In5.Cu")
		(net "P5E_PEX0_STN5_RX_DP<90>")
	)
	(segment
		(start 77.630782 -365.74476)
		(end 77.536802 -365.61776)
		(width 0.1651)
		(layer "In5.Cu")
		(net "P5E_PEX0_STN5_RX_DP<90>")
	)
	(segment
		(start 77.536802 -365.61776)
		(end 77.607414 -365.14024)
		(width 0.1651)
		(layer "In5.Cu")
		(net "P5E_PEX0_STN5_RX_DP<90>")
	)
	(segment
		(start 77.187806 -367.9698)
		(end 77.258672 -367.49228)
		(width 0.1651)
		(layer "In5.Cu")
		(net "P5E_PEX0_STN5_RX_DP<90>")
	)
	(segment
		(start 67.629532 -319.921128)
		(end 67.629532 -316.455298)
		(width 0.1143)
		(layer "In5.Cu")
		(net "P5E_PEX0_STN5_RX_DP<90>")
	)
	(segment
		(start 68.199762 -316.115192)
		(end 68.199762 -315.849762)
		(width 0.1143)
		(layer "In5.Cu")
		(net "P5E_PEX0_STN5_RX_DP<90>")
	)
	(segment
		(start 44.498768 -351.316798)
		(end 44.498768 -350.685354)
		(width 0.13462)
		(layer "F.Cu")
		(net "P5E_PEX0_STN7_TX_C_DP<124>")
	)
	(segment
		(start 44.204128 -351.611438)
		(end 44.498768 -351.316798)
		(width 0.13462)
		(layer "F.Cu")
		(net "P5E_PEX0_STN7_TX_C_DP<124>")
	)
	(segment
		(start 44.498768 -350.685354)
		(end 44.178728 -350.365314)
		(width 0.13462)
		(layer "F.Cu")
		(net "P5E_PEX0_STN7_TX_C_DP<124>")
	)
	(segment
		(start 37.602414 -374.490488)
		(end 37.193728 -374.899174)
		(width 0.1651)
		(layer "In7.Cu")
		(net "P5E_PEX0_STN7_TX_C_DP<124>")
	)
	(segment
		(start 39.29634 -365.618776)
		(end 39.084758 -366.066324)
		(width 0.1651)
		(layer "In7.Cu")
		(net "P5E_PEX0_STN7_TX_C_DP<124>")
	)
	(segment
		(start 44.494958 -352.435922)
		(end 42.940478 -353.990402)
		(width 0.1651)
		(layer "In7.Cu")
		(net "P5E_PEX0_STN7_TX_C_DP<124>")
	)
	(segment
		(start 38.966394 -366.108742)
		(end 38.754304 -366.556798)
		(width 0.1651)
		(layer "In7.Cu")
		(net "P5E_PEX0_STN7_TX_C_DP<124>")
	)
	(segment
		(start 39.084758 -366.066324)
		(end 38.966394 -366.108742)
		(width 0.1651)
		(layer "In7.Cu")
		(net "P5E_PEX0_STN7_TX_C_DP<124>")
	)
	(segment
		(start 37.602414 -369.870736)
		(end 37.602414 -374.490488)
		(width 0.1651)
		(layer "In7.Cu")
		(net "P5E_PEX0_STN7_TX_C_DP<124>")
	)
	(segment
		(start 44.494958 -351.902268)
		(end 44.494958 -352.435922)
		(width 0.1651)
		(layer "In7.Cu")
		(net "P5E_PEX0_STN7_TX_C_DP<124>")
	)
	(segment
		(start 39.253922 -365.500412)
		(end 39.29634 -365.618776)
		(width 0.1651)
		(layer "In7.Cu")
		(net "P5E_PEX0_STN7_TX_C_DP<124>")
	)
	(segment
		(start 40.083994 -363.953552)
		(end 39.96563 -363.99597)
		(width 0.1651)
		(layer "In7.Cu")
		(net "P5E_PEX0_STN7_TX_C_DP<124>")
	)
	(segment
		(start 39.584376 -365.009938)
		(end 39.466012 -365.052356)
		(width 0.1651)
		(layer "In7.Cu")
		(net "P5E_PEX0_STN7_TX_C_DP<124>")
	)
	(segment
		(start 42.940478 -357.913686)
		(end 40.083994 -363.953552)
		(width 0.1651)
		(layer "In7.Cu")
		(net "P5E_PEX0_STN7_TX_C_DP<124>")
	)
	(segment
		(start 39.466012 -365.052356)
		(end 39.253922 -365.500412)
		(width 0.1651)
		(layer "In7.Cu")
		(net "P5E_PEX0_STN7_TX_C_DP<124>")
	)
	(segment
		(start 39.75354 -364.444026)
		(end 39.795958 -364.56239)
		(width 0.1651)
		(layer "In7.Cu")
		(net "P5E_PEX0_STN7_TX_C_DP<124>")
	)
	(segment
		(start 38.754304 -366.556798)
		(end 38.796722 -366.675162)
		(width 0.1651)
		(layer "In7.Cu")
		(net "P5E_PEX0_STN7_TX_C_DP<124>")
	)
	(segment
		(start 36.710112 -374.772174)
		(end 36.710112 -374.390158)
		(width 0.1651)
		(layer "In7.Cu")
		(net "P5E_PEX0_STN7_TX_C_DP<124>")
	)
	(segment
		(start 38.796722 -366.675162)
		(end 38.169596 -368.001042)
		(width 0.1651)
		(layer "In7.Cu")
		(net "P5E_PEX0_STN7_TX_C_DP<124>")
	)
	(segment
		(start 38.169596 -368.001042)
		(end 37.602414 -369.870736)
		(width 0.1651)
		(layer "In7.Cu")
		(net "P5E_PEX0_STN7_TX_C_DP<124>")
	)
	(segment
		(start 36.837112 -374.899174)
		(end 36.710112 -374.772174)
		(width 0.1651)
		(layer "In7.Cu")
		(net "P5E_PEX0_STN7_TX_C_DP<124>")
	)
	(segment
		(start 44.204128 -351.611438)
		(end 44.494958 -351.902268)
		(width 0.1651)
		(layer "In7.Cu")
		(net "P5E_PEX0_STN7_TX_C_DP<124>")
	)
	(segment
		(start 39.795958 -364.56239)
		(end 39.584376 -365.009938)
		(width 0.1651)
		(layer "In7.Cu")
		(net "P5E_PEX0_STN7_TX_C_DP<124>")
	)
	(segment
		(start 37.193728 -374.899174)
		(end 36.837112 -374.899174)
		(width 0.1651)
		(layer "In7.Cu")
		(net "P5E_PEX0_STN7_TX_C_DP<124>")
	)
	(segment
		(start 42.940478 -353.990402)
		(end 42.940478 -357.913686)
		(width 0.1651)
		(layer "In7.Cu")
		(net "P5E_PEX0_STN7_TX_C_DP<124>")
	)
	(segment
		(start 39.96563 -363.99597)
		(end 39.75354 -364.444026)
		(width 0.1651)
		(layer "In7.Cu")
		(net "P5E_PEX0_STN7_TX_C_DP<124>")
	)
	(segment
		(start 67.884802 -349.511874)
		(end 67.884802 -348.88043)
		(width 0.13462)
		(layer "F.Cu")
		(net "P5E_PEX0_STN5_TX_DP<83>")
	)
	(segment
		(start 67.564762 -349.831914)
		(end 67.884802 -349.511874)
		(width 0.13462)
		(layer "F.Cu")
		(net "P5E_PEX0_STN5_TX_DP<83>")
	)
	(segment
		(start 67.884802 -348.88043)
		(end 67.590162 -348.58579)
		(width 0.13462)
		(layer "F.Cu")
		(net "P5E_PEX0_STN5_TX_DP<83>")
	)
	(segment
		(start 64.82588 -332.525624)
		(end 60.933838 -324.29704)
		(width 0.1651)
		(layer "In7.Cu")
		(net "P5E_PEX0_STN5_TX_DP<83>")
	)
	(segment
		(start 60.979558 -319.81648)
		(end 60.979558 -313.605418)
		(width 0.1143)
		(layer "In7.Cu")
		(net "P5E_PEX0_STN5_TX_DP<83>")
	)
	(segment
		(start 67.880992 -348.29496)
		(end 67.880992 -347.541342)
		(width 0.1651)
		(layer "In7.Cu")
		(net "P5E_PEX0_STN5_TX_DP<83>")
	)
	(segment
		(start 69.435472 -345.986862)
		(end 69.435472 -341.357204)
		(width 0.1651)
		(layer "In7.Cu")
		(net "P5E_PEX0_STN5_TX_DP<83>")
	)
	(segment
		(start 69.435472 -341.357204)
		(end 69.051678 -340.43112)
		(width 0.1651)
		(layer "In7.Cu")
		(net "P5E_PEX0_STN5_TX_DP<83>")
	)
	(segment
		(start 61.549788 -313.265312)
		(end 61.549788 -312.999882)
		(width 0.1143)
		(layer "In7.Cu")
		(net "P5E_PEX0_STN5_TX_DP<83>")
	)
	(segment
		(start 60.979558 -313.605418)
		(end 61.205364 -313.379612)
		(width 0.1143)
		(layer "In7.Cu")
		(net "P5E_PEX0_STN5_TX_DP<83>")
	)
	(segment
		(start 69.051678 -340.43112)
		(end 64.82588 -332.525624)
		(width 0.1651)
		(layer "In7.Cu")
		(net "P5E_PEX0_STN5_TX_DP<83>")
	)
	(segment
		(start 60.933838 -319.8622)
		(end 60.979558 -319.81648)
		(width 0.1143)
		(layer "In7.Cu")
		(net "P5E_PEX0_STN5_TX_DP<83>")
	)
	(segment
		(start 61.435488 -313.379612)
		(end 61.549788 -313.265312)
		(width 0.1143)
		(layer "In7.Cu")
		(net "P5E_PEX0_STN5_TX_DP<83>")
	)
	(segment
		(start 67.880992 -347.541342)
		(end 69.435472 -345.986862)
		(width 0.1651)
		(layer "In7.Cu")
		(net "P5E_PEX0_STN5_TX_DP<83>")
	)
	(segment
		(start 67.590162 -348.58579)
		(end 67.880992 -348.29496)
		(width 0.1651)
		(layer "In7.Cu")
		(net "P5E_PEX0_STN5_TX_DP<83>")
	)
	(segment
		(start 60.933838 -319.890648)
		(end 60.933838 -319.8622)
		(width 0.1143)
		(layer "In7.Cu")
		(net "P5E_PEX0_STN5_TX_DP<83>")
	)
	(segment
		(start 61.205364 -313.379612)
		(end 61.435488 -313.379612)
		(width 0.1143)
		(layer "In7.Cu")
		(net "P5E_PEX0_STN5_TX_DP<83>")
	)
	(segment
		(start 60.933838 -324.29704)
		(end 60.933838 -319.890648)
		(width 0.1651)
		(layer "In7.Cu")
		(net "P5E_PEX0_STN5_TX_DP<83>")
	)
	(segment
		(start 139.817348 -349.831914)
		(end 140.137388 -349.511874)
		(width 0.13462)
		(layer "F.Cu")
		(net "P5E_PEX1_STN5_TX_DP<93>")
	)
	(segment
		(start 140.137388 -349.511874)
		(end 140.137388 -348.88043)
		(width 0.13462)
		(layer "F.Cu")
		(net "P5E_PEX1_STN5_TX_DP<93>")
	)
	(segment
		(start 140.137388 -348.88043)
		(end 139.842748 -348.58579)
		(width 0.13462)
		(layer "F.Cu")
		(net "P5E_PEX1_STN5_TX_DP<93>")
	)
	(segment
		(start 181.691534 -326.282304)
		(end 176.058068 -329.294236)
		(width 0.1651)
		(layer "In13.Cu")
		(net "P5E_PEX1_STN5_TX_DP<93>")
	)
	(segment
		(start 143.431768 -339.882988)
		(end 143.20774 -339.975698)
		(width 0.1651)
		(layer "In13.Cu")
		(net "P5E_PEX1_STN5_TX_DP<93>")
	)
	(segment
		(start 147.400518 -339.882988)
		(end 143.431768 -339.882988)
		(width 0.1651)
		(layer "In13.Cu")
		(net "P5E_PEX1_STN5_TX_DP<93>")
	)
	(segment
		(start 187.035694 -313.379612)
		(end 186.794902 -313.379612)
		(width 0.1143)
		(layer "In13.Cu")
		(net "P5E_PEX1_STN5_TX_DP<93>")
	)
	(segment
		(start 186.579764 -313.59475)
		(end 186.579764 -319.995296)
		(width 0.1143)
		(layer "In13.Cu")
		(net "P5E_PEX1_STN5_TX_DP<93>")
	)
	(segment
		(start 186.794902 -313.379612)
		(end 186.579764 -313.59475)
		(width 0.1143)
		(layer "In13.Cu")
		(net "P5E_PEX1_STN5_TX_DP<93>")
	)
	(segment
		(start 141.688058 -341.364062)
		(end 141.688058 -345.952572)
		(width 0.1651)
		(layer "In13.Cu")
		(net "P5E_PEX1_STN5_TX_DP<93>")
	)
	(segment
		(start 186.534044 -320.063114)
		(end 186.534044 -322.12788)
		(width 0.1651)
		(layer "In13.Cu")
		(net "P5E_PEX1_STN5_TX_DP<93>")
	)
	(segment
		(start 183.341264 -325.180706)
		(end 181.691534 -326.282304)
		(width 0.1651)
		(layer "In13.Cu")
		(net "P5E_PEX1_STN5_TX_DP<93>")
	)
	(segment
		(start 140.133578 -348.29496)
		(end 139.842748 -348.58579)
		(width 0.1651)
		(layer "In13.Cu")
		(net "P5E_PEX1_STN5_TX_DP<93>")
	)
	(segment
		(start 176.058068 -329.294236)
		(end 165.36035 -333.897478)
		(width 0.1651)
		(layer "In13.Cu")
		(net "P5E_PEX1_STN5_TX_DP<93>")
	)
	(segment
		(start 143.207486 -339.975952)
		(end 142.983458 -340.068662)
		(width 0.1651)
		(layer "In13.Cu")
		(net "P5E_PEX1_STN5_TX_DP<93>")
	)
	(segment
		(start 187.149994 -313.265312)
		(end 187.035694 -313.379612)
		(width 0.1143)
		(layer "In13.Cu")
		(net "P5E_PEX1_STN5_TX_DP<93>")
	)
	(segment
		(start 186.579764 -319.995296)
		(end 186.534044 -320.041016)
		(width 0.1143)
		(layer "In13.Cu")
		(net "P5E_PEX1_STN5_TX_DP<93>")
	)
	(segment
		(start 187.149994 -312.999882)
		(end 187.149994 -313.265312)
		(width 0.1143)
		(layer "In13.Cu")
		(net "P5E_PEX1_STN5_TX_DP<93>")
	)
	(segment
		(start 140.133578 -347.507052)
		(end 140.133578 -348.29496)
		(width 0.1651)
		(layer "In13.Cu")
		(net "P5E_PEX1_STN5_TX_DP<93>")
	)
	(segment
		(start 142.983458 -340.068662)
		(end 141.688058 -341.364062)
		(width 0.1651)
		(layer "In13.Cu")
		(net "P5E_PEX1_STN5_TX_DP<93>")
	)
	(segment
		(start 186.534044 -320.041016)
		(end 186.534044 -320.063114)
		(width 0.1143)
		(layer "In13.Cu")
		(net "P5E_PEX1_STN5_TX_DP<93>")
	)
	(segment
		(start 184.992264 -324.0786)
		(end 183.341518 -325.180706)
		(width 0.1651)
		(layer "In13.Cu")
		(net "P5E_PEX1_STN5_TX_DP<93>")
	)
	(segment
		(start 141.688058 -345.952572)
		(end 140.133578 -347.507052)
		(width 0.1651)
		(layer "In13.Cu")
		(net "P5E_PEX1_STN5_TX_DP<93>")
	)
	(segment
		(start 165.36035 -333.897478)
		(end 147.400518 -339.882988)
		(width 0.1651)
		(layer "In13.Cu")
		(net "P5E_PEX1_STN5_TX_DP<93>")
	)
	(segment
		(start 186.2455 -322.824856)
		(end 184.992264 -324.0786)
		(width 0.1651)
		(layer "In13.Cu")
		(net "P5E_PEX1_STN5_TX_DP<93>")
	)
	(segment
		(start 183.341518 -325.180706)
		(end 183.341264 -325.180706)
		(width 0.1651)
		(layer "In13.Cu")
		(net "P5E_PEX1_STN5_TX_DP<93>")
	)
	(segment
		(start 143.20774 -339.975698)
		(end 143.207486 -339.975952)
		(width 0.1651)
		(layer "In13.Cu")
		(net "P5E_PEX1_STN5_TX_DP<93>")
	)
	(segment
		(start 186.534044 -322.12788)
		(end 186.2455 -322.824856)
		(width 0.1651)
		(layer "In13.Cu")
		(net "P5E_PEX1_STN5_TX_DP<93>")
	)
	(segment
		(start 331.85227 -33.95218)
		(end 331.221334 -33.95218)
		(width 0.13462)
		(layer "F.Cu")
		(net "P5E_PEX2_STN2_TX_DN<35>")
	)
	(segment
		(start 332.147164 -33.657286)
		(end 331.85227 -33.95218)
		(width 0.13462)
		(layer "F.Cu")
		(net "P5E_PEX2_STN2_TX_DN<35>")
	)
	(segment
		(start 331.221334 -33.95218)
		(end 330.90104 -33.631886)
		(width 0.13462)
		(layer "F.Cu")
		(net "P5E_PEX2_STN2_TX_DN<35>")
	)
	(segment
		(start 336.535522 -67.91071)
		(end 332.269846 -74.235564)
		(width 0.1651)
		(layer "In11.Cu")
		(net "P5E_PEX2_STN2_TX_DN<35>")
	)
	(segment
		(start 325.388986 -80.13319)
		(end 311.259982 -105.014776)
		(width 0.1651)
		(layer "In11.Cu")
		(net "P5E_PEX2_STN2_TX_DN<35>")
	)
	(segment
		(start 332.269846 -74.235564)
		(end 327.566528 -77.950314)
		(width 0.1651)
		(layer "In11.Cu")
		(net "P5E_PEX2_STN2_TX_DN<35>")
	)
	(segment
		(start 311.259982 -105.014776)
		(end 309.561738 -118.211854)
		(width 0.1651)
		(layer "In11.Cu")
		(net "P5E_PEX2_STN2_TX_DN<35>")
	)
	(segment
		(start 287.773618 -278.229568)
		(end 287.935416 -278.229568)
		(width 0.1143)
		(layer "In11.Cu")
		(net "P5E_PEX2_STN2_TX_DN<35>")
	)
	(segment
		(start 287.935416 -278.229568)
		(end 288.049716 -278.115268)
		(width 0.1143)
		(layer "In11.Cu")
		(net "P5E_PEX2_STN2_TX_DN<35>")
	)
	(segment
		(start 308.593998 -141.7955)
		(end 308.287674 -149.256242)
		(width 0.1651)
		(layer "In11.Cu")
		(net "P5E_PEX2_STN2_TX_DN<35>")
	)
	(segment
		(start 287.715706 -265.478768)
		(end 287.715706 -271.399)
		(width 0.1651)
		(layer "In11.Cu")
		(net "P5E_PEX2_STN2_TX_DN<35>")
	)
	(segment
		(start 327.566528 -77.950314)
		(end 325.388986 -80.13319)
		(width 0.1651)
		(layer "In11.Cu")
		(net "P5E_PEX2_STN2_TX_DN<35>")
	)
	(segment
		(start 338.455 -42.785538)
		(end 338.684362 -56.765698)
		(width 0.1651)
		(layer "In11.Cu")
		(net "P5E_PEX2_STN2_TX_DN<35>")
	)
	(segment
		(start 287.715706 -271.427448)
		(end 287.669986 -271.473168)
		(width 0.1143)
		(layer "In11.Cu")
		(net "P5E_PEX2_STN2_TX_DN<35>")
	)
	(segment
		(start 332.147164 -33.657286)
		(end 332.342236 -33.852358)
		(width 0.1651)
		(layer "In11.Cu")
		(net "P5E_PEX2_STN2_TX_DN<35>")
	)
	(segment
		(start 333.603346 -34.082736)
		(end 334.144874 -34.57829)
		(width 0.1651)
		(layer "In11.Cu")
		(net "P5E_PEX2_STN2_TX_DN<35>")
	)
	(segment
		(start 333.121508 -33.948116)
		(end 333.603346 -34.082736)
		(width 0.1651)
		(layer "In11.Cu")
		(net "P5E_PEX2_STN2_TX_DN<35>")
	)
	(segment
		(start 334.144874 -34.57829)
		(end 338.35848 -42.414952)
		(width 0.1651)
		(layer "In11.Cu")
		(net "P5E_PEX2_STN2_TX_DN<35>")
	)
	(segment
		(start 332.57363 -33.948116)
		(end 333.121508 -33.948116)
		(width 0.1651)
		(layer "In11.Cu")
		(net "P5E_PEX2_STN2_TX_DN<35>")
	)
	(segment
		(start 338.35848 -42.414952)
		(end 338.455 -42.785538)
		(width 0.1651)
		(layer "In11.Cu")
		(net "P5E_PEX2_STN2_TX_DN<35>")
	)
	(segment
		(start 309.561738 -118.211854)
		(end 309.032656 -131.103624)
		(width 0.1651)
		(layer "In11.Cu")
		(net "P5E_PEX2_STN2_TX_DN<35>")
	)
	(segment
		(start 287.669986 -278.125936)
		(end 287.773618 -278.229568)
		(width 0.1143)
		(layer "In11.Cu")
		(net "P5E_PEX2_STN2_TX_DN<35>")
	)
	(segment
		(start 287.669986 -271.473168)
		(end 287.669986 -278.125936)
		(width 0.1143)
		(layer "In11.Cu")
		(net "P5E_PEX2_STN2_TX_DN<35>")
	)
	(segment
		(start 306.824634 -161.53003)
		(end 287.715706 -265.478768)
		(width 0.1651)
		(layer "In11.Cu")
		(net "P5E_PEX2_STN2_TX_DN<35>")
	)
	(segment
		(start 309.032656 -139.897866)
		(end 308.593998 -141.7955)
		(width 0.1651)
		(layer "In11.Cu")
		(net "P5E_PEX2_STN2_TX_DN<35>")
	)
	(segment
		(start 332.342236 -33.852358)
		(end 332.57363 -33.948116)
		(width 0.1651)
		(layer "In11.Cu")
		(net "P5E_PEX2_STN2_TX_DN<35>")
	)
	(segment
		(start 308.287674 -149.256242)
		(end 306.824634 -161.53003)
		(width 0.1651)
		(layer "In11.Cu")
		(net "P5E_PEX2_STN2_TX_DN<35>")
	)
	(segment
		(start 288.049716 -278.115268)
		(end 288.049716 -277.849838)
		(width 0.1143)
		(layer "In11.Cu")
		(net "P5E_PEX2_STN2_TX_DN<35>")
	)
	(segment
		(start 309.032656 -131.103624)
		(end 309.032656 -139.897866)
		(width 0.1651)
		(layer "In11.Cu")
		(net "P5E_PEX2_STN2_TX_DN<35>")
	)
	(segment
		(start 338.684362 -56.765698)
		(end 336.535522 -67.91071)
		(width 0.1651)
		(layer "In11.Cu")
		(net "P5E_PEX2_STN2_TX_DN<35>")
	)
	(segment
		(start 287.715706 -271.399)
		(end 287.715706 -271.427448)
		(width 0.1143)
		(layer "In11.Cu")
		(net "P5E_PEX2_STN2_TX_DN<35>")
	)
	(segment
		(start 432.185318 -152.1968)
		(end 431.542698 -152.1968)
		(width 0.13462)
		(layer "F.Cu")
		(net "P5E_PEX3_STN0_TX_DP<13>")
	)
	(segment
		(start 432.47437 -152.485852)
		(end 432.185318 -152.1968)
		(width 0.13462)
		(layer "F.Cu")
		(net "P5E_PEX3_STN0_TX_DP<13>")
	)
	(segment
		(start 431.542698 -152.1968)
		(end 431.228246 -152.511252)
		(width 0.13462)
		(layer "F.Cu")
		(net "P5E_PEX3_STN0_TX_DP<13>")
	)
	(segment
		(start 424.434 -271.471898)
		(end 424.434 -269.98803)
		(width 0.1651)
		(layer "In9.Cu")
		(net "P5E_PEX3_STN0_TX_DP<13>")
	)
	(segment
		(start 427.238414 -171.523152)
		(end 435.608984 -157.023562)
		(width 0.1651)
		(layer "In9.Cu")
		(net "P5E_PEX3_STN0_TX_DP<13>")
	)
	(segment
		(start 434.774594 -154.211528)
		(end 434.548534 -153.873454)
		(width 0.1651)
		(layer "In9.Cu")
		(net "P5E_PEX3_STN0_TX_DP<13>")
	)
	(segment
		(start 421.897556 -221.36227)
		(end 425.783502 -176.952402)
		(width 0.1651)
		(layer "In9.Cu")
		(net "P5E_PEX3_STN0_TX_DP<13>")
	)
	(segment
		(start 425.343828 -267.79093)
		(end 425.343828 -260.763004)
		(width 0.1651)
		(layer "In9.Cu")
		(net "P5E_PEX3_STN0_TX_DP<13>")
	)
	(segment
		(start 424.434 -269.98803)
		(end 425.343828 -267.79093)
		(width 0.1651)
		(layer "In9.Cu")
		(net "P5E_PEX3_STN0_TX_DP<13>")
	)
	(segment
		(start 433.984146 -153.02865)
		(end 434.012086 -152.88768)
		(width 0.1651)
		(layer "In9.Cu")
		(net "P5E_PEX3_STN0_TX_DP<13>")
	)
	(segment
		(start 434.548534 -153.873454)
		(end 434.576728 -153.732484)
		(width 0.1651)
		(layer "In9.Cu")
		(net "P5E_PEX3_STN0_TX_DP<13>")
	)
	(segment
		(start 435.608984 -155.632658)
		(end 435.221888 -154.697938)
		(width 0.1651)
		(layer "In9.Cu")
		(net "P5E_PEX3_STN0_TX_DP<13>")
	)
	(segment
		(start 435.221888 -154.697938)
		(end 434.915564 -154.239468)
		(width 0.1651)
		(layer "In9.Cu")
		(net "P5E_PEX3_STN0_TX_DP<13>")
	)
	(segment
		(start 434.210206 -153.366724)
		(end 433.984146 -153.02865)
		(width 0.1651)
		(layer "In9.Cu")
		(net "P5E_PEX3_STN0_TX_DP<13>")
	)
	(segment
		(start 434.351176 -153.394664)
		(end 434.210206 -153.366724)
		(width 0.1651)
		(layer "In9.Cu")
		(net "P5E_PEX3_STN0_TX_DP<13>")
	)
	(segment
		(start 424.47972 -278.205184)
		(end 424.47972 -271.546066)
		(width 0.1143)
		(layer "In9.Cu")
		(net "P5E_PEX3_STN0_TX_DP<13>")
	)
	(segment
		(start 435.608984 -157.023562)
		(end 435.608984 -155.632658)
		(width 0.1651)
		(layer "In9.Cu")
		(net "P5E_PEX3_STN0_TX_DP<13>")
	)
	(segment
		(start 424.694604 -278.420068)
		(end 424.47972 -278.205184)
		(width 0.1143)
		(layer "In9.Cu")
		(net "P5E_PEX3_STN0_TX_DP<13>")
	)
	(segment
		(start 425.049696 -278.799798)
		(end 425.049696 -278.534368)
		(width 0.1143)
		(layer "In9.Cu")
		(net "P5E_PEX3_STN0_TX_DP<13>")
	)
	(segment
		(start 432.7652 -152.195022)
		(end 432.47437 -152.485852)
		(width 0.1651)
		(layer "In9.Cu")
		(net "P5E_PEX3_STN0_TX_DP<13>")
	)
	(segment
		(start 434.350922 -153.394664)
		(end 434.351176 -153.394664)
		(width 0.1651)
		(layer "In9.Cu")
		(net "P5E_PEX3_STN0_TX_DP<13>")
	)
	(segment
		(start 424.47972 -271.546066)
		(end 424.434 -271.500346)
		(width 0.1143)
		(layer "In9.Cu")
		(net "P5E_PEX3_STN0_TX_DP<13>")
	)
	(segment
		(start 425.049696 -278.534368)
		(end 424.935396 -278.420068)
		(width 0.1143)
		(layer "In9.Cu")
		(net "P5E_PEX3_STN0_TX_DP<13>")
	)
	(segment
		(start 434.576728 -153.732484)
		(end 434.350922 -153.394664)
		(width 0.1651)
		(layer "In9.Cu")
		(net "P5E_PEX3_STN0_TX_DP<13>")
	)
	(segment
		(start 434.012086 -152.88768)
		(end 433.786534 -152.54986)
		(width 0.1651)
		(layer "In9.Cu")
		(net "P5E_PEX3_STN0_TX_DP<13>")
	)
	(segment
		(start 434.915564 -154.239468)
		(end 434.774594 -154.211528)
		(width 0.1651)
		(layer "In9.Cu")
		(net "P5E_PEX3_STN0_TX_DP<13>")
	)
	(segment
		(start 433.786534 -152.54986)
		(end 433.431696 -152.195022)
		(width 0.1651)
		(layer "In9.Cu")
		(net "P5E_PEX3_STN0_TX_DP<13>")
	)
	(segment
		(start 425.343828 -260.763004)
		(end 421.897556 -221.36227)
		(width 0.1651)
		(layer "In9.Cu")
		(net "P5E_PEX3_STN0_TX_DP<13>")
	)
	(segment
		(start 424.935396 -278.420068)
		(end 424.694604 -278.420068)
		(width 0.1143)
		(layer "In9.Cu")
		(net "P5E_PEX3_STN0_TX_DP<13>")
	)
	(segment
		(start 425.783502 -176.952402)
		(end 427.238414 -171.523152)
		(width 0.1651)
		(layer "In9.Cu")
		(net "P5E_PEX3_STN0_TX_DP<13>")
	)
	(segment
		(start 433.431696 -152.195022)
		(end 432.7652 -152.195022)
		(width 0.1651)
		(layer "In9.Cu")
		(net "P5E_PEX3_STN0_TX_DP<13>")
	)
	(segment
		(start 424.434 -271.500346)
		(end 424.434 -271.471898)
		(width 0.1143)
		(layer "In9.Cu")
		(net "P5E_PEX3_STN0_TX_DP<13>")
	)
	(segment
		(start 384.192272 -348.880938)
		(end 384.48742 -348.58579)
		(width 0.13462)
		(layer "F.Cu")
		(net "P5E_PEX3_STN6_TX_DN<97>")
	)
	(segment
		(start 384.192272 -349.511366)
		(end 384.192272 -348.880938)
		(width 0.13462)
		(layer "F.Cu")
		(net "P5E_PEX3_STN6_TX_DN<97>")
	)
	(segment
		(start 384.51282 -349.831914)
		(end 384.192272 -349.511366)
		(width 0.13462)
		(layer "F.Cu")
		(net "P5E_PEX3_STN6_TX_DN<97>")
	)
	(segment
		(start 404.720298 -319.915032)
		(end 404.720298 -311.784492)
		(width 0.1143)
		(layer "In7.Cu")
		(net "P5E_PEX3_STN6_TX_DN<97>")
	)
	(segment
		(start 404.985728 -311.670192)
		(end 405.100028 -311.784492)
		(width 0.1143)
		(layer "In7.Cu")
		(net "P5E_PEX3_STN6_TX_DN<97>")
	)
	(segment
		(start 404.766018 -319.960752)
		(end 404.720298 -319.915032)
		(width 0.1143)
		(layer "In7.Cu")
		(net "P5E_PEX3_STN6_TX_DN<97>")
	)
	(segment
		(start 404.766018 -319.9892)
		(end 404.766018 -319.960752)
		(width 0.1143)
		(layer "In7.Cu")
		(net "P5E_PEX3_STN6_TX_DN<97>")
	)
	(segment
		(start 404.720298 -311.784492)
		(end 404.834598 -311.670192)
		(width 0.1143)
		(layer "In7.Cu")
		(net "P5E_PEX3_STN6_TX_DN<97>")
	)
	(segment
		(start 404.00732 -323.6341)
		(end 404.766018 -321.80276)
		(width 0.1651)
		(layer "In7.Cu")
		(net "P5E_PEX3_STN6_TX_DN<97>")
	)
	(segment
		(start 404.834598 -311.670192)
		(end 404.985728 -311.670192)
		(width 0.1143)
		(layer "In7.Cu")
		(net "P5E_PEX3_STN6_TX_DN<97>")
	)
	(segment
		(start 405.100028 -311.784492)
		(end 405.100028 -312.049922)
		(width 0.1143)
		(layer "In7.Cu")
		(net "P5E_PEX3_STN6_TX_DN<97>")
	)
	(segment
		(start 384.19659 -347.784674)
		(end 385.75107 -346.230194)
		(width 0.1651)
		(layer "In7.Cu")
		(net "P5E_PEX3_STN6_TX_DN<97>")
	)
	(segment
		(start 401.592288 -326.049132)
		(end 404.00732 -323.6341)
		(width 0.1651)
		(layer "In7.Cu")
		(net "P5E_PEX3_STN6_TX_DN<97>")
	)
	(segment
		(start 384.19659 -348.29496)
		(end 384.19659 -347.784674)
		(width 0.1651)
		(layer "In7.Cu")
		(net "P5E_PEX3_STN6_TX_DN<97>")
	)
	(segment
		(start 385.75107 -346.230194)
		(end 385.75107 -341.003636)
		(width 0.1651)
		(layer "In7.Cu")
		(net "P5E_PEX3_STN6_TX_DN<97>")
	)
	(segment
		(start 385.75107 -341.003636)
		(end 401.592288 -326.049132)
		(width 0.1651)
		(layer "In7.Cu")
		(net "P5E_PEX3_STN6_TX_DN<97>")
	)
	(segment
		(start 404.766018 -321.80276)
		(end 404.766018 -319.9892)
		(width 0.1651)
		(layer "In7.Cu")
		(net "P5E_PEX3_STN6_TX_DN<97>")
	)
	(segment
		(start 384.48742 -348.58579)
		(end 384.19659 -348.29496)
		(width 0.1651)
		(layer "In7.Cu")
		(net "P5E_PEX3_STN6_TX_DN<97>")
	)
	(segment
		(start 37.420042 -316.914022)
		(end 37.534342 -316.799722)
		(width 0.1143)
		(layer "In5.Cu")
		(net "P5E_PEX0_STN7_RX_DP<122>")
	)
	(segment
		(start 37.420042 -319.05448)
		(end 37.420042 -316.914022)
		(width 0.1143)
		(layer "In5.Cu")
		(net "P5E_PEX0_STN7_RX_DP<122>")
	)
	(segment
		(start 37.534342 -316.799722)
		(end 37.799772 -316.799722)
		(width 0.1143)
		(layer "In5.Cu")
		(net "P5E_PEX0_STN7_RX_DP<122>")
	)
	(segment
		(start 37.004498 -357.810054)
		(end 37.004498 -341.647526)
		(width 0.1651)
		(layer "In5.Cu")
		(net "P5E_PEX0_STN7_RX_DP<122>")
	)
	(segment
		(start 36.449 -336.007964)
		(end 36.449 -329.244706)
		(width 0.1651)
		(layer "In5.Cu")
		(net "P5E_PEX0_STN7_RX_DP<122>")
	)
	(segment
		(start 32.924242 -382.9812)
		(end 33.458912 -382.44653)
		(width 0.1651)
		(layer "In5.Cu")
		(net "P5E_PEX0_STN7_RX_DP<122>")
	)
	(segment
		(start 37.465762 -321.112388)
		(end 37.465762 -319.128648)
		(width 0.1651)
		(layer "In5.Cu")
		(net "P5E_PEX0_STN7_RX_DP<122>")
	)
	(segment
		(start 37.004498 -341.647526)
		(end 36.449 -336.007964)
		(width 0.1651)
		(layer "In5.Cu")
		(net "P5E_PEX0_STN7_RX_DP<122>")
	)
	(segment
		(start 32.43707 -382.9812)
		(end 32.924242 -382.9812)
		(width 0.1651)
		(layer "In5.Cu")
		(net "P5E_PEX0_STN7_RX_DP<122>")
	)
	(segment
		(start 37.465762 -319.128648)
		(end 37.465762 -319.1002)
		(width 0.1143)
		(layer "In5.Cu")
		(net "P5E_PEX0_STN7_RX_DP<122>")
	)
	(segment
		(start 36.449 -329.244706)
		(end 37.46373 -321.11442)
		(width 0.1651)
		(layer "In5.Cu")
		(net "P5E_PEX0_STN7_RX_DP<122>")
	)
	(segment
		(start 37.46373 -321.11442)
		(end 37.465762 -321.112388)
		(width 0.1651)
		(layer "In5.Cu")
		(net "P5E_PEX0_STN7_RX_DP<122>")
	)
	(segment
		(start 36.746942 -359.546906)
		(end 37.004498 -357.810054)
		(width 0.1651)
		(layer "In5.Cu")
		(net "P5E_PEX0_STN7_RX_DP<122>")
	)
	(segment
		(start 33.458912 -382.44653)
		(end 33.458912 -370.385594)
		(width 0.1651)
		(layer "In5.Cu")
		(net "P5E_PEX0_STN7_RX_DP<122>")
	)
	(segment
		(start 37.465762 -319.1002)
		(end 37.420042 -319.05448)
		(width 0.1143)
		(layer "In5.Cu")
		(net "P5E_PEX0_STN7_RX_DP<122>")
	)
	(segment
		(start 32.31007 -383.490216)
		(end 32.31007 -383.1082)
		(width 0.1651)
		(layer "In5.Cu")
		(net "P5E_PEX0_STN7_RX_DP<122>")
	)
	(segment
		(start 33.458912 -370.385594)
		(end 36.746942 -359.546906)
		(width 0.1651)
		(layer "In5.Cu")
		(net "P5E_PEX0_STN7_RX_DP<122>")
	)
	(segment
		(start 32.31007 -383.1082)
		(end 32.43707 -382.9812)
		(width 0.1651)
		(layer "In5.Cu")
		(net "P5E_PEX0_STN7_RX_DP<122>")
	)
	(segment
		(start 47.607728 -357.46309)
		(end 47.607728 -356.831646)
		(width 0.13462)
		(layer "F.Cu")
		(net "P5E_PEX0_STN7_TX_C_DP<126>")
	)
	(segment
		(start 47.313088 -357.75773)
		(end 47.607728 -357.46309)
		(width 0.13462)
		(layer "F.Cu")
		(net "P5E_PEX0_STN7_TX_C_DP<126>")
	)
	(segment
		(start 47.607728 -356.831646)
		(end 47.287688 -356.511606)
		(width 0.13462)
		(layer "F.Cu")
		(net "P5E_PEX0_STN7_TX_C_DP<126>")
	)
	(segment
		(start 43.527218 -365.888778)
		(end 43.492166 -365.762032)
		(width 0.1651)
		(layer "In7.Cu")
		(net "P5E_PEX0_STN7_TX_C_DP<126>")
	)
	(segment
		(start 42.703496 -367.342928)
		(end 42.94124 -366.923066)
		(width 0.1651)
		(layer "In7.Cu")
		(net "P5E_PEX0_STN7_TX_C_DP<126>")
	)
	(segment
		(start 41.2369 -374.899174)
		(end 41.593516 -374.899174)
		(width 0.1651)
		(layer "In7.Cu")
		(net "P5E_PEX0_STN7_TX_C_DP<126>")
	)
	(segment
		(start 47.603918 -358.692704)
		(end 47.603918 -358.04856)
		(width 0.1651)
		(layer "In7.Cu")
		(net "P5E_PEX0_STN7_TX_C_DP<126>")
	)
	(segment
		(start 41.593516 -374.899174)
		(end 42.002202 -374.490488)
		(width 0.1651)
		(layer "In7.Cu")
		(net "P5E_PEX0_STN7_TX_C_DP<126>")
	)
	(segment
		(start 43.492166 -365.762032)
		(end 43.748706 -365.30915)
		(width 0.1651)
		(layer "In7.Cu")
		(net "P5E_PEX0_STN7_TX_C_DP<126>")
	)
	(segment
		(start 43.748706 -365.30915)
		(end 43.875452 -365.274352)
		(width 0.1651)
		(layer "In7.Cu")
		(net "P5E_PEX0_STN7_TX_C_DP<126>")
	)
	(segment
		(start 42.94124 -366.923066)
		(end 42.912792 -366.820196)
		(width 0.1651)
		(layer "In7.Cu")
		(net "P5E_PEX0_STN7_TX_C_DP<126>")
	)
	(segment
		(start 42.002202 -370.003832)
		(end 42.703496 -367.342928)
		(width 0.1651)
		(layer "In7.Cu")
		(net "P5E_PEX0_STN7_TX_C_DP<126>")
	)
	(segment
		(start 43.186604 -366.337088)
		(end 43.289474 -366.30864)
		(width 0.1651)
		(layer "In7.Cu")
		(net "P5E_PEX0_STN7_TX_C_DP<126>")
	)
	(segment
		(start 42.002202 -374.490488)
		(end 42.002202 -370.003832)
		(width 0.1651)
		(layer "In7.Cu")
		(net "P5E_PEX0_STN7_TX_C_DP<126>")
	)
	(segment
		(start 43.289474 -366.30864)
		(end 43.527218 -365.888778)
		(width 0.1651)
		(layer "In7.Cu")
		(net "P5E_PEX0_STN7_TX_C_DP<126>")
	)
	(segment
		(start 47.603918 -358.04856)
		(end 47.313088 -357.75773)
		(width 0.1651)
		(layer "In7.Cu")
		(net "P5E_PEX0_STN7_TX_C_DP<126>")
	)
	(segment
		(start 41.1099 -374.390158)
		(end 41.1099 -374.772174)
		(width 0.1651)
		(layer "In7.Cu")
		(net "P5E_PEX0_STN7_TX_C_DP<126>")
	)
	(segment
		(start 43.875452 -365.274352)
		(end 47.603918 -358.692704)
		(width 0.1651)
		(layer "In7.Cu")
		(net "P5E_PEX0_STN7_TX_C_DP<126>")
	)
	(segment
		(start 41.1099 -374.772174)
		(end 41.2369 -374.899174)
		(width 0.1651)
		(layer "In7.Cu")
		(net "P5E_PEX0_STN7_TX_C_DP<126>")
	)
	(segment
		(start 42.912792 -366.820196)
		(end 43.186604 -366.337088)
		(width 0.1651)
		(layer "In7.Cu")
		(net "P5E_PEX0_STN7_TX_C_DP<126>")
	)
	(segment
		(start 86.538562 -349.511874)
		(end 86.538562 -348.88043)
		(width 0.13462)
		(layer "F.Cu")
		(net "P5E_PEX0_STN5_TX_DP<92>")
	)
	(segment
		(start 86.218522 -349.831914)
		(end 86.538562 -349.511874)
		(width 0.13462)
		(layer "F.Cu")
		(net "P5E_PEX0_STN5_TX_DP<92>")
	)
	(segment
		(start 86.538562 -348.88043)
		(end 86.243922 -348.58579)
		(width 0.13462)
		(layer "F.Cu")
		(net "P5E_PEX0_STN5_TX_DP<92>")
	)
	(segment
		(start 86.534752 -347.541342)
		(end 88.089232 -345.986862)
		(width 0.1651)
		(layer "In7.Cu")
		(net "P5E_PEX0_STN5_TX_DP<92>")
	)
	(segment
		(start 69.483986 -319.941448)
		(end 69.483986 -319.913)
		(width 0.1143)
		(layer "In7.Cu")
		(net "P5E_PEX0_STN5_TX_DP<92>")
	)
	(segment
		(start 69.529706 -311.705498)
		(end 69.755512 -311.479692)
		(width 0.1143)
		(layer "In7.Cu")
		(net "P5E_PEX0_STN5_TX_DP<92>")
	)
	(segment
		(start 70.726046 -323.092826)
		(end 69.840602 -321.767708)
		(width 0.1651)
		(layer "In7.Cu")
		(net "P5E_PEX0_STN5_TX_DP<92>")
	)
	(segment
		(start 69.755512 -311.479692)
		(end 69.985636 -311.479692)
		(width 0.1143)
		(layer "In7.Cu")
		(net "P5E_PEX0_STN5_TX_DP<92>")
	)
	(segment
		(start 69.985636 -311.479692)
		(end 70.099936 -311.365392)
		(width 0.1143)
		(layer "In7.Cu")
		(net "P5E_PEX0_STN5_TX_DP<92>")
	)
	(segment
		(start 69.483986 -319.913)
		(end 69.529706 -319.86728)
		(width 0.1143)
		(layer "In7.Cu")
		(net "P5E_PEX0_STN5_TX_DP<92>")
	)
	(segment
		(start 86.243922 -348.58579)
		(end 86.534752 -348.29496)
		(width 0.1651)
		(layer "In7.Cu")
		(net "P5E_PEX0_STN5_TX_DP<92>")
	)
	(segment
		(start 88.089232 -341.656162)
		(end 87.240618 -339.607398)
		(width 0.1651)
		(layer "In7.Cu")
		(net "P5E_PEX0_STN5_TX_DP<92>")
	)
	(segment
		(start 69.483986 -320.906648)
		(end 69.483986 -319.941448)
		(width 0.1651)
		(layer "In7.Cu")
		(net "P5E_PEX0_STN5_TX_DP<92>")
	)
	(segment
		(start 88.089232 -345.986862)
		(end 88.089232 -341.656162)
		(width 0.1651)
		(layer "In7.Cu")
		(net "P5E_PEX0_STN5_TX_DP<92>")
	)
	(segment
		(start 70.099936 -311.365392)
		(end 70.099936 -311.099962)
		(width 0.1143)
		(layer "In7.Cu")
		(net "P5E_PEX0_STN5_TX_DP<92>")
	)
	(segment
		(start 87.240618 -339.607398)
		(end 70.726046 -323.092826)
		(width 0.1651)
		(layer "In7.Cu")
		(net "P5E_PEX0_STN5_TX_DP<92>")
	)
	(segment
		(start 69.529706 -319.86728)
		(end 69.529706 -311.705498)
		(width 0.1143)
		(layer "In7.Cu")
		(net "P5E_PEX0_STN5_TX_DP<92>")
	)
	(segment
		(start 86.534752 -348.29496)
		(end 86.534752 -347.541342)
		(width 0.1651)
		(layer "In7.Cu")
		(net "P5E_PEX0_STN5_TX_DP<92>")
	)
	(segment
		(start 69.840602 -321.767708)
		(end 69.483986 -320.906648)
		(width 0.1651)
		(layer "In7.Cu")
		(net "P5E_PEX0_STN5_TX_DP<92>")
	)
	(segment
		(start 137.302748 -355.658166)
		(end 137.302748 -355.026722)
		(width 0.13462)
		(layer "F.Cu")
		(net "P5E_PEX1_STN5_TX_DN<92>")
	)
	(segment
		(start 137.622788 -355.978206)
		(end 137.302748 -355.658166)
		(width 0.13462)
		(layer "F.Cu")
		(net "P5E_PEX1_STN5_TX_DN<92>")
	)
	(segment
		(start 137.302748 -355.026722)
		(end 137.597388 -354.732082)
		(width 0.13462)
		(layer "F.Cu")
		(net "P5E_PEX1_STN5_TX_DN<92>")
	)
	(segment
		(start 183.183022 -324.466204)
		(end 181.809644 -325.383652)
		(width 0.1651)
		(layer "In13.Cu")
		(net "P5E_PEX1_STN5_TX_DN<92>")
	)
	(segment
		(start 185.866024 -321.974972)
		(end 185.676286 -322.432934)
		(width 0.1651)
		(layer "In13.Cu")
		(net "P5E_PEX1_STN5_TX_DN<92>")
	)
	(segment
		(start 186.200034 -312.049922)
		(end 186.200034 -311.784492)
		(width 0.1143)
		(layer "In13.Cu")
		(net "P5E_PEX1_STN5_TX_DN<92>")
	)
	(segment
		(start 138.861038 -352.308922)
		(end 137.306558 -353.863402)
		(width 0.1651)
		(layer "In13.Cu")
		(net "P5E_PEX1_STN5_TX_DN<92>")
	)
	(segment
		(start 165.077394 -333.274416)
		(end 147.828254 -339.022944)
		(width 0.1651)
		(layer "In13.Cu")
		(net "P5E_PEX1_STN5_TX_DN<92>")
	)
	(segment
		(start 185.676286 -322.432934)
		(end 184.568592 -323.540628)
		(width 0.1651)
		(layer "In13.Cu")
		(net "P5E_PEX1_STN5_TX_DN<92>")
	)
	(segment
		(start 137.306558 -353.863402)
		(end 137.306558 -354.441252)
		(width 0.1651)
		(layer "In13.Cu")
		(net "P5E_PEX1_STN5_TX_DN<92>")
	)
	(segment
		(start 185.866024 -320.063114)
		(end 185.866024 -321.974972)
		(width 0.1651)
		(layer "In13.Cu")
		(net "P5E_PEX1_STN5_TX_DN<92>")
	)
	(segment
		(start 137.306558 -354.441252)
		(end 137.597388 -354.732082)
		(width 0.1651)
		(layer "In13.Cu")
		(net "P5E_PEX1_STN5_TX_DN<92>")
	)
	(segment
		(start 185.866024 -320.041016)
		(end 185.866024 -320.063114)
		(width 0.1143)
		(layer "In13.Cu")
		(net "P5E_PEX1_STN5_TX_DN<92>")
	)
	(segment
		(start 183.183276 -324.46595)
		(end 183.183022 -324.466204)
		(width 0.1651)
		(layer "In13.Cu")
		(net "P5E_PEX1_STN5_TX_DN<92>")
	)
	(segment
		(start 147.828254 -339.022944)
		(end 144.145 -339.022944)
		(width 0.1651)
		(layer "In13.Cu")
		(net "P5E_PEX1_STN5_TX_DN<92>")
	)
	(segment
		(start 138.861038 -341.480902)
		(end 138.861038 -352.308922)
		(width 0.1651)
		(layer "In13.Cu")
		(net "P5E_PEX1_STN5_TX_DN<92>")
	)
	(segment
		(start 185.923936 -311.670192)
		(end 185.820304 -311.773824)
		(width 0.1143)
		(layer "In13.Cu")
		(net "P5E_PEX1_STN5_TX_DN<92>")
	)
	(segment
		(start 184.568592 -323.540628)
		(end 183.183276 -324.46595)
		(width 0.1651)
		(layer "In13.Cu")
		(net "P5E_PEX1_STN5_TX_DN<92>")
	)
	(segment
		(start 144.145 -339.022944)
		(end 142.988284 -339.253068)
		(width 0.1651)
		(layer "In13.Cu")
		(net "P5E_PEX1_STN5_TX_DN<92>")
	)
	(segment
		(start 186.200034 -311.784492)
		(end 186.085734 -311.670192)
		(width 0.1143)
		(layer "In13.Cu")
		(net "P5E_PEX1_STN5_TX_DN<92>")
	)
	(segment
		(start 186.085734 -311.670192)
		(end 185.923936 -311.670192)
		(width 0.1143)
		(layer "In13.Cu")
		(net "P5E_PEX1_STN5_TX_DN<92>")
	)
	(segment
		(start 185.820304 -319.995296)
		(end 185.866024 -320.041016)
		(width 0.1143)
		(layer "In13.Cu")
		(net "P5E_PEX1_STN5_TX_DN<92>")
	)
	(segment
		(start 142.988284 -339.253068)
		(end 139.745974 -340.595966)
		(width 0.1651)
		(layer "In13.Cu")
		(net "P5E_PEX1_STN5_TX_DN<92>")
	)
	(segment
		(start 175.181768 -328.926698)
		(end 165.077394 -333.274416)
		(width 0.1651)
		(layer "In13.Cu")
		(net "P5E_PEX1_STN5_TX_DN<92>")
	)
	(segment
		(start 185.820304 -311.773824)
		(end 185.820304 -319.995296)
		(width 0.1143)
		(layer "In13.Cu")
		(net "P5E_PEX1_STN5_TX_DN<92>")
	)
	(segment
		(start 139.745974 -340.595966)
		(end 138.861038 -341.480902)
		(width 0.1651)
		(layer "In13.Cu")
		(net "P5E_PEX1_STN5_TX_DN<92>")
	)
	(segment
		(start 181.809644 -325.383652)
		(end 175.181768 -328.926698)
		(width 0.1651)
		(layer "In13.Cu")
		(net "P5E_PEX1_STN5_TX_DN<92>")
	)
	(segment
		(start 302.569626 -28.829)
		(end 302.258984 -29.139642)
		(width 0.13462)
		(layer "F.Cu")
		(net "P5E_PEX2_STN2_TX_DP<36>")
	)
	(segment
		(start 303.219866 -28.829)
		(end 302.569626 -28.829)
		(width 0.13462)
		(layer "F.Cu")
		(net "P5E_PEX2_STN2_TX_DP<36>")
	)
	(segment
		(start 303.505108 -29.114242)
		(end 303.219866 -28.829)
		(width 0.13462)
		(layer "F.Cu")
		(net "P5E_PEX2_STN2_TX_DP<36>")
	)
	(segment
		(start 296.17416 -108.054394)
		(end 294.543226 -116.64442)
		(width 0.1651)
		(layer "In11.Cu")
		(net "P5E_PEX2_STN2_TX_DP<36>")
	)
	(segment
		(start 286.529526 -280.10485)
		(end 286.744664 -280.319988)
		(width 0.1143)
		(layer "In11.Cu")
		(net "P5E_PEX2_STN2_TX_DP<36>")
	)
	(segment
		(start 286.483806 -271.427448)
		(end 286.529526 -271.473168)
		(width 0.1143)
		(layer "In11.Cu")
		(net "P5E_PEX2_STN2_TX_DP<36>")
	)
	(segment
		(start 323.19214 -60.556902)
		(end 322.562474 -62.898274)
		(width 0.1651)
		(layer "In11.Cu")
		(net "P5E_PEX2_STN2_TX_DP<36>")
	)
	(segment
		(start 303.505108 -29.114242)
		(end 303.795938 -28.823412)
		(width 0.1651)
		(layer "In11.Cu")
		(net "P5E_PEX2_STN2_TX_DP<36>")
	)
	(segment
		(start 322.562474 -62.898274)
		(end 321.591686 -64.855598)
		(width 0.1651)
		(layer "In11.Cu")
		(net "P5E_PEX2_STN2_TX_DP<36>")
	)
	(segment
		(start 308.07025 -30.02661)
		(end 308.42077 -30.37713)
		(width 0.1651)
		(layer "In11.Cu")
		(net "P5E_PEX2_STN2_TX_DP<36>")
	)
	(segment
		(start 309.247032 -31.203392)
		(end 309.372762 -31.203392)
		(width 0.1651)
		(layer "In11.Cu")
		(net "P5E_PEX2_STN2_TX_DP<36>")
	)
	(segment
		(start 303.795938 -28.823412)
		(end 306.115466 -28.823412)
		(width 0.1651)
		(layer "In11.Cu")
		(net "P5E_PEX2_STN2_TX_DP<36>")
	)
	(segment
		(start 308.07025 -29.90088)
		(end 308.07025 -30.02661)
		(width 0.1651)
		(layer "In11.Cu")
		(net "P5E_PEX2_STN2_TX_DP<36>")
	)
	(segment
		(start 306.115466 -28.823412)
		(end 307.61559 -29.445966)
		(width 0.1651)
		(layer "In11.Cu")
		(net "P5E_PEX2_STN2_TX_DP<36>")
	)
	(segment
		(start 294.02532 -120.93321)
		(end 286.483806 -263.41705)
		(width 0.1651)
		(layer "In11.Cu")
		(net "P5E_PEX2_STN2_TX_DP<36>")
	)
	(segment
		(start 315.220858 -39.897558)
		(end 322.07581 -47.726854)
		(width 0.1651)
		(layer "In11.Cu")
		(net "P5E_PEX2_STN2_TX_DP<36>")
	)
	(segment
		(start 286.483806 -263.41705)
		(end 286.483806 -271.399)
		(width 0.1651)
		(layer "In11.Cu")
		(net "P5E_PEX2_STN2_TX_DP<36>")
	)
	(segment
		(start 308.896512 -30.727142)
		(end 308.896512 -30.852872)
		(width 0.1651)
		(layer "In11.Cu")
		(net "P5E_PEX2_STN2_TX_DP<36>")
	)
	(segment
		(start 321.591686 -64.855598)
		(end 299.356272 -93.902784)
		(width 0.1651)
		(layer "In11.Cu")
		(net "P5E_PEX2_STN2_TX_DP<36>")
	)
	(segment
		(start 287.099756 -280.434288)
		(end 287.099756 -280.699718)
		(width 0.1143)
		(layer "In11.Cu")
		(net "P5E_PEX2_STN2_TX_DP<36>")
	)
	(segment
		(start 299.356272 -93.902784)
		(end 296.17416 -108.054394)
		(width 0.1651)
		(layer "In11.Cu")
		(net "P5E_PEX2_STN2_TX_DP<36>")
	)
	(segment
		(start 286.483806 -271.399)
		(end 286.483806 -271.427448)
		(width 0.1143)
		(layer "In11.Cu")
		(net "P5E_PEX2_STN2_TX_DP<36>")
	)
	(segment
		(start 307.61559 -29.445966)
		(end 308.07025 -29.90088)
		(width 0.1651)
		(layer "In11.Cu")
		(net "P5E_PEX2_STN2_TX_DP<36>")
	)
	(segment
		(start 322.07581 -47.726854)
		(end 323.19214 -58.452766)
		(width 0.1651)
		(layer "In11.Cu")
		(net "P5E_PEX2_STN2_TX_DP<36>")
	)
	(segment
		(start 294.543226 -116.64442)
		(end 294.02532 -120.93321)
		(width 0.1651)
		(layer "In11.Cu")
		(net "P5E_PEX2_STN2_TX_DP<36>")
	)
	(segment
		(start 308.5465 -30.37713)
		(end 308.896512 -30.727142)
		(width 0.1651)
		(layer "In11.Cu")
		(net "P5E_PEX2_STN2_TX_DP<36>")
	)
	(segment
		(start 310.232552 -32.063182)
		(end 315.220858 -39.897558)
		(width 0.1651)
		(layer "In11.Cu")
		(net "P5E_PEX2_STN2_TX_DP<36>")
	)
	(segment
		(start 309.372762 -31.203392)
		(end 310.232552 -32.063182)
		(width 0.1651)
		(layer "In11.Cu")
		(net "P5E_PEX2_STN2_TX_DP<36>")
	)
	(segment
		(start 286.744664 -280.319988)
		(end 286.985456 -280.319988)
		(width 0.1143)
		(layer "In11.Cu")
		(net "P5E_PEX2_STN2_TX_DP<36>")
	)
	(segment
		(start 308.896512 -30.852872)
		(end 309.247032 -31.203392)
		(width 0.1651)
		(layer "In11.Cu")
		(net "P5E_PEX2_STN2_TX_DP<36>")
	)
	(segment
		(start 323.19214 -58.452766)
		(end 323.19214 -60.556902)
		(width 0.1651)
		(layer "In11.Cu")
		(net "P5E_PEX2_STN2_TX_DP<36>")
	)
	(segment
		(start 286.985456 -280.319988)
		(end 287.099756 -280.434288)
		(width 0.1143)
		(layer "In11.Cu")
		(net "P5E_PEX2_STN2_TX_DP<36>")
	)
	(segment
		(start 286.529526 -271.473168)
		(end 286.529526 -280.10485)
		(width 0.1143)
		(layer "In11.Cu")
		(net "P5E_PEX2_STN2_TX_DP<36>")
	)
	(segment
		(start 308.42077 -30.37713)
		(end 308.5465 -30.37713)
		(width 0.1651)
		(layer "In11.Cu")
		(net "P5E_PEX2_STN2_TX_DP<36>")
	)
	(segment
		(start 429.832262 -150.67915)
		(end 429.546512 -150.3934)
		(width 0.13462)
		(layer "F.Cu")
		(net "P5E_PEX3_STN0_TX_DN<12>")
	)
	(segment
		(start 429.546512 -150.3934)
		(end 428.897288 -150.3934)
		(width 0.13462)
		(layer "F.Cu")
		(net "P5E_PEX3_STN0_TX_DN<12>")
	)
	(segment
		(start 428.897288 -150.3934)
		(end 428.586138 -150.70455)
		(width 0.13462)
		(layer "F.Cu")
		(net "P5E_PEX3_STN0_TX_DN<12>")
	)
	(segment
		(start 436.083202 -154.044904)
		(end 434.43906 -151.58466)
		(width 0.1651)
		(layer "In9.Cu")
		(net "P5E_PEX3_STN0_TX_DN<12>")
	)
	(segment
		(start 425.38396 -271.554448)
		(end 425.38396 -271.526)
		(width 0.1143)
		(layer "In9.Cu")
		(net "P5E_PEX3_STN0_TX_DN<12>")
	)
	(segment
		(start 425.644818 -280.319988)
		(end 425.42968 -280.10485)
		(width 0.1143)
		(layer "In9.Cu")
		(net "P5E_PEX3_STN0_TX_DN<12>")
	)
	(segment
		(start 425.72178 -269.301722)
		(end 425.821348 -269.260574)
		(width 0.1651)
		(layer "In9.Cu")
		(net "P5E_PEX3_STN0_TX_DN<12>")
	)
	(segment
		(start 425.38396 -271.526)
		(end 425.38396 -270.316706)
		(width 0.1651)
		(layer "In9.Cu")
		(net "P5E_PEX3_STN0_TX_DN<12>")
	)
	(segment
		(start 426.825156 -177.518314)
		(end 426.862748 -177.088292)
		(width 0.1651)
		(layer "In9.Cu")
		(net "P5E_PEX3_STN0_TX_DN<12>")
	)
	(segment
		(start 425.99991 -280.699718)
		(end 425.99991 -280.434288)
		(width 0.1143)
		(layer "In9.Cu")
		(net "P5E_PEX3_STN0_TX_DN<12>")
	)
	(segment
		(start 433.756816 -150.902416)
		(end 432.516026 -150.38832)
		(width 0.1651)
		(layer "In9.Cu")
		(net "P5E_PEX3_STN0_TX_DN<12>")
	)
	(segment
		(start 426.767498 -178.176428)
		(end 426.663612 -178.05273)
		(width 0.1651)
		(layer "In9.Cu")
		(net "P5E_PEX3_STN0_TX_DN<12>")
	)
	(segment
		(start 425.573444 -269.859252)
		(end 425.532042 -269.759684)
		(width 0.1651)
		(layer "In9.Cu")
		(net "P5E_PEX3_STN0_TX_DN<12>")
	)
	(segment
		(start 426.701204 -177.6222)
		(end 426.825156 -177.518314)
		(width 0.1651)
		(layer "In9.Cu")
		(net "P5E_PEX3_STN0_TX_DN<12>")
	)
	(segment
		(start 432.516026 -150.38832)
		(end 430.123092 -150.38832)
		(width 0.1651)
		(layer "In9.Cu")
		(net "P5E_PEX3_STN0_TX_DN<12>")
	)
	(segment
		(start 426.311568 -268.076934)
		(end 426.311568 -260.829806)
		(width 0.1651)
		(layer "In9.Cu")
		(net "P5E_PEX3_STN0_TX_DN<12>")
	)
	(segment
		(start 424.847512 -200.12406)
		(end 426.767498 -178.176428)
		(width 0.1651)
		(layer "In9.Cu")
		(net "P5E_PEX3_STN0_TX_DN<12>")
	)
	(segment
		(start 426.311568 -260.829806)
		(end 422.924986 -222.097346)
		(width 0.1651)
		(layer "In9.Cu")
		(net "P5E_PEX3_STN0_TX_DN<12>")
	)
	(segment
		(start 425.88561 -280.319988)
		(end 425.644818 -280.319988)
		(width 0.1143)
		(layer "In9.Cu")
		(net "P5E_PEX3_STN0_TX_DN<12>")
	)
	(segment
		(start 430.123092 -150.38832)
		(end 429.832262 -150.67915)
		(width 0.1651)
		(layer "In9.Cu")
		(net "P5E_PEX3_STN0_TX_DN<12>")
	)
	(segment
		(start 428.323248 -171.638976)
		(end 436.576724 -157.341824)
		(width 0.1651)
		(layer "In9.Cu")
		(net "P5E_PEX3_STN0_TX_DN<12>")
	)
	(segment
		(start 425.821348 -269.260574)
		(end 426.311568 -268.076934)
		(width 0.1651)
		(layer "In9.Cu")
		(net "P5E_PEX3_STN0_TX_DN<12>")
	)
	(segment
		(start 425.42968 -280.10485)
		(end 425.42968 -271.600168)
		(width 0.1143)
		(layer "In9.Cu")
		(net "P5E_PEX3_STN0_TX_DN<12>")
	)
	(segment
		(start 425.99991 -280.434288)
		(end 425.88561 -280.319988)
		(width 0.1143)
		(layer "In9.Cu")
		(net "P5E_PEX3_STN0_TX_DN<12>")
	)
	(segment
		(start 426.663612 -178.05273)
		(end 426.701204 -177.6222)
		(width 0.1651)
		(layer "In9.Cu")
		(net "P5E_PEX3_STN0_TX_DN<12>")
	)
	(segment
		(start 436.576724 -155.236926)
		(end 436.083202 -154.044904)
		(width 0.1651)
		(layer "In9.Cu")
		(net "P5E_PEX3_STN0_TX_DN<12>")
	)
	(segment
		(start 422.924986 -222.097346)
		(end 424.847512 -200.12406)
		(width 0.1651)
		(layer "In9.Cu")
		(net "P5E_PEX3_STN0_TX_DN<12>")
	)
	(segment
		(start 425.532042 -269.759684)
		(end 425.72178 -269.301722)
		(width 0.1651)
		(layer "In9.Cu")
		(net "P5E_PEX3_STN0_TX_DN<12>")
	)
	(segment
		(start 434.43906 -151.58466)
		(end 433.756816 -150.902416)
		(width 0.1651)
		(layer "In9.Cu")
		(net "P5E_PEX3_STN0_TX_DN<12>")
	)
	(segment
		(start 425.38396 -270.316706)
		(end 425.573444 -269.859252)
		(width 0.1651)
		(layer "In9.Cu")
		(net "P5E_PEX3_STN0_TX_DN<12>")
	)
	(segment
		(start 425.42968 -271.600168)
		(end 425.38396 -271.554448)
		(width 0.1143)
		(layer "In9.Cu")
		(net "P5E_PEX3_STN0_TX_DN<12>")
	)
	(segment
		(start 426.862748 -177.088292)
		(end 428.323248 -171.638976)
		(width 0.1651)
		(layer "In9.Cu")
		(net "P5E_PEX3_STN0_TX_DN<12>")
	)
	(segment
		(start 436.576724 -157.341824)
		(end 436.576724 -155.236926)
		(width 0.1651)
		(layer "In9.Cu")
		(net "P5E_PEX3_STN0_TX_DN<12>")
	)
	(segment
		(start 416.081464 -343.365074)
		(end 416.081464 -342.734646)
		(width 0.13462)
		(layer "F.Cu")
		(net "P5E_PEX3_STN7_TX_DN<114>")
	)
	(segment
		(start 416.402012 -343.685622)
		(end 416.081464 -343.365074)
		(width 0.13462)
		(layer "F.Cu")
		(net "P5E_PEX3_STN7_TX_DN<114>")
	)
	(segment
		(start 416.081464 -342.734646)
		(end 416.376612 -342.439498)
		(width 0.13462)
		(layer "F.Cu")
		(net "P5E_PEX3_STN7_TX_DN<114>")
	)
	(segment
		(start 383.995168 -303.120044)
		(end 390.176004 -303.120044)
		(width 0.1143)
		(layer "In11.Cu")
		(net "P5E_PEX3_STN7_TX_DN<114>")
	)
	(segment
		(start 373.54764 -307.080412)
		(end 373.822722 -306.668678)
		(width 0.1651)
		(layer "In11.Cu")
		(net "P5E_PEX3_STN7_TX_DN<114>")
	)
	(segment
		(start 415.22142 -340.312502)
		(end 374.133364 -331.130402)
		(width 0.1651)
		(layer "In11.Cu")
		(net "P5E_PEX3_STN7_TX_DN<114>")
	)
	(segment
		(start 366.56264 -322.438522)
		(end 366.56264 -318.88303)
		(width 0.1651)
		(layer "In11.Cu")
		(net "P5E_PEX3_STN7_TX_DN<114>")
	)
	(segment
		(start 372.467886 -308.696614)
		(end 372.626382 -308.664864)
		(width 0.1651)
		(layer "In11.Cu")
		(net "P5E_PEX3_STN7_TX_DN<114>")
	)
	(segment
		(start 373.145304 -307.682646)
		(end 373.3038 -307.650896)
		(width 0.1651)
		(layer "In11.Cu")
		(net "P5E_PEX3_STN7_TX_DN<114>")
	)
	(segment
		(start 373.579136 -307.238908)
		(end 373.54764 -307.080412)
		(width 0.1651)
		(layer "In11.Cu")
		(net "P5E_PEX3_STN7_TX_DN<114>")
	)
	(segment
		(start 375.388632 -305.264312)
		(end 375.388632 -305.102768)
		(width 0.1651)
		(layer "In11.Cu")
		(net "P5E_PEX3_STN7_TX_DN<114>")
	)
	(segment
		(start 372.626382 -308.664864)
		(end 372.901718 -308.252876)
		(width 0.1651)
		(layer "In11.Cu")
		(net "P5E_PEX3_STN7_TX_DN<114>")
	)
	(segment
		(start 383.949448 -303.165764)
		(end 383.995168 -303.120044)
		(width 0.1143)
		(layer "In11.Cu")
		(net "P5E_PEX3_STN7_TX_DN<114>")
	)
	(segment
		(start 372.901718 -308.252876)
		(end 372.870222 -308.09438)
		(width 0.1651)
		(layer "In11.Cu")
		(net "P5E_PEX3_STN7_TX_DN<114>")
	)
	(segment
		(start 378.379736 -303.355248)
		(end 378.83719 -303.165764)
		(width 0.1651)
		(layer "In11.Cu")
		(net "P5E_PEX3_STN7_TX_DN<114>")
	)
	(segment
		(start 369.184936 -313.815222)
		(end 369.460272 -313.403234)
		(width 0.1651)
		(layer "In11.Cu")
		(net "P5E_PEX3_STN7_TX_DN<114>")
	)
	(segment
		(start 368.033046 -315.33338)
		(end 368.349022 -314.860432)
		(width 0.1651)
		(layer "In11.Cu")
		(net "P5E_PEX3_STN7_TX_DN<114>")
	)
	(segment
		(start 378.83719 -303.165764)
		(end 383.921 -303.165764)
		(width 0.1651)
		(layer "In11.Cu")
		(net "P5E_PEX3_STN7_TX_DN<114>")
	)
	(segment
		(start 373.3038 -307.650896)
		(end 373.579136 -307.238908)
		(width 0.1651)
		(layer "In11.Cu")
		(net "P5E_PEX3_STN7_TX_DN<114>")
	)
	(segment
		(start 375.388632 -305.102768)
		(end 376.256804 -304.234596)
		(width 0.1651)
		(layer "In11.Cu")
		(net "P5E_PEX3_STN7_TX_DN<114>")
	)
	(segment
		(start 390.279636 -303.385474)
		(end 390.165336 -303.499774)
		(width 0.1143)
		(layer "In11.Cu")
		(net "P5E_PEX3_STN7_TX_DN<114>")
	)
	(segment
		(start 416.085782 -342.148668)
		(end 416.085782 -341.503)
		(width 0.1651)
		(layer "In11.Cu")
		(net "P5E_PEX3_STN7_TX_DN<114>")
	)
	(segment
		(start 369.460272 -313.403234)
		(end 369.428776 -313.244738)
		(width 0.1651)
		(layer "In11.Cu")
		(net "P5E_PEX3_STN7_TX_DN<114>")
	)
	(segment
		(start 373.822722 -306.668678)
		(end 374.876568 -305.614832)
		(width 0.1651)
		(layer "In11.Cu")
		(net "P5E_PEX3_STN7_TX_DN<114>")
	)
	(segment
		(start 374.876568 -305.614832)
		(end 375.038112 -305.614832)
		(width 0.1651)
		(layer "In11.Cu")
		(net "P5E_PEX3_STN7_TX_DN<114>")
	)
	(segment
		(start 368.349022 -314.860432)
		(end 368.507518 -314.828936)
		(width 0.1651)
		(layer "In11.Cu")
		(net "P5E_PEX3_STN7_TX_DN<114>")
	)
	(segment
		(start 390.165336 -303.499774)
		(end 389.899906 -303.499774)
		(width 0.1143)
		(layer "In11.Cu")
		(net "P5E_PEX3_STN7_TX_DN<114>")
	)
	(segment
		(start 366.56264 -318.88303)
		(end 368.033046 -315.33338)
		(width 0.1651)
		(layer "In11.Cu")
		(net "P5E_PEX3_STN7_TX_DN<114>")
	)
	(segment
		(start 369.428776 -313.244738)
		(end 372.467886 -308.696614)
		(width 0.1651)
		(layer "In11.Cu")
		(net "P5E_PEX3_STN7_TX_DN<114>")
	)
	(segment
		(start 375.038112 -305.614832)
		(end 375.388632 -305.264312)
		(width 0.1651)
		(layer "In11.Cu")
		(net "P5E_PEX3_STN7_TX_DN<114>")
	)
	(segment
		(start 390.279636 -303.223676)
		(end 390.279636 -303.385474)
		(width 0.1143)
		(layer "In11.Cu")
		(net "P5E_PEX3_STN7_TX_DN<114>")
	)
	(segment
		(start 377.7107 -303.632362)
		(end 377.860052 -303.694338)
		(width 0.1651)
		(layer "In11.Cu")
		(net "P5E_PEX3_STN7_TX_DN<114>")
	)
	(segment
		(start 390.176004 -303.120044)
		(end 390.279636 -303.223676)
		(width 0.1143)
		(layer "In11.Cu")
		(net "P5E_PEX3_STN7_TX_DN<114>")
	)
	(segment
		(start 383.921 -303.165764)
		(end 383.949448 -303.165764)
		(width 0.1143)
		(layer "In11.Cu")
		(net "P5E_PEX3_STN7_TX_DN<114>")
	)
	(segment
		(start 368.399568 -326.872854)
		(end 366.56264 -322.438522)
		(width 0.1651)
		(layer "In11.Cu")
		(net "P5E_PEX3_STN7_TX_DN<114>")
	)
	(segment
		(start 370.854224 -329.327764)
		(end 368.399568 -326.873108)
		(width 0.1651)
		(layer "In11.Cu")
		(net "P5E_PEX3_STN7_TX_DN<114>")
	)
	(segment
		(start 378.31776 -303.504854)
		(end 378.379736 -303.355248)
		(width 0.1651)
		(layer "In11.Cu")
		(net "P5E_PEX3_STN7_TX_DN<114>")
	)
	(segment
		(start 368.507518 -314.828936)
		(end 368.782854 -314.416948)
		(width 0.1651)
		(layer "In11.Cu")
		(net "P5E_PEX3_STN7_TX_DN<114>")
	)
	(segment
		(start 374.133364 -331.130402)
		(end 370.854224 -329.327764)
		(width 0.1651)
		(layer "In11.Cu")
		(net "P5E_PEX3_STN7_TX_DN<114>")
	)
	(segment
		(start 368.782854 -314.416948)
		(end 368.751358 -314.258452)
		(width 0.1651)
		(layer "In11.Cu")
		(net "P5E_PEX3_STN7_TX_DN<114>")
	)
	(segment
		(start 368.399568 -326.873108)
		(end 368.399568 -326.872854)
		(width 0.1651)
		(layer "In11.Cu")
		(net "P5E_PEX3_STN7_TX_DN<114>")
	)
	(segment
		(start 368.751358 -314.258452)
		(end 369.02644 -313.846718)
		(width 0.1651)
		(layer "In11.Cu")
		(net "P5E_PEX3_STN7_TX_DN<114>")
	)
	(segment
		(start 369.02644 -313.846718)
		(end 369.184936 -313.815222)
		(width 0.1651)
		(layer "In11.Cu")
		(net "P5E_PEX3_STN7_TX_DN<114>")
	)
	(segment
		(start 416.085782 -341.503)
		(end 415.22142 -340.312502)
		(width 0.1651)
		(layer "In11.Cu")
		(net "P5E_PEX3_STN7_TX_DN<114>")
	)
	(segment
		(start 376.256804 -304.234596)
		(end 377.7107 -303.632362)
		(width 0.1651)
		(layer "In11.Cu")
		(net "P5E_PEX3_STN7_TX_DN<114>")
	)
	(segment
		(start 377.860052 -303.694338)
		(end 378.31776 -303.504854)
		(width 0.1651)
		(layer "In11.Cu")
		(net "P5E_PEX3_STN7_TX_DN<114>")
	)
	(segment
		(start 416.376612 -342.439498)
		(end 416.085782 -342.148668)
		(width 0.1651)
		(layer "In11.Cu")
		(net "P5E_PEX3_STN7_TX_DN<114>")
	)
	(segment
		(start 372.870222 -308.09438)
		(end 373.145304 -307.682646)
		(width 0.1651)
		(layer "In11.Cu")
		(net "P5E_PEX3_STN7_TX_DN<114>")
	)
	(segment
		(start 51.285648 -351.611438)
		(end 50.991008 -351.316798)
		(width 0.13462)
		(layer "F.Cu")
		(net "P5E_PEX0_STN7_TX_C_DN<127>")
	)
	(segment
		(start 50.991008 -351.316798)
		(end 50.991008 -350.685354)
		(width 0.13462)
		(layer "F.Cu")
		(net "P5E_PEX0_STN7_TX_C_DN<127>")
	)
	(segment
		(start 50.991008 -350.685354)
		(end 51.311048 -350.365314)
		(width 0.13462)
		(layer "F.Cu")
		(net "P5E_PEX0_STN7_TX_C_DN<127>")
	)
	(segment
		(start 43.310048 -376.408188)
		(end 43.437048 -376.281188)
		(width 0.1651)
		(layer "In7.Cu")
		(net "P5E_PEX0_STN7_TX_C_DN<127>")
	)
	(segment
		(start 50.994818 -352.552762)
		(end 50.994818 -351.902268)
		(width 0.1651)
		(layer "In7.Cu")
		(net "P5E_PEX0_STN7_TX_C_DN<127>")
	)
	(segment
		(start 50.994818 -351.902268)
		(end 51.285648 -351.611438)
		(width 0.1651)
		(layer "In7.Cu")
		(net "P5E_PEX0_STN7_TX_C_DN<127>")
	)
	(segment
		(start 43.310048 -376.790204)
		(end 43.310048 -376.408188)
		(width 0.1651)
		(layer "In7.Cu")
		(net "P5E_PEX0_STN7_TX_C_DN<127>")
	)
	(segment
		(start 45.34789 -365.906812)
		(end 49.440338 -358.250744)
		(width 0.1651)
		(layer "In7.Cu")
		(net "P5E_PEX0_STN7_TX_C_DN<127>")
	)
	(segment
		(start 49.440338 -358.250744)
		(end 49.440338 -354.107242)
		(width 0.1651)
		(layer "In7.Cu")
		(net "P5E_PEX0_STN7_TX_C_DN<127>")
	)
	(segment
		(start 49.440338 -354.107242)
		(end 50.994818 -352.552762)
		(width 0.1651)
		(layer "In7.Cu")
		(net "P5E_PEX0_STN7_TX_C_DN<127>")
	)
	(segment
		(start 44.169584 -376.281188)
		(end 44.48429 -375.966482)
		(width 0.1651)
		(layer "In7.Cu")
		(net "P5E_PEX0_STN7_TX_C_DN<127>")
	)
	(segment
		(start 44.48429 -369.354608)
		(end 45.34789 -365.906812)
		(width 0.1651)
		(layer "In7.Cu")
		(net "P5E_PEX0_STN7_TX_C_DN<127>")
	)
	(segment
		(start 43.437048 -376.281188)
		(end 44.169584 -376.281188)
		(width 0.1651)
		(layer "In7.Cu")
		(net "P5E_PEX0_STN7_TX_C_DN<127>")
	)
	(segment
		(start 44.48429 -375.966482)
		(end 44.48429 -369.354608)
		(width 0.1651)
		(layer "In7.Cu")
		(net "P5E_PEX0_STN7_TX_C_DN<127>")
	)
	(segment
		(start 61.666882 -349.511874)
		(end 61.666882 -348.88043)
		(width 0.13462)
		(layer "F.Cu")
		(net "P5E_PEX0_STN5_TX_DP<80>")
	)
	(segment
		(start 61.346842 -349.831914)
		(end 61.666882 -349.511874)
		(width 0.13462)
		(layer "F.Cu")
		(net "P5E_PEX0_STN5_TX_DP<80>")
	)
	(segment
		(start 61.666882 -348.88043)
		(end 61.372242 -348.58579)
		(width 0.13462)
		(layer "F.Cu")
		(net "P5E_PEX0_STN5_TX_DP<80>")
	)
	(segment
		(start 61.372242 -348.58579)
		(end 61.663072 -348.29496)
		(width 0.1651)
		(layer "In7.Cu")
		(net "P5E_PEX0_STN5_TX_DP<80>")
	)
	(segment
		(start 58.355484 -311.479692)
		(end 58.585608 -311.479692)
		(width 0.1143)
		(layer "In7.Cu")
		(net "P5E_PEX0_STN5_TX_DP<80>")
	)
	(segment
		(start 60.37707 -346.48902)
		(end 59.859164 -345.394788)
		(width 0.1651)
		(layer "In7.Cu")
		(net "P5E_PEX0_STN5_TX_DP<80>")
	)
	(segment
		(start 59.859164 -345.394788)
		(end 58.083958 -327.36917)
		(width 0.1651)
		(layer "In7.Cu")
		(net "P5E_PEX0_STN5_TX_DP<80>")
	)
	(segment
		(start 58.129678 -311.705498)
		(end 58.355484 -311.479692)
		(width 0.1143)
		(layer "In7.Cu")
		(net "P5E_PEX0_STN5_TX_DP<80>")
	)
	(segment
		(start 58.083958 -319.8622)
		(end 58.129678 -319.81648)
		(width 0.1143)
		(layer "In7.Cu")
		(net "P5E_PEX0_STN5_TX_DP<80>")
	)
	(segment
		(start 58.585608 -311.479692)
		(end 58.699908 -311.365392)
		(width 0.1143)
		(layer "In7.Cu")
		(net "P5E_PEX0_STN5_TX_DP<80>")
	)
	(segment
		(start 61.663072 -347.775022)
		(end 60.37707 -346.48902)
		(width 0.1651)
		(layer "In7.Cu")
		(net "P5E_PEX0_STN5_TX_DP<80>")
	)
	(segment
		(start 58.083958 -319.890648)
		(end 58.083958 -319.8622)
		(width 0.1143)
		(layer "In7.Cu")
		(net "P5E_PEX0_STN5_TX_DP<80>")
	)
	(segment
		(start 61.663072 -348.29496)
		(end 61.663072 -347.775022)
		(width 0.1651)
		(layer "In7.Cu")
		(net "P5E_PEX0_STN5_TX_DP<80>")
	)
	(segment
		(start 58.129678 -319.81648)
		(end 58.129678 -311.705498)
		(width 0.1143)
		(layer "In7.Cu")
		(net "P5E_PEX0_STN5_TX_DP<80>")
	)
	(segment
		(start 58.083958 -327.36917)
		(end 58.083958 -319.890648)
		(width 0.1651)
		(layer "In7.Cu")
		(net "P5E_PEX0_STN5_TX_DP<80>")
	)
	(segment
		(start 58.699908 -311.365392)
		(end 58.699908 -311.099962)
		(width 0.1143)
		(layer "In7.Cu")
		(net "P5E_PEX0_STN5_TX_DP<80>")
	)
	(segment
		(start 215.752426 -33.95218)
		(end 215.12149 -33.95218)
		(width 0.13462)
		(layer "F.Cu")
		(net "P5E_PEX1_STN2_TX_DN<35>")
	)
	(segment
		(start 216.04732 -33.657286)
		(end 215.752426 -33.95218)
		(width 0.13462)
		(layer "F.Cu")
		(net "P5E_PEX1_STN2_TX_DN<35>")
	)
	(segment
		(start 215.12149 -33.95218)
		(end 214.801196 -33.631886)
		(width 0.13462)
		(layer "F.Cu")
		(net "P5E_PEX1_STN2_TX_DN<35>")
	)
	(segment
		(start 217.021664 -33.948116)
		(end 217.503502 -34.082736)
		(width 0.1651)
		(layer "In11.Cu")
		(net "P5E_PEX1_STN2_TX_DN<35>")
	)
	(segment
		(start 171.615862 -265.478768)
		(end 171.615862 -271.399)
		(width 0.1651)
		(layer "In11.Cu")
		(net "P5E_PEX1_STN2_TX_DN<35>")
	)
	(segment
		(start 222.355156 -42.785538)
		(end 222.584518 -56.765698)
		(width 0.1651)
		(layer "In11.Cu")
		(net "P5E_PEX1_STN2_TX_DN<35>")
	)
	(segment
		(start 171.949872 -278.115268)
		(end 171.949872 -277.849838)
		(width 0.1143)
		(layer "In11.Cu")
		(net "P5E_PEX1_STN2_TX_DN<35>")
	)
	(segment
		(start 216.04732 -33.657286)
		(end 216.242392 -33.852358)
		(width 0.1651)
		(layer "In11.Cu")
		(net "P5E_PEX1_STN2_TX_DN<35>")
	)
	(segment
		(start 192.932812 -131.103624)
		(end 192.932812 -139.897866)
		(width 0.1651)
		(layer "In11.Cu")
		(net "P5E_PEX1_STN2_TX_DN<35>")
	)
	(segment
		(start 217.503502 -34.082736)
		(end 218.04503 -34.57829)
		(width 0.1651)
		(layer "In11.Cu")
		(net "P5E_PEX1_STN2_TX_DN<35>")
	)
	(segment
		(start 216.473786 -33.948116)
		(end 217.021664 -33.948116)
		(width 0.1651)
		(layer "In11.Cu")
		(net "P5E_PEX1_STN2_TX_DN<35>")
	)
	(segment
		(start 171.835572 -278.229568)
		(end 171.949872 -278.115268)
		(width 0.1143)
		(layer "In11.Cu")
		(net "P5E_PEX1_STN2_TX_DN<35>")
	)
	(segment
		(start 171.615862 -271.399)
		(end 171.615862 -271.427448)
		(width 0.1143)
		(layer "In11.Cu")
		(net "P5E_PEX1_STN2_TX_DN<35>")
	)
	(segment
		(start 216.170002 -74.235564)
		(end 211.466684 -77.950314)
		(width 0.1651)
		(layer "In11.Cu")
		(net "P5E_PEX1_STN2_TX_DN<35>")
	)
	(segment
		(start 211.466684 -77.950314)
		(end 209.289142 -80.13319)
		(width 0.1651)
		(layer "In11.Cu")
		(net "P5E_PEX1_STN2_TX_DN<35>")
	)
	(segment
		(start 190.72479 -161.53003)
		(end 171.615862 -265.478768)
		(width 0.1651)
		(layer "In11.Cu")
		(net "P5E_PEX1_STN2_TX_DN<35>")
	)
	(segment
		(start 192.494154 -141.7955)
		(end 192.18783 -149.256242)
		(width 0.1651)
		(layer "In11.Cu")
		(net "P5E_PEX1_STN2_TX_DN<35>")
	)
	(segment
		(start 193.461894 -118.211854)
		(end 192.932812 -131.103624)
		(width 0.1651)
		(layer "In11.Cu")
		(net "P5E_PEX1_STN2_TX_DN<35>")
	)
	(segment
		(start 220.435678 -67.91071)
		(end 216.170002 -74.235564)
		(width 0.1651)
		(layer "In11.Cu")
		(net "P5E_PEX1_STN2_TX_DN<35>")
	)
	(segment
		(start 195.160138 -105.014776)
		(end 193.461894 -118.211854)
		(width 0.1651)
		(layer "In11.Cu")
		(net "P5E_PEX1_STN2_TX_DN<35>")
	)
	(segment
		(start 171.673774 -278.229568)
		(end 171.835572 -278.229568)
		(width 0.1143)
		(layer "In11.Cu")
		(net "P5E_PEX1_STN2_TX_DN<35>")
	)
	(segment
		(start 209.289142 -80.13319)
		(end 195.160138 -105.014776)
		(width 0.1651)
		(layer "In11.Cu")
		(net "P5E_PEX1_STN2_TX_DN<35>")
	)
	(segment
		(start 222.584518 -56.765698)
		(end 220.435678 -67.91071)
		(width 0.1651)
		(layer "In11.Cu")
		(net "P5E_PEX1_STN2_TX_DN<35>")
	)
	(segment
		(start 218.04503 -34.57829)
		(end 222.258636 -42.414952)
		(width 0.1651)
		(layer "In11.Cu")
		(net "P5E_PEX1_STN2_TX_DN<35>")
	)
	(segment
		(start 192.18783 -149.256242)
		(end 190.72479 -161.53003)
		(width 0.1651)
		(layer "In11.Cu")
		(net "P5E_PEX1_STN2_TX_DN<35>")
	)
	(segment
		(start 216.242392 -33.852358)
		(end 216.473786 -33.948116)
		(width 0.1651)
		(layer "In11.Cu")
		(net "P5E_PEX1_STN2_TX_DN<35>")
	)
	(segment
		(start 192.932812 -139.897866)
		(end 192.494154 -141.7955)
		(width 0.1651)
		(layer "In11.Cu")
		(net "P5E_PEX1_STN2_TX_DN<35>")
	)
	(segment
		(start 171.570142 -278.125936)
		(end 171.673774 -278.229568)
		(width 0.1143)
		(layer "In11.Cu")
		(net "P5E_PEX1_STN2_TX_DN<35>")
	)
	(segment
		(start 171.615862 -271.427448)
		(end 171.570142 -271.473168)
		(width 0.1143)
		(layer "In11.Cu")
		(net "P5E_PEX1_STN2_TX_DN<35>")
	)
	(segment
		(start 222.258636 -42.414952)
		(end 222.355156 -42.785538)
		(width 0.1651)
		(layer "In11.Cu")
		(net "P5E_PEX1_STN2_TX_DN<35>")
	)
	(segment
		(start 171.570142 -271.473168)
		(end 171.570142 -278.125936)
		(width 0.1143)
		(layer "In11.Cu")
		(net "P5E_PEX1_STN2_TX_DN<35>")
	)
	(segment
		(start 280.147268 -30.05709)
		(end 279.851358 -30.353)
		(width 0.13462)
		(layer "F.Cu")
		(net "P5E_PEX2_STN2_TX_DN<41>")
	)
	(segment
		(start 279.222454 -30.353)
		(end 278.901144 -30.03169)
		(width 0.13462)
		(layer "F.Cu")
		(net "P5E_PEX2_STN2_TX_DN<41>")
	)
	(segment
		(start 279.851358 -30.353)
		(end 279.222454 -30.353)
		(width 0.13462)
		(layer "F.Cu")
		(net "P5E_PEX2_STN2_TX_DN<41>")
	)
	(segment
		(start 289.000946 -119.31269)
		(end 287.671764 -135.163052)
		(width 0.1651)
		(layer "In11.Cu")
		(net "P5E_PEX2_STN2_TX_DN<41>")
	)
	(segment
		(start 285.227522 -35.26917)
		(end 295.123108 -48.058832)
		(width 0.1651)
		(layer "In11.Cu")
		(net "P5E_PEX2_STN2_TX_DN<41>")
	)
	(segment
		(start 282.015692 -269.827756)
		(end 282.015692 -271.399)
		(width 0.1651)
		(layer "In11.Cu")
		(net "P5E_PEX2_STN2_TX_DN<41>")
	)
	(segment
		(start 280.888694 -30.34792)
		(end 281.319478 -30.525212)
		(width 0.1651)
		(layer "In11.Cu")
		(net "P5E_PEX2_STN2_TX_DN<41>")
	)
	(segment
		(start 282.349702 -278.115268)
		(end 282.349702 -277.849838)
		(width 0.1143)
		(layer "In11.Cu")
		(net "P5E_PEX2_STN2_TX_DN<41>")
	)
	(segment
		(start 283.888942 -33.072578)
		(end 285.227522 -35.26917)
		(width 0.1651)
		(layer "In11.Cu")
		(net "P5E_PEX2_STN2_TX_DN<41>")
	)
	(segment
		(start 282.073604 -278.229568)
		(end 282.235402 -278.229568)
		(width 0.1143)
		(layer "In11.Cu")
		(net "P5E_PEX2_STN2_TX_DN<41>")
	)
	(segment
		(start 296.472102 -60.550298)
		(end 295.959022 -69.628766)
		(width 0.1651)
		(layer "In11.Cu")
		(net "P5E_PEX2_STN2_TX_DN<41>")
	)
	(segment
		(start 281.969972 -278.125936)
		(end 282.073604 -278.229568)
		(width 0.1143)
		(layer "In11.Cu")
		(net "P5E_PEX2_STN2_TX_DN<41>")
	)
	(segment
		(start 295.123108 -48.058832)
		(end 295.818052 -50.066194)
		(width 0.1651)
		(layer "In11.Cu")
		(net "P5E_PEX2_STN2_TX_DN<41>")
	)
	(segment
		(start 295.959022 -69.628766)
		(end 289.000946 -119.31269)
		(width 0.1651)
		(layer "In11.Cu")
		(net "P5E_PEX2_STN2_TX_DN<41>")
	)
	(segment
		(start 295.818052 -50.066194)
		(end 296.472102 -60.550298)
		(width 0.1651)
		(layer "In11.Cu")
		(net "P5E_PEX2_STN2_TX_DN<41>")
	)
	(segment
		(start 282.015692 -271.427448)
		(end 281.969972 -271.473168)
		(width 0.1143)
		(layer "In11.Cu")
		(net "P5E_PEX2_STN2_TX_DN<41>")
	)
	(segment
		(start 280.147268 -30.05709)
		(end 280.438098 -30.34792)
		(width 0.1651)
		(layer "In11.Cu")
		(net "P5E_PEX2_STN2_TX_DN<41>")
	)
	(segment
		(start 281.651456 -266.126976)
		(end 282.015692 -269.827756)
		(width 0.1651)
		(layer "In11.Cu")
		(net "P5E_PEX2_STN2_TX_DN<41>")
	)
	(segment
		(start 281.969972 -271.473168)
		(end 281.969972 -278.125936)
		(width 0.1143)
		(layer "In11.Cu")
		(net "P5E_PEX2_STN2_TX_DN<41>")
	)
	(segment
		(start 281.299666 -252.662436)
		(end 281.651456 -266.126976)
		(width 0.1651)
		(layer "In11.Cu")
		(net "P5E_PEX2_STN2_TX_DN<41>")
	)
	(segment
		(start 281.319478 -30.525212)
		(end 283.888942 -33.072578)
		(width 0.1651)
		(layer "In11.Cu")
		(net "P5E_PEX2_STN2_TX_DN<41>")
	)
	(segment
		(start 282.015692 -271.399)
		(end 282.015692 -271.427448)
		(width 0.1143)
		(layer "In11.Cu")
		(net "P5E_PEX2_STN2_TX_DN<41>")
	)
	(segment
		(start 282.235402 -278.229568)
		(end 282.349702 -278.115268)
		(width 0.1143)
		(layer "In11.Cu")
		(net "P5E_PEX2_STN2_TX_DN<41>")
	)
	(segment
		(start 287.671764 -135.163052)
		(end 281.299666 -252.662436)
		(width 0.1651)
		(layer "In11.Cu")
		(net "P5E_PEX2_STN2_TX_DN<41>")
	)
	(segment
		(start 280.438098 -30.34792)
		(end 280.888694 -30.34792)
		(width 0.1651)
		(layer "In11.Cu")
		(net "P5E_PEX2_STN2_TX_DN<41>")
	)
	(segment
		(start 432.185318 -121.07672)
		(end 431.542698 -121.07672)
		(width 0.13462)
		(layer "F.Cu")
		(net "P5E_PEX3_STN0_TX_DP<1>")
	)
	(segment
		(start 431.542698 -121.07672)
		(end 431.228246 -121.391172)
		(width 0.13462)
		(layer "F.Cu")
		(net "P5E_PEX3_STN0_TX_DP<1>")
	)
	(segment
		(start 432.47437 -121.365772)
		(end 432.185318 -121.07672)
		(width 0.13462)
		(layer "F.Cu")
		(net "P5E_PEX3_STN0_TX_DP<1>")
	)
	(segment
		(start 436.995824 -285.443422)
		(end 433.881022 -286.733742)
		(width 0.1651)
		(layer "In9.Cu")
		(net "P5E_PEX3_STN0_TX_DP<1>")
	)
	(segment
		(start 437.443118 -129.282698)
		(end 437.388254 -129.41554)
		(width 0.1651)
		(layer "In9.Cu")
		(net "P5E_PEX3_STN0_TX_DP<1>")
	)
	(segment
		(start 435.73192 -125.15215)
		(end 435.677056 -125.284738)
		(width 0.1651)
		(layer "In9.Cu")
		(net "P5E_PEX3_STN0_TX_DP<1>")
	)
	(segment
		(start 436.412894 -126.795022)
		(end 436.41264 -126.795022)
		(width 0.1651)
		(layer "In9.Cu")
		(net "P5E_PEX3_STN0_TX_DP<1>")
	)
	(segment
		(start 436.162704 -249.726958)
		(end 446.069212 -264.552176)
		(width 0.1651)
		(layer "In9.Cu")
		(net "P5E_PEX3_STN0_TX_DP<1>")
	)
	(segment
		(start 435.852062 -125.707394)
		(end 435.985158 -125.762512)
		(width 0.1651)
		(layer "In9.Cu")
		(net "P5E_PEX3_STN0_TX_DP<1>")
	)
	(segment
		(start 423.529506 -287.235646)
		(end 423.415206 -287.349946)
		(width 0.1143)
		(layer "In9.Cu")
		(net "P5E_PEX3_STN0_TX_DP<1>")
	)
	(segment
		(start 438.337452 -175.723042)
		(end 437.426608 -179.117498)
		(width 0.1651)
		(layer "In9.Cu")
		(net "P5E_PEX3_STN0_TX_DP<1>")
	)
	(segment
		(start 447.742564 -272.553176)
		(end 446.2272 -276.212046)
		(width 0.1651)
		(layer "In9.Cu")
		(net "P5E_PEX3_STN0_TX_DP<1>")
	)
	(segment
		(start 436.84063 -127.827786)
		(end 437.015382 -128.249934)
		(width 0.1651)
		(layer "In9.Cu")
		(net "P5E_PEX3_STN0_TX_DP<1>")
	)
	(segment
		(start 423.529506 -286.994854)
		(end 423.529506 -287.235646)
		(width 0.1143)
		(layer "In9.Cu")
		(net "P5E_PEX3_STN0_TX_DP<1>")
	)
	(segment
		(start 436.159656 -126.18466)
		(end 436.104792 -126.317502)
		(width 0.1651)
		(layer "In9.Cu")
		(net "P5E_PEX3_STN0_TX_DP<1>")
	)
	(segment
		(start 436.104792 -126.317502)
		(end 436.279798 -126.740158)
		(width 0.1651)
		(layer "In9.Cu")
		(net "P5E_PEX3_STN0_TX_DP<1>")
	)
	(segment
		(start 438.617106 -131.734306)
		(end 447.221864 -152.507442)
		(width 0.1651)
		(layer "In9.Cu")
		(net "P5E_PEX3_STN0_TX_DP<1>")
	)
	(segment
		(start 432.119532 -286.779462)
		(end 423.744898 -286.779462)
		(width 0.1143)
		(layer "In9.Cu")
		(net "P5E_PEX3_STN0_TX_DP<1>")
	)
	(segment
		(start 435.984904 -125.762512)
		(end 436.159656 -126.18466)
		(width 0.1651)
		(layer "In9.Cu")
		(net "P5E_PEX3_STN0_TX_DP<1>")
	)
	(segment
		(start 432.47437 -121.365772)
		(end 432.7652 -121.074942)
		(width 0.1651)
		(layer "In9.Cu")
		(net "P5E_PEX3_STN0_TX_DP<1>")
	)
	(segment
		(start 436.532782 -127.350012)
		(end 436.707788 -127.772668)
		(width 0.1651)
		(layer "In9.Cu")
		(net "P5E_PEX3_STN0_TX_DP<1>")
	)
	(segment
		(start 434.233828 -121.991882)
		(end 434.556916 -122.31497)
		(width 0.1651)
		(layer "In9.Cu")
		(net "P5E_PEX3_STN0_TX_DP<1>")
	)
	(segment
		(start 436.960518 -128.382776)
		(end 437.135524 -128.805432)
		(width 0.1651)
		(layer "In9.Cu")
		(net "P5E_PEX3_STN0_TX_DP<1>")
	)
	(segment
		(start 433.766468 -121.524522)
		(end 433.766468 -121.668286)
		(width 0.1651)
		(layer "In9.Cu")
		(net "P5E_PEX3_STN0_TX_DP<1>")
	)
	(segment
		(start 436.587646 -127.21717)
		(end 436.532782 -127.350012)
		(width 0.1651)
		(layer "In9.Cu")
		(net "P5E_PEX3_STN0_TX_DP<1>")
	)
	(segment
		(start 438.34685 -131.463796)
		(end 438.61736 -131.734306)
		(width 0.1651)
		(layer "In9.Cu")
		(net "P5E_PEX3_STN0_TX_DP<1>")
	)
	(segment
		(start 433.766468 -121.668286)
		(end 434.090064 -121.991882)
		(width 0.1651)
		(layer "In9.Cu")
		(net "P5E_PEX3_STN0_TX_DP<1>")
	)
	(segment
		(start 447.221864 -152.507442)
		(end 447.221864 -159.802068)
		(width 0.1651)
		(layer "In9.Cu")
		(net "P5E_PEX3_STN0_TX_DP<1>")
	)
	(segment
		(start 436.707788 -127.772668)
		(end 436.84063 -127.827786)
		(width 0.1651)
		(layer "In9.Cu")
		(net "P5E_PEX3_STN0_TX_DP<1>")
	)
	(segment
		(start 437.268366 -128.86055)
		(end 437.443118 -129.282698)
		(width 0.1651)
		(layer "In9.Cu")
		(net "P5E_PEX3_STN0_TX_DP<1>")
	)
	(segment
		(start 434.090064 -121.991882)
		(end 434.233828 -121.991882)
		(width 0.1651)
		(layer "In9.Cu")
		(net "P5E_PEX3_STN0_TX_DP<1>")
	)
	(segment
		(start 437.135524 -128.805432)
		(end 437.268366 -128.86055)
		(width 0.1651)
		(layer "In9.Cu")
		(net "P5E_PEX3_STN0_TX_DP<1>")
	)
	(segment
		(start 436.279798 -126.740158)
		(end 436.412894 -126.795022)
		(width 0.1651)
		(layer "In9.Cu")
		(net "P5E_PEX3_STN0_TX_DP<1>")
	)
	(segment
		(start 434.676804 -122.86996)
		(end 434.85181 -123.292616)
		(width 0.1651)
		(layer "In9.Cu")
		(net "P5E_PEX3_STN0_TX_DP<1>")
	)
	(segment
		(start 437.015382 -128.249934)
		(end 436.960518 -128.382776)
		(width 0.1651)
		(layer "In9.Cu")
		(net "P5E_PEX3_STN0_TX_DP<1>")
	)
	(segment
		(start 437.388254 -129.41554)
		(end 437.56326 -129.838196)
		(width 0.1651)
		(layer "In9.Cu")
		(net "P5E_PEX3_STN0_TX_DP<1>")
	)
	(segment
		(start 423.415206 -287.349946)
		(end 423.149776 -287.349946)
		(width 0.1143)
		(layer "In9.Cu")
		(net "P5E_PEX3_STN0_TX_DP<1>")
	)
	(segment
		(start 446.069212 -264.552176)
		(end 446.685924 -266.04087)
		(width 0.1651)
		(layer "In9.Cu")
		(net "P5E_PEX3_STN0_TX_DP<1>")
	)
	(segment
		(start 446.685924 -266.04087)
		(end 447.302636 -267.52931)
		(width 0.1651)
		(layer "In9.Cu")
		(net "P5E_PEX3_STN0_TX_DP<1>")
	)
	(segment
		(start 432.1937 -286.733742)
		(end 432.165252 -286.733742)
		(width 0.1143)
		(layer "In9.Cu")
		(net "P5E_PEX3_STN0_TX_DP<1>")
	)
	(segment
		(start 436.587392 -127.21717)
		(end 436.587646 -127.21717)
		(width 0.1651)
		(layer "In9.Cu")
		(net "P5E_PEX3_STN0_TX_DP<1>")
	)
	(segment
		(start 432.165252 -286.733742)
		(end 432.119532 -286.779462)
		(width 0.1143)
		(layer "In9.Cu")
		(net "P5E_PEX3_STN0_TX_DP<1>")
	)
	(segment
		(start 447.302636 -267.52931)
		(end 447.742564 -272.553176)
		(width 0.1651)
		(layer "In9.Cu")
		(net "P5E_PEX3_STN0_TX_DP<1>")
	)
	(segment
		(start 433.881022 -286.733742)
		(end 432.1937 -286.733742)
		(width 0.1651)
		(layer "In9.Cu")
		(net "P5E_PEX3_STN0_TX_DP<1>")
	)
	(segment
		(start 446.960498 -160.780222)
		(end 438.337452 -175.723042)
		(width 0.1651)
		(layer "In9.Cu")
		(net "P5E_PEX3_STN0_TX_DP<1>")
	)
	(segment
		(start 437.56326 -129.838196)
		(end 437.696356 -129.89306)
		(width 0.1651)
		(layer "In9.Cu")
		(net "P5E_PEX3_STN0_TX_DP<1>")
	)
	(segment
		(start 447.221864 -159.802068)
		(end 446.960498 -160.780222)
		(width 0.1651)
		(layer "In9.Cu")
		(net "P5E_PEX3_STN0_TX_DP<1>")
	)
	(segment
		(start 423.744898 -286.779462)
		(end 423.529506 -286.994854)
		(width 0.1143)
		(layer "In9.Cu")
		(net "P5E_PEX3_STN0_TX_DP<1>")
	)
	(segment
		(start 434.85181 -123.292616)
		(end 434.984652 -123.347734)
		(width 0.1651)
		(layer "In9.Cu")
		(net "P5E_PEX3_STN0_TX_DP<1>")
	)
	(segment
		(start 433.711096 -221.635828)
		(end 433.71135 -221.635828)
		(width 0.1651)
		(layer "In9.Cu")
		(net "P5E_PEX3_STN0_TX_DP<1>")
	)
	(segment
		(start 432.7652 -121.074942)
		(end 433.316888 -121.074942)
		(width 0.1651)
		(layer "In9.Cu")
		(net "P5E_PEX3_STN0_TX_DP<1>")
	)
	(segment
		(start 433.709064 -221.611444)
		(end 433.711096 -221.635828)
		(width 0.1651)
		(layer "In9.Cu")
		(net "P5E_PEX3_STN0_TX_DP<1>")
	)
	(segment
		(start 436.41264 -126.795022)
		(end 436.587392 -127.21717)
		(width 0.1651)
		(layer "In9.Cu")
		(net "P5E_PEX3_STN0_TX_DP<1>")
	)
	(segment
		(start 435.985158 -125.762512)
		(end 435.984904 -125.762512)
		(width 0.1651)
		(layer "In9.Cu")
		(net "P5E_PEX3_STN0_TX_DP<1>")
	)
	(segment
		(start 437.696102 -129.89306)
		(end 438.34685 -131.463796)
		(width 0.1651)
		(layer "In9.Cu")
		(net "P5E_PEX3_STN0_TX_DP<1>")
	)
	(segment
		(start 438.61736 -131.734306)
		(end 438.617106 -131.734306)
		(width 0.1651)
		(layer "In9.Cu")
		(net "P5E_PEX3_STN0_TX_DP<1>")
	)
	(segment
		(start 433.71135 -221.635828)
		(end 436.162704 -249.726958)
		(width 0.1651)
		(layer "In9.Cu")
		(net "P5E_PEX3_STN0_TX_DP<1>")
	)
	(segment
		(start 435.677056 -125.284738)
		(end 435.852062 -125.707394)
		(width 0.1651)
		(layer "In9.Cu")
		(net "P5E_PEX3_STN0_TX_DP<1>")
	)
	(segment
		(start 433.316888 -121.074942)
		(end 433.766468 -121.524522)
		(width 0.1651)
		(layer "In9.Cu")
		(net "P5E_PEX3_STN0_TX_DP<1>")
	)
	(segment
		(start 437.426608 -179.117498)
		(end 433.709064 -221.611444)
		(width 0.1651)
		(layer "In9.Cu")
		(net "P5E_PEX3_STN0_TX_DP<1>")
	)
	(segment
		(start 434.731668 -122.737118)
		(end 434.676804 -122.86996)
		(width 0.1651)
		(layer "In9.Cu")
		(net "P5E_PEX3_STN0_TX_DP<1>")
	)
	(segment
		(start 434.556916 -122.31497)
		(end 434.731668 -122.737118)
		(width 0.1651)
		(layer "In9.Cu")
		(net "P5E_PEX3_STN0_TX_DP<1>")
	)
	(segment
		(start 437.696356 -129.89306)
		(end 437.696102 -129.89306)
		(width 0.1651)
		(layer "In9.Cu")
		(net "P5E_PEX3_STN0_TX_DP<1>")
	)
	(segment
		(start 446.2272 -276.212046)
		(end 436.995824 -285.443422)
		(width 0.1651)
		(layer "In9.Cu")
		(net "P5E_PEX3_STN0_TX_DP<1>")
	)
	(segment
		(start 434.984652 -123.347734)
		(end 435.73192 -125.15215)
		(width 0.1651)
		(layer "In9.Cu")
		(net "P5E_PEX3_STN0_TX_DP<1>")
	)
	(segment
		(start 378.2949 -355.978206)
		(end 377.974352 -355.657658)
		(width 0.13462)
		(layer "F.Cu")
		(net "P5E_PEX3_STN6_TX_DN<108>")
	)
	(segment
		(start 377.974352 -355.02723)
		(end 378.2695 -354.732082)
		(width 0.13462)
		(layer "F.Cu")
		(net "P5E_PEX3_STN6_TX_DN<108>")
	)
	(segment
		(start 377.974352 -355.657658)
		(end 377.974352 -355.02723)
		(width 0.13462)
		(layer "F.Cu")
		(net "P5E_PEX3_STN6_TX_DN<108>")
	)
	(segment
		(start 392.678666 -324.42658)
		(end 394.177266 -321.785742)
		(width 0.1651)
		(layer "In13.Cu")
		(net "P5E_PEX3_STN6_TX_DN<108>")
	)
	(segment
		(start 394.177266 -321.785742)
		(end 394.31595 -321.451478)
		(width 0.1651)
		(layer "In13.Cu")
		(net "P5E_PEX3_STN6_TX_DN<108>")
	)
	(segment
		(start 377.97867 -354.441252)
		(end 377.97867 -353.930966)
		(width 0.1651)
		(layer "In13.Cu")
		(net "P5E_PEX3_STN6_TX_DN<108>")
	)
	(segment
		(start 379.53315 -352.376486)
		(end 379.53315 -341.837518)
		(width 0.1651)
		(layer "In13.Cu")
		(net "P5E_PEX3_STN6_TX_DN<108>")
	)
	(segment
		(start 394.27023 -313.673744)
		(end 394.373862 -313.570112)
		(width 0.1143)
		(layer "In13.Cu")
		(net "P5E_PEX3_STN6_TX_DN<108>")
	)
	(segment
		(start 377.97867 -353.930966)
		(end 379.53315 -352.376486)
		(width 0.1651)
		(layer "In13.Cu")
		(net "P5E_PEX3_STN6_TX_DN<108>")
	)
	(segment
		(start 394.373862 -313.570112)
		(end 394.53566 -313.570112)
		(width 0.1143)
		(layer "In13.Cu")
		(net "P5E_PEX3_STN6_TX_DN<108>")
	)
	(segment
		(start 394.31595 -321.451478)
		(end 394.31595 -320.046096)
		(width 0.1651)
		(layer "In13.Cu")
		(net "P5E_PEX3_STN6_TX_DN<108>")
	)
	(segment
		(start 394.27023 -319.971928)
		(end 394.27023 -313.673744)
		(width 0.1143)
		(layer "In13.Cu")
		(net "P5E_PEX3_STN6_TX_DN<108>")
	)
	(segment
		(start 394.31595 -320.017648)
		(end 394.27023 -319.971928)
		(width 0.1143)
		(layer "In13.Cu")
		(net "P5E_PEX3_STN6_TX_DN<108>")
	)
	(segment
		(start 394.31595 -320.046096)
		(end 394.31595 -320.017648)
		(width 0.1143)
		(layer "In13.Cu")
		(net "P5E_PEX3_STN6_TX_DN<108>")
	)
	(segment
		(start 378.2695 -354.732082)
		(end 377.97867 -354.441252)
		(width 0.1651)
		(layer "In13.Cu")
		(net "P5E_PEX3_STN6_TX_DN<108>")
	)
	(segment
		(start 394.53566 -313.570112)
		(end 394.64996 -313.684412)
		(width 0.1143)
		(layer "In13.Cu")
		(net "P5E_PEX3_STN6_TX_DN<108>")
	)
	(segment
		(start 379.53315 -341.837518)
		(end 385.647946 -334.54848)
		(width 0.1651)
		(layer "In13.Cu")
		(net "P5E_PEX3_STN6_TX_DN<108>")
	)
	(segment
		(start 394.64996 -313.684412)
		(end 394.64996 -313.949842)
		(width 0.1143)
		(layer "In13.Cu")
		(net "P5E_PEX3_STN6_TX_DN<108>")
	)
	(segment
		(start 385.647946 -334.54848)
		(end 392.678666 -324.42658)
		(width 0.1651)
		(layer "In13.Cu")
		(net "P5E_PEX3_STN6_TX_DN<108>")
	)
	(segment
		(start 47.882048 -357.46309)
		(end 47.882048 -356.831646)
		(width 0.13462)
		(layer "F.Cu")
		(net "P5E_PEX0_STN7_TX_C_DN<126>")
	)
	(segment
		(start 47.882048 -356.831646)
		(end 48.202088 -356.511606)
		(width 0.13462)
		(layer "F.Cu")
		(net "P5E_PEX0_STN7_TX_C_DN<126>")
	)
	(segment
		(start 48.176688 -357.75773)
		(end 47.882048 -357.46309)
		(width 0.13462)
		(layer "F.Cu")
		(net "P5E_PEX0_STN7_TX_C_DN<126>")
	)
	(segment
		(start 41.1099 -375.69013)
		(end 41.1099 -375.308114)
		(width 0.1651)
		(layer "In7.Cu")
		(net "P5E_PEX0_STN7_TX_C_DN<126>")
	)
	(segment
		(start 47.885858 -358.04856)
		(end 48.176688 -357.75773)
		(width 0.1651)
		(layer "In7.Cu")
		(net "P5E_PEX0_STN7_TX_C_DN<126>")
	)
	(segment
		(start 41.710356 -375.181114)
		(end 42.284142 -374.607328)
		(width 0.1651)
		(layer "In7.Cu")
		(net "P5E_PEX0_STN7_TX_C_DN<126>")
	)
	(segment
		(start 42.284142 -374.607328)
		(end 42.284142 -370.040408)
		(width 0.1651)
		(layer "In7.Cu")
		(net "P5E_PEX0_STN7_TX_C_DN<126>")
	)
	(segment
		(start 47.885858 -358.767126)
		(end 47.885858 -358.04856)
		(width 0.1651)
		(layer "In7.Cu")
		(net "P5E_PEX0_STN7_TX_C_DN<126>")
	)
	(segment
		(start 42.966894 -367.450116)
		(end 47.885858 -358.767126)
		(width 0.1651)
		(layer "In7.Cu")
		(net "P5E_PEX0_STN7_TX_C_DN<126>")
	)
	(segment
		(start 41.2369 -375.181114)
		(end 41.710356 -375.181114)
		(width 0.1651)
		(layer "In7.Cu")
		(net "P5E_PEX0_STN7_TX_C_DN<126>")
	)
	(segment
		(start 42.284142 -370.040408)
		(end 42.966894 -367.450116)
		(width 0.1651)
		(layer "In7.Cu")
		(net "P5E_PEX0_STN7_TX_C_DN<126>")
	)
	(segment
		(start 41.1099 -375.308114)
		(end 41.2369 -375.181114)
		(width 0.1651)
		(layer "In7.Cu")
		(net "P5E_PEX0_STN7_TX_C_DN<126>")
	)
	(segment
		(start 21.652484 -33.95218)
		(end 21.021548 -33.95218)
		(width 0.13462)
		(layer "F.Cu")
		(net "P5E_PEX0_STN2_TX_DN<47>")
	)
	(segment
		(start 21.947378 -33.657286)
		(end 21.652484 -33.95218)
		(width 0.13462)
		(layer "F.Cu")
		(net "P5E_PEX0_STN2_TX_DN<47>")
	)
	(segment
		(start 21.021548 -33.95218)
		(end 20.701254 -33.631886)
		(width 0.13462)
		(layer "F.Cu")
		(net "P5E_PEX0_STN2_TX_DN<47>")
	)
	(segment
		(start 31.37027 -117.07495)
		(end 31.883858 -138.226292)
		(width 0.1651)
		(layer "In11.Cu")
		(net "P5E_PEX0_STN2_TX_DN<47>")
	)
	(segment
		(start 21.947378 -33.657286)
		(end 22.14499 -33.854898)
		(width 0.1651)
		(layer "In11.Cu")
		(net "P5E_PEX0_STN2_TX_DN<47>")
	)
	(segment
		(start 44.070016 -278.125936)
		(end 44.173648 -278.229568)
		(width 0.1143)
		(layer "In11.Cu")
		(net "P5E_PEX0_STN2_TX_DN<47>")
	)
	(segment
		(start 32.043116 -104.589834)
		(end 31.37027 -117.07495)
		(width 0.1651)
		(layer "In11.Cu")
		(net "P5E_PEX0_STN2_TX_DN<47>")
	)
	(segment
		(start 44.115736 -271.399)
		(end 44.115736 -271.427448)
		(width 0.1143)
		(layer "In11.Cu")
		(net "P5E_PEX0_STN2_TX_DN<47>")
	)
	(segment
		(start 22.773386 -33.948116)
		(end 23.19655 -34.151316)
		(width 0.1651)
		(layer "In11.Cu")
		(net "P5E_PEX0_STN2_TX_DN<47>")
	)
	(segment
		(start 44.070016 -271.473168)
		(end 44.070016 -278.125936)
		(width 0.1143)
		(layer "In11.Cu")
		(net "P5E_PEX0_STN2_TX_DN<47>")
	)
	(segment
		(start 34.221674 -47.342298)
		(end 35.245802 -49.197768)
		(width 0.1651)
		(layer "In11.Cu")
		(net "P5E_PEX0_STN2_TX_DN<47>")
	)
	(segment
		(start 23.19655 -34.151316)
		(end 24.494236 -35.183572)
		(width 0.1651)
		(layer "In11.Cu")
		(net "P5E_PEX0_STN2_TX_DN<47>")
	)
	(segment
		(start 44.115736 -270.728694)
		(end 44.115736 -271.399)
		(width 0.1651)
		(layer "In11.Cu")
		(net "P5E_PEX0_STN2_TX_DN<47>")
	)
	(segment
		(start 22.14499 -33.854898)
		(end 22.370288 -33.948116)
		(width 0.1651)
		(layer "In11.Cu")
		(net "P5E_PEX0_STN2_TX_DN<47>")
	)
	(segment
		(start 44.335446 -278.229568)
		(end 44.449746 -278.115268)
		(width 0.1143)
		(layer "In11.Cu")
		(net "P5E_PEX0_STN2_TX_DN<47>")
	)
	(segment
		(start 44.115736 -271.427448)
		(end 44.070016 -271.473168)
		(width 0.1143)
		(layer "In11.Cu")
		(net "P5E_PEX0_STN2_TX_DN<47>")
	)
	(segment
		(start 44.449746 -278.115268)
		(end 44.449746 -277.849838)
		(width 0.1143)
		(layer "In11.Cu")
		(net "P5E_PEX0_STN2_TX_DN<47>")
	)
	(segment
		(start 35.558984 -78.909926)
		(end 32.043116 -104.589834)
		(width 0.1651)
		(layer "In11.Cu")
		(net "P5E_PEX0_STN2_TX_DN<47>")
	)
	(segment
		(start 31.883858 -138.226292)
		(end 43.082972 -264.507726)
		(width 0.1651)
		(layer "In11.Cu")
		(net "P5E_PEX0_STN2_TX_DN<47>")
	)
	(segment
		(start 24.494236 -35.183572)
		(end 34.221674 -47.342298)
		(width 0.1651)
		(layer "In11.Cu")
		(net "P5E_PEX0_STN2_TX_DN<47>")
	)
	(segment
		(start 22.370288 -33.948116)
		(end 22.773386 -33.948116)
		(width 0.1651)
		(layer "In11.Cu")
		(net "P5E_PEX0_STN2_TX_DN<47>")
	)
	(segment
		(start 44.173648 -278.229568)
		(end 44.335446 -278.229568)
		(width 0.1143)
		(layer "In11.Cu")
		(net "P5E_PEX0_STN2_TX_DN<47>")
	)
	(segment
		(start 43.082972 -264.507726)
		(end 44.115736 -270.728694)
		(width 0.1651)
		(layer "In11.Cu")
		(net "P5E_PEX0_STN2_TX_DN<47>")
	)
	(segment
		(start 35.740086 -50.623724)
		(end 36.41852 -62.636908)
		(width 0.1651)
		(layer "In11.Cu")
		(net "P5E_PEX0_STN2_TX_DN<47>")
	)
	(segment
		(start 36.41852 -62.636908)
		(end 35.558984 -78.909926)
		(width 0.1651)
		(layer "In11.Cu")
		(net "P5E_PEX0_STN2_TX_DN<47>")
	)
	(segment
		(start 35.245802 -49.197768)
		(end 35.740086 -50.623724)
		(width 0.1651)
		(layer "In11.Cu")
		(net "P5E_PEX0_STN2_TX_DN<47>")
	)
	(segment
		(start 190.047372 -30.05709)
		(end 189.751462 -30.353)
		(width 0.13462)
		(layer "F.Cu")
		(net "P5E_PEX1_STN2_TX_DN<37>")
	)
	(segment
		(start 189.751462 -30.353)
		(end 189.122558 -30.353)
		(width 0.13462)
		(layer "F.Cu")
		(net "P5E_PEX1_STN2_TX_DN<37>")
	)
	(segment
		(start 189.122558 -30.353)
		(end 188.801248 -30.03169)
		(width 0.13462)
		(layer "F.Cu")
		(net "P5E_PEX1_STN2_TX_DN<37>")
	)
	(segment
		(start 191.379602 -30.500066)
		(end 193.792602 -32.913066)
		(width 0.1651)
		(layer "In11.Cu")
		(net "P5E_PEX1_STN2_TX_DN<37>")
	)
	(segment
		(start 205.305152 -48.032416)
		(end 206.371444 -58.532522)
		(width 0.1651)
		(layer "In11.Cu")
		(net "P5E_PEX1_STN2_TX_DN<37>")
	)
	(segment
		(start 206.371444 -58.532522)
		(end 206.371444 -60.458604)
		(width 0.1651)
		(layer "In11.Cu")
		(net "P5E_PEX1_STN2_TX_DN<37>")
	)
	(segment
		(start 198.52005 -40.511984)
		(end 205.305152 -48.032416)
		(width 0.1651)
		(layer "In11.Cu")
		(net "P5E_PEX1_STN2_TX_DN<37>")
	)
	(segment
		(start 169.715942 -271.427448)
		(end 169.670222 -271.473168)
		(width 0.1143)
		(layer "In11.Cu")
		(net "P5E_PEX1_STN2_TX_DN<37>")
	)
	(segment
		(start 169.773854 -278.229568)
		(end 169.935652 -278.229568)
		(width 0.1143)
		(layer "In11.Cu")
		(net "P5E_PEX1_STN2_TX_DN<37>")
	)
	(segment
		(start 190.047372 -30.05709)
		(end 190.338202 -30.34792)
		(width 0.1651)
		(layer "In11.Cu")
		(net "P5E_PEX1_STN2_TX_DN<37>")
	)
	(segment
		(start 204.817472 -64.616076)
		(end 182.632858 -93.609922)
		(width 0.1651)
		(layer "In11.Cu")
		(net "P5E_PEX1_STN2_TX_DN<37>")
	)
	(segment
		(start 179.336192 -107.879896)
		(end 177.891694 -115.272058)
		(width 0.1651)
		(layer "In11.Cu")
		(net "P5E_PEX1_STN2_TX_DN<37>")
	)
	(segment
		(start 206.371444 -60.458604)
		(end 205.772512 -62.700916)
		(width 0.1651)
		(layer "In11.Cu")
		(net "P5E_PEX1_STN2_TX_DN<37>")
	)
	(segment
		(start 169.935652 -278.229568)
		(end 170.049952 -278.115268)
		(width 0.1143)
		(layer "In11.Cu")
		(net "P5E_PEX1_STN2_TX_DN<37>")
	)
	(segment
		(start 193.792602 -32.913066)
		(end 198.52005 -40.511984)
		(width 0.1651)
		(layer "In11.Cu")
		(net "P5E_PEX1_STN2_TX_DN<37>")
	)
	(segment
		(start 169.715942 -271.399)
		(end 169.715942 -271.427448)
		(width 0.1143)
		(layer "In11.Cu")
		(net "P5E_PEX1_STN2_TX_DN<37>")
	)
	(segment
		(start 169.670222 -271.473168)
		(end 169.670222 -278.125936)
		(width 0.1143)
		(layer "In11.Cu")
		(net "P5E_PEX1_STN2_TX_DN<37>")
	)
	(segment
		(start 169.715942 -263.306306)
		(end 169.715942 -271.399)
		(width 0.1651)
		(layer "In11.Cu")
		(net "P5E_PEX1_STN2_TX_DN<37>")
	)
	(segment
		(start 169.670222 -278.125936)
		(end 169.773854 -278.229568)
		(width 0.1143)
		(layer "In11.Cu")
		(net "P5E_PEX1_STN2_TX_DN<37>")
	)
	(segment
		(start 170.049952 -278.115268)
		(end 170.049952 -277.849838)
		(width 0.1143)
		(layer "In11.Cu")
		(net "P5E_PEX1_STN2_TX_DN<37>")
	)
	(segment
		(start 182.632858 -93.609922)
		(end 179.336192 -107.879896)
		(width 0.1651)
		(layer "In11.Cu")
		(net "P5E_PEX1_STN2_TX_DN<37>")
	)
	(segment
		(start 205.772512 -62.700916)
		(end 204.817472 -64.616076)
		(width 0.1651)
		(layer "In11.Cu")
		(net "P5E_PEX1_STN2_TX_DN<37>")
	)
	(segment
		(start 190.338202 -30.34792)
		(end 191.012318 -30.34792)
		(width 0.1651)
		(layer "In11.Cu")
		(net "P5E_PEX1_STN2_TX_DN<37>")
	)
	(segment
		(start 191.012318 -30.34792)
		(end 191.379602 -30.500066)
		(width 0.1651)
		(layer "In11.Cu")
		(net "P5E_PEX1_STN2_TX_DN<37>")
	)
	(segment
		(start 177.214022 -120.76176)
		(end 169.715942 -263.306306)
		(width 0.1651)
		(layer "In11.Cu")
		(net "P5E_PEX1_STN2_TX_DN<37>")
	)
	(segment
		(start 177.891694 -115.272058)
		(end 177.214022 -120.76176)
		(width 0.1651)
		(layer "In11.Cu")
		(net "P5E_PEX1_STN2_TX_DN<37>")
	)
	(segment
		(start 340.778084 -355.026722)
		(end 340.483444 -354.732082)
		(width 0.13462)
		(layer "F.Cu")
		(net "P5E_PEX2_STN5_TX_DP<94>")
	)
	(segment
		(start 340.778084 -355.658166)
		(end 340.778084 -355.026722)
		(width 0.13462)
		(layer "F.Cu")
		(net "P5E_PEX2_STN5_TX_DP<94>")
	)
	(segment
		(start 340.458044 -355.978206)
		(end 340.778084 -355.658166)
		(width 0.13462)
		(layer "F.Cu")
		(net "P5E_PEX2_STN5_TX_DP<94>")
	)
	(segment
		(start 342.32723 -341.709502)
		(end 342.15705 -341.305896)
		(width 0.1651)
		(layer "In7.Cu")
		(net "P5E_PEX2_STN5_TX_DP<94>")
	)
	(segment
		(start 304.747676 -321.629532)
		(end 303.583848 -320.465704)
		(width 0.1651)
		(layer "In7.Cu")
		(net "P5E_PEX2_STN5_TX_DP<94>")
	)
	(segment
		(start 303.629568 -311.705498)
		(end 303.855374 -311.479692)
		(width 0.1143)
		(layer "In7.Cu")
		(net "P5E_PEX2_STN5_TX_DP<94>")
	)
	(segment
		(start 340.774274 -353.814126)
		(end 342.328754 -352.259646)
		(width 0.1651)
		(layer "In7.Cu")
		(net "P5E_PEX2_STN5_TX_DP<94>")
	)
	(segment
		(start 303.855374 -311.479692)
		(end 304.085498 -311.479692)
		(width 0.1143)
		(layer "In7.Cu")
		(net "P5E_PEX2_STN5_TX_DP<94>")
	)
	(segment
		(start 304.199798 -311.365392)
		(end 304.199798 -311.099962)
		(width 0.1143)
		(layer "In7.Cu")
		(net "P5E_PEX2_STN5_TX_DP<94>")
	)
	(segment
		(start 342.328754 -352.259646)
		(end 342.328754 -341.71255)
		(width 0.1651)
		(layer "In7.Cu")
		(net "P5E_PEX2_STN5_TX_DP<94>")
	)
	(segment
		(start 303.583848 -320.465704)
		(end 303.583848 -319.916048)
		(width 0.1651)
		(layer "In7.Cu")
		(net "P5E_PEX2_STN5_TX_DP<94>")
	)
	(segment
		(start 341.98687 -340.902544)
		(end 326.992488 -330.780136)
		(width 0.1651)
		(layer "In7.Cu")
		(net "P5E_PEX2_STN5_TX_DP<94>")
	)
	(segment
		(start 340.774274 -354.441252)
		(end 340.774274 -353.814126)
		(width 0.1651)
		(layer "In7.Cu")
		(net "P5E_PEX2_STN5_TX_DP<94>")
	)
	(segment
		(start 342.328754 -341.71255)
		(end 342.32723 -341.709502)
		(width 0.1651)
		(layer "In7.Cu")
		(net "P5E_PEX2_STN5_TX_DP<94>")
	)
	(segment
		(start 326.992488 -330.780136)
		(end 304.747676 -321.629532)
		(width 0.1651)
		(layer "In7.Cu")
		(net "P5E_PEX2_STN5_TX_DP<94>")
	)
	(segment
		(start 304.085498 -311.479692)
		(end 304.199798 -311.365392)
		(width 0.1143)
		(layer "In7.Cu")
		(net "P5E_PEX2_STN5_TX_DP<94>")
	)
	(segment
		(start 303.629568 -319.84188)
		(end 303.629568 -311.705498)
		(width 0.1143)
		(layer "In7.Cu")
		(net "P5E_PEX2_STN5_TX_DP<94>")
	)
	(segment
		(start 340.483444 -354.732082)
		(end 340.774274 -354.441252)
		(width 0.1651)
		(layer "In7.Cu")
		(net "P5E_PEX2_STN5_TX_DP<94>")
	)
	(segment
		(start 342.15705 -341.305642)
		(end 341.98687 -340.902544)
		(width 0.1651)
		(layer "In7.Cu")
		(net "P5E_PEX2_STN5_TX_DP<94>")
	)
	(segment
		(start 303.583848 -319.916048)
		(end 303.583848 -319.8876)
		(width 0.1143)
		(layer "In7.Cu")
		(net "P5E_PEX2_STN5_TX_DP<94>")
	)
	(segment
		(start 303.583848 -319.8876)
		(end 303.629568 -319.84188)
		(width 0.1143)
		(layer "In7.Cu")
		(net "P5E_PEX2_STN5_TX_DP<94>")
	)
	(segment
		(start 342.15705 -341.305896)
		(end 342.15705 -341.305642)
		(width 0.1651)
		(layer "In7.Cu")
		(net "P5E_PEX2_STN5_TX_DP<94>")
	)
	(segment
		(start 429.832262 -146.215608)
		(end 429.54067 -146.5072)
		(width 0.13462)
		(layer "F.Cu")
		(net "P5E_PEX3_STN0_TX_DN<10>")
	)
	(segment
		(start 428.90313 -146.5072)
		(end 428.586138 -146.190208)
		(width 0.13462)
		(layer "F.Cu")
		(net "P5E_PEX3_STN0_TX_DN<10>")
	)
	(segment
		(start 429.54067 -146.5072)
		(end 428.90313 -146.5072)
		(width 0.13462)
		(layer "F.Cu")
		(net "P5E_PEX3_STN0_TX_DN<10>")
	)
	(segment
		(start 427.56582 -271.155414)
		(end 427.56582 -271.526)
		(width 0.1651)
		(layer "In9.Cu")
		(net "P5E_PEX3_STN0_TX_DN<10>")
	)
	(segment
		(start 427.89983 -280.015188)
		(end 427.89983 -279.749758)
		(width 0.1143)
		(layer "In9.Cu")
		(net "P5E_PEX3_STN0_TX_DN<10>")
	)
	(segment
		(start 425.150026 -222.099124)
		(end 428.528988 -260.752844)
		(width 0.1651)
		(layer "In9.Cu")
		(net "P5E_PEX3_STN0_TX_DN<10>")
	)
	(segment
		(start 427.56582 -271.554448)
		(end 427.5201 -271.600168)
		(width 0.1143)
		(layer "In9.Cu")
		(net "P5E_PEX3_STN0_TX_DN<10>")
	)
	(segment
		(start 435.647846 -148.725128)
		(end 437.32704 -151.238204)
		(width 0.1651)
		(layer "In9.Cu")
		(net "P5E_PEX3_STN0_TX_DN<10>")
	)
	(segment
		(start 429.832262 -146.215608)
		(end 430.123092 -146.506438)
		(width 0.1651)
		(layer "In9.Cu")
		(net "P5E_PEX3_STN0_TX_DN<10>")
	)
	(segment
		(start 427.78553 -280.129488)
		(end 427.89983 -280.015188)
		(width 0.1143)
		(layer "In9.Cu")
		(net "P5E_PEX3_STN0_TX_DN<10>")
	)
	(segment
		(start 430.374806 -172.601128)
		(end 429.053498 -177.529236)
		(width 0.1651)
		(layer "In9.Cu")
		(net "P5E_PEX3_STN0_TX_DN<10>")
	)
	(segment
		(start 438.794144 -158.01594)
		(end 430.374806 -172.601128)
		(width 0.1651)
		(layer "In9.Cu")
		(net "P5E_PEX3_STN0_TX_DN<10>")
	)
	(segment
		(start 429.053498 -177.529236)
		(end 425.150026 -222.099124)
		(width 0.1651)
		(layer "In9.Cu")
		(net "P5E_PEX3_STN0_TX_DN<10>")
	)
	(segment
		(start 432.350164 -146.527774)
		(end 434.241448 -147.31111)
		(width 0.1651)
		(layer "In9.Cu")
		(net "P5E_PEX3_STN0_TX_DN<10>")
	)
	(segment
		(start 427.56582 -271.526)
		(end 427.56582 -271.554448)
		(width 0.1143)
		(layer "In9.Cu")
		(net "P5E_PEX3_STN0_TX_DN<10>")
	)
	(segment
		(start 438.794144 -154.780488)
		(end 438.794144 -158.01594)
		(width 0.1651)
		(layer "In9.Cu")
		(net "P5E_PEX3_STN0_TX_DN<10>")
	)
	(segment
		(start 430.123092 -146.506438)
		(end 432.328828 -146.506438)
		(width 0.1651)
		(layer "In9.Cu")
		(net "P5E_PEX3_STN0_TX_DN<10>")
	)
	(segment
		(start 428.528988 -260.752844)
		(end 428.528988 -268.829536)
		(width 0.1651)
		(layer "In9.Cu")
		(net "P5E_PEX3_STN0_TX_DN<10>")
	)
	(segment
		(start 435.647846 -148.717508)
		(end 435.647846 -148.725128)
		(width 0.1651)
		(layer "In9.Cu")
		(net "P5E_PEX3_STN0_TX_DN<10>")
	)
	(segment
		(start 427.5201 -271.600168)
		(end 427.5201 -280.025856)
		(width 0.1143)
		(layer "In9.Cu")
		(net "P5E_PEX3_STN0_TX_DN<10>")
	)
	(segment
		(start 428.528988 -268.829536)
		(end 427.56582 -271.155414)
		(width 0.1651)
		(layer "In9.Cu")
		(net "P5E_PEX3_STN0_TX_DN<10>")
	)
	(segment
		(start 434.241448 -147.31111)
		(end 435.647846 -148.717508)
		(width 0.1651)
		(layer "In9.Cu")
		(net "P5E_PEX3_STN0_TX_DN<10>")
	)
	(segment
		(start 427.5201 -280.025856)
		(end 427.623732 -280.129488)
		(width 0.1143)
		(layer "In9.Cu")
		(net "P5E_PEX3_STN0_TX_DN<10>")
	)
	(segment
		(start 432.328828 -146.506438)
		(end 432.350164 -146.527774)
		(width 0.1651)
		(layer "In9.Cu")
		(net "P5E_PEX3_STN0_TX_DN<10>")
	)
	(segment
		(start 437.32704 -151.238204)
		(end 438.794144 -154.780488)
		(width 0.1651)
		(layer "In9.Cu")
		(net "P5E_PEX3_STN0_TX_DN<10>")
	)
	(segment
		(start 427.623732 -280.129488)
		(end 427.78553 -280.129488)
		(width 0.1143)
		(layer "In9.Cu")
		(net "P5E_PEX3_STN0_TX_DN<10>")
	)
	(segment
		(start 418.916104 -349.512382)
		(end 418.916104 -348.879922)
		(width 0.13462)
		(layer "F.Cu")
		(net "P5E_PEX3_STN7_TX_DP<116>")
	)
	(segment
		(start 418.596572 -349.831914)
		(end 418.916104 -349.512382)
		(width 0.13462)
		(layer "F.Cu")
		(net "P5E_PEX3_STN7_TX_DP<116>")
	)
	(segment
		(start 418.916104 -348.879922)
		(end 418.621972 -348.58579)
		(width 0.13462)
		(layer "F.Cu")
		(net "P5E_PEX3_STN7_TX_DP<116>")
	)
	(segment
		(start 390.470136 -305.044856)
		(end 390.470136 -305.285648)
		(width 0.1143)
		(layer "In11.Cu")
		(net "P5E_PEX3_STN7_TX_DP<116>")
	)
	(segment
		(start 380.151132 -305.039522)
		(end 380.151386 -305.039268)
		(width 0.1651)
		(layer "In11.Cu")
		(net "P5E_PEX3_STN7_TX_DP<116>")
	)
	(segment
		(start 420.467282 -346.113354)
		(end 420.467282 -342.292686)
		(width 0.1651)
		(layer "In11.Cu")
		(net "P5E_PEX3_STN7_TX_DP<116>")
	)
	(segment
		(start 372.000526 -327.989946)
		(end 369.913154 -325.902574)
		(width 0.1651)
		(layer "In11.Cu")
		(net "P5E_PEX3_STN7_TX_DP<116>")
	)
	(segment
		(start 383.995168 -304.829464)
		(end 390.254744 -304.829464)
		(width 0.1143)
		(layer "In11.Cu")
		(net "P5E_PEX3_STN7_TX_DP<116>")
	)
	(segment
		(start 420.467282 -342.292686)
		(end 419.802056 -340.989412)
		(width 0.1651)
		(layer "In11.Cu")
		(net "P5E_PEX3_STN7_TX_DP<116>")
	)
	(segment
		(start 418.912802 -347.667834)
		(end 420.467282 -346.113354)
		(width 0.1651)
		(layer "In11.Cu")
		(net "P5E_PEX3_STN7_TX_DP<116>")
	)
	(segment
		(start 368.928396 -317.845694)
		(end 375.033032 -308.709568)
		(width 0.1651)
		(layer "In11.Cu")
		(net "P5E_PEX3_STN7_TX_DP<116>")
	)
	(segment
		(start 383.949448 -304.783744)
		(end 383.995168 -304.829464)
		(width 0.1143)
		(layer "In11.Cu")
		(net "P5E_PEX3_STN7_TX_DP<116>")
	)
	(segment
		(start 377.679204 -306.063396)
		(end 380.151132 -305.039522)
		(width 0.1651)
		(layer "In11.Cu")
		(net "P5E_PEX3_STN7_TX_DP<116>")
	)
	(segment
		(start 390.470136 -305.285648)
		(end 390.584436 -305.399948)
		(width 0.1143)
		(layer "In11.Cu")
		(net "P5E_PEX3_STN7_TX_DP<116>")
	)
	(segment
		(start 369.913154 -325.902574)
		(end 368.38636 -322.216526)
		(width 0.1651)
		(layer "In11.Cu")
		(net "P5E_PEX3_STN7_TX_DP<116>")
	)
	(segment
		(start 390.584436 -305.399948)
		(end 390.849866 -305.399948)
		(width 0.1143)
		(layer "In11.Cu")
		(net "P5E_PEX3_STN7_TX_DP<116>")
	)
	(segment
		(start 380.768352 -304.783744)
		(end 383.921 -304.783744)
		(width 0.1651)
		(layer "In11.Cu")
		(net "P5E_PEX3_STN7_TX_DP<116>")
	)
	(segment
		(start 380.151386 -305.039268)
		(end 380.768352 -304.783744)
		(width 0.1651)
		(layer "In11.Cu")
		(net "P5E_PEX3_STN7_TX_DP<116>")
	)
	(segment
		(start 418.912802 -348.29496)
		(end 418.912802 -347.667834)
		(width 0.1651)
		(layer "In11.Cu")
		(net "P5E_PEX3_STN7_TX_DP<116>")
	)
	(segment
		(start 418.621972 -348.58579)
		(end 418.912802 -348.29496)
		(width 0.1651)
		(layer "In11.Cu")
		(net "P5E_PEX3_STN7_TX_DP<116>")
	)
	(segment
		(start 419.802056 -340.989412)
		(end 417.125912 -339.047836)
		(width 0.1651)
		(layer "In11.Cu")
		(net "P5E_PEX3_STN7_TX_DP<116>")
	)
	(segment
		(start 383.921 -304.783744)
		(end 383.949448 -304.783744)
		(width 0.1143)
		(layer "In11.Cu")
		(net "P5E_PEX3_STN7_TX_DP<116>")
	)
	(segment
		(start 417.125912 -339.047836)
		(end 374.966484 -329.620626)
		(width 0.1651)
		(layer "In11.Cu")
		(net "P5E_PEX3_STN7_TX_DP<116>")
	)
	(segment
		(start 390.254744 -304.829464)
		(end 390.470136 -305.044856)
		(width 0.1143)
		(layer "In11.Cu")
		(net "P5E_PEX3_STN7_TX_DP<116>")
	)
	(segment
		(start 368.38636 -322.216526)
		(end 368.38636 -319.154302)
		(width 0.1651)
		(layer "In11.Cu")
		(net "P5E_PEX3_STN7_TX_DP<116>")
	)
	(segment
		(start 374.966484 -329.620626)
		(end 372.000526 -327.989946)
		(width 0.1651)
		(layer "In11.Cu")
		(net "P5E_PEX3_STN7_TX_DP<116>")
	)
	(segment
		(start 368.38636 -319.154302)
		(end 368.928396 -317.845694)
		(width 0.1651)
		(layer "In11.Cu")
		(net "P5E_PEX3_STN7_TX_DP<116>")
	)
	(segment
		(start 375.033032 -308.709568)
		(end 377.679204 -306.063396)
		(width 0.1651)
		(layer "In11.Cu")
		(net "P5E_PEX3_STN7_TX_DP<116>")
	)
	(segment
		(start 47.313088 -345.465146)
		(end 47.607728 -345.170506)
		(width 0.13462)
		(layer "F.Cu")
		(net "P5E_PEX0_STN7_TX_C_DP<125>")
	)
	(segment
		(start 47.607728 -344.539062)
		(end 47.287688 -344.219022)
		(width 0.13462)
		(layer "F.Cu")
		(net "P5E_PEX0_STN7_TX_C_DP<125>")
	)
	(segment
		(start 47.607728 -345.170506)
		(end 47.607728 -344.539062)
		(width 0.13462)
		(layer "F.Cu")
		(net "P5E_PEX0_STN7_TX_C_DP<125>")
	)
	(segment
		(start 39.802308 -369.54714)
		(end 39.976044 -368.888264)
		(width 0.1651)
		(layer "In7.Cu")
		(net "P5E_PEX0_STN7_TX_C_DP<125>")
	)
	(segment
		(start 46.049438 -347.912182)
		(end 47.603918 -346.357702)
		(width 0.1651)
		(layer "In7.Cu")
		(net "P5E_PEX0_STN7_TX_C_DP<125>")
	)
	(segment
		(start 39.802308 -375.759218)
		(end 39.802308 -369.54714)
		(width 0.1651)
		(layer "In7.Cu")
		(net "P5E_PEX0_STN7_TX_C_DP<125>")
	)
	(segment
		(start 38.910006 -375.872248)
		(end 39.037006 -375.999248)
		(width 0.1651)
		(layer "In7.Cu")
		(net "P5E_PEX0_STN7_TX_C_DP<125>")
	)
	(segment
		(start 38.910006 -375.490232)
		(end 38.910006 -375.872248)
		(width 0.1651)
		(layer "In7.Cu")
		(net "P5E_PEX0_STN7_TX_C_DP<125>")
	)
	(segment
		(start 45.849794 -358.519222)
		(end 46.049438 -357.861616)
		(width 0.1651)
		(layer "In7.Cu")
		(net "P5E_PEX0_STN7_TX_C_DP<125>")
	)
	(segment
		(start 47.603918 -346.357702)
		(end 47.603918 -345.755976)
		(width 0.1651)
		(layer "In7.Cu")
		(net "P5E_PEX0_STN7_TX_C_DP<125>")
	)
	(segment
		(start 39.976044 -368.888264)
		(end 45.849794 -358.519222)
		(width 0.1651)
		(layer "In7.Cu")
		(net "P5E_PEX0_STN7_TX_C_DP<125>")
	)
	(segment
		(start 46.049438 -357.861616)
		(end 46.049438 -347.912182)
		(width 0.1651)
		(layer "In7.Cu")
		(net "P5E_PEX0_STN7_TX_C_DP<125>")
	)
	(segment
		(start 39.037006 -375.999248)
		(end 39.562278 -375.999248)
		(width 0.1651)
		(layer "In7.Cu")
		(net "P5E_PEX0_STN7_TX_C_DP<125>")
	)
	(segment
		(start 47.603918 -345.755976)
		(end 47.313088 -345.465146)
		(width 0.1651)
		(layer "In7.Cu")
		(net "P5E_PEX0_STN7_TX_C_DP<125>")
	)
	(segment
		(start 39.562278 -375.999248)
		(end 39.802308 -375.759218)
		(width 0.1651)
		(layer "In7.Cu")
		(net "P5E_PEX0_STN7_TX_C_DP<125>")
	)
	(segment
		(start 97.019618 -32.13608)
		(end 96.369886 -32.13608)
		(width 0.13462)
		(layer "F.Cu")
		(net "P5E_PEX0_STN2_TX_DN<34>")
	)
	(segment
		(start 96.369886 -32.13608)
		(end 96.05899 -31.825184)
		(width 0.13462)
		(layer "F.Cu")
		(net "P5E_PEX0_STN2_TX_DN<34>")
	)
	(segment
		(start 97.305114 -31.850584)
		(end 97.019618 -32.13608)
		(width 0.13462)
		(layer "F.Cu")
		(net "P5E_PEX0_STN2_TX_DN<34>")
	)
	(segment
		(start 77.787754 -132.513578)
		(end 77.787754 -140.132816)
		(width 0.1651)
		(layer "In11.Cu")
		(net "P5E_PEX0_STN2_TX_DN<34>")
	)
	(segment
		(start 56.420004 -271.473168)
		(end 56.420004 -280.025856)
		(width 0.1143)
		(layer "In11.Cu")
		(net "P5E_PEX0_STN2_TX_DN<34>")
	)
	(segment
		(start 75.63231 -161.43859)
		(end 56.465724 -265.666982)
		(width 0.1651)
		(layer "In11.Cu")
		(net "P5E_PEX0_STN2_TX_DN<34>")
	)
	(segment
		(start 56.465724 -265.666982)
		(end 56.465724 -271.399)
		(width 0.1651)
		(layer "In11.Cu")
		(net "P5E_PEX0_STN2_TX_DN<34>")
	)
	(segment
		(start 97.305114 -31.850584)
		(end 97.595944 -32.141414)
		(width 0.1651)
		(layer "In11.Cu")
		(net "P5E_PEX0_STN2_TX_DN<34>")
	)
	(segment
		(start 103.017574 -74.425556)
		(end 102.427024 -75.263756)
		(width 0.1651)
		(layer "In11.Cu")
		(net "P5E_PEX0_STN2_TX_DN<34>")
	)
	(segment
		(start 106.980736 -41.785794)
		(end 107.209336 -42.652188)
		(width 0.1651)
		(layer "In11.Cu")
		(net "P5E_PEX0_STN2_TX_DN<34>")
	)
	(segment
		(start 77.379576 -141.883892)
		(end 77.051662 -149.41169)
		(width 0.1651)
		(layer "In11.Cu")
		(net "P5E_PEX0_STN2_TX_DN<34>")
	)
	(segment
		(start 77.051662 -149.413722)
		(end 77.051408 -149.413976)
		(width 0.1651)
		(layer "In11.Cu")
		(net "P5E_PEX0_STN2_TX_DN<34>")
	)
	(segment
		(start 56.523636 -280.129488)
		(end 56.685434 -280.129488)
		(width 0.1143)
		(layer "In11.Cu")
		(net "P5E_PEX0_STN2_TX_DN<34>")
	)
	(segment
		(start 105.243122 -68.266056)
		(end 103.017574 -74.425556)
		(width 0.1651)
		(layer "In11.Cu")
		(net "P5E_PEX0_STN2_TX_DN<34>")
	)
	(segment
		(start 56.799734 -280.015188)
		(end 56.799734 -279.749504)
		(width 0.1143)
		(layer "In11.Cu")
		(net "P5E_PEX0_STN2_TX_DN<34>")
	)
	(segment
		(start 107.209336 -42.652188)
		(end 107.460542 -56.75376)
		(width 0.1651)
		(layer "In11.Cu")
		(net "P5E_PEX0_STN2_TX_DN<34>")
	)
	(segment
		(start 78.403196 -118.379748)
		(end 77.787754 -132.513578)
		(width 0.1651)
		(layer "In11.Cu")
		(net "P5E_PEX0_STN2_TX_DN<34>")
	)
	(segment
		(start 56.465724 -271.399)
		(end 56.465724 -271.427448)
		(width 0.1143)
		(layer "In11.Cu")
		(net "P5E_PEX0_STN2_TX_DN<34>")
	)
	(segment
		(start 79.209646 -111.841534)
		(end 78.403196 -118.379748)
		(width 0.1651)
		(layer "In11.Cu")
		(net "P5E_PEX0_STN2_TX_DN<34>")
	)
	(segment
		(start 80.016858 -105.301288)
		(end 79.2099 -111.841534)
		(width 0.1651)
		(layer "In11.Cu")
		(net "P5E_PEX0_STN2_TX_DN<34>")
	)
	(segment
		(start 56.465724 -271.427448)
		(end 56.420004 -271.473168)
		(width 0.1143)
		(layer "In11.Cu")
		(net "P5E_PEX0_STN2_TX_DN<34>")
	)
	(segment
		(start 77.051408 -149.413976)
		(end 77.0509 -149.418294)
		(width 0.1651)
		(layer "In11.Cu")
		(net "P5E_PEX0_STN2_TX_DN<34>")
	)
	(segment
		(start 56.685434 -280.129488)
		(end 56.799734 -280.015188)
		(width 0.1143)
		(layer "In11.Cu")
		(net "P5E_PEX0_STN2_TX_DN<34>")
	)
	(segment
		(start 93.963998 -80.722724)
		(end 80.016858 -105.301288)
		(width 0.1651)
		(layer "In11.Cu")
		(net "P5E_PEX0_STN2_TX_DN<34>")
	)
	(segment
		(start 95.913702 -78.775052)
		(end 93.963998 -80.722724)
		(width 0.1651)
		(layer "In11.Cu")
		(net "P5E_PEX0_STN2_TX_DN<34>")
	)
	(segment
		(start 102.672134 -33.86836)
		(end 106.980736 -41.785794)
		(width 0.1651)
		(layer "In11.Cu")
		(net "P5E_PEX0_STN2_TX_DN<34>")
	)
	(segment
		(start 100.963222 -32.141414)
		(end 102.672134 -33.86836)
		(width 0.1651)
		(layer "In11.Cu")
		(net "P5E_PEX0_STN2_TX_DN<34>")
	)
	(segment
		(start 79.2099 -111.841534)
		(end 79.209646 -111.841534)
		(width 0.1651)
		(layer "In11.Cu")
		(net "P5E_PEX0_STN2_TX_DN<34>")
	)
	(segment
		(start 97.595944 -32.141414)
		(end 100.963222 -32.141414)
		(width 0.1651)
		(layer "In11.Cu")
		(net "P5E_PEX0_STN2_TX_DN<34>")
	)
	(segment
		(start 77.787754 -140.132816)
		(end 77.379576 -141.883892)
		(width 0.1651)
		(layer "In11.Cu")
		(net "P5E_PEX0_STN2_TX_DN<34>")
	)
	(segment
		(start 77.0509 -149.418294)
		(end 75.63231 -161.43859)
		(width 0.1651)
		(layer "In11.Cu")
		(net "P5E_PEX0_STN2_TX_DN<34>")
	)
	(segment
		(start 107.460542 -56.75376)
		(end 105.243122 -68.266056)
		(width 0.1651)
		(layer "In11.Cu")
		(net "P5E_PEX0_STN2_TX_DN<34>")
	)
	(segment
		(start 56.420004 -280.025856)
		(end 56.523636 -280.129488)
		(width 0.1143)
		(layer "In11.Cu")
		(net "P5E_PEX0_STN2_TX_DN<34>")
	)
	(segment
		(start 102.427024 -75.263756)
		(end 95.913702 -78.775052)
		(width 0.1651)
		(layer "In11.Cu")
		(net "P5E_PEX0_STN2_TX_DN<34>")
	)
	(segment
		(start 77.051662 -149.41169)
		(end 77.051662 -149.413722)
		(width 0.1651)
		(layer "In11.Cu")
		(net "P5E_PEX0_STN2_TX_DN<34>")
	)
	(segment
		(start 215.75141 -30.353)
		(end 215.122506 -30.353)
		(width 0.13462)
		(layer "F.Cu")
		(net "P5E_PEX1_STN2_TX_DN<33>")
	)
	(segment
		(start 215.122506 -30.353)
		(end 214.801196 -30.03169)
		(width 0.13462)
		(layer "F.Cu")
		(net "P5E_PEX1_STN2_TX_DN<33>")
	)
	(segment
		(start 216.04732 -30.05709)
		(end 215.75141 -30.353)
		(width 0.13462)
		(layer "F.Cu")
		(net "P5E_PEX1_STN2_TX_DN<33>")
	)
	(segment
		(start 173.850046 -278.115268)
		(end 173.850046 -277.849838)
		(width 0.1143)
		(layer "In11.Cu")
		(net "P5E_PEX1_STN2_TX_DN<33>")
	)
	(segment
		(start 194.227704 -148.24456)
		(end 194.000628 -150.936706)
		(width 0.1651)
		(layer "In11.Cu")
		(net "P5E_PEX1_STN2_TX_DN<33>")
	)
	(segment
		(start 216.04732 -30.05709)
		(end 216.230708 -30.240478)
		(width 0.1651)
		(layer "In11.Cu")
		(net "P5E_PEX1_STN2_TX_DN<33>")
	)
	(segment
		(start 194.842892 -140.401802)
		(end 194.499738 -141.878812)
		(width 0.1651)
		(layer "In11.Cu")
		(net "P5E_PEX1_STN2_TX_DN<33>")
	)
	(segment
		(start 194.499738 -141.878812)
		(end 194.227704 -148.24456)
		(width 0.1651)
		(layer "In11.Cu")
		(net "P5E_PEX1_STN2_TX_DN<33>")
	)
	(segment
		(start 216.489534 -30.34792)
		(end 216.839292 -30.34792)
		(width 0.1651)
		(layer "In11.Cu")
		(net "P5E_PEX1_STN2_TX_DN<33>")
	)
	(segment
		(start 216.839292 -30.34792)
		(end 217.44813 -30.615128)
		(width 0.1651)
		(layer "In11.Cu")
		(net "P5E_PEX1_STN2_TX_DN<33>")
	)
	(segment
		(start 192.778888 -161.060384)
		(end 173.516036 -265.859514)
		(width 0.1651)
		(layer "In11.Cu")
		(net "P5E_PEX1_STN2_TX_DN<33>")
	)
	(segment
		(start 195.495418 -118.553992)
		(end 194.842892 -133.840982)
		(width 0.1651)
		(layer "In11.Cu")
		(net "P5E_PEX1_STN2_TX_DN<33>")
	)
	(segment
		(start 173.470316 -278.125936)
		(end 173.573948 -278.229568)
		(width 0.1143)
		(layer "In11.Cu")
		(net "P5E_PEX1_STN2_TX_DN<33>")
	)
	(segment
		(start 217.44813 -30.615128)
		(end 219.294202 -32.441388)
		(width 0.1651)
		(layer "In11.Cu")
		(net "P5E_PEX1_STN2_TX_DN<33>")
	)
	(segment
		(start 224.27057 -42.544492)
		(end 224.54362 -56.860948)
		(width 0.1651)
		(layer "In11.Cu")
		(net "P5E_PEX1_STN2_TX_DN<33>")
	)
	(segment
		(start 194.000628 -150.936706)
		(end 194.000374 -150.936706)
		(width 0.1651)
		(layer "In11.Cu")
		(net "P5E_PEX1_STN2_TX_DN<33>")
	)
	(segment
		(start 173.516036 -271.427448)
		(end 173.470316 -271.473168)
		(width 0.1143)
		(layer "In11.Cu")
		(net "P5E_PEX1_STN2_TX_DN<33>")
	)
	(segment
		(start 219.294202 -32.441388)
		(end 223.760538 -40.622982)
		(width 0.1651)
		(layer "In11.Cu")
		(net "P5E_PEX1_STN2_TX_DN<33>")
	)
	(segment
		(start 224.54362 -56.860948)
		(end 222.276416 -68.499228)
		(width 0.1651)
		(layer "In11.Cu")
		(net "P5E_PEX1_STN2_TX_DN<33>")
	)
	(segment
		(start 194.000374 -150.936706)
		(end 193.77279 -153.6319)
		(width 0.1651)
		(layer "In11.Cu")
		(net "P5E_PEX1_STN2_TX_DN<33>")
	)
	(segment
		(start 219.192856 -76.002388)
		(end 212.60562 -79.581502)
		(width 0.1651)
		(layer "In11.Cu")
		(net "P5E_PEX1_STN2_TX_DN<33>")
	)
	(segment
		(start 210.807554 -81.35493)
		(end 207.383126 -87.404956)
		(width 0.1651)
		(layer "In11.Cu")
		(net "P5E_PEX1_STN2_TX_DN<33>")
	)
	(segment
		(start 193.77279 -153.6319)
		(end 192.778888 -161.060384)
		(width 0.1651)
		(layer "In11.Cu")
		(net "P5E_PEX1_STN2_TX_DN<33>")
	)
	(segment
		(start 223.760538 -40.622982)
		(end 224.27057 -42.544492)
		(width 0.1651)
		(layer "In11.Cu")
		(net "P5E_PEX1_STN2_TX_DN<33>")
	)
	(segment
		(start 219.969588 -74.95667)
		(end 219.192856 -76.002388)
		(width 0.1651)
		(layer "In11.Cu")
		(net "P5E_PEX1_STN2_TX_DN<33>")
	)
	(segment
		(start 203.958952 -93.454728)
		(end 203.958952 -93.454474)
		(width 0.1651)
		(layer "In11.Cu")
		(net "P5E_PEX1_STN2_TX_DN<33>")
	)
	(segment
		(start 212.60562 -79.581502)
		(end 210.807554 -81.35493)
		(width 0.1651)
		(layer "In11.Cu")
		(net "P5E_PEX1_STN2_TX_DN<33>")
	)
	(segment
		(start 194.842892 -133.840982)
		(end 194.842892 -140.401802)
		(width 0.1651)
		(layer "In11.Cu")
		(net "P5E_PEX1_STN2_TX_DN<33>")
	)
	(segment
		(start 173.516036 -271.399)
		(end 173.516036 -271.427448)
		(width 0.1143)
		(layer "In11.Cu")
		(net "P5E_PEX1_STN2_TX_DN<33>")
	)
	(segment
		(start 173.516036 -265.859514)
		(end 173.516036 -271.399)
		(width 0.1651)
		(layer "In11.Cu")
		(net "P5E_PEX1_STN2_TX_DN<33>")
	)
	(segment
		(start 173.735746 -278.229568)
		(end 173.850046 -278.115268)
		(width 0.1143)
		(layer "In11.Cu")
		(net "P5E_PEX1_STN2_TX_DN<33>")
	)
	(segment
		(start 173.470316 -271.473168)
		(end 173.470316 -278.125936)
		(width 0.1143)
		(layer "In11.Cu")
		(net "P5E_PEX1_STN2_TX_DN<33>")
	)
	(segment
		(start 207.383126 -87.404956)
		(end 203.958952 -93.454728)
		(width 0.1651)
		(layer "In11.Cu")
		(net "P5E_PEX1_STN2_TX_DN<33>")
	)
	(segment
		(start 197.110604 -105.554018)
		(end 195.495418 -118.553992)
		(width 0.1651)
		(layer "In11.Cu")
		(net "P5E_PEX1_STN2_TX_DN<33>")
	)
	(segment
		(start 203.958952 -93.454474)
		(end 197.110604 -105.554018)
		(width 0.1651)
		(layer "In11.Cu")
		(net "P5E_PEX1_STN2_TX_DN<33>")
	)
	(segment
		(start 222.276416 -68.499228)
		(end 219.969588 -74.95667)
		(width 0.1651)
		(layer "In11.Cu")
		(net "P5E_PEX1_STN2_TX_DN<33>")
	)
	(segment
		(start 173.573948 -278.229568)
		(end 173.735746 -278.229568)
		(width 0.1143)
		(layer "In11.Cu")
		(net "P5E_PEX1_STN2_TX_DN<33>")
	)
	(segment
		(start 216.230708 -30.240478)
		(end 216.489534 -30.34792)
		(width 0.1651)
		(layer "In11.Cu")
		(net "P5E_PEX1_STN2_TX_DN<33>")
	)
	(segment
		(start 279.22093 -34.2265)
		(end 278.901144 -34.546286)
		(width 0.13462)
		(layer "F.Cu")
		(net "P5E_PEX2_STN2_TX_DP<43>")
	)
	(segment
		(start 280.147268 -34.520886)
		(end 279.852882 -34.2265)
		(width 0.13462)
		(layer "F.Cu")
		(net "P5E_PEX2_STN2_TX_DP<43>")
	)
	(segment
		(start 279.852882 -34.2265)
		(end 279.22093 -34.2265)
		(width 0.13462)
		(layer "F.Cu")
		(net "P5E_PEX2_STN2_TX_DP<43>")
	)
	(segment
		(start 292.763702 -68.413884)
		(end 282.552394 -95.389446)
		(width 0.1651)
		(layer "In11.Cu")
		(net "P5E_PEX2_STN2_TX_DP<43>")
	)
	(segment
		(start 282.552394 -95.389446)
		(end 280.865326 -101.587808)
		(width 0.1651)
		(layer "In11.Cu")
		(net "P5E_PEX2_STN2_TX_DP<43>")
	)
	(segment
		(start 293.617396 -50.549048)
		(end 294.244014 -60.343288)
		(width 0.1651)
		(layer "In11.Cu")
		(net "P5E_PEX2_STN2_TX_DP<43>")
	)
	(segment
		(start 277.730966 -111.631222)
		(end 276.542246 -112.80267)
		(width 0.1651)
		(layer "In11.Cu")
		(net "P5E_PEX2_STN2_TX_DP<43>")
	)
	(segment
		(start 281.240992 -34.230056)
		(end 282.939744 -35.954716)
		(width 0.1651)
		(layer "In11.Cu")
		(net "P5E_PEX2_STN2_TX_DP<43>")
	)
	(segment
		(start 282.939744 -35.954716)
		(end 283.779976 -37.047678)
		(width 0.1651)
		(layer "In11.Cu")
		(net "P5E_PEX2_STN2_TX_DP<43>")
	)
	(segment
		(start 283.78023 -37.047678)
		(end 283.763974 -37.172392)
		(width 0.1651)
		(layer "In11.Cu")
		(net "P5E_PEX2_STN2_TX_DP<43>")
	)
	(segment
		(start 294.244014 -60.343288)
		(end 292.763702 -68.413884)
		(width 0.1651)
		(layer "In11.Cu")
		(net "P5E_PEX2_STN2_TX_DP<43>")
	)
	(segment
		(start 284.90291 -38.507924)
		(end 293.17823 -49.270158)
		(width 0.1651)
		(layer "In11.Cu")
		(net "P5E_PEX2_STN2_TX_DP<43>")
	)
	(segment
		(start 284.77845 -38.491668)
		(end 284.90291 -38.507924)
		(width 0.1651)
		(layer "In11.Cu")
		(net "P5E_PEX2_STN2_TX_DP<43>")
	)
	(segment
		(start 284.492446 -37.974016)
		(end 284.47619 -38.09873)
		(width 0.1651)
		(layer "In11.Cu")
		(net "P5E_PEX2_STN2_TX_DP<43>")
	)
	(segment
		(start 279.879552 -278.20493)
		(end 280.09469 -278.420068)
		(width 0.1143)
		(layer "In11.Cu")
		(net "P5E_PEX2_STN2_TX_DP<43>")
	)
	(segment
		(start 284.47619 -38.09873)
		(end 284.77845 -38.491668)
		(width 0.1651)
		(layer "In11.Cu")
		(net "P5E_PEX2_STN2_TX_DP<43>")
	)
	(segment
		(start 279.879552 -271.473168)
		(end 279.879552 -278.20493)
		(width 0.1143)
		(layer "In11.Cu")
		(net "P5E_PEX2_STN2_TX_DP<43>")
	)
	(segment
		(start 293.17823 -49.270158)
		(end 293.617396 -50.549048)
		(width 0.1651)
		(layer "In11.Cu")
		(net "P5E_PEX2_STN2_TX_DP<43>")
	)
	(segment
		(start 274.711414 -146.815048)
		(end 275.774658 -162.54476)
		(width 0.1651)
		(layer "In11.Cu")
		(net "P5E_PEX2_STN2_TX_DP<43>")
	)
	(segment
		(start 276.542246 -112.80267)
		(end 274.997164 -115.113054)
		(width 0.1651)
		(layer "In11.Cu")
		(net "P5E_PEX2_STN2_TX_DP<43>")
	)
	(segment
		(start 274.997164 -115.113054)
		(end 274.719288 -116.42979)
		(width 0.1651)
		(layer "In11.Cu")
		(net "P5E_PEX2_STN2_TX_DP<43>")
	)
	(segment
		(start 280.335482 -278.420068)
		(end 280.449782 -278.534368)
		(width 0.1143)
		(layer "In11.Cu")
		(net "P5E_PEX2_STN2_TX_DP<43>")
	)
	(segment
		(start 279.833832 -271.427448)
		(end 279.879552 -271.473168)
		(width 0.1143)
		(layer "In11.Cu")
		(net "P5E_PEX2_STN2_TX_DP<43>")
	)
	(segment
		(start 284.190694 -37.581586)
		(end 284.492446 -37.974016)
		(width 0.1651)
		(layer "In11.Cu")
		(net "P5E_PEX2_STN2_TX_DP<43>")
	)
	(segment
		(start 280.865326 -101.587808)
		(end 277.730966 -111.631222)
		(width 0.1651)
		(layer "In11.Cu")
		(net "P5E_PEX2_STN2_TX_DP<43>")
	)
	(segment
		(start 283.779976 -37.047678)
		(end 283.78023 -37.047678)
		(width 0.1651)
		(layer "In11.Cu")
		(net "P5E_PEX2_STN2_TX_DP<43>")
	)
	(segment
		(start 280.449782 -278.534368)
		(end 280.449782 -278.799798)
		(width 0.1143)
		(layer "In11.Cu")
		(net "P5E_PEX2_STN2_TX_DP<43>")
	)
	(segment
		(start 279.452832 -265.771376)
		(end 279.833832 -269.63751)
		(width 0.1651)
		(layer "In11.Cu")
		(net "P5E_PEX2_STN2_TX_DP<43>")
	)
	(segment
		(start 280.09469 -278.420068)
		(end 280.335482 -278.420068)
		(width 0.1143)
		(layer "In11.Cu")
		(net "P5E_PEX2_STN2_TX_DP<43>")
	)
	(segment
		(start 275.774658 -162.54476)
		(end 279.452832 -265.771376)
		(width 0.1651)
		(layer "In11.Cu")
		(net "P5E_PEX2_STN2_TX_DP<43>")
	)
	(segment
		(start 274.719288 -116.42979)
		(end 274.711414 -146.815048)
		(width 0.1651)
		(layer "In11.Cu")
		(net "P5E_PEX2_STN2_TX_DP<43>")
	)
	(segment
		(start 280.147268 -34.520886)
		(end 280.438098 -34.230056)
		(width 0.1651)
		(layer "In11.Cu")
		(net "P5E_PEX2_STN2_TX_DP<43>")
	)
	(segment
		(start 284.06598 -37.56533)
		(end 284.190694 -37.581586)
		(width 0.1651)
		(layer "In11.Cu")
		(net "P5E_PEX2_STN2_TX_DP<43>")
	)
	(segment
		(start 279.833832 -269.63751)
		(end 279.833832 -271.399)
		(width 0.1651)
		(layer "In11.Cu")
		(net "P5E_PEX2_STN2_TX_DP<43>")
	)
	(segment
		(start 279.833832 -271.399)
		(end 279.833832 -271.427448)
		(width 0.1143)
		(layer "In11.Cu")
		(net "P5E_PEX2_STN2_TX_DP<43>")
	)
	(segment
		(start 283.763974 -37.172392)
		(end 284.06598 -37.56533)
		(width 0.1651)
		(layer "In11.Cu")
		(net "P5E_PEX2_STN2_TX_DP<43>")
	)
	(segment
		(start 280.438098 -34.230056)
		(end 281.240992 -34.230056)
		(width 0.1651)
		(layer "In11.Cu")
		(net "P5E_PEX2_STN2_TX_DP<43>")
	)
	(segment
		(start 383.4257 -120.087898)
		(end 383.727198 -119.7864)
		(width 0.13462)
		(layer "F.Cu")
		(net "P5E_PEX3_STN1_TX_DN<24>")
	)
	(segment
		(start 384.344926 -119.7864)
		(end 384.671824 -120.113298)
		(width 0.13462)
		(layer "F.Cu")
		(net "P5E_PEX3_STN1_TX_DN<24>")
	)
	(segment
		(start 383.727198 -119.7864)
		(end 384.344926 -119.7864)
		(width 0.13462)
		(layer "F.Cu")
		(net "P5E_PEX3_STN1_TX_DN<24>")
	)
	(segment
		(start 415.215832 -271.471898)
		(end 415.215832 -264.235184)
		(width 0.1651)
		(layer "In9.Cu")
		(net "P5E_PEX3_STN1_TX_DN<24>")
	)
	(segment
		(start 381.426974 -120.868694)
		(end 381.588518 -120.868694)
		(width 0.1651)
		(layer "In9.Cu")
		(net "P5E_PEX3_STN1_TX_DN<24>")
	)
	(segment
		(start 379.932946 -123.705366)
		(end 379.932692 -123.705366)
		(width 0.1651)
		(layer "In9.Cu")
		(net "P5E_PEX3_STN1_TX_DN<24>")
	)
	(segment
		(start 379.81636 -158.457646)
		(end 379.45187 -151.045672)
		(width 0.1651)
		(layer "In9.Cu")
		(net "P5E_PEX3_STN1_TX_DN<24>")
	)
	(segment
		(start 378.724414 -126.889002)
		(end 378.909072 -126.442724)
		(width 0.1651)
		(layer "In9.Cu")
		(net "P5E_PEX3_STN1_TX_DN<24>")
	)
	(segment
		(start 378.591318 -126.943866)
		(end 378.724414 -126.889002)
		(width 0.1651)
		(layer "In9.Cu")
		(net "P5E_PEX3_STN1_TX_DN<24>")
	)
	(segment
		(start 415.170112 -271.546066)
		(end 415.215832 -271.500346)
		(width 0.1143)
		(layer "In9.Cu")
		(net "P5E_PEX3_STN1_TX_DN<24>")
	)
	(segment
		(start 383.13487 -119.797068)
		(end 383.4257 -120.087898)
		(width 0.1651)
		(layer "In9.Cu")
		(net "P5E_PEX3_STN1_TX_DN<24>")
	)
	(segment
		(start 379.485652 -124.784866)
		(end 379.618748 -124.730002)
		(width 0.1651)
		(layer "In9.Cu")
		(net "P5E_PEX3_STN1_TX_DN<24>")
	)
	(segment
		(start 380.697486 -122.124724)
		(end 380.642622 -121.992136)
		(width 0.1651)
		(layer "In9.Cu")
		(net "P5E_PEX3_STN1_TX_DN<24>")
	)
	(segment
		(start 381.929894 -120.365774)
		(end 382.4986 -119.797068)
		(width 0.1651)
		(layer "In9.Cu")
		(net "P5E_PEX3_STN1_TX_DN<24>")
	)
	(segment
		(start 379.803406 -124.283724)
		(end 379.748288 -124.151136)
		(width 0.1651)
		(layer "In9.Cu")
		(net "P5E_PEX3_STN1_TX_DN<24>")
	)
	(segment
		(start 380.379986 -122.625866)
		(end 380.512828 -122.571002)
		(width 0.1651)
		(layer "In9.Cu")
		(net "P5E_PEX3_STN1_TX_DN<24>")
	)
	(segment
		(start 380.642622 -121.992136)
		(end 380.882144 -121.413524)
		(width 0.1651)
		(layer "In9.Cu")
		(net "P5E_PEX3_STN1_TX_DN<24>")
	)
	(segment
		(start 415.170112 -278.12619)
		(end 415.170112 -271.546066)
		(width 0.1143)
		(layer "In9.Cu")
		(net "P5E_PEX3_STN1_TX_DN<24>")
	)
	(segment
		(start 379.618748 -124.730002)
		(end 379.803406 -124.283724)
		(width 0.1651)
		(layer "In9.Cu")
		(net "P5E_PEX3_STN1_TX_DN<24>")
	)
	(segment
		(start 378.853954 -126.310136)
		(end 379.038612 -125.864366)
		(width 0.1651)
		(layer "In9.Cu")
		(net "P5E_PEX3_STN1_TX_DN<24>")
	)
	(segment
		(start 378.144024 -128.023874)
		(end 378.144024 -128.02362)
		(width 0.1651)
		(layer "In9.Cu")
		(net "P5E_PEX3_STN1_TX_DN<24>")
	)
	(segment
		(start 377.489466 -129.604516)
		(end 377.696984 -129.103374)
		(width 0.1651)
		(layer "In9.Cu")
		(net "P5E_PEX3_STN1_TX_DN<24>")
	)
	(segment
		(start 379.171454 -125.809502)
		(end 379.356112 -125.363224)
		(width 0.1651)
		(layer "In9.Cu")
		(net "P5E_PEX3_STN1_TX_DN<24>")
	)
	(segment
		(start 379.084078 -143.564356)
		(end 376.529092 -137.396474)
		(width 0.1651)
		(layer "In9.Cu")
		(net "P5E_PEX3_STN1_TX_DN<24>")
	)
	(segment
		(start 415.435288 -278.229568)
		(end 415.27349 -278.229568)
		(width 0.1143)
		(layer "In9.Cu")
		(net "P5E_PEX3_STN1_TX_DN<24>")
	)
	(segment
		(start 415.215832 -264.235184)
		(end 380.394972 -161.3662)
		(width 0.1651)
		(layer "In9.Cu")
		(net "P5E_PEX3_STN1_TX_DN<24>")
	)
	(segment
		(start 380.394972 -161.3662)
		(end 379.81636 -158.457646)
		(width 0.1651)
		(layer "In9.Cu")
		(net "P5E_PEX3_STN1_TX_DN<24>")
	)
	(segment
		(start 378.27712 -127.968756)
		(end 378.461778 -127.522478)
		(width 0.1651)
		(layer "In9.Cu")
		(net "P5E_PEX3_STN1_TX_DN<24>")
	)
	(segment
		(start 376.529092 -137.396474)
		(end 376.529092 -131.92252)
		(width 0.1651)
		(layer "In9.Cu")
		(net "P5E_PEX3_STN1_TX_DN<24>")
	)
	(segment
		(start 378.461778 -127.522478)
		(end 378.40666 -127.38989)
		(width 0.1651)
		(layer "In9.Cu")
		(net "P5E_PEX3_STN1_TX_DN<24>")
	)
	(segment
		(start 377.829826 -129.04851)
		(end 378.014484 -128.602232)
		(width 0.1651)
		(layer "In9.Cu")
		(net "P5E_PEX3_STN1_TX_DN<24>")
	)
	(segment
		(start 377.359672 -130.183382)
		(end 377.544584 -129.737104)
		(width 0.1651)
		(layer "In9.Cu")
		(net "P5E_PEX3_STN1_TX_DN<24>")
	)
	(segment
		(start 380.195328 -123.071636)
		(end 380.379986 -122.625866)
		(width 0.1651)
		(layer "In9.Cu")
		(net "P5E_PEX3_STN1_TX_DN<24>")
	)
	(segment
		(start 378.909072 -126.442724)
		(end 378.853954 -126.310136)
		(width 0.1651)
		(layer "In9.Cu")
		(net "P5E_PEX3_STN1_TX_DN<24>")
	)
	(segment
		(start 379.356112 -125.363224)
		(end 379.300994 -125.230636)
		(width 0.1651)
		(layer "In9.Cu")
		(net "P5E_PEX3_STN1_TX_DN<24>")
	)
	(segment
		(start 378.014484 -128.602232)
		(end 377.959366 -128.469644)
		(width 0.1651)
		(layer "In9.Cu")
		(net "P5E_PEX3_STN1_TX_DN<24>")
	)
	(segment
		(start 379.748288 -124.151136)
		(end 379.932946 -123.705366)
		(width 0.1651)
		(layer "In9.Cu")
		(net "P5E_PEX3_STN1_TX_DN<24>")
	)
	(segment
		(start 376.529092 -131.92252)
		(end 377.22683 -130.238246)
		(width 0.1651)
		(layer "In9.Cu")
		(net "P5E_PEX3_STN1_TX_DN<24>")
	)
	(segment
		(start 378.144024 -128.02362)
		(end 378.27712 -127.968756)
		(width 0.1651)
		(layer "In9.Cu")
		(net "P5E_PEX3_STN1_TX_DN<24>")
	)
	(segment
		(start 377.959366 -128.469644)
		(end 378.144024 -128.023874)
		(width 0.1651)
		(layer "In9.Cu")
		(net "P5E_PEX3_STN1_TX_DN<24>")
	)
	(segment
		(start 378.591318 -126.94412)
		(end 378.591318 -126.943866)
		(width 0.1651)
		(layer "In9.Cu")
		(net "P5E_PEX3_STN1_TX_DN<24>")
	)
	(segment
		(start 378.40666 -127.38989)
		(end 378.591318 -126.94412)
		(width 0.1651)
		(layer "In9.Cu")
		(net "P5E_PEX3_STN1_TX_DN<24>")
	)
	(segment
		(start 415.215832 -271.500346)
		(end 415.215832 -271.471898)
		(width 0.1143)
		(layer "In9.Cu")
		(net "P5E_PEX3_STN1_TX_DN<24>")
	)
	(segment
		(start 377.69673 -129.103374)
		(end 377.829826 -129.04851)
		(width 0.1651)
		(layer "In9.Cu")
		(net "P5E_PEX3_STN1_TX_DN<24>")
	)
	(segment
		(start 379.45187 -151.045672)
		(end 379.084078 -143.564356)
		(width 0.1651)
		(layer "In9.Cu")
		(net "P5E_PEX3_STN1_TX_DN<24>")
	)
	(segment
		(start 379.038358 -125.864366)
		(end 379.171454 -125.809502)
		(width 0.1651)
		(layer "In9.Cu")
		(net "P5E_PEX3_STN1_TX_DN<24>")
	)
	(segment
		(start 382.4986 -119.797068)
		(end 383.13487 -119.797068)
		(width 0.1651)
		(layer "In9.Cu")
		(net "P5E_PEX3_STN1_TX_DN<24>")
	)
	(segment
		(start 379.038612 -125.864366)
		(end 379.038358 -125.864366)
		(width 0.1651)
		(layer "In9.Cu")
		(net "P5E_PEX3_STN1_TX_DN<24>")
	)
	(segment
		(start 379.932692 -123.705366)
		(end 380.065788 -123.650502)
		(width 0.1651)
		(layer "In9.Cu")
		(net "P5E_PEX3_STN1_TX_DN<24>")
	)
	(segment
		(start 380.250446 -123.204224)
		(end 380.195328 -123.071636)
		(width 0.1651)
		(layer "In9.Cu")
		(net "P5E_PEX3_STN1_TX_DN<24>")
	)
	(segment
		(start 377.22683 -130.238246)
		(end 377.359672 -130.183382)
		(width 0.1651)
		(layer "In9.Cu")
		(net "P5E_PEX3_STN1_TX_DN<24>")
	)
	(segment
		(start 380.065788 -123.650502)
		(end 380.250446 -123.204224)
		(width 0.1651)
		(layer "In9.Cu")
		(net "P5E_PEX3_STN1_TX_DN<24>")
	)
	(segment
		(start 377.696984 -129.103374)
		(end 377.69673 -129.103374)
		(width 0.1651)
		(layer "In9.Cu")
		(net "P5E_PEX3_STN1_TX_DN<24>")
	)
	(segment
		(start 381.929894 -120.527318)
		(end 381.929894 -120.365774)
		(width 0.1651)
		(layer "In9.Cu")
		(net "P5E_PEX3_STN1_TX_DN<24>")
	)
	(segment
		(start 380.882144 -121.413524)
		(end 381.426974 -120.868694)
		(width 0.1651)
		(layer "In9.Cu")
		(net "P5E_PEX3_STN1_TX_DN<24>")
	)
	(segment
		(start 415.27349 -278.229568)
		(end 415.170112 -278.12619)
		(width 0.1143)
		(layer "In9.Cu")
		(net "P5E_PEX3_STN1_TX_DN<24>")
	)
	(segment
		(start 380.512828 -122.571002)
		(end 380.697486 -122.124724)
		(width 0.1651)
		(layer "In9.Cu")
		(net "P5E_PEX3_STN1_TX_DN<24>")
	)
	(segment
		(start 379.300994 -125.230636)
		(end 379.485652 -124.784866)
		(width 0.1651)
		(layer "In9.Cu")
		(net "P5E_PEX3_STN1_TX_DN<24>")
	)
	(segment
		(start 415.549588 -277.849838)
		(end 415.549588 -278.115268)
		(width 0.1143)
		(layer "In9.Cu")
		(net "P5E_PEX3_STN1_TX_DN<24>")
	)
	(segment
		(start 377.544584 -129.737104)
		(end 377.489466 -129.604516)
		(width 0.1651)
		(layer "In9.Cu")
		(net "P5E_PEX3_STN1_TX_DN<24>")
	)
	(segment
		(start 415.549588 -278.115268)
		(end 415.435288 -278.229568)
		(width 0.1143)
		(layer "In9.Cu")
		(net "P5E_PEX3_STN1_TX_DN<24>")
	)
	(segment
		(start 381.588518 -120.868694)
		(end 381.929894 -120.527318)
		(width 0.1651)
		(layer "In9.Cu")
		(net "P5E_PEX3_STN1_TX_DN<24>")
	)
	(segment
		(start 377.974352 -343.365074)
		(end 377.974352 -342.734646)
		(width 0.13462)
		(layer "F.Cu")
		(net "P5E_PEX3_STN6_TX_DN<109>")
	)
	(segment
		(start 377.974352 -342.734646)
		(end 378.2695 -342.439498)
		(width 0.13462)
		(layer "F.Cu")
		(net "P5E_PEX3_STN6_TX_DN<109>")
	)
	(segment
		(start 378.2949 -343.685622)
		(end 377.974352 -343.365074)
		(width 0.13462)
		(layer "F.Cu")
		(net "P5E_PEX3_STN6_TX_DN<109>")
	)
	(segment
		(start 378.2695 -342.439498)
		(end 377.97867 -342.148668)
		(width 0.1651)
		(layer "In13.Cu")
		(net "P5E_PEX3_STN6_TX_DN<109>")
	)
	(segment
		(start 384.38201 -334.266032)
		(end 392.113008 -323.398388)
		(width 0.1651)
		(layer "In13.Cu")
		(net "P5E_PEX3_STN6_TX_DN<109>")
	)
	(segment
		(start 377.97867 -342.148668)
		(end 377.97867 -341.675974)
		(width 0.1651)
		(layer "In13.Cu")
		(net "P5E_PEX3_STN6_TX_DN<109>")
	)
	(segment
		(start 393.5857 -311.670192)
		(end 393.7 -311.784492)
		(width 0.1143)
		(layer "In13.Cu")
		(net "P5E_PEX3_STN6_TX_DN<109>")
	)
	(segment
		(start 393.365736 -321.12458)
		(end 393.365736 -320.046096)
		(width 0.1651)
		(layer "In13.Cu")
		(net "P5E_PEX3_STN6_TX_DN<109>")
	)
	(segment
		(start 393.365736 -320.017648)
		(end 393.320016 -319.971928)
		(width 0.1143)
		(layer "In13.Cu")
		(net "P5E_PEX3_STN6_TX_DN<109>")
	)
	(segment
		(start 393.365736 -320.046096)
		(end 393.365736 -320.017648)
		(width 0.1143)
		(layer "In13.Cu")
		(net "P5E_PEX3_STN6_TX_DN<109>")
	)
	(segment
		(start 393.7 -311.784492)
		(end 393.7 -312.049922)
		(width 0.1143)
		(layer "In13.Cu")
		(net "P5E_PEX3_STN6_TX_DN<109>")
	)
	(segment
		(start 393.210542 -321.49923)
		(end 393.365736 -321.12458)
		(width 0.1651)
		(layer "In13.Cu")
		(net "P5E_PEX3_STN6_TX_DN<109>")
	)
	(segment
		(start 377.97867 -341.675974)
		(end 384.38201 -334.266032)
		(width 0.1651)
		(layer "In13.Cu")
		(net "P5E_PEX3_STN6_TX_DN<109>")
	)
	(segment
		(start 393.423902 -311.670192)
		(end 393.5857 -311.670192)
		(width 0.1143)
		(layer "In13.Cu")
		(net "P5E_PEX3_STN6_TX_DN<109>")
	)
	(segment
		(start 393.320016 -319.971928)
		(end 393.320016 -311.774078)
		(width 0.1143)
		(layer "In13.Cu")
		(net "P5E_PEX3_STN6_TX_DN<109>")
	)
	(segment
		(start 393.320016 -311.774078)
		(end 393.423902 -311.670192)
		(width 0.1143)
		(layer "In13.Cu")
		(net "P5E_PEX3_STN6_TX_DN<109>")
	)
	(segment
		(start 392.113008 -323.398388)
		(end 393.210542 -321.49923)
		(width 0.1651)
		(layer "In13.Cu")
		(net "P5E_PEX3_STN6_TX_DN<109>")
	)
	(segment
		(start 50.716688 -350.685354)
		(end 50.396648 -350.365314)
		(width 0.13462)
		(layer "F.Cu")
		(net "P5E_PEX0_STN7_TX_C_DP<127>")
	)
	(segment
		(start 50.716688 -351.316798)
		(end 50.716688 -350.685354)
		(width 0.13462)
		(layer "F.Cu")
		(net "P5E_PEX0_STN7_TX_C_DP<127>")
	)
	(segment
		(start 50.422048 -351.611438)
		(end 50.716688 -351.316798)
		(width 0.13462)
		(layer "F.Cu")
		(net "P5E_PEX0_STN7_TX_C_DP<127>")
	)
	(segment
		(start 44.355512 -368.24793)
		(end 44.238164 -368.716306)
		(width 0.1651)
		(layer "In7.Cu")
		(net "P5E_PEX0_STN7_TX_C_DP<127>")
	)
	(segment
		(start 44.052744 -375.999248)
		(end 43.437048 -375.999248)
		(width 0.1651)
		(layer "In7.Cu")
		(net "P5E_PEX0_STN7_TX_C_DP<127>")
	)
	(segment
		(start 49.158398 -358.179878)
		(end 45.082714 -365.80445)
		(width 0.1651)
		(layer "In7.Cu")
		(net "P5E_PEX0_STN7_TX_C_DP<127>")
	)
	(segment
		(start 44.20235 -375.849642)
		(end 44.052744 -375.999248)
		(width 0.1651)
		(layer "In7.Cu")
		(net "P5E_PEX0_STN7_TX_C_DP<127>")
	)
	(segment
		(start 49.158398 -353.990402)
		(end 49.158398 -358.179878)
		(width 0.1651)
		(layer "In7.Cu")
		(net "P5E_PEX0_STN7_TX_C_DP<127>")
	)
	(segment
		(start 50.422048 -351.611438)
		(end 50.712878 -351.902268)
		(width 0.1651)
		(layer "In7.Cu")
		(net "P5E_PEX0_STN7_TX_C_DP<127>")
	)
	(segment
		(start 45.082714 -365.80445)
		(end 44.491148 -368.16665)
		(width 0.1651)
		(layer "In7.Cu")
		(net "P5E_PEX0_STN7_TX_C_DP<127>")
	)
	(segment
		(start 44.319444 -368.851688)
		(end 44.20235 -369.31981)
		(width 0.1651)
		(layer "In7.Cu")
		(net "P5E_PEX0_STN7_TX_C_DP<127>")
	)
	(segment
		(start 44.491148 -368.16665)
		(end 44.355512 -368.24793)
		(width 0.1651)
		(layer "In7.Cu")
		(net "P5E_PEX0_STN7_TX_C_DP<127>")
	)
	(segment
		(start 44.238164 -368.716306)
		(end 44.319444 -368.851688)
		(width 0.1651)
		(layer "In7.Cu")
		(net "P5E_PEX0_STN7_TX_C_DP<127>")
	)
	(segment
		(start 50.712878 -351.902268)
		(end 50.712878 -352.435922)
		(width 0.1651)
		(layer "In7.Cu")
		(net "P5E_PEX0_STN7_TX_C_DP<127>")
	)
	(segment
		(start 43.437048 -375.999248)
		(end 43.310048 -375.872248)
		(width 0.1651)
		(layer "In7.Cu")
		(net "P5E_PEX0_STN7_TX_C_DP<127>")
	)
	(segment
		(start 44.20235 -369.31981)
		(end 44.20235 -375.849642)
		(width 0.1651)
		(layer "In7.Cu")
		(net "P5E_PEX0_STN7_TX_C_DP<127>")
	)
	(segment
		(start 50.712878 -352.435922)
		(end 49.158398 -353.990402)
		(width 0.1651)
		(layer "In7.Cu")
		(net "P5E_PEX0_STN7_TX_C_DP<127>")
	)
	(segment
		(start 43.310048 -375.872248)
		(end 43.310048 -375.490232)
		(width 0.1651)
		(layer "In7.Cu")
		(net "P5E_PEX0_STN7_TX_C_DP<127>")
	)
	(segment
		(start 99.020884 -34.2265)
		(end 98.701098 -34.546286)
		(width 0.13462)
		(layer "F.Cu")
		(net "P5E_PEX0_STN2_TX_DP<35>")
	)
	(segment
		(start 99.652836 -34.2265)
		(end 99.020884 -34.2265)
		(width 0.13462)
		(layer "F.Cu")
		(net "P5E_PEX0_STN2_TX_DP<35>")
	)
	(segment
		(start 99.947222 -34.520886)
		(end 99.652836 -34.2265)
		(width 0.13462)
		(layer "F.Cu")
		(net "P5E_PEX0_STN2_TX_DP<35>")
	)
	(segment
		(start 78.787244 -104.92359)
		(end 77.080364 -118.187978)
		(width 0.1651)
		(layer "In11.Cu")
		(net "P5E_PEX0_STN2_TX_DP<35>")
	)
	(segment
		(start 74.345546 -161.487866)
		(end 55.233824 -265.45286)
		(width 0.1651)
		(layer "In11.Cu")
		(net "P5E_PEX0_STN2_TX_DP<35>")
	)
	(segment
		(start 104.069642 -67.800728)
		(end 101.964744 -70.921626)
		(width 0.1651)
		(layer "In11.Cu")
		(net "P5E_PEX0_STN2_TX_DP<35>")
	)
	(segment
		(start 76.113386 -141.757654)
		(end 75.8063 -149.233636)
		(width 0.1651)
		(layer "In11.Cu")
		(net "P5E_PEX0_STN2_TX_DP<35>")
	)
	(segment
		(start 102.296722 -35.82797)
		(end 105.894124 -42.518584)
		(width 0.1651)
		(layer "In11.Cu")
		(net "P5E_PEX0_STN2_TX_DP<35>")
	)
	(segment
		(start 101.907086 -35.344862)
		(end 102.141782 -35.781488)
		(width 0.1651)
		(layer "In11.Cu")
		(net "P5E_PEX0_STN2_TX_DP<35>")
	)
	(segment
		(start 95.166688 -77.751178)
		(end 95.166942 -77.751178)
		(width 0.1651)
		(layer "In11.Cu")
		(net "P5E_PEX0_STN2_TX_DP<35>")
	)
	(segment
		(start 101.262688 -34.336228)
		(end 101.719126 -34.754058)
		(width 0.1651)
		(layer "In11.Cu")
		(net "P5E_PEX0_STN2_TX_DP<35>")
	)
	(segment
		(start 99.947222 -34.520886)
		(end 100.238052 -34.230056)
		(width 0.1651)
		(layer "In11.Cu")
		(net "P5E_PEX0_STN2_TX_DP<35>")
	)
	(segment
		(start 101.96449 -70.921626)
		(end 99.860608 -74.041508)
		(width 0.1651)
		(layer "In11.Cu")
		(net "P5E_PEX0_STN2_TX_DP<35>")
	)
	(segment
		(start 55.233824 -265.45286)
		(end 55.233824 -271.399)
		(width 0.1651)
		(layer "In11.Cu")
		(net "P5E_PEX0_STN2_TX_DP<35>")
	)
	(segment
		(start 106.201972 -56.74106)
		(end 104.069642 -67.800728)
		(width 0.1651)
		(layer "In11.Cu")
		(net "P5E_PEX0_STN2_TX_DP<35>")
	)
	(segment
		(start 102.141782 -35.781488)
		(end 102.296722 -35.82797)
		(width 0.1651)
		(layer "In11.Cu")
		(net "P5E_PEX0_STN2_TX_DP<35>")
	)
	(segment
		(start 101.964744 -70.921626)
		(end 101.96449 -70.921626)
		(width 0.1651)
		(layer "In11.Cu")
		(net "P5E_PEX0_STN2_TX_DP<35>")
	)
	(segment
		(start 77.080364 -118.187978)
		(end 76.550774 -131.097782)
		(width 0.1651)
		(layer "In11.Cu")
		(net "P5E_PEX0_STN2_TX_DP<35>")
	)
	(segment
		(start 55.279544 -271.473168)
		(end 55.279544 -278.20493)
		(width 0.1143)
		(layer "In11.Cu")
		(net "P5E_PEX0_STN2_TX_DP<35>")
	)
	(segment
		(start 100.238052 -34.230056)
		(end 100.882704 -34.230056)
		(width 0.1651)
		(layer "In11.Cu")
		(net "P5E_PEX0_STN2_TX_DP<35>")
	)
	(segment
		(start 55.735474 -278.420068)
		(end 55.849774 -278.534368)
		(width 0.1143)
		(layer "In11.Cu")
		(net "P5E_PEX0_STN2_TX_DP<35>")
	)
	(segment
		(start 101.719126 -34.754058)
		(end 101.953568 -35.190176)
		(width 0.1651)
		(layer "In11.Cu")
		(net "P5E_PEX0_STN2_TX_DP<35>")
	)
	(segment
		(start 95.166942 -77.751178)
		(end 92.962476 -79.960724)
		(width 0.1651)
		(layer "In11.Cu")
		(net "P5E_PEX0_STN2_TX_DP<35>")
	)
	(segment
		(start 99.860608 -74.041508)
		(end 95.178626 -77.73924)
		(width 0.1651)
		(layer "In11.Cu")
		(net "P5E_PEX0_STN2_TX_DP<35>")
	)
	(segment
		(start 55.279544 -278.20493)
		(end 55.494682 -278.420068)
		(width 0.1143)
		(layer "In11.Cu")
		(net "P5E_PEX0_STN2_TX_DP<35>")
	)
	(segment
		(start 105.973626 -42.823892)
		(end 106.201972 -56.74106)
		(width 0.1651)
		(layer "In11.Cu")
		(net "P5E_PEX0_STN2_TX_DP<35>")
	)
	(segment
		(start 55.233824 -271.399)
		(end 55.233824 -271.427448)
		(width 0.1143)
		(layer "In11.Cu")
		(net "P5E_PEX0_STN2_TX_DP<35>")
	)
	(segment
		(start 92.962476 -79.960724)
		(end 78.787244 -104.92359)
		(width 0.1651)
		(layer "In11.Cu")
		(net "P5E_PEX0_STN2_TX_DP<35>")
	)
	(segment
		(start 95.178626 -77.73924)
		(end 95.166688 -77.751178)
		(width 0.1651)
		(layer "In11.Cu")
		(net "P5E_PEX0_STN2_TX_DP<35>")
	)
	(segment
		(start 55.849774 -278.534368)
		(end 55.849774 -278.799798)
		(width 0.1143)
		(layer "In11.Cu")
		(net "P5E_PEX0_STN2_TX_DP<35>")
	)
	(segment
		(start 105.894124 -42.518584)
		(end 105.973626 -42.823892)
		(width 0.1651)
		(layer "In11.Cu")
		(net "P5E_PEX0_STN2_TX_DP<35>")
	)
	(segment
		(start 76.550774 -139.865608)
		(end 76.113386 -141.757654)
		(width 0.1651)
		(layer "In11.Cu")
		(net "P5E_PEX0_STN2_TX_DP<35>")
	)
	(segment
		(start 55.233824 -271.427448)
		(end 55.279544 -271.473168)
		(width 0.1143)
		(layer "In11.Cu")
		(net "P5E_PEX0_STN2_TX_DP<35>")
	)
	(segment
		(start 55.494682 -278.420068)
		(end 55.735474 -278.420068)
		(width 0.1143)
		(layer "In11.Cu")
		(net "P5E_PEX0_STN2_TX_DP<35>")
	)
	(segment
		(start 100.882704 -34.230056)
		(end 101.262688 -34.336228)
		(width 0.1651)
		(layer "In11.Cu")
		(net "P5E_PEX0_STN2_TX_DP<35>")
	)
	(segment
		(start 75.8063 -149.233636)
		(end 74.345546 -161.487866)
		(width 0.1651)
		(layer "In11.Cu")
		(net "P5E_PEX0_STN2_TX_DP<35>")
	)
	(segment
		(start 76.550774 -131.097782)
		(end 76.550774 -139.865608)
		(width 0.1651)
		(layer "In11.Cu")
		(net "P5E_PEX0_STN2_TX_DP<35>")
	)
	(segment
		(start 101.953568 -35.190176)
		(end 101.907086 -35.344862)
		(width 0.1651)
		(layer "In11.Cu")
		(net "P5E_PEX0_STN2_TX_DP<35>")
	)
	(segment
		(start 163.12261 -30.353)
		(end 162.8013 -30.03169)
		(width 0.13462)
		(layer "F.Cu")
		(net "P5E_PEX1_STN2_TX_DN<41>")
	)
	(segment
		(start 163.751514 -30.353)
		(end 163.12261 -30.353)
		(width 0.13462)
		(layer "F.Cu")
		(net "P5E_PEX1_STN2_TX_DN<41>")
	)
	(segment
		(start 164.047424 -30.05709)
		(end 163.751514 -30.353)
		(width 0.13462)
		(layer "F.Cu")
		(net "P5E_PEX1_STN2_TX_DN<41>")
	)
	(segment
		(start 165.219634 -30.525212)
		(end 167.789098 -33.072578)
		(width 0.1651)
		(layer "In11.Cu")
		(net "P5E_PEX1_STN2_TX_DN<41>")
	)
	(segment
		(start 164.78885 -30.34792)
		(end 165.219634 -30.525212)
		(width 0.1651)
		(layer "In11.Cu")
		(net "P5E_PEX1_STN2_TX_DN<41>")
	)
	(segment
		(start 167.789098 -33.072578)
		(end 169.127678 -35.26917)
		(width 0.1651)
		(layer "In11.Cu")
		(net "P5E_PEX1_STN2_TX_DN<41>")
	)
	(segment
		(start 180.372258 -60.550298)
		(end 179.859178 -69.628766)
		(width 0.1651)
		(layer "In11.Cu")
		(net "P5E_PEX1_STN2_TX_DN<41>")
	)
	(segment
		(start 164.047424 -30.05709)
		(end 164.338254 -30.34792)
		(width 0.1651)
		(layer "In11.Cu")
		(net "P5E_PEX1_STN2_TX_DN<41>")
	)
	(segment
		(start 171.57192 -135.163052)
		(end 165.199822 -252.662436)
		(width 0.1651)
		(layer "In11.Cu")
		(net "P5E_PEX1_STN2_TX_DN<41>")
	)
	(segment
		(start 166.135558 -278.229568)
		(end 166.249858 -278.115268)
		(width 0.1143)
		(layer "In11.Cu")
		(net "P5E_PEX1_STN2_TX_DN<41>")
	)
	(segment
		(start 165.915848 -271.427448)
		(end 165.870128 -271.473168)
		(width 0.1143)
		(layer "In11.Cu")
		(net "P5E_PEX1_STN2_TX_DN<41>")
	)
	(segment
		(start 165.870128 -278.125936)
		(end 165.97376 -278.229568)
		(width 0.1143)
		(layer "In11.Cu")
		(net "P5E_PEX1_STN2_TX_DN<41>")
	)
	(segment
		(start 179.023264 -48.058832)
		(end 179.718208 -50.066194)
		(width 0.1651)
		(layer "In11.Cu")
		(net "P5E_PEX1_STN2_TX_DN<41>")
	)
	(segment
		(start 166.249858 -278.115268)
		(end 166.249858 -277.849838)
		(width 0.1143)
		(layer "In11.Cu")
		(net "P5E_PEX1_STN2_TX_DN<41>")
	)
	(segment
		(start 179.859178 -69.628766)
		(end 172.901102 -119.31269)
		(width 0.1651)
		(layer "In11.Cu")
		(net "P5E_PEX1_STN2_TX_DN<41>")
	)
	(segment
		(start 165.551612 -266.126976)
		(end 165.915848 -269.827756)
		(width 0.1651)
		(layer "In11.Cu")
		(net "P5E_PEX1_STN2_TX_DN<41>")
	)
	(segment
		(start 165.915848 -271.399)
		(end 165.915848 -271.427448)
		(width 0.1143)
		(layer "In11.Cu")
		(net "P5E_PEX1_STN2_TX_DN<41>")
	)
	(segment
		(start 179.718208 -50.066194)
		(end 180.372258 -60.550298)
		(width 0.1651)
		(layer "In11.Cu")
		(net "P5E_PEX1_STN2_TX_DN<41>")
	)
	(segment
		(start 165.870128 -271.473168)
		(end 165.870128 -278.125936)
		(width 0.1143)
		(layer "In11.Cu")
		(net "P5E_PEX1_STN2_TX_DN<41>")
	)
	(segment
		(start 164.338254 -30.34792)
		(end 164.78885 -30.34792)
		(width 0.1651)
		(layer "In11.Cu")
		(net "P5E_PEX1_STN2_TX_DN<41>")
	)
	(segment
		(start 165.97376 -278.229568)
		(end 166.135558 -278.229568)
		(width 0.1143)
		(layer "In11.Cu")
		(net "P5E_PEX1_STN2_TX_DN<41>")
	)
	(segment
		(start 169.127678 -35.26917)
		(end 179.023264 -48.058832)
		(width 0.1651)
		(layer "In11.Cu")
		(net "P5E_PEX1_STN2_TX_DN<41>")
	)
	(segment
		(start 165.915848 -269.827756)
		(end 165.915848 -271.399)
		(width 0.1651)
		(layer "In11.Cu")
		(net "P5E_PEX1_STN2_TX_DN<41>")
	)
	(segment
		(start 165.199822 -252.662436)
		(end 165.551612 -266.126976)
		(width 0.1651)
		(layer "In11.Cu")
		(net "P5E_PEX1_STN2_TX_DN<41>")
	)
	(segment
		(start 172.901102 -119.31269)
		(end 171.57192 -135.163052)
		(width 0.1651)
		(layer "In11.Cu")
		(net "P5E_PEX1_STN2_TX_DN<41>")
	)
	(segment
		(start 331.22235 -30.353)
		(end 330.90104 -30.03169)
		(width 0.13462)
		(layer "F.Cu")
		(net "P5E_PEX2_STN2_TX_DN<33>")
	)
	(segment
		(start 331.851254 -30.353)
		(end 331.22235 -30.353)
		(width 0.13462)
		(layer "F.Cu")
		(net "P5E_PEX2_STN2_TX_DN<33>")
	)
	(segment
		(start 332.147164 -30.05709)
		(end 331.851254 -30.353)
		(width 0.13462)
		(layer "F.Cu")
		(net "P5E_PEX2_STN2_TX_DN<33>")
	)
	(segment
		(start 289.61588 -271.399)
		(end 289.61588 -271.427448)
		(width 0.1143)
		(layer "In11.Cu")
		(net "P5E_PEX2_STN2_TX_DN<33>")
	)
	(segment
		(start 310.942736 -140.401802)
		(end 310.599582 -141.878812)
		(width 0.1651)
		(layer "In11.Cu")
		(net "P5E_PEX2_STN2_TX_DN<33>")
	)
	(segment
		(start 289.673792 -278.229568)
		(end 289.83559 -278.229568)
		(width 0.1143)
		(layer "In11.Cu")
		(net "P5E_PEX2_STN2_TX_DN<33>")
	)
	(segment
		(start 328.705464 -79.581502)
		(end 326.907398 -81.35493)
		(width 0.1651)
		(layer "In11.Cu")
		(net "P5E_PEX2_STN2_TX_DN<33>")
	)
	(segment
		(start 289.83559 -278.229568)
		(end 289.94989 -278.115268)
		(width 0.1143)
		(layer "In11.Cu")
		(net "P5E_PEX2_STN2_TX_DN<33>")
	)
	(segment
		(start 320.058796 -93.454728)
		(end 320.058796 -93.454474)
		(width 0.1651)
		(layer "In11.Cu")
		(net "P5E_PEX2_STN2_TX_DN<33>")
	)
	(segment
		(start 309.872634 -153.6319)
		(end 308.878732 -161.060384)
		(width 0.1651)
		(layer "In11.Cu")
		(net "P5E_PEX2_STN2_TX_DN<33>")
	)
	(segment
		(start 323.48297 -87.404956)
		(end 320.058796 -93.454728)
		(width 0.1651)
		(layer "In11.Cu")
		(net "P5E_PEX2_STN2_TX_DN<33>")
	)
	(segment
		(start 332.939136 -30.34792)
		(end 333.547974 -30.615128)
		(width 0.1651)
		(layer "In11.Cu")
		(net "P5E_PEX2_STN2_TX_DN<33>")
	)
	(segment
		(start 289.94989 -278.115268)
		(end 289.94989 -277.849838)
		(width 0.1143)
		(layer "In11.Cu")
		(net "P5E_PEX2_STN2_TX_DN<33>")
	)
	(segment
		(start 320.058796 -93.454474)
		(end 313.210448 -105.554018)
		(width 0.1651)
		(layer "In11.Cu")
		(net "P5E_PEX2_STN2_TX_DN<33>")
	)
	(segment
		(start 335.2927 -76.002388)
		(end 328.705464 -79.581502)
		(width 0.1651)
		(layer "In11.Cu")
		(net "P5E_PEX2_STN2_TX_DN<33>")
	)
	(segment
		(start 339.860382 -40.622982)
		(end 340.370414 -42.544492)
		(width 0.1651)
		(layer "In11.Cu")
		(net "P5E_PEX2_STN2_TX_DN<33>")
	)
	(segment
		(start 335.394046 -32.441388)
		(end 339.860382 -40.622982)
		(width 0.1651)
		(layer "In11.Cu")
		(net "P5E_PEX2_STN2_TX_DN<33>")
	)
	(segment
		(start 310.599582 -141.878812)
		(end 310.327548 -148.24456)
		(width 0.1651)
		(layer "In11.Cu")
		(net "P5E_PEX2_STN2_TX_DN<33>")
	)
	(segment
		(start 333.547974 -30.615128)
		(end 335.394046 -32.441388)
		(width 0.1651)
		(layer "In11.Cu")
		(net "P5E_PEX2_STN2_TX_DN<33>")
	)
	(segment
		(start 340.643464 -56.860948)
		(end 338.37626 -68.499228)
		(width 0.1651)
		(layer "In11.Cu")
		(net "P5E_PEX2_STN2_TX_DN<33>")
	)
	(segment
		(start 326.907398 -81.35493)
		(end 323.48297 -87.404956)
		(width 0.1651)
		(layer "In11.Cu")
		(net "P5E_PEX2_STN2_TX_DN<33>")
	)
	(segment
		(start 289.61588 -271.427448)
		(end 289.57016 -271.473168)
		(width 0.1143)
		(layer "In11.Cu")
		(net "P5E_PEX2_STN2_TX_DN<33>")
	)
	(segment
		(start 310.942736 -133.840982)
		(end 310.942736 -140.401802)
		(width 0.1651)
		(layer "In11.Cu")
		(net "P5E_PEX2_STN2_TX_DN<33>")
	)
	(segment
		(start 338.37626 -68.499228)
		(end 336.069432 -74.95667)
		(width 0.1651)
		(layer "In11.Cu")
		(net "P5E_PEX2_STN2_TX_DN<33>")
	)
	(segment
		(start 310.327548 -148.24456)
		(end 310.100472 -150.936706)
		(width 0.1651)
		(layer "In11.Cu")
		(net "P5E_PEX2_STN2_TX_DN<33>")
	)
	(segment
		(start 311.595262 -118.553992)
		(end 310.942736 -133.840982)
		(width 0.1651)
		(layer "In11.Cu")
		(net "P5E_PEX2_STN2_TX_DN<33>")
	)
	(segment
		(start 332.589378 -30.34792)
		(end 332.939136 -30.34792)
		(width 0.1651)
		(layer "In11.Cu")
		(net "P5E_PEX2_STN2_TX_DN<33>")
	)
	(segment
		(start 340.370414 -42.544492)
		(end 340.643464 -56.860948)
		(width 0.1651)
		(layer "In11.Cu")
		(net "P5E_PEX2_STN2_TX_DN<33>")
	)
	(segment
		(start 313.210448 -105.554018)
		(end 311.595262 -118.553992)
		(width 0.1651)
		(layer "In11.Cu")
		(net "P5E_PEX2_STN2_TX_DN<33>")
	)
	(segment
		(start 289.61588 -265.859514)
		(end 289.61588 -271.399)
		(width 0.1651)
		(layer "In11.Cu")
		(net "P5E_PEX2_STN2_TX_DN<33>")
	)
	(segment
		(start 332.147164 -30.05709)
		(end 332.330552 -30.240478)
		(width 0.1651)
		(layer "In11.Cu")
		(net "P5E_PEX2_STN2_TX_DN<33>")
	)
	(segment
		(start 310.100218 -150.936706)
		(end 309.872634 -153.6319)
		(width 0.1651)
		(layer "In11.Cu")
		(net "P5E_PEX2_STN2_TX_DN<33>")
	)
	(segment
		(start 289.57016 -271.473168)
		(end 289.57016 -278.125936)
		(width 0.1143)
		(layer "In11.Cu")
		(net "P5E_PEX2_STN2_TX_DN<33>")
	)
	(segment
		(start 336.069432 -74.95667)
		(end 335.2927 -76.002388)
		(width 0.1651)
		(layer "In11.Cu")
		(net "P5E_PEX2_STN2_TX_DN<33>")
	)
	(segment
		(start 308.878732 -161.060384)
		(end 289.61588 -265.859514)
		(width 0.1651)
		(layer "In11.Cu")
		(net "P5E_PEX2_STN2_TX_DN<33>")
	)
	(segment
		(start 310.100472 -150.936706)
		(end 310.100218 -150.936706)
		(width 0.1651)
		(layer "In11.Cu")
		(net "P5E_PEX2_STN2_TX_DN<33>")
	)
	(segment
		(start 289.57016 -278.125936)
		(end 289.673792 -278.229568)
		(width 0.1143)
		(layer "In11.Cu")
		(net "P5E_PEX2_STN2_TX_DN<33>")
	)
	(segment
		(start 332.330552 -30.240478)
		(end 332.589378 -30.34792)
		(width 0.1651)
		(layer "In11.Cu")
		(net "P5E_PEX2_STN2_TX_DN<33>")
	)
	(segment
		(start 429.832262 -154.279346)
		(end 429.527716 -153.9748)
		(width 0.13462)
		(layer "F.Cu")
		(net "P5E_PEX3_STN0_TX_DN<14>")
	)
	(segment
		(start 428.916084 -153.9748)
		(end 428.586138 -154.304746)
		(width 0.13462)
		(layer "F.Cu")
		(net "P5E_PEX3_STN0_TX_DN<14>")
	)
	(segment
		(start 429.527716 -153.9748)
		(end 428.916084 -153.9748)
		(width 0.13462)
		(layer "F.Cu")
		(net "P5E_PEX3_STN0_TX_DN<14>")
	)
	(segment
		(start 424.376088 -260.679438)
		(end 420.927784 -221.249748)
		(width 0.1651)
		(layer "In9.Cu")
		(net "P5E_PEX3_STN0_TX_DN<14>")
	)
	(segment
		(start 424.51274 -179.246022)
		(end 424.55592 -178.752246)
		(width 0.1651)
		(layer "In9.Cu")
		(net "P5E_PEX3_STN0_TX_DN<14>")
	)
	(segment
		(start 423.48404 -271.526)
		(end 423.48404 -269.758414)
		(width 0.1651)
		(layer "In9.Cu")
		(net "P5E_PEX3_STN0_TX_DN<14>")
	)
	(segment
		(start 424.816778 -176.794414)
		(end 426.32503 -171.164758)
		(width 0.1651)
		(layer "In9.Cu")
		(net "P5E_PEX3_STN0_TX_DN<14>")
	)
	(segment
		(start 434.38699 -155.254706)
		(end 433.1208 -153.988516)
		(width 0.1651)
		(layer "In9.Cu")
		(net "P5E_PEX3_STN0_TX_DN<14>")
	)
	(segment
		(start 423.744898 -280.319988)
		(end 423.52976 -280.10485)
		(width 0.1143)
		(layer "In9.Cu")
		(net "P5E_PEX3_STN0_TX_DN<14>")
	)
	(segment
		(start 424.55084 -179.835556)
		(end 424.593766 -179.342288)
		(width 0.1651)
		(layer "In9.Cu")
		(net "P5E_PEX3_STN0_TX_DN<14>")
	)
	(segment
		(start 423.98569 -280.319988)
		(end 423.744898 -280.319988)
		(width 0.1143)
		(layer "In9.Cu")
		(net "P5E_PEX3_STN0_TX_DN<14>")
	)
	(segment
		(start 424.491912 -180.50637)
		(end 424.410886 -180.410104)
		(width 0.1651)
		(layer "In9.Cu")
		(net "P5E_PEX3_STN0_TX_DN<14>")
	)
	(segment
		(start 424.69562 -178.178206)
		(end 424.614848 -178.08194)
		(width 0.1651)
		(layer "In9.Cu")
		(net "P5E_PEX3_STN0_TX_DN<14>")
	)
	(segment
		(start 434.641244 -155.868624)
		(end 434.38699 -155.254706)
		(width 0.1651)
		(layer "In9.Cu")
		(net "P5E_PEX3_STN0_TX_DN<14>")
	)
	(segment
		(start 424.658028 -177.588418)
		(end 424.754548 -177.507646)
		(width 0.1651)
		(layer "In9.Cu")
		(net "P5E_PEX3_STN0_TX_DN<14>")
	)
	(segment
		(start 424.410886 -180.410104)
		(end 424.454066 -179.916328)
		(width 0.1651)
		(layer "In9.Cu")
		(net "P5E_PEX3_STN0_TX_DN<14>")
	)
	(segment
		(start 424.652694 -178.671474)
		(end 424.69562 -178.178206)
		(width 0.1651)
		(layer "In9.Cu")
		(net "P5E_PEX3_STN0_TX_DN<14>")
	)
	(segment
		(start 424.593766 -179.342288)
		(end 424.51274 -179.246022)
		(width 0.1651)
		(layer "In9.Cu")
		(net "P5E_PEX3_STN0_TX_DN<14>")
	)
	(segment
		(start 424.09999 -280.434288)
		(end 423.98569 -280.319988)
		(width 0.1143)
		(layer "In9.Cu")
		(net "P5E_PEX3_STN0_TX_DN<14>")
	)
	(segment
		(start 424.754548 -177.507646)
		(end 424.816778 -176.794414)
		(width 0.1651)
		(layer "In9.Cu")
		(net "P5E_PEX3_STN0_TX_DN<14>")
	)
	(segment
		(start 423.52976 -271.600168)
		(end 423.48404 -271.554448)
		(width 0.1143)
		(layer "In9.Cu")
		(net "P5E_PEX3_STN0_TX_DN<14>")
	)
	(segment
		(start 424.09999 -280.699718)
		(end 424.09999 -280.434288)
		(width 0.1143)
		(layer "In9.Cu")
		(net "P5E_PEX3_STN0_TX_DN<14>")
	)
	(segment
		(start 420.927784 -221.249748)
		(end 424.491912 -180.50637)
		(width 0.1651)
		(layer "In9.Cu")
		(net "P5E_PEX3_STN0_TX_DN<14>")
	)
	(segment
		(start 424.614848 -178.08194)
		(end 424.658028 -177.588418)
		(width 0.1651)
		(layer "In9.Cu")
		(net "P5E_PEX3_STN0_TX_DN<14>")
	)
	(segment
		(start 433.1208 -153.988516)
		(end 430.123092 -153.988516)
		(width 0.1651)
		(layer "In9.Cu")
		(net "P5E_PEX3_STN0_TX_DN<14>")
	)
	(segment
		(start 434.641244 -156.760164)
		(end 434.641244 -155.868624)
		(width 0.1651)
		(layer "In9.Cu")
		(net "P5E_PEX3_STN0_TX_DN<14>")
	)
	(segment
		(start 424.55592 -178.752246)
		(end 424.652694 -178.671474)
		(width 0.1651)
		(layer "In9.Cu")
		(net "P5E_PEX3_STN0_TX_DN<14>")
	)
	(segment
		(start 430.123092 -153.988516)
		(end 429.832262 -154.279346)
		(width 0.1651)
		(layer "In9.Cu")
		(net "P5E_PEX3_STN0_TX_DN<14>")
	)
	(segment
		(start 426.32503 -171.164758)
		(end 434.641244 -156.760164)
		(width 0.1651)
		(layer "In9.Cu")
		(net "P5E_PEX3_STN0_TX_DN<14>")
	)
	(segment
		(start 424.376088 -267.60424)
		(end 424.376088 -260.679438)
		(width 0.1651)
		(layer "In9.Cu")
		(net "P5E_PEX3_STN0_TX_DN<14>")
	)
	(segment
		(start 423.52976 -280.10485)
		(end 423.52976 -271.600168)
		(width 0.1143)
		(layer "In9.Cu")
		(net "P5E_PEX3_STN0_TX_DN<14>")
	)
	(segment
		(start 423.48404 -271.554448)
		(end 423.48404 -271.526)
		(width 0.1143)
		(layer "In9.Cu")
		(net "P5E_PEX3_STN0_TX_DN<14>")
	)
	(segment
		(start 424.454066 -179.916328)
		(end 424.55084 -179.835556)
		(width 0.1651)
		(layer "In9.Cu")
		(net "P5E_PEX3_STN0_TX_DN<14>")
	)
	(segment
		(start 423.48404 -269.758414)
		(end 424.376088 -267.60424)
		(width 0.1651)
		(layer "In9.Cu")
		(net "P5E_PEX3_STN0_TX_DN<14>")
	)
	(segment
		(start 383.59842 -355.978206)
		(end 383.917952 -355.658674)
		(width 0.13462)
		(layer "F.Cu")
		(net "P5E_PEX3_STN6_TX_DP<105>")
	)
	(segment
		(start 383.917952 -355.658674)
		(end 383.917952 -355.026214)
		(width 0.13462)
		(layer "F.Cu")
		(net "P5E_PEX3_STN6_TX_DP<105>")
	)
	(segment
		(start 383.917952 -355.026214)
		(end 383.62382 -354.732082)
		(width 0.13462)
		(layer "F.Cu")
		(net "P5E_PEX3_STN6_TX_DP<105>")
	)
	(segment
		(start 397.144748 -311.479692)
		(end 397.38554 -311.479692)
		(width 0.1143)
		(layer "In13.Cu")
		(net "P5E_PEX3_STN6_TX_DP<105>")
	)
	(segment
		(start 396.88389 -322.303902)
		(end 396.88389 -320.046096)
		(width 0.1651)
		(layer "In13.Cu")
		(net "P5E_PEX3_STN6_TX_DP<105>")
	)
	(segment
		(start 385.46913 -342.217248)
		(end 385.725416 -341.25408)
		(width 0.1651)
		(layer "In13.Cu")
		(net "P5E_PEX3_STN6_TX_DP<105>")
	)
	(segment
		(start 385.725416 -341.25408)
		(end 389.920734 -334.953356)
		(width 0.1651)
		(layer "In13.Cu")
		(net "P5E_PEX3_STN6_TX_DP<105>")
	)
	(segment
		(start 385.46913 -352.259646)
		(end 385.46913 -342.217248)
		(width 0.1651)
		(layer "In13.Cu")
		(net "P5E_PEX3_STN6_TX_DP<105>")
	)
	(segment
		(start 383.91465 -354.441252)
		(end 383.91465 -353.814126)
		(width 0.1651)
		(layer "In13.Cu")
		(net "P5E_PEX3_STN6_TX_DP<105>")
	)
	(segment
		(start 389.920734 -334.953356)
		(end 395.165072 -325.89343)
		(width 0.1651)
		(layer "In13.Cu")
		(net "P5E_PEX3_STN6_TX_DP<105>")
	)
	(segment
		(start 396.92961 -319.971928)
		(end 396.92961 -311.69483)
		(width 0.1143)
		(layer "In13.Cu")
		(net "P5E_PEX3_STN6_TX_DP<105>")
	)
	(segment
		(start 395.165072 -325.89343)
		(end 396.545308 -323.121274)
		(width 0.1651)
		(layer "In13.Cu")
		(net "P5E_PEX3_STN6_TX_DP<105>")
	)
	(segment
		(start 383.62382 -354.732082)
		(end 383.91465 -354.441252)
		(width 0.1651)
		(layer "In13.Cu")
		(net "P5E_PEX3_STN6_TX_DP<105>")
	)
	(segment
		(start 396.88389 -320.017648)
		(end 396.92961 -319.971928)
		(width 0.1143)
		(layer "In13.Cu")
		(net "P5E_PEX3_STN6_TX_DP<105>")
	)
	(segment
		(start 383.91465 -353.814126)
		(end 385.46913 -352.259646)
		(width 0.1651)
		(layer "In13.Cu")
		(net "P5E_PEX3_STN6_TX_DP<105>")
	)
	(segment
		(start 397.38554 -311.479692)
		(end 397.49984 -311.365392)
		(width 0.1143)
		(layer "In13.Cu")
		(net "P5E_PEX3_STN6_TX_DP<105>")
	)
	(segment
		(start 396.545308 -323.121274)
		(end 396.88389 -322.303902)
		(width 0.1651)
		(layer "In13.Cu")
		(net "P5E_PEX3_STN6_TX_DP<105>")
	)
	(segment
		(start 396.92961 -311.69483)
		(end 397.144748 -311.479692)
		(width 0.1143)
		(layer "In13.Cu")
		(net "P5E_PEX3_STN6_TX_DP<105>")
	)
	(segment
		(start 397.49984 -311.365392)
		(end 397.49984 -311.099962)
		(width 0.1143)
		(layer "In13.Cu")
		(net "P5E_PEX3_STN6_TX_DP<105>")
	)
	(segment
		(start 396.88389 -320.046096)
		(end 396.88389 -320.017648)
		(width 0.1143)
		(layer "In13.Cu")
		(net "P5E_PEX3_STN6_TX_DP<105>")
	)
	(segment
		(start 74.109834 -371.972078)
		(end 74.236834 -372.099078)
		(width 0.1651)
		(layer "In5.Cu")
		(net "P5E_PEX0_STN5_RX_DP<89>")
	)
	(segment
		(start 75.080368 -367.162588)
		(end 75.10399 -366.680242)
		(width 0.1651)
		(layer "In5.Cu")
		(net "P5E_PEX0_STN5_RX_DP<89>")
	)
	(segment
		(start 75.00239 -371.86743)
		(end 75.00239 -369.410742)
		(width 0.1651)
		(layer "In5.Cu")
		(net "P5E_PEX0_STN5_RX_DP<89>")
	)
	(segment
		(start 75.00239 -369.410742)
		(end 75.161394 -367.793524)
		(width 0.1651)
		(layer "In5.Cu")
		(net "P5E_PEX0_STN5_RX_DP<89>")
	)
	(segment
		(start 75.221338 -366.57407)
		(end 75.24496 -366.092232)
		(width 0.1651)
		(layer "In5.Cu")
		(net "P5E_PEX0_STN5_RX_DP<89>")
	)
	(segment
		(start 74.236834 -372.099078)
		(end 74.770742 -372.099078)
		(width 0.1651)
		(layer "In5.Cu")
		(net "P5E_PEX0_STN5_RX_DP<89>")
	)
	(segment
		(start 75.653392 -357.77043)
		(end 75.653392 -342.26627)
		(width 0.1651)
		(layer "In5.Cu")
		(net "P5E_PEX0_STN5_RX_DP<89>")
	)
	(segment
		(start 75.18654 -367.279682)
		(end 75.080368 -367.162588)
		(width 0.1651)
		(layer "In5.Cu")
		(net "P5E_PEX0_STN5_RX_DP<89>")
	)
	(segment
		(start 67.297554 -324.601078)
		(end 66.633852 -321.648074)
		(width 0.1651)
		(layer "In5.Cu")
		(net "P5E_PEX0_STN5_RX_DP<89>")
	)
	(segment
		(start 75.653392 -342.26627)
		(end 67.297554 -324.601078)
		(width 0.1651)
		(layer "In5.Cu")
		(net "P5E_PEX0_STN5_RX_DP<89>")
	)
	(segment
		(start 75.279504 -365.38662)
		(end 75.653392 -357.77043)
		(width 0.1651)
		(layer "In5.Cu")
		(net "P5E_PEX0_STN5_RX_DP<89>")
	)
	(segment
		(start 66.633852 -319.995296)
		(end 66.633852 -319.966848)
		(width 0.1143)
		(layer "In5.Cu")
		(net "P5E_PEX0_STN5_RX_DP<89>")
	)
	(segment
		(start 75.142852 -365.510318)
		(end 75.279504 -365.38662)
		(width 0.1651)
		(layer "In5.Cu")
		(net "P5E_PEX0_STN5_RX_DP<89>")
	)
	(segment
		(start 75.161394 -367.793524)
		(end 75.18654 -367.279682)
		(width 0.1651)
		(layer "In5.Cu")
		(net "P5E_PEX0_STN5_RX_DP<89>")
	)
	(segment
		(start 75.10399 -366.680242)
		(end 75.221338 -366.57407)
		(width 0.1651)
		(layer "In5.Cu")
		(net "P5E_PEX0_STN5_RX_DP<89>")
	)
	(segment
		(start 75.24496 -366.092232)
		(end 75.121262 -365.95558)
		(width 0.1651)
		(layer "In5.Cu")
		(net "P5E_PEX0_STN5_RX_DP<89>")
	)
	(segment
		(start 67.249802 -318.015366)
		(end 67.249802 -317.749936)
		(width 0.1143)
		(layer "In5.Cu")
		(net "P5E_PEX0_STN5_RX_DP<89>")
	)
	(segment
		(start 67.135502 -318.129666)
		(end 67.249802 -318.015366)
		(width 0.1143)
		(layer "In5.Cu")
		(net "P5E_PEX0_STN5_RX_DP<89>")
	)
	(segment
		(start 74.109834 -371.590062)
		(end 74.109834 -371.972078)
		(width 0.1651)
		(layer "In5.Cu")
		(net "P5E_PEX0_STN5_RX_DP<89>")
	)
	(segment
		(start 66.905378 -318.129666)
		(end 67.135502 -318.129666)
		(width 0.1143)
		(layer "In5.Cu")
		(net "P5E_PEX0_STN5_RX_DP<89>")
	)
	(segment
		(start 66.633852 -319.966848)
		(end 66.679572 -319.921128)
		(width 0.1143)
		(layer "In5.Cu")
		(net "P5E_PEX0_STN5_RX_DP<89>")
	)
	(segment
		(start 66.679572 -318.355472)
		(end 66.905378 -318.129666)
		(width 0.1143)
		(layer "In5.Cu")
		(net "P5E_PEX0_STN5_RX_DP<89>")
	)
	(segment
		(start 66.679572 -319.921128)
		(end 66.679572 -318.355472)
		(width 0.1143)
		(layer "In5.Cu")
		(net "P5E_PEX0_STN5_RX_DP<89>")
	)
	(segment
		(start 74.770742 -372.099078)
		(end 75.00239 -371.86743)
		(width 0.1651)
		(layer "In5.Cu")
		(net "P5E_PEX0_STN5_RX_DP<89>")
	)
	(segment
		(start 66.633852 -321.648074)
		(end 66.633852 -319.995296)
		(width 0.1651)
		(layer "In5.Cu")
		(net "P5E_PEX0_STN5_RX_DP<89>")
	)
	(segment
		(start 75.121262 -365.95558)
		(end 75.142852 -365.510318)
		(width 0.1651)
		(layer "In5.Cu")
		(net "P5E_PEX0_STN5_RX_DP<89>")
	)
	(segment
		(start 44.773088 -350.685354)
		(end 45.093128 -350.365314)
		(width 0.13462)
		(layer "F.Cu")
		(net "P5E_PEX0_STN7_TX_C_DN<124>")
	)
	(segment
		(start 45.067728 -351.611438)
		(end 44.773088 -351.316798)
		(width 0.13462)
		(layer "F.Cu")
		(net "P5E_PEX0_STN7_TX_C_DN<124>")
	)
	(segment
		(start 44.773088 -351.316798)
		(end 44.773088 -350.685354)
		(width 0.13462)
		(layer "F.Cu")
		(net "P5E_PEX0_STN7_TX_C_DN<124>")
	)
	(segment
		(start 38.433502 -368.102896)
		(end 43.222418 -357.977186)
		(width 0.1651)
		(layer "In7.Cu")
		(net "P5E_PEX0_STN7_TX_C_DN<124>")
	)
	(segment
		(start 37.884354 -369.912646)
		(end 38.433502 -368.102896)
		(width 0.1651)
		(layer "In7.Cu")
		(net "P5E_PEX0_STN7_TX_C_DN<124>")
	)
	(segment
		(start 36.837112 -375.181114)
		(end 37.310568 -375.181114)
		(width 0.1651)
		(layer "In7.Cu")
		(net "P5E_PEX0_STN7_TX_C_DN<124>")
	)
	(segment
		(start 43.222418 -354.107242)
		(end 44.776898 -352.552762)
		(width 0.1651)
		(layer "In7.Cu")
		(net "P5E_PEX0_STN7_TX_C_DN<124>")
	)
	(segment
		(start 44.776898 -352.552762)
		(end 44.776898 -351.902268)
		(width 0.1651)
		(layer "In7.Cu")
		(net "P5E_PEX0_STN7_TX_C_DN<124>")
	)
	(segment
		(start 36.710112 -375.69013)
		(end 36.710112 -375.308114)
		(width 0.1651)
		(layer "In7.Cu")
		(net "P5E_PEX0_STN7_TX_C_DN<124>")
	)
	(segment
		(start 43.222418 -357.977186)
		(end 43.222418 -354.107242)
		(width 0.1651)
		(layer "In7.Cu")
		(net "P5E_PEX0_STN7_TX_C_DN<124>")
	)
	(segment
		(start 37.310568 -375.181114)
		(end 37.884354 -374.607328)
		(width 0.1651)
		(layer "In7.Cu")
		(net "P5E_PEX0_STN7_TX_C_DN<124>")
	)
	(segment
		(start 36.710112 -375.308114)
		(end 36.837112 -375.181114)
		(width 0.1651)
		(layer "In7.Cu")
		(net "P5E_PEX0_STN7_TX_C_DN<124>")
	)
	(segment
		(start 44.776898 -351.902268)
		(end 45.067728 -351.611438)
		(width 0.1651)
		(layer "In7.Cu")
		(net "P5E_PEX0_STN7_TX_C_DN<124>")
	)
	(segment
		(start 37.884354 -374.607328)
		(end 37.884354 -369.912646)
		(width 0.1651)
		(layer "In7.Cu")
		(net "P5E_PEX0_STN7_TX_C_DN<124>")
	)
	(segment
		(start 99.947222 -30.05709)
		(end 99.651312 -30.353)
		(width 0.13462)
		(layer "F.Cu")
		(net "P5E_PEX0_STN2_TX_DN<33>")
	)
	(segment
		(start 99.022408 -30.353)
		(end 98.701098 -30.03169)
		(width 0.13462)
		(layer "F.Cu")
		(net "P5E_PEX0_STN2_TX_DN<33>")
	)
	(segment
		(start 99.651312 -30.353)
		(end 99.022408 -30.353)
		(width 0.13462)
		(layer "F.Cu")
		(net "P5E_PEX0_STN2_TX_DN<33>")
	)
	(segment
		(start 100.389436 -30.34792)
		(end 100.739194 -30.34792)
		(width 0.1651)
		(layer "In11.Cu")
		(net "P5E_PEX0_STN2_TX_DN<33>")
	)
	(segment
		(start 106.176318 -68.499228)
		(end 103.86949 -74.95667)
		(width 0.1651)
		(layer "In11.Cu")
		(net "P5E_PEX0_STN2_TX_DN<33>")
	)
	(segment
		(start 76.67879 -161.060384)
		(end 57.415938 -265.859514)
		(width 0.1651)
		(layer "In11.Cu")
		(net "P5E_PEX0_STN2_TX_DN<33>")
	)
	(segment
		(start 87.858854 -93.454728)
		(end 87.858854 -93.454474)
		(width 0.1651)
		(layer "In11.Cu")
		(net "P5E_PEX0_STN2_TX_DN<33>")
	)
	(segment
		(start 77.672692 -153.6319)
		(end 76.67879 -161.060384)
		(width 0.1651)
		(layer "In11.Cu")
		(net "P5E_PEX0_STN2_TX_DN<33>")
	)
	(segment
		(start 57.635648 -278.229568)
		(end 57.749948 -278.115268)
		(width 0.1143)
		(layer "In11.Cu")
		(net "P5E_PEX0_STN2_TX_DN<33>")
	)
	(segment
		(start 57.415938 -271.427448)
		(end 57.370218 -271.473168)
		(width 0.1143)
		(layer "In11.Cu")
		(net "P5E_PEX0_STN2_TX_DN<33>")
	)
	(segment
		(start 57.47385 -278.229568)
		(end 57.635648 -278.229568)
		(width 0.1143)
		(layer "In11.Cu")
		(net "P5E_PEX0_STN2_TX_DN<33>")
	)
	(segment
		(start 100.739194 -30.34792)
		(end 101.348032 -30.615128)
		(width 0.1651)
		(layer "In11.Cu")
		(net "P5E_PEX0_STN2_TX_DN<33>")
	)
	(segment
		(start 79.39532 -118.553992)
		(end 78.742794 -133.840982)
		(width 0.1651)
		(layer "In11.Cu")
		(net "P5E_PEX0_STN2_TX_DN<33>")
	)
	(segment
		(start 103.194104 -32.441388)
		(end 107.66044 -40.622982)
		(width 0.1651)
		(layer "In11.Cu")
		(net "P5E_PEX0_STN2_TX_DN<33>")
	)
	(segment
		(start 77.900276 -150.936706)
		(end 77.672692 -153.6319)
		(width 0.1651)
		(layer "In11.Cu")
		(net "P5E_PEX0_STN2_TX_DN<33>")
	)
	(segment
		(start 87.858854 -93.454474)
		(end 81.010506 -105.554018)
		(width 0.1651)
		(layer "In11.Cu")
		(net "P5E_PEX0_STN2_TX_DN<33>")
	)
	(segment
		(start 107.66044 -40.622982)
		(end 108.170472 -42.544492)
		(width 0.1651)
		(layer "In11.Cu")
		(net "P5E_PEX0_STN2_TX_DN<33>")
	)
	(segment
		(start 91.283028 -87.404956)
		(end 87.858854 -93.454728)
		(width 0.1651)
		(layer "In11.Cu")
		(net "P5E_PEX0_STN2_TX_DN<33>")
	)
	(segment
		(start 57.415938 -271.399)
		(end 57.415938 -271.427448)
		(width 0.1143)
		(layer "In11.Cu")
		(net "P5E_PEX0_STN2_TX_DN<33>")
	)
	(segment
		(start 100.13061 -30.240478)
		(end 100.389436 -30.34792)
		(width 0.1651)
		(layer "In11.Cu")
		(net "P5E_PEX0_STN2_TX_DN<33>")
	)
	(segment
		(start 78.742794 -140.401802)
		(end 78.39964 -141.878812)
		(width 0.1651)
		(layer "In11.Cu")
		(net "P5E_PEX0_STN2_TX_DN<33>")
	)
	(segment
		(start 96.505522 -79.581502)
		(end 94.707456 -81.35493)
		(width 0.1651)
		(layer "In11.Cu")
		(net "P5E_PEX0_STN2_TX_DN<33>")
	)
	(segment
		(start 81.010506 -105.554018)
		(end 79.39532 -118.553992)
		(width 0.1651)
		(layer "In11.Cu")
		(net "P5E_PEX0_STN2_TX_DN<33>")
	)
	(segment
		(start 57.749948 -278.115268)
		(end 57.749948 -277.849838)
		(width 0.1143)
		(layer "In11.Cu")
		(net "P5E_PEX0_STN2_TX_DN<33>")
	)
	(segment
		(start 99.947222 -30.05709)
		(end 100.13061 -30.240478)
		(width 0.1651)
		(layer "In11.Cu")
		(net "P5E_PEX0_STN2_TX_DN<33>")
	)
	(segment
		(start 78.742794 -133.840982)
		(end 78.742794 -140.401802)
		(width 0.1651)
		(layer "In11.Cu")
		(net "P5E_PEX0_STN2_TX_DN<33>")
	)
	(segment
		(start 57.370218 -271.473168)
		(end 57.370218 -278.125936)
		(width 0.1143)
		(layer "In11.Cu")
		(net "P5E_PEX0_STN2_TX_DN<33>")
	)
	(segment
		(start 77.90053 -150.936706)
		(end 77.900276 -150.936706)
		(width 0.1651)
		(layer "In11.Cu")
		(net "P5E_PEX0_STN2_TX_DN<33>")
	)
	(segment
		(start 94.707456 -81.35493)
		(end 91.283028 -87.404956)
		(width 0.1651)
		(layer "In11.Cu")
		(net "P5E_PEX0_STN2_TX_DN<33>")
	)
	(segment
		(start 57.415938 -265.859514)
		(end 57.415938 -271.399)
		(width 0.1651)
		(layer "In11.Cu")
		(net "P5E_PEX0_STN2_TX_DN<33>")
	)
	(segment
		(start 78.127606 -148.24456)
		(end 77.90053 -150.936706)
		(width 0.1651)
		(layer "In11.Cu")
		(net "P5E_PEX0_STN2_TX_DN<33>")
	)
	(segment
		(start 103.86949 -74.95667)
		(end 103.092758 -76.002388)
		(width 0.1651)
		(layer "In11.Cu")
		(net "P5E_PEX0_STN2_TX_DN<33>")
	)
	(segment
		(start 57.370218 -278.125936)
		(end 57.47385 -278.229568)
		(width 0.1143)
		(layer "In11.Cu")
		(net "P5E_PEX0_STN2_TX_DN<33>")
	)
	(segment
		(start 78.39964 -141.878812)
		(end 78.127606 -148.24456)
		(width 0.1651)
		(layer "In11.Cu")
		(net "P5E_PEX0_STN2_TX_DN<33>")
	)
	(segment
		(start 108.170472 -42.544492)
		(end 108.443522 -56.860948)
		(width 0.1651)
		(layer "In11.Cu")
		(net "P5E_PEX0_STN2_TX_DN<33>")
	)
	(segment
		(start 103.092758 -76.002388)
		(end 96.505522 -79.581502)
		(width 0.1651)
		(layer "In11.Cu")
		(net "P5E_PEX0_STN2_TX_DN<33>")
	)
	(segment
		(start 101.348032 -30.615128)
		(end 103.194104 -32.441388)
		(width 0.1651)
		(layer "In11.Cu")
		(net "P5E_PEX0_STN2_TX_DN<33>")
	)
	(segment
		(start 108.443522 -56.860948)
		(end 106.176318 -68.499228)
		(width 0.1651)
		(layer "In11.Cu")
		(net "P5E_PEX0_STN2_TX_DN<33>")
	)
	(segment
		(start 137.302748 -349.511874)
		(end 137.302748 -348.88043)
		(width 0.13462)
		(layer "F.Cu")
		(net "P5E_PEX1_STN5_TX_DN<84>")
	)
	(segment
		(start 137.302748 -348.88043)
		(end 137.597388 -348.58579)
		(width 0.13462)
		(layer "F.Cu")
		(net "P5E_PEX1_STN5_TX_DN<84>")
	)
	(segment
		(start 137.622788 -349.831914)
		(end 137.302748 -349.511874)
		(width 0.13462)
		(layer "F.Cu")
		(net "P5E_PEX1_STN5_TX_DN<84>")
	)
	(segment
		(start 139.214606 -340.83752)
		(end 170.44035 -331.365352)
		(width 0.1651)
		(layer "In7.Cu")
		(net "P5E_PEX1_STN5_TX_DN<84>")
	)
	(segment
		(start 138.861038 -346.182442)
		(end 138.861038 -341.314278)
		(width 0.1651)
		(layer "In7.Cu")
		(net "P5E_PEX1_STN5_TX_DN<84>")
	)
	(segment
		(start 178.485546 -311.670192)
		(end 178.599846 -311.784492)
		(width 0.1143)
		(layer "In7.Cu")
		(net "P5E_PEX1_STN5_TX_DN<84>")
	)
	(segment
		(start 178.265836 -323.804026)
		(end 178.265836 -320.016886)
		(width 0.1651)
		(layer "In7.Cu")
		(net "P5E_PEX1_STN5_TX_DN<84>")
	)
	(segment
		(start 178.599846 -311.784492)
		(end 178.599846 -312.049922)
		(width 0.1143)
		(layer "In7.Cu")
		(net "P5E_PEX1_STN5_TX_DN<84>")
	)
	(segment
		(start 137.597388 -348.58579)
		(end 137.306558 -348.29496)
		(width 0.1651)
		(layer "In7.Cu")
		(net "P5E_PEX1_STN5_TX_DN<84>")
	)
	(segment
		(start 178.334416 -311.670192)
		(end 178.485546 -311.670192)
		(width 0.1143)
		(layer "In7.Cu")
		(net "P5E_PEX1_STN5_TX_DN<84>")
	)
	(segment
		(start 178.265836 -319.988438)
		(end 178.220116 -319.942718)
		(width 0.1143)
		(layer "In7.Cu")
		(net "P5E_PEX1_STN5_TX_DN<84>")
	)
	(segment
		(start 178.220116 -319.942718)
		(end 178.220116 -311.784492)
		(width 0.1143)
		(layer "In7.Cu")
		(net "P5E_PEX1_STN5_TX_DN<84>")
	)
	(segment
		(start 137.306558 -347.736922)
		(end 138.861038 -346.182442)
		(width 0.1651)
		(layer "In7.Cu")
		(net "P5E_PEX1_STN5_TX_DN<84>")
	)
	(segment
		(start 137.306558 -348.29496)
		(end 137.306558 -347.736922)
		(width 0.1651)
		(layer "In7.Cu")
		(net "P5E_PEX1_STN5_TX_DN<84>")
	)
	(segment
		(start 177.295302 -326.146922)
		(end 178.265836 -323.804026)
		(width 0.1651)
		(layer "In7.Cu")
		(net "P5E_PEX1_STN5_TX_DN<84>")
	)
	(segment
		(start 178.265836 -320.016886)
		(end 178.265836 -319.988438)
		(width 0.1143)
		(layer "In7.Cu")
		(net "P5E_PEX1_STN5_TX_DN<84>")
	)
	(segment
		(start 174.525686 -328.916538)
		(end 177.295302 -326.146922)
		(width 0.1651)
		(layer "In7.Cu")
		(net "P5E_PEX1_STN5_TX_DN<84>")
	)
	(segment
		(start 178.220116 -311.784492)
		(end 178.334416 -311.670192)
		(width 0.1143)
		(layer "In7.Cu")
		(net "P5E_PEX1_STN5_TX_DN<84>")
	)
	(segment
		(start 138.861038 -341.314278)
		(end 139.214606 -340.83752)
		(width 0.1651)
		(layer "In7.Cu")
		(net "P5E_PEX1_STN5_TX_DN<84>")
	)
	(segment
		(start 170.44035 -331.365352)
		(end 174.525686 -328.916538)
		(width 0.1651)
		(layer "In7.Cu")
		(net "P5E_PEX1_STN5_TX_DN<84>")
	)
	(segment
		(start 277.201122 -28.55468)
		(end 276.588474 -28.55468)
		(width 0.13462)
		(layer "F.Cu")
		(net "P5E_PEX2_STN2_TX_DN<40>")
	)
	(segment
		(start 276.588474 -28.55468)
		(end 276.259036 -28.225242)
		(width 0.13462)
		(layer "F.Cu")
		(net "P5E_PEX2_STN2_TX_DN<40>")
	)
	(segment
		(start 277.50516 -28.250642)
		(end 277.201122 -28.55468)
		(width 0.13462)
		(layer "F.Cu")
		(net "P5E_PEX2_STN2_TX_DN<40>")
	)
	(segment
		(start 277.50516 -28.250642)
		(end 277.79599 -28.541472)
		(width 0.1651)
		(layer "In11.Cu")
		(net "P5E_PEX2_STN2_TX_DN<40>")
	)
	(segment
		(start 282.920186 -280.025856)
		(end 283.023818 -280.129488)
		(width 0.1143)
		(layer "In11.Cu")
		(net "P5E_PEX2_STN2_TX_DN<40>")
	)
	(segment
		(start 283.185616 -280.129488)
		(end 283.299916 -280.015188)
		(width 0.1143)
		(layer "In11.Cu")
		(net "P5E_PEX2_STN2_TX_DN<40>")
	)
	(segment
		(start 282.920186 -271.473168)
		(end 282.920186 -280.025856)
		(width 0.1143)
		(layer "In11.Cu")
		(net "P5E_PEX2_STN2_TX_DN<40>")
	)
	(segment
		(start 295.75379 -46.926246)
		(end 296.780458 -49.856136)
		(width 0.1651)
		(layer "In11.Cu")
		(net "P5E_PEX2_STN2_TX_DN<40>")
	)
	(segment
		(start 282.965906 -271.427448)
		(end 282.920186 -271.473168)
		(width 0.1143)
		(layer "In11.Cu")
		(net "P5E_PEX2_STN2_TX_DN<40>")
	)
	(segment
		(start 280.13914 -28.541472)
		(end 281.504898 -29.110178)
		(width 0.1651)
		(layer "In11.Cu")
		(net "P5E_PEX2_STN2_TX_DN<40>")
	)
	(segment
		(start 286.01416 -34.710116)
		(end 295.75379 -46.926246)
		(width 0.1651)
		(layer "In11.Cu")
		(net "P5E_PEX2_STN2_TX_DN<40>")
	)
	(segment
		(start 277.79599 -28.541472)
		(end 280.13914 -28.541472)
		(width 0.1651)
		(layer "In11.Cu")
		(net "P5E_PEX2_STN2_TX_DN<40>")
	)
	(segment
		(start 297.017186 -69.60997)
		(end 289.970718 -119.313452)
		(width 0.1651)
		(layer "In11.Cu")
		(net "P5E_PEX2_STN2_TX_DN<40>")
	)
	(segment
		(start 282.965906 -271.399)
		(end 282.965906 -271.427448)
		(width 0.1143)
		(layer "In11.Cu")
		(net "P5E_PEX2_STN2_TX_DN<40>")
	)
	(segment
		(start 297.019218 -69.597016)
		(end 297.01744 -69.60997)
		(width 0.1651)
		(layer "In11.Cu")
		(net "P5E_PEX2_STN2_TX_DN<40>")
	)
	(segment
		(start 281.504898 -29.110178)
		(end 284.270196 -31.857696)
		(width 0.1651)
		(layer "In11.Cu")
		(net "P5E_PEX2_STN2_TX_DN<40>")
	)
	(segment
		(start 282.974542 -271.221962)
		(end 282.965906 -271.230598)
		(width 0.1651)
		(layer "In11.Cu")
		(net "P5E_PEX2_STN2_TX_DN<40>")
	)
	(segment
		(start 282.601416 -266.016486)
		(end 282.974542 -269.806928)
		(width 0.1651)
		(layer "In11.Cu")
		(net "P5E_PEX2_STN2_TX_DN<40>")
	)
	(segment
		(start 283.299916 -280.015188)
		(end 283.299916 -279.749504)
		(width 0.1143)
		(layer "In11.Cu")
		(net "P5E_PEX2_STN2_TX_DN<40>")
	)
	(segment
		(start 282.965906 -271.230598)
		(end 282.965906 -271.399)
		(width 0.1651)
		(layer "In11.Cu")
		(net "P5E_PEX2_STN2_TX_DN<40>")
	)
	(segment
		(start 297.01744 -69.60997)
		(end 297.017186 -69.60997)
		(width 0.1651)
		(layer "In11.Cu")
		(net "P5E_PEX2_STN2_TX_DN<40>")
	)
	(segment
		(start 297.446192 -60.605162)
		(end 297.019218 -69.597016)
		(width 0.1651)
		(layer "In11.Cu")
		(net "P5E_PEX2_STN2_TX_DN<40>")
	)
	(segment
		(start 284.270196 -31.857696)
		(end 286.01416 -34.710116)
		(width 0.1651)
		(layer "In11.Cu")
		(net "P5E_PEX2_STN2_TX_DN<40>")
	)
	(segment
		(start 288.630106 -135.263128)
		(end 282.328112 -252.61824)
		(width 0.1651)
		(layer "In11.Cu")
		(net "P5E_PEX2_STN2_TX_DN<40>")
	)
	(segment
		(start 282.328112 -252.61824)
		(end 282.601416 -266.016486)
		(width 0.1651)
		(layer "In11.Cu")
		(net "P5E_PEX2_STN2_TX_DN<40>")
	)
	(segment
		(start 296.780458 -49.856136)
		(end 297.446192 -60.605162)
		(width 0.1651)
		(layer "In11.Cu")
		(net "P5E_PEX2_STN2_TX_DN<40>")
	)
	(segment
		(start 282.974542 -269.806928)
		(end 282.974542 -271.221962)
		(width 0.1651)
		(layer "In11.Cu")
		(net "P5E_PEX2_STN2_TX_DN<40>")
	)
	(segment
		(start 283.023818 -280.129488)
		(end 283.185616 -280.129488)
		(width 0.1143)
		(layer "In11.Cu")
		(net "P5E_PEX2_STN2_TX_DN<40>")
	)
	(segment
		(start 289.970718 -119.313452)
		(end 288.630106 -135.263128)
		(width 0.1651)
		(layer "In11.Cu")
		(net "P5E_PEX2_STN2_TX_DN<40>")
	)
	(segment
		(start 429.542448 -142.90548)
		(end 428.901352 -142.90548)
		(width 0.13462)
		(layer "F.Cu")
		(net "P5E_PEX3_STN0_TX_DN<8>")
	)
	(segment
		(start 428.901352 -142.90548)
		(end 428.586138 -142.590266)
		(width 0.13462)
		(layer "F.Cu")
		(net "P5E_PEX3_STN0_TX_DN<8>")
	)
	(segment
		(start 429.832262 -142.615666)
		(end 429.542448 -142.90548)
		(width 0.13462)
		(layer "F.Cu")
		(net "P5E_PEX3_STN0_TX_DN<8>")
	)
	(segment
		(start 427.12513 -222.047308)
		(end 430.464468 -260.268466)
		(width 0.1651)
		(layer "In9.Cu")
		(net "P5E_PEX3_STN0_TX_DN<8>")
	)
	(segment
		(start 430.123092 -142.906496)
		(end 430.542192 -142.906496)
		(width 0.1651)
		(layer "In9.Cu")
		(net "P5E_PEX3_STN0_TX_DN<8>")
	)
	(segment
		(start 438.40908 -148.674074)
		(end 440.729624 -154.276552)
		(width 0.1651)
		(layer "In9.Cu")
		(net "P5E_PEX3_STN0_TX_DN<8>")
	)
	(segment
		(start 433.719478 -143.430498)
		(end 437.292496 -147.003516)
		(width 0.1651)
		(layer "In9.Cu")
		(net "P5E_PEX3_STN0_TX_DN<8>")
	)
	(segment
		(start 430.370234 -276.6441)
		(end 430.370234 -276.785578)
		(width 0.1143)
		(layer "In9.Cu")
		(net "P5E_PEX3_STN0_TX_DN<8>")
	)
	(segment
		(start 440.729624 -158.516574)
		(end 432.204368 -173.28642)
		(width 0.1651)
		(layer "In9.Cu")
		(net "P5E_PEX3_STN0_TX_DN<8>")
	)
	(segment
		(start 431.366168 -271.776952)
		(end 431.366168 -271.8054)
		(width 0.1143)
		(layer "In9.Cu")
		(net "P5E_PEX3_STN0_TX_DN<8>")
	)
	(segment
		(start 431.320448 -276.262592)
		(end 431.075592 -276.507448)
		(width 0.1143)
		(layer "In9.Cu")
		(net "P5E_PEX3_STN0_TX_DN<8>")
	)
	(segment
		(start 430.484534 -276.899878)
		(end 430.749964 -276.899878)
		(width 0.1143)
		(layer "In9.Cu")
		(net "P5E_PEX3_STN0_TX_DN<8>")
	)
	(segment
		(start 432.204368 -173.28642)
		(end 430.99736 -177.788062)
		(width 0.1651)
		(layer "In9.Cu")
		(net "P5E_PEX3_STN0_TX_DN<8>")
	)
	(segment
		(start 430.506886 -276.507448)
		(end 430.370234 -276.6441)
		(width 0.1143)
		(layer "In9.Cu")
		(net "P5E_PEX3_STN0_TX_DN<8>")
	)
	(segment
		(start 431.943002 -142.69466)
		(end 433.719478 -143.430498)
		(width 0.1651)
		(layer "In9.Cu")
		(net "P5E_PEX3_STN0_TX_DN<8>")
	)
	(segment
		(start 430.542192 -142.906496)
		(end 431.054002 -142.69466)
		(width 0.1651)
		(layer "In9.Cu")
		(net "P5E_PEX3_STN0_TX_DN<8>")
	)
	(segment
		(start 431.075592 -276.507448)
		(end 430.506886 -276.507448)
		(width 0.1143)
		(layer "In9.Cu")
		(net "P5E_PEX3_STN0_TX_DN<8>")
	)
	(segment
		(start 440.729624 -154.276552)
		(end 440.729624 -158.516574)
		(width 0.1651)
		(layer "In9.Cu")
		(net "P5E_PEX3_STN0_TX_DN<8>")
	)
	(segment
		(start 430.464468 -260.268466)
		(end 430.464468 -261.20217)
		(width 0.1651)
		(layer "In9.Cu")
		(net "P5E_PEX3_STN0_TX_DN<8>")
	)
	(segment
		(start 437.292496 -147.003516)
		(end 438.40908 -148.674074)
		(width 0.1651)
		(layer "In9.Cu")
		(net "P5E_PEX3_STN0_TX_DN<8>")
	)
	(segment
		(start 430.99736 -177.788062)
		(end 427.12513 -222.047308)
		(width 0.1651)
		(layer "In9.Cu")
		(net "P5E_PEX3_STN0_TX_DN<8>")
	)
	(segment
		(start 431.320448 -271.85112)
		(end 431.320448 -276.262592)
		(width 0.1143)
		(layer "In9.Cu")
		(net "P5E_PEX3_STN0_TX_DN<8>")
	)
	(segment
		(start 431.366168 -271.8054)
		(end 431.320448 -271.85112)
		(width 0.1143)
		(layer "In9.Cu")
		(net "P5E_PEX3_STN0_TX_DN<8>")
	)
	(segment
		(start 431.054002 -142.69466)
		(end 431.943002 -142.69466)
		(width 0.1651)
		(layer "In9.Cu")
		(net "P5E_PEX3_STN0_TX_DN<8>")
	)
	(segment
		(start 431.366168 -270.358108)
		(end 431.366168 -271.776952)
		(width 0.1651)
		(layer "In9.Cu")
		(net "P5E_PEX3_STN0_TX_DN<8>")
	)
	(segment
		(start 430.464468 -261.20217)
		(end 431.366168 -270.358108)
		(width 0.1651)
		(layer "In9.Cu")
		(net "P5E_PEX3_STN0_TX_DN<8>")
	)
	(segment
		(start 430.370234 -276.785578)
		(end 430.484534 -276.899878)
		(width 0.1143)
		(layer "In9.Cu")
		(net "P5E_PEX3_STN0_TX_DN<8>")
	)
	(segment
		(start 429.832262 -142.615666)
		(end 430.123092 -142.906496)
		(width 0.1651)
		(layer "In9.Cu")
		(net "P5E_PEX3_STN0_TX_DN<8>")
	)
	(segment
		(start 435.055772 -355.978206)
		(end 434.735224 -355.657658)
		(width 0.13462)
		(layer "F.Cu")
		(net "P5E_PEX3_STN7_TX_DN<124>")
	)
	(segment
		(start 434.735224 -355.657658)
		(end 434.735224 -355.02723)
		(width 0.13462)
		(layer "F.Cu")
		(net "P5E_PEX3_STN7_TX_DN<124>")
	)
	(segment
		(start 434.735224 -355.02723)
		(end 435.030372 -354.732082)
		(width 0.13462)
		(layer "F.Cu")
		(net "P5E_PEX3_STN7_TX_DN<124>")
	)
	(segment
		(start 393.515342 -324.285102)
		(end 393.036298 -324.15861)
		(width 0.1651)
		(layer "In11.Cu")
		(net "P5E_PEX3_STN7_TX_DN<124>")
	)
	(segment
		(start 393.578588 -324.394068)
		(end 393.515342 -324.285102)
		(width 0.1651)
		(layer "In11.Cu")
		(net "P5E_PEX3_STN7_TX_DN<124>")
	)
	(segment
		(start 394.70838 -324.692264)
		(end 394.645134 -324.583298)
		(width 0.1651)
		(layer "In11.Cu")
		(net "P5E_PEX3_STN7_TX_DN<124>")
	)
	(segment
		(start 393.036298 -324.15861)
		(end 392.927586 -324.221856)
		(width 0.1651)
		(layer "In11.Cu")
		(net "P5E_PEX3_STN7_TX_DN<124>")
	)
	(segment
		(start 387.680708 -321.996308)
		(end 387.665722 -321.96024)
		(width 0.1651)
		(layer "In11.Cu")
		(net "P5E_PEX3_STN7_TX_DN<124>")
	)
	(segment
		(start 387.665722 -320.056256)
		(end 387.665722 -320.034158)
		(width 0.1143)
		(layer "In11.Cu")
		(net "P5E_PEX3_STN7_TX_DN<124>")
	)
	(segment
		(start 394.645134 -324.583298)
		(end 394.16609 -324.456806)
		(width 0.1651)
		(layer "In11.Cu")
		(net "P5E_PEX3_STN7_TX_DN<124>")
	)
	(segment
		(start 392.448796 -324.095618)
		(end 392.38555 -323.986906)
		(width 0.1651)
		(layer "In11.Cu")
		(net "P5E_PEX3_STN7_TX_DN<124>")
	)
	(segment
		(start 387.665722 -321.96024)
		(end 387.665722 -320.056256)
		(width 0.1651)
		(layer "In11.Cu")
		(net "P5E_PEX3_STN7_TX_DN<124>")
	)
	(segment
		(start 395.295882 -324.755002)
		(end 395.18717 -324.818248)
		(width 0.1651)
		(layer "In11.Cu")
		(net "P5E_PEX3_STN7_TX_DN<124>")
	)
	(segment
		(start 387.885686 -311.670192)
		(end 387.999986 -311.784492)
		(width 0.1143)
		(layer "In11.Cu")
		(net "P5E_PEX3_STN7_TX_DN<124>")
	)
	(segment
		(start 394.16609 -324.456806)
		(end 394.057378 -324.520052)
		(width 0.1651)
		(layer "In11.Cu")
		(net "P5E_PEX3_STN7_TX_DN<124>")
	)
	(segment
		(start 394.70838 -324.69201)
		(end 394.70838 -324.692264)
		(width 0.1651)
		(layer "In11.Cu")
		(net "P5E_PEX3_STN7_TX_DN<124>")
	)
	(segment
		(start 436.294022 -341.5538)
		(end 434.7972 -339.217)
		(width 0.1651)
		(layer "In11.Cu")
		(net "P5E_PEX3_STN7_TX_DN<124>")
	)
	(segment
		(start 394.057378 -324.520052)
		(end 393.578588 -324.393814)
		(width 0.1651)
		(layer "In11.Cu")
		(net "P5E_PEX3_STN7_TX_DN<124>")
	)
	(segment
		(start 387.620002 -319.988438)
		(end 387.620002 -311.774078)
		(width 0.1143)
		(layer "In11.Cu")
		(net "P5E_PEX3_STN7_TX_DN<124>")
	)
	(segment
		(start 395.774926 -324.881494)
		(end 395.295882 -324.755002)
		(width 0.1651)
		(layer "In11.Cu")
		(net "P5E_PEX3_STN7_TX_DN<124>")
	)
	(segment
		(start 395.18717 -324.818248)
		(end 394.70838 -324.69201)
		(width 0.1651)
		(layer "In11.Cu")
		(net "P5E_PEX3_STN7_TX_DN<124>")
	)
	(segment
		(start 388.822946 -323.138546)
		(end 387.680708 -321.996308)
		(width 0.1651)
		(layer "In11.Cu")
		(net "P5E_PEX3_STN7_TX_DN<124>")
	)
	(segment
		(start 436.294022 -352.376486)
		(end 436.294022 -341.5538)
		(width 0.1651)
		(layer "In11.Cu")
		(net "P5E_PEX3_STN7_TX_DN<124>")
	)
	(segment
		(start 391.797794 -323.92366)
		(end 388.822946 -323.138546)
		(width 0.1651)
		(layer "In11.Cu")
		(net "P5E_PEX3_STN7_TX_DN<124>")
	)
	(segment
		(start 434.739542 -353.930966)
		(end 436.294022 -352.376486)
		(width 0.1651)
		(layer "In11.Cu")
		(net "P5E_PEX3_STN7_TX_DN<124>")
	)
	(segment
		(start 387.999986 -311.784492)
		(end 387.999986 -312.049922)
		(width 0.1143)
		(layer "In11.Cu")
		(net "P5E_PEX3_STN7_TX_DN<124>")
	)
	(segment
		(start 391.906506 -323.860414)
		(end 391.797794 -323.92366)
		(width 0.1651)
		(layer "In11.Cu")
		(net "P5E_PEX3_STN7_TX_DN<124>")
	)
	(segment
		(start 434.7972 -339.217)
		(end 425.713398 -332.876144)
		(width 0.1651)
		(layer "In11.Cu")
		(net "P5E_PEX3_STN7_TX_DN<124>")
	)
	(segment
		(start 393.578588 -324.393814)
		(end 393.578588 -324.394068)
		(width 0.1651)
		(layer "In11.Cu")
		(net "P5E_PEX3_STN7_TX_DN<124>")
	)
	(segment
		(start 434.739542 -354.441252)
		(end 434.739542 -353.930966)
		(width 0.1651)
		(layer "In11.Cu")
		(net "P5E_PEX3_STN7_TX_DN<124>")
	)
	(segment
		(start 425.713398 -332.876144)
		(end 395.838172 -324.990206)
		(width 0.1651)
		(layer "In11.Cu")
		(net "P5E_PEX3_STN7_TX_DN<124>")
	)
	(segment
		(start 392.927586 -324.221856)
		(end 392.448796 -324.095618)
		(width 0.1651)
		(layer "In11.Cu")
		(net "P5E_PEX3_STN7_TX_DN<124>")
	)
	(segment
		(start 387.665722 -320.034158)
		(end 387.620002 -319.988438)
		(width 0.1143)
		(layer "In11.Cu")
		(net "P5E_PEX3_STN7_TX_DN<124>")
	)
	(segment
		(start 392.38555 -323.986906)
		(end 391.906506 -323.860414)
		(width 0.1651)
		(layer "In11.Cu")
		(net "P5E_PEX3_STN7_TX_DN<124>")
	)
	(segment
		(start 435.030372 -354.732082)
		(end 434.739542 -354.441252)
		(width 0.1651)
		(layer "In11.Cu")
		(net "P5E_PEX3_STN7_TX_DN<124>")
	)
	(segment
		(start 395.838172 -324.99046)
		(end 395.774926 -324.881494)
		(width 0.1651)
		(layer "In11.Cu")
		(net "P5E_PEX3_STN7_TX_DN<124>")
	)
	(segment
		(start 387.723888 -311.670192)
		(end 387.885686 -311.670192)
		(width 0.1143)
		(layer "In11.Cu")
		(net "P5E_PEX3_STN7_TX_DN<124>")
	)
	(segment
		(start 387.620002 -311.774078)
		(end 387.723888 -311.670192)
		(width 0.1143)
		(layer "In11.Cu")
		(net "P5E_PEX3_STN7_TX_DN<124>")
	)
	(segment
		(start 395.838172 -324.990206)
		(end 395.838172 -324.99046)
		(width 0.1651)
		(layer "In11.Cu")
		(net "P5E_PEX3_STN7_TX_DN<124>")
	)
	(segment
		(start 31.259018 -383.55778)
		(end 31.259018 -368.803682)
		(width 0.1651)
		(layer "In5.Cu")
		(net "P5E_PEX0_STN7_RX_DP<121>")
	)
	(segment
		(start 35.327082 -311.727342)
		(end 35.847528 -311.206896)
		(width 0.1651)
		(layer "In5.Cu")
		(net "P5E_PEX0_STN7_RX_DP<121>")
	)
	(segment
		(start 35.867594 -311.18683)
		(end 35.867594 -311.121806)
		(width 0.1143)
		(layer "In5.Cu")
		(net "P5E_PEX0_STN7_RX_DP<121>")
	)
	(segment
		(start 31.259018 -368.803682)
		(end 33.779714 -358.740964)
		(width 0.1651)
		(layer "In5.Cu")
		(net "P5E_PEX0_STN7_RX_DP<121>")
	)
	(segment
		(start 35.7632 -322.882514)
		(end 35.7632 -319.586356)
		(width 0.1651)
		(layer "In5.Cu")
		(net "P5E_PEX0_STN7_RX_DP<121>")
	)
	(segment
		(start 35.327082 -318.533272)
		(end 35.327082 -311.727342)
		(width 0.1651)
		(layer "In5.Cu")
		(net "P5E_PEX0_STN7_RX_DP<121>")
	)
	(segment
		(start 33.779714 -358.740964)
		(end 33.895538 -357.80218)
		(width 0.1651)
		(layer "In5.Cu")
		(net "P5E_PEX0_STN7_RX_DP<121>")
	)
	(segment
		(start 33.895538 -357.80218)
		(end 33.895538 -341.8459)
		(width 0.1651)
		(layer "In5.Cu")
		(net "P5E_PEX0_STN7_RX_DP<121>")
	)
	(segment
		(start 30.735778 -384.08102)
		(end 31.259018 -383.55778)
		(width 0.1651)
		(layer "In5.Cu")
		(net "P5E_PEX0_STN7_RX_DP<121>")
	)
	(segment
		(start 30.109922 -384.590036)
		(end 30.109922 -384.20802)
		(width 0.1651)
		(layer "In5.Cu")
		(net "P5E_PEX0_STN7_RX_DP<121>")
	)
	(segment
		(start 33.895538 -341.8459)
		(end 35.7632 -322.882514)
		(width 0.1651)
		(layer "In5.Cu")
		(net "P5E_PEX0_STN7_RX_DP<121>")
	)
	(segment
		(start 37.420042 -310.494172)
		(end 37.420042 -310.264048)
		(width 0.1143)
		(layer "In5.Cu")
		(net "P5E_PEX0_STN7_RX_DP<121>")
	)
	(segment
		(start 37.420042 -310.264048)
		(end 37.534342 -310.149748)
		(width 0.1143)
		(layer "In5.Cu")
		(net "P5E_PEX0_STN7_RX_DP<121>")
	)
	(segment
		(start 35.867594 -311.121806)
		(end 36.269422 -310.719978)
		(width 0.1143)
		(layer "In5.Cu")
		(net "P5E_PEX0_STN7_RX_DP<121>")
	)
	(segment
		(start 35.7632 -319.586356)
		(end 35.327082 -318.533272)
		(width 0.1651)
		(layer "In5.Cu")
		(net "P5E_PEX0_STN7_RX_DP<121>")
	)
	(segment
		(start 30.109922 -384.20802)
		(end 30.236922 -384.08102)
		(width 0.1651)
		(layer "In5.Cu")
		(net "P5E_PEX0_STN7_RX_DP<121>")
	)
	(segment
		(start 35.847528 -311.206896)
		(end 35.867594 -311.18683)
		(width 0.1143)
		(layer "In5.Cu")
		(net "P5E_PEX0_STN7_RX_DP<121>")
	)
	(segment
		(start 36.269422 -310.719978)
		(end 37.194236 -310.719978)
		(width 0.1143)
		(layer "In5.Cu")
		(net "P5E_PEX0_STN7_RX_DP<121>")
	)
	(segment
		(start 37.534342 -310.149748)
		(end 37.799772 -310.149748)
		(width 0.1143)
		(layer "In5.Cu")
		(net "P5E_PEX0_STN7_RX_DP<121>")
	)
	(segment
		(start 30.236922 -384.08102)
		(end 30.735778 -384.08102)
		(width 0.1651)
		(layer "In5.Cu")
		(net "P5E_PEX0_STN7_RX_DP<121>")
	)
	(segment
		(start 37.194236 -310.719978)
		(end 37.420042 -310.494172)
		(width 0.1143)
		(layer "In5.Cu")
		(net "P5E_PEX0_STN7_RX_DP<121>")
	)
	(segment
		(start 47.882048 -344.539062)
		(end 48.202088 -344.219022)
		(width 0.13462)
		(layer "F.Cu")
		(net "P5E_PEX0_STN7_TX_C_DN<125>")
	)
	(segment
		(start 47.882048 -345.170506)
		(end 47.882048 -344.539062)
		(width 0.13462)
		(layer "F.Cu")
		(net "P5E_PEX0_STN7_TX_C_DN<125>")
	)
	(segment
		(start 48.176688 -345.465146)
		(end 47.882048 -345.170506)
		(width 0.13462)
		(layer "F.Cu")
		(net "P5E_PEX0_STN7_TX_C_DN<125>")
	)
	(segment
		(start 46.331378 -357.903526)
		(end 46.331378 -348.029022)
		(width 0.1651)
		(layer "In7.Cu")
		(net "P5E_PEX0_STN7_TX_C_DN<125>")
	)
	(segment
		(start 39.037006 -376.281188)
		(end 39.679118 -376.281188)
		(width 0.1651)
		(layer "In7.Cu")
		(net "P5E_PEX0_STN7_TX_C_DN<125>")
	)
	(segment
		(start 40.084248 -375.876058)
		(end 40.084248 -369.583716)
		(width 0.1651)
		(layer "In7.Cu")
		(net "P5E_PEX0_STN7_TX_C_DN<125>")
	)
	(segment
		(start 38.910006 -376.408188)
		(end 39.037006 -376.281188)
		(width 0.1651)
		(layer "In7.Cu")
		(net "P5E_PEX0_STN7_TX_C_DN<125>")
	)
	(segment
		(start 39.679118 -376.281188)
		(end 40.084248 -375.876058)
		(width 0.1651)
		(layer "In7.Cu")
		(net "P5E_PEX0_STN7_TX_C_DN<125>")
	)
	(segment
		(start 40.084248 -369.583716)
		(end 40.239442 -368.995452)
		(width 0.1651)
		(layer "In7.Cu")
		(net "P5E_PEX0_STN7_TX_C_DN<125>")
	)
	(segment
		(start 47.885858 -346.474542)
		(end 47.885858 -345.755976)
		(width 0.1651)
		(layer "In7.Cu")
		(net "P5E_PEX0_STN7_TX_C_DN<125>")
	)
	(segment
		(start 46.331378 -348.029022)
		(end 47.885858 -346.474542)
		(width 0.1651)
		(layer "In7.Cu")
		(net "P5E_PEX0_STN7_TX_C_DN<125>")
	)
	(segment
		(start 47.885858 -345.755976)
		(end 48.176688 -345.465146)
		(width 0.1651)
		(layer "In7.Cu")
		(net "P5E_PEX0_STN7_TX_C_DN<125>")
	)
	(segment
		(start 46.110652 -358.631236)
		(end 46.331378 -357.903526)
		(width 0.1651)
		(layer "In7.Cu")
		(net "P5E_PEX0_STN7_TX_C_DN<125>")
	)
	(segment
		(start 38.910006 -376.790204)
		(end 38.910006 -376.408188)
		(width 0.1651)
		(layer "In7.Cu")
		(net "P5E_PEX0_STN7_TX_C_DN<125>")
	)
	(segment
		(start 40.239442 -368.995452)
		(end 46.110652 -358.631236)
		(width 0.1651)
		(layer "In7.Cu")
		(net "P5E_PEX0_STN7_TX_C_DN<125>")
	)
	(segment
		(start 68.479162 -349.831914)
		(end 68.159122 -349.511874)
		(width 0.13462)
		(layer "F.Cu")
		(net "P5E_PEX0_STN5_TX_DN<83>")
	)
	(segment
		(start 68.159122 -348.88043)
		(end 68.453762 -348.58579)
		(width 0.13462)
		(layer "F.Cu")
		(net "P5E_PEX0_STN5_TX_DN<83>")
	)
	(segment
		(start 68.159122 -349.511874)
		(end 68.159122 -348.88043)
		(width 0.13462)
		(layer "F.Cu")
		(net "P5E_PEX0_STN5_TX_DN<83>")
	)
	(segment
		(start 68.162932 -348.29496)
		(end 68.162932 -347.658182)
		(width 0.1651)
		(layer "In7.Cu")
		(net "P5E_PEX0_STN5_TX_DN<83>")
	)
	(segment
		(start 61.215778 -324.23354)
		(end 61.215778 -319.890648)
		(width 0.1651)
		(layer "In7.Cu")
		(net "P5E_PEX0_STN5_TX_DN<83>")
	)
	(segment
		(start 61.215778 -319.8622)
		(end 61.170058 -319.81648)
		(width 0.1143)
		(layer "In7.Cu")
		(net "P5E_PEX0_STN5_TX_DN<83>")
	)
	(segment
		(start 61.215778 -319.890648)
		(end 61.215778 -319.8622)
		(width 0.1143)
		(layer "In7.Cu")
		(net "P5E_PEX0_STN5_TX_DN<83>")
	)
	(segment
		(start 68.162932 -347.658182)
		(end 69.717412 -346.103702)
		(width 0.1651)
		(layer "In7.Cu")
		(net "P5E_PEX0_STN5_TX_DN<83>")
	)
	(segment
		(start 61.435488 -313.570112)
		(end 61.549788 -313.684412)
		(width 0.1143)
		(layer "In7.Cu")
		(net "P5E_PEX0_STN5_TX_DN<83>")
	)
	(segment
		(start 65.077848 -332.398878)
		(end 61.215778 -324.23354)
		(width 0.1651)
		(layer "In7.Cu")
		(net "P5E_PEX0_STN5_TX_DN<83>")
	)
	(segment
		(start 61.549788 -313.684412)
		(end 61.549788 -313.949842)
		(width 0.1143)
		(layer "In7.Cu")
		(net "P5E_PEX0_STN5_TX_DN<83>")
	)
	(segment
		(start 68.453762 -348.58579)
		(end 68.162932 -348.29496)
		(width 0.1651)
		(layer "In7.Cu")
		(net "P5E_PEX0_STN5_TX_DN<83>")
	)
	(segment
		(start 69.306948 -340.31047)
		(end 65.077848 -332.398878)
		(width 0.1651)
		(layer "In7.Cu")
		(net "P5E_PEX0_STN5_TX_DN<83>")
	)
	(segment
		(start 69.717412 -346.103702)
		(end 69.717412 -341.30107)
		(width 0.1651)
		(layer "In7.Cu")
		(net "P5E_PEX0_STN5_TX_DN<83>")
	)
	(segment
		(start 61.170058 -319.81648)
		(end 61.170058 -313.684412)
		(width 0.1143)
		(layer "In7.Cu")
		(net "P5E_PEX0_STN5_TX_DN<83>")
	)
	(segment
		(start 61.170058 -313.684412)
		(end 61.284358 -313.570112)
		(width 0.1143)
		(layer "In7.Cu")
		(net "P5E_PEX0_STN5_TX_DN<83>")
	)
	(segment
		(start 69.717412 -341.30107)
		(end 69.306948 -340.31047)
		(width 0.1651)
		(layer "In7.Cu")
		(net "P5E_PEX0_STN5_TX_DN<83>")
	)
	(segment
		(start 61.284358 -313.570112)
		(end 61.435488 -313.570112)
		(width 0.1143)
		(layer "In7.Cu")
		(net "P5E_PEX0_STN5_TX_DN<83>")
	)
	(segment
		(start 143.520668 -355.026722)
		(end 143.815308 -354.732082)
		(width 0.13462)
		(layer "F.Cu")
		(net "P5E_PEX1_STN5_TX_DN<95>")
	)
	(segment
		(start 143.520668 -355.658166)
		(end 143.520668 -355.026722)
		(width 0.13462)
		(layer "F.Cu")
		(net "P5E_PEX1_STN5_TX_DN<95>")
	)
	(segment
		(start 143.840708 -355.978206)
		(end 143.520668 -355.658166)
		(width 0.13462)
		(layer "F.Cu")
		(net "P5E_PEX1_STN5_TX_DN<95>")
	)
	(segment
		(start 189.049914 -313.684412)
		(end 189.049914 -313.949842)
		(width 0.1143)
		(layer "In13.Cu")
		(net "P5E_PEX1_STN5_TX_DN<95>")
	)
	(segment
		(start 180.582062 -329.439524)
		(end 182.35295 -328.49312)
		(width 0.1651)
		(layer "In13.Cu")
		(net "P5E_PEX1_STN5_TX_DN<95>")
	)
	(segment
		(start 143.524478 -353.816666)
		(end 146.222974 -351.11817)
		(width 0.1651)
		(layer "In13.Cu")
		(net "P5E_PEX1_STN5_TX_DN<95>")
	)
	(segment
		(start 188.935614 -313.570112)
		(end 189.049914 -313.684412)
		(width 0.1143)
		(layer "In13.Cu")
		(net "P5E_PEX1_STN5_TX_DN<95>")
	)
	(segment
		(start 178.833018 -330.374752)
		(end 180.581808 -329.440032)
		(width 0.1651)
		(layer "In13.Cu")
		(net "P5E_PEX1_STN5_TX_DN<95>")
	)
	(segment
		(start 188.773816 -313.570112)
		(end 188.935614 -313.570112)
		(width 0.1143)
		(layer "In13.Cu")
		(net "P5E_PEX1_STN5_TX_DN<95>")
	)
	(segment
		(start 186.367928 -325.810626)
		(end 188.15558 -324.022974)
		(width 0.1651)
		(layer "In13.Cu")
		(net "P5E_PEX1_STN5_TX_DN<95>")
	)
	(segment
		(start 188.670184 -313.673744)
		(end 188.773816 -313.570112)
		(width 0.1143)
		(layer "In13.Cu")
		(net "P5E_PEX1_STN5_TX_DN<95>")
	)
	(segment
		(start 188.670184 -319.995296)
		(end 188.670184 -313.673744)
		(width 0.1143)
		(layer "In13.Cu")
		(net "P5E_PEX1_STN5_TX_DN<95>")
	)
	(segment
		(start 188.715904 -320.041016)
		(end 188.670184 -319.995296)
		(width 0.1143)
		(layer "In13.Cu")
		(net "P5E_PEX1_STN5_TX_DN<95>")
	)
	(segment
		(start 180.581808 -329.440032)
		(end 180.582062 -329.439524)
		(width 0.1651)
		(layer "In13.Cu")
		(net "P5E_PEX1_STN5_TX_DN<95>")
	)
	(segment
		(start 143.524478 -354.441252)
		(end 143.524478 -353.816666)
		(width 0.1651)
		(layer "In13.Cu")
		(net "P5E_PEX1_STN5_TX_DN<95>")
	)
	(segment
		(start 143.815308 -354.732082)
		(end 143.524478 -354.441252)
		(width 0.1651)
		(layer "In13.Cu")
		(net "P5E_PEX1_STN5_TX_DN<95>")
	)
	(segment
		(start 146.222974 -351.11817)
		(end 146.222974 -351.118424)
		(width 0.1651)
		(layer "In13.Cu")
		(net "P5E_PEX1_STN5_TX_DN<95>")
	)
	(segment
		(start 146.222974 -351.118424)
		(end 178.833018 -330.374752)
		(width 0.1651)
		(layer "In13.Cu")
		(net "P5E_PEX1_STN5_TX_DN<95>")
	)
	(segment
		(start 188.715904 -322.669916)
		(end 188.715904 -320.063114)
		(width 0.1651)
		(layer "In13.Cu")
		(net "P5E_PEX1_STN5_TX_DN<95>")
	)
	(segment
		(start 188.15558 -324.022974)
		(end 188.715904 -322.669916)
		(width 0.1651)
		(layer "In13.Cu")
		(net "P5E_PEX1_STN5_TX_DN<95>")
	)
	(segment
		(start 188.715904 -320.063114)
		(end 188.715904 -320.041016)
		(width 0.1143)
		(layer "In13.Cu")
		(net "P5E_PEX1_STN5_TX_DN<95>")
	)
	(segment
		(start 182.35295 -328.49312)
		(end 186.367928 -325.810626)
		(width 0.1651)
		(layer "In13.Cu")
		(net "P5E_PEX1_STN5_TX_DN<95>")
	)
	(segment
		(start 331.451204 -349.511874)
		(end 331.451204 -348.88043)
		(width 0.13462)
		(layer "F.Cu")
		(net "P5E_PEX2_STN5_TX_DP<89>")
	)
	(segment
		(start 331.451204 -348.88043)
		(end 331.156564 -348.58579)
		(width 0.13462)
		(layer "F.Cu")
		(net "P5E_PEX2_STN5_TX_DP<89>")
	)
	(segment
		(start 331.131164 -349.831914)
		(end 331.451204 -349.511874)
		(width 0.13462)
		(layer "F.Cu")
		(net "P5E_PEX2_STN5_TX_DP<89>")
	)
	(segment
		(start 298.879514 -313.605418)
		(end 299.10532 -313.379612)
		(width 0.1143)
		(layer "In7.Cu")
		(net "P5E_PEX2_STN5_TX_DP<89>")
	)
	(segment
		(start 302.41621 -326.343264)
		(end 300.071028 -323.997828)
		(width 0.1651)
		(layer "In7.Cu")
		(net "P5E_PEX2_STN5_TX_DP<89>")
	)
	(segment
		(start 332.506828 -341.001858)
		(end 324.607682 -335.45653)
		(width 0.1651)
		(layer "In7.Cu")
		(net "P5E_PEX2_STN5_TX_DP<89>")
	)
	(segment
		(start 331.447394 -348.29496)
		(end 331.447394 -347.667834)
		(width 0.1651)
		(layer "In7.Cu")
		(net "P5E_PEX2_STN5_TX_DP<89>")
	)
	(segment
		(start 331.156564 -348.58579)
		(end 331.447394 -348.29496)
		(width 0.1651)
		(layer "In7.Cu")
		(net "P5E_PEX2_STN5_TX_DP<89>")
	)
	(segment
		(start 298.833794 -319.916048)
		(end 298.833794 -319.8876)
		(width 0.1143)
		(layer "In7.Cu")
		(net "P5E_PEX2_STN5_TX_DP<89>")
	)
	(segment
		(start 299.335444 -313.379612)
		(end 299.449744 -313.265312)
		(width 0.1143)
		(layer "In7.Cu")
		(net "P5E_PEX2_STN5_TX_DP<89>")
	)
	(segment
		(start 298.879514 -319.84188)
		(end 298.879514 -313.605418)
		(width 0.1143)
		(layer "In7.Cu")
		(net "P5E_PEX2_STN5_TX_DP<89>")
	)
	(segment
		(start 333.001874 -342.14562)
		(end 332.506828 -341.001858)
		(width 0.1651)
		(layer "In7.Cu")
		(net "P5E_PEX2_STN5_TX_DP<89>")
	)
	(segment
		(start 333.001874 -346.113354)
		(end 333.001874 -342.14562)
		(width 0.1651)
		(layer "In7.Cu")
		(net "P5E_PEX2_STN5_TX_DP<89>")
	)
	(segment
		(start 298.833794 -319.8876)
		(end 298.879514 -319.84188)
		(width 0.1143)
		(layer "In7.Cu")
		(net "P5E_PEX2_STN5_TX_DP<89>")
	)
	(segment
		(start 299.10532 -313.379612)
		(end 299.335444 -313.379612)
		(width 0.1143)
		(layer "In7.Cu")
		(net "P5E_PEX2_STN5_TX_DP<89>")
	)
	(segment
		(start 298.833794 -321.011042)
		(end 298.833794 -319.916048)
		(width 0.1651)
		(layer "In7.Cu")
		(net "P5E_PEX2_STN5_TX_DP<89>")
	)
	(segment
		(start 331.447394 -347.667834)
		(end 333.001874 -346.113354)
		(width 0.1651)
		(layer "In7.Cu")
		(net "P5E_PEX2_STN5_TX_DP<89>")
	)
	(segment
		(start 299.449744 -313.265312)
		(end 299.449744 -312.999882)
		(width 0.1143)
		(layer "In7.Cu")
		(net "P5E_PEX2_STN5_TX_DP<89>")
	)
	(segment
		(start 324.607682 -335.45653)
		(end 302.41621 -326.343264)
		(width 0.1651)
		(layer "In7.Cu")
		(net "P5E_PEX2_STN5_TX_DP<89>")
	)
	(segment
		(start 300.071028 -323.997828)
		(end 298.833794 -321.011042)
		(width 0.1651)
		(layer "In7.Cu")
		(net "P5E_PEX2_STN5_TX_DP<89>")
	)
	(segment
		(start 386.067808 -125.494542)
		(end 386.36575 -125.1966)
		(width 0.13462)
		(layer "F.Cu")
		(net "P5E_PEX3_STN1_TX_DP<27>")
	)
	(segment
		(start 386.99059 -125.1966)
		(end 387.313932 -125.519942)
		(width 0.13462)
		(layer "F.Cu")
		(net "P5E_PEX3_STN1_TX_DP<27>")
	)
	(segment
		(start 386.36575 -125.1966)
		(end 386.99059 -125.1966)
		(width 0.13462)
		(layer "F.Cu")
		(net "P5E_PEX3_STN1_TX_DP<27>")
	)
	(segment
		(start 382.75768 -128.575562)
		(end 382.63449 -128.599946)
		(width 0.1651)
		(layer "In9.Cu")
		(net "P5E_PEX3_STN1_TX_DP<27>")
	)
	(segment
		(start 381.495808 -141.523212)
		(end 381.447802 -141.63929)
		(width 0.1651)
		(layer "In9.Cu")
		(net "P5E_PEX3_STN1_TX_DP<27>")
	)
	(segment
		(start 381.43815 -130.596132)
		(end 381.279654 -130.627628)
		(width 0.1651)
		(layer "In9.Cu")
		(net "P5E_PEX3_STN1_TX_DP<27>")
	)
	(segment
		(start 381.062484 -140.410438)
		(end 381.000508 -140.55979)
		(width 0.1651)
		(layer "In9.Cu")
		(net "P5E_PEX3_STN1_TX_DP<27>")
	)
	(segment
		(start 379.432312 -134.125716)
		(end 379.432312 -136.774428)
		(width 0.1651)
		(layer "In9.Cu")
		(net "P5E_PEX3_STN1_TX_DP<27>")
	)
	(segment
		(start 381.279654 -130.627628)
		(end 381.004572 -131.039362)
		(width 0.1651)
		(layer "In9.Cu")
		(net "P5E_PEX3_STN1_TX_DP<27>")
	)
	(segment
		(start 381.957072 -129.613914)
		(end 381.68199 -130.025648)
		(width 0.1651)
		(layer "In9.Cu")
		(net "P5E_PEX3_STN1_TX_DP<27>")
	)
	(segment
		(start 380.231396 -132.196332)
		(end 379.432312 -134.125716)
		(width 0.1651)
		(layer "In9.Cu")
		(net "P5E_PEX3_STN1_TX_DP<27>")
	)
	(segment
		(start 385.776978 -125.203712)
		(end 385.209288 -125.203712)
		(width 0.1651)
		(layer "In9.Cu")
		(net "P5E_PEX3_STN1_TX_DP<27>")
	)
	(segment
		(start 381.000508 -140.55979)
		(end 381.189992 -141.017244)
		(width 0.1651)
		(layer "In9.Cu")
		(net "P5E_PEX3_STN1_TX_DP<27>")
	)
	(segment
		(start 381.189992 -141.017244)
		(end 381.30607 -141.06525)
		(width 0.1651)
		(layer "In9.Cu")
		(net "P5E_PEX3_STN1_TX_DP<27>")
	)
	(segment
		(start 381.004572 -131.039362)
		(end 381.036068 -131.197858)
		(width 0.1651)
		(layer "In9.Cu")
		(net "P5E_PEX3_STN1_TX_DP<27>")
	)
	(segment
		(start 382.362202 -150.200614)
		(end 382.713484 -157.341062)
		(width 0.1651)
		(layer "In9.Cu")
		(net "P5E_PEX3_STN1_TX_DP<27>")
	)
	(segment
		(start 382.390904 -129.170176)
		(end 382.115568 -129.582164)
		(width 0.1651)
		(layer "In9.Cu")
		(net "P5E_PEX3_STN1_TX_DP<27>")
	)
	(segment
		(start 381.036068 -131.197858)
		(end 380.760732 -131.609846)
		(width 0.1651)
		(layer "In9.Cu")
		(net "P5E_PEX3_STN1_TX_DP<27>")
	)
	(segment
		(start 381.68199 -130.025648)
		(end 381.713486 -130.184144)
		(width 0.1651)
		(layer "In9.Cu")
		(net "P5E_PEX3_STN1_TX_DP<27>")
	)
	(segment
		(start 380.723394 -139.890754)
		(end 380.873 -139.95273)
		(width 0.1651)
		(layer "In9.Cu")
		(net "P5E_PEX3_STN1_TX_DP<27>")
	)
	(segment
		(start 380.595886 -139.283948)
		(end 380.53391 -139.4333)
		(width 0.1651)
		(layer "In9.Cu")
		(net "P5E_PEX3_STN1_TX_DP<27>")
	)
	(segment
		(start 382.007618 -142.991078)
		(end 382.362202 -150.200614)
		(width 0.1651)
		(layer "In9.Cu")
		(net "P5E_PEX3_STN1_TX_DP<27>")
	)
	(segment
		(start 382.359408 -129.01168)
		(end 382.390904 -129.170176)
		(width 0.1651)
		(layer "In9.Cu")
		(net "P5E_PEX3_STN1_TX_DP<27>")
	)
	(segment
		(start 380.53391 -139.4333)
		(end 380.723394 -139.890754)
		(width 0.1651)
		(layer "In9.Cu")
		(net "P5E_PEX3_STN1_TX_DP<27>")
	)
	(segment
		(start 382.997964 -128.216152)
		(end 382.75768 -128.575562)
		(width 0.1651)
		(layer "In9.Cu")
		(net "P5E_PEX3_STN1_TX_DP<27>")
	)
	(segment
		(start 418.123878 -280.129488)
		(end 418.285676 -280.129488)
		(width 0.1143)
		(layer "In9.Cu")
		(net "P5E_PEX3_STN1_TX_DP<27>")
	)
	(segment
		(start 383.580132 -127.184912)
		(end 383.604516 -127.308356)
		(width 0.1651)
		(layer "In9.Cu")
		(net "P5E_PEX3_STN1_TX_DP<27>")
	)
	(segment
		(start 418.065966 -263.596628)
		(end 418.065966 -271.526)
		(width 0.1651)
		(layer "In9.Cu")
		(net "P5E_PEX3_STN1_TX_DP<27>")
	)
	(segment
		(start 380.067312 -138.30681)
		(end 380.256796 -138.764264)
		(width 0.1651)
		(layer "In9.Cu")
		(net "P5E_PEX3_STN1_TX_DP<27>")
	)
	(segment
		(start 381.713486 -130.184144)
		(end 381.43815 -130.596132)
		(width 0.1651)
		(layer "In9.Cu")
		(net "P5E_PEX3_STN1_TX_DP<27>")
	)
	(segment
		(start 386.067808 -125.494542)
		(end 385.776978 -125.203712)
		(width 0.1651)
		(layer "In9.Cu")
		(net "P5E_PEX3_STN1_TX_DP<27>")
	)
	(segment
		(start 385.209288 -125.203712)
		(end 384.288792 -126.124208)
		(width 0.1651)
		(layer "In9.Cu")
		(net "P5E_PEX3_STN1_TX_DP<27>")
	)
	(segment
		(start 380.129034 -138.157458)
		(end 380.067312 -138.30681)
		(width 0.1651)
		(layer "In9.Cu")
		(net "P5E_PEX3_STN1_TX_DP<27>")
	)
	(segment
		(start 382.115568 -129.582164)
		(end 381.957072 -129.613914)
		(width 0.1651)
		(layer "In9.Cu")
		(net "P5E_PEX3_STN1_TX_DP<27>")
	)
	(segment
		(start 418.020246 -271.600168)
		(end 418.020246 -280.025856)
		(width 0.1143)
		(layer "In9.Cu")
		(net "P5E_PEX3_STN1_TX_DP<27>")
	)
	(segment
		(start 380.873 -139.95273)
		(end 381.062484 -140.410438)
		(width 0.1651)
		(layer "In9.Cu")
		(net "P5E_PEX3_STN1_TX_DP<27>")
	)
	(segment
		(start 380.760732 -131.609846)
		(end 380.602236 -131.641342)
		(width 0.1651)
		(layer "In9.Cu")
		(net "P5E_PEX3_STN1_TX_DP<27>")
	)
	(segment
		(start 380.602236 -131.641342)
		(end 380.231396 -132.196332)
		(width 0.1651)
		(layer "In9.Cu")
		(net "P5E_PEX3_STN1_TX_DP<27>")
	)
	(segment
		(start 382.713484 -157.341062)
		(end 383.5908 -161.75228)
		(width 0.1651)
		(layer "In9.Cu")
		(net "P5E_PEX3_STN1_TX_DP<27>")
	)
	(segment
		(start 418.285676 -280.129488)
		(end 418.399976 -280.015188)
		(width 0.1143)
		(layer "In9.Cu")
		(net "P5E_PEX3_STN1_TX_DP<27>")
	)
	(segment
		(start 383.364486 -127.667512)
		(end 383.241042 -127.69215)
		(width 0.1651)
		(layer "In9.Cu")
		(net "P5E_PEX3_STN1_TX_DP<27>")
	)
	(segment
		(start 418.020246 -280.025856)
		(end 418.123878 -280.129488)
		(width 0.1143)
		(layer "In9.Cu")
		(net "P5E_PEX3_STN1_TX_DP<27>")
	)
	(segment
		(start 381.30607 -141.06525)
		(end 381.495808 -141.523212)
		(width 0.1651)
		(layer "In9.Cu")
		(net "P5E_PEX3_STN1_TX_DP<27>")
	)
	(segment
		(start 384.288792 -126.124208)
		(end 383.580132 -127.184912)
		(width 0.1651)
		(layer "In9.Cu")
		(net "P5E_PEX3_STN1_TX_DP<27>")
	)
	(segment
		(start 382.973326 -128.092962)
		(end 382.997964 -128.216152)
		(width 0.1651)
		(layer "In9.Cu")
		(net "P5E_PEX3_STN1_TX_DP<27>")
	)
	(segment
		(start 383.5908 -161.75228)
		(end 418.065966 -263.596628)
		(width 0.1651)
		(layer "In9.Cu")
		(net "P5E_PEX3_STN1_TX_DP<27>")
	)
	(segment
		(start 418.065966 -271.554448)
		(end 418.020246 -271.600168)
		(width 0.1143)
		(layer "In9.Cu")
		(net "P5E_PEX3_STN1_TX_DP<27>")
	)
	(segment
		(start 383.604516 -127.308356)
		(end 383.364486 -127.667512)
		(width 0.1651)
		(layer "In9.Cu")
		(net "P5E_PEX3_STN1_TX_DP<27>")
	)
	(segment
		(start 418.065966 -271.526)
		(end 418.065966 -271.554448)
		(width 0.1143)
		(layer "In9.Cu")
		(net "P5E_PEX3_STN1_TX_DP<27>")
	)
	(segment
		(start 380.256796 -138.764264)
		(end 380.406402 -138.82624)
		(width 0.1651)
		(layer "In9.Cu")
		(net "P5E_PEX3_STN1_TX_DP<27>")
	)
	(segment
		(start 418.399976 -280.015188)
		(end 418.399976 -279.749504)
		(width 0.1143)
		(layer "In9.Cu")
		(net "P5E_PEX3_STN1_TX_DP<27>")
	)
	(segment
		(start 379.789944 -137.637774)
		(end 379.93955 -137.69975)
		(width 0.1651)
		(layer "In9.Cu")
		(net "P5E_PEX3_STN1_TX_DP<27>")
	)
	(segment
		(start 380.406402 -138.82624)
		(end 380.595886 -139.283948)
		(width 0.1651)
		(layer "In9.Cu")
		(net "P5E_PEX3_STN1_TX_DP<27>")
	)
	(segment
		(start 381.447802 -141.63929)
		(end 382.007618 -142.991078)
		(width 0.1651)
		(layer "In9.Cu")
		(net "P5E_PEX3_STN1_TX_DP<27>")
	)
	(segment
		(start 379.93955 -137.69975)
		(end 380.129034 -138.157458)
		(width 0.1651)
		(layer "In9.Cu")
		(net "P5E_PEX3_STN1_TX_DP<27>")
	)
	(segment
		(start 379.432312 -136.774428)
		(end 379.789944 -137.637774)
		(width 0.1651)
		(layer "In9.Cu")
		(net "P5E_PEX3_STN1_TX_DP<27>")
	)
	(segment
		(start 382.63449 -128.599946)
		(end 382.359408 -129.01168)
		(width 0.1651)
		(layer "In9.Cu")
		(net "P5E_PEX3_STN1_TX_DP<27>")
	)
	(segment
		(start 383.241042 -127.69215)
		(end 382.973326 -128.092962)
		(width 0.1651)
		(layer "In9.Cu")
		(net "P5E_PEX3_STN1_TX_DP<27>")
	)
	(segment
		(start 377.700032 -348.879922)
		(end 377.4059 -348.58579)
		(width 0.13462)
		(layer "F.Cu")
		(net "P5E_PEX3_STN6_TX_DP<100>")
	)
	(segment
		(start 377.700032 -349.512382)
		(end 377.700032 -348.879922)
		(width 0.13462)
		(layer "F.Cu")
		(net "P5E_PEX3_STN6_TX_DP<100>")
	)
	(segment
		(start 377.3805 -349.831914)
		(end 377.700032 -349.512382)
		(width 0.13462)
		(layer "F.Cu")
		(net "P5E_PEX3_STN6_TX_DP<100>")
	)
	(segment
		(start 401.633944 -320.823336)
		(end 401.633944 -319.9892)
		(width 0.1651)
		(layer "In7.Cu")
		(net "P5E_PEX3_STN6_TX_DP<100>")
	)
	(segment
		(start 401.679664 -319.915032)
		(end 401.679664 -313.605418)
		(width 0.1143)
		(layer "In7.Cu")
		(net "P5E_PEX3_STN6_TX_DP<100>")
	)
	(segment
		(start 379.25121 -341.47506)
		(end 399.495518 -323.502782)
		(width 0.1651)
		(layer "In7.Cu")
		(net "P5E_PEX3_STN6_TX_DP<100>")
	)
	(segment
		(start 377.69673 -348.29496)
		(end 377.69673 -347.667834)
		(width 0.1651)
		(layer "In7.Cu")
		(net "P5E_PEX3_STN6_TX_DP<100>")
	)
	(segment
		(start 379.25121 -346.113354)
		(end 379.25121 -341.47506)
		(width 0.1651)
		(layer "In7.Cu")
		(net "P5E_PEX3_STN6_TX_DP<100>")
	)
	(segment
		(start 402.135594 -313.379612)
		(end 402.249894 -313.265312)
		(width 0.1143)
		(layer "In7.Cu")
		(net "P5E_PEX3_STN6_TX_DP<100>")
	)
	(segment
		(start 401.90547 -313.379612)
		(end 402.135594 -313.379612)
		(width 0.1143)
		(layer "In7.Cu")
		(net "P5E_PEX3_STN6_TX_DP<100>")
	)
	(segment
		(start 401.251166 -321.747134)
		(end 401.633944 -320.823336)
		(width 0.1651)
		(layer "In7.Cu")
		(net "P5E_PEX3_STN6_TX_DP<100>")
	)
	(segment
		(start 401.633944 -319.960752)
		(end 401.679664 -319.915032)
		(width 0.1143)
		(layer "In7.Cu")
		(net "P5E_PEX3_STN6_TX_DP<100>")
	)
	(segment
		(start 402.249894 -313.265312)
		(end 402.249894 -312.999882)
		(width 0.1143)
		(layer "In7.Cu")
		(net "P5E_PEX3_STN6_TX_DP<100>")
	)
	(segment
		(start 399.495518 -323.502782)
		(end 401.251166 -321.747134)
		(width 0.1651)
		(layer "In7.Cu")
		(net "P5E_PEX3_STN6_TX_DP<100>")
	)
	(segment
		(start 377.69673 -347.667834)
		(end 379.25121 -346.113354)
		(width 0.1651)
		(layer "In7.Cu")
		(net "P5E_PEX3_STN6_TX_DP<100>")
	)
	(segment
		(start 401.633944 -319.9892)
		(end 401.633944 -319.960752)
		(width 0.1143)
		(layer "In7.Cu")
		(net "P5E_PEX3_STN6_TX_DP<100>")
	)
	(segment
		(start 377.4059 -348.58579)
		(end 377.69673 -348.29496)
		(width 0.1651)
		(layer "In7.Cu")
		(net "P5E_PEX3_STN6_TX_DP<100>")
	)
	(segment
		(start 401.679664 -313.605418)
		(end 401.90547 -313.379612)
		(width 0.1143)
		(layer "In7.Cu")
		(net "P5E_PEX3_STN6_TX_DP<100>")
	)
	(segment
		(start 66.870072 -318.434466)
		(end 66.984372 -318.320166)
		(width 0.1143)
		(layer "In5.Cu")
		(net "P5E_PEX0_STN5_RX_DN<89>")
	)
	(segment
		(start 75.935332 -342.20277)
		(end 67.566032 -324.508622)
		(width 0.1651)
		(layer "In5.Cu")
		(net "P5E_PEX0_STN5_RX_DN<89>")
	)
	(segment
		(start 66.915792 -321.616578)
		(end 66.915792 -319.995296)
		(width 0.1651)
		(layer "In5.Cu")
		(net "P5E_PEX0_STN5_RX_DN<89>")
	)
	(segment
		(start 75.28433 -371.98427)
		(end 75.28433 -369.424712)
		(width 0.1651)
		(layer "In5.Cu")
		(net "P5E_PEX0_STN5_RX_DN<89>")
	)
	(segment
		(start 74.109834 -372.890034)
		(end 74.109834 -372.508018)
		(width 0.1651)
		(layer "In5.Cu")
		(net "P5E_PEX0_STN5_RX_DN<89>")
	)
	(segment
		(start 74.887582 -372.381018)
		(end 75.28433 -371.98427)
		(width 0.1651)
		(layer "In5.Cu")
		(net "P5E_PEX0_STN5_RX_DN<89>")
	)
	(segment
		(start 67.135502 -318.320166)
		(end 67.249802 -318.434466)
		(width 0.1143)
		(layer "In5.Cu")
		(net "P5E_PEX0_STN5_RX_DN<89>")
	)
	(segment
		(start 75.935332 -357.777542)
		(end 75.935332 -342.20277)
		(width 0.1651)
		(layer "In5.Cu")
		(net "P5E_PEX0_STN5_RX_DN<89>")
	)
	(segment
		(start 66.870072 -319.921128)
		(end 66.870072 -318.434466)
		(width 0.1143)
		(layer "In5.Cu")
		(net "P5E_PEX0_STN5_RX_DN<89>")
	)
	(segment
		(start 67.566032 -324.508622)
		(end 66.915792 -321.616578)
		(width 0.1651)
		(layer "In5.Cu")
		(net "P5E_PEX0_STN5_RX_DN<89>")
	)
	(segment
		(start 66.915792 -319.995296)
		(end 66.915792 -319.966848)
		(width 0.1143)
		(layer "In5.Cu")
		(net "P5E_PEX0_STN5_RX_DN<89>")
	)
	(segment
		(start 74.109834 -372.508018)
		(end 74.236834 -372.381018)
		(width 0.1651)
		(layer "In5.Cu")
		(net "P5E_PEX0_STN5_RX_DN<89>")
	)
	(segment
		(start 66.984372 -318.320166)
		(end 67.135502 -318.320166)
		(width 0.1143)
		(layer "In5.Cu")
		(net "P5E_PEX0_STN5_RX_DN<89>")
	)
	(segment
		(start 66.915792 -319.966848)
		(end 66.870072 -319.921128)
		(width 0.1143)
		(layer "In5.Cu")
		(net "P5E_PEX0_STN5_RX_DN<89>")
	)
	(segment
		(start 75.28433 -369.424712)
		(end 75.442826 -367.814352)
		(width 0.1651)
		(layer "In5.Cu")
		(net "P5E_PEX0_STN5_RX_DN<89>")
	)
	(segment
		(start 74.236834 -372.381018)
		(end 74.887582 -372.381018)
		(width 0.1651)
		(layer "In5.Cu")
		(net "P5E_PEX0_STN5_RX_DN<89>")
	)
	(segment
		(start 75.442826 -367.814352)
		(end 75.935332 -357.777542)
		(width 0.1651)
		(layer "In5.Cu")
		(net "P5E_PEX0_STN5_RX_DN<89>")
	)
	(segment
		(start 67.249802 -318.434466)
		(end 67.249802 -318.699896)
		(width 0.1143)
		(layer "In5.Cu")
		(net "P5E_PEX0_STN5_RX_DN<89>")
	)
	(segment
		(start 74.377042 -349.511874)
		(end 74.377042 -348.88043)
		(width 0.13462)
		(layer "F.Cu")
		(net "P5E_PEX0_STN5_TX_DN<86>")
	)
	(segment
		(start 74.697082 -349.831914)
		(end 74.377042 -349.511874)
		(width 0.13462)
		(layer "F.Cu")
		(net "P5E_PEX0_STN5_TX_DN<86>")
	)
	(segment
		(start 74.377042 -348.88043)
		(end 74.671682 -348.58579)
		(width 0.13462)
		(layer "F.Cu")
		(net "P5E_PEX0_STN5_TX_DN<86>")
	)
	(segment
		(start 74.059034 -338.05495)
		(end 73.783698 -337.642962)
		(width 0.1651)
		(layer "In7.Cu")
		(net "P5E_PEX0_STN5_TX_DN<86>")
	)
	(segment
		(start 64.065912 -319.8876)
		(end 64.020192 -319.84188)
		(width 0.1143)
		(layer "In7.Cu")
		(net "P5E_PEX0_STN5_TX_DN<86>")
	)
	(segment
		(start 75.935332 -341.023194)
		(end 74.03465 -338.178394)
		(width 0.1651)
		(layer "In7.Cu")
		(net "P5E_PEX0_STN5_TX_DN<86>")
	)
	(segment
		(start 64.426084 -323.67474)
		(end 64.065912 -322.80479)
		(width 0.1651)
		(layer "In7.Cu")
		(net "P5E_PEX0_STN5_TX_DN<86>")
	)
	(segment
		(start 64.020192 -311.784492)
		(end 64.134492 -311.670192)
		(width 0.1143)
		(layer "In7.Cu")
		(net "P5E_PEX0_STN5_TX_DN<86>")
	)
	(segment
		(start 74.671682 -348.58579)
		(end 74.380852 -348.29496)
		(width 0.1651)
		(layer "In7.Cu")
		(net "P5E_PEX0_STN5_TX_DN<86>")
	)
	(segment
		(start 69.662802 -331.635608)
		(end 66.586354 -327.487788)
		(width 0.1651)
		(layer "In7.Cu")
		(net "P5E_PEX0_STN5_TX_DN<86>")
	)
	(segment
		(start 64.134492 -311.670192)
		(end 64.285622 -311.670192)
		(width 0.1143)
		(layer "In7.Cu")
		(net "P5E_PEX0_STN5_TX_DN<86>")
	)
	(segment
		(start 64.399922 -311.784492)
		(end 64.399922 -312.049922)
		(width 0.1143)
		(layer "In7.Cu")
		(net "P5E_PEX0_STN5_TX_DN<86>")
	)
	(segment
		(start 73.660254 -337.618578)
		(end 69.662802 -331.635608)
		(width 0.1651)
		(layer "In7.Cu")
		(net "P5E_PEX0_STN5_TX_DN<86>")
	)
	(segment
		(start 74.380852 -347.658182)
		(end 75.935332 -346.103702)
		(width 0.1651)
		(layer "In7.Cu")
		(net "P5E_PEX0_STN5_TX_DN<86>")
	)
	(segment
		(start 75.935332 -346.103702)
		(end 75.935332 -341.023194)
		(width 0.1651)
		(layer "In7.Cu")
		(net "P5E_PEX0_STN5_TX_DN<86>")
	)
	(segment
		(start 64.065912 -319.916048)
		(end 64.065912 -319.8876)
		(width 0.1143)
		(layer "In7.Cu")
		(net "P5E_PEX0_STN5_TX_DN<86>")
	)
	(segment
		(start 73.783698 -337.642962)
		(end 73.660254 -337.618578)
		(width 0.1651)
		(layer "In7.Cu")
		(net "P5E_PEX0_STN5_TX_DN<86>")
	)
	(segment
		(start 74.03465 -338.178394)
		(end 74.059034 -338.05495)
		(width 0.1651)
		(layer "In7.Cu")
		(net "P5E_PEX0_STN5_TX_DN<86>")
	)
	(segment
		(start 64.285622 -311.670192)
		(end 64.399922 -311.784492)
		(width 0.1143)
		(layer "In7.Cu")
		(net "P5E_PEX0_STN5_TX_DN<86>")
	)
	(segment
		(start 74.380852 -348.29496)
		(end 74.380852 -347.658182)
		(width 0.1651)
		(layer "In7.Cu")
		(net "P5E_PEX0_STN5_TX_DN<86>")
	)
	(segment
		(start 64.065912 -322.80479)
		(end 64.065912 -319.916048)
		(width 0.1651)
		(layer "In7.Cu")
		(net "P5E_PEX0_STN5_TX_DN<86>")
	)
	(segment
		(start 64.020192 -319.84188)
		(end 64.020192 -311.784492)
		(width 0.1143)
		(layer "In7.Cu")
		(net "P5E_PEX0_STN5_TX_DN<86>")
	)
	(segment
		(start 66.586354 -327.487788)
		(end 64.426084 -323.67474)
		(width 0.1651)
		(layer "In7.Cu")
		(net "P5E_PEX0_STN5_TX_DN<86>")
	)
	(segment
		(start 213.11997 -28.829)
		(end 212.46973 -28.829)
		(width 0.13462)
		(layer "F.Cu")
		(net "P5E_PEX1_STN2_TX_DP<32>")
	)
	(segment
		(start 212.46973 -28.829)
		(end 212.159088 -29.139642)
		(width 0.13462)
		(layer "F.Cu")
		(net "P5E_PEX1_STN2_TX_DP<32>")
	)
	(segment
		(start 213.405212 -29.114242)
		(end 213.11997 -28.829)
		(width 0.13462)
		(layer "F.Cu")
		(net "P5E_PEX1_STN2_TX_DP<32>")
	)
	(segment
		(start 174.184056 -266.06373)
		(end 174.184056 -271.399)
		(width 0.1651)
		(layer "In11.Cu")
		(net "P5E_PEX1_STN2_TX_DP<32>")
	)
	(segment
		(start 195.515992 -135.763508)
		(end 195.515992 -140.76553)
		(width 0.1651)
		(layer "In11.Cu")
		(net "P5E_PEX1_STN2_TX_DP<32>")
	)
	(segment
		(start 211.331556 -81.8134)
		(end 197.767956 -105.9434)
		(width 0.1651)
		(layer "In11.Cu")
		(net "P5E_PEX1_STN2_TX_DP<32>")
	)
	(segment
		(start 219.644976 -76.534772)
		(end 213.011258 -80.133698)
		(width 0.1651)
		(layer "In11.Cu")
		(net "P5E_PEX1_STN2_TX_DP<32>")
	)
	(segment
		(start 220.995494 -33.924494)
		(end 220.959934 -34.045144)
		(width 0.1651)
		(layer "In11.Cu")
		(net "P5E_PEX1_STN2_TX_DP<32>")
	)
	(segment
		(start 195.25488 -141.889734)
		(end 195.068952 -146.24304)
		(width 0.1651)
		(layer "In11.Cu")
		(net "P5E_PEX1_STN2_TX_DP<32>")
	)
	(segment
		(start 174.229776 -280.10485)
		(end 174.444914 -280.319988)
		(width 0.1143)
		(layer "In11.Cu")
		(net "P5E_PEX1_STN2_TX_DP<32>")
	)
	(segment
		(start 217.753438 -29.735018)
		(end 219.85986 -31.84652)
		(width 0.1651)
		(layer "In11.Cu")
		(net "P5E_PEX1_STN2_TX_DP<32>")
	)
	(segment
		(start 220.637354 -33.454594)
		(end 220.758004 -33.4899)
		(width 0.1651)
		(layer "In11.Cu")
		(net "P5E_PEX1_STN2_TX_DP<32>")
	)
	(segment
		(start 225.240342 -56.946546)
		(end 222.940626 -68.690744)
		(width 0.1651)
		(layer "In11.Cu")
		(net "P5E_PEX1_STN2_TX_DP<32>")
	)
	(segment
		(start 220.758004 -33.4899)
		(end 220.995494 -33.924494)
		(width 0.1651)
		(layer "In11.Cu")
		(net "P5E_PEX1_STN2_TX_DP<32>")
	)
	(segment
		(start 213.011258 -80.133698)
		(end 211.331556 -81.8134)
		(width 0.1651)
		(layer "In11.Cu")
		(net "P5E_PEX1_STN2_TX_DP<32>")
	)
	(segment
		(start 221.197932 -34.479992)
		(end 221.318582 -34.515298)
		(width 0.1651)
		(layer "In11.Cu")
		(net "P5E_PEX1_STN2_TX_DP<32>")
	)
	(segment
		(start 193.491612 -161.014918)
		(end 174.184056 -266.06373)
		(width 0.1651)
		(layer "In11.Cu")
		(net "P5E_PEX1_STN2_TX_DP<32>")
	)
	(segment
		(start 215.459818 -28.823412)
		(end 217.753438 -29.735018)
		(width 0.1651)
		(layer "In11.Cu")
		(net "P5E_PEX1_STN2_TX_DP<32>")
	)
	(segment
		(start 194.444366 -153.837386)
		(end 193.491612 -161.014918)
		(width 0.1651)
		(layer "In11.Cu")
		(net "P5E_PEX1_STN2_TX_DP<32>")
	)
	(segment
		(start 224.26803 -39.912036)
		(end 224.952306 -42.485818)
		(width 0.1651)
		(layer "In11.Cu")
		(net "P5E_PEX1_STN2_TX_DP<32>")
	)
	(segment
		(start 220.54312 -75.376786)
		(end 219.644976 -76.534772)
		(width 0.1651)
		(layer "In11.Cu")
		(net "P5E_PEX1_STN2_TX_DP<32>")
	)
	(segment
		(start 221.318582 -34.515298)
		(end 224.26803 -39.912036)
		(width 0.1651)
		(layer "In11.Cu")
		(net "P5E_PEX1_STN2_TX_DP<32>")
	)
	(segment
		(start 224.952306 -42.485818)
		(end 225.240342 -56.946546)
		(width 0.1651)
		(layer "In11.Cu")
		(net "P5E_PEX1_STN2_TX_DP<32>")
	)
	(segment
		(start 220.959934 -34.045144)
		(end 221.197932 -34.479992)
		(width 0.1651)
		(layer "In11.Cu")
		(net "P5E_PEX1_STN2_TX_DP<32>")
	)
	(segment
		(start 197.767956 -105.9434)
		(end 196.274944 -117.958362)
		(width 0.1651)
		(layer "In11.Cu")
		(net "P5E_PEX1_STN2_TX_DP<32>")
	)
	(segment
		(start 174.444914 -280.319988)
		(end 174.685706 -280.319988)
		(width 0.1143)
		(layer "In11.Cu")
		(net "P5E_PEX1_STN2_TX_DP<32>")
	)
	(segment
		(start 222.940626 -68.690744)
		(end 220.54312 -75.376786)
		(width 0.1651)
		(layer "In11.Cu")
		(net "P5E_PEX1_STN2_TX_DP<32>")
	)
	(segment
		(start 213.696042 -28.823412)
		(end 215.459818 -28.823412)
		(width 0.1651)
		(layer "In11.Cu")
		(net "P5E_PEX1_STN2_TX_DP<32>")
	)
	(segment
		(start 174.229776 -271.473168)
		(end 174.229776 -280.10485)
		(width 0.1143)
		(layer "In11.Cu")
		(net "P5E_PEX1_STN2_TX_DP<32>")
	)
	(segment
		(start 174.800006 -280.434288)
		(end 174.800006 -280.699718)
		(width 0.1143)
		(layer "In11.Cu")
		(net "P5E_PEX1_STN2_TX_DP<32>")
	)
	(segment
		(start 195.515992 -140.76553)
		(end 195.25488 -141.889734)
		(width 0.1651)
		(layer "In11.Cu")
		(net "P5E_PEX1_STN2_TX_DP<32>")
	)
	(segment
		(start 174.685706 -280.319988)
		(end 174.800006 -280.434288)
		(width 0.1143)
		(layer "In11.Cu")
		(net "P5E_PEX1_STN2_TX_DP<32>")
	)
	(segment
		(start 220.39961 -33.019492)
		(end 220.637354 -33.454594)
		(width 0.1651)
		(layer "In11.Cu")
		(net "P5E_PEX1_STN2_TX_DP<32>")
	)
	(segment
		(start 196.274944 -117.958362)
		(end 195.515992 -135.763508)
		(width 0.1651)
		(layer "In11.Cu")
		(net "P5E_PEX1_STN2_TX_DP<32>")
	)
	(segment
		(start 213.405212 -29.114242)
		(end 213.696042 -28.823412)
		(width 0.1651)
		(layer "In11.Cu")
		(net "P5E_PEX1_STN2_TX_DP<32>")
	)
	(segment
		(start 220.434916 -32.898842)
		(end 220.39961 -33.019492)
		(width 0.1651)
		(layer "In11.Cu")
		(net "P5E_PEX1_STN2_TX_DP<32>")
	)
	(segment
		(start 174.184056 -271.427448)
		(end 174.229776 -271.473168)
		(width 0.1143)
		(layer "In11.Cu")
		(net "P5E_PEX1_STN2_TX_DP<32>")
	)
	(segment
		(start 195.068952 -146.24304)
		(end 194.444366 -153.837386)
		(width 0.1651)
		(layer "In11.Cu")
		(net "P5E_PEX1_STN2_TX_DP<32>")
	)
	(segment
		(start 219.85986 -31.84652)
		(end 220.434916 -32.898842)
		(width 0.1651)
		(layer "In11.Cu")
		(net "P5E_PEX1_STN2_TX_DP<32>")
	)
	(segment
		(start 174.184056 -271.399)
		(end 174.184056 -271.427448)
		(width 0.1143)
		(layer "In11.Cu")
		(net "P5E_PEX1_STN2_TX_DP<32>")
	)
	(segment
		(start 328.616564 -355.026722)
		(end 328.911204 -354.732082)
		(width 0.13462)
		(layer "F.Cu")
		(net "P5E_PEX2_STN5_TX_DN<88>")
	)
	(segment
		(start 328.936604 -355.978206)
		(end 328.616564 -355.658166)
		(width 0.13462)
		(layer "F.Cu")
		(net "P5E_PEX2_STN5_TX_DN<88>")
	)
	(segment
		(start 328.616564 -355.658166)
		(end 328.616564 -355.026722)
		(width 0.13462)
		(layer "F.Cu")
		(net "P5E_PEX2_STN5_TX_DN<88>")
	)
	(segment
		(start 298.165774 -319.8876)
		(end 298.120054 -319.84188)
		(width 0.1143)
		(layer "In7.Cu")
		(net "P5E_PEX2_STN5_TX_DN<88>")
	)
	(segment
		(start 300.481492 -325.533512)
		(end 299.591476 -324.643496)
		(width 0.1651)
		(layer "In7.Cu")
		(net "P5E_PEX2_STN5_TX_DN<88>")
	)
	(segment
		(start 298.120054 -319.84188)
		(end 298.120054 -311.784492)
		(width 0.1143)
		(layer "In7.Cu")
		(net "P5E_PEX2_STN5_TX_DN<88>")
	)
	(segment
		(start 328.620374 -353.930966)
		(end 330.174854 -352.376486)
		(width 0.1651)
		(layer "In7.Cu")
		(net "P5E_PEX2_STN5_TX_DN<88>")
	)
	(segment
		(start 329.6412 -340.7664)
		(end 328.317098 -338.972144)
		(width 0.1651)
		(layer "In7.Cu")
		(net "P5E_PEX2_STN5_TX_DN<88>")
	)
	(segment
		(start 328.317098 -338.972144)
		(end 323.778372 -335.882488)
		(width 0.1651)
		(layer "In7.Cu")
		(net "P5E_PEX2_STN5_TX_DN<88>")
	)
	(segment
		(start 298.165774 -319.916048)
		(end 298.165774 -319.8876)
		(width 0.1143)
		(layer "In7.Cu")
		(net "P5E_PEX2_STN5_TX_DN<88>")
	)
	(segment
		(start 298.385484 -311.670192)
		(end 298.499784 -311.784492)
		(width 0.1143)
		(layer "In7.Cu")
		(net "P5E_PEX2_STN5_TX_DN<88>")
	)
	(segment
		(start 301.763938 -326.815958)
		(end 300.957488 -326.009508)
		(width 0.1651)
		(layer "In7.Cu")
		(net "P5E_PEX2_STN5_TX_DN<88>")
	)
	(segment
		(start 298.165774 -321.201288)
		(end 298.165774 -319.916048)
		(width 0.1651)
		(layer "In7.Cu")
		(net "P5E_PEX2_STN5_TX_DN<88>")
	)
	(segment
		(start 328.911204 -354.732082)
		(end 328.620374 -354.441252)
		(width 0.1651)
		(layer "In7.Cu")
		(net "P5E_PEX2_STN5_TX_DN<88>")
	)
	(segment
		(start 300.957488 -326.009508)
		(end 300.957488 -325.883778)
		(width 0.1651)
		(layer "In7.Cu")
		(net "P5E_PEX2_STN5_TX_DN<88>")
	)
	(segment
		(start 328.620374 -354.441252)
		(end 328.620374 -353.930966)
		(width 0.1651)
		(layer "In7.Cu")
		(net "P5E_PEX2_STN5_TX_DN<88>")
	)
	(segment
		(start 300.957488 -325.883778)
		(end 300.607222 -325.533512)
		(width 0.1651)
		(layer "In7.Cu")
		(net "P5E_PEX2_STN5_TX_DN<88>")
	)
	(segment
		(start 299.591476 -324.643496)
		(end 298.165774 -321.201288)
		(width 0.1651)
		(layer "In7.Cu")
		(net "P5E_PEX2_STN5_TX_DN<88>")
	)
	(segment
		(start 298.499784 -311.784492)
		(end 298.499784 -312.049922)
		(width 0.1143)
		(layer "In7.Cu")
		(net "P5E_PEX2_STN5_TX_DN<88>")
	)
	(segment
		(start 300.607222 -325.533512)
		(end 300.481492 -325.533512)
		(width 0.1651)
		(layer "In7.Cu")
		(net "P5E_PEX2_STN5_TX_DN<88>")
	)
	(segment
		(start 298.120054 -311.784492)
		(end 298.234354 -311.670192)
		(width 0.1143)
		(layer "In7.Cu")
		(net "P5E_PEX2_STN5_TX_DN<88>")
	)
	(segment
		(start 330.174854 -342.0872)
		(end 329.6412 -340.7664)
		(width 0.1651)
		(layer "In7.Cu")
		(net "P5E_PEX2_STN5_TX_DN<88>")
	)
	(segment
		(start 330.174854 -352.376486)
		(end 330.174854 -342.0872)
		(width 0.1651)
		(layer "In7.Cu")
		(net "P5E_PEX2_STN5_TX_DN<88>")
	)
	(segment
		(start 298.234354 -311.670192)
		(end 298.385484 -311.670192)
		(width 0.1143)
		(layer "In7.Cu")
		(net "P5E_PEX2_STN5_TX_DN<88>")
	)
	(segment
		(start 323.778372 -335.882488)
		(end 301.763938 -326.815958)
		(width 0.1651)
		(layer "In7.Cu")
		(net "P5E_PEX2_STN5_TX_DN<88>")
	)
	(segment
		(start 386.376164 -136.14908)
		(end 386.980176 -136.14908)
		(width 0.13462)
		(layer "F.Cu")
		(net "P5E_PEX3_STN1_TX_DN<31>")
	)
	(segment
		(start 386.980176 -136.14908)
		(end 387.313932 -135.815324)
		(width 0.13462)
		(layer "F.Cu")
		(net "P5E_PEX3_STN1_TX_DN<31>")
	)
	(segment
		(start 386.067808 -135.840724)
		(end 386.376164 -136.14908)
		(width 0.13462)
		(layer "F.Cu")
		(net "P5E_PEX3_STN1_TX_DN<31>")
	)
	(segment
		(start 385.050792 -136.131554)
		(end 385.776978 -136.131554)
		(width 0.1651)
		(layer "In9.Cu")
		(net "P5E_PEX3_STN1_TX_DN<31>")
	)
	(segment
		(start 421.844724 -280.319988)
		(end 421.629586 -280.10485)
		(width 0.1143)
		(layer "In9.Cu")
		(net "P5E_PEX3_STN1_TX_DN<31>")
	)
	(segment
		(start 385.776978 -136.131554)
		(end 386.067808 -135.840724)
		(width 0.1651)
		(layer "In9.Cu")
		(net "P5E_PEX3_STN1_TX_DN<31>")
	)
	(segment
		(start 385.89585 -138.46683)
		(end 384.6576 -137.22858)
		(width 0.1651)
		(layer "In9.Cu")
		(net "P5E_PEX3_STN1_TX_DN<31>")
	)
	(segment
		(start 386.319522 -139.489688)
		(end 385.89585 -138.46683)
		(width 0.1651)
		(layer "In9.Cu")
		(net "P5E_PEX3_STN1_TX_DN<31>")
	)
	(segment
		(start 421.629586 -280.10485)
		(end 421.629586 -271.600168)
		(width 0.1143)
		(layer "In9.Cu")
		(net "P5E_PEX3_STN1_TX_DN<31>")
	)
	(segment
		(start 422.199816 -280.434288)
		(end 422.085516 -280.319988)
		(width 0.1143)
		(layer "In9.Cu")
		(net "P5E_PEX3_STN1_TX_DN<31>")
	)
	(segment
		(start 422.199816 -280.699718)
		(end 422.199816 -280.434288)
		(width 0.1143)
		(layer "In9.Cu")
		(net "P5E_PEX3_STN1_TX_DN<31>")
	)
	(segment
		(start 421.583866 -271.554448)
		(end 421.583866 -271.526)
		(width 0.1143)
		(layer "In9.Cu")
		(net "P5E_PEX3_STN1_TX_DN<31>")
	)
	(segment
		(start 395.424406 -185.333386)
		(end 386.319522 -139.489688)
		(width 0.1651)
		(layer "In9.Cu")
		(net "P5E_PEX3_STN1_TX_DN<31>")
	)
	(segment
		(start 422.085516 -280.319988)
		(end 421.844724 -280.319988)
		(width 0.1143)
		(layer "In9.Cu")
		(net "P5E_PEX3_STN1_TX_DN<31>")
	)
	(segment
		(start 421.583866 -271.526)
		(end 421.583866 -262.6106)
		(width 0.1651)
		(layer "In9.Cu")
		(net "P5E_PEX3_STN1_TX_DN<31>")
	)
	(segment
		(start 384.6576 -136.524746)
		(end 385.050792 -136.131554)
		(width 0.1651)
		(layer "In9.Cu")
		(net "P5E_PEX3_STN1_TX_DN<31>")
	)
	(segment
		(start 421.629586 -271.600168)
		(end 421.583866 -271.554448)
		(width 0.1143)
		(layer "In9.Cu")
		(net "P5E_PEX3_STN1_TX_DN<31>")
	)
	(segment
		(start 384.6576 -137.22858)
		(end 384.6576 -136.524746)
		(width 0.1651)
		(layer "In9.Cu")
		(net "P5E_PEX3_STN1_TX_DN<31>")
	)
	(segment
		(start 421.583866 -262.6106)
		(end 395.424406 -185.333386)
		(width 0.1651)
		(layer "In9.Cu")
		(net "P5E_PEX3_STN1_TX_DN<31>")
	)
	(segment
		(start 377.3805 -355.978206)
		(end 377.700032 -355.658674)
		(width 0.13462)
		(layer "F.Cu")
		(net "P5E_PEX3_STN6_TX_DP<108>")
	)
	(segment
		(start 377.700032 -355.026214)
		(end 377.4059 -354.732082)
		(width 0.13462)
		(layer "F.Cu")
		(net "P5E_PEX3_STN6_TX_DP<108>")
	)
	(segment
		(start 377.700032 -355.658674)
		(end 377.700032 -355.026214)
		(width 0.13462)
		(layer "F.Cu")
		(net "P5E_PEX3_STN6_TX_DP<108>")
	)
	(segment
		(start 394.64996 -313.265312)
		(end 394.64996 -312.999882)
		(width 0.1143)
		(layer "In13.Cu")
		(net "P5E_PEX3_STN6_TX_DP<108>")
	)
	(segment
		(start 394.03401 -321.39509)
		(end 394.03401 -320.046096)
		(width 0.1651)
		(layer "In13.Cu")
		(net "P5E_PEX3_STN6_TX_DP<108>")
	)
	(segment
		(start 394.07973 -313.59475)
		(end 394.294868 -313.379612)
		(width 0.1143)
		(layer "In13.Cu")
		(net "P5E_PEX3_STN6_TX_DP<108>")
	)
	(segment
		(start 377.69673 -354.441252)
		(end 377.69673 -353.814126)
		(width 0.1651)
		(layer "In13.Cu")
		(net "P5E_PEX3_STN6_TX_DP<108>")
	)
	(segment
		(start 394.53566 -313.379612)
		(end 394.64996 -313.265312)
		(width 0.1143)
		(layer "In13.Cu")
		(net "P5E_PEX3_STN6_TX_DP<108>")
	)
	(segment
		(start 385.423664 -334.37703)
		(end 392.439652 -324.276212)
		(width 0.1651)
		(layer "In13.Cu")
		(net "P5E_PEX3_STN6_TX_DP<108>")
	)
	(segment
		(start 379.25121 -341.734902)
		(end 385.423664 -334.37703)
		(width 0.1651)
		(layer "In13.Cu")
		(net "P5E_PEX3_STN6_TX_DP<108>")
	)
	(segment
		(start 377.4059 -354.732082)
		(end 377.69673 -354.441252)
		(width 0.1651)
		(layer "In13.Cu")
		(net "P5E_PEX3_STN6_TX_DP<108>")
	)
	(segment
		(start 394.07973 -319.971928)
		(end 394.07973 -313.59475)
		(width 0.1143)
		(layer "In13.Cu")
		(net "P5E_PEX3_STN6_TX_DP<108>")
	)
	(segment
		(start 394.294868 -313.379612)
		(end 394.53566 -313.379612)
		(width 0.1143)
		(layer "In13.Cu")
		(net "P5E_PEX3_STN6_TX_DP<108>")
	)
	(segment
		(start 394.03401 -320.017648)
		(end 394.07973 -319.971928)
		(width 0.1143)
		(layer "In13.Cu")
		(net "P5E_PEX3_STN6_TX_DP<108>")
	)
	(segment
		(start 392.439652 -324.276212)
		(end 393.923266 -321.661536)
		(width 0.1651)
		(layer "In13.Cu")
		(net "P5E_PEX3_STN6_TX_DP<108>")
	)
	(segment
		(start 377.69673 -353.814126)
		(end 379.25121 -352.259646)
		(width 0.1651)
		(layer "In13.Cu")
		(net "P5E_PEX3_STN6_TX_DP<108>")
	)
	(segment
		(start 379.25121 -352.259646)
		(end 379.25121 -341.734902)
		(width 0.1651)
		(layer "In13.Cu")
		(net "P5E_PEX3_STN6_TX_DP<108>")
	)
	(segment
		(start 393.923266 -321.661536)
		(end 394.03401 -321.39509)
		(width 0.1651)
		(layer "In13.Cu")
		(net "P5E_PEX3_STN6_TX_DP<108>")
	)
	(segment
		(start 394.03401 -320.046096)
		(end 394.03401 -320.017648)
		(width 0.1143)
		(layer "In13.Cu")
		(net "P5E_PEX3_STN6_TX_DP<108>")
	)
	(segment
		(start 33.819084 -338.706968)
		(end 33.91027 -338.817966)
		(width 0.1651)
		(layer "In5.Cu")
		(net "P5E_PEX0_STN7_RX_DN<121>")
	)
	(segment
		(start 30.236922 -383.79908)
		(end 30.109922 -383.67208)
		(width 0.1651)
		(layer "In5.Cu")
		(net "P5E_PEX0_STN7_RX_DN<121>")
	)
	(segment
		(start 37.115242 -310.149748)
		(end 37.229542 -310.264048)
		(width 0.1143)
		(layer "In5.Cu")
		(net "P5E_PEX0_STN7_RX_DN<121>")
	)
	(segment
		(start 33.750758 -339.401658)
		(end 33.702244 -339.894926)
		(width 0.1651)
		(layer "In5.Cu")
		(net "P5E_PEX0_STN7_RX_DN<121>")
	)
	(segment
		(start 36.849812 -310.149748)
		(end 37.115242 -310.149748)
		(width 0.1143)
		(layer "In5.Cu")
		(net "P5E_PEX0_STN7_RX_DN<121>")
	)
	(segment
		(start 35.48126 -319.64249)
		(end 35.48126 -322.868544)
		(width 0.1651)
		(layer "In5.Cu")
		(net "P5E_PEX0_STN7_RX_DN<121>")
	)
	(segment
		(start 34.567876 -332.144878)
		(end 34.45637 -332.23581)
		(width 0.1651)
		(layer "In5.Cu")
		(net "P5E_PEX0_STN7_RX_DN<121>")
	)
	(segment
		(start 34.567622 -332.144878)
		(end 34.567876 -332.144878)
		(width 0.1651)
		(layer "In5.Cu")
		(net "P5E_PEX0_STN7_RX_DN<121>")
	)
	(segment
		(start 35.732212 -310.987694)
		(end 35.668204 -310.98744)
		(width 0.1143)
		(layer "In5.Cu")
		(net "P5E_PEX0_STN7_RX_DN<121>")
	)
	(segment
		(start 30.618938 -383.79908)
		(end 30.236922 -383.79908)
		(width 0.1651)
		(layer "In5.Cu")
		(net "P5E_PEX0_STN7_RX_DN<121>")
	)
	(segment
		(start 35.045142 -318.589406)
		(end 35.48126 -319.64249)
		(width 0.1651)
		(layer "In5.Cu")
		(net "P5E_PEX0_STN7_RX_DN<121>")
	)
	(segment
		(start 35.668204 -310.98744)
		(end 35.648138 -311.007506)
		(width 0.1143)
		(layer "In5.Cu")
		(net "P5E_PEX0_STN7_RX_DN<121>")
	)
	(segment
		(start 33.702244 -339.894926)
		(end 33.79343 -340.005924)
		(width 0.1651)
		(layer "In5.Cu")
		(net "P5E_PEX0_STN7_RX_DN<121>")
	)
	(segment
		(start 33.79343 -340.005924)
		(end 33.613598 -341.83193)
		(width 0.1651)
		(layer "In5.Cu")
		(net "P5E_PEX0_STN7_RX_DN<121>")
	)
	(segment
		(start 33.867598 -338.2137)
		(end 33.819084 -338.706968)
		(width 0.1651)
		(layer "In5.Cu")
		(net "P5E_PEX0_STN7_RX_DN<121>")
	)
	(segment
		(start 37.229542 -310.264048)
		(end 37.229542 -310.415178)
		(width 0.1143)
		(layer "In5.Cu")
		(net "P5E_PEX0_STN7_RX_DN<121>")
	)
	(segment
		(start 35.648138 -311.007506)
		(end 35.045142 -311.610502)
		(width 0.1651)
		(layer "In5.Cu")
		(net "P5E_PEX0_STN7_RX_DN<121>")
	)
	(segment
		(start 33.936178 -337.518756)
		(end 34.027364 -337.629754)
		(width 0.1651)
		(layer "In5.Cu")
		(net "P5E_PEX0_STN7_RX_DN<121>")
	)
	(segment
		(start 33.501838 -358.689148)
		(end 30.977078 -368.768884)
		(width 0.1651)
		(layer "In5.Cu")
		(net "P5E_PEX0_STN7_RX_DN<121>")
	)
	(segment
		(start 35.045142 -311.610502)
		(end 35.045142 -318.589406)
		(width 0.1651)
		(layer "In5.Cu")
		(net "P5E_PEX0_STN7_RX_DN<121>")
	)
	(segment
		(start 35.48126 -322.868544)
		(end 34.567622 -332.144878)
		(width 0.1651)
		(layer "In5.Cu")
		(net "P5E_PEX0_STN7_RX_DN<121>")
	)
	(segment
		(start 34.45637 -332.23581)
		(end 34.407856 -332.729078)
		(width 0.1651)
		(layer "In5.Cu")
		(net "P5E_PEX0_STN7_RX_DN<121>")
	)
	(segment
		(start 36.190428 -310.529478)
		(end 35.732212 -310.987694)
		(width 0.1143)
		(layer "In5.Cu")
		(net "P5E_PEX0_STN7_RX_DN<121>")
	)
	(segment
		(start 30.977078 -383.44094)
		(end 30.618938 -383.79908)
		(width 0.1651)
		(layer "In5.Cu")
		(net "P5E_PEX0_STN7_RX_DN<121>")
	)
	(segment
		(start 33.861756 -339.310726)
		(end 33.86201 -339.310726)
		(width 0.1651)
		(layer "In5.Cu")
		(net "P5E_PEX0_STN7_RX_DN<121>")
	)
	(segment
		(start 33.86201 -339.310726)
		(end 33.750758 -339.401658)
		(width 0.1651)
		(layer "In5.Cu")
		(net "P5E_PEX0_STN7_RX_DN<121>")
	)
	(segment
		(start 37.114988 -310.529478)
		(end 36.190428 -310.529478)
		(width 0.1143)
		(layer "In5.Cu")
		(net "P5E_PEX0_STN7_RX_DN<121>")
	)
	(segment
		(start 34.499042 -332.840076)
		(end 34.095944 -336.934302)
		(width 0.1651)
		(layer "In5.Cu")
		(net "P5E_PEX0_STN7_RX_DN<121>")
	)
	(segment
		(start 37.229542 -310.415178)
		(end 37.114988 -310.529478)
		(width 0.1143)
		(layer "In5.Cu")
		(net "P5E_PEX0_STN7_RX_DN<121>")
	)
	(segment
		(start 34.407856 -332.729078)
		(end 34.499042 -332.840076)
		(width 0.1651)
		(layer "In5.Cu")
		(net "P5E_PEX0_STN7_RX_DN<121>")
	)
	(segment
		(start 34.027364 -337.629754)
		(end 33.97885 -338.122514)
		(width 0.1651)
		(layer "In5.Cu")
		(net "P5E_PEX0_STN7_RX_DN<121>")
	)
	(segment
		(start 33.613598 -357.784654)
		(end 33.501838 -358.689148)
		(width 0.1651)
		(layer "In5.Cu")
		(net "P5E_PEX0_STN7_RX_DN<121>")
	)
	(segment
		(start 30.109922 -383.67208)
		(end 30.109922 -383.290064)
		(width 0.1651)
		(layer "In5.Cu")
		(net "P5E_PEX0_STN7_RX_DN<121>")
	)
	(segment
		(start 33.91027 -338.817966)
		(end 33.861756 -339.310726)
		(width 0.1651)
		(layer "In5.Cu")
		(net "P5E_PEX0_STN7_RX_DN<121>")
	)
	(segment
		(start 33.97885 -338.122514)
		(end 33.867598 -338.2137)
		(width 0.1651)
		(layer "In5.Cu")
		(net "P5E_PEX0_STN7_RX_DN<121>")
	)
	(segment
		(start 33.613598 -341.83193)
		(end 33.613598 -357.784654)
		(width 0.1651)
		(layer "In5.Cu")
		(net "P5E_PEX0_STN7_RX_DN<121>")
	)
	(segment
		(start 34.095944 -336.934302)
		(end 33.984692 -337.025488)
		(width 0.1651)
		(layer "In5.Cu")
		(net "P5E_PEX0_STN7_RX_DN<121>")
	)
	(segment
		(start 30.977078 -368.768884)
		(end 30.977078 -383.44094)
		(width 0.1651)
		(layer "In5.Cu")
		(net "P5E_PEX0_STN7_RX_DN<121>")
	)
	(segment
		(start 33.984692 -337.025488)
		(end 33.936178 -337.518756)
		(width 0.1651)
		(layer "In5.Cu")
		(net "P5E_PEX0_STN7_RX_DN<121>")
	)
	(segment
		(start 77.211682 -355.658166)
		(end 77.211682 -355.026722)
		(width 0.13462)
		(layer "F.Cu")
		(net "P5E_PEX0_STN5_TX_DP<88>")
	)
	(segment
		(start 76.891642 -355.978206)
		(end 77.211682 -355.658166)
		(width 0.13462)
		(layer "F.Cu")
		(net "P5E_PEX0_STN5_TX_DP<88>")
	)
	(segment
		(start 77.211682 -355.026722)
		(end 76.917042 -354.732082)
		(width 0.13462)
		(layer "F.Cu")
		(net "P5E_PEX0_STN5_TX_DP<88>")
	)
	(segment
		(start 66.299842 -311.365392)
		(end 66.299842 -311.099962)
		(width 0.1143)
		(layer "In7.Cu")
		(net "P5E_PEX0_STN5_TX_DP<88>")
	)
	(segment
		(start 65.955418 -311.479692)
		(end 66.185542 -311.479692)
		(width 0.1143)
		(layer "In7.Cu")
		(net "P5E_PEX0_STN5_TX_DP<88>")
	)
	(segment
		(start 77.207872 -353.825302)
		(end 78.762352 -352.270822)
		(width 0.1651)
		(layer "In7.Cu")
		(net "P5E_PEX0_STN5_TX_DP<88>")
	)
	(segment
		(start 67.666362 -325.780908)
		(end 66.178684 -323.299328)
		(width 0.1651)
		(layer "In7.Cu")
		(net "P5E_PEX0_STN5_TX_DP<88>")
	)
	(segment
		(start 66.178684 -323.299328)
		(end 65.683892 -322.10375)
		(width 0.1651)
		(layer "In7.Cu")
		(net "P5E_PEX0_STN5_TX_DP<88>")
	)
	(segment
		(start 65.683892 -322.10375)
		(end 65.683892 -319.916048)
		(width 0.1651)
		(layer "In7.Cu")
		(net "P5E_PEX0_STN5_TX_DP<88>")
	)
	(segment
		(start 65.683892 -319.916048)
		(end 65.683892 -319.8876)
		(width 0.1143)
		(layer "In7.Cu")
		(net "P5E_PEX0_STN5_TX_DP<88>")
	)
	(segment
		(start 65.729612 -311.705498)
		(end 65.955418 -311.479692)
		(width 0.1143)
		(layer "In7.Cu")
		(net "P5E_PEX0_STN5_TX_DP<88>")
	)
	(segment
		(start 66.185542 -311.479692)
		(end 66.299842 -311.365392)
		(width 0.1143)
		(layer "In7.Cu")
		(net "P5E_PEX0_STN5_TX_DP<88>")
	)
	(segment
		(start 77.207872 -354.441252)
		(end 77.207872 -353.825302)
		(width 0.1651)
		(layer "In7.Cu")
		(net "P5E_PEX0_STN5_TX_DP<88>")
	)
	(segment
		(start 78.762352 -341.059262)
		(end 77.291184 -337.50885)
		(width 0.1651)
		(layer "In7.Cu")
		(net "P5E_PEX0_STN5_TX_DP<88>")
	)
	(segment
		(start 77.291184 -337.50885)
		(end 67.666362 -325.780908)
		(width 0.1651)
		(layer "In7.Cu")
		(net "P5E_PEX0_STN5_TX_DP<88>")
	)
	(segment
		(start 65.683892 -319.8876)
		(end 65.729612 -319.84188)
		(width 0.1143)
		(layer "In7.Cu")
		(net "P5E_PEX0_STN5_TX_DP<88>")
	)
	(segment
		(start 65.729612 -319.84188)
		(end 65.729612 -311.705498)
		(width 0.1143)
		(layer "In7.Cu")
		(net "P5E_PEX0_STN5_TX_DP<88>")
	)
	(segment
		(start 78.762352 -352.270822)
		(end 78.762352 -341.059262)
		(width 0.1651)
		(layer "In7.Cu")
		(net "P5E_PEX0_STN5_TX_DP<88>")
	)
	(segment
		(start 76.917042 -354.732082)
		(end 77.207872 -354.441252)
		(width 0.1651)
		(layer "In7.Cu")
		(net "P5E_PEX0_STN5_TX_DP<88>")
	)
	(segment
		(start 133.919468 -355.658166)
		(end 133.919468 -355.026722)
		(width 0.13462)
		(layer "F.Cu")
		(net "P5E_PEX1_STN5_TX_DP<83>")
	)
	(segment
		(start 133.599428 -355.978206)
		(end 133.919468 -355.658166)
		(width 0.13462)
		(layer "F.Cu")
		(net "P5E_PEX1_STN5_TX_DP<83>")
	)
	(segment
		(start 133.919468 -355.026722)
		(end 133.624828 -354.732082)
		(width 0.13462)
		(layer "F.Cu")
		(net "P5E_PEX1_STN5_TX_DP<83>")
	)
	(segment
		(start 135.470138 -352.151442)
		(end 135.470138 -341.313262)
		(width 0.1651)
		(layer "In7.Cu")
		(net "P5E_PEX1_STN5_TX_DP<83>")
	)
	(segment
		(start 177.305462 -313.379612)
		(end 177.535586 -313.379612)
		(width 0.1143)
		(layer "In7.Cu")
		(net "P5E_PEX1_STN5_TX_DP<83>")
	)
	(segment
		(start 177.079656 -313.605418)
		(end 177.305462 -313.379612)
		(width 0.1143)
		(layer "In7.Cu")
		(net "P5E_PEX1_STN5_TX_DP<83>")
	)
	(segment
		(start 177.033936 -320.002408)
		(end 177.033936 -319.97396)
		(width 0.1143)
		(layer "In7.Cu")
		(net "P5E_PEX1_STN5_TX_DP<83>")
	)
	(segment
		(start 177.033936 -319.97396)
		(end 177.079656 -319.92824)
		(width 0.1143)
		(layer "In7.Cu")
		(net "P5E_PEX1_STN5_TX_DP<83>")
	)
	(segment
		(start 136.03986 -340.74354)
		(end 136.83742 -340.265258)
		(width 0.1651)
		(layer "In7.Cu")
		(net "P5E_PEX1_STN5_TX_DP<83>")
	)
	(segment
		(start 177.535586 -313.379612)
		(end 177.649886 -313.265312)
		(width 0.1143)
		(layer "In7.Cu")
		(net "P5E_PEX1_STN5_TX_DP<83>")
	)
	(segment
		(start 136.83742 -340.265258)
		(end 145.111978 -337.75523)
		(width 0.1651)
		(layer "In7.Cu")
		(net "P5E_PEX1_STN5_TX_DP<83>")
	)
	(segment
		(start 177.033936 -323.43598)
		(end 177.033936 -320.002408)
		(width 0.1651)
		(layer "In7.Cu")
		(net "P5E_PEX1_STN5_TX_DP<83>")
	)
	(segment
		(start 176.169828 -325.522082)
		(end 177.033936 -323.43598)
		(width 0.1651)
		(layer "In7.Cu")
		(net "P5E_PEX1_STN5_TX_DP<83>")
	)
	(segment
		(start 133.624828 -354.732082)
		(end 133.915658 -354.441252)
		(width 0.1651)
		(layer "In7.Cu")
		(net "P5E_PEX1_STN5_TX_DP<83>")
	)
	(segment
		(start 133.915658 -354.441252)
		(end 133.915658 -353.705922)
		(width 0.1651)
		(layer "In7.Cu")
		(net "P5E_PEX1_STN5_TX_DP<83>")
	)
	(segment
		(start 135.470138 -341.313262)
		(end 136.03986 -340.74354)
		(width 0.1651)
		(layer "In7.Cu")
		(net "P5E_PEX1_STN5_TX_DP<83>")
	)
	(segment
		(start 169.935144 -330.2254)
		(end 173.757336 -327.934574)
		(width 0.1651)
		(layer "In7.Cu")
		(net "P5E_PEX1_STN5_TX_DP<83>")
	)
	(segment
		(start 177.649886 -313.265312)
		(end 177.649886 -312.999882)
		(width 0.1143)
		(layer "In7.Cu")
		(net "P5E_PEX1_STN5_TX_DP<83>")
	)
	(segment
		(start 145.111978 -337.75523)
		(end 169.935144 -330.2254)
		(width 0.1651)
		(layer "In7.Cu")
		(net "P5E_PEX1_STN5_TX_DP<83>")
	)
	(segment
		(start 173.757336 -327.934574)
		(end 176.169828 -325.522082)
		(width 0.1651)
		(layer "In7.Cu")
		(net "P5E_PEX1_STN5_TX_DP<83>")
	)
	(segment
		(start 133.915658 -353.705922)
		(end 135.470138 -352.151442)
		(width 0.1651)
		(layer "In7.Cu")
		(net "P5E_PEX1_STN5_TX_DP<83>")
	)
	(segment
		(start 177.079656 -319.92824)
		(end 177.079656 -313.605418)
		(width 0.1143)
		(layer "In7.Cu")
		(net "P5E_PEX1_STN5_TX_DP<83>")
	)
	(segment
		(start 334.240124 -355.978206)
		(end 334.560164 -355.658166)
		(width 0.13462)
		(layer "F.Cu")
		(net "P5E_PEX2_STN5_TX_DP<91>")
	)
	(segment
		(start 334.560164 -355.026722)
		(end 334.265524 -354.732082)
		(width 0.13462)
		(layer "F.Cu")
		(net "P5E_PEX2_STN5_TX_DP<91>")
	)
	(segment
		(start 334.560164 -355.658166)
		(end 334.560164 -355.026722)
		(width 0.13462)
		(layer "F.Cu")
		(net "P5E_PEX2_STN5_TX_DP<91>")
	)
	(segment
		(start 336.110834 -341.986616)
		(end 335.776316 -341.106252)
		(width 0.1651)
		(layer "In7.Cu")
		(net "P5E_PEX2_STN5_TX_DP<91>")
	)
	(segment
		(start 303.613312 -324.662546)
		(end 301.643542 -322.692522)
		(width 0.1651)
		(layer "In7.Cu")
		(net "P5E_PEX2_STN5_TX_DP<91>")
	)
	(segment
		(start 334.265524 -354.732082)
		(end 334.556354 -354.441252)
		(width 0.1651)
		(layer "In7.Cu")
		(net "P5E_PEX2_STN5_TX_DP<91>")
	)
	(segment
		(start 300.733968 -320.496946)
		(end 300.733968 -319.941448)
		(width 0.1651)
		(layer "In7.Cu")
		(net "P5E_PEX2_STN5_TX_DP<91>")
	)
	(segment
		(start 325.219314 -333.466948)
		(end 303.613312 -324.662546)
		(width 0.1651)
		(layer "In7.Cu")
		(net "P5E_PEX2_STN5_TX_DP<91>")
	)
	(segment
		(start 334.556354 -354.441252)
		(end 334.556354 -353.814126)
		(width 0.1651)
		(layer "In7.Cu")
		(net "P5E_PEX2_STN5_TX_DP<91>")
	)
	(segment
		(start 334.556354 -353.814126)
		(end 336.110834 -352.259646)
		(width 0.1651)
		(layer "In7.Cu")
		(net "P5E_PEX2_STN5_TX_DP<91>")
	)
	(segment
		(start 335.776316 -341.106252)
		(end 333.453994 -338.95665)
		(width 0.1651)
		(layer "In7.Cu")
		(net "P5E_PEX2_STN5_TX_DP<91>")
	)
	(segment
		(start 300.733968 -319.941448)
		(end 300.733968 -319.913)
		(width 0.1143)
		(layer "In7.Cu")
		(net "P5E_PEX2_STN5_TX_DP<91>")
	)
	(segment
		(start 301.005494 -313.379612)
		(end 301.235618 -313.379612)
		(width 0.1143)
		(layer "In7.Cu")
		(net "P5E_PEX2_STN5_TX_DP<91>")
	)
	(segment
		(start 301.349918 -313.265312)
		(end 301.349918 -312.999882)
		(width 0.1143)
		(layer "In7.Cu")
		(net "P5E_PEX2_STN5_TX_DP<91>")
	)
	(segment
		(start 301.235618 -313.379612)
		(end 301.349918 -313.265312)
		(width 0.1143)
		(layer "In7.Cu")
		(net "P5E_PEX2_STN5_TX_DP<91>")
	)
	(segment
		(start 300.779688 -319.86728)
		(end 300.779688 -313.605418)
		(width 0.1143)
		(layer "In7.Cu")
		(net "P5E_PEX2_STN5_TX_DP<91>")
	)
	(segment
		(start 333.453994 -338.95665)
		(end 325.219314 -333.466948)
		(width 0.1651)
		(layer "In7.Cu")
		(net "P5E_PEX2_STN5_TX_DP<91>")
	)
	(segment
		(start 301.643542 -322.692522)
		(end 300.733968 -320.496946)
		(width 0.1651)
		(layer "In7.Cu")
		(net "P5E_PEX2_STN5_TX_DP<91>")
	)
	(segment
		(start 300.733968 -319.913)
		(end 300.779688 -319.86728)
		(width 0.1143)
		(layer "In7.Cu")
		(net "P5E_PEX2_STN5_TX_DP<91>")
	)
	(segment
		(start 300.779688 -313.605418)
		(end 301.005494 -313.379612)
		(width 0.1143)
		(layer "In7.Cu")
		(net "P5E_PEX2_STN5_TX_DP<91>")
	)
	(segment
		(start 336.110834 -352.259646)
		(end 336.110834 -341.986616)
		(width 0.1651)
		(layer "In7.Cu")
		(net "P5E_PEX2_STN5_TX_DP<91>")
	)
	(segment
		(start 429.832262 -133.505702)
		(end 429.530764 -133.8072)
		(width 0.13462)
		(layer "F.Cu")
		(net "P5E_PEX3_STN0_TX_DN<6>")
	)
	(segment
		(start 429.530764 -133.8072)
		(end 428.913036 -133.8072)
		(width 0.13462)
		(layer "F.Cu")
		(net "P5E_PEX3_STN0_TX_DN<6>")
	)
	(segment
		(start 428.913036 -133.8072)
		(end 428.586138 -133.480302)
		(width 0.13462)
		(layer "F.Cu")
		(net "P5E_PEX3_STN0_TX_DN<6>")
	)
	(segment
		(start 442.368178 -273.714718)
		(end 434.448458 -281.634438)
		(width 0.1651)
		(layer "In9.Cu")
		(net "P5E_PEX3_STN0_TX_DN<6>")
	)
	(segment
		(start 432.143408 -282.220162)
		(end 425.723812 -282.220162)
		(width 0.1143)
		(layer "In9.Cu")
		(net "P5E_PEX3_STN0_TX_DN<6>")
	)
	(segment
		(start 434.448458 -281.634438)
		(end 432.923696 -282.265882)
		(width 0.1651)
		(layer "In9.Cu")
		(net "P5E_PEX3_STN0_TX_DN<6>")
	)
	(segment
		(start 433.914804 -134.558024)
		(end 434.696108 -135.339328)
		(width 0.1651)
		(layer "In9.Cu")
		(net "P5E_PEX3_STN0_TX_DN<6>")
	)
	(segment
		(start 432.913536 -178.200304)
		(end 429.112934 -221.640654)
		(width 0.1651)
		(layer "In9.Cu")
		(net "P5E_PEX3_STN0_TX_DN<6>")
	)
	(segment
		(start 425.62018 -282.323794)
		(end 425.62018 -282.485592)
		(width 0.1143)
		(layer "In9.Cu")
		(net "P5E_PEX3_STN0_TX_DN<6>")
	)
	(segment
		(start 442.295026 -267.264388)
		(end 442.891418 -268.704568)
		(width 0.1651)
		(layer "In9.Cu")
		(net "P5E_PEX3_STN0_TX_DN<6>")
	)
	(segment
		(start 425.73448 -282.599892)
		(end 425.99991 -282.599892)
		(width 0.1143)
		(layer "In9.Cu")
		(net "P5E_PEX3_STN0_TX_DN<6>")
	)
	(segment
		(start 430.123092 -133.796532)
		(end 432.076352 -133.796532)
		(width 0.1651)
		(layer "In9.Cu")
		(net "P5E_PEX3_STN0_TX_DN<6>")
	)
	(segment
		(start 443.143894 -271.584166)
		(end 442.368178 -273.714718)
		(width 0.1651)
		(layer "In9.Cu")
		(net "P5E_PEX3_STN0_TX_DN<6>")
	)
	(segment
		(start 442.665104 -158.997904)
		(end 434.069236 -173.890686)
		(width 0.1651)
		(layer "In9.Cu")
		(net "P5E_PEX3_STN0_TX_DN<6>")
	)
	(segment
		(start 432.076352 -133.796532)
		(end 433.914804 -134.558024)
		(width 0.1651)
		(layer "In9.Cu")
		(net "P5E_PEX3_STN0_TX_DN<6>")
	)
	(segment
		(start 439.14695 -145.434812)
		(end 442.665104 -153.928572)
		(width 0.1651)
		(layer "In9.Cu")
		(net "P5E_PEX3_STN0_TX_DN<6>")
	)
	(segment
		(start 425.723812 -282.220162)
		(end 425.62018 -282.323794)
		(width 0.1143)
		(layer "In9.Cu")
		(net "P5E_PEX3_STN0_TX_DN<6>")
	)
	(segment
		(start 429.112934 -221.640654)
		(end 431.715164 -251.430536)
		(width 0.1651)
		(layer "In9.Cu")
		(net "P5E_PEX3_STN0_TX_DN<6>")
	)
	(segment
		(start 432.217576 -282.265882)
		(end 432.189128 -282.265882)
		(width 0.1143)
		(layer "In9.Cu")
		(net "P5E_PEX3_STN0_TX_DN<6>")
	)
	(segment
		(start 432.189128 -282.265882)
		(end 432.143408 -282.220162)
		(width 0.1143)
		(layer "In9.Cu")
		(net "P5E_PEX3_STN0_TX_DN<6>")
	)
	(segment
		(start 442.665104 -153.928572)
		(end 442.665104 -158.997904)
		(width 0.1651)
		(layer "In9.Cu")
		(net "P5E_PEX3_STN0_TX_DN<6>")
	)
	(segment
		(start 438.687718 -144.97558)
		(end 439.14695 -145.434812)
		(width 0.1651)
		(layer "In9.Cu")
		(net "P5E_PEX3_STN0_TX_DN<6>")
	)
	(segment
		(start 434.069236 -173.890686)
		(end 432.913536 -178.200304)
		(width 0.1651)
		(layer "In9.Cu")
		(net "P5E_PEX3_STN0_TX_DN<6>")
	)
	(segment
		(start 429.832262 -133.505702)
		(end 430.123092 -133.796532)
		(width 0.1651)
		(layer "In9.Cu")
		(net "P5E_PEX3_STN0_TX_DN<6>")
	)
	(segment
		(start 425.62018 -282.485592)
		(end 425.73448 -282.599892)
		(width 0.1143)
		(layer "In9.Cu")
		(net "P5E_PEX3_STN0_TX_DN<6>")
	)
	(segment
		(start 432.923696 -282.265882)
		(end 432.217576 -282.265882)
		(width 0.1651)
		(layer "In9.Cu")
		(net "P5E_PEX3_STN0_TX_DN<6>")
	)
	(segment
		(start 431.715164 -251.430536)
		(end 442.295026 -267.264388)
		(width 0.1651)
		(layer "In9.Cu")
		(net "P5E_PEX3_STN0_TX_DN<6>")
	)
	(segment
		(start 442.891418 -268.704568)
		(end 443.143894 -271.584166)
		(width 0.1651)
		(layer "In9.Cu")
		(net "P5E_PEX3_STN0_TX_DN<6>")
	)
	(segment
		(start 434.696108 -135.339328)
		(end 438.687718 -144.97558)
		(width 0.1651)
		(layer "In9.Cu")
		(net "P5E_PEX3_STN0_TX_DN<6>")
	)
	(segment
		(start 440.953144 -355.657658)
		(end 440.953144 -355.02723)
		(width 0.13462)
		(layer "F.Cu")
		(net "P5E_PEX3_STN7_TX_DN<127>")
	)
	(segment
		(start 441.273692 -355.978206)
		(end 440.953144 -355.657658)
		(width 0.13462)
		(layer "F.Cu")
		(net "P5E_PEX3_STN7_TX_DN<127>")
	)
	(segment
		(start 440.953144 -355.02723)
		(end 441.248292 -354.732082)
		(width 0.13462)
		(layer "F.Cu")
		(net "P5E_PEX3_STN7_TX_DN<127>")
	)
	(segment
		(start 441.248292 -354.732082)
		(end 440.957462 -354.441252)
		(width 0.1651)
		(layer "In11.Cu")
		(net "P5E_PEX3_STN7_TX_DN<127>")
	)
	(segment
		(start 393.576556 -321.064128)
		(end 390.65073 -320.293746)
		(width 0.1651)
		(layer "In11.Cu")
		(net "P5E_PEX3_STN7_TX_DN<127>")
	)
	(segment
		(start 442.511942 -352.376486)
		(end 442.511942 -341.286846)
		(width 0.1651)
		(layer "In11.Cu")
		(net "P5E_PEX3_STN7_TX_DN<127>")
	)
	(segment
		(start 441.16371 -339.404452)
		(end 441.162694 -339.40369)
		(width 0.1651)
		(layer "In11.Cu")
		(net "P5E_PEX3_STN7_TX_DN<127>")
	)
	(segment
		(start 440.957462 -354.441252)
		(end 440.957462 -353.930966)
		(width 0.1651)
		(layer "In11.Cu")
		(net "P5E_PEX3_STN7_TX_DN<127>")
	)
	(segment
		(start 441.202064 -339.43163)
		(end 441.181744 -339.417406)
		(width 0.1651)
		(layer "In11.Cu")
		(net "P5E_PEX3_STN7_TX_DN<127>")
	)
	(segment
		(start 395.294612 -321.424554)
		(end 394.815568 -321.29857)
		(width 0.1651)
		(layer "In11.Cu")
		(net "P5E_PEX3_STN7_TX_DN<127>")
	)
	(segment
		(start 394.164566 -321.126866)
		(end 393.685522 -321.000882)
		(width 0.1651)
		(layer "In11.Cu")
		(net "P5E_PEX3_STN7_TX_DN<127>")
	)
	(segment
		(start 393.57681 -321.064128)
		(end 393.576556 -321.064128)
		(width 0.1651)
		(layer "In11.Cu")
		(net "P5E_PEX3_STN7_TX_DN<127>")
	)
	(segment
		(start 390.469882 -319.79108)
		(end 390.469882 -313.673998)
		(width 0.1143)
		(layer "In11.Cu")
		(net "P5E_PEX3_STN7_TX_DN<127>")
	)
	(segment
		(start 390.469882 -313.673998)
		(end 390.573768 -313.570112)
		(width 0.1143)
		(layer "In11.Cu")
		(net "P5E_PEX3_STN7_TX_DN<127>")
	)
	(segment
		(start 441.856368 -340.350602)
		(end 441.222638 -339.446108)
		(width 0.1651)
		(layer "In11.Cu")
		(net "P5E_PEX3_STN7_TX_DN<127>")
	)
	(segment
		(start 390.573768 -313.570112)
		(end 390.735566 -313.570112)
		(width 0.1143)
		(layer "In11.Cu")
		(net "P5E_PEX3_STN7_TX_DN<127>")
	)
	(segment
		(start 441.856622 -340.350856)
		(end 441.856368 -340.350856)
		(width 0.1651)
		(layer "In11.Cu")
		(net "P5E_PEX3_STN7_TX_DN<127>")
	)
	(segment
		(start 395.358112 -321.53352)
		(end 395.294612 -321.424554)
		(width 0.1651)
		(layer "In11.Cu")
		(net "P5E_PEX3_STN7_TX_DN<127>")
	)
	(segment
		(start 394.815568 -321.29857)
		(end 394.706856 -321.361816)
		(width 0.1651)
		(layer "In11.Cu")
		(net "P5E_PEX3_STN7_TX_DN<127>")
	)
	(segment
		(start 390.515602 -320.118486)
		(end 390.515602 -319.865248)
		(width 0.1651)
		(layer "In11.Cu")
		(net "P5E_PEX3_STN7_TX_DN<127>")
	)
	(segment
		(start 427.85665 -330.092304)
		(end 395.358112 -321.53352)
		(width 0.1651)
		(layer "In11.Cu")
		(net "P5E_PEX3_STN7_TX_DN<127>")
	)
	(segment
		(start 441.161932 -339.403182)
		(end 441.161678 -339.403436)
		(width 0.1651)
		(layer "In11.Cu")
		(net "P5E_PEX3_STN7_TX_DN<127>")
	)
	(segment
		(start 440.957462 -353.930966)
		(end 442.511942 -352.376486)
		(width 0.1651)
		(layer "In11.Cu")
		(net "P5E_PEX3_STN7_TX_DN<127>")
	)
	(segment
		(start 441.856368 -340.350856)
		(end 441.856368 -340.350602)
		(width 0.1651)
		(layer "In11.Cu")
		(net "P5E_PEX3_STN7_TX_DN<127>")
	)
	(segment
		(start 393.685522 -321.000882)
		(end 393.57681 -321.064128)
		(width 0.1651)
		(layer "In11.Cu")
		(net "P5E_PEX3_STN7_TX_DN<127>")
	)
	(segment
		(start 441.222638 -339.446108)
		(end 441.202064 -339.43163)
		(width 0.1651)
		(layer "In11.Cu")
		(net "P5E_PEX3_STN7_TX_DN<127>")
	)
	(segment
		(start 390.849866 -313.684412)
		(end 390.849866 -313.949842)
		(width 0.1143)
		(layer "In11.Cu")
		(net "P5E_PEX3_STN7_TX_DN<127>")
	)
	(segment
		(start 390.65073 -320.293746)
		(end 390.515602 -320.118486)
		(width 0.1651)
		(layer "In11.Cu")
		(net "P5E_PEX3_STN7_TX_DN<127>")
	)
	(segment
		(start 394.706856 -321.361816)
		(end 394.228066 -321.235832)
		(width 0.1651)
		(layer "In11.Cu")
		(net "P5E_PEX3_STN7_TX_DN<127>")
	)
	(segment
		(start 394.228066 -321.235832)
		(end 394.164566 -321.126866)
		(width 0.1651)
		(layer "In11.Cu")
		(net "P5E_PEX3_STN7_TX_DN<127>")
	)
	(segment
		(start 441.181744 -339.417152)
		(end 441.16371 -339.404452)
		(width 0.1651)
		(layer "In11.Cu")
		(net "P5E_PEX3_STN7_TX_DN<127>")
	)
	(segment
		(start 441.161424 -339.403436)
		(end 427.85665 -330.092304)
		(width 0.1651)
		(layer "In11.Cu")
		(net "P5E_PEX3_STN7_TX_DN<127>")
	)
	(segment
		(start 441.181744 -339.417406)
		(end 441.181744 -339.417152)
		(width 0.1651)
		(layer "In11.Cu")
		(net "P5E_PEX3_STN7_TX_DN<127>")
	)
	(segment
		(start 441.161678 -339.403436)
		(end 441.161424 -339.403436)
		(width 0.1651)
		(layer "In11.Cu")
		(net "P5E_PEX3_STN7_TX_DN<127>")
	)
	(segment
		(start 390.515602 -319.865248)
		(end 390.515602 -319.8368)
		(width 0.1143)
		(layer "In11.Cu")
		(net "P5E_PEX3_STN7_TX_DN<127>")
	)
	(segment
		(start 390.515602 -319.8368)
		(end 390.469882 -319.79108)
		(width 0.1143)
		(layer "In11.Cu")
		(net "P5E_PEX3_STN7_TX_DN<127>")
	)
	(segment
		(start 442.511942 -341.286846)
		(end 441.856622 -340.350856)
		(width 0.1651)
		(layer "In11.Cu")
		(net "P5E_PEX3_STN7_TX_DN<127>")
	)
	(segment
		(start 390.735566 -313.570112)
		(end 390.849866 -313.684412)
		(width 0.1143)
		(layer "In11.Cu")
		(net "P5E_PEX3_STN7_TX_DN<127>")
	)
	(segment
		(start 441.162694 -339.40369)
		(end 441.161932 -339.403182)
		(width 0.1651)
		(layer "In11.Cu")
		(net "P5E_PEX3_STN7_TX_DN<127>")
	)
	(segment
		(start 61.941202 -348.88043)
		(end 62.235842 -348.58579)
		(width 0.13462)
		(layer "F.Cu")
		(net "P5E_PEX0_STN5_TX_DN<80>")
	)
	(segment
		(start 62.261242 -349.831914)
		(end 61.941202 -349.511874)
		(width 0.13462)
		(layer "F.Cu")
		(net "P5E_PEX0_STN5_TX_DN<80>")
	)
	(segment
		(start 61.941202 -349.511874)
		(end 61.941202 -348.88043)
		(width 0.13462)
		(layer "F.Cu")
		(net "P5E_PEX0_STN5_TX_DN<80>")
	)
	(segment
		(start 58.365898 -319.890648)
		(end 58.365898 -319.8622)
		(width 0.1143)
		(layer "In7.Cu")
		(net "P5E_PEX0_STN5_TX_DN<80>")
	)
	(segment
		(start 61.945012 -348.29496)
		(end 61.945012 -347.658182)
		(width 0.1651)
		(layer "In7.Cu")
		(net "P5E_PEX0_STN5_TX_DN<80>")
	)
	(segment
		(start 58.365898 -327.3552)
		(end 58.365898 -319.890648)
		(width 0.1651)
		(layer "In7.Cu")
		(net "P5E_PEX0_STN5_TX_DN<80>")
	)
	(segment
		(start 58.320178 -311.784492)
		(end 58.434478 -311.670192)
		(width 0.1143)
		(layer "In7.Cu")
		(net "P5E_PEX0_STN5_TX_DN<80>")
	)
	(segment
		(start 58.434478 -311.670192)
		(end 58.585608 -311.670192)
		(width 0.1143)
		(layer "In7.Cu")
		(net "P5E_PEX0_STN5_TX_DN<80>")
	)
	(segment
		(start 60.611004 -346.324174)
		(end 60.135008 -345.318334)
		(width 0.1651)
		(layer "In7.Cu")
		(net "P5E_PEX0_STN5_TX_DN<80>")
	)
	(segment
		(start 60.135008 -345.318334)
		(end 58.365898 -327.3552)
		(width 0.1651)
		(layer "In7.Cu")
		(net "P5E_PEX0_STN5_TX_DN<80>")
	)
	(segment
		(start 58.699908 -311.784492)
		(end 58.699908 -312.049922)
		(width 0.1143)
		(layer "In7.Cu")
		(net "P5E_PEX0_STN5_TX_DN<80>")
	)
	(segment
		(start 58.320178 -319.81648)
		(end 58.320178 -311.784492)
		(width 0.1143)
		(layer "In7.Cu")
		(net "P5E_PEX0_STN5_TX_DN<80>")
	)
	(segment
		(start 58.585608 -311.670192)
		(end 58.699908 -311.784492)
		(width 0.1143)
		(layer "In7.Cu")
		(net "P5E_PEX0_STN5_TX_DN<80>")
	)
	(segment
		(start 58.365898 -319.8622)
		(end 58.320178 -319.81648)
		(width 0.1143)
		(layer "In7.Cu")
		(net "P5E_PEX0_STN5_TX_DN<80>")
	)
	(segment
		(start 61.945012 -347.658182)
		(end 60.611004 -346.324174)
		(width 0.1651)
		(layer "In7.Cu")
		(net "P5E_PEX0_STN5_TX_DN<80>")
	)
	(segment
		(start 62.235842 -348.58579)
		(end 61.945012 -348.29496)
		(width 0.1651)
		(layer "In7.Cu")
		(net "P5E_PEX0_STN5_TX_DN<80>")
	)
	(segment
		(start 140.411708 -355.658166)
		(end 140.411708 -355.026722)
		(width 0.13462)
		(layer "F.Cu")
		(net "P5E_PEX1_STN5_TX_DN<86>")
	)
	(segment
		(start 140.731748 -355.978206)
		(end 140.411708 -355.658166)
		(width 0.13462)
		(layer "F.Cu")
		(net "P5E_PEX1_STN5_TX_DN<86>")
	)
	(segment
		(start 140.411708 -355.026722)
		(end 140.706348 -354.732082)
		(width 0.13462)
		(layer "F.Cu")
		(net "P5E_PEX1_STN5_TX_DN<86>")
	)
	(segment
		(start 171.36618 -333.330804)
		(end 164.973508 -335.978754)
		(width 0.1651)
		(layer "In7.Cu")
		(net "P5E_PEX1_STN5_TX_DN<86>")
	)
	(segment
		(start 140.415518 -354.441252)
		(end 140.706348 -354.732082)
		(width 0.1651)
		(layer "In7.Cu")
		(net "P5E_PEX1_STN5_TX_DN<86>")
	)
	(segment
		(start 180.16601 -320.016886)
		(end 180.16601 -324.485254)
		(width 0.1651)
		(layer "In7.Cu")
		(net "P5E_PEX1_STN5_TX_DN<86>")
	)
	(segment
		(start 179.110386 -327.03389)
		(end 175.727868 -330.416408)
		(width 0.1651)
		(layer "In7.Cu")
		(net "P5E_PEX1_STN5_TX_DN<86>")
	)
	(segment
		(start 180.38572 -311.670192)
		(end 180.23459 -311.670192)
		(width 0.1143)
		(layer "In7.Cu")
		(net "P5E_PEX1_STN5_TX_DN<86>")
	)
	(segment
		(start 180.12029 -311.784492)
		(end 180.12029 -319.942718)
		(width 0.1143)
		(layer "In7.Cu")
		(net "P5E_PEX1_STN5_TX_DN<86>")
	)
	(segment
		(start 175.727868 -330.416408)
		(end 171.36618 -333.330804)
		(width 0.1651)
		(layer "In7.Cu")
		(net "P5E_PEX1_STN5_TX_DN<86>")
	)
	(segment
		(start 180.23459 -311.670192)
		(end 180.12029 -311.784492)
		(width 0.1143)
		(layer "In7.Cu")
		(net "P5E_PEX1_STN5_TX_DN<86>")
	)
	(segment
		(start 146.848068 -342.90508)
		(end 146.750786 -342.858852)
		(width 0.1651)
		(layer "In7.Cu")
		(net "P5E_PEX1_STN5_TX_DN<86>")
	)
	(segment
		(start 164.973508 -335.978754)
		(end 164.973508 -335.979008)
		(width 0.1651)
		(layer "In7.Cu")
		(net "P5E_PEX1_STN5_TX_DN<86>")
	)
	(segment
		(start 164.973508 -335.979008)
		(end 158.599886 -338.61883)
		(width 0.1651)
		(layer "In7.Cu")
		(net "P5E_PEX1_STN5_TX_DN<86>")
	)
	(segment
		(start 180.16601 -319.988438)
		(end 180.16601 -320.016886)
		(width 0.1143)
		(layer "In7.Cu")
		(net "P5E_PEX1_STN5_TX_DN<86>")
	)
	(segment
		(start 142.758414 -344.20683)
		(end 141.969998 -344.994992)
		(width 0.1651)
		(layer "In7.Cu")
		(net "P5E_PEX1_STN5_TX_DN<86>")
	)
	(segment
		(start 180.16601 -324.485254)
		(end 179.110386 -327.03389)
		(width 0.1651)
		(layer "In7.Cu")
		(net "P5E_PEX1_STN5_TX_DN<86>")
	)
	(segment
		(start 147.360894 -342.640412)
		(end 147.314666 -342.737948)
		(width 0.1651)
		(layer "In7.Cu")
		(net "P5E_PEX1_STN5_TX_DN<86>")
	)
	(segment
		(start 141.969998 -352.268282)
		(end 140.415518 -353.822762)
		(width 0.1651)
		(layer "In7.Cu")
		(net "P5E_PEX1_STN5_TX_DN<86>")
	)
	(segment
		(start 147.314666 -342.737948)
		(end 146.848068 -342.90508)
		(width 0.1651)
		(layer "In7.Cu")
		(net "P5E_PEX1_STN5_TX_DN<86>")
	)
	(segment
		(start 180.12029 -319.942718)
		(end 180.16601 -319.988438)
		(width 0.1143)
		(layer "In7.Cu")
		(net "P5E_PEX1_STN5_TX_DN<86>")
	)
	(segment
		(start 180.50002 -312.049922)
		(end 180.50002 -311.784492)
		(width 0.1143)
		(layer "In7.Cu")
		(net "P5E_PEX1_STN5_TX_DN<86>")
	)
	(segment
		(start 180.50002 -311.784492)
		(end 180.38572 -311.670192)
		(width 0.1143)
		(layer "In7.Cu")
		(net "P5E_PEX1_STN5_TX_DN<86>")
	)
	(segment
		(start 158.599886 -338.61883)
		(end 147.360894 -342.640412)
		(width 0.1651)
		(layer "In7.Cu")
		(net "P5E_PEX1_STN5_TX_DN<86>")
	)
	(segment
		(start 140.415518 -353.822762)
		(end 140.415518 -354.441252)
		(width 0.1651)
		(layer "In7.Cu")
		(net "P5E_PEX1_STN5_TX_DN<86>")
	)
	(segment
		(start 146.750786 -342.858852)
		(end 144.237964 -343.758012)
		(width 0.1651)
		(layer "In7.Cu")
		(net "P5E_PEX1_STN5_TX_DN<86>")
	)
	(segment
		(start 144.237964 -343.758012)
		(end 142.758414 -344.20683)
		(width 0.1651)
		(layer "In7.Cu")
		(net "P5E_PEX1_STN5_TX_DN<86>")
	)
	(segment
		(start 141.969998 -344.994992)
		(end 141.969998 -352.268282)
		(width 0.1651)
		(layer "In7.Cu")
		(net "P5E_PEX1_STN5_TX_DN<86>")
	)
	(segment
		(start 325.233284 -348.88043)
		(end 324.938644 -348.58579)
		(width 0.13462)
		(layer "F.Cu")
		(net "P5E_PEX2_STN5_TX_DP<86>")
	)
	(segment
		(start 325.233284 -349.511874)
		(end 325.233284 -348.88043)
		(width 0.13462)
		(layer "F.Cu")
		(net "P5E_PEX2_STN5_TX_DP<86>")
	)
	(segment
		(start 324.913244 -349.831914)
		(end 325.233284 -349.511874)
		(width 0.13462)
		(layer "F.Cu")
		(net "P5E_PEX2_STN5_TX_DP<86>")
	)
	(segment
		(start 326.783954 -342.015826)
		(end 325.794624 -340.43239)
		(width 0.1651)
		(layer "In7.Cu")
		(net "P5E_PEX2_STN5_TX_DP<86>")
	)
	(segment
		(start 295.983914 -321.775328)
		(end 295.983914 -319.890648)
		(width 0.1651)
		(layer "In7.Cu")
		(net "P5E_PEX2_STN5_TX_DP<86>")
	)
	(segment
		(start 300.168818 -328.634598)
		(end 297.874944 -326.340724)
		(width 0.1651)
		(layer "In7.Cu")
		(net "P5E_PEX2_STN5_TX_DP<86>")
	)
	(segment
		(start 325.229474 -347.667834)
		(end 326.783954 -346.113354)
		(width 0.1651)
		(layer "In7.Cu")
		(net "P5E_PEX2_STN5_TX_DP<86>")
	)
	(segment
		(start 295.983914 -319.8622)
		(end 296.029634 -319.81648)
		(width 0.1143)
		(layer "In7.Cu")
		(net "P5E_PEX2_STN5_TX_DP<86>")
	)
	(segment
		(start 296.029634 -319.81648)
		(end 296.029634 -311.705498)
		(width 0.1143)
		(layer "In7.Cu")
		(net "P5E_PEX2_STN5_TX_DP<86>")
	)
	(segment
		(start 296.029634 -311.705498)
		(end 296.25544 -311.479692)
		(width 0.1143)
		(layer "In7.Cu")
		(net "P5E_PEX2_STN5_TX_DP<86>")
	)
	(segment
		(start 325.229474 -348.29496)
		(end 325.229474 -347.667834)
		(width 0.1651)
		(layer "In7.Cu")
		(net "P5E_PEX2_STN5_TX_DP<86>")
	)
	(segment
		(start 324.938644 -348.58579)
		(end 325.229474 -348.29496)
		(width 0.1651)
		(layer "In7.Cu")
		(net "P5E_PEX2_STN5_TX_DP<86>")
	)
	(segment
		(start 295.983914 -319.890648)
		(end 295.983914 -319.8622)
		(width 0.1143)
		(layer "In7.Cu")
		(net "P5E_PEX2_STN5_TX_DP<86>")
	)
	(segment
		(start 325.794624 -340.43239)
		(end 321.672966 -337.695794)
		(width 0.1651)
		(layer "In7.Cu")
		(net "P5E_PEX2_STN5_TX_DP<86>")
	)
	(segment
		(start 326.783954 -346.113354)
		(end 326.783954 -342.015826)
		(width 0.1651)
		(layer "In7.Cu")
		(net "P5E_PEX2_STN5_TX_DP<86>")
	)
	(segment
		(start 296.25544 -311.479692)
		(end 296.485564 -311.479692)
		(width 0.1143)
		(layer "In7.Cu")
		(net "P5E_PEX2_STN5_TX_DP<86>")
	)
	(segment
		(start 296.485564 -311.479692)
		(end 296.599864 -311.365392)
		(width 0.1143)
		(layer "In7.Cu")
		(net "P5E_PEX2_STN5_TX_DP<86>")
	)
	(segment
		(start 296.599864 -311.365392)
		(end 296.599864 -311.099962)
		(width 0.1143)
		(layer "In7.Cu")
		(net "P5E_PEX2_STN5_TX_DP<86>")
	)
	(segment
		(start 321.672966 -337.695794)
		(end 300.168818 -328.634598)
		(width 0.1651)
		(layer "In7.Cu")
		(net "P5E_PEX2_STN5_TX_DP<86>")
	)
	(segment
		(start 297.874944 -326.340724)
		(end 295.983914 -321.775328)
		(width 0.1651)
		(layer "In7.Cu")
		(net "P5E_PEX2_STN5_TX_DP<86>")
	)
	(segment
		(start 386.067808 -110.977934)
		(end 386.352542 -110.6932)
		(width 0.13462)
		(layer "F.Cu")
		(net "P5E_PEX3_STN1_TX_DN<22>")
	)
	(segment
		(start 387.003798 -110.6932)
		(end 387.313932 -111.003334)
		(width 0.13462)
		(layer "F.Cu")
		(net "P5E_PEX3_STN1_TX_DN<22>")
	)
	(segment
		(start 386.352542 -110.6932)
		(end 387.003798 -110.6932)
		(width 0.13462)
		(layer "F.Cu")
		(net "P5E_PEX3_STN1_TX_DN<22>")
	)
	(segment
		(start 413.270192 -271.546066)
		(end 413.270192 -278.12619)
		(width 0.1143)
		(layer "In9.Cu")
		(net "P5E_PEX3_STN1_TX_DN<22>")
	)
	(segment
		(start 379.516386 -117.007386)
		(end 379.400308 -117.055392)
		(width 0.1651)
		(layer "In9.Cu")
		(net "P5E_PEX3_STN1_TX_DN<22>")
	)
	(segment
		(start 381.494792 -112.23117)
		(end 381.305054 -112.689132)
		(width 0.1651)
		(layer "In9.Cu")
		(net "P5E_PEX3_STN1_TX_DN<22>")
	)
	(segment
		(start 381.188722 -112.737138)
		(end 380.999238 -113.194592)
		(width 0.1651)
		(layer "In9.Cu")
		(net "P5E_PEX3_STN1_TX_DN<22>")
	)
	(segment
		(start 378.365004 -119.787924)
		(end 378.175266 -120.245886)
		(width 0.1651)
		(layer "In9.Cu")
		(net "P5E_PEX3_STN1_TX_DN<22>")
	)
	(segment
		(start 413.535368 -278.229568)
		(end 413.649668 -278.115268)
		(width 0.1143)
		(layer "In9.Cu")
		(net "P5E_PEX3_STN1_TX_DN<22>")
	)
	(segment
		(start 377.530106 -151.43353)
		(end 377.894088 -158.844488)
		(width 0.1651)
		(layer "In9.Cu")
		(net "P5E_PEX3_STN1_TX_DN<22>")
	)
	(segment
		(start 378.953268 -118.134892)
		(end 378.763784 -118.592346)
		(width 0.1651)
		(layer "In9.Cu")
		(net "P5E_PEX3_STN1_TX_DN<22>")
	)
	(segment
		(start 380.410466 -114.848132)
		(end 380.294388 -114.896392)
		(width 0.1651)
		(layer "In9.Cu")
		(net "P5E_PEX3_STN1_TX_DN<22>")
	)
	(segment
		(start 385.191 -110.687104)
		(end 385.0767 -110.801404)
		(width 0.1651)
		(layer "In9.Cu")
		(net "P5E_PEX3_STN1_TX_DN<22>")
	)
	(segment
		(start 381.047498 -113.31067)
		(end 380.85776 -113.768632)
		(width 0.1651)
		(layer "In9.Cu")
		(net "P5E_PEX3_STN1_TX_DN<22>")
	)
	(segment
		(start 380.552198 -114.274346)
		(end 380.551944 -114.274092)
		(width 0.1651)
		(layer "In9.Cu")
		(net "P5E_PEX3_STN1_TX_DN<22>")
	)
	(segment
		(start 379.069346 -118.086886)
		(end 378.953268 -118.134892)
		(width 0.1651)
		(layer "In9.Cu")
		(net "P5E_PEX3_STN1_TX_DN<22>")
	)
	(segment
		(start 413.649668 -278.115268)
		(end 413.649668 -277.849838)
		(width 0.1143)
		(layer "In9.Cu")
		(net "P5E_PEX3_STN1_TX_DN<22>")
	)
	(segment
		(start 378.458984 -161.684716)
		(end 413.315912 -264.660634)
		(width 0.1651)
		(layer "In9.Cu")
		(net "P5E_PEX3_STN1_TX_DN<22>")
	)
	(segment
		(start 413.315912 -264.660634)
		(end 413.315912 -271.471898)
		(width 0.1651)
		(layer "In9.Cu")
		(net "P5E_PEX3_STN1_TX_DN<22>")
	)
	(segment
		(start 380.551944 -114.274092)
		(end 380.600204 -114.39017)
		(width 0.1651)
		(layer "In9.Cu")
		(net "P5E_PEX3_STN1_TX_DN<22>")
	)
	(segment
		(start 381.636016 -111.657638)
		(end 381.446532 -112.115092)
		(width 0.1651)
		(layer "In9.Cu")
		(net "P5E_PEX3_STN1_TX_DN<22>")
	)
	(segment
		(start 413.315912 -271.500346)
		(end 413.270192 -271.546066)
		(width 0.1143)
		(layer "In9.Cu")
		(net "P5E_PEX3_STN1_TX_DN<22>")
	)
	(segment
		(start 374.593612 -131.49326)
		(end 374.593612 -137.75055)
		(width 0.1651)
		(layer "In9.Cu")
		(net "P5E_PEX3_STN1_TX_DN<22>")
	)
	(segment
		(start 378.812044 -118.708424)
		(end 378.622306 -119.166386)
		(width 0.1651)
		(layer "In9.Cu")
		(net "P5E_PEX3_STN1_TX_DN<22>")
	)
	(segment
		(start 379.259084 -117.628924)
		(end 379.069346 -118.086886)
		(width 0.1651)
		(layer "In9.Cu")
		(net "P5E_PEX3_STN1_TX_DN<22>")
	)
	(segment
		(start 384.5941 -110.801404)
		(end 384.4798 -110.687104)
		(width 0.1651)
		(layer "In9.Cu")
		(net "P5E_PEX3_STN1_TX_DN<22>")
	)
	(segment
		(start 380.999238 -113.194592)
		(end 381.047498 -113.31067)
		(width 0.1651)
		(layer "In9.Cu")
		(net "P5E_PEX3_STN1_TX_DN<22>")
	)
	(segment
		(start 413.270192 -278.12619)
		(end 413.37357 -278.229568)
		(width 0.1143)
		(layer "In9.Cu")
		(net "P5E_PEX3_STN1_TX_DN<22>")
	)
	(segment
		(start 379.847348 -115.975892)
		(end 379.657864 -116.433346)
		(width 0.1651)
		(layer "In9.Cu")
		(net "P5E_PEX3_STN1_TX_DN<22>")
	)
	(segment
		(start 380.294388 -114.896392)
		(end 380.294642 -114.896392)
		(width 0.1651)
		(layer "In9.Cu")
		(net "P5E_PEX3_STN1_TX_DN<22>")
	)
	(segment
		(start 413.315912 -271.471898)
		(end 413.315912 -271.500346)
		(width 0.1143)
		(layer "In9.Cu")
		(net "P5E_PEX3_STN1_TX_DN<22>")
	)
	(segment
		(start 380.105158 -115.353846)
		(end 380.104904 -115.353846)
		(width 0.1651)
		(layer "In9.Cu")
		(net "P5E_PEX3_STN1_TX_DN<22>")
	)
	(segment
		(start 378.175266 -120.245886)
		(end 378.059188 -120.293892)
		(width 0.1651)
		(layer "In9.Cu")
		(net "P5E_PEX3_STN1_TX_DN<22>")
	)
	(segment
		(start 378.622306 -119.166386)
		(end 378.506228 -119.214392)
		(width 0.1651)
		(layer "In9.Cu")
		(net "P5E_PEX3_STN1_TX_DN<22>")
	)
	(segment
		(start 413.37357 -278.229568)
		(end 413.535368 -278.229568)
		(width 0.1143)
		(layer "In9.Cu")
		(net "P5E_PEX3_STN1_TX_DN<22>")
	)
	(segment
		(start 383.156714 -111.021368)
		(end 382.710436 -111.206026)
		(width 0.1651)
		(layer "In9.Cu")
		(net "P5E_PEX3_STN1_TX_DN<22>")
	)
	(segment
		(start 382.710436 -111.206026)
		(end 382.561084 -111.14405)
		(width 0.1651)
		(layer "In9.Cu")
		(net "P5E_PEX3_STN1_TX_DN<22>")
	)
	(segment
		(start 385.776978 -110.687104)
		(end 385.191 -110.687104)
		(width 0.1651)
		(layer "In9.Cu")
		(net "P5E_PEX3_STN1_TX_DN<22>")
	)
	(segment
		(start 384.4798 -110.687104)
		(end 383.664206 -110.687104)
		(width 0.1651)
		(layer "In9.Cu")
		(net "P5E_PEX3_STN1_TX_DN<22>")
	)
	(segment
		(start 383.218436 -110.871762)
		(end 383.156714 -111.021368)
		(width 0.1651)
		(layer "In9.Cu")
		(net "P5E_PEX3_STN1_TX_DN<22>")
	)
	(segment
		(start 378.316744 -119.671846)
		(end 378.365004 -119.787924)
		(width 0.1651)
		(layer "In9.Cu")
		(net "P5E_PEX3_STN1_TX_DN<22>")
	)
	(segment
		(start 377.805696 -120.906032)
		(end 374.593612 -131.49326)
		(width 0.1651)
		(layer "In9.Cu")
		(net "P5E_PEX3_STN1_TX_DN<22>")
	)
	(segment
		(start 382.561084 -111.14405)
		(end 381.858012 -111.435388)
		(width 0.1651)
		(layer "In9.Cu")
		(net "P5E_PEX3_STN1_TX_DN<22>")
	)
	(segment
		(start 380.294642 -114.896392)
		(end 380.105158 -115.353846)
		(width 0.1651)
		(layer "In9.Cu")
		(net "P5E_PEX3_STN1_TX_DN<22>")
	)
	(segment
		(start 380.85776 -113.768632)
		(end 380.741428 -113.816638)
		(width 0.1651)
		(layer "In9.Cu")
		(net "P5E_PEX3_STN1_TX_DN<22>")
	)
	(segment
		(start 380.153164 -115.469924)
		(end 379.963426 -115.927886)
		(width 0.1651)
		(layer "In9.Cu")
		(net "P5E_PEX3_STN1_TX_DN<22>")
	)
	(segment
		(start 377.530106 -151.433276)
		(end 377.530106 -151.43353)
		(width 0.1651)
		(layer "In9.Cu")
		(net "P5E_PEX3_STN1_TX_DN<22>")
	)
	(segment
		(start 380.741682 -113.816638)
		(end 380.552198 -114.274346)
		(width 0.1651)
		(layer "In9.Cu")
		(net "P5E_PEX3_STN1_TX_DN<22>")
	)
	(segment
		(start 385.0767 -110.801404)
		(end 384.5941 -110.801404)
		(width 0.1651)
		(layer "In9.Cu")
		(net "P5E_PEX3_STN1_TX_DN<22>")
	)
	(segment
		(start 378.059188 -120.293892)
		(end 377.805696 -120.906032)
		(width 0.1651)
		(layer "In9.Cu")
		(net "P5E_PEX3_STN1_TX_DN<22>")
	)
	(segment
		(start 378.506228 -119.214392)
		(end 378.316744 -119.671846)
		(width 0.1651)
		(layer "In9.Cu")
		(net "P5E_PEX3_STN1_TX_DN<22>")
	)
	(segment
		(start 380.600204 -114.39017)
		(end 380.410466 -114.848132)
		(width 0.1651)
		(layer "In9.Cu")
		(net "P5E_PEX3_STN1_TX_DN<22>")
	)
	(segment
		(start 379.400308 -117.055392)
		(end 379.210824 -117.512846)
		(width 0.1651)
		(layer "In9.Cu")
		(net "P5E_PEX3_STN1_TX_DN<22>")
	)
	(segment
		(start 379.210824 -117.512846)
		(end 379.259084 -117.628924)
		(width 0.1651)
		(layer "In9.Cu")
		(net "P5E_PEX3_STN1_TX_DN<22>")
	)
	(segment
		(start 381.446532 -112.115092)
		(end 381.494792 -112.23117)
		(width 0.1651)
		(layer "In9.Cu")
		(net "P5E_PEX3_STN1_TX_DN<22>")
	)
	(segment
		(start 379.963426 -115.927886)
		(end 379.847348 -115.975892)
		(width 0.1651)
		(layer "In9.Cu")
		(net "P5E_PEX3_STN1_TX_DN<22>")
	)
	(segment
		(start 386.067808 -110.977934)
		(end 385.776978 -110.687104)
		(width 0.1651)
		(layer "In9.Cu")
		(net "P5E_PEX3_STN1_TX_DN<22>")
	)
	(segment
		(start 381.636016 -111.657384)
		(end 381.636016 -111.657638)
		(width 0.1651)
		(layer "In9.Cu")
		(net "P5E_PEX3_STN1_TX_DN<22>")
	)
	(segment
		(start 383.664206 -110.687104)
		(end 383.218436 -110.871762)
		(width 0.1651)
		(layer "In9.Cu")
		(net "P5E_PEX3_STN1_TX_DN<22>")
	)
	(segment
		(start 378.763784 -118.592346)
		(end 378.812044 -118.708424)
		(width 0.1651)
		(layer "In9.Cu")
		(net "P5E_PEX3_STN1_TX_DN<22>")
	)
	(segment
		(start 374.593612 -137.75055)
		(end 377.163076 -143.952976)
		(width 0.1651)
		(layer "In9.Cu")
		(net "P5E_PEX3_STN1_TX_DN<22>")
	)
	(segment
		(start 379.657864 -116.433346)
		(end 379.706124 -116.549424)
		(width 0.1651)
		(layer "In9.Cu")
		(net "P5E_PEX3_STN1_TX_DN<22>")
	)
	(segment
		(start 379.706124 -116.549424)
		(end 379.516386 -117.007386)
		(width 0.1651)
		(layer "In9.Cu")
		(net "P5E_PEX3_STN1_TX_DN<22>")
	)
	(segment
		(start 380.104904 -115.353846)
		(end 380.153164 -115.469924)
		(width 0.1651)
		(layer "In9.Cu")
		(net "P5E_PEX3_STN1_TX_DN<22>")
	)
	(segment
		(start 381.305054 -112.689132)
		(end 381.188722 -112.737138)
		(width 0.1651)
		(layer "In9.Cu")
		(net "P5E_PEX3_STN1_TX_DN<22>")
	)
	(segment
		(start 377.163076 -143.952976)
		(end 377.530106 -151.433276)
		(width 0.1651)
		(layer "In9.Cu")
		(net "P5E_PEX3_STN1_TX_DN<22>")
	)
	(segment
		(start 381.858012 -111.435388)
		(end 381.636016 -111.657384)
		(width 0.1651)
		(layer "In9.Cu")
		(net "P5E_PEX3_STN1_TX_DN<22>")
	)
	(segment
		(start 377.894088 -158.844488)
		(end 378.458984 -161.684716)
		(width 0.1651)
		(layer "In9.Cu")
		(net "P5E_PEX3_STN1_TX_DN<22>")
	)
	(segment
		(start 380.741428 -113.816638)
		(end 380.741682 -113.816638)
		(width 0.1651)
		(layer "In9.Cu")
		(net "P5E_PEX3_STN1_TX_DN<22>")
	)
	(segment
		(start 440.678824 -343.36609)
		(end 440.678824 -342.73363)
		(width 0.13462)
		(layer "F.Cu")
		(net "P5E_PEX3_STN7_TX_DP<126>")
	)
	(segment
		(start 440.359292 -343.685622)
		(end 440.678824 -343.36609)
		(width 0.13462)
		(layer "F.Cu")
		(net "P5E_PEX3_STN7_TX_DP<126>")
	)
	(segment
		(start 440.678824 -342.73363)
		(end 440.384692 -342.439498)
		(width 0.13462)
		(layer "F.Cu")
		(net "P5E_PEX3_STN7_TX_DP<126>")
	)
	(segment
		(start 440.675522 -341.503508)
		(end 440.675522 -342.148668)
		(width 0.1651)
		(layer "In11.Cu")
		(net "P5E_PEX3_STN7_TX_DP<126>")
	)
	(segment
		(start 389.283702 -321.098926)
		(end 389.510524 -321.393566)
		(width 0.1651)
		(layer "In11.Cu")
		(net "P5E_PEX3_STN7_TX_DP<126>")
	)
	(segment
		(start 426.802804 -331.221842)
		(end 439.877708 -340.359238)
		(width 0.1651)
		(layer "In11.Cu")
		(net "P5E_PEX3_STN7_TX_DP<126>")
	)
	(segment
		(start 440.276488 -340.9315)
		(end 440.276742 -340.9315)
		(width 0.1651)
		(layer "In11.Cu")
		(net "P5E_PEX3_STN7_TX_DP<126>")
	)
	(segment
		(start 389.510524 -321.393566)
		(end 426.802804 -331.221842)
		(width 0.1651)
		(layer "In11.Cu")
		(net "P5E_PEX3_STN7_TX_DP<126>")
	)
	(segment
		(start 389.544814 -311.479692)
		(end 389.329422 -311.695084)
		(width 0.1143)
		(layer "In11.Cu")
		(net "P5E_PEX3_STN7_TX_DP<126>")
	)
	(segment
		(start 389.283702 -320.034158)
		(end 389.283702 -320.056256)
		(width 0.1143)
		(layer "In11.Cu")
		(net "P5E_PEX3_STN7_TX_DP<126>")
	)
	(segment
		(start 440.675522 -342.148668)
		(end 440.384692 -342.439498)
		(width 0.1651)
		(layer "In11.Cu")
		(net "P5E_PEX3_STN7_TX_DP<126>")
	)
	(segment
		(start 389.899906 -311.099962)
		(end 389.899906 -311.365392)
		(width 0.1143)
		(layer "In11.Cu")
		(net "P5E_PEX3_STN7_TX_DP<126>")
	)
	(segment
		(start 389.329422 -319.988438)
		(end 389.283702 -320.034158)
		(width 0.1143)
		(layer "In11.Cu")
		(net "P5E_PEX3_STN7_TX_DP<126>")
	)
	(segment
		(start 439.877708 -340.359238)
		(end 440.276488 -340.9315)
		(width 0.1651)
		(layer "In11.Cu")
		(net "P5E_PEX3_STN7_TX_DP<126>")
	)
	(segment
		(start 389.329422 -311.695084)
		(end 389.329422 -319.988438)
		(width 0.1143)
		(layer "In11.Cu")
		(net "P5E_PEX3_STN7_TX_DP<126>")
	)
	(segment
		(start 389.899906 -311.365392)
		(end 389.785606 -311.479692)
		(width 0.1143)
		(layer "In11.Cu")
		(net "P5E_PEX3_STN7_TX_DP<126>")
	)
	(segment
		(start 440.276742 -340.9315)
		(end 440.675522 -341.503508)
		(width 0.1651)
		(layer "In11.Cu")
		(net "P5E_PEX3_STN7_TX_DP<126>")
	)
	(segment
		(start 389.785606 -311.479692)
		(end 389.544814 -311.479692)
		(width 0.1143)
		(layer "In11.Cu")
		(net "P5E_PEX3_STN7_TX_DP<126>")
	)
	(segment
		(start 389.283702 -320.056256)
		(end 389.283702 -321.098926)
		(width 0.1651)
		(layer "In11.Cu")
		(net "P5E_PEX3_STN7_TX_DP<126>")
	)
	(segment
		(start 96.388428 -28.55468)
		(end 96.05899 -28.225242)
		(width 0.13462)
		(layer "F.Cu")
		(net "P5E_PEX0_STN2_TX_DN<32>")
	)
	(segment
		(start 97.001076 -28.55468)
		(end 96.388428 -28.55468)
		(width 0.13462)
		(layer "F.Cu")
		(net "P5E_PEX0_STN2_TX_DN<32>")
	)
	(segment
		(start 97.305114 -28.250642)
		(end 97.001076 -28.55468)
		(width 0.13462)
		(layer "F.Cu")
		(net "P5E_PEX0_STN2_TX_DN<32>")
	)
	(segment
		(start 97.475802 -28.42133)
		(end 97.766124 -28.541472)
		(width 0.1651)
		(layer "In11.Cu")
		(net "P5E_PEX0_STN2_TX_DN<32>")
	)
	(segment
		(start 99.413822 -28.541472)
		(end 101.811836 -29.49448)
		(width 0.1651)
		(layer "In11.Cu")
		(net "P5E_PEX0_STN2_TX_DN<32>")
	)
	(segment
		(start 79.435452 -141.928088)
		(end 79.25054 -146.260566)
		(width 0.1651)
		(layer "In11.Cu")
		(net "P5E_PEX0_STN2_TX_DN<32>")
	)
	(segment
		(start 58.42381 -280.129488)
		(end 58.585608 -280.129488)
		(width 0.1143)
		(layer "In11.Cu")
		(net "P5E_PEX0_STN2_TX_DN<32>")
	)
	(segment
		(start 79.697834 -140.798042)
		(end 79.435452 -141.928088)
		(width 0.1651)
		(layer "In11.Cu")
		(net "P5E_PEX0_STN2_TX_DN<32>")
	)
	(segment
		(start 58.699908 -280.015188)
		(end 58.699908 -279.749504)
		(width 0.1143)
		(layer "In11.Cu")
		(net "P5E_PEX0_STN2_TX_DN<32>")
	)
	(segment
		(start 97.766124 -28.541472)
		(end 99.413822 -28.541472)
		(width 0.1651)
		(layer "In11.Cu")
		(net "P5E_PEX0_STN2_TX_DN<32>")
	)
	(segment
		(start 109.13364 -42.446194)
		(end 109.422946 -56.971184)
		(width 0.1651)
		(layer "In11.Cu")
		(net "P5E_PEX0_STN2_TX_DN<32>")
	)
	(segment
		(start 58.365898 -266.089638)
		(end 58.365898 -271.399)
		(width 0.1651)
		(layer "In11.Cu")
		(net "P5E_PEX0_STN2_TX_DN<32>")
	)
	(segment
		(start 79.697834 -135.769604)
		(end 79.697834 -140.798042)
		(width 0.1651)
		(layer "In11.Cu")
		(net "P5E_PEX0_STN2_TX_DN<32>")
	)
	(segment
		(start 108.431838 -39.806626)
		(end 109.13364 -42.446194)
		(width 0.1651)
		(layer "In11.Cu")
		(net "P5E_PEX0_STN2_TX_DN<32>")
	)
	(segment
		(start 101.811836 -29.49448)
		(end 103.987854 -31.675832)
		(width 0.1651)
		(layer "In11.Cu")
		(net "P5E_PEX0_STN2_TX_DN<32>")
	)
	(segment
		(start 104.693466 -75.5142)
		(end 103.731568 -76.754482)
		(width 0.1651)
		(layer "In11.Cu")
		(net "P5E_PEX0_STN2_TX_DN<32>")
	)
	(segment
		(start 103.731568 -76.754482)
		(end 97.081594 -80.362044)
		(width 0.1651)
		(layer "In11.Cu")
		(net "P5E_PEX0_STN2_TX_DN<32>")
	)
	(segment
		(start 97.081594 -80.362044)
		(end 95.45828 -81.985358)
		(width 0.1651)
		(layer "In11.Cu")
		(net "P5E_PEX0_STN2_TX_DN<32>")
	)
	(segment
		(start 95.45828 -81.985358)
		(end 81.940908 -106.033316)
		(width 0.1651)
		(layer "In11.Cu")
		(net "P5E_PEX0_STN2_TX_DN<32>")
	)
	(segment
		(start 58.365898 -271.427448)
		(end 58.320178 -271.473168)
		(width 0.1143)
		(layer "In11.Cu")
		(net "P5E_PEX0_STN2_TX_DN<32>")
	)
	(segment
		(start 80.456278 -117.98173)
		(end 79.697834 -135.769604)
		(width 0.1651)
		(layer "In11.Cu")
		(net "P5E_PEX0_STN2_TX_DN<32>")
	)
	(segment
		(start 58.365898 -271.399)
		(end 58.365898 -271.427448)
		(width 0.1143)
		(layer "In11.Cu")
		(net "P5E_PEX0_STN2_TX_DN<32>")
	)
	(segment
		(start 58.585608 -280.129488)
		(end 58.699908 -280.015188)
		(width 0.1143)
		(layer "In11.Cu")
		(net "P5E_PEX0_STN2_TX_DN<32>")
	)
	(segment
		(start 97.305114 -28.250642)
		(end 97.475802 -28.42133)
		(width 0.1651)
		(layer "In11.Cu")
		(net "P5E_PEX0_STN2_TX_DN<32>")
	)
	(segment
		(start 58.320178 -280.025856)
		(end 58.42381 -280.129488)
		(width 0.1143)
		(layer "In11.Cu")
		(net "P5E_PEX0_STN2_TX_DN<32>")
	)
	(segment
		(start 109.422946 -56.971184)
		(end 107.113324 -68.765928)
		(width 0.1651)
		(layer "In11.Cu")
		(net "P5E_PEX0_STN2_TX_DN<32>")
	)
	(segment
		(start 79.25054 -146.260566)
		(end 78.624684 -153.867612)
		(width 0.1651)
		(layer "In11.Cu")
		(net "P5E_PEX0_STN2_TX_DN<32>")
	)
	(segment
		(start 78.624684 -153.867612)
		(end 77.670152 -161.05886)
		(width 0.1651)
		(layer "In11.Cu")
		(net "P5E_PEX0_STN2_TX_DN<32>")
	)
	(segment
		(start 58.320178 -271.473168)
		(end 58.320178 -280.025856)
		(width 0.1143)
		(layer "In11.Cu")
		(net "P5E_PEX0_STN2_TX_DN<32>")
	)
	(segment
		(start 77.670152 -161.05886)
		(end 58.365898 -266.089638)
		(width 0.1651)
		(layer "In11.Cu")
		(net "P5E_PEX0_STN2_TX_DN<32>")
	)
	(segment
		(start 107.113324 -68.765928)
		(end 104.693466 -75.5142)
		(width 0.1651)
		(layer "In11.Cu")
		(net "P5E_PEX0_STN2_TX_DN<32>")
	)
	(segment
		(start 103.987854 -31.675832)
		(end 108.431838 -39.806626)
		(width 0.1651)
		(layer "In11.Cu")
		(net "P5E_PEX0_STN2_TX_DN<32>")
	)
	(segment
		(start 81.940908 -106.033316)
		(end 80.456278 -117.98173)
		(width 0.1651)
		(layer "In11.Cu")
		(net "P5E_PEX0_STN2_TX_DN<32>")
	)
	(segment
		(start 161.101532 -32.4104)
		(end 160.488376 -32.4104)
		(width 0.13462)
		(layer "F.Cu")
		(net "P5E_PEX1_STN2_TX_DP<42>")
	)
	(segment
		(start 160.488376 -32.4104)
		(end 160.159192 -32.739584)
		(width 0.13462)
		(layer "F.Cu")
		(net "P5E_PEX1_STN2_TX_DP<42>")
	)
	(segment
		(start 161.405316 -32.714184)
		(end 161.101532 -32.4104)
		(width 0.13462)
		(layer "F.Cu")
		(net "P5E_PEX1_STN2_TX_DP<42>")
	)
	(segment
		(start 163.13785 -32.512254)
		(end 162.64255 -32.512254)
		(width 0.1651)
		(layer "In11.Cu")
		(net "P5E_PEX1_STN2_TX_DP<42>")
	)
	(segment
		(start 164.944806 -280.319988)
		(end 164.729668 -280.10485)
		(width 0.1143)
		(layer "In11.Cu")
		(net "P5E_PEX1_STN2_TX_DP<42>")
	)
	(segment
		(start 165.185598 -280.319988)
		(end 164.944806 -280.319988)
		(width 0.1143)
		(layer "In11.Cu")
		(net "P5E_PEX1_STN2_TX_DP<42>")
	)
	(segment
		(start 178.489864 -50.426366)
		(end 177.87366 -48.627538)
		(width 0.1651)
		(layer "In11.Cu")
		(net "P5E_PEX1_STN2_TX_DP<42>")
	)
	(segment
		(start 179.123086 -60.449968)
		(end 178.489864 -50.426366)
		(width 0.1651)
		(layer "In11.Cu")
		(net "P5E_PEX1_STN2_TX_DP<42>")
	)
	(segment
		(start 165.299898 -280.434288)
		(end 165.185598 -280.319988)
		(width 0.1143)
		(layer "In11.Cu")
		(net "P5E_PEX1_STN2_TX_DP<42>")
	)
	(segment
		(start 163.22675 -32.423354)
		(end 163.13785 -32.512254)
		(width 0.1651)
		(layer "In11.Cu")
		(net "P5E_PEX1_STN2_TX_DP<42>")
	)
	(segment
		(start 164.729668 -280.10485)
		(end 164.729668 -271.473168)
		(width 0.1143)
		(layer "In11.Cu")
		(net "P5E_PEX1_STN2_TX_DP<42>")
	)
	(segment
		(start 167.184324 -34.785046)
		(end 165.010846 -32.568896)
		(width 0.1651)
		(layer "In11.Cu")
		(net "P5E_PEX1_STN2_TX_DP<42>")
	)
	(segment
		(start 164.683948 -270.440658)
		(end 164.35324 -267.083794)
		(width 0.1651)
		(layer "In11.Cu")
		(net "P5E_PEX1_STN2_TX_DP<42>")
	)
	(segment
		(start 161.939732 -115.996212)
		(end 167.364156 -95.718122)
		(width 0.1651)
		(layer "In11.Cu")
		(net "P5E_PEX1_STN2_TX_DP<42>")
	)
	(segment
		(start 167.364156 -95.718122)
		(end 177.637948 -68.584318)
		(width 0.1651)
		(layer "In11.Cu")
		(net "P5E_PEX1_STN2_TX_DP<42>")
	)
	(segment
		(start 164.35324 -267.083794)
		(end 160.839404 -161.954718)
		(width 0.1651)
		(layer "In11.Cu")
		(net "P5E_PEX1_STN2_TX_DP<42>")
	)
	(segment
		(start 162.55365 -32.423354)
		(end 161.696146 -32.423354)
		(width 0.1651)
		(layer "In11.Cu")
		(net "P5E_PEX1_STN2_TX_DP<42>")
	)
	(segment
		(start 162.20059 -141.878558)
		(end 161.939732 -115.996212)
		(width 0.1651)
		(layer "In11.Cu")
		(net "P5E_PEX1_STN2_TX_DP<42>")
	)
	(segment
		(start 165.299898 -280.699718)
		(end 165.299898 -280.434288)
		(width 0.1143)
		(layer "In11.Cu")
		(net "P5E_PEX1_STN2_TX_DP<42>")
	)
	(segment
		(start 164.683948 -271.427448)
		(end 164.683948 -271.399)
		(width 0.1143)
		(layer "In11.Cu")
		(net "P5E_PEX1_STN2_TX_DP<42>")
	)
	(segment
		(start 177.87366 -48.627538)
		(end 167.184324 -34.785046)
		(width 0.1651)
		(layer "In11.Cu")
		(net "P5E_PEX1_STN2_TX_DP<42>")
	)
	(segment
		(start 164.524182 -32.423354)
		(end 163.22675 -32.423354)
		(width 0.1651)
		(layer "In11.Cu")
		(net "P5E_PEX1_STN2_TX_DP<42>")
	)
	(segment
		(start 162.64255 -32.512254)
		(end 162.55365 -32.423354)
		(width 0.1651)
		(layer "In11.Cu")
		(net "P5E_PEX1_STN2_TX_DP<42>")
	)
	(segment
		(start 160.839404 -161.954718)
		(end 162.20059 -141.878558)
		(width 0.1651)
		(layer "In11.Cu")
		(net "P5E_PEX1_STN2_TX_DP<42>")
	)
	(segment
		(start 165.010846 -32.568896)
		(end 164.524182 -32.423354)
		(width 0.1651)
		(layer "In11.Cu")
		(net "P5E_PEX1_STN2_TX_DP<42>")
	)
	(segment
		(start 164.729668 -271.473168)
		(end 164.683948 -271.427448)
		(width 0.1143)
		(layer "In11.Cu")
		(net "P5E_PEX1_STN2_TX_DP<42>")
	)
	(segment
		(start 161.696146 -32.423354)
		(end 161.405316 -32.714184)
		(width 0.1651)
		(layer "In11.Cu")
		(net "P5E_PEX1_STN2_TX_DP<42>")
	)
	(segment
		(start 164.683948 -271.399)
		(end 164.683948 -270.440658)
		(width 0.1651)
		(layer "In11.Cu")
		(net "P5E_PEX1_STN2_TX_DP<42>")
	)
	(segment
		(start 177.637948 -68.584318)
		(end 179.123086 -60.449968)
		(width 0.1651)
		(layer "In11.Cu")
		(net "P5E_PEX1_STN2_TX_DP<42>")
	)
	(segment
		(start 305.85283 -34.2265)
		(end 305.220878 -34.2265)
		(width 0.13462)
		(layer "F.Cu")
		(net "P5E_PEX2_STN2_TX_DP<39>")
	)
	(segment
		(start 305.220878 -34.2265)
		(end 304.901092 -34.546286)
		(width 0.13462)
		(layer "F.Cu")
		(net "P5E_PEX2_STN2_TX_DP<39>")
	)
	(segment
		(start 306.147216 -34.520886)
		(end 305.85283 -34.2265)
		(width 0.13462)
		(layer "F.Cu")
		(net "P5E_PEX2_STN2_TX_DP<39>")
	)
	(segment
		(start 310.450992 -38.39083)
		(end 312.668666 -42.014394)
		(width 0.1651)
		(layer "In11.Cu")
		(net "P5E_PEX2_STN2_TX_DP<39>")
	)
	(segment
		(start 283.679646 -271.473168)
		(end 283.679646 -278.20493)
		(width 0.1143)
		(layer "In11.Cu")
		(net "P5E_PEX2_STN2_TX_DP<39>")
	)
	(segment
		(start 283.894784 -278.420068)
		(end 284.135576 -278.420068)
		(width 0.1143)
		(layer "In11.Cu")
		(net "P5E_PEX2_STN2_TX_DP<39>")
	)
	(segment
		(start 284.135576 -278.420068)
		(end 284.249876 -278.534368)
		(width 0.1143)
		(layer "In11.Cu")
		(net "P5E_PEX2_STN2_TX_DP<39>")
	)
	(segment
		(start 312.668666 -42.014394)
		(end 319.211452 -49.155858)
		(width 0.1651)
		(layer "In11.Cu")
		(net "P5E_PEX2_STN2_TX_DP<39>")
	)
	(segment
		(start 310.099202 -37.816536)
		(end 310.069992 -37.93871)
		(width 0.1651)
		(layer "In11.Cu")
		(net "P5E_PEX2_STN2_TX_DP<39>")
	)
	(segment
		(start 309.840884 -37.394134)
		(end 310.099202 -37.816536)
		(width 0.1651)
		(layer "In11.Cu")
		(net "P5E_PEX2_STN2_TX_DP<39>")
	)
	(segment
		(start 310.328818 -38.361366)
		(end 310.450992 -38.39083)
		(width 0.1651)
		(layer "In11.Cu")
		(net "P5E_PEX2_STN2_TX_DP<39>")
	)
	(segment
		(start 283.633926 -271.427448)
		(end 283.679646 -271.473168)
		(width 0.1143)
		(layer "In11.Cu")
		(net "P5E_PEX2_STN2_TX_DP<39>")
	)
	(segment
		(start 283.633926 -271.399)
		(end 283.633926 -271.427448)
		(width 0.1143)
		(layer "In11.Cu")
		(net "P5E_PEX2_STN2_TX_DP<39>")
	)
	(segment
		(start 291.846762 -114.435636)
		(end 291.129212 -120.262396)
		(width 0.1651)
		(layer "In11.Cu")
		(net "P5E_PEX2_STN2_TX_DP<39>")
	)
	(segment
		(start 306.955444 -34.230056)
		(end 307.410612 -34.419794)
		(width 0.1651)
		(layer "In11.Cu")
		(net "P5E_PEX2_STN2_TX_DP<39>")
	)
	(segment
		(start 309.71871 -37.36467)
		(end 309.840884 -37.394134)
		(width 0.1651)
		(layer "In11.Cu")
		(net "P5E_PEX2_STN2_TX_DP<39>")
	)
	(segment
		(start 291.129212 -120.262396)
		(end 291.128704 -120.262396)
		(width 0.1651)
		(layer "In11.Cu")
		(net "P5E_PEX2_STN2_TX_DP<39>")
	)
	(segment
		(start 310.069992 -37.93871)
		(end 310.328818 -38.361366)
		(width 0.1651)
		(layer "In11.Cu")
		(net "P5E_PEX2_STN2_TX_DP<39>")
	)
	(segment
		(start 283.679646 -278.20493)
		(end 283.894784 -278.420068)
		(width 0.1143)
		(layer "In11.Cu")
		(net "P5E_PEX2_STN2_TX_DP<39>")
	)
	(segment
		(start 290.984686 -121.433336)
		(end 283.633926 -262.791702)
		(width 0.1651)
		(layer "In11.Cu")
		(net "P5E_PEX2_STN2_TX_DP<39>")
	)
	(segment
		(start 283.633926 -262.791702)
		(end 283.633926 -271.399)
		(width 0.1651)
		(layer "In11.Cu")
		(net "P5E_PEX2_STN2_TX_DP<39>")
	)
	(segment
		(start 320.19494 -60.128404)
		(end 319.71107 -61.953394)
		(width 0.1651)
		(layer "In11.Cu")
		(net "P5E_PEX2_STN2_TX_DP<39>")
	)
	(segment
		(start 306.147216 -34.520886)
		(end 306.438046 -34.230056)
		(width 0.1651)
		(layer "In11.Cu")
		(net "P5E_PEX2_STN2_TX_DP<39>")
	)
	(segment
		(start 319.71107 -61.953394)
		(end 318.84239 -63.68415)
		(width 0.1651)
		(layer "In11.Cu")
		(net "P5E_PEX2_STN2_TX_DP<39>")
	)
	(segment
		(start 320.19494 -58.556144)
		(end 320.19494 -60.128404)
		(width 0.1651)
		(layer "In11.Cu")
		(net "P5E_PEX2_STN2_TX_DP<39>")
	)
	(segment
		(start 318.84239 -63.68415)
		(end 296.569384 -92.692474)
		(width 0.1651)
		(layer "In11.Cu")
		(net "P5E_PEX2_STN2_TX_DP<39>")
	)
	(segment
		(start 309.459884 -36.942014)
		(end 309.71871 -37.36467)
		(width 0.1651)
		(layer "In11.Cu")
		(net "P5E_PEX2_STN2_TX_DP<39>")
	)
	(segment
		(start 291.105844 -120.44807)
		(end 290.984686 -121.433336)
		(width 0.1651)
		(layer "In11.Cu")
		(net "P5E_PEX2_STN2_TX_DP<39>")
	)
	(segment
		(start 296.569384 -92.692474)
		(end 293.269924 -107.162092)
		(width 0.1651)
		(layer "In11.Cu")
		(net "P5E_PEX2_STN2_TX_DP<39>")
	)
	(segment
		(start 291.106098 -120.44807)
		(end 291.105844 -120.44807)
		(width 0.1651)
		(layer "In11.Cu")
		(net "P5E_PEX2_STN2_TX_DP<39>")
	)
	(segment
		(start 306.438046 -34.230056)
		(end 306.955444 -34.230056)
		(width 0.1651)
		(layer "In11.Cu")
		(net "P5E_PEX2_STN2_TX_DP<39>")
	)
	(segment
		(start 309.00243 -36.024312)
		(end 309.489348 -36.819586)
		(width 0.1651)
		(layer "In11.Cu")
		(net "P5E_PEX2_STN2_TX_DP<39>")
	)
	(segment
		(start 291.128704 -120.262396)
		(end 291.106098 -120.44807)
		(width 0.1651)
		(layer "In11.Cu")
		(net "P5E_PEX2_STN2_TX_DP<39>")
	)
	(segment
		(start 307.410612 -34.419794)
		(end 309.00243 -36.024312)
		(width 0.1651)
		(layer "In11.Cu")
		(net "P5E_PEX2_STN2_TX_DP<39>")
	)
	(segment
		(start 309.489348 -36.819586)
		(end 309.459884 -36.942014)
		(width 0.1651)
		(layer "In11.Cu")
		(net "P5E_PEX2_STN2_TX_DP<39>")
	)
	(segment
		(start 293.269924 -107.162092)
		(end 291.846762 -114.435636)
		(width 0.1651)
		(layer "In11.Cu")
		(net "P5E_PEX2_STN2_TX_DP<39>")
	)
	(segment
		(start 284.249876 -278.534368)
		(end 284.249876 -278.799798)
		(width 0.1143)
		(layer "In11.Cu")
		(net "P5E_PEX2_STN2_TX_DP<39>")
	)
	(segment
		(start 319.211452 -49.155858)
		(end 320.19494 -58.556144)
		(width 0.1651)
		(layer "In11.Cu")
		(net "P5E_PEX2_STN2_TX_DP<39>")
	)
	(segment
		(start 428.906432 -130.2004)
		(end 428.586138 -129.880106)
		(width 0.13462)
		(layer "F.Cu")
		(net "P5E_PEX3_STN0_TX_DN<4>")
	)
	(segment
		(start 429.537368 -130.2004)
		(end 428.906432 -130.2004)
		(width 0.13462)
		(layer "F.Cu")
		(net "P5E_PEX3_STN0_TX_DN<4>")
	)
	(segment
		(start 429.832262 -129.905506)
		(end 429.537368 -130.2004)
		(width 0.13462)
		(layer "F.Cu")
		(net "P5E_PEX3_STN0_TX_DN<4>")
	)
	(segment
		(start 445.111632 -272.151602)
		(end 444.03518 -274.749768)
		(width 0.1651)
		(layer "In9.Cu")
		(net "P5E_PEX3_STN0_TX_DN<4>")
	)
	(segment
		(start 433.329842 -284.165802)
		(end 432.217576 -284.165802)
		(width 0.1651)
		(layer "In9.Cu")
		(net "P5E_PEX3_STN0_TX_DN<4>")
	)
	(segment
		(start 432.189128 -284.165802)
		(end 432.143408 -284.120082)
		(width 0.1143)
		(layer "In9.Cu")
		(net "P5E_PEX3_STN0_TX_DN<4>")
	)
	(segment
		(start 435.853078 -174.772828)
		(end 434.808122 -178.670712)
		(width 0.1651)
		(layer "In9.Cu")
		(net "P5E_PEX3_STN0_TX_DN<4>")
	)
	(segment
		(start 430.123092 -130.196336)
		(end 432.560222 -130.196336)
		(width 0.1651)
		(layer "In9.Cu")
		(net "P5E_PEX3_STN0_TX_DN<4>")
	)
	(segment
		(start 431.052732 -221.593156)
		(end 433.596796 -250.731782)
		(width 0.1651)
		(layer "In9.Cu")
		(net "P5E_PEX3_STN0_TX_DN<4>")
	)
	(segment
		(start 444.03518 -274.749768)
		(end 435.531006 -283.253942)
		(width 0.1651)
		(layer "In9.Cu")
		(net "P5E_PEX3_STN0_TX_DN<4>")
	)
	(segment
		(start 433.596796 -250.731782)
		(end 443.963806 -266.247626)
		(width 0.1651)
		(layer "In9.Cu")
		(net "P5E_PEX3_STN0_TX_DN<4>")
	)
	(segment
		(start 444.521336 -159.752792)
		(end 435.853078 -174.772828)
		(width 0.1651)
		(layer "In9.Cu")
		(net "P5E_PEX3_STN0_TX_DN<4>")
	)
	(segment
		(start 425.73448 -284.499812)
		(end 425.99991 -284.499812)
		(width 0.1143)
		(layer "In9.Cu")
		(net "P5E_PEX3_STN0_TX_DN<4>")
	)
	(segment
		(start 435.531006 -283.253942)
		(end 433.329842 -284.165802)
		(width 0.1651)
		(layer "In9.Cu")
		(net "P5E_PEX3_STN0_TX_DN<4>")
	)
	(segment
		(start 443.963806 -266.247626)
		(end 444.764668 -268.181582)
		(width 0.1651)
		(layer "In9.Cu")
		(net "P5E_PEX3_STN0_TX_DN<4>")
	)
	(segment
		(start 434.808122 -178.670712)
		(end 431.052732 -221.593156)
		(width 0.1651)
		(layer "In9.Cu")
		(net "P5E_PEX3_STN0_TX_DN<4>")
	)
	(segment
		(start 440.898534 -144.448784)
		(end 444.600584 -153.386282)
		(width 0.1651)
		(layer "In9.Cu")
		(net "P5E_PEX3_STN0_TX_DN<4>")
	)
	(segment
		(start 444.600584 -153.386282)
		(end 444.600584 -159.455866)
		(width 0.1651)
		(layer "In9.Cu")
		(net "P5E_PEX3_STN0_TX_DN<4>")
	)
	(segment
		(start 425.62018 -284.223714)
		(end 425.62018 -284.385512)
		(width 0.1143)
		(layer "In9.Cu")
		(net "P5E_PEX3_STN0_TX_DN<4>")
	)
	(segment
		(start 429.832262 -129.905506)
		(end 430.123092 -130.196336)
		(width 0.1651)
		(layer "In9.Cu")
		(net "P5E_PEX3_STN0_TX_DN<4>")
	)
	(segment
		(start 432.560222 -130.196336)
		(end 433.62753 -130.63855)
		(width 0.1651)
		(layer "In9.Cu")
		(net "P5E_PEX3_STN0_TX_DN<4>")
	)
	(segment
		(start 432.217576 -284.165802)
		(end 432.189128 -284.165802)
		(width 0.1143)
		(layer "In9.Cu")
		(net "P5E_PEX3_STN0_TX_DN<4>")
	)
	(segment
		(start 440.726322 -144.276572)
		(end 440.898534 -144.448784)
		(width 0.1651)
		(layer "In9.Cu")
		(net "P5E_PEX3_STN0_TX_DN<4>")
	)
	(segment
		(start 432.143408 -284.120082)
		(end 425.723812 -284.120082)
		(width 0.1143)
		(layer "In9.Cu")
		(net "P5E_PEX3_STN0_TX_DN<4>")
	)
	(segment
		(start 425.723812 -284.120082)
		(end 425.62018 -284.223714)
		(width 0.1143)
		(layer "In9.Cu")
		(net "P5E_PEX3_STN0_TX_DN<4>")
	)
	(segment
		(start 425.62018 -284.385512)
		(end 425.73448 -284.499812)
		(width 0.1143)
		(layer "In9.Cu")
		(net "P5E_PEX3_STN0_TX_DN<4>")
	)
	(segment
		(start 444.764668 -268.181582)
		(end 445.111632 -272.151602)
		(width 0.1651)
		(layer "In9.Cu")
		(net "P5E_PEX3_STN0_TX_DN<4>")
	)
	(segment
		(start 433.62753 -130.63855)
		(end 436.102252 -133.113272)
		(width 0.1651)
		(layer "In9.Cu")
		(net "P5E_PEX3_STN0_TX_DN<4>")
	)
	(segment
		(start 436.102252 -133.113272)
		(end 440.726322 -144.276572)
		(width 0.1651)
		(layer "In9.Cu")
		(net "P5E_PEX3_STN0_TX_DN<4>")
	)
	(segment
		(start 444.600584 -159.455866)
		(end 444.521336 -159.752792)
		(width 0.1651)
		(layer "In9.Cu")
		(net "P5E_PEX3_STN0_TX_DN<4>")
	)
	(segment
		(start 387.301232 -349.511366)
		(end 387.301232 -348.880938)
		(width 0.13462)
		(layer "F.Cu")
		(net "P5E_PEX3_STN6_TX_DN<104>")
	)
	(segment
		(start 387.62178 -349.831914)
		(end 387.301232 -349.511366)
		(width 0.13462)
		(layer "F.Cu")
		(net "P5E_PEX3_STN6_TX_DN<104>")
	)
	(segment
		(start 387.301232 -348.880938)
		(end 387.59638 -348.58579)
		(width 0.13462)
		(layer "F.Cu")
		(net "P5E_PEX3_STN6_TX_DN<104>")
	)
	(segment
		(start 388.86003 -341.84209)
		(end 398.11579 -322.724272)
		(width 0.1651)
		(layer "In13.Cu")
		(net "P5E_PEX3_STN6_TX_DN<104>")
	)
	(segment
		(start 387.30555 -348.29496)
		(end 387.30555 -347.784674)
		(width 0.1651)
		(layer "In13.Cu")
		(net "P5E_PEX3_STN6_TX_DN<104>")
	)
	(segment
		(start 398.11579 -322.724272)
		(end 398.11579 -320.046096)
		(width 0.1651)
		(layer "In13.Cu")
		(net "P5E_PEX3_STN6_TX_DN<104>")
	)
	(segment
		(start 388.86003 -346.230194)
		(end 388.86003 -341.84209)
		(width 0.1651)
		(layer "In13.Cu")
		(net "P5E_PEX3_STN6_TX_DN<104>")
	)
	(segment
		(start 398.3355 -313.570112)
		(end 398.4498 -313.684412)
		(width 0.1143)
		(layer "In13.Cu")
		(net "P5E_PEX3_STN6_TX_DN<104>")
	)
	(segment
		(start 398.11579 -320.046096)
		(end 398.11579 -320.017648)
		(width 0.1143)
		(layer "In13.Cu")
		(net "P5E_PEX3_STN6_TX_DN<104>")
	)
	(segment
		(start 398.07007 -313.673744)
		(end 398.173702 -313.570112)
		(width 0.1143)
		(layer "In13.Cu")
		(net "P5E_PEX3_STN6_TX_DN<104>")
	)
	(segment
		(start 398.11579 -320.017648)
		(end 398.07007 -319.971928)
		(width 0.1143)
		(layer "In13.Cu")
		(net "P5E_PEX3_STN6_TX_DN<104>")
	)
	(segment
		(start 387.30555 -347.784674)
		(end 388.86003 -346.230194)
		(width 0.1651)
		(layer "In13.Cu")
		(net "P5E_PEX3_STN6_TX_DN<104>")
	)
	(segment
		(start 398.173702 -313.570112)
		(end 398.3355 -313.570112)
		(width 0.1143)
		(layer "In13.Cu")
		(net "P5E_PEX3_STN6_TX_DN<104>")
	)
	(segment
		(start 398.4498 -313.684412)
		(end 398.4498 -313.949842)
		(width 0.1143)
		(layer "In13.Cu")
		(net "P5E_PEX3_STN6_TX_DN<104>")
	)
	(segment
		(start 398.07007 -319.971928)
		(end 398.07007 -313.673744)
		(width 0.1143)
		(layer "In13.Cu")
		(net "P5E_PEX3_STN6_TX_DN<104>")
	)
	(segment
		(start 387.59638 -348.58579)
		(end 387.30555 -348.29496)
		(width 0.1651)
		(layer "In13.Cu")
		(net "P5E_PEX3_STN6_TX_DN<104>")
	)
	(segment
		(start 47.947326 -30.05709)
		(end 47.651416 -30.353)
		(width 0.13462)
		(layer "F.Cu")
		(net "P5E_PEX0_STN2_TX_DN<41>")
	)
	(segment
		(start 47.022512 -30.353)
		(end 46.701202 -30.03169)
		(width 0.13462)
		(layer "F.Cu")
		(net "P5E_PEX0_STN2_TX_DN<41>")
	)
	(segment
		(start 47.651416 -30.353)
		(end 47.022512 -30.353)
		(width 0.13462)
		(layer "F.Cu")
		(net "P5E_PEX0_STN2_TX_DN<41>")
	)
	(segment
		(start 49.81575 -271.427448)
		(end 49.77003 -271.473168)
		(width 0.1143)
		(layer "In11.Cu")
		(net "P5E_PEX0_STN2_TX_DN<41>")
	)
	(segment
		(start 49.451514 -266.126976)
		(end 49.81575 -269.827756)
		(width 0.1651)
		(layer "In11.Cu")
		(net "P5E_PEX0_STN2_TX_DN<41>")
	)
	(segment
		(start 50.03546 -278.229568)
		(end 50.14976 -278.115268)
		(width 0.1143)
		(layer "In11.Cu")
		(net "P5E_PEX0_STN2_TX_DN<41>")
	)
	(segment
		(start 47.947326 -30.05709)
		(end 48.238156 -30.34792)
		(width 0.1651)
		(layer "In11.Cu")
		(net "P5E_PEX0_STN2_TX_DN<41>")
	)
	(segment
		(start 49.77003 -278.125936)
		(end 49.873662 -278.229568)
		(width 0.1143)
		(layer "In11.Cu")
		(net "P5E_PEX0_STN2_TX_DN<41>")
	)
	(segment
		(start 62.923166 -48.058832)
		(end 63.61811 -50.066194)
		(width 0.1651)
		(layer "In11.Cu")
		(net "P5E_PEX0_STN2_TX_DN<41>")
	)
	(segment
		(start 51.689 -33.072578)
		(end 53.02758 -35.26917)
		(width 0.1651)
		(layer "In11.Cu")
		(net "P5E_PEX0_STN2_TX_DN<41>")
	)
	(segment
		(start 63.75908 -69.628766)
		(end 56.801004 -119.31269)
		(width 0.1651)
		(layer "In11.Cu")
		(net "P5E_PEX0_STN2_TX_DN<41>")
	)
	(segment
		(start 63.61811 -50.066194)
		(end 64.27216 -60.550298)
		(width 0.1651)
		(layer "In11.Cu")
		(net "P5E_PEX0_STN2_TX_DN<41>")
	)
	(segment
		(start 49.81575 -269.827756)
		(end 49.81575 -271.399)
		(width 0.1651)
		(layer "In11.Cu")
		(net "P5E_PEX0_STN2_TX_DN<41>")
	)
	(segment
		(start 49.77003 -271.473168)
		(end 49.77003 -278.125936)
		(width 0.1143)
		(layer "In11.Cu")
		(net "P5E_PEX0_STN2_TX_DN<41>")
	)
	(segment
		(start 53.02758 -35.26917)
		(end 62.923166 -48.058832)
		(width 0.1651)
		(layer "In11.Cu")
		(net "P5E_PEX0_STN2_TX_DN<41>")
	)
	(segment
		(start 55.471822 -135.163052)
		(end 49.099724 -252.662436)
		(width 0.1651)
		(layer "In11.Cu")
		(net "P5E_PEX0_STN2_TX_DN<41>")
	)
	(segment
		(start 48.238156 -30.34792)
		(end 48.688752 -30.34792)
		(width 0.1651)
		(layer "In11.Cu")
		(net "P5E_PEX0_STN2_TX_DN<41>")
	)
	(segment
		(start 64.27216 -60.550298)
		(end 63.75908 -69.628766)
		(width 0.1651)
		(layer "In11.Cu")
		(net "P5E_PEX0_STN2_TX_DN<41>")
	)
	(segment
		(start 50.14976 -278.115268)
		(end 50.14976 -277.849838)
		(width 0.1143)
		(layer "In11.Cu")
		(net "P5E_PEX0_STN2_TX_DN<41>")
	)
	(segment
		(start 49.119536 -30.525212)
		(end 51.689 -33.072578)
		(width 0.1651)
		(layer "In11.Cu")
		(net "P5E_PEX0_STN2_TX_DN<41>")
	)
	(segment
		(start 49.81575 -271.399)
		(end 49.81575 -271.427448)
		(width 0.1143)
		(layer "In11.Cu")
		(net "P5E_PEX0_STN2_TX_DN<41>")
	)
	(segment
		(start 49.873662 -278.229568)
		(end 50.03546 -278.229568)
		(width 0.1143)
		(layer "In11.Cu")
		(net "P5E_PEX0_STN2_TX_DN<41>")
	)
	(segment
		(start 56.801004 -119.31269)
		(end 55.471822 -135.163052)
		(width 0.1651)
		(layer "In11.Cu")
		(net "P5E_PEX0_STN2_TX_DN<41>")
	)
	(segment
		(start 48.688752 -30.34792)
		(end 49.119536 -30.525212)
		(width 0.1651)
		(layer "In11.Cu")
		(net "P5E_PEX0_STN2_TX_DN<41>")
	)
	(segment
		(start 49.099724 -252.662436)
		(end 49.451514 -266.126976)
		(width 0.1651)
		(layer "In11.Cu")
		(net "P5E_PEX0_STN2_TX_DN<41>")
	)
	(segment
		(start 137.75309 -34.2265)
		(end 137.121138 -34.2265)
		(width 0.13462)
		(layer "F.Cu")
		(net "P5E_PEX1_STN2_TX_DP<47>")
	)
	(segment
		(start 138.047476 -34.520886)
		(end 137.75309 -34.2265)
		(width 0.13462)
		(layer "F.Cu")
		(net "P5E_PEX1_STN2_TX_DP<47>")
	)
	(segment
		(start 137.121138 -34.2265)
		(end 136.801352 -34.546286)
		(width 0.13462)
		(layer "F.Cu")
		(net "P5E_PEX1_STN2_TX_DP<47>")
	)
	(segment
		(start 159.933894 -271.427448)
		(end 159.979614 -271.473168)
		(width 0.1143)
		(layer "In11.Cu")
		(net "P5E_PEX1_STN2_TX_DP<47>")
	)
	(segment
		(start 160.435544 -278.420068)
		(end 160.549844 -278.534368)
		(width 0.1143)
		(layer "In11.Cu")
		(net "P5E_PEX1_STN2_TX_DP<47>")
	)
	(segment
		(start 160.194752 -278.420068)
		(end 160.435544 -278.420068)
		(width 0.1143)
		(layer "In11.Cu")
		(net "P5E_PEX1_STN2_TX_DP<47>")
	)
	(segment
		(start 151.377904 -78.883256)
		(end 147.86229 -104.563164)
		(width 0.1651)
		(layer "In11.Cu")
		(net "P5E_PEX1_STN2_TX_DP<47>")
	)
	(segment
		(start 138.809222 -34.230056)
		(end 139.146026 -34.391854)
		(width 0.1651)
		(layer "In11.Cu")
		(net "P5E_PEX1_STN2_TX_DP<47>")
	)
	(segment
		(start 152.23617 -62.637416)
		(end 151.377904 -78.883256)
		(width 0.1651)
		(layer "In11.Cu")
		(net "P5E_PEX1_STN2_TX_DP<47>")
	)
	(segment
		(start 141.235176 -36.436046)
		(end 141.217396 -36.596574)
		(width 0.1651)
		(layer "In11.Cu")
		(net "P5E_PEX1_STN2_TX_DP<47>")
	)
	(segment
		(start 141.217396 -36.596574)
		(end 141.527022 -36.98367)
		(width 0.1651)
		(layer "In11.Cu")
		(net "P5E_PEX1_STN2_TX_DP<47>")
	)
	(segment
		(start 159.979614 -271.473168)
		(end 159.979614 -278.20493)
		(width 0.1143)
		(layer "In11.Cu")
		(net "P5E_PEX1_STN2_TX_DP<47>")
	)
	(segment
		(start 151.560784 -50.678842)
		(end 152.23617 -62.637416)
		(width 0.1651)
		(layer "In11.Cu")
		(net "P5E_PEX1_STN2_TX_DP<47>")
	)
	(segment
		(start 160.549844 -278.534368)
		(end 160.549844 -278.799798)
		(width 0.1143)
		(layer "In11.Cu")
		(net "P5E_PEX1_STN2_TX_DP<47>")
	)
	(segment
		(start 147.86229 -104.563164)
		(end 147.188174 -117.070886)
		(width 0.1651)
		(layer "In11.Cu")
		(net "P5E_PEX1_STN2_TX_DP<47>")
	)
	(segment
		(start 140.393928 -35.384486)
		(end 141.235176 -36.436046)
		(width 0.1651)
		(layer "In11.Cu")
		(net "P5E_PEX1_STN2_TX_DP<47>")
	)
	(segment
		(start 158.903162 -264.543286)
		(end 159.933894 -270.752062)
		(width 0.1651)
		(layer "In11.Cu")
		(net "P5E_PEX1_STN2_TX_DP<47>")
	)
	(segment
		(start 150.086314 -47.499778)
		(end 151.087328 -49.31283)
		(width 0.1651)
		(layer "In11.Cu")
		(net "P5E_PEX1_STN2_TX_DP<47>")
	)
	(segment
		(start 159.933894 -271.399)
		(end 159.933894 -271.427448)
		(width 0.1143)
		(layer "In11.Cu")
		(net "P5E_PEX1_STN2_TX_DP<47>")
	)
	(segment
		(start 159.933894 -270.752062)
		(end 159.933894 -271.399)
		(width 0.1651)
		(layer "In11.Cu")
		(net "P5E_PEX1_STN2_TX_DP<47>")
	)
	(segment
		(start 138.047476 -34.520886)
		(end 138.338306 -34.230056)
		(width 0.1651)
		(layer "In11.Cu")
		(net "P5E_PEX1_STN2_TX_DP<47>")
	)
	(segment
		(start 141.527022 -36.98367)
		(end 141.68755 -37.00145)
		(width 0.1651)
		(layer "In11.Cu")
		(net "P5E_PEX1_STN2_TX_DP<47>")
	)
	(segment
		(start 147.188174 -117.070886)
		(end 147.70227 -138.242294)
		(width 0.1651)
		(layer "In11.Cu")
		(net "P5E_PEX1_STN2_TX_DP<47>")
	)
	(segment
		(start 141.68755 -37.00145)
		(end 150.086314 -47.499778)
		(width 0.1651)
		(layer "In11.Cu")
		(net "P5E_PEX1_STN2_TX_DP<47>")
	)
	(segment
		(start 151.087328 -49.31283)
		(end 151.560784 -50.678842)
		(width 0.1651)
		(layer "In11.Cu")
		(net "P5E_PEX1_STN2_TX_DP<47>")
	)
	(segment
		(start 139.146026 -34.391854)
		(end 140.393928 -35.384486)
		(width 0.1651)
		(layer "In11.Cu")
		(net "P5E_PEX1_STN2_TX_DP<47>")
	)
	(segment
		(start 147.70227 -138.242294)
		(end 158.903162 -264.543286)
		(width 0.1651)
		(layer "In11.Cu")
		(net "P5E_PEX1_STN2_TX_DP<47>")
	)
	(segment
		(start 159.979614 -278.20493)
		(end 160.194752 -278.420068)
		(width 0.1143)
		(layer "In11.Cu")
		(net "P5E_PEX1_STN2_TX_DP<47>")
	)
	(segment
		(start 138.338306 -34.230056)
		(end 138.809222 -34.230056)
		(width 0.1651)
		(layer "In11.Cu")
		(net "P5E_PEX1_STN2_TX_DP<47>")
	)
	(segment
		(start 253.852934 -34.2265)
		(end 253.220982 -34.2265)
		(width 0.13462)
		(layer "F.Cu")
		(net "P5E_PEX2_STN2_TX_DP<47>")
	)
	(segment
		(start 254.14732 -34.520886)
		(end 253.852934 -34.2265)
		(width 0.13462)
		(layer "F.Cu")
		(net "P5E_PEX2_STN2_TX_DP<47>")
	)
	(segment
		(start 253.220982 -34.2265)
		(end 252.901196 -34.546286)
		(width 0.13462)
		(layer "F.Cu")
		(net "P5E_PEX2_STN2_TX_DP<47>")
	)
	(segment
		(start 276.079458 -271.473168)
		(end 276.079458 -278.20493)
		(width 0.1143)
		(layer "In11.Cu")
		(net "P5E_PEX2_STN2_TX_DP<47>")
	)
	(segment
		(start 268.336014 -62.637416)
		(end 267.477748 -78.883256)
		(width 0.1651)
		(layer "In11.Cu")
		(net "P5E_PEX2_STN2_TX_DP<47>")
	)
	(segment
		(start 254.909066 -34.230056)
		(end 255.24587 -34.391854)
		(width 0.1651)
		(layer "In11.Cu")
		(net "P5E_PEX2_STN2_TX_DP<47>")
	)
	(segment
		(start 276.535388 -278.420068)
		(end 276.649688 -278.534368)
		(width 0.1143)
		(layer "In11.Cu")
		(net "P5E_PEX2_STN2_TX_DP<47>")
	)
	(segment
		(start 263.288018 -117.070886)
		(end 263.802114 -138.242294)
		(width 0.1651)
		(layer "In11.Cu")
		(net "P5E_PEX2_STN2_TX_DP<47>")
	)
	(segment
		(start 276.649688 -278.534368)
		(end 276.649688 -278.799798)
		(width 0.1143)
		(layer "In11.Cu")
		(net "P5E_PEX2_STN2_TX_DP<47>")
	)
	(segment
		(start 275.003006 -264.543286)
		(end 276.033738 -270.752062)
		(width 0.1651)
		(layer "In11.Cu")
		(net "P5E_PEX2_STN2_TX_DP<47>")
	)
	(segment
		(start 276.033738 -271.399)
		(end 276.033738 -271.427448)
		(width 0.1143)
		(layer "In11.Cu")
		(net "P5E_PEX2_STN2_TX_DP<47>")
	)
	(segment
		(start 263.802114 -138.242294)
		(end 275.003006 -264.543286)
		(width 0.1651)
		(layer "In11.Cu")
		(net "P5E_PEX2_STN2_TX_DP<47>")
	)
	(segment
		(start 266.186158 -47.499778)
		(end 267.187172 -49.31283)
		(width 0.1651)
		(layer "In11.Cu")
		(net "P5E_PEX2_STN2_TX_DP<47>")
	)
	(segment
		(start 255.24587 -34.391854)
		(end 256.493772 -35.384486)
		(width 0.1651)
		(layer "In11.Cu")
		(net "P5E_PEX2_STN2_TX_DP<47>")
	)
	(segment
		(start 257.787394 -37.00145)
		(end 266.186158 -47.499778)
		(width 0.1651)
		(layer "In11.Cu")
		(net "P5E_PEX2_STN2_TX_DP<47>")
	)
	(segment
		(start 257.626866 -36.98367)
		(end 257.787394 -37.00145)
		(width 0.1651)
		(layer "In11.Cu")
		(net "P5E_PEX2_STN2_TX_DP<47>")
	)
	(segment
		(start 276.033738 -270.752062)
		(end 276.033738 -271.399)
		(width 0.1651)
		(layer "In11.Cu")
		(net "P5E_PEX2_STN2_TX_DP<47>")
	)
	(segment
		(start 276.079458 -278.20493)
		(end 276.294596 -278.420068)
		(width 0.1143)
		(layer "In11.Cu")
		(net "P5E_PEX2_STN2_TX_DP<47>")
	)
	(segment
		(start 257.33502 -36.436046)
		(end 257.31724 -36.596574)
		(width 0.1651)
		(layer "In11.Cu")
		(net "P5E_PEX2_STN2_TX_DP<47>")
	)
	(segment
		(start 276.294596 -278.420068)
		(end 276.535388 -278.420068)
		(width 0.1143)
		(layer "In11.Cu")
		(net "P5E_PEX2_STN2_TX_DP<47>")
	)
	(segment
		(start 267.660628 -50.678842)
		(end 268.336014 -62.637416)
		(width 0.1651)
		(layer "In11.Cu")
		(net "P5E_PEX2_STN2_TX_DP<47>")
	)
	(segment
		(start 254.14732 -34.520886)
		(end 254.43815 -34.230056)
		(width 0.1651)
		(layer "In11.Cu")
		(net "P5E_PEX2_STN2_TX_DP<47>")
	)
	(segment
		(start 256.493772 -35.384486)
		(end 257.33502 -36.436046)
		(width 0.1651)
		(layer "In11.Cu")
		(net "P5E_PEX2_STN2_TX_DP<47>")
	)
	(segment
		(start 267.477748 -78.883256)
		(end 263.962134 -104.563164)
		(width 0.1651)
		(layer "In11.Cu")
		(net "P5E_PEX2_STN2_TX_DP<47>")
	)
	(segment
		(start 254.43815 -34.230056)
		(end 254.909066 -34.230056)
		(width 0.1651)
		(layer "In11.Cu")
		(net "P5E_PEX2_STN2_TX_DP<47>")
	)
	(segment
		(start 263.962134 -104.563164)
		(end 263.288018 -117.070886)
		(width 0.1651)
		(layer "In11.Cu")
		(net "P5E_PEX2_STN2_TX_DP<47>")
	)
	(segment
		(start 257.31724 -36.596574)
		(end 257.626866 -36.98367)
		(width 0.1651)
		(layer "In11.Cu")
		(net "P5E_PEX2_STN2_TX_DP<47>")
	)
	(segment
		(start 267.187172 -49.31283)
		(end 267.660628 -50.678842)
		(width 0.1651)
		(layer "In11.Cu")
		(net "P5E_PEX2_STN2_TX_DP<47>")
	)
	(segment
		(start 276.033738 -271.427448)
		(end 276.079458 -271.473168)
		(width 0.1143)
		(layer "In11.Cu")
		(net "P5E_PEX2_STN2_TX_DP<47>")
	)
	(segment
		(start 383.713482 -105.00868)
		(end 384.358642 -105.00868)
		(width 0.13462)
		(layer "F.Cu")
		(net "P5E_PEX3_STN1_TX_DN<19>")
	)
	(segment
		(start 384.358642 -105.00868)
		(end 384.671824 -104.695498)
		(width 0.13462)
		(layer "F.Cu")
		(net "P5E_PEX3_STN1_TX_DN<19>")
	)
	(segment
		(start 383.4257 -104.720898)
		(end 383.713482 -105.00868)
		(width 0.13462)
		(layer "F.Cu")
		(net "P5E_PEX3_STN1_TX_DN<19>")
	)
	(segment
		(start 410.685488 -280.319988)
		(end 410.799788 -280.434288)
		(width 0.1143)
		(layer "In9.Cu")
		(net "P5E_PEX3_STN1_TX_DN<19>")
	)
	(segment
		(start 373.970804 -144.659096)
		(end 374.327928 -151.935942)
		(width 0.1651)
		(layer "In9.Cu")
		(net "P5E_PEX3_STN1_TX_DN<19>")
	)
	(segment
		(start 382.472692 -105.011728)
		(end 379.258322 -108.226098)
		(width 0.1651)
		(layer "In9.Cu")
		(net "P5E_PEX3_STN1_TX_DN<19>")
	)
	(segment
		(start 383.13487 -105.011728)
		(end 382.472692 -105.011728)
		(width 0.1651)
		(layer "In9.Cu")
		(net "P5E_PEX3_STN1_TX_DN<19>")
	)
	(segment
		(start 374.327928 -151.935688)
		(end 374.506236 -155.565094)
		(width 0.1651)
		(layer "In9.Cu")
		(net "P5E_PEX3_STN1_TX_DN<19>")
	)
	(segment
		(start 410.799788 -280.434288)
		(end 410.799788 -280.699718)
		(width 0.1143)
		(layer "In9.Cu")
		(net "P5E_PEX3_STN1_TX_DN<19>")
	)
	(segment
		(start 379.258322 -108.226098)
		(end 379.257814 -108.226098)
		(width 0.1651)
		(layer "In9.Cu")
		(net "P5E_PEX3_STN1_TX_DN<19>")
	)
	(segment
		(start 374.506236 -155.565094)
		(end 374.685306 -159.213042)
		(width 0.1651)
		(layer "In9.Cu")
		(net "P5E_PEX3_STN1_TX_DN<19>")
	)
	(segment
		(start 371.408452 -131.059428)
		(end 371.408452 -138.47318)
		(width 0.1651)
		(layer "In9.Cu")
		(net "P5E_PEX3_STN1_TX_DN<19>")
	)
	(segment
		(start 375.291858 -162.262312)
		(end 410.183838 -265.345164)
		(width 0.1651)
		(layer "In9.Cu")
		(net "P5E_PEX3_STN1_TX_DN<19>")
	)
	(segment
		(start 410.183838 -271.554448)
		(end 410.229558 -271.600168)
		(width 0.1143)
		(layer "In9.Cu")
		(net "P5E_PEX3_STN1_TX_DN<19>")
	)
	(segment
		(start 374.685306 -159.213042)
		(end 375.291858 -162.262312)
		(width 0.1651)
		(layer "In9.Cu")
		(net "P5E_PEX3_STN1_TX_DN<19>")
	)
	(segment
		(start 410.183838 -265.345164)
		(end 410.183838 -271.526)
		(width 0.1651)
		(layer "In9.Cu")
		(net "P5E_PEX3_STN1_TX_DN<19>")
	)
	(segment
		(start 375.80824 -116.556028)
		(end 371.408452 -131.059428)
		(width 0.1651)
		(layer "In9.Cu")
		(net "P5E_PEX3_STN1_TX_DN<19>")
	)
	(segment
		(start 410.229558 -271.600168)
		(end 410.229558 -280.10485)
		(width 0.1143)
		(layer "In9.Cu")
		(net "P5E_PEX3_STN1_TX_DN<19>")
	)
	(segment
		(start 371.408452 -138.47318)
		(end 373.970804 -144.659096)
		(width 0.1651)
		(layer "In9.Cu")
		(net "P5E_PEX3_STN1_TX_DN<19>")
	)
	(segment
		(start 383.4257 -104.720898)
		(end 383.13487 -105.011728)
		(width 0.1651)
		(layer "In9.Cu")
		(net "P5E_PEX3_STN1_TX_DN<19>")
	)
	(segment
		(start 379.257814 -108.226098)
		(end 375.80824 -116.556028)
		(width 0.1651)
		(layer "In9.Cu")
		(net "P5E_PEX3_STN1_TX_DN<19>")
	)
	(segment
		(start 374.327928 -151.935942)
		(end 374.327928 -151.935688)
		(width 0.1651)
		(layer "In9.Cu")
		(net "P5E_PEX3_STN1_TX_DN<19>")
	)
	(segment
		(start 410.183838 -271.526)
		(end 410.183838 -271.554448)
		(width 0.1143)
		(layer "In9.Cu")
		(net "P5E_PEX3_STN1_TX_DN<19>")
	)
	(segment
		(start 410.229558 -280.10485)
		(end 410.444696 -280.319988)
		(width 0.1143)
		(layer "In9.Cu")
		(net "P5E_PEX3_STN1_TX_DN<19>")
	)
	(segment
		(start 410.444696 -280.319988)
		(end 410.685488 -280.319988)
		(width 0.1143)
		(layer "In9.Cu")
		(net "P5E_PEX3_STN1_TX_DN<19>")
	)
	(segment
		(start 412.972504 -348.880938)
		(end 413.267652 -348.58579)
		(width 0.13462)
		(layer "F.Cu")
		(net "P5E_PEX3_STN7_TX_DN<113>")
	)
	(segment
		(start 413.293052 -349.831914)
		(end 412.972504 -349.511366)
		(width 0.13462)
		(layer "F.Cu")
		(net "P5E_PEX3_STN7_TX_DN<113>")
	)
	(segment
		(start 412.972504 -349.511366)
		(end 412.972504 -348.880938)
		(width 0.13462)
		(layer "F.Cu")
		(net "P5E_PEX3_STN7_TX_DN<113>")
	)
	(segment
		(start 365.56442 -318.678052)
		(end 367.380266 -314.294012)
		(width 0.1651)
		(layer "In11.Cu")
		(net "P5E_PEX3_STN7_TX_DN<113>")
	)
	(segment
		(start 372.830598 -306.136802)
		(end 373.761762 -305.205638)
		(width 0.1651)
		(layer "In11.Cu")
		(net "P5E_PEX3_STN7_TX_DN<113>")
	)
	(segment
		(start 371.423438 -308.42585)
		(end 371.395244 -308.285134)
		(width 0.1651)
		(layer "In11.Cu")
		(net "P5E_PEX3_STN7_TX_DN<113>")
	)
	(segment
		(start 370.484654 -309.830724)
		(end 370.75999 -309.418736)
		(width 0.1651)
		(layer "In11.Cu")
		(net "P5E_PEX3_STN7_TX_DN<113>")
	)
	(segment
		(start 371.670326 -307.873146)
		(end 371.811296 -307.845206)
		(width 0.1651)
		(layer "In11.Cu")
		(net "P5E_PEX3_STN7_TX_DN<113>")
	)
	(segment
		(start 375.100342 -304.010822)
		(end 375.100342 -303.867058)
		(width 0.1651)
		(layer "In11.Cu")
		(net "P5E_PEX3_STN7_TX_DN<113>")
	)
	(segment
		(start 373.761762 -305.205638)
		(end 373.905526 -305.205638)
		(width 0.1651)
		(layer "In11.Cu")
		(net "P5E_PEX3_STN7_TX_DN<113>")
	)
	(segment
		(start 392.179556 -302.24984)
		(end 392.179556 -302.435514)
		(width 0.1143)
		(layer "In11.Cu")
		(net "P5E_PEX3_STN7_TX_DN<113>")
	)
	(segment
		(start 414.090612 -341.347044)
		(end 413.4739 -340.90229)
		(width 0.1651)
		(layer "In11.Cu")
		(net "P5E_PEX3_STN7_TX_DN<113>")
	)
	(segment
		(start 369.680744 -310.85155)
		(end 369.680236 -310.851296)
		(width 0.1651)
		(layer "In11.Cu")
		(net "P5E_PEX3_STN7_TX_DN<113>")
	)
	(segment
		(start 413.4739 -340.90229)
		(end 373.812562 -332.203298)
		(width 0.1651)
		(layer "In11.Cu")
		(net "P5E_PEX3_STN7_TX_DN<113>")
	)
	(segment
		(start 414.531302 -342.086946)
		(end 414.090612 -341.347044)
		(width 0.1651)
		(layer "In11.Cu")
		(net "P5E_PEX3_STN7_TX_DN<113>")
	)
	(segment
		(start 369.157758 -311.815988)
		(end 369.433348 -311.404)
		(width 0.1651)
		(layer "In11.Cu")
		(net "P5E_PEX3_STN7_TX_DN<113>")
	)
	(segment
		(start 369.017042 -311.844436)
		(end 369.017042 -311.844182)
		(width 0.1651)
		(layer "In11.Cu")
		(net "P5E_PEX3_STN7_TX_DN<113>")
	)
	(segment
		(start 372.058692 -307.292248)
		(end 372.830598 -306.136802)
		(width 0.1651)
		(layer "In11.Cu")
		(net "P5E_PEX3_STN7_TX_DN<113>")
	)
	(segment
		(start 375.552716 -303.414684)
		(end 378.4473 -302.215804)
		(width 0.1651)
		(layer "In11.Cu")
		(net "P5E_PEX3_STN7_TX_DN<113>")
	)
	(segment
		(start 370.73205 -309.277766)
		(end 371.007132 -308.866032)
		(width 0.1651)
		(layer "In11.Cu")
		(net "P5E_PEX3_STN7_TX_DN<113>")
	)
	(segment
		(start 371.67058 -307.873146)
		(end 371.670326 -307.873146)
		(width 0.1651)
		(layer "In11.Cu")
		(net "P5E_PEX3_STN7_TX_DN<113>")
	)
	(segment
		(start 374.256046 -304.711354)
		(end 374.606058 -304.361342)
		(width 0.1651)
		(layer "In11.Cu")
		(net "P5E_PEX3_STN7_TX_DN<113>")
	)
	(segment
		(start 392.0998 -302.170084)
		(end 392.179556 -302.24984)
		(width 0.1143)
		(layer "In11.Cu")
		(net "P5E_PEX3_STN7_TX_DN<113>")
	)
	(segment
		(start 370.343684 -309.858664)
		(end 370.484654 -309.830724)
		(width 0.1651)
		(layer "In11.Cu")
		(net "P5E_PEX3_STN7_TX_DN<113>")
	)
	(segment
		(start 378.4473 -302.215804)
		(end 383.921 -302.215804)
		(width 0.1651)
		(layer "In11.Cu")
		(net "P5E_PEX3_STN7_TX_DN<113>")
	)
	(segment
		(start 371.006878 -308.865778)
		(end 371.147848 -308.837838)
		(width 0.1651)
		(layer "In11.Cu")
		(net "P5E_PEX3_STN7_TX_DN<113>")
	)
	(segment
		(start 369.405154 -311.26303)
		(end 369.405408 -311.263284)
		(width 0.1651)
		(layer "In11.Cu")
		(net "P5E_PEX3_STN7_TX_DN<113>")
	)
	(segment
		(start 392.065256 -302.549814)
		(end 391.799826 -302.549814)
		(width 0.1143)
		(layer "In11.Cu")
		(net "P5E_PEX3_STN7_TX_DN<113>")
	)
	(segment
		(start 370.068602 -310.270398)
		(end 370.343684 -309.858664)
		(width 0.1651)
		(layer "In11.Cu")
		(net "P5E_PEX3_STN7_TX_DN<113>")
	)
	(segment
		(start 367.542064 -327.478644)
		(end 365.56442 -322.703952)
		(width 0.1651)
		(layer "In11.Cu")
		(net "P5E_PEX3_STN7_TX_DN<113>")
	)
	(segment
		(start 365.56442 -322.703952)
		(end 365.56442 -318.678052)
		(width 0.1651)
		(layer "In11.Cu")
		(net "P5E_PEX3_STN7_TX_DN<113>")
	)
	(segment
		(start 413.267652 -348.58579)
		(end 412.976822 -348.29496)
		(width 0.1651)
		(layer "In11.Cu")
		(net "P5E_PEX3_STN7_TX_DN<113>")
	)
	(segment
		(start 367.380266 -314.294012)
		(end 369.017042 -311.844436)
		(width 0.1651)
		(layer "In11.Cu")
		(net "P5E_PEX3_STN7_TX_DN<113>")
	)
	(segment
		(start 370.398802 -330.335382)
		(end 367.542064 -327.478644)
		(width 0.1651)
		(layer "In11.Cu")
		(net "P5E_PEX3_STN7_TX_DN<113>")
	)
	(segment
		(start 369.433348 -311.404)
		(end 369.405154 -311.26303)
		(width 0.1651)
		(layer "In11.Cu")
		(net "P5E_PEX3_STN7_TX_DN<113>")
	)
	(segment
		(start 383.949448 -302.215804)
		(end 383.995168 -302.170084)
		(width 0.1143)
		(layer "In11.Cu")
		(net "P5E_PEX3_STN7_TX_DN<113>")
	)
	(segment
		(start 374.606058 -304.361342)
		(end 374.749822 -304.361342)
		(width 0.1651)
		(layer "In11.Cu")
		(net "P5E_PEX3_STN7_TX_DN<113>")
	)
	(segment
		(start 392.179556 -302.435514)
		(end 392.065256 -302.549814)
		(width 0.1143)
		(layer "In11.Cu")
		(net "P5E_PEX3_STN7_TX_DN<113>")
	)
	(segment
		(start 372.086632 -307.433218)
		(end 372.058692 -307.292248)
		(width 0.1651)
		(layer "In11.Cu")
		(net "P5E_PEX3_STN7_TX_DN<113>")
	)
	(segment
		(start 370.096796 -310.411368)
		(end 370.068602 -310.270398)
		(width 0.1651)
		(layer "In11.Cu")
		(net "P5E_PEX3_STN7_TX_DN<113>")
	)
	(segment
		(start 374.749822 -304.361342)
		(end 375.100342 -304.010822)
		(width 0.1651)
		(layer "In11.Cu")
		(net "P5E_PEX3_STN7_TX_DN<113>")
	)
	(segment
		(start 370.75999 -309.418736)
		(end 370.73205 -309.277766)
		(width 0.1651)
		(layer "In11.Cu")
		(net "P5E_PEX3_STN7_TX_DN<113>")
	)
	(segment
		(start 383.995168 -302.170084)
		(end 392.0998 -302.170084)
		(width 0.1143)
		(layer "In11.Cu")
		(net "P5E_PEX3_STN7_TX_DN<113>")
	)
	(segment
		(start 373.812562 -332.203298)
		(end 370.398802 -330.335382)
		(width 0.1651)
		(layer "In11.Cu")
		(net "P5E_PEX3_STN7_TX_DN<113>")
	)
	(segment
		(start 369.405408 -311.263284)
		(end 369.680744 -310.85155)
		(width 0.1651)
		(layer "In11.Cu")
		(net "P5E_PEX3_STN7_TX_DN<113>")
	)
	(segment
		(start 412.976822 -347.784674)
		(end 414.531302 -346.230194)
		(width 0.1651)
		(layer "In11.Cu")
		(net "P5E_PEX3_STN7_TX_DN<113>")
	)
	(segment
		(start 374.256046 -304.855118)
		(end 374.256046 -304.711354)
		(width 0.1651)
		(layer "In11.Cu")
		(net "P5E_PEX3_STN7_TX_DN<113>")
	)
	(segment
		(start 371.395244 -308.285134)
		(end 371.67058 -307.873146)
		(width 0.1651)
		(layer "In11.Cu")
		(net "P5E_PEX3_STN7_TX_DN<113>")
	)
	(segment
		(start 371.811296 -307.845206)
		(end 372.086632 -307.433218)
		(width 0.1651)
		(layer "In11.Cu")
		(net "P5E_PEX3_STN7_TX_DN<113>")
	)
	(segment
		(start 369.017042 -311.844182)
		(end 369.157758 -311.815988)
		(width 0.1651)
		(layer "In11.Cu")
		(net "P5E_PEX3_STN7_TX_DN<113>")
	)
	(segment
		(start 371.147848 -308.837838)
		(end 371.423438 -308.42585)
		(width 0.1651)
		(layer "In11.Cu")
		(net "P5E_PEX3_STN7_TX_DN<113>")
	)
	(segment
		(start 414.531302 -346.230194)
		(end 414.531302 -342.086946)
		(width 0.1651)
		(layer "In11.Cu")
		(net "P5E_PEX3_STN7_TX_DN<113>")
	)
	(segment
		(start 373.905526 -305.205638)
		(end 374.256046 -304.855118)
		(width 0.1651)
		(layer "In11.Cu")
		(net "P5E_PEX3_STN7_TX_DN<113>")
	)
	(segment
		(start 369.821206 -310.823356)
		(end 370.096796 -310.411368)
		(width 0.1651)
		(layer "In11.Cu")
		(net "P5E_PEX3_STN7_TX_DN<113>")
	)
	(segment
		(start 412.976822 -348.29496)
		(end 412.976822 -347.784674)
		(width 0.1651)
		(layer "In11.Cu")
		(net "P5E_PEX3_STN7_TX_DN<113>")
	)
	(segment
		(start 369.680236 -310.851296)
		(end 369.821206 -310.823356)
		(width 0.1651)
		(layer "In11.Cu")
		(net "P5E_PEX3_STN7_TX_DN<113>")
	)
	(segment
		(start 371.007132 -308.866032)
		(end 371.006878 -308.865778)
		(width 0.1651)
		(layer "In11.Cu")
		(net "P5E_PEX3_STN7_TX_DN<113>")
	)
	(segment
		(start 383.921 -302.215804)
		(end 383.949448 -302.215804)
		(width 0.1143)
		(layer "In11.Cu")
		(net "P5E_PEX3_STN7_TX_DN<113>")
	)
	(segment
		(start 375.100342 -303.867058)
		(end 375.552716 -303.414684)
		(width 0.1651)
		(layer "In11.Cu")
		(net "P5E_PEX3_STN7_TX_DN<113>")
	)
	(segment
		(start 71.01967 -32.13608)
		(end 70.369938 -32.13608)
		(width 0.13462)
		(layer "F.Cu")
		(net "P5E_PEX0_STN2_TX_DN<38>")
	)
	(segment
		(start 70.369938 -32.13608)
		(end 70.059042 -31.825184)
		(width 0.13462)
		(layer "F.Cu")
		(net "P5E_PEX0_STN2_TX_DN<38>")
	)
	(segment
		(start 71.305166 -31.850584)
		(end 71.01967 -32.13608)
		(width 0.13462)
		(layer "F.Cu")
		(net "P5E_PEX0_STN2_TX_DN<38>")
	)
	(segment
		(start 52.723796 -280.129488)
		(end 52.885594 -280.129488)
		(width 0.1143)
		(layer "In11.Cu")
		(net "P5E_PEX0_STN2_TX_DN<38>")
	)
	(segment
		(start 60.781438 -115.457732)
		(end 60.091066 -121.058686)
		(width 0.1651)
		(layer "In11.Cu")
		(net "P5E_PEX0_STN2_TX_DN<38>")
	)
	(segment
		(start 81.511902 -41.298876)
		(end 88.213438 -48.575468)
		(width 0.1651)
		(layer "In11.Cu")
		(net "P5E_PEX0_STN2_TX_DN<38>")
	)
	(segment
		(start 89.243662 -60.348876)
		(end 88.706198 -62.36716)
		(width 0.1651)
		(layer "In11.Cu")
		(net "P5E_PEX0_STN2_TX_DN<38>")
	)
	(segment
		(start 88.213438 -48.575468)
		(end 89.243662 -58.49747)
		(width 0.1651)
		(layer "In11.Cu")
		(net "P5E_PEX0_STN2_TX_DN<38>")
	)
	(segment
		(start 52.885594 -280.129488)
		(end 52.999894 -280.015188)
		(width 0.1143)
		(layer "In11.Cu")
		(net "P5E_PEX0_STN2_TX_DN<38>")
	)
	(segment
		(start 88.706198 -62.36716)
		(end 87.790528 -64.219836)
		(width 0.1651)
		(layer "In11.Cu")
		(net "P5E_PEX0_STN2_TX_DN<38>")
	)
	(segment
		(start 73.764648 -32.141414)
		(end 75.550522 -32.78378)
		(width 0.1651)
		(layer "In11.Cu")
		(net "P5E_PEX0_STN2_TX_DN<38>")
	)
	(segment
		(start 87.790528 -64.219836)
		(end 65.648586 -93.193108)
		(width 0.1651)
		(layer "In11.Cu")
		(net "P5E_PEX0_STN2_TX_DN<38>")
	)
	(segment
		(start 89.243662 -58.49747)
		(end 89.243662 -60.348876)
		(width 0.1651)
		(layer "In11.Cu")
		(net "P5E_PEX0_STN2_TX_DN<38>")
	)
	(segment
		(start 71.595996 -32.141414)
		(end 73.764648 -32.141414)
		(width 0.1651)
		(layer "In11.Cu")
		(net "P5E_PEX0_STN2_TX_DN<38>")
	)
	(segment
		(start 77.361796 -34.539936)
		(end 81.511902 -41.298876)
		(width 0.1651)
		(layer "In11.Cu")
		(net "P5E_PEX0_STN2_TX_DN<38>")
	)
	(segment
		(start 71.305166 -31.850584)
		(end 71.595996 -32.141414)
		(width 0.1651)
		(layer "In11.Cu")
		(net "P5E_PEX0_STN2_TX_DN<38>")
	)
	(segment
		(start 52.620164 -280.025856)
		(end 52.723796 -280.129488)
		(width 0.1143)
		(layer "In11.Cu")
		(net "P5E_PEX0_STN2_TX_DN<38>")
	)
	(segment
		(start 52.665884 -263.18337)
		(end 52.665884 -271.399)
		(width 0.1651)
		(layer "In11.Cu")
		(net "P5E_PEX0_STN2_TX_DN<38>")
	)
	(segment
		(start 52.620164 -271.473168)
		(end 52.620164 -280.025856)
		(width 0.1143)
		(layer "In11.Cu")
		(net "P5E_PEX0_STN2_TX_DN<38>")
	)
	(segment
		(start 52.665884 -271.427448)
		(end 52.620164 -271.473168)
		(width 0.1143)
		(layer "In11.Cu")
		(net "P5E_PEX0_STN2_TX_DN<38>")
	)
	(segment
		(start 62.301374 -107.679744)
		(end 60.781438 -115.457732)
		(width 0.1651)
		(layer "In11.Cu")
		(net "P5E_PEX0_STN2_TX_DN<38>")
	)
	(segment
		(start 52.999894 -280.015188)
		(end 52.999894 -279.749504)
		(width 0.1143)
		(layer "In11.Cu")
		(net "P5E_PEX0_STN2_TX_DN<38>")
	)
	(segment
		(start 60.091066 -121.058686)
		(end 52.665884 -263.18337)
		(width 0.1651)
		(layer "In11.Cu")
		(net "P5E_PEX0_STN2_TX_DN<38>")
	)
	(segment
		(start 65.648586 -93.193108)
		(end 62.301374 -107.679744)
		(width 0.1651)
		(layer "In11.Cu")
		(net "P5E_PEX0_STN2_TX_DN<38>")
	)
	(segment
		(start 52.665884 -271.399)
		(end 52.665884 -271.427448)
		(width 0.1143)
		(layer "In11.Cu")
		(net "P5E_PEX0_STN2_TX_DN<38>")
	)
	(segment
		(start 75.550522 -32.78378)
		(end 77.361796 -34.539936)
		(width 0.1651)
		(layer "In11.Cu")
		(net "P5E_PEX0_STN2_TX_DN<38>")
	)
	(segment
		(start 131.084828 -348.88043)
		(end 131.379468 -348.58579)
		(width 0.13462)
		(layer "F.Cu")
		(net "P5E_PEX1_STN5_TX_DN<81>")
	)
	(segment
		(start 131.084828 -349.511874)
		(end 131.084828 -348.88043)
		(width 0.13462)
		(layer "F.Cu")
		(net "P5E_PEX1_STN5_TX_DN<81>")
	)
	(segment
		(start 131.404868 -349.831914)
		(end 131.084828 -349.511874)
		(width 0.13462)
		(layer "F.Cu")
		(net "P5E_PEX1_STN5_TX_DN<81>")
	)
	(segment
		(start 175.749966 -313.684412)
		(end 175.749966 -313.949842)
		(width 0.1143)
		(layer "In7.Cu")
		(net "P5E_PEX1_STN5_TX_DN<81>")
	)
	(segment
		(start 132.643118 -341.211662)
		(end 133.730492 -340.124288)
		(width 0.1651)
		(layer "In7.Cu")
		(net "P5E_PEX1_STN5_TX_DN<81>")
	)
	(segment
		(start 175.415956 -319.97396)
		(end 175.370236 -319.92824)
		(width 0.1143)
		(layer "In7.Cu")
		(net "P5E_PEX1_STN5_TX_DN<81>")
	)
	(segment
		(start 175.415956 -322.85432)
		(end 175.415956 -320.002408)
		(width 0.1651)
		(layer "In7.Cu")
		(net "P5E_PEX1_STN5_TX_DN<81>")
	)
	(segment
		(start 131.088638 -348.29496)
		(end 131.088638 -347.736922)
		(width 0.1651)
		(layer "In7.Cu")
		(net "P5E_PEX1_STN5_TX_DN<81>")
	)
	(segment
		(start 135.819642 -338.872068)
		(end 169.27195 -328.72426)
		(width 0.1651)
		(layer "In7.Cu")
		(net "P5E_PEX1_STN5_TX_DN<81>")
	)
	(segment
		(start 131.379468 -348.58579)
		(end 131.088638 -348.29496)
		(width 0.1651)
		(layer "In7.Cu")
		(net "P5E_PEX1_STN5_TX_DN<81>")
	)
	(segment
		(start 133.730492 -340.124288)
		(end 135.819642 -338.872068)
		(width 0.1651)
		(layer "In7.Cu")
		(net "P5E_PEX1_STN5_TX_DN<81>")
	)
	(segment
		(start 132.643118 -346.182442)
		(end 132.643118 -341.211662)
		(width 0.1651)
		(layer "In7.Cu")
		(net "P5E_PEX1_STN5_TX_DN<81>")
	)
	(segment
		(start 174.625762 -324.762114)
		(end 175.415956 -322.85432)
		(width 0.1651)
		(layer "In7.Cu")
		(net "P5E_PEX1_STN5_TX_DN<81>")
	)
	(segment
		(start 175.370236 -319.92824)
		(end 175.370236 -313.684412)
		(width 0.1143)
		(layer "In7.Cu")
		(net "P5E_PEX1_STN5_TX_DN<81>")
	)
	(segment
		(start 175.415956 -320.002408)
		(end 175.415956 -319.97396)
		(width 0.1143)
		(layer "In7.Cu")
		(net "P5E_PEX1_STN5_TX_DN<81>")
	)
	(segment
		(start 172.74667 -326.641206)
		(end 174.625762 -324.762114)
		(width 0.1651)
		(layer "In7.Cu")
		(net "P5E_PEX1_STN5_TX_DN<81>")
	)
	(segment
		(start 169.27195 -328.72426)
		(end 172.74667 -326.641206)
		(width 0.1651)
		(layer "In7.Cu")
		(net "P5E_PEX1_STN5_TX_DN<81>")
	)
	(segment
		(start 175.484536 -313.570112)
		(end 175.635666 -313.570112)
		(width 0.1143)
		(layer "In7.Cu")
		(net "P5E_PEX1_STN5_TX_DN<81>")
	)
	(segment
		(start 175.370236 -313.684412)
		(end 175.484536 -313.570112)
		(width 0.1143)
		(layer "In7.Cu")
		(net "P5E_PEX1_STN5_TX_DN<81>")
	)
	(segment
		(start 131.088638 -347.736922)
		(end 132.643118 -346.182442)
		(width 0.1651)
		(layer "In7.Cu")
		(net "P5E_PEX1_STN5_TX_DN<81>")
	)
	(segment
		(start 175.635666 -313.570112)
		(end 175.749966 -313.684412)
		(width 0.1143)
		(layer "In7.Cu")
		(net "P5E_PEX1_STN5_TX_DN<81>")
	)
	(segment
		(start 322.124324 -355.026722)
		(end 322.124324 -355.658166)
		(width 0.13462)
		(layer "F.Cu")
		(net "P5E_PEX2_STN5_TX_DP<85>")
	)
	(segment
		(start 321.829684 -354.732082)
		(end 322.124324 -355.026722)
		(width 0.13462)
		(layer "F.Cu")
		(net "P5E_PEX2_STN5_TX_DP<85>")
	)
	(segment
		(start 322.124324 -355.658166)
		(end 321.804284 -355.978206)
		(width 0.13462)
		(layer "F.Cu")
		(net "P5E_PEX2_STN5_TX_DP<85>")
	)
	(segment
		(start 296.974768 -326.845168)
		(end 295.033954 -322.159884)
		(width 0.1651)
		(layer "In7.Cu")
		(net "P5E_PEX2_STN5_TX_DP<85>")
	)
	(segment
		(start 320.68516 -338.561426)
		(end 299.711618 -329.582272)
		(width 0.1651)
		(layer "In7.Cu")
		(net "P5E_PEX2_STN5_TX_DP<85>")
	)
	(segment
		(start 299.711618 -329.582272)
		(end 296.974768 -326.845168)
		(width 0.1651)
		(layer "In7.Cu")
		(net "P5E_PEX2_STN5_TX_DP<85>")
	)
	(segment
		(start 295.033954 -319.8368)
		(end 295.079674 -319.79108)
		(width 0.1143)
		(layer "In7.Cu")
		(net "P5E_PEX2_STN5_TX_DP<85>")
	)
	(segment
		(start 321.959224 -339.696552)
		(end 321.959224 -339.696298)
		(width 0.1651)
		(layer "In7.Cu")
		(net "P5E_PEX2_STN5_TX_DP<85>")
	)
	(segment
		(start 320.973196 -338.750402)
		(end 320.68516 -338.561426)
		(width 0.1651)
		(layer "In7.Cu")
		(net "P5E_PEX2_STN5_TX_DP<85>")
	)
	(segment
		(start 295.649904 -313.265312)
		(end 295.649904 -312.999882)
		(width 0.1143)
		(layer "In7.Cu")
		(net "P5E_PEX2_STN5_TX_DP<85>")
	)
	(segment
		(start 321.959224 -339.696298)
		(end 320.973196 -338.750402)
		(width 0.1651)
		(layer "In7.Cu")
		(net "P5E_PEX2_STN5_TX_DP<85>")
	)
	(segment
		(start 295.079674 -313.605418)
		(end 295.30548 -313.379612)
		(width 0.1143)
		(layer "In7.Cu")
		(net "P5E_PEX2_STN5_TX_DP<85>")
	)
	(segment
		(start 295.033954 -322.159884)
		(end 295.033954 -319.865248)
		(width 0.1651)
		(layer "In7.Cu")
		(net "P5E_PEX2_STN5_TX_DP<85>")
	)
	(segment
		(start 323.674994 -341.76462)
		(end 322.945252 -340.642702)
		(width 0.1651)
		(layer "In7.Cu")
		(net "P5E_PEX2_STN5_TX_DP<85>")
	)
	(segment
		(start 321.829684 -354.732082)
		(end 322.120514 -354.441252)
		(width 0.1651)
		(layer "In7.Cu")
		(net "P5E_PEX2_STN5_TX_DP<85>")
	)
	(segment
		(start 295.30548 -313.379612)
		(end 295.535604 -313.379612)
		(width 0.1143)
		(layer "In7.Cu")
		(net "P5E_PEX2_STN5_TX_DP<85>")
	)
	(segment
		(start 295.079674 -319.79108)
		(end 295.079674 -313.605418)
		(width 0.1143)
		(layer "In7.Cu")
		(net "P5E_PEX2_STN5_TX_DP<85>")
	)
	(segment
		(start 295.535604 -313.379612)
		(end 295.649904 -313.265312)
		(width 0.1143)
		(layer "In7.Cu")
		(net "P5E_PEX2_STN5_TX_DP<85>")
	)
	(segment
		(start 322.945252 -340.642702)
		(end 321.959224 -339.696552)
		(width 0.1651)
		(layer "In7.Cu")
		(net "P5E_PEX2_STN5_TX_DP<85>")
	)
	(segment
		(start 323.674994 -352.259646)
		(end 323.674994 -341.76462)
		(width 0.1651)
		(layer "In7.Cu")
		(net "P5E_PEX2_STN5_TX_DP<85>")
	)
	(segment
		(start 295.033954 -319.865248)
		(end 295.033954 -319.8368)
		(width 0.1143)
		(layer "In7.Cu")
		(net "P5E_PEX2_STN5_TX_DP<85>")
	)
	(segment
		(start 322.120514 -354.441252)
		(end 322.120514 -353.814126)
		(width 0.1651)
		(layer "In7.Cu")
		(net "P5E_PEX2_STN5_TX_DP<85>")
	)
	(segment
		(start 322.120514 -353.814126)
		(end 323.674994 -352.259646)
		(width 0.1651)
		(layer "In7.Cu")
		(net "P5E_PEX2_STN5_TX_DP<85>")
	)
	(segment
		(start 383.4257 -134.034276)
		(end 383.711704 -134.32028)
		(width 0.13462)
		(layer "F.Cu")
		(net "P5E_PEX3_STN1_TX_DP<30>")
	)
	(segment
		(start 383.711704 -134.32028)
		(end 384.36042 -134.32028)
		(width 0.13462)
		(layer "F.Cu")
		(net "P5E_PEX3_STN1_TX_DP<30>")
	)
	(segment
		(start 384.36042 -134.32028)
		(end 384.671824 -134.008876)
		(width 0.13462)
		(layer "F.Cu")
		(net "P5E_PEX3_STN1_TX_DP<30>")
	)
	(segment
		(start 420.633906 -271.471898)
		(end 420.633906 -262.993378)
		(width 0.1651)
		(layer "In9.Cu")
		(net "P5E_PEX3_STN1_TX_DP<30>")
	)
	(segment
		(start 421.249602 -278.534368)
		(end 421.135302 -278.420068)
		(width 0.1143)
		(layer "In9.Cu")
		(net "P5E_PEX3_STN1_TX_DP<30>")
	)
	(segment
		(start 420.89451 -278.420068)
		(end 420.679626 -278.205184)
		(width 0.1143)
		(layer "In9.Cu")
		(net "P5E_PEX3_STN1_TX_DP<30>")
	)
	(segment
		(start 420.633906 -271.500346)
		(end 420.633906 -271.471898)
		(width 0.1143)
		(layer "In9.Cu")
		(net "P5E_PEX3_STN1_TX_DP<30>")
	)
	(segment
		(start 384.700018 -139.158218)
		(end 382.874012 -137.332212)
		(width 0.1651)
		(layer "In9.Cu")
		(net "P5E_PEX3_STN1_TX_DP<30>")
	)
	(segment
		(start 421.135302 -278.420068)
		(end 420.89451 -278.420068)
		(width 0.1143)
		(layer "In9.Cu")
		(net "P5E_PEX3_STN1_TX_DP<30>")
	)
	(segment
		(start 383.13487 -134.325106)
		(end 383.4257 -134.034276)
		(width 0.1651)
		(layer "In9.Cu")
		(net "P5E_PEX3_STN1_TX_DP<30>")
	)
	(segment
		(start 420.679626 -271.546066)
		(end 420.633906 -271.500346)
		(width 0.1143)
		(layer "In9.Cu")
		(net "P5E_PEX3_STN1_TX_DP<30>")
	)
	(segment
		(start 421.249602 -278.799798)
		(end 421.249602 -278.534368)
		(width 0.1143)
		(layer "In9.Cu")
		(net "P5E_PEX3_STN1_TX_DP<30>")
	)
	(segment
		(start 420.633906 -262.993378)
		(end 393.648692 -183.275986)
		(width 0.1651)
		(layer "In9.Cu")
		(net "P5E_PEX3_STN1_TX_DP<30>")
	)
	(segment
		(start 393.648692 -183.275986)
		(end 385.053078 -140.010642)
		(width 0.1651)
		(layer "In9.Cu")
		(net "P5E_PEX3_STN1_TX_DP<30>")
	)
	(segment
		(start 382.874012 -137.332212)
		(end 382.0414 -135.323072)
		(width 0.1651)
		(layer "In9.Cu")
		(net "P5E_PEX3_STN1_TX_DP<30>")
	)
	(segment
		(start 382.0414 -134.956296)
		(end 382.16459 -134.659116)
		(width 0.1651)
		(layer "In9.Cu")
		(net "P5E_PEX3_STN1_TX_DP<30>")
	)
	(segment
		(start 385.053078 -140.010642)
		(end 384.700018 -139.158218)
		(width 0.1651)
		(layer "In9.Cu")
		(net "P5E_PEX3_STN1_TX_DP<30>")
	)
	(segment
		(start 382.16459 -134.659116)
		(end 382.4986 -134.325106)
		(width 0.1651)
		(layer "In9.Cu")
		(net "P5E_PEX3_STN1_TX_DP<30>")
	)
	(segment
		(start 382.4986 -134.325106)
		(end 383.13487 -134.325106)
		(width 0.1651)
		(layer "In9.Cu")
		(net "P5E_PEX3_STN1_TX_DP<30>")
	)
	(segment
		(start 420.679626 -278.205184)
		(end 420.679626 -271.546066)
		(width 0.1143)
		(layer "In9.Cu")
		(net "P5E_PEX3_STN1_TX_DP<30>")
	)
	(segment
		(start 382.0414 -135.323072)
		(end 382.0414 -134.956296)
		(width 0.1651)
		(layer "In9.Cu")
		(net "P5E_PEX3_STN1_TX_DP<30>")
	)
	(segment
		(start 374.865392 -355.657658)
		(end 374.865392 -355.02723)
		(width 0.13462)
		(layer "F.Cu")
		(net "P5E_PEX3_STN6_TX_DN<101>")
	)
	(segment
		(start 375.18594 -355.978206)
		(end 374.865392 -355.657658)
		(width 0.13462)
		(layer "F.Cu")
		(net "P5E_PEX3_STN6_TX_DN<101>")
	)
	(segment
		(start 374.865392 -355.02723)
		(end 375.16054 -354.732082)
		(width 0.13462)
		(layer "F.Cu")
		(net "P5E_PEX3_STN6_TX_DN<101>")
	)
	(segment
		(start 400.965924 -319.960752)
		(end 400.920204 -319.915032)
		(width 0.1143)
		(layer "In7.Cu")
		(net "P5E_PEX3_STN6_TX_DN<101>")
	)
	(segment
		(start 401.299934 -311.784492)
		(end 401.299934 -312.049922)
		(width 0.1143)
		(layer "In7.Cu")
		(net "P5E_PEX3_STN6_TX_DN<101>")
	)
	(segment
		(start 376.42419 -341.727028)
		(end 399.242788 -322.785232)
		(width 0.1651)
		(layer "In7.Cu")
		(net "P5E_PEX3_STN6_TX_DN<101>")
	)
	(segment
		(start 374.86971 -354.441252)
		(end 374.86971 -353.930966)
		(width 0.1651)
		(layer "In7.Cu")
		(net "P5E_PEX3_STN6_TX_DN<101>")
	)
	(segment
		(start 400.965924 -319.9892)
		(end 400.965924 -319.960752)
		(width 0.1143)
		(layer "In7.Cu")
		(net "P5E_PEX3_STN6_TX_DN<101>")
	)
	(segment
		(start 400.965924 -320.599054)
		(end 400.965924 -319.9892)
		(width 0.1651)
		(layer "In7.Cu")
		(net "P5E_PEX3_STN6_TX_DN<101>")
	)
	(segment
		(start 375.16054 -354.732082)
		(end 374.86971 -354.441252)
		(width 0.1651)
		(layer "In7.Cu")
		(net "P5E_PEX3_STN6_TX_DN<101>")
	)
	(segment
		(start 376.42419 -352.376486)
		(end 376.42419 -341.727028)
		(width 0.1651)
		(layer "In7.Cu")
		(net "P5E_PEX3_STN6_TX_DN<101>")
	)
	(segment
		(start 400.920204 -319.915032)
		(end 400.920204 -311.784492)
		(width 0.1143)
		(layer "In7.Cu")
		(net "P5E_PEX3_STN6_TX_DN<101>")
	)
	(segment
		(start 399.242788 -322.785232)
		(end 400.638264 -321.389756)
		(width 0.1651)
		(layer "In7.Cu")
		(net "P5E_PEX3_STN6_TX_DN<101>")
	)
	(segment
		(start 374.86971 -353.930966)
		(end 376.42419 -352.376486)
		(width 0.1651)
		(layer "In7.Cu")
		(net "P5E_PEX3_STN6_TX_DN<101>")
	)
	(segment
		(start 401.034504 -311.670192)
		(end 401.185634 -311.670192)
		(width 0.1143)
		(layer "In7.Cu")
		(net "P5E_PEX3_STN6_TX_DN<101>")
	)
	(segment
		(start 400.920204 -311.784492)
		(end 401.034504 -311.670192)
		(width 0.1143)
		(layer "In7.Cu")
		(net "P5E_PEX3_STN6_TX_DN<101>")
	)
	(segment
		(start 400.638264 -321.389756)
		(end 400.965924 -320.599054)
		(width 0.1651)
		(layer "In7.Cu")
		(net "P5E_PEX3_STN6_TX_DN<101>")
	)
	(segment
		(start 401.185634 -311.670192)
		(end 401.299934 -311.784492)
		(width 0.1143)
		(layer "In7.Cu")
		(net "P5E_PEX3_STN6_TX_DN<101>")
	)
	(segment
		(start 45.305218 -32.714184)
		(end 45.001434 -32.4104)
		(width 0.13462)
		(layer "F.Cu")
		(net "P5E_PEX0_STN2_TX_DP<42>")
	)
	(segment
		(start 45.001434 -32.4104)
		(end 44.388278 -32.4104)
		(width 0.13462)
		(layer "F.Cu")
		(net "P5E_PEX0_STN2_TX_DP<42>")
	)
	(segment
		(start 44.388278 -32.4104)
		(end 44.059094 -32.739584)
		(width 0.13462)
		(layer "F.Cu")
		(net "P5E_PEX0_STN2_TX_DP<42>")
	)
	(segment
		(start 44.739306 -161.954718)
		(end 46.100492 -141.878558)
		(width 0.1651)
		(layer "In11.Cu")
		(net "P5E_PEX0_STN2_TX_DP<42>")
	)
	(segment
		(start 48.58385 -271.399)
		(end 48.58385 -270.440658)
		(width 0.1651)
		(layer "In11.Cu")
		(net "P5E_PEX0_STN2_TX_DP<42>")
	)
	(segment
		(start 48.58385 -270.440658)
		(end 48.253142 -267.083794)
		(width 0.1651)
		(layer "In11.Cu")
		(net "P5E_PEX0_STN2_TX_DP<42>")
	)
	(segment
		(start 49.0855 -280.319988)
		(end 48.844708 -280.319988)
		(width 0.1143)
		(layer "In11.Cu")
		(net "P5E_PEX0_STN2_TX_DP<42>")
	)
	(segment
		(start 48.58385 -271.427448)
		(end 48.58385 -271.399)
		(width 0.1143)
		(layer "In11.Cu")
		(net "P5E_PEX0_STN2_TX_DP<42>")
	)
	(segment
		(start 46.100492 -141.878558)
		(end 45.839634 -115.996212)
		(width 0.1651)
		(layer "In11.Cu")
		(net "P5E_PEX0_STN2_TX_DP<42>")
	)
	(segment
		(start 48.62957 -280.10485)
		(end 48.62957 -271.473168)
		(width 0.1143)
		(layer "In11.Cu")
		(net "P5E_PEX0_STN2_TX_DP<42>")
	)
	(segment
		(start 61.773562 -48.627538)
		(end 51.084226 -34.785046)
		(width 0.1651)
		(layer "In11.Cu")
		(net "P5E_PEX0_STN2_TX_DP<42>")
	)
	(segment
		(start 46.55185 -32.423354)
		(end 45.596048 -32.423354)
		(width 0.1651)
		(layer "In11.Cu")
		(net "P5E_PEX0_STN2_TX_DP<42>")
	)
	(segment
		(start 45.839634 -115.996212)
		(end 51.264058 -95.718122)
		(width 0.1651)
		(layer "In11.Cu")
		(net "P5E_PEX0_STN2_TX_DP<42>")
	)
	(segment
		(start 63.022988 -60.449968)
		(end 62.389766 -50.426366)
		(width 0.1651)
		(layer "In11.Cu")
		(net "P5E_PEX0_STN2_TX_DP<42>")
	)
	(segment
		(start 48.253142 -267.083794)
		(end 44.739306 -161.954718)
		(width 0.1651)
		(layer "In11.Cu")
		(net "P5E_PEX0_STN2_TX_DP<42>")
	)
	(segment
		(start 48.844708 -280.319988)
		(end 48.62957 -280.10485)
		(width 0.1143)
		(layer "In11.Cu")
		(net "P5E_PEX0_STN2_TX_DP<42>")
	)
	(segment
		(start 48.62957 -271.473168)
		(end 48.58385 -271.427448)
		(width 0.1143)
		(layer "In11.Cu")
		(net "P5E_PEX0_STN2_TX_DP<42>")
	)
	(segment
		(start 47.22495 -32.423354)
		(end 47.13605 -32.512254)
		(width 0.1651)
		(layer "In11.Cu")
		(net "P5E_PEX0_STN2_TX_DP<42>")
	)
	(segment
		(start 49.1998 -280.434288)
		(end 49.0855 -280.319988)
		(width 0.1143)
		(layer "In11.Cu")
		(net "P5E_PEX0_STN2_TX_DP<42>")
	)
	(segment
		(start 61.53785 -68.584318)
		(end 63.022988 -60.449968)
		(width 0.1651)
		(layer "In11.Cu")
		(net "P5E_PEX0_STN2_TX_DP<42>")
	)
	(segment
		(start 46.64075 -32.512254)
		(end 46.55185 -32.423354)
		(width 0.1651)
		(layer "In11.Cu")
		(net "P5E_PEX0_STN2_TX_DP<42>")
	)
	(segment
		(start 48.424084 -32.423354)
		(end 47.22495 -32.423354)
		(width 0.1651)
		(layer "In11.Cu")
		(net "P5E_PEX0_STN2_TX_DP<42>")
	)
	(segment
		(start 49.1998 -280.699718)
		(end 49.1998 -280.434288)
		(width 0.1143)
		(layer "In11.Cu")
		(net "P5E_PEX0_STN2_TX_DP<42>")
	)
	(segment
		(start 51.264058 -95.718122)
		(end 61.53785 -68.584318)
		(width 0.1651)
		(layer "In11.Cu")
		(net "P5E_PEX0_STN2_TX_DP<42>")
	)
	(segment
		(start 51.084226 -34.785046)
		(end 48.910748 -32.568896)
		(width 0.1651)
		(layer "In11.Cu")
		(net "P5E_PEX0_STN2_TX_DP<42>")
	)
	(segment
		(start 48.910748 -32.568896)
		(end 48.424084 -32.423354)
		(width 0.1651)
		(layer "In11.Cu")
		(net "P5E_PEX0_STN2_TX_DP<42>")
	)
	(segment
		(start 45.596048 -32.423354)
		(end 45.305218 -32.714184)
		(width 0.1651)
		(layer "In11.Cu")
		(net "P5E_PEX0_STN2_TX_DP<42>")
	)
	(segment
		(start 47.13605 -32.512254)
		(end 46.64075 -32.512254)
		(width 0.1651)
		(layer "In11.Cu")
		(net "P5E_PEX0_STN2_TX_DP<42>")
	)
	(segment
		(start 62.389766 -50.426366)
		(end 61.773562 -48.627538)
		(width 0.1651)
		(layer "In11.Cu")
		(net "P5E_PEX0_STN2_TX_DP<42>")
	)
	(segment
		(start 143.520668 -349.511874)
		(end 143.520668 -348.88043)
		(width 0.13462)
		(layer "F.Cu")
		(net "P5E_PEX1_STN5_TX_DN<87>")
	)
	(segment
		(start 143.840708 -349.831914)
		(end 143.520668 -349.511874)
		(width 0.13462)
		(layer "F.Cu")
		(net "P5E_PEX1_STN5_TX_DN<87>")
	)
	(segment
		(start 143.520668 -348.88043)
		(end 143.815308 -348.58579)
		(width 0.13462)
		(layer "F.Cu")
		(net "P5E_PEX1_STN5_TX_DN<87>")
	)
	(segment
		(start 143.860012 -347.401388)
		(end 143.860012 -347.401642)
		(width 0.1651)
		(layer "In7.Cu")
		(net "P5E_PEX1_STN5_TX_DN<87>")
	)
	(segment
		(start 181.11597 -319.97396)
		(end 181.07025 -319.92824)
		(width 0.1143)
		(layer "In7.Cu")
		(net "P5E_PEX1_STN5_TX_DN<87>")
	)
	(segment
		(start 181.07025 -319.92824)
		(end 181.07025 -313.684412)
		(width 0.1143)
		(layer "In7.Cu")
		(net "P5E_PEX1_STN5_TX_DN<87>")
	)
	(segment
		(start 180.037486 -327.457562)
		(end 181.11597 -324.853808)
		(width 0.1651)
		(layer "In7.Cu")
		(net "P5E_PEX1_STN5_TX_DN<87>")
	)
	(segment
		(start 143.524478 -348.29496)
		(end 143.524478 -347.736922)
		(width 0.1651)
		(layer "In7.Cu")
		(net "P5E_PEX1_STN5_TX_DN<87>")
	)
	(segment
		(start 143.524478 -347.736922)
		(end 143.860012 -347.401388)
		(width 0.1651)
		(layer "In7.Cu")
		(net "P5E_PEX1_STN5_TX_DN<87>")
	)
	(segment
		(start 143.815308 -348.58579)
		(end 143.524478 -348.29496)
		(width 0.1651)
		(layer "In7.Cu")
		(net "P5E_PEX1_STN5_TX_DN<87>")
	)
	(segment
		(start 176.33696 -331.158088)
		(end 180.037486 -327.457562)
		(width 0.1651)
		(layer "In7.Cu")
		(net "P5E_PEX1_STN5_TX_DN<87>")
	)
	(segment
		(start 181.33568 -313.570112)
		(end 181.44998 -313.684412)
		(width 0.1143)
		(layer "In7.Cu")
		(net "P5E_PEX1_STN5_TX_DN<87>")
	)
	(segment
		(start 181.18455 -313.570112)
		(end 181.33568 -313.570112)
		(width 0.1143)
		(layer "In7.Cu")
		(net "P5E_PEX1_STN5_TX_DN<87>")
	)
	(segment
		(start 181.07025 -313.684412)
		(end 181.18455 -313.570112)
		(width 0.1143)
		(layer "In7.Cu")
		(net "P5E_PEX1_STN5_TX_DN<87>")
	)
	(segment
		(start 171.816014 -334.179164)
		(end 176.33696 -331.158088)
		(width 0.1651)
		(layer "In7.Cu")
		(net "P5E_PEX1_STN5_TX_DN<87>")
	)
	(segment
		(start 181.11597 -320.002408)
		(end 181.11597 -319.97396)
		(width 0.1143)
		(layer "In7.Cu")
		(net "P5E_PEX1_STN5_TX_DN<87>")
	)
	(segment
		(start 143.860012 -347.401642)
		(end 171.816014 -334.179164)
		(width 0.1651)
		(layer "In7.Cu")
		(net "P5E_PEX1_STN5_TX_DN<87>")
	)
	(segment
		(start 181.11597 -324.853808)
		(end 181.11597 -320.002408)
		(width 0.1651)
		(layer "In7.Cu")
		(net "P5E_PEX1_STN5_TX_DN<87>")
	)
	(segment
		(start 181.44998 -313.684412)
		(end 181.44998 -313.949842)
		(width 0.1143)
		(layer "In7.Cu")
		(net "P5E_PEX1_STN5_TX_DN<87>")
	)
	(segment
		(start 305.851306 -30.353)
		(end 305.222402 -30.353)
		(width 0.13462)
		(layer "F.Cu")
		(net "P5E_PEX2_STN2_TX_DN<37>")
	)
	(segment
		(start 305.222402 -30.353)
		(end 304.901092 -30.03169)
		(width 0.13462)
		(layer "F.Cu")
		(net "P5E_PEX2_STN2_TX_DN<37>")
	)
	(segment
		(start 306.147216 -30.05709)
		(end 305.851306 -30.353)
		(width 0.13462)
		(layer "F.Cu")
		(net "P5E_PEX2_STN2_TX_DN<37>")
	)
	(segment
		(start 298.732702 -93.609922)
		(end 295.436036 -107.879896)
		(width 0.1651)
		(layer "In11.Cu")
		(net "P5E_PEX2_STN2_TX_DN<37>")
	)
	(segment
		(start 293.313866 -120.76176)
		(end 285.815786 -263.306306)
		(width 0.1651)
		(layer "In11.Cu")
		(net "P5E_PEX2_STN2_TX_DN<37>")
	)
	(segment
		(start 309.892446 -32.913066)
		(end 314.619894 -40.511984)
		(width 0.1651)
		(layer "In11.Cu")
		(net "P5E_PEX2_STN2_TX_DN<37>")
	)
	(segment
		(start 285.815786 -263.306306)
		(end 285.815786 -271.399)
		(width 0.1651)
		(layer "In11.Cu")
		(net "P5E_PEX2_STN2_TX_DN<37>")
	)
	(segment
		(start 322.471288 -58.532522)
		(end 322.471288 -60.458604)
		(width 0.1651)
		(layer "In11.Cu")
		(net "P5E_PEX2_STN2_TX_DN<37>")
	)
	(segment
		(start 286.149796 -278.115268)
		(end 286.149796 -277.849838)
		(width 0.1143)
		(layer "In11.Cu")
		(net "P5E_PEX2_STN2_TX_DN<37>")
	)
	(segment
		(start 314.619894 -40.511984)
		(end 321.404996 -48.032416)
		(width 0.1651)
		(layer "In11.Cu")
		(net "P5E_PEX2_STN2_TX_DN<37>")
	)
	(segment
		(start 322.471288 -60.458604)
		(end 321.872356 -62.700916)
		(width 0.1651)
		(layer "In11.Cu")
		(net "P5E_PEX2_STN2_TX_DN<37>")
	)
	(segment
		(start 307.112162 -30.34792)
		(end 307.479446 -30.500066)
		(width 0.1651)
		(layer "In11.Cu")
		(net "P5E_PEX2_STN2_TX_DN<37>")
	)
	(segment
		(start 285.770066 -271.473168)
		(end 285.770066 -278.125936)
		(width 0.1143)
		(layer "In11.Cu")
		(net "P5E_PEX2_STN2_TX_DN<37>")
	)
	(segment
		(start 293.991538 -115.272058)
		(end 293.313866 -120.76176)
		(width 0.1651)
		(layer "In11.Cu")
		(net "P5E_PEX2_STN2_TX_DN<37>")
	)
	(segment
		(start 286.035496 -278.229568)
		(end 286.149796 -278.115268)
		(width 0.1143)
		(layer "In11.Cu")
		(net "P5E_PEX2_STN2_TX_DN<37>")
	)
	(segment
		(start 295.436036 -107.879896)
		(end 293.991538 -115.272058)
		(width 0.1651)
		(layer "In11.Cu")
		(net "P5E_PEX2_STN2_TX_DN<37>")
	)
	(segment
		(start 306.147216 -30.05709)
		(end 306.438046 -30.34792)
		(width 0.1651)
		(layer "In11.Cu")
		(net "P5E_PEX2_STN2_TX_DN<37>")
	)
	(segment
		(start 321.872356 -62.700916)
		(end 320.917316 -64.616076)
		(width 0.1651)
		(layer "In11.Cu")
		(net "P5E_PEX2_STN2_TX_DN<37>")
	)
	(segment
		(start 320.917316 -64.616076)
		(end 298.732702 -93.609922)
		(width 0.1651)
		(layer "In11.Cu")
		(net "P5E_PEX2_STN2_TX_DN<37>")
	)
	(segment
		(start 285.815786 -271.399)
		(end 285.815786 -271.427448)
		(width 0.1143)
		(layer "In11.Cu")
		(net "P5E_PEX2_STN2_TX_DN<37>")
	)
	(segment
		(start 285.873698 -278.229568)
		(end 286.035496 -278.229568)
		(width 0.1143)
		(layer "In11.Cu")
		(net "P5E_PEX2_STN2_TX_DN<37>")
	)
	(segment
		(start 307.479446 -30.500066)
		(end 309.892446 -32.913066)
		(width 0.1651)
		(layer "In11.Cu")
		(net "P5E_PEX2_STN2_TX_DN<37>")
	)
	(segment
		(start 321.404996 -48.032416)
		(end 322.471288 -58.532522)
		(width 0.1651)
		(layer "In11.Cu")
		(net "P5E_PEX2_STN2_TX_DN<37>")
	)
	(segment
		(start 285.815786 -271.427448)
		(end 285.770066 -271.473168)
		(width 0.1143)
		(layer "In11.Cu")
		(net "P5E_PEX2_STN2_TX_DN<37>")
	)
	(segment
		(start 285.770066 -278.125936)
		(end 285.873698 -278.229568)
		(width 0.1143)
		(layer "In11.Cu")
		(net "P5E_PEX2_STN2_TX_DN<37>")
	)
	(segment
		(start 306.438046 -30.34792)
		(end 307.112162 -30.34792)
		(width 0.1651)
		(layer "In11.Cu")
		(net "P5E_PEX2_STN2_TX_DN<37>")
	)
	(segment
		(start 432.47437 -155.222194)
		(end 432.172364 -155.5242)
		(width 0.13462)
		(layer "F.Cu")
		(net "P5E_PEX3_STN0_TX_DN<15>")
	)
	(segment
		(start 431.555652 -155.5242)
		(end 431.228246 -155.196794)
		(width 0.13462)
		(layer "F.Cu")
		(net "P5E_PEX3_STN0_TX_DN<15>")
	)
	(segment
		(start 432.172364 -155.5242)
		(end 431.555652 -155.5242)
		(width 0.13462)
		(layer "F.Cu")
		(net "P5E_PEX3_STN0_TX_DN<15>")
	)
	(segment
		(start 433.490878 -155.513024)
		(end 433.957222 -155.979368)
		(width 0.1651)
		(layer "In9.Cu")
		(net "P5E_PEX3_STN0_TX_DN<15>")
	)
	(segment
		(start 433.957222 -156.571442)
		(end 425.474384 -171.265088)
		(width 0.1651)
		(layer "In9.Cu")
		(net "P5E_PEX3_STN0_TX_DN<15>")
	)
	(segment
		(start 422.7703 -278.12619)
		(end 422.873678 -278.229568)
		(width 0.1143)
		(layer "In9.Cu")
		(net "P5E_PEX3_STN0_TX_DN<15>")
	)
	(segment
		(start 422.81602 -269.584932)
		(end 422.81602 -271.471898)
		(width 0.1651)
		(layer "In9.Cu")
		(net "P5E_PEX3_STN0_TX_DN<15>")
	)
	(segment
		(start 420.16299 -220.410278)
		(end 423.690288 -260.731254)
		(width 0.1651)
		(layer "In9.Cu")
		(net "P5E_PEX3_STN0_TX_DN<15>")
	)
	(segment
		(start 422.81602 -271.500346)
		(end 422.7703 -271.546066)
		(width 0.1143)
		(layer "In9.Cu")
		(net "P5E_PEX3_STN0_TX_DN<15>")
	)
	(segment
		(start 423.035476 -278.229568)
		(end 423.149776 -278.115268)
		(width 0.1143)
		(layer "In9.Cu")
		(net "P5E_PEX3_STN0_TX_DN<15>")
	)
	(segment
		(start 423.971974 -176.871122)
		(end 420.16299 -220.410278)
		(width 0.1651)
		(layer "In9.Cu")
		(net "P5E_PEX3_STN0_TX_DN<15>")
	)
	(segment
		(start 422.81602 -271.471898)
		(end 422.81602 -271.500346)
		(width 0.1143)
		(layer "In9.Cu")
		(net "P5E_PEX3_STN0_TX_DN<15>")
	)
	(segment
		(start 432.47437 -155.222194)
		(end 432.7652 -155.513024)
		(width 0.1651)
		(layer "In9.Cu")
		(net "P5E_PEX3_STN0_TX_DN<15>")
	)
	(segment
		(start 425.474384 -171.265088)
		(end 423.971974 -176.871122)
		(width 0.1651)
		(layer "In9.Cu")
		(net "P5E_PEX3_STN0_TX_DN<15>")
	)
	(segment
		(start 422.7703 -271.546066)
		(end 422.7703 -278.12619)
		(width 0.1143)
		(layer "In9.Cu")
		(net "P5E_PEX3_STN0_TX_DN<15>")
	)
	(segment
		(start 433.957222 -155.979368)
		(end 433.957222 -156.571442)
		(width 0.1651)
		(layer "In9.Cu")
		(net "P5E_PEX3_STN0_TX_DN<15>")
	)
	(segment
		(start 423.149776 -278.115268)
		(end 423.149776 -277.849838)
		(width 0.1143)
		(layer "In9.Cu")
		(net "P5E_PEX3_STN0_TX_DN<15>")
	)
	(segment
		(start 422.873678 -278.229568)
		(end 423.035476 -278.229568)
		(width 0.1143)
		(layer "In9.Cu")
		(net "P5E_PEX3_STN0_TX_DN<15>")
	)
	(segment
		(start 432.7652 -155.513024)
		(end 433.490878 -155.513024)
		(width 0.1651)
		(layer "In9.Cu")
		(net "P5E_PEX3_STN0_TX_DN<15>")
	)
	(segment
		(start 423.690288 -260.731254)
		(end 423.690288 -267.473684)
		(width 0.1651)
		(layer "In9.Cu")
		(net "P5E_PEX3_STN0_TX_DN<15>")
	)
	(segment
		(start 423.690288 -267.473684)
		(end 422.81602 -269.584932)
		(width 0.1651)
		(layer "In9.Cu")
		(net "P5E_PEX3_STN0_TX_DN<15>")
	)
	(segment
		(start 377.974352 -348.880938)
		(end 378.2695 -348.58579)
		(width 0.13462)
		(layer "F.Cu")
		(net "P5E_PEX3_STN6_TX_DN<100>")
	)
	(segment
		(start 378.2949 -349.831914)
		(end 377.974352 -349.511366)
		(width 0.13462)
		(layer "F.Cu")
		(net "P5E_PEX3_STN6_TX_DN<100>")
	)
	(segment
		(start 377.974352 -349.511366)
		(end 377.974352 -348.880938)
		(width 0.13462)
		(layer "F.Cu")
		(net "P5E_PEX3_STN6_TX_DN<100>")
	)
	(segment
		(start 401.49018 -321.9069)
		(end 401.915884 -320.87947)
		(width 0.1651)
		(layer "In7.Cu")
		(net "P5E_PEX3_STN6_TX_DN<100>")
	)
	(segment
		(start 377.97867 -347.784674)
		(end 379.53315 -346.230194)
		(width 0.1651)
		(layer "In7.Cu")
		(net "P5E_PEX3_STN6_TX_DN<100>")
	)
	(segment
		(start 399.689066 -323.708014)
		(end 401.49018 -321.9069)
		(width 0.1651)
		(layer "In7.Cu")
		(net "P5E_PEX3_STN6_TX_DN<100>")
	)
	(segment
		(start 402.249894 -313.684412)
		(end 402.249894 -313.949842)
		(width 0.1143)
		(layer "In7.Cu")
		(net "P5E_PEX3_STN6_TX_DN<100>")
	)
	(segment
		(start 377.97867 -348.29496)
		(end 377.97867 -347.784674)
		(width 0.1651)
		(layer "In7.Cu")
		(net "P5E_PEX3_STN6_TX_DN<100>")
	)
	(segment
		(start 379.53315 -346.230194)
		(end 379.53315 -341.601806)
		(width 0.1651)
		(layer "In7.Cu")
		(net "P5E_PEX3_STN6_TX_DN<100>")
	)
	(segment
		(start 379.53315 -341.601806)
		(end 399.689066 -323.708014)
		(width 0.1651)
		(layer "In7.Cu")
		(net "P5E_PEX3_STN6_TX_DN<100>")
	)
	(segment
		(start 401.870164 -313.684412)
		(end 401.984464 -313.570112)
		(width 0.1143)
		(layer "In7.Cu")
		(net "P5E_PEX3_STN6_TX_DN<100>")
	)
	(segment
		(start 401.870164 -319.915032)
		(end 401.870164 -313.684412)
		(width 0.1143)
		(layer "In7.Cu")
		(net "P5E_PEX3_STN6_TX_DN<100>")
	)
	(segment
		(start 401.915884 -319.960752)
		(end 401.870164 -319.915032)
		(width 0.1143)
		(layer "In7.Cu")
		(net "P5E_PEX3_STN6_TX_DN<100>")
	)
	(segment
		(start 401.915884 -319.9892)
		(end 401.915884 -319.960752)
		(width 0.1143)
		(layer "In7.Cu")
		(net "P5E_PEX3_STN6_TX_DN<100>")
	)
	(segment
		(start 402.135594 -313.570112)
		(end 402.249894 -313.684412)
		(width 0.1143)
		(layer "In7.Cu")
		(net "P5E_PEX3_STN6_TX_DN<100>")
	)
	(segment
		(start 378.2695 -348.58579)
		(end 377.97867 -348.29496)
		(width 0.1651)
		(layer "In7.Cu")
		(net "P5E_PEX3_STN6_TX_DN<100>")
	)
	(segment
		(start 401.915884 -320.87947)
		(end 401.915884 -319.9892)
		(width 0.1651)
		(layer "In7.Cu")
		(net "P5E_PEX3_STN6_TX_DN<100>")
	)
	(segment
		(start 401.984464 -313.570112)
		(end 402.135594 -313.570112)
		(width 0.1143)
		(layer "In7.Cu")
		(net "P5E_PEX3_STN6_TX_DN<100>")
	)
	(segment
		(start 71.001128 -28.55468)
		(end 70.38848 -28.55468)
		(width 0.13462)
		(layer "F.Cu")
		(net "P5E_PEX0_STN2_TX_DN<36>")
	)
	(segment
		(start 70.38848 -28.55468)
		(end 70.059042 -28.225242)
		(width 0.13462)
		(layer "F.Cu")
		(net "P5E_PEX0_STN2_TX_DN<36>")
	)
	(segment
		(start 71.305166 -28.250642)
		(end 71.001128 -28.55468)
		(width 0.13462)
		(layer "F.Cu")
		(net "P5E_PEX0_STN2_TX_DN<36>")
	)
	(segment
		(start 62.622176 -116.6876)
		(end 62.106556 -120.957594)
		(width 0.1651)
		(layer "In11.Cu")
		(net "P5E_PEX0_STN2_TX_DN<36>")
	)
	(segment
		(start 54.785514 -280.129488)
		(end 54.899814 -280.015188)
		(width 0.1143)
		(layer "In11.Cu")
		(net "P5E_PEX0_STN2_TX_DN<36>")
	)
	(segment
		(start 90.14714 -47.60849)
		(end 91.274138 -58.438034)
		(width 0.1651)
		(layer "In11.Cu")
		(net "P5E_PEX0_STN2_TX_DN<36>")
	)
	(segment
		(start 67.41795 -94.024958)
		(end 64.25057 -108.111798)
		(width 0.1651)
		(layer "In11.Cu")
		(net "P5E_PEX0_STN2_TX_DN<36>")
	)
	(segment
		(start 54.520084 -271.473168)
		(end 54.520084 -280.025856)
		(width 0.1143)
		(layer "In11.Cu")
		(net "P5E_PEX0_STN2_TX_DN<36>")
	)
	(segment
		(start 64.25057 -108.111798)
		(end 62.622176 -116.6876)
		(width 0.1651)
		(layer "In11.Cu")
		(net "P5E_PEX0_STN2_TX_DN<36>")
	)
	(segment
		(start 71.595996 -28.541472)
		(end 73.971912 -28.541472)
		(width 0.1651)
		(layer "In11.Cu")
		(net "P5E_PEX0_STN2_TX_DN<36>")
	)
	(segment
		(start 90.627708 -62.998604)
		(end 89.632536 -65.005458)
		(width 0.1651)
		(layer "In11.Cu")
		(net "P5E_PEX0_STN2_TX_DN<36>")
	)
	(segment
		(start 75.575414 -29.206952)
		(end 78.253844 -31.885636)
		(width 0.1651)
		(layer "In11.Cu")
		(net "P5E_PEX0_STN2_TX_DN<36>")
	)
	(segment
		(start 91.274138 -58.438034)
		(end 91.274138 -60.59424)
		(width 0.1651)
		(layer "In11.Cu")
		(net "P5E_PEX0_STN2_TX_DN<36>")
	)
	(segment
		(start 54.623716 -280.129488)
		(end 54.785514 -280.129488)
		(width 0.1143)
		(layer "In11.Cu")
		(net "P5E_PEX0_STN2_TX_DN<36>")
	)
	(segment
		(start 91.274138 -60.59424)
		(end 90.627708 -62.998604)
		(width 0.1651)
		(layer "In11.Cu")
		(net "P5E_PEX0_STN2_TX_DN<36>")
	)
	(segment
		(start 54.899814 -280.015188)
		(end 54.899814 -279.749504)
		(width 0.1143)
		(layer "In11.Cu")
		(net "P5E_PEX0_STN2_TX_DN<36>")
	)
	(segment
		(start 54.565804 -271.399)
		(end 54.565804 -271.427448)
		(width 0.1143)
		(layer "In11.Cu")
		(net "P5E_PEX0_STN2_TX_DN<36>")
	)
	(segment
		(start 62.106556 -120.957594)
		(end 54.565804 -263.42467)
		(width 0.1651)
		(layer "In11.Cu")
		(net "P5E_PEX0_STN2_TX_DN<36>")
	)
	(segment
		(start 54.520084 -280.025856)
		(end 54.623716 -280.129488)
		(width 0.1143)
		(layer "In11.Cu")
		(net "P5E_PEX0_STN2_TX_DN<36>")
	)
	(segment
		(start 54.565804 -271.427448)
		(end 54.520084 -271.473168)
		(width 0.1143)
		(layer "In11.Cu")
		(net "P5E_PEX0_STN2_TX_DN<36>")
	)
	(segment
		(start 73.971912 -28.541472)
		(end 75.575414 -29.206952)
		(width 0.1651)
		(layer "In11.Cu")
		(net "P5E_PEX0_STN2_TX_DN<36>")
	)
	(segment
		(start 89.632536 -65.005458)
		(end 67.41795 -94.024958)
		(width 0.1651)
		(layer "In11.Cu")
		(net "P5E_PEX0_STN2_TX_DN<36>")
	)
	(segment
		(start 71.305166 -28.250642)
		(end 71.595996 -28.541472)
		(width 0.1651)
		(layer "In11.Cu")
		(net "P5E_PEX0_STN2_TX_DN<36>")
	)
	(segment
		(start 54.565804 -263.42467)
		(end 54.565804 -271.399)
		(width 0.1651)
		(layer "In11.Cu")
		(net "P5E_PEX0_STN2_TX_DN<36>")
	)
	(segment
		(start 83.24723 -39.727886)
		(end 90.14714 -47.60849)
		(width 0.1651)
		(layer "In11.Cu")
		(net "P5E_PEX0_STN2_TX_DN<36>")
	)
	(segment
		(start 78.253844 -31.885636)
		(end 83.24723 -39.727886)
		(width 0.1651)
		(layer "In11.Cu")
		(net "P5E_PEX0_STN2_TX_DN<36>")
	)
	(segment
		(start 134.193788 -349.511874)
		(end 134.193788 -348.88043)
		(width 0.13462)
		(layer "F.Cu")
		(net "P5E_PEX1_STN5_TX_DN<90>")
	)
	(segment
		(start 134.513828 -349.831914)
		(end 134.193788 -349.511874)
		(width 0.13462)
		(layer "F.Cu")
		(net "P5E_PEX1_STN5_TX_DN<90>")
	)
	(segment
		(start 134.193788 -348.88043)
		(end 134.488428 -348.58579)
		(width 0.13462)
		(layer "F.Cu")
		(net "P5E_PEX1_STN5_TX_DN<90>")
	)
	(segment
		(start 183.92013 -319.995296)
		(end 183.96585 -320.041016)
		(width 0.1143)
		(layer "In13.Cu")
		(net "P5E_PEX1_STN5_TX_DN<90>")
	)
	(segment
		(start 184.023762 -311.670192)
		(end 183.92013 -311.773824)
		(width 0.1143)
		(layer "In13.Cu")
		(net "P5E_PEX1_STN5_TX_DN<90>")
	)
	(segment
		(start 134.197598 -348.29496)
		(end 134.488428 -348.58579)
		(width 0.1651)
		(layer "In13.Cu")
		(net "P5E_PEX1_STN5_TX_DN<90>")
	)
	(segment
		(start 183.96585 -321.410584)
		(end 183.32323 -322.053204)
		(width 0.1651)
		(layer "In13.Cu")
		(net "P5E_PEX1_STN5_TX_DN<90>")
	)
	(segment
		(start 143.118586 -336.998056)
		(end 141.958822 -337.228942)
		(width 0.1651)
		(layer "In13.Cu")
		(net "P5E_PEX1_STN5_TX_DN<90>")
	)
	(segment
		(start 135.752078 -346.078556)
		(end 134.197598 -347.633036)
		(width 0.1651)
		(layer "In13.Cu")
		(net "P5E_PEX1_STN5_TX_DN<90>")
	)
	(segment
		(start 177.576734 -325.334122)
		(end 177.57648 -325.334376)
		(width 0.1651)
		(layer "In13.Cu")
		(net "P5E_PEX1_STN5_TX_DN<90>")
	)
	(segment
		(start 183.92013 -311.773824)
		(end 183.92013 -319.995296)
		(width 0.1143)
		(layer "In13.Cu")
		(net "P5E_PEX1_STN5_TX_DN<90>")
	)
	(segment
		(start 135.752078 -340.855554)
		(end 135.752078 -346.078556)
		(width 0.1651)
		(layer "In13.Cu")
		(net "P5E_PEX1_STN5_TX_DN<90>")
	)
	(segment
		(start 137.554716 -339.052916)
		(end 135.752078 -340.855554)
		(width 0.1651)
		(layer "In13.Cu")
		(net "P5E_PEX1_STN5_TX_DN<90>")
	)
	(segment
		(start 183.32323 -322.053204)
		(end 181.758844 -323.098414)
		(width 0.1651)
		(layer "In13.Cu")
		(net "P5E_PEX1_STN5_TX_DN<90>")
	)
	(segment
		(start 183.96585 -320.041016)
		(end 183.96585 -320.063114)
		(width 0.1143)
		(layer "In13.Cu")
		(net "P5E_PEX1_STN5_TX_DN<90>")
	)
	(segment
		(start 184.29986 -312.049922)
		(end 184.29986 -311.784492)
		(width 0.1143)
		(layer "In13.Cu")
		(net "P5E_PEX1_STN5_TX_DN<90>")
	)
	(segment
		(start 164.643816 -331.33538)
		(end 147.652486 -336.998056)
		(width 0.1651)
		(layer "In13.Cu")
		(net "P5E_PEX1_STN5_TX_DN<90>")
	)
	(segment
		(start 183.96585 -320.063114)
		(end 183.96585 -321.410584)
		(width 0.1651)
		(layer "In13.Cu")
		(net "P5E_PEX1_STN5_TX_DN<90>")
	)
	(segment
		(start 134.197598 -347.633036)
		(end 134.197598 -348.29496)
		(width 0.1651)
		(layer "In13.Cu")
		(net "P5E_PEX1_STN5_TX_DN<90>")
	)
	(segment
		(start 177.57648 -325.334376)
		(end 173.396148 -327.569068)
		(width 0.1651)
		(layer "In13.Cu")
		(net "P5E_PEX1_STN5_TX_DN<90>")
	)
	(segment
		(start 184.29986 -311.784492)
		(end 184.18556 -311.670192)
		(width 0.1143)
		(layer "In13.Cu")
		(net "P5E_PEX1_STN5_TX_DN<90>")
	)
	(segment
		(start 181.758844 -323.098414)
		(end 177.576734 -325.334122)
		(width 0.1651)
		(layer "In13.Cu")
		(net "P5E_PEX1_STN5_TX_DN<90>")
	)
	(segment
		(start 173.396148 -327.569068)
		(end 164.643816 -331.33538)
		(width 0.1651)
		(layer "In13.Cu")
		(net "P5E_PEX1_STN5_TX_DN<90>")
	)
	(segment
		(start 147.652486 -336.998056)
		(end 143.118586 -336.998056)
		(width 0.1651)
		(layer "In13.Cu")
		(net "P5E_PEX1_STN5_TX_DN<90>")
	)
	(segment
		(start 141.958822 -337.228942)
		(end 137.554716 -339.052916)
		(width 0.1651)
		(layer "In13.Cu")
		(net "P5E_PEX1_STN5_TX_DN<90>")
	)
	(segment
		(start 184.18556 -311.670192)
		(end 184.023762 -311.670192)
		(width 0.1143)
		(layer "In13.Cu")
		(net "P5E_PEX1_STN5_TX_DN<90>")
	)
	(segment
		(start 322.124324 -343.365582)
		(end 322.124324 -342.734138)
		(width 0.13462)
		(layer "F.Cu")
		(net "P5E_PEX2_STN5_TX_DP<84>")
	)
	(segment
		(start 322.124324 -342.734138)
		(end 321.829684 -342.439498)
		(width 0.13462)
		(layer "F.Cu")
		(net "P5E_PEX2_STN5_TX_DP<84>")
	)
	(segment
		(start 321.804284 -343.685622)
		(end 322.124324 -343.365582)
		(width 0.13462)
		(layer "F.Cu")
		(net "P5E_PEX2_STN5_TX_DP<84>")
	)
	(segment
		(start 321.829684 -342.439498)
		(end 322.120514 -342.148668)
		(width 0.1651)
		(layer "In7.Cu")
		(net "P5E_PEX2_STN5_TX_DP<84>")
	)
	(segment
		(start 294.08374 -319.865248)
		(end 294.08374 -319.8368)
		(width 0.1143)
		(layer "In7.Cu")
		(net "P5E_PEX2_STN5_TX_DP<84>")
	)
	(segment
		(start 319.851024 -339.396832)
		(end 299.194474 -330.479654)
		(width 0.1651)
		(layer "In7.Cu")
		(net "P5E_PEX2_STN5_TX_DP<84>")
	)
	(segment
		(start 294.355266 -311.479692)
		(end 294.58539 -311.479692)
		(width 0.1143)
		(layer "In7.Cu")
		(net "P5E_PEX2_STN5_TX_DP<84>")
	)
	(segment
		(start 322.120514 -341.708486)
		(end 321.88023 -341.291418)
		(width 0.1651)
		(layer "In7.Cu")
		(net "P5E_PEX2_STN5_TX_DP<84>")
	)
	(segment
		(start 320.434716 -339.795104)
		(end 319.851024 -339.396832)
		(width 0.1651)
		(layer "In7.Cu")
		(net "P5E_PEX2_STN5_TX_DP<84>")
	)
	(segment
		(start 294.58539 -311.479692)
		(end 294.69969 -311.365392)
		(width 0.1143)
		(layer "In7.Cu")
		(net "P5E_PEX2_STN5_TX_DP<84>")
	)
	(segment
		(start 296.182288 -327.467468)
		(end 294.08374 -322.40093)
		(width 0.1651)
		(layer "In7.Cu")
		(net "P5E_PEX2_STN5_TX_DP<84>")
	)
	(segment
		(start 294.12946 -319.79108)
		(end 294.12946 -311.705498)
		(width 0.1143)
		(layer "In7.Cu")
		(net "P5E_PEX2_STN5_TX_DP<84>")
	)
	(segment
		(start 294.08374 -319.8368)
		(end 294.12946 -319.79108)
		(width 0.1143)
		(layer "In7.Cu")
		(net "P5E_PEX2_STN5_TX_DP<84>")
	)
	(segment
		(start 321.88023 -341.291418)
		(end 320.434716 -339.795104)
		(width 0.1651)
		(layer "In7.Cu")
		(net "P5E_PEX2_STN5_TX_DP<84>")
	)
	(segment
		(start 294.08374 -322.40093)
		(end 294.08374 -319.865248)
		(width 0.1651)
		(layer "In7.Cu")
		(net "P5E_PEX2_STN5_TX_DP<84>")
	)
	(segment
		(start 322.120514 -342.148668)
		(end 322.120514 -341.708486)
		(width 0.1651)
		(layer "In7.Cu")
		(net "P5E_PEX2_STN5_TX_DP<84>")
	)
	(segment
		(start 294.69969 -311.365392)
		(end 294.69969 -311.099962)
		(width 0.1143)
		(layer "In7.Cu")
		(net "P5E_PEX2_STN5_TX_DP<84>")
	)
	(segment
		(start 294.12946 -311.705498)
		(end 294.355266 -311.479692)
		(width 0.1143)
		(layer "In7.Cu")
		(net "P5E_PEX2_STN5_TX_DP<84>")
	)
	(segment
		(start 299.194474 -330.479654)
		(end 296.182288 -327.467468)
		(width 0.1651)
		(layer "In7.Cu")
		(net "P5E_PEX2_STN5_TX_DP<84>")
	)
	(segment
		(start 386.983478 -99.8728)
		(end 387.313932 -100.203254)
		(width 0.13462)
		(layer "F.Cu")
		(net "P5E_PEX3_STN1_TX_DN<16>")
	)
	(segment
		(start 386.372862 -99.8728)
		(end 386.983478 -99.8728)
		(width 0.13462)
		(layer "F.Cu")
		(net "P5E_PEX3_STN1_TX_DN<16>")
	)
	(segment
		(start 386.067808 -100.177854)
		(end 386.372862 -99.8728)
		(width 0.13462)
		(layer "F.Cu")
		(net "P5E_PEX3_STN1_TX_DN<16>")
	)
	(segment
		(start 407.673556 -278.229568)
		(end 407.835354 -278.229568)
		(width 0.1143)
		(layer "In9.Cu")
		(net "P5E_PEX3_STN1_TX_DN<16>")
	)
	(segment
		(start 381.67056 -101.43744)
		(end 381.67056 -101.598984)
		(width 0.1651)
		(layer "In9.Cu")
		(net "P5E_PEX3_STN1_TX_DN<16>")
	)
	(segment
		(start 385.776978 -99.887024)
		(end 384.614166 -99.887024)
		(width 0.1651)
		(layer "In9.Cu")
		(net "P5E_PEX3_STN1_TX_DN<16>")
	)
	(segment
		(start 375.713498 -108.829348)
		(end 374.688354 -111.304832)
		(width 0.1651)
		(layer "In9.Cu")
		(net "P5E_PEX3_STN1_TX_DN<16>")
	)
	(segment
		(start 378.29363 -104.975914)
		(end 377.952 -105.317544)
		(width 0.1651)
		(layer "In9.Cu")
		(net "P5E_PEX3_STN1_TX_DN<16>")
	)
	(segment
		(start 384.167126 -100.071936)
		(end 384.105404 -100.221542)
		(width 0.1651)
		(layer "In9.Cu")
		(net "P5E_PEX3_STN1_TX_DN<16>")
	)
	(segment
		(start 375.990612 -108.160312)
		(end 376.052588 -108.309664)
		(width 0.1651)
		(layer "In9.Cu")
		(net "P5E_PEX3_STN1_TX_DN<16>")
	)
	(segment
		(start 376.329702 -107.641136)
		(end 376.180096 -107.702858)
		(width 0.1651)
		(layer "In9.Cu")
		(net "P5E_PEX3_STN1_TX_DN<16>")
	)
	(segment
		(start 371.38483 -145.35912)
		(end 372.095776 -159.841184)
		(width 0.1651)
		(layer "In9.Cu")
		(net "P5E_PEX3_STN1_TX_DN<16>")
	)
	(segment
		(start 376.180096 -107.702858)
		(end 375.990612 -108.160312)
		(width 0.1651)
		(layer "In9.Cu")
		(net "P5E_PEX3_STN1_TX_DN<16>")
	)
	(segment
		(start 407.570178 -271.546066)
		(end 407.570178 -278.12619)
		(width 0.1143)
		(layer "In9.Cu")
		(net "P5E_PEX3_STN1_TX_DN<16>")
	)
	(segment
		(start 376.052588 -108.309664)
		(end 375.863104 -108.767626)
		(width 0.1651)
		(layer "In9.Cu")
		(net "P5E_PEX3_STN1_TX_DN<16>")
	)
	(segment
		(start 380.484888 -102.784656)
		(end 380.323344 -102.784656)
		(width 0.1651)
		(layer "In9.Cu")
		(net "P5E_PEX3_STN1_TX_DN<16>")
	)
	(segment
		(start 372.095776 -159.841184)
		(end 372.652798 -162.641534)
		(width 0.1651)
		(layer "In9.Cu")
		(net "P5E_PEX3_STN1_TX_DN<16>")
	)
	(segment
		(start 377.790456 -105.317544)
		(end 376.728228 -106.379772)
		(width 0.1651)
		(layer "In9.Cu")
		(net "P5E_PEX3_STN1_TX_DN<16>")
	)
	(segment
		(start 378.29363 -104.81437)
		(end 378.29363 -104.975914)
		(width 0.1651)
		(layer "In9.Cu")
		(net "P5E_PEX3_STN1_TX_DN<16>")
	)
	(segment
		(start 407.570178 -278.12619)
		(end 407.673556 -278.229568)
		(width 0.1143)
		(layer "In9.Cu")
		(net "P5E_PEX3_STN1_TX_DN<16>")
	)
	(segment
		(start 368.787172 -139.08786)
		(end 371.38483 -145.35912)
		(width 0.1651)
		(layer "In9.Cu")
		(net "P5E_PEX3_STN1_TX_DN<16>")
	)
	(segment
		(start 380.323344 -102.784656)
		(end 379.982222 -103.125778)
		(width 0.1651)
		(layer "In9.Cu")
		(net "P5E_PEX3_STN1_TX_DN<16>")
	)
	(segment
		(start 379.137926 -104.131618)
		(end 378.796296 -104.473248)
		(width 0.1651)
		(layer "In9.Cu")
		(net "P5E_PEX3_STN1_TX_DN<16>")
	)
	(segment
		(start 378.796296 -104.473248)
		(end 378.634752 -104.473248)
		(width 0.1651)
		(layer "In9.Cu")
		(net "P5E_PEX3_STN1_TX_DN<16>")
	)
	(segment
		(start 383.659126 -100.4062)
		(end 383.509774 -100.344224)
		(width 0.1651)
		(layer "In9.Cu")
		(net "P5E_PEX3_STN1_TX_DN<16>")
	)
	(segment
		(start 407.615898 -265.937492)
		(end 407.615898 -271.471898)
		(width 0.1651)
		(layer "In9.Cu")
		(net "P5E_PEX3_STN1_TX_DN<16>")
	)
	(segment
		(start 372.652798 -162.641534)
		(end 407.615898 -265.937492)
		(width 0.1651)
		(layer "In9.Cu")
		(net "P5E_PEX3_STN1_TX_DN<16>")
	)
	(segment
		(start 379.640592 -103.628952)
		(end 379.479048 -103.628952)
		(width 0.1651)
		(layer "In9.Cu")
		(net "P5E_PEX3_STN1_TX_DN<16>")
	)
	(segment
		(start 383.509774 -100.344224)
		(end 382.236472 -100.871528)
		(width 0.1651)
		(layer "In9.Cu")
		(net "P5E_PEX3_STN1_TX_DN<16>")
	)
	(segment
		(start 375.863104 -108.767626)
		(end 375.713498 -108.829348)
		(width 0.1651)
		(layer "In9.Cu")
		(net "P5E_PEX3_STN1_TX_DN<16>")
	)
	(segment
		(start 386.067808 -100.177854)
		(end 385.776978 -99.887024)
		(width 0.1651)
		(layer "In9.Cu")
		(net "P5E_PEX3_STN1_TX_DN<16>")
	)
	(segment
		(start 382.236472 -100.871528)
		(end 381.67056 -101.43744)
		(width 0.1651)
		(layer "In9.Cu")
		(net "P5E_PEX3_STN1_TX_DN<16>")
	)
	(segment
		(start 379.982222 -103.125778)
		(end 379.982222 -103.287322)
		(width 0.1651)
		(layer "In9.Cu")
		(net "P5E_PEX3_STN1_TX_DN<16>")
	)
	(segment
		(start 376.457464 -107.033822)
		(end 376.519186 -107.183174)
		(width 0.1651)
		(layer "In9.Cu")
		(net "P5E_PEX3_STN1_TX_DN<16>")
	)
	(segment
		(start 377.952 -105.317544)
		(end 377.790456 -105.317544)
		(width 0.1651)
		(layer "In9.Cu")
		(net "P5E_PEX3_STN1_TX_DN<16>")
	)
	(segment
		(start 378.634752 -104.473248)
		(end 378.29363 -104.81437)
		(width 0.1651)
		(layer "In9.Cu")
		(net "P5E_PEX3_STN1_TX_DN<16>")
	)
	(segment
		(start 407.949654 -278.115268)
		(end 407.949654 -277.849838)
		(width 0.1143)
		(layer "In9.Cu")
		(net "P5E_PEX3_STN1_TX_DN<16>")
	)
	(segment
		(start 407.615898 -271.500346)
		(end 407.570178 -271.546066)
		(width 0.1143)
		(layer "In9.Cu")
		(net "P5E_PEX3_STN1_TX_DN<16>")
	)
	(segment
		(start 384.614166 -99.887024)
		(end 384.167126 -100.071936)
		(width 0.1651)
		(layer "In9.Cu")
		(net "P5E_PEX3_STN1_TX_DN<16>")
	)
	(segment
		(start 376.519186 -107.183174)
		(end 376.329702 -107.641136)
		(width 0.1651)
		(layer "In9.Cu")
		(net "P5E_PEX3_STN1_TX_DN<16>")
	)
	(segment
		(start 380.826518 -102.281482)
		(end 380.826518 -102.443026)
		(width 0.1651)
		(layer "In9.Cu")
		(net "P5E_PEX3_STN1_TX_DN<16>")
	)
	(segment
		(start 379.479048 -103.628952)
		(end 379.137926 -103.970074)
		(width 0.1651)
		(layer "In9.Cu")
		(net "P5E_PEX3_STN1_TX_DN<16>")
	)
	(segment
		(start 384.105404 -100.221542)
		(end 383.659126 -100.4062)
		(width 0.1651)
		(layer "In9.Cu")
		(net "P5E_PEX3_STN1_TX_DN<16>")
	)
	(segment
		(start 379.982222 -103.287322)
		(end 379.640592 -103.628952)
		(width 0.1651)
		(layer "In9.Cu")
		(net "P5E_PEX3_STN1_TX_DN<16>")
	)
	(segment
		(start 407.615898 -271.471898)
		(end 407.615898 -271.500346)
		(width 0.1143)
		(layer "In9.Cu")
		(net "P5E_PEX3_STN1_TX_DN<16>")
	)
	(segment
		(start 381.329184 -101.94036)
		(end 381.16764 -101.94036)
		(width 0.1651)
		(layer "In9.Cu")
		(net "P5E_PEX3_STN1_TX_DN<16>")
	)
	(segment
		(start 381.16764 -101.94036)
		(end 380.826518 -102.281482)
		(width 0.1651)
		(layer "In9.Cu")
		(net "P5E_PEX3_STN1_TX_DN<16>")
	)
	(segment
		(start 374.688354 -111.304832)
		(end 368.787172 -130.75666)
		(width 0.1651)
		(layer "In9.Cu")
		(net "P5E_PEX3_STN1_TX_DN<16>")
	)
	(segment
		(start 379.137926 -103.970074)
		(end 379.137926 -104.131618)
		(width 0.1651)
		(layer "In9.Cu")
		(net "P5E_PEX3_STN1_TX_DN<16>")
	)
	(segment
		(start 376.728228 -106.379772)
		(end 376.457464 -107.033822)
		(width 0.1651)
		(layer "In9.Cu")
		(net "P5E_PEX3_STN1_TX_DN<16>")
	)
	(segment
		(start 380.826518 -102.443026)
		(end 380.484888 -102.784656)
		(width 0.1651)
		(layer "In9.Cu")
		(net "P5E_PEX3_STN1_TX_DN<16>")
	)
	(segment
		(start 381.67056 -101.598984)
		(end 381.329184 -101.94036)
		(width 0.1651)
		(layer "In9.Cu")
		(net "P5E_PEX3_STN1_TX_DN<16>")
	)
	(segment
		(start 407.835354 -278.229568)
		(end 407.949654 -278.115268)
		(width 0.1143)
		(layer "In9.Cu")
		(net "P5E_PEX3_STN1_TX_DN<16>")
	)
	(segment
		(start 368.787172 -130.75666)
		(end 368.787172 -139.08786)
		(width 0.1651)
		(layer "In9.Cu")
		(net "P5E_PEX3_STN1_TX_DN<16>")
	)
	(segment
		(start 425.408344 -348.880938)
		(end 425.703492 -348.58579)
		(width 0.13462)
		(layer "F.Cu")
		(net "P5E_PEX3_STN7_TX_DN<119>")
	)
	(segment
		(start 425.408344 -349.511366)
		(end 425.408344 -348.880938)
		(width 0.13462)
		(layer "F.Cu")
		(net "P5E_PEX3_STN7_TX_DN<119>")
	)
	(segment
		(start 425.728892 -349.831914)
		(end 425.408344 -349.511366)
		(width 0.13462)
		(layer "F.Cu")
		(net "P5E_PEX3_STN7_TX_DN<119>")
	)
	(segment
		(start 380.960122 -309.580788)
		(end 381.310388 -309.230522)
		(width 0.1651)
		(layer "In11.Cu")
		(net "P5E_PEX3_STN7_TX_DN<119>")
	)
	(segment
		(start 374.230392 -316.184788)
		(end 374.356122 -316.184788)
		(width 0.1651)
		(layer "In11.Cu")
		(net "P5E_PEX3_STN7_TX_DN<119>")
	)
	(segment
		(start 392.179556 -308.135528)
		(end 392.065256 -308.249828)
		(width 0.1143)
		(layer "In11.Cu")
		(net "P5E_PEX3_STN7_TX_DN<119>")
	)
	(segment
		(start 372.76278 -324.165214)
		(end 371.9322 -322.160138)
		(width 0.1651)
		(layer "In11.Cu")
		(net "P5E_PEX3_STN7_TX_DN<119>")
	)
	(segment
		(start 371.972078 -319.551304)
		(end 372.2497 -318.88049)
		(width 0.1651)
		(layer "In11.Cu")
		(net "P5E_PEX3_STN7_TX_DN<119>")
	)
	(segment
		(start 376.358912 -314.056268)
		(end 376.708924 -313.706256)
		(width 0.1651)
		(layer "In11.Cu")
		(net "P5E_PEX3_STN7_TX_DN<119>")
	)
	(segment
		(start 381.965708 -308.449472)
		(end 383.253742 -307.915818)
		(width 0.1651)
		(layer "In11.Cu")
		(net "P5E_PEX3_STN7_TX_DN<119>")
	)
	(segment
		(start 377.185174 -313.355736)
		(end 377.185174 -313.230006)
		(width 0.1651)
		(layer "In11.Cu")
		(net "P5E_PEX3_STN7_TX_DN<119>")
	)
	(segment
		(start 377.185174 -313.230006)
		(end 379.181868 -311.233312)
		(width 0.1651)
		(layer "In11.Cu")
		(net "P5E_PEX3_STN7_TX_DN<119>")
	)
	(segment
		(start 373.95658 -325.359014)
		(end 372.76278 -324.165214)
		(width 0.1651)
		(layer "In11.Cu")
		(net "P5E_PEX3_STN7_TX_DN<119>")
	)
	(segment
		(start 374.706388 -315.708792)
		(end 375.0564 -315.35878)
		(width 0.1651)
		(layer "In11.Cu")
		(net "P5E_PEX3_STN7_TX_DN<119>")
	)
	(segment
		(start 374.706388 -315.834522)
		(end 374.706388 -315.708792)
		(width 0.1651)
		(layer "In11.Cu")
		(net "P5E_PEX3_STN7_TX_DN<119>")
	)
	(segment
		(start 371.9322 -319.647316)
		(end 371.972078 -319.551304)
		(width 0.1651)
		(layer "In11.Cu")
		(net "P5E_PEX3_STN7_TX_DN<119>")
	)
	(segment
		(start 426.967142 -341.7062)
		(end 426.3644 -340.8934)
		(width 0.1651)
		(layer "In11.Cu")
		(net "P5E_PEX3_STN7_TX_DN<119>")
	)
	(segment
		(start 375.53265 -314.88253)
		(end 375.882662 -314.532518)
		(width 0.1651)
		(layer "In11.Cu")
		(net "P5E_PEX3_STN7_TX_DN<119>")
	)
	(segment
		(start 375.53265 -315.00826)
		(end 375.53265 -314.88253)
		(width 0.1651)
		(layer "In11.Cu")
		(net "P5E_PEX3_STN7_TX_DN<119>")
	)
	(segment
		(start 376.358912 -314.181998)
		(end 376.358912 -314.056268)
		(width 0.1651)
		(layer "In11.Cu")
		(net "P5E_PEX3_STN7_TX_DN<119>")
	)
	(segment
		(start 373.68988 -316.7253)
		(end 374.230392 -316.184788)
		(width 0.1651)
		(layer "In11.Cu")
		(net "P5E_PEX3_STN7_TX_DN<119>")
	)
	(segment
		(start 425.412662 -347.784674)
		(end 426.967142 -346.230194)
		(width 0.1651)
		(layer "In11.Cu")
		(net "P5E_PEX3_STN7_TX_DN<119>")
	)
	(segment
		(start 379.658118 -310.882792)
		(end 379.658118 -310.757062)
		(width 0.1651)
		(layer "In11.Cu")
		(net "P5E_PEX3_STN7_TX_DN<119>")
	)
	(segment
		(start 380.834392 -309.580788)
		(end 380.960122 -309.580788)
		(width 0.1651)
		(layer "In11.Cu")
		(net "P5E_PEX3_STN7_TX_DN<119>")
	)
	(segment
		(start 376.008392 -314.532518)
		(end 376.358912 -314.181998)
		(width 0.1651)
		(layer "In11.Cu")
		(net "P5E_PEX3_STN7_TX_DN<119>")
	)
	(segment
		(start 380.13386 -310.40705)
		(end 380.48438 -310.05653)
		(width 0.1651)
		(layer "In11.Cu")
		(net "P5E_PEX3_STN7_TX_DN<119>")
	)
	(segment
		(start 375.882662 -314.532518)
		(end 376.008392 -314.532518)
		(width 0.1651)
		(layer "In11.Cu")
		(net "P5E_PEX3_STN7_TX_DN<119>")
	)
	(segment
		(start 379.181868 -311.233312)
		(end 379.307598 -311.233312)
		(width 0.1651)
		(layer "In11.Cu")
		(net "P5E_PEX3_STN7_TX_DN<119>")
	)
	(segment
		(start 372.2497 -318.88049)
		(end 373.68988 -316.7253)
		(width 0.1651)
		(layer "In11.Cu")
		(net "P5E_PEX3_STN7_TX_DN<119>")
	)
	(segment
		(start 381.310388 -309.104792)
		(end 381.965708 -308.449472)
		(width 0.1651)
		(layer "In11.Cu")
		(net "P5E_PEX3_STN7_TX_DN<119>")
	)
	(segment
		(start 376.708924 -313.706256)
		(end 376.834654 -313.706256)
		(width 0.1651)
		(layer "In11.Cu")
		(net "P5E_PEX3_STN7_TX_DN<119>")
	)
	(segment
		(start 425.412662 -348.29496)
		(end 425.412662 -347.784674)
		(width 0.1651)
		(layer "In11.Cu")
		(net "P5E_PEX3_STN7_TX_DN<119>")
	)
	(segment
		(start 425.703492 -348.58579)
		(end 425.412662 -348.29496)
		(width 0.1651)
		(layer "In11.Cu")
		(net "P5E_PEX3_STN7_TX_DN<119>")
	)
	(segment
		(start 383.968752 -307.915818)
		(end 383.9972 -307.915818)
		(width 0.1143)
		(layer "In11.Cu")
		(net "P5E_PEX3_STN7_TX_DN<119>")
	)
	(segment
		(start 392.075924 -307.870098)
		(end 392.179556 -307.97373)
		(width 0.1143)
		(layer "In11.Cu")
		(net "P5E_PEX3_STN7_TX_DN<119>")
	)
	(segment
		(start 380.48438 -309.9308)
		(end 380.834392 -309.580788)
		(width 0.1651)
		(layer "In11.Cu")
		(net "P5E_PEX3_STN7_TX_DN<119>")
	)
	(segment
		(start 381.310388 -309.230522)
		(end 381.310388 -309.104792)
		(width 0.1651)
		(layer "In11.Cu")
		(net "P5E_PEX3_STN7_TX_DN<119>")
	)
	(segment
		(start 380.00813 -310.40705)
		(end 380.13386 -310.40705)
		(width 0.1651)
		(layer "In11.Cu")
		(net "P5E_PEX3_STN7_TX_DN<119>")
	)
	(segment
		(start 392.065256 -308.249828)
		(end 391.799826 -308.249828)
		(width 0.1143)
		(layer "In11.Cu")
		(net "P5E_PEX3_STN7_TX_DN<119>")
	)
	(segment
		(start 426.3644 -340.8934)
		(end 419.863524 -336.426302)
		(width 0.1651)
		(layer "In11.Cu")
		(net "P5E_PEX3_STN7_TX_DN<119>")
	)
	(segment
		(start 383.253742 -307.915818)
		(end 383.968752 -307.915818)
		(width 0.1651)
		(layer "In11.Cu")
		(net "P5E_PEX3_STN7_TX_DN<119>")
	)
	(segment
		(start 374.356122 -316.184788)
		(end 374.706388 -315.834522)
		(width 0.1651)
		(layer "In11.Cu")
		(net "P5E_PEX3_STN7_TX_DN<119>")
	)
	(segment
		(start 392.179556 -307.97373)
		(end 392.179556 -308.135528)
		(width 0.1143)
		(layer "In11.Cu")
		(net "P5E_PEX3_STN7_TX_DN<119>")
	)
	(segment
		(start 379.658118 -310.757062)
		(end 380.00813 -310.40705)
		(width 0.1651)
		(layer "In11.Cu")
		(net "P5E_PEX3_STN7_TX_DN<119>")
	)
	(segment
		(start 383.9972 -307.915818)
		(end 384.04292 -307.870098)
		(width 0.1143)
		(layer "In11.Cu")
		(net "P5E_PEX3_STN7_TX_DN<119>")
	)
	(segment
		(start 380.48438 -310.05653)
		(end 380.48438 -309.9308)
		(width 0.1651)
		(layer "In11.Cu")
		(net "P5E_PEX3_STN7_TX_DN<119>")
	)
	(segment
		(start 384.04292 -307.870098)
		(end 392.075924 -307.870098)
		(width 0.1143)
		(layer "In11.Cu")
		(net "P5E_PEX3_STN7_TX_DN<119>")
	)
	(segment
		(start 375.0564 -315.35878)
		(end 375.18213 -315.35878)
		(width 0.1651)
		(layer "In11.Cu")
		(net "P5E_PEX3_STN7_TX_DN<119>")
	)
	(segment
		(start 426.967142 -346.230194)
		(end 426.967142 -341.7062)
		(width 0.1651)
		(layer "In11.Cu")
		(net "P5E_PEX3_STN7_TX_DN<119>")
	)
	(segment
		(start 376.157744 -326.57161)
		(end 373.95658 -325.359014)
		(width 0.1651)
		(layer "In11.Cu")
		(net "P5E_PEX3_STN7_TX_DN<119>")
	)
	(segment
		(start 376.834654 -313.706256)
		(end 377.185174 -313.355736)
		(width 0.1651)
		(layer "In11.Cu")
		(net "P5E_PEX3_STN7_TX_DN<119>")
	)
	(segment
		(start 375.18213 -315.35878)
		(end 375.53265 -315.00826)
		(width 0.1651)
		(layer "In11.Cu")
		(net "P5E_PEX3_STN7_TX_DN<119>")
	)
	(segment
		(start 371.9322 -322.160138)
		(end 371.9322 -319.647316)
		(width 0.1651)
		(layer "In11.Cu")
		(net "P5E_PEX3_STN7_TX_DN<119>")
	)
	(segment
		(start 379.307598 -311.233312)
		(end 379.658118 -310.882792)
		(width 0.1651)
		(layer "In11.Cu")
		(net "P5E_PEX3_STN7_TX_DN<119>")
	)
	(segment
		(start 419.863524 -336.426302)
		(end 376.157744 -326.57161)
		(width 0.1651)
		(layer "In11.Cu")
		(net "P5E_PEX3_STN7_TX_DN<119>")
	)
	(segment
		(start 83.429602 -343.365582)
		(end 83.429602 -342.734138)
		(width 0.13462)
		(layer "F.Cu")
		(net "P5E_PEX0_STN5_TX_DP<90>")
	)
	(segment
		(start 83.429602 -342.734138)
		(end 83.134962 -342.439498)
		(width 0.13462)
		(layer "F.Cu")
		(net "P5E_PEX0_STN5_TX_DP<90>")
	)
	(segment
		(start 83.109562 -343.685622)
		(end 83.429602 -343.365582)
		(width 0.13462)
		(layer "F.Cu")
		(net "P5E_PEX0_STN5_TX_DP<90>")
	)
	(segment
		(start 67.583812 -321.463924)
		(end 67.583812 -319.916048)
		(width 0.1651)
		(layer "In7.Cu")
		(net "P5E_PEX0_STN5_TX_DP<90>")
	)
	(segment
		(start 83.051904 -340.098126)
		(end 74.42327 -329.584304)
		(width 0.1651)
		(layer "In7.Cu")
		(net "P5E_PEX0_STN5_TX_DP<90>")
	)
	(segment
		(start 68.199762 -311.365392)
		(end 68.199762 -311.099962)
		(width 0.1143)
		(layer "In7.Cu")
		(net "P5E_PEX0_STN5_TX_DP<90>")
	)
	(segment
		(start 67.629532 -311.705498)
		(end 67.855338 -311.479692)
		(width 0.1143)
		(layer "In7.Cu")
		(net "P5E_PEX0_STN5_TX_DP<90>")
	)
	(segment
		(start 67.629532 -319.84188)
		(end 67.629532 -311.705498)
		(width 0.1143)
		(layer "In7.Cu")
		(net "P5E_PEX0_STN5_TX_DP<90>")
	)
	(segment
		(start 68.071238 -322.64096)
		(end 67.583812 -321.463924)
		(width 0.1651)
		(layer "In7.Cu")
		(net "P5E_PEX0_STN5_TX_DP<90>")
	)
	(segment
		(start 69.262244 -324.423024)
		(end 68.071238 -322.64096)
		(width 0.1651)
		(layer "In7.Cu")
		(net "P5E_PEX0_STN5_TX_DP<90>")
	)
	(segment
		(start 67.583812 -319.8876)
		(end 67.629532 -319.84188)
		(width 0.1143)
		(layer "In7.Cu")
		(net "P5E_PEX0_STN5_TX_DP<90>")
	)
	(segment
		(start 83.425792 -342.148668)
		(end 83.425792 -341.000588)
		(width 0.1651)
		(layer "In7.Cu")
		(net "P5E_PEX0_STN5_TX_DP<90>")
	)
	(segment
		(start 68.085462 -311.479692)
		(end 68.199762 -311.365392)
		(width 0.1143)
		(layer "In7.Cu")
		(net "P5E_PEX0_STN5_TX_DP<90>")
	)
	(segment
		(start 83.425538 -341.000334)
		(end 83.051904 -340.098126)
		(width 0.1651)
		(layer "In7.Cu")
		(net "P5E_PEX0_STN5_TX_DP<90>")
	)
	(segment
		(start 83.134962 -342.439498)
		(end 83.425792 -342.148668)
		(width 0.1651)
		(layer "In7.Cu")
		(net "P5E_PEX0_STN5_TX_DP<90>")
	)
	(segment
		(start 83.425792 -341.000588)
		(end 83.425538 -341.000334)
		(width 0.1651)
		(layer "In7.Cu")
		(net "P5E_PEX0_STN5_TX_DP<90>")
	)
	(segment
		(start 74.42327 -329.584304)
		(end 69.262244 -324.423024)
		(width 0.1651)
		(layer "In7.Cu")
		(net "P5E_PEX0_STN5_TX_DP<90>")
	)
	(segment
		(start 67.583812 -319.916048)
		(end 67.583812 -319.8876)
		(width 0.1143)
		(layer "In7.Cu")
		(net "P5E_PEX0_STN5_TX_DP<90>")
	)
	(segment
		(start 67.855338 -311.479692)
		(end 68.085462 -311.479692)
		(width 0.1143)
		(layer "In7.Cu")
		(net "P5E_PEX0_STN5_TX_DP<90>")
	)
	(segment
		(start 190.047372 -34.520886)
		(end 189.765686 -34.2392)
		(width 0.13462)
		(layer "F.Cu")
		(net "P5E_PEX1_STN2_TX_DP<39>")
	)
	(segment
		(start 189.765686 -34.2392)
		(end 189.108334 -34.2392)
		(width 0.13462)
		(layer "F.Cu")
		(net "P5E_PEX1_STN2_TX_DP<39>")
	)
	(segment
		(start 189.108334 -34.2392)
		(end 188.801248 -34.546286)
		(width 0.13462)
		(layer "F.Cu")
		(net "P5E_PEX1_STN2_TX_DP<39>")
	)
	(segment
		(start 174.884842 -121.433336)
		(end 167.534082 -262.791702)
		(width 0.1651)
		(layer "In11.Cu")
		(net "P5E_PEX1_STN2_TX_DP<39>")
	)
	(segment
		(start 177.17008 -107.162092)
		(end 175.746918 -114.435636)
		(width 0.1651)
		(layer "In11.Cu")
		(net "P5E_PEX1_STN2_TX_DP<39>")
	)
	(segment
		(start 175.02886 -120.262396)
		(end 175.006254 -120.44807)
		(width 0.1651)
		(layer "In11.Cu")
		(net "P5E_PEX1_STN2_TX_DP<39>")
	)
	(segment
		(start 192.902586 -36.024312)
		(end 193.389504 -36.819586)
		(width 0.1651)
		(layer "In11.Cu")
		(net "P5E_PEX1_STN2_TX_DP<39>")
	)
	(segment
		(start 167.534082 -271.427448)
		(end 167.579802 -271.473168)
		(width 0.1143)
		(layer "In11.Cu")
		(net "P5E_PEX1_STN2_TX_DP<39>")
	)
	(segment
		(start 203.611226 -61.953394)
		(end 202.742546 -63.68415)
		(width 0.1651)
		(layer "In11.Cu")
		(net "P5E_PEX1_STN2_TX_DP<39>")
	)
	(segment
		(start 193.999358 -37.816536)
		(end 193.970148 -37.93871)
		(width 0.1651)
		(layer "In11.Cu")
		(net "P5E_PEX1_STN2_TX_DP<39>")
	)
	(segment
		(start 168.150032 -278.534368)
		(end 168.150032 -278.799798)
		(width 0.1143)
		(layer "In11.Cu")
		(net "P5E_PEX1_STN2_TX_DP<39>")
	)
	(segment
		(start 190.047372 -34.520886)
		(end 190.338202 -34.230056)
		(width 0.1651)
		(layer "In11.Cu")
		(net "P5E_PEX1_STN2_TX_DP<39>")
	)
	(segment
		(start 167.579802 -278.20493)
		(end 167.79494 -278.420068)
		(width 0.1143)
		(layer "In11.Cu")
		(net "P5E_PEX1_STN2_TX_DP<39>")
	)
	(segment
		(start 193.970148 -37.93871)
		(end 194.228974 -38.361366)
		(width 0.1651)
		(layer "In11.Cu")
		(net "P5E_PEX1_STN2_TX_DP<39>")
	)
	(segment
		(start 204.095096 -58.556144)
		(end 204.095096 -60.128404)
		(width 0.1651)
		(layer "In11.Cu")
		(net "P5E_PEX1_STN2_TX_DP<39>")
	)
	(segment
		(start 167.534082 -262.791702)
		(end 167.534082 -271.399)
		(width 0.1651)
		(layer "In11.Cu")
		(net "P5E_PEX1_STN2_TX_DP<39>")
	)
	(segment
		(start 167.579802 -271.473168)
		(end 167.579802 -278.20493)
		(width 0.1143)
		(layer "In11.Cu")
		(net "P5E_PEX1_STN2_TX_DP<39>")
	)
	(segment
		(start 194.351148 -38.39083)
		(end 196.568822 -42.014394)
		(width 0.1651)
		(layer "In11.Cu")
		(net "P5E_PEX1_STN2_TX_DP<39>")
	)
	(segment
		(start 194.228974 -38.361366)
		(end 194.351148 -38.39083)
		(width 0.1651)
		(layer "In11.Cu")
		(net "P5E_PEX1_STN2_TX_DP<39>")
	)
	(segment
		(start 167.534082 -271.399)
		(end 167.534082 -271.427448)
		(width 0.1143)
		(layer "In11.Cu")
		(net "P5E_PEX1_STN2_TX_DP<39>")
	)
	(segment
		(start 190.338202 -34.230056)
		(end 190.8556 -34.230056)
		(width 0.1651)
		(layer "In11.Cu")
		(net "P5E_PEX1_STN2_TX_DP<39>")
	)
	(segment
		(start 175.006 -120.44807)
		(end 174.884842 -121.433336)
		(width 0.1651)
		(layer "In11.Cu")
		(net "P5E_PEX1_STN2_TX_DP<39>")
	)
	(segment
		(start 204.095096 -60.128404)
		(end 203.611226 -61.953394)
		(width 0.1651)
		(layer "In11.Cu")
		(net "P5E_PEX1_STN2_TX_DP<39>")
	)
	(segment
		(start 193.389504 -36.819586)
		(end 193.36004 -36.942014)
		(width 0.1651)
		(layer "In11.Cu")
		(net "P5E_PEX1_STN2_TX_DP<39>")
	)
	(segment
		(start 168.035732 -278.420068)
		(end 168.150032 -278.534368)
		(width 0.1143)
		(layer "In11.Cu")
		(net "P5E_PEX1_STN2_TX_DP<39>")
	)
	(segment
		(start 175.006254 -120.44807)
		(end 175.006 -120.44807)
		(width 0.1651)
		(layer "In11.Cu")
		(net "P5E_PEX1_STN2_TX_DP<39>")
	)
	(segment
		(start 196.568822 -42.014394)
		(end 203.111608 -49.155858)
		(width 0.1651)
		(layer "In11.Cu")
		(net "P5E_PEX1_STN2_TX_DP<39>")
	)
	(segment
		(start 191.310768 -34.419794)
		(end 192.902586 -36.024312)
		(width 0.1651)
		(layer "In11.Cu")
		(net "P5E_PEX1_STN2_TX_DP<39>")
	)
	(segment
		(start 175.746918 -114.435636)
		(end 175.029368 -120.262396)
		(width 0.1651)
		(layer "In11.Cu")
		(net "P5E_PEX1_STN2_TX_DP<39>")
	)
	(segment
		(start 180.46954 -92.692474)
		(end 177.17008 -107.162092)
		(width 0.1651)
		(layer "In11.Cu")
		(net "P5E_PEX1_STN2_TX_DP<39>")
	)
	(segment
		(start 167.79494 -278.420068)
		(end 168.035732 -278.420068)
		(width 0.1143)
		(layer "In11.Cu")
		(net "P5E_PEX1_STN2_TX_DP<39>")
	)
	(segment
		(start 202.742546 -63.68415)
		(end 180.46954 -92.692474)
		(width 0.1651)
		(layer "In11.Cu")
		(net "P5E_PEX1_STN2_TX_DP<39>")
	)
	(segment
		(start 193.618866 -37.36467)
		(end 193.74104 -37.394134)
		(width 0.1651)
		(layer "In11.Cu")
		(net "P5E_PEX1_STN2_TX_DP<39>")
	)
	(segment
		(start 203.111608 -49.155858)
		(end 204.095096 -58.556144)
		(width 0.1651)
		(layer "In11.Cu")
		(net "P5E_PEX1_STN2_TX_DP<39>")
	)
	(segment
		(start 193.74104 -37.394134)
		(end 193.999358 -37.816536)
		(width 0.1651)
		(layer "In11.Cu")
		(net "P5E_PEX1_STN2_TX_DP<39>")
	)
	(segment
		(start 190.8556 -34.230056)
		(end 191.310768 -34.419794)
		(width 0.1651)
		(layer "In11.Cu")
		(net "P5E_PEX1_STN2_TX_DP<39>")
	)
	(segment
		(start 193.36004 -36.942014)
		(end 193.618866 -37.36467)
		(width 0.1651)
		(layer "In11.Cu")
		(net "P5E_PEX1_STN2_TX_DP<39>")
	)
	(segment
		(start 175.029368 -120.262396)
		(end 175.02886 -120.262396)
		(width 0.1651)
		(layer "In11.Cu")
		(net "P5E_PEX1_STN2_TX_DP<39>")
	)
	(segment
		(start 332.045564 -349.831914)
		(end 331.725524 -349.511874)
		(width 0.13462)
		(layer "F.Cu")
		(net "P5E_PEX2_STN5_TX_DN<89>")
	)
	(segment
		(start 331.725524 -348.88043)
		(end 332.020164 -348.58579)
		(width 0.13462)
		(layer "F.Cu")
		(net "P5E_PEX2_STN5_TX_DN<89>")
	)
	(segment
		(start 331.725524 -349.511874)
		(end 331.725524 -348.88043)
		(width 0.13462)
		(layer "F.Cu")
		(net "P5E_PEX2_STN5_TX_DN<89>")
	)
	(segment
		(start 333.283814 -346.230194)
		(end 333.283814 -342.0872)
		(width 0.1651)
		(layer "In7.Cu")
		(net "P5E_PEX2_STN5_TX_DN<89>")
	)
	(segment
		(start 299.070014 -319.84188)
		(end 299.070014 -313.684412)
		(width 0.1143)
		(layer "In7.Cu")
		(net "P5E_PEX2_STN5_TX_DN<89>")
	)
	(segment
		(start 324.743826 -335.20761)
		(end 302.575722 -326.103742)
		(width 0.1651)
		(layer "In7.Cu")
		(net "P5E_PEX2_STN5_TX_DN<89>")
	)
	(segment
		(start 299.449744 -313.684412)
		(end 299.449744 -313.949842)
		(width 0.1143)
		(layer "In7.Cu")
		(net "P5E_PEX2_STN5_TX_DN<89>")
	)
	(segment
		(start 299.335444 -313.570112)
		(end 299.449744 -313.684412)
		(width 0.1143)
		(layer "In7.Cu")
		(net "P5E_PEX2_STN5_TX_DN<89>")
	)
	(segment
		(start 299.115734 -320.954908)
		(end 299.115734 -319.916048)
		(width 0.1651)
		(layer "In7.Cu")
		(net "P5E_PEX2_STN5_TX_DN<89>")
	)
	(segment
		(start 302.575722 -326.103742)
		(end 301.926498 -325.454518)
		(width 0.1651)
		(layer "In7.Cu")
		(net "P5E_PEX2_STN5_TX_DN<89>")
	)
	(segment
		(start 300.310042 -323.838062)
		(end 299.115734 -320.954908)
		(width 0.1651)
		(layer "In7.Cu")
		(net "P5E_PEX2_STN5_TX_DN<89>")
	)
	(segment
		(start 333.283814 -342.0872)
		(end 332.734158 -340.816692)
		(width 0.1651)
		(layer "In7.Cu")
		(net "P5E_PEX2_STN5_TX_DN<89>")
	)
	(segment
		(start 331.729334 -347.784674)
		(end 333.283814 -346.230194)
		(width 0.1651)
		(layer "In7.Cu")
		(net "P5E_PEX2_STN5_TX_DN<89>")
	)
	(segment
		(start 332.020164 -348.58579)
		(end 331.729334 -348.29496)
		(width 0.1651)
		(layer "In7.Cu")
		(net "P5E_PEX2_STN5_TX_DN<89>")
	)
	(segment
		(start 299.070014 -313.684412)
		(end 299.184314 -313.570112)
		(width 0.1143)
		(layer "In7.Cu")
		(net "P5E_PEX2_STN5_TX_DN<89>")
	)
	(segment
		(start 301.575978 -324.996302)
		(end 301.468282 -324.996302)
		(width 0.1651)
		(layer "In7.Cu")
		(net "P5E_PEX2_STN5_TX_DN<89>")
	)
	(segment
		(start 301.926498 -325.346822)
		(end 301.575978 -324.996302)
		(width 0.1651)
		(layer "In7.Cu")
		(net "P5E_PEX2_STN5_TX_DN<89>")
	)
	(segment
		(start 301.926498 -325.454518)
		(end 301.926498 -325.346822)
		(width 0.1651)
		(layer "In7.Cu")
		(net "P5E_PEX2_STN5_TX_DN<89>")
	)
	(segment
		(start 299.115734 -319.916048)
		(end 299.115734 -319.8876)
		(width 0.1143)
		(layer "In7.Cu")
		(net "P5E_PEX2_STN5_TX_DN<89>")
	)
	(segment
		(start 299.184314 -313.570112)
		(end 299.335444 -313.570112)
		(width 0.1143)
		(layer "In7.Cu")
		(net "P5E_PEX2_STN5_TX_DN<89>")
	)
	(segment
		(start 331.729334 -348.29496)
		(end 331.729334 -347.784674)
		(width 0.1651)
		(layer "In7.Cu")
		(net "P5E_PEX2_STN5_TX_DN<89>")
	)
	(segment
		(start 301.468282 -324.996302)
		(end 300.310042 -323.838062)
		(width 0.1651)
		(layer "In7.Cu")
		(net "P5E_PEX2_STN5_TX_DN<89>")
	)
	(segment
		(start 299.115734 -319.8876)
		(end 299.070014 -319.84188)
		(width 0.1143)
		(layer "In7.Cu")
		(net "P5E_PEX2_STN5_TX_DN<89>")
	)
	(segment
		(start 332.734158 -340.816692)
		(end 324.743826 -335.20761)
		(width 0.1651)
		(layer "In7.Cu")
		(net "P5E_PEX2_STN5_TX_DN<89>")
	)
	(segment
		(start 431.54854 -124.67082)
		(end 431.228246 -124.991114)
		(width 0.13462)
		(layer "F.Cu")
		(net "P5E_PEX3_STN0_TX_DP<3>")
	)
	(segment
		(start 432.47437 -124.965714)
		(end 432.179476 -124.67082)
		(width 0.13462)
		(layer "F.Cu")
		(net "P5E_PEX3_STN0_TX_DP<3>")
	)
	(segment
		(start 432.179476 -124.67082)
		(end 431.54854 -124.67082)
		(width 0.13462)
		(layer "F.Cu")
		(net "P5E_PEX3_STN0_TX_DP<3>")
	)
	(segment
		(start 435.563264 -130.687318)
		(end 435.696614 -130.74142)
		(width 0.1651)
		(layer "In9.Cu")
		(net "P5E_PEX3_STN0_TX_DP<3>")
	)
	(segment
		(start 434.951632 -129.235454)
		(end 435.129178 -129.657094)
		(width 0.1651)
		(layer "In9.Cu")
		(net "P5E_PEX3_STN0_TX_DP<3>")
	)
	(segment
		(start 433.959508 -126.621286)
		(end 434.137054 -127.042418)
		(width 0.1651)
		(layer "In9.Cu")
		(net "P5E_PEX3_STN0_TX_DP<3>")
	)
	(segment
		(start 433.52339 -124.887736)
		(end 433.699412 -125.312932)
		(width 0.1651)
		(layer "In9.Cu")
		(net "P5E_PEX3_STN0_TX_DP<3>")
	)
	(segment
		(start 435.262274 -129.71145)
		(end 435.43982 -130.132582)
		(width 0.1651)
		(layer "In9.Cu")
		(net "P5E_PEX3_STN0_TX_DP<3>")
	)
	(segment
		(start 435.87416 -131.162552)
		(end 435.820058 -131.295648)
		(width 0.1651)
		(layer "In9.Cu")
		(net "P5E_PEX3_STN0_TX_DP<3>")
	)
	(segment
		(start 423.529506 -285.09468)
		(end 423.529506 -285.335472)
		(width 0.1143)
		(layer "In9.Cu")
		(net "P5E_PEX3_STN0_TX_DP<3>")
	)
	(segment
		(start 444.607188 -275.130006)
		(end 435.912768 -283.824426)
		(width 0.1651)
		(layer "In9.Cu")
		(net "P5E_PEX3_STN0_TX_DP<3>")
	)
	(segment
		(start 433.476654 -284.833568)
		(end 432.1937 -284.833568)
		(width 0.1651)
		(layer "In9.Cu")
		(net "P5E_PEX3_STN0_TX_DP<3>")
	)
	(segment
		(start 434.260498 -127.597154)
		(end 434.393848 -127.651256)
		(width 0.1651)
		(layer "In9.Cu")
		(net "P5E_PEX3_STN0_TX_DP<3>")
	)
	(segment
		(start 432.119532 -284.879288)
		(end 423.744898 -284.879288)
		(width 0.1143)
		(layer "In9.Cu")
		(net "P5E_PEX3_STN0_TX_DP<3>")
	)
	(segment
		(start 434.694838 -128.627124)
		(end 434.828188 -128.681226)
		(width 0.1651)
		(layer "In9.Cu")
		(net "P5E_PEX3_STN0_TX_DP<3>")
	)
	(segment
		(start 433.699412 -125.312932)
		(end 433.959508 -126.621286)
		(width 0.1651)
		(layer "In9.Cu")
		(net "P5E_PEX3_STN0_TX_DP<3>")
	)
	(segment
		(start 445.79667 -272.258028)
		(end 444.607188 -275.130006)
		(width 0.1651)
		(layer "In9.Cu")
		(net "P5E_PEX3_STN0_TX_DP<3>")
	)
	(segment
		(start 445.425576 -267.996162)
		(end 445.79667 -272.258028)
		(width 0.1651)
		(layer "In9.Cu")
		(net "P5E_PEX3_STN0_TX_DP<3>")
	)
	(segment
		(start 423.529506 -285.335472)
		(end 423.415206 -285.449772)
		(width 0.1143)
		(layer "In9.Cu")
		(net "P5E_PEX3_STN0_TX_DP<3>")
	)
	(segment
		(start 445.152526 -160.047178)
		(end 436.494428 -175.049942)
		(width 0.1651)
		(layer "In9.Cu")
		(net "P5E_PEX3_STN0_TX_DP<3>")
	)
	(segment
		(start 434.57114 -128.072388)
		(end 434.571394 -128.072388)
		(width 0.1651)
		(layer "In9.Cu")
		(net "P5E_PEX3_STN0_TX_DP<3>")
	)
	(segment
		(start 435.00548 -129.102358)
		(end 435.005734 -129.102358)
		(width 0.1651)
		(layer "In9.Cu")
		(net "P5E_PEX3_STN0_TX_DP<3>")
	)
	(segment
		(start 434.137054 -127.042418)
		(end 434.082952 -127.175514)
		(width 0.1651)
		(layer "In9.Cu")
		(net "P5E_PEX3_STN0_TX_DP<3>")
	)
	(segment
		(start 435.493414 -178.781202)
		(end 431.74412 -221.628208)
		(width 0.1651)
		(layer "In9.Cu")
		(net "P5E_PEX3_STN0_TX_DP<3>")
	)
	(segment
		(start 436.892446 -132.92328)
		(end 437.072532 -133.358636)
		(width 0.1651)
		(layer "In9.Cu")
		(net "P5E_PEX3_STN0_TX_DP<3>")
	)
	(segment
		(start 437.753252 -135.001762)
		(end 445.286384 -153.18867)
		(width 0.1651)
		(layer "In9.Cu")
		(net "P5E_PEX3_STN0_TX_DP<3>")
	)
	(segment
		(start 434.517292 -128.205484)
		(end 434.694838 -128.627124)
		(width 0.1651)
		(layer "In9.Cu")
		(net "P5E_PEX3_STN0_TX_DP<3>")
	)
	(segment
		(start 432.165252 -284.833568)
		(end 432.119532 -284.879288)
		(width 0.1143)
		(layer "In9.Cu")
		(net "P5E_PEX3_STN0_TX_DP<3>")
	)
	(segment
		(start 432.47437 -124.965714)
		(end 432.7652 -124.674884)
		(width 0.1651)
		(layer "In9.Cu")
		(net "P5E_PEX3_STN0_TX_DP<3>")
	)
	(segment
		(start 437.192674 -133.91388)
		(end 437.325516 -133.968998)
		(width 0.1651)
		(layer "In9.Cu")
		(net "P5E_PEX3_STN0_TX_DP<3>")
	)
	(segment
		(start 436.494428 -175.049942)
		(end 435.493414 -178.781202)
		(width 0.1651)
		(layer "In9.Cu")
		(net "P5E_PEX3_STN0_TX_DP<3>")
	)
	(segment
		(start 434.263546 -250.487688)
		(end 444.548768 -265.879326)
		(width 0.1651)
		(layer "In9.Cu")
		(net "P5E_PEX3_STN0_TX_DP<3>")
	)
	(segment
		(start 437.445404 -134.523988)
		(end 437.62041 -134.946644)
		(width 0.1651)
		(layer "In9.Cu")
		(net "P5E_PEX3_STN0_TX_DP<3>")
	)
	(segment
		(start 444.548768 -265.879326)
		(end 445.425576 -267.996162)
		(width 0.1651)
		(layer "In9.Cu")
		(net "P5E_PEX3_STN0_TX_DP<3>")
	)
	(segment
		(start 434.571394 -128.072388)
		(end 434.517292 -128.205484)
		(width 0.1651)
		(layer "In9.Cu")
		(net "P5E_PEX3_STN0_TX_DP<3>")
	)
	(segment
		(start 431.74412 -221.628208)
		(end 434.263546 -250.487688)
		(width 0.1651)
		(layer "In9.Cu")
		(net "P5E_PEX3_STN0_TX_DP<3>")
	)
	(segment
		(start 434.393594 -127.651256)
		(end 434.57114 -128.072388)
		(width 0.1651)
		(layer "In9.Cu")
		(net "P5E_PEX3_STN0_TX_DP<3>")
	)
	(segment
		(start 437.017668 -133.491224)
		(end 437.192674 -133.91388)
		(width 0.1651)
		(layer "In9.Cu")
		(net "P5E_PEX3_STN0_TX_DP<3>")
	)
	(segment
		(start 435.696614 -130.74142)
		(end 435.87416 -131.162552)
		(width 0.1651)
		(layer "In9.Cu")
		(net "P5E_PEX3_STN0_TX_DP<3>")
	)
	(segment
		(start 436.41518 -132.44576)
		(end 436.892446 -132.92328)
		(width 0.1651)
		(layer "In9.Cu")
		(net "P5E_PEX3_STN0_TX_DP<3>")
	)
	(segment
		(start 435.262528 -129.711196)
		(end 435.262274 -129.71145)
		(width 0.1651)
		(layer "In9.Cu")
		(net "P5E_PEX3_STN0_TX_DP<3>")
	)
	(segment
		(start 435.005734 -129.102358)
		(end 434.951632 -129.235454)
		(width 0.1651)
		(layer "In9.Cu")
		(net "P5E_PEX3_STN0_TX_DP<3>")
	)
	(segment
		(start 437.072532 -133.358636)
		(end 437.017668 -133.491224)
		(width 0.1651)
		(layer "In9.Cu")
		(net "P5E_PEX3_STN0_TX_DP<3>")
	)
	(segment
		(start 432.1937 -284.833568)
		(end 432.165252 -284.833568)
		(width 0.1143)
		(layer "In9.Cu")
		(net "P5E_PEX3_STN0_TX_DP<3>")
	)
	(segment
		(start 437.500268 -134.391146)
		(end 437.445404 -134.523988)
		(width 0.1651)
		(layer "In9.Cu")
		(net "P5E_PEX3_STN0_TX_DP<3>")
	)
	(segment
		(start 435.385718 -130.265678)
		(end 435.563264 -130.687318)
		(width 0.1651)
		(layer "In9.Cu")
		(net "P5E_PEX3_STN0_TX_DP<3>")
	)
	(segment
		(start 437.325516 -133.968998)
		(end 437.500268 -134.391146)
		(width 0.1651)
		(layer "In9.Cu")
		(net "P5E_PEX3_STN0_TX_DP<3>")
	)
	(segment
		(start 433.310538 -124.674884)
		(end 433.52339 -124.887736)
		(width 0.1651)
		(layer "In9.Cu")
		(net "P5E_PEX3_STN0_TX_DP<3>")
	)
	(segment
		(start 435.129178 -129.657094)
		(end 435.262528 -129.711196)
		(width 0.1651)
		(layer "In9.Cu")
		(net "P5E_PEX3_STN0_TX_DP<3>")
	)
	(segment
		(start 434.393848 -127.651256)
		(end 434.393594 -127.651256)
		(width 0.1651)
		(layer "In9.Cu")
		(net "P5E_PEX3_STN0_TX_DP<3>")
	)
	(segment
		(start 434.827934 -128.681226)
		(end 435.00548 -129.102358)
		(width 0.1651)
		(layer "In9.Cu")
		(net "P5E_PEX3_STN0_TX_DP<3>")
	)
	(segment
		(start 432.7652 -124.674884)
		(end 433.310538 -124.674884)
		(width 0.1651)
		(layer "In9.Cu")
		(net "P5E_PEX3_STN0_TX_DP<3>")
	)
	(segment
		(start 435.43982 -130.132582)
		(end 435.385718 -130.265678)
		(width 0.1651)
		(layer "In9.Cu")
		(net "P5E_PEX3_STN0_TX_DP<3>")
	)
	(segment
		(start 445.286384 -159.546544)
		(end 445.152526 -160.047178)
		(width 0.1651)
		(layer "In9.Cu")
		(net "P5E_PEX3_STN0_TX_DP<3>")
	)
	(segment
		(start 437.62041 -134.946644)
		(end 437.753252 -135.001762)
		(width 0.1651)
		(layer "In9.Cu")
		(net "P5E_PEX3_STN0_TX_DP<3>")
	)
	(segment
		(start 435.912768 -283.824426)
		(end 433.476654 -284.833568)
		(width 0.1651)
		(layer "In9.Cu")
		(net "P5E_PEX3_STN0_TX_DP<3>")
	)
	(segment
		(start 423.415206 -285.449772)
		(end 423.149776 -285.449772)
		(width 0.1143)
		(layer "In9.Cu")
		(net "P5E_PEX3_STN0_TX_DP<3>")
	)
	(segment
		(start 435.997604 -131.717288)
		(end 436.130954 -131.77139)
		(width 0.1651)
		(layer "In9.Cu")
		(net "P5E_PEX3_STN0_TX_DP<3>")
	)
	(segment
		(start 434.082952 -127.175514)
		(end 434.260498 -127.597154)
		(width 0.1651)
		(layer "In9.Cu")
		(net "P5E_PEX3_STN0_TX_DP<3>")
	)
	(segment
		(start 436.130954 -131.77139)
		(end 436.41518 -132.44576)
		(width 0.1651)
		(layer "In9.Cu")
		(net "P5E_PEX3_STN0_TX_DP<3>")
	)
	(segment
		(start 445.286384 -153.18867)
		(end 445.286384 -159.546544)
		(width 0.1651)
		(layer "In9.Cu")
		(net "P5E_PEX3_STN0_TX_DP<3>")
	)
	(segment
		(start 423.744898 -284.879288)
		(end 423.529506 -285.09468)
		(width 0.1143)
		(layer "In9.Cu")
		(net "P5E_PEX3_STN0_TX_DP<3>")
	)
	(segment
		(start 434.828188 -128.681226)
		(end 434.827934 -128.681226)
		(width 0.1651)
		(layer "In9.Cu")
		(net "P5E_PEX3_STN0_TX_DP<3>")
	)
	(segment
		(start 435.820058 -131.295648)
		(end 435.997604 -131.717288)
		(width 0.1651)
		(layer "In9.Cu")
		(net "P5E_PEX3_STN0_TX_DP<3>")
	)
	(segment
		(start 374.27154 -349.831914)
		(end 374.591072 -349.512382)
		(width 0.13462)
		(layer "F.Cu")
		(net "P5E_PEX3_STN6_TX_DP<110>")
	)
	(segment
		(start 374.591072 -348.879922)
		(end 374.29694 -348.58579)
		(width 0.13462)
		(layer "F.Cu")
		(net "P5E_PEX3_STN6_TX_DP<110>")
	)
	(segment
		(start 374.591072 -349.512382)
		(end 374.591072 -348.879922)
		(width 0.13462)
		(layer "F.Cu")
		(net "P5E_PEX3_STN6_TX_DP<110>")
	)
	(segment
		(start 392.179556 -319.946528)
		(end 392.179556 -313.59475)
		(width 0.1143)
		(layer "In13.Cu")
		(net "P5E_PEX3_STN6_TX_DP<110>")
	)
	(segment
		(start 374.58777 -347.667834)
		(end 376.14225 -346.113354)
		(width 0.1651)
		(layer "In13.Cu")
		(net "P5E_PEX3_STN6_TX_DP<110>")
	)
	(segment
		(start 374.29694 -348.58579)
		(end 374.58777 -348.29496)
		(width 0.1651)
		(layer "In13.Cu")
		(net "P5E_PEX3_STN6_TX_DP<110>")
	)
	(segment
		(start 392.749786 -313.265312)
		(end 392.749786 -312.999882)
		(width 0.1143)
		(layer "In13.Cu")
		(net "P5E_PEX3_STN6_TX_DP<110>")
	)
	(segment
		(start 392.133836 -320.822828)
		(end 392.133836 -320.020696)
		(width 0.1651)
		(layer "In13.Cu")
		(net "P5E_PEX3_STN6_TX_DP<110>")
	)
	(segment
		(start 376.14225 -341.951056)
		(end 376.365262 -341.09025)
		(width 0.1651)
		(layer "In13.Cu")
		(net "P5E_PEX3_STN6_TX_DP<110>")
	)
	(segment
		(start 392.133836 -320.020696)
		(end 392.133836 -319.992248)
		(width 0.1143)
		(layer "In13.Cu")
		(net "P5E_PEX3_STN6_TX_DP<110>")
	)
	(segment
		(start 376.14225 -346.113354)
		(end 376.14225 -341.951056)
		(width 0.1651)
		(layer "In13.Cu")
		(net "P5E_PEX3_STN6_TX_DP<110>")
	)
	(segment
		(start 374.58777 -348.29496)
		(end 374.58777 -347.667834)
		(width 0.1651)
		(layer "In13.Cu")
		(net "P5E_PEX3_STN6_TX_DP<110>")
	)
	(segment
		(start 392.394694 -313.379612)
		(end 392.635486 -313.379612)
		(width 0.1143)
		(layer "In13.Cu")
		(net "P5E_PEX3_STN6_TX_DP<110>")
	)
	(segment
		(start 391.0711 -322.647056)
		(end 392.133836 -320.822828)
		(width 0.1651)
		(layer "In13.Cu")
		(net "P5E_PEX3_STN6_TX_DP<110>")
	)
	(segment
		(start 392.133836 -319.992248)
		(end 392.179556 -319.946528)
		(width 0.1143)
		(layer "In13.Cu")
		(net "P5E_PEX3_STN6_TX_DP<110>")
	)
	(segment
		(start 376.365262 -341.09025)
		(end 381.395986 -335.337658)
		(width 0.1651)
		(layer "In13.Cu")
		(net "P5E_PEX3_STN6_TX_DP<110>")
	)
	(segment
		(start 392.179556 -313.59475)
		(end 392.394694 -313.379612)
		(width 0.1143)
		(layer "In13.Cu")
		(net "P5E_PEX3_STN6_TX_DP<110>")
	)
	(segment
		(start 381.395986 -335.337658)
		(end 391.0711 -322.647056)
		(width 0.1651)
		(layer "In13.Cu")
		(net "P5E_PEX3_STN6_TX_DP<110>")
	)
	(segment
		(start 392.635486 -313.379612)
		(end 392.749786 -313.265312)
		(width 0.1143)
		(layer "In13.Cu")
		(net "P5E_PEX3_STN6_TX_DP<110>")
	)
	(segment
		(start 65.370202 -355.978206)
		(end 65.050162 -355.658166)
		(width 0.13462)
		(layer "F.Cu")
		(net "P5E_PEX0_STN5_TX_DN<82>")
	)
	(segment
		(start 65.050162 -355.658166)
		(end 65.050162 -355.026722)
		(width 0.13462)
		(layer "F.Cu")
		(net "P5E_PEX0_STN5_TX_DN<82>")
	)
	(segment
		(start 65.050162 -355.026722)
		(end 65.344802 -354.732082)
		(width 0.13462)
		(layer "F.Cu")
		(net "P5E_PEX0_STN5_TX_DN<82>")
	)
	(segment
		(start 60.265818 -319.890648)
		(end 60.265818 -319.8622)
		(width 0.1143)
		(layer "In7.Cu")
		(net "P5E_PEX0_STN5_TX_DN<82>")
	)
	(segment
		(start 65.053972 -353.942142)
		(end 66.608452 -352.387662)
		(width 0.1651)
		(layer "In7.Cu")
		(net "P5E_PEX0_STN5_TX_DN<82>")
	)
	(segment
		(start 60.265818 -324.74916)
		(end 60.265818 -319.890648)
		(width 0.1651)
		(layer "In7.Cu")
		(net "P5E_PEX0_STN5_TX_DN<82>")
	)
	(segment
		(start 60.334398 -311.670192)
		(end 60.485528 -311.670192)
		(width 0.1143)
		(layer "In7.Cu")
		(net "P5E_PEX0_STN5_TX_DN<82>")
	)
	(segment
		(start 65.053972 -354.441252)
		(end 65.053972 -353.942142)
		(width 0.1651)
		(layer "In7.Cu")
		(net "P5E_PEX0_STN5_TX_DN<82>")
	)
	(segment
		(start 60.220098 -311.784492)
		(end 60.334398 -311.670192)
		(width 0.1143)
		(layer "In7.Cu")
		(net "P5E_PEX0_STN5_TX_DN<82>")
	)
	(segment
		(start 60.265818 -319.8622)
		(end 60.220098 -319.81648)
		(width 0.1143)
		(layer "In7.Cu")
		(net "P5E_PEX0_STN5_TX_DN<82>")
	)
	(segment
		(start 60.485528 -311.670192)
		(end 60.599828 -311.784492)
		(width 0.1143)
		(layer "In7.Cu")
		(net "P5E_PEX0_STN5_TX_DN<82>")
	)
	(segment
		(start 65.344802 -354.732082)
		(end 65.053972 -354.441252)
		(width 0.1651)
		(layer "In7.Cu")
		(net "P5E_PEX0_STN5_TX_DN<82>")
	)
	(segment
		(start 66.608452 -340.061296)
		(end 60.265818 -324.74916)
		(width 0.1651)
		(layer "In7.Cu")
		(net "P5E_PEX0_STN5_TX_DN<82>")
	)
	(segment
		(start 60.220098 -319.81648)
		(end 60.220098 -311.784492)
		(width 0.1143)
		(layer "In7.Cu")
		(net "P5E_PEX0_STN5_TX_DN<82>")
	)
	(segment
		(start 66.608452 -352.387662)
		(end 66.608452 -340.061296)
		(width 0.1651)
		(layer "In7.Cu")
		(net "P5E_PEX0_STN5_TX_DN<82>")
	)
	(segment
		(start 60.599828 -311.784492)
		(end 60.599828 -312.049922)
		(width 0.1143)
		(layer "In7.Cu")
		(net "P5E_PEX0_STN5_TX_DN<82>")
	)
	(segment
		(start 186.469782 -28.829)
		(end 186.15914 -29.139642)
		(width 0.13462)
		(layer "F.Cu")
		(net "P5E_PEX1_STN2_TX_DP<36>")
	)
	(segment
		(start 187.120022 -28.829)
		(end 186.469782 -28.829)
		(width 0.13462)
		(layer "F.Cu")
		(net "P5E_PEX1_STN2_TX_DP<36>")
	)
	(segment
		(start 187.405264 -29.114242)
		(end 187.120022 -28.829)
		(width 0.13462)
		(layer "F.Cu")
		(net "P5E_PEX1_STN2_TX_DP<36>")
	)
	(segment
		(start 199.121014 -39.897558)
		(end 205.975966 -47.726854)
		(width 0.1651)
		(layer "In11.Cu")
		(net "P5E_PEX1_STN2_TX_DP<36>")
	)
	(segment
		(start 191.970406 -30.02661)
		(end 192.320926 -30.37713)
		(width 0.1651)
		(layer "In11.Cu")
		(net "P5E_PEX1_STN2_TX_DP<36>")
	)
	(segment
		(start 183.256428 -93.902784)
		(end 180.074316 -108.054394)
		(width 0.1651)
		(layer "In11.Cu")
		(net "P5E_PEX1_STN2_TX_DP<36>")
	)
	(segment
		(start 170.429682 -271.473168)
		(end 170.429682 -280.10485)
		(width 0.1143)
		(layer "In11.Cu")
		(net "P5E_PEX1_STN2_TX_DP<36>")
	)
	(segment
		(start 193.272918 -31.203392)
		(end 194.132708 -32.063182)
		(width 0.1651)
		(layer "In11.Cu")
		(net "P5E_PEX1_STN2_TX_DP<36>")
	)
	(segment
		(start 180.074316 -108.054394)
		(end 178.443382 -116.64442)
		(width 0.1651)
		(layer "In11.Cu")
		(net "P5E_PEX1_STN2_TX_DP<36>")
	)
	(segment
		(start 207.092296 -60.556902)
		(end 206.46263 -62.898274)
		(width 0.1651)
		(layer "In11.Cu")
		(net "P5E_PEX1_STN2_TX_DP<36>")
	)
	(segment
		(start 178.443382 -116.64442)
		(end 177.925476 -120.93321)
		(width 0.1651)
		(layer "In11.Cu")
		(net "P5E_PEX1_STN2_TX_DP<36>")
	)
	(segment
		(start 170.429682 -280.10485)
		(end 170.64482 -280.319988)
		(width 0.1143)
		(layer "In11.Cu")
		(net "P5E_PEX1_STN2_TX_DP<36>")
	)
	(segment
		(start 170.64482 -280.319988)
		(end 170.885612 -280.319988)
		(width 0.1143)
		(layer "In11.Cu")
		(net "P5E_PEX1_STN2_TX_DP<36>")
	)
	(segment
		(start 205.975966 -47.726854)
		(end 207.092296 -58.452766)
		(width 0.1651)
		(layer "In11.Cu")
		(net "P5E_PEX1_STN2_TX_DP<36>")
	)
	(segment
		(start 192.446656 -30.37713)
		(end 192.796668 -30.727142)
		(width 0.1651)
		(layer "In11.Cu")
		(net "P5E_PEX1_STN2_TX_DP<36>")
	)
	(segment
		(start 170.383962 -271.399)
		(end 170.383962 -271.427448)
		(width 0.1143)
		(layer "In11.Cu")
		(net "P5E_PEX1_STN2_TX_DP<36>")
	)
	(segment
		(start 192.320926 -30.37713)
		(end 192.446656 -30.37713)
		(width 0.1651)
		(layer "In11.Cu")
		(net "P5E_PEX1_STN2_TX_DP<36>")
	)
	(segment
		(start 187.405264 -29.114242)
		(end 187.696094 -28.823412)
		(width 0.1651)
		(layer "In11.Cu")
		(net "P5E_PEX1_STN2_TX_DP<36>")
	)
	(segment
		(start 205.491842 -64.855598)
		(end 183.256428 -93.902784)
		(width 0.1651)
		(layer "In11.Cu")
		(net "P5E_PEX1_STN2_TX_DP<36>")
	)
	(segment
		(start 170.999912 -280.434288)
		(end 170.999912 -280.699718)
		(width 0.1143)
		(layer "In11.Cu")
		(net "P5E_PEX1_STN2_TX_DP<36>")
	)
	(segment
		(start 193.147188 -31.203392)
		(end 193.272918 -31.203392)
		(width 0.1651)
		(layer "In11.Cu")
		(net "P5E_PEX1_STN2_TX_DP<36>")
	)
	(segment
		(start 192.796668 -30.852872)
		(end 193.147188 -31.203392)
		(width 0.1651)
		(layer "In11.Cu")
		(net "P5E_PEX1_STN2_TX_DP<36>")
	)
	(segment
		(start 191.515746 -29.445966)
		(end 191.970406 -29.90088)
		(width 0.1651)
		(layer "In11.Cu")
		(net "P5E_PEX1_STN2_TX_DP<36>")
	)
	(segment
		(start 190.015622 -28.823412)
		(end 191.515746 -29.445966)
		(width 0.1651)
		(layer "In11.Cu")
		(net "P5E_PEX1_STN2_TX_DP<36>")
	)
	(segment
		(start 192.796668 -30.727142)
		(end 192.796668 -30.852872)
		(width 0.1651)
		(layer "In11.Cu")
		(net "P5E_PEX1_STN2_TX_DP<36>")
	)
	(segment
		(start 170.383962 -271.427448)
		(end 170.429682 -271.473168)
		(width 0.1143)
		(layer "In11.Cu")
		(net "P5E_PEX1_STN2_TX_DP<36>")
	)
	(segment
		(start 194.132708 -32.063182)
		(end 199.121014 -39.897558)
		(width 0.1651)
		(layer "In11.Cu")
		(net "P5E_PEX1_STN2_TX_DP<36>")
	)
	(segment
		(start 170.885612 -280.319988)
		(end 170.999912 -280.434288)
		(width 0.1143)
		(layer "In11.Cu")
		(net "P5E_PEX1_STN2_TX_DP<36>")
	)
	(segment
		(start 187.696094 -28.823412)
		(end 190.015622 -28.823412)
		(width 0.1651)
		(layer "In11.Cu")
		(net "P5E_PEX1_STN2_TX_DP<36>")
	)
	(segment
		(start 177.925476 -120.93321)
		(end 170.383962 -263.41705)
		(width 0.1651)
		(layer "In11.Cu")
		(net "P5E_PEX1_STN2_TX_DP<36>")
	)
	(segment
		(start 191.970406 -29.90088)
		(end 191.970406 -30.02661)
		(width 0.1651)
		(layer "In11.Cu")
		(net "P5E_PEX1_STN2_TX_DP<36>")
	)
	(segment
		(start 207.092296 -58.452766)
		(end 207.092296 -60.556902)
		(width 0.1651)
		(layer "In11.Cu")
		(net "P5E_PEX1_STN2_TX_DP<36>")
	)
	(segment
		(start 170.383962 -263.41705)
		(end 170.383962 -271.399)
		(width 0.1651)
		(layer "In11.Cu")
		(net "P5E_PEX1_STN2_TX_DP<36>")
	)
	(segment
		(start 206.46263 -62.898274)
		(end 205.491842 -64.855598)
		(width 0.1651)
		(layer "In11.Cu")
		(net "P5E_PEX1_STN2_TX_DP<36>")
	)
	(segment
		(start 334.834484 -355.026722)
		(end 335.129124 -354.732082)
		(width 0.13462)
		(layer "F.Cu")
		(net "P5E_PEX2_STN5_TX_DN<91>")
	)
	(segment
		(start 335.154524 -355.978206)
		(end 334.834484 -355.658166)
		(width 0.13462)
		(layer "F.Cu")
		(net "P5E_PEX2_STN5_TX_DN<91>")
	)
	(segment
		(start 334.834484 -355.658166)
		(end 334.834484 -355.026722)
		(width 0.13462)
		(layer "F.Cu")
		(net "P5E_PEX2_STN5_TX_DN<91>")
	)
	(segment
		(start 314.500768 -328.712322)
		(end 314.04179 -328.525124)
		(width 0.1651)
		(layer "In7.Cu")
		(net "P5E_PEX2_STN5_TX_DN<91>")
	)
	(segment
		(start 301.349918 -313.684412)
		(end 301.349918 -313.949842)
		(width 0.1143)
		(layer "In7.Cu")
		(net "P5E_PEX2_STN5_TX_DN<91>")
	)
	(segment
		(start 301.882556 -322.532756)
		(end 301.015908 -320.440812)
		(width 0.1651)
		(layer "In7.Cu")
		(net "P5E_PEX2_STN5_TX_DN<91>")
	)
	(segment
		(start 313.942476 -328.567034)
		(end 303.77257 -324.42277)
		(width 0.1651)
		(layer "In7.Cu")
		(net "P5E_PEX2_STN5_TX_DN<91>")
	)
	(segment
		(start 300.970188 -313.684412)
		(end 301.084488 -313.570112)
		(width 0.1143)
		(layer "In7.Cu")
		(net "P5E_PEX2_STN5_TX_DN<91>")
	)
	(segment
		(start 301.015908 -320.440812)
		(end 301.015908 -319.941448)
		(width 0.1651)
		(layer "In7.Cu")
		(net "P5E_PEX2_STN5_TX_DN<91>")
	)
	(segment
		(start 325.352156 -333.216504)
		(end 314.542424 -328.811636)
		(width 0.1651)
		(layer "In7.Cu")
		(net "P5E_PEX2_STN5_TX_DN<91>")
	)
	(segment
		(start 334.838294 -353.930966)
		(end 336.392774 -352.376486)
		(width 0.1651)
		(layer "In7.Cu")
		(net "P5E_PEX2_STN5_TX_DN<91>")
	)
	(segment
		(start 336.392774 -341.9348)
		(end 336.0166 -340.9442)
		(width 0.1651)
		(layer "In7.Cu")
		(net "P5E_PEX2_STN5_TX_DN<91>")
	)
	(segment
		(start 336.0166 -340.9442)
		(end 333.629 -338.7344)
		(width 0.1651)
		(layer "In7.Cu")
		(net "P5E_PEX2_STN5_TX_DN<91>")
	)
	(segment
		(start 334.838294 -354.441252)
		(end 334.838294 -353.930966)
		(width 0.1651)
		(layer "In7.Cu")
		(net "P5E_PEX2_STN5_TX_DN<91>")
	)
	(segment
		(start 301.084488 -313.570112)
		(end 301.235618 -313.570112)
		(width 0.1143)
		(layer "In7.Cu")
		(net "P5E_PEX2_STN5_TX_DN<91>")
	)
	(segment
		(start 301.015908 -319.913)
		(end 300.970188 -319.86728)
		(width 0.1143)
		(layer "In7.Cu")
		(net "P5E_PEX2_STN5_TX_DN<91>")
	)
	(segment
		(start 301.235618 -313.570112)
		(end 301.349918 -313.684412)
		(width 0.1143)
		(layer "In7.Cu")
		(net "P5E_PEX2_STN5_TX_DN<91>")
	)
	(segment
		(start 314.04179 -328.525124)
		(end 313.942476 -328.567034)
		(width 0.1651)
		(layer "In7.Cu")
		(net "P5E_PEX2_STN5_TX_DN<91>")
	)
	(segment
		(start 300.970188 -319.86728)
		(end 300.970188 -313.684412)
		(width 0.1143)
		(layer "In7.Cu")
		(net "P5E_PEX2_STN5_TX_DN<91>")
	)
	(segment
		(start 335.129124 -354.732082)
		(end 334.838294 -354.441252)
		(width 0.1651)
		(layer "In7.Cu")
		(net "P5E_PEX2_STN5_TX_DN<91>")
	)
	(segment
		(start 301.015908 -319.941448)
		(end 301.015908 -319.913)
		(width 0.1143)
		(layer "In7.Cu")
		(net "P5E_PEX2_STN5_TX_DN<91>")
	)
	(segment
		(start 333.629 -338.7344)
		(end 325.352156 -333.216504)
		(width 0.1651)
		(layer "In7.Cu")
		(net "P5E_PEX2_STN5_TX_DN<91>")
	)
	(segment
		(start 336.392774 -352.376486)
		(end 336.392774 -341.9348)
		(width 0.1651)
		(layer "In7.Cu")
		(net "P5E_PEX2_STN5_TX_DN<91>")
	)
	(segment
		(start 314.542424 -328.811636)
		(end 314.500768 -328.712322)
		(width 0.1651)
		(layer "In7.Cu")
		(net "P5E_PEX2_STN5_TX_DN<91>")
	)
	(segment
		(start 303.77257 -324.42277)
		(end 301.882556 -322.532756)
		(width 0.1651)
		(layer "In7.Cu")
		(net "P5E_PEX2_STN5_TX_DN<91>")
	)
	(segment
		(start 428.89932 -134.08152)
		(end 428.586138 -134.394702)
		(width 0.13462)
		(layer "F.Cu")
		(net "P5E_PEX3_STN0_TX_DP<6>")
	)
	(segment
		(start 429.832262 -134.369302)
		(end 429.54448 -134.08152)
		(width 0.13462)
		(layer "F.Cu")
		(net "P5E_PEX3_STN0_TX_DP<6>")
	)
	(segment
		(start 429.54448 -134.08152)
		(end 428.89932 -134.08152)
		(width 0.13462)
		(layer "F.Cu")
		(net "P5E_PEX3_STN0_TX_DP<6>")
	)
	(segment
		(start 433.06238 -134.510272)
		(end 433.755038 -134.797038)
		(width 0.1651)
		(layer "In9.Cu")
		(net "P5E_PEX3_STN0_TX_DP<6>")
	)
	(segment
		(start 430.892458 -134.078472)
		(end 430.999138 -134.185152)
		(width 0.1651)
		(layer "In9.Cu")
		(net "P5E_PEX3_STN0_TX_DP<6>")
	)
	(segment
		(start 431.440336 -251.527056)
		(end 436.77078 -259.504434)
		(width 0.1651)
		(layer "In9.Cu")
		(net "P5E_PEX3_STN0_TX_DP<6>")
	)
	(segment
		(start 432.019964 -134.078472)
		(end 432.442366 -134.253478)
		(width 0.1651)
		(layer "In9.Cu")
		(net "P5E_PEX3_STN0_TX_DP<6>")
	)
	(segment
		(start 435.744112 -138.606784)
		(end 435.918864 -139.028932)
		(width 0.1651)
		(layer "In9.Cu")
		(net "P5E_PEX3_STN0_TX_DP<6>")
	)
	(segment
		(start 429.832262 -134.369302)
		(end 430.123092 -134.078472)
		(width 0.1651)
		(layer "In9.Cu")
		(net "P5E_PEX3_STN0_TX_DP<6>")
	)
	(segment
		(start 432.634644 -178.151028)
		(end 428.829724 -221.640654)
		(width 0.1651)
		(layer "In9.Cu")
		(net "P5E_PEX3_STN0_TX_DP<6>")
	)
	(segment
		(start 442.124592 -273.559524)
		(end 434.288692 -281.395424)
		(width 0.1651)
		(layer "In9.Cu")
		(net "P5E_PEX3_STN0_TX_DP<6>")
	)
	(segment
		(start 425.644818 -282.029662)
		(end 425.42968 -282.2448)
		(width 0.1143)
		(layer "In9.Cu")
		(net "P5E_PEX3_STN0_TX_DP<6>")
	)
	(segment
		(start 428.83201 -221.665038)
		(end 431.440336 -251.527056)
		(width 0.1651)
		(layer "In9.Cu")
		(net "P5E_PEX3_STN0_TX_DP<6>")
	)
	(segment
		(start 436.77078 -259.504434)
		(end 442.04509 -267.397992)
		(width 0.1651)
		(layer "In9.Cu")
		(net "P5E_PEX3_STN0_TX_DP<6>")
	)
	(segment
		(start 435.008528 -137.096246)
		(end 435.183534 -137.518902)
		(width 0.1651)
		(layer "In9.Cu")
		(net "P5E_PEX3_STN0_TX_DP<6>")
	)
	(segment
		(start 432.189128 -281.983942)
		(end 432.143408 -282.029662)
		(width 0.1143)
		(layer "In9.Cu")
		(net "P5E_PEX3_STN0_TX_DP<6>")
	)
	(segment
		(start 435.491128 -137.996168)
		(end 435.436264 -138.12901)
		(width 0.1651)
		(layer "In9.Cu")
		(net "P5E_PEX3_STN0_TX_DP<6>")
	)
	(segment
		(start 435.864 -139.161774)
		(end 436.039006 -139.58443)
		(width 0.1651)
		(layer "In9.Cu")
		(net "P5E_PEX3_STN0_TX_DP<6>")
	)
	(segment
		(start 436.599838 -140.672058)
		(end 438.448704 -145.135346)
		(width 0.1651)
		(layer "In9.Cu")
		(net "P5E_PEX3_STN0_TX_DP<6>")
	)
	(segment
		(start 436.172102 -139.639294)
		(end 436.346854 -140.061442)
		(width 0.1651)
		(layer "In9.Cu")
		(net "P5E_PEX3_STN0_TX_DP<6>")
	)
	(segment
		(start 428.829724 -221.640654)
		(end 428.831756 -221.665038)
		(width 0.1651)
		(layer "In9.Cu")
		(net "P5E_PEX3_STN0_TX_DP<6>")
	)
	(segment
		(start 428.831756 -221.665038)
		(end 428.83201 -221.665038)
		(width 0.1651)
		(layer "In9.Cu")
		(net "P5E_PEX3_STN0_TX_DP<6>")
	)
	(segment
		(start 435.918864 -139.028932)
		(end 435.864 -139.161774)
		(width 0.1651)
		(layer "In9.Cu")
		(net "P5E_PEX3_STN0_TX_DP<6>")
	)
	(segment
		(start 432.442366 -134.253478)
		(end 432.442366 -134.253224)
		(width 0.1651)
		(layer "In9.Cu")
		(net "P5E_PEX3_STN0_TX_DP<6>")
	)
	(segment
		(start 435.063392 -136.963404)
		(end 435.008528 -137.096246)
		(width 0.1651)
		(layer "In9.Cu")
		(net "P5E_PEX3_STN0_TX_DP<6>")
	)
	(segment
		(start 432.500278 -134.392924)
		(end 432.922934 -134.56793)
		(width 0.1651)
		(layer "In9.Cu")
		(net "P5E_PEX3_STN0_TX_DP<6>")
	)
	(segment
		(start 425.42968 -282.2448)
		(end 425.42968 -282.485592)
		(width 0.1143)
		(layer "In9.Cu")
		(net "P5E_PEX3_STN0_TX_DP<6>")
	)
	(segment
		(start 436.039006 -139.58443)
		(end 436.172102 -139.639294)
		(width 0.1651)
		(layer "In9.Cu")
		(net "P5E_PEX3_STN0_TX_DP<6>")
	)
	(segment
		(start 434.288692 -281.395424)
		(end 432.867562 -281.983942)
		(width 0.1651)
		(layer "In9.Cu")
		(net "P5E_PEX3_STN0_TX_DP<6>")
	)
	(segment
		(start 432.143408 -282.029662)
		(end 425.644818 -282.029662)
		(width 0.1143)
		(layer "In9.Cu")
		(net "P5E_PEX3_STN0_TX_DP<6>")
	)
	(segment
		(start 431.456338 -134.185152)
		(end 431.563018 -134.078472)
		(width 0.1651)
		(layer "In9.Cu")
		(net "P5E_PEX3_STN0_TX_DP<6>")
	)
	(segment
		(start 435.183534 -137.518902)
		(end 435.316376 -137.57402)
		(width 0.1651)
		(layer "In9.Cu")
		(net "P5E_PEX3_STN0_TX_DP<6>")
	)
	(segment
		(start 434.631846 -135.921242)
		(end 434.574188 -136.060688)
		(width 0.1651)
		(layer "In9.Cu")
		(net "P5E_PEX3_STN0_TX_DP<6>")
	)
	(segment
		(start 432.922934 -134.56793)
		(end 433.06238 -134.510272)
		(width 0.1651)
		(layer "In9.Cu")
		(net "P5E_PEX3_STN0_TX_DP<6>")
	)
	(segment
		(start 425.31538 -282.599892)
		(end 425.04995 -282.599892)
		(width 0.1143)
		(layer "In9.Cu")
		(net "P5E_PEX3_STN0_TX_DP<6>")
	)
	(segment
		(start 438.907936 -145.594578)
		(end 442.383164 -153.984706)
		(width 0.1651)
		(layer "In9.Cu")
		(net "P5E_PEX3_STN0_TX_DP<6>")
	)
	(segment
		(start 442.383164 -158.922212)
		(end 433.806346 -173.78172)
		(width 0.1651)
		(layer "In9.Cu")
		(net "P5E_PEX3_STN0_TX_DP<6>")
	)
	(segment
		(start 442.04509 -267.397992)
		(end 442.614304 -268.772386)
		(width 0.1651)
		(layer "In9.Cu")
		(net "P5E_PEX3_STN0_TX_DP<6>")
	)
	(segment
		(start 434.749194 -136.483344)
		(end 434.888894 -136.541256)
		(width 0.1651)
		(layer "In9.Cu")
		(net "P5E_PEX3_STN0_TX_DP<6>")
	)
	(segment
		(start 435.316376 -137.57402)
		(end 435.491128 -137.996168)
		(width 0.1651)
		(layer "In9.Cu")
		(net "P5E_PEX3_STN0_TX_DP<6>")
	)
	(segment
		(start 435.61127 -138.551666)
		(end 435.744112 -138.606784)
		(width 0.1651)
		(layer "In9.Cu")
		(net "P5E_PEX3_STN0_TX_DP<6>")
	)
	(segment
		(start 435.436264 -138.12901)
		(end 435.61127 -138.551666)
		(width 0.1651)
		(layer "In9.Cu")
		(net "P5E_PEX3_STN0_TX_DP<6>")
	)
	(segment
		(start 431.563018 -134.078472)
		(end 432.019964 -134.078472)
		(width 0.1651)
		(layer "In9.Cu")
		(net "P5E_PEX3_STN0_TX_DP<6>")
	)
	(segment
		(start 432.217576 -281.983942)
		(end 432.189128 -281.983942)
		(width 0.1143)
		(layer "In9.Cu")
		(net "P5E_PEX3_STN0_TX_DP<6>")
	)
	(segment
		(start 430.999138 -134.185152)
		(end 431.456338 -134.185152)
		(width 0.1651)
		(layer "In9.Cu")
		(net "P5E_PEX3_STN0_TX_DP<6>")
	)
	(segment
		(start 442.857382 -271.54632)
		(end 442.124592 -273.559524)
		(width 0.1651)
		(layer "In9.Cu")
		(net "P5E_PEX3_STN0_TX_DP<6>")
	)
	(segment
		(start 432.867562 -281.983942)
		(end 432.217576 -281.983942)
		(width 0.1651)
		(layer "In9.Cu")
		(net "P5E_PEX3_STN0_TX_DP<6>")
	)
	(segment
		(start 432.442366 -134.253224)
		(end 432.500278 -134.392924)
		(width 0.1651)
		(layer "In9.Cu")
		(net "P5E_PEX3_STN0_TX_DP<6>")
	)
	(segment
		(start 430.123092 -134.078472)
		(end 430.892458 -134.078472)
		(width 0.1651)
		(layer "In9.Cu")
		(net "P5E_PEX3_STN0_TX_DP<6>")
	)
	(segment
		(start 436.29199 -140.194284)
		(end 436.466996 -140.61694)
		(width 0.1651)
		(layer "In9.Cu")
		(net "P5E_PEX3_STN0_TX_DP<6>")
	)
	(segment
		(start 433.806346 -173.78172)
		(end 432.634644 -178.151028)
		(width 0.1651)
		(layer "In9.Cu")
		(net "P5E_PEX3_STN0_TX_DP<6>")
	)
	(segment
		(start 425.42968 -282.485592)
		(end 425.31538 -282.599892)
		(width 0.1143)
		(layer "In9.Cu")
		(net "P5E_PEX3_STN0_TX_DP<6>")
	)
	(segment
		(start 442.614304 -268.772386)
		(end 442.857382 -271.54632)
		(width 0.1651)
		(layer "In9.Cu")
		(net "P5E_PEX3_STN0_TX_DP<6>")
	)
	(segment
		(start 434.457094 -135.499094)
		(end 434.631846 -135.921242)
		(width 0.1651)
		(layer "In9.Cu")
		(net "P5E_PEX3_STN0_TX_DP<6>")
	)
	(segment
		(start 438.448704 -145.135346)
		(end 438.907936 -145.594578)
		(width 0.1651)
		(layer "In9.Cu")
		(net "P5E_PEX3_STN0_TX_DP<6>")
	)
	(segment
		(start 442.383164 -153.984706)
		(end 442.383164 -158.922212)
		(width 0.1651)
		(layer "In9.Cu")
		(net "P5E_PEX3_STN0_TX_DP<6>")
	)
	(segment
		(start 434.88864 -136.541256)
		(end 435.063392 -136.963404)
		(width 0.1651)
		(layer "In9.Cu")
		(net "P5E_PEX3_STN0_TX_DP<6>")
	)
	(segment
		(start 434.888894 -136.541256)
		(end 434.88864 -136.541256)
		(width 0.1651)
		(layer "In9.Cu")
		(net "P5E_PEX3_STN0_TX_DP<6>")
	)
	(segment
		(start 436.466996 -140.61694)
		(end 436.599838 -140.672058)
		(width 0.1651)
		(layer "In9.Cu")
		(net "P5E_PEX3_STN0_TX_DP<6>")
	)
	(segment
		(start 436.346854 -140.061442)
		(end 436.29199 -140.194284)
		(width 0.1651)
		(layer "In9.Cu")
		(net "P5E_PEX3_STN0_TX_DP<6>")
	)
	(segment
		(start 433.755038 -134.797038)
		(end 434.457094 -135.499094)
		(width 0.1651)
		(layer "In9.Cu")
		(net "P5E_PEX3_STN0_TX_DP<6>")
	)
	(segment
		(start 434.574188 -136.060688)
		(end 434.749194 -136.483344)
		(width 0.1651)
		(layer "In9.Cu")
		(net "P5E_PEX3_STN0_TX_DP<6>")
	)
	(segment
		(start 380.48946 -355.978206)
		(end 380.808992 -355.658674)
		(width 0.13462)
		(layer "F.Cu")
		(net "P5E_PEX3_STN6_TX_DP<98>")
	)
	(segment
		(start 380.808992 -355.026214)
		(end 380.51486 -354.732082)
		(width 0.13462)
		(layer "F.Cu")
		(net "P5E_PEX3_STN6_TX_DP<98>")
	)
	(segment
		(start 380.808992 -355.658674)
		(end 380.808992 -355.026214)
		(width 0.13462)
		(layer "F.Cu")
		(net "P5E_PEX3_STN6_TX_DP<98>")
	)
	(segment
		(start 403.579584 -313.605418)
		(end 403.80539 -313.379612)
		(width 0.1143)
		(layer "In7.Cu")
		(net "P5E_PEX3_STN6_TX_DP<98>")
	)
	(segment
		(start 403.80539 -313.379612)
		(end 404.035514 -313.379612)
		(width 0.1143)
		(layer "In7.Cu")
		(net "P5E_PEX3_STN6_TX_DP<98>")
	)
	(segment
		(start 404.149814 -313.265312)
		(end 404.149814 -312.999882)
		(width 0.1143)
		(layer "In7.Cu")
		(net "P5E_PEX3_STN6_TX_DP<98>")
	)
	(segment
		(start 382.36017 -352.259646)
		(end 382.36017 -341.394034)
		(width 0.1651)
		(layer "In7.Cu")
		(net "P5E_PEX3_STN6_TX_DP<98>")
	)
	(segment
		(start 380.80569 -353.814126)
		(end 382.36017 -352.259646)
		(width 0.1651)
		(layer "In7.Cu")
		(net "P5E_PEX3_STN6_TX_DP<98>")
	)
	(segment
		(start 402.85924 -323.01942)
		(end 403.533864 -321.391026)
		(width 0.1651)
		(layer "In7.Cu")
		(net "P5E_PEX3_STN6_TX_DP<98>")
	)
	(segment
		(start 380.80569 -354.441252)
		(end 380.80569 -353.814126)
		(width 0.1651)
		(layer "In7.Cu")
		(net "P5E_PEX3_STN6_TX_DP<98>")
	)
	(segment
		(start 403.533864 -319.9892)
		(end 403.533864 -319.960752)
		(width 0.1143)
		(layer "In7.Cu")
		(net "P5E_PEX3_STN6_TX_DP<98>")
	)
	(segment
		(start 380.51486 -354.732082)
		(end 380.80569 -354.441252)
		(width 0.1651)
		(layer "In7.Cu")
		(net "P5E_PEX3_STN6_TX_DP<98>")
	)
	(segment
		(start 400.971004 -324.907656)
		(end 402.85924 -323.01942)
		(width 0.1651)
		(layer "In7.Cu")
		(net "P5E_PEX3_STN6_TX_DP<98>")
	)
	(segment
		(start 403.533864 -321.391026)
		(end 403.533864 -319.9892)
		(width 0.1651)
		(layer "In7.Cu")
		(net "P5E_PEX3_STN6_TX_DP<98>")
	)
	(segment
		(start 382.36017 -341.394034)
		(end 400.971004 -324.907656)
		(width 0.1651)
		(layer "In7.Cu")
		(net "P5E_PEX3_STN6_TX_DP<98>")
	)
	(segment
		(start 403.579584 -319.915032)
		(end 403.579584 -313.605418)
		(width 0.1143)
		(layer "In7.Cu")
		(net "P5E_PEX3_STN6_TX_DP<98>")
	)
	(segment
		(start 403.533864 -319.960752)
		(end 403.579584 -319.915032)
		(width 0.1143)
		(layer "In7.Cu")
		(net "P5E_PEX3_STN6_TX_DP<98>")
	)
	(segment
		(start 404.035514 -313.379612)
		(end 404.149814 -313.265312)
		(width 0.1143)
		(layer "In7.Cu")
		(net "P5E_PEX3_STN6_TX_DP<98>")
	)
	(segment
		(start 64.775842 -355.658166)
		(end 64.775842 -355.026722)
		(width 0.13462)
		(layer "F.Cu")
		(net "P5E_PEX0_STN5_TX_DP<82>")
	)
	(segment
		(start 64.775842 -355.026722)
		(end 64.481202 -354.732082)
		(width 0.13462)
		(layer "F.Cu")
		(net "P5E_PEX0_STN5_TX_DP<82>")
	)
	(segment
		(start 64.455802 -355.978206)
		(end 64.775842 -355.658166)
		(width 0.13462)
		(layer "F.Cu")
		(net "P5E_PEX0_STN5_TX_DP<82>")
	)
	(segment
		(start 59.983878 -319.8622)
		(end 60.029598 -319.81648)
		(width 0.1143)
		(layer "In7.Cu")
		(net "P5E_PEX0_STN5_TX_DP<82>")
	)
	(segment
		(start 66.326512 -352.270822)
		(end 66.326512 -340.11743)
		(width 0.1651)
		(layer "In7.Cu")
		(net "P5E_PEX0_STN5_TX_DP<82>")
	)
	(segment
		(start 60.029598 -311.705498)
		(end 60.255404 -311.479692)
		(width 0.1143)
		(layer "In7.Cu")
		(net "P5E_PEX0_STN5_TX_DP<82>")
	)
	(segment
		(start 64.772032 -353.825302)
		(end 66.326512 -352.270822)
		(width 0.1651)
		(layer "In7.Cu")
		(net "P5E_PEX0_STN5_TX_DP<82>")
	)
	(segment
		(start 64.481202 -354.732082)
		(end 64.772032 -354.441252)
		(width 0.1651)
		(layer "In7.Cu")
		(net "P5E_PEX0_STN5_TX_DP<82>")
	)
	(segment
		(start 66.326512 -340.11743)
		(end 59.983878 -324.805294)
		(width 0.1651)
		(layer "In7.Cu")
		(net "P5E_PEX0_STN5_TX_DP<82>")
	)
	(segment
		(start 64.772032 -354.441252)
		(end 64.772032 -353.825302)
		(width 0.1651)
		(layer "In7.Cu")
		(net "P5E_PEX0_STN5_TX_DP<82>")
	)
	(segment
		(start 60.599828 -311.365392)
		(end 60.599828 -311.099962)
		(width 0.1143)
		(layer "In7.Cu")
		(net "P5E_PEX0_STN5_TX_DP<82>")
	)
	(segment
		(start 59.983878 -324.805294)
		(end 59.983878 -319.890648)
		(width 0.1651)
		(layer "In7.Cu")
		(net "P5E_PEX0_STN5_TX_DP<82>")
	)
	(segment
		(start 60.485528 -311.479692)
		(end 60.599828 -311.365392)
		(width 0.1143)
		(layer "In7.Cu")
		(net "P5E_PEX0_STN5_TX_DP<82>")
	)
	(segment
		(start 60.255404 -311.479692)
		(end 60.485528 -311.479692)
		(width 0.1143)
		(layer "In7.Cu")
		(net "P5E_PEX0_STN5_TX_DP<82>")
	)
	(segment
		(start 59.983878 -319.890648)
		(end 59.983878 -319.8622)
		(width 0.1143)
		(layer "In7.Cu")
		(net "P5E_PEX0_STN5_TX_DP<82>")
	)
	(segment
		(start 60.029598 -319.81648)
		(end 60.029598 -311.705498)
		(width 0.1143)
		(layer "In7.Cu")
		(net "P5E_PEX0_STN5_TX_DP<82>")
	)
	(segment
		(start 131.084828 -342.734138)
		(end 131.379468 -342.439498)
		(width 0.13462)
		(layer "F.Cu")
		(net "P5E_PEX1_STN5_TX_DN<88>")
	)
	(segment
		(start 131.084828 -343.365582)
		(end 131.084828 -342.734138)
		(width 0.13462)
		(layer "F.Cu")
		(net "P5E_PEX1_STN5_TX_DN<88>")
	)
	(segment
		(start 131.404868 -343.685622)
		(end 131.084828 -343.365582)
		(width 0.13462)
		(layer "F.Cu")
		(net "P5E_PEX1_STN5_TX_DN<88>")
	)
	(segment
		(start 182.06593 -320.068448)
		(end 182.06593 -320.04)
		(width 0.1143)
		(layer "In13.Cu")
		(net "P5E_PEX1_STN5_TX_DN<88>")
	)
	(segment
		(start 182.123842 -311.670192)
		(end 182.28564 -311.670192)
		(width 0.1143)
		(layer "In13.Cu")
		(net "P5E_PEX1_STN5_TX_DN<88>")
	)
	(segment
		(start 147.14347 -335.071212)
		(end 155.480258 -332.292706)
		(width 0.1651)
		(layer "In13.Cu")
		(net "P5E_PEX1_STN5_TX_DN<88>")
	)
	(segment
		(start 155.480004 -332.292706)
		(end 163.78555 -329.524614)
		(width 0.1651)
		(layer "In13.Cu")
		(net "P5E_PEX1_STN5_TX_DN<88>")
	)
	(segment
		(start 142.115794 -335.071212)
		(end 147.14347 -335.071212)
		(width 0.1651)
		(layer "In13.Cu")
		(net "P5E_PEX1_STN5_TX_DN<88>")
	)
	(segment
		(start 181.792372 -320.768726)
		(end 182.06593 -320.494914)
		(width 0.1651)
		(layer "In13.Cu")
		(net "P5E_PEX1_STN5_TX_DN<88>")
	)
	(segment
		(start 133.843268 -338.497926)
		(end 142.115794 -335.071212)
		(width 0.1651)
		(layer "In13.Cu")
		(net "P5E_PEX1_STN5_TX_DN<88>")
	)
	(segment
		(start 163.78555 -329.524614)
		(end 172.12818 -325.934832)
		(width 0.1651)
		(layer "In13.Cu")
		(net "P5E_PEX1_STN5_TX_DN<88>")
	)
	(segment
		(start 133.843268 -338.497672)
		(end 133.843268 -338.497926)
		(width 0.1651)
		(layer "In13.Cu")
		(net "P5E_PEX1_STN5_TX_DN<88>")
	)
	(segment
		(start 182.06593 -320.494914)
		(end 182.06593 -320.068448)
		(width 0.1651)
		(layer "In13.Cu")
		(net "P5E_PEX1_STN5_TX_DN<88>")
	)
	(segment
		(start 131.088638 -341.252302)
		(end 133.843268 -338.497672)
		(width 0.1651)
		(layer "In13.Cu")
		(net "P5E_PEX1_STN5_TX_DN<88>")
	)
	(segment
		(start 182.02021 -319.99428)
		(end 182.02021 -311.773824)
		(width 0.1143)
		(layer "In13.Cu")
		(net "P5E_PEX1_STN5_TX_DN<88>")
	)
	(segment
		(start 172.12818 -325.934832)
		(end 181.792372 -320.768726)
		(width 0.1651)
		(layer "In13.Cu")
		(net "P5E_PEX1_STN5_TX_DN<88>")
	)
	(segment
		(start 182.39994 -311.784492)
		(end 182.39994 -312.049922)
		(width 0.1143)
		(layer "In13.Cu")
		(net "P5E_PEX1_STN5_TX_DN<88>")
	)
	(segment
		(start 182.02021 -311.773824)
		(end 182.123842 -311.670192)
		(width 0.1143)
		(layer "In13.Cu")
		(net "P5E_PEX1_STN5_TX_DN<88>")
	)
	(segment
		(start 131.379468 -342.439498)
		(end 131.088638 -342.148668)
		(width 0.1651)
		(layer "In13.Cu")
		(net "P5E_PEX1_STN5_TX_DN<88>")
	)
	(segment
		(start 131.088638 -342.148668)
		(end 131.088638 -341.252302)
		(width 0.1651)
		(layer "In13.Cu")
		(net "P5E_PEX1_STN5_TX_DN<88>")
	)
	(segment
		(start 155.480258 -332.292706)
		(end 155.480004 -332.292706)
		(width 0.1651)
		(layer "In13.Cu")
		(net "P5E_PEX1_STN5_TX_DN<88>")
	)
	(segment
		(start 182.06593 -320.04)
		(end 182.02021 -319.99428)
		(width 0.1143)
		(layer "In13.Cu")
		(net "P5E_PEX1_STN5_TX_DN<88>")
	)
	(segment
		(start 182.28564 -311.670192)
		(end 182.39994 -311.784492)
		(width 0.1143)
		(layer "In13.Cu")
		(net "P5E_PEX1_STN5_TX_DN<88>")
	)
	(segment
		(start 251.505212 -32.714184)
		(end 251.201428 -32.4104)
		(width 0.13462)
		(layer "F.Cu")
		(net "P5E_PEX2_STN2_TX_DP<46>")
	)
	(segment
		(start 251.201428 -32.4104)
		(end 250.588272 -32.4104)
		(width 0.13462)
		(layer "F.Cu")
		(net "P5E_PEX2_STN2_TX_DP<46>")
	)
	(segment
		(start 250.588272 -32.4104)
		(end 250.259088 -32.739584)
		(width 0.13462)
		(layer "F.Cu")
		(net "P5E_PEX2_STN2_TX_DP<46>")
	)
	(segment
		(start 252.468888 -32.423354)
		(end 252.557788 -32.512254)
		(width 0.1651)
		(layer "In11.Cu")
		(net "P5E_PEX2_STN2_TX_DP<46>")
	)
	(segment
		(start 252.557788 -32.512254)
		(end 253.053088 -32.512254)
		(width 0.1651)
		(layer "In11.Cu")
		(net "P5E_PEX2_STN2_TX_DP<46>")
	)
	(segment
		(start 276.983952 -271.399)
		(end 276.983952 -271.427448)
		(width 0.1143)
		(layer "In11.Cu")
		(net "P5E_PEX2_STN2_TX_DP<46>")
	)
	(segment
		(start 256.42189 -33.620456)
		(end 266.757658 -46.559216)
		(width 0.1651)
		(layer "In11.Cu")
		(net "P5E_PEX2_STN2_TX_DP<46>")
	)
	(segment
		(start 276.983952 -270.220948)
		(end 276.983952 -271.399)
		(width 0.1651)
		(layer "In11.Cu")
		(net "P5E_PEX2_STN2_TX_DP<46>")
	)
	(segment
		(start 253.053088 -32.512254)
		(end 253.141988 -32.423354)
		(width 0.1651)
		(layer "In11.Cu")
		(net "P5E_PEX2_STN2_TX_DP<46>")
	)
	(segment
		(start 266.757658 -46.559216)
		(end 268.067028 -48.925734)
		(width 0.1651)
		(layer "In11.Cu")
		(net "P5E_PEX2_STN2_TX_DP<46>")
	)
	(segment
		(start 277.24481 -280.319988)
		(end 277.485602 -280.319988)
		(width 0.1143)
		(layer "In11.Cu")
		(net "P5E_PEX2_STN2_TX_DP<46>")
	)
	(segment
		(start 264.295636 -116.818664)
		(end 264.758678 -138.17854)
		(width 0.1651)
		(layer "In11.Cu")
		(net "P5E_PEX2_STN2_TX_DP<46>")
	)
	(segment
		(start 276.983952 -271.427448)
		(end 277.029672 -271.473168)
		(width 0.1143)
		(layer "In11.Cu")
		(net "P5E_PEX2_STN2_TX_DP<46>")
	)
	(segment
		(start 275.978366 -264.559288)
		(end 276.983952 -270.220948)
		(width 0.1651)
		(layer "In11.Cu")
		(net "P5E_PEX2_STN2_TX_DP<46>")
	)
	(segment
		(start 268.476984 -78.744572)
		(end 264.898632 -104.937814)
		(width 0.1651)
		(layer "In11.Cu")
		(net "P5E_PEX2_STN2_TX_DP<46>")
	)
	(segment
		(start 277.485602 -280.319988)
		(end 277.599902 -280.434288)
		(width 0.1143)
		(layer "In11.Cu")
		(net "P5E_PEX2_STN2_TX_DP<46>")
	)
	(segment
		(start 269.361666 -62.965838)
		(end 268.476984 -78.744572)
		(width 0.1651)
		(layer "In11.Cu")
		(net "P5E_PEX2_STN2_TX_DP<46>")
	)
	(segment
		(start 268.067028 -48.925734)
		(end 268.619732 -50.504344)
		(width 0.1651)
		(layer "In11.Cu")
		(net "P5E_PEX2_STN2_TX_DP<46>")
	)
	(segment
		(start 251.796042 -32.423354)
		(end 252.468888 -32.423354)
		(width 0.1651)
		(layer "In11.Cu")
		(net "P5E_PEX2_STN2_TX_DP<46>")
	)
	(segment
		(start 277.599902 -280.434288)
		(end 277.599902 -280.699718)
		(width 0.1143)
		(layer "In11.Cu")
		(net "P5E_PEX2_STN2_TX_DP<46>")
	)
	(segment
		(start 268.619732 -50.504344)
		(end 269.361666 -62.965838)
		(width 0.1651)
		(layer "In11.Cu")
		(net "P5E_PEX2_STN2_TX_DP<46>")
	)
	(segment
		(start 264.758678 -138.17854)
		(end 275.978366 -264.559288)
		(width 0.1651)
		(layer "In11.Cu")
		(net "P5E_PEX2_STN2_TX_DP<46>")
	)
	(segment
		(start 253.529084 -32.423354)
		(end 256.42189 -33.620456)
		(width 0.1651)
		(layer "In11.Cu")
		(net "P5E_PEX2_STN2_TX_DP<46>")
	)
	(segment
		(start 253.141988 -32.423354)
		(end 253.529084 -32.423354)
		(width 0.1651)
		(layer "In11.Cu")
		(net "P5E_PEX2_STN2_TX_DP<46>")
	)
	(segment
		(start 277.029672 -280.10485)
		(end 277.24481 -280.319988)
		(width 0.1143)
		(layer "In11.Cu")
		(net "P5E_PEX2_STN2_TX_DP<46>")
	)
	(segment
		(start 277.029672 -271.473168)
		(end 277.029672 -280.10485)
		(width 0.1143)
		(layer "In11.Cu")
		(net "P5E_PEX2_STN2_TX_DP<46>")
	)
	(segment
		(start 264.898632 -104.937814)
		(end 264.295636 -116.818664)
		(width 0.1651)
		(layer "In11.Cu")
		(net "P5E_PEX2_STN2_TX_DP<46>")
	)
	(segment
		(start 251.505212 -32.714184)
		(end 251.796042 -32.423354)
		(width 0.1651)
		(layer "In11.Cu")
		(net "P5E_PEX2_STN2_TX_DP<46>")
	)
	(segment
		(start 386.067808 -107.377738)
		(end 386.359146 -107.0864)
		(width 0.13462)
		(layer "F.Cu")
		(net "P5E_PEX3_STN1_TX_DN<20>")
	)
	(segment
		(start 386.997194 -107.0864)
		(end 387.313932 -107.403138)
		(width 0.13462)
		(layer "F.Cu")
		(net "P5E_PEX3_STN1_TX_DN<20>")
	)
	(segment
		(start 386.359146 -107.0864)
		(end 386.997194 -107.0864)
		(width 0.13462)
		(layer "F.Cu")
		(net "P5E_PEX3_STN1_TX_DN<20>")
	)
	(segment
		(start 379.390656 -111.44504)
		(end 379.575314 -110.99927)
		(width 0.1651)
		(layer "In9.Cu")
		(net "P5E_PEX3_STN1_TX_DN<20>")
	)
	(segment
		(start 380.113286 -109.700314)
		(end 381.0381 -108.7755)
		(width 0.1651)
		(layer "In9.Cu")
		(net "P5E_PEX3_STN1_TX_DN<20>")
	)
	(segment
		(start 376.640852 -118.084092)
		(end 377.196096 -116.743226)
		(width 0.1651)
		(layer "In9.Cu")
		(net "P5E_PEX3_STN1_TX_DN<20>")
	)
	(segment
		(start 381.199644 -108.7755)
		(end 381.541274 -108.43387)
		(width 0.1651)
		(layer "In9.Cu")
		(net "P5E_PEX3_STN1_TX_DN<20>")
	)
	(segment
		(start 377.744736 -115.418616)
		(end 377.894342 -115.35664)
		(width 0.1651)
		(layer "In9.Cu")
		(net "P5E_PEX3_STN1_TX_DN<20>")
	)
	(segment
		(start 411.415992 -271.500346)
		(end 411.415992 -271.471898)
		(width 0.1143)
		(layer "In9.Cu")
		(net "P5E_PEX3_STN1_TX_DN<20>")
	)
	(segment
		(start 379.118368 -112.102392)
		(end 379.267974 -112.040416)
		(width 0.1651)
		(layer "In9.Cu")
		(net "P5E_PEX3_STN1_TX_DN<20>")
	)
	(segment
		(start 372.658132 -138.197844)
		(end 372.658132 -131.214368)
		(width 0.1651)
		(layer "In9.Cu")
		(net "P5E_PEX3_STN1_TX_DN<20>")
	)
	(segment
		(start 378.535946 -113.807494)
		(end 378.47397 -113.658142)
		(width 0.1651)
		(layer "In9.Cu")
		(net "P5E_PEX3_STN1_TX_DN<20>")
	)
	(segment
		(start 411.415992 -265.086338)
		(end 376.524012 -162.004248)
		(width 0.1651)
		(layer "In9.Cu")
		(net "P5E_PEX3_STN1_TX_DN<20>")
	)
	(segment
		(start 378.201682 -114.315494)
		(end 378.351288 -114.253518)
		(width 0.1651)
		(layer "In9.Cu")
		(net "P5E_PEX3_STN1_TX_DN<20>")
	)
	(segment
		(start 384.4036 -107.086908)
		(end 384.5179 -107.201208)
		(width 0.1651)
		(layer "In9.Cu")
		(net "P5E_PEX3_STN1_TX_DN<20>")
	)
	(segment
		(start 411.749748 -278.115268)
		(end 411.635448 -278.229568)
		(width 0.1143)
		(layer "In9.Cu")
		(net "P5E_PEX3_STN1_TX_DN<20>")
	)
	(segment
		(start 379.72492 -110.937294)
		(end 379.909578 -110.49127)
		(width 0.1651)
		(layer "In9.Cu")
		(net "P5E_PEX3_STN1_TX_DN<20>")
	)
	(segment
		(start 381.882396 -107.931204)
		(end 383.920746 -107.086908)
		(width 0.1651)
		(layer "In9.Cu")
		(net "P5E_PEX3_STN1_TX_DN<20>")
	)
	(segment
		(start 378.017024 -114.761264)
		(end 378.201682 -114.315494)
		(width 0.1651)
		(layer "In9.Cu")
		(net "P5E_PEX3_STN1_TX_DN<20>")
	)
	(segment
		(start 411.370272 -271.546066)
		(end 411.415992 -271.500346)
		(width 0.1143)
		(layer "In9.Cu")
		(net "P5E_PEX3_STN1_TX_DN<20>")
	)
	(segment
		(start 411.47365 -278.229568)
		(end 411.370272 -278.12619)
		(width 0.1143)
		(layer "In9.Cu")
		(net "P5E_PEX3_STN1_TX_DN<20>")
	)
	(segment
		(start 385.1148 -107.086908)
		(end 385.776978 -107.086908)
		(width 0.1651)
		(layer "In9.Cu")
		(net "P5E_PEX3_STN1_TX_DN<20>")
	)
	(segment
		(start 377.345702 -116.68125)
		(end 377.53036 -116.235226)
		(width 0.1651)
		(layer "In9.Cu")
		(net "P5E_PEX3_STN1_TX_DN<20>")
	)
	(segment
		(start 411.635448 -278.229568)
		(end 411.47365 -278.229568)
		(width 0.1143)
		(layer "In9.Cu")
		(net "P5E_PEX3_STN1_TX_DN<20>")
	)
	(segment
		(start 375.963688 -159.187134)
		(end 375.23801 -144.425924)
		(width 0.1651)
		(layer "In9.Cu")
		(net "P5E_PEX3_STN1_TX_DN<20>")
	)
	(segment
		(start 381.0381 -108.7755)
		(end 381.199644 -108.7755)
		(width 0.1651)
		(layer "In9.Cu")
		(net "P5E_PEX3_STN1_TX_DN<20>")
	)
	(segment
		(start 383.920746 -107.086908)
		(end 384.4036 -107.086908)
		(width 0.1651)
		(layer "In9.Cu")
		(net "P5E_PEX3_STN1_TX_DN<20>")
	)
	(segment
		(start 378.930916 -112.555274)
		(end 379.118368 -112.102392)
		(width 0.1651)
		(layer "In9.Cu")
		(net "P5E_PEX3_STN1_TX_DN<20>")
	)
	(segment
		(start 381.541274 -108.43387)
		(end 381.541274 -108.272326)
		(width 0.1651)
		(layer "In9.Cu")
		(net "P5E_PEX3_STN1_TX_DN<20>")
	)
	(segment
		(start 381.541274 -108.272326)
		(end 381.882396 -107.931204)
		(width 0.1651)
		(layer "In9.Cu")
		(net "P5E_PEX3_STN1_TX_DN<20>")
	)
	(segment
		(start 379.267974 -112.040416)
		(end 379.452632 -111.594392)
		(width 0.1651)
		(layer "In9.Cu")
		(net "P5E_PEX3_STN1_TX_DN<20>")
	)
	(segment
		(start 377.53036 -116.235226)
		(end 377.468384 -116.085874)
		(width 0.1651)
		(layer "In9.Cu")
		(net "P5E_PEX3_STN1_TX_DN<20>")
	)
	(segment
		(start 378.658628 -113.212372)
		(end 378.80798 -113.15065)
		(width 0.1651)
		(layer "In9.Cu")
		(net "P5E_PEX3_STN1_TX_DN<20>")
	)
	(segment
		(start 411.415992 -271.471898)
		(end 411.415992 -265.086338)
		(width 0.1651)
		(layer "In9.Cu")
		(net "P5E_PEX3_STN1_TX_DN<20>")
	)
	(segment
		(start 379.452632 -111.594392)
		(end 379.390656 -111.44504)
		(width 0.1651)
		(layer "In9.Cu")
		(net "P5E_PEX3_STN1_TX_DN<20>")
	)
	(segment
		(start 378.351288 -114.253518)
		(end 378.535946 -113.807494)
		(width 0.1651)
		(layer "In9.Cu")
		(net "P5E_PEX3_STN1_TX_DN<20>")
	)
	(segment
		(start 411.370272 -278.12619)
		(end 411.370272 -271.546066)
		(width 0.1143)
		(layer "In9.Cu")
		(net "P5E_PEX3_STN1_TX_DN<20>")
	)
	(segment
		(start 379.575314 -110.99927)
		(end 379.72492 -110.937294)
		(width 0.1651)
		(layer "In9.Cu")
		(net "P5E_PEX3_STN1_TX_DN<20>")
	)
	(segment
		(start 379.909578 -110.49127)
		(end 379.847602 -110.341918)
		(width 0.1651)
		(layer "In9.Cu")
		(net "P5E_PEX3_STN1_TX_DN<20>")
	)
	(segment
		(start 385.0005 -107.201208)
		(end 385.1148 -107.086908)
		(width 0.1651)
		(layer "In9.Cu")
		(net "P5E_PEX3_STN1_TX_DN<20>")
	)
	(segment
		(start 384.5179 -107.201208)
		(end 385.0005 -107.201208)
		(width 0.1651)
		(layer "In9.Cu")
		(net "P5E_PEX3_STN1_TX_DN<20>")
	)
	(segment
		(start 378.992892 -112.704626)
		(end 378.930916 -112.555274)
		(width 0.1651)
		(layer "In9.Cu")
		(net "P5E_PEX3_STN1_TX_DN<20>")
	)
	(segment
		(start 385.776978 -107.086908)
		(end 386.067808 -107.377738)
		(width 0.1651)
		(layer "In9.Cu")
		(net "P5E_PEX3_STN1_TX_DN<20>")
	)
	(segment
		(start 379.847602 -110.341918)
		(end 380.113286 -109.700314)
		(width 0.1651)
		(layer "In9.Cu")
		(net "P5E_PEX3_STN1_TX_DN<20>")
	)
	(segment
		(start 411.749748 -277.849838)
		(end 411.749748 -278.115268)
		(width 0.1143)
		(layer "In9.Cu")
		(net "P5E_PEX3_STN1_TX_DN<20>")
	)
	(segment
		(start 377.468384 -116.085874)
		(end 377.744736 -115.418616)
		(width 0.1651)
		(layer "In9.Cu")
		(net "P5E_PEX3_STN1_TX_DN<20>")
	)
	(segment
		(start 378.079 -114.910616)
		(end 378.017024 -114.761264)
		(width 0.1651)
		(layer "In9.Cu")
		(net "P5E_PEX3_STN1_TX_DN<20>")
	)
	(segment
		(start 377.196096 -116.743226)
		(end 377.345702 -116.68125)
		(width 0.1651)
		(layer "In9.Cu")
		(net "P5E_PEX3_STN1_TX_DN<20>")
	)
	(segment
		(start 378.80798 -113.15065)
		(end 378.992892 -112.704626)
		(width 0.1651)
		(layer "In9.Cu")
		(net "P5E_PEX3_STN1_TX_DN<20>")
	)
	(segment
		(start 377.894342 -115.35664)
		(end 378.079 -114.910616)
		(width 0.1651)
		(layer "In9.Cu")
		(net "P5E_PEX3_STN1_TX_DN<20>")
	)
	(segment
		(start 375.23801 -144.425924)
		(end 372.658132 -138.197844)
		(width 0.1651)
		(layer "In9.Cu")
		(net "P5E_PEX3_STN1_TX_DN<20>")
	)
	(segment
		(start 372.658132 -131.214368)
		(end 376.640852 -118.084092)
		(width 0.1651)
		(layer "In9.Cu")
		(net "P5E_PEX3_STN1_TX_DN<20>")
	)
	(segment
		(start 376.524012 -162.004248)
		(end 375.963688 -159.187134)
		(width 0.1651)
		(layer "In9.Cu")
		(net "P5E_PEX3_STN1_TX_DN<20>")
	)
	(segment
		(start 378.47397 -113.658142)
		(end 378.658628 -113.212372)
		(width 0.1651)
		(layer "In9.Cu")
		(net "P5E_PEX3_STN1_TX_DN<20>")
	)
	(segment
		(start 387.62178 -343.685622)
		(end 387.301232 -343.365074)
		(width 0.13462)
		(layer "F.Cu")
		(net "P5E_PEX3_STN6_TX_DN<96>")
	)
	(segment
		(start 387.301232 -342.734646)
		(end 387.59638 -342.439498)
		(width 0.13462)
		(layer "F.Cu")
		(net "P5E_PEX3_STN6_TX_DN<96>")
	)
	(segment
		(start 387.301232 -343.365074)
		(end 387.301232 -342.734646)
		(width 0.13462)
		(layer "F.Cu")
		(net "P5E_PEX3_STN6_TX_DN<96>")
	)
	(segment
		(start 405.715978 -319.960752)
		(end 405.670258 -319.915032)
		(width 0.1143)
		(layer "In7.Cu")
		(net "P5E_PEX3_STN6_TX_DN<96>")
	)
	(segment
		(start 405.935688 -313.570112)
		(end 406.049988 -313.684412)
		(width 0.1143)
		(layer "In7.Cu")
		(net "P5E_PEX3_STN6_TX_DN<96>")
	)
	(segment
		(start 405.715978 -321.98437)
		(end 405.715978 -319.9892)
		(width 0.1651)
		(layer "In7.Cu")
		(net "P5E_PEX3_STN6_TX_DN<96>")
	)
	(segment
		(start 406.049988 -313.684412)
		(end 406.049988 -313.949842)
		(width 0.1143)
		(layer "In7.Cu")
		(net "P5E_PEX3_STN6_TX_DN<96>")
	)
	(segment
		(start 387.30555 -342.148668)
		(end 387.30555 -341.50046)
		(width 0.1651)
		(layer "In7.Cu")
		(net "P5E_PEX3_STN6_TX_DN<96>")
	)
	(segment
		(start 405.670258 -313.684412)
		(end 405.784558 -313.570112)
		(width 0.1143)
		(layer "In7.Cu")
		(net "P5E_PEX3_STN6_TX_DN<96>")
	)
	(segment
		(start 387.59638 -342.439498)
		(end 387.30555 -342.148668)
		(width 0.1651)
		(layer "In7.Cu")
		(net "P5E_PEX3_STN6_TX_DN<96>")
	)
	(segment
		(start 405.715978 -319.9892)
		(end 405.715978 -319.960752)
		(width 0.1143)
		(layer "In7.Cu")
		(net "P5E_PEX3_STN6_TX_DN<96>")
	)
	(segment
		(start 387.30555 -341.50046)
		(end 404.743666 -324.331584)
		(width 0.1651)
		(layer "In7.Cu")
		(net "P5E_PEX3_STN6_TX_DN<96>")
	)
	(segment
		(start 405.784558 -313.570112)
		(end 405.935688 -313.570112)
		(width 0.1143)
		(layer "In7.Cu")
		(net "P5E_PEX3_STN6_TX_DN<96>")
	)
	(segment
		(start 405.670258 -319.915032)
		(end 405.670258 -313.684412)
		(width 0.1143)
		(layer "In7.Cu")
		(net "P5E_PEX3_STN6_TX_DN<96>")
	)
	(segment
		(start 404.743666 -324.331584)
		(end 405.715978 -321.98437)
		(width 0.1651)
		(layer "In7.Cu")
		(net "P5E_PEX3_STN6_TX_DN<96>")
	)
	(segment
		(start 80.000602 -349.831914)
		(end 80.320642 -349.511874)
		(width 0.13462)
		(layer "F.Cu")
		(net "P5E_PEX0_STN5_TX_DP<89>")
	)
	(segment
		(start 80.320642 -349.511874)
		(end 80.320642 -348.88043)
		(width 0.13462)
		(layer "F.Cu")
		(net "P5E_PEX0_STN5_TX_DP<89>")
	)
	(segment
		(start 80.320642 -348.88043)
		(end 80.026002 -348.58579)
		(width 0.13462)
		(layer "F.Cu")
		(net "P5E_PEX0_STN5_TX_DP<89>")
	)
	(segment
		(start 81.871312 -341.74049)
		(end 81.502758 -340.710774)
		(width 0.1651)
		(layer "In7.Cu")
		(net "P5E_PEX0_STN5_TX_DP<89>")
	)
	(segment
		(start 80.026002 -348.58579)
		(end 80.316832 -348.29496)
		(width 0.1651)
		(layer "In7.Cu")
		(net "P5E_PEX0_STN5_TX_DP<89>")
	)
	(segment
		(start 68.544186 -325.127366)
		(end 67.124326 -323.002656)
		(width 0.1651)
		(layer "In7.Cu")
		(net "P5E_PEX0_STN5_TX_DP<89>")
	)
	(segment
		(start 66.633852 -321.818508)
		(end 66.633852 -319.916048)
		(width 0.1651)
		(layer "In7.Cu")
		(net "P5E_PEX0_STN5_TX_DP<89>")
	)
	(segment
		(start 66.679572 -319.84188)
		(end 66.679572 -313.605418)
		(width 0.1143)
		(layer "In7.Cu")
		(net "P5E_PEX0_STN5_TX_DP<89>")
	)
	(segment
		(start 66.633852 -319.916048)
		(end 66.633852 -319.8876)
		(width 0.1143)
		(layer "In7.Cu")
		(net "P5E_PEX0_STN5_TX_DP<89>")
	)
	(segment
		(start 67.249802 -313.265312)
		(end 67.249802 -312.999882)
		(width 0.1143)
		(layer "In7.Cu")
		(net "P5E_PEX0_STN5_TX_DP<89>")
	)
	(segment
		(start 67.124326 -323.002656)
		(end 66.633852 -321.818508)
		(width 0.1651)
		(layer "In7.Cu")
		(net "P5E_PEX0_STN5_TX_DP<89>")
	)
	(segment
		(start 69.489574 -326.073008)
		(end 68.544186 -325.127366)
		(width 0.1651)
		(layer "In7.Cu")
		(net "P5E_PEX0_STN5_TX_DP<89>")
	)
	(segment
		(start 66.633852 -319.8876)
		(end 66.679572 -319.84188)
		(width 0.1143)
		(layer "In7.Cu")
		(net "P5E_PEX0_STN5_TX_DP<89>")
	)
	(segment
		(start 66.905378 -313.379612)
		(end 67.135502 -313.379612)
		(width 0.1143)
		(layer "In7.Cu")
		(net "P5E_PEX0_STN5_TX_DP<89>")
	)
	(segment
		(start 66.679572 -313.605418)
		(end 66.905378 -313.379612)
		(width 0.1143)
		(layer "In7.Cu")
		(net "P5E_PEX0_STN5_TX_DP<89>")
	)
	(segment
		(start 80.316832 -348.29496)
		(end 80.316832 -347.541342)
		(width 0.1651)
		(layer "In7.Cu")
		(net "P5E_PEX0_STN5_TX_DP<89>")
	)
	(segment
		(start 80.316832 -347.541342)
		(end 81.871312 -345.986862)
		(width 0.1651)
		(layer "In7.Cu")
		(net "P5E_PEX0_STN5_TX_DP<89>")
	)
	(segment
		(start 81.502758 -340.710774)
		(end 69.489574 -326.073008)
		(width 0.1651)
		(layer "In7.Cu")
		(net "P5E_PEX0_STN5_TX_DP<89>")
	)
	(segment
		(start 81.871312 -345.986862)
		(end 81.871312 -341.74049)
		(width 0.1651)
		(layer "In7.Cu")
		(net "P5E_PEX0_STN5_TX_DP<89>")
	)
	(segment
		(start 67.135502 -313.379612)
		(end 67.249802 -313.265312)
		(width 0.1143)
		(layer "In7.Cu")
		(net "P5E_PEX0_STN5_TX_DP<89>")
	)
	(segment
		(start 128.295908 -355.978206)
		(end 127.975868 -355.658166)
		(width 0.13462)
		(layer "F.Cu")
		(net "P5E_PEX1_STN5_TX_DN<80>")
	)
	(segment
		(start 127.975868 -355.658166)
		(end 127.975868 -355.026722)
		(width 0.13462)
		(layer "F.Cu")
		(net "P5E_PEX1_STN5_TX_DN<80>")
	)
	(segment
		(start 127.975868 -355.026722)
		(end 128.270508 -354.732082)
		(width 0.13462)
		(layer "F.Cu")
		(net "P5E_PEX1_STN5_TX_DN<80>")
	)
	(segment
		(start 174.465996 -319.988438)
		(end 174.420276 -319.942718)
		(width 0.1143)
		(layer "In7.Cu")
		(net "P5E_PEX1_STN5_TX_DN<80>")
	)
	(segment
		(start 174.420276 -311.784492)
		(end 174.534576 -311.670192)
		(width 0.1143)
		(layer "In7.Cu")
		(net "P5E_PEX1_STN5_TX_DN<80>")
	)
	(segment
		(start 174.534576 -311.670192)
		(end 174.685706 -311.670192)
		(width 0.1143)
		(layer "In7.Cu")
		(net "P5E_PEX1_STN5_TX_DN<80>")
	)
	(segment
		(start 174.465996 -320.016886)
		(end 174.465996 -319.988438)
		(width 0.1143)
		(layer "In7.Cu")
		(net "P5E_PEX1_STN5_TX_DN<80>")
	)
	(segment
		(start 174.685706 -311.670192)
		(end 174.800006 -311.784492)
		(width 0.1143)
		(layer "In7.Cu")
		(net "P5E_PEX1_STN5_TX_DN<80>")
	)
	(segment
		(start 135.16864 -338.071206)
		(end 143.580866 -335.519014)
		(width 0.1651)
		(layer "In7.Cu")
		(net "P5E_PEX1_STN5_TX_DN<80>")
	)
	(segment
		(start 143.580866 -335.519014)
		(end 151.993092 -332.967076)
		(width 0.1651)
		(layer "In7.Cu")
		(net "P5E_PEX1_STN5_TX_DN<80>")
	)
	(segment
		(start 151.993092 -332.967076)
		(end 151.993092 -332.96733)
		(width 0.1651)
		(layer "In7.Cu")
		(net "P5E_PEX1_STN5_TX_DN<80>")
	)
	(segment
		(start 127.979678 -354.441252)
		(end 127.979678 -353.822762)
		(width 0.1651)
		(layer "In7.Cu")
		(net "P5E_PEX1_STN5_TX_DN<80>")
	)
	(segment
		(start 130.192272 -341.054182)
		(end 135.16864 -338.071206)
		(width 0.1651)
		(layer "In7.Cu")
		(net "P5E_PEX1_STN5_TX_DN<80>")
	)
	(segment
		(start 151.993092 -332.96733)
		(end 168.883838 -327.843134)
		(width 0.1651)
		(layer "In7.Cu")
		(net "P5E_PEX1_STN5_TX_DN<80>")
	)
	(segment
		(start 129.534158 -341.712296)
		(end 130.192272 -341.054182)
		(width 0.1651)
		(layer "In7.Cu")
		(net "P5E_PEX1_STN5_TX_DN<80>")
	)
	(segment
		(start 128.270508 -354.732082)
		(end 127.979678 -354.441252)
		(width 0.1651)
		(layer "In7.Cu")
		(net "P5E_PEX1_STN5_TX_DN<80>")
	)
	(segment
		(start 174.465996 -322.518024)
		(end 174.465996 -320.016886)
		(width 0.1651)
		(layer "In7.Cu")
		(net "P5E_PEX1_STN5_TX_DN<80>")
	)
	(segment
		(start 174.420276 -319.942718)
		(end 174.420276 -311.784492)
		(width 0.1143)
		(layer "In7.Cu")
		(net "P5E_PEX1_STN5_TX_DN<80>")
	)
	(segment
		(start 127.979678 -353.822762)
		(end 129.534158 -352.268282)
		(width 0.1651)
		(layer "In7.Cu")
		(net "P5E_PEX1_STN5_TX_DN<80>")
	)
	(segment
		(start 174.800006 -311.784492)
		(end 174.800006 -312.049922)
		(width 0.1143)
		(layer "In7.Cu")
		(net "P5E_PEX1_STN5_TX_DN<80>")
	)
	(segment
		(start 129.534158 -352.268282)
		(end 129.534158 -341.712296)
		(width 0.1651)
		(layer "In7.Cu")
		(net "P5E_PEX1_STN5_TX_DN<80>")
	)
	(segment
		(start 168.883838 -327.843134)
		(end 172.154596 -325.882508)
		(width 0.1651)
		(layer "In7.Cu")
		(net "P5E_PEX1_STN5_TX_DN<80>")
	)
	(segment
		(start 172.154596 -325.882508)
		(end 173.721268 -324.315836)
		(width 0.1651)
		(layer "In7.Cu")
		(net "P5E_PEX1_STN5_TX_DN<80>")
	)
	(segment
		(start 173.721268 -324.315836)
		(end 174.465996 -322.518024)
		(width 0.1651)
		(layer "In7.Cu")
		(net "P5E_PEX1_STN5_TX_DN<80>")
	)
	(segment
		(start 334.834484 -343.365582)
		(end 334.834484 -342.734138)
		(width 0.13462)
		(layer "F.Cu")
		(net "P5E_PEX2_STN5_TX_DN<90>")
	)
	(segment
		(start 335.154524 -343.685622)
		(end 334.834484 -343.365582)
		(width 0.13462)
		(layer "F.Cu")
		(net "P5E_PEX2_STN5_TX_DN<90>")
	)
	(segment
		(start 334.834484 -342.734138)
		(end 335.129124 -342.439498)
		(width 0.13462)
		(layer "F.Cu")
		(net "P5E_PEX2_STN5_TX_DN<90>")
	)
	(segment
		(start 300.019974 -319.86728)
		(end 300.019974 -311.784492)
		(width 0.1143)
		(layer "In7.Cu")
		(net "P5E_PEX2_STN5_TX_DN<90>")
	)
	(segment
		(start 314.297568 -329.756262)
		(end 314.181744 -329.804776)
		(width 0.1651)
		(layer "In7.Cu")
		(net "P5E_PEX2_STN5_TX_DN<90>")
	)
	(segment
		(start 300.065694 -319.941448)
		(end 300.065694 -319.913)
		(width 0.1143)
		(layer "In7.Cu")
		(net "P5E_PEX2_STN5_TX_DN<90>")
	)
	(segment
		(start 300.065694 -320.696082)
		(end 300.065694 -319.941448)
		(width 0.1651)
		(layer "In7.Cu")
		(net "P5E_PEX2_STN5_TX_DN<90>")
	)
	(segment
		(start 301.073058 -323.127878)
		(end 300.065694 -320.696082)
		(width 0.1651)
		(layer "In7.Cu")
		(net "P5E_PEX2_STN5_TX_DN<90>")
	)
	(segment
		(start 334.5688 -340.9442)
		(end 332.8416 -339.3694)
		(width 0.1651)
		(layer "In7.Cu")
		(net "P5E_PEX2_STN5_TX_DN<90>")
	)
	(segment
		(start 300.285404 -311.670192)
		(end 300.399704 -311.784492)
		(width 0.1143)
		(layer "In7.Cu")
		(net "P5E_PEX2_STN5_TX_DN<90>")
	)
	(segment
		(start 300.065694 -319.913)
		(end 300.019974 -319.86728)
		(width 0.1143)
		(layer "In7.Cu")
		(net "P5E_PEX2_STN5_TX_DN<90>")
	)
	(segment
		(start 300.019974 -311.784492)
		(end 300.134274 -311.670192)
		(width 0.1143)
		(layer "In7.Cu")
		(net "P5E_PEX2_STN5_TX_DN<90>")
	)
	(segment
		(start 325.224902 -334.314292)
		(end 314.80506 -330.059284)
		(width 0.1651)
		(layer "In7.Cu")
		(net "P5E_PEX2_STN5_TX_DN<90>")
	)
	(segment
		(start 334.59293 -341.005922)
		(end 334.592676 -341.00516)
		(width 0.1651)
		(layer "In7.Cu")
		(net "P5E_PEX2_STN5_TX_DN<90>")
	)
	(segment
		(start 314.181744 -329.804776)
		(end 303.311306 -325.366126)
		(width 0.1651)
		(layer "In7.Cu")
		(net "P5E_PEX2_STN5_TX_DN<90>")
	)
	(segment
		(start 334.592676 -341.00516)
		(end 334.5688 -340.9442)
		(width 0.1651)
		(layer "In7.Cu")
		(net "P5E_PEX2_STN5_TX_DN<90>")
	)
	(segment
		(start 303.311306 -325.366126)
		(end 301.073058 -323.127878)
		(width 0.1651)
		(layer "In7.Cu")
		(net "P5E_PEX2_STN5_TX_DN<90>")
	)
	(segment
		(start 335.129124 -342.439498)
		(end 334.838294 -342.148668)
		(width 0.1651)
		(layer "In7.Cu")
		(net "P5E_PEX2_STN5_TX_DN<90>")
	)
	(segment
		(start 314.756292 -329.943714)
		(end 314.297568 -329.756262)
		(width 0.1651)
		(layer "In7.Cu")
		(net "P5E_PEX2_STN5_TX_DN<90>")
	)
	(segment
		(start 314.80506 -330.059538)
		(end 314.756292 -329.943714)
		(width 0.1651)
		(layer "In7.Cu")
		(net "P5E_PEX2_STN5_TX_DN<90>")
	)
	(segment
		(start 332.8416 -339.3694)
		(end 325.224902 -334.314292)
		(width 0.1651)
		(layer "In7.Cu")
		(net "P5E_PEX2_STN5_TX_DN<90>")
	)
	(segment
		(start 334.838294 -342.148668)
		(end 334.838294 -341.633048)
		(width 0.1651)
		(layer "In7.Cu")
		(net "P5E_PEX2_STN5_TX_DN<90>")
	)
	(segment
		(start 314.80506 -330.059284)
		(end 314.80506 -330.059538)
		(width 0.1651)
		(layer "In7.Cu")
		(net "P5E_PEX2_STN5_TX_DN<90>")
	)
	(segment
		(start 300.134274 -311.670192)
		(end 300.285404 -311.670192)
		(width 0.1143)
		(layer "In7.Cu")
		(net "P5E_PEX2_STN5_TX_DN<90>")
	)
	(segment
		(start 334.838294 -341.633048)
		(end 334.59293 -341.005922)
		(width 0.1651)
		(layer "In7.Cu")
		(net "P5E_PEX2_STN5_TX_DN<90>")
	)
	(segment
		(start 300.399704 -311.784492)
		(end 300.399704 -312.049922)
		(width 0.1143)
		(layer "In7.Cu")
		(net "P5E_PEX2_STN5_TX_DN<90>")
	)
	(segment
		(start 431.544476 -135.88492)
		(end 431.228246 -136.20115)
		(width 0.13462)
		(layer "F.Cu")
		(net "P5E_PEX3_STN0_TX_DP<7>")
	)
	(segment
		(start 432.47437 -136.17575)
		(end 432.18354 -135.88492)
		(width 0.13462)
		(layer "F.Cu")
		(net "P5E_PEX3_STN0_TX_DP<7>")
	)
	(segment
		(start 432.18354 -135.88492)
		(end 431.544476 -135.88492)
		(width 0.13462)
		(layer "F.Cu")
		(net "P5E_PEX3_STN0_TX_DP<7>")
	)
	(segment
		(start 430.048162 -246.652034)
		(end 432.234848 -271.68348)
		(width 0.1651)
		(layer "In9.Cu")
		(net "P5E_PEX3_STN0_TX_DP<7>")
	)
	(segment
		(start 435.79796 -141.556994)
		(end 435.972712 -141.979142)
		(width 0.1651)
		(layer "In9.Cu")
		(net "P5E_PEX3_STN0_TX_DP<7>")
	)
	(segment
		(start 432.11242 -277.275798)
		(end 431.404776 -278.71039)
		(width 0.1651)
		(layer "In9.Cu")
		(net "P5E_PEX3_STN0_TX_DP<7>")
	)
	(segment
		(start 435.972712 -141.979142)
		(end 435.915054 -142.118588)
		(width 0.1651)
		(layer "In9.Cu")
		(net "P5E_PEX3_STN0_TX_DP<7>")
	)
	(segment
		(start 427.85792 -221.581218)
		(end 430.047908 -246.652034)
		(width 0.1651)
		(layer "In9.Cu")
		(net "P5E_PEX3_STN0_TX_DP<7>")
	)
	(segment
		(start 430.179734 -279.400254)
		(end 430.179734 -279.635458)
		(width 0.1143)
		(layer "In9.Cu")
		(net "P5E_PEX3_STN0_TX_DP<7>")
	)
	(segment
		(start 436.09006 -142.541244)
		(end 436.22976 -142.599156)
		(width 0.1651)
		(layer "In9.Cu")
		(net "P5E_PEX3_STN0_TX_DP<7>")
	)
	(segment
		(start 432.7652 -135.88492)
		(end 433.34432 -135.88492)
		(width 0.1651)
		(layer "In9.Cu")
		(net "P5E_PEX3_STN0_TX_DP<7>")
	)
	(segment
		(start 434.67782 -138.853418)
		(end 434.620162 -138.992864)
		(width 0.1651)
		(layer "In9.Cu")
		(net "P5E_PEX3_STN0_TX_DP<7>")
	)
	(segment
		(start 438.091326 -146.146774)
		(end 438.091072 -146.146774)
		(width 0.1651)
		(layer "In9.Cu")
		(net "P5E_PEX3_STN0_TX_DP<7>")
	)
	(segment
		(start 438.091072 -146.146774)
		(end 441.415424 -154.171904)
		(width 0.1651)
		(layer "In9.Cu")
		(net "P5E_PEX3_STN0_TX_DP<7>")
	)
	(segment
		(start 431.827432 -177.393854)
		(end 431.827686 -177.393854)
		(width 0.1651)
		(layer "In9.Cu")
		(net "P5E_PEX3_STN0_TX_DP<7>")
	)
	(segment
		(start 431.15103 -278.96439)
		(end 431.15103 -279.028652)
		(width 0.1143)
		(layer "In9.Cu")
		(net "P5E_PEX3_STN0_TX_DP<7>")
	)
	(segment
		(start 430.047908 -246.652034)
		(end 430.048162 -246.652034)
		(width 0.1651)
		(layer "In9.Cu")
		(net "P5E_PEX3_STN0_TX_DP<7>")
	)
	(segment
		(start 434.503322 -138.43127)
		(end 434.503068 -138.43127)
		(width 0.1651)
		(layer "In9.Cu")
		(net "P5E_PEX3_STN0_TX_DP<7>")
	)
	(segment
		(start 431.404776 -278.71039)
		(end 431.171096 -278.944324)
		(width 0.1651)
		(layer "In9.Cu")
		(net "P5E_PEX3_STN0_TX_DP<7>")
	)
	(segment
		(start 434.246274 -137.81151)
		(end 434.188616 -137.950702)
		(width 0.1651)
		(layer "In9.Cu")
		(net "P5E_PEX3_STN0_TX_DP<7>")
	)
	(segment
		(start 434.795168 -139.41552)
		(end 434.934868 -139.473178)
		(width 0.1651)
		(layer "In9.Cu")
		(net "P5E_PEX3_STN0_TX_DP<7>")
	)
	(segment
		(start 431.001932 -279.17775)
		(end 430.40173 -279.17775)
		(width 0.1143)
		(layer "In9.Cu")
		(net "P5E_PEX3_STN0_TX_DP<7>")
	)
	(segment
		(start 434.503068 -138.43127)
		(end 434.67782 -138.853418)
		(width 0.1651)
		(layer "In9.Cu")
		(net "P5E_PEX3_STN0_TX_DP<7>")
	)
	(segment
		(start 437.421782 -145.47723)
		(end 438.091326 -146.146774)
		(width 0.1651)
		(layer "In9.Cu")
		(net "P5E_PEX3_STN0_TX_DP<7>")
	)
	(segment
		(start 430.065434 -279.749758)
		(end 429.800004 -279.749758)
		(width 0.1143)
		(layer "In9.Cu")
		(net "P5E_PEX3_STN0_TX_DP<7>")
	)
	(segment
		(start 436.22976 -142.599156)
		(end 436.229506 -142.599156)
		(width 0.1651)
		(layer "In9.Cu")
		(net "P5E_PEX3_STN0_TX_DP<7>")
	)
	(segment
		(start 432.47437 -136.17575)
		(end 432.7652 -135.88492)
		(width 0.1651)
		(layer "In9.Cu")
		(net "P5E_PEX3_STN0_TX_DP<7>")
	)
	(segment
		(start 434.934868 -139.473178)
		(end 434.934614 -139.473178)
		(width 0.1651)
		(layer "In9.Cu")
		(net "P5E_PEX3_STN0_TX_DP<7>")
	)
	(segment
		(start 434.188616 -137.950702)
		(end 434.363622 -138.373358)
		(width 0.1651)
		(layer "In9.Cu")
		(net "P5E_PEX3_STN0_TX_DP<7>")
	)
	(segment
		(start 435.65826 -141.499336)
		(end 435.79796 -141.556994)
		(width 0.1651)
		(layer "In9.Cu")
		(net "P5E_PEX3_STN0_TX_DP<7>")
	)
	(segment
		(start 432.274218 -175.729646)
		(end 431.97653 -176.839118)
		(width 0.1651)
		(layer "In9.Cu")
		(net "P5E_PEX3_STN0_TX_DP<7>")
	)
	(segment
		(start 435.36616 -140.515086)
		(end 435.540912 -140.937234)
		(width 0.1651)
		(layer "In9.Cu")
		(net "P5E_PEX3_STN0_TX_DP<7>")
	)
	(segment
		(start 431.15103 -279.028652)
		(end 431.001932 -279.17775)
		(width 0.1143)
		(layer "In9.Cu")
		(net "P5E_PEX3_STN0_TX_DP<7>")
	)
	(segment
		(start 433.52212 -136.06272)
		(end 433.800758 -136.735566)
		(width 0.1651)
		(layer "In9.Cu")
		(net "P5E_PEX3_STN0_TX_DP<7>")
	)
	(segment
		(start 433.7431 -136.874758)
		(end 433.917852 -137.297414)
		(width 0.1651)
		(layer "In9.Cu")
		(net "P5E_PEX3_STN0_TX_DP<7>")
	)
	(segment
		(start 433.34432 -135.88492)
		(end 433.52212 -136.06272)
		(width 0.1651)
		(layer "In9.Cu")
		(net "P5E_PEX3_STN0_TX_DP<7>")
	)
	(segment
		(start 431.672746 -177.972212)
		(end 427.85792 -221.581218)
		(width 0.1651)
		(layer "In9.Cu")
		(net "P5E_PEX3_STN0_TX_DP<7>")
	)
	(segment
		(start 430.40173 -279.17775)
		(end 430.179734 -279.400254)
		(width 0.1143)
		(layer "In9.Cu")
		(net "P5E_PEX3_STN0_TX_DP<7>")
	)
	(segment
		(start 441.415424 -154.171904)
		(end 441.415424 -158.684722)
		(width 0.1651)
		(layer "In9.Cu")
		(net "P5E_PEX3_STN0_TX_DP<7>")
	)
	(segment
		(start 435.915054 -142.118588)
		(end 436.09006 -142.541244)
		(width 0.1651)
		(layer "In9.Cu")
		(net "P5E_PEX3_STN0_TX_DP<7>")
	)
	(segment
		(start 435.540912 -140.937234)
		(end 435.483254 -141.07668)
		(width 0.1651)
		(layer "In9.Cu")
		(net "P5E_PEX3_STN0_TX_DP<7>")
	)
	(segment
		(start 430.179734 -279.635458)
		(end 430.065434 -279.749758)
		(width 0.1143)
		(layer "In9.Cu")
		(net "P5E_PEX3_STN0_TX_DP<7>")
	)
	(segment
		(start 431.827686 -177.393854)
		(end 431.672746 -177.972212)
		(width 0.1651)
		(layer "In9.Cu")
		(net "P5E_PEX3_STN0_TX_DP<7>")
	)
	(segment
		(start 431.976276 -176.839118)
		(end 431.827432 -177.393854)
		(width 0.1651)
		(layer "In9.Cu")
		(net "P5E_PEX3_STN0_TX_DP<7>")
	)
	(segment
		(start 431.171096 -278.944324)
		(end 431.15103 -278.96439)
		(width 0.1143)
		(layer "In9.Cu")
		(net "P5E_PEX3_STN0_TX_DP<7>")
	)
	(segment
		(start 431.97653 -176.839118)
		(end 431.976276 -176.839118)
		(width 0.1651)
		(layer "In9.Cu")
		(net "P5E_PEX3_STN0_TX_DP<7>")
	)
	(segment
		(start 435.226714 -140.457428)
		(end 435.366414 -140.515086)
		(width 0.1651)
		(layer "In9.Cu")
		(net "P5E_PEX3_STN0_TX_DP<7>")
	)
	(segment
		(start 434.620162 -138.992864)
		(end 434.795168 -139.41552)
		(width 0.1651)
		(layer "In9.Cu")
		(net "P5E_PEX3_STN0_TX_DP<7>")
	)
	(segment
		(start 435.109366 -139.895326)
		(end 435.051708 -140.034772)
		(width 0.1651)
		(layer "In9.Cu")
		(net "P5E_PEX3_STN0_TX_DP<7>")
	)
	(segment
		(start 433.917852 -137.297414)
		(end 434.057552 -137.355326)
		(width 0.1651)
		(layer "In9.Cu")
		(net "P5E_PEX3_STN0_TX_DP<7>")
	)
	(segment
		(start 432.273964 -175.729646)
		(end 432.274218 -175.729646)
		(width 0.1651)
		(layer "In9.Cu")
		(net "P5E_PEX3_STN0_TX_DP<7>")
	)
	(segment
		(start 435.483254 -141.07668)
		(end 435.65826 -141.499336)
		(width 0.1651)
		(layer "In9.Cu")
		(net "P5E_PEX3_STN0_TX_DP<7>")
	)
	(segment
		(start 435.051708 -140.034772)
		(end 435.226714 -140.457428)
		(width 0.1651)
		(layer "In9.Cu")
		(net "P5E_PEX3_STN0_TX_DP<7>")
	)
	(segment
		(start 434.057552 -137.355326)
		(end 434.246274 -137.81151)
		(width 0.1651)
		(layer "In9.Cu")
		(net "P5E_PEX3_STN0_TX_DP<7>")
	)
	(segment
		(start 433.800758 -136.735566)
		(end 433.7431 -136.874758)
		(width 0.1651)
		(layer "In9.Cu")
		(net "P5E_PEX3_STN0_TX_DP<7>")
	)
	(segment
		(start 441.415424 -158.684722)
		(end 432.878738 -173.475142)
		(width 0.1651)
		(layer "In9.Cu")
		(net "P5E_PEX3_STN0_TX_DP<7>")
	)
	(segment
		(start 432.878738 -173.475142)
		(end 432.273964 -175.729646)
		(width 0.1651)
		(layer "In9.Cu")
		(net "P5E_PEX3_STN0_TX_DP<7>")
	)
	(segment
		(start 436.229506 -142.599156)
		(end 437.421782 -145.47723)
		(width 0.1651)
		(layer "In9.Cu")
		(net "P5E_PEX3_STN0_TX_DP<7>")
	)
	(segment
		(start 434.934614 -139.473178)
		(end 435.109366 -139.895326)
		(width 0.1651)
		(layer "In9.Cu")
		(net "P5E_PEX3_STN0_TX_DP<7>")
	)
	(segment
		(start 432.234848 -271.68348)
		(end 432.11242 -277.275798)
		(width 0.1651)
		(layer "In9.Cu")
		(net "P5E_PEX3_STN0_TX_DP<7>")
	)
	(segment
		(start 435.366414 -140.515086)
		(end 435.36616 -140.515086)
		(width 0.1651)
		(layer "In9.Cu")
		(net "P5E_PEX3_STN0_TX_DP<7>")
	)
	(segment
		(start 434.363622 -138.373358)
		(end 434.503322 -138.43127)
		(width 0.1651)
		(layer "In9.Cu")
		(net "P5E_PEX3_STN0_TX_DP<7>")
	)
	(segment
		(start 372.07698 -349.831914)
		(end 371.756432 -349.511366)
		(width 0.13462)
		(layer "F.Cu")
		(net "P5E_PEX3_STN6_TX_DN<103>")
	)
	(segment
		(start 371.756432 -349.511366)
		(end 371.756432 -348.880938)
		(width 0.13462)
		(layer "F.Cu")
		(net "P5E_PEX3_STN6_TX_DN<103>")
	)
	(segment
		(start 371.756432 -348.880938)
		(end 372.05158 -348.58579)
		(width 0.13462)
		(layer "F.Cu")
		(net "P5E_PEX3_STN6_TX_DN<103>")
	)
	(segment
		(start 372.05158 -348.58579)
		(end 371.76075 -348.29496)
		(width 0.1651)
		(layer "In7.Cu")
		(net "P5E_PEX3_STN6_TX_DN<103>")
	)
	(segment
		(start 397.802862 -321.462908)
		(end 399.066004 -320.199766)
		(width 0.1651)
		(layer "In7.Cu")
		(net "P5E_PEX3_STN6_TX_DN<103>")
	)
	(segment
		(start 399.066004 -320.199766)
		(end 399.066004 -319.977008)
		(width 0.1651)
		(layer "In7.Cu")
		(net "P5E_PEX3_STN6_TX_DN<103>")
	)
	(segment
		(start 399.400014 -311.784492)
		(end 399.400014 -312.049922)
		(width 0.1143)
		(layer "In7.Cu")
		(net "P5E_PEX3_STN6_TX_DN<103>")
	)
	(segment
		(start 371.76075 -348.29496)
		(end 371.76075 -347.784674)
		(width 0.1651)
		(layer "In7.Cu")
		(net "P5E_PEX3_STN6_TX_DN<103>")
	)
	(segment
		(start 371.76075 -347.784674)
		(end 373.31523 -346.230194)
		(width 0.1651)
		(layer "In7.Cu")
		(net "P5E_PEX3_STN6_TX_DN<103>")
	)
	(segment
		(start 399.066004 -319.94856)
		(end 399.020284 -319.90284)
		(width 0.1143)
		(layer "In7.Cu")
		(net "P5E_PEX3_STN6_TX_DN<103>")
	)
	(segment
		(start 373.31523 -346.230194)
		(end 373.31523 -341.335614)
		(width 0.1651)
		(layer "In7.Cu")
		(net "P5E_PEX3_STN6_TX_DN<103>")
	)
	(segment
		(start 399.020284 -319.90284)
		(end 399.020284 -311.784492)
		(width 0.1143)
		(layer "In7.Cu")
		(net "P5E_PEX3_STN6_TX_DN<103>")
	)
	(segment
		(start 399.020284 -311.784492)
		(end 399.134584 -311.670192)
		(width 0.1143)
		(layer "In7.Cu")
		(net "P5E_PEX3_STN6_TX_DN<103>")
	)
	(segment
		(start 373.31523 -341.335614)
		(end 397.802862 -321.462908)
		(width 0.1651)
		(layer "In7.Cu")
		(net "P5E_PEX3_STN6_TX_DN<103>")
	)
	(segment
		(start 399.285714 -311.670192)
		(end 399.400014 -311.784492)
		(width 0.1143)
		(layer "In7.Cu")
		(net "P5E_PEX3_STN6_TX_DN<103>")
	)
	(segment
		(start 399.134584 -311.670192)
		(end 399.285714 -311.670192)
		(width 0.1143)
		(layer "In7.Cu")
		(net "P5E_PEX3_STN6_TX_DN<103>")
	)
	(segment
		(start 399.066004 -319.977008)
		(end 399.066004 -319.94856)
		(width 0.1143)
		(layer "In7.Cu")
		(net "P5E_PEX3_STN6_TX_DN<103>")
	)
	(segment
		(start 73.947274 -34.520886)
		(end 73.652888 -34.2265)
		(width 0.13462)
		(layer "F.Cu")
		(net "P5E_PEX0_STN2_TX_DP<39>")
	)
	(segment
		(start 73.020936 -34.2265)
		(end 72.70115 -34.546286)
		(width 0.13462)
		(layer "F.Cu")
		(net "P5E_PEX0_STN2_TX_DP<39>")
	)
	(segment
		(start 73.652888 -34.2265)
		(end 73.020936 -34.2265)
		(width 0.13462)
		(layer "F.Cu")
		(net "P5E_PEX0_STN2_TX_DP<39>")
	)
	(segment
		(start 61.069982 -107.162092)
		(end 59.64682 -114.435636)
		(width 0.1651)
		(layer "In11.Cu")
		(net "P5E_PEX0_STN2_TX_DP<39>")
	)
	(segment
		(start 51.433984 -262.791702)
		(end 51.433984 -271.399)
		(width 0.1651)
		(layer "In11.Cu")
		(net "P5E_PEX0_STN2_TX_DP<39>")
	)
	(segment
		(start 77.518768 -37.36467)
		(end 77.640942 -37.394134)
		(width 0.1651)
		(layer "In11.Cu")
		(net "P5E_PEX0_STN2_TX_DP<39>")
	)
	(segment
		(start 58.92927 -120.262396)
		(end 58.928762 -120.262396)
		(width 0.1651)
		(layer "In11.Cu")
		(net "P5E_PEX0_STN2_TX_DP<39>")
	)
	(segment
		(start 77.259942 -36.942014)
		(end 77.518768 -37.36467)
		(width 0.1651)
		(layer "In11.Cu")
		(net "P5E_PEX0_STN2_TX_DP<39>")
	)
	(segment
		(start 73.947274 -34.520886)
		(end 74.238104 -34.230056)
		(width 0.1651)
		(layer "In11.Cu")
		(net "P5E_PEX0_STN2_TX_DP<39>")
	)
	(segment
		(start 58.905902 -120.44807)
		(end 58.784744 -121.433336)
		(width 0.1651)
		(layer "In11.Cu")
		(net "P5E_PEX0_STN2_TX_DP<39>")
	)
	(segment
		(start 80.468724 -42.014394)
		(end 87.01151 -49.155858)
		(width 0.1651)
		(layer "In11.Cu")
		(net "P5E_PEX0_STN2_TX_DP<39>")
	)
	(segment
		(start 87.994998 -58.556144)
		(end 87.994998 -60.128404)
		(width 0.1651)
		(layer "In11.Cu")
		(net "P5E_PEX0_STN2_TX_DP<39>")
	)
	(segment
		(start 87.994998 -60.128404)
		(end 87.511128 -61.953394)
		(width 0.1651)
		(layer "In11.Cu")
		(net "P5E_PEX0_STN2_TX_DP<39>")
	)
	(segment
		(start 51.694842 -278.420068)
		(end 51.935634 -278.420068)
		(width 0.1143)
		(layer "In11.Cu")
		(net "P5E_PEX0_STN2_TX_DP<39>")
	)
	(segment
		(start 59.64682 -114.435636)
		(end 58.92927 -120.262396)
		(width 0.1651)
		(layer "In11.Cu")
		(net "P5E_PEX0_STN2_TX_DP<39>")
	)
	(segment
		(start 87.01151 -49.155858)
		(end 87.994998 -58.556144)
		(width 0.1651)
		(layer "In11.Cu")
		(net "P5E_PEX0_STN2_TX_DP<39>")
	)
	(segment
		(start 58.906156 -120.44807)
		(end 58.905902 -120.44807)
		(width 0.1651)
		(layer "In11.Cu")
		(net "P5E_PEX0_STN2_TX_DP<39>")
	)
	(segment
		(start 74.238104 -34.230056)
		(end 74.755502 -34.230056)
		(width 0.1651)
		(layer "In11.Cu")
		(net "P5E_PEX0_STN2_TX_DP<39>")
	)
	(segment
		(start 75.21067 -34.419794)
		(end 76.802488 -36.024312)
		(width 0.1651)
		(layer "In11.Cu")
		(net "P5E_PEX0_STN2_TX_DP<39>")
	)
	(segment
		(start 78.25105 -38.39083)
		(end 80.468724 -42.014394)
		(width 0.1651)
		(layer "In11.Cu")
		(net "P5E_PEX0_STN2_TX_DP<39>")
	)
	(segment
		(start 77.87005 -37.93871)
		(end 78.128876 -38.361366)
		(width 0.1651)
		(layer "In11.Cu")
		(net "P5E_PEX0_STN2_TX_DP<39>")
	)
	(segment
		(start 58.784744 -121.433336)
		(end 51.433984 -262.791702)
		(width 0.1651)
		(layer "In11.Cu")
		(net "P5E_PEX0_STN2_TX_DP<39>")
	)
	(segment
		(start 64.369442 -92.692474)
		(end 61.069982 -107.162092)
		(width 0.1651)
		(layer "In11.Cu")
		(net "P5E_PEX0_STN2_TX_DP<39>")
	)
	(segment
		(start 86.642448 -63.68415)
		(end 64.369442 -92.692474)
		(width 0.1651)
		(layer "In11.Cu")
		(net "P5E_PEX0_STN2_TX_DP<39>")
	)
	(segment
		(start 51.433984 -271.399)
		(end 51.433984 -271.427448)
		(width 0.1143)
		(layer "In11.Cu")
		(net "P5E_PEX0_STN2_TX_DP<39>")
	)
	(segment
		(start 87.511128 -61.953394)
		(end 86.642448 -63.68415)
		(width 0.1651)
		(layer "In11.Cu")
		(net "P5E_PEX0_STN2_TX_DP<39>")
	)
	(segment
		(start 77.640942 -37.394134)
		(end 77.89926 -37.816536)
		(width 0.1651)
		(layer "In11.Cu")
		(net "P5E_PEX0_STN2_TX_DP<39>")
	)
	(segment
		(start 51.479704 -278.20493)
		(end 51.694842 -278.420068)
		(width 0.1143)
		(layer "In11.Cu")
		(net "P5E_PEX0_STN2_TX_DP<39>")
	)
	(segment
		(start 77.89926 -37.816536)
		(end 77.87005 -37.93871)
		(width 0.1651)
		(layer "In11.Cu")
		(net "P5E_PEX0_STN2_TX_DP<39>")
	)
	(segment
		(start 51.433984 -271.427448)
		(end 51.479704 -271.473168)
		(width 0.1143)
		(layer "In11.Cu")
		(net "P5E_PEX0_STN2_TX_DP<39>")
	)
	(segment
		(start 78.128876 -38.361366)
		(end 78.25105 -38.39083)
		(width 0.1651)
		(layer "In11.Cu")
		(net "P5E_PEX0_STN2_TX_DP<39>")
	)
	(segment
		(start 51.935634 -278.420068)
		(end 52.049934 -278.534368)
		(width 0.1143)
		(layer "In11.Cu")
		(net "P5E_PEX0_STN2_TX_DP<39>")
	)
	(segment
		(start 77.289406 -36.819586)
		(end 77.259942 -36.942014)
		(width 0.1651)
		(layer "In11.Cu")
		(net "P5E_PEX0_STN2_TX_DP<39>")
	)
	(segment
		(start 51.479704 -271.473168)
		(end 51.479704 -278.20493)
		(width 0.1143)
		(layer "In11.Cu")
		(net "P5E_PEX0_STN2_TX_DP<39>")
	)
	(segment
		(start 58.928762 -120.262396)
		(end 58.906156 -120.44807)
		(width 0.1651)
		(layer "In11.Cu")
		(net "P5E_PEX0_STN2_TX_DP<39>")
	)
	(segment
		(start 76.802488 -36.024312)
		(end 77.289406 -36.819586)
		(width 0.1651)
		(layer "In11.Cu")
		(net "P5E_PEX0_STN2_TX_DP<39>")
	)
	(segment
		(start 52.049934 -278.534368)
		(end 52.049934 -278.799798)
		(width 0.1143)
		(layer "In11.Cu")
		(net "P5E_PEX0_STN2_TX_DP<39>")
	)
	(segment
		(start 74.755502 -34.230056)
		(end 75.21067 -34.419794)
		(width 0.1651)
		(layer "In11.Cu")
		(net "P5E_PEX0_STN2_TX_DP<39>")
	)
	(segment
		(start 140.411708 -343.365582)
		(end 140.411708 -342.734138)
		(width 0.13462)
		(layer "F.Cu")
		(net "P5E_PEX1_STN5_TX_DN<85>")
	)
	(segment
		(start 140.411708 -342.734138)
		(end 140.706348 -342.439498)
		(width 0.13462)
		(layer "F.Cu")
		(net "P5E_PEX1_STN5_TX_DN<85>")
	)
	(segment
		(start 140.731748 -343.685622)
		(end 140.411708 -343.365582)
		(width 0.13462)
		(layer "F.Cu")
		(net "P5E_PEX1_STN5_TX_DN<85>")
	)
	(segment
		(start 140.5509 -341.430864)
		(end 155.69057 -336.83829)
		(width 0.1651)
		(layer "In7.Cu")
		(net "P5E_PEX1_STN5_TX_DN<85>")
	)
	(segment
		(start 155.69057 -336.83829)
		(end 155.690824 -336.838036)
		(width 0.1651)
		(layer "In7.Cu")
		(net "P5E_PEX1_STN5_TX_DN<85>")
	)
	(segment
		(start 175.117252 -329.675744)
		(end 178.223926 -326.56907)
		(width 0.1651)
		(layer "In7.Cu")
		(net "P5E_PEX1_STN5_TX_DN<85>")
	)
	(segment
		(start 179.55006 -313.684412)
		(end 179.55006 -313.949842)
		(width 0.1143)
		(layer "In7.Cu")
		(net "P5E_PEX1_STN5_TX_DN<85>")
	)
	(segment
		(start 140.415518 -341.612982)
		(end 140.5509 -341.430864)
		(width 0.1651)
		(layer "In7.Cu")
		(net "P5E_PEX1_STN5_TX_DN<85>")
	)
	(segment
		(start 178.223926 -326.56907)
		(end 179.21605 -324.173596)
		(width 0.1651)
		(layer "In7.Cu")
		(net "P5E_PEX1_STN5_TX_DN<85>")
	)
	(segment
		(start 140.415518 -342.148668)
		(end 140.415518 -341.612982)
		(width 0.1651)
		(layer "In7.Cu")
		(net "P5E_PEX1_STN5_TX_DN<85>")
	)
	(segment
		(start 155.690824 -336.838036)
		(end 170.829986 -332.245716)
		(width 0.1651)
		(layer "In7.Cu")
		(net "P5E_PEX1_STN5_TX_DN<85>")
	)
	(segment
		(start 140.706348 -342.439498)
		(end 140.415518 -342.148668)
		(width 0.1651)
		(layer "In7.Cu")
		(net "P5E_PEX1_STN5_TX_DN<85>")
	)
	(segment
		(start 179.21605 -320.002408)
		(end 179.21605 -319.97396)
		(width 0.1143)
		(layer "In7.Cu")
		(net "P5E_PEX1_STN5_TX_DN<85>")
	)
	(segment
		(start 179.43576 -313.570112)
		(end 179.55006 -313.684412)
		(width 0.1143)
		(layer "In7.Cu")
		(net "P5E_PEX1_STN5_TX_DN<85>")
	)
	(segment
		(start 179.17033 -313.684412)
		(end 179.28463 -313.570112)
		(width 0.1143)
		(layer "In7.Cu")
		(net "P5E_PEX1_STN5_TX_DN<85>")
	)
	(segment
		(start 179.17033 -319.92824)
		(end 179.17033 -313.684412)
		(width 0.1143)
		(layer "In7.Cu")
		(net "P5E_PEX1_STN5_TX_DN<85>")
	)
	(segment
		(start 170.829986 -332.245716)
		(end 175.117252 -329.675744)
		(width 0.1651)
		(layer "In7.Cu")
		(net "P5E_PEX1_STN5_TX_DN<85>")
	)
	(segment
		(start 179.21605 -324.173596)
		(end 179.21605 -320.002408)
		(width 0.1651)
		(layer "In7.Cu")
		(net "P5E_PEX1_STN5_TX_DN<85>")
	)
	(segment
		(start 179.28463 -313.570112)
		(end 179.43576 -313.570112)
		(width 0.1143)
		(layer "In7.Cu")
		(net "P5E_PEX1_STN5_TX_DN<85>")
	)
	(segment
		(start 179.21605 -319.97396)
		(end 179.17033 -319.92824)
		(width 0.1143)
		(layer "In7.Cu")
		(net "P5E_PEX1_STN5_TX_DN<85>")
	)
	(segment
		(start 329.219814 -28.829)
		(end 328.569574 -28.829)
		(width 0.13462)
		(layer "F.Cu")
		(net "P5E_PEX2_STN2_TX_DP<32>")
	)
	(segment
		(start 328.569574 -28.829)
		(end 328.258932 -29.139642)
		(width 0.13462)
		(layer "F.Cu")
		(net "P5E_PEX2_STN2_TX_DP<32>")
	)
	(segment
		(start 329.505056 -29.114242)
		(end 329.219814 -28.829)
		(width 0.13462)
		(layer "F.Cu")
		(net "P5E_PEX2_STN2_TX_DP<32>")
	)
	(segment
		(start 327.4314 -81.8134)
		(end 313.8678 -105.9434)
		(width 0.1651)
		(layer "In11.Cu")
		(net "P5E_PEX2_STN2_TX_DP<32>")
	)
	(segment
		(start 290.89985 -280.434288)
		(end 290.89985 -280.699718)
		(width 0.1143)
		(layer "In11.Cu")
		(net "P5E_PEX2_STN2_TX_DP<32>")
	)
	(segment
		(start 341.05215 -42.485818)
		(end 341.340186 -56.946546)
		(width 0.1651)
		(layer "In11.Cu")
		(net "P5E_PEX2_STN2_TX_DP<32>")
	)
	(segment
		(start 331.559662 -28.823412)
		(end 333.853282 -29.735018)
		(width 0.1651)
		(layer "In11.Cu")
		(net "P5E_PEX2_STN2_TX_DP<32>")
	)
	(segment
		(start 337.297776 -34.479992)
		(end 337.418426 -34.515298)
		(width 0.1651)
		(layer "In11.Cu")
		(net "P5E_PEX2_STN2_TX_DP<32>")
	)
	(segment
		(start 290.78555 -280.319988)
		(end 290.89985 -280.434288)
		(width 0.1143)
		(layer "In11.Cu")
		(net "P5E_PEX2_STN2_TX_DP<32>")
	)
	(segment
		(start 336.642964 -75.376786)
		(end 335.74482 -76.534772)
		(width 0.1651)
		(layer "In11.Cu")
		(net "P5E_PEX2_STN2_TX_DP<32>")
	)
	(segment
		(start 313.8678 -105.9434)
		(end 312.374788 -117.958362)
		(width 0.1651)
		(layer "In11.Cu")
		(net "P5E_PEX2_STN2_TX_DP<32>")
	)
	(segment
		(start 311.354724 -141.889734)
		(end 311.168796 -146.24304)
		(width 0.1651)
		(layer "In11.Cu")
		(net "P5E_PEX2_STN2_TX_DP<32>")
	)
	(segment
		(start 290.32962 -280.10485)
		(end 290.544758 -280.319988)
		(width 0.1143)
		(layer "In11.Cu")
		(net "P5E_PEX2_STN2_TX_DP<32>")
	)
	(segment
		(start 311.615836 -140.76553)
		(end 311.354724 -141.889734)
		(width 0.1651)
		(layer "In11.Cu")
		(net "P5E_PEX2_STN2_TX_DP<32>")
	)
	(segment
		(start 329.505056 -29.114242)
		(end 329.795886 -28.823412)
		(width 0.1651)
		(layer "In11.Cu")
		(net "P5E_PEX2_STN2_TX_DP<32>")
	)
	(segment
		(start 335.959704 -31.84652)
		(end 336.53476 -32.898842)
		(width 0.1651)
		(layer "In11.Cu")
		(net "P5E_PEX2_STN2_TX_DP<32>")
	)
	(segment
		(start 340.367874 -39.912036)
		(end 341.05215 -42.485818)
		(width 0.1651)
		(layer "In11.Cu")
		(net "P5E_PEX2_STN2_TX_DP<32>")
	)
	(segment
		(start 336.499454 -33.019492)
		(end 336.737198 -33.454594)
		(width 0.1651)
		(layer "In11.Cu")
		(net "P5E_PEX2_STN2_TX_DP<32>")
	)
	(segment
		(start 329.795886 -28.823412)
		(end 331.559662 -28.823412)
		(width 0.1651)
		(layer "In11.Cu")
		(net "P5E_PEX2_STN2_TX_DP<32>")
	)
	(segment
		(start 311.615836 -135.763508)
		(end 311.615836 -140.76553)
		(width 0.1651)
		(layer "In11.Cu")
		(net "P5E_PEX2_STN2_TX_DP<32>")
	)
	(segment
		(start 336.737198 -33.454594)
		(end 336.857848 -33.4899)
		(width 0.1651)
		(layer "In11.Cu")
		(net "P5E_PEX2_STN2_TX_DP<32>")
	)
	(segment
		(start 337.095338 -33.924494)
		(end 337.059778 -34.045144)
		(width 0.1651)
		(layer "In11.Cu")
		(net "P5E_PEX2_STN2_TX_DP<32>")
	)
	(segment
		(start 311.168796 -146.24304)
		(end 310.54421 -153.837386)
		(width 0.1651)
		(layer "In11.Cu")
		(net "P5E_PEX2_STN2_TX_DP<32>")
	)
	(segment
		(start 337.059778 -34.045144)
		(end 337.297776 -34.479992)
		(width 0.1651)
		(layer "In11.Cu")
		(net "P5E_PEX2_STN2_TX_DP<32>")
	)
	(segment
		(start 290.2839 -271.399)
		(end 290.2839 -271.427448)
		(width 0.1143)
		(layer "In11.Cu")
		(net "P5E_PEX2_STN2_TX_DP<32>")
	)
	(segment
		(start 290.544758 -280.319988)
		(end 290.78555 -280.319988)
		(width 0.1143)
		(layer "In11.Cu")
		(net "P5E_PEX2_STN2_TX_DP<32>")
	)
	(segment
		(start 329.111102 -80.133698)
		(end 327.4314 -81.8134)
		(width 0.1651)
		(layer "In11.Cu")
		(net "P5E_PEX2_STN2_TX_DP<32>")
	)
	(segment
		(start 310.54421 -153.837386)
		(end 309.591456 -161.014918)
		(width 0.1651)
		(layer "In11.Cu")
		(net "P5E_PEX2_STN2_TX_DP<32>")
	)
	(segment
		(start 336.857848 -33.4899)
		(end 337.095338 -33.924494)
		(width 0.1651)
		(layer "In11.Cu")
		(net "P5E_PEX2_STN2_TX_DP<32>")
	)
	(segment
		(start 312.374788 -117.958362)
		(end 311.615836 -135.763508)
		(width 0.1651)
		(layer "In11.Cu")
		(net "P5E_PEX2_STN2_TX_DP<32>")
	)
	(segment
		(start 333.853282 -29.735018)
		(end 335.959704 -31.84652)
		(width 0.1651)
		(layer "In11.Cu")
		(net "P5E_PEX2_STN2_TX_DP<32>")
	)
	(segment
		(start 290.32962 -271.473168)
		(end 290.32962 -280.10485)
		(width 0.1143)
		(layer "In11.Cu")
		(net "P5E_PEX2_STN2_TX_DP<32>")
	)
	(segment
		(start 290.2839 -266.06373)
		(end 290.2839 -271.399)
		(width 0.1651)
		(layer "In11.Cu")
		(net "P5E_PEX2_STN2_TX_DP<32>")
	)
	(segment
		(start 336.53476 -32.898842)
		(end 336.499454 -33.019492)
		(width 0.1651)
		(layer "In11.Cu")
		(net "P5E_PEX2_STN2_TX_DP<32>")
	)
	(segment
		(start 339.04047 -68.690744)
		(end 336.642964 -75.376786)
		(width 0.1651)
		(layer "In11.Cu")
		(net "P5E_PEX2_STN2_TX_DP<32>")
	)
	(segment
		(start 337.418426 -34.515298)
		(end 340.367874 -39.912036)
		(width 0.1651)
		(layer "In11.Cu")
		(net "P5E_PEX2_STN2_TX_DP<32>")
	)
	(segment
		(start 335.74482 -76.534772)
		(end 329.111102 -80.133698)
		(width 0.1651)
		(layer "In11.Cu")
		(net "P5E_PEX2_STN2_TX_DP<32>")
	)
	(segment
		(start 290.2839 -271.427448)
		(end 290.32962 -271.473168)
		(width 0.1143)
		(layer "In11.Cu")
		(net "P5E_PEX2_STN2_TX_DP<32>")
	)
	(segment
		(start 309.591456 -161.014918)
		(end 290.2839 -266.06373)
		(width 0.1651)
		(layer "In11.Cu")
		(net "P5E_PEX2_STN2_TX_DP<32>")
	)
	(segment
		(start 341.340186 -56.946546)
		(end 339.04047 -68.690744)
		(width 0.1651)
		(layer "In11.Cu")
		(net "P5E_PEX2_STN2_TX_DP<32>")
	)
	(segment
		(start 334.240124 -349.831914)
		(end 334.560164 -349.511874)
		(width 0.13462)
		(layer "F.Cu")
		(net "P5E_PEX2_STN6_TX_DP<101>")
	)
	(segment
		(start 334.560164 -349.511874)
		(end 334.560164 -348.88043)
		(width 0.13462)
		(layer "F.Cu")
		(net "P5E_PEX2_STN6_TX_DP<101>")
	)
	(segment
		(start 334.560164 -348.88043)
		(end 334.265524 -348.58579)
		(width 0.13462)
		(layer "F.Cu")
		(net "P5E_PEX2_STN6_TX_DP<101>")
	)
	(segment
		(start 336.110834 -346.113354)
		(end 336.110834 -342.145874)
		(width 0.1651)
		(layer "In13.Cu")
		(net "P5E_PEX2_STN6_TX_DP<101>")
	)
	(segment
		(start 285.085536 -311.479692)
		(end 285.199836 -311.365392)
		(width 0.1143)
		(layer "In13.Cu")
		(net "P5E_PEX2_STN6_TX_DP<101>")
	)
	(segment
		(start 335.5467 -341.28202)
		(end 331.721206 -337.856576)
		(width 0.1651)
		(layer "In13.Cu")
		(net "P5E_PEX2_STN6_TX_DP<101>")
	)
	(segment
		(start 284.717998 -323.165978)
		(end 284.583886 -322.842128)
		(width 0.1651)
		(layer "In13.Cu")
		(net "P5E_PEX2_STN6_TX_DP<101>")
	)
	(segment
		(start 336.110834 -342.145874)
		(end 335.5467 -341.28202)
		(width 0.1651)
		(layer "In13.Cu")
		(net "P5E_PEX2_STN6_TX_DP<101>")
	)
	(segment
		(start 285.199836 -311.365392)
		(end 285.199836 -311.099962)
		(width 0.1143)
		(layer "In13.Cu")
		(net "P5E_PEX2_STN6_TX_DP<101>")
	)
	(segment
		(start 286.25292 -324.7009)
		(end 284.717998 -323.165978)
		(width 0.1651)
		(layer "In13.Cu")
		(net "P5E_PEX2_STN6_TX_DP<101>")
	)
	(segment
		(start 331.721206 -337.856576)
		(end 314.68441 -330.288138)
		(width 0.1651)
		(layer "In13.Cu")
		(net "P5E_PEX2_STN6_TX_DP<101>")
	)
	(segment
		(start 334.556354 -348.29496)
		(end 334.556354 -347.667834)
		(width 0.1651)
		(layer "In13.Cu")
		(net "P5E_PEX2_STN6_TX_DP<101>")
	)
	(segment
		(start 284.629606 -319.921128)
		(end 284.629606 -311.7596)
		(width 0.1143)
		(layer "In13.Cu")
		(net "P5E_PEX2_STN6_TX_DP<101>")
	)
	(segment
		(start 284.583886 -319.966848)
		(end 284.629606 -319.921128)
		(width 0.1143)
		(layer "In13.Cu")
		(net "P5E_PEX2_STN6_TX_DP<101>")
	)
	(segment
		(start 284.629606 -311.7596)
		(end 284.909514 -311.479692)
		(width 0.1143)
		(layer "In13.Cu")
		(net "P5E_PEX2_STN6_TX_DP<101>")
	)
	(segment
		(start 284.909514 -311.479692)
		(end 285.085536 -311.479692)
		(width 0.1143)
		(layer "In13.Cu")
		(net "P5E_PEX2_STN6_TX_DP<101>")
	)
	(segment
		(start 284.583886 -322.842128)
		(end 284.583886 -319.995296)
		(width 0.1651)
		(layer "In13.Cu")
		(net "P5E_PEX2_STN6_TX_DP<101>")
	)
	(segment
		(start 284.583886 -319.995296)
		(end 284.583886 -319.966848)
		(width 0.1143)
		(layer "In13.Cu")
		(net "P5E_PEX2_STN6_TX_DP<101>")
	)
	(segment
		(start 334.556354 -347.667834)
		(end 336.110834 -346.113354)
		(width 0.1651)
		(layer "In13.Cu")
		(net "P5E_PEX2_STN6_TX_DP<101>")
	)
	(segment
		(start 314.68441 -330.288138)
		(end 286.25292 -324.7009)
		(width 0.1651)
		(layer "In13.Cu")
		(net "P5E_PEX2_STN6_TX_DP<101>")
	)
	(segment
		(start 334.265524 -348.58579)
		(end 334.556354 -348.29496)
		(width 0.1651)
		(layer "In13.Cu")
		(net "P5E_PEX2_STN6_TX_DP<101>")
	)
	(segment
		(start 386.983986 -121.5898)
		(end 387.313932 -121.919746)
		(width 0.13462)
		(layer "F.Cu")
		(net "P5E_PEX3_STN1_TX_DP<25>")
	)
	(segment
		(start 386.372354 -121.5898)
		(end 386.983986 -121.5898)
		(width 0.13462)
		(layer "F.Cu")
		(net "P5E_PEX3_STN1_TX_DP<25>")
	)
	(segment
		(start 386.067808 -121.894346)
		(end 386.372354 -121.5898)
		(width 0.13462)
		(layer "F.Cu")
		(net "P5E_PEX3_STN1_TX_DP<25>")
	)
	(segment
		(start 416.499802 -280.015188)
		(end 416.385502 -280.129488)
		(width 0.1143)
		(layer "In9.Cu")
		(net "P5E_PEX3_STN1_TX_DP<25>")
	)
	(segment
		(start 382.754124 -121.603516)
		(end 383.4257 -121.603516)
		(width 0.1651)
		(layer "In9.Cu")
		(net "P5E_PEX3_STN1_TX_DP<25>")
	)
	(segment
		(start 384.5052 -121.692416)
		(end 384.9116 -121.692416)
		(width 0.1651)
		(layer "In9.Cu")
		(net "P5E_PEX3_STN1_TX_DP<25>")
	)
	(segment
		(start 380.038356 -143.330422)
		(end 377.496832 -137.195052)
		(width 0.1651)
		(layer "In9.Cu")
		(net "P5E_PEX3_STN1_TX_DP<25>")
	)
	(segment
		(start 377.496832 -132.382006)
		(end 378.107956 -130.906774)
		(width 0.1651)
		(layer "In9.Cu")
		(net "P5E_PEX3_STN1_TX_DP<25>")
	)
	(segment
		(start 379.896624 -126.588012)
		(end 380.012702 -126.540006)
		(width 0.1651)
		(layer "In9.Cu")
		(net "P5E_PEX3_STN1_TX_DP<25>")
	)
	(segment
		(start 380.601728 -124.886212)
		(end 380.791212 -124.428758)
		(width 0.1651)
		(layer "In9.Cu")
		(net "P5E_PEX3_STN1_TX_DP<25>")
	)
	(segment
		(start 380.343918 -125.508512)
		(end 380.343918 -125.508258)
		(width 0.1651)
		(layer "In9.Cu")
		(net "P5E_PEX3_STN1_TX_DP<25>")
	)
	(segment
		(start 378.365766 -130.284474)
		(end 378.55525 -129.82702)
		(width 0.1651)
		(layer "In9.Cu")
		(net "P5E_PEX3_STN1_TX_DP<25>")
	)
	(segment
		(start 379.00229 -128.747266)
		(end 379.118368 -128.69926)
		(width 0.1651)
		(layer "In9.Cu")
		(net "P5E_PEX3_STN1_TX_DP<25>")
	)
	(segment
		(start 381.400812 -122.956828)
		(end 381.771398 -122.586242)
		(width 0.1651)
		(layer "In9.Cu")
		(net "P5E_PEX3_STN1_TX_DP<25>")
	)
	(segment
		(start 380.012702 -126.540006)
		(end 380.202694 -126.082044)
		(width 0.1651)
		(layer "In9.Cu")
		(net "P5E_PEX3_STN1_TX_DP<25>")
	)
	(segment
		(start 383.4257 -121.603516)
		(end 383.5146 -121.692416)
		(width 0.1651)
		(layer "In9.Cu")
		(net "P5E_PEX3_STN1_TX_DP<25>")
	)
	(segment
		(start 380.769368 -158.205678)
		(end 380.038356 -143.330422)
		(width 0.1651)
		(layer "In9.Cu")
		(net "P5E_PEX3_STN1_TX_DP<25>")
	)
	(segment
		(start 384.0099 -121.603516)
		(end 384.4163 -121.603516)
		(width 0.1651)
		(layer "In9.Cu")
		(net "P5E_PEX3_STN1_TX_DP<25>")
	)
	(segment
		(start 379.2601 -128.12522)
		(end 379.449584 -127.667766)
		(width 0.1651)
		(layer "In9.Cu")
		(net "P5E_PEX3_STN1_TX_DP<25>")
	)
	(segment
		(start 379.896878 -126.588012)
		(end 379.896624 -126.588012)
		(width 0.1651)
		(layer "In9.Cu")
		(net "P5E_PEX3_STN1_TX_DP<25>")
	)
	(segment
		(start 380.649988 -125.00229)
		(end 380.601728 -124.886212)
		(width 0.1651)
		(layer "In9.Cu")
		(net "P5E_PEX3_STN1_TX_DP<25>")
	)
	(segment
		(start 380.791212 -124.428758)
		(end 380.791212 -124.428504)
		(width 0.1651)
		(layer "In9.Cu")
		(net "P5E_PEX3_STN1_TX_DP<25>")
	)
	(segment
		(start 381.771398 -122.586242)
		(end 381.915162 -122.586242)
		(width 0.1651)
		(layer "In9.Cu")
		(net "P5E_PEX3_STN1_TX_DP<25>")
	)
	(segment
		(start 379.449584 -127.667766)
		(end 379.449584 -127.667512)
		(width 0.1651)
		(layer "In9.Cu")
		(net "P5E_PEX3_STN1_TX_DP<25>")
	)
	(segment
		(start 385.0005 -121.603516)
		(end 385.776978 -121.603516)
		(width 0.1651)
		(layer "In9.Cu")
		(net "P5E_PEX3_STN1_TX_DP<25>")
	)
	(segment
		(start 378.861066 -129.321052)
		(end 378.812806 -129.204974)
		(width 0.1651)
		(layer "In9.Cu")
		(net "P5E_PEX3_STN1_TX_DP<25>")
	)
	(segment
		(start 416.385502 -280.129488)
		(end 416.223704 -280.129488)
		(width 0.1143)
		(layer "In9.Cu")
		(net "P5E_PEX3_STN1_TX_DP<25>")
	)
	(segment
		(start 380.343918 -125.508258)
		(end 380.459996 -125.460252)
		(width 0.1651)
		(layer "In9.Cu")
		(net "P5E_PEX3_STN1_TX_DP<25>")
	)
	(segment
		(start 416.499802 -279.749504)
		(end 416.499802 -280.015188)
		(width 0.1143)
		(layer "In9.Cu")
		(net "P5E_PEX3_STN1_TX_DP<25>")
	)
	(segment
		(start 383.5146 -121.692416)
		(end 383.921 -121.692416)
		(width 0.1651)
		(layer "In9.Cu")
		(net "P5E_PEX3_STN1_TX_DP<25>")
	)
	(segment
		(start 378.554996 -129.82702)
		(end 378.671074 -129.779014)
		(width 0.1651)
		(layer "In9.Cu")
		(net "P5E_PEX3_STN1_TX_DP<25>")
	)
	(segment
		(start 380.154434 -125.965966)
		(end 380.343918 -125.508512)
		(width 0.1651)
		(layer "In9.Cu")
		(net "P5E_PEX3_STN1_TX_DP<25>")
	)
	(segment
		(start 379.118368 -128.69926)
		(end 379.30836 -128.241298)
		(width 0.1651)
		(layer "In9.Cu")
		(net "P5E_PEX3_STN1_TX_DP<25>")
	)
	(segment
		(start 378.414026 -130.400552)
		(end 378.365766 -130.284474)
		(width 0.1651)
		(layer "In9.Cu")
		(net "P5E_PEX3_STN1_TX_DP<25>")
	)
	(segment
		(start 416.120072 -271.600168)
		(end 416.165792 -271.554448)
		(width 0.1143)
		(layer "In9.Cu")
		(net "P5E_PEX3_STN1_TX_DP<25>")
	)
	(segment
		(start 379.565662 -127.619506)
		(end 379.755654 -127.161544)
		(width 0.1651)
		(layer "In9.Cu")
		(net "P5E_PEX3_STN1_TX_DP<25>")
	)
	(segment
		(start 416.165792 -264.021824)
		(end 381.371602 -161.233104)
		(width 0.1651)
		(layer "In9.Cu")
		(net "P5E_PEX3_STN1_TX_DP<25>")
	)
	(segment
		(start 380.202694 -126.082044)
		(end 380.154434 -125.965966)
		(width 0.1651)
		(layer "In9.Cu")
		(net "P5E_PEX3_STN1_TX_DP<25>")
	)
	(segment
		(start 416.120072 -280.025856)
		(end 416.120072 -271.600168)
		(width 0.1143)
		(layer "In9.Cu")
		(net "P5E_PEX3_STN1_TX_DP<25>")
	)
	(segment
		(start 380.90729 -124.380498)
		(end 381.097028 -123.92279)
		(width 0.1651)
		(layer "In9.Cu")
		(net "P5E_PEX3_STN1_TX_DP<25>")
	)
	(segment
		(start 385.776978 -121.603516)
		(end 386.067808 -121.894346)
		(width 0.1651)
		(layer "In9.Cu")
		(net "P5E_PEX3_STN1_TX_DP<25>")
	)
	(segment
		(start 416.165792 -271.526)
		(end 416.165792 -264.021824)
		(width 0.1651)
		(layer "In9.Cu")
		(net "P5E_PEX3_STN1_TX_DP<25>")
	)
	(segment
		(start 381.049022 -123.806458)
		(end 381.400812 -122.956828)
		(width 0.1651)
		(layer "In9.Cu")
		(net "P5E_PEX3_STN1_TX_DP<25>")
	)
	(segment
		(start 380.459996 -125.460252)
		(end 380.649988 -125.00229)
		(width 0.1651)
		(layer "In9.Cu")
		(net "P5E_PEX3_STN1_TX_DP<25>")
	)
	(segment
		(start 377.496832 -137.195052)
		(end 377.496832 -132.382006)
		(width 0.1651)
		(layer "In9.Cu")
		(net "P5E_PEX3_STN1_TX_DP<25>")
	)
	(segment
		(start 379.755654 -127.161544)
		(end 379.707394 -127.045466)
		(width 0.1651)
		(layer "In9.Cu")
		(net "P5E_PEX3_STN1_TX_DP<25>")
	)
	(segment
		(start 381.915162 -122.586242)
		(end 382.265682 -122.235722)
		(width 0.1651)
		(layer "In9.Cu")
		(net "P5E_PEX3_STN1_TX_DP<25>")
	)
	(segment
		(start 416.223704 -280.129488)
		(end 416.120072 -280.025856)
		(width 0.1143)
		(layer "In9.Cu")
		(net "P5E_PEX3_STN1_TX_DP<25>")
	)
	(segment
		(start 379.449584 -127.667512)
		(end 379.565662 -127.619506)
		(width 0.1651)
		(layer "In9.Cu")
		(net "P5E_PEX3_STN1_TX_DP<25>")
	)
	(segment
		(start 379.707394 -127.045466)
		(end 379.896878 -126.588012)
		(width 0.1651)
		(layer "In9.Cu")
		(net "P5E_PEX3_STN1_TX_DP<25>")
	)
	(segment
		(start 378.107956 -130.906774)
		(end 378.107956 -130.90652)
		(width 0.1651)
		(layer "In9.Cu")
		(net "P5E_PEX3_STN1_TX_DP<25>")
	)
	(segment
		(start 379.00229 -128.74752)
		(end 379.00229 -128.747266)
		(width 0.1651)
		(layer "In9.Cu")
		(net "P5E_PEX3_STN1_TX_DP<25>")
	)
	(segment
		(start 416.165792 -271.554448)
		(end 416.165792 -271.526)
		(width 0.1143)
		(layer "In9.Cu")
		(net "P5E_PEX3_STN1_TX_DP<25>")
	)
	(segment
		(start 383.921 -121.692416)
		(end 384.0099 -121.603516)
		(width 0.1651)
		(layer "In9.Cu")
		(net "P5E_PEX3_STN1_TX_DP<25>")
	)
	(segment
		(start 378.671074 -129.779014)
		(end 378.861066 -129.321052)
		(width 0.1651)
		(layer "In9.Cu")
		(net "P5E_PEX3_STN1_TX_DP<25>")
	)
	(segment
		(start 381.097028 -123.92279)
		(end 381.049022 -123.806458)
		(width 0.1651)
		(layer "In9.Cu")
		(net "P5E_PEX3_STN1_TX_DP<25>")
	)
	(segment
		(start 382.265682 -122.091958)
		(end 382.754124 -121.603516)
		(width 0.1651)
		(layer "In9.Cu")
		(net "P5E_PEX3_STN1_TX_DP<25>")
	)
	(segment
		(start 378.812806 -129.204974)
		(end 379.00229 -128.74752)
		(width 0.1651)
		(layer "In9.Cu")
		(net "P5E_PEX3_STN1_TX_DP<25>")
	)
	(segment
		(start 384.9116 -121.692416)
		(end 385.0005 -121.603516)
		(width 0.1651)
		(layer "In9.Cu")
		(net "P5E_PEX3_STN1_TX_DP<25>")
	)
	(segment
		(start 379.30836 -128.241298)
		(end 379.2601 -128.12522)
		(width 0.1651)
		(layer "In9.Cu")
		(net "P5E_PEX3_STN1_TX_DP<25>")
	)
	(segment
		(start 378.55525 -129.82702)
		(end 378.554996 -129.82702)
		(width 0.1651)
		(layer "In9.Cu")
		(net "P5E_PEX3_STN1_TX_DP<25>")
	)
	(segment
		(start 380.791212 -124.428504)
		(end 380.90729 -124.380498)
		(width 0.1651)
		(layer "In9.Cu")
		(net "P5E_PEX3_STN1_TX_DP<25>")
	)
	(segment
		(start 378.224034 -130.858514)
		(end 378.414026 -130.400552)
		(width 0.1651)
		(layer "In9.Cu")
		(net "P5E_PEX3_STN1_TX_DP<25>")
	)
	(segment
		(start 381.371602 -161.233104)
		(end 380.769368 -158.205678)
		(width 0.1651)
		(layer "In9.Cu")
		(net "P5E_PEX3_STN1_TX_DP<25>")
	)
	(segment
		(start 382.265682 -122.235722)
		(end 382.265682 -122.091958)
		(width 0.1651)
		(layer "In9.Cu")
		(net "P5E_PEX3_STN1_TX_DP<25>")
	)
	(segment
		(start 384.4163 -121.603516)
		(end 384.5052 -121.692416)
		(width 0.1651)
		(layer "In9.Cu")
		(net "P5E_PEX3_STN1_TX_DP<25>")
	)
	(segment
		(start 378.107956 -130.90652)
		(end 378.224034 -130.858514)
		(width 0.1651)
		(layer "In9.Cu")
		(net "P5E_PEX3_STN1_TX_DP<25>")
	)
	(segment
		(start 383.917952 -349.512382)
		(end 383.917952 -348.879922)
		(width 0.13462)
		(layer "F.Cu")
		(net "P5E_PEX3_STN6_TX_DP<97>")
	)
	(segment
		(start 383.59842 -349.831914)
		(end 383.917952 -349.512382)
		(width 0.13462)
		(layer "F.Cu")
		(net "P5E_PEX3_STN6_TX_DP<97>")
	)
	(segment
		(start 383.917952 -348.879922)
		(end 383.62382 -348.58579)
		(width 0.13462)
		(layer "F.Cu")
		(net "P5E_PEX3_STN6_TX_DP<97>")
	)
	(segment
		(start 404.484078 -319.9892)
		(end 404.484078 -319.960752)
		(width 0.1143)
		(layer "In7.Cu")
		(net "P5E_PEX3_STN6_TX_DP<97>")
	)
	(segment
		(start 383.91465 -347.667834)
		(end 385.46913 -346.113354)
		(width 0.1651)
		(layer "In7.Cu")
		(net "P5E_PEX3_STN6_TX_DP<97>")
	)
	(segment
		(start 385.46913 -346.113354)
		(end 385.46913 -340.88197)
		(width 0.1651)
		(layer "In7.Cu")
		(net "P5E_PEX3_STN6_TX_DP<97>")
	)
	(segment
		(start 404.529798 -319.915032)
		(end 404.529798 -311.705498)
		(width 0.1143)
		(layer "In7.Cu")
		(net "P5E_PEX3_STN6_TX_DP<97>")
	)
	(segment
		(start 404.985728 -311.479692)
		(end 405.100028 -311.365392)
		(width 0.1143)
		(layer "In7.Cu")
		(net "P5E_PEX3_STN6_TX_DP<97>")
	)
	(segment
		(start 383.91465 -348.29496)
		(end 383.91465 -347.667834)
		(width 0.1651)
		(layer "In7.Cu")
		(net "P5E_PEX3_STN6_TX_DP<97>")
	)
	(segment
		(start 404.484078 -321.746626)
		(end 404.484078 -319.9892)
		(width 0.1651)
		(layer "In7.Cu")
		(net "P5E_PEX3_STN6_TX_DP<97>")
	)
	(segment
		(start 404.484078 -319.960752)
		(end 404.529798 -319.915032)
		(width 0.1143)
		(layer "In7.Cu")
		(net "P5E_PEX3_STN6_TX_DP<97>")
	)
	(segment
		(start 401.395692 -325.846948)
		(end 403.768306 -323.474334)
		(width 0.1651)
		(layer "In7.Cu")
		(net "P5E_PEX3_STN6_TX_DP<97>")
	)
	(segment
		(start 405.100028 -311.365392)
		(end 405.100028 -311.099962)
		(width 0.1143)
		(layer "In7.Cu")
		(net "P5E_PEX3_STN6_TX_DP<97>")
	)
	(segment
		(start 404.755604 -311.479692)
		(end 404.985728 -311.479692)
		(width 0.1143)
		(layer "In7.Cu")
		(net "P5E_PEX3_STN6_TX_DP<97>")
	)
	(segment
		(start 383.62382 -348.58579)
		(end 383.91465 -348.29496)
		(width 0.1651)
		(layer "In7.Cu")
		(net "P5E_PEX3_STN6_TX_DP<97>")
	)
	(segment
		(start 403.768306 -323.474334)
		(end 404.484078 -321.746626)
		(width 0.1651)
		(layer "In7.Cu")
		(net "P5E_PEX3_STN6_TX_DP<97>")
	)
	(segment
		(start 385.46913 -340.88197)
		(end 401.395692 -325.846948)
		(width 0.1651)
		(layer "In7.Cu")
		(net "P5E_PEX3_STN6_TX_DP<97>")
	)
	(segment
		(start 404.529798 -311.705498)
		(end 404.755604 -311.479692)
		(width 0.1143)
		(layer "In7.Cu")
		(net "P5E_PEX3_STN6_TX_DP<97>")
	)
	(zone
		(layer "F.Cu")
		(hatch none 0.5)
		(connect_pads
			(clearance 0)
		)
		(min_thickness 0.25)
		(keepout
			(tracks not_allowed)
			(vias allowed)
			(pads allowed)
			(copperpour not_allowed)
			(footprints allowed)
		)
		(placement
			(enabled no)
			(sheetname "")
		)
		(fill
			(thermal_gap 0.5)
			(thermal_bridge_width 0.5)
			(island_removal_mode 0)
		)
		(polygon
			(pts
				(arc
					(start 405.264874 -5.999988)
					(mid 400.264884 -10.999978)
					(end 395.264894 -5.999988)
				)
				(arc
					(start 395.264894 -5.999988)
					(mid 400.264884 -0.999998)
					(end 405.264874 -5.999988)
				)
			)
		)
	)
	(zone
		(layer "F.Cu")
		(hatch none 0.5)
		(connect_pads
			(clearance 0)
		)
		(min_thickness 0.25)
		(keepout
			(tracks not_allowed)
			(vias allowed)
			(pads allowed)
			(copperpour not_allowed)
			(footprints allowed)
		)
		(placement
			(enabled no)
			(sheetname "")
		)
		(fill
			(thermal_gap 0.5)
			(thermal_bridge_width 0.5)
			(island_removal_mode 0)
		)
		(polygon
			(pts
				(arc
					(start 347.89999 -72.69988)
					(mid 349.899986 -70.699884)
					(end 351.899982 -72.69988)
				)
				(arc
					(start 351.899982 -72.69988)
					(mid 349.899986 -74.699876)
					(end 347.89999 -72.69988)
				)
			)
		)
	)
	(zone
		(layer "F.Cu")
		(hatch none 0.5)
		(connect_pads
			(clearance 0)
		)
		(min_thickness 0.25)
		(keepout
			(tracks allowed)
			(vias allowed)
			(pads allowed)
			(copperpour allowed)
			(footprints allowed)
		)
		(placement
			(enabled no)
			(sheetname "")
		)
		(fill
			(thermal_gap 0.5)
			(thermal_bridge_width 0.5)
			(island_removal_mode 0)
		)
		(polygon
			(pts
				(xy 152.055068 -123.928124) (xy 152.055068 -122.576844) (xy 153.335228 -122.576844) (xy 153.335228 -123.928124)
			)
		)
	)
	(zone
		(layer "F.Cu")
		(hatch none 0.5)
		(connect_pads
			(clearance 0)
		)
		(min_thickness 0.25)
		(keepout
			(tracks allowed)
			(vias allowed)
			(pads allowed)
			(copperpour allowed)
			(footprints allowed)
		)
		(placement
			(enabled no)
			(sheetname "")
		)
		(fill
			(thermal_gap 0.5)
			(thermal_bridge_width 0.5)
			(island_removal_mode 0)
		)
		(polygon
			(pts
				(xy 106.7308 -88.138) (xy 106.7308 -83.8962) (xy 110.998 -83.8962) (xy 110.998 -88.138)
			)
		)
	)
	(zone
		(layer "F.Cu")
		(hatch none 0.5)
		(connect_pads
			(clearance 0)
		)
		(min_thickness 0.25)
		(keepout
			(tracks allowed)
			(vias allowed)
			(pads allowed)
			(copperpour allowed)
			(footprints allowed)
		)
		(placement
			(enabled no)
			(sheetname "")
		)
		(fill
			(thermal_gap 0.5)
			(thermal_bridge_width 0.5)
			(island_removal_mode 0)
		)
		(polygon
			(pts
				(xy 98.760026 -46.986444) (xy 99.752404 -46.986444) (xy 99.83724 -46.901608) (xy 99.83724 -46.211744)
				(xy 99.789234 -46.163738) (xy 98.73996 -46.163738) (xy 98.672142 -46.231556) (xy 98.672142 -46.89856)
			)
		)
	)
	(zone
		(layer "F.Cu")
		(hatch none 0.5)
		(connect_pads
			(clearance 0)
		)
		(min_thickness 0.25)
		(keepout
			(tracks not_allowed)
			(vias allowed)
			(pads allowed)
			(copperpour not_allowed)
			(footprints allowed)
		)
		(placement
			(enabled no)
			(sheetname "")
		)
		(fill
			(thermal_gap 0.5)
			(thermal_bridge_width 0.5)
			(island_removal_mode 0)
		)
		(polygon
			(pts
				(arc
					(start 173.064932 -5.999988)
					(mid 168.064942 -10.999978)
					(end 163.064952 -5.999988)
				)
				(arc
					(start 163.064952 -5.999988)
					(mid 168.064942 -0.999998)
					(end 173.064932 -5.999988)
				)
			)
		)
	)
	(zone
		(layer "F.Cu")
		(hatch none 0.5)
		(connect_pads
			(clearance 0)
		)
		(min_thickness 0.25)
		(keepout
			(tracks allowed)
			(vias allowed)
			(pads allowed)
			(copperpour allowed)
			(footprints allowed)
		)
		(placement
			(enabled no)
			(sheetname "")
		)
		(fill
			(thermal_gap 0.5)
			(thermal_bridge_width 0.5)
			(island_removal_mode 0)
		)
		(polygon
			(pts
				(xy 161.145728 -139.281662) (xy 162.523424 -139.281662) (xy 162.88131 -138.923776) (xy 162.88131 -132.947664)
				(xy 162.88131 -129.875026) (xy 162.761676 -129.755392) (xy 160.931352 -129.755392) (xy 160.44799 -130.238754)
				(xy 160.44799 -133.30555) (xy 160.44799 -138.583924)
			)
		)
	)
	(zone
		(layer "F.Cu")
		(hatch none 0.5)
		(connect_pads
			(clearance 0)
		)
		(min_thickness 0.25)
		(keepout
			(tracks not_allowed)
			(vias allowed)
			(pads allowed)
			(copperpour not_allowed)
			(footprints allowed)
		)
		(placement
			(enabled no)
			(sheetname "")
		)
		(fill
			(thermal_gap 0.5)
			(thermal_bridge_width 0.5)
			(island_removal_mode 0)
		)
		(polygon
			(pts
				(arc
					(start 373.450104 -320.900044)
					(mid 377.950222 -316.399926)
					(end 382.450086 -320.900044)
				)
				(arc
					(start 382.450086 -320.900044)
					(mid 377.950222 -325.399908)
					(end 373.450104 -320.900044)
				)
			)
		)
	)
	(zone
		(layer "F.Cu")
		(hatch none 0.5)
		(connect_pads
			(clearance 0)
		)
		(min_thickness 0.25)
		(keepout
			(tracks not_allowed)
			(vias allowed)
			(pads allowed)
			(copperpour not_allowed)
			(footprints allowed)
		)
		(placement
			(enabled no)
			(sheetname "")
		)
		(fill
			(thermal_gap 0.5)
			(thermal_bridge_width 0.5)
			(island_removal_mode 0)
		)
		(polygon
			(pts
				(xy 151.619966 -23.219918) (xy 151.619966 -18.219928) (xy 147.420076 -18.219928) (xy 147.420076 -23.219918)
			)
		)
	)
	(zone
		(layer "F.Cu")
		(hatch none 0.5)
		(connect_pads
			(clearance 0)
		)
		(min_thickness 0.25)
		(keepout
			(tracks allowed)
			(vias allowed)
			(pads allowed)
			(copperpour allowed)
			(footprints not_allowed)
		)
		(placement
			(enabled no)
			(sheetname "")
		)
		(fill
			(thermal_gap 0.5)
			(thermal_bridge_width 0.5)
			(island_removal_mode 0)
		)
		(polygon
			(pts
				(xy 241.503962 -361.045506) (xy 249.091958 -361.045506) (xy 249.091958 -343.75471) (xy 241.503962 -343.75471)
			)
		)
	)
	(zone
		(layer "F.Cu")
		(hatch none 0.5)
		(connect_pads
			(clearance 0)
		)
		(min_thickness 0.25)
		(keepout
			(tracks allowed)
			(vias allowed)
			(pads allowed)
			(copperpour allowed)
			(footprints allowed)
		)
		(placement
			(enabled no)
			(sheetname "")
		)
		(fill
			(thermal_gap 0.5)
			(thermal_bridge_width 0.5)
			(island_removal_mode 0)
		)
		(polygon
			(pts
				(xy 387.836664 -356.952042) (xy 386.485384 -356.952042) (xy 386.485384 -355.671882) (xy 387.836664 -355.671882)
			)
		)
	)
	(zone
		(layer "F.Cu")
		(hatch none 0.5)
		(connect_pads
			(clearance 0)
		)
		(min_thickness 0.25)
		(keepout
			(tracks not_allowed)
			(vias allowed)
			(pads allowed)
			(copperpour not_allowed)
			(footprints allowed)
		)
		(placement
			(enabled no)
			(sheetname "")
		)
		(fill
			(thermal_gap 0.5)
			(thermal_bridge_width 0.5)
			(island_removal_mode 0)
		)
		(polygon
			(pts
				(arc
					(start 28.764992 -17.999964)
					(mid 25.96515 -20.799806)
					(end 23.165054 -17.999964)
				)
				(arc
					(start 23.165054 -17.999964)
					(mid 25.96515 -15.199868)
					(end 28.764992 -17.999964)
				)
			)
		)
	)
	(zone
		(layer "F.Cu")
		(hatch none 0.5)
		(connect_pads
			(clearance 0)
		)
		(min_thickness 0.25)
		(keepout
			(tracks not_allowed)
			(vias allowed)
			(pads allowed)
			(copperpour not_allowed)
			(footprints allowed)
		)
		(placement
			(enabled no)
			(sheetname "")
		)
		(fill
			(thermal_gap 0.5)
			(thermal_bridge_width 0.5)
			(island_removal_mode 0)
		)
		(polygon
			(pts
				(arc
					(start 264.299954 -98.700082)
					(mid 259.299964 -103.700072)
					(end 254.299974 -98.700082)
				)
				(arc
					(start 254.299974 -98.700082)
					(mid 259.299964 -93.700092)
					(end 264.299954 -98.700082)
				)
			)
		)
	)
	(zone
		(layer "F.Cu")
		(hatch none 0.5)
		(connect_pads
			(clearance 0)
		)
		(min_thickness 0.25)
		(keepout
			(tracks allowed)
			(vias allowed)
			(pads allowed)
			(copperpour allowed)
			(footprints allowed)
		)
		(placement
			(enabled no)
			(sheetname "")
		)
		(fill
			(thermal_gap 0.5)
			(thermal_bridge_width 0.5)
			(island_removal_mode 0)
		)
		(polygon
			(pts
				(xy 323.065902 -99.187) (xy 324.158102 -99.187) (xy 324.615302 -99.6442) (xy 325.199502 -99.6442)
				(xy 325.326502 -99.5172) (xy 325.326502 -98.806) (xy 324.996302 -98.4758) (xy 323.116702 -98.4758)
				(xy 323.015102 -98.5774) (xy 323.015102 -99.1362)
			)
		)
	)
	(zone
		(layer "F.Cu")
		(hatch none 0.5)
		(connect_pads
			(clearance 0)
		)
		(min_thickness 0.25)
		(keepout
			(tracks allowed)
			(vias allowed)
			(pads allowed)
			(copperpour allowed)
			(footprints allowed)
		)
		(placement
			(enabled no)
			(sheetname "")
		)
		(fill
			(thermal_gap 0.5)
			(thermal_bridge_width 0.5)
			(island_removal_mode 0)
		)
		(polygon
			(pts
				(xy 341.561928 -350.781874) (xy 340.210648 -350.781874) (xy 340.210648 -349.501714) (xy 341.561928 -349.501714)
			)
		)
	)
	(zone
		(layer "F.Cu")
		(hatch none 0.5)
		(connect_pads
			(clearance 0)
		)
		(min_thickness 0.25)
		(keepout
			(tracks allowed)
			(vias allowed)
			(pads allowed)
			(copperpour allowed)
			(footprints not_allowed)
		)
		(placement
			(enabled no)
			(sheetname "")
		)
		(fill
			(thermal_gap 0.5)
			(thermal_bridge_width 0.5)
			(island_removal_mode 0)
		)
		(polygon
			(pts
				(arc
					(start 239.940592 -232.750106)
					(mid 251.898912 -243.750167)
					(end 263.857232 -232.750106)
				)
				(xy 263.960102 -232.750106) (xy 263.960102 -218.250008)
				(arc
					(start 263.857232 -218.250008)
					(mid 251.898912 -207.249947)
					(end 239.940592 -218.250008)
				)
				(xy 239.840008 -218.250008) (xy 239.840008 -232.750106)
			)
		)
	)
	(zone
		(layer "F.Cu")
		(hatch none 0.5)
		(connect_pads
			(clearance 0)
		)
		(min_thickness 0.25)
		(keepout
			(tracks allowed)
			(vias allowed)
			(pads allowed)
			(copperpour allowed)
			(footprints not_allowed)
		)
		(placement
			(enabled no)
			(sheetname "")
		)
		(fill
			(thermal_gap 0.5)
			(thermal_bridge_width 0.5)
			(island_removal_mode 0)
		)
		(polygon
			(pts
				(arc
					(start 357.89997 -72.69988)
					(mid 349.899986 -80.699864)
					(end 341.900002 -72.69988)
				)
				(arc
					(start 341.900002 -72.69988)
					(mid 349.899986 -64.699896)
					(end 357.89997 -72.69988)
				)
			)
		)
	)
	(zone
		(layer "F.Cu")
		(hatch none 0.5)
		(connect_pads
			(clearance 0)
		)
		(min_thickness 0.25)
		(keepout
			(tracks allowed)
			(vias allowed)
			(pads allowed)
			(copperpour allowed)
			(footprints allowed)
		)
		(placement
			(enabled no)
			(sheetname "")
		)
		(fill
			(thermal_gap 0.5)
			(thermal_bridge_width 0.5)
			(island_removal_mode 0)
		)
		(polygon
			(pts
				(xy 39.090092 -350.80575) (xy 37.738812 -350.80575) (xy 37.738812 -349.52559) (xy 39.090092 -349.52559)
			)
		)
	)
	(zone
		(layer "F.Cu")
		(hatch none 0.5)
		(connect_pads
			(clearance 0)
		)
		(min_thickness 0.25)
		(keepout
			(tracks allowed)
			(vias allowed)
			(pads allowed)
			(copperpour allowed)
			(footprints allowed)
		)
		(placement
			(enabled no)
			(sheetname "")
		)
		(fill
			(thermal_gap 0.5)
			(thermal_bridge_width 0.5)
			(island_removal_mode 0)
		)
		(polygon
			(pts
				(xy 296.956226 -356.928166) (xy 295.604946 -356.928166) (xy 295.604946 -355.648006) (xy 296.956226 -355.648006)
			)
		)
	)
	(zone
		(layer "F.Cu")
		(hatch none 0.5)
		(connect_pads
			(clearance 0)
		)
		(min_thickness 0.25)
		(keepout
			(tracks not_allowed)
			(vias allowed)
			(pads allowed)
			(copperpour not_allowed)
			(footprints allowed)
		)
		(placement
			(enabled no)
			(sheetname "")
		)
		(fill
			(thermal_gap 0.5)
			(thermal_bridge_width 0.5)
			(island_removal_mode 0)
		)
		(polygon
			(pts
				(xy 188.719968 -18.150078) (xy 188.719968 -13.150088) (xy 184.520078 -13.150088) (xy 184.520078 -18.150078)
			)
		)
	)
	(zone
		(layer "F.Cu")
		(hatch none 0.5)
		(connect_pads
			(clearance 0)
		)
		(min_thickness 0.25)
		(keepout
			(tracks allowed)
			(vias allowed)
			(pads allowed)
			(copperpour allowed)
			(footprints allowed)
		)
		(placement
			(enabled no)
			(sheetname "")
		)
		(fill
			(thermal_gap 0.5)
			(thermal_bridge_width 0.5)
			(island_removal_mode 0)
		)
		(polygon
			(pts
				(xy 231.241346 -77.514958) (xy 231.241346 -76.678028) (xy 231.241346 -76.187554) (xy 231.241092 -76.1873)
				(xy 229.793292 -76.1873) (xy 229.672642 -76.30795) (xy 229.672642 -76.617322) (xy 229.702868 -76.647548)
				(xy 229.702868 -77.492098) (xy 229.785926 -77.575156) (xy 231.181148 -77.575156)
			)
		)
	)
	(zone
		(layer "F.Cu")
		(hatch none 0.5)
		(connect_pads
			(clearance 0)
		)
		(min_thickness 0.25)
		(keepout
			(tracks allowed)
			(vias allowed)
			(pads allowed)
			(copperpour allowed)
			(footprints allowed)
		)
		(placement
			(enabled no)
			(sheetname "")
		)
		(fill
			(thermal_gap 0.5)
			(thermal_bridge_width 0.5)
			(island_removal_mode 0)
		)
		(polygon
			(pts
				(xy 340.653624 -90.73896) (xy 340.653624 -89.601802) (xy 340.595712 -89.54389) (xy 337.741006 -89.54389)
				(xy 337.694524 -89.590372) (xy 337.694524 -91.191588) (xy 337.694524 -91.35745) (xy 337.794854 -91.45778)
				(xy 340.421722 -91.45778) (xy 340.653624 -91.225878)
			)
		)
	)
	(zone
		(layer "F.Cu")
		(hatch none 0.5)
		(connect_pads
			(clearance 0)
		)
		(min_thickness 0.25)
		(keepout
			(tracks allowed)
			(vias allowed)
			(pads allowed)
			(copperpour allowed)
			(footprints not_allowed)
		)
		(placement
			(enabled no)
			(sheetname "")
		)
		(fill
			(thermal_gap 0.5)
			(thermal_bridge_width 0.5)
			(island_removal_mode 0)
		)
		(polygon
			(pts
				(arc
					(start 7.74065 -218.250008)
					(mid 19.698959 -207.249947)
					(end 31.657036 -218.250008)
				)
			)
		)
	)
	(zone
		(layer "F.Cu")
		(hatch none 0.5)
		(connect_pads
			(clearance 0)
		)
		(min_thickness 0.25)
		(keepout
			(tracks allowed)
			(vias allowed)
			(pads allowed)
			(copperpour allowed)
			(footprints allowed)
		)
		(placement
			(enabled no)
			(sheetname "")
		)
		(fill
			(thermal_gap 0.5)
			(thermal_bridge_width 0.5)
			(island_removal_mode 0)
		)
		(polygon
			(pts
				(xy 227.340922 -279.784556) (xy 230.261922 -279.784556) (xy 230.515922 -279.530556) (xy 230.515922 -276.482556)
				(xy 230.134922 -276.101556) (xy 227.213922 -276.101556) (xy 226.705922 -276.609556) (xy 226.705922 -279.149556)
			)
		)
	)
	(zone
		(layer "F.Cu")
		(hatch none 0.5)
		(connect_pads
			(clearance 0)
		)
		(min_thickness 0.25)
		(keepout
			(tracks allowed)
			(vias allowed)
			(pads allowed)
			(copperpour allowed)
			(footprints allowed)
		)
		(placement
			(enabled no)
			(sheetname "")
		)
		(fill
			(thermal_gap 0.5)
			(thermal_bridge_width 0.5)
			(island_removal_mode 0)
		)
		(polygon
			(pts
				(xy 211.209128 -32.954468) (xy 211.209128 -31.603188) (xy 212.489288 -31.603188) (xy 212.489288 -32.954468)
			)
		)
	)
	(zone
		(layer "F.Cu")
		(hatch none 0.5)
		(connect_pads
			(clearance 0)
		)
		(min_thickness 0.25)
		(keepout
			(tracks allowed)
			(vias allowed)
			(pads allowed)
			(copperpour allowed)
			(footprints allowed)
		)
		(placement
			(enabled no)
			(sheetname "")
		)
		(fill
			(thermal_gap 0.5)
			(thermal_bridge_width 0.5)
			(island_removal_mode 0)
		)
		(polygon
			(pts
				(xy 416.591496 -344.659458) (xy 415.240216 -344.659458) (xy 415.240216 -343.379298) (xy 416.591496 -343.379298)
			)
		)
	)
	(zone
		(layer "F.Cu")
		(hatch none 0.5)
		(connect_pads
			(clearance 0)
		)
		(min_thickness 0.25)
		(keepout
			(tracks not_allowed)
			(vias allowed)
			(pads allowed)
			(copperpour not_allowed)
			(footprints allowed)
		)
		(placement
			(enabled no)
			(sheetname "")
		)
		(fill
			(thermal_gap 0.5)
			(thermal_bridge_width 0.5)
			(island_removal_mode 0)
		)
		(polygon
			(pts
				(arc
					(start 257.350006 -320.900044)
					(mid 261.850124 -316.399926)
					(end 266.349988 -320.900044)
				)
				(arc
					(start 266.349988 -320.900044)
					(mid 261.850124 -325.399908)
					(end 257.350006 -320.900044)
				)
			)
		)
	)
	(zone
		(layer "F.Cu")
		(hatch none 0.5)
		(connect_pads
			(clearance 0)
		)
		(min_thickness 0.25)
		(keepout
			(tracks allowed)
			(vias allowed)
			(pads allowed)
			(copperpour allowed)
			(footprints allowed)
		)
		(placement
			(enabled no)
			(sheetname "")
		)
		(fill
			(thermal_gap 0.5)
			(thermal_bridge_width 0.5)
			(island_removal_mode 0)
		)
		(polygon
			(pts
				(xy 35.955224 -113.024666) (xy 35.955224 -111.673386) (xy 37.235384 -111.673386) (xy 37.235384 -113.024666)
			)
		)
	)
	(zone
		(layer "F.Cu")
		(hatch none 0.5)
		(connect_pads
			(clearance 0)
		)
		(min_thickness 0.25)
		(keepout
			(tracks allowed)
			(vias allowed)
			(pads allowed)
			(copperpour allowed)
			(footprints not_allowed)
		)
		(placement
			(enabled no)
			(sheetname "")
		)
		(fill
			(thermal_gap 0.5)
			(thermal_bridge_width 0.5)
			(island_removal_mode 0)
		)
		(polygon
			(pts
				(arc
					(start 123.840494 -218.250008)
					(mid 135.798814 -207.249947)
					(end 147.757134 -218.250008)
				)
			)
		)
	)
	(zone
		(layer "F.Cu")
		(hatch none 0.5)
		(connect_pads
			(clearance 0)
		)
		(min_thickness 0.25)
		(keepout
			(tracks allowed)
			(vias allowed)
			(pads allowed)
			(copperpour allowed)
			(footprints allowed)
		)
		(placement
			(enabled no)
			(sheetname "")
		)
		(fill
			(thermal_gap 0.5)
			(thermal_bridge_width 0.5)
			(island_removal_mode 0)
		)
		(polygon
			(pts
				(xy 427.636178 -134.609586) (xy 427.636178 -133.258306) (xy 428.916338 -133.258306) (xy 428.916338 -134.609586)
			)
		)
	)
	(zone
		(layer "F.Cu")
		(hatch none 0.5)
		(connect_pads
			(clearance 0)
		)
		(min_thickness 0.25)
		(keepout
			(tracks allowed)
			(vias allowed)
			(pads allowed)
			(copperpour allowed)
			(footprints not_allowed)
		)
		(placement
			(enabled no)
			(sheetname "")
		)
		(fill
			(thermal_gap 0.5)
			(thermal_bridge_width 0.5)
			(island_removal_mode 0)
		)
		(polygon
			(pts
				(arc
					(start 191.399922 -393.100052)
					(mid 199.399906 -385.100068)
					(end 207.39989 -393.100052)
				)
				(arc
					(start 207.39989 -393.100052)
					(mid 199.399906 -401.100036)
					(end 191.399922 -393.100052)
				)
			)
		)
	)
	(zone
		(layer "F.Cu")
		(hatch none 0.5)
		(connect_pads
			(clearance 0)
		)
		(min_thickness 0.25)
		(keepout
			(tracks allowed)
			(vias allowed)
			(pads allowed)
			(copperpour allowed)
			(footprints allowed)
		)
		(placement
			(enabled no)
			(sheetname "")
		)
		(fill
			(thermal_gap 0.5)
			(thermal_bridge_width 0.5)
			(island_removal_mode 0)
		)
		(polygon
			(pts
				(xy 9.477756 -35.458146) (xy 10.788142 -35.458146) (xy 11.001502 -35.244786) (xy 11.001502 -27.397456)
				(xy 10.833862 -27.229816) (xy 9.325356 -27.229816) (xy 8.85317 -27.702002) (xy 8.85317 -34.83356)
			)
		)
	)
	(zone
		(layer "F.Cu")
		(hatch none 0.5)
		(connect_pads
			(clearance 0)
		)
		(min_thickness 0.25)
		(keepout
			(tracks not_allowed)
			(vias allowed)
			(pads allowed)
			(copperpour not_allowed)
			(footprints allowed)
		)
		(placement
			(enabled no)
			(sheetname "")
		)
		(fill
			(thermal_gap 0.5)
			(thermal_bridge_width 0.5)
			(island_removal_mode 0)
		)
		(polygon
			(pts
				(xy 368.920014 -18.150078) (xy 368.920014 -13.150088) (xy 364.720124 -13.150088) (xy 364.720124 -18.150078)
			)
		)
	)
	(zone
		(layer "F.Cu")
		(hatch none 0.5)
		(connect_pads
			(clearance 0)
		)
		(min_thickness 0.25)
		(keepout
			(tracks allowed)
			(vias allowed)
			(pads allowed)
			(copperpour allowed)
			(footprints allowed)
		)
		(placement
			(enabled no)
			(sheetname "")
		)
		(fill
			(thermal_gap 0.5)
			(thermal_bridge_width 0.5)
			(island_removal_mode 0)
		)
		(polygon
			(pts
				(xy 111.638334 -88.306402) (xy 112.694212 -88.306402) (xy 112.949482 -88.051132) (xy 112.949482 -87.52459)
				(xy 113.56594 -86.908132) (xy 113.56594 -85.531452) (xy 112.949482 -84.914994) (xy 112.949482 -83.560158)
				(xy 112.89157 -83.502246) (xy 111.742474 -83.502246) (xy 111.580168 -83.664552) (xy 111.580168 -88.248236)
			)
		)
	)
	(zone
		(layer "F.Cu")
		(hatch none 0.5)
		(connect_pads
			(clearance 0)
		)
		(min_thickness 0.25)
		(keepout
			(tracks allowed)
			(vias allowed)
			(pads allowed)
			(copperpour allowed)
			(footprints allowed)
		)
		(placement
			(enabled no)
			(sheetname "")
		)
		(fill
			(thermal_gap 0.5)
			(thermal_bridge_width 0.5)
			(island_removal_mode 0)
		)
		(polygon
			(pts
				(xy 314.178188 -149.126194) (xy 314.178188 -147.774914) (xy 315.458348 -147.774914) (xy 315.458348 -149.126194)
			)
		)
	)
	(zone
		(layer "F.Cu")
		(hatch none 0.5)
		(connect_pads
			(clearance 0)
		)
		(min_thickness 0.25)
		(keepout
			(tracks allowed)
			(vias allowed)
			(pads allowed)
			(copperpour allowed)
			(footprints allowed)
		)
		(placement
			(enabled no)
			(sheetname "")
		)
		(fill
			(thermal_gap 0.5)
			(thermal_bridge_width 0.5)
			(island_removal_mode 0)
		)
		(polygon
			(pts
				(xy 335.915 -88.9) (xy 335.915 -84.6328) (xy 340.2076 -84.6328) (xy 340.2076 -88.9)
			)
		)
	)
	(zone
		(layer "F.Cu")
		(hatch none 0.5)
		(connect_pads
			(clearance 0)
		)
		(min_thickness 0.25)
		(keepout
			(tracks allowed)
			(vias allowed)
			(pads allowed)
			(copperpour allowed)
			(footprints not_allowed)
		)
		(placement
			(enabled no)
			(sheetname "")
		)
		(fill
			(thermal_gap 0.5)
			(thermal_bridge_width 0.5)
			(island_removal_mode 0)
		)
		(polygon
			(pts
				(xy 330.820014 -18.150078) (xy 330.820014 -13.150088) (xy 326.620124 -13.150088) (xy 326.620124 -18.150078)
			)
		)
	)
	(zone
		(layer "F.Cu")
		(hatch none 0.5)
		(connect_pads
			(clearance 0)
		)
		(min_thickness 0.25)
		(keepout
			(tracks allowed)
			(vias allowed)
			(pads allowed)
			(copperpour allowed)
			(footprints allowed)
		)
		(placement
			(enabled no)
			(sheetname "")
		)
		(fill
			(thermal_gap 0.5)
			(thermal_bridge_width 0.5)
			(island_removal_mode 0)
		)
		(polygon
			(pts
				(xy 51.787298 -98.563176) (xy 49.976786 -98.563176) (xy 49.930304 -98.609658) (xy 49.930304 -113.35258)
				(xy 50.075592 -113.497868) (xy 51.827684 -113.497868) (xy 51.903122 -113.42243) (xy 51.903122 -98.679)
			)
		)
	)
	(zone
		(layer "F.Cu")
		(hatch none 0.5)
		(connect_pads
			(clearance 0)
		)
		(min_thickness 0.25)
		(keepout
			(tracks allowed)
			(vias allowed)
			(pads allowed)
			(copperpour allowed)
			(footprints not_allowed)
		)
		(placement
			(enabled no)
			(sheetname "")
		)
		(fill
			(thermal_gap 0.5)
			(thermal_bridge_width 0.5)
			(island_removal_mode 0)
		)
		(polygon
			(pts
				(arc
					(start 453.600058 -407.599896)
					(mid 461.600042 -399.599912)
					(end 469.600026 -407.599896)
				)
				(arc
					(start 469.600026 -407.599896)
					(mid 461.600042 -415.59988)
					(end 453.600058 -407.599896)
				)
			)
		)
	)
	(zone
		(layer "F.Cu")
		(hatch none 0.5)
		(connect_pads
			(clearance 0)
		)
		(min_thickness 0.25)
		(keepout
			(tracks allowed)
			(vias allowed)
			(pads allowed)
			(copperpour allowed)
			(footprints allowed)
		)
		(placement
			(enabled no)
			(sheetname "")
		)
		(fill
			(thermal_gap 0.5)
			(thermal_bridge_width 0.5)
			(island_removal_mode 0)
		)
		(polygon
			(pts
				(xy 35.955224 -123.928124) (xy 35.955224 -122.576844) (xy 37.235384 -122.576844) (xy 37.235384 -123.928124)
			)
		)
	)
	(zone
		(layer "F.Cu")
		(hatch none 0.5)
		(connect_pads
			(clearance 0)
		)
		(min_thickness 0.25)
		(keepout
			(tracks allowed)
			(vias allowed)
			(pads allowed)
			(copperpour allowed)
			(footprints allowed)
		)
		(placement
			(enabled no)
			(sheetname "")
		)
		(fill
			(thermal_gap 0.5)
			(thermal_bridge_width 0.5)
			(island_removal_mode 0)
		)
		(polygon
			(pts
				(xy 400.087338 -98.563176) (xy 398.276826 -98.563176) (xy 398.230344 -98.609658) (xy 398.230344 -113.35258)
				(xy 398.375632 -113.497868) (xy 400.127724 -113.497868) (xy 400.203162 -113.42243) (xy 400.203162 -98.679)
			)
		)
	)
	(zone
		(layer "F.Cu")
		(hatch none 0.5)
		(connect_pads
			(clearance 0)
		)
		(min_thickness 0.25)
		(keepout
			(tracks allowed)
			(vias allowed)
			(pads allowed)
			(copperpour allowed)
			(footprints allowed)
		)
		(placement
			(enabled no)
			(sheetname "")
		)
		(fill
			(thermal_gap 0.5)
			(thermal_bridge_width 0.5)
			(island_removal_mode 0)
		)
		(polygon
			(pts
				(xy 241.847878 -307.485288) (xy 242.536472 -307.485288) (xy 242.62207 -307.39969) (xy 242.62207 -306.987448)
				(xy 242.431062 -306.79644) (xy 241.802666 -306.79644) (xy 241.737134 -306.861972) (xy 241.737134 -307.374544)
			)
		)
	)
	(zone
		(layer "F.Cu")
		(hatch none 0.5)
		(connect_pads
			(clearance 0)
		)
		(min_thickness 0.25)
		(keepout
			(tracks allowed)
			(vias allowed)
			(pads allowed)
			(copperpour allowed)
			(footprints allowed)
		)
		(placement
			(enabled no)
			(sheetname "")
		)
		(fill
			(thermal_gap 0.5)
			(thermal_bridge_width 0.5)
			(island_removal_mode 0)
		)
		(polygon
			(pts
				(xy 341.561928 -356.928166) (xy 340.210648 -356.928166) (xy 340.210648 -355.648006) (xy 341.561928 -355.648006)
			)
		)
	)
	(zone
		(layer "F.Cu")
		(hatch none 0.5)
		(connect_pads
			(clearance 0)
		)
		(min_thickness 0.25)
		(keepout
			(tracks allowed)
			(vias allowed)
			(pads allowed)
			(copperpour allowed)
			(footprints not_allowed)
		)
		(placement
			(enabled no)
			(sheetname "")
		)
		(fill
			(thermal_gap 0.5)
			(thermal_bridge_width 0.5)
			(island_removal_mode 0)
		)
		(polygon
			(pts
				(xy 267.165074 -40.120062) (xy 275.164804 -40.120062) (xy 275.165058 -13.850112) (xy 267.165074 -13.850112)
			)
		)
	)
	(zone
		(layer "F.Cu")
		(hatch none 0.5)
		(connect_pads
			(clearance 0)
		)
		(min_thickness 0.25)
		(keepout
			(tracks allowed)
			(vias allowed)
			(pads allowed)
			(copperpour allowed)
			(footprints allowed)
		)
		(placement
			(enabled no)
			(sheetname "")
		)
		(fill
			(thermal_gap 0.5)
			(thermal_bridge_width 0.5)
			(island_removal_mode 0)
		)
		(polygon
			(pts
				(xy 131.619752 -344.659458) (xy 130.268472 -344.659458) (xy 130.268472 -343.379298) (xy 131.619752 -343.379298)
			)
		)
	)
	(zone
		(layer "F.Cu")
		(hatch none 0.5)
		(connect_pads
			(clearance 0)
		)
		(min_thickness 0.25)
		(keepout
			(tracks allowed)
			(vias allowed)
			(pads allowed)
			(copperpour allowed)
			(footprints allowed)
		)
		(placement
			(enabled no)
			(sheetname "")
		)
		(fill
			(thermal_gap 0.5)
			(thermal_bridge_width 0.5)
			(island_removal_mode 0)
		)
		(polygon
			(pts
				(xy 267.71092 -35.427666) (xy 269.051786 -35.427666) (xy 269.249906 -35.229546) (xy 269.249906 -27.641296)
				(xy 268.975586 -27.366976) (xy 267.61948 -27.366976) (xy 267.23848 -27.747976) (xy 267.23848 -34.955226)
			)
		)
	)
	(zone
		(layer "F.Cu")
		(hatch none 0.5)
		(connect_pads
			(clearance 0)
		)
		(min_thickness 0.25)
		(keepout
			(tracks allowed)
			(vias allowed)
			(pads allowed)
			(copperpour allowed)
			(footprints allowed)
		)
		(placement
			(enabled no)
			(sheetname "")
		)
		(fill
			(thermal_gap 0.5)
			(thermal_bridge_width 0.5)
			(island_removal_mode 0)
		)
		(polygon
			(pts
				(xy 301.309024 -29.354526) (xy 301.309024 -28.003246) (xy 302.589184 -28.003246) (xy 302.589184 -29.354526)
			)
		)
	)
	(zone
		(layer "F.Cu")
		(hatch none 0.5)
		(connect_pads
			(clearance 0)
		)
		(min_thickness 0.25)
		(keepout
			(tracks allowed)
			(vias allowed)
			(pads allowed)
			(copperpour allowed)
			(footprints allowed)
		)
		(placement
			(enabled no)
			(sheetname "")
		)
		(fill
			(thermal_gap 0.5)
			(thermal_bridge_width 0.5)
			(island_removal_mode 0)
		)
		(polygon
			(pts
				(xy 390.945624 -344.659458) (xy 389.594344 -344.659458) (xy 389.594344 -343.379298) (xy 390.945624 -343.379298)
			)
		)
	)
	(zone
		(layer "F.Cu")
		(hatch none 0.5)
		(connect_pads
			(clearance 0)
		)
		(min_thickness 0.25)
		(keepout
			(tracks allowed)
			(vias allowed)
			(pads allowed)
			(copperpour allowed)
			(footprints allowed)
		)
		(placement
			(enabled no)
			(sheetname "")
		)
		(fill
			(thermal_gap 0.5)
			(thermal_bridge_width 0.5)
			(island_removal_mode 0)
		)
		(polygon
			(pts
				(xy 270.797274 -122.13463) (xy 270.797274 -120.78335) (xy 272.077434 -120.78335) (xy 272.077434 -122.13463)
			)
		)
	)
	(zone
		(layer "F.Cu")
		(hatch none 0.5)
		(connect_pads
			(clearance 0)
		)
		(min_thickness 0.25)
		(keepout
			(tracks allowed)
			(vias allowed)
			(pads allowed)
			(copperpour allowed)
			(footprints allowed)
		)
		(placement
			(enabled no)
			(sheetname "")
		)
		(fill
			(thermal_gap 0.5)
			(thermal_bridge_width 0.5)
			(island_removal_mode 0)
		)
		(polygon
			(pts
				(xy 103.28402 -383.841752) (xy 102.44709 -383.841752) (xy 101.956616 -383.841752) (xy 101.956362 -383.842006)
				(xy 101.956362 -385.289806) (xy 102.077012 -385.410456) (xy 102.386384 -385.410456) (xy 102.41661 -385.38023)
				(xy 103.26116 -385.38023) (xy 103.344218 -385.297172) (xy 103.344218 -383.90195)
			)
		)
	)
	(zone
		(layer "F.Cu")
		(hatch none 0.5)
		(connect_pads
			(clearance 0)
		)
		(min_thickness 0.25)
		(keepout
			(tracks allowed)
			(vias allowed)
			(pads allowed)
			(copperpour allowed)
			(footprints allowed)
		)
		(placement
			(enabled no)
			(sheetname "")
		)
		(fill
			(thermal_gap 0.5)
			(thermal_bridge_width 0.5)
			(island_removal_mode 0)
		)
		(polygon
			(pts
				(xy 331.191362 -52.800758) (xy 331.191362 -55.718456) (xy 331.400912 -55.928006) (xy 332.013814 -55.928006)
				(xy 332.013814 -52.870608) (xy 331.943964 -52.800758)
			)
		)
	)
	(zone
		(layer "F.Cu")
		(hatch none 0.5)
		(connect_pads
			(clearance 0)
		)
		(min_thickness 0.25)
		(keepout
			(tracks not_allowed)
			(vias allowed)
			(pads allowed)
			(copperpour not_allowed)
			(footprints allowed)
		)
		(placement
			(enabled no)
			(sheetname "")
		)
		(fill
			(thermal_gap 0.5)
			(thermal_bridge_width 0.5)
			(island_removal_mode 0)
		)
		(polygon
			(pts
				(arc
					(start 460.000096 -13.599922)
					(mid 461.600042 -11.999976)
					(end 463.199988 -13.599922)
				)
				(arc
					(start 463.199988 -15.200122)
					(mid 461.600042 -16.800068)
					(end 460.000096 -15.200122)
				)
			)
		)
	)
	(zone
		(layer "F.Cu")
		(hatch none 0.5)
		(connect_pads
			(clearance 0)
		)
		(min_thickness 0.25)
		(keepout
			(tracks allowed)
			(vias allowed)
			(pads allowed)
			(copperpour allowed)
			(footprints allowed)
		)
		(placement
			(enabled no)
			(sheetname "")
		)
		(fill
			(thermal_gap 0.5)
			(thermal_bridge_width 0.5)
			(island_removal_mode 0)
		)
		(polygon
			(pts
				(xy 340.514178 -284.67558) (xy 341.4268 -284.67558) (xy 341.822786 -284.279594) (xy 341.822786 -282.410408)
				(xy 340.294214 -282.410408) (xy 340.23935 -282.465272) (xy 340.23935 -284.400752)
			)
		)
	)
	(zone
		(layer "F.Cu")
		(hatch none 0.5)
		(connect_pads
			(clearance 0)
		)
		(min_thickness 0.25)
		(keepout
			(tracks allowed)
			(vias allowed)
			(pads allowed)
			(copperpour allowed)
			(footprints allowed)
		)
		(placement
			(enabled no)
			(sheetname "")
		)
		(fill
			(thermal_gap 0.5)
			(thermal_bridge_width 0.5)
			(island_removal_mode 0)
		)
		(polygon
			(pts
				(xy 71.75119 -31.160974) (xy 71.75119 -29.809694) (xy 73.03135 -29.809694) (xy 73.03135 -31.160974)
			)
		)
	)
	(zone
		(layer "F.Cu")
		(hatch none 0.5)
		(connect_pads
			(clearance 0)
		)
		(min_thickness 0.25)
		(keepout
			(tracks not_allowed)
			(vias allowed)
			(pads allowed)
			(copperpour not_allowed)
			(footprints allowed)
		)
		(placement
			(enabled no)
			(sheetname "")
		)
		(fill
			(thermal_gap 0.5)
			(thermal_bridge_width 0.5)
			(island_removal_mode 0)
		)
		(polygon
			(pts
				(xy 241.720116 -23.219918) (xy 241.720116 -18.219928) (xy 237.519972 -18.219928) (xy 237.519972 -23.219918)
			)
		)
	)
	(zone
		(layer "F.Cu")
		(hatch none 0.5)
		(connect_pads
			(clearance 0)
		)
		(min_thickness 0.25)
		(keepout
			(tracks allowed)
			(vias allowed)
			(pads allowed)
			(copperpour allowed)
			(footprints allowed)
		)
		(placement
			(enabled no)
			(sheetname "")
		)
		(fill
			(thermal_gap 0.5)
			(thermal_bridge_width 0.5)
			(island_removal_mode 0)
		)
		(polygon
			(pts
				(xy 430.278286 -145.525998) (xy 430.278286 -144.174718) (xy 431.558446 -144.174718) (xy 431.558446 -145.525998)
			)
		)
	)
	(zone
		(layer "F.Cu")
		(hatch none 0.5)
		(connect_pads
			(clearance 0)
		)
		(min_thickness 0.25)
		(keepout
			(tracks allowed)
			(vias allowed)
			(pads allowed)
			(copperpour allowed)
			(footprints allowed)
		)
		(placement
			(enabled no)
			(sheetname "")
		)
		(fill
			(thermal_gap 0.5)
			(thermal_bridge_width 0.5)
			(island_removal_mode 0)
		)
		(polygon
			(pts
				(xy 72.991472 -52.800758) (xy 72.991472 -55.718456) (xy 73.201022 -55.928006) (xy 73.813924 -55.928006)
				(xy 73.813924 -52.870608) (xy 73.744074 -52.800758)
			)
		)
	)
	(zone
		(layer "F.Cu")
		(hatch none 0.5)
		(connect_pads
			(clearance 0)
		)
		(min_thickness 0.25)
		(keepout
			(tracks not_allowed)
			(vias allowed)
			(pads allowed)
			(copperpour not_allowed)
			(footprints allowed)
		)
		(placement
			(enabled no)
			(sheetname "")
		)
		(fill
			(thermal_gap 0.5)
			(thermal_bridge_width 0.5)
			(island_removal_mode 0)
		)
		(polygon
			(pts
				(arc
					(start 13.800074 -194.360038)
					(mid 15.80007 -192.360042)
					(end 17.800066 -194.360038)
				)
				(arc
					(start 17.800066 -194.360038)
					(mid 15.80007 -196.360034)
					(end 13.800074 -194.360038)
				)
			)
		)
	)
	(zone
		(layer "F.Cu")
		(hatch none 0.5)
		(connect_pads
			(clearance 0)
		)
		(min_thickness 0.25)
		(keepout
			(tracks allowed)
			(vias allowed)
			(pads allowed)
			(copperpour allowed)
			(footprints allowed)
		)
		(placement
			(enabled no)
			(sheetname "")
		)
		(fill
			(thermal_gap 0.5)
			(thermal_bridge_width 0.5)
			(island_removal_mode 0)
		)
		(polygon
			(pts
				(xy 104.689656 -384.690366) (xy 104.689656 -385.527296) (xy 104.689656 -386.01777) (xy 104.68991 -386.018024)
				(xy 106.13771 -386.018024) (xy 106.25836 -385.897374) (xy 106.25836 -385.588002) (xy 106.228134 -385.557776)
				(xy 106.228134 -384.713226) (xy 106.145076 -384.630168) (xy 104.749854 -384.630168)
			)
		)
	)
	(zone
		(layer "F.Cu")
		(hatch none 0.5)
		(connect_pads
			(clearance 0)
		)
		(min_thickness 0.25)
		(keepout
			(tracks allowed)
			(vias allowed)
			(pads allowed)
			(copperpour allowed)
			(footprints allowed)
		)
		(placement
			(enabled no)
			(sheetname "")
		)
		(fill
			(thermal_gap 0.5)
			(thermal_bridge_width 0.5)
			(island_removal_mode 0)
		)
		(polygon
			(pts
				(xy 339.067902 -113.665) (xy 339.067902 -109.855) (xy 340.591902 -109.855) (xy 340.591902 -113.665)
			)
		)
	)
	(zone
		(layer "F.Cu")
		(hatch none 0.5)
		(connect_pads
			(clearance 0)
		)
		(min_thickness 0.25)
		(keepout
			(tracks allowed)
			(vias allowed)
			(pads allowed)
			(copperpour allowed)
			(footprints allowed)
		)
		(placement
			(enabled no)
			(sheetname "")
		)
		(fill
			(thermal_gap 0.5)
			(thermal_bridge_width 0.5)
			(island_removal_mode 0)
		)
		(polygon
			(pts
				(xy 65.585086 -356.952042) (xy 64.233806 -356.952042) (xy 64.233806 -355.671882) (xy 65.585086 -355.671882)
			)
		)
	)
	(zone
		(layer "F.Cu")
		(hatch none 0.5)
		(connect_pads
			(clearance 0)
		)
		(min_thickness 0.25)
		(keepout
			(tracks allowed)
			(vias allowed)
			(pads allowed)
			(copperpour allowed)
			(footprints allowed)
		)
		(placement
			(enabled no)
			(sheetname "")
		)
		(fill
			(thermal_gap 0.5)
			(thermal_bridge_width 0.5)
			(island_removal_mode 0)
		)
		(polygon
			(pts
				(xy 87.347806 -356.952042) (xy 85.996526 -356.952042) (xy 85.996526 -355.671882) (xy 87.347806 -355.671882)
			)
		)
	)
	(zone
		(layer "F.Cu")
		(hatch none 0.5)
		(connect_pads
			(clearance 0)
		)
		(min_thickness 0.25)
		(keepout
			(tracks allowed)
			(vias allowed)
			(pads allowed)
			(copperpour allowed)
			(footprints allowed)
		)
		(placement
			(enabled no)
			(sheetname "")
		)
		(fill
			(thermal_gap 0.5)
			(thermal_bridge_width 0.5)
			(island_removal_mode 0)
		)
		(polygon
			(pts
				(xy 84.238846 -356.952042) (xy 82.887566 -356.952042) (xy 82.887566 -355.671882) (xy 84.238846 -355.671882)
			)
		)
	)
	(zone
		(layer "F.Cu")
		(hatch none 0.5)
		(connect_pads
			(clearance 0)
		)
		(min_thickness 0.25)
		(keepout
			(tracks allowed)
			(vias allowed)
			(pads allowed)
			(copperpour allowed)
			(footprints allowed)
		)
		(placement
			(enabled no)
			(sheetname "")
		)
		(fill
			(thermal_gap 0.5)
			(thermal_bridge_width 0.5)
			(island_removal_mode 0)
		)
		(polygon
			(pts
				(xy 272.109946 -356.952042) (xy 270.758666 -356.952042) (xy 270.758666 -355.671882) (xy 272.109946 -355.671882)
			)
		)
	)
	(zone
		(layer "F.Cu")
		(hatch none 0.5)
		(connect_pads
			(clearance 0)
		)
		(min_thickness 0.25)
		(keepout
			(tracks allowed)
			(vias allowed)
			(pads allowed)
			(copperpour allowed)
			(footprints allowed)
		)
		(placement
			(enabled no)
			(sheetname "")
		)
		(fill
			(thermal_gap 0.5)
			(thermal_bridge_width 0.5)
			(island_removal_mode 0)
		)
		(polygon
			(pts
				(xy 188.60135 -115.203224) (xy 190.071248 -115.203224) (xy 190.155068 -115.119404) (xy 190.155068 -114.394996)
				(xy 189.918848 -114.158776) (xy 188.632846 -114.158776) (xy 188.412374 -114.379248) (xy 188.412374 -115.014248)
			)
		)
	)
	(zone
		(layer "F.Cu")
		(hatch none 0.5)
		(connect_pads
			(clearance 0)
		)
		(min_thickness 0.25)
		(keepout
			(tracks allowed)
			(vias allowed)
			(pads allowed)
			(copperpour allowed)
			(footprints allowed)
		)
		(placement
			(enabled no)
			(sheetname "")
		)
		(fill
			(thermal_gap 0.5)
			(thermal_bridge_width 0.5)
			(island_removal_mode 0)
		)
		(polygon
			(pts
				(xy 360.270806 -287.02) (xy 365.223806 -287.02) (xy 365.477806 -286.766) (xy 365.477806 -286.004)
				(xy 365.223806 -285.75) (xy 364.080806 -285.75) (xy 363.826806 -285.496) (xy 363.826806 -284.861)
				(xy 364.080806 -284.607) (xy 364.588806 -284.607) (xy 364.715806 -284.48) (xy 364.715806 -282.829)
				(xy 364.461806 -282.575) (xy 360.524806 -282.575) (xy 360.270806 -282.829)
			)
		)
	)
	(zone
		(layer "F.Cu")
		(hatch none 0.5)
		(connect_pads
			(clearance 0)
		)
		(min_thickness 0.25)
		(keepout
			(tracks allowed)
			(vias allowed)
			(pads allowed)
			(copperpour allowed)
			(footprints allowed)
		)
		(placement
			(enabled no)
			(sheetname "")
		)
		(fill
			(thermal_gap 0.5)
			(thermal_bridge_width 0.5)
			(island_removal_mode 0)
		)
		(polygon
			(pts
				(xy 327.308972 -29.354526) (xy 327.308972 -28.003246) (xy 328.589132 -28.003246) (xy 328.589132 -29.354526)
			)
		)
	)
	(zone
		(layer "F.Cu")
		(hatch none 0.5)
		(connect_pads
			(clearance 0)
		)
		(min_thickness 0.25)
		(keepout
			(tracks allowed)
			(vias allowed)
			(pads allowed)
			(copperpour allowed)
			(footprints allowed)
		)
		(placement
			(enabled no)
			(sheetname "")
		)
		(fill
			(thermal_gap 0.5)
			(thermal_bridge_width 0.5)
			(island_removal_mode 0)
		)
		(polygon
			(pts
				(xy 93.565726 -350.781874) (xy 92.214446 -350.781874) (xy 92.214446 -349.501714) (xy 93.565726 -349.501714)
			)
		)
	)
	(zone
		(layer "F.Cu")
		(hatch none 0.5)
		(connect_pads
			(clearance 0)
		)
		(min_thickness 0.25)
		(keepout
			(tracks allowed)
			(vias allowed)
			(pads allowed)
			(copperpour allowed)
			(footprints not_allowed)
		)
		(placement
			(enabled no)
			(sheetname "")
		)
		(fill
			(thermal_gap 0.5)
			(thermal_bridge_width 0.5)
			(island_removal_mode 0)
		)
		(polygon
			(pts
				(xy 14.600428 -310.330088) (xy 19.15033 -310.330088)
				(arc
					(start 19.15033 -305.28006)
					(mid 17.293134 -304.207649)
					(end 16.256762 -302.330104)
				)
				(xy 0.99695 -302.330104)
				(arc
					(start 0.99695 -308.28996)
					(mid 4.086426 -307.453105)
					(end 6.800342 -309.150004)
				)
				(xy 14.600428 -309.150004)
			)
		)
	)
	(zone
		(layer "F.Cu")
		(hatch none 0.5)
		(connect_pads
			(clearance 0)
		)
		(min_thickness 0.25)
		(keepout
			(tracks not_allowed)
			(vias allowed)
			(pads allowed)
			(copperpour not_allowed)
			(footprints allowed)
		)
		(placement
			(enabled no)
			(sheetname "")
		)
		(fill
			(thermal_gap 0.5)
			(thermal_bridge_width 0.5)
			(island_removal_mode 0)
		)
		(polygon
			(pts
				(arc
					(start 6.75005 -311.410096)
					(mid 3.50012 -314.660026)
					(end 0.249936 -311.410096)
				)
				(arc
					(start 0.249936 -311.410096)
					(mid 3.50012 -308.159912)
					(end 6.75005 -311.410096)
				)
			)
		)
	)
	(zone
		(layer "F.Cu")
		(hatch none 0.5)
		(connect_pads
			(clearance 0)
		)
		(min_thickness 0.25)
		(keepout
			(tracks allowed)
			(vias allowed)
			(pads allowed)
			(copperpour allowed)
			(footprints allowed)
		)
		(placement
			(enabled no)
			(sheetname "")
		)
		(fill
			(thermal_gap 0.5)
			(thermal_bridge_width 0.5)
			(island_removal_mode 0)
		)
		(polygon
			(pts
				(xy 290.738306 -344.659458) (xy 289.387026 -344.659458) (xy 289.387026 -343.379298) (xy 290.738306 -343.379298)
			)
		)
	)
	(zone
		(layer "F.Cu")
		(hatch none 0.5)
		(connect_pads
			(clearance 0)
		)
		(min_thickness 0.25)
		(keepout
			(tracks allowed)
			(vias allowed)
			(pads allowed)
			(copperpour allowed)
			(footprints allowed)
		)
		(placement
			(enabled no)
			(sheetname "")
		)
		(fill
			(thermal_gap 0.5)
			(thermal_bridge_width 0.5)
			(island_removal_mode 0)
		)
		(polygon
			(pts
				(xy 232.570274 -84.723732) (xy 232.570274 -83.886802) (xy 232.570274 -83.396328) (xy 232.57002 -83.396074)
				(xy 231.12222 -83.396074) (xy 231.00157 -83.516724) (xy 231.00157 -83.826096) (xy 231.031796 -83.856322)
				(xy 231.031796 -84.700872) (xy 231.114854 -84.78393) (xy 232.510076 -84.78393)
			)
		)
	)
	(zone
		(layer "F.Cu")
		(hatch none 0.5)
		(connect_pads
			(clearance 0)
		)
		(min_thickness 0.25)
		(keepout
			(tracks allowed)
			(vias allowed)
			(pads allowed)
			(copperpour allowed)
			(footprints allowed)
		)
		(placement
			(enabled no)
			(sheetname "")
		)
		(fill
			(thermal_gap 0.5)
			(thermal_bridge_width 0.5)
			(island_removal_mode 0)
		)
		(polygon
			(pts
				(xy 195.435982 -143.71955) (xy 195.435982 -142.36827) (xy 196.716142 -142.36827) (xy 196.716142 -143.71955)
			)
		)
	)
	(zone
		(layer "F.Cu")
		(hatch none 0.5)
		(connect_pads
			(clearance 0)
		)
		(min_thickness 0.25)
		(keepout
			(tracks allowed)
			(vias allowed)
			(pads allowed)
			(copperpour allowed)
			(footprints allowed)
		)
		(placement
			(enabled no)
			(sheetname "")
		)
		(fill
			(thermal_gap 0.5)
			(thermal_bridge_width 0.5)
			(island_removal_mode 0)
		)
		(polygon
			(pts
				(xy 61.316616 -35.458146) (xy 62.825122 -35.458146) (xy 63.038482 -35.244786) (xy 63.038482 -27.427682)
				(xy 62.642242 -27.031442) (xy 61.408056 -27.031442) (xy 60.844176 -27.595322) (xy 60.844176 -34.985706)
			)
		)
	)
	(zone
		(layer "F.Cu")
		(hatch none 0.5)
		(connect_pads
			(clearance 0)
		)
		(min_thickness 0.25)
		(keepout
			(tracks allowed)
			(vias allowed)
			(pads allowed)
			(copperpour allowed)
			(footprints allowed)
		)
		(placement
			(enabled no)
			(sheetname "")
		)
		(fill
			(thermal_gap 0.5)
			(thermal_bridge_width 0.5)
			(island_removal_mode 0)
		)
		(polygon
			(pts
				(xy 106.86796 -113.665) (xy 106.86796 -109.855) (xy 108.39196 -109.855) (xy 108.39196 -113.665)
			)
		)
	)
	(zone
		(layer "F.Cu")
		(hatch none 0.5)
		(connect_pads
			(clearance 0)
		)
		(min_thickness 0.25)
		(keepout
			(tracks allowed)
			(vias allowed)
			(pads allowed)
			(copperpour allowed)
			(footprints allowed)
		)
		(placement
			(enabled no)
			(sheetname "")
		)
		(fill
			(thermal_gap 0.5)
			(thermal_bridge_width 0.5)
			(island_removal_mode 0)
		)
		(polygon
			(pts
				(xy 103.15702 -390.019032) (xy 104.577388 -390.019032) (xy 104.665272 -389.931148) (xy 104.665272 -388.805928)
				(xy 104.497632 -388.638288) (xy 103.029258 -388.638288) (xy 103.026972 -388.640828) (xy 101.52761 -388.640828)
				(xy 101.427026 -388.741412) (xy 101.427026 -389.759444) (xy 101.686614 -390.019032)
			)
		)
	)
	(zone
		(layer "F.Cu")
		(hatch none 0.5)
		(connect_pads
			(clearance 0)
		)
		(min_thickness 0.25)
		(keepout
			(tracks allowed)
			(vias allowed)
			(pads allowed)
			(copperpour allowed)
			(footprints allowed)
		)
		(placement
			(enabled no)
			(sheetname "")
		)
		(fill
			(thermal_gap 0.5)
			(thermal_bridge_width 0.5)
			(island_removal_mode 0)
		)
		(polygon
			(pts
				(xy 92.661486 -27.55011) (xy 95.061532 -27.55011) (xy 95.152972 -27.45867) (xy 95.152972 -26.33853)
				(xy 95.092012 -26.27757) (xy 92.646246 -26.27757) (xy 92.524326 -26.39949) (xy 92.524326 -27.41295)
			)
		)
	)
	(zone
		(layer "F.Cu")
		(hatch none 0.5)
		(connect_pads
			(clearance 0)
		)
		(min_thickness 0.25)
		(keepout
			(tracks not_allowed)
			(vias allowed)
			(pads allowed)
			(copperpour not_allowed)
			(footprints allowed)
		)
		(placement
			(enabled no)
			(sheetname "")
		)
		(fill
			(thermal_gap 0.5)
			(thermal_bridge_width 0.5)
			(island_removal_mode 0)
		)
		(polygon
			(pts
				(arc
					(start 344.899996 -72.69988)
					(mid 349.899986 -67.69989)
					(end 354.899976 -72.69988)
				)
				(arc
					(start 354.899976 -72.69988)
					(mid 349.899986 -77.69987)
					(end 344.899996 -72.69988)
				)
			)
		)
	)
	(zone
		(layer "F.Cu")
		(hatch none 0.5)
		(connect_pads
			(clearance 0)
		)
		(min_thickness 0.25)
		(keepout
			(tracks allowed)
			(vias allowed)
			(pads allowed)
			(copperpour allowed)
			(footprints allowed)
		)
		(placement
			(enabled no)
			(sheetname "")
		)
		(fill
			(thermal_gap 0.5)
			(thermal_bridge_width 0.5)
			(island_removal_mode 0)
		)
		(polygon
			(pts
				(xy 81.978246 -145.525998) (xy 81.978246 -144.174718) (xy 83.258406 -144.174718) (xy 83.258406 -145.525998)
			)
		)
	)
	(zone
		(layer "F.Cu")
		(hatch none 0.5)
		(connect_pads
			(clearance 0)
		)
		(min_thickness 0.25)
		(keepout
			(tracks allowed)
			(vias allowed)
			(pads allowed)
			(copperpour allowed)
			(footprints allowed)
		)
		(placement
			(enabled no)
			(sheetname "")
		)
		(fill
			(thermal_gap 0.5)
			(thermal_bridge_width 0.5)
			(island_removal_mode 0)
		)
		(polygon
			(pts
				(xy 152.055068 -120.328182) (xy 152.055068 -118.976902) (xy 153.335228 -118.976902) (xy 153.335228 -120.328182)
			)
		)
	)
	(zone
		(layer "F.Cu")
		(hatch none 0.5)
		(connect_pads
			(clearance 0)
		)
		(min_thickness 0.25)
		(keepout
			(tracks allowed)
			(vias allowed)
			(pads allowed)
			(copperpour allowed)
			(footprints not_allowed)
		)
		(placement
			(enabled no)
			(sheetname "")
		)
		(fill
			(thermal_gap 0.5)
			(thermal_bridge_width 0.5)
			(island_removal_mode 0)
		)
		(polygon
			(pts
				(xy 170.947334 -165.34511) (xy 170.947334 -90.054938) (xy 155.912312 -90.054938) (xy 155.912312 -165.34511)
			)
		)
	)
	(zone
		(layer "F.Cu")
		(hatch none 0.5)
		(connect_pads
			(clearance 0)
		)
		(min_thickness 0.25)
		(keepout
			(tracks allowed)
			(vias allowed)
			(pads allowed)
			(copperpour allowed)
			(footprints not_allowed)
		)
		(placement
			(enabled no)
			(sheetname "")
		)
		(fill
			(thermal_gap 0.5)
			(thermal_bridge_width 0.5)
			(island_removal_mode 0)
		)
		(polygon
			(pts
				(xy 242.990116 -232.750106) (xy 242.990116 -218.250008) (xy 239.840008 -218.250008) (xy 239.840008 -232.750106)
			)
		)
	)
	(zone
		(layer "F.Cu")
		(hatch none 0.5)
		(connect_pads
			(clearance 0)
		)
		(min_thickness 0.25)
		(keepout
			(tracks allowed)
			(vias allowed)
			(pads allowed)
			(copperpour allowed)
			(footprints allowed)
		)
		(placement
			(enabled no)
			(sheetname "")
		)
		(fill
			(thermal_gap 0.5)
			(thermal_bridge_width 0.5)
			(island_removal_mode 0)
		)
		(polygon
			(pts
				(xy 246.68861 -35.519868) (xy 248.516902 -35.519868) (xy 248.753376 -35.283394) (xy 248.753376 -26.930096)
				(xy 248.516902 -26.693622) (xy 246.860822 -26.693622) (xy 246.68861 -26.865834)
			)
		)
	)
	(zone
		(layer "F.Cu")
		(hatch none 0.5)
		(connect_pads
			(clearance 0)
		)
		(min_thickness 0.25)
		(keepout
			(tracks allowed)
			(vias allowed)
			(pads allowed)
			(copperpour allowed)
			(footprints allowed)
		)
		(placement
			(enabled no)
			(sheetname "")
		)
		(fill
			(thermal_gap 0.5)
			(thermal_bridge_width 0.5)
			(island_removal_mode 0)
		)
		(polygon
			(pts
				(xy 40.488616 -35.519868) (xy 42.316908 -35.519868) (xy 42.553382 -35.283394) (xy 42.553382 -26.930096)
				(xy 42.316908 -26.693622) (xy 40.660828 -26.693622) (xy 40.488616 -26.865834)
			)
		)
	)
	(zone
		(layer "F.Cu")
		(hatch none 0.5)
		(connect_pads
			(clearance 0)
		)
		(min_thickness 0.25)
		(keepout
			(tracks allowed)
			(vias allowed)
			(pads allowed)
			(copperpour allowed)
			(footprints allowed)
		)
		(placement
			(enabled no)
			(sheetname "")
		)
		(fill
			(thermal_gap 0.5)
			(thermal_bridge_width 0.5)
			(island_removal_mode 0)
		)
		(polygon
			(pts
				(xy 129.877058 -230.378) (xy 129.877058 -220.599) (xy 131.909058 -220.599) (xy 131.909058 -230.378)
			)
		)
	)
	(zone
		(layer "F.Cu")
		(hatch none 0.5)
		(connect_pads
			(clearance 0)
		)
		(min_thickness 0.25)
		(keepout
			(tracks allowed)
			(vias allowed)
			(pads allowed)
			(copperpour allowed)
			(footprints allowed)
		)
		(placement
			(enabled no)
			(sheetname "")
		)
		(fill
			(thermal_gap 0.5)
			(thermal_bridge_width 0.5)
			(island_removal_mode 0)
		)
		(polygon
			(pts
				(xy 235.19003 -84.607146) (xy 235.19003 -83.770216) (xy 235.19003 -83.279742) (xy 235.189776 -83.279488)
				(xy 233.741976 -83.279488) (xy 233.621326 -83.400138) (xy 233.621326 -83.70951) (xy 233.651552 -83.739736)
				(xy 233.651552 -84.584286) (xy 233.73461 -84.667344) (xy 235.129832 -84.667344)
			)
		)
	)
	(zone
		(layer "F.Cu")
		(hatch none 0.5)
		(connect_pads
			(clearance 0)
		)
		(min_thickness 0.25)
		(keepout
			(tracks allowed)
			(vias allowed)
			(pads allowed)
			(copperpour allowed)
			(footprints allowed)
		)
		(placement
			(enabled no)
			(sheetname "")
		)
		(fill
			(thermal_gap 0.5)
			(thermal_bridge_width 0.5)
			(island_removal_mode 0)
		)
		(polygon
			(pts
				(xy 427.636178 -143.71955) (xy 427.636178 -142.36827) (xy 428.916338 -142.36827) (xy 428.916338 -143.71955)
			)
		)
	)
	(zone
		(layer "F.Cu")
		(hatch none 0.5)
		(connect_pads
			(clearance 0)
		)
		(min_thickness 0.25)
		(keepout
			(tracks allowed)
			(vias allowed)
			(pads allowed)
			(copperpour allowed)
			(footprints allowed)
		)
		(placement
			(enabled no)
			(sheetname "")
		)
		(fill
			(thermal_gap 0.5)
			(thermal_bridge_width 0.5)
			(island_removal_mode 0)
		)
		(polygon
			(pts
				(xy 384.255264 -105.824782) (xy 384.255264 -104.473502) (xy 385.535424 -104.473502) (xy 385.535424 -105.824782)
			)
		)
	)
	(zone
		(layer "F.Cu")
		(hatch none 0.5)
		(connect_pads
			(clearance 0)
		)
		(min_thickness 0.25)
		(keepout
			(tracks allowed)
			(vias allowed)
			(pads allowed)
			(copperpour allowed)
			(footprints allowed)
		)
		(placement
			(enabled no)
			(sheetname "")
		)
		(fill
			(thermal_gap 0.5)
			(thermal_bridge_width 0.5)
			(island_removal_mode 0)
		)
		(polygon
			(pts
				(xy 275.309076 -32.954468) (xy 275.309076 -31.603188) (xy 276.589236 -31.603188) (xy 276.589236 -32.954468)
			)
		)
	)
	(zone
		(layer "F.Cu")
		(hatch none 0.5)
		(connect_pads
			(clearance 0)
		)
		(min_thickness 0.25)
		(keepout
			(tracks allowed)
			(vias allowed)
			(pads allowed)
			(copperpour allowed)
			(footprints allowed)
		)
		(placement
			(enabled no)
			(sheetname "")
		)
		(fill
			(thermal_gap 0.5)
			(thermal_bridge_width 0.5)
			(island_removal_mode 0)
		)
		(polygon
			(pts
				(xy 6.058154 -387.363462) (xy 5.221224 -387.363462) (xy 4.73075 -387.363462) (xy 4.730496 -387.363716)
				(xy 4.730496 -388.811516) (xy 4.851146 -388.932166) (xy 5.160518 -388.932166) (xy 5.190744 -388.90194)
				(xy 6.035294 -388.90194) (xy 6.118352 -388.818882) (xy 6.118352 -387.42366)
			)
		)
	)
	(zone
		(layer "F.Cu")
		(hatch none 0.5)
		(connect_pads
			(clearance 0)
		)
		(min_thickness 0.25)
		(keepout
			(tracks allowed)
			(vias allowed)
			(pads allowed)
			(copperpour allowed)
			(footprints allowed)
		)
		(placement
			(enabled no)
			(sheetname "")
		)
		(fill
			(thermal_gap 0.5)
			(thermal_bridge_width 0.5)
			(island_removal_mode 0)
		)
		(polygon
			(pts
				(xy 172.616876 -350.80575) (xy 171.265596 -350.80575) (xy 171.265596 -349.52559) (xy 172.616876 -349.52559)
			)
		)
	)
	(zone
		(layer "F.Cu")
		(hatch none 0.5)
		(connect_pads
			(clearance 0)
		)
		(min_thickness 0.25)
		(keepout
			(tracks allowed)
			(vias allowed)
			(pads allowed)
			(copperpour allowed)
			(footprints not_allowed)
		)
		(placement
			(enabled no)
			(sheetname "")
		)
		(fill
			(thermal_gap 0.5)
			(thermal_bridge_width 0.5)
			(island_removal_mode 0)
		)
		(polygon
			(pts
				(arc
					(start 125.700028 -72.69988)
					(mid 117.700044 -80.699864)
					(end 109.70006 -72.69988)
				)
				(arc
					(start 109.70006 -72.69988)
					(mid 117.700044 -64.699896)
					(end 125.700028 -72.69988)
				)
			)
		)
	)
	(zone
		(layer "F.Cu")
		(hatch none 0.5)
		(connect_pads
			(clearance 0)
		)
		(min_thickness 0.25)
		(keepout
			(tracks allowed)
			(vias allowed)
			(pads allowed)
			(copperpour allowed)
			(footprints not_allowed)
		)
		(placement
			(enabled no)
			(sheetname "")
		)
		(fill
			(thermal_gap 0.5)
			(thermal_bridge_width 0.5)
			(island_removal_mode 0)
		)
		(polygon
			(pts
				(xy 207.75803 -365.400082) (xy 253.757938 -365.400082) (xy 253.757938 -342.399874) (xy 209.749898 -342.399874)
				(xy 209.749898 -339.39988) (xy 207.75803 -339.39988)
			)
		)
	)
	(zone
		(layer "F.Cu")
		(hatch none 0.5)
		(connect_pads
			(clearance 0)
		)
		(min_thickness 0.25)
		(keepout
			(tracks allowed)
			(vias allowed)
			(pads allowed)
			(copperpour allowed)
			(footprints allowed)
		)
		(placement
			(enabled no)
			(sheetname "")
		)
		(fill
			(thermal_gap 0.5)
			(thermal_bridge_width 0.5)
			(island_removal_mode 0)
		)
		(polygon
			(pts
				(xy 420.980108 -136.909302) (xy 423.06748 -136.909302) (xy 423.38752 -136.589262) (xy 423.38752 -129.185162)
				(xy 421.042592 -129.185162) (xy 420.96436 -129.263394) (xy 420.96436 -136.893554)
			)
		)
	)
	(zone
		(layer "F.Cu")
		(hatch none 0.5)
		(connect_pads
			(clearance 0)
		)
		(min_thickness 0.25)
		(keepout
			(tracks allowed)
			(vias allowed)
			(pads allowed)
			(copperpour allowed)
			(footprints allowed)
		)
		(placement
			(enabled no)
			(sheetname "")
		)
		(fill
			(thermal_gap 0.5)
			(thermal_bridge_width 0.5)
			(island_removal_mode 0)
		)
		(polygon
			(pts
				(xy 398.364964 -126.219204) (xy 400.452336 -126.219204) (xy 400.772376 -125.899164) (xy 400.772376 -118.495064)
				(xy 398.427448 -118.495064) (xy 398.349216 -118.573296) (xy 398.349216 -126.203456)
			)
		)
	)
	(zone
		(layer "F.Cu")
		(hatch none 0.5)
		(connect_pads
			(clearance 0)
		)
		(min_thickness 0.25)
		(keepout
			(tracks allowed)
			(vias allowed)
			(pads allowed)
			(copperpour allowed)
			(footprints not_allowed)
		)
		(placement
			(enabled no)
			(sheetname "")
		)
		(fill
			(thermal_gap 0.5)
			(thermal_bridge_width 0.5)
			(island_removal_mode 0)
		)
		(polygon
			(pts
				(arc
					(start 341.900002 -194.360038)
					(mid 349.899986 -186.360054)
					(end 357.89997 -194.360038)
				)
				(arc
					(start 357.89997 -194.360038)
					(mid 349.899986 -202.360022)
					(end 341.900002 -194.360038)
				)
			)
		)
	)
	(zone
		(layer "F.Cu")
		(hatch none 0.5)
		(connect_pads
			(clearance 0)
		)
		(min_thickness 0.25)
		(keepout
			(tracks allowed)
			(vias allowed)
			(pads allowed)
			(copperpour allowed)
			(footprints not_allowed)
		)
		(placement
			(enabled no)
			(sheetname "")
		)
		(fill
			(thermal_gap 0.5)
			(thermal_bridge_width 0.5)
			(island_removal_mode 0)
		)
		(polygon
			(pts
				(xy 267.10005 -271.15008) (xy 267.10005 -320.650108) (xy 316.600078 -320.650108) (xy 316.600078 -271.15008)
			)
		)
	)
	(zone
		(layer "F.Cu")
		(hatch none 0.5)
		(connect_pads
			(clearance 0)
		)
		(min_thickness 0.25)
		(keepout
			(tracks allowed)
			(vias allowed)
			(pads allowed)
			(copperpour allowed)
			(footprints allowed)
		)
		(placement
			(enabled no)
			(sheetname "")
		)
		(fill
			(thermal_gap 0.5)
			(thermal_bridge_width 0.5)
			(island_removal_mode 0)
		)
		(polygon
			(pts
				(xy 384.727704 -356.952042) (xy 383.376424 -356.952042) (xy 383.376424 -355.671882) (xy 384.727704 -355.671882)
			)
		)
	)
	(zone
		(layer "F.Cu")
		(hatch none 0.5)
		(connect_pads
			(clearance 0)
		)
		(min_thickness 0.25)
		(keepout
			(tracks allowed)
			(vias allowed)
			(pads allowed)
			(copperpour allowed)
			(footprints allowed)
		)
		(placement
			(enabled no)
			(sheetname "")
		)
		(fill
			(thermal_gap 0.5)
			(thermal_bridge_width 0.5)
			(island_removal_mode 0)
		)
		(polygon
			(pts
				(xy 161.986722 -140.988288) (xy 163.230052 -140.988288) (xy 163.324286 -140.894054) (xy 163.324286 -140.028168)
				(xy 163.229798 -139.93368) (xy 161.772346 -139.93368) (xy 161.566606 -140.13942) (xy 161.566606 -140.568172)
			)
		)
	)
	(zone
		(layer "F.Cu")
		(hatch none 0.5)
		(connect_pads
			(clearance 0)
		)
		(min_thickness 0.25)
		(keepout
			(tracks allowed)
			(vias allowed)
			(pads allowed)
			(copperpour allowed)
			(footprints allowed)
		)
		(placement
			(enabled no)
			(sheetname "")
		)
		(fill
			(thermal_gap 0.5)
			(thermal_bridge_width 0.5)
			(island_removal_mode 0)
		)
		(polygon
			(pts
				(xy 48.416972 -350.781874) (xy 47.065692 -350.781874) (xy 47.065692 -349.501714) (xy 48.416972 -349.501714)
			)
		)
	)
	(zone
		(layer "F.Cu")
		(hatch none 0.5)
		(connect_pads
			(clearance 0)
		)
		(min_thickness 0.25)
		(keepout
			(tracks not_allowed)
			(vias allowed)
			(pads allowed)
			(copperpour not_allowed)
			(footprints allowed)
		)
		(placement
			(enabled no)
			(sheetname "")
		)
		(fill
			(thermal_gap 0.5)
			(thermal_bridge_width 0.5)
			(island_removal_mode 0)
		)
		(polygon
			(pts
				(arc
					(start 197.39991 -393.100052)
					(mid 199.399906 -391.100056)
					(end 201.399902 -393.100052)
				)
				(arc
					(start 201.399902 -393.100052)
					(mid 199.399906 -395.100048)
					(end 197.39991 -393.100052)
				)
			)
		)
	)
	(zone
		(layer "F.Cu")
		(hatch none 0.5)
		(connect_pads
			(clearance 0)
		)
		(min_thickness 0.25)
		(keepout
			(tracks allowed)
			(vias allowed)
			(pads allowed)
			(copperpour allowed)
			(footprints allowed)
		)
		(placement
			(enabled no)
			(sheetname "")
		)
		(fill
			(thermal_gap 0.5)
			(thermal_bridge_width 0.5)
			(island_removal_mode 0)
		)
		(polygon
			(pts
				(xy 71.803006 -344.659458) (xy 70.451726 -344.659458) (xy 70.451726 -343.379298) (xy 71.803006 -343.379298)
			)
		)
	)
	(zone
		(layer "F.Cu")
		(hatch none 0.5)
		(connect_pads
			(clearance 0)
		)
		(min_thickness 0.25)
		(keepout
			(tracks allowed)
			(vias allowed)
			(pads allowed)
			(copperpour allowed)
			(footprints not_allowed)
		)
		(placement
			(enabled no)
			(sheetname "")
		)
		(fill
			(thermal_gap 0.5)
			(thermal_bridge_width 0.5)
			(island_removal_mode 0)
		)
		(polygon
			(pts
				(xy 173.420024 -23.219918) (xy 177.619914 -23.219918) (xy 177.619914 -18.219928) (xy 173.420024 -18.219928)
			)
		)
	)
	(zone
		(layer "F.Cu")
		(hatch none 0.5)
		(connect_pads
			(clearance 0)
		)
		(min_thickness 0.25)
		(keepout
			(tracks allowed)
			(vias allowed)
			(pads allowed)
			(copperpour allowed)
			(footprints not_allowed)
		)
		(placement
			(enabled no)
			(sheetname "")
		)
		(fill
			(thermal_gap 0.5)
			(thermal_bridge_width 0.5)
			(island_removal_mode 0)
		)
		(polygon
			(pts
				(xy 274.009866 -217.717878) (xy 294.03294 -217.717878) (xy 294.03294 -226.692968) (xy 274.009866 -226.692968)
			)
		)
		(polygon
			(pts
				(xy 275.380958 -219.096844) (xy 275.380958 -225.283014) (xy 292.629844 -225.283014) (xy 292.629844 -219.096844)
			)
		)
	)
	(zone
		(layer "F.Cu")
		(hatch none 0.5)
		(connect_pads
			(clearance 0)
		)
		(min_thickness 0.25)
		(keepout
			(tracks allowed)
			(vias allowed)
			(pads allowed)
			(copperpour allowed)
			(footprints allowed)
		)
		(placement
			(enabled no)
			(sheetname "")
		)
		(fill
			(thermal_gap 0.5)
			(thermal_bridge_width 0.5)
			(island_removal_mode 0)
		)
		(polygon
			(pts
				(xy 67.512692 -156.836872) (xy 69.323204 -156.836872) (xy 69.369686 -156.79039) (xy 69.369686 -142.047468)
				(xy 69.224398 -141.90218) (xy 67.472306 -141.90218) (xy 67.396868 -141.977618) (xy 67.396868 -156.721048)
			)
		)
	)
	(zone
		(layer "F.Cu")
		(hatch none 0.5)
		(connect_pads
			(clearance 0)
		)
		(min_thickness 0.25)
		(keepout
			(tracks allowed)
			(vias allowed)
			(pads allowed)
			(copperpour allowed)
			(footprints allowed)
		)
		(placement
			(enabled no)
			(sheetname "")
		)
		(fill
			(thermal_gap 0.5)
			(thermal_bridge_width 0.5)
			(island_removal_mode 0)
		)
		(polygon
			(pts
				(xy 268.155166 -113.024666) (xy 268.155166 -111.673386) (xy 269.435326 -111.673386) (xy 269.435326 -113.024666)
			)
		)
	)
	(zone
		(layer "F.Cu")
		(hatch none 0.5)
		(connect_pads
			(clearance 0)
		)
		(min_thickness 0.25)
		(keepout
			(tracks allowed)
			(vias allowed)
			(pads allowed)
			(copperpour allowed)
			(footprints allowed)
		)
		(placement
			(enabled no)
			(sheetname "")
		)
		(fill
			(thermal_gap 0.5)
			(thermal_bridge_width 0.5)
			(island_removal_mode 0)
		)
		(polygon
			(pts
				(xy 98.99142 -52.800758) (xy 98.99142 -55.718456) (xy 99.20097 -55.928006) (xy 99.813872 -55.928006)
				(xy 99.813872 -52.870608) (xy 99.744022 -52.800758)
			)
		)
	)
	(zone
		(layer "F.Cu")
		(hatch none 0.5)
		(connect_pads
			(clearance 0)
		)
		(min_thickness 0.25)
		(keepout
			(tracks not_allowed)
			(vias allowed)
			(pads allowed)
			(copperpour not_allowed)
			(footprints allowed)
		)
		(placement
			(enabled no)
			(sheetname "")
		)
		(fill
			(thermal_gap 0.5)
			(thermal_bridge_width 0.5)
			(island_removal_mode 0)
		)
		(polygon
			(pts
				(arc
					(start 259.599938 -320.900044)
					(mid 261.850124 -318.649858)
					(end 264.100056 -320.900044)
				)
				(arc
					(start 264.100056 -320.900044)
					(mid 261.850124 -323.149976)
					(end 259.599938 -320.900044)
				)
			)
		)
	)
	(zone
		(layer "F.Cu")
		(hatch none 0.5)
		(connect_pads
			(clearance 0)
		)
		(min_thickness 0.25)
		(keepout
			(tracks allowed)
			(vias allowed)
			(pads allowed)
			(copperpour allowed)
			(footprints allowed)
		)
		(placement
			(enabled no)
			(sheetname "")
		)
		(fill
			(thermal_gap 0.5)
			(thermal_bridge_width 0.5)
			(island_removal_mode 0)
		)
		(polygon
			(pts
				(xy 338.452968 -356.952042) (xy 337.101688 -356.952042) (xy 337.101688 -355.671882) (xy 338.452968 -355.671882)
			)
		)
	)
	(zone
		(layer "F.Cu")
		(hatch none 0.5)
		(connect_pads
			(clearance 0)
		)
		(min_thickness 0.25)
		(keepout
			(tracks allowed)
			(vias allowed)
			(pads allowed)
			(copperpour allowed)
			(footprints not_allowed)
		)
		(placement
			(enabled no)
			(sheetname "")
		)
		(fill
			(thermal_gap 0.5)
			(thermal_bridge_width 0.5)
			(island_removal_mode 0)
		)
		(polygon
			(pts
				(xy 316.600078 -320.650108) (xy 316.600078 -271.15008) (xy 267.10005 -271.15008) (xy 267.10005 -320.650108)
			)
		)
	)
	(zone
		(layer "F.Cu")
		(hatch none 0.5)
		(connect_pads
			(clearance 0)
		)
		(min_thickness 0.25)
		(keepout
			(tracks allowed)
			(vias allowed)
			(pads allowed)
			(copperpour allowed)
			(footprints allowed)
		)
		(placement
			(enabled no)
			(sheetname "")
		)
		(fill
			(thermal_gap 0.5)
			(thermal_bridge_width 0.5)
			(island_removal_mode 0)
		)
		(polygon
			(pts
				(xy 112.965992 -350.80575) (xy 111.614712 -350.80575) (xy 111.614712 -349.52559) (xy 112.965992 -349.52559)
			)
		)
	)
	(zone
		(layer "F.Cu")
		(hatch none 0.5)
		(connect_pads
			(clearance 0)
		)
		(min_thickness 0.25)
		(keepout
			(tracks allowed)
			(vias allowed)
			(pads allowed)
			(copperpour allowed)
			(footprints allowed)
		)
		(placement
			(enabled no)
			(sheetname "")
		)
		(fill
			(thermal_gap 0.5)
			(thermal_bridge_width 0.5)
			(island_removal_mode 0)
		)
		(polygon
			(pts
				(xy 432.136296 -350.80575) (xy 430.785016 -350.80575) (xy 430.785016 -349.52559) (xy 432.136296 -349.52559)
			)
		)
	)
	(zone
		(layer "F.Cu")
		(hatch none 0.5)
		(connect_pads
			(clearance 0)
		)
		(min_thickness 0.25)
		(keepout
			(tracks allowed)
			(vias allowed)
			(pads allowed)
			(copperpour allowed)
			(footprints allowed)
		)
		(placement
			(enabled no)
			(sheetname "")
		)
		(fill
			(thermal_gap 0.5)
			(thermal_bridge_width 0.5)
			(island_removal_mode 0)
		)
		(polygon
			(pts
				(xy 99.95916 -47.3202) (xy 99.95916 -45.5676) (xy 101.73716 -45.5676) (xy 101.73716 -47.3202)
			)
		)
	)
	(zone
		(layer "F.Cu")
		(hatch none 0.5)
		(connect_pads
			(clearance 0)
		)
		(min_thickness 0.25)
		(keepout
			(tracks allowed)
			(vias allowed)
			(pads allowed)
			(copperpour allowed)
			(footprints not_allowed)
		)
		(placement
			(enabled no)
			(sheetname "")
		)
		(fill
			(thermal_gap 0.5)
			(thermal_bridge_width 0.5)
			(island_removal_mode 0)
		)
		(polygon
			(pts
				(arc
					(start 276.165056 -5.999988)
					(mid 284.16504 1.999996)
					(end 292.165024 -5.999988)
				)
				(arc
					(start 292.165024 -5.999988)
					(mid 284.16504 -13.999972)
					(end 276.165056 -5.999988)
				)
			)
		)
	)
	(zone
		(layer "F.Cu")
		(hatch none 0.5)
		(connect_pads
			(clearance 0)
		)
		(min_thickness 0.25)
		(keepout
			(tracks allowed)
			(vias allowed)
			(pads allowed)
			(copperpour allowed)
			(footprints allowed)
		)
		(placement
			(enabled no)
			(sheetname "")
		)
		(fill
			(thermal_gap 0.5)
			(thermal_bridge_width 0.5)
			(island_removal_mode 0)
		)
		(polygon
			(pts
				(xy 151.355806 -35.503612) (xy 152.727406 -35.503612) (xy 153.016712 -35.214306) (xy 153.016712 -27.366976)
				(xy 152.864312 -27.214576) (xy 151.371046 -27.214576) (xy 150.990046 -27.595576) (xy 150.990046 -35.137852)
			)
		)
	)
	(zone
		(layer "F.Cu")
		(hatch none 0.5)
		(connect_pads
			(clearance 0)
		)
		(min_thickness 0.25)
		(keepout
			(tracks allowed)
			(vias allowed)
			(pads allowed)
			(copperpour allowed)
			(footprints not_allowed)
		)
		(placement
			(enabled no)
			(sheetname "")
		)
		(fill
			(thermal_gap 0.5)
			(thermal_bridge_width 0.5)
			(island_removal_mode 0)
		)
		(polygon
			(pts
				(xy 79.487522 -165.34511) (xy 79.487522 -90.054938) (xy 64.4525 -90.054938) (xy 64.4525 -165.34511)
			)
		)
	)
	(zone
		(layer "F.Cu")
		(hatch none 0.5)
		(connect_pads
			(clearance 0)
		)
		(min_thickness 0.25)
		(keepout
			(tracks allowed)
			(vias allowed)
			(pads allowed)
			(copperpour allowed)
			(footprints allowed)
		)
		(placement
			(enabled no)
			(sheetname "")
		)
		(fill
			(thermal_gap 0.5)
			(thermal_bridge_width 0.5)
			(island_removal_mode 0)
		)
		(polygon
			(pts
				(xy 119.910098 -287.02) (xy 124.863098 -287.02) (xy 125.117098 -286.766) (xy 125.117098 -286.004)
				(xy 124.863098 -285.75) (xy 123.720098 -285.75) (xy 123.466098 -285.496) (xy 123.466098 -284.861)
				(xy 123.720098 -284.607) (xy 124.228098 -284.607) (xy 124.355098 -284.48) (xy 124.355098 -282.829)
				(xy 124.101098 -282.575) (xy 120.164098 -282.575) (xy 119.910098 -282.829)
			)
		)
	)
	(zone
		(layer "F.Cu")
		(hatch none 0.5)
		(connect_pads
			(clearance 0)
		)
		(min_thickness 0.25)
		(keepout
			(tracks allowed)
			(vias allowed)
			(pads allowed)
			(copperpour allowed)
			(footprints allowed)
		)
		(placement
			(enabled no)
			(sheetname "")
		)
		(fill
			(thermal_gap 0.5)
			(thermal_bridge_width 0.5)
			(island_removal_mode 0)
		)
		(polygon
			(pts
				(xy 81.978246 -156.326078) (xy 81.978246 -154.974798) (xy 83.258406 -154.974798) (xy 83.258406 -156.326078)
			)
		)
	)
	(zone
		(layer "F.Cu")
		(hatch none 0.5)
		(connect_pads
			(clearance 0)
		)
		(min_thickness 0.25)
		(keepout
			(tracks allowed)
			(vias allowed)
			(pads allowed)
			(copperpour allowed)
			(footprints not_allowed)
		)
		(placement
			(enabled no)
			(sheetname "")
		)
		(fill
			(thermal_gap 0.5)
			(thermal_bridge_width 0.5)
			(island_removal_mode 0)
		)
		(polygon
			(pts
				(arc
					(start 219.758006 -347.400118)
					(mid 215.758014 -351.40011)
					(end 211.758022 -347.400118)
				)
				(arc
					(start 211.758022 -347.400118)
					(mid 215.758014 -343.400126)
					(end 219.758006 -347.400118)
				)
			)
		)
	)
	(zone
		(layer "F.Cu")
		(hatch none 0.5)
		(connect_pads
			(clearance 0)
		)
		(min_thickness 0.25)
		(keepout
			(tracks not_allowed)
			(vias allowed)
			(pads allowed)
			(copperpour not_allowed)
			(footprints allowed)
		)
		(placement
			(enabled no)
			(sheetname "")
		)
		(fill
			(thermal_gap 0.5)
			(thermal_bridge_width 0.5)
			(island_removal_mode 0)
		)
		(polygon
			(pts
				(arc
					(start 143.500094 -270.89989)
					(mid 145.750026 -268.649958)
					(end 147.999958 -270.89989)
				)
				(arc
					(start 147.999958 -270.89989)
					(mid 145.750026 -273.149822)
					(end 143.500094 -270.89989)
				)
			)
		)
	)
	(zone
		(layer "F.Cu")
		(hatch none 0.5)
		(connect_pads
			(clearance 0)
		)
		(min_thickness 0.25)
		(keepout
			(tracks allowed)
			(vias allowed)
			(pads allowed)
			(copperpour allowed)
			(footprints allowed)
		)
		(placement
			(enabled no)
			(sheetname "")
		)
		(fill
			(thermal_gap 0.5)
			(thermal_bridge_width 0.5)
			(island_removal_mode 0)
		)
		(polygon
			(pts
				(xy 392.77417 -126.219204) (xy 394.861542 -126.219204) (xy 395.181582 -125.899164) (xy 395.181582 -118.495064)
				(xy 392.836654 -118.495064) (xy 392.758422 -118.573296) (xy 392.758422 -126.203456)
			)
		)
	)
	(zone
		(layer "F.Cu")
		(hatch none 0.5)
		(connect_pads
			(clearance 0)
		)
		(min_thickness 0.25)
		(keepout
			(tracks allowed)
			(vias allowed)
			(pads allowed)
			(copperpour allowed)
			(footprints allowed)
		)
		(placement
			(enabled no)
			(sheetname "")
		)
		(fill
			(thermal_gap 0.5)
			(thermal_bridge_width 0.5)
			(island_removal_mode 0)
		)
		(polygon
			(pts
				(xy 272.109946 -344.659458) (xy 270.758666 -344.659458) (xy 270.758666 -343.379298) (xy 272.109946 -343.379298)
			)
		)
	)
	(zone
		(layer "F.Cu")
		(hatch none 0.5)
		(connect_pads
			(clearance 0)
		)
		(min_thickness 0.25)
		(keepout
			(tracks allowed)
			(vias allowed)
			(pads allowed)
			(copperpour allowed)
			(footprints allowed)
		)
		(placement
			(enabled no)
			(sheetname "")
		)
		(fill
			(thermal_gap 0.5)
			(thermal_bridge_width 0.5)
			(island_removal_mode 0)
		)
		(polygon
			(pts
				(xy 233.909362 -86.120732) (xy 233.909362 -85.283802) (xy 233.909362 -84.793328) (xy 233.909108 -84.793074)
				(xy 232.461308 -84.793074) (xy 232.340658 -84.913724) (xy 232.340658 -85.223096) (xy 232.370884 -85.253322)
				(xy 232.370884 -86.097872) (xy 232.453942 -86.18093) (xy 233.849164 -86.18093)
			)
		)
	)
	(zone
		(layer "F.Cu")
		(hatch none 0.5)
		(connect_pads
			(clearance 0)
		)
		(min_thickness 0.25)
		(keepout
			(tracks allowed)
			(vias allowed)
			(pads allowed)
			(copperpour allowed)
			(footprints allowed)
		)
		(placement
			(enabled no)
			(sheetname "")
		)
		(fill
			(thermal_gap 0.5)
			(thermal_bridge_width 0.5)
			(island_removal_mode 0)
		)
		(polygon
			(pts
				(xy 181.943756 -356.928166) (xy 180.592476 -356.928166) (xy 180.592476 -355.648006) (xy 181.943756 -355.648006)
			)
		)
	)
	(zone
		(layer "F.Cu")
		(hatch none 0.5)
		(connect_pads
			(clearance 0)
		)
		(min_thickness 0.25)
		(keepout
			(tracks allowed)
			(vias allowed)
			(pads allowed)
			(copperpour allowed)
			(footprints allowed)
		)
		(placement
			(enabled no)
			(sheetname "")
		)
		(fill
			(thermal_gap 0.5)
			(thermal_bridge_width 0.5)
			(island_removal_mode 0)
		)
		(polygon
			(pts
				(xy 198.07809 -156.326078) (xy 198.07809 -154.974798) (xy 199.35825 -154.974798) (xy 199.35825 -156.326078)
			)
		)
	)
	(zone
		(layer "F.Cu")
		(hatch none 0.5)
		(connect_pads
			(clearance 0)
		)
		(min_thickness 0.25)
		(keepout
			(tracks allowed)
			(vias allowed)
			(pads allowed)
			(copperpour allowed)
			(footprints allowed)
		)
		(placement
			(enabled no)
			(sheetname "")
		)
		(fill
			(thermal_gap 0.5)
			(thermal_bridge_width 0.5)
			(island_removal_mode 0)
		)
		(polygon
			(pts
				(xy 87.347806 -350.80575) (xy 85.996526 -350.80575) (xy 85.996526 -349.52559) (xy 87.347806 -349.52559)
			)
		)
	)
	(zone
		(layer "F.Cu")
		(hatch none 0.5)
		(connect_pads
			(clearance 0)
		)
		(min_thickness 0.25)
		(keepout
			(tracks allowed)
			(vias allowed)
			(pads allowed)
			(copperpour allowed)
			(footprints allowed)
		)
		(placement
			(enabled no)
			(sheetname "")
		)
		(fill
			(thermal_gap 0.5)
			(thermal_bridge_width 0.5)
			(island_removal_mode 0)
		)
		(polygon
			(pts
				(xy 138.059414 -47.3202) (xy 138.059414 -45.5676) (xy 139.837414 -45.5676) (xy 139.837414 -47.3202)
			)
		)
	)
	(zone
		(layer "F.Cu")
		(hatch none 0.5)
		(connect_pads
			(clearance 0)
		)
		(min_thickness 0.25)
		(keepout
			(tracks allowed)
			(vias allowed)
			(pads allowed)
			(copperpour allowed)
			(footprints allowed)
		)
		(placement
			(enabled no)
			(sheetname "")
		)
		(fill
			(thermal_gap 0.5)
			(thermal_bridge_width 0.5)
			(island_removal_mode 0)
		)
		(polygon
			(pts
				(xy 136.86028 -46.986444) (xy 137.852658 -46.986444) (xy 137.937494 -46.901608) (xy 137.937494 -46.211744)
				(xy 137.889488 -46.163738) (xy 136.840214 -46.163738) (xy 136.772396 -46.231556) (xy 136.772396 -46.89856)
			)
		)
	)
	(zone
		(layer "F.Cu")
		(hatch none 0.5)
		(connect_pads
			(clearance 0)
		)
		(min_thickness 0.25)
		(keepout
			(tracks not_allowed)
			(vias allowed)
			(pads allowed)
			(copperpour not_allowed)
			(footprints allowed)
		)
		(placement
			(enabled no)
			(sheetname "")
		)
		(fill
			(thermal_gap 0.5)
			(thermal_bridge_width 0.5)
			(island_removal_mode 0)
		)
		(polygon
			(pts
				(arc
					(start 270.20012 -393.100052)
					(mid 268.200124 -395.100048)
					(end 266.199874 -393.100052)
				)
				(arc
					(start 266.199874 -393.100052)
					(mid 268.200124 -391.099802)
					(end 270.20012 -393.100052)
				)
			)
		)
	)
	(zone
		(layer "F.Cu")
		(hatch none 0.5)
		(connect_pads
			(clearance 0)
		)
		(min_thickness 0.25)
		(keepout
			(tracks allowed)
			(vias allowed)
			(pads allowed)
			(copperpour allowed)
			(footprints allowed)
		)
		(placement
			(enabled no)
			(sheetname "")
		)
		(fill
			(thermal_gap 0.5)
			(thermal_bridge_width 0.5)
			(island_removal_mode 0)
		)
		(polygon
			(pts
				(xy 175.725836 -356.928166) (xy 174.374556 -356.928166) (xy 174.374556 -355.648006) (xy 175.725836 -355.648006)
			)
		)
	)
	(zone
		(layer "F.Cu")
		(hatch none 0.5)
		(connect_pads
			(clearance 0)
		)
		(min_thickness 0.25)
		(keepout
			(tracks allowed)
			(vias allowed)
			(pads allowed)
			(copperpour allowed)
			(footprints allowed)
		)
		(placement
			(enabled no)
			(sheetname "")
		)
		(fill
			(thermal_gap 0.5)
			(thermal_bridge_width 0.5)
			(island_removal_mode 0)
		)
		(polygon
			(pts
				(xy 130.588766 -35.519868) (xy 132.417058 -35.519868) (xy 132.653532 -35.283394) (xy 132.653532 -26.930096)
				(xy 132.417058 -26.693622) (xy 130.760978 -26.693622) (xy 130.588766 -26.865834)
			)
		)
	)
	(zone
		(layer "F.Cu")
		(hatch none 0.5)
		(connect_pads
			(clearance 0)
		)
		(min_thickness 0.25)
		(keepout
			(tracks allowed)
			(vias allowed)
			(pads allowed)
			(copperpour allowed)
			(footprints not_allowed)
		)
		(placement
			(enabled no)
			(sheetname "")
		)
		(fill
			(thermal_gap 0.5)
			(thermal_bridge_width 0.5)
			(island_removal_mode 0)
		)
		(polygon
			(pts
				(xy 143.542258 -177.9651) (xy 207.95742 -177.9651) (xy 207.95742 -107.780074) (xy 195.587366 -107.780074)
				(xy 195.587366 -165.34511) (xy 180.552344 -165.34511) (xy 180.552344 -107.780074) (xy 170.947334 -107.780074)
				(xy 170.947334 -165.34511) (xy 155.912312 -165.34511) (xy 155.912312 -107.780074) (xy 143.542258 -107.780074)
			)
		)
	)
	(zone
		(layer "F.Cu")
		(hatch none 0.5)
		(connect_pads
			(clearance 0)
		)
		(min_thickness 0.25)
		(keepout
			(tracks allowed)
			(vias allowed)
			(pads allowed)
			(copperpour allowed)
			(footprints not_allowed)
		)
		(placement
			(enabled no)
			(sheetname "")
		)
		(fill
			(thermal_gap 0.5)
			(thermal_bridge_width 0.5)
			(island_removal_mode 0)
		)
		(polygon
			(pts
				(xy 420.91991 -18.150078) (xy 420.91991 -13.150088) (xy 416.72002 -13.150088) (xy 416.72002 -18.150078)
			)
		)
	)
	(zone
		(layer "F.Cu")
		(hatch none 0.5)
		(connect_pads
			(clearance 0)
		)
		(min_thickness 0.25)
		(keepout
			(tracks allowed)
			(vias allowed)
			(pads allowed)
			(copperpour allowed)
			(footprints allowed)
		)
		(placement
			(enabled no)
			(sheetname "")
		)
		(fill
			(thermal_gap 0.5)
			(thermal_bridge_width 0.5)
			(island_removal_mode 0)
		)
		(polygon
			(pts
				(xy 159.209232 -32.954468) (xy 159.209232 -31.603188) (xy 160.489392 -31.603188) (xy 160.489392 -32.954468)
			)
		)
	)
	(zone
		(layer "F.Cu")
		(hatch none 0.5)
		(connect_pads
			(clearance 0)
		)
		(min_thickness 0.25)
		(keepout
			(tracks allowed)
			(vias allowed)
			(pads allowed)
			(copperpour allowed)
			(footprints allowed)
		)
		(placement
			(enabled no)
			(sheetname "")
		)
		(fill
			(thermal_gap 0.5)
			(thermal_bridge_width 0.5)
			(island_removal_mode 0)
		)
		(polygon
			(pts
				(xy 129.237994 -318.544956) (xy 129.237994 -316.893956) (xy 131.269994 -316.893956) (xy 131.269994 -318.544956)
			)
		)
	)
	(zone
		(layer "F.Cu")
		(hatch none 0.5)
		(connect_pads
			(clearance 0)
		)
		(min_thickness 0.25)
		(keepout
			(tracks allowed)
			(vias allowed)
			(pads allowed)
			(copperpour allowed)
			(footprints allowed)
		)
		(placement
			(enabled no)
			(sheetname "")
		)
		(fill
			(thermal_gap 0.5)
			(thermal_bridge_width 0.5)
			(island_removal_mode 0)
		)
		(polygon
			(pts
				(xy 394.051282 -34.76117) (xy 394.051282 -33.40989) (xy 395.331442 -33.40989) (xy 395.331442 -34.76117)
			)
		)
	)
	(zone
		(layer "F.Cu")
		(hatch none 0.5)
		(connect_pads
			(clearance 0)
		)
		(min_thickness 0.25)
		(keepout
			(tracks allowed)
			(vias allowed)
			(pads allowed)
			(copperpour allowed)
			(footprints allowed)
		)
		(placement
			(enabled no)
			(sheetname "")
		)
		(fill
			(thermal_gap 0.5)
			(thermal_bridge_width 0.5)
			(island_removal_mode 0)
		)
		(polygon
			(pts
				(xy 311.53608 -143.71955) (xy 311.53608 -142.36827) (xy 312.81624 -142.36827) (xy 312.81624 -143.71955)
			)
		)
	)
	(zone
		(layer "F.Cu")
		(hatch none 0.5)
		(connect_pads
			(clearance 0)
		)
		(min_thickness 0.25)
		(keepout
			(tracks allowed)
			(vias allowed)
			(pads allowed)
			(copperpour allowed)
			(footprints not_allowed)
		)
		(placement
			(enabled no)
			(sheetname "")
		)
		(fill
			(thermal_gap 0.5)
			(thermal_bridge_width 0.5)
			(island_removal_mode 0)
		)
		(polygon
			(pts
				(arc
					(start 26.800048 -84.70011)
					(mid 18.800064 -92.700094)
					(end 10.80008 -84.70011)
				)
				(arc
					(start 10.80008 -84.70011)
					(mid 18.800064 -76.700126)
					(end 26.800048 -84.70011)
				)
			)
		)
	)
	(zone
		(layer "F.Cu")
		(hatch none 0.5)
		(connect_pads
			(clearance 0)
		)
		(min_thickness 0.25)
		(keepout
			(tracks allowed)
			(vias allowed)
			(pads allowed)
			(copperpour allowed)
			(footprints allowed)
		)
		(placement
			(enabled no)
			(sheetname "")
		)
		(fill
			(thermal_gap 0.5)
			(thermal_bridge_width 0.5)
			(island_removal_mode 0)
		)
		(polygon
			(pts
				(xy 410.398976 -350.80575) (xy 409.047696 -350.80575) (xy 409.047696 -349.52559) (xy 410.398976 -349.52559)
			)
		)
	)
	(zone
		(layer "F.Cu")
		(hatch none 0.5)
		(connect_pads
			(clearance 0)
		)
		(min_thickness 0.25)
		(keepout
			(tracks allowed)
			(vias allowed)
			(pads allowed)
			(copperpour allowed)
			(footprints not_allowed)
		)
		(placement
			(enabled no)
			(sheetname "")
		)
		(fill
			(thermal_gap 0.5)
			(thermal_bridge_width 0.5)
			(island_removal_mode 0)
		)
		(polygon
			(pts
				(xy 84.399882 -320.650108) (xy 84.399882 -271.15008) (xy 34.900108 -271.15008) (xy 34.900108 -320.650108)
			)
		)
	)
	(zone
		(layer "F.Cu")
		(hatch none 0.5)
		(connect_pads
			(clearance 0)
		)
		(min_thickness 0.25)
		(keepout
			(tracks allowed)
			(vias allowed)
			(pads allowed)
			(copperpour allowed)
			(footprints allowed)
		)
		(placement
			(enabled no)
			(sheetname "")
		)
		(fill
			(thermal_gap 0.5)
			(thermal_bridge_width 0.5)
			(island_removal_mode 0)
		)
		(polygon
			(pts
				(xy 144.055592 -344.635582) (xy 142.704312 -344.635582) (xy 142.704312 -343.355422) (xy 144.055592 -343.355422)
			)
		)
	)
	(zone
		(layer "F.Cu")
		(hatch none 0.5)
		(connect_pads
			(clearance 0)
		)
		(min_thickness 0.25)
		(keepout
			(tracks allowed)
			(vias allowed)
			(pads allowed)
			(copperpour allowed)
			(footprints allowed)
		)
		(placement
			(enabled no)
			(sheetname "")
		)
		(fill
			(thermal_gap 0.5)
			(thermal_bridge_width 0.5)
			(island_removal_mode 0)
		)
		(polygon
			(pts
				(xy 270.797274 -104.01808) (xy 270.797274 -102.6668) (xy 272.077434 -102.6668) (xy 272.077434 -104.01808)
			)
		)
	)
	(zone
		(layer "F.Cu")
		(hatch none 0.5)
		(connect_pads
			(clearance 0)
		)
		(min_thickness 0.25)
		(keepout
			(tracks allowed)
			(vias allowed)
			(pads allowed)
			(copperpour allowed)
			(footprints allowed)
		)
		(placement
			(enabled no)
			(sheetname "")
		)
		(fill
			(thermal_gap 0.5)
			(thermal_bridge_width 0.5)
			(island_removal_mode 0)
		)
		(polygon
			(pts
				(xy 353.134422 -256.288286) (xy 355.176074 -256.288286) (xy 355.759766 -255.704594) (xy 355.759766 -254.088138)
				(xy 352.684588 -254.088138) (xy 352.35642 -254.416306) (xy 352.35642 -255.510284)
			)
		)
	)
	(zone
		(layer "F.Cu")
		(hatch none 0.5)
		(connect_pads
			(clearance 0)
		)
		(min_thickness 0.25)
		(keepout
			(tracks allowed)
			(vias allowed)
			(pads allowed)
			(copperpour allowed)
			(footprints allowed)
		)
		(placement
			(enabled no)
			(sheetname "")
		)
		(fill
			(thermal_gap 0.5)
			(thermal_bridge_width 0.5)
			(island_removal_mode 0)
		)
		(polygon
			(pts
				(xy 269.000986 -344.659458) (xy 267.649706 -344.659458) (xy 267.649706 -343.379298) (xy 269.000986 -343.379298)
			)
		)
	)
	(zone
		(layer "F.Cu")
		(hatch none 0.5)
		(connect_pads
			(clearance 0)
		)
		(min_thickness 0.25)
		(keepout
			(tracks allowed)
			(vias allowed)
			(pads allowed)
			(copperpour allowed)
			(footprints allowed)
		)
		(placement
			(enabled no)
			(sheetname "")
		)
		(fill
			(thermal_gap 0.5)
			(thermal_bridge_width 0.5)
			(island_removal_mode 0)
		)
		(polygon
			(pts
				(xy 429.027336 -350.80575) (xy 427.676056 -350.80575) (xy 427.676056 -349.52559) (xy 429.027336 -349.52559)
			)
		)
	)
	(zone
		(layer "F.Cu")
		(hatch none 0.5)
		(connect_pads
			(clearance 0)
		)
		(min_thickness 0.25)
		(keepout
			(tracks allowed)
			(vias allowed)
			(pads allowed)
			(copperpour allowed)
			(footprints not_allowed)
		)
		(placement
			(enabled no)
			(sheetname "")
		)
		(fill
			(thermal_gap 0.5)
			(thermal_bridge_width 0.5)
			(island_removal_mode 0)
		)
		(polygon
			(pts
				(xy 401.07997 -394.269976) (xy 401.07997 -417.58997) (xy 414.530032 -417.58997) (xy 414.530032 -394.269976)
			)
		)
	)
	(zone
		(layer "F.Cu")
		(hatch none 0.5)
		(connect_pads
			(clearance 0)
		)
		(min_thickness 0.25)
		(keepout
			(tracks allowed)
			(vias allowed)
			(pads allowed)
			(copperpour allowed)
			(footprints allowed)
		)
		(placement
			(enabled no)
			(sheetname "")
		)
		(fill
			(thermal_gap 0.5)
			(thermal_bridge_width 0.5)
			(island_removal_mode 0)
		)
		(polygon
			(pts
				(xy 110.332774 -312.599578) (xy 111.983774 -312.599578) (xy 111.983774 -314.631578) (xy 110.332774 -314.631578)
			)
		)
	)
	(zone
		(layer "F.Cu")
		(hatch none 0.5)
		(connect_pads
			(clearance 0)
		)
		(min_thickness 0.25)
		(keepout
			(tracks allowed)
			(vias allowed)
			(pads allowed)
			(copperpour allowed)
			(footprints allowed)
		)
		(placement
			(enabled no)
			(sheetname "")
		)
		(fill
			(thermal_gap 0.5)
			(thermal_bridge_width 0.5)
			(island_removal_mode 0)
		)
		(polygon
			(pts
				(xy 322.908168 -344.659458) (xy 321.556888 -344.659458) (xy 321.556888 -343.379298) (xy 322.908168 -343.379298)
			)
		)
	)
	(zone
		(layer "F.Cu")
		(hatch none 0.5)
		(connect_pads
			(clearance 0)
		)
		(min_thickness 0.25)
		(keepout
			(tracks allowed)
			(vias allowed)
			(pads allowed)
			(copperpour allowed)
			(footprints allowed)
		)
		(placement
			(enabled no)
			(sheetname "")
		)
		(fill
			(thermal_gap 0.5)
			(thermal_bridge_width 0.5)
			(island_removal_mode 0)
		)
		(polygon
			(pts
				(xy 369.060222 -46.986444) (xy 370.0526 -46.986444) (xy 370.137436 -46.901608) (xy 370.137436 -46.211744)
				(xy 370.08943 -46.163738) (xy 369.040156 -46.163738) (xy 368.972338 -46.231556) (xy 368.972338 -46.89856)
			)
		)
	)
	(zone
		(layer "F.Cu")
		(hatch none 0.5)
		(connect_pads
			(clearance 0)
		)
		(min_thickness 0.25)
		(keepout
			(tracks allowed)
			(vias allowed)
			(pads allowed)
			(copperpour allowed)
			(footprints not_allowed)
		)
		(placement
			(enabled no)
			(sheetname "")
		)
		(fill
			(thermal_gap 0.5)
			(thermal_bridge_width 0.5)
			(island_removal_mode 0)
		)
		(polygon
			(pts
				(xy 260.809994 -232.750106) (xy 263.960102 -232.750106) (xy 263.960102 -218.250008) (xy 260.809994 -218.250008)
			)
		)
	)
	(zone
		(layer "F.Cu")
		(hatch none 0.5)
		(connect_pads
			(clearance 0)
		)
		(min_thickness 0.25)
		(keepout
			(tracks allowed)
			(vias allowed)
			(pads allowed)
			(copperpour allowed)
			(footprints allowed)
		)
		(placement
			(enabled no)
			(sheetname "")
		)
		(fill
			(thermal_gap 0.5)
			(thermal_bridge_width 0.5)
			(island_removal_mode 0)
		)
		(polygon
			(pts
				(xy 246.053864 -230.378) (xy 246.053864 -220.599) (xy 248.085864 -220.599) (xy 248.085864 -230.378)
			)
		)
	)
	(zone
		(layer "F.Cu")
		(hatch none 0.5)
		(connect_pads
			(clearance 0)
		)
		(min_thickness 0.25)
		(keepout
			(tracks allowed)
			(vias allowed)
			(pads allowed)
			(copperpour allowed)
			(footprints allowed)
		)
		(placement
			(enabled no)
			(sheetname "")
		)
		(fill
			(thermal_gap 0.5)
			(thermal_bridge_width 0.5)
			(island_removal_mode 0)
		)
		(polygon
			(pts
				(xy 413.507936 -350.80575) (xy 412.156656 -350.80575) (xy 412.156656 -349.52559) (xy 413.507936 -349.52559)
			)
		)
	)
	(zone
		(layer "F.Cu")
		(hatch none 0.5)
		(connect_pads
			(clearance 0)
		)
		(min_thickness 0.25)
		(keepout
			(tracks allowed)
			(vias allowed)
			(pads allowed)
			(copperpour allowed)
			(footprints allowed)
		)
		(placement
			(enabled no)
			(sheetname "")
		)
		(fill
			(thermal_gap 0.5)
			(thermal_bridge_width 0.5)
			(island_removal_mode 0)
		)
		(polygon
			(pts
				(xy 65.585086 -344.659458) (xy 64.233806 -344.659458) (xy 64.233806 -343.379298) (xy 65.585086 -343.379298)
			)
		)
	)
	(zone
		(layer "F.Cu")
		(hatch none 0.5)
		(connect_pads
			(clearance 0)
		)
		(min_thickness 0.25)
		(keepout
			(tracks allowed)
			(vias allowed)
			(pads allowed)
			(copperpour allowed)
			(footprints not_allowed)
		)
		(placement
			(enabled no)
			(sheetname "")
		)
		(fill
			(thermal_gap 0.5)
			(thermal_bridge_width 0.5)
			(island_removal_mode 0)
		)
		(polygon
			(pts
				(xy 376.910092 -232.750106) (xy 380.059946 -232.750106) (xy 380.059946 -218.250008) (xy 376.910092 -218.250008)
			)
		)
	)
	(zone
		(layer "F.Cu")
		(hatch none 0.5)
		(connect_pads
			(clearance 0)
		)
		(min_thickness 0.25)
		(keepout
			(tracks allowed)
			(vias allowed)
			(pads allowed)
			(copperpour allowed)
			(footprints allowed)
		)
		(placement
			(enabled no)
			(sheetname "")
		)
		(fill
			(thermal_gap 0.5)
			(thermal_bridge_width 0.5)
			(island_removal_mode 0)
		)
		(polygon
			(pts
				(xy 449.94703 -208.864962) (xy 451.75043 -208.864962) (xy 451.75043 -207.540098) (xy 451.742556 -207.532224)
				(xy 450.00291 -207.532224) (xy 449.915026 -207.620108) (xy 449.915026 -208.832958)
			)
		)
	)
	(zone
		(layer "F.Cu")
		(hatch none 0.5)
		(connect_pads
			(clearance 0)
		)
		(min_thickness 0.25)
		(keepout
			(tracks allowed)
			(vias allowed)
			(pads allowed)
			(copperpour allowed)
			(footprints allowed)
		)
		(placement
			(enabled no)
			(sheetname "")
		)
		(fill
			(thermal_gap 0.5)
			(thermal_bridge_width 0.5)
			(island_removal_mode 0)
		)
		(polygon
			(pts
				(xy 415.333434 -28.022042) (xy 417.11626 -28.022042) (xy 417.5125 -27.625802) (xy 417.5125 -25.842976)
				(xy 417.37534 -25.705816) (xy 415.226754 -25.705816) (xy 415.013394 -25.919176) (xy 414.967674 -25.919176)
				(xy 414.967674 -27.656282)
			)
		)
	)
	(zone
		(layer "F.Cu")
		(hatch none 0.5)
		(connect_pads
			(clearance 0)
		)
		(min_thickness 0.25)
		(keepout
			(tracks allowed)
			(vias allowed)
			(pads allowed)
			(copperpour allowed)
			(footprints allowed)
		)
		(placement
			(enabled no)
			(sheetname "")
		)
		(fill
			(thermal_gap 0.5)
			(thermal_bridge_width 0.5)
			(island_removal_mode 0)
		)
		(polygon
			(pts
				(xy 299.712634 -156.836872) (xy 301.523146 -156.836872) (xy 301.569628 -156.79039) (xy 301.569628 -142.047468)
				(xy 301.42434 -141.90218) (xy 299.672248 -141.90218) (xy 299.59681 -141.977618) (xy 299.59681 -156.721048)
			)
		)
	)
	(zone
		(layer "F.Cu")
		(hatch none 0.5)
		(connect_pads
			(clearance 0)
		)
		(min_thickness 0.25)
		(keepout
			(tracks allowed)
			(vias allowed)
			(pads allowed)
			(copperpour allowed)
			(footprints allowed)
		)
		(placement
			(enabled no)
			(sheetname "")
		)
		(fill
			(thermal_gap 0.5)
			(thermal_bridge_width 0.5)
			(island_removal_mode 0)
		)
		(polygon
			(pts
				(xy 72.760078 -46.986444) (xy 73.752456 -46.986444) (xy 73.837292 -46.901608) (xy 73.837292 -46.211744)
				(xy 73.789286 -46.163738) (xy 72.740012 -46.163738) (xy 72.672194 -46.231556) (xy 72.672194 -46.89856)
			)
		)
	)
	(zone
		(layer "F.Cu")
		(hatch none 0.5)
		(connect_pads
			(clearance 0)
		)
		(min_thickness 0.25)
		(keepout
			(tracks not_allowed)
			(vias allowed)
			(pads allowed)
			(copperpour not_allowed)
			(footprints allowed)
		)
		(placement
			(enabled no)
			(sheetname "")
		)
		(fill
			(thermal_gap 0.5)
			(thermal_bridge_width 0.5)
			(island_removal_mode 0)
		)
		(polygon
			(pts
				(arc
					(start 85.149944 -270.89989)
					(mid 89.650062 -266.399772)
					(end 94.149926 -270.89989)
				)
				(arc
					(start 94.149926 -270.89989)
					(mid 89.650062 -275.399754)
					(end 85.149944 -270.89989)
				)
			)
		)
	)
	(zone
		(layer "F.Cu")
		(hatch none 0.5)
		(connect_pads
			(clearance 0)
		)
		(min_thickness 0.25)
		(keepout
			(tracks allowed)
			(vias allowed)
			(pads allowed)
			(copperpour allowed)
			(footprints allowed)
		)
		(placement
			(enabled no)
			(sheetname "")
		)
		(fill
			(thermal_gap 0.5)
			(thermal_bridge_width 0.5)
			(island_removal_mode 0)
		)
		(polygon
			(pts
				(xy 232.2576 -94.0562) (xy 232.2576 -90.4748) (xy 235.7882 -90.4748) (xy 235.7882 -94.0562)
			)
		)
	)
	(zone
		(layer "F.Cu")
		(hatch none 0.5)
		(connect_pads
			(clearance 0)
		)
		(min_thickness 0.25)
		(keepout
			(tracks not_allowed)
			(vias allowed)
			(pads allowed)
			(copperpour not_allowed)
			(footprints allowed)
		)
		(placement
			(enabled no)
			(sheetname "")
		)
		(fill
			(thermal_gap 0.5)
			(thermal_bridge_width 0.5)
			(island_removal_mode 0)
		)
		(polygon
			(pts
				(xy 20.619974 -18.150078) (xy 20.619974 -13.150088) (xy 16.420084 -13.150088) (xy 16.420084 -18.150078)
			)
		)
	)
	(zone
		(layer "F.Cu")
		(hatch none 0.5)
		(connect_pads
			(clearance 0)
		)
		(min_thickness 0.25)
		(keepout
			(tracks not_allowed)
			(vias allowed)
			(pads allowed)
			(copperpour not_allowed)
			(footprints allowed)
		)
		(placement
			(enabled no)
			(sheetname "")
		)
		(fill
			(thermal_gap 0.5)
			(thermal_bridge_width 0.5)
			(island_removal_mode 0)
		)
		(polygon
			(pts
				(arc
					(start 141.249908 -270.89989)
					(mid 145.750026 -266.399772)
					(end 150.24989 -270.89989)
				)
				(arc
					(start 150.24989 -270.89989)
					(mid 145.750026 -275.399754)
					(end 141.249908 -270.89989)
				)
			)
		)
	)
	(zone
		(layer "F.Cu")
		(hatch none 0.5)
		(connect_pads
			(clearance 0)
		)
		(min_thickness 0.25)
		(keepout
			(tracks allowed)
			(vias allowed)
			(pads allowed)
			(copperpour allowed)
			(footprints allowed)
		)
		(placement
			(enabled no)
			(sheetname "")
		)
		(fill
			(thermal_gap 0.5)
			(thermal_bridge_width 0.5)
			(island_removal_mode 0)
		)
		(polygon
			(pts
				(xy 79.336138 -134.609586) (xy 79.336138 -133.258306) (xy 80.616298 -133.258306) (xy 80.616298 -134.609586)
			)
		)
	)
	(zone
		(layer "F.Cu")
		(hatch none 0.5)
		(connect_pads
			(clearance 0)
		)
		(min_thickness 0.25)
		(keepout
			(tracks allowed)
			(vias allowed)
			(pads allowed)
			(copperpour allowed)
			(footprints allowed)
		)
		(placement
			(enabled no)
			(sheetname "")
		)
		(fill
			(thermal_gap 0.5)
			(thermal_bridge_width 0.5)
			(island_removal_mode 0)
		)
		(polygon
			(pts
				(xy 124.789946 -284.544262) (xy 125.266704 -284.544262) (xy 125.52807 -284.805628) (xy 125.644656 -284.805628)
				(xy 125.852936 -284.597348) (xy 125.852936 -282.759404) (xy 125.455172 -282.36164) (xy 124.879354 -282.36164)
				(xy 124.727716 -282.513278) (xy 124.727716 -284.482032)
			)
		)
	)
	(zone
		(layer "F.Cu")
		(hatch none 0.5)
		(connect_pads
			(clearance 0)
		)
		(min_thickness 0.25)
		(keepout
			(tracks not_allowed)
			(vias allowed)
			(pads allowed)
			(copperpour not_allowed)
			(footprints allowed)
		)
		(placement
			(enabled no)
			(sheetname "")
		)
		(fill
			(thermal_gap 0.5)
			(thermal_bridge_width 0.5)
			(island_removal_mode 0)
		)
		(polygon
			(pts
				(arc
					(start 352.700082 -72.69988)
					(mid 349.899986 -75.499976)
					(end 347.09989 -72.69988)
				)
				(arc
					(start 347.09989 -72.69988)
					(mid 349.899986 -69.899784)
					(end 352.700082 -72.69988)
				)
			)
		)
	)
	(zone
		(layer "F.Cu")
		(hatch none 0.5)
		(connect_pads
			(clearance 0)
		)
		(min_thickness 0.25)
		(keepout
			(tracks allowed)
			(vias allowed)
			(pads allowed)
			(copperpour allowed)
			(footprints allowed)
		)
		(placement
			(enabled no)
			(sheetname "")
		)
		(fill
			(thermal_gap 0.5)
			(thermal_bridge_width 0.5)
			(island_removal_mode 0)
		)
		(polygon
			(pts
				(xy 268.155166 -123.928124) (xy 268.155166 -122.576844) (xy 269.435326 -122.576844) (xy 269.435326 -123.928124)
			)
		)
	)
	(zone
		(layer "F.Cu")
		(hatch none 0.5)
		(connect_pads
			(clearance 0)
		)
		(min_thickness 0.25)
		(keepout
			(tracks allowed)
			(vias allowed)
			(pads allowed)
			(copperpour allowed)
			(footprints allowed)
		)
		(placement
			(enabled no)
			(sheetname "")
		)
		(fill
			(thermal_gap 0.5)
			(thermal_bridge_width 0.5)
			(island_removal_mode 0)
		)
		(polygon
			(pts
				(xy 277.09749 -113.527078) (xy 278.908002 -113.527078) (xy 278.954484 -113.480596) (xy 278.954484 -98.737674)
				(xy 278.809196 -98.592386) (xy 277.057104 -98.592386) (xy 276.981666 -98.667824) (xy 276.981666 -113.411254)
			)
		)
	)
	(zone
		(layer "F.Cu")
		(hatch none 0.5)
		(connect_pads
			(clearance 0)
		)
		(min_thickness 0.25)
		(keepout
			(tracks allowed)
			(vias allowed)
			(pads allowed)
			(copperpour allowed)
			(footprints allowed)
		)
		(placement
			(enabled no)
			(sheetname "")
		)
		(fill
			(thermal_gap 0.5)
			(thermal_bridge_width 0.5)
			(island_removal_mode 0)
		)
		(polygon
			(pts
				(arc
					(start 209.70367 -217.965782)
					(mid 209.718549 -217.929861)
					(end 209.75447 -217.914982)
				)
				(arc
					(start 210.432142 -217.914982)
					(mid 210.468063 -217.929861)
					(end 210.482942 -217.965782)
				)
				(arc
					(start 210.482942 -218.562682)
					(mid 210.468063 -218.598603)
					(end 210.432142 -218.613482)
				)
				(arc
					(start 209.75447 -218.613482)
					(mid 209.718549 -218.598603)
					(end 209.70367 -218.562682)
				)
			)
		)
	)
	(zone
		(layer "F.Cu")
		(hatch none 0.5)
		(connect_pads
			(clearance 0)
		)
		(min_thickness 0.25)
		(keepout
			(tracks allowed)
			(vias allowed)
			(pads allowed)
			(copperpour allowed)
			(footprints not_allowed)
		)
		(placement
			(enabled no)
			(sheetname "")
		)
		(fill
			(thermal_gap 0.5)
			(thermal_bridge_width 0.5)
			(island_removal_mode 0)
		)
		(polygon
			(pts
				(xy 452.53656 -312.609992) (xy 452.53656 -311.580022)
				(arc
					(start 460.806546 -311.580022)
					(mid 463.518065 -309.892673)
					(end 466.60054 -310.728106)
				)
				(xy 466.60054 -304.610008)
				(arc
					(start 447.450718 -304.610008)
					(mid 450.278647 -305.781848)
					(end 451.449948 -308.61)
				)
				(arc
					(start 451.449948 -308.61)
					(mid 450.278377 -311.438421)
					(end 447.449956 -312.609992)
				)
			)
		)
	)
	(zone
		(layer "F.Cu")
		(hatch none 0.5)
		(connect_pads
			(clearance 0)
		)
		(min_thickness 0.25)
		(keepout
			(tracks allowed)
			(vias allowed)
			(pads allowed)
			(copperpour allowed)
			(footprints allowed)
		)
		(placement
			(enabled no)
			(sheetname "")
		)
		(fill
			(thermal_gap 0.5)
			(thermal_bridge_width 0.5)
			(island_removal_mode 0)
		)
		(polygon
			(pts
				(xy 427.636178 -119.799608) (xy 427.636178 -118.448328) (xy 428.916338 -118.448328) (xy 428.916338 -119.799608)
			)
		)
	)
	(zone
		(layer "F.Cu")
		(hatch none 0.5)
		(connect_pads
			(clearance 0)
		)
		(min_thickness 0.25)
		(keepout
			(tracks allowed)
			(vias allowed)
			(pads allowed)
			(copperpour allowed)
			(footprints allowed)
		)
		(placement
			(enabled no)
			(sheetname "")
		)
		(fill
			(thermal_gap 0.5)
			(thermal_bridge_width 0.5)
			(island_removal_mode 0)
		)
		(polygon
			(pts
				(xy 397.163544 -356.952042) (xy 395.812264 -356.952042) (xy 395.812264 -355.671882) (xy 397.163544 -355.671882)
			)
		)
	)
	(zone
		(layer "F.Cu")
		(hatch none 0.5)
		(connect_pads
			(clearance 0)
		)
		(min_thickness 0.25)
		(keepout
			(tracks allowed)
			(vias allowed)
			(pads allowed)
			(copperpour allowed)
			(footprints allowed)
		)
		(placement
			(enabled no)
			(sheetname "")
		)
		(fill
			(thermal_gap 0.5)
			(thermal_bridge_width 0.5)
			(island_removal_mode 0)
		)
		(polygon
			(pts
				(xy 79.336138 -147.319492) (xy 79.336138 -145.968212) (xy 80.616298 -145.968212) (xy 80.616298 -147.319492)
			)
		)
	)
	(zone
		(layer "F.Cu")
		(hatch none 0.5)
		(connect_pads
			(clearance 0)
		)
		(min_thickness 0.25)
		(keepout
			(tracks allowed)
			(vias allowed)
			(pads allowed)
			(copperpour allowed)
			(footprints not_allowed)
		)
		(placement
			(enabled no)
			(sheetname "")
		)
		(fill
			(thermal_gap 0.5)
			(thermal_bridge_width 0.5)
			(island_removal_mode 0)
		)
		(polygon
			(pts
				(xy 91.857576 -177.9651) (xy 91.857576 -107.780074) (xy 79.487522 -107.780074) (xy 79.487522 -165.34511)
				(xy 64.4525 -165.34511) (xy 64.4525 -107.780074) (xy 54.84749 -107.780074) (xy 54.84749 -165.34511)
				(xy 39.812468 -165.34511) (xy 39.812468 -107.780074) (xy 27.442414 -107.780074) (xy 27.442414 -177.9651)
			)
		)
	)
	(zone
		(layer "F.Cu")
		(hatch none 0.5)
		(connect_pads
			(clearance 0)
		)
		(min_thickness 0.25)
		(keepout
			(tracks allowed)
			(vias allowed)
			(pads allowed)
			(copperpour allowed)
			(footprints allowed)
		)
		(placement
			(enabled no)
			(sheetname "")
		)
		(fill
			(thermal_gap 0.5)
			(thermal_bridge_width 0.5)
			(island_removal_mode 0)
		)
		(polygon
			(pts
				(xy 113.732818 -312.599578) (xy 115.383818 -312.599578) (xy 115.383818 -314.631578) (xy 113.732818 -314.631578)
			)
		)
	)
	(zone
		(layer "F.Cu")
		(hatch none 0.5)
		(connect_pads
			(clearance 0)
		)
		(min_thickness 0.25)
		(keepout
			(tracks not_allowed)
			(vias allowed)
			(pads allowed)
			(copperpour not_allowed)
			(footprints allowed)
		)
		(placement
			(enabled no)
			(sheetname "")
		)
		(fill
			(thermal_gap 0.5)
			(thermal_bridge_width 0.5)
			(island_removal_mode 0)
		)
		(polygon
			(pts
				(arc
					(start 25.150064 -270.89989)
					(mid 29.650182 -266.399772)
					(end 34.150046 -270.89989)
				)
				(arc
					(start 34.150046 -270.89989)
					(mid 29.650182 -275.399754)
					(end 25.150064 -270.89989)
				)
			)
		)
	)
	(zone
		(layer "F.Cu")
		(hatch none 0.5)
		(connect_pads
			(clearance 0)
		)
		(min_thickness 0.25)
		(keepout
			(tracks allowed)
			(vias allowed)
			(pads allowed)
			(copperpour allowed)
			(footprints allowed)
		)
		(placement
			(enabled no)
			(sheetname "")
		)
		(fill
			(thermal_gap 0.5)
			(thermal_bridge_width 0.5)
			(island_removal_mode 0)
		)
		(polygon
			(pts
				(xy 375.400824 -356.952042) (xy 374.049544 -356.952042) (xy 374.049544 -355.671882) (xy 375.400824 -355.671882)
			)
		)
	)
	(zone
		(layer "F.Cu")
		(hatch none 0.5)
		(connect_pads
			(clearance 0)
		)
		(min_thickness 0.25)
		(keepout
			(tracks allowed)
			(vias allowed)
			(pads allowed)
			(copperpour allowed)
			(footprints allowed)
		)
		(placement
			(enabled no)
			(sheetname "")
		)
		(fill
			(thermal_gap 0.5)
			(thermal_bridge_width 0.5)
			(island_removal_mode 0)
		)
		(polygon
			(pts
				(xy 281.411426 -350.80575) (xy 280.060146 -350.80575) (xy 280.060146 -349.52559) (xy 281.411426 -349.52559)
			)
		)
	)
	(zone
		(layer "F.Cu")
		(hatch none 0.5)
		(connect_pads
			(clearance 0)
		)
		(min_thickness 0.25)
		(keepout
			(tracks allowed)
			(vias allowed)
			(pads allowed)
			(copperpour allowed)
			(footprints not_allowed)
		)
		(placement
			(enabled no)
			(sheetname "")
		)
		(fill
			(thermal_gap 0.5)
			(thermal_bridge_width 0.5)
			(island_removal_mode 0)
		)
		(polygon
			(pts
				(xy 35.520122 -23.219918) (xy 35.520122 -18.219928) (xy 31.319978 -18.219928) (xy 31.319978 -23.219918)
			)
		)
	)
	(zone
		(layer "F.Cu")
		(hatch none 0.5)
		(connect_pads
			(clearance 0)
		)
		(min_thickness 0.25)
		(keepout
			(tracks allowed)
			(vias allowed)
			(pads allowed)
			(copperpour allowed)
			(footprints allowed)
		)
		(placement
			(enabled no)
			(sheetname "")
		)
		(fill
			(thermal_gap 0.5)
			(thermal_bridge_width 0.5)
			(island_removal_mode 0)
		)
		(polygon
			(pts
				(xy 397.163544 -344.659458) (xy 395.812264 -344.659458) (xy 395.812264 -343.379298) (xy 397.163544 -343.379298)
			)
		)
	)
	(zone
		(layer "F.Cu")
		(hatch none 0.5)
		(connect_pads
			(clearance 0)
		)
		(min_thickness 0.25)
		(keepout
			(tracks not_allowed)
			(vias allowed)
			(pads allowed)
			(copperpour not_allowed)
			(footprints allowed)
		)
		(placement
			(enabled no)
			(sheetname "")
		)
		(fill
			(thermal_gap 0.5)
			(thermal_bridge_width 0.5)
			(island_removal_mode 0)
		)
		(polygon
			(pts
				(arc
					(start 115.700048 -72.69988)
					(mid 117.700044 -70.699884)
					(end 119.70004 -72.69988)
				)
				(arc
					(start 119.70004 -72.69988)
					(mid 117.700044 -74.699876)
					(end 115.700048 -72.69988)
				)
			)
		)
	)
	(zone
		(layer "F.Cu")
		(hatch none 0.5)
		(connect_pads
			(clearance 0)
		)
		(min_thickness 0.25)
		(keepout
			(tracks allowed)
			(vias allowed)
			(pads allowed)
			(copperpour allowed)
			(footprints allowed)
		)
		(placement
			(enabled no)
			(sheetname "")
		)
		(fill
			(thermal_gap 0.5)
			(thermal_bridge_width 0.5)
			(island_removal_mode 0)
		)
		(polygon
			(pts
				(xy 416.591496 -350.80575) (xy 415.240216 -350.80575) (xy 415.240216 -349.52559) (xy 416.591496 -349.52559)
			)
		)
	)
	(zone
		(layer "F.Cu")
		(hatch none 0.5)
		(connect_pads
			(clearance 0)
		)
		(min_thickness 0.25)
		(keepout
			(tracks allowed)
			(vias allowed)
			(pads allowed)
			(copperpour allowed)
			(footprints allowed)
		)
		(placement
			(enabled no)
			(sheetname "")
		)
		(fill
			(thermal_gap 0.5)
			(thermal_bridge_width 0.5)
			(island_removal_mode 0)
		)
		(polygon
			(pts
				(xy 229.517702 -82.831178) (xy 230.43388 -82.831178) (xy 230.561388 -82.70367) (xy 230.561388 -82.382614)
				(xy 230.484172 -82.305398) (xy 229.46741 -82.305398) (xy 229.347522 -82.425286) (xy 229.347522 -82.660998)
			)
		)
	)
	(zone
		(layer "F.Cu")
		(hatch none 0.5)
		(connect_pads
			(clearance 0)
		)
		(min_thickness 0.25)
		(keepout
			(tracks allowed)
			(vias allowed)
			(pads allowed)
			(copperpour allowed)
			(footprints allowed)
		)
		(placement
			(enabled no)
			(sheetname "")
		)
		(fill
			(thermal_gap 0.5)
			(thermal_bridge_width 0.5)
			(island_removal_mode 0)
		)
		(polygon
			(pts
				(xy 166.398956 -350.80575) (xy 165.047676 -350.80575) (xy 165.047676 -349.52559) (xy 166.398956 -349.52559)
			)
		)
	)
	(zone
		(layer "F.Cu")
		(hatch none 0.5)
		(connect_pads
			(clearance 0)
		)
		(min_thickness 0.25)
		(keepout
			(tracks allowed)
			(vias allowed)
			(pads allowed)
			(copperpour allowed)
			(footprints not_allowed)
		)
		(placement
			(enabled no)
			(sheetname "")
		)
		(fill
			(thermal_gap 0.5)
			(thermal_bridge_width 0.5)
			(island_removal_mode 0)
		)
		(polygon
			(pts
				(xy 199.419972 -23.219918) (xy 203.620116 -23.219918) (xy 203.620116 -18.219928) (xy 199.419972 -18.219928)
			)
		)
	)
	(zone
		(layer "F.Cu")
		(hatch none 0.5)
		(connect_pads
			(clearance 0)
		)
		(min_thickness 0.25)
		(keepout
			(tracks allowed)
			(vias allowed)
			(pads allowed)
			(copperpour allowed)
			(footprints allowed)
		)
		(placement
			(enabled no)
			(sheetname "")
		)
		(fill
			(thermal_gap 0.5)
			(thermal_bridge_width 0.5)
			(island_removal_mode 0)
		)
		(polygon
			(pts
				(xy 195.435982 -119.799608) (xy 195.435982 -118.448328) (xy 196.716142 -118.448328) (xy 196.716142 -119.799608)
			)
		)
	)
	(zone
		(layer "F.Cu")
		(hatch none 0.5)
		(connect_pads
			(clearance 0)
		)
		(min_thickness 0.25)
		(keepout
			(tracks allowed)
			(vias allowed)
			(pads allowed)
			(copperpour allowed)
			(footprints allowed)
		)
		(placement
			(enabled no)
			(sheetname "")
		)
		(fill
			(thermal_gap 0.5)
			(thermal_bridge_width 0.5)
			(island_removal_mode 0)
		)
		(polygon
			(pts
				(xy 403.381464 -350.781874) (xy 402.030184 -350.781874) (xy 402.030184 -349.501714) (xy 403.381464 -349.501714)
			)
		)
	)
	(zone
		(layer "F.Cu")
		(hatch none 0.5)
		(connect_pads
			(clearance 0)
		)
		(min_thickness 0.25)
		(keepout
			(tracks not_allowed)
			(vias allowed)
			(pads allowed)
			(copperpour not_allowed)
			(footprints allowed)
		)
		(placement
			(enabled no)
			(sheetname "")
		)
		(fill
			(thermal_gap 0.5)
			(thermal_bridge_width 0.5)
			(island_removal_mode 0)
		)
		(polygon
			(pts
				(arc
					(start 170.865038 -5.999988)
					(mid 168.065196 -8.79983)
					(end 165.2651 -5.999988)
				)
				(arc
					(start 165.2651 -5.999988)
					(mid 168.065196 -3.199892)
					(end 170.865038 -5.999988)
				)
			)
		)
	)
	(zone
		(layer "F.Cu")
		(hatch none 0.5)
		(connect_pads
			(clearance 0)
		)
		(min_thickness 0.25)
		(keepout
			(tracks allowed)
			(vias allowed)
			(pads allowed)
			(copperpour allowed)
			(footprints allowed)
		)
		(placement
			(enabled no)
			(sheetname "")
		)
		(fill
			(thermal_gap 0.5)
			(thermal_bridge_width 0.5)
			(island_removal_mode 0)
		)
		(polygon
			(pts
				(xy 298.688506 -35.519868) (xy 300.516798 -35.519868) (xy 300.753272 -35.283394) (xy 300.753272 -26.930096)
				(xy 300.516798 -26.693622) (xy 298.860718 -26.693622) (xy 298.688506 -26.865834)
			)
		)
	)
	(zone
		(layer "F.Cu")
		(hatch none 0.5)
		(connect_pads
			(clearance 0)
		)
		(min_thickness 0.25)
		(keepout
			(tracks allowed)
			(vias allowed)
			(pads allowed)
			(copperpour allowed)
			(footprints not_allowed)
		)
		(placement
			(enabled no)
			(sheetname "")
		)
		(fill
			(thermal_gap 0.5)
			(thermal_bridge_width 0.5)
			(island_removal_mode 0)
		)
		(polygon
			(pts
				(arc
					(start 102.015036 -17.999964)
					(mid 110.01502 -9.99998)
					(end 118.015004 -17.999964)
				)
				(arc
					(start 118.015004 -17.999964)
					(mid 110.01502 -25.999948)
					(end 102.015036 -17.999964)
				)
			)
		)
	)
	(zone
		(layer "F.Cu")
		(hatch none 0.5)
		(connect_pads
			(clearance 0)
		)
		(min_thickness 0.25)
		(keepout
			(tracks allowed)
			(vias allowed)
			(pads allowed)
			(copperpour allowed)
			(footprints allowed)
		)
		(placement
			(enabled no)
			(sheetname "")
		)
		(fill
			(thermal_gap 0.5)
			(thermal_bridge_width 0.5)
			(island_removal_mode 0)
		)
		(polygon
			(pts
				(xy 443.40907 -29.354526) (xy 443.40907 -28.003246) (xy 444.68923 -28.003246) (xy 444.68923 -29.354526)
			)
		)
	)
	(zone
		(layer "F.Cu")
		(hatch none 0.5)
		(connect_pads
			(clearance 0)
		)
		(min_thickness 0.25)
		(keepout
			(tracks allowed)
			(vias allowed)
			(pads allowed)
			(copperpour allowed)
			(footprints allowed)
		)
		(placement
			(enabled no)
			(sheetname "")
		)
		(fill
			(thermal_gap 0.5)
			(thermal_bridge_width 0.5)
			(island_removal_mode 0)
		)
		(polygon
			(pts
				(xy 79.336138 -131.00939) (xy 79.336138 -129.65811) (xy 80.616298 -129.65811) (xy 80.616298 -131.00939)
			)
		)
	)
	(zone
		(layer "F.Cu")
		(hatch none 0.5)
		(connect_pads
			(clearance 0)
		)
		(min_thickness 0.25)
		(keepout
			(tracks allowed)
			(vias allowed)
			(pads allowed)
			(copperpour allowed)
			(footprints allowed)
		)
		(placement
			(enabled no)
			(sheetname "")
		)
		(fill
			(thermal_gap 0.5)
			(thermal_bridge_width 0.5)
			(island_removal_mode 0)
		)
		(polygon
			(pts
				(xy 159.209232 -29.354526) (xy 159.209232 -28.003246) (xy 160.489392 -28.003246) (xy 160.489392 -29.354526)
			)
		)
	)
	(zone
		(layer "F.Cu")
		(hatch none 0.5)
		(connect_pads
			(clearance 0)
		)
		(min_thickness 0.25)
		(keepout
			(tracks allowed)
			(vias allowed)
			(pads allowed)
			(copperpour allowed)
			(footprints not_allowed)
		)
		(placement
			(enabled no)
			(sheetname "")
		)
		(fill
			(thermal_gap 0.5)
			(thermal_bridge_width 0.5)
			(island_removal_mode 0)
		)
		(polygon
			(pts
				(xy 427.787562 -165.34511) (xy 427.787562 -90.054938) (xy 412.75254 -90.054938) (xy 412.75254 -165.34511)
			)
		)
	)
	(zone
		(layer "F.Cu")
		(hatch none 0.5)
		(connect_pads
			(clearance 0)
		)
		(min_thickness 0.25)
		(keepout
			(tracks allowed)
			(vias allowed)
			(pads allowed)
			(copperpour allowed)
			(footprints allowed)
		)
		(placement
			(enabled no)
			(sheetname "")
		)
		(fill
			(thermal_gap 0.5)
			(thermal_bridge_width 0.5)
			(island_removal_mode 0)
		)
		(polygon
			(pts
				(xy 268.155166 -109.424724) (xy 268.155166 -108.073444) (xy 269.435326 -108.073444) (xy 269.435326 -109.424724)
			)
		)
	)
	(zone
		(layer "F.Cu")
		(hatch none 0.5)
		(connect_pads
			(clearance 0)
		)
		(min_thickness 0.25)
		(keepout
			(tracks allowed)
			(vias allowed)
			(pads allowed)
			(copperpour allowed)
			(footprints allowed)
		)
		(placement
			(enabled no)
			(sheetname "")
		)
		(fill
			(thermal_gap 0.5)
			(thermal_bridge_width 0.5)
			(island_removal_mode 0)
		)
		(polygon
			(pts
				(xy 74.911966 -344.659458) (xy 73.560686 -344.659458) (xy 73.560686 -343.379298) (xy 74.911966 -343.379298)
			)
		)
	)
	(zone
		(layer "F.Cu")
		(hatch none 0.5)
		(connect_pads
			(clearance 0)
		)
		(min_thickness 0.25)
		(keepout
			(tracks allowed)
			(vias allowed)
			(pads allowed)
			(copperpour allowed)
			(footprints allowed)
		)
		(placement
			(enabled no)
			(sheetname "")
		)
		(fill
			(thermal_gap 0.5)
			(thermal_bridge_width 0.5)
			(island_removal_mode 0)
		)
		(polygon
			(pts
				(xy 78.020926 -344.659458) (xy 76.669646 -344.659458) (xy 76.669646 -343.379298) (xy 78.020926 -343.379298)
			)
		)
	)
	(zone
		(layer "F.Cu")
		(hatch none 0.5)
		(connect_pads
			(clearance 0)
		)
		(min_thickness 0.25)
		(keepout
			(tracks allowed)
			(vias allowed)
			(pads allowed)
			(copperpour allowed)
			(footprints allowed)
		)
		(placement
			(enabled no)
			(sheetname "")
		)
		(fill
			(thermal_gap 0.5)
			(thermal_bridge_width 0.5)
			(island_removal_mode 0)
		)
		(polygon
			(pts
				(xy 227.730558 -152.759664) (xy 228.191568 -153.220674) (xy 231.710992 -153.220674) (xy 232.001314 -152.930352)
				(xy 232.001314 -152.118568) (xy 232.001314 -151.360632) (xy 232.001314 -150.490174) (xy 231.688386 -150.177246)
				(xy 231.426766 -150.177246) (xy 226.843082 -150.177246) (xy 226.361752 -150.177246) (xy 226.292156 -150.246842)
				(xy 226.292156 -151.575262) (xy 226.541838 -151.824944) (xy 226.795838 -151.824944)
			)
		)
	)
	(zone
		(layer "F.Cu")
		(hatch none 0.5)
		(connect_pads
			(clearance 0)
		)
		(min_thickness 0.25)
		(keepout
			(tracks allowed)
			(vias allowed)
			(pads allowed)
			(copperpour allowed)
			(footprints allowed)
		)
		(placement
			(enabled no)
			(sheetname "")
		)
		(fill
			(thermal_gap 0.5)
			(thermal_bridge_width 0.5)
			(island_removal_mode 0)
		)
		(polygon
			(pts
				(xy 436.245 -22.733) (xy 436.245 -21.971) (xy 438.912 -21.971) (xy 438.912 -22.733)
			)
		)
	)
	(zone
		(layer "F.Cu")
		(hatch none 0.5)
		(connect_pads
			(clearance 0)
		)
		(min_thickness 0.25)
		(keepout
			(tracks allowed)
			(vias allowed)
			(pads allowed)
			(copperpour allowed)
			(footprints allowed)
		)
		(placement
			(enabled no)
			(sheetname "")
		)
		(fill
			(thermal_gap 0.5)
			(thermal_bridge_width 0.5)
			(island_removal_mode 0)
		)
		(polygon
			(pts
				(xy 166.164768 -137.42924) (xy 168.25214 -137.42924) (xy 168.57218 -137.1092) (xy 168.57218 -129.7051)
				(xy 166.227252 -129.7051) (xy 166.14902 -129.783332) (xy 166.14902 -137.413492)
			)
		)
	)
	(zone
		(layer "F.Cu")
		(hatch none 0.5)
		(connect_pads
			(clearance 0)
		)
		(min_thickness 0.25)
		(keepout
			(tracks not_allowed)
			(vias allowed)
			(pads allowed)
			(copperpour not_allowed)
			(footprints allowed)
		)
		(placement
			(enabled no)
			(sheetname "")
		)
		(fill
			(thermal_gap 0.5)
			(thermal_bridge_width 0.5)
			(island_removal_mode 0)
		)
		(polygon
			(pts
				(arc
					(start 463.14995 -398.100042)
					(mid 461.600042 -399.64995)
					(end 460.04988 -398.100042)
				)
				(arc
					(start 460.04988 -398.100042)
					(mid 461.600042 -396.54988)
					(end 463.14995 -398.100042)
				)
			)
		)
	)
	(zone
		(layer "F.Cu")
		(hatch none 0.5)
		(connect_pads
			(clearance 0)
		)
		(min_thickness 0.25)
		(keepout
			(tracks allowed)
			(vias allowed)
			(pads allowed)
			(copperpour allowed)
			(footprints allowed)
		)
		(placement
			(enabled no)
			(sheetname "")
		)
		(fill
			(thermal_gap 0.5)
			(thermal_bridge_width 0.5)
			(island_removal_mode 0)
		)
		(polygon
			(pts
				(xy 454.31456 -268.09192) (xy 454.31456 -265.94308) (xy 455.94778 -265.94308) (xy 455.94778 -268.09192)
			)
		)
	)
	(zone
		(layer "F.Cu")
		(hatch none 0.5)
		(connect_pads
			(clearance 0)
		)
		(min_thickness 0.25)
		(keepout
			(tracks allowed)
			(vias allowed)
			(pads allowed)
			(copperpour allowed)
			(footprints allowed)
		)
		(placement
			(enabled no)
			(sheetname "")
		)
		(fill
			(thermal_gap 0.5)
			(thermal_bridge_width 0.5)
			(island_removal_mode 0)
		)
		(polygon
			(pts
				(xy 384.727704 -344.659458) (xy 383.376424 -344.659458) (xy 383.376424 -343.379298) (xy 384.727704 -343.379298)
			)
		)
	)
	(zone
		(layer "F.Cu")
		(hatch none 0.5)
		(connect_pads
			(clearance 0)
		)
		(min_thickness 0.25)
		(keepout
			(tracks allowed)
			(vias allowed)
			(pads allowed)
			(copperpour allowed)
			(footprints not_allowed)
		)
		(placement
			(enabled no)
			(sheetname "")
		)
		(fill
			(thermal_gap 0.5)
			(thermal_bridge_width 0.5)
			(island_removal_mode 0)
		)
		(polygon
			(pts
				(arc
					(start 392.2649 -5.999988)
					(mid 400.265138 2.00025)
					(end 408.265122 -5.999988)
				)
				(arc
					(start 408.265122 -5.999988)
					(mid 400.265138 -13.999972)
					(end 392.2649 -5.999988)
				)
			)
		)
	)
	(zone
		(layer "F.Cu")
		(hatch none 0.5)
		(connect_pads
			(clearance 0)
		)
		(min_thickness 0.25)
		(keepout
			(tracks allowed)
			(vias allowed)
			(pads allowed)
			(copperpour allowed)
			(footprints allowed)
		)
		(placement
			(enabled no)
			(sheetname "")
		)
		(fill
			(thermal_gap 0.5)
			(thermal_bridge_width 0.5)
			(island_removal_mode 0)
		)
		(polygon
			(pts
				(xy 278.960072 -46.986444) (xy 279.95245 -46.986444) (xy 280.037286 -46.901608) (xy 280.037286 -46.211744)
				(xy 279.98928 -46.163738) (xy 278.940006 -46.163738) (xy 278.872188 -46.231556) (xy 278.872188 -46.89856)
			)
		)
	)
	(zone
		(layer "F.Cu")
		(hatch none 0.5)
		(connect_pads
			(clearance 0)
		)
		(min_thickness 0.25)
		(keepout
			(tracks allowed)
			(vias allowed)
			(pads allowed)
			(copperpour allowed)
			(footprints allowed)
		)
		(placement
			(enabled no)
			(sheetname "")
		)
		(fill
			(thermal_gap 0.5)
			(thermal_bridge_width 0.5)
			(island_removal_mode 0)
		)
		(polygon
			(pts
				(xy 417.535106 -129.180844) (xy 415.447734 -129.180844) (xy 415.127694 -129.500884) (xy 415.127694 -136.904984)
				(xy 417.472622 -136.904984) (xy 417.550854 -136.826752) (xy 417.550854 -129.196592)
			)
		)
	)
	(zone
		(layer "F.Cu")
		(hatch none 0.5)
		(connect_pads
			(clearance 0)
		)
		(min_thickness 0.25)
		(keepout
			(tracks allowed)
			(vias allowed)
			(pads allowed)
			(copperpour allowed)
			(footprints not_allowed)
		)
		(placement
			(enabled no)
			(sheetname "")
		)
		(fill
			(thermal_gap 0.5)
			(thermal_bridge_width 0.5)
			(island_removal_mode 0)
		)
		(polygon
			(pts
				(xy 257.849878 -342.399874) (xy 257.849878 -263.649968) (xy 251.350018 -258.739894) (xy 251.350018 -322.200016)
				(xy 216.250012 -322.200016) (xy 216.250012 -258.739894) (xy 209.749898 -263.649968) (xy 209.749898 -342.399874)
			)
		)
	)
	(zone
		(layer "F.Cu")
		(hatch none 0.5)
		(connect_pads
			(clearance 0)
		)
		(min_thickness 0.25)
		(keepout
			(tracks allowed)
			(vias allowed)
			(pads allowed)
			(copperpour allowed)
			(footprints allowed)
		)
		(placement
			(enabled no)
			(sheetname "")
		)
		(fill
			(thermal_gap 0.5)
			(thermal_bridge_width 0.5)
			(island_removal_mode 0)
		)
		(polygon
			(pts
				(xy 269.000986 -350.80575) (xy 267.649706 -350.80575) (xy 267.649706 -349.52559) (xy 269.000986 -349.52559)
			)
		)
	)
	(zone
		(layer "F.Cu")
		(hatch none 0.5)
		(connect_pads
			(clearance 0)
		)
		(min_thickness 0.25)
		(keepout
			(tracks allowed)
			(vias allowed)
			(pads allowed)
			(copperpour allowed)
			(footprints allowed)
		)
		(placement
			(enabled no)
			(sheetname "")
		)
		(fill
			(thermal_gap 0.5)
			(thermal_bridge_width 0.5)
			(island_removal_mode 0)
		)
		(polygon
			(pts
				(xy 420.05123 -31.160974) (xy 420.05123 -29.809694) (xy 421.33139 -29.809694) (xy 421.33139 -31.160974)
			)
		)
	)
	(zone
		(layer "F.Cu")
		(hatch none 0.5)
		(connect_pads
			(clearance 0)
		)
		(min_thickness 0.25)
		(keepout
			(tracks allowed)
			(vias allowed)
			(pads allowed)
			(copperpour allowed)
			(footprints allowed)
		)
		(placement
			(enabled no)
			(sheetname "")
		)
		(fill
			(thermal_gap 0.5)
			(thermal_bridge_width 0.5)
			(island_removal_mode 0)
		)
		(polygon
			(pts
				(xy 275.193506 -356.952042) (xy 273.842226 -356.952042) (xy 273.842226 -355.671882) (xy 275.193506 -355.671882)
			)
		)
	)
	(zone
		(layer "F.Cu")
		(hatch none 0.5)
		(connect_pads
			(clearance 0)
		)
		(min_thickness 0.25)
		(keepout
			(tracks allowed)
			(vias allowed)
			(pads allowed)
			(copperpour allowed)
			(footprints not_allowed)
		)
		(placement
			(enabled no)
			(sheetname "")
		)
		(fill
			(thermal_gap 0.5)
			(thermal_bridge_width 0.5)
			(island_removal_mode 0)
		)
		(polygon
			(pts
				(arc
					(start 109.70006 -194.360038)
					(mid 117.700044 -186.360054)
					(end 125.700028 -194.360038)
				)
				(arc
					(start 125.700028 -194.360038)
					(mid 117.700044 -202.360022)
					(end 109.70006 -194.360038)
				)
			)
		)
	)
	(zone
		(layer "F.Cu")
		(hatch none 0.5)
		(connect_pads
			(clearance 0)
		)
		(min_thickness 0.25)
		(keepout
			(tracks allowed)
			(vias allowed)
			(pads allowed)
			(copperpour allowed)
			(footprints allowed)
		)
		(placement
			(enabled no)
			(sheetname "")
		)
		(fill
			(thermal_gap 0.5)
			(thermal_bridge_width 0.5)
			(island_removal_mode 0)
		)
		(polygon
			(pts
				(xy 430.811686 -136.416034) (xy 430.811686 -135.064754) (xy 432.091846 -135.064754) (xy 432.091846 -136.416034)
			)
		)
	)
	(zone
		(layer "F.Cu")
		(hatch none 0.5)
		(connect_pads
			(clearance 0)
		)
		(min_thickness 0.25)
		(keepout
			(tracks allowed)
			(vias allowed)
			(pads allowed)
			(copperpour allowed)
			(footprints allowed)
		)
		(placement
			(enabled no)
			(sheetname "")
		)
		(fill
			(thermal_gap 0.5)
			(thermal_bridge_width 0.5)
			(island_removal_mode 0)
		)
		(polygon
			(pts
				(xy 272.688558 -35.519868) (xy 274.51685 -35.519868) (xy 274.753324 -35.283394) (xy 274.753324 -26.930096)
				(xy 274.51685 -26.693622) (xy 272.86077 -26.693622) (xy 272.688558 -26.865834)
			)
		)
	)
	(zone
		(layer "F.Cu")
		(hatch none 0.5)
		(connect_pads
			(clearance 0)
		)
		(min_thickness 0.25)
		(keepout
			(tracks allowed)
			(vias allowed)
			(pads allowed)
			(copperpour allowed)
			(footprints allowed)
		)
		(placement
			(enabled no)
			(sheetname "")
		)
		(fill
			(thermal_gap 0.5)
			(thermal_bridge_width 0.5)
			(island_removal_mode 0)
		)
		(polygon
			(pts
				(xy 240.853468 -50.241708) (xy 237.93577 -50.241708) (xy 237.72622 -50.451258) (xy 237.72622 -51.06416)
				(xy 240.783618 -51.06416) (xy 240.853468 -50.99431)
			)
		)
	)
	(zone
		(layer "F.Cu")
		(hatch none 0.5)
		(connect_pads
			(clearance 0)
		)
		(min_thickness 0.25)
		(keepout
			(tracks allowed)
			(vias allowed)
			(pads allowed)
			(copperpour allowed)
			(footprints not_allowed)
		)
		(placement
			(enabled no)
			(sheetname "")
		)
		(fill
			(thermal_gap 0.5)
			(thermal_bridge_width 0.5)
			(island_removal_mode 0)
		)
		(polygon
			(pts
				(xy 9.51992 -23.219918) (xy 9.51992 -18.219928) (xy 5.32003 -18.219928) (xy 5.32003 -23.219918)
			)
		)
	)
	(zone
		(layer "F.Cu")
		(hatch none 0.5)
		(connect_pads
			(clearance 0)
		)
		(min_thickness 0.25)
		(keepout
			(tracks allowed)
			(vias allowed)
			(pads allowed)
			(copperpour allowed)
			(footprints allowed)
		)
		(placement
			(enabled no)
			(sheetname "")
		)
		(fill
			(thermal_gap 0.5)
			(thermal_bridge_width 0.5)
			(island_removal_mode 0)
		)
		(polygon
			(pts
				(xy 394.051282 -31.160974) (xy 394.051282 -29.809694) (xy 395.331442 -29.809694) (xy 395.331442 -31.160974)
			)
		)
	)
	(zone
		(layer "F.Cu")
		(hatch none 0.5)
		(connect_pads
			(clearance 0)
		)
		(min_thickness 0.25)
		(keepout
			(tracks allowed)
			(vias allowed)
			(pads allowed)
			(copperpour allowed)
			(footprints allowed)
		)
		(placement
			(enabled no)
			(sheetname "")
		)
		(fill
			(thermal_gap 0.5)
			(thermal_bridge_width 0.5)
			(island_removal_mode 0)
		)
		(polygon
			(pts
				(xy 383.436622 -320.012822) (xy 383.436622 -271.326102) (xy 432.103022 -271.326102) (xy 432.103022 -320.012822)
			)
		)
	)
	(zone
		(layer "F.Cu")
		(hatch none 0.5)
		(connect_pads
			(clearance 0)
		)
		(min_thickness 0.25)
		(keepout
			(tracks not_allowed)
			(vias allowed)
			(pads allowed)
			(copperpour not_allowed)
			(footprints allowed)
		)
		(placement
			(enabled no)
			(sheetname "")
		)
		(fill
			(thermal_gap 0.5)
			(thermal_bridge_width 0.5)
			(island_removal_mode 0)
		)
		(polygon
			(pts
				(arc
					(start 403.06498 -5.999988)
					(mid 400.265138 -8.79983)
					(end 397.465042 -5.999988)
				)
				(arc
					(start 397.465042 -5.999988)
					(mid 400.265138 -3.199892)
					(end 403.06498 -5.999988)
				)
			)
		)
	)
	(zone
		(layer "F.Cu")
		(hatch none 0.5)
		(connect_pads
			(clearance 0)
		)
		(min_thickness 0.25)
		(keepout
			(tracks allowed)
			(vias allowed)
			(pads allowed)
			(copperpour allowed)
			(footprints allowed)
		)
		(placement
			(enabled no)
			(sheetname "")
		)
		(fill
			(thermal_gap 0.5)
			(thermal_bridge_width 0.5)
			(island_removal_mode 0)
		)
		(polygon
			(pts
				(xy 241.578638 -35.458146) (xy 243.087144 -35.458146) (xy 243.178584 -35.366706) (xy 243.178584 -27.564842)
				(xy 242.812824 -27.199082) (xy 241.746278 -27.199082) (xy 241.380518 -27.564842) (xy 241.380518 -35.260026)
			)
		)
	)
	(zone
		(layer "F.Cu")
		(hatch none 0.5)
		(connect_pads
			(clearance 0)
		)
		(min_thickness 0.25)
		(keepout
			(tracks allowed)
			(vias allowed)
			(pads allowed)
			(copperpour allowed)
			(footprints allowed)
		)
		(placement
			(enabled no)
			(sheetname "")
		)
		(fill
			(thermal_gap 0.5)
			(thermal_bridge_width 0.5)
			(island_removal_mode 0)
		)
		(polygon
			(pts
				(xy 126.111 -22.606) (xy 126.111 -21.844) (xy 128.524 -21.844) (xy 128.524 -22.606)
			)
		)
	)
	(zone
		(layer "F.Cu")
		(hatch none 0.5)
		(connect_pads
			(clearance 0)
		)
		(min_thickness 0.25)
		(keepout
			(tracks allowed)
			(vias allowed)
			(pads allowed)
			(copperpour allowed)
			(footprints allowed)
		)
		(placement
			(enabled no)
			(sheetname "")
		)
		(fill
			(thermal_gap 0.5)
			(thermal_bridge_width 0.5)
			(island_removal_mode 0)
		)
		(polygon
			(pts
				(xy 236.969046 -383.273808) (xy 237.65764 -383.273808) (xy 237.743238 -383.18821) (xy 237.743238 -382.775968)
				(xy 237.55223 -382.58496) (xy 236.923834 -382.58496) (xy 236.858302 -382.650492) (xy 236.858302 -383.163064)
			)
		)
	)
	(zone
		(layer "F.Cu")
		(hatch none 0.5)
		(connect_pads
			(clearance 0)
		)
		(min_thickness 0.25)
		(keepout
			(tracks allowed)
			(vias allowed)
			(pads allowed)
			(copperpour allowed)
			(footprints not_allowed)
		)
		(placement
			(enabled no)
			(sheetname "")
		)
		(fill
			(thermal_gap 0.5)
			(thermal_bridge_width 0.5)
			(island_removal_mode 0)
		)
		(polygon
			(pts
				(arc
					(start 356.04069 -232.750106)
					(mid 367.998999 -243.750167)
					(end 379.957076 -232.750106)
				)
				(xy 380.059946 -232.750106) (xy 380.059946 -218.250008)
				(arc
					(start 379.957076 -218.250008)
					(mid 367.998999 -207.2502)
					(end 356.04069 -218.250008)
				)
				(xy 355.940106 -218.250008) (xy 355.940106 -232.750106)
			)
		)
	)
	(zone
		(layer "F.Cu")
		(hatch none 0.5)
		(connect_pads
			(clearance 0)
		)
		(min_thickness 0.25)
		(keepout
			(tracks allowed)
			(vias allowed)
			(pads allowed)
			(copperpour allowed)
			(footprints allowed)
		)
		(placement
			(enabled no)
			(sheetname "")
		)
		(fill
			(thermal_gap 0.5)
			(thermal_bridge_width 0.5)
			(island_removal_mode 0)
		)
		(polygon
			(pts
				(xy 178.054 -22.733) (xy 178.054 -21.717) (xy 180.594 -21.717) (xy 180.594 -22.733)
			)
		)
	)
	(zone
		(layer "F.Cu")
		(hatch none 0.5)
		(connect_pads
			(clearance 0)
		)
		(min_thickness 0.25)
		(keepout
			(tracks allowed)
			(vias allowed)
			(pads allowed)
			(copperpour allowed)
			(footprints allowed)
		)
		(placement
			(enabled no)
			(sheetname "")
		)
		(fill
			(thermal_gap 0.5)
			(thermal_bridge_width 0.5)
			(island_removal_mode 0)
		)
		(polygon
			(pts
				(xy 74.254106 -116.118386) (xy 72.87641 -116.118386) (xy 72.518524 -116.476272) (xy 72.518524 -122.452384)
				(xy 72.518524 -125.525022) (xy 72.638158 -125.644656) (xy 74.468482 -125.644656) (xy 74.951844 -125.161294)
				(xy 74.951844 -122.094498) (xy 74.951844 -116.816124)
			)
		)
	)
	(zone
		(layer "F.Cu")
		(hatch none 0.5)
		(connect_pads
			(clearance 0)
		)
		(min_thickness 0.25)
		(keepout
			(tracks allowed)
			(vias allowed)
			(pads allowed)
			(copperpour allowed)
			(footprints allowed)
		)
		(placement
			(enabled no)
			(sheetname "")
		)
		(fill
			(thermal_gap 0.5)
			(thermal_bridge_width 0.5)
			(island_removal_mode 0)
		)
		(polygon
			(pts
				(xy 140.946632 -344.635582) (xy 139.595352 -344.635582) (xy 139.595352 -343.355422) (xy 140.946632 -343.355422)
			)
		)
	)
	(zone
		(layer "F.Cu")
		(hatch none 0.5)
		(connect_pads
			(clearance 0)
		)
		(min_thickness 0.25)
		(keepout
			(tracks allowed)
			(vias allowed)
			(pads allowed)
			(copperpour allowed)
			(footprints allowed)
		)
		(placement
			(enabled no)
			(sheetname "")
		)
		(fill
			(thermal_gap 0.5)
			(thermal_bridge_width 0.5)
			(island_removal_mode 0)
		)
		(polygon
			(pts
				(xy 66.488564 -35.519868) (xy 68.316856 -35.519868) (xy 68.55333 -35.283394) (xy 68.55333 -26.930096)
				(xy 68.316856 -26.693622) (xy 66.660776 -26.693622) (xy 66.488564 -26.865834)
			)
		)
	)
	(zone
		(layer "F.Cu")
		(hatch none 0.5)
		(connect_pads
			(clearance 0)
		)
		(min_thickness 0.25)
		(keepout
			(tracks allowed)
			(vias allowed)
			(pads allowed)
			(copperpour allowed)
			(footprints allowed)
		)
		(placement
			(enabled no)
			(sheetname "")
		)
		(fill
			(thermal_gap 0.5)
			(thermal_bridge_width 0.5)
			(island_removal_mode 0)
		)
		(polygon
			(pts
				(xy 435.245256 -344.659458) (xy 433.893976 -344.659458) (xy 433.893976 -343.379298) (xy 435.245256 -343.379298)
			)
		)
	)
	(zone
		(layer "F.Cu")
		(hatch none 0.5)
		(connect_pads
			(clearance 0)
		)
		(min_thickness 0.25)
		(keepout
			(tracks allowed)
			(vias allowed)
			(pads allowed)
			(copperpour allowed)
			(footprints allowed)
		)
		(placement
			(enabled no)
			(sheetname "")
		)
		(fill
			(thermal_gap 0.5)
			(thermal_bridge_width 0.5)
			(island_removal_mode 0)
		)
		(polygon
			(pts
				(xy 455.194924 -208.952592) (xy 456.415902 -208.952592) (xy 456.535536 -208.832958) (xy 456.535536 -207.811624)
				(xy 456.367896 -207.643984) (xy 454.731882 -207.643984) (xy 454.731882 -208.48955)
			)
		)
	)
	(zone
		(layer "F.Cu")
		(hatch none 0.5)
		(connect_pads
			(clearance 0)
		)
		(min_thickness 0.25)
		(keepout
			(tracks allowed)
			(vias allowed)
			(pads allowed)
			(copperpour allowed)
			(footprints allowed)
		)
		(placement
			(enabled no)
			(sheetname "")
		)
		(fill
			(thermal_gap 0.5)
			(thermal_bridge_width 0.5)
			(island_removal_mode 0)
		)
		(polygon
			(pts
				(xy 216.059258 -47.3202) (xy 216.059258 -45.5676) (xy 217.837258 -45.5676) (xy 217.837258 -47.3202)
			)
		)
	)
	(zone
		(layer "F.Cu")
		(hatch none 0.5)
		(connect_pads
			(clearance 0)
		)
		(min_thickness 0.25)
		(keepout
			(tracks allowed)
			(vias allowed)
			(pads allowed)
			(copperpour allowed)
			(footprints allowed)
		)
		(placement
			(enabled no)
			(sheetname "")
		)
		(fill
			(thermal_gap 0.5)
			(thermal_bridge_width 0.5)
			(island_removal_mode 0)
		)
		(polygon
			(pts
				(xy 71.803006 -356.952042) (xy 70.451726 -356.952042) (xy 70.451726 -355.671882) (xy 71.803006 -355.671882)
			)
		)
	)
	(zone
		(layer "F.Cu")
		(hatch none 0.5)
		(connect_pads
			(clearance 0)
		)
		(min_thickness 0.25)
		(keepout
			(tracks allowed)
			(vias allowed)
			(pads allowed)
			(copperpour allowed)
			(footprints allowed)
		)
		(placement
			(enabled no)
			(sheetname "")
		)
		(fill
			(thermal_gap 0.5)
			(thermal_bridge_width 0.5)
			(island_removal_mode 0)
		)
		(polygon
			(pts
				(xy 404.70582 -380.846076) (xy 405.816816 -380.846076) (xy 405.94026 -380.722632) (xy 405.94026 -379.545342)
				(xy 405.873712 -379.478794) (xy 404.667974 -379.478794) (xy 404.639526 -379.507242) (xy 404.639526 -380.779782)
			)
		)
	)
	(zone
		(layer "F.Cu")
		(hatch none 0.5)
		(connect_pads
			(clearance 0)
		)
		(min_thickness 0.25)
		(keepout
			(tracks allowed)
			(vias allowed)
			(pads allowed)
			(copperpour allowed)
			(footprints allowed)
		)
		(placement
			(enabled no)
			(sheetname "")
		)
		(fill
			(thermal_gap 0.5)
			(thermal_bridge_width 0.5)
			(island_removal_mode 0)
		)
		(polygon
			(pts
				(xy 81.129886 -350.80575) (xy 79.778606 -350.80575) (xy 79.778606 -349.52559) (xy 81.129886 -349.52559)
			)
		)
	)
	(zone
		(layer "F.Cu")
		(hatch none 0.5)
		(connect_pads
			(clearance 0)
		)
		(min_thickness 0.25)
		(keepout
			(tracks allowed)
			(vias allowed)
			(pads allowed)
			(copperpour allowed)
			(footprints allowed)
		)
		(placement
			(enabled no)
			(sheetname "")
		)
		(fill
			(thermal_gap 0.5)
			(thermal_bridge_width 0.5)
			(island_removal_mode 0)
		)
		(polygon
			(pts
				(xy 447.060066 -46.986444) (xy 448.052444 -46.986444) (xy 448.13728 -46.901608) (xy 448.13728 -46.211744)
				(xy 448.089274 -46.163738) (xy 447.04 -46.163738) (xy 446.972182 -46.231556) (xy 446.972182 -46.89856)
			)
		)
	)
	(zone
		(layer "F.Cu")
		(hatch none 0.5)
		(connect_pads
			(clearance 0)
		)
		(min_thickness 0.25)
		(keepout
			(tracks allowed)
			(vias allowed)
			(pads allowed)
			(copperpour allowed)
			(footprints allowed)
		)
		(placement
			(enabled no)
			(sheetname "")
		)
		(fill
			(thermal_gap 0.5)
			(thermal_bridge_width 0.5)
			(island_removal_mode 0)
		)
		(polygon
			(pts
				(xy 311.53608 -119.799608) (xy 311.53608 -118.448328) (xy 312.81624 -118.448328) (xy 312.81624 -119.799608)
			)
		)
	)
	(zone
		(layer "F.Cu")
		(hatch none 0.5)
		(connect_pads
			(clearance 0)
		)
		(min_thickness 0.25)
		(keepout
			(tracks allowed)
			(vias allowed)
			(pads allowed)
			(copperpour allowed)
			(footprints allowed)
		)
		(placement
			(enabled no)
			(sheetname "")
		)
		(fill
			(thermal_gap 0.5)
			(thermal_bridge_width 0.5)
			(island_removal_mode 0)
		)
		(polygon
			(pts
				(xy 81.978246 -132.816092) (xy 81.978246 -131.464812) (xy 83.258406 -131.464812) (xy 83.258406 -132.816092)
			)
		)
	)
	(zone
		(layer "F.Cu")
		(hatch none 0.5)
		(connect_pads
			(clearance 0)
		)
		(min_thickness 0.25)
		(keepout
			(tracks allowed)
			(vias allowed)
			(pads allowed)
			(copperpour allowed)
			(footprints allowed)
		)
		(placement
			(enabled no)
			(sheetname "")
		)
		(fill
			(thermal_gap 0.5)
			(thermal_bridge_width 0.5)
			(island_removal_mode 0)
		)
		(polygon
			(pts
				(xy 263.22655 -86.703662) (xy 263.751314 -86.703662) (xy 265.37285 -85.082126) (xy 265.37285 -82.061812)
				(xy 264.898632 -81.58734) (xy 264.898632 -80.939132) (xy 264.277348 -80.317848) (xy 263.85901 -79.89951)
				(xy 263.85901 -79.468472) (xy 263.858248 -79.467456) (xy 263.858248 -78.885034) (xy 263.663684 -78.69047)
				(xy 261.50062 -78.69047) (xy 260.29158 -79.89951) (xy 255.691386 -79.89951) (xy 254.796036 -79.89951)
				(xy 253.393448 -81.302098) (xy 253.393448 -82.197448) (xy 253.393448 -85.375496) (xy 253.895352 -85.8774)
				(xy 254.896366 -86.878414) (xy 256.883662 -88.86571) (xy 257.386836 -89.368884) (xy 258.420108 -89.368884)
				(xy 258.923282 -88.86571) (xy 262.463534 -88.86571) (xy 263.22655 -88.102694)
			)
		)
	)
	(zone
		(layer "F.Cu")
		(hatch none 0.5)
		(connect_pads
			(clearance 0)
		)
		(min_thickness 0.25)
		(keepout
			(tracks allowed)
			(vias allowed)
			(pads allowed)
			(copperpour allowed)
			(footprints allowed)
		)
		(placement
			(enabled no)
			(sheetname "")
		)
		(fill
			(thermal_gap 0.5)
			(thermal_bridge_width 0.5)
			(island_removal_mode 0)
		)
		(polygon
			(pts
				(xy 266.684252 -54.008274) (xy 263.766554 -54.008274) (xy 263.557004 -54.217824) (xy 263.557004 -54.830726)
				(xy 266.614402 -54.830726) (xy 266.684252 -54.760876)
			)
		)
	)
	(zone
		(layer "F.Cu")
		(hatch none 0.5)
		(connect_pads
			(clearance 0)
		)
		(min_thickness 0.25)
		(keepout
			(tracks allowed)
			(vias allowed)
			(pads allowed)
			(copperpour allowed)
			(footprints not_allowed)
		)
		(placement
			(enabled no)
			(sheetname "")
		)
		(fill
			(thermal_gap 0.5)
			(thermal_bridge_width 0.5)
			(island_removal_mode 0)
		)
		(polygon
			(pts
				(arc
					(start 6.800342 -309.150004)
					(mid 7.124288 -309.717461)
					(end 7.351522 -310.330088)
				)
				(xy 14.600428 -310.330088) (xy 14.600428 -309.150004)
			)
		)
	)
	(zone
		(layer "F.Cu")
		(hatch none 0.5)
		(connect_pads
			(clearance 0)
		)
		(min_thickness 0.25)
		(keepout
			(tracks allowed)
			(vias allowed)
			(pads allowed)
			(copperpour allowed)
			(footprints allowed)
		)
		(placement
			(enabled no)
			(sheetname "")
		)
		(fill
			(thermal_gap 0.5)
			(thermal_bridge_width 0.5)
			(island_removal_mode 0)
		)
		(polygon
			(pts
				(xy 202.709272 -368.391948) (xy 202.709272 -367.263426) (xy 204.2414 -367.263426) (xy 204.2414 -368.391948)
			)
		)
	)
	(zone
		(layer "F.Cu")
		(hatch none 0.5)
		(connect_pads
			(clearance 0)
		)
		(min_thickness 0.25)
		(keepout
			(tracks allowed)
			(vias allowed)
			(pads allowed)
			(copperpour allowed)
			(footprints allowed)
		)
		(placement
			(enabled no)
			(sheetname "")
		)
		(fill
			(thermal_gap 0.5)
			(thermal_bridge_width 0.5)
			(island_removal_mode 0)
		)
		(polygon
			(pts
				(xy 430.278286 -149.126194) (xy 430.278286 -147.774914) (xy 431.558446 -147.774914) (xy 431.558446 -149.126194)
			)
		)
	)
	(zone
		(layer "F.Cu")
		(hatch none 0.5)
		(connect_pads
			(clearance 0)
		)
		(min_thickness 0.25)
		(keepout
			(tracks allowed)
			(vias allowed)
			(pads allowed)
			(copperpour allowed)
			(footprints not_allowed)
		)
		(placement
			(enabled no)
			(sheetname "")
		)
		(fill
			(thermal_gap 0.5)
			(thermal_bridge_width 0.5)
			(island_removal_mode 0)
		)
		(polygon
			(pts
				(xy 98.620072 -18.150078) (xy 98.620072 -13.150088) (xy 94.419928 -13.150088) (xy 94.419928 -18.150078)
			)
		)
	)
	(zone
		(layer "F.Cu")
		(hatch none 0.5)
		(connect_pads
			(clearance 0)
		)
		(min_thickness 0.25)
		(keepout
			(tracks allowed)
			(vias allowed)
			(pads allowed)
			(copperpour allowed)
			(footprints allowed)
		)
		(placement
			(enabled no)
			(sheetname "")
		)
		(fill
			(thermal_gap 0.5)
			(thermal_bridge_width 0.5)
			(island_removal_mode 0)
		)
		(polygon
			(pts
				(xy 137.091674 -52.800758) (xy 137.091674 -55.718456) (xy 137.301224 -55.928006) (xy 137.914126 -55.928006)
				(xy 137.914126 -52.870608) (xy 137.844276 -52.800758)
			)
		)
	)
	(zone
		(layer "F.Cu")
		(hatch none 0.5)
		(connect_pads
			(clearance 0)
		)
		(min_thickness 0.25)
		(keepout
			(tracks allowed)
			(vias allowed)
			(pads allowed)
			(copperpour allowed)
			(footprints allowed)
		)
		(placement
			(enabled no)
			(sheetname "")
		)
		(fill
			(thermal_gap 0.5)
			(thermal_bridge_width 0.5)
			(island_removal_mode 0)
		)
		(polygon
			(pts
				(xy 246.50192 -385.58216) (xy 246.50192 -382.2573) (xy 249.82678 -382.2573) (xy 249.82678 -385.58216)
			)
		)
	)
	(zone
		(layer "F.Cu")
		(hatch none 0.5)
		(connect_pads
			(clearance 0)
		)
		(min_thickness 0.25)
		(keepout
			(tracks allowed)
			(vias allowed)
			(pads allowed)
			(copperpour allowed)
			(footprints allowed)
		)
		(placement
			(enabled no)
			(sheetname "")
		)
		(fill
			(thermal_gap 0.5)
			(thermal_bridge_width 0.5)
			(island_removal_mode 0)
		)
		(polygon
			(pts
				(xy 390.945624 -350.80575) (xy 389.594344 -350.80575) (xy 389.594344 -349.52559) (xy 390.945624 -349.52559)
			)
		)
	)
	(zone
		(layer "F.Cu")
		(hatch none 0.5)
		(connect_pads
			(clearance 0)
		)
		(min_thickness 0.25)
		(keepout
			(tracks allowed)
			(vias allowed)
			(pads allowed)
			(copperpour allowed)
			(footprints allowed)
		)
		(placement
			(enabled no)
			(sheetname "")
		)
		(fill
			(thermal_gap 0.5)
			(thermal_bridge_width 0.5)
			(island_removal_mode 0)
		)
		(polygon
			(pts
				(xy 300.065186 -350.781874) (xy 298.713906 -350.781874) (xy 298.713906 -349.501714) (xy 300.065186 -349.501714)
			)
		)
	)
	(zone
		(layer "F.Cu")
		(hatch none 0.5)
		(connect_pads
			(clearance 0)
		)
		(min_thickness 0.25)
		(keepout
			(tracks allowed)
			(vias allowed)
			(pads allowed)
			(copperpour allowed)
			(footprints not_allowed)
		)
		(placement
			(enabled no)
			(sheetname "")
		)
		(fill
			(thermal_gap 0.5)
			(thermal_bridge_width 0.5)
			(island_removal_mode 0)
		)
		(polygon
			(pts
				(xy 441.950094 -264.189972) (xy 441.950094 -342.399874) (xy 466.600032 -342.399874) (xy 466.600032 -322.200016)
				(xy 448.449954 -322.200016) (xy 448.449954 -260.439916)
			)
		)
	)
	(zone
		(layer "F.Cu")
		(hatch none 0.5)
		(connect_pads
			(clearance 0)
		)
		(min_thickness 0.25)
		(keepout
			(tracks allowed)
			(vias allowed)
			(pads allowed)
			(copperpour allowed)
			(footprints allowed)
		)
		(placement
			(enabled no)
			(sheetname "")
		)
		(fill
			(thermal_gap 0.5)
			(thermal_bridge_width 0.5)
			(island_removal_mode 0)
		)
		(polygon
			(pts
				(xy 133.881876 -150.189692) (xy 133.881876 -148.437092) (xy 135.659876 -148.437092) (xy 135.659876 -150.189692)
			)
		)
	)
	(zone
		(layer "F.Cu")
		(hatch none 0.5)
		(connect_pads
			(clearance 0)
		)
		(min_thickness 0.25)
		(keepout
			(tracks allowed)
			(vias allowed)
			(pads allowed)
			(copperpour allowed)
			(footprints allowed)
		)
		(placement
			(enabled no)
			(sheetname "")
		)
		(fill
			(thermal_gap 0.5)
			(thermal_bridge_width 0.5)
			(island_removal_mode 0)
		)
		(polygon
			(pts
				(xy 103.857552 -88.311736) (xy 105.586784 -88.311736) (xy 106.00436 -87.89416) (xy 106.00436 -85.747352)
				(xy 105.516934 -85.259926) (xy 104.089708 -85.259926) (xy 103.753158 -85.596476) (xy 103.753158 -85.862922)
				(xy 103.37927 -85.862922) (xy 102.874572 -86.36762) (xy 102.874572 -86.500716) (xy 100.872798 -86.500716)
				(xy 100.412296 -86.961218) (xy 100.412296 -87.886794) (xy 100.837238 -88.311736) (xy 102.98049 -88.311736)
			)
		)
	)
	(zone
		(layer "F.Cu")
		(hatch none 0.5)
		(connect_pads
			(clearance 0)
		)
		(min_thickness 0.25)
		(keepout
			(tracks not_allowed)
			(vias allowed)
			(pads allowed)
			(copperpour not_allowed)
			(footprints allowed)
		)
		(placement
			(enabled no)
			(sheetname "")
		)
		(fill
			(thermal_gap 0.5)
			(thermal_bridge_width 0.5)
			(island_removal_mode 0)
		)
		(polygon
			(pts
				(arc
					(start 203.300076 -98.700082)
					(mid 208.300066 -93.700092)
					(end 213.300056 -98.700082)
				)
				(arc
					(start 213.300056 -98.700082)
					(mid 208.300066 -103.700072)
					(end 203.300076 -98.700082)
				)
			)
		)
		(polygon
			(pts
				(arc
					(start 210.000088 -98.700082)
					(mid 208.300066 -100.400104)
					(end 206.600044 -98.700082)
				)
				(arc
					(start 206.600044 -98.700082)
					(mid 208.300066 -97.00006)
					(end 210.000088 -98.700082)
				)
			)
		)
	)
	(zone
		(layer "F.Cu")
		(hatch none 0.5)
		(connect_pads
			(clearance 0)
		)
		(min_thickness 0.25)
		(keepout
			(tracks allowed)
			(vias allowed)
			(pads allowed)
			(copperpour allowed)
			(footprints allowed)
		)
		(placement
			(enabled no)
			(sheetname "")
		)
		(fill
			(thermal_gap 0.5)
			(thermal_bridge_width 0.5)
			(island_removal_mode 0)
		)
		(polygon
			(pts
				(xy 39.090092 -356.952042) (xy 37.738812 -356.952042) (xy 37.738812 -355.671882) (xy 39.090092 -355.671882)
			)
		)
	)
	(zone
		(layer "F.Cu")
		(hatch none 0.5)
		(connect_pads
			(clearance 0)
		)
		(min_thickness 0.25)
		(keepout
			(tracks allowed)
			(vias allowed)
			(pads allowed)
			(copperpour allowed)
			(footprints allowed)
		)
		(placement
			(enabled no)
			(sheetname "")
		)
		(fill
			(thermal_gap 0.5)
			(thermal_bridge_width 0.5)
			(island_removal_mode 0)
		)
		(polygon
			(pts
				(xy 163.289996 -350.80575) (xy 161.938716 -350.80575) (xy 161.938716 -349.52559) (xy 163.289996 -349.52559)
			)
		)
	)
	(zone
		(layer "F.Cu")
		(hatch none 0.5)
		(connect_pads
			(clearance 0)
		)
		(min_thickness 0.25)
		(keepout
			(tracks allowed)
			(vias allowed)
			(pads allowed)
			(copperpour allowed)
			(footprints allowed)
		)
		(placement
			(enabled no)
			(sheetname "")
		)
		(fill
			(thermal_gap 0.5)
			(thermal_bridge_width 0.5)
			(island_removal_mode 0)
		)
		(polygon
			(pts
				(xy 35.955224 -135.13816) (xy 35.955224 -133.78688) (xy 37.235384 -133.78688) (xy 37.235384 -135.13816)
			)
		)
	)
	(zone
		(layer "F.Cu")
		(hatch none 0.5)
		(connect_pads
			(clearance 0)
		)
		(min_thickness 0.25)
		(keepout
			(tracks not_allowed)
			(vias allowed)
			(pads allowed)
			(copperpour not_allowed)
			(footprints allowed)
		)
		(placement
			(enabled no)
			(sheetname "")
		)
		(fill
			(thermal_gap 0.5)
			(thermal_bridge_width 0.5)
			(island_removal_mode 0)
		)
		(polygon
			(pts
				(arc
					(start 319.600072 -270.89989)
					(mid 321.850004 -268.649958)
					(end 324.099936 -270.89989)
				)
				(arc
					(start 324.099936 -270.89989)
					(mid 321.850004 -273.149822)
					(end 319.600072 -270.89989)
				)
			)
		)
	)
	(zone
		(layer "F.Cu")
		(hatch none 0.5)
		(connect_pads
			(clearance 0)
		)
		(min_thickness 0.25)
		(keepout
			(tracks not_allowed)
			(vias allowed)
			(pads allowed)
			(copperpour not_allowed)
			(footprints allowed)
		)
		(placement
			(enabled no)
			(sheetname "")
		)
		(fill
			(thermal_gap 0.5)
			(thermal_bridge_width 0.5)
			(island_removal_mode 0)
		)
		(polygon
			(pts
				(arc
					(start 464.09991 -398.100042)
					(mid 461.600042 -400.59991)
					(end 459.09992 -398.100042)
				)
				(arc
					(start 459.09992 -398.100042)
					(mid 461.600042 -395.59992)
					(end 464.09991 -398.100042)
				)
			)
		)
	)
	(zone
		(layer "F.Cu")
		(hatch none 0.5)
		(connect_pads
			(clearance 0)
		)
		(min_thickness 0.25)
		(keepout
			(tracks allowed)
			(vias allowed)
			(pads allowed)
			(copperpour allowed)
			(footprints allowed)
		)
		(placement
			(enabled no)
			(sheetname "")
		)
		(fill
			(thermal_gap 0.5)
			(thermal_bridge_width 0.5)
			(island_removal_mode 0)
		)
		(polygon
			(pts
				(xy 278.302466 -350.80575) (xy 276.951186 -350.80575) (xy 276.951186 -349.52559) (xy 278.302466 -349.52559)
			)
		)
	)
	(zone
		(layer "F.Cu")
		(hatch none 0.5)
		(connect_pads
			(clearance 0)
		)
		(min_thickness 0.25)
		(keepout
			(tracks allowed)
			(vias allowed)
			(pads allowed)
			(copperpour allowed)
			(footprints allowed)
		)
		(placement
			(enabled no)
			(sheetname "")
		)
		(fill
			(thermal_gap 0.5)
			(thermal_bridge_width 0.5)
			(island_removal_mode 0)
		)
		(polygon
			(pts
				(xy 128.173988 -127.44831) (xy 128.806448 -127.44831) (xy 128.973834 -127.280924) (xy 128.973834 -124.025406)
				(xy 128.583182 -123.634754) (xy 127.969264 -123.634754) (xy 127.894842 -123.709176) (xy 127.894842 -127.169164)
			)
		)
	)
	(zone
		(layer "F.Cu")
		(hatch none 0.5)
		(connect_pads
			(clearance 0)
		)
		(min_thickness 0.25)
		(keepout
			(tracks allowed)
			(vias allowed)
			(pads allowed)
			(copperpour allowed)
			(footprints allowed)
		)
		(placement
			(enabled no)
			(sheetname "")
		)
		(fill
			(thermal_gap 0.5)
			(thermal_bridge_width 0.5)
			(island_removal_mode 0)
		)
		(polygon
			(pts
				(xy 35.139122 -320.012822) (xy 35.139122 -271.326102) (xy 83.805522 -271.326102) (xy 83.805522 -320.012822)
			)
		)
	)
	(zone
		(layer "F.Cu")
		(hatch none 0.5)
		(connect_pads
			(clearance 0)
		)
		(min_thickness 0.25)
		(keepout
			(tracks not_allowed)
			(vias allowed)
			(pads allowed)
			(copperpour not_allowed)
			(footprints allowed)
		)
		(placement
			(enabled no)
			(sheetname "")
		)
		(fill
			(thermal_gap 0.5)
			(thermal_bridge_width 0.5)
			(island_removal_mode 0)
		)
		(polygon
			(pts
				(arc
					(start 345.015058 -17.999964)
					(mid 342.215216 -20.799806)
					(end 339.41512 -17.999964)
				)
				(arc
					(start 339.41512 -17.999964)
					(mid 342.215216 -15.199868)
					(end 345.015058 -17.999964)
				)
			)
		)
	)
	(zone
		(layer "F.Cu")
		(hatch none 0.5)
		(connect_pads
			(clearance 0)
		)
		(min_thickness 0.25)
		(keepout
			(tracks allowed)
			(vias allowed)
			(pads allowed)
			(copperpour allowed)
			(footprints allowed)
		)
		(placement
			(enabled no)
			(sheetname "")
		)
		(fill
			(thermal_gap 0.5)
			(thermal_bridge_width 0.5)
			(island_removal_mode 0)
		)
		(polygon
			(pts
				(xy 284.520386 -356.952042) (xy 283.169106 -356.952042) (xy 283.169106 -355.671882) (xy 284.520386 -355.671882)
			)
		)
	)
	(zone
		(layer "F.Cu")
		(hatch none 0.5)
		(connect_pads
			(clearance 0)
		)
		(min_thickness 0.25)
		(keepout
			(tracks allowed)
			(vias allowed)
			(pads allowed)
			(copperpour allowed)
			(footprints allowed)
		)
		(placement
			(enabled no)
			(sheetname "")
		)
		(fill
			(thermal_gap 0.5)
			(thermal_bridge_width 0.5)
			(island_removal_mode 0)
		)
		(polygon
			(pts
				(xy 422.809416 -350.80575) (xy 421.458136 -350.80575) (xy 421.458136 -349.52559) (xy 422.809416 -349.52559)
			)
		)
	)
	(zone
		(layer "F.Cu")
		(hatch none 0.5)
		(connect_pads
			(clearance 0)
		)
		(min_thickness 0.25)
		(keepout
			(tracks allowed)
			(vias allowed)
			(pads allowed)
			(copperpour allowed)
			(footprints allowed)
		)
		(placement
			(enabled no)
			(sheetname "")
		)
		(fill
			(thermal_gap 0.5)
			(thermal_bridge_width 0.5)
			(island_removal_mode 0)
		)
		(polygon
			(pts
				(xy 131.619752 -350.80575) (xy 130.268472 -350.80575) (xy 130.268472 -349.52559) (xy 131.619752 -349.52559)
			)
		)
	)
	(zone
		(layer "F.Cu")
		(hatch none 0.5)
		(connect_pads
			(clearance 0)
		)
		(min_thickness 0.25)
		(keepout
			(tracks allowed)
			(vias allowed)
			(pads allowed)
			(copperpour allowed)
			(footprints allowed)
		)
		(placement
			(enabled no)
			(sheetname "")
		)
		(fill
			(thermal_gap 0.5)
			(thermal_bridge_width 0.5)
			(island_removal_mode 0)
		)
		(polygon
			(pts
				(xy 101.6 -393.93622) (xy 101.6 -390.41832) (xy 105.12806 -390.41832) (xy 105.12806 -393.93622)
			)
		)
	)
	(zone
		(layer "F.Cu")
		(hatch none 0.5)
		(connect_pads
			(clearance 0)
		)
		(min_thickness 0.25)
		(keepout
			(tracks allowed)
			(vias allowed)
			(pads allowed)
			(copperpour allowed)
			(footprints allowed)
		)
		(placement
			(enabled no)
			(sheetname "")
		)
		(fill
			(thermal_gap 0.5)
			(thermal_bridge_width 0.5)
			(island_removal_mode 0)
		)
		(polygon
			(pts
				(xy 415.812732 -156.836872) (xy 417.623244 -156.836872) (xy 417.669726 -156.79039) (xy 417.669726 -142.047468)
				(xy 417.524438 -141.90218) (xy 415.772346 -141.90218) (xy 415.696908 -141.977618) (xy 415.696908 -156.721048)
			)
		)
	)
	(zone
		(layer "F.Cu")
		(hatch none 0.5)
		(connect_pads
			(clearance 0)
		)
		(min_thickness 0.25)
		(keepout
			(tracks allowed)
			(vias allowed)
			(pads allowed)
			(copperpour allowed)
			(footprints allowed)
		)
		(placement
			(enabled no)
			(sheetname "")
		)
		(fill
			(thermal_gap 0.5)
			(thermal_bridge_width 0.5)
			(island_removal_mode 0)
		)
		(polygon
			(pts
				(xy 161.85134 -34.76117) (xy 161.85134 -33.40989) (xy 163.1315 -33.40989) (xy 163.1315 -34.76117)
			)
		)
	)
	(zone
		(layer "F.Cu")
		(hatch none 0.5)
		(connect_pads
			(clearance 0)
		)
		(min_thickness 0.25)
		(keepout
			(tracks allowed)
			(vias allowed)
			(pads allowed)
			(copperpour allowed)
			(footprints allowed)
		)
		(placement
			(enabled no)
			(sheetname "")
		)
		(fill
			(thermal_gap 0.5)
			(thermal_bridge_width 0.5)
			(island_removal_mode 0)
		)
		(polygon
			(pts
				(xy 29.763212 -344.659458) (xy 28.411932 -344.659458) (xy 28.411932 -343.379298) (xy 29.763212 -343.379298)
			)
		)
	)
	(zone
		(layer "F.Cu")
		(hatch none 0.5)
		(connect_pads
			(clearance 0)
		)
		(min_thickness 0.25)
		(keepout
			(tracks allowed)
			(vias allowed)
			(pads allowed)
			(copperpour allowed)
			(footprints allowed)
		)
		(placement
			(enabled no)
			(sheetname "")
		)
		(fill
			(thermal_gap 0.5)
			(thermal_bridge_width 0.5)
			(island_removal_mode 0)
		)
		(polygon
			(pts
				(xy 419.700456 -344.659458) (xy 418.349176 -344.659458) (xy 418.349176 -343.379298) (xy 419.700456 -343.379298)
			)
		)
	)
	(zone
		(layer "F.Cu")
		(hatch none 0.5)
		(connect_pads
			(clearance 0)
		)
		(min_thickness 0.25)
		(keepout
			(tracks allowed)
			(vias allowed)
			(pads allowed)
			(copperpour allowed)
			(footprints allowed)
		)
		(placement
			(enabled no)
			(sheetname "")
		)
		(fill
			(thermal_gap 0.5)
			(thermal_bridge_width 0.5)
			(island_removal_mode 0)
		)
		(polygon
			(pts
				(xy 242.189 -22.606) (xy 242.189 -21.971) (xy 244.729 -21.971) (xy 244.729 -22.606)
			)
		)
	)
	(zone
		(layer "F.Cu")
		(hatch none 0.5)
		(connect_pads
			(clearance 0)
		)
		(min_thickness 0.25)
		(keepout
			(tracks allowed)
			(vias allowed)
			(pads allowed)
			(copperpour allowed)
			(footprints allowed)
		)
		(placement
			(enabled no)
			(sheetname "")
		)
		(fill
			(thermal_gap 0.5)
			(thermal_bridge_width 0.5)
			(island_removal_mode 0)
		)
		(polygon
			(pts
				(xy 55.377588 -371.621812) (xy 56.214518 -371.621812) (xy 56.704992 -371.621812) (xy 56.705246 -371.621558)
				(xy 56.705246 -370.173758) (xy 56.584596 -370.053108) (xy 56.275224 -370.053108) (xy 56.244998 -370.083334)
				(xy 55.400448 -370.083334) (xy 55.31739 -370.166392) (xy 55.31739 -371.561614)
			)
		)
	)
	(zone
		(layer "F.Cu")
		(hatch none 0.5)
		(connect_pads
			(clearance 0)
		)
		(min_thickness 0.25)
		(keepout
			(tracks allowed)
			(vias allowed)
			(pads allowed)
			(copperpour allowed)
			(footprints not_allowed)
		)
		(placement
			(enabled no)
			(sheetname "")
		)
		(fill
			(thermal_gap 0.5)
			(thermal_bridge_width 0.5)
			(island_removal_mode 0)
		)
		(polygon
			(pts
				(xy 357.26497 -40.120062) (xy 365.264954 -40.120062) (xy 365.264954 -13.850112) (xy 357.26497 -13.850112)
			)
		)
	)
	(zone
		(layer "F.Cu")
		(hatch none 0.5)
		(connect_pads
			(clearance 0)
		)
		(min_thickness 0.25)
		(keepout
			(tracks allowed)
			(vias allowed)
			(pads allowed)
			(copperpour allowed)
			(footprints allowed)
		)
		(placement
			(enabled no)
			(sheetname "")
		)
		(fill
			(thermal_gap 0.5)
			(thermal_bridge_width 0.5)
			(island_removal_mode 0)
		)
		(polygon
			(pts
				(xy 417.409122 -32.954468) (xy 417.409122 -31.603188) (xy 418.689282 -31.603188) (xy 418.689282 -32.954468)
			)
		)
	)
	(zone
		(layer "F.Cu")
		(hatch none 0.5)
		(connect_pads
			(clearance 0)
		)
		(min_thickness 0.25)
		(keepout
			(tracks allowed)
			(vias allowed)
			(pads allowed)
			(copperpour allowed)
			(footprints allowed)
		)
		(placement
			(enabled no)
			(sheetname "")
		)
		(fill
			(thermal_gap 0.5)
			(thermal_bridge_width 0.5)
			(island_removal_mode 0)
		)
		(polygon
			(pts
				(xy 209.715608 -118.428516) (xy 209.715608 -121.346214) (xy 209.925158 -121.555764) (xy 210.53806 -121.555764)
				(xy 210.53806 -118.498366) (xy 210.46821 -118.428516)
			)
		)
	)
	(zone
		(layer "F.Cu")
		(hatch none 0.5)
		(connect_pads
			(clearance 0)
		)
		(min_thickness 0.25)
		(keepout
			(tracks allowed)
			(vias allowed)
			(pads allowed)
			(copperpour allowed)
			(footprints not_allowed)
		)
		(placement
			(enabled no)
			(sheetname "")
		)
		(fill
			(thermal_gap 0.5)
			(thermal_bridge_width 0.5)
			(island_removal_mode 0)
		)
		(polygon
			(pts
				(xy 86.965028 -40.120062) (xy 94.965012 -40.120062) (xy 94.965012 -13.850112) (xy 86.965028 -13.850112)
			)
		)
	)
	(zone
		(layer "F.Cu")
		(hatch none 0.5)
		(connect_pads
			(clearance 0)
		)
		(min_thickness 0.25)
		(keepout
			(tracks allowed)
			(vias allowed)
			(pads allowed)
			(copperpour allowed)
			(footprints allowed)
		)
		(placement
			(enabled no)
			(sheetname "")
		)
		(fill
			(thermal_gap 0.5)
			(thermal_bridge_width 0.5)
			(island_removal_mode 0)
		)
		(polygon
			(pts
				(xy 391.409174 -32.954468) (xy 391.409174 -31.603188) (xy 392.689334 -31.603188) (xy 392.689334 -32.954468)
			)
		)
	)
	(zone
		(layer "F.Cu")
		(hatch none 0.5)
		(connect_pads
			(clearance 0)
		)
		(min_thickness 0.25)
		(keepout
			(tracks allowed)
			(vias allowed)
			(pads allowed)
			(copperpour allowed)
			(footprints not_allowed)
		)
		(placement
			(enabled no)
			(sheetname "")
		)
		(fill
			(thermal_gap 0.5)
			(thermal_bridge_width 0.5)
			(island_removal_mode 0)
		)
		(polygon
			(pts
				(arc
					(start 456.79995 -84.70011)
					(mid 448.799966 -92.700094)
					(end 440.799982 -84.70011)
				)
				(arc
					(start 440.799982 -84.70011)
					(mid 448.799966 -76.700126)
					(end 456.79995 -84.70011)
				)
			)
		)
	)
	(zone
		(layer "F.Cu")
		(hatch none 0.5)
		(connect_pads
			(clearance 0)
		)
		(min_thickness 0.25)
		(keepout
			(tracks allowed)
			(vias allowed)
			(pads allowed)
			(copperpour allowed)
			(footprints allowed)
		)
		(placement
			(enabled no)
			(sheetname "")
		)
		(fill
			(thermal_gap 0.5)
			(thermal_bridge_width 0.5)
			(island_removal_mode 0)
		)
		(polygon
			(pts
				(xy 81.978246 -149.126194) (xy 81.978246 -147.774914) (xy 83.258406 -147.774914) (xy 83.258406 -149.126194)
			)
		)
	)
	(zone
		(layer "F.Cu")
		(hatch none 0.5)
		(connect_pads
			(clearance 0)
		)
		(min_thickness 0.25)
		(keepout
			(tracks allowed)
			(vias allowed)
			(pads allowed)
			(copperpour allowed)
			(footprints not_allowed)
		)
		(placement
			(enabled no)
			(sheetname "")
		)
		(fill
			(thermal_gap 0.5)
			(thermal_bridge_width 0.5)
			(island_removal_mode 0)
		)
		(polygon
			(pts
				(arc
					(start 200.699878 -385.20624)
					(mid 207.38018 -392.539971)
					(end 201.789284 -400.734784)
				)
				(arc
					(start 265.810746 -400.734784)
					(mid 260.219416 -392.54008)
					(end 266.899898 -385.20624)
				)
				(xy 266.899898 -382.400048) (xy 200.699878 -382.400048)
			)
		)
	)
	(zone
		(layer "F.Cu")
		(hatch none 0.5)
		(connect_pads
			(clearance 0)
		)
		(min_thickness 0.25)
		(keepout
			(tracks allowed)
			(vias allowed)
			(pads allowed)
			(copperpour allowed)
			(footprints allowed)
		)
		(placement
			(enabled no)
			(sheetname "")
		)
		(fill
			(thermal_gap 0.5)
			(thermal_bridge_width 0.5)
			(island_removal_mode 0)
		)
		(polygon
			(pts
				(xy 268.155166 -120.328182) (xy 268.155166 -118.976902) (xy 269.435326 -118.976902) (xy 269.435326 -120.328182)
			)
		)
	)
	(zone
		(layer "F.Cu")
		(hatch none 0.5)
		(connect_pads
			(clearance 0)
		)
		(min_thickness 0.25)
		(keepout
			(tracks allowed)
			(vias allowed)
			(pads allowed)
			(copperpour allowed)
			(footprints allowed)
		)
		(placement
			(enabled no)
			(sheetname "")
		)
		(fill
			(thermal_gap 0.5)
			(thermal_bridge_width 0.5)
			(island_removal_mode 0)
		)
		(polygon
			(pts
				(xy 306.602384 -141.87297) (xy 304.791872 -141.87297) (xy 304.74539 -141.919452) (xy 304.74539 -156.662374)
				(xy 304.890678 -156.807662) (xy 306.64277 -156.807662) (xy 306.718208 -156.732224) (xy 306.718208 -141.988794)
			)
		)
	)
	(zone
		(layer "F.Cu")
		(hatch none 0.5)
		(connect_pads
			(clearance 0)
		)
		(min_thickness 0.25)
		(keepout
			(tracks allowed)
			(vias allowed)
			(pads allowed)
			(copperpour allowed)
			(footprints allowed)
		)
		(placement
			(enabled no)
			(sheetname "")
		)
		(fill
			(thermal_gap 0.5)
			(thermal_bridge_width 0.5)
			(island_removal_mode 0)
		)
		(polygon
			(pts
				(xy 131.395978 -178.99888) (xy 131.395978 -177.24628) (xy 133.173978 -177.24628) (xy 133.173978 -178.99888)
			)
		)
	)
	(zone
		(layer "F.Cu")
		(hatch none 0.5)
		(connect_pads
			(clearance 0)
		)
		(min_thickness 0.25)
		(keepout
			(tracks allowed)
			(vias allowed)
			(pads allowed)
			(copperpour allowed)
			(footprints allowed)
		)
		(placement
			(enabled no)
			(sheetname "")
		)
		(fill
			(thermal_gap 0.5)
			(thermal_bridge_width 0.5)
			(island_removal_mode 0)
		)
		(polygon
			(pts
				(xy 48.416972 -344.635582) (xy 47.065692 -344.635582) (xy 47.065692 -343.355422) (xy 48.416972 -343.355422)
			)
		)
	)
	(zone
		(layer "F.Cu")
		(hatch none 0.5)
		(connect_pads
			(clearance 0)
		)
		(min_thickness 0.25)
		(keepout
			(tracks allowed)
			(vias allowed)
			(pads allowed)
			(copperpour allowed)
			(footprints allowed)
		)
		(placement
			(enabled no)
			(sheetname "")
		)
		(fill
			(thermal_gap 0.5)
			(thermal_bridge_width 0.5)
			(island_removal_mode 0)
		)
		(polygon
			(pts
				(xy 255.832864 -230.378) (xy 255.832864 -220.599) (xy 257.864864 -220.599) (xy 257.864864 -230.378)
			)
		)
	)
	(zone
		(layer "F.Cu")
		(hatch none 0.5)
		(connect_pads
			(clearance 0)
		)
		(min_thickness 0.25)
		(keepout
			(tracks not_allowed)
			(vias allowed)
			(pads allowed)
			(copperpour not_allowed)
			(footprints allowed)
		)
		(placement
			(enabled no)
			(sheetname "")
		)
		(fill
			(thermal_gap 0.5)
			(thermal_bridge_width 0.5)
			(island_removal_mode 0)
		)
		(polygon
			(pts
				(arc
					(start 25.150064 -320.900044)
					(mid 29.650182 -316.399926)
					(end 34.150046 -320.900044)
				)
				(arc
					(start 34.150046 -320.900044)
					(mid 29.650182 -325.399908)
					(end 25.150064 -320.900044)
				)
			)
		)
	)
	(zone
		(layer "F.Cu")
		(hatch none 0.5)
		(connect_pads
			(clearance 0)
		)
		(min_thickness 0.25)
		(keepout
			(tracks allowed)
			(vias allowed)
			(pads allowed)
			(copperpour allowed)
			(footprints not_allowed)
		)
		(placement
			(enabled no)
			(sheetname "")
		)
		(fill
			(thermal_gap 0.5)
			(thermal_bridge_width 0.5)
			(island_removal_mode 0)
		)
		(polygon
			(pts
				(arc
					(start 269.899892 -370.954046)
					(mid 279.756208 -377.190565)
					(end 272.91284 -386.635498)
				)
				(arc
					(start 272.91284 -386.635498)
					(mid 276.093342 -394.400705)
					(end 270.589248 -400.734784)
				)
				(xy 273.079972 -400.734784) (xy 273.079972 -417.58997) (xy 283.03982 -417.58997) (xy 283.03982 -361.790234)
				(xy 312.139838 -361.790234) (xy 312.139838 -394.269976) (xy 327.039986 -394.269976) (xy 327.039986 -361.790234)
				(xy 356.140004 -361.790234)
				(arc
					(start 356.140004 -404.684738)
					(mid 363.589989 -399.600023)
					(end 371.039898 -404.684992)
				)
				(xy 371.039898 -361.790234) (xy 400.139916 -361.790234) (xy 400.139916 -394.269976) (xy 415.03981 -394.269976)
				(xy 415.03981 -361.790234) (xy 444.139828 -361.790234) (xy 444.139828 -417.58997)
				(arc
					(start 465.600034 -417.58997)
					(mid 466.307139 -417.297077)
					(end 466.600032 -416.589972)
				)
				(arc
					(start 466.600032 -413.844994)
					(mid 458.135878 -414.811048)
					(end 453.600058 -407.599896)
				)
				(arc
					(start 453.600058 -407.599896)
					(mid 455.33165 -402.629282)
					(end 459.77683 -399.810478)
				)
				(arc
					(start 459.77683 -399.810478)
					(mid 459.275303 -399.01979)
					(end 459.09992 -398.100042)
				)
				(arc
					(start 459.09992 -398.100042)
					(mid 461.600042 -395.59992)
					(end 464.09991 -398.100042)
				)
				(arc
					(start 464.09991 -398.100042)
					(mid 463.924585 -399.019737)
					(end 463.423254 -399.810478)
				)
				(arc
					(start 463.423254 -399.810478)
					(mid 465.09795 -400.405251)
					(end 466.600032 -401.355052)
				)
				(xy 466.600032 -342.399874) (xy 441.950094 -342.399874) (xy 441.950094 -329.3999) (xy 373.949976 -329.3999)
				(xy 373.949976 -342.399874) (xy 325.849996 -342.399874) (xy 325.849996 -329.3999) (xy 269.899892 -329.3999)
			)
		)
	)
	(zone
		(layer "F.Cu")
		(hatch none 0.5)
		(connect_pads
			(clearance 0)
		)
		(min_thickness 0.25)
		(keepout
			(tracks allowed)
			(vias allowed)
			(pads allowed)
			(copperpour allowed)
			(footprints allowed)
		)
		(placement
			(enabled no)
			(sheetname "")
		)
		(fill
			(thermal_gap 0.5)
			(thermal_bridge_width 0.5)
			(island_removal_mode 0)
		)
		(polygon
			(pts
				(xy 72.680068 -136.909302) (xy 74.76744 -136.909302) (xy 75.08748 -136.589262) (xy 75.08748 -129.185162)
				(xy 72.742552 -129.185162) (xy 72.66432 -129.263394) (xy 72.66432 -136.893554)
			)
		)
	)
	(zone
		(layer "F.Cu")
		(hatch none 0.5)
		(connect_pads
			(clearance 0)
		)
		(min_thickness 0.25)
		(keepout
			(tracks allowed)
			(vias allowed)
			(pads allowed)
			(copperpour allowed)
			(footprints allowed)
		)
		(placement
			(enabled no)
			(sheetname "")
		)
		(fill
			(thermal_gap 0.5)
			(thermal_bridge_width 0.5)
			(island_removal_mode 0)
		)
		(polygon
			(pts
				(xy 422.702482 -141.87297) (xy 420.89197 -141.87297) (xy 420.845488 -141.919452) (xy 420.845488 -156.662374)
				(xy 420.990776 -156.807662) (xy 422.742868 -156.807662) (xy 422.818306 -156.732224) (xy 422.818306 -141.988794)
			)
		)
	)
	(zone
		(layer "F.Cu")
		(hatch none 0.5)
		(connect_pads
			(clearance 0)
		)
		(min_thickness 0.25)
		(keepout
			(tracks allowed)
			(vias allowed)
			(pads allowed)
			(copperpour allowed)
			(footprints allowed)
		)
		(placement
			(enabled no)
			(sheetname "")
		)
		(fill
			(thermal_gap 0.5)
			(thermal_bridge_width 0.5)
			(island_removal_mode 0)
		)
		(polygon
			(pts
				(xy 318.684148 -54.008274) (xy 315.76645 -54.008274) (xy 315.5569 -54.217824) (xy 315.5569 -54.830726)
				(xy 318.614298 -54.830726) (xy 318.684148 -54.760876)
			)
		)
	)
	(zone
		(layer "F.Cu")
		(hatch none 0.5)
		(connect_pads
			(clearance 0)
		)
		(min_thickness 0.25)
		(keepout
			(tracks allowed)
			(vias allowed)
			(pads allowed)
			(copperpour allowed)
			(footprints allowed)
		)
		(placement
			(enabled no)
			(sheetname "")
		)
		(fill
			(thermal_gap 0.5)
			(thermal_bridge_width 0.5)
			(island_removal_mode 0)
		)
		(polygon
			(pts
				(xy 108.783628 -88.799416) (xy 111.162592 -88.799416) (xy 111.307626 -88.94445) (xy 111.307626 -89.9541)
				(xy 111.017558 -90.244168) (xy 110.637828 -90.623898) (xy 108.99521 -90.623898) (xy 108.61548 -90.244168)
				(xy 108.568998 -90.197686) (xy 108.568998 -89.014046)
			)
		)
	)
	(zone
		(layer "F.Cu")
		(hatch none 0.5)
		(connect_pads
			(clearance 0)
		)
		(min_thickness 0.25)
		(keepout
			(tracks allowed)
			(vias allowed)
			(pads allowed)
			(copperpour allowed)
			(footprints allowed)
		)
		(placement
			(enabled no)
			(sheetname "")
		)
		(fill
			(thermal_gap 0.5)
			(thermal_bridge_width 0.5)
			(island_removal_mode 0)
		)
		(polygon
			(pts
				(xy 73.959212 -47.3202) (xy 73.959212 -45.5676) (xy 75.737212 -45.5676) (xy 75.737212 -47.3202)
			)
		)
	)
	(zone
		(layer "F.Cu")
		(hatch none 0.5)
		(connect_pads
			(clearance 0)
		)
		(min_thickness 0.25)
		(keepout
			(tracks allowed)
			(vias allowed)
			(pads allowed)
			(copperpour allowed)
			(footprints allowed)
		)
		(placement
			(enabled no)
			(sheetname "")
		)
		(fill
			(thermal_gap 0.5)
			(thermal_bridge_width 0.5)
			(island_removal_mode 0)
		)
		(polygon
			(pts
				(xy 448.74942 -268.10208) (xy 448.74942 -265.98372) (xy 450.40296 -265.98372) (xy 450.40296 -268.10208)
			)
		)
	)
	(zone
		(layer "F.Cu")
		(hatch none 0.5)
		(connect_pads
			(clearance 0)
		)
		(min_thickness 0.25)
		(keepout
			(tracks allowed)
			(vias allowed)
			(pads allowed)
			(copperpour allowed)
			(footprints allowed)
		)
		(placement
			(enabled no)
			(sheetname "")
		)
		(fill
			(thermal_gap 0.5)
			(thermal_bridge_width 0.5)
			(island_removal_mode 0)
		)
		(polygon
			(pts
				(xy 387.836664 -344.659458) (xy 386.485384 -344.659458) (xy 386.485384 -343.379298) (xy 387.836664 -343.379298)
			)
		)
	)
	(zone
		(layer "F.Cu")
		(hatch none 0.5)
		(connect_pads
			(clearance 0)
		)
		(min_thickness 0.25)
		(keepout
			(tracks allowed)
			(vias allowed)
			(pads allowed)
			(copperpour allowed)
			(footprints allowed)
		)
		(placement
			(enabled no)
			(sheetname "")
		)
		(fill
			(thermal_gap 0.5)
			(thermal_bridge_width 0.5)
			(island_removal_mode 0)
		)
		(polygon
			(pts
				(xy 17.109186 -29.354526) (xy 17.109186 -28.003246) (xy 18.389346 -28.003246) (xy 18.389346 -29.354526)
			)
		)
	)
	(zone
		(layer "F.Cu")
		(hatch none 0.5)
		(connect_pads
			(clearance 0)
		)
		(min_thickness 0.25)
		(keepout
			(tracks not_allowed)
			(vias allowed)
			(pads allowed)
			(copperpour not_allowed)
			(footprints allowed)
		)
		(placement
			(enabled no)
			(sheetname "")
		)
		(fill
			(thermal_gap 0.5)
			(thermal_bridge_width 0.5)
			(island_removal_mode 0)
		)
		(polygon
			(pts
				(arc
					(start 95.899986 -289.820096)
					(mid 99.15017 -286.569912)
					(end 102.4001 -289.820096)
				)
				(arc
					(start 102.4001 -289.820096)
					(mid 99.15017 -293.070026)
					(end 95.899986 -289.820096)
				)
			)
		)
	)
	(zone
		(layer "F.Cu")
		(hatch none 0.5)
		(connect_pads
			(clearance 0)
		)
		(min_thickness 0.25)
		(keepout
			(tracks allowed)
			(vias allowed)
			(pads allowed)
			(copperpour allowed)
			(footprints not_allowed)
		)
		(placement
			(enabled no)
			(sheetname "")
		)
		(fill
			(thermal_gap 0.5)
			(thermal_bridge_width 0.5)
			(island_removal_mode 0)
		)
		(polygon
			(pts
				(xy 373.949976 -329.3999) (xy 441.950094 -329.3999) (xy 441.950094 -262.400034) (xy 373.949976 -262.400034)
			)
		)
	)
	(zone
		(layer "F.Cu")
		(hatch none 0.5)
		(connect_pads
			(clearance 0)
		)
		(min_thickness 0.25)
		(keepout
			(tracks allowed)
			(vias allowed)
			(pads allowed)
			(copperpour allowed)
			(footprints allowed)
		)
		(placement
			(enabled no)
			(sheetname "")
		)
		(fill
			(thermal_gap 0.5)
			(thermal_bridge_width 0.5)
			(island_removal_mode 0)
		)
		(polygon
			(pts
				(xy 241.255042 -236.605064) (xy 241.61242 -236.605064) (xy 241.738658 -236.478826) (xy 241.738658 -235.41609)
				(xy 241.688366 -235.365798) (xy 241.270028 -235.365798) (xy 241.18951 -235.446316) (xy 241.18951 -236.539532)
			)
		)
	)
	(zone
		(layer "F.Cu")
		(hatch none 0.5)
		(connect_pads
			(clearance 0)
		)
		(min_thickness 0.25)
		(keepout
			(tracks allowed)
			(vias allowed)
			(pads allowed)
			(copperpour allowed)
			(footprints allowed)
		)
		(placement
			(enabled no)
			(sheetname "")
		)
		(fill
			(thermal_gap 0.5)
			(thermal_bridge_width 0.5)
			(island_removal_mode 0)
		)
		(polygon
			(pts
				(xy 119.183912 -350.80575) (xy 117.832632 -350.80575) (xy 117.832632 -349.52559) (xy 119.183912 -349.52559)
			)
		)
	)
	(zone
		(layer "F.Cu")
		(hatch none 0.5)
		(connect_pads
			(clearance 0)
		)
		(min_thickness 0.25)
		(keepout
			(tracks allowed)
			(vias allowed)
			(pads allowed)
			(copperpour allowed)
			(footprints allowed)
		)
		(placement
			(enabled no)
			(sheetname "")
		)
		(fill
			(thermal_gap 0.5)
			(thermal_bridge_width 0.5)
			(island_removal_mode 0)
		)
		(polygon
			(pts
				(xy 74.911966 -350.80575) (xy 73.560686 -350.80575) (xy 73.560686 -349.52559) (xy 74.911966 -349.52559)
			)
		)
	)
	(zone
		(layer "F.Cu")
		(hatch none 0.5)
		(connect_pads
			(clearance 0)
		)
		(min_thickness 0.25)
		(keepout
			(tracks not_allowed)
			(vias allowed)
			(pads allowed)
			(copperpour not_allowed)
			(footprints allowed)
		)
		(placement
			(enabled no)
			(sheetname "")
		)
		(fill
			(thermal_gap 0.5)
			(thermal_bridge_width 0.5)
			(island_removal_mode 0)
		)
		(polygon
			(pts
				(xy 253.322836 -215.467692) (xy 253.399036 -215.467692) (xy 253.399036 -212.521292) (xy 253.451868 -212.521292)
				(xy 253.451868 -212.419692) (xy 253.322836 -212.419692)
			)
		)
	)
	(zone
		(layer "F.Cu")
		(hatch none 0.5)
		(connect_pads
			(clearance 0)
		)
		(min_thickness 0.25)
		(keepout
			(tracks allowed)
			(vias allowed)
			(pads allowed)
			(copperpour allowed)
			(footprints allowed)
		)
		(placement
			(enabled no)
			(sheetname "")
		)
		(fill
			(thermal_gap 0.5)
			(thermal_bridge_width 0.5)
			(island_removal_mode 0)
		)
		(polygon
			(pts
				(xy 329.126088 -356.952042) (xy 327.774808 -356.952042) (xy 327.774808 -355.671882) (xy 329.126088 -355.671882)
			)
		)
	)
	(zone
		(layer "F.Cu")
		(hatch none 0.5)
		(connect_pads
			(clearance 0)
		)
		(min_thickness 0.25)
		(keepout
			(tracks allowed)
			(vias allowed)
			(pads allowed)
			(copperpour allowed)
			(footprints not_allowed)
		)
		(placement
			(enabled no)
			(sheetname "")
		)
		(fill
			(thermal_gap 0.5)
			(thermal_bridge_width 0.5)
			(island_removal_mode 0)
		)
		(polygon
			(pts
				(xy 289.520122 -23.219918) (xy 293.720012 -23.219918) (xy 293.720012 -18.219928) (xy 289.520122 -18.219928)
			)
		)
	)
	(zone
		(layer "F.Cu")
		(hatch none 0.5)
		(connect_pads
			(clearance 0)
		)
		(min_thickness 0.25)
		(keepout
			(tracks allowed)
			(vias allowed)
			(pads allowed)
			(copperpour allowed)
			(footprints allowed)
		)
		(placement
			(enabled no)
			(sheetname "")
		)
		(fill
			(thermal_gap 0.5)
			(thermal_bridge_width 0.5)
			(island_removal_mode 0)
		)
		(polygon
			(pts
				(xy 197.488556 -344.635582) (xy 196.137276 -344.635582) (xy 196.137276 -343.355422) (xy 197.488556 -343.355422)
			)
		)
	)
	(zone
		(layer "F.Cu")
		(hatch none 0.5)
		(connect_pads
			(clearance 0)
		)
		(min_thickness 0.25)
		(keepout
			(tracks allowed)
			(vias allowed)
			(pads allowed)
			(copperpour allowed)
			(footprints allowed)
		)
		(placement
			(enabled no)
			(sheetname "")
		)
		(fill
			(thermal_gap 0.5)
			(thermal_bridge_width 0.5)
			(island_removal_mode 0)
		)
		(polygon
			(pts
				(xy 430.278286 -152.726136) (xy 430.278286 -151.374856) (xy 431.558446 -151.374856) (xy 431.558446 -152.726136)
			)
		)
	)
	(zone
		(layer "F.Cu")
		(hatch none 0.5)
		(connect_pads
			(clearance 0)
		)
		(min_thickness 0.25)
		(keepout
			(tracks not_allowed)
			(vias allowed)
			(pads allowed)
			(copperpour not_allowed)
			(footprints allowed)
		)
		(placement
			(enabled no)
			(sheetname "")
		)
		(fill
			(thermal_gap 0.5)
			(thermal_bridge_width 0.5)
			(island_removal_mode 0)
		)
		(polygon
			(pts
				(xy 214.719916 -18.150078) (xy 214.719916 -13.150088) (xy 210.520026 -13.150088) (xy 210.520026 -18.150078)
			)
		)
	)
	(zone
		(layer "F.Cu")
		(hatch none 0.5)
		(connect_pads
			(clearance 0)
		)
		(min_thickness 0.25)
		(keepout
			(tracks not_allowed)
			(vias allowed)
			(pads allowed)
			(copperpour not_allowed)
			(footprints allowed)
		)
		(placement
			(enabled no)
			(sheetname "")
		)
		(fill
			(thermal_gap 0.5)
			(thermal_bridge_width 0.5)
			(island_removal_mode 0)
		)
		(polygon
			(pts
				(arc
					(start 211.758022 -347.400118)
					(mid 215.758014 -343.400126)
					(end 219.758006 -347.400118)
				)
				(arc
					(start 219.758006 -347.400118)
					(mid 215.758014 -351.40011)
					(end 211.758022 -347.400118)
				)
			)
		)
	)
	(zone
		(layer "F.Cu")
		(hatch none 0.5)
		(connect_pads
			(clearance 0)
		)
		(min_thickness 0.25)
		(keepout
			(tracks allowed)
			(vias allowed)
			(pads allowed)
			(copperpour allowed)
			(footprints allowed)
		)
		(placement
			(enabled no)
			(sheetname "")
		)
		(fill
			(thermal_gap 0.5)
			(thermal_bridge_width 0.5)
			(island_removal_mode 0)
		)
		(polygon
			(pts
				(xy 344.670888 -356.928166) (xy 343.319608 -356.928166) (xy 343.319608 -355.648006) (xy 344.670888 -355.648006)
			)
		)
	)
	(zone
		(layer "F.Cu")
		(hatch none 0.5)
		(connect_pads
			(clearance 0)
		)
		(min_thickness 0.25)
		(keepout
			(tracks allowed)
			(vias allowed)
			(pads allowed)
			(copperpour allowed)
			(footprints not_allowed)
		)
		(placement
			(enabled no)
			(sheetname "")
		)
		(fill
			(thermal_gap 0.5)
			(thermal_bridge_width 0.5)
			(island_removal_mode 0)
		)
		(polygon
			(pts
				(xy 216.250012 -303.980088) (xy 248.333514 -303.980088)
				(arc
					(start 248.350024 -297.369992)
					(mid 249.187746 -294.920506)
					(end 251.350018 -293.497)
				)
				(xy 251.350018 -258.739894) (xy 233.799888 -245.483126) (xy 216.250012 -258.739894)
			)
		)
	)
	(zone
		(layer "F.Cu")
		(hatch none 0.5)
		(connect_pads
			(clearance 0)
		)
		(min_thickness 0.25)
		(keepout
			(tracks allowed)
			(vias allowed)
			(pads allowed)
			(copperpour allowed)
			(footprints allowed)
		)
		(placement
			(enabled no)
			(sheetname "")
		)
		(fill
			(thermal_gap 0.5)
			(thermal_bridge_width 0.5)
			(island_removal_mode 0)
		)
		(polygon
			(pts
				(xy 448.2592 -47.3202) (xy 448.2592 -45.5676) (xy 450.0372 -45.5676) (xy 450.0372 -47.3202)
			)
		)
	)
	(zone
		(layer "F.Cu")
		(hatch none 0.5)
		(connect_pads
			(clearance 0)
		)
		(min_thickness 0.25)
		(keepout
			(tracks not_allowed)
			(vias allowed)
			(pads allowed)
			(copperpour not_allowed)
			(footprints allowed)
		)
		(placement
			(enabled no)
			(sheetname "")
		)
		(fill
			(thermal_gap 0.5)
			(thermal_bridge_width 0.5)
			(island_removal_mode 0)
		)
		(polygon
			(pts
				(arc
					(start 259.599938 -270.89989)
					(mid 261.850124 -268.649704)
					(end 264.100056 -270.89989)
				)
				(arc
					(start 264.100056 -270.89989)
					(mid 261.850124 -273.149822)
					(end 259.599938 -270.89989)
				)
			)
		)
	)
	(zone
		(layer "F.Cu")
		(hatch none 0.5)
		(connect_pads
			(clearance 0)
		)
		(min_thickness 0.25)
		(keepout
			(tracks allowed)
			(vias allowed)
			(pads allowed)
			(copperpour allowed)
			(footprints allowed)
		)
		(placement
			(enabled no)
			(sheetname "")
		)
		(fill
			(thermal_gap 0.5)
			(thermal_bridge_width 0.5)
			(island_removal_mode 0)
		)
		(polygon
			(pts
				(xy 410.398976 -344.659458) (xy 409.047696 -344.659458) (xy 409.047696 -343.379298) (xy 410.398976 -343.379298)
			)
		)
	)
	(zone
		(layer "F.Cu")
		(hatch none 0.5)
		(connect_pads
			(clearance 0)
		)
		(min_thickness 0.25)
		(keepout
			(tracks allowed)
			(vias allowed)
			(pads allowed)
			(copperpour allowed)
			(footprints allowed)
		)
		(placement
			(enabled no)
			(sheetname "")
		)
		(fill
			(thermal_gap 0.5)
			(thermal_bridge_width 0.5)
			(island_removal_mode 0)
		)
		(polygon
			(pts
				(xy 72.501506 -115.203224) (xy 73.971404 -115.203224) (xy 74.055224 -115.119404) (xy 74.055224 -114.394996)
				(xy 73.819004 -114.158776) (xy 72.533002 -114.158776) (xy 72.31253 -114.379248) (xy 72.31253 -115.014248)
			)
		)
	)
	(zone
		(layer "F.Cu")
		(hatch none 0.5)
		(connect_pads
			(clearance 0)
		)
		(min_thickness 0.25)
		(keepout
			(tracks allowed)
			(vias allowed)
			(pads allowed)
			(copperpour allowed)
			(footprints allowed)
		)
		(placement
			(enabled no)
			(sheetname "")
		)
		(fill
			(thermal_gap 0.5)
			(thermal_bridge_width 0.5)
			(island_removal_mode 0)
		)
		(polygon
			(pts
				(xy 38.597332 -122.13463) (xy 38.597332 -120.78335) (xy 39.877492 -120.78335) (xy 39.877492 -122.13463)
			)
		)
	)
	(zone
		(layer "F.Cu")
		(hatch none 0.5)
		(connect_pads
			(clearance 0)
		)
		(min_thickness 0.25)
		(keepout
			(tracks allowed)
			(vias allowed)
			(pads allowed)
			(copperpour allowed)
			(footprints allowed)
		)
		(placement
			(enabled no)
			(sheetname "")
		)
		(fill
			(thermal_gap 0.5)
			(thermal_bridge_width 0.5)
			(island_removal_mode 0)
		)
		(polygon
			(pts
				(xy 223.693482 -267.968476) (xy 223.693482 -265.819636) (xy 225.326702 -265.819636) (xy 225.326702 -267.968476)
			)
		)
	)
	(zone
		(layer "F.Cu")
		(hatch none 0.5)
		(connect_pads
			(clearance 0)
		)
		(min_thickness 0.25)
		(keepout
			(tracks not_allowed)
			(vias allowed)
			(pads allowed)
			(copperpour not_allowed)
			(footprints allowed)
		)
		(placement
			(enabled no)
			(sheetname "")
		)
		(fill
			(thermal_gap 0.5)
			(thermal_bridge_width 0.5)
			(island_removal_mode 0)
		)
		(polygon
			(pts
				(arc
					(start 132.999988 -276.010116)
					(mid 136.250172 -272.759932)
					(end 139.500102 -276.010116)
				)
				(arc
					(start 139.500102 -276.010116)
					(mid 136.250172 -279.260046)
					(end 132.999988 -276.010116)
				)
			)
		)
	)
	(zone
		(layer "F.Cu")
		(hatch none 0.5)
		(connect_pads
			(clearance 0)
		)
		(min_thickness 0.25)
		(keepout
			(tracks allowed)
			(vias allowed)
			(pads allowed)
			(copperpour allowed)
			(footprints allowed)
		)
		(placement
			(enabled no)
			(sheetname "")
		)
		(fill
			(thermal_gap 0.5)
			(thermal_bridge_width 0.5)
			(island_removal_mode 0)
		)
		(polygon
			(pts
				(xy 126.715266 -156.560012) (xy 130.525266 -156.560012) (xy 130.525266 -158.084012) (xy 126.715266 -158.084012)
			)
		)
	)
	(zone
		(layer "F.Cu")
		(hatch none 0.5)
		(connect_pads
			(clearance 0)
		)
		(min_thickness 0.25)
		(keepout
			(tracks allowed)
			(vias allowed)
			(pads allowed)
			(copperpour allowed)
			(footprints not_allowed)
		)
		(placement
			(enabled no)
			(sheetname "")
		)
		(fill
			(thermal_gap 0.5)
			(thermal_bridge_width 0.5)
			(island_removal_mode 0)
		)
		(polygon
			(pts
				(xy 435.820058 -18.219928) (xy 431.619914 -18.219928) (xy 431.619914 -23.219918) (xy 435.820058 -23.219918)
			)
		)
	)
	(zone
		(layer "F.Cu")
		(hatch none 0.5)
		(connect_pads
			(clearance 0)
		)
		(min_thickness 0.25)
		(keepout
			(tracks allowed)
			(vias allowed)
			(pads allowed)
			(copperpour allowed)
			(footprints allowed)
		)
		(placement
			(enabled no)
			(sheetname "")
		)
		(fill
			(thermal_gap 0.5)
			(thermal_bridge_width 0.5)
			(island_removal_mode 0)
		)
		(polygon
			(pts
				(xy 329.126088 -344.659458) (xy 327.774808 -344.659458) (xy 327.774808 -343.379298) (xy 329.126088 -343.379298)
			)
		)
	)
	(zone
		(layer "F.Cu")
		(hatch none 0.5)
		(connect_pads
			(clearance 0)
		)
		(min_thickness 0.25)
		(keepout
			(tracks allowed)
			(vias allowed)
			(pads allowed)
			(copperpour allowed)
			(footprints allowed)
		)
		(placement
			(enabled no)
			(sheetname "")
		)
		(fill
			(thermal_gap 0.5)
			(thermal_bridge_width 0.5)
			(island_removal_mode 0)
		)
		(polygon
			(pts
				(xy 23.545292 -344.659458) (xy 22.194012 -344.659458) (xy 22.194012 -343.379298) (xy 23.545292 -343.379298)
			)
		)
	)
	(zone
		(layer "F.Cu")
		(hatch none 0.5)
		(connect_pads
			(clearance 0)
		)
		(min_thickness 0.25)
		(keepout
			(tracks allowed)
			(vias allowed)
			(pads allowed)
			(copperpour allowed)
			(footprints allowed)
		)
		(placement
			(enabled no)
			(sheetname "")
		)
		(fill
			(thermal_gap 0.5)
			(thermal_bridge_width 0.5)
			(island_removal_mode 0)
		)
		(polygon
			(pts
				(xy 128.510792 -344.659458) (xy 127.159512 -344.659458) (xy 127.159512 -343.379298) (xy 128.510792 -343.379298)
			)
		)
	)
	(zone
		(layer "F.Cu")
		(hatch none 0.5)
		(connect_pads
			(clearance 0)
		)
		(min_thickness 0.25)
		(keepout
			(tracks allowed)
			(vias allowed)
			(pads allowed)
			(copperpour allowed)
			(footprints allowed)
		)
		(placement
			(enabled no)
			(sheetname "")
		)
		(fill
			(thermal_gap 0.5)
			(thermal_bridge_width 0.5)
			(island_removal_mode 0)
		)
		(polygon
			(pts
				(xy 386.897372 -104.01808) (xy 386.897372 -102.6668) (xy 388.177532 -102.6668) (xy 388.177532 -104.01808)
			)
		)
	)
	(zone
		(layer "F.Cu")
		(hatch none 0.5)
		(connect_pads
			(clearance 0)
		)
		(min_thickness 0.25)
		(keepout
			(tracks allowed)
			(vias allowed)
			(pads allowed)
			(copperpour allowed)
			(footprints allowed)
		)
		(placement
			(enabled no)
			(sheetname "")
		)
		(fill
			(thermal_gap 0.5)
			(thermal_bridge_width 0.5)
			(island_removal_mode 0)
		)
		(polygon
			(pts
				(xy 38.597332 -136.944608) (xy 38.597332 -135.593328) (xy 39.877492 -135.593328) (xy 39.877492 -136.944608)
			)
		)
	)
	(zone
		(layer "F.Cu")
		(hatch none 0.5)
		(connect_pads
			(clearance 0)
		)
		(min_thickness 0.25)
		(keepout
			(tracks allowed)
			(vias allowed)
			(pads allowed)
			(copperpour allowed)
			(footprints allowed)
		)
		(placement
			(enabled no)
			(sheetname "")
		)
		(fill
			(thermal_gap 0.5)
			(thermal_bridge_width 0.5)
			(island_removal_mode 0)
		)
		(polygon
			(pts
				(xy 213.851236 -31.160974) (xy 213.851236 -29.809694) (xy 215.131396 -29.809694) (xy 215.131396 -31.160974)
			)
		)
	)
	(zone
		(layer "F.Cu")
		(hatch none 0.5)
		(connect_pads
			(clearance 0)
		)
		(min_thickness 0.25)
		(keepout
			(tracks not_allowed)
			(vias allowed)
			(pads allowed)
			(copperpour not_allowed)
			(footprints allowed)
		)
		(placement
			(enabled no)
			(sheetname "")
		)
		(fill
			(thermal_gap 0.5)
			(thermal_bridge_width 0.5)
			(island_removal_mode 0)
		)
		(polygon
			(pts
				(arc
					(start 319.600072 -320.900044)
					(mid 321.850004 -318.650112)
					(end 324.099936 -320.900044)
				)
				(arc
					(start 324.099936 -320.900044)
					(mid 321.850004 -323.149976)
					(end 319.600072 -320.900044)
				)
			)
		)
	)
	(zone
		(layer "F.Cu")
		(hatch none 0.5)
		(connect_pads
			(clearance 0)
		)
		(min_thickness 0.25)
		(keepout
			(tracks allowed)
			(vias allowed)
			(pads allowed)
			(copperpour allowed)
			(footprints not_allowed)
		)
		(placement
			(enabled no)
			(sheetname "")
		)
		(fill
			(thermal_gap 0.5)
			(thermal_bridge_width 0.5)
			(island_removal_mode 0)
		)
		(polygon
			(pts
				(xy 154.519884 -394.269976) (xy 141.070076 -394.269976) (xy 141.070076 -417.58997) (xy 154.519884 -417.58997)
			)
		)
	)
	(zone
		(layer "F.Cu")
		(hatch none 0.5)
		(connect_pads
			(clearance 0)
		)
		(min_thickness 0.25)
		(keepout
			(tracks allowed)
			(vias allowed)
			(pads allowed)
			(copperpour allowed)
			(footprints allowed)
		)
		(placement
			(enabled no)
			(sheetname "")
		)
		(fill
			(thermal_gap 0.5)
			(thermal_bridge_width 0.5)
			(island_removal_mode 0)
		)
		(polygon
			(pts
				(xy 249.309128 -32.954468) (xy 249.309128 -31.603188) (xy 250.589288 -31.603188) (xy 250.589288 -32.954468)
			)
		)
	)
	(zone
		(layer "F.Cu")
		(hatch none 0.5)
		(connect_pads
			(clearance 0)
		)
		(min_thickness 0.25)
		(keepout
			(tracks allowed)
			(vias allowed)
			(pads allowed)
			(copperpour allowed)
			(footprints allowed)
		)
		(placement
			(enabled no)
			(sheetname "")
		)
		(fill
			(thermal_gap 0.5)
			(thermal_bridge_width 0.5)
			(island_removal_mode 0)
		)
		(polygon
			(pts
				(xy 102.92461 -224.775014) (xy 104.12603 -224.775014) (xy 104.475026 -224.426018) (xy 104.475026 -223.79305)
				(xy 104.41051 -223.728534) (xy 103.622094 -223.728534) (xy 102.795324 -224.555304) (xy 102.795324 -224.645728)
			)
		)
	)
	(zone
		(layer "F.Cu")
		(hatch none 0.5)
		(connect_pads
			(clearance 0)
		)
		(min_thickness 0.25)
		(keepout
			(tracks allowed)
			(vias allowed)
			(pads allowed)
			(copperpour allowed)
			(footprints allowed)
		)
		(placement
			(enabled no)
			(sheetname "")
		)
		(fill
			(thermal_gap 0.5)
			(thermal_bridge_width 0.5)
			(island_removal_mode 0)
		)
		(polygon
			(pts
				(xy 381.618744 -344.659458) (xy 380.267464 -344.659458) (xy 380.267464 -343.379298) (xy 381.618744 -343.379298)
			)
		)
	)
	(zone
		(layer "F.Cu")
		(hatch none 0.5)
		(connect_pads
			(clearance 0)
		)
		(min_thickness 0.25)
		(keepout
			(tracks allowed)
			(vias allowed)
			(pads allowed)
			(copperpour allowed)
			(footprints allowed)
		)
		(placement
			(enabled no)
			(sheetname "")
		)
		(fill
			(thermal_gap 0.5)
			(thermal_bridge_width 0.5)
			(island_removal_mode 0)
		)
		(polygon
			(pts
				(xy 268.155166 -105.824782) (xy 268.155166 -104.473502) (xy 269.435326 -104.473502) (xy 269.435326 -105.824782)
			)
		)
	)
	(zone
		(layer "F.Cu")
		(hatch none 0.5)
		(connect_pads
			(clearance 0)
		)
		(min_thickness 0.25)
		(keepout
			(tracks allowed)
			(vias allowed)
			(pads allowed)
			(copperpour allowed)
			(footprints allowed)
		)
		(placement
			(enabled no)
			(sheetname "")
		)
		(fill
			(thermal_gap 0.5)
			(thermal_bridge_width 0.5)
			(island_removal_mode 0)
		)
		(polygon
			(pts
				(xy 92.883482 -35.316922) (xy 94.390718 -35.316922) (xy 94.610682 -35.096958) (xy 94.610682 -27.653996)
				(xy 94.265242 -27.308556) (xy 92.914724 -27.308556) (xy 92.569284 -27.653996) (xy 92.569284 -35.002724)
			)
		)
	)
	(zone
		(layer "F.Cu")
		(hatch none 0.5)
		(connect_pads
			(clearance 0)
		)
		(min_thickness 0.25)
		(keepout
			(tracks allowed)
			(vias allowed)
			(pads allowed)
			(copperpour allowed)
			(footprints allowed)
		)
		(placement
			(enabled no)
			(sheetname "")
		)
		(fill
			(thermal_gap 0.5)
			(thermal_bridge_width 0.5)
			(island_removal_mode 0)
		)
		(polygon
			(pts
				(xy 218.128342 -267.978636) (xy 218.128342 -265.860276) (xy 219.781882 -265.860276) (xy 219.781882 -267.978636)
			)
		)
	)
	(zone
		(layer "F.Cu")
		(hatch none 0.5)
		(connect_pads
			(clearance 0)
		)
		(min_thickness 0.25)
		(keepout
			(tracks allowed)
			(vias allowed)
			(pads allowed)
			(copperpour allowed)
			(footprints allowed)
		)
		(placement
			(enabled no)
			(sheetname "")
		)
		(fill
			(thermal_gap 0.5)
			(thermal_bridge_width 0.5)
			(island_removal_mode 0)
		)
		(polygon
			(pts
				(xy 172.616876 -356.928166) (xy 171.265596 -356.928166) (xy 171.265596 -355.648006) (xy 172.616876 -355.648006)
			)
		)
	)
	(zone
		(layer "F.Cu")
		(hatch none 0.5)
		(connect_pads
			(clearance 0)
		)
		(min_thickness 0.25)
		(keepout
			(tracks allowed)
			(vias allowed)
			(pads allowed)
			(copperpour allowed)
			(footprints not_allowed)
		)
		(placement
			(enabled no)
			(sheetname "")
		)
		(fill
			(thermal_gap 0.5)
			(thermal_bridge_width 0.5)
			(island_removal_mode 0)
		)
		(polygon
			(pts
				(xy 273.079972 -400.734784) (xy 202.160124 -400.734784)
				(arc
					(start 202.160124 -416.56508)
					(mid 202.786667 -416.349012)
					(end 203.445364 -416.275774)
				)
				(arc
					(start 271.794478 -416.275774)
					(mid 272.453314 -416.34912)
					(end 273.079972 -416.565334)
				)
			)
		)
	)
	(zone
		(layer "F.Cu")
		(hatch none 0.5)
		(connect_pads
			(clearance 0)
		)
		(min_thickness 0.25)
		(keepout
			(tracks allowed)
			(vias allowed)
			(pads allowed)
			(copperpour allowed)
			(footprints allowed)
		)
		(placement
			(enabled no)
			(sheetname "")
		)
		(fill
			(thermal_gap 0.5)
			(thermal_bridge_width 0.5)
			(island_removal_mode 0)
		)
		(polygon
			(pts
				(xy 48.4378 -19.7358) (xy 48.4378 -19.2024) (xy 49.5046 -19.2024) (xy 49.5046 -19.7358)
			)
		)
	)
	(zone
		(layer "F.Cu")
		(hatch none 0.5)
		(connect_pads
			(clearance 0)
		)
		(min_thickness 0.25)
		(keepout
			(tracks allowed)
			(vias allowed)
			(pads allowed)
			(copperpour allowed)
			(footprints allowed)
		)
		(placement
			(enabled no)
			(sheetname "")
		)
		(fill
			(thermal_gap 0.5)
			(thermal_bridge_width 0.5)
			(island_removal_mode 0)
		)
		(polygon
			(pts
				(xy 429.027336 -356.952042) (xy 427.676056 -356.952042) (xy 427.676056 -355.671882) (xy 429.027336 -355.671882)
			)
		)
	)
	(zone
		(layer "F.Cu")
		(hatch none 0.5)
		(connect_pads
			(clearance 0)
		)
		(min_thickness 0.25)
		(keepout
			(tracks not_allowed)
			(vias allowed)
			(pads allowed)
			(copperpour not_allowed)
			(footprints allowed)
		)
		(placement
			(enabled no)
			(sheetname "")
		)
		(fill
			(thermal_gap 0.5)
			(thermal_bridge_width 0.5)
			(island_removal_mode 0)
		)
		(polygon
			(pts
				(xy 203.620116 -23.219918) (xy 203.620116 -18.219928) (xy 199.419972 -18.219928) (xy 199.419972 -23.219918)
			)
		)
	)
	(zone
		(layer "F.Cu")
		(hatch none 0.5)
		(connect_pads
			(clearance 0)
		)
		(min_thickness 0.25)
		(keepout
			(tracks allowed)
			(vias allowed)
			(pads allowed)
			(copperpour allowed)
			(footprints allowed)
		)
		(placement
			(enabled no)
			(sheetname "")
		)
		(fill
			(thermal_gap 0.5)
			(thermal_bridge_width 0.5)
			(island_removal_mode 0)
		)
		(polygon
			(pts
				(xy 314.178188 -132.816092) (xy 314.178188 -131.464812) (xy 315.458348 -131.464812) (xy 315.458348 -132.816092)
			)
		)
	)
	(zone
		(layer "F.Cu")
		(hatch none 0.5)
		(connect_pads
			(clearance 0)
		)
		(min_thickness 0.25)
		(keepout
			(tracks not_allowed)
			(vias allowed)
			(pads allowed)
			(copperpour not_allowed)
			(footprints allowed)
		)
		(placement
			(enabled no)
			(sheetname "")
		)
		(fill
			(thermal_gap 0.5)
			(thermal_bridge_width 0.5)
			(island_removal_mode 0)
		)
		(polygon
			(pts
				(arc
					(start 112.700054 -72.69988)
					(mid 117.700044 -67.69989)
					(end 122.700034 -72.69988)
				)
				(arc
					(start 122.700034 -72.69988)
					(mid 117.700044 -77.69987)
					(end 112.700054 -72.69988)
				)
			)
		)
	)
	(zone
		(layer "F.Cu")
		(hatch none 0.5)
		(connect_pads
			(clearance 0)
		)
		(min_thickness 0.25)
		(keepout
			(tracks allowed)
			(vias allowed)
			(pads allowed)
			(copperpour allowed)
			(footprints allowed)
		)
		(placement
			(enabled no)
			(sheetname "")
		)
		(fill
			(thermal_gap 0.5)
			(thermal_bridge_width 0.5)
			(island_removal_mode 0)
		)
		(polygon
			(pts
				(xy 74.911966 -356.952042) (xy 73.560686 -356.952042) (xy 73.560686 -355.671882) (xy 74.911966 -355.671882)
			)
		)
	)
	(zone
		(layer "F.Cu")
		(hatch none 0.5)
		(connect_pads
			(clearance 0)
		)
		(min_thickness 0.25)
		(keepout
			(tracks allowed)
			(vias allowed)
			(pads allowed)
			(copperpour allowed)
			(footprints allowed)
		)
		(placement
			(enabled no)
			(sheetname "")
		)
		(fill
			(thermal_gap 0.5)
			(thermal_bridge_width 0.5)
			(island_removal_mode 0)
		)
		(polygon
			(pts
				(xy 396.73784 -19.7358) (xy 396.73784 -19.2024) (xy 397.80464 -19.2024) (xy 397.80464 -19.7358)
			)
		)
	)
	(zone
		(layer "F.Cu")
		(hatch none 0.5)
		(connect_pads
			(clearance 0)
		)
		(min_thickness 0.25)
		(keepout
			(tracks allowed)
			(vias allowed)
			(pads allowed)
			(copperpour allowed)
			(footprints allowed)
		)
		(placement
			(enabled no)
			(sheetname "")
		)
		(fill
			(thermal_gap 0.5)
			(thermal_bridge_width 0.5)
			(island_removal_mode 0)
		)
		(polygon
			(pts
				(xy 395.291564 -52.800758) (xy 395.291564 -55.718456) (xy 395.501114 -55.928006) (xy 396.114016 -55.928006)
				(xy 396.114016 -52.870608) (xy 396.044166 -52.800758)
			)
		)
	)
	(zone
		(layer "F.Cu")
		(hatch none 0.5)
		(connect_pads
			(clearance 0)
		)
		(min_thickness 0.25)
		(keepout
			(tracks allowed)
			(vias allowed)
			(pads allowed)
			(copperpour allowed)
			(footprints allowed)
		)
		(placement
			(enabled no)
			(sheetname "")
		)
		(fill
			(thermal_gap 0.5)
			(thermal_bridge_width 0.5)
			(island_removal_mode 0)
		)
		(polygon
			(pts
				(xy 325.815706 -120.352312) (xy 325.815706 -122.616214) (xy 326.025256 -122.825764) (xy 326.638158 -122.825764)
				(xy 326.638158 -119.768366) (xy 326.568308 -119.698516) (xy 325.815706 -119.698516) (xy 325.10984 -119.698516)
				(xy 325.097394 -119.710962) (xy 325.097394 -120.134888) (xy 325.314818 -120.352312)
			)
		)
	)
	(zone
		(layer "F.Cu")
		(hatch none 0.5)
		(connect_pads
			(clearance 0)
		)
		(min_thickness 0.25)
		(keepout
			(tracks allowed)
			(vias allowed)
			(pads allowed)
			(copperpour allowed)
			(footprints allowed)
		)
		(placement
			(enabled no)
			(sheetname "")
		)
		(fill
			(thermal_gap 0.5)
			(thermal_bridge_width 0.5)
			(island_removal_mode 0)
		)
		(polygon
			(pts
				(xy 48.416972 -356.928166) (xy 47.065692 -356.928166) (xy 47.065692 -355.648006) (xy 48.416972 -355.648006)
			)
		)
	)
	(zone
		(layer "F.Cu")
		(hatch none 0.5)
		(connect_pads
			(clearance 0)
		)
		(min_thickness 0.25)
		(keepout
			(tracks allowed)
			(vias allowed)
			(pads allowed)
			(copperpour allowed)
			(footprints allowed)
		)
		(placement
			(enabled no)
			(sheetname "")
		)
		(fill
			(thermal_gap 0.5)
			(thermal_bridge_width 0.5)
			(island_removal_mode 0)
		)
		(polygon
			(pts
				(xy 79.336138 -150.919434) (xy 79.336138 -149.568154) (xy 80.616298 -149.568154) (xy 80.616298 -150.919434)
			)
		)
	)
	(zone
		(layer "F.Cu")
		(hatch none 0.5)
		(connect_pads
			(clearance 0)
		)
		(min_thickness 0.25)
		(keepout
			(tracks allowed)
			(vias allowed)
			(pads allowed)
			(copperpour allowed)
			(footprints allowed)
		)
		(placement
			(enabled no)
			(sheetname "")
		)
		(fill
			(thermal_gap 0.5)
			(thermal_bridge_width 0.5)
			(island_removal_mode 0)
		)
		(polygon
			(pts
				(xy 190.537846 -19.7358) (xy 190.537846 -19.2024) (xy 191.604646 -19.2024) (xy 191.604646 -19.7358)
			)
		)
	)
	(zone
		(layer "F.Cu")
		(hatch none 0.5)
		(connect_pads
			(clearance 0)
		)
		(min_thickness 0.25)
		(keepout
			(tracks allowed)
			(vias allowed)
			(pads allowed)
			(copperpour allowed)
			(footprints allowed)
		)
		(placement
			(enabled no)
			(sheetname "")
		)
		(fill
			(thermal_gap 0.5)
			(thermal_bridge_width 0.5)
			(island_removal_mode 0)
		)
		(polygon
			(pts
				(xy 134.728712 -356.952042) (xy 133.377432 -356.952042) (xy 133.377432 -355.671882) (xy 134.728712 -355.671882)
			)
		)
	)
	(zone
		(layer "F.Cu")
		(hatch none 0.5)
		(connect_pads
			(clearance 0)
		)
		(min_thickness 0.25)
		(keepout
			(tracks allowed)
			(vias allowed)
			(pads allowed)
			(copperpour allowed)
			(footprints allowed)
		)
		(placement
			(enabled no)
			(sheetname "")
		)
		(fill
			(thermal_gap 0.5)
			(thermal_bridge_width 0.5)
			(island_removal_mode 0)
		)
		(polygon
			(pts
				(xy 327.308972 -32.954468) (xy 327.308972 -31.603188) (xy 328.589132 -31.603188) (xy 328.589132 -32.954468)
			)
		)
	)
	(zone
		(layer "F.Cu")
		(hatch none 0.5)
		(connect_pads
			(clearance 0)
		)
		(min_thickness 0.25)
		(keepout
			(tracks allowed)
			(vias allowed)
			(pads allowed)
			(copperpour allowed)
			(footprints allowed)
		)
		(placement
			(enabled no)
			(sheetname "")
		)
		(fill
			(thermal_gap 0.5)
			(thermal_bridge_width 0.5)
			(island_removal_mode 0)
		)
		(polygon
			(pts
				(xy 181.943756 -344.659458) (xy 180.592476 -344.659458) (xy 180.592476 -343.379298) (xy 181.943756 -343.379298)
			)
		)
	)
	(zone
		(layer "F.Cu")
		(hatch none 0.5)
		(connect_pads
			(clearance 0)
		)
		(min_thickness 0.25)
		(keepout
			(tracks allowed)
			(vias allowed)
			(pads allowed)
			(copperpour allowed)
			(footprints not_allowed)
		)
		(placement
			(enabled no)
			(sheetname "")
		)
		(fill
			(thermal_gap 0.5)
			(thermal_bridge_width 0.5)
			(island_removal_mode 0)
		)
		(polygon
			(pts
				(xy 312.139838 -361.790234) (xy 283.03982 -361.790234) (xy 283.03982 -417.58997) (xy 312.139838 -417.58997)
			)
		)
	)
	(zone
		(layer "F.Cu")
		(hatch none 0.5)
		(connect_pads
			(clearance 0)
		)
		(min_thickness 0.25)
		(keepout
			(tracks allowed)
			(vias allowed)
			(pads allowed)
			(copperpour allowed)
			(footprints allowed)
		)
		(placement
			(enabled no)
			(sheetname "")
		)
		(fill
			(thermal_gap 0.5)
			(thermal_bridge_width 0.5)
			(island_removal_mode 0)
		)
		(polygon
			(pts
				(xy 166.398956 -344.659458) (xy 165.047676 -344.659458) (xy 165.047676 -343.379298) (xy 166.398956 -343.379298)
			)
		)
	)
	(zone
		(layer "F.Cu")
		(hatch none 0.5)
		(connect_pads
			(clearance 0)
		)
		(min_thickness 0.25)
		(keepout
			(tracks allowed)
			(vias allowed)
			(pads allowed)
			(copperpour allowed)
			(footprints allowed)
		)
		(placement
			(enabled no)
			(sheetname "")
		)
		(fill
			(thermal_gap 0.5)
			(thermal_bridge_width 0.5)
			(island_removal_mode 0)
		)
		(polygon
			(pts
				(xy 326.017128 -350.80575) (xy 324.665848 -350.80575) (xy 324.665848 -349.52559) (xy 326.017128 -349.52559)
			)
		)
	)
	(zone
		(layer "F.Cu")
		(hatch none 0.5)
		(connect_pads
			(clearance 0)
		)
		(min_thickness 0.25)
		(keepout
			(tracks allowed)
			(vias allowed)
			(pads allowed)
			(copperpour allowed)
			(footprints allowed)
		)
		(placement
			(enabled no)
			(sheetname "")
		)
		(fill
			(thermal_gap 0.5)
			(thermal_bridge_width 0.5)
			(island_removal_mode 0)
		)
		(polygon
			(pts
				(xy 311.53608 -134.609586) (xy 311.53608 -133.258306) (xy 312.81624 -133.258306) (xy 312.81624 -134.609586)
			)
		)
	)
	(zone
		(layer "F.Cu")
		(hatch none 0.5)
		(connect_pads
			(clearance 0)
		)
		(min_thickness 0.25)
		(keepout
			(tracks allowed)
			(vias allowed)
			(pads allowed)
			(copperpour allowed)
			(footprints allowed)
		)
		(placement
			(enabled no)
			(sheetname "")
		)
		(fill
			(thermal_gap 0.5)
			(thermal_bridge_width 0.5)
			(island_removal_mode 0)
		)
		(polygon
			(pts
				(xy 32.872172 -344.659458) (xy 31.520892 -344.659458) (xy 31.520892 -343.379298) (xy 32.872172 -343.379298)
			)
		)
	)
	(zone
		(layer "F.Cu")
		(hatch none 0.5)
		(connect_pads
			(clearance 0)
		)
		(min_thickness 0.25)
		(keepout
			(tracks allowed)
			(vias allowed)
			(pads allowed)
			(copperpour allowed)
			(footprints allowed)
		)
		(placement
			(enabled no)
			(sheetname "")
		)
		(fill
			(thermal_gap 0.5)
			(thermal_bridge_width 0.5)
			(island_removal_mode 0)
		)
		(polygon
			(pts
				(xy 198.07809 -121.606056) (xy 198.07809 -120.254776) (xy 199.35825 -120.254776) (xy 199.35825 -121.606056)
			)
		)
	)
	(zone
		(layer "F.Cu")
		(hatch none 0.5)
		(connect_pads
			(clearance 0)
		)
		(min_thickness 0.25)
		(keepout
			(tracks allowed)
			(vias allowed)
			(pads allowed)
			(copperpour allowed)
			(footprints allowed)
		)
		(placement
			(enabled no)
			(sheetname "")
		)
		(fill
			(thermal_gap 0.5)
			(thermal_bridge_width 0.5)
			(island_removal_mode 0)
		)
		(polygon
			(pts
				(xy 363.479842 -316.895988) (xy 363.479842 -318.546988) (xy 361.447842 -318.546988) (xy 361.447842 -316.895988)
			)
		)
	)
	(zone
		(layer "F.Cu")
		(hatch none 0.5)
		(connect_pads
			(clearance 0)
		)
		(min_thickness 0.25)
		(keepout
			(tracks allowed)
			(vias allowed)
			(pads allowed)
			(copperpour allowed)
			(footprints not_allowed)
		)
		(placement
			(enabled no)
			(sheetname "")
		)
		(fill
			(thermal_gap 0.5)
			(thermal_bridge_width 0.5)
			(island_removal_mode 0)
		)
		(polygon
			(pts
				(xy 267.720064 -23.219918) (xy 267.720064 -18.219928) (xy 263.51992 -18.219928) (xy 263.51992 -23.219918)
			)
		)
	)
	(zone
		(layer "F.Cu")
		(hatch none 0.5)
		(connect_pads
			(clearance 0)
		)
		(min_thickness 0.25)
		(keepout
			(tracks allowed)
			(vias allowed)
			(pads allowed)
			(copperpour allowed)
			(footprints allowed)
		)
		(placement
			(enabled no)
			(sheetname "")
		)
		(fill
			(thermal_gap 0.5)
			(thermal_bridge_width 0.5)
			(island_removal_mode 0)
		)
		(polygon
			(pts
				(xy 92.417138 -99.576382) (xy 93.00591 -99.576382) (xy 93.055186 -99.527106) (xy 93.055186 -98.938334)
				(xy 92.628212 -98.51136) (xy 91.945206 -98.51136) (xy 91.89593 -98.560636) (xy 91.89593 -99.055174)
			)
		)
	)
	(zone
		(layer "F.Cu")
		(hatch none 0.5)
		(connect_pads
			(clearance 0)
		)
		(min_thickness 0.25)
		(keepout
			(tracks allowed)
			(vias allowed)
			(pads allowed)
			(copperpour allowed)
			(footprints not_allowed)
		)
		(placement
			(enabled no)
			(sheetname "")
		)
		(fill
			(thermal_gap 0.5)
			(thermal_bridge_width 0.5)
			(island_removal_mode 0)
		)
		(polygon
			(pts
				(xy 383.264918 -40.120062) (xy 391.264902 -40.120062) (xy 391.264902 -13.850112) (xy 383.264918 -13.850112)
			)
		)
	)
	(zone
		(layer "F.Cu")
		(hatch none 0.5)
		(connect_pads
			(clearance 0)
		)
		(min_thickness 0.25)
		(keepout
			(tracks allowed)
			(vias allowed)
			(pads allowed)
			(copperpour allowed)
			(footprints allowed)
		)
		(placement
			(enabled no)
			(sheetname "")
		)
		(fill
			(thermal_gap 0.5)
			(thermal_bridge_width 0.5)
			(island_removal_mode 0)
		)
		(polygon
			(pts
				(xy 96.039686 -100.623624) (xy 98.957384 -100.623624) (xy 99.166934 -100.414074) (xy 99.166934 -99.801172)
				(xy 96.109536 -99.801172) (xy 96.039686 -99.871022)
			)
		)
	)
	(zone
		(layer "F.Cu")
		(hatch none 0.5)
		(connect_pads
			(clearance 0)
		)
		(min_thickness 0.25)
		(keepout
			(tracks not_allowed)
			(vias allowed)
			(pads allowed)
			(copperpour not_allowed)
			(footprints allowed)
		)
		(placement
			(enabled no)
			(sheetname "")
		)
		(fill
			(thermal_gap 0.5)
			(thermal_bridge_width 0.5)
			(island_removal_mode 0)
		)
		(polygon
			(pts
				(xy 383.819908 -23.219918) (xy 383.819908 -18.219928) (xy 379.620018 -18.219928) (xy 379.620018 -23.219918)
			)
		)
	)
	(zone
		(layer "F.Cu")
		(hatch none 0.5)
		(connect_pads
			(clearance 0)
		)
		(min_thickness 0.25)
		(keepout
			(tracks not_allowed)
			(vias allowed)
			(pads allowed)
			(copperpour not_allowed)
			(footprints allowed)
		)
		(placement
			(enabled no)
			(sheetname "")
		)
		(fill
			(thermal_gap 0.5)
			(thermal_bridge_width 0.5)
			(island_removal_mode 0)
		)
		(polygon
			(pts
				(arc
					(start 375.700036 -320.900044)
					(mid 377.949968 -318.650112)
					(end 380.1999 -320.900044)
				)
				(arc
					(start 380.1999 -320.900044)
					(mid 377.949968 -323.149976)
					(end 375.700036 -320.900044)
				)
			)
		)
	)
	(zone
		(layer "F.Cu")
		(hatch none 0.5)
		(connect_pads
			(clearance 0)
		)
		(min_thickness 0.25)
		(keepout
			(tracks allowed)
			(vias allowed)
			(pads allowed)
			(copperpour allowed)
			(footprints allowed)
		)
		(placement
			(enabled no)
			(sheetname "")
		)
		(fill
			(thermal_gap 0.5)
			(thermal_bridge_width 0.5)
			(island_removal_mode 0)
		)
		(polygon
			(pts
				(xy 162.860228 -46.986444) (xy 163.852606 -46.986444) (xy 163.937442 -46.901608) (xy 163.937442 -46.211744)
				(xy 163.889436 -46.163738) (xy 162.840162 -46.163738) (xy 162.772344 -46.231556) (xy 162.772344 -46.89856)
			)
		)
	)
	(zone
		(layer "F.Cu")
		(hatch none 0.5)
		(connect_pads
			(clearance 0)
		)
		(min_thickness 0.25)
		(keepout
			(tracks allowed)
			(vias allowed)
			(pads allowed)
			(copperpour allowed)
			(footprints allowed)
		)
		(placement
			(enabled no)
			(sheetname "")
		)
		(fill
			(thermal_gap 0.5)
			(thermal_bridge_width 0.5)
			(island_removal_mode 0)
		)
		(polygon
			(pts
				(xy 208.100168 -220.674946) (xy 208.480406 -220.674946) (xy 208.5975 -220.557852) (xy 208.5975 -220.228668)
				(xy 208.451196 -220.082364) (xy 208.07807 -220.082364) (xy 208.027016 -220.133418) (xy 208.027016 -220.601794)
			)
		)
	)
	(zone
		(layer "F.Cu")
		(hatch none 0.5)
		(connect_pads
			(clearance 0)
		)
		(min_thickness 0.25)
		(keepout
			(tracks allowed)
			(vias allowed)
			(pads allowed)
			(copperpour allowed)
			(footprints not_allowed)
		)
		(placement
			(enabled no)
			(sheetname "")
		)
		(fill
			(thermal_gap 0.5)
			(thermal_bridge_width 0.5)
			(island_removal_mode 0)
		)
		(polygon
			(pts
				(xy 34.900108 -271.15008) (xy 34.900108 -320.650108) (xy 84.399882 -320.650108) (xy 84.399882 -271.15008)
			)
		)
	)
	(zone
		(layer "F.Cu")
		(hatch none 0.5)
		(connect_pads
			(clearance 0)
		)
		(min_thickness 0.25)
		(keepout
			(tracks allowed)
			(vias allowed)
			(pads allowed)
			(copperpour allowed)
			(footprints allowed)
		)
		(placement
			(enabled no)
			(sheetname "")
		)
		(fill
			(thermal_gap 0.5)
			(thermal_bridge_width 0.5)
			(island_removal_mode 0)
		)
		(polygon
			(pts
				(xy 129.541778 -181.060344) (xy 129.541778 -178.251866) (xy 128.961896 -177.671984) (xy 128.961896 -176.054004)
				(xy 129.52095 -175.49495) (xy 129.541778 -175.474122) (xy 129.541778 -174.353474) (xy 131.679442 -174.353474)
				(xy 132.131308 -173.901608) (xy 132.834888 -173.901608) (xy 132.834888 -174.018448) (xy 133.169914 -174.353474)
				(xy 136.431528 -174.353474) (xy 136.431528 -181.060344)
			)
		)
	)
	(zone
		(layer "F.Cu")
		(hatch none 0.5)
		(connect_pads
			(clearance 0)
		)
		(min_thickness 0.25)
		(keepout
			(tracks allowed)
			(vias allowed)
			(pads allowed)
			(copperpour allowed)
			(footprints not_allowed)
		)
		(placement
			(enabled no)
			(sheetname "")
		)
		(fill
			(thermal_gap 0.5)
			(thermal_bridge_width 0.5)
			(island_removal_mode 0)
		)
		(polygon
			(pts
				(xy 72.620124 -18.150078) (xy 72.620124 -13.150088) (xy 68.41998 -13.150088) (xy 68.41998 -18.150078)
			)
		)
	)
	(zone
		(layer "F.Cu")
		(hatch none 0.5)
		(connect_pads
			(clearance 0)
		)
		(min_thickness 0.25)
		(keepout
			(tracks allowed)
			(vias allowed)
			(pads allowed)
			(copperpour allowed)
			(footprints allowed)
		)
		(placement
			(enabled no)
			(sheetname "")
		)
		(fill
			(thermal_gap 0.5)
			(thermal_bridge_width 0.5)
			(island_removal_mode 0)
		)
		(polygon
			(pts
				(xy 214.860124 -46.986444) (xy 215.852502 -46.986444) (xy 215.937338 -46.901608) (xy 215.937338 -46.211744)
				(xy 215.889332 -46.163738) (xy 214.840058 -46.163738) (xy 214.77224 -46.231556) (xy 214.77224 -46.89856)
			)
		)
	)
	(zone
		(layer "F.Cu")
		(hatch none 0.5)
		(connect_pads
			(clearance 0)
		)
		(min_thickness 0.25)
		(keepout
			(tracks not_allowed)
			(vias allowed)
			(pads allowed)
			(copperpour not_allowed)
			(footprints allowed)
		)
		(placement
			(enabled no)
			(sheetname "")
		)
		(fill
			(thermal_gap 0.5)
			(thermal_bridge_width 0.5)
			(island_removal_mode 0)
		)
		(polygon
			(pts
				(xy 357.81996 -23.219918) (xy 357.81996 -18.219928) (xy 353.62007 -18.219928) (xy 353.62007 -23.219918)
			)
		)
	)
	(zone
		(layer "F.Cu")
		(hatch none 0.5)
		(connect_pads
			(clearance 0)
		)
		(min_thickness 0.25)
		(keepout
			(tracks allowed)
			(vias allowed)
			(pads allowed)
			(copperpour allowed)
			(footprints allowed)
		)
		(placement
			(enabled no)
			(sheetname "")
		)
		(fill
			(thermal_gap 0.5)
			(thermal_bridge_width 0.5)
			(island_removal_mode 0)
		)
		(polygon
			(pts
				(xy 119.183912 -356.952042) (xy 117.832632 -356.952042) (xy 117.832632 -355.671882) (xy 119.183912 -355.671882)
			)
		)
	)
	(zone
		(layer "F.Cu")
		(hatch none 0.5)
		(connect_pads
			(clearance 0)
		)
		(min_thickness 0.25)
		(keepout
			(tracks allowed)
			(vias allowed)
			(pads allowed)
			(copperpour allowed)
			(footprints allowed)
		)
		(placement
			(enabled no)
			(sheetname "")
		)
		(fill
			(thermal_gap 0.5)
			(thermal_bridge_width 0.5)
			(island_removal_mode 0)
		)
		(polygon
			(pts
				(xy 384.302 -22.606) (xy 384.302 -21.971) (xy 386.842 -21.971) (xy 386.842 -22.606)
			)
		)
	)
	(zone
		(layer "F.Cu")
		(hatch none 0.5)
		(connect_pads
			(clearance 0)
		)
		(min_thickness 0.25)
		(keepout
			(tracks allowed)
			(vias allowed)
			(pads allowed)
			(copperpour allowed)
			(footprints allowed)
		)
		(placement
			(enabled no)
			(sheetname "")
		)
		(fill
			(thermal_gap 0.5)
			(thermal_bridge_width 0.5)
			(island_removal_mode 0)
		)
		(polygon
			(pts
				(xy 430.278286 -156.326078) (xy 430.278286 -154.974798) (xy 431.558446 -154.974798) (xy 431.558446 -156.326078)
			)
		)
	)
	(zone
		(layer "F.Cu")
		(hatch none 0.5)
		(connect_pads
			(clearance 0)
		)
		(min_thickness 0.25)
		(keepout
			(tracks allowed)
			(vias allowed)
			(pads allowed)
			(copperpour allowed)
			(footprints not_allowed)
		)
		(placement
			(enabled no)
			(sheetname "")
		)
		(fill
			(thermal_gap 0.5)
			(thermal_bridge_width 0.5)
			(island_removal_mode 0)
		)
		(polygon
			(pts
				(arc
					(start 356.04069 -218.250008)
					(mid 367.998999 -207.249947)
					(end 379.957076 -218.250008)
				)
			)
		)
	)
	(zone
		(layer "F.Cu")
		(hatch none 0.5)
		(connect_pads
			(clearance 0)
		)
		(min_thickness 0.25)
		(keepout
			(tracks allowed)
			(vias allowed)
			(pads allowed)
			(copperpour allowed)
			(footprints allowed)
		)
		(placement
			(enabled no)
			(sheetname "")
		)
		(fill
			(thermal_gap 0.5)
			(thermal_bridge_width 0.5)
			(island_removal_mode 0)
		)
		(polygon
			(pts
				(xy 322.908168 -356.952042) (xy 321.556888 -356.952042) (xy 321.556888 -355.671882) (xy 322.908168 -355.671882)
			)
		)
	)
	(zone
		(layer "F.Cu")
		(hatch none 0.5)
		(connect_pads
			(clearance 0)
		)
		(min_thickness 0.25)
		(keepout
			(tracks allowed)
			(vias allowed)
			(pads allowed)
			(copperpour allowed)
			(footprints allowed)
		)
		(placement
			(enabled no)
			(sheetname "")
		)
		(fill
			(thermal_gap 0.5)
			(thermal_bridge_width 0.5)
			(island_removal_mode 0)
		)
		(polygon
			(pts
				(xy 68.694046 -344.659458) (xy 67.342766 -344.659458) (xy 67.342766 -343.379298) (xy 68.694046 -343.379298)
			)
		)
	)
	(zone
		(layer "F.Cu")
		(hatch none 0.5)
		(connect_pads
			(clearance 0)
		)
		(min_thickness 0.25)
		(keepout
			(tracks not_allowed)
			(vias allowed)
			(pads allowed)
			(copperpour not_allowed)
			(footprints allowed)
		)
		(placement
			(enabled no)
			(sheetname "")
		)
		(fill
			(thermal_gap 0.5)
			(thermal_bridge_width 0.5)
			(island_removal_mode 0)
		)
		(polygon
			(pts
				(xy 402.809964 -417.58997) (xy 412.809944 -417.58997) (xy 412.809944 -396.54988) (xy 402.809964 -396.54988)
			)
		)
	)
	(zone
		(layer "F.Cu")
		(hatch none 0.5)
		(connect_pads
			(clearance 0)
		)
		(min_thickness 0.25)
		(keepout
			(tracks allowed)
			(vias allowed)
			(pads allowed)
			(copperpour allowed)
			(footprints not_allowed)
		)
		(placement
			(enabled no)
			(sheetname "")
		)
		(fill
			(thermal_gap 0.5)
			(thermal_bridge_width 0.5)
			(island_removal_mode 0)
		)
		(polygon
			(pts
				(xy 87.520018 -23.219918) (xy 87.520018 -18.219928) (xy 83.319874 -18.219928) (xy 83.319874 -23.219918)
			)
		)
	)
	(zone
		(layer "F.Cu")
		(hatch none 0.5)
		(connect_pads
			(clearance 0)
		)
		(min_thickness 0.25)
		(keepout
			(tracks allowed)
			(vias allowed)
			(pads allowed)
			(copperpour allowed)
			(footprints allowed)
		)
		(placement
			(enabled no)
			(sheetname "")
		)
		(fill
			(thermal_gap 0.5)
			(thermal_bridge_width 0.5)
			(island_removal_mode 0)
		)
		(polygon
			(pts
				(xy 163.070286 -52.889912) (xy 163.070286 -55.80761) (xy 163.279836 -56.01716) (xy 163.892738 -56.01716)
				(xy 163.892738 -52.959762) (xy 163.822888 -52.889912)
			)
		)
	)
	(zone
		(layer "F.Cu")
		(hatch none 0.5)
		(connect_pads
			(clearance 0)
		)
		(min_thickness 0.25)
		(keepout
			(tracks allowed)
			(vias allowed)
			(pads allowed)
			(copperpour allowed)
			(footprints allowed)
		)
		(placement
			(enabled no)
			(sheetname "")
		)
		(fill
			(thermal_gap 0.5)
			(thermal_bridge_width 0.5)
			(island_removal_mode 0)
		)
		(polygon
			(pts
				(xy 226.46767 -144.254982) (xy 231.380284 -144.254982) (xy 231.568498 -144.066768) (xy 231.568498 -143.480028)
				(xy 232.348024 -142.700502) (xy 232.348024 -141.638274) (xy 231.693212 -140.983462) (xy 227.808536 -140.983462)
				(xy 227.2411 -141.550898) (xy 227.2411 -141.948154) (xy 227.083874 -142.10538) (xy 227.073206 -142.10538)
				(xy 226.348036 -142.83055) (xy 226.348036 -144.135348)
			)
		)
	)
	(zone
		(layer "F.Cu")
		(hatch none 0.5)
		(connect_pads
			(clearance 0)
		)
		(min_thickness 0.25)
		(keepout
			(tracks allowed)
			(vias allowed)
			(pads allowed)
			(copperpour allowed)
			(footprints allowed)
		)
		(placement
			(enabled no)
			(sheetname "")
		)
		(fill
			(thermal_gap 0.5)
			(thermal_bridge_width 0.5)
			(island_removal_mode 0)
		)
		(polygon
			(pts
				(xy 134.728712 -344.659458) (xy 133.377432 -344.659458) (xy 133.377432 -343.379298) (xy 134.728712 -343.379298)
			)
		)
	)
	(zone
		(layer "F.Cu")
		(hatch none 0.5)
		(connect_pads
			(clearance 0)
		)
		(min_thickness 0.25)
		(keepout
			(tracks allowed)
			(vias allowed)
			(pads allowed)
			(copperpour allowed)
			(footprints allowed)
		)
		(placement
			(enabled no)
			(sheetname "")
		)
		(fill
			(thermal_gap 0.5)
			(thermal_bridge_width 0.5)
			(island_removal_mode 0)
		)
		(polygon
			(pts
				(xy 54.451504 -365.03356) (xy 54.451504 -365.87049) (xy 54.451504 -366.360964) (xy 54.451758 -366.361218)
				(xy 55.899558 -366.361218) (xy 56.020208 -366.240568) (xy 56.020208 -365.931196) (xy 55.989982 -365.90097)
				(xy 55.989982 -365.05642) (xy 55.906924 -364.973362) (xy 54.511702 -364.973362)
			)
		)
	)
	(zone
		(layer "F.Cu")
		(hatch none 0.5)
		(connect_pads
			(clearance 0)
		)
		(min_thickness 0.25)
		(keepout
			(tracks allowed)
			(vias allowed)
			(pads allowed)
			(copperpour allowed)
			(footprints allowed)
		)
		(placement
			(enabled no)
			(sheetname "")
		)
		(fill
			(thermal_gap 0.5)
			(thermal_bridge_width 0.5)
			(island_removal_mode 0)
		)
		(polygon
			(pts
				(xy 441.463176 -356.928166) (xy 440.111896 -356.928166) (xy 440.111896 -355.648006) (xy 441.463176 -355.648006)
			)
		)
	)
	(zone
		(layer "F.Cu")
		(hatch none 0.5)
		(connect_pads
			(clearance 0)
		)
		(min_thickness 0.25)
		(keepout
			(tracks allowed)
			(vias allowed)
			(pads allowed)
			(copperpour allowed)
			(footprints not_allowed)
		)
		(placement
			(enabled no)
			(sheetname "")
		)
		(fill
			(thermal_gap 0.5)
			(thermal_bridge_width 0.5)
			(island_removal_mode 0)
		)
		(polygon
			(pts
				(xy 195.587366 -165.34511) (xy 195.587366 -90.054938) (xy 180.552344 -90.054938) (xy 180.552344 -165.34511)
			)
		)
	)
	(zone
		(layer "F.Cu")
		(hatch none 0.5)
		(connect_pads
			(clearance 0)
		)
		(min_thickness 0.25)
		(keepout
			(tracks allowed)
			(vias allowed)
			(pads allowed)
			(copperpour allowed)
			(footprints allowed)
		)
		(placement
			(enabled no)
			(sheetname "")
		)
		(fill
			(thermal_gap 0.5)
			(thermal_bridge_width 0.5)
			(island_removal_mode 0)
		)
		(polygon
			(pts
				(xy 280.637742 -19.7358) (xy 280.637742 -19.2024) (xy 281.704542 -19.2024) (xy 281.704542 -19.7358)
			)
		)
	)
	(zone
		(layer "F.Cu")
		(hatch none 0.5)
		(connect_pads
			(clearance 0)
		)
		(min_thickness 0.25)
		(keepout
			(tracks allowed)
			(vias allowed)
			(pads allowed)
			(copperpour allowed)
			(footprints allowed)
		)
		(placement
			(enabled no)
			(sheetname "")
		)
		(fill
			(thermal_gap 0.5)
			(thermal_bridge_width 0.5)
			(island_removal_mode 0)
		)
		(polygon
			(pts
				(xy 93.565726 -356.928166) (xy 92.214446 -356.928166) (xy 92.214446 -355.648006) (xy 93.565726 -355.648006)
			)
		)
	)
	(zone
		(layer "F.Cu")
		(hatch none 0.5)
		(connect_pads
			(clearance 0)
		)
		(min_thickness 0.25)
		(keepout
			(tracks allowed)
			(vias allowed)
			(pads allowed)
			(copperpour allowed)
			(footprints allowed)
		)
		(placement
			(enabled no)
			(sheetname "")
		)
		(fill
			(thermal_gap 0.5)
			(thermal_bridge_width 0.5)
			(island_removal_mode 0)
		)
		(polygon
			(pts
				(xy 237.80496 -267.958316) (xy 237.80496 -265.850116) (xy 239.43818 -265.850116) (xy 239.43818 -267.958316)
			)
		)
	)
	(zone
		(layer "F.Cu")
		(hatch none 0.5)
		(connect_pads
			(clearance 0)
		)
		(min_thickness 0.25)
		(keepout
			(tracks allowed)
			(vias allowed)
			(pads allowed)
			(copperpour allowed)
			(footprints allowed)
		)
		(placement
			(enabled no)
			(sheetname "")
		)
		(fill
			(thermal_gap 0.5)
			(thermal_bridge_width 0.5)
			(island_removal_mode 0)
		)
		(polygon
			(pts
				(xy 329.95108 -34.76117) (xy 329.95108 -33.40989) (xy 331.23124 -33.40989) (xy 331.23124 -34.76117)
			)
		)
	)
	(zone
		(layer "F.Cu")
		(hatch none 0.5)
		(connect_pads
			(clearance 0)
		)
		(min_thickness 0.25)
		(keepout
			(tracks allowed)
			(vias allowed)
			(pads allowed)
			(copperpour allowed)
			(footprints allowed)
		)
		(placement
			(enabled no)
			(sheetname "")
		)
		(fill
			(thermal_gap 0.5)
			(thermal_bridge_width 0.5)
			(island_removal_mode 0)
		)
		(polygon
			(pts
				(xy 125.401832 -356.952042) (xy 124.050552 -356.952042) (xy 124.050552 -355.671882) (xy 125.401832 -355.671882)
			)
		)
	)
	(zone
		(layer "F.Cu")
		(hatch none 0.5)
		(connect_pads
			(clearance 0)
		)
		(min_thickness 0.25)
		(keepout
			(tracks allowed)
			(vias allowed)
			(pads allowed)
			(copperpour allowed)
			(footprints allowed)
		)
		(placement
			(enabled no)
			(sheetname "")
		)
		(fill
			(thermal_gap 0.5)
			(thermal_bridge_width 0.5)
			(island_removal_mode 0)
		)
		(polygon
			(pts
				(xy 421.291512 -52.800758) (xy 421.291512 -55.718456) (xy 421.501062 -55.928006) (xy 422.113964 -55.928006)
				(xy 422.113964 -52.870608) (xy 422.044114 -52.800758)
			)
		)
	)
	(zone
		(layer "F.Cu")
		(hatch none 0.5)
		(connect_pads
			(clearance 0)
		)
		(min_thickness 0.25)
		(keepout
			(tracks allowed)
			(vias allowed)
			(pads allowed)
			(copperpour allowed)
			(footprints allowed)
		)
		(placement
			(enabled no)
			(sheetname "")
		)
		(fill
			(thermal_gap 0.5)
			(thermal_bridge_width 0.5)
			(island_removal_mode 0)
		)
		(polygon
			(pts
				(xy 221.554802 -267.958316) (xy 221.554802 -265.850116) (xy 223.188022 -265.850116) (xy 223.188022 -267.958316)
			)
		)
	)
	(zone
		(layer "F.Cu")
		(hatch none 0.5)
		(connect_pads
			(clearance 0)
		)
		(min_thickness 0.25)
		(keepout
			(tracks allowed)
			(vias allowed)
			(pads allowed)
			(copperpour allowed)
			(footprints allowed)
		)
		(placement
			(enabled no)
			(sheetname "")
		)
		(fill
			(thermal_gap 0.5)
			(thermal_bridge_width 0.5)
			(island_removal_mode 0)
		)
		(polygon
			(pts
				(xy 301.435008 -117.970808) (xy 299.347636 -117.970808) (xy 299.027596 -118.290848) (xy 299.027596 -125.694948)
				(xy 301.372524 -125.694948) (xy 301.450756 -125.616716) (xy 301.450756 -117.986556)
			)
		)
	)
	(zone
		(layer "F.Cu")
		(hatch none 0.5)
		(connect_pads
			(clearance 0)
		)
		(min_thickness 0.25)
		(keepout
			(tracks allowed)
			(vias allowed)
			(pads allowed)
			(copperpour allowed)
			(footprints allowed)
		)
		(placement
			(enabled no)
			(sheetname "")
		)
		(fill
			(thermal_gap 0.5)
			(thermal_bridge_width 0.5)
			(island_removal_mode 0)
		)
		(polygon
			(pts
				(xy 301.435008 -129.180844) (xy 299.347636 -129.180844) (xy 299.027596 -129.500884) (xy 299.027596 -136.904984)
				(xy 301.372524 -136.904984) (xy 301.450756 -136.826752) (xy 301.450756 -129.196592)
			)
		)
	)
	(zone
		(layer "F.Cu")
		(hatch none 0.5)
		(connect_pads
			(clearance 0)
		)
		(min_thickness 0.25)
		(keepout
			(tracks allowed)
			(vias allowed)
			(pads allowed)
			(copperpour allowed)
			(footprints not_allowed)
		)
		(placement
			(enabled no)
			(sheetname "")
		)
		(fill
			(thermal_gap 0.5)
			(thermal_bridge_width 0.5)
			(island_removal_mode 0)
		)
		(polygon
			(pts
				(xy 237.82909 -54.349904) (xy 224.124012 -54.349904) (xy 224.124012 -74.04989) (xy 237.82909 -74.04989)
			)
		)
	)
	(zone
		(layer "F.Cu")
		(hatch none 0.5)
		(connect_pads
			(clearance 0)
		)
		(min_thickness 0.25)
		(keepout
			(tracks allowed)
			(vias allowed)
			(pads allowed)
			(copperpour allowed)
			(footprints allowed)
		)
		(placement
			(enabled no)
			(sheetname "")
		)
		(fill
			(thermal_gap 0.5)
			(thermal_bridge_width 0.5)
			(island_removal_mode 0)
		)
		(polygon
			(pts
				(xy 150.584408 -54.008274) (xy 147.66671 -54.008274) (xy 147.45716 -54.217824) (xy 147.45716 -54.830726)
				(xy 150.514558 -54.830726) (xy 150.584408 -54.760876)
			)
		)
	)
	(zone
		(layer "F.Cu")
		(hatch none 0.5)
		(connect_pads
			(clearance 0)
		)
		(min_thickness 0.25)
		(keepout
			(tracks allowed)
			(vias allowed)
			(pads allowed)
			(copperpour allowed)
			(footprints not_allowed)
		)
		(placement
			(enabled no)
			(sheetname "")
		)
		(fill
			(thermal_gap 0.5)
			(thermal_bridge_width 0.5)
			(island_removal_mode 0)
		)
		(polygon
			(pts
				(xy 394.919962 -18.150078) (xy 394.919962 -13.150088) (xy 390.720072 -13.150088) (xy 390.720072 -18.150078)
			)
		)
	)
	(zone
		(layer "F.Cu")
		(hatch none 0.5)
		(connect_pads
			(clearance 0)
		)
		(min_thickness 0.25)
		(keepout
			(tracks not_allowed)
			(vias allowed)
			(pads allowed)
			(copperpour not_allowed)
			(footprints allowed)
		)
		(placement
			(enabled no)
			(sheetname "")
		)
		(fill
			(thermal_gap 0.5)
			(thermal_bridge_width 0.5)
			(island_removal_mode 0)
		)
		(polygon
			(pts
				(xy 293.720012 -23.219918) (xy 293.720012 -18.219928) (xy 289.520122 -18.219928) (xy 289.520122 -23.219918)
			)
		)
	)
	(zone
		(layer "F.Cu")
		(hatch none 0.5)
		(connect_pads
			(clearance 0)
		)
		(min_thickness 0.25)
		(keepout
			(tracks allowed)
			(vias allowed)
			(pads allowed)
			(copperpour allowed)
			(footprints allowed)
		)
		(placement
			(enabled no)
			(sheetname "")
		)
		(fill
			(thermal_gap 0.5)
			(thermal_bridge_width 0.5)
			(island_removal_mode 0)
		)
		(polygon
			(pts
				(xy 97.751138 -31.160974) (xy 97.751138 -29.809694) (xy 99.031298 -29.809694) (xy 99.031298 -31.160974)
			)
		)
	)
	(zone
		(layer "F.Cu")
		(hatch none 0.5)
		(connect_pads
			(clearance 0)
		)
		(min_thickness 0.25)
		(keepout
			(tracks allowed)
			(vias allowed)
			(pads allowed)
			(copperpour allowed)
			(footprints allowed)
		)
		(placement
			(enabled no)
			(sheetname "")
		)
		(fill
			(thermal_gap 0.5)
			(thermal_bridge_width 0.5)
			(island_removal_mode 0)
		)
		(polygon
			(pts
				(xy 113.264188 -163.534598) (xy 114.436144 -163.534598) (xy 114.501168 -163.469574) (xy 114.501168 -162.995102)
				(xy 113.217452 -162.995102) (xy 113.050066 -163.162488) (xy 113.050066 -163.320476)
			)
		)
	)
	(zone
		(layer "F.Cu")
		(hatch none 0.5)
		(connect_pads
			(clearance 0)
		)
		(min_thickness 0.25)
		(keepout
			(tracks not_allowed)
			(vias allowed)
			(pads allowed)
			(copperpour not_allowed)
			(footprints allowed)
		)
		(placement
			(enabled no)
			(sheetname "")
		)
		(fill
			(thermal_gap 0.5)
			(thermal_bridge_width 0.5)
			(island_removal_mode 0)
		)
		(polygon
			(pts
				(arc
					(start 143.500094 -320.900044)
					(mid 145.750026 -318.650112)
					(end 147.999958 -320.900044)
				)
				(arc
					(start 147.999958 -320.900044)
					(mid 145.750026 -323.149976)
					(end 143.500094 -320.900044)
				)
			)
		)
	)
	(zone
		(layer "F.Cu")
		(hatch none 0.5)
		(connect_pads
			(clearance 0)
		)
		(min_thickness 0.25)
		(keepout
			(tracks allowed)
			(vias allowed)
			(pads allowed)
			(copperpour allowed)
			(footprints not_allowed)
		)
		(placement
			(enabled no)
			(sheetname "")
		)
		(fill
			(thermal_gap 0.5)
			(thermal_bridge_width 0.5)
			(island_removal_mode 0)
		)
		(polygon
			(pts
				(xy 4.800092 -107.780074) (xy 39.812468 -107.780074) (xy 39.812468 -90.054938) (xy 54.84749 -90.054938)
				(xy 54.84749 -107.780074) (xy 64.4525 -107.780074) (xy 64.4525 -90.054938) (xy 79.487522 -90.054938)
				(xy 79.487522 -107.780074) (xy 155.912312 -107.780074) (xy 155.912312 -90.054938) (xy 170.947334 -90.054938)
				(xy 170.947334 -107.780074) (xy 180.552344 -107.780074) (xy 180.552344 -90.054938) (xy 195.587366 -90.054938)
				(xy 195.587366 -107.780074) (xy 213.300056 -107.780074) (xy 213.300056 -99.695)
				(arc
					(start 213.19998 -99.695)
					(mid 207.800101 -103.674924)
					(end 203.300076 -98.700082)
				)
				(arc
					(start 203.300076 -98.700082)
					(mid 207.799969 -93.725165)
					(end 213.19998 -97.70491)
				)
				(xy 213.300056 -97.70491) (xy 213.300056 -81.19999) (xy 254.299974 -81.19999) (xy 254.299974 -97.70491)
				(arc
					(start 254.40005 -97.70491)
					(mid 259.800058 -93.725202)
					(end 264.299954 -98.700082)
				)
				(arc
					(start 264.299954 -98.700082)
					(mid 259.799938 -103.675012)
					(end 254.40005 -99.695)
				)
				(xy 254.299974 -99.695) (xy 254.299974 -107.780074) (xy 272.01241 -107.780074) (xy 272.01241 -90.054938)
				(xy 287.047432 -90.054938) (xy 287.047432 -107.780074) (xy 296.652442 -107.780074) (xy 296.652442 -90.054938)
				(xy 311.687464 -90.054938) (xy 311.687464 -107.780074) (xy 388.112508 -107.780074) (xy 388.112508 -90.054938)
				(xy 403.14753 -90.054938) (xy 403.14753 -107.780074) (xy 412.75254 -107.780074) (xy 412.75254 -90.054938)
				(xy 427.787562 -90.054938) (xy 427.787562 -107.780074) (xy 462.799938 -107.780074)
				(arc
					(start 462.799938 -87.588344)
					(mid 463.028382 -86.44035)
					(end 463.678778 -85.46719)
				)
				(arc
					(start 466.30717 -82.838798)
					(mid 466.523952 -82.514361)
					(end 466.600032 -82.131662)
				)
				(xy 466.600032 -40.120062) (xy 0.999998 -40.120062)
				(arc
					(start 0.999998 -82.131662)
					(mid 1.076118 -82.514345)
					(end 1.29286 -82.838798)
				)
				(arc
					(start 3.921252 -85.46719)
					(mid 4.571602 -86.440369)
					(end 4.800092 -87.588344)
				)
			)
		)
	)
	(zone
		(layer "F.Cu")
		(hatch none 0.5)
		(connect_pads
			(clearance 0)
		)
		(min_thickness 0.25)
		(keepout
			(tracks not_allowed)
			(vias allowed)
			(pads allowed)
			(copperpour not_allowed)
			(footprints allowed)
		)
		(placement
			(enabled no)
			(sheetname "")
		)
		(fill
			(thermal_gap 0.5)
			(thermal_bridge_width 0.5)
			(island_removal_mode 0)
		)
		(polygon
			(pts
				(arc
					(start 463.14995 -13.599922)
					(mid 461.600042 -12.050014)
					(end 460.04988 -13.599922)
				)
				(arc
					(start 460.04988 -15.200122)
					(mid 461.600042 -16.750284)
					(end 463.14995 -15.200122)
				)
			)
		)
	)
	(zone
		(layer "F.Cu")
		(hatch none 0.5)
		(connect_pads
			(clearance 0)
		)
		(min_thickness 0.25)
		(keepout
			(tracks allowed)
			(vias allowed)
			(pads allowed)
			(copperpour allowed)
			(footprints allowed)
		)
		(placement
			(enabled no)
			(sheetname "")
		)
		(fill
			(thermal_gap 0.5)
			(thermal_bridge_width 0.5)
			(island_removal_mode 0)
		)
		(polygon
			(pts
				(xy 23.593298 -230.378) (xy 23.593298 -220.599) (xy 25.625298 -220.599) (xy 25.625298 -230.378)
			)
		)
	)
	(zone
		(layer "F.Cu")
		(hatch none 0.5)
		(connect_pads
			(clearance 0)
		)
		(min_thickness 0.25)
		(keepout
			(tracks allowed)
			(vias allowed)
			(pads allowed)
			(copperpour allowed)
			(footprints allowed)
		)
		(placement
			(enabled no)
			(sheetname "")
		)
		(fill
			(thermal_gap 0.5)
			(thermal_bridge_width 0.5)
			(island_removal_mode 0)
		)
		(polygon
			(pts
				(xy 326.017128 -344.659458) (xy 324.665848 -344.659458) (xy 324.665848 -343.379298) (xy 326.017128 -343.379298)
			)
		)
	)
	(zone
		(layer "F.Cu")
		(hatch none 0.5)
		(connect_pads
			(clearance 0)
		)
		(min_thickness 0.25)
		(keepout
			(tracks allowed)
			(vias allowed)
			(pads allowed)
			(copperpour allowed)
			(footprints allowed)
		)
		(placement
			(enabled no)
			(sheetname "")
		)
		(fill
			(thermal_gap 0.5)
			(thermal_bridge_width 0.5)
			(island_removal_mode 0)
		)
		(polygon
			(pts
				(xy 335.344008 -344.659458) (xy 333.992728 -344.659458) (xy 333.992728 -343.379298) (xy 335.344008 -343.379298)
			)
		)
	)
	(zone
		(layer "F.Cu")
		(hatch none 0.5)
		(connect_pads
			(clearance 0)
		)
		(min_thickness 0.25)
		(keepout
			(tracks allowed)
			(vias allowed)
			(pads allowed)
			(copperpour allowed)
			(footprints allowed)
		)
		(placement
			(enabled no)
			(sheetname "")
		)
		(fill
			(thermal_gap 0.5)
			(thermal_bridge_width 0.5)
			(island_removal_mode 0)
		)
		(polygon
			(pts
				(xy 434.784246 -54.008274) (xy 431.866548 -54.008274) (xy 431.656998 -54.217824) (xy 431.656998 -54.830726)
				(xy 434.714396 -54.830726) (xy 434.784246 -54.760876)
			)
		)
	)
	(zone
		(layer "F.Cu")
		(hatch none 0.5)
		(connect_pads
			(clearance 0)
		)
		(min_thickness 0.25)
		(keepout
			(tracks allowed)
			(vias allowed)
			(pads allowed)
			(copperpour allowed)
			(footprints allowed)
		)
		(placement
			(enabled no)
			(sheetname "")
		)
		(fill
			(thermal_gap 0.5)
			(thermal_bridge_width 0.5)
			(island_removal_mode 0)
		)
		(polygon
			(pts
				(xy 357.173276 -284.67558) (xy 358.085898 -284.67558) (xy 358.481884 -284.279594) (xy 358.481884 -282.410408)
				(xy 356.953312 -282.410408) (xy 356.898448 -282.465272) (xy 356.898448 -284.400752)
			)
		)
	)
	(zone
		(layer "F.Cu")
		(hatch none 0.5)
		(connect_pads
			(clearance 0)
		)
		(min_thickness 0.25)
		(keepout
			(tracks allowed)
			(vias allowed)
			(pads allowed)
			(copperpour allowed)
			(footprints not_allowed)
		)
		(placement
			(enabled no)
			(sheetname "")
		)
		(fill
			(thermal_gap 0.5)
			(thermal_bridge_width 0.5)
			(island_removal_mode 0)
		)
		(polygon
			(pts
				(xy 100.161598 -278.85009)
				(arc
					(start 100.161598 -285.949898)
					(mid 101.75386 -286.783489)
					(end 102.82047 -288.230056)
				)
				(xy 135.23849 -288.230056)
				(arc
					(start 135.23849 -279.88006)
					(mid 133.084077 -278.454887)
					(end 132.249926 -276.010116)
				)
				(xy 132.249926 -278.85009)
			)
		)
	)
	(zone
		(layer "F.Cu")
		(hatch none 0.5)
		(connect_pads
			(clearance 0)
		)
		(min_thickness 0.25)
		(keepout
			(tracks allowed)
			(vias allowed)
			(pads allowed)
			(copperpour allowed)
			(footprints not_allowed)
		)
		(placement
			(enabled no)
			(sheetname "")
		)
		(fill
			(thermal_gap 0.5)
			(thermal_bridge_width 0.5)
			(island_removal_mode 0)
		)
		(polygon
			(pts
				(xy 263.51992 -23.219918) (xy 267.720064 -23.219918) (xy 267.720064 -18.219928) (xy 263.51992 -18.219928)
			)
		)
	)
	(zone
		(layer "F.Cu")
		(hatch none 0.5)
		(connect_pads
			(clearance 0)
		)
		(min_thickness 0.25)
		(keepout
			(tracks allowed)
			(vias allowed)
			(pads allowed)
			(copperpour allowed)
			(footprints allowed)
		)
		(placement
			(enabled no)
			(sheetname "")
		)
		(fill
			(thermal_gap 0.5)
			(thermal_bridge_width 0.5)
			(island_removal_mode 0)
		)
		(polygon
			(pts
				(xy 12.535662 -276.354794) (xy 12.535662 -274.703794) (xy 14.186662 -274.703794) (xy 14.186662 -276.354794)
			)
		)
	)
	(zone
		(layer "F.Cu")
		(hatch none 0.5)
		(connect_pads
			(clearance 0)
		)
		(min_thickness 0.25)
		(keepout
			(tracks allowed)
			(vias allowed)
			(pads allowed)
			(copperpour allowed)
			(footprints allowed)
		)
		(placement
			(enabled no)
			(sheetname "")
		)
		(fill
			(thermal_gap 0.5)
			(thermal_bridge_width 0.5)
			(island_removal_mode 0)
		)
		(polygon
			(pts
				(xy 20.991576 -52.800758) (xy 20.991576 -55.718456) (xy 21.201126 -55.928006) (xy 21.814028 -55.928006)
				(xy 21.814028 -52.870608) (xy 21.744178 -52.800758)
			)
		)
	)
	(zone
		(layer "F.Cu")
		(hatch none 0.5)
		(connect_pads
			(clearance 0)
		)
		(min_thickness 0.25)
		(keepout
			(tracks allowed)
			(vias allowed)
			(pads allowed)
			(copperpour allowed)
			(footprints allowed)
		)
		(placement
			(enabled no)
			(sheetname "")
		)
		(fill
			(thermal_gap 0.5)
			(thermal_bridge_width 0.5)
			(island_removal_mode 0)
		)
		(polygon
			(pts
				(xy 227.27793 -118.018052) (xy 232.273602 -118.018052) (xy 232.490772 -117.800882) (xy 232.490772 -117.515132)
				(xy 232.365042 -117.389402) (xy 227.34651 -117.389402) (xy 227.18649 -117.549422) (xy 227.18649 -117.926612)
			)
		)
	)
	(zone
		(layer "F.Cu")
		(hatch none 0.5)
		(connect_pads
			(clearance 0)
		)
		(min_thickness 0.25)
		(keepout
			(tracks allowed)
			(vias allowed)
			(pads allowed)
			(copperpour allowed)
			(footprints allowed)
		)
		(placement
			(enabled no)
			(sheetname "")
		)
		(fill
			(thermal_gap 0.5)
			(thermal_bridge_width 0.5)
			(island_removal_mode 0)
		)
		(polygon
			(pts
				(xy 131.619752 -356.952042) (xy 130.268472 -356.952042) (xy 130.268472 -355.671882) (xy 131.619752 -355.671882)
			)
		)
	)
	(zone
		(layer "F.Cu")
		(hatch none 0.5)
		(connect_pads
			(clearance 0)
		)
		(min_thickness 0.25)
		(keepout
			(tracks allowed)
			(vias allowed)
			(pads allowed)
			(copperpour allowed)
			(footprints allowed)
		)
		(placement
			(enabled no)
			(sheetname "")
		)
		(fill
			(thermal_gap 0.5)
			(thermal_bridge_width 0.5)
			(island_removal_mode 0)
		)
		(polygon
			(pts
				(xy 81.129886 -344.659458) (xy 79.778606 -344.659458) (xy 79.778606 -343.379298) (xy 81.129886 -343.379298)
			)
		)
	)
	(zone
		(layer "F.Cu")
		(hatch none 0.5)
		(connect_pads
			(clearance 0)
		)
		(min_thickness 0.25)
		(keepout
			(tracks not_allowed)
			(vias allowed)
			(pads allowed)
			(copperpour not_allowed)
			(footprints allowed)
		)
		(placement
			(enabled no)
			(sheetname "")
		)
		(fill
			(thermal_gap 0.5)
			(thermal_bridge_width 0.5)
			(island_removal_mode 0)
		)
		(polygon
			(pts
				(arc
					(start 206.600044 -98.700082)
					(mid 208.300066 -97.00006)
					(end 210.000088 -98.700082)
				)
				(arc
					(start 210.000088 -98.700082)
					(mid 208.300066 -100.400104)
					(end 206.600044 -98.700082)
				)
			)
		)
	)
	(zone
		(layer "F.Cu")
		(hatch none 0.5)
		(connect_pads
			(clearance 0)
		)
		(min_thickness 0.25)
		(keepout
			(tracks allowed)
			(vias allowed)
			(pads allowed)
			(copperpour allowed)
			(footprints allowed)
		)
		(placement
			(enabled no)
			(sheetname "")
		)
		(fill
			(thermal_gap 0.5)
			(thermal_bridge_width 0.5)
			(island_removal_mode 0)
		)
		(polygon
			(pts
				(xy 233.82732 -81.986374) (xy 232.99039 -81.986374) (xy 232.499916 -81.986374) (xy 232.499662 -81.986628)
				(xy 232.499662 -83.434428) (xy 232.620312 -83.555078) (xy 232.929684 -83.555078) (xy 232.95991 -83.524852)
				(xy 233.80446 -83.524852) (xy 233.887518 -83.441794) (xy 233.887518 -82.046572)
			)
		)
	)
	(zone
		(layer "F.Cu")
		(hatch none 0.5)
		(connect_pads
			(clearance 0)
		)
		(min_thickness 0.25)
		(keepout
			(tracks allowed)
			(vias allowed)
			(pads allowed)
			(copperpour allowed)
			(footprints allowed)
		)
		(placement
			(enabled no)
			(sheetname "")
		)
		(fill
			(thermal_gap 0.5)
			(thermal_bridge_width 0.5)
			(island_removal_mode 0)
		)
		(polygon
			(pts
				(xy 348.67469 -284.67558) (xy 349.587312 -284.67558) (xy 349.983298 -284.279594) (xy 349.983298 -282.410408)
				(xy 348.454726 -282.410408) (xy 348.399862 -282.465272) (xy 348.399862 -284.400752)
			)
		)
	)
	(zone
		(layer "F.Cu")
		(hatch none 0.5)
		(connect_pads
			(clearance 0)
		)
		(min_thickness 0.25)
		(keepout
			(tracks allowed)
			(vias allowed)
			(pads allowed)
			(copperpour allowed)
			(footprints allowed)
		)
		(placement
			(enabled no)
			(sheetname "")
		)
		(fill
			(thermal_gap 0.5)
			(thermal_bridge_width 0.5)
			(island_removal_mode 0)
		)
		(polygon
			(pts
				(xy 386.897372 -122.13463) (xy 386.897372 -120.78335) (xy 388.177532 -120.78335) (xy 388.177532 -122.13463)
			)
		)
	)
	(zone
		(layer "F.Cu")
		(hatch none 0.5)
		(connect_pads
			(clearance 0)
		)
		(min_thickness 0.25)
		(keepout
			(tracks allowed)
			(vias allowed)
			(pads allowed)
			(copperpour allowed)
			(footprints not_allowed)
		)
		(placement
			(enabled no)
			(sheetname "")
		)
		(fill
			(thermal_gap 0.5)
			(thermal_bridge_width 0.5)
			(island_removal_mode 0)
		)
		(polygon
			(pts
				(xy 162.72002 -18.150078) (xy 162.72002 -13.150088) (xy 158.519876 -13.150088) (xy 158.519876 -18.150078)
			)
		)
	)
	(zone
		(layer "F.Cu")
		(hatch none 0.5)
		(connect_pads
			(clearance 0)
		)
		(min_thickness 0.25)
		(keepout
			(tracks not_allowed)
			(vias allowed)
			(pads allowed)
			(copperpour not_allowed)
			(footprints allowed)
		)
		(placement
			(enabled no)
			(sheetname "")
		)
		(fill
			(thermal_gap 0.5)
			(thermal_bridge_width 0.5)
			(island_removal_mode 0)
		)
		(polygon
			(pts
				(arc
					(start 443.799976 -84.70011)
					(mid 448.799966 -79.70012)
					(end 453.799956 -84.70011)
				)
				(arc
					(start 453.799956 -84.70011)
					(mid 448.799966 -89.7001)
					(end 443.799976 -84.70011)
				)
			)
		)
	)
	(zone
		(layer "F.Cu")
		(hatch none 0.5)
		(connect_pads
			(clearance 0)
		)
		(min_thickness 0.25)
		(keepout
			(tracks allowed)
			(vias allowed)
			(pads allowed)
			(copperpour allowed)
			(footprints not_allowed)
		)
		(placement
			(enabled no)
			(sheetname "")
		)
		(fill
			(thermal_gap 0.5)
			(thermal_bridge_width 0.5)
			(island_removal_mode 0)
		)
		(polygon
			(pts
				(xy 8.96493 -40.120062) (xy 16.964914 -40.120062) (xy 16.964914 -13.850112) (xy 8.96493 -13.850112)
			)
		)
	)
	(zone
		(layer "F.Cu")
		(hatch none 0.5)
		(connect_pads
			(clearance 0)
		)
		(min_thickness 0.25)
		(keepout
			(tracks allowed)
			(vias allowed)
			(pads allowed)
			(copperpour allowed)
			(footprints not_allowed)
		)
		(placement
			(enabled no)
			(sheetname "")
		)
		(fill
			(thermal_gap 0.5)
			(thermal_bridge_width 0.5)
			(island_removal_mode 0)
		)
		(polygon
			(pts
				(xy 311.687464 -165.34511) (xy 311.687464 -90.054938) (xy 296.652442 -90.054938) (xy 296.652442 -165.34511)
			)
		)
	)
	(zone
		(layer "F.Cu")
		(hatch none 0.5)
		(connect_pads
			(clearance 0)
		)
		(min_thickness 0.25)
		(keepout
			(tracks allowed)
			(vias allowed)
			(pads allowed)
			(copperpour allowed)
			(footprints allowed)
		)
		(placement
			(enabled no)
			(sheetname "")
		)
		(fill
			(thermal_gap 0.5)
			(thermal_bridge_width 0.5)
			(island_removal_mode 0)
		)
		(polygon
			(pts
				(xy 14.614652 -35.334448) (xy 16.326612 -35.334448) (xy 16.562578 -35.098482) (xy 16.562578 -26.926794)
				(xy 16.169132 -26.533348) (xy 14.870176 -26.533348) (xy 14.614652 -26.788872)
			)
		)
	)
	(zone
		(layer "F.Cu")
		(hatch none 0.5)
		(connect_pads
			(clearance 0)
		)
		(min_thickness 0.25)
		(keepout
			(tracks allowed)
			(vias allowed)
			(pads allowed)
			(copperpour allowed)
			(footprints allowed)
		)
		(placement
			(enabled no)
			(sheetname "")
		)
		(fill
			(thermal_gap 0.5)
			(thermal_bridge_width 0.5)
			(island_removal_mode 0)
		)
		(polygon
			(pts
				(xy 143.462502 -199.852534)
				(arc
					(start 143.462502 -201.132186)
					(mid 143.447623 -201.168107)
					(end 143.411702 -201.182986)
				)
				(arc
					(start 142.701772 -201.182986)
					(mid 142.665851 -201.168107)
					(end 142.650972 -201.132186)
				)
				(xy 142.650972 -199.852534) (xy 142.650972 -199.287384) (xy 142.720822 -199.217534) (xy 142.973298 -199.217534)
				(xy 143.462502 -199.706738)
			)
		)
	)
	(zone
		(layer "F.Cu")
		(hatch none 0.5)
		(connect_pads
			(clearance 0)
		)
		(min_thickness 0.25)
		(keepout
			(tracks allowed)
			(vias allowed)
			(pads allowed)
			(copperpour allowed)
			(footprints allowed)
		)
		(placement
			(enabled no)
			(sheetname "")
		)
		(fill
			(thermal_gap 0.5)
			(thermal_bridge_width 0.5)
			(island_removal_mode 0)
		)
		(polygon
			(pts
				(xy 292.6842 -54.008274) (xy 289.766502 -54.008274) (xy 289.556952 -54.217824) (xy 289.556952 -54.830726)
				(xy 292.61435 -54.830726) (xy 292.6842 -54.760876)
			)
		)
	)
	(zone
		(layer "F.Cu")
		(hatch none 0.5)
		(connect_pads
			(clearance 0)
		)
		(min_thickness 0.25)
		(keepout
			(tracks not_allowed)
			(vias allowed)
			(pads allowed)
			(copperpour not_allowed)
			(footprints allowed)
		)
		(placement
			(enabled no)
			(sheetname "")
		)
		(fill
			(thermal_gap 0.5)
			(thermal_bridge_width 0.5)
			(island_removal_mode 0)
		)
		(polygon
			(pts
				(arc
					(start 112.815116 -17.999964)
					(mid 110.01502 -20.80006)
					(end 107.214924 -17.999964)
				)
				(arc
					(start 107.214924 -17.999964)
					(mid 110.01502 -15.199868)
					(end 112.815116 -17.999964)
				)
			)
		)
	)
	(zone
		(layer "F.Cu")
		(hatch none 0.5)
		(connect_pads
			(clearance 0)
		)
		(min_thickness 0.25)
		(keepout
			(tracks not_allowed)
			(vias allowed)
			(pads allowed)
			(copperpour not_allowed)
			(footprints allowed)
		)
		(placement
			(enabled no)
			(sheetname "")
		)
		(fill
			(thermal_gap 0.5)
			(thermal_bridge_width 0.5)
			(island_removal_mode 0)
		)
		(polygon
			(pts
				(arc
					(start 433.449984 -270.89989)
					(mid 437.950102 -266.399772)
					(end 442.449966 -270.89989)
				)
				(arc
					(start 442.449966 -270.89989)
					(mid 437.950102 -275.399754)
					(end 433.449984 -270.89989)
				)
			)
		)
	)
	(zone
		(layer "F.Cu")
		(hatch none 0.5)
		(connect_pads
			(clearance 0)
		)
		(min_thickness 0.25)
		(keepout
			(tracks allowed)
			(vias allowed)
			(pads allowed)
			(copperpour allowed)
			(footprints allowed)
		)
		(placement
			(enabled no)
			(sheetname "")
		)
		(fill
			(thermal_gap 0.5)
			(thermal_bridge_width 0.5)
			(island_removal_mode 0)
		)
		(polygon
			(pts
				(xy 279.191466 -52.800758) (xy 279.191466 -55.718456) (xy 279.401016 -55.928006) (xy 280.013918 -55.928006)
				(xy 280.013918 -52.870608) (xy 279.944068 -52.800758)
			)
		)
	)
	(zone
		(layer "F.Cu")
		(hatch none 0.5)
		(connect_pads
			(clearance 0)
		)
		(min_thickness 0.25)
		(keepout
			(tracks allowed)
			(vias allowed)
			(pads allowed)
			(copperpour allowed)
			(footprints allowed)
		)
		(placement
			(enabled no)
			(sheetname "")
		)
		(fill
			(thermal_gap 0.5)
			(thermal_bridge_width 0.5)
			(island_removal_mode 0)
		)
		(polygon
			(pts
				(xy 328.239628 -100.623624) (xy 331.157326 -100.623624) (xy 331.366876 -100.414074) (xy 331.366876 -99.801172)
				(xy 328.309478 -99.801172) (xy 328.239628 -99.871022)
			)
		)
	)
	(zone
		(layer "F.Cu")
		(hatch none 0.5)
		(connect_pads
			(clearance 0)
		)
		(min_thickness 0.25)
		(keepout
			(tracks allowed)
			(vias allowed)
			(pads allowed)
			(copperpour allowed)
			(footprints allowed)
		)
		(placement
			(enabled no)
			(sheetname "")
		)
		(fill
			(thermal_gap 0.5)
			(thermal_bridge_width 0.5)
			(island_removal_mode 0)
		)
		(polygon
			(pts
				(xy 338.508848 -320.296032) (xy 338.508848 -321.947032) (xy 336.476848 -321.947032) (xy 336.476848 -320.296032)
			)
		)
	)
	(zone
		(layer "F.Cu")
		(hatch none 0.5)
		(connect_pads
			(clearance 0)
		)
		(min_thickness 0.25)
		(keepout
			(tracks allowed)
			(vias allowed)
			(pads allowed)
			(copperpour allowed)
			(footprints allowed)
		)
		(placement
			(enabled no)
			(sheetname "")
		)
		(fill
			(thermal_gap 0.5)
			(thermal_bridge_width 0.5)
			(island_removal_mode 0)
		)
		(polygon
			(pts
				(xy 188.860176 -46.986444) (xy 189.852554 -46.986444) (xy 189.93739 -46.901608) (xy 189.93739 -46.211744)
				(xy 189.889384 -46.163738) (xy 188.84011 -46.163738) (xy 188.772292 -46.231556) (xy 188.772292 -46.89856)
			)
		)
	)
	(zone
		(layer "F.Cu")
		(hatch none 0.5)
		(connect_pads
			(clearance 0)
		)
		(min_thickness 0.25)
		(keepout
			(tracks allowed)
			(vias allowed)
			(pads allowed)
			(copperpour allowed)
			(footprints allowed)
		)
		(placement
			(enabled no)
			(sheetname "")
		)
		(fill
			(thermal_gap 0.5)
			(thermal_bridge_width 0.5)
			(island_removal_mode 0)
		)
		(polygon
			(pts
				(xy 311.53608 -147.319492) (xy 311.53608 -145.968212) (xy 312.81624 -145.968212) (xy 312.81624 -147.319492)
			)
		)
	)
	(zone
		(layer "F.Cu")
		(hatch none 0.5)
		(connect_pads
			(clearance 0)
		)
		(min_thickness 0.25)
		(keepout
			(tracks allowed)
			(vias allowed)
			(pads allowed)
			(copperpour allowed)
			(footprints allowed)
		)
		(placement
			(enabled no)
			(sheetname "")
		)
		(fill
			(thermal_gap 0.5)
			(thermal_bridge_width 0.5)
			(island_removal_mode 0)
		)
		(polygon
			(pts
				(xy 69.235066 -129.180844) (xy 67.147694 -129.180844) (xy 66.827654 -129.500884) (xy 66.827654 -136.904984)
				(xy 69.172582 -136.904984) (xy 69.250814 -136.826752) (xy 69.250814 -129.196592)
			)
		)
	)
	(zone
		(layer "F.Cu")
		(hatch none 0.5)
		(connect_pads
			(clearance 0)
		)
		(min_thickness 0.25)
		(keepout
			(tracks allowed)
			(vias allowed)
			(pads allowed)
			(copperpour allowed)
			(footprints allowed)
		)
		(placement
			(enabled no)
			(sheetname "")
		)
		(fill
			(thermal_gap 0.5)
			(thermal_bridge_width 0.5)
			(island_removal_mode 0)
		)
		(polygon
			(pts
				(xy 366.0902 -150.1902) (xy 366.0902 -148.5392) (xy 367.8174 -148.5392) (xy 367.8174 -150.1902)
			)
		)
	)
	(zone
		(layer "F.Cu")
		(hatch none 0.5)
		(connect_pads
			(clearance 0)
		)
		(min_thickness 0.25)
		(keepout
			(tracks allowed)
			(vias allowed)
			(pads allowed)
			(copperpour allowed)
			(footprints allowed)
		)
		(placement
			(enabled no)
			(sheetname "")
		)
		(fill
			(thermal_gap 0.5)
			(thermal_bridge_width 0.5)
			(island_removal_mode 0)
		)
		(polygon
			(pts
				(xy 97.6122 -244.1194) (xy 97.6122 -242.3414) (xy 99.3902 -242.3414) (xy 99.3902 -244.1194)
			)
		)
	)
	(zone
		(layer "F.Cu")
		(hatch none 0.5)
		(connect_pads
			(clearance 0)
		)
		(min_thickness 0.25)
		(keepout
			(tracks allowed)
			(vias allowed)
			(pads allowed)
			(copperpour allowed)
			(footprints not_allowed)
		)
		(placement
			(enabled no)
			(sheetname "")
		)
		(fill
			(thermal_gap 0.5)
			(thermal_bridge_width 0.5)
			(island_removal_mode 0)
		)
		(polygon
			(pts
				(xy 200.49998 -320.650108) (xy 200.49998 -271.15008) (xy 150.999952 -271.15008) (xy 150.999952 -320.650108)
			)
		)
	)
	(zone
		(layer "F.Cu")
		(hatch none 0.5)
		(connect_pads
			(clearance 0)
		)
		(min_thickness 0.25)
		(keepout
			(tracks allowed)
			(vias allowed)
			(pads allowed)
			(copperpour allowed)
			(footprints allowed)
		)
		(placement
			(enabled no)
			(sheetname "")
		)
		(fill
			(thermal_gap 0.5)
			(thermal_bridge_width 0.5)
			(island_removal_mode 0)
		)
		(polygon
			(pts
				(xy 38.597332 -133.344666) (xy 38.597332 -131.993386) (xy 39.877492 -131.993386) (xy 39.877492 -133.344666)
			)
		)
	)
	(zone
		(layer "F.Cu")
		(hatch none 0.5)
		(connect_pads
			(clearance 0)
		)
		(min_thickness 0.25)
		(keepout
			(tracks not_allowed)
			(vias allowed)
			(pads allowed)
			(copperpour not_allowed)
			(footprints allowed)
		)
		(placement
			(enabled no)
			(sheetname "")
		)
		(fill
			(thermal_gap 0.5)
			(thermal_bridge_width 0.5)
			(island_removal_mode 0)
		)
		(polygon
			(pts
				(arc
					(start 289.16503 -5.999988)
					(mid 284.16504 -10.999978)
					(end 279.16505 -5.999988)
				)
				(arc
					(start 279.16505 -5.999988)
					(mid 284.16504 -0.999998)
					(end 289.16503 -5.999988)
				)
			)
		)
	)
	(zone
		(layer "F.Cu")
		(hatch none 0.5)
		(connect_pads
			(clearance 0)
		)
		(min_thickness 0.25)
		(keepout
			(tracks allowed)
			(vias allowed)
			(pads allowed)
			(copperpour allowed)
			(footprints not_allowed)
		)
		(placement
			(enabled no)
			(sheetname "")
		)
		(fill
			(thermal_gap 0.5)
			(thermal_bridge_width 0.5)
			(island_removal_mode 0)
		)
		(polygon
			(pts
				(arc
					(start -1.999996 -407.599896)
					(mid 5.999988 -399.599912)
					(end 13.999972 -407.599896)
				)
				(arc
					(start 13.999972 -407.599896)
					(mid 5.999988 -415.59988)
					(end -1.999996 -407.599896)
				)
			)
		)
	)
	(zone
		(layer "F.Cu")
		(hatch none 0.5)
		(connect_pads
			(clearance 0)
		)
		(min_thickness 0.25)
		(keepout
			(tracks allowed)
			(vias allowed)
			(pads allowed)
			(copperpour allowed)
			(footprints not_allowed)
		)
		(placement
			(enabled no)
			(sheetname "")
		)
		(fill
			(thermal_gap 0.5)
			(thermal_bridge_width 0.5)
			(island_removal_mode 0)
		)
		(polygon
			(pts
				(arc
					(start 260.199886 -393.100052)
					(mid 268.200124 -385.099814)
					(end 276.200108 -393.100052)
				)
				(arc
					(start 276.200108 -393.100052)
					(mid 268.200124 -401.100036)
					(end 260.199886 -393.100052)
				)
			)
		)
	)
	(zone
		(layer "F.Cu")
		(hatch none 0.5)
		(connect_pads
			(clearance 0)
		)
		(min_thickness 0.25)
		(keepout
			(tracks allowed)
			(vias allowed)
			(pads allowed)
			(copperpour allowed)
			(footprints allowed)
		)
		(placement
			(enabled no)
			(sheetname "")
		)
		(fill
			(thermal_gap 0.5)
			(thermal_bridge_width 0.5)
			(island_removal_mode 0)
		)
		(polygon
			(pts
				(xy 203.408026 -35.549586) (xy 204.962252 -35.549586) (xy 205.114652 -35.397186) (xy 205.114652 -27.503882)
				(xy 205.068932 -27.458162) (xy 203.301346 -27.458162) (xy 202.82916 -27.930348) (xy 202.82916 -34.97072)
			)
		)
	)
	(zone
		(layer "F.Cu")
		(hatch none 0.5)
		(connect_pads
			(clearance 0)
		)
		(min_thickness 0.25)
		(keepout
			(tracks allowed)
			(vias allowed)
			(pads allowed)
			(copperpour allowed)
			(footprints allowed)
		)
		(placement
			(enabled no)
			(sheetname "")
		)
		(fill
			(thermal_gap 0.5)
			(thermal_bridge_width 0.5)
			(island_removal_mode 0)
		)
		(polygon
			(pts
				(xy 81.129886 -356.952042) (xy 79.778606 -356.952042) (xy 79.778606 -355.671882) (xy 81.129886 -355.671882)
			)
		)
	)
	(zone
		(layer "F.Cu")
		(hatch none 0.5)
		(connect_pads
			(clearance 0)
		)
		(min_thickness 0.25)
		(keepout
			(tracks allowed)
			(vias allowed)
			(pads allowed)
			(copperpour allowed)
			(footprints allowed)
		)
		(placement
			(enabled no)
			(sheetname "")
		)
		(fill
			(thermal_gap 0.5)
			(thermal_bridge_width 0.5)
			(island_removal_mode 0)
		)
		(polygon
			(pts
				(xy 45.308012 -350.80575) (xy 43.956732 -350.80575) (xy 43.956732 -349.52559) (xy 45.308012 -349.52559)
			)
		)
	)
	(zone
		(layer "F.Cu")
		(hatch none 0.5)
		(connect_pads
			(clearance 0)
		)
		(min_thickness 0.25)
		(keepout
			(tracks allowed)
			(vias allowed)
			(pads allowed)
			(copperpour allowed)
			(footprints allowed)
		)
		(placement
			(enabled no)
			(sheetname "")
		)
		(fill
			(thermal_gap 0.5)
			(thermal_bridge_width 0.5)
			(island_removal_mode 0)
		)
		(polygon
			(pts
				(xy 268.155166 -135.13816) (xy 268.155166 -133.78688) (xy 269.435326 -133.78688) (xy 269.435326 -135.13816)
			)
		)
	)
	(zone
		(layer "F.Cu")
		(hatch none 0.5)
		(connect_pads
			(clearance 0)
		)
		(min_thickness 0.25)
		(keepout
			(tracks allowed)
			(vias allowed)
			(pads allowed)
			(copperpour allowed)
			(footprints allowed)
		)
		(placement
			(enabled no)
			(sheetname "")
		)
		(fill
			(thermal_gap 0.5)
			(thermal_bridge_width 0.5)
			(island_removal_mode 0)
		)
		(polygon
			(pts
				(arc
					(start 145.918174 -206.308198)
					(mid 145.954095 -206.323077)
					(end 145.968974 -206.358998)
				)
				(xy 145.968974 -207.068928) (xy 145.969736 -207.06969) (xy 145.969736 -207.610202) (xy 145.964402 -207.615536)
				(xy 144.601946 -207.615536) (xy 144.587722 -207.601312) (xy 144.587722 -207.068928)
				(arc
					(start 144.587722 -206.358998)
					(mid 144.602601 -206.323077)
					(end 144.638522 -206.308198)
				)
			)
		)
	)
	(zone
		(layer "F.Cu")
		(hatch none 0.5)
		(connect_pads
			(clearance 0)
		)
		(min_thickness 0.25)
		(keepout
			(tracks not_allowed)
			(vias allowed)
			(pads allowed)
			(copperpour not_allowed)
			(footprints allowed)
		)
		(placement
			(enabled no)
			(sheetname "")
		)
		(fill
			(thermal_gap 0.5)
			(thermal_bridge_width 0.5)
			(island_removal_mode 0)
		)
		(polygon
			(pts
				(arc
					(start 231.115108 -5.999988)
					(mid 226.115118 -10.999978)
					(end 221.114874 -5.999988)
				)
				(arc
					(start 221.114874 -5.999988)
					(mid 226.115118 -0.999744)
					(end 231.115108 -5.999988)
				)
			)
		)
	)
	(zone
		(layer "F.Cu")
		(hatch none 0.5)
		(connect_pads
			(clearance 0)
		)
		(min_thickness 0.25)
		(keepout
			(tracks allowed)
			(vias allowed)
			(pads allowed)
			(copperpour allowed)
			(footprints allowed)
		)
		(placement
			(enabled no)
			(sheetname "")
		)
		(fill
			(thermal_gap 0.5)
			(thermal_bridge_width 0.5)
			(island_removal_mode 0)
		)
		(polygon
			(pts
				(xy 101.455982 -113.89741) (xy 106.451654 -113.89741) (xy 106.668824 -113.68024) (xy 106.668824 -113.39449)
				(xy 106.543094 -113.26876) (xy 101.524562 -113.26876) (xy 101.364542 -113.42878) (xy 101.364542 -113.80597)
			)
		)
	)
	(zone
		(layer "F.Cu")
		(hatch none 0.5)
		(connect_pads
			(clearance 0)
		)
		(min_thickness 0.25)
		(keepout
			(tracks not_allowed)
			(vias allowed)
			(pads allowed)
			(copperpour not_allowed)
			(footprints allowed)
		)
		(placement
			(enabled no)
			(sheetname "")
		)
		(fill
			(thermal_gap 0.5)
			(thermal_bridge_width 0.5)
			(island_removal_mode 0)
		)
		(polygon
			(pts
				(arc
					(start 458.732382 -5.999988)
					(mid 455.93254 -8.79983)
					(end 453.132444 -5.999988)
				)
				(arc
					(start 453.132444 -5.999988)
					(mid 455.93254 -3.199892)
					(end 458.732382 -5.999988)
				)
			)
		)
	)
	(zone
		(layer "F.Cu")
		(hatch none 0.5)
		(connect_pads
			(clearance 0)
		)
		(min_thickness 0.25)
		(keepout
			(tracks allowed)
			(vias allowed)
			(pads allowed)
			(copperpour allowed)
			(footprints allowed)
		)
		(placement
			(enabled no)
			(sheetname "")
		)
		(fill
			(thermal_gap 0.5)
			(thermal_bridge_width 0.5)
			(island_removal_mode 0)
		)
		(polygon
			(pts
				(xy 50.064924 -137.42924) (xy 52.152296 -137.42924) (xy 52.472336 -137.1092) (xy 52.472336 -129.7051)
				(xy 50.127408 -129.7051) (xy 50.049176 -129.783332) (xy 50.049176 -137.413492)
			)
		)
	)
	(zone
		(layer "F.Cu")
		(hatch none 0.5)
		(connect_pads
			(clearance 0)
		)
		(min_thickness 0.25)
		(keepout
			(tracks allowed)
			(vias allowed)
			(pads allowed)
			(copperpour allowed)
			(footprints allowed)
		)
		(placement
			(enabled no)
			(sheetname "")
		)
		(fill
			(thermal_gap 0.5)
			(thermal_bridge_width 0.5)
			(island_removal_mode 0)
		)
		(polygon
			(pts
				(xy 403.381464 -356.928166) (xy 402.030184 -356.928166) (xy 402.030184 -355.648006) (xy 403.381464 -355.648006)
			)
		)
	)
	(zone
		(layer "F.Cu")
		(hatch none 0.5)
		(connect_pads
			(clearance 0)
		)
		(min_thickness 0.25)
		(keepout
			(tracks not_allowed)
			(vias allowed)
			(pads allowed)
			(copperpour not_allowed)
			(footprints allowed)
		)
		(placement
			(enabled no)
			(sheetname "")
		)
		(fill
			(thermal_gap 0.5)
			(thermal_bridge_width 0.5)
			(island_removal_mode 0)
		)
		(polygon
			(pts
				(arc
					(start 433.449984 -320.900044)
					(mid 437.950102 -316.399926)
					(end 442.449966 -320.900044)
				)
				(arc
					(start 442.449966 -320.900044)
					(mid 437.950102 -325.399908)
					(end 433.449984 -320.900044)
				)
			)
		)
	)
	(zone
		(layer "F.Cu")
		(hatch none 0.5)
		(connect_pads
			(clearance 0)
		)
		(min_thickness 0.25)
		(keepout
			(tracks allowed)
			(vias allowed)
			(pads allowed)
			(copperpour allowed)
			(footprints allowed)
		)
		(placement
			(enabled no)
			(sheetname "")
		)
		(fill
			(thermal_gap 0.5)
			(thermal_bridge_width 0.5)
			(island_removal_mode 0)
		)
		(polygon
			(pts
				(xy 270.797274 -111.218218) (xy 270.797274 -109.866938) (xy 272.077434 -109.866938) (xy 272.077434 -111.218218)
			)
		)
	)
	(zone
		(layer "F.Cu")
		(hatch none 0.5)
		(connect_pads
			(clearance 0)
		)
		(min_thickness 0.25)
		(keepout
			(tracks allowed)
			(vias allowed)
			(pads allowed)
			(copperpour allowed)
			(footprints allowed)
		)
		(placement
			(enabled no)
			(sheetname "")
		)
		(fill
			(thermal_gap 0.5)
			(thermal_bridge_width 0.5)
			(island_removal_mode 0)
		)
		(polygon
			(pts
				(xy 427.636178 -147.319492) (xy 427.636178 -145.968212) (xy 428.916338 -145.968212) (xy 428.916338 -147.319492)
			)
		)
	)
	(zone
		(layer "F.Cu")
		(hatch none 0.5)
		(connect_pads
			(clearance 0)
		)
		(min_thickness 0.25)
		(keepout
			(tracks allowed)
			(vias allowed)
			(pads allowed)
			(copperpour allowed)
			(footprints allowed)
		)
		(placement
			(enabled no)
			(sheetname "")
		)
		(fill
			(thermal_gap 0.5)
			(thermal_bridge_width 0.5)
			(island_removal_mode 0)
		)
		(polygon
			(pts
				(xy 116.074952 -350.80575) (xy 114.723672 -350.80575) (xy 114.723672 -349.52559) (xy 116.074952 -349.52559)
			)
		)
	)
	(zone
		(layer "F.Cu")
		(hatch none 0.5)
		(connect_pads
			(clearance 0)
		)
		(min_thickness 0.25)
		(keepout
			(tracks allowed)
			(vias allowed)
			(pads allowed)
			(copperpour allowed)
			(footprints allowed)
		)
		(placement
			(enabled no)
			(sheetname "")
		)
		(fill
			(thermal_gap 0.5)
			(thermal_bridge_width 0.5)
			(island_removal_mode 0)
		)
		(polygon
			(pts
				(xy 43.109134 -32.954468) (xy 43.109134 -31.603188) (xy 44.389294 -31.603188) (xy 44.389294 -32.954468)
			)
		)
	)
	(zone
		(layer "F.Cu")
		(hatch none 0.5)
		(connect_pads
			(clearance 0)
		)
		(min_thickness 0.25)
		(keepout
			(tracks allowed)
			(vias allowed)
			(pads allowed)
			(copperpour allowed)
			(footprints allowed)
		)
		(placement
			(enabled no)
			(sheetname "")
		)
		(fill
			(thermal_gap 0.5)
			(thermal_bridge_width 0.5)
			(island_removal_mode 0)
		)
		(polygon
			(pts
				(xy 347.581982 -314.64123) (xy 345.930982 -314.64123) (xy 345.930982 -312.60923) (xy 347.581982 -312.60923)
			)
		)
	)
	(zone
		(layer "F.Cu")
		(hatch none 0.5)
		(connect_pads
			(clearance 0)
		)
		(min_thickness 0.25)
		(keepout
			(tracks allowed)
			(vias allowed)
			(pads allowed)
			(copperpour allowed)
			(footprints allowed)
		)
		(placement
			(enabled no)
			(sheetname "")
		)
		(fill
			(thermal_gap 0.5)
			(thermal_bridge_width 0.5)
			(island_removal_mode 0)
		)
		(polygon
			(pts
				(xy 319.799208 -356.952042) (xy 318.447928 -356.952042) (xy 318.447928 -355.671882) (xy 319.799208 -355.671882)
			)
		)
	)
	(zone
		(layer "F.Cu")
		(hatch none 0.5)
		(connect_pads
			(clearance 0)
		)
		(min_thickness 0.25)
		(keepout
			(tracks allowed)
			(vias allowed)
			(pads allowed)
			(copperpour allowed)
			(footprints allowed)
		)
		(placement
			(enabled no)
			(sheetname "")
		)
		(fill
			(thermal_gap 0.5)
			(thermal_bridge_width 0.5)
			(island_removal_mode 0)
		)
		(polygon
			(pts
				(xy 246.861584 -27.55011) (xy 249.26163 -27.55011) (xy 249.35307 -27.45867) (xy 249.35307 -26.33853)
				(xy 249.29211 -26.27757) (xy 246.846344 -26.27757) (xy 246.724424 -26.39949) (xy 246.724424 -27.41295)
			)
		)
	)
	(zone
		(layer "F.Cu")
		(hatch none 0.5)
		(connect_pads
			(clearance 0)
		)
		(min_thickness 0.25)
		(keepout
			(tracks not_allowed)
			(vias allowed)
			(pads allowed)
			(copperpour not_allowed)
			(footprints allowed)
		)
		(placement
			(enabled no)
			(sheetname "")
		)
		(fill
			(thermal_gap 0.5)
			(thermal_bridge_width 0.5)
			(island_removal_mode 0)
		)
		(polygon
			(pts
				(arc
					(start 201.250042 -270.89989)
					(mid 205.75016 -266.399772)
					(end 210.250024 -270.89989)
				)
				(arc
					(start 210.250024 -270.89989)
					(mid 205.75016 -275.399754)
					(end 201.250042 -270.89989)
				)
			)
		)
	)
	(zone
		(layer "F.Cu")
		(hatch none 0.5)
		(connect_pads
			(clearance 0)
		)
		(min_thickness 0.25)
		(keepout
			(tracks allowed)
			(vias allowed)
			(pads allowed)
			(copperpour allowed)
			(footprints not_allowed)
		)
		(placement
			(enabled no)
			(sheetname "")
		)
		(fill
			(thermal_gap 0.5)
			(thermal_bridge_width 0.5)
			(island_removal_mode 0)
		)
		(polygon
			(pts
				(xy 448.449954 -322.200016) (xy 466.600032 -322.200016)
				(arc
					(start 466.600032 -316.972442)
					(mid 462.367917 -317.455617)
					(end 460.099918 -313.85002)
				)
				(arc
					(start 460.099918 -313.85002)
					(mid 460.149531 -313.222229)
					(end 460.297022 -312.609992)
				)
				(xy 448.449954 -312.609992)
			)
		)
	)
	(zone
		(layer "F.Cu")
		(hatch none 0.5)
		(connect_pads
			(clearance 0)
		)
		(min_thickness 0.25)
		(keepout
			(tracks allowed)
			(vias allowed)
			(pads allowed)
			(copperpour allowed)
			(footprints not_allowed)
		)
		(placement
			(enabled no)
			(sheetname "")
		)
		(fill
			(thermal_gap 0.5)
			(thermal_bridge_width 0.5)
			(island_removal_mode 0)
		)
		(polygon
			(pts
				(xy 375.742454 -177.9651) (xy 440.157616 -177.9651) (xy 440.157616 -107.780074) (xy 427.787562 -107.780074)
				(xy 427.787562 -165.34511) (xy 412.75254 -165.34511) (xy 412.75254 -107.780074) (xy 403.14753 -107.780074)
				(xy 403.14753 -165.34511) (xy 388.112508 -165.34511) (xy 388.112508 -107.780074) (xy 375.742454 -107.780074)
			)
		)
	)
	(zone
		(layer "F.Cu")
		(hatch none 0.5)
		(connect_pads
			(clearance 0)
		)
		(min_thickness 0.25)
		(keepout
			(tracks not_allowed)
			(vias allowed)
			(pads allowed)
			(copperpour not_allowed)
			(footprints allowed)
		)
		(placement
			(enabled no)
			(sheetname "")
		)
		(fill
			(thermal_gap 0.5)
			(thermal_bridge_width 0.5)
			(island_removal_mode 0)
		)
		(polygon
			(pts
				(xy 324.79996 -396.56004) (xy 324.79996 -417.599876) (xy 314.79998 -417.599876) (xy 314.79998 -396.56004)
			)
		)
	)
	(zone
		(layer "F.Cu")
		(hatch none 0.5)
		(connect_pads
			(clearance 0)
		)
		(min_thickness 0.25)
		(keepout
			(tracks not_allowed)
			(vias allowed)
			(pads allowed)
			(copperpour not_allowed)
			(footprints allowed)
		)
		(placement
			(enabled no)
			(sheetname "")
		)
		(fill
			(thermal_gap 0.5)
			(thermal_bridge_width 0.5)
			(island_removal_mode 0)
		)
		(polygon
			(pts
				(arc
					(start 460.84998 -313.85002)
					(mid 464.100164 -310.599836)
					(end 467.350094 -313.85002)
				)
				(arc
					(start 467.350094 -313.85002)
					(mid 464.100164 -317.09995)
					(end 460.84998 -313.85002)
				)
			)
		)
	)
	(zone
		(layer "F.Cu")
		(hatch none 0.5)
		(connect_pads
			(clearance 0)
		)
		(min_thickness 0.25)
		(keepout
			(tracks allowed)
			(vias allowed)
			(pads allowed)
			(copperpour allowed)
			(footprints allowed)
		)
		(placement
			(enabled no)
			(sheetname "")
		)
		(fill
			(thermal_gap 0.5)
			(thermal_bridge_width 0.5)
			(island_removal_mode 0)
		)
		(polygon
			(pts
				(xy 128.07061 -287.02) (xy 133.02361 -287.02) (xy 133.27761 -286.766) (xy 133.27761 -286.004) (xy 133.02361 -285.75)
				(xy 131.88061 -285.75) (xy 131.62661 -285.496) (xy 131.62661 -284.861) (xy 131.88061 -284.607) (xy 132.38861 -284.607)
				(xy 132.51561 -284.48) (xy 132.51561 -282.829) (xy 132.26161 -282.575) (xy 128.32461 -282.575) (xy 128.07061 -282.829)
			)
		)
	)
	(zone
		(layer "F.Cu")
		(hatch none 0.5)
		(connect_pads
			(clearance 0)
		)
		(min_thickness 0.25)
		(keepout
			(tracks allowed)
			(vias allowed)
			(pads allowed)
			(copperpour allowed)
			(footprints allowed)
		)
		(placement
			(enabled no)
			(sheetname "")
		)
		(fill
			(thermal_gap 0.5)
			(thermal_bridge_width 0.5)
			(island_removal_mode 0)
		)
		(polygon
			(pts
				(xy 78.020926 -350.80575) (xy 76.669646 -350.80575) (xy 76.669646 -349.52559) (xy 78.020926 -349.52559)
			)
		)
	)
	(zone
		(layer "F.Cu")
		(hatch none 0.5)
		(connect_pads
			(clearance 0)
		)
		(min_thickness 0.25)
		(keepout
			(tracks allowed)
			(vias allowed)
			(pads allowed)
			(copperpour allowed)
			(footprints allowed)
		)
		(placement
			(enabled no)
			(sheetname "")
		)
		(fill
			(thermal_gap 0.5)
			(thermal_bridge_width 0.5)
			(island_removal_mode 0)
		)
		(polygon
			(pts
				(xy 51.525932 -344.635582) (xy 50.174652 -344.635582) (xy 50.174652 -343.355422) (xy 51.525932 -343.355422)
			)
		)
	)
	(zone
		(layer "F.Cu")
		(hatch none 0.5)
		(connect_pads
			(clearance 0)
		)
		(min_thickness 0.25)
		(keepout
			(tracks allowed)
			(vias allowed)
			(pads allowed)
			(copperpour allowed)
			(footprints allowed)
		)
		(placement
			(enabled no)
			(sheetname "")
		)
		(fill
			(thermal_gap 0.5)
			(thermal_bridge_width 0.5)
			(island_removal_mode 0)
		)
		(polygon
			(pts
				(xy 187.851288 -31.160974) (xy 187.851288 -29.809694) (xy 189.131448 -29.809694) (xy 189.131448 -31.160974)
			)
		)
	)
	(zone
		(layer "F.Cu")
		(hatch none 0.5)
		(connect_pads
			(clearance 0)
		)
		(min_thickness 0.25)
		(keepout
			(tracks allowed)
			(vias allowed)
			(pads allowed)
			(copperpour allowed)
			(footprints allowed)
		)
		(placement
			(enabled no)
			(sheetname "")
		)
		(fill
			(thermal_gap 0.5)
			(thermal_bridge_width 0.5)
			(island_removal_mode 0)
		)
		(polygon
			(pts
				(xy 35.955224 -109.424724) (xy 35.955224 -108.073444) (xy 37.235384 -108.073444) (xy 37.235384 -109.424724)
			)
		)
	)
	(zone
		(layer "F.Cu")
		(hatch none 0.5)
		(connect_pads
			(clearance 0)
		)
		(min_thickness 0.25)
		(keepout
			(tracks allowed)
			(vias allowed)
			(pads allowed)
			(copperpour allowed)
			(footprints allowed)
		)
		(placement
			(enabled no)
			(sheetname "")
		)
		(fill
			(thermal_gap 0.5)
			(thermal_bridge_width 0.5)
			(island_removal_mode 0)
		)
		(polygon
			(pts
				(arc
					(start 136.462516 -212.575394)
					(mid 136.447637 -212.611315)
					(end 136.411716 -212.626194)
				)
				(arc
					(start 135.701786 -212.626194)
					(mid 135.665865 -212.611315)
					(end 135.650986 -212.575394)
				)
				(arc
					(start 135.650986 -211.295742)
					(mid 135.665865 -211.259821)
					(end 135.701786 -211.244942)
				)
				(arc
					(start 136.411716 -211.244942)
					(mid 136.447637 -211.259821)
					(end 136.462516 -211.295742)
				)
			)
		)
	)
	(zone
		(layer "F.Cu")
		(hatch none 0.5)
		(connect_pads
			(clearance 0)
		)
		(min_thickness 0.25)
		(keepout
			(tracks allowed)
			(vias allowed)
			(pads allowed)
			(copperpour allowed)
			(footprints allowed)
		)
		(placement
			(enabled no)
			(sheetname "")
		)
		(fill
			(thermal_gap 0.5)
			(thermal_bridge_width 0.5)
			(island_removal_mode 0)
		)
		(polygon
			(pts
				(xy 216.537794 -19.7358) (xy 216.537794 -19.2024) (xy 217.604594 -19.2024) (xy 217.604594 -19.7358)
			)
		)
	)
	(zone
		(layer "F.Cu")
		(hatch none 0.5)
		(connect_pads
			(clearance 0)
		)
		(min_thickness 0.25)
		(keepout
			(tracks allowed)
			(vias allowed)
			(pads allowed)
			(copperpour allowed)
			(footprints not_allowed)
		)
		(placement
			(enabled no)
			(sheetname "")
		)
		(fill
			(thermal_gap 0.5)
			(thermal_bridge_width 0.5)
			(island_removal_mode 0)
		)
		(polygon
			(pts
				(xy 448.449954 -304.610008) (xy 466.60054 -304.610008) (xy 466.60054 -249.968512) (xy 448.449954 -260.439916)
			)
		)
	)
	(zone
		(layer "F.Cu")
		(hatch none 0.5)
		(connect_pads
			(clearance 0)
		)
		(min_thickness 0.25)
		(keepout
			(tracks allowed)
			(vias allowed)
			(pads allowed)
			(copperpour allowed)
			(footprints allowed)
		)
		(placement
			(enabled no)
			(sheetname "")
		)
		(fill
			(thermal_gap 0.5)
			(thermal_bridge_width 0.5)
			(island_removal_mode 0)
		)
		(polygon
			(pts
				(xy 81.978246 -152.726136) (xy 81.978246 -151.374856) (xy 83.258406 -151.374856) (xy 83.258406 -152.726136)
			)
		)
	)
	(zone
		(layer "F.Cu")
		(hatch none 0.5)
		(connect_pads
			(clearance 0)
		)
		(min_thickness 0.25)
		(keepout
			(tracks allowed)
			(vias allowed)
			(pads allowed)
			(copperpour allowed)
			(footprints allowed)
		)
		(placement
			(enabled no)
			(sheetname "")
		)
		(fill
			(thermal_gap 0.5)
			(thermal_bridge_width 0.5)
			(island_removal_mode 0)
		)
		(polygon
			(pts
				(xy 389.333486 -28.022042) (xy 391.116312 -28.022042) (xy 391.512552 -27.625802) (xy 391.512552 -25.842976)
				(xy 391.375392 -25.705816) (xy 389.226806 -25.705816) (xy 389.013446 -25.919176) (xy 388.967726 -25.919176)
				(xy 388.967726 -27.656282)
			)
		)
	)
	(zone
		(layer "F.Cu")
		(hatch none 0.5)
		(connect_pads
			(clearance 0)
		)
		(min_thickness 0.25)
		(keepout
			(tracks allowed)
			(vias allowed)
			(pads allowed)
			(copperpour allowed)
			(footprints allowed)
		)
		(placement
			(enabled no)
			(sheetname "")
		)
		(fill
			(thermal_gap 0.5)
			(thermal_bridge_width 0.5)
			(island_removal_mode 0)
		)
		(polygon
			(pts
				(xy 12.281662 -277.497794) (xy 15.202662 -277.497794) (xy 15.456662 -277.243794) (xy 15.456662 -274.195794)
				(xy 15.075662 -273.814794) (xy 12.154662 -273.814794) (xy 11.646662 -274.322794) (xy 11.646662 -276.862794)
			)
		)
	)
	(zone
		(layer "F.Cu")
		(hatch none 0.5)
		(connect_pads
			(clearance 0)
		)
		(min_thickness 0.25)
		(keepout
			(tracks allowed)
			(vias allowed)
			(pads allowed)
			(copperpour allowed)
			(footprints allowed)
		)
		(placement
			(enabled no)
			(sheetname "")
		)
		(fill
			(thermal_gap 0.5)
			(thermal_bridge_width 0.5)
			(island_removal_mode 0)
		)
		(polygon
			(pts
				(xy 369.291616 -52.800758) (xy 369.291616 -55.718456) (xy 369.501166 -55.928006) (xy 370.114068 -55.928006)
				(xy 370.114068 -52.870608) (xy 370.044218 -52.800758)
			)
		)
	)
	(zone
		(layer "F.Cu")
		(hatch none 0.5)
		(connect_pads
			(clearance 0)
		)
		(min_thickness 0.25)
		(keepout
			(tracks allowed)
			(vias allowed)
			(pads allowed)
			(copperpour allowed)
			(footprints allowed)
		)
		(placement
			(enabled no)
			(sheetname "")
		)
		(fill
			(thermal_gap 0.5)
			(thermal_bridge_width 0.5)
			(island_removal_mode 0)
		)
		(polygon
			(pts
				(xy 251.951236 -31.160974) (xy 251.951236 -29.809694) (xy 253.231396 -29.809694) (xy 253.231396 -31.160974)
			)
		)
	)
	(zone
		(layer "F.Cu")
		(hatch none 0.5)
		(connect_pads
			(clearance 0)
		)
		(min_thickness 0.25)
		(keepout
			(tracks allowed)
			(vias allowed)
			(pads allowed)
			(copperpour allowed)
			(footprints allowed)
		)
		(placement
			(enabled no)
			(sheetname "")
		)
		(fill
			(thermal_gap 0.5)
			(thermal_bridge_width 0.5)
			(island_removal_mode 0)
		)
		(polygon
			(pts
				(xy 351.17278 -260.21792) (xy 351.17278 -256.64922) (xy 354.75164 -256.64922) (xy 354.75164 -260.21792)
			)
		)
	)
	(zone
		(layer "F.Cu")
		(hatch none 0.5)
		(connect_pads
			(clearance 0)
		)
		(min_thickness 0.25)
		(keepout
			(tracks allowed)
			(vias allowed)
			(pads allowed)
			(copperpour allowed)
			(footprints allowed)
		)
		(placement
			(enabled no)
			(sheetname "")
		)
		(fill
			(thermal_gap 0.5)
			(thermal_bridge_width 0.5)
			(island_removal_mode 0)
		)
		(polygon
			(pts
				(xy 227.443538 -58.962798) (xy 226.606608 -58.962798) (xy 226.116134 -58.962798) (xy 226.11588 -58.963052)
				(xy 226.11588 -60.410852) (xy 226.23653 -60.531502) (xy 226.545902 -60.531502) (xy 226.576128 -60.501276)
				(xy 227.420678 -60.501276) (xy 227.503736 -60.418218) (xy 227.503736 -59.022996)
			)
		)
	)
	(zone
		(layer "F.Cu")
		(hatch none 0.5)
		(connect_pads
			(clearance 0)
		)
		(min_thickness 0.25)
		(keepout
			(tracks allowed)
			(vias allowed)
			(pads allowed)
			(copperpour allowed)
			(footprints allowed)
		)
		(placement
			(enabled no)
			(sheetname "")
		)
		(fill
			(thermal_gap 0.5)
			(thermal_bridge_width 0.5)
			(island_removal_mode 0)
		)
		(polygon
			(pts
				(xy 430.278286 -121.606056) (xy 430.278286 -120.254776) (xy 431.558446 -120.254776) (xy 431.558446 -121.606056)
			)
		)
	)
	(zone
		(layer "F.Cu")
		(hatch none 0.5)
		(connect_pads
			(clearance 0)
		)
		(min_thickness 0.25)
		(keepout
			(tracks allowed)
			(vias allowed)
			(pads allowed)
			(copperpour allowed)
			(footprints allowed)
		)
		(placement
			(enabled no)
			(sheetname "")
		)
		(fill
			(thermal_gap 0.5)
			(thermal_bridge_width 0.5)
			(island_removal_mode 0)
		)
		(polygon
			(pts
				(xy 335.344008 -350.80575) (xy 333.992728 -350.80575) (xy 333.992728 -349.52559) (xy 335.344008 -349.52559)
			)
		)
	)
	(zone
		(layer "F.Cu")
		(hatch none 0.5)
		(connect_pads
			(clearance 0)
		)
		(min_thickness 0.25)
		(keepout
			(tracks allowed)
			(vias allowed)
			(pads allowed)
			(copperpour allowed)
			(footprints not_allowed)
		)
		(placement
			(enabled no)
			(sheetname "")
		)
		(fill
			(thermal_gap 0.5)
			(thermal_bridge_width 0.5)
			(island_removal_mode 0)
		)
		(polygon
			(pts
				(xy 272.01241 -107.780074) (xy 259.642356 -107.780074) (xy 259.642356 -177.9651) (xy 324.057518 -177.9651)
				(xy 324.057518 -107.780074) (xy 311.687464 -107.780074) (xy 311.687464 -165.34511) (xy 296.652442 -165.34511)
				(xy 296.652442 -107.780074) (xy 287.047432 -107.780074) (xy 287.047432 -165.34511) (xy 272.01241 -165.34511)
			)
		)
	)
	(zone
		(layer "F.Cu")
		(hatch none 0.5)
		(connect_pads
			(clearance 0)
		)
		(min_thickness 0.25)
		(keepout
			(tracks allowed)
			(vias allowed)
			(pads allowed)
			(copperpour allowed)
			(footprints allowed)
		)
		(placement
			(enabled no)
			(sheetname "")
		)
		(fill
			(thermal_gap 0.5)
			(thermal_bridge_width 0.5)
			(island_removal_mode 0)
		)
		(polygon
			(pts
				(xy 384.255264 -131.538218) (xy 384.255264 -130.186938) (xy 385.535424 -130.186938) (xy 385.535424 -131.538218)
			)
		)
	)
	(zone
		(layer "F.Cu")
		(hatch none 0.5)
		(connect_pads
			(clearance 0)
		)
		(min_thickness 0.25)
		(keepout
			(tracks allowed)
			(vias allowed)
			(pads allowed)
			(copperpour allowed)
			(footprints allowed)
		)
		(placement
			(enabled no)
			(sheetname "")
		)
		(fill
			(thermal_gap 0.5)
			(thermal_bridge_width 0.5)
			(island_removal_mode 0)
		)
		(polygon
			(pts
				(xy 12.30884 -139.05357) (xy 12.965176 -139.05357) (xy 13.078714 -138.940032) (xy 13.078714 -138.157204)
				(xy 12.7127 -137.79119) (xy 12.7127 -135.556752) (xy 12.346686 -135.190738) (xy 12.346432 -135.190738)
				(xy 12.030964 -135.506206) (xy 12.030964 -138.775694)
			)
		)
	)
	(zone
		(layer "F.Cu")
		(hatch none 0.5)
		(connect_pads
			(clearance 0)
		)
		(min_thickness 0.25)
		(keepout
			(tracks allowed)
			(vias allowed)
			(pads allowed)
			(copperpour allowed)
			(footprints not_allowed)
		)
		(placement
			(enabled no)
			(sheetname "")
		)
		(fill
			(thermal_gap 0.5)
			(thermal_bridge_width 0.5)
			(island_removal_mode 0)
		)
		(polygon
			(pts
				(xy 252.819916 -18.150078) (xy 252.819916 -13.150088) (xy 248.620026 -13.150088) (xy 248.620026 -18.150078)
			)
		)
	)
	(zone
		(layer "F.Cu")
		(hatch none 0.5)
		(connect_pads
			(clearance 0)
		)
		(min_thickness 0.25)
		(keepout
			(tracks allowed)
			(vias allowed)
			(pads allowed)
			(copperpour allowed)
			(footprints not_allowed)
		)
		(placement
			(enabled no)
			(sheetname "")
		)
		(fill
			(thermal_gap 0.5)
			(thermal_bridge_width 0.5)
			(island_removal_mode 0)
		)
		(polygon
			(pts
				(arc
					(start -0.500126 -311.410096)
					(mid 3.50012 -307.40985)
					(end 7.500112 -311.410096)
				)
				(arc
					(start 7.500112 -311.410096)
					(mid 3.50012 -315.410088)
					(end -0.500126 -311.410096)
				)
			)
		)
	)
	(zone
		(layer "F.Cu")
		(hatch none 0.5)
		(connect_pads
			(clearance 0)
		)
		(min_thickness 0.25)
		(keepout
			(tracks not_allowed)
			(vias allowed)
			(pads allowed)
			(copperpour not_allowed)
			(footprints allowed)
		)
		(placement
			(enabled no)
			(sheetname "")
		)
		(fill
			(thermal_gap 0.5)
			(thermal_bridge_width 0.5)
			(island_removal_mode 0)
		)
		(polygon
			(pts
				(arc
					(start 337.214972 -17.999964)
					(mid 342.214962 -12.999974)
					(end 347.214952 -17.999964)
				)
				(arc
					(start 347.214952 -17.999964)
					(mid 342.214962 -22.999954)
					(end 337.214972 -17.999964)
				)
			)
		)
	)
	(zone
		(layer "F.Cu")
		(hatch none 0.5)
		(connect_pads
			(clearance 0)
		)
		(min_thickness 0.25)
		(keepout
			(tracks allowed)
			(vias allowed)
			(pads allowed)
			(copperpour allowed)
			(footprints allowed)
		)
		(placement
			(enabled no)
			(sheetname "")
		)
		(fill
			(thermal_gap 0.5)
			(thermal_bridge_width 0.5)
			(island_removal_mode 0)
		)
		(polygon
			(pts
				(xy 71.803006 -350.80575) (xy 70.451726 -350.80575) (xy 70.451726 -349.52559) (xy 71.803006 -349.52559)
			)
		)
	)
	(zone
		(layer "F.Cu")
		(hatch none 0.5)
		(connect_pads
			(clearance 0)
		)
		(min_thickness 0.25)
		(keepout
			(tracks allowed)
			(vias allowed)
			(pads allowed)
			(copperpour allowed)
			(footprints allowed)
		)
		(placement
			(enabled no)
			(sheetname "")
		)
		(fill
			(thermal_gap 0.5)
			(thermal_bridge_width 0.5)
			(island_removal_mode 0)
		)
		(polygon
			(pts
				(xy 18.391632 -148.199348) (xy 19.032474 -148.199348) (xy 19.05508 -148.176742) (xy 19.05508 -147.203922)
				(xy 18.858992 -147.007834) (xy 18.165318 -147.007834) (xy 18.165318 -147.332192) (xy 18.391632 -147.558506)
			)
		)
	)
	(zone
		(layer "F.Cu")
		(hatch none 0.5)
		(connect_pads
			(clearance 0)
		)
		(min_thickness 0.25)
		(keepout
			(tracks allowed)
			(vias allowed)
			(pads allowed)
			(copperpour allowed)
			(footprints allowed)
		)
		(placement
			(enabled no)
			(sheetname "")
		)
		(fill
			(thermal_gap 0.5)
			(thermal_bridge_width 0.5)
			(island_removal_mode 0)
		)
		(polygon
			(pts
				(xy 243.84508 -278.641556) (xy 243.84508 -276.990556) (xy 245.49608 -276.990556) (xy 245.49608 -278.641556)
			)
		)
	)
	(zone
		(layer "F.Cu")
		(hatch none 0.5)
		(connect_pads
			(clearance 0)
		)
		(min_thickness 0.25)
		(keepout
			(tracks allowed)
			(vias allowed)
			(pads allowed)
			(copperpour allowed)
			(footprints allowed)
		)
		(placement
			(enabled no)
			(sheetname "")
		)
		(fill
			(thermal_gap 0.5)
			(thermal_bridge_width 0.5)
			(island_removal_mode 0)
		)
		(polygon
			(pts
				(xy 387.836664 -350.80575) (xy 386.485384 -350.80575) (xy 386.485384 -349.52559) (xy 387.836664 -349.52559)
			)
		)
	)
	(zone
		(layer "F.Cu")
		(hatch none 0.5)
		(connect_pads
			(clearance 0)
		)
		(min_thickness 0.25)
		(keepout
			(tracks allowed)
			(vias allowed)
			(pads allowed)
			(copperpour allowed)
			(footprints not_allowed)
		)
		(placement
			(enabled no)
			(sheetname "")
		)
		(fill
			(thermal_gap 0.5)
			(thermal_bridge_width 0.5)
			(island_removal_mode 0)
		)
		(polygon
			(pts
				(xy 241.720116 -23.219918) (xy 241.720116 -18.219928) (xy 237.519972 -18.219928) (xy 237.519972 -23.219918)
			)
		)
	)
	(zone
		(layer "F.Cu")
		(hatch none 0.5)
		(connect_pads
			(clearance 0)
		)
		(min_thickness 0.25)
		(keepout
			(tracks allowed)
			(vias allowed)
			(pads allowed)
			(copperpour allowed)
			(footprints allowed)
		)
		(placement
			(enabled no)
			(sheetname "")
		)
		(fill
			(thermal_gap 0.5)
			(thermal_bridge_width 0.5)
			(island_removal_mode 0)
		)
		(polygon
			(pts
				(xy 195.435982 -147.319492) (xy 195.435982 -145.968212) (xy 196.716142 -145.968212) (xy 196.716142 -147.319492)
			)
		)
	)
	(zone
		(layer "F.Cu")
		(hatch none 0.5)
		(connect_pads
			(clearance 0)
		)
		(min_thickness 0.25)
		(keepout
			(tracks allowed)
			(vias allowed)
			(pads allowed)
			(copperpour allowed)
			(footprints allowed)
		)
		(placement
			(enabled no)
			(sheetname "")
		)
		(fill
			(thermal_gap 0.5)
			(thermal_bridge_width 0.5)
			(island_removal_mode 0)
		)
		(polygon
			(pts
				(xy 452.17588 -268.08176) (xy 452.17588 -265.97356) (xy 453.8091 -265.97356) (xy 453.8091 -268.08176)
			)
		)
	)
	(zone
		(layer "F.Cu")
		(hatch none 0.5)
		(connect_pads
			(clearance 0)
		)
		(min_thickness 0.25)
		(keepout
			(tracks allowed)
			(vias allowed)
			(pads allowed)
			(copperpour allowed)
			(footprints allowed)
		)
		(placement
			(enabled no)
			(sheetname "")
		)
		(fill
			(thermal_gap 0.5)
			(thermal_bridge_width 0.5)
			(island_removal_mode 0)
		)
		(polygon
			(pts
				(xy 84.238846 -344.659458) (xy 82.887566 -344.659458) (xy 82.887566 -343.379298) (xy 84.238846 -343.379298)
			)
		)
	)
	(zone
		(layer "F.Cu")
		(hatch none 0.5)
		(connect_pads
			(clearance 0)
		)
		(min_thickness 0.25)
		(keepout
			(tracks allowed)
			(vias allowed)
			(pads allowed)
			(copperpour allowed)
			(footprints allowed)
		)
		(placement
			(enabled no)
			(sheetname "")
		)
		(fill
			(thermal_gap 0.5)
			(thermal_bridge_width 0.5)
			(island_removal_mode 0)
		)
		(polygon
			(pts
				(xy 241.990372 -229.551738) (xy 242.494054 -229.551738) (xy 242.917218 -229.128574) (xy 242.917218 -228.473508)
				(xy 242.776248 -228.332538) (xy 242.413536 -228.332538) (xy 241.990372 -228.755702)
			)
		)
	)
	(zone
		(layer "F.Cu")
		(hatch none 0.5)
		(connect_pads
			(clearance 0)
		)
		(min_thickness 0.25)
		(keepout
			(tracks allowed)
			(vias allowed)
			(pads allowed)
			(copperpour allowed)
			(footprints not_allowed)
		)
		(placement
			(enabled no)
			(sheetname "")
		)
		(fill
			(thermal_gap 0.5)
			(thermal_bridge_width 0.5)
			(island_removal_mode 0)
		)
		(polygon
			(pts
				(xy 93.650054 -262.400034) (xy 25.649936 -262.400034) (xy 25.649936 -329.3999) (xy 93.650054 -329.3999)
			)
		)
	)
	(zone
		(layer "F.Cu")
		(hatch none 0.5)
		(connect_pads
			(clearance 0)
		)
		(min_thickness 0.25)
		(keepout
			(tracks allowed)
			(vias allowed)
			(pads allowed)
			(copperpour allowed)
			(footprints allowed)
		)
		(placement
			(enabled no)
			(sheetname "")
		)
		(fill
			(thermal_gap 0.5)
			(thermal_bridge_width 0.5)
			(island_removal_mode 0)
		)
		(polygon
			(pts
				(xy 126.51867 -151.266398) (xy 126.928118 -151.266398) (xy 127.095504 -151.433784) (xy 127.095504 -156.208222)
				(xy 126.816358 -156.487368) (xy 126.518924 -156.487368) (xy 126.388622 -156.357066) (xy 126.388622 -151.396446)
			)
		)
	)
	(zone
		(layer "F.Cu")
		(hatch none 0.5)
		(connect_pads
			(clearance 0)
		)
		(min_thickness 0.25)
		(keepout
			(tracks allowed)
			(vias allowed)
			(pads allowed)
			(copperpour allowed)
			(footprints allowed)
		)
		(placement
			(enabled no)
			(sheetname "")
		)
		(fill
			(thermal_gap 0.5)
			(thermal_bridge_width 0.5)
			(island_removal_mode 0)
		)
		(polygon
			(pts
				(xy 400.272504 -350.781874) (xy 398.921224 -350.781874) (xy 398.921224 -349.501714) (xy 400.272504 -349.501714)
			)
		)
	)
	(zone
		(layer "F.Cu")
		(hatch none 0.5)
		(connect_pads
			(clearance 0)
		)
		(min_thickness 0.25)
		(keepout
			(tracks allowed)
			(vias allowed)
			(pads allowed)
			(copperpour allowed)
			(footprints allowed)
		)
		(placement
			(enabled no)
			(sheetname "")
		)
		(fill
			(thermal_gap 0.5)
			(thermal_bridge_width 0.5)
			(island_removal_mode 0)
		)
		(polygon
			(pts
				(xy 182.588662 -35.519868) (xy 184.416954 -35.519868) (xy 184.653428 -35.283394) (xy 184.653428 -26.930096)
				(xy 184.416954 -26.693622) (xy 182.760874 -26.693622) (xy 182.588662 -26.865834)
			)
		)
	)
	(zone
		(layer "F.Cu")
		(hatch none 0.5)
		(connect_pads
			(clearance 0)
		)
		(min_thickness 0.25)
		(keepout
			(tracks allowed)
			(vias allowed)
			(pads allowed)
			(copperpour allowed)
			(footprints not_allowed)
		)
		(placement
			(enabled no)
			(sheetname "")
		)
		(fill
			(thermal_gap 0.5)
			(thermal_bridge_width 0.5)
			(island_removal_mode 0)
		)
		(polygon
			(pts
				(xy 400.139916 -361.790234) (xy 371.039898 -361.790234) (xy 371.039898 -417.58997) (xy 400.139916 -417.58997)
			)
		)
	)
	(zone
		(layer "F.Cu")
		(hatch none 0.5)
		(connect_pads
			(clearance 0)
		)
		(min_thickness 0.25)
		(keepout
			(tracks allowed)
			(vias allowed)
			(pads allowed)
			(copperpour allowed)
			(footprints allowed)
		)
		(placement
			(enabled no)
			(sheetname "")
		)
		(fill
			(thermal_gap 0.5)
			(thermal_bridge_width 0.5)
			(island_removal_mode 0)
		)
		(polygon
			(pts
				(xy 154.697176 -125.734826) (xy 154.697176 -124.383546) (xy 155.977336 -124.383546) (xy 155.977336 -125.734826)
			)
		)
	)
	(zone
		(layer "F.Cu")
		(hatch none 0.5)
		(connect_pads
			(clearance 0)
		)
		(min_thickness 0.25)
		(keepout
			(tracks allowed)
			(vias allowed)
			(pads allowed)
			(copperpour allowed)
			(footprints allowed)
		)
		(placement
			(enabled no)
			(sheetname "")
		)
		(fill
			(thermal_gap 0.5)
			(thermal_bridge_width 0.5)
			(island_removal_mode 0)
		)
		(polygon
			(pts
				(xy 218.54922 -386.79628) (xy 215.72982 -386.79628) (xy 214.503 -385.56946) (xy 214.503 -382.93548)
				(xy 215.2142 -382.22428) (xy 218.41714 -382.22428) (xy 218.70162 -382.50876) (xy 218.70162 -386.64388)
			)
		)
	)
	(zone
		(layer "F.Cu")
		(hatch none 0.5)
		(connect_pads
			(clearance 0)
		)
		(min_thickness 0.25)
		(keepout
			(tracks allowed)
			(vias allowed)
			(pads allowed)
			(copperpour allowed)
			(footprints allowed)
		)
		(placement
			(enabled no)
			(sheetname "")
		)
		(fill
			(thermal_gap 0.5)
			(thermal_bridge_width 0.5)
			(island_removal_mode 0)
		)
		(polygon
			(pts
				(xy 95.10903 -29.354526) (xy 95.10903 -28.003246) (xy 96.38919 -28.003246) (xy 96.38919 -29.354526)
			)
		)
	)
	(zone
		(layer "F.Cu")
		(hatch none 0.5)
		(connect_pads
			(clearance 0)
		)
		(min_thickness 0.25)
		(keepout
			(tracks allowed)
			(vias allowed)
			(pads allowed)
			(copperpour allowed)
			(footprints allowed)
		)
		(placement
			(enabled no)
			(sheetname "")
		)
		(fill
			(thermal_gap 0.5)
			(thermal_bridge_width 0.5)
			(island_removal_mode 0)
		)
		(polygon
			(pts
				(xy 293.847266 -350.80575) (xy 292.495986 -350.80575) (xy 292.495986 -349.52559) (xy 293.847266 -349.52559)
			)
		)
	)
	(zone
		(layer "F.Cu")
		(hatch none 0.5)
		(connect_pads
			(clearance 0)
		)
		(min_thickness 0.25)
		(keepout
			(tracks allowed)
			(vias allowed)
			(pads allowed)
			(copperpour allowed)
			(footprints allowed)
		)
		(placement
			(enabled no)
			(sheetname "")
		)
		(fill
			(thermal_gap 0.5)
			(thermal_bridge_width 0.5)
			(island_removal_mode 0)
		)
		(polygon
			(pts
				(xy 417.535106 -117.970808) (xy 415.447734 -117.970808) (xy 415.127694 -118.290848) (xy 415.127694 -125.694948)
				(xy 417.472622 -125.694948) (xy 417.550854 -125.616716) (xy 417.550854 -117.986556)
			)
		)
	)
	(zone
		(layer "F.Cu")
		(hatch none 0.5)
		(connect_pads
			(clearance 0)
		)
		(min_thickness 0.25)
		(keepout
			(tracks allowed)
			(vias allowed)
			(pads allowed)
			(copperpour allowed)
			(footprints allowed)
		)
		(placement
			(enabled no)
			(sheetname "")
		)
		(fill
			(thermal_gap 0.5)
			(thermal_bridge_width 0.5)
			(island_removal_mode 0)
		)
		(polygon
			(pts
				(xy 62.476126 -344.659458) (xy 61.124846 -344.659458) (xy 61.124846 -343.379298) (xy 62.476126 -343.379298)
			)
		)
	)
	(zone
		(layer "F.Cu")
		(hatch none 0.5)
		(connect_pads
			(clearance 0)
		)
		(min_thickness 0.25)
		(keepout
			(tracks allowed)
			(vias allowed)
			(pads allowed)
			(copperpour allowed)
			(footprints not_allowed)
		)
		(placement
			(enabled no)
			(sheetname "")
		)
		(fill
			(thermal_gap 0.5)
			(thermal_bridge_width 0.5)
			(island_removal_mode 0)
		)
		(polygon
			(pts
				(arc
					(start 248.350024 -297.369992)
					(mid 252.350016 -293.37)
					(end 256.350008 -297.369992)
				)
				(arc
					(start 256.350008 -297.369992)
					(mid 252.350016 -301.369984)
					(end 248.350024 -297.369992)
				)
			)
		)
	)
	(zone
		(layer "F.Cu")
		(hatch none 0.5)
		(connect_pads
			(clearance 0)
		)
		(min_thickness 0.25)
		(keepout
			(tracks allowed)
			(vias allowed)
			(pads allowed)
			(copperpour allowed)
			(footprints allowed)
		)
		(placement
			(enabled no)
			(sheetname "")
		)
		(fill
			(thermal_gap 0.5)
			(thermal_bridge_width 0.5)
			(island_removal_mode 0)
		)
		(polygon
			(pts
				(xy 372.291864 -350.80575) (xy 370.940584 -350.80575) (xy 370.940584 -349.52559) (xy 372.291864 -349.52559)
			)
		)
	)
	(zone
		(layer "F.Cu")
		(hatch none 0.5)
		(connect_pads
			(clearance 0)
		)
		(min_thickness 0.25)
		(keepout
			(tracks allowed)
			(vias allowed)
			(pads allowed)
			(copperpour allowed)
			(footprints not_allowed)
		)
		(placement
			(enabled no)
			(sheetname "")
		)
		(fill
			(thermal_gap 0.5)
			(thermal_bridge_width 0.5)
			(island_removal_mode 0)
		)
		(polygon
			(pts
				(xy 177.064924 -40.120062) (xy 185.064908 -40.120062) (xy 185.064908 -13.850112) (xy 177.064924 -13.850112)
			)
		)
	)
	(zone
		(layer "F.Cu")
		(hatch none 0.5)
		(connect_pads
			(clearance 0)
		)
		(min_thickness 0.25)
		(keepout
			(tracks allowed)
			(vias allowed)
			(pads allowed)
			(copperpour allowed)
			(footprints allowed)
		)
		(placement
			(enabled no)
			(sheetname "")
		)
		(fill
			(thermal_gap 0.5)
			(thermal_bridge_width 0.5)
			(island_removal_mode 0)
		)
		(polygon
			(pts
				(arc
					(start 380.716028 -243.651786)
					(mid 380.730907 -243.615865)
					(end 380.766828 -243.600986)
				)
				(arc
					(start 381.446532 -243.600986)
					(mid 381.482453 -243.615865)
					(end 381.497332 -243.651786)
				)
				(arc
					(start 381.497332 -244.927628)
					(mid 381.482453 -244.963549)
					(end 381.446532 -244.978428)
				)
				(arc
					(start 380.766828 -244.978428)
					(mid 380.730907 -244.963549)
					(end 380.716028 -244.927628)
				)
			)
		)
	)
	(zone
		(layer "F.Cu")
		(hatch none 0.5)
		(connect_pads
			(clearance 0)
		)
		(min_thickness 0.25)
		(keepout
			(tracks allowed)
			(vias allowed)
			(pads allowed)
			(copperpour allowed)
			(footprints allowed)
		)
		(placement
			(enabled no)
			(sheetname "")
		)
		(fill
			(thermal_gap 0.5)
			(thermal_bridge_width 0.5)
			(island_removal_mode 0)
		)
		(polygon
			(pts
				(xy 388.788656 -35.519868) (xy 390.616948 -35.519868) (xy 390.853422 -35.283394) (xy 390.853422 -26.930096)
				(xy 390.616948 -26.693622) (xy 388.960868 -26.693622) (xy 388.788656 -26.865834)
			)
		)
	)
	(zone
		(layer "F.Cu")
		(hatch none 0.5)
		(connect_pads
			(clearance 0)
		)
		(min_thickness 0.25)
		(keepout
			(tracks allowed)
			(vias allowed)
			(pads allowed)
			(copperpour allowed)
			(footprints allowed)
		)
		(placement
			(enabled no)
			(sheetname "")
		)
		(fill
			(thermal_gap 0.5)
			(thermal_bridge_width 0.5)
			(island_removal_mode 0)
		)
		(polygon
			(pts
				(xy 112.965992 -344.659458) (xy 111.614712 -344.659458) (xy 111.614712 -343.379298) (xy 112.965992 -343.379298)
			)
		)
	)
	(zone
		(layer "F.Cu")
		(hatch none 0.5)
		(connect_pads
			(clearance 0)
		)
		(min_thickness 0.25)
		(keepout
			(tracks allowed)
			(vias allowed)
			(pads allowed)
			(copperpour allowed)
			(footprints not_allowed)
		)
		(placement
			(enabled no)
			(sheetname "")
		)
		(fill
			(thermal_gap 0.5)
			(thermal_bridge_width 0.5)
			(island_removal_mode 0)
		)
		(polygon
			(pts
				(arc
					(start 16.150082 -301.410116)
					(mid 20.150074 -297.410124)
					(end 24.150066 -301.410116)
				)
				(arc
					(start 24.150066 -301.410116)
					(mid 20.150074 -305.410108)
					(end 16.150082 -301.410116)
				)
			)
		)
	)
	(zone
		(layer "F.Cu")
		(hatch none 0.5)
		(connect_pads
			(clearance 0)
		)
		(min_thickness 0.25)
		(keepout
			(tracks allowed)
			(vias allowed)
			(pads allowed)
			(copperpour allowed)
			(footprints allowed)
		)
		(placement
			(enabled no)
			(sheetname "")
		)
		(fill
			(thermal_gap 0.5)
			(thermal_bridge_width 0.5)
			(island_removal_mode 0)
		)
		(polygon
			(pts
				(xy 366.68456 -148.213826) (xy 367.31829 -148.213826) (xy 367.378488 -148.153628) (xy 367.378488 -147.007326)
				(xy 367.30305 -146.931888) (xy 366.368076 -146.931888) (xy 366.307624 -146.99234) (xy 366.307624 -147.83689)
			)
		)
	)
	(zone
		(layer "F.Cu")
		(hatch none 0.5)
		(connect_pads
			(clearance 0)
		)
		(min_thickness 0.25)
		(keepout
			(tracks allowed)
			(vias allowed)
			(pads allowed)
			(copperpour allowed)
			(footprints allowed)
		)
		(placement
			(enabled no)
			(sheetname "")
		)
		(fill
			(thermal_gap 0.5)
			(thermal_bridge_width 0.5)
			(island_removal_mode 0)
		)
		(polygon
			(pts
				(xy 194.379596 -344.635582) (xy 193.028316 -344.635582) (xy 193.028316 -343.355422) (xy 194.379596 -343.355422)
			)
		)
	)
	(zone
		(layer "F.Cu")
		(hatch none 0.5)
		(connect_pads
			(clearance 0)
		)
		(min_thickness 0.25)
		(keepout
			(tracks allowed)
			(vias allowed)
			(pads allowed)
			(copperpour allowed)
			(footprints allowed)
		)
		(placement
			(enabled no)
			(sheetname "")
		)
		(fill
			(thermal_gap 0.5)
			(thermal_bridge_width 0.5)
			(island_removal_mode 0)
		)
		(polygon
			(pts
				(xy 314.178188 -121.606056) (xy 314.178188 -120.254776) (xy 315.458348 -120.254776) (xy 315.458348 -121.606056)
			)
		)
	)
	(zone
		(layer "F.Cu")
		(hatch none 0.5)
		(connect_pads
			(clearance 0)
		)
		(min_thickness 0.25)
		(keepout
			(tracks allowed)
			(vias allowed)
			(pads allowed)
			(copperpour allowed)
			(footprints allowed)
		)
		(placement
			(enabled no)
			(sheetname "")
		)
		(fill
			(thermal_gap 0.5)
			(thermal_bridge_width 0.5)
			(island_removal_mode 0)
		)
		(polygon
			(pts
				(xy 211.209128 -29.354526) (xy 211.209128 -28.003246) (xy 212.489288 -28.003246) (xy 212.489288 -29.354526)
			)
		)
	)
	(zone
		(layer "F.Cu")
		(hatch none 0.5)
		(connect_pads
			(clearance 0)
		)
		(min_thickness 0.25)
		(keepout
			(tracks allowed)
			(vias allowed)
			(pads allowed)
			(copperpour allowed)
			(footprints allowed)
		)
		(placement
			(enabled no)
			(sheetname "")
		)
		(fill
			(thermal_gap 0.5)
			(thermal_bridge_width 0.5)
			(island_removal_mode 0)
		)
		(polygon
			(pts
				(xy 47.959264 -47.3202) (xy 47.959264 -45.5676) (xy 49.737264 -45.5676) (xy 49.737264 -47.3202)
			)
		)
	)
	(zone
		(layer "F.Cu")
		(hatch none 0.5)
		(connect_pads
			(clearance 0)
		)
		(min_thickness 0.25)
		(keepout
			(tracks allowed)
			(vias allowed)
			(pads allowed)
			(copperpour allowed)
			(footprints not_allowed)
		)
		(placement
			(enabled no)
			(sheetname "")
		)
		(fill
			(thermal_gap 0.5)
			(thermal_bridge_width 0.5)
			(island_removal_mode 0)
		)
		(polygon
			(pts
				(arc
					(start 160.064958 -5.999988)
					(mid 168.064942 1.999996)
					(end 176.064926 -5.999988)
				)
				(arc
					(start 176.064926 -5.999988)
					(mid 168.064942 -13.999972)
					(end 160.064958 -5.999988)
				)
			)
		)
	)
	(zone
		(layer "F.Cu")
		(hatch none 0.5)
		(connect_pads
			(clearance 0)
		)
		(min_thickness 0.25)
		(keepout
			(tracks allowed)
			(vias allowed)
			(pads allowed)
			(copperpour allowed)
			(footprints allowed)
		)
		(placement
			(enabled no)
			(sheetname "")
		)
		(fill
			(thermal_gap 0.5)
			(thermal_bridge_width 0.5)
			(island_removal_mode 0)
		)
		(polygon
			(pts
				(xy 7.26186 -389.335518) (xy 7.26186 -383.59715) (xy 13.142722 -383.59715) (xy 13.142722 -389.335518)
			)
		)
	)
	(zone
		(layer "F.Cu")
		(hatch none 0.5)
		(connect_pads
			(clearance 0)
		)
		(min_thickness 0.25)
		(keepout
			(tracks allowed)
			(vias allowed)
			(pads allowed)
			(copperpour allowed)
			(footprints allowed)
		)
		(placement
			(enabled no)
			(sheetname "")
		)
		(fill
			(thermal_gap 0.5)
			(thermal_bridge_width 0.5)
			(island_removal_mode 0)
		)
		(polygon
			(pts
				(xy 386.897372 -111.218218) (xy 386.897372 -109.866938) (xy 388.177532 -109.866938) (xy 388.177532 -111.218218)
			)
		)
	)
	(zone
		(layer "F.Cu")
		(hatch none 0.5)
		(connect_pads
			(clearance 0)
		)
		(min_thickness 0.25)
		(keepout
			(tracks allowed)
			(vias allowed)
			(pads allowed)
			(copperpour allowed)
			(footprints allowed)
		)
		(placement
			(enabled no)
			(sheetname "")
		)
		(fill
			(thermal_gap 0.5)
			(thermal_bridge_width 0.5)
			(island_removal_mode 0)
		)
		(polygon
			(pts
				(xy 370.737892 -19.7358) (xy 370.737892 -19.2024) (xy 371.804692 -19.2024) (xy 371.804692 -19.7358)
			)
		)
	)
	(zone
		(layer "F.Cu")
		(hatch none 0.5)
		(connect_pads
			(clearance 0)
		)
		(min_thickness 0.25)
		(keepout
			(tracks not_allowed)
			(vias allowed)
			(pads allowed)
			(copperpour not_allowed)
			(footprints allowed)
		)
		(placement
			(enabled no)
			(sheetname "")
		)
		(fill
			(thermal_gap 0.5)
			(thermal_bridge_width 0.5)
			(island_removal_mode 0)
		)
		(polygon
			(pts
				(arc
					(start 194.399916 -393.100052)
					(mid 199.399906 -388.100062)
					(end 204.399896 -393.100052)
				)
				(arc
					(start 204.399896 -393.100052)
					(mid 199.399906 -398.100042)
					(end 194.399916 -393.100052)
				)
			)
		)
	)
	(zone
		(layer "F.Cu")
		(hatch none 0.5)
		(connect_pads
			(clearance 0)
		)
		(min_thickness 0.25)
		(keepout
			(tracks allowed)
			(vias allowed)
			(pads allowed)
			(copperpour allowed)
			(footprints allowed)
		)
		(placement
			(enabled no)
			(sheetname "")
		)
		(fill
			(thermal_gap 0.5)
			(thermal_bridge_width 0.5)
			(island_removal_mode 0)
		)
		(polygon
			(pts
				(xy 241.451638 -226.088702) (xy 241.451638 -225.251772) (xy 241.451638 -224.761298) (xy 241.451384 -224.761044)
				(xy 240.003584 -224.761044) (xy 239.882934 -224.881694) (xy 239.882934 -225.191066) (xy 239.91316 -225.221292)
				(xy 239.91316 -226.065842) (xy 239.996218 -226.1489) (xy 241.39144 -226.1489)
			)
		)
	)
	(zone
		(layer "F.Cu")
		(hatch none 0.5)
		(connect_pads
			(clearance 0)
		)
		(min_thickness 0.25)
		(keepout
			(tracks allowed)
			(vias allowed)
			(pads allowed)
			(copperpour allowed)
			(footprints allowed)
		)
		(placement
			(enabled no)
			(sheetname "")
		)
		(fill
			(thermal_gap 0.5)
			(thermal_bridge_width 0.5)
			(island_removal_mode 0)
		)
		(polygon
			(pts
				(xy 38.597332 -125.734826) (xy 38.597332 -124.383546) (xy 39.877492 -124.383546) (xy 39.877492 -125.734826)
			)
		)
	)
	(zone
		(layer "F.Cu")
		(hatch none 0.5)
		(connect_pads
			(clearance 0)
		)
		(min_thickness 0.25)
		(keepout
			(tracks allowed)
			(vias allowed)
			(pads allowed)
			(copperpour allowed)
			(footprints allowed)
		)
		(placement
			(enabled no)
			(sheetname "")
		)
		(fill
			(thermal_gap 0.5)
			(thermal_bridge_width 0.5)
			(island_removal_mode 0)
		)
		(polygon
			(pts
				(xy 51.525932 -350.781874) (xy 50.174652 -350.781874) (xy 50.174652 -349.501714) (xy 51.525932 -349.501714)
			)
		)
	)
	(zone
		(layer "F.Cu")
		(hatch none 0.5)
		(connect_pads
			(clearance 0)
		)
		(min_thickness 0.25)
		(keepout
			(tracks not_allowed)
			(vias allowed)
			(pads allowed)
			(copperpour not_allowed)
			(footprints allowed)
		)
		(placement
			(enabled no)
			(sheetname "")
		)
		(fill
			(thermal_gap 0.5)
			(thermal_bridge_width 0.5)
			(island_removal_mode 0)
		)
		(polygon
			(pts
				(xy 409.82011 -23.219918) (xy 409.82011 -18.219928) (xy 405.619966 -18.219928) (xy 405.619966 -23.219918)
			)
		)
	)
	(zone
		(layer "F.Cu")
		(hatch none 0.5)
		(connect_pads
			(clearance 0)
		)
		(min_thickness 0.25)
		(keepout
			(tracks allowed)
			(vias allowed)
			(pads allowed)
			(copperpour allowed)
			(footprints not_allowed)
		)
		(placement
			(enabled no)
			(sheetname "")
		)
		(fill
			(thermal_gap 0.5)
			(thermal_bridge_width 0.5)
			(island_removal_mode 0)
		)
		(polygon
			(pts
				(arc
					(start 7.800086 -194.360038)
					(mid 15.80007 -186.360054)
					(end 23.800054 -194.360038)
				)
				(arc
					(start 23.800054 -194.360038)
					(mid 15.80007 -202.360022)
					(end 7.800086 -194.360038)
				)
			)
		)
	)
	(zone
		(layer "F.Cu")
		(hatch none 0.5)
		(connect_pads
			(clearance 0)
		)
		(min_thickness 0.25)
		(keepout
			(tracks allowed)
			(vias allowed)
			(pads allowed)
			(copperpour allowed)
			(footprints allowed)
		)
		(placement
			(enabled no)
			(sheetname "")
		)
		(fill
			(thermal_gap 0.5)
			(thermal_bridge_width 0.5)
			(island_removal_mode 0)
		)
		(polygon
			(pts
				(xy 303.951132 -31.160974) (xy 303.951132 -29.809694) (xy 305.231292 -29.809694) (xy 305.231292 -31.160974)
			)
		)
	)
	(zone
		(layer "F.Cu")
		(hatch none 0.5)
		(connect_pads
			(clearance 0)
		)
		(min_thickness 0.25)
		(keepout
			(tracks not_allowed)
			(vias allowed)
			(pads allowed)
			(copperpour not_allowed)
			(footprints allowed)
		)
		(placement
			(enabled no)
			(sheetname "")
		)
		(fill
			(thermal_gap 0.5)
			(thermal_bridge_width 0.5)
			(island_removal_mode 0)
		)
		(polygon
			(pts
				(arc
					(start 444.200026 -308.61)
					(mid 447.449956 -305.36007)
					(end 450.699886 -308.61)
				)
				(arc
					(start 450.699886 -308.61)
					(mid 447.449956 -311.85993)
					(end 444.200026 -308.61)
				)
			)
		)
	)
	(zone
		(layer "F.Cu")
		(hatch none 0.5)
		(connect_pads
			(clearance 0)
		)
		(min_thickness 0.25)
		(keepout
			(tracks allowed)
			(vias allowed)
			(pads allowed)
			(copperpour allowed)
			(footprints allowed)
		)
		(placement
			(enabled no)
			(sheetname "")
		)
		(fill
			(thermal_gap 0.5)
			(thermal_bridge_width 0.5)
			(island_removal_mode 0)
		)
		(polygon
			(pts
				(xy 68.694046 -356.952042) (xy 67.342766 -356.952042) (xy 67.342766 -355.671882) (xy 68.694046 -355.671882)
			)
		)
	)
	(zone
		(layer "F.Cu")
		(hatch none 0.5)
		(connect_pads
			(clearance 0)
		)
		(min_thickness 0.25)
		(keepout
			(tracks allowed)
			(vias allowed)
			(pads allowed)
			(copperpour allowed)
			(footprints not_allowed)
		)
		(placement
			(enabled no)
			(sheetname "")
		)
		(fill
			(thermal_gap 0.5)
			(thermal_bridge_width 0.5)
			(island_removal_mode 0)
		)
		(polygon
			(pts
				(xy 357.81996 -23.219918) (xy 357.81996 -18.219928) (xy 353.62007 -18.219928) (xy 353.62007 -23.219918)
			)
		)
	)
	(zone
		(layer "F.Cu")
		(hatch none 0.5)
		(connect_pads
			(clearance 0)
		)
		(min_thickness 0.25)
		(keepout
			(tracks allowed)
			(vias allowed)
			(pads allowed)
			(copperpour allowed)
			(footprints allowed)
		)
		(placement
			(enabled no)
			(sheetname "")
		)
		(fill
			(thermal_gap 0.5)
			(thermal_bridge_width 0.5)
			(island_removal_mode 0)
		)
		(polygon
			(pts
				(xy 234.3785 -267.978636) (xy 234.3785 -265.860276) (xy 236.03204 -265.860276) (xy 236.03204 -267.978636)
			)
		)
	)
	(zone
		(layer "F.Cu")
		(hatch none 0.5)
		(connect_pads
			(clearance 0)
		)
		(min_thickness 0.25)
		(keepout
			(tracks allowed)
			(vias allowed)
			(pads allowed)
			(copperpour allowed)
			(footprints not_allowed)
		)
		(placement
			(enabled no)
			(sheetname "")
		)
		(fill
			(thermal_gap 0.5)
			(thermal_bridge_width 0.5)
			(island_removal_mode 0)
		)
		(polygon
			(pts
				(xy 293.720012 -23.219918) (xy 293.720012 -18.219928) (xy 289.520122 -18.219928) (xy 289.520122 -23.219918)
			)
		)
	)
	(zone
		(layer "F.Cu")
		(hatch none 0.5)
		(connect_pads
			(clearance 0)
		)
		(min_thickness 0.25)
		(keepout
			(tracks allowed)
			(vias allowed)
			(pads allowed)
			(copperpour allowed)
			(footprints allowed)
		)
		(placement
			(enabled no)
			(sheetname "")
		)
		(fill
			(thermal_gap 0.5)
			(thermal_bridge_width 0.5)
			(island_removal_mode 0)
		)
		(polygon
			(pts
				(xy 414.788604 -35.519868) (xy 416.616896 -35.519868) (xy 416.85337 -35.283394) (xy 416.85337 -26.930096)
				(xy 416.616896 -26.693622) (xy 414.960816 -26.693622) (xy 414.788604 -26.865834)
			)
		)
	)
	(zone
		(layer "F.Cu")
		(hatch none 0.5)
		(connect_pads
			(clearance 0)
		)
		(min_thickness 0.25)
		(keepout
			(tracks allowed)
			(vias allowed)
			(pads allowed)
			(copperpour allowed)
			(footprints allowed)
		)
		(placement
			(enabled no)
			(sheetname "")
		)
		(fill
			(thermal_gap 0.5)
			(thermal_bridge_width 0.5)
			(island_removal_mode 0)
		)
		(polygon
			(pts
				(xy 457.66228 -268.0716) (xy 457.66228 -265.92276) (xy 459.3336 -265.92276) (xy 459.3336 -268.0716)
			)
		)
	)
	(zone
		(layer "F.Cu")
		(hatch none 0.5)
		(connect_pads
			(clearance 0)
		)
		(min_thickness 0.25)
		(keepout
			(tracks allowed)
			(vias allowed)
			(pads allowed)
			(copperpour allowed)
			(footprints not_allowed)
		)
		(placement
			(enabled no)
			(sheetname "")
		)
		(fill
			(thermal_gap 0.5)
			(thermal_bridge_width 0.5)
			(island_removal_mode 0)
		)
		(polygon
			(pts
				(xy 34.964878 -40.120062) (xy 42.964862 -40.120062) (xy 42.965116 -13.850112) (xy 34.964878 -13.850112)
			)
		)
	)
	(zone
		(layer "F.Cu")
		(hatch none 0.5)
		(connect_pads
			(clearance 0)
		)
		(min_thickness 0.25)
		(keepout
			(tracks allowed)
			(vias allowed)
			(pads allowed)
			(copperpour allowed)
			(footprints not_allowed)
		)
		(placement
			(enabled no)
			(sheetname "")
		)
		(fill
			(thermal_gap 0.5)
			(thermal_bridge_width 0.5)
			(island_removal_mode 0)
		)
		(polygon
			(pts
				(arc
					(start 0.999998 -401.355052)
					(mid 2.164116 -400.579593)
					(end 3.44551 -400.018758)
				)
				(arc
					(start 3.44551 -400.018758)
					(mid 2.776283 -397.159057)
					(end 5.199888 -395.500098)
				)
				(arc
					(start 6.800088 -395.500098)
					(mid 9.223764 -397.15903)
					(end 8.554466 -400.018758)
				)
				(arc
					(start 8.554466 -400.018758)
					(mid 12.497475 -402.932812)
					(end 13.999972 -407.599896)
				)
				(arc
					(start 13.999972 -407.599896)
					(mid 9.464114 -414.810969)
					(end 0.999998 -413.844994)
				)
				(arc
					(start 0.999998 -416.589972)
					(mid 1.292891 -417.297077)
					(end 1.999996 -417.58997)
				)
				(xy 23.459948 -417.58997) (xy 23.459948 -361.790234) (xy 52.559966 -361.790234) (xy 52.559966 -394.269976)
				(xy 67.45986 -394.269976) (xy 67.45986 -361.790234) (xy 96.559878 -361.790234)
				(arc
					(start 96.559878 -404.684992)
					(mid 104.01007 -399.599879)
					(end 111.460026 -404.685246)
				)
				(xy 111.460026 -361.790234) (xy 140.560044 -361.790234) (xy 140.560044 -394.269976) (xy 155.460192 -394.269976)
				(xy 155.460192 -361.790234) (xy 184.56021 -361.790234) (xy 184.56021 -417.58997) (xy 202.160124 -417.58997)
				(arc
					(start 202.160124 -400.6088)
					(mid 192.345704 -396.872762)
					(end 194.68719 -386.635498)
				)
				(arc
					(start 194.68719 -386.635498)
					(mid 187.843731 -377.190724)
					(end 197.699884 -370.954046)
				)
				(xy 197.699884 -329.3999) (xy 141.750034 -329.3999) (xy 141.750034 -342.399874) (xy 93.650054 -342.399874)
				(xy 93.650054 -329.3999) (xy 25.649936 -329.3999) (xy 25.649936 -342.399874) (xy 0.999998 -342.399874)
			)
		)
	)
	(zone
		(layer "F.Cu")
		(hatch none 0.5)
		(connect_pads
			(clearance 0)
		)
		(min_thickness 0.25)
		(keepout
			(tracks allowed)
			(vias allowed)
			(pads allowed)
			(copperpour allowed)
			(footprints not_allowed)
		)
		(placement
			(enabled no)
			(sheetname "")
		)
		(fill
			(thermal_gap 0.5)
			(thermal_bridge_width 0.5)
			(island_removal_mode 0)
		)
		(polygon
			(pts
				(xy 121.419874 -23.219918) (xy 125.620018 -23.219918) (xy 125.620018 -18.219928) (xy 121.419874 -18.219928)
			)
		)
	)
	(zone
		(layer "F.Cu")
		(hatch none 0.5)
		(connect_pads
			(clearance 0)
		)
		(min_thickness 0.25)
		(keepout
			(tracks allowed)
			(vias allowed)
			(pads allowed)
			(copperpour allowed)
			(footprints not_allowed)
		)
		(placement
			(enabled no)
			(sheetname "")
		)
		(fill
			(thermal_gap 0.5)
			(thermal_bridge_width 0.5)
			(island_removal_mode 0)
		)
		(polygon
			(pts
				(xy 184.56021 -361.790234) (xy 155.460192 -361.790234) (xy 155.460192 -417.58997) (xy 184.56021 -417.58997)
			)
		)
	)
	(zone
		(layer "F.Cu")
		(hatch none 0.5)
		(connect_pads
			(clearance 0)
		)
		(min_thickness 0.25)
		(keepout
			(tracks allowed)
			(vias allowed)
			(pads allowed)
			(copperpour allowed)
			(footprints allowed)
		)
		(placement
			(enabled no)
			(sheetname "")
		)
		(fill
			(thermal_gap 0.5)
			(thermal_bridge_width 0.5)
			(island_removal_mode 0)
		)
		(polygon
			(pts
				(xy 100.23221 -384.861816) (xy 100.23221 -384.024886) (xy 100.23221 -383.534412) (xy 100.231956 -383.534158)
				(xy 98.784156 -383.534158) (xy 98.663506 -383.654808) (xy 98.663506 -383.96418) (xy 98.693732 -383.994406)
				(xy 98.693732 -384.838956) (xy 98.77679 -384.922014) (xy 100.172012 -384.922014)
			)
		)
	)
	(zone
		(layer "F.Cu")
		(hatch none 0.5)
		(connect_pads
			(clearance 0)
		)
		(min_thickness 0.25)
		(keepout
			(tracks allowed)
			(vias allowed)
			(pads allowed)
			(copperpour allowed)
			(footprints allowed)
		)
		(placement
			(enabled no)
			(sheetname "")
		)
		(fill
			(thermal_gap 0.5)
			(thermal_bridge_width 0.5)
			(island_removal_mode 0)
		)
		(polygon
			(pts
				(xy 216.59088 -385.83616) (xy 216.59088 -382.50114) (xy 221.93504 -382.50114) (xy 221.93504 -385.83616)
			)
		)
	)
	(zone
		(layer "F.Cu")
		(hatch none 0.5)
		(connect_pads
			(clearance 0)
		)
		(min_thickness 0.25)
		(keepout
			(tracks allowed)
			(vias allowed)
			(pads allowed)
			(copperpour allowed)
			(footprints allowed)
		)
		(placement
			(enabled no)
			(sheetname "")
		)
		(fill
			(thermal_gap 0.5)
			(thermal_bridge_width 0.5)
			(island_removal_mode 0)
		)
		(polygon
			(pts
				(xy 287.629346 -344.659458) (xy 286.278066 -344.659458) (xy 286.278066 -343.379298) (xy 287.629346 -343.379298)
			)
		)
	)
	(zone
		(layer "F.Cu")
		(hatch none 0.5)
		(connect_pads
			(clearance 0)
		)
		(min_thickness 0.25)
		(keepout
			(tracks allowed)
			(vias allowed)
			(pads allowed)
			(copperpour allowed)
			(footprints allowed)
		)
		(placement
			(enabled no)
			(sheetname "")
		)
		(fill
			(thermal_gap 0.5)
			(thermal_bridge_width 0.5)
			(island_removal_mode 0)
		)
		(polygon
			(pts
				(xy 440.788552 -35.519868) (xy 442.616844 -35.519868) (xy 442.853318 -35.283394) (xy 442.853318 -26.930096)
				(xy 442.616844 -26.693622) (xy 440.960764 -26.693622) (xy 440.788552 -26.865834)
			)
		)
	)
	(zone
		(layer "F.Cu")
		(hatch none 0.5)
		(connect_pads
			(clearance 0)
		)
		(min_thickness 0.25)
		(keepout
			(tracks allowed)
			(vias allowed)
			(pads allowed)
			(copperpour allowed)
			(footprints allowed)
		)
		(placement
			(enabled no)
			(sheetname "")
		)
		(fill
			(thermal_gap 0.5)
			(thermal_bridge_width 0.5)
			(island_removal_mode 0)
		)
		(polygon
			(pts
				(xy 422.554146 -116.118386) (xy 421.17645 -116.118386) (xy 420.818564 -116.476272) (xy 420.818564 -122.452384)
				(xy 420.818564 -125.525022) (xy 420.938198 -125.644656) (xy 422.768522 -125.644656) (xy 423.251884 -125.161294)
				(xy 423.251884 -122.094498) (xy 423.251884 -116.816124)
			)
		)
	)
	(zone
		(layer "F.Cu")
		(hatch none 0.5)
		(connect_pads
			(clearance 0)
		)
		(min_thickness 0.25)
		(keepout
			(tracks allowed)
			(vias allowed)
			(pads allowed)
			(copperpour allowed)
			(footprints not_allowed)
		)
		(placement
			(enabled no)
			(sheetname "")
		)
		(fill
			(thermal_gap 0.5)
			(thermal_bridge_width 0.5)
			(island_removal_mode 0)
		)
		(polygon
			(pts
				(xy 96.559878 -361.790234) (xy 67.45986 -361.790234) (xy 67.45986 -417.58997) (xy 96.559878 -417.58997)
			)
		)
	)
	(zone
		(layer "F.Cu")
		(hatch none 0.5)
		(connect_pads
			(clearance 0)
		)
		(min_thickness 0.25)
		(keepout
			(tracks allowed)
			(vias allowed)
			(pads allowed)
			(copperpour allowed)
			(footprints allowed)
		)
		(placement
			(enabled no)
			(sheetname "")
		)
		(fill
			(thermal_gap 0.5)
			(thermal_bridge_width 0.5)
			(island_removal_mode 0)
		)
		(polygon
			(pts
				(xy 104.267 -321.945) (xy 104.267 -320.294) (xy 106.299 -320.294) (xy 106.299 -321.945)
			)
		)
	)
	(zone
		(layer "F.Cu")
		(hatch none 0.5)
		(connect_pads
			(clearance 0)
		)
		(min_thickness 0.25)
		(keepout
			(tracks not_allowed)
			(vias allowed)
			(pads allowed)
			(copperpour not_allowed)
			(footprints allowed)
		)
		(placement
			(enabled no)
			(sheetname "")
		)
		(fill
			(thermal_gap 0.5)
			(thermal_bridge_width 0.5)
			(island_removal_mode 0)
		)
		(polygon
			(pts
				(arc
					(start 85.149944 -320.900044)
					(mid 89.650062 -316.399926)
					(end 94.149926 -320.900044)
				)
				(arc
					(start 94.149926 -320.900044)
					(mid 89.650062 -325.399908)
					(end 85.149944 -320.900044)
				)
			)
		)
	)
	(zone
		(layer "F.Cu")
		(hatch none 0.5)
		(connect_pads
			(clearance 0)
		)
		(min_thickness 0.25)
		(keepout
			(tracks allowed)
			(vias allowed)
			(pads allowed)
			(copperpour allowed)
			(footprints allowed)
		)
		(placement
			(enabled no)
			(sheetname "")
		)
		(fill
			(thermal_gap 0.5)
			(thermal_bridge_width 0.5)
			(island_removal_mode 0)
		)
		(polygon
			(pts
				(xy 429.027336 -344.659458) (xy 427.676056 -344.659458) (xy 427.676056 -343.379298) (xy 429.027336 -343.379298)
			)
		)
	)
	(zone
		(layer "F.Cu")
		(hatch none 0.5)
		(connect_pads
			(clearance 0)
		)
		(min_thickness 0.25)
		(keepout
			(tracks allowed)
			(vias allowed)
			(pads allowed)
			(copperpour allowed)
			(footprints allowed)
		)
		(placement
			(enabled no)
			(sheetname "")
		)
		(fill
			(thermal_gap 0.5)
			(thermal_bridge_width 0.5)
			(island_removal_mode 0)
		)
		(polygon
			(pts
				(xy 35.981132 -344.659458) (xy 34.629852 -344.659458) (xy 34.629852 -343.379298) (xy 35.981132 -343.379298)
			)
		)
	)
	(zone
		(layer "F.Cu")
		(hatch none 0.5)
		(connect_pads
			(clearance 0)
		)
		(min_thickness 0.25)
		(keepout
			(tracks not_allowed)
			(vias allowed)
			(pads allowed)
			(copperpour not_allowed)
			(footprints allowed)
		)
		(placement
			(enabled no)
			(sheetname "")
		)
		(fill
			(thermal_gap 0.5)
			(thermal_bridge_width 0.5)
			(island_removal_mode 0)
		)
		(polygon
			(pts
				(xy 420.91991 -18.150078) (xy 420.91991 -13.150088) (xy 416.72002 -13.150088) (xy 416.72002 -18.150078)
			)
		)
	)
	(zone
		(layer "F.Cu")
		(hatch none 0.5)
		(connect_pads
			(clearance 0)
		)
		(min_thickness 0.25)
		(keepout
			(tracks allowed)
			(vias allowed)
			(pads allowed)
			(copperpour allowed)
			(footprints allowed)
		)
		(placement
			(enabled no)
			(sheetname "")
		)
		(fill
			(thermal_gap 0.5)
			(thermal_bridge_width 0.5)
			(island_removal_mode 0)
		)
		(polygon
			(pts
				(xy 239.794034 -235.944918) (xy 240.11128 -235.944918) (xy 240.212118 -235.84408) (xy 240.212118 -234.91698)
				(xy 240.1316 -234.836462) (xy 239.718342 -234.836462) (xy 239.688116 -234.866688) (xy 239.688116 -235.839)
			)
		)
	)
	(zone
		(layer "F.Cu")
		(hatch none 0.5)
		(connect_pads
			(clearance 0)
		)
		(min_thickness 0.25)
		(keepout
			(tracks not_allowed)
			(vias allowed)
			(pads allowed)
			(copperpour not_allowed)
			(footprints allowed)
		)
		(placement
			(enabled no)
			(sheetname "")
		)
		(fill
			(thermal_gap 0.5)
			(thermal_bridge_width 0.5)
			(island_removal_mode 0)
		)
		(polygon
			(pts
				(arc
					(start 27.399996 -270.89989)
					(mid 29.650182 -268.649704)
					(end 31.900114 -270.89989)
				)
				(arc
					(start 31.900114 -270.89989)
					(mid 29.650182 -273.149822)
					(end 27.399996 -270.89989)
				)
			)
		)
	)
	(zone
		(layer "F.Cu")
		(hatch none 0.5)
		(connect_pads
			(clearance 0)
		)
		(min_thickness 0.25)
		(keepout
			(tracks allowed)
			(vias allowed)
			(pads allowed)
			(copperpour allowed)
			(footprints not_allowed)
		)
		(placement
			(enabled no)
			(sheetname "")
		)
		(fill
			(thermal_gap 0.5)
			(thermal_bridge_width 0.5)
			(island_removal_mode 0)
		)
		(polygon
			(pts
				(arc
					(start 31.657036 -232.750106)
					(mid 19.698959 -243.749914)
					(end 7.74065 -232.750106)
				)
			)
		)
	)
	(zone
		(layer "F.Cu")
		(hatch none 0.5)
		(connect_pads
			(clearance 0)
		)
		(min_thickness 0.25)
		(keepout
			(tracks allowed)
			(vias allowed)
			(pads allowed)
			(copperpour allowed)
			(footprints allowed)
		)
		(placement
			(enabled no)
			(sheetname "")
		)
		(fill
			(thermal_gap 0.5)
			(thermal_bridge_width 0.5)
			(island_removal_mode 0)
		)
		(polygon
			(pts
				(xy 447.900044 -235.025438) (xy 447.900044 -234.037886) (xy 449.919598 -234.037886) (xy 449.919598 -235.025438)
			)
		)
	)
	(zone
		(layer "F.Cu")
		(hatch none 0.5)
		(connect_pads
			(clearance 0)
		)
		(min_thickness 0.25)
		(keepout
			(tracks allowed)
			(vias allowed)
			(pads allowed)
			(copperpour allowed)
			(footprints allowed)
		)
		(placement
			(enabled no)
			(sheetname "")
		)
		(fill
			(thermal_gap 0.5)
			(thermal_bridge_width 0.5)
			(island_removal_mode 0)
		)
		(polygon
			(pts
				(xy 217.6272 -103.0478) (xy 217.6272 -101.3714) (xy 219.3798 -101.3714) (xy 219.3798 -103.0478)
			)
		)
	)
	(zone
		(layer "F.Cu")
		(hatch none 0.5)
		(connect_pads
			(clearance 0)
		)
		(min_thickness 0.25)
		(keepout
			(tracks allowed)
			(vias allowed)
			(pads allowed)
			(copperpour allowed)
			(footprints allowed)
		)
		(placement
			(enabled no)
			(sheetname "")
		)
		(fill
			(thermal_gap 0.5)
			(thermal_bridge_width 0.5)
			(island_removal_mode 0)
		)
		(polygon
			(pts
				(xy 358.267 -22.733) (xy 358.267 -21.844) (xy 360.934 -21.844) (xy 360.934 -22.733)
			)
		)
	)
	(zone
		(layer "F.Cu")
		(hatch none 0.5)
		(connect_pads
			(clearance 0)
		)
		(min_thickness 0.25)
		(keepout
			(tracks allowed)
			(vias allowed)
			(pads allowed)
			(copperpour allowed)
			(footprints allowed)
		)
		(placement
			(enabled no)
			(sheetname "")
		)
		(fill
			(thermal_gap 0.5)
			(thermal_bridge_width 0.5)
			(island_removal_mode 0)
		)
		(polygon
			(pts
				(xy 32.872172 -356.952042) (xy 31.520892 -356.952042) (xy 31.520892 -355.671882) (xy 32.872172 -355.671882)
			)
		)
	)
	(zone
		(layer "F.Cu")
		(hatch none 0.5)
		(connect_pads
			(clearance 0)
		)
		(min_thickness 0.25)
		(keepout
			(tracks allowed)
			(vias allowed)
			(pads allowed)
			(copperpour allowed)
			(footprints allowed)
		)
		(placement
			(enabled no)
			(sheetname "")
		)
		(fill
			(thermal_gap 0.5)
			(thermal_bridge_width 0.5)
			(island_removal_mode 0)
		)
		(polygon
			(pts
				(xy 93.73108 -123.188476) (xy 94.36354 -123.188476) (xy 94.530926 -123.02109) (xy 94.530926 -119.765572)
				(xy 94.140274 -119.37492) (xy 93.526356 -119.37492) (xy 92.66047 -119.37492) (xy 92.56776 -119.46763)
				(xy 92.56776 -120.118886) (xy 92.735146 -120.286272) (xy 93.451934 -120.286272) (xy 93.451934 -122.90933)
			)
		)
	)
	(zone
		(layer "F.Cu")
		(hatch none 0.5)
		(connect_pads
			(clearance 0)
		)
		(min_thickness 0.25)
		(keepout
			(tracks allowed)
			(vias allowed)
			(pads allowed)
			(copperpour allowed)
			(footprints allowed)
		)
		(placement
			(enabled no)
			(sheetname "")
		)
		(fill
			(thermal_gap 0.5)
			(thermal_bridge_width 0.5)
			(island_removal_mode 0)
		)
		(polygon
			(pts
				(xy 319.701926 -35.458146) (xy 320.875152 -35.458146) (xy 321.164712 -35.168586) (xy 321.164712 -27.534616)
				(xy 320.920872 -27.290776) (xy 319.580006 -27.290776) (xy 319.061846 -27.808936) (xy 319.061846 -34.818066)
			)
		)
	)
	(zone
		(layer "F.Cu")
		(hatch none 0.5)
		(connect_pads
			(clearance 0)
		)
		(min_thickness 0.25)
		(keepout
			(tracks allowed)
			(vias allowed)
			(pads allowed)
			(copperpour allowed)
			(footprints allowed)
		)
		(placement
			(enabled no)
			(sheetname "")
		)
		(fill
			(thermal_gap 0.5)
			(thermal_bridge_width 0.5)
			(island_removal_mode 0)
		)
		(polygon
			(pts
				(xy 386.897372 -100.418138) (xy 386.897372 -99.066858) (xy 388.177532 -99.066858) (xy 388.177532 -100.418138)
			)
		)
	)
	(zone
		(layer "F.Cu")
		(hatch none 0.5)
		(connect_pads
			(clearance 0)
		)
		(min_thickness 0.25)
		(keepout
			(tracks allowed)
			(vias allowed)
			(pads allowed)
			(copperpour allowed)
			(footprints allowed)
		)
		(placement
			(enabled no)
			(sheetname "")
		)
		(fill
			(thermal_gap 0.5)
			(thermal_bridge_width 0.5)
			(island_removal_mode 0)
		)
		(polygon
			(pts
				(xy 20.436332 -350.80575) (xy 19.085052 -350.80575) (xy 19.085052 -349.52559) (xy 20.436332 -349.52559)
			)
		)
	)
	(zone
		(layer "F.Cu")
		(hatch none 0.5)
		(connect_pads
			(clearance 0)
		)
		(min_thickness 0.25)
		(keepout
			(tracks allowed)
			(vias allowed)
			(pads allowed)
			(copperpour allowed)
			(footprints not_allowed)
		)
		(placement
			(enabled no)
			(sheetname "")
		)
		(fill
			(thermal_gap 0.5)
			(thermal_bridge_width 0.5)
			(island_removal_mode 0)
		)
		(polygon
			(pts
				(arc
					(start 327.35012 -289.820096)
					(mid 331.350112 -285.820104)
					(end 335.350104 -289.820096)
				)
				(arc
					(start 335.350104 -289.820096)
					(mid 331.350112 -293.820088)
					(end 327.35012 -289.820096)
				)
			)
		)
	)
	(zone
		(layer "F.Cu")
		(hatch none 0.5)
		(connect_pads
			(clearance 0)
		)
		(min_thickness 0.25)
		(keepout
			(tracks allowed)
			(vias allowed)
			(pads allowed)
			(copperpour allowed)
			(footprints allowed)
		)
		(placement
			(enabled no)
			(sheetname "")
		)
		(fill
			(thermal_gap 0.5)
			(thermal_bridge_width 0.5)
			(island_removal_mode 0)
		)
		(polygon
			(pts
				(xy 40.66159 -27.55011) (xy 43.061636 -27.55011) (xy 43.153076 -27.45867) (xy 43.153076 -26.33853)
				(xy 43.092116 -26.27757) (xy 40.64635 -26.27757) (xy 40.52443 -26.39949) (xy 40.52443 -27.41295)
			)
		)
	)
	(zone
		(layer "F.Cu")
		(hatch none 0.5)
		(connect_pads
			(clearance 0)
		)
		(min_thickness 0.25)
		(keepout
			(tracks allowed)
			(vias allowed)
			(pads allowed)
			(copperpour allowed)
			(footprints allowed)
		)
		(placement
			(enabled no)
			(sheetname "")
		)
		(fill
			(thermal_gap 0.5)
			(thermal_bridge_width 0.5)
			(island_removal_mode 0)
		)
		(polygon
			(pts
				(xy 185.052716 -344.659458) (xy 183.701436 -344.659458) (xy 183.701436 -343.379298) (xy 185.052716 -343.379298)
			)
		)
	)
	(zone
		(layer "F.Cu")
		(hatch none 0.5)
		(connect_pads
			(clearance 0)
		)
		(min_thickness 0.25)
		(keepout
			(tracks allowed)
			(vias allowed)
			(pads allowed)
			(copperpour allowed)
			(footprints not_allowed)
		)
		(placement
			(enabled no)
			(sheetname "")
		)
		(fill
			(thermal_gap 0.5)
			(thermal_bridge_width 0.5)
			(island_removal_mode 0)
		)
		(polygon
			(pts
				(arc
					(start 118.015004 -17.999964)
					(mid 110.01502 -25.999948)
					(end 102.015036 -17.999964)
				)
				(arc
					(start 102.015036 -17.999964)
					(mid 110.01502 -9.99998)
					(end 118.015004 -17.999964)
				)
			)
		)
	)
	(zone
		(layer "F.Cu")
		(hatch none 0.5)
		(connect_pads
			(clearance 0)
		)
		(min_thickness 0.25)
		(keepout
			(tracks not_allowed)
			(vias allowed)
			(pads allowed)
			(copperpour not_allowed)
			(footprints allowed)
		)
		(placement
			(enabled no)
			(sheetname "")
		)
		(fill
			(thermal_gap 0.5)
			(thermal_bridge_width 0.5)
			(island_removal_mode 0)
		)
		(polygon
			(pts
				(xy 54.790086 -417.58997) (xy 64.790066 -417.58997) (xy 64.790066 -396.54988) (xy 54.790086 -396.54988)
			)
		)
	)
	(zone
		(layer "F.Cu")
		(hatch none 0.5)
		(connect_pads
			(clearance 0)
		)
		(min_thickness 0.25)
		(keepout
			(tracks allowed)
			(vias allowed)
			(pads allowed)
			(copperpour allowed)
			(footprints allowed)
		)
		(placement
			(enabled no)
			(sheetname "")
		)
		(fill
			(thermal_gap 0.5)
			(thermal_bridge_width 0.5)
			(island_removal_mode 0)
		)
		(polygon
			(pts
				(xy 344.181938 -314.64123) (xy 342.530938 -314.64123) (xy 342.530938 -312.60923) (xy 344.181938 -312.60923)
			)
		)
	)
	(zone
		(layer "F.Cu")
		(hatch none 0.5)
		(connect_pads
			(clearance 0)
		)
		(min_thickness 0.25)
		(keepout
			(tracks allowed)
			(vias allowed)
			(pads allowed)
			(copperpour allowed)
			(footprints allowed)
		)
		(placement
			(enabled no)
			(sheetname "")
		)
		(fill
			(thermal_gap 0.5)
			(thermal_bridge_width 0.5)
			(island_removal_mode 0)
		)
		(polygon
			(pts
				(xy 324.688454 -35.519868) (xy 326.516746 -35.519868) (xy 326.75322 -35.283394) (xy 326.75322 -26.930096)
				(xy 326.516746 -26.693622) (xy 324.860666 -26.693622) (xy 324.688454 -26.865834)
			)
		)
	)
	(zone
		(layer "F.Cu")
		(hatch none 0.5)
		(connect_pads
			(clearance 0)
		)
		(min_thickness 0.25)
		(keepout
			(tracks allowed)
			(vias allowed)
			(pads allowed)
			(copperpour allowed)
			(footprints not_allowed)
		)
		(placement
			(enabled no)
			(sheetname "")
		)
		(fill
			(thermal_gap 0.5)
			(thermal_bridge_width 0.5)
			(island_removal_mode 0)
		)
		(polygon
			(pts
				(xy 315.52007 -23.219918) (xy 319.71996 -23.219918) (xy 319.71996 -18.219928) (xy 315.52007 -18.219928)
			)
		)
	)
	(zone
		(layer "F.Cu")
		(hatch none 0.5)
		(connect_pads
			(clearance 0)
		)
		(min_thickness 0.25)
		(keepout
			(tracks allowed)
			(vias allowed)
			(pads allowed)
			(copperpour allowed)
			(footprints allowed)
		)
		(placement
			(enabled no)
			(sheetname "")
		)
		(fill
			(thermal_gap 0.5)
			(thermal_bridge_width 0.5)
			(island_removal_mode 0)
		)
		(polygon
			(pts
				(xy 427.636178 -123.39955) (xy 427.636178 -122.04827) (xy 428.916338 -122.04827) (xy 428.916338 -123.39955)
			)
		)
	)
	(zone
		(layer "F.Cu")
		(hatch none 0.5)
		(connect_pads
			(clearance 0)
		)
		(min_thickness 0.25)
		(keepout
			(tracks allowed)
			(vias allowed)
			(pads allowed)
			(copperpour allowed)
			(footprints allowed)
		)
		(placement
			(enabled no)
			(sheetname "")
		)
		(fill
			(thermal_gap 0.5)
			(thermal_bridge_width 0.5)
			(island_removal_mode 0)
		)
		(polygon
			(pts
				(xy 301.309024 -32.954468) (xy 301.309024 -31.603188) (xy 302.589184 -31.603188) (xy 302.589184 -32.954468)
			)
		)
	)
	(zone
		(layer "F.Cu")
		(hatch none 0.5)
		(connect_pads
			(clearance 0)
		)
		(min_thickness 0.25)
		(keepout
			(tracks allowed)
			(vias allowed)
			(pads allowed)
			(copperpour allowed)
			(footprints allowed)
		)
		(placement
			(enabled no)
			(sheetname "")
		)
		(fill
			(thermal_gap 0.5)
			(thermal_bridge_width 0.5)
			(island_removal_mode 0)
		)
		(polygon
			(pts
				(xy 442.021722 -122.776996) (xy 442.582808 -122.776996) (xy 442.6839 -122.675904) (xy 442.6839 -119.806212)
				(xy 442.591952 -119.714264) (xy 441.23991 -119.714264) (xy 441.129674 -119.8245) (xy 441.129674 -120.109742)
				(xy 441.249308 -120.229376) (xy 441.84697 -120.229376) (xy 442.021722 -120.404128)
			)
		)
	)
	(zone
		(layer "F.Cu")
		(hatch none 0.5)
		(connect_pads
			(clearance 0)
		)
		(min_thickness 0.25)
		(keepout
			(tracks allowed)
			(vias allowed)
			(pads allowed)
			(copperpour allowed)
			(footprints not_allowed)
		)
		(placement
			(enabled no)
			(sheetname "")
		)
		(fill
			(thermal_gap 0.5)
			(thermal_bridge_width 0.5)
			(island_removal_mode 0)
		)
		(polygon
			(pts
				(xy 432.699922 -320.650108) (xy 432.699922 -271.15008) (xy 383.199894 -271.15008) (xy 383.199894 -320.650108)
			)
		)
	)
	(zone
		(layer "F.Cu")
		(hatch none 0.5)
		(connect_pads
			(clearance 0)
		)
		(min_thickness 0.25)
		(keepout
			(tracks allowed)
			(vias allowed)
			(pads allowed)
			(copperpour allowed)
			(footprints allowed)
		)
		(placement
			(enabled no)
			(sheetname "")
		)
		(fill
			(thermal_gap 0.5)
			(thermal_bridge_width 0.5)
			(island_removal_mode 0)
		)
		(polygon
			(pts
				(xy 108.130848 -284.544262) (xy 108.607606 -284.544262) (xy 108.868972 -284.805628) (xy 108.985558 -284.805628)
				(xy 109.193838 -284.597348) (xy 109.193838 -282.759404) (xy 108.796074 -282.36164) (xy 108.220256 -282.36164)
				(xy 108.068618 -282.513278) (xy 108.068618 -284.482032)
			)
		)
	)
	(zone
		(layer "F.Cu")
		(hatch none 0.5)
		(connect_pads
			(clearance 0)
		)
		(min_thickness 0.25)
		(keepout
			(tracks allowed)
			(vias allowed)
			(pads allowed)
			(copperpour allowed)
			(footprints allowed)
		)
		(placement
			(enabled no)
			(sheetname "")
		)
		(fill
			(thermal_gap 0.5)
			(thermal_bridge_width 0.5)
			(island_removal_mode 0)
		)
		(polygon
			(pts
				(xy 446.051178 -31.160974) (xy 446.051178 -29.809694) (xy 447.331338 -29.809694) (xy 447.331338 -31.160974)
			)
		)
	)
	(zone
		(layer "F.Cu")
		(hatch none 0.5)
		(connect_pads
			(clearance 0)
		)
		(min_thickness 0.25)
		(keepout
			(tracks allowed)
			(vias allowed)
			(pads allowed)
			(copperpour allowed)
			(footprints allowed)
		)
		(placement
			(enabled no)
			(sheetname "")
		)
		(fill
			(thermal_gap 0.5)
			(thermal_bridge_width 0.5)
			(island_removal_mode 0)
		)
		(polygon
			(pts
				(xy 188.161676 -356.90429) (xy 186.810396 -356.90429) (xy 186.810396 -355.62413) (xy 188.161676 -355.62413)
			)
		)
	)
	(zone
		(layer "F.Cu")
		(hatch none 0.5)
		(connect_pads
			(clearance 0)
		)
		(min_thickness 0.25)
		(keepout
			(tracks allowed)
			(vias allowed)
			(pads allowed)
			(copperpour allowed)
			(footprints allowed)
		)
		(placement
			(enabled no)
			(sheetname "")
		)
		(fill
			(thermal_gap 0.5)
			(thermal_bridge_width 0.5)
			(island_removal_mode 0)
		)
		(polygon
			(pts
				(xy 316.715648 -350.80575) (xy 315.364368 -350.80575) (xy 315.364368 -349.52559) (xy 316.715648 -349.52559)
			)
		)
	)
	(zone
		(layer "F.Cu")
		(hatch none 0.5)
		(connect_pads
			(clearance 0)
		)
		(min_thickness 0.25)
		(keepout
			(tracks allowed)
			(vias allowed)
			(pads allowed)
			(copperpour allowed)
			(footprints allowed)
		)
		(placement
			(enabled no)
			(sheetname "")
		)
		(fill
			(thermal_gap 0.5)
			(thermal_bridge_width 0.5)
			(island_removal_mode 0)
		)
		(polygon
			(pts
				(xy 81.978246 -125.205998) (xy 81.978246 -123.854718) (xy 83.258406 -123.854718) (xy 83.258406 -125.205998)
			)
		)
	)
	(zone
		(layer "F.Cu")
		(hatch none 0.5)
		(connect_pads
			(clearance 0)
		)
		(min_thickness 0.25)
		(keepout
			(tracks allowed)
			(vias allowed)
			(pads allowed)
			(copperpour allowed)
			(footprints allowed)
		)
		(placement
			(enabled no)
			(sheetname "")
		)
		(fill
			(thermal_gap 0.5)
			(thermal_bridge_width 0.5)
			(island_removal_mode 0)
		)
		(polygon
			(pts
				(xy 87.190326 -35.5346) (xy 88.714072 -35.5346) (xy 88.912192 -35.33648) (xy 88.912192 -27.519122)
				(xy 88.744552 -27.351482) (xy 87.068406 -27.351482) (xy 86.733126 -27.686762) (xy 86.733126 -35.0774)
			)
		)
	)
	(zone
		(layer "F.Cu")
		(hatch none 0.5)
		(connect_pads
			(clearance 0)
		)
		(min_thickness 0.25)
		(keepout
			(tracks allowed)
			(vias allowed)
			(pads allowed)
			(copperpour allowed)
			(footprints allowed)
		)
		(placement
			(enabled no)
			(sheetname "")
		)
		(fill
			(thermal_gap 0.5)
			(thermal_bridge_width 0.5)
			(island_removal_mode 0)
		)
		(polygon
			(pts
				(xy 97.751138 -34.76117) (xy 97.751138 -33.40989) (xy 99.031298 -33.40989) (xy 99.031298 -34.76117)
			)
		)
	)
	(zone
		(layer "F.Cu")
		(hatch none 0.5)
		(connect_pads
			(clearance 0)
		)
		(min_thickness 0.25)
		(keepout
			(tracks allowed)
			(vias allowed)
			(pads allowed)
			(copperpour allowed)
			(footprints allowed)
		)
		(placement
			(enabled no)
			(sheetname "")
		)
		(fill
			(thermal_gap 0.5)
			(thermal_bridge_width 0.5)
			(island_removal_mode 0)
		)
		(polygon
			(pts
				(xy 154.697176 -104.01808) (xy 154.697176 -102.6668) (xy 155.977336 -102.6668) (xy 155.977336 -104.01808)
			)
		)
	)
	(zone
		(layer "F.Cu")
		(hatch none 0.5)
		(connect_pads
			(clearance 0)
		)
		(min_thickness 0.25)
		(keepout
			(tracks allowed)
			(vias allowed)
			(pads allowed)
			(copperpour allowed)
			(footprints allowed)
		)
		(placement
			(enabled no)
			(sheetname "")
		)
		(fill
			(thermal_gap 0.5)
			(thermal_bridge_width 0.5)
			(island_removal_mode 0)
		)
		(polygon
			(pts
				(xy 450.234558 -229.53218) (xy 450.234558 -225.362008) (xy 454.463912 -225.362008) (xy 454.463912 -229.53218)
			)
		)
	)
	(zone
		(layer "F.Cu")
		(hatch none 0.5)
		(connect_pads
			(clearance 0)
		)
		(min_thickness 0.25)
		(keepout
			(tracks allowed)
			(vias allowed)
			(pads allowed)
			(copperpour allowed)
			(footprints allowed)
		)
		(placement
			(enabled no)
			(sheetname "")
		)
		(fill
			(thermal_gap 0.5)
			(thermal_bridge_width 0.5)
			(island_removal_mode 0)
		)
		(polygon
			(pts
				(xy 447.29146 -52.800758) (xy 447.29146 -55.718456) (xy 447.50101 -55.928006) (xy 448.113912 -55.928006)
				(xy 448.113912 -52.870608) (xy 448.044062 -52.800758)
			)
		)
	)
	(zone
		(layer "F.Cu")
		(hatch none 0.5)
		(connect_pads
			(clearance 0)
		)
		(min_thickness 0.25)
		(keepout
			(tracks allowed)
			(vias allowed)
			(pads allowed)
			(copperpour allowed)
			(footprints allowed)
		)
		(placement
			(enabled no)
			(sheetname "")
		)
		(fill
			(thermal_gap 0.5)
			(thermal_bridge_width 0.5)
			(island_removal_mode 0)
		)
		(polygon
			(pts
				(xy 105.581704 -392.295126) (xy 106.357674 -392.295126) (xy 106.525314 -392.462766) (xy 107.009946 -392.462766)
				(xy 107.089448 -392.383264) (xy 107.089448 -391.122154) (xy 106.825034 -390.85774) (xy 105.506774 -390.85774)
				(xy 105.453942 -390.910572) (xy 105.453942 -392.167364)
			)
		)
	)
	(zone
		(layer "F.Cu")
		(hatch none 0.5)
		(connect_pads
			(clearance 0)
		)
		(min_thickness 0.25)
		(keepout
			(tracks allowed)
			(vias allowed)
			(pads allowed)
			(copperpour allowed)
			(footprints allowed)
		)
		(placement
			(enabled no)
			(sheetname "")
		)
		(fill
			(thermal_gap 0.5)
			(thermal_bridge_width 0.5)
			(island_removal_mode 0)
		)
		(polygon
			(pts
				(xy 384.727704 -350.80575) (xy 383.376424 -350.80575) (xy 383.376424 -349.52559) (xy 384.727704 -349.52559)
			)
		)
	)
	(zone
		(layer "F.Cu")
		(hatch none 0.5)
		(connect_pads
			(clearance 0)
		)
		(min_thickness 0.25)
		(keepout
			(tracks allowed)
			(vias allowed)
			(pads allowed)
			(copperpour allowed)
			(footprints allowed)
		)
		(placement
			(enabled no)
			(sheetname "")
		)
		(fill
			(thermal_gap 0.5)
			(thermal_bridge_width 0.5)
			(island_removal_mode 0)
		)
		(polygon
			(pts
				(xy 122.292872 -344.659458) (xy 120.941592 -344.659458) (xy 120.941592 -343.379298) (xy 122.292872 -343.379298)
			)
		)
	)
	(zone
		(layer "F.Cu")
		(hatch none 0.5)
		(connect_pads
			(clearance 0)
		)
		(min_thickness 0.25)
		(keepout
			(tracks allowed)
			(vias allowed)
			(pads allowed)
			(copperpour allowed)
			(footprints allowed)
		)
		(placement
			(enabled no)
			(sheetname "")
		)
		(fill
			(thermal_gap 0.5)
			(thermal_bridge_width 0.5)
			(island_removal_mode 0)
		)
		(polygon
			(pts
				(xy 384.255264 -120.328182) (xy 384.255264 -118.976902) (xy 385.535424 -118.976902) (xy 385.535424 -120.328182)
			)
		)
	)
	(zone
		(layer "F.Cu")
		(hatch none 0.5)
		(connect_pads
			(clearance 0)
		)
		(min_thickness 0.25)
		(keepout
			(tracks allowed)
			(vias allowed)
			(pads allowed)
			(copperpour allowed)
			(footprints allowed)
		)
		(placement
			(enabled no)
			(sheetname "")
		)
		(fill
			(thermal_gap 0.5)
			(thermal_bridge_width 0.5)
			(island_removal_mode 0)
		)
		(polygon
			(pts
				(xy 69.109082 -29.354526) (xy 69.109082 -28.003246) (xy 70.389242 -28.003246) (xy 70.389242 -29.354526)
			)
		)
	)
	(zone
		(layer "F.Cu")
		(hatch none 0.5)
		(connect_pads
			(clearance 0)
		)
		(min_thickness 0.25)
		(keepout
			(tracks allowed)
			(vias allowed)
			(pads allowed)
			(copperpour allowed)
			(footprints allowed)
		)
		(placement
			(enabled no)
			(sheetname "")
		)
		(fill
			(thermal_gap 0.5)
			(thermal_bridge_width 0.5)
			(island_removal_mode 0)
		)
		(polygon
			(pts
				(xy 26.654252 -350.80575) (xy 25.302972 -350.80575) (xy 25.302972 -349.52559) (xy 26.654252 -349.52559)
			)
		)
	)
	(zone
		(layer "F.Cu")
		(hatch none 0.5)
		(connect_pads
			(clearance 0)
		)
		(min_thickness 0.25)
		(keepout
			(tracks allowed)
			(vias allowed)
			(pads allowed)
			(copperpour allowed)
			(footprints allowed)
		)
		(placement
			(enabled no)
			(sheetname "")
		)
		(fill
			(thermal_gap 0.5)
			(thermal_bridge_width 0.5)
			(island_removal_mode 0)
		)
		(polygon
			(pts
				(xy 427.636178 -131.00939) (xy 427.636178 -129.65811) (xy 428.916338 -129.65811) (xy 428.916338 -131.00939)
			)
		)
	)
	(zone
		(layer "F.Cu")
		(hatch none 0.5)
		(connect_pads
			(clearance 0)
		)
		(min_thickness 0.25)
		(keepout
			(tracks allowed)
			(vias allowed)
			(pads allowed)
			(copperpour allowed)
			(footprints allowed)
		)
		(placement
			(enabled no)
			(sheetname "")
		)
		(fill
			(thermal_gap 0.5)
			(thermal_bridge_width 0.5)
			(island_removal_mode 0)
		)
		(polygon
			(pts
				(xy 68.694046 -350.80575) (xy 67.342766 -350.80575) (xy 67.342766 -349.52559) (xy 68.694046 -349.52559)
			)
		)
	)
	(zone
		(layer "F.Cu")
		(hatch none 0.5)
		(connect_pads
			(clearance 0)
		)
		(min_thickness 0.25)
		(keepout
			(tracks allowed)
			(vias allowed)
			(pads allowed)
			(copperpour allowed)
			(footprints allowed)
		)
		(placement
			(enabled no)
			(sheetname "")
		)
		(fill
			(thermal_gap 0.5)
			(thermal_bridge_width 0.5)
			(island_removal_mode 0)
		)
		(polygon
			(pts
				(xy 116.29136 -284.544262) (xy 116.768118 -284.544262) (xy 117.029484 -284.805628) (xy 117.14607 -284.805628)
				(xy 117.35435 -284.597348) (xy 117.35435 -282.759404) (xy 116.956586 -282.36164) (xy 116.380768 -282.36164)
				(xy 116.22913 -282.513278) (xy 116.22913 -284.482032)
			)
		)
	)
	(zone
		(layer "F.Cu")
		(hatch none 0.5)
		(connect_pads
			(clearance 0)
		)
		(min_thickness 0.25)
		(keepout
			(tracks allowed)
			(vias allowed)
			(pads allowed)
			(copperpour allowed)
			(footprints not_allowed)
		)
		(placement
			(enabled no)
			(sheetname "")
		)
		(fill
			(thermal_gap 0.5)
			(thermal_bridge_width 0.5)
			(island_removal_mode 0)
		)
		(polygon
			(pts
				(arc
					(start 357.89997 -194.360038)
					(mid 349.899986 -202.360022)
					(end 341.900002 -194.360038)
				)
				(arc
					(start 341.900002 -194.360038)
					(mid 349.899986 -186.360054)
					(end 357.89997 -194.360038)
				)
			)
		)
	)
	(zone
		(layer "F.Cu")
		(hatch none 0.5)
		(connect_pads
			(clearance 0)
		)
		(min_thickness 0.25)
		(keepout
			(tracks not_allowed)
			(vias allowed)
			(pads allowed)
			(copperpour not_allowed)
			(footprints allowed)
		)
		(placement
			(enabled no)
			(sheetname "")
		)
		(fill
			(thermal_gap 0.5)
			(thermal_bridge_width 0.5)
			(island_removal_mode 0)
		)
		(polygon
			(pts
				(arc
					(start 231.799892 -194.360038)
					(mid 233.799888 -192.360042)
					(end 235.799884 -194.360038)
				)
				(arc
					(start 235.799884 -194.360038)
					(mid 233.799888 -196.360034)
					(end 231.799892 -194.360038)
				)
			)
		)
	)
	(zone
		(layer "F.Cu")
		(hatch none 0.5)
		(connect_pads
			(clearance 0)
		)
		(min_thickness 0.25)
		(keepout
			(tracks allowed)
			(vias allowed)
			(pads allowed)
			(copperpour allowed)
			(footprints allowed)
		)
		(placement
			(enabled no)
			(sheetname "")
		)
		(fill
			(thermal_gap 0.5)
			(thermal_bridge_width 0.5)
			(island_removal_mode 0)
		)
		(polygon
			(pts
				(xy 425.918376 -344.659458) (xy 424.567096 -344.659458) (xy 424.567096 -343.379298) (xy 425.918376 -343.379298)
			)
		)
	)
	(zone
		(layer "F.Cu")
		(hatch none 0.5)
		(connect_pads
			(clearance 0)
		)
		(min_thickness 0.25)
		(keepout
			(tracks allowed)
			(vias allowed)
			(pads allowed)
			(copperpour allowed)
			(footprints allowed)
		)
		(placement
			(enabled no)
			(sheetname "")
		)
		(fill
			(thermal_gap 0.5)
			(thermal_bridge_width 0.5)
			(island_removal_mode 0)
		)
		(polygon
			(pts
				(xy 173.451266 -54.831742) (xy 176.368964 -54.831742) (xy 176.578514 -54.622192) (xy 176.578514 -54.00929)
				(xy 173.521116 -54.00929) (xy 173.451266 -54.07914)
			)
		)
	)
	(zone
		(layer "F.Cu")
		(hatch none 0.5)
		(connect_pads
			(clearance 0)
		)
		(min_thickness 0.25)
		(keepout
			(tracks allowed)
			(vias allowed)
			(pads allowed)
			(copperpour allowed)
			(footprints allowed)
		)
		(placement
			(enabled no)
			(sheetname "")
		)
		(fill
			(thermal_gap 0.5)
			(thermal_bridge_width 0.5)
			(island_removal_mode 0)
		)
		(polygon
			(pts
				(xy 116.074952 -344.659458) (xy 114.723672 -344.659458) (xy 114.723672 -343.379298) (xy 116.074952 -343.379298)
			)
		)
	)
	(zone
		(layer "F.Cu")
		(hatch none 0.5)
		(connect_pads
			(clearance 0)
		)
		(min_thickness 0.25)
		(keepout
			(tracks allowed)
			(vias allowed)
			(pads allowed)
			(copperpour allowed)
			(footprints not_allowed)
		)
		(placement
			(enabled no)
			(sheetname "")
		)
		(fill
			(thermal_gap 0.5)
			(thermal_bridge_width 0.5)
			(island_removal_mode 0)
		)
		(polygon
			(pts
				(arc
					(start 460.099918 -313.85002)
					(mid 464.09991 -309.850028)
					(end 468.099902 -313.85002)
				)
				(arc
					(start 468.099902 -313.85002)
					(mid 464.09991 -317.850012)
					(end 460.099918 -313.85002)
				)
			)
		)
	)
	(zone
		(layer "F.Cu")
		(hatch none 0.5)
		(connect_pads
			(clearance 0)
		)
		(min_thickness 0.25)
		(keepout
			(tracks allowed)
			(vias allowed)
			(pads allowed)
			(copperpour allowed)
			(footprints allowed)
		)
		(placement
			(enabled no)
			(sheetname "")
		)
		(fill
			(thermal_gap 0.5)
			(thermal_bridge_width 0.5)
			(island_removal_mode 0)
		)
		(polygon
			(pts
				(xy 443.40907 -32.954468) (xy 443.40907 -31.603188) (xy 444.68923 -31.603188) (xy 444.68923 -32.954468)
			)
		)
	)
	(zone
		(layer "F.Cu")
		(hatch none 0.5)
		(connect_pads
			(clearance 0)
		)
		(min_thickness 0.25)
		(keepout
			(tracks allowed)
			(vias allowed)
			(pads allowed)
			(copperpour allowed)
			(footprints allowed)
		)
		(placement
			(enabled no)
			(sheetname "")
		)
		(fill
			(thermal_gap 0.5)
			(thermal_bridge_width 0.5)
			(island_removal_mode 0)
		)
		(polygon
			(pts
				(xy 111.101124 -159.726376) (xy 111.963454 -159.726376) (xy 112.302798 -159.387032) (xy 112.302798 -159.03829)
				(xy 111.139732 -159.03829) (xy 111.101124 -159.076898)
			)
		)
	)
	(zone
		(layer "F.Cu")
		(hatch none 0.5)
		(connect_pads
			(clearance 0)
		)
		(min_thickness 0.25)
		(keepout
			(tracks allowed)
			(vias allowed)
			(pads allowed)
			(copperpour allowed)
			(footprints allowed)
		)
		(placement
			(enabled no)
			(sheetname "")
		)
		(fill
			(thermal_gap 0.5)
			(thermal_bridge_width 0.5)
			(island_removal_mode 0)
		)
		(polygon
			(pts
				(xy 88.011 -22.606) (xy 88.011 -21.844) (xy 90.551 -21.844) (xy 90.551 -22.606)
			)
		)
	)
	(zone
		(layer "F.Cu")
		(hatch none 0.5)
		(connect_pads
			(clearance 0)
		)
		(min_thickness 0.25)
		(keepout
			(tracks allowed)
			(vias allowed)
			(pads allowed)
			(copperpour allowed)
			(footprints allowed)
		)
		(placement
			(enabled no)
			(sheetname "")
		)
		(fill
			(thermal_gap 0.5)
			(thermal_bridge_width 0.5)
			(island_removal_mode 0)
		)
		(polygon
			(pts
				(xy 3.069082 -265.691874) (xy 3.069082 -263.573514) (xy 4.722622 -263.573514) (xy 4.722622 -265.691874)
			)
		)
	)
	(zone
		(layer "F.Cu")
		(hatch none 0.5)
		(connect_pads
			(clearance 0)
		)
		(min_thickness 0.25)
		(keepout
			(tracks allowed)
			(vias allowed)
			(pads allowed)
			(copperpour allowed)
			(footprints not_allowed)
		)
		(placement
			(enabled no)
			(sheetname "")
		)
		(fill
			(thermal_gap 0.5)
			(thermal_bridge_width 0.5)
			(island_removal_mode 0)
		)
		(polygon
			(pts
				(arc
					(start 212.989922 -311.179972)
					(mid 216.989914 -307.17998)
					(end 220.989906 -311.179972)
				)
				(arc
					(start 220.989906 -311.179972)
					(mid 216.989914 -315.179964)
					(end 212.989922 -311.179972)
				)
			)
		)
	)
	(zone
		(layer "F.Cu")
		(hatch none 0.5)
		(connect_pads
			(clearance 0)
		)
		(min_thickness 0.25)
		(keepout
			(tracks allowed)
			(vias allowed)
			(pads allowed)
			(copperpour allowed)
			(footprints allowed)
		)
		(placement
			(enabled no)
			(sheetname "")
		)
		(fill
			(thermal_gap 0.5)
			(thermal_bridge_width 0.5)
			(island_removal_mode 0)
		)
		(polygon
			(pts
				(xy 169.507916 -356.928166) (xy 168.156636 -356.928166) (xy 168.156636 -355.648006) (xy 169.507916 -355.648006)
			)
		)
	)
	(zone
		(layer "F.Cu")
		(hatch none 0.5)
		(connect_pads
			(clearance 0)
		)
		(min_thickness 0.25)
		(keepout
			(tracks not_allowed)
			(vias allowed)
			(pads allowed)
			(copperpour not_allowed)
			(footprints allowed)
		)
		(placement
			(enabled no)
			(sheetname "")
		)
		(fill
			(thermal_gap 0.5)
			(thermal_bridge_width 0.5)
			(island_removal_mode 0)
		)
		(polygon
			(pts
				(arc
					(start 141.249908 -320.900044)
					(mid 145.750026 -316.399926)
					(end 150.24989 -320.900044)
				)
				(arc
					(start 150.24989 -320.900044)
					(mid 145.750026 -325.399908)
					(end 141.249908 -320.900044)
				)
			)
		)
	)
	(zone
		(layer "F.Cu")
		(hatch none 0.5)
		(connect_pads
			(clearance 0)
		)
		(min_thickness 0.25)
		(keepout
			(tracks allowed)
			(vias allowed)
			(pads allowed)
			(copperpour allowed)
			(footprints not_allowed)
		)
		(placement
			(enabled no)
			(sheetname "")
		)
		(fill
			(thermal_gap 0.5)
			(thermal_bridge_width 0.5)
			(island_removal_mode 0)
		)
		(polygon
			(pts
				(xy 368.920014 -18.150078) (xy 368.920014 -13.150088) (xy 364.720124 -13.150088) (xy 364.720124 -18.150078)
			)
		)
	)
	(zone
		(layer "F.Cu")
		(hatch none 0.5)
		(connect_pads
			(clearance 0)
		)
		(min_thickness 0.25)
		(keepout
			(tracks allowed)
			(vias allowed)
			(pads allowed)
			(copperpour allowed)
			(footprints allowed)
		)
		(placement
			(enabled no)
			(sheetname "")
		)
		(fill
			(thermal_gap 0.5)
			(thermal_bridge_width 0.5)
			(island_removal_mode 0)
		)
		(polygon
			(pts
				(xy 386.897372 -136.944608) (xy 386.897372 -135.593328) (xy 388.177532 -135.593328) (xy 388.177532 -136.944608)
			)
		)
	)
	(zone
		(layer "F.Cu")
		(hatch none 0.5)
		(connect_pads
			(clearance 0)
		)
		(min_thickness 0.25)
		(keepout
			(tracks allowed)
			(vias allowed)
			(pads allowed)
			(copperpour allowed)
			(footprints allowed)
		)
		(placement
			(enabled no)
			(sheetname "")
		)
		(fill
			(thermal_gap 0.5)
			(thermal_bridge_width 0.5)
			(island_removal_mode 0)
		)
		(polygon
			(pts
				(xy 332.159102 -47.3202) (xy 332.159102 -45.5676) (xy 333.937102 -45.5676) (xy 333.937102 -47.3202)
			)
		)
	)
	(zone
		(layer "F.Cu")
		(hatch none 0.5)
		(connect_pads
			(clearance 0)
		)
		(min_thickness 0.25)
		(keepout
			(tracks allowed)
			(vias allowed)
			(pads allowed)
			(copperpour allowed)
			(footprints allowed)
		)
		(placement
			(enabled no)
			(sheetname "")
		)
		(fill
			(thermal_gap 0.5)
			(thermal_bridge_width 0.5)
			(island_removal_mode 0)
		)
		(polygon
			(pts
				(xy 365.333788 -284.67558) (xy 366.24641 -284.67558) (xy 366.642396 -284.279594) (xy 366.642396 -282.410408)
				(xy 365.113824 -282.410408) (xy 365.05896 -282.465272) (xy 365.05896 -284.400752)
			)
		)
	)
	(zone
		(layer "F.Cu")
		(hatch none 0.5)
		(connect_pads
			(clearance 0)
		)
		(min_thickness 0.25)
		(keepout
			(tracks allowed)
			(vias allowed)
			(pads allowed)
			(copperpour allowed)
			(footprints allowed)
		)
		(placement
			(enabled no)
			(sheetname "")
		)
		(fill
			(thermal_gap 0.5)
			(thermal_bridge_width 0.5)
			(island_removal_mode 0)
		)
		(polygon
			(pts
				(xy 375.400824 -344.659458) (xy 374.049544 -344.659458) (xy 374.049544 -343.379298) (xy 375.400824 -343.379298)
			)
		)
	)
	(zone
		(layer "F.Cu")
		(hatch none 0.5)
		(connect_pads
			(clearance 0)
		)
		(min_thickness 0.25)
		(keepout
			(tracks allowed)
			(vias allowed)
			(pads allowed)
			(copperpour allowed)
			(footprints allowed)
		)
		(placement
			(enabled no)
			(sheetname "")
		)
		(fill
			(thermal_gap 0.5)
			(thermal_bridge_width 0.5)
			(island_removal_mode 0)
		)
		(polygon
			(pts
				(xy 446.051178 -34.76117) (xy 446.051178 -33.40989) (xy 447.331338 -33.40989) (xy 447.331338 -34.76117)
			)
		)
	)
	(zone
		(layer "F.Cu")
		(hatch none 0.5)
		(connect_pads
			(clearance 0)
		)
		(min_thickness 0.25)
		(keepout
			(tracks allowed)
			(vias allowed)
			(pads allowed)
			(copperpour allowed)
			(footprints allowed)
		)
		(placement
			(enabled no)
			(sheetname "")
		)
		(fill
			(thermal_gap 0.5)
			(thermal_bridge_width 0.5)
			(island_removal_mode 0)
		)
		(polygon
			(pts
				(xy 137.837672 -350.80575) (xy 136.486392 -350.80575) (xy 136.486392 -349.52559) (xy 137.837672 -349.52559)
			)
		)
	)
	(zone
		(layer "F.Cu")
		(hatch none 0.5)
		(connect_pads
			(clearance 0)
		)
		(min_thickness 0.25)
		(keepout
			(tracks not_allowed)
			(vias allowed)
			(pads allowed)
			(copperpour not_allowed)
			(footprints allowed)
		)
		(placement
			(enabled no)
			(sheetname "")
		)
		(fill
			(thermal_gap 0.5)
			(thermal_bridge_width 0.5)
			(island_removal_mode 0)
		)
		(polygon
			(pts
				(xy 455.06386 -249.232928) (xy 455.06386 -246.348504) (xy 455.255122 -246.348504) (xy 455.255122 -249.232928)
			)
		)
	)
	(zone
		(layer "F.Cu")
		(hatch none 0.5)
		(connect_pads
			(clearance 0)
		)
		(min_thickness 0.25)
		(keepout
			(tracks allowed)
			(vias allowed)
			(pads allowed)
			(copperpour allowed)
			(footprints allowed)
		)
		(placement
			(enabled no)
			(sheetname "")
		)
		(fill
			(thermal_gap 0.5)
			(thermal_bridge_width 0.5)
			(island_removal_mode 0)
		)
		(polygon
			(pts
				(xy 167.887142 -98.563176) (xy 166.07663 -98.563176) (xy 166.030148 -98.609658) (xy 166.030148 -113.35258)
				(xy 166.175436 -113.497868) (xy 167.927528 -113.497868) (xy 168.002966 -113.42243) (xy 168.002966 -98.679)
			)
		)
	)
	(zone
		(layer "F.Cu")
		(hatch none 0.5)
		(connect_pads
			(clearance 0)
		)
		(min_thickness 0.25)
		(keepout
			(tracks not_allowed)
			(vias allowed)
			(pads allowed)
			(copperpour not_allowed)
			(footprints allowed)
		)
		(placement
			(enabled no)
			(sheetname "")
		)
		(fill
			(thermal_gap 0.5)
			(thermal_bridge_width 0.5)
			(island_removal_mode 0)
		)
		(polygon
			(pts
				(arc
					(start 120.499886 -194.360038)
					(mid 117.700044 -197.15988)
					(end 114.899948 -194.360038)
				)
				(arc
					(start 114.899948 -194.360038)
					(mid 117.700044 -191.559942)
					(end 120.499886 -194.360038)
				)
			)
		)
	)
	(zone
		(layer "F.Cu")
		(hatch none 0.5)
		(connect_pads
			(clearance 0)
		)
		(min_thickness 0.25)
		(keepout
			(tracks allowed)
			(vias allowed)
			(pads allowed)
			(copperpour allowed)
			(footprints allowed)
		)
		(placement
			(enabled no)
			(sheetname "")
		)
		(fill
			(thermal_gap 0.5)
			(thermal_bridge_width 0.5)
			(island_removal_mode 0)
		)
		(polygon
			(pts
				(xy 154.697176 -107.618022) (xy 154.697176 -106.266742) (xy 155.977336 -106.266742) (xy 155.977336 -107.618022)
			)
		)
	)
	(zone
		(layer "F.Cu")
		(hatch none 0.5)
		(connect_pads
			(clearance 0)
		)
		(min_thickness 0.25)
		(keepout
			(tracks allowed)
			(vias allowed)
			(pads allowed)
			(copperpour allowed)
			(footprints allowed)
		)
		(placement
			(enabled no)
			(sheetname "")
		)
		(fill
			(thermal_gap 0.5)
			(thermal_bridge_width 0.5)
			(island_removal_mode 0)
		)
		(polygon
			(pts
				(xy 11.981942 -265.661394) (xy 11.981942 -263.512554) (xy 13.653262 -263.512554) (xy 13.653262 -265.661394)
			)
		)
	)
	(zone
		(layer "F.Cu")
		(hatch none 0.5)
		(connect_pads
			(clearance 0)
		)
		(min_thickness 0.25)
		(keepout
			(tracks allowed)
			(vias allowed)
			(pads allowed)
			(copperpour allowed)
			(footprints allowed)
		)
		(placement
			(enabled no)
			(sheetname "")
		)
		(fill
			(thermal_gap 0.5)
			(thermal_bridge_width 0.5)
			(island_removal_mode 0)
		)
		(polygon
			(pts
				(xy 439.166 -99.187) (xy 440.2582 -99.187) (xy 440.7154 -99.6442) (xy 441.2996 -99.6442) (xy 441.4266 -99.5172)
				(xy 441.4266 -98.806) (xy 441.0964 -98.4758) (xy 439.2168 -98.4758) (xy 439.1152 -98.5774) (xy 439.1152 -99.1362)
			)
		)
	)
	(zone
		(layer "F.Cu")
		(hatch none 0.5)
		(connect_pads
			(clearance 0)
		)
		(min_thickness 0.25)
		(keepout
			(tracks allowed)
			(vias allowed)
			(pads allowed)
			(copperpour allowed)
			(footprints allowed)
		)
		(placement
			(enabled no)
			(sheetname "")
		)
		(fill
			(thermal_gap 0.5)
			(thermal_bridge_width 0.5)
			(island_removal_mode 0)
		)
		(polygon
			(pts
				(xy 275.309076 -29.354526) (xy 275.309076 -28.003246) (xy 276.589236 -28.003246) (xy 276.589236 -29.354526)
			)
		)
	)
	(zone
		(layer "F.Cu")
		(hatch none 0.5)
		(connect_pads
			(clearance 0)
		)
		(min_thickness 0.25)
		(keepout
			(tracks allowed)
			(vias allowed)
			(pads allowed)
			(copperpour allowed)
			(footprints allowed)
		)
		(placement
			(enabled no)
			(sheetname "")
		)
		(fill
			(thermal_gap 0.5)
			(thermal_bridge_width 0.5)
			(island_removal_mode 0)
		)
		(polygon
			(pts
				(xy 238.192056 -81.79689) (xy 238.192056 -82.63382) (xy 238.192056 -83.124294) (xy 238.19231 -83.124548)
				(xy 239.64011 -83.124548) (xy 239.76076 -83.003898) (xy 239.76076 -82.694526) (xy 239.730534 -82.6643)
				(xy 239.730534 -81.81975) (xy 239.647476 -81.736692) (xy 238.252254 -81.736692)
			)
		)
	)
	(zone
		(layer "F.Cu")
		(hatch none 0.5)
		(connect_pads
			(clearance 0)
		)
		(min_thickness 0.25)
		(keepout
			(tracks allowed)
			(vias allowed)
			(pads allowed)
			(copperpour allowed)
			(footprints allowed)
		)
		(placement
			(enabled no)
			(sheetname "")
		)
		(fill
			(thermal_gap 0.5)
			(thermal_bridge_width 0.5)
			(island_removal_mode 0)
		)
		(polygon
			(pts
				(xy 272.861532 -27.55011) (xy 275.261578 -27.55011) (xy 275.353018 -27.45867) (xy 275.353018 -26.33853)
				(xy 275.292058 -26.27757) (xy 272.846292 -26.27757) (xy 272.724372 -26.39949) (xy 272.724372 -27.41295)
			)
		)
	)
	(zone
		(layer "F.Cu")
		(hatch none 0.5)
		(connect_pads
			(clearance 0)
		)
		(min_thickness 0.25)
		(keepout
			(tracks allowed)
			(vias allowed)
			(pads allowed)
			(copperpour allowed)
			(footprints allowed)
		)
		(placement
			(enabled no)
			(sheetname "")
		)
		(fill
			(thermal_gap 0.5)
			(thermal_bridge_width 0.5)
			(island_removal_mode 0)
		)
		(polygon
			(pts
				(xy 298.86148 -27.55011) (xy 301.261526 -27.55011) (xy 301.352966 -27.45867) (xy 301.352966 -26.33853)
				(xy 301.292006 -26.27757) (xy 298.84624 -26.27757) (xy 298.72432 -26.39949) (xy 298.72432 -27.41295)
			)
		)
	)
	(zone
		(layer "F.Cu")
		(hatch none 0.5)
		(connect_pads
			(clearance 0)
		)
		(min_thickness 0.25)
		(keepout
			(tracks allowed)
			(vias allowed)
			(pads allowed)
			(copperpour allowed)
			(footprints allowed)
		)
		(placement
			(enabled no)
			(sheetname "")
		)
		(fill
			(thermal_gap 0.5)
			(thermal_bridge_width 0.5)
			(island_removal_mode 0)
		)
		(polygon
			(pts
				(xy 333.353664 -89.032588) (xy 334.85074 -89.032588) (xy 335.163922 -88.719406) (xy 335.163922 -86.108286)
				(xy 335.140808 -86.085172) (xy 332.866238 -86.085172) (xy 332.784958 -86.166452) (xy 332.784958 -88.463882)
			)
		)
	)
	(zone
		(layer "F.Cu")
		(hatch none 0.5)
		(connect_pads
			(clearance 0)
		)
		(min_thickness 0.25)
		(keepout
			(tracks allowed)
			(vias allowed)
			(pads allowed)
			(copperpour allowed)
			(footprints allowed)
		)
		(placement
			(enabled no)
			(sheetname "")
		)
		(fill
			(thermal_gap 0.5)
			(thermal_bridge_width 0.5)
			(island_removal_mode 0)
		)
		(polygon
			(pts
				(xy 250.275344 -383.273808) (xy 250.963938 -383.273808) (xy 251.049536 -383.18821) (xy 251.049536 -382.775968)
				(xy 250.858528 -382.58496) (xy 250.230132 -382.58496) (xy 250.1646 -382.650492) (xy 250.1646 -383.163064)
			)
		)
	)
	(zone
		(layer "F.Cu")
		(hatch none 0.5)
		(connect_pads
			(clearance 0)
		)
		(min_thickness 0.25)
		(keepout
			(tracks allowed)
			(vias allowed)
			(pads allowed)
			(copperpour allowed)
			(footprints allowed)
		)
		(placement
			(enabled no)
			(sheetname "")
		)
		(fill
			(thermal_gap 0.5)
			(thermal_bridge_width 0.5)
			(island_removal_mode 0)
		)
		(polygon
			(pts
				(xy 277.245826 -139.281662) (xy 278.623522 -139.281662) (xy 278.981408 -138.923776) (xy 278.981408 -132.947664)
				(xy 278.981408 -129.875026) (xy 278.861774 -129.755392) (xy 277.03145 -129.755392) (xy 276.548088 -130.238754)
				(xy 276.548088 -133.30555) (xy 276.548088 -138.583924)
			)
		)
	)
	(zone
		(layer "F.Cu")
		(hatch none 0.5)
		(connect_pads
			(clearance 0)
		)
		(min_thickness 0.25)
		(keepout
			(tracks allowed)
			(vias allowed)
			(pads allowed)
			(copperpour allowed)
			(footprints allowed)
		)
		(placement
			(enabled no)
			(sheetname "")
		)
		(fill
			(thermal_gap 0.5)
			(thermal_bridge_width 0.5)
			(island_removal_mode 0)
		)
		(polygon
			(pts
				(xy 11.29665 -305.173126) (xy 11.985244 -305.173126) (xy 12.070842 -305.087528) (xy 12.070842 -304.675286)
				(xy 11.879834 -304.484278) (xy 11.251438 -304.484278) (xy 11.185906 -304.54981) (xy 11.185906 -305.062382)
			)
		)
	)
	(zone
		(layer "F.Cu")
		(hatch none 0.5)
		(connect_pads
			(clearance 0)
		)
		(min_thickness 0.25)
		(keepout
			(tracks allowed)
			(vias allowed)
			(pads allowed)
			(copperpour allowed)
			(footprints allowed)
		)
		(placement
			(enabled no)
			(sheetname "")
		)
		(fill
			(thermal_gap 0.5)
			(thermal_bridge_width 0.5)
			(island_removal_mode 0)
		)
		(polygon
			(pts
				(arc
					(start 379.514862 -240.671604)
					(mid 379.550783 -240.686483)
					(end 379.565662 -240.722404)
				)
				(arc
					(start 379.565662 -241.402108)
					(mid 379.550783 -241.438029)
					(end 379.514862 -241.452908)
				)
				(arc
					(start 378.23902 -241.452908)
					(mid 378.203099 -241.438029)
					(end 378.18822 -241.402108)
				)
				(arc
					(start 378.18822 -240.722404)
					(mid 378.203099 -240.686483)
					(end 378.23902 -240.671604)
				)
			)
		)
	)
	(zone
		(layer "F.Cu")
		(hatch none 0.5)
		(connect_pads
			(clearance 0)
		)
		(min_thickness 0.25)
		(keepout
			(tracks not_allowed)
			(vias allowed)
			(pads allowed)
			(copperpour not_allowed)
			(footprints allowed)
		)
		(placement
			(enabled no)
			(sheetname "")
		)
		(fill
			(thermal_gap 0.5)
			(thermal_bridge_width 0.5)
			(island_removal_mode 0)
		)
		(polygon
			(pts
				(arc
					(start 373.450104 -270.89989)
					(mid 377.950222 -266.399772)
					(end 382.450086 -270.89989)
				)
				(arc
					(start 382.450086 -270.89989)
					(mid 377.950222 -275.399754)
					(end 373.450104 -270.89989)
				)
			)
		)
	)
	(zone
		(layer "F.Cu")
		(hatch none 0.5)
		(connect_pads
			(clearance 0)
		)
		(min_thickness 0.25)
		(keepout
			(tracks allowed)
			(vias allowed)
			(pads allowed)
			(copperpour allowed)
			(footprints allowed)
		)
		(placement
			(enabled no)
			(sheetname "")
		)
		(fill
			(thermal_gap 0.5)
			(thermal_bridge_width 0.5)
			(island_removal_mode 0)
		)
		(polygon
			(pts
				(xy 268.155166 -131.538218) (xy 268.155166 -130.186938) (xy 269.435326 -130.186938) (xy 269.435326 -131.538218)
			)
		)
	)
	(zone
		(layer "F.Cu")
		(hatch none 0.5)
		(connect_pads
			(clearance 0)
		)
		(min_thickness 0.25)
		(keepout
			(tracks allowed)
			(vias allowed)
			(pads allowed)
			(copperpour allowed)
			(footprints allowed)
		)
		(placement
			(enabled no)
			(sheetname "")
		)
		(fill
			(thermal_gap 0.5)
			(thermal_bridge_width 0.5)
			(island_removal_mode 0)
		)
		(polygon
			(pts
				(xy 363.479842 -320.296032) (xy 363.479842 -321.947032) (xy 361.447842 -321.947032) (xy 361.447842 -320.296032)
			)
		)
	)
	(zone
		(layer "F.Cu")
		(hatch none 0.5)
		(connect_pads
			(clearance 0)
		)
		(min_thickness 0.25)
		(keepout
			(tracks allowed)
			(vias allowed)
			(pads allowed)
			(copperpour allowed)
			(footprints not_allowed)
		)
		(placement
			(enabled no)
			(sheetname "")
		)
		(fill
			(thermal_gap 0.5)
			(thermal_bridge_width 0.5)
			(island_removal_mode 0)
		)
		(polygon
			(pts
				(xy 452.53656 -312.609992)
				(arc
					(start 460.297022 -312.609992)
					(mid 460.514608 -312.076616)
					(end 460.806546 -311.580022)
				)
				(xy 452.53656 -311.580022)
			)
		)
	)
	(zone
		(layer "F.Cu")
		(hatch none 0.5)
		(connect_pads
			(clearance 0)
		)
		(min_thickness 0.25)
		(keepout
			(tracks allowed)
			(vias allowed)
			(pads allowed)
			(copperpour allowed)
			(footprints allowed)
		)
		(placement
			(enabled no)
			(sheetname "")
		)
		(fill
			(thermal_gap 0.5)
			(thermal_bridge_width 0.5)
			(island_removal_mode 0)
		)
		(polygon
			(pts
				(xy 243.59108 -279.784556) (xy 246.51208 -279.784556) (xy 246.76608 -279.530556) (xy 246.76608 -276.482556)
				(xy 246.38508 -276.101556) (xy 243.46408 -276.101556) (xy 242.95608 -276.609556) (xy 242.95608 -279.149556)
			)
		)
	)
	(zone
		(layer "F.Cu")
		(hatch none 0.5)
		(connect_pads
			(clearance 0)
		)
		(min_thickness 0.25)
		(keepout
			(tracks allowed)
			(vias allowed)
			(pads allowed)
			(copperpour allowed)
			(footprints allowed)
		)
		(placement
			(enabled no)
			(sheetname "")
		)
		(fill
			(thermal_gap 0.5)
			(thermal_bridge_width 0.5)
			(island_removal_mode 0)
		)
		(polygon
			(pts
				(xy 35.955224 -131.538218) (xy 35.955224 -130.186938) (xy 37.235384 -130.186938) (xy 37.235384 -131.538218)
			)
		)
	)
	(zone
		(layer "F.Cu")
		(hatch none 0.5)
		(connect_pads
			(clearance 0)
		)
		(min_thickness 0.25)
		(keepout
			(tracks allowed)
			(vias allowed)
			(pads allowed)
			(copperpour allowed)
			(footprints allowed)
		)
		(placement
			(enabled no)
			(sheetname "")
		)
		(fill
			(thermal_gap 0.5)
			(thermal_bridge_width 0.5)
			(island_removal_mode 0)
		)
		(polygon
			(pts
				(xy 6.495542 -265.671554) (xy 6.495542 -263.563354) (xy 8.128762 -263.563354) (xy 8.128762 -265.671554)
			)
		)
	)
	(zone
		(layer "F.Cu")
		(hatch none 0.5)
		(connect_pads
			(clearance 0)
		)
		(min_thickness 0.25)
		(keepout
			(tracks allowed)
			(vias allowed)
			(pads allowed)
			(copperpour allowed)
			(footprints not_allowed)
		)
		(placement
			(enabled no)
			(sheetname "")
		)
		(fill
			(thermal_gap 0.5)
			(thermal_bridge_width 0.5)
			(island_removal_mode 0)
		)
		(polygon
			(pts
				(xy 66.52006 -394.269976) (xy 53.069998 -394.269976) (xy 53.069998 -417.58997) (xy 66.52006 -417.58997)
			)
		)
	)
	(zone
		(layer "F.Cu")
		(hatch none 0.5)
		(connect_pads
			(clearance 0)
		)
		(min_thickness 0.25)
		(keepout
			(tracks not_allowed)
			(vias allowed)
			(pads allowed)
			(copperpour not_allowed)
			(footprints allowed)
		)
		(placement
			(enabled no)
			(sheetname "")
		)
		(fill
			(thermal_gap 0.5)
			(thermal_bridge_width 0.5)
			(island_removal_mode 0)
		)
		(polygon
			(pts
				(xy 252.819916 -18.150078) (xy 252.819916 -13.150088) (xy 248.620026 -13.150088) (xy 248.620026 -18.150078)
			)
		)
	)
	(zone
		(layer "F.Cu")
		(hatch none 0.5)
		(connect_pads
			(clearance 0)
		)
		(min_thickness 0.25)
		(keepout
			(tracks allowed)
			(vias allowed)
			(pads allowed)
			(copperpour allowed)
			(footprints not_allowed)
		)
		(placement
			(enabled no)
			(sheetname "")
		)
		(fill
			(thermal_gap 0.5)
			(thermal_bridge_width 0.5)
			(island_removal_mode 0)
		)
		(polygon
			(pts
				(arc
					(start 147.757134 -232.750106)
					(mid 135.798814 -243.750167)
					(end 123.840494 -232.750106)
				)
			)
		)
	)
	(zone
		(layer "F.Cu")
		(hatch none 0.5)
		(connect_pads
			(clearance 0)
		)
		(min_thickness 0.25)
		(keepout
			(tracks allowed)
			(vias allowed)
			(pads allowed)
			(copperpour allowed)
			(footprints allowed)
		)
		(placement
			(enabled no)
			(sheetname "")
		)
		(fill
			(thermal_gap 0.5)
			(thermal_bridge_width 0.5)
			(island_removal_mode 0)
		)
		(polygon
			(pts
				(xy 384.864864 -102.224586) (xy 384.864864 -100.873306) (xy 386.145024 -100.873306) (xy 386.145024 -102.224586)
			)
		)
	)
	(zone
		(layer "F.Cu")
		(hatch none 0.5)
		(connect_pads
			(clearance 0)
		)
		(min_thickness 0.25)
		(keepout
			(tracks not_allowed)
			(vias allowed)
			(pads allowed)
			(copperpour not_allowed)
			(footprints allowed)
		)
		(placement
			(enabled no)
			(sheetname "")
		)
		(fill
			(thermal_gap 0.5)
			(thermal_bridge_width 0.5)
			(island_removal_mode 0)
		)
		(polygon
			(pts
				(arc
					(start 6.800088 -395.500098)
					(mid 9.400032 -398.100042)
					(end 6.800088 -400.699986)
				)
				(arc
					(start 5.199888 -400.699986)
					(mid 2.599944 -398.100042)
					(end 5.199888 -395.500098)
				)
			)
		)
		(polygon
			(pts
				(arc
					(start 5.199888 -399.699988)
					(mid 3.599942 -398.100042)
					(end 5.199888 -396.500096)
				)
				(arc
					(start 6.800088 -396.500096)
					(mid 8.400034 -398.100042)
					(end 6.800088 -399.699988)
				)
			)
		)
	)
	(zone
		(layer "F.Cu")
		(hatch none 0.5)
		(connect_pads
			(clearance 0)
		)
		(min_thickness 0.25)
		(keepout
			(tracks not_allowed)
			(vias allowed)
			(pads allowed)
			(copperpour not_allowed)
			(footprints allowed)
		)
		(placement
			(enabled no)
			(sheetname "")
		)
		(fill
			(thermal_gap 0.5)
			(thermal_bridge_width 0.5)
			(island_removal_mode 0)
		)
		(polygon
			(pts
				(arc
					(start 203.499974 -270.89989)
					(mid 205.75016 -268.649704)
					(end 208.000092 -270.89989)
				)
				(arc
					(start 208.000092 -270.89989)
					(mid 205.75016 -273.149822)
					(end 203.499974 -270.89989)
				)
			)
		)
	)
	(zone
		(layer "F.Cu")
		(hatch none 0.5)
		(connect_pads
			(clearance 0)
		)
		(min_thickness 0.25)
		(keepout
			(tracks allowed)
			(vias allowed)
			(pads allowed)
			(copperpour allowed)
			(footprints allowed)
		)
		(placement
			(enabled no)
			(sheetname "")
		)
		(fill
			(thermal_gap 0.5)
			(thermal_bridge_width 0.5)
			(island_removal_mode 0)
		)
		(polygon
			(pts
				(xy 438.354216 -344.635582) (xy 437.002936 -344.635582) (xy 437.002936 -343.355422) (xy 438.354216 -343.355422)
			)
		)
	)
	(zone
		(layer "F.Cu")
		(hatch none 0.5)
		(connect_pads
			(clearance 0)
		)
		(min_thickness 0.25)
		(keepout
			(tracks allowed)
			(vias allowed)
			(pads allowed)
			(copperpour allowed)
			(footprints not_allowed)
		)
		(placement
			(enabled no)
			(sheetname "")
		)
		(fill
			(thermal_gap 0.5)
			(thermal_bridge_width 0.5)
			(island_removal_mode 0)
		)
		(polygon
			(pts
				(xy 19.150076 -260.439916) (xy 19.150076 -322.200016) (xy 0.999998 -322.200016) (xy 0.999998 -342.399874)
				(xy 25.649936 -342.399874) (xy 25.649936 -264.189972)
			)
		)
	)
	(zone
		(layer "F.Cu")
		(hatch none 0.5)
		(connect_pads
			(clearance 0)
		)
		(min_thickness 0.25)
		(keepout
			(tracks allowed)
			(vias allowed)
			(pads allowed)
			(copperpour allowed)
			(footprints allowed)
		)
		(placement
			(enabled no)
			(sheetname "")
		)
		(fill
			(thermal_gap 0.5)
			(thermal_bridge_width 0.5)
			(island_removal_mode 0)
		)
		(polygon
			(pts
				(xy 14.661642 -27.55011) (xy 17.061688 -27.55011) (xy 17.153128 -27.45867) (xy 17.153128 -26.33853)
				(xy 17.092168 -26.27757) (xy 14.646402 -26.27757) (xy 14.524482 -26.39949) (xy 14.524482 -27.41295)
			)
		)
	)
	(zone
		(layer "F.Cu")
		(hatch none 0.5)
		(connect_pads
			(clearance 0)
		)
		(min_thickness 0.25)
		(keepout
			(tracks allowed)
			(vias allowed)
			(pads allowed)
			(copperpour allowed)
			(footprints allowed)
		)
		(placement
			(enabled no)
			(sheetname "")
		)
		(fill
			(thermal_gap 0.5)
			(thermal_bridge_width 0.5)
			(island_removal_mode 0)
		)
		(polygon
			(pts
				(xy 356.784402 -54.008274) (xy 353.866704 -54.008274) (xy 353.657154 -54.217824) (xy 353.657154 -54.830726)
				(xy 356.714552 -54.830726) (xy 356.784402 -54.760876)
			)
		)
	)
	(zone
		(layer "F.Cu")
		(hatch none 0.5)
		(connect_pads
			(clearance 0)
		)
		(min_thickness 0.25)
		(keepout
			(tracks allowed)
			(vias allowed)
			(pads allowed)
			(copperpour allowed)
			(footprints allowed)
		)
		(placement
			(enabled no)
			(sheetname "")
		)
		(fill
			(thermal_gap 0.5)
			(thermal_bridge_width 0.5)
			(island_removal_mode 0)
		)
		(polygon
			(pts
				(xy 395.06017 -46.986444) (xy 396.052548 -46.986444) (xy 396.137384 -46.901608) (xy 396.137384 -46.211744)
				(xy 396.089378 -46.163738) (xy 395.040104 -46.163738) (xy 394.972286 -46.231556) (xy 394.972286 -46.89856)
			)
		)
	)
	(zone
		(layer "F.Cu")
		(hatch none 0.5)
		(connect_pads
			(clearance 0)
		)
		(min_thickness 0.25)
		(keepout
			(tracks allowed)
			(vias allowed)
			(pads allowed)
			(copperpour allowed)
			(footprints not_allowed)
		)
		(placement
			(enabled no)
			(sheetname "")
		)
		(fill
			(thermal_gap 0.5)
			(thermal_bridge_width 0.5)
			(island_removal_mode 0)
		)
		(polygon
			(pts
				(xy 0.999998 -40.120062) (xy 466.600032 -40.120062)
				(arc
					(start 466.600032 -1.999996)
					(mid 466.307139 -1.292891)
					(end 465.600034 -0.999998)
				)
				(arc
					(start 462.177384 -0.999998)
					(mid 463.48099 -3.350446)
					(end 463.932524 -5.999988)
				)
				(arc
					(start 463.932524 -5.999988)
					(mid 463.46922 -8.682935)
					(end 462.132934 -11.055096)
				)
				(arc
					(start 462.132934 -11.055096)
					(mid 463.618165 -11.960626)
					(end 464.199986 -13.599922)
				)
				(arc
					(start 464.199986 -15.200122)
					(mid 461.600042 -17.800066)
					(end 459.000098 -15.200122)
				)
				(arc
					(start 459.000098 -13.388594)
					(mid 451.490655 -12.653639)
					(end 447.932556 -5.999988)
				)
				(arc
					(start 447.932556 -5.999988)
					(mid 448.383959 -3.350456)
					(end 449.687442 -0.999998)
				)
				(arc
					(start 446.265046 -0.999998)
					(mid 445.557941 -1.292891)
					(end 445.265048 -1.999996)
				)
				(arc
					(start 445.265048 -11.850116)
					(mid 445.141191 -12.542999)
					(end 444.784988 -13.150088)
				)
				(xy 446.920112 -13.150088) (xy 446.920112 -18.150078) (xy 442.719968 -18.150078) (xy 442.719968 -13.850112)
				(arc
					(start 435.265068 -13.850112)
					(mid 433.850857 -13.264327)
					(end 433.265072 -11.850116)
				)
				(arc
					(start 433.265072 -1.999996)
					(mid 432.972179 -1.292891)
					(end 432.265074 -0.999998)
				)
				(arc
					(start 420.265098 -0.999998)
					(mid 419.557993 -1.292891)
					(end 419.2651 -1.999996)
				)
				(arc
					(start 419.2651 -11.850116)
					(mid 419.141137 -12.543032)
					(end 418.784786 -13.150088)
				)
				(xy 420.91991 -13.150088) (xy 420.91991 -18.150078) (xy 416.72002 -18.150078) (xy 416.72002 -13.850112)
				(arc
					(start 409.26512 -13.850112)
					(mid 407.850909 -13.264327)
					(end 407.265124 -11.850116)
				)
				(arc
					(start 407.265124 -9.87298)
					(mid 400.265077 -13.99998)
					(end 393.264898 -9.87298)
				)
				(arc
					(start 393.264898 -11.850116)
					(mid 393.141041 -12.542999)
					(end 392.784838 -13.150088)
				)
				(xy 394.919962 -13.150088) (xy 394.919962 -18.150078) (xy 390.720072 -18.150078) (xy 390.720072 -13.850112)
				(arc
					(start 383.264918 -13.850112)
					(mid 381.850707 -13.264327)
					(end 381.264922 -11.850116)
				)
				(arc
					(start 381.264922 -1.999996)
					(mid 380.972029 -1.292891)
					(end 380.264924 -0.999998)
				)
				(arc
					(start 368.264948 -0.999998)
					(mid 367.557843 -1.292891)
					(end 367.26495 -1.999996)
				)
				(arc
					(start 367.26495 -11.850116)
					(mid 367.141093 -12.542999)
					(end 366.78489 -13.150088)
				)
				(xy 368.920014 -13.150088) (xy 368.920014 -18.150078) (xy 364.720124 -18.150078) (xy 364.720124 -13.850112)
				(arc
					(start 357.26497 -13.850112)
					(mid 355.850759 -13.264327)
					(end 355.264974 -11.850116)
				)
				(arc
					(start 355.264974 -1.999996)
					(mid 354.972081 -1.292891)
					(end 354.264976 -0.999998)
				)
				(arc
					(start 330.164948 -0.999998)
					(mid 329.457843 -1.292891)
					(end 329.16495 -1.999996)
				)
				(arc
					(start 329.16495 -11.850116)
					(mid 329.041093 -12.542999)
					(end 328.68489 -13.150088)
				)
				(xy 330.820014 -13.150088) (xy 330.820014 -18.150078) (xy 326.620124 -18.150078) (xy 326.620124 -13.850112)
				(arc
					(start 319.16497 -13.850112)
					(mid 317.750759 -13.264327)
					(end 317.164974 -11.850116)
				)
				(arc
					(start 317.164974 -1.999996)
					(mid 316.872081 -1.292891)
					(end 316.164976 -0.999998)
				)
				(arc
					(start 304.165 -0.999998)
					(mid 303.457895 -1.292891)
					(end 303.165002 -1.999996)
				)
				(arc
					(start 303.165002 -11.850116)
					(mid 303.041145 -12.542999)
					(end 302.684942 -13.150088)
				)
				(xy 304.820066 -13.150088) (xy 304.820066 -18.150078) (xy 300.619922 -18.150078) (xy 300.619922 -13.850112)
				(arc
					(start 293.165022 -13.850112)
					(mid 291.750811 -13.264327)
					(end 291.165026 -11.850116)
				)
				(arc
					(start 291.165026 -9.87298)
					(mid 284.16504 -13.99998)
					(end 277.165054 -9.87298)
				)
				(arc
					(start 277.165054 -11.850116)
					(mid 277.041197 -12.542999)
					(end 276.684994 -13.150088)
				)
				(xy 278.820118 -13.150088) (xy 278.820118 -18.150078) (xy 274.619974 -18.150078) (xy 274.619974 -13.850112)
				(arc
					(start 267.165074 -13.850112)
					(mid 265.750863 -13.264327)
					(end 265.165078 -11.850116)
				)
				(arc
					(start 265.165078 -1.999996)
					(mid 264.872185 -1.292891)
					(end 264.16508 -0.999998)
				)
				(arc
					(start 252.165104 -0.999998)
					(mid 251.457999 -1.292891)
					(end 251.165106 -1.999996)
				)
				(arc
					(start 251.165106 -11.850116)
					(mid 251.041143 -12.543032)
					(end 250.684792 -13.150088)
				)
				(xy 252.819916 -13.150088) (xy 252.819916 -18.150078) (xy 248.620026 -18.150078) (xy 248.620026 -13.850112)
				(arc
					(start 241.165126 -13.850112)
					(mid 239.750915 -13.264327)
					(end 239.164876 -11.850116)
				)
				(arc
					(start 239.164876 -1.999996)
					(mid 238.871983 -1.292891)
					(end 238.164878 -0.999998)
				)
				(arc
					(start 232.359962 -0.999998)
					(mid 226.115197 -13.999862)
					(end 219.87002 -0.999998)
				)
				(arc
					(start 214.065104 -0.999998)
					(mid 213.357999 -1.292891)
					(end 213.065106 -1.999996)
				)
				(arc
					(start 213.065106 -11.850116)
					(mid 212.941143 -12.543032)
					(end 212.584792 -13.150088)
				)
				(xy 214.719916 -13.150088) (xy 214.719916 -18.150078) (xy 210.520026 -18.150078) (xy 210.520026 -13.850112)
				(arc
					(start 203.065126 -13.850112)
					(mid 201.650915 -13.264327)
					(end 201.064876 -11.850116)
				)
				(arc
					(start 201.064876 -1.999996)
					(mid 200.771983 -1.292891)
					(end 200.064878 -0.999998)
				)
				(arc
					(start 188.064902 -0.999998)
					(mid 187.357797 -1.292891)
					(end 187.064904 -1.999996)
				)
				(arc
					(start 187.064904 -11.850116)
					(mid 186.941047 -12.542999)
					(end 186.584844 -13.150088)
				)
				(xy 188.719968 -13.150088) (xy 188.719968 -18.150078) (xy 184.520078 -18.150078) (xy 184.520078 -13.850112)
				(arc
					(start 177.064924 -13.850112)
					(mid 175.650713 -13.264327)
					(end 175.064928 -11.850116)
				)
				(arc
					(start 175.064928 -9.87298)
					(mid 168.064942 -13.99998)
					(end 161.064956 -9.87298)
				)
				(arc
					(start 161.064956 -11.850116)
					(mid 160.941099 -12.542999)
					(end 160.584896 -13.150088)
				)
				(xy 162.72002 -13.150088) (xy 162.72002 -18.150078) (xy 158.519876 -18.150078) (xy 158.519876 -13.850112)
				(arc
					(start 151.064976 -13.850112)
					(mid 149.650765 -13.264327)
					(end 149.06498 -11.850116)
				)
				(arc
					(start 149.06498 -1.999996)
					(mid 148.772087 -1.292891)
					(end 148.064982 -0.999998)
				)
				(arc
					(start 136.065006 -0.999998)
					(mid 135.357901 -1.292891)
					(end 135.065008 -1.999996)
				)
				(arc
					(start 135.065008 -11.850116)
					(mid 134.941151 -12.542999)
					(end 134.584948 -13.150088)
				)
				(xy 136.720072 -13.150088) (xy 136.720072 -18.150078) (xy 132.519928 -18.150078) (xy 132.519928 -13.850112)
				(arc
					(start 125.065028 -13.850112)
					(mid 123.650817 -13.264327)
					(end 123.065032 -11.850116)
				)
				(arc
					(start 123.065032 -1.999996)
					(mid 122.772139 -1.292891)
					(end 122.065034 -0.999998)
				)
				(arc
					(start 97.965006 -0.999998)
					(mid 97.257901 -1.292891)
					(end 96.965008 -1.999996)
				)
				(arc
					(start 96.965008 -11.850116)
					(mid 96.841151 -12.542999)
					(end 96.484948 -13.150088)
				)
				(xy 98.620072 -13.150088) (xy 98.620072 -18.150078) (xy 94.419928 -18.150078) (xy 94.419928 -13.850112)
				(arc
					(start 86.965028 -13.850112)
					(mid 85.550817 -13.264327)
					(end 84.965032 -11.850116)
				)
				(arc
					(start 84.965032 -1.999996)
					(mid 84.672139 -1.292891)
					(end 83.965034 -0.999998)
				)
				(arc
					(start 71.965058 -0.999998)
					(mid 71.257953 -1.292891)
					(end 70.96506 -1.999996)
				)
				(arc
					(start 70.96506 -11.850116)
					(mid 70.841097 -12.543032)
					(end 70.484746 -13.150088)
				)
				(xy 72.620124 -13.150088) (xy 72.620124 -18.150078) (xy 68.41998 -18.150078) (xy 68.41998 -13.850112)
				(arc
					(start 60.96508 -13.850112)
					(mid 59.550869 -13.264327)
					(end 58.965084 -11.850116)
				)
				(arc
					(start 58.965084 -1.999996)
					(mid 58.672191 -1.292891)
					(end 57.965086 -0.999998)
				)
				(arc
					(start 45.96511 -0.999998)
					(mid 45.258005 -1.292891)
					(end 44.965112 -1.999996)
				)
				(arc
					(start 44.965112 -11.850116)
					(mid 44.841149 -12.543032)
					(end 44.484798 -13.150088)
				)
				(xy 46.619922 -13.150088) (xy 46.619922 -18.150078) (xy 42.420032 -18.150078) (xy 42.420032 -13.850112)
				(arc
					(start 34.964878 -13.850112)
					(mid 33.550667 -13.264327)
					(end 32.964882 -11.850116)
				)
				(arc
					(start 32.964882 -1.999996)
					(mid 32.671989 -1.292891)
					(end 31.964884 -0.999998)
				)
				(arc
					(start 19.964908 -0.999998)
					(mid 19.257803 -1.292891)
					(end 18.96491 -1.999996)
				)
				(arc
					(start 18.96491 -11.850116)
					(mid 18.841053 -12.542999)
					(end 18.48485 -13.150088)
				)
				(arc
					(start 19.602704 -13.150088)
					(mid 28.524362 -10.420523)
					(end 33.96488 -17.999964)
				)
				(arc
					(start 33.96488 -17.999964)
					(mid 33.964239 -18.109956)
					(end 33.962086 -18.219928)
				)
				(xy 35.520122 -18.219928) (xy 35.520122 -23.219918)
				(arc
					(start 32.027368 -23.219918)
					(mid 23.251404 -25.525816)
					(end 17.966436 -18.150078)
				)
				(xy 16.420084 -18.150078) (xy 16.420084 -13.850112)
				(arc
					(start 8.96493 -13.850112)
					(mid 7.550719 -13.264327)
					(end 6.964934 -11.850116)
				)
				(arc
					(start 6.964934 -1.999996)
					(mid 6.672041 -1.292891)
					(end 5.964936 -0.999998)
				)
				(arc
					(start 1.999996 -0.999998)
					(mid 1.292891 -1.292891)
					(end 0.999998 -1.999996)
				)
			)
		)
	)
	(zone
		(layer "F.Cu")
		(hatch none 0.5)
		(connect_pads
			(clearance 0)
		)
		(min_thickness 0.25)
		(keepout
			(tracks not_allowed)
			(vias allowed)
			(pads allowed)
			(copperpour not_allowed)
			(footprints allowed)
		)
		(placement
			(enabled no)
			(sheetname "")
		)
		(fill
			(thermal_gap 0.5)
			(thermal_bridge_width 0.5)
			(island_removal_mode 0)
		)
		(polygon
			(pts
				(arc
					(start 10.999978 -407.599896)
					(mid 5.999988 -412.599886)
					(end 0.999998 -407.599896)
				)
				(arc
					(start 0.999998 -407.599896)
					(mid 5.999988 -402.599906)
					(end 10.999978 -407.599896)
				)
			)
		)
	)
	(zone
		(layer "F.Cu")
		(hatch none 0.5)
		(connect_pads
			(clearance 0)
		)
		(min_thickness 0.25)
		(keepout
			(tracks allowed)
			(vias allowed)
			(pads allowed)
			(copperpour allowed)
			(footprints allowed)
		)
		(placement
			(enabled no)
			(sheetname "")
		)
		(fill
			(thermal_gap 0.5)
			(thermal_bridge_width 0.5)
			(island_removal_mode 0)
		)
		(polygon
			(pts
				(xy 138.53795 -19.7358) (xy 138.53795 -19.2024) (xy 139.60475 -19.2024) (xy 139.60475 -19.7358)
			)
		)
	)
	(zone
		(layer "F.Cu")
		(hatch none 0.5)
		(connect_pads
			(clearance 0)
		)
		(min_thickness 0.25)
		(keepout
			(tracks allowed)
			(vias allowed)
			(pads allowed)
			(copperpour allowed)
			(footprints allowed)
		)
		(placement
			(enabled no)
			(sheetname "")
		)
		(fill
			(thermal_gap 0.5)
			(thermal_bridge_width 0.5)
			(island_removal_mode 0)
		)
		(polygon
			(pts
				(xy 125.401832 -344.659458) (xy 124.050552 -344.659458) (xy 124.050552 -343.379298) (xy 125.401832 -343.379298)
			)
		)
	)
	(zone
		(layer "F.Cu")
		(hatch none 0.5)
		(connect_pads
			(clearance 0)
		)
		(min_thickness 0.25)
		(keepout
			(tracks allowed)
			(vias allowed)
			(pads allowed)
			(copperpour allowed)
			(footprints allowed)
		)
		(placement
			(enabled no)
			(sheetname "")
		)
		(fill
			(thermal_gap 0.5)
			(thermal_bridge_width 0.5)
			(island_removal_mode 0)
		)
		(polygon
			(pts
				(xy 177.564542 -35.488626) (xy 178.753262 -35.488626) (xy 179.058062 -35.183826) (xy 179.058062 -27.427936)
				(xy 178.997102 -27.366976) (xy 177.259996 -27.366976) (xy 177.138076 -27.488896) (xy 177.138076 -35.06216)
			)
		)
	)
	(zone
		(layer "F.Cu")
		(hatch none 0.5)
		(connect_pads
			(clearance 0)
		)
		(min_thickness 0.25)
		(keepout
			(tracks allowed)
			(vias allowed)
			(pads allowed)
			(copperpour allowed)
			(footprints allowed)
		)
		(placement
			(enabled no)
			(sheetname "")
		)
		(fill
			(thermal_gap 0.5)
			(thermal_bridge_width 0.5)
			(island_removal_mode 0)
		)
		(polygon
			(pts
				(xy 32.872172 -350.80575) (xy 31.520892 -350.80575) (xy 31.520892 -349.52559) (xy 32.872172 -349.52559)
			)
		)
	)
	(zone
		(layer "F.Cu")
		(hatch none 0.5)
		(connect_pads
			(clearance 0)
		)
		(min_thickness 0.25)
		(keepout
			(tracks allowed)
			(vias allowed)
			(pads allowed)
			(copperpour allowed)
			(footprints allowed)
		)
		(placement
			(enabled no)
			(sheetname "")
		)
		(fill
			(thermal_gap 0.5)
			(thermal_bridge_width 0.5)
			(island_removal_mode 0)
		)
		(polygon
			(pts
				(xy 134.384542 -148.266912) (xy 135.138414 -148.266912) (xy 135.146034 -148.274532) (xy 135.311896 -148.10867)
				(xy 135.311896 -147.03044) (xy 135.259064 -146.977608) (xy 134.105396 -146.977608) (xy 134.105396 -147.987766)
			)
		)
	)
	(zone
		(layer "F.Cu")
		(hatch none 0.5)
		(connect_pads
			(clearance 0)
		)
		(min_thickness 0.25)
		(keepout
			(tracks allowed)
			(vias allowed)
			(pads allowed)
			(copperpour allowed)
			(footprints allowed)
		)
		(placement
			(enabled no)
			(sheetname "")
		)
		(fill
			(thermal_gap 0.5)
			(thermal_bridge_width 0.5)
			(island_removal_mode 0)
		)
		(polygon
			(pts
				(xy 233.24566 -385.56946) (xy 233.24566 -382.20396) (xy 236.55274 -382.20396) (xy 236.55274 -385.56946)
			)
		)
	)
	(zone
		(layer "F.Cu")
		(hatch none 0.5)
		(connect_pads
			(clearance 0)
		)
		(min_thickness 0.25)
		(keepout
			(tracks allowed)
			(vias allowed)
			(pads allowed)
			(copperpour allowed)
			(footprints allowed)
		)
		(placement
			(enabled no)
			(sheetname "")
		)
		(fill
			(thermal_gap 0.5)
			(thermal_bridge_width 0.5)
			(island_removal_mode 0)
		)
		(polygon
			(pts
				(xy 365.409226 -32.954468) (xy 365.409226 -31.603188) (xy 366.689386 -31.603188) (xy 366.689386 -32.954468)
			)
		)
	)
	(zone
		(layer "F.Cu")
		(hatch none 0.5)
		(connect_pads
			(clearance 0)
		)
		(min_thickness 0.25)
		(keepout
			(tracks not_allowed)
			(vias allowed)
			(pads allowed)
			(copperpour not_allowed)
			(footprints allowed)
		)
		(placement
			(enabled no)
			(sheetname "")
		)
		(fill
			(thermal_gap 0.5)
			(thermal_bridge_width 0.5)
			(island_removal_mode 0)
		)
		(polygon
			(pts
				(xy 162.72002 -18.150078) (xy 162.72002 -13.150088) (xy 158.519876 -13.150088) (xy 158.519876 -18.150078)
			)
		)
	)
	(zone
		(layer "F.Cu")
		(hatch none 0.5)
		(connect_pads
			(clearance 0)
		)
		(min_thickness 0.25)
		(keepout
			(tracks allowed)
			(vias allowed)
			(pads allowed)
			(copperpour allowed)
			(footprints allowed)
		)
		(placement
			(enabled no)
			(sheetname "")
		)
		(fill
			(thermal_gap 0.5)
			(thermal_bridge_width 0.5)
			(island_removal_mode 0)
		)
		(polygon
			(pts
				(xy 123.564904 -312.599578) (xy 125.215904 -312.599578) (xy 125.215904 -314.631578) (xy 123.564904 -314.631578)
			)
		)
	)
	(zone
		(layer "F.Cu")
		(hatch none 0.5)
		(connect_pads
			(clearance 0)
		)
		(min_thickness 0.25)
		(keepout
			(tracks allowed)
			(vias allowed)
			(pads allowed)
			(copperpour allowed)
			(footprints not_allowed)
		)
		(placement
			(enabled no)
			(sheetname "")
		)
		(fill
			(thermal_gap 0.5)
			(thermal_bridge_width 0.5)
			(island_removal_mode 0)
		)
		(polygon
			(pts
				(xy 147.420076 -23.219918) (xy 151.619966 -23.219918) (xy 151.619966 -18.219928) (xy 147.420076 -18.219928)
			)
		)
	)
	(zone
		(layer "F.Cu")
		(hatch none 0.5)
		(connect_pads
			(clearance 0)
		)
		(min_thickness 0.25)
		(keepout
			(tracks allowed)
			(vias allowed)
			(pads allowed)
			(copperpour allowed)
			(footprints allowed)
		)
		(placement
			(enabled no)
			(sheetname "")
		)
		(fill
			(thermal_gap 0.5)
			(thermal_bridge_width 0.5)
			(island_removal_mode 0)
		)
		(polygon
			(pts
				(xy 208.761584 -27.55011) (xy 211.16163 -27.55011) (xy 211.25307 -27.45867) (xy 211.25307 -26.33853)
				(xy 211.19211 -26.27757) (xy 208.746344 -26.27757) (xy 208.624424 -26.39949) (xy 208.624424 -27.41295)
			)
		)
	)
	(zone
		(layer "F.Cu")
		(hatch none 0.5)
		(connect_pads
			(clearance 0)
		)
		(min_thickness 0.25)
		(keepout
			(tracks not_allowed)
			(vias allowed)
			(pads allowed)
			(copperpour not_allowed)
			(footprints allowed)
		)
		(placement
			(enabled no)
			(sheetname "")
		)
		(fill
			(thermal_gap 0.5)
			(thermal_bridge_width 0.5)
			(island_removal_mode 0)
		)
		(polygon
			(pts
				(xy 46.619922 -18.150078) (xy 46.619922 -13.150088) (xy 42.420032 -13.150088) (xy 42.420032 -18.150078)
			)
		)
	)
	(zone
		(layer "F.Cu")
		(hatch none 0.5)
		(connect_pads
			(clearance 0)
		)
		(min_thickness 0.25)
		(keepout
			(tracks allowed)
			(vias allowed)
			(pads allowed)
			(copperpour allowed)
			(footprints allowed)
		)
		(placement
			(enabled no)
			(sheetname "")
		)
		(fill
			(thermal_gap 0.5)
			(thermal_bridge_width 0.5)
			(island_removal_mode 0)
		)
		(polygon
			(pts
				(xy 314.178188 -156.326078) (xy 314.178188 -154.974798) (xy 315.458348 -154.974798) (xy 315.458348 -156.326078)
			)
		)
	)
	(zone
		(layer "F.Cu")
		(hatch none 0.5)
		(connect_pads
			(clearance 0)
		)
		(min_thickness 0.25)
		(keepout
			(tracks allowed)
			(vias allowed)
			(pads allowed)
			(copperpour allowed)
			(footprints allowed)
		)
		(placement
			(enabled no)
			(sheetname "")
		)
		(fill
			(thermal_gap 0.5)
			(thermal_bridge_width 0.5)
			(island_removal_mode 0)
		)
		(polygon
			(pts
				(xy 152.055068 -105.824782) (xy 152.055068 -104.473502) (xy 153.335228 -104.473502) (xy 153.335228 -105.824782)
			)
		)
	)
	(zone
		(layer "F.Cu")
		(hatch none 0.5)
		(connect_pads
			(clearance 0)
		)
		(min_thickness 0.25)
		(keepout
			(tracks allowed)
			(vias allowed)
			(pads allowed)
			(copperpour allowed)
			(footprints allowed)
		)
		(placement
			(enabled no)
			(sheetname "")
		)
		(fill
			(thermal_gap 0.5)
			(thermal_bridge_width 0.5)
			(island_removal_mode 0)
		)
		(polygon
			(pts
				(xy 228.617526 -370.671344) (xy 228.617526 -367.321084) (xy 231.932226 -367.321084) (xy 231.932226 -370.671344)
			)
		)
	)
	(zone
		(layer "F.Cu")
		(hatch none 0.5)
		(connect_pads
			(clearance 0)
		)
		(min_thickness 0.25)
		(keepout
			(tracks allowed)
			(vias allowed)
			(pads allowed)
			(copperpour allowed)
			(footprints allowed)
		)
		(placement
			(enabled no)
			(sheetname "")
		)
		(fill
			(thermal_gap 0.5)
			(thermal_bridge_width 0.5)
			(island_removal_mode 0)
		)
		(polygon
			(pts
				(xy 300.065186 -344.635582) (xy 298.713906 -344.635582) (xy 298.713906 -343.355422) (xy 300.065186 -343.355422)
			)
		)
	)
	(zone
		(layer "F.Cu")
		(hatch none 0.5)
		(connect_pads
			(clearance 0)
		)
		(min_thickness 0.25)
		(keepout
			(tracks allowed)
			(vias allowed)
			(pads allowed)
			(copperpour allowed)
			(footprints allowed)
		)
		(placement
			(enabled no)
			(sheetname "")
		)
		(fill
			(thermal_gap 0.5)
			(thermal_bridge_width 0.5)
			(island_removal_mode 0)
		)
		(polygon
			(pts
				(xy 381.618744 -350.80575) (xy 380.267464 -350.80575) (xy 380.267464 -349.52559) (xy 381.618744 -349.52559)
			)
		)
	)
	(zone
		(layer "F.Cu")
		(hatch none 0.5)
		(connect_pads
			(clearance 0)
		)
		(min_thickness 0.25)
		(keepout
			(tracks allowed)
			(vias allowed)
			(pads allowed)
			(copperpour allowed)
			(footprints allowed)
		)
		(placement
			(enabled no)
			(sheetname "")
		)
		(fill
			(thermal_gap 0.5)
			(thermal_bridge_width 0.5)
			(island_removal_mode 0)
		)
		(polygon
			(pts
				(xy 239.94364 -267.968476) (xy 239.94364 -265.819636) (xy 241.57686 -265.819636) (xy 241.57686 -267.968476)
			)
		)
	)
	(zone
		(layer "F.Cu")
		(hatch none 0.5)
		(connect_pads
			(clearance 0)
		)
		(min_thickness 0.25)
		(keepout
			(tracks not_allowed)
			(vias allowed)
			(pads allowed)
			(copperpour not_allowed)
			(footprints allowed)
		)
		(placement
			(enabled no)
			(sheetname "")
		)
		(fill
			(thermal_gap 0.5)
			(thermal_bridge_width 0.5)
			(island_removal_mode 0)
		)
		(polygon
			(pts
				(arc
					(start 446.79997 -84.70011)
					(mid 448.799966 -82.700114)
					(end 450.799962 -84.70011)
				)
				(arc
					(start 450.799962 -84.70011)
					(mid 448.799966 -86.700106)
					(end 446.79997 -84.70011)
				)
			)
		)
	)
	(zone
		(layer "F.Cu")
		(hatch none 0.5)
		(connect_pads
			(clearance 0)
		)
		(min_thickness 0.25)
		(keepout
			(tracks allowed)
			(vias allowed)
			(pads allowed)
			(copperpour allowed)
			(footprints allowed)
		)
		(placement
			(enabled no)
			(sheetname "")
		)
		(fill
			(thermal_gap 0.5)
			(thermal_bridge_width 0.5)
			(island_removal_mode 0)
		)
		(polygon
			(pts
				(xy 400.272504 -344.635582) (xy 398.921224 -344.635582) (xy 398.921224 -343.355422) (xy 400.272504 -343.355422)
			)
		)
	)
	(zone
		(layer "F.Cu")
		(hatch none 0.5)
		(connect_pads
			(clearance 0)
		)
		(min_thickness 0.25)
		(keepout
			(tracks allowed)
			(vias allowed)
			(pads allowed)
			(copperpour allowed)
			(footprints allowed)
		)
		(placement
			(enabled no)
			(sheetname "")
		)
		(fill
			(thermal_gap 0.5)
			(thermal_bridge_width 0.5)
			(island_removal_mode 0)
		)
		(polygon
			(pts
				(xy 329.95108 -31.160974) (xy 329.95108 -29.809694) (xy 331.23124 -29.809694) (xy 331.23124 -31.160974)
			)
		)
	)
	(zone
		(layer "F.Cu")
		(hatch none 0.5)
		(connect_pads
			(clearance 0)
		)
		(min_thickness 0.25)
		(keepout
			(tracks allowed)
			(vias allowed)
			(pads allowed)
			(copperpour allowed)
			(footprints not_allowed)
		)
		(placement
			(enabled no)
			(sheetname "")
		)
		(fill
			(thermal_gap 0.5)
			(thermal_bridge_width 0.5)
			(island_removal_mode 0)
		)
		(polygon
			(pts
				(arc
					(start 10.80008 -84.70011)
					(mid 18.800064 -76.700126)
					(end 26.800048 -84.70011)
				)
				(arc
					(start 26.800048 -84.70011)
					(mid 18.800064 -92.700094)
					(end 10.80008 -84.70011)
				)
			)
		)
	)
	(zone
		(layer "F.Cu")
		(hatch none 0.5)
		(connect_pads
			(clearance 0)
		)
		(min_thickness 0.25)
		(keepout
			(tracks allowed)
			(vias allowed)
			(pads allowed)
			(copperpour allowed)
			(footprints not_allowed)
		)
		(placement
			(enabled no)
			(sheetname "")
		)
		(fill
			(thermal_gap 0.5)
			(thermal_bridge_width 0.5)
			(island_removal_mode 0)
		)
		(polygon
			(pts
				(xy 83.319874 -23.219918) (xy 87.520018 -23.219918) (xy 87.520018 -18.219928) (xy 83.319874 -18.219928)
			)
		)
	)
	(zone
		(layer "F.Cu")
		(hatch none 0.5)
		(connect_pads
			(clearance 0)
		)
		(min_thickness 0.25)
		(keepout
			(tracks allowed)
			(vias allowed)
			(pads allowed)
			(copperpour allowed)
			(footprints not_allowed)
		)
		(placement
			(enabled no)
			(sheetname "")
		)
		(fill
			(thermal_gap 0.5)
			(thermal_bridge_width 0.5)
			(island_removal_mode 0)
		)
		(polygon
			(pts
				(xy 287.047432 -165.34511) (xy 287.047432 -90.054938) (xy 272.01241 -90.054938) (xy 272.01241 -165.34511)
			)
		)
	)
	(zone
		(layer "F.Cu")
		(hatch none 0.5)
		(connect_pads
			(clearance 0)
		)
		(min_thickness 0.25)
		(keepout
			(tracks allowed)
			(vias allowed)
			(pads allowed)
			(copperpour allowed)
			(footprints not_allowed)
		)
		(placement
			(enabled no)
			(sheetname "")
		)
		(fill
			(thermal_gap 0.5)
			(thermal_bridge_width 0.5)
			(island_removal_mode 0)
		)
		(polygon
			(pts
				(arc
					(start 96.009968 -407.599896)
					(mid 104.009952 -399.599912)
					(end 112.009936 -407.599896)
				)
				(arc
					(start 112.009936 -407.599896)
					(mid 104.009952 -415.59988)
					(end 96.009968 -407.599896)
				)
			)
		)
	)
	(zone
		(layer "F.Cu")
		(hatch none 0.5)
		(connect_pads
			(clearance 0)
		)
		(min_thickness 0.25)
		(keepout
			(tracks allowed)
			(vias allowed)
			(pads allowed)
			(copperpour allowed)
			(footprints allowed)
		)
		(placement
			(enabled no)
			(sheetname "")
		)
		(fill
			(thermal_gap 0.5)
			(thermal_bridge_width 0.5)
			(island_removal_mode 0)
		)
		(polygon
			(pts
				(xy 320.167 -22.733) (xy 320.167 -21.971) (xy 322.834 -21.971) (xy 322.834 -22.733)
			)
		)
	)
	(zone
		(layer "F.Cu")
		(hatch none 0.5)
		(connect_pads
			(clearance 0)
		)
		(min_thickness 0.25)
		(keepout
			(tracks allowed)
			(vias allowed)
			(pads allowed)
			(copperpour allowed)
			(footprints allowed)
		)
		(placement
			(enabled no)
			(sheetname "")
		)
		(fill
			(thermal_gap 0.5)
			(thermal_bridge_width 0.5)
			(island_removal_mode 0)
		)
		(polygon
			(pts
				(xy 304.701448 -115.203224) (xy 306.171346 -115.203224) (xy 306.255166 -115.119404) (xy 306.255166 -114.394996)
				(xy 306.018946 -114.158776) (xy 304.732944 -114.158776) (xy 304.512472 -114.379248) (xy 304.512472 -115.014248)
			)
		)
	)
	(zone
		(layer "F.Cu")
		(hatch none 0.5)
		(connect_pads
			(clearance 0)
		)
		(min_thickness 0.25)
		(keepout
			(tracks allowed)
			(vias allowed)
			(pads allowed)
			(copperpour allowed)
			(footprints not_allowed)
		)
		(placement
			(enabled no)
			(sheetname "")
		)
		(fill
			(thermal_gap 0.5)
			(thermal_bridge_width 0.5)
			(island_removal_mode 0)
		)
		(polygon
			(pts
				(xy 151.619966 -23.219918) (xy 151.619966 -18.219928) (xy 147.420076 -18.219928) (xy 147.420076 -23.219918)
			)
		)
	)
	(zone
		(layer "F.Cu")
		(hatch none 0.5)
		(connect_pads
			(clearance 0)
		)
		(min_thickness 0.25)
		(keepout
			(tracks allowed)
			(vias allowed)
			(pads allowed)
			(copperpour allowed)
			(footprints allowed)
		)
		(placement
			(enabled no)
			(sheetname "")
		)
		(fill
			(thermal_gap 0.5)
			(thermal_bridge_width 0.5)
			(island_removal_mode 0)
		)
		(polygon
			(pts
				(xy 352.110294 -287.02) (xy 357.063294 -287.02) (xy 357.317294 -286.766) (xy 357.317294 -286.004)
				(xy 357.063294 -285.75) (xy 355.920294 -285.75) (xy 355.666294 -285.496) (xy 355.666294 -284.861)
				(xy 355.920294 -284.607) (xy 356.428294 -284.607) (xy 356.555294 -284.48) (xy 356.555294 -282.829)
				(xy 356.301294 -282.575) (xy 352.364294 -282.575) (xy 352.110294 -282.829)
			)
		)
	)
	(zone
		(layer "F.Cu")
		(hatch none 0.5)
		(connect_pads
			(clearance 0)
		)
		(min_thickness 0.25)
		(keepout
			(tracks allowed)
			(vias allowed)
			(pads allowed)
			(copperpour allowed)
			(footprints allowed)
		)
		(placement
			(enabled no)
			(sheetname "")
		)
		(fill
			(thermal_gap 0.5)
			(thermal_bridge_width 0.5)
			(island_removal_mode 0)
		)
		(polygon
			(pts
				(xy 104.85882 -381.286004) (xy 105.69575 -381.286004) (xy 106.186224 -381.286004) (xy 106.186478 -381.28575)
				(xy 106.186478 -379.83795) (xy 106.065828 -379.7173) (xy 105.756456 -379.7173) (xy 105.72623 -379.747526)
				(xy 104.88168 -379.747526) (xy 104.798622 -379.830584) (xy 104.798622 -381.225806)
			)
		)
	)
	(zone
		(layer "F.Cu")
		(hatch none 0.5)
		(connect_pads
			(clearance 0)
		)
		(min_thickness 0.25)
		(keepout
			(tracks allowed)
			(vias allowed)
			(pads allowed)
			(copperpour allowed)
			(footprints allowed)
		)
		(placement
			(enabled no)
			(sheetname "")
		)
		(fill
			(thermal_gap 0.5)
			(thermal_bridge_width 0.5)
			(island_removal_mode 0)
		)
		(polygon
			(pts
				(xy 38.597332 -100.418138) (xy 38.597332 -99.066858) (xy 39.877492 -99.066858) (xy 39.877492 -100.418138)
			)
		)
	)
	(zone
		(layer "F.Cu")
		(hatch none 0.5)
		(connect_pads
			(clearance 0)
		)
		(min_thickness 0.25)
		(keepout
			(tracks allowed)
			(vias allowed)
			(pads allowed)
			(copperpour allowed)
			(footprints not_allowed)
		)
		(placement
			(enabled no)
			(sheetname "")
		)
		(fill
			(thermal_gap 0.5)
			(thermal_bridge_width 0.5)
			(island_removal_mode 0)
		)
		(polygon
			(pts
				(arc
					(start 364.450122 -276.010116)
					(mid 368.450114 -272.010124)
					(end 372.450106 -276.010116)
				)
				(arc
					(start 372.450106 -276.010116)
					(mid 368.450114 -280.010108)
					(end 364.450122 -276.010116)
				)
			)
		)
	)
	(zone
		(layer "F.Cu")
		(hatch none 0.5)
		(connect_pads
			(clearance 0)
		)
		(min_thickness 0.25)
		(keepout
			(tracks allowed)
			(vias allowed)
			(pads allowed)
			(copperpour allowed)
			(footprints allowed)
		)
		(placement
			(enabled no)
			(sheetname "")
		)
		(fill
			(thermal_gap 0.5)
			(thermal_bridge_width 0.5)
			(island_removal_mode 0)
		)
		(polygon
			(pts
				(xy 35.814 -22.606) (xy 35.814 -21.717) (xy 38.608 -21.717) (xy 38.608 -22.606)
			)
		)
	)
	(zone
		(layer "F.Cu")
		(hatch none 0.5)
		(connect_pads
			(clearance 0)
		)
		(min_thickness 0.25)
		(keepout
			(tracks allowed)
			(vias allowed)
			(pads allowed)
			(copperpour allowed)
			(footprints not_allowed)
		)
		(placement
			(enabled no)
			(sheetname "")
		)
		(fill
			(thermal_gap 0.5)
			(thermal_bridge_width 0.5)
			(island_removal_mode 0)
		)
		(polygon
			(pts
				(arc
					(start 350.214946 -17.999964)
					(mid 342.214962 -25.999948)
					(end 334.214978 -17.999964)
				)
				(arc
					(start 334.214978 -17.999964)
					(mid 342.214962 -9.99998)
					(end 350.214946 -17.999964)
				)
			)
		)
	)
	(zone
		(layer "F.Cu")
		(hatch none 0.5)
		(connect_pads
			(clearance 0)
		)
		(min_thickness 0.25)
		(keepout
			(tracks allowed)
			(vias allowed)
			(pads allowed)
			(copperpour allowed)
			(footprints allowed)
		)
		(placement
			(enabled no)
			(sheetname "")
		)
		(fill
			(thermal_gap 0.5)
			(thermal_bridge_width 0.5)
			(island_removal_mode 0)
		)
		(polygon
			(pts
				(xy 222.92437 -193.691256) (xy 224.331022 -193.691256) (xy 224.604834 -193.417444) (xy 224.604834 -191.831722)
				(xy 224.236534 -191.463422) (xy 222.679006 -191.463422) (xy 222.679006 -193.445892)
			)
		)
	)
	(zone
		(layer "F.Cu")
		(hatch none 0.5)
		(connect_pads
			(clearance 0)
		)
		(min_thickness 0.25)
		(keepout
			(tracks not_allowed)
			(vias allowed)
			(pads allowed)
			(copperpour not_allowed)
			(footprints allowed)
		)
		(placement
			(enabled no)
			(sheetname "")
		)
		(fill
			(thermal_gap 0.5)
			(thermal_bridge_width 0.5)
			(island_removal_mode 0)
		)
		(polygon
			(pts
				(xy 435.820058 -23.219918) (xy 435.820058 -18.219928) (xy 431.619914 -18.219928) (xy 431.619914 -23.219918)
			)
		)
	)
	(zone
		(layer "F.Cu")
		(hatch none 0.5)
		(connect_pads
			(clearance 0)
		)
		(min_thickness 0.25)
		(keepout
			(tracks allowed)
			(vias allowed)
			(pads allowed)
			(copperpour allowed)
			(footprints allowed)
		)
		(placement
			(enabled no)
			(sheetname "")
		)
		(fill
			(thermal_gap 0.5)
			(thermal_bridge_width 0.5)
			(island_removal_mode 0)
		)
		(polygon
			(pts
				(xy 152.055068 -109.424724) (xy 152.055068 -108.073444) (xy 153.335228 -108.073444) (xy 153.335228 -109.424724)
			)
		)
	)
	(zone
		(layer "F.Cu")
		(hatch none 0.5)
		(connect_pads
			(clearance 0)
		)
		(min_thickness 0.25)
		(keepout
			(tracks allowed)
			(vias allowed)
			(pads allowed)
			(copperpour allowed)
			(footprints allowed)
		)
		(placement
			(enabled no)
			(sheetname "")
		)
		(fill
			(thermal_gap 0.5)
			(thermal_bridge_width 0.5)
			(island_removal_mode 0)
		)
		(polygon
			(pts
				(xy 229.80523 -79.63027) (xy 229.80523 -78.79334) (xy 229.80523 -78.302866) (xy 229.804976 -78.302612)
				(xy 228.357176 -78.302612) (xy 228.236526 -78.423262) (xy 228.236526 -78.732634) (xy 228.266752 -78.76286)
				(xy 228.266752 -79.60741) (xy 228.34981 -79.690468) (xy 229.745032 -79.690468)
			)
		)
	)
	(zone
		(layer "F.Cu")
		(hatch none 0.5)
		(connect_pads
			(clearance 0)
		)
		(min_thickness 0.25)
		(keepout
			(tracks not_allowed)
			(vias allowed)
			(pads allowed)
			(copperpour not_allowed)
			(footprints allowed)
		)
		(placement
			(enabled no)
			(sheetname "")
		)
		(fill
			(thermal_gap 0.5)
			(thermal_bridge_width 0.5)
			(island_removal_mode 0)
		)
		(polygon
			(pts
				(arc
					(start 352.700082 -194.360038)
					(mid 349.899986 -197.160134)
					(end 347.09989 -194.360038)
				)
				(arc
					(start 347.09989 -194.360038)
					(mid 349.899986 -191.559942)
					(end 352.700082 -194.360038)
				)
			)
		)
	)
	(zone
		(layer "F.Cu")
		(hatch none 0.5)
		(connect_pads
			(clearance 0)
		)
		(min_thickness 0.25)
		(keepout
			(tracks allowed)
			(vias allowed)
			(pads allowed)
			(copperpour allowed)
			(footprints allowed)
		)
		(placement
			(enabled no)
			(sheetname "")
		)
		(fill
			(thermal_gap 0.5)
			(thermal_bridge_width 0.5)
			(island_removal_mode 0)
		)
		(polygon
			(pts
				(xy 384.255264 -135.13816) (xy 384.255264 -133.78688) (xy 385.535424 -133.78688) (xy 385.535424 -135.13816)
			)
		)
	)
	(zone
		(layer "F.Cu")
		(hatch none 0.5)
		(connect_pads
			(clearance 0)
		)
		(min_thickness 0.25)
		(keepout
			(tracks allowed)
			(vias allowed)
			(pads allowed)
			(copperpour allowed)
			(footprints allowed)
		)
		(placement
			(enabled no)
			(sheetname "")
		)
		(fill
			(thermal_gap 0.5)
			(thermal_bridge_width 0.5)
			(island_removal_mode 0)
		)
		(polygon
			(pts
				(xy 106.2863 -375.67362) (xy 106.2863 -374.83669) (xy 106.2863 -374.346216) (xy 106.286046 -374.345962)
				(xy 104.838246 -374.345962) (xy 104.717596 -374.466612) (xy 104.717596 -374.775984) (xy 104.747822 -374.80621)
				(xy 104.747822 -375.65076) (xy 104.83088 -375.733818) (xy 106.226102 -375.733818)
			)
		)
	)
	(zone
		(layer "F.Cu")
		(hatch none 0.5)
		(connect_pads
			(clearance 0)
		)
		(min_thickness 0.25)
		(keepout
			(tracks allowed)
			(vias allowed)
			(pads allowed)
			(copperpour allowed)
			(footprints not_allowed)
		)
		(placement
			(enabled no)
			(sheetname "")
		)
		(fill
			(thermal_gap 0.5)
			(thermal_bridge_width 0.5)
			(island_removal_mode 0)
		)
		(polygon
			(pts
				(xy 125.620018 -23.219918) (xy 125.620018 -18.219928) (xy 121.419874 -18.219928) (xy 121.419874 -23.219918)
			)
		)
	)
	(zone
		(layer "F.Cu")
		(hatch none 0.5)
		(connect_pads
			(clearance 0)
		)
		(min_thickness 0.25)
		(keepout
			(tracks allowed)
			(vias allowed)
			(pads allowed)
			(copperpour allowed)
			(footprints not_allowed)
		)
		(placement
			(enabled no)
			(sheetname "")
		)
		(fill
			(thermal_gap 0.5)
			(thermal_bridge_width 0.5)
			(island_removal_mode 0)
		)
		(polygon
			(pts
				(arc
					(start 109.70006 -72.69988)
					(mid 117.700044 -64.699896)
					(end 125.700028 -72.69988)
				)
				(arc
					(start 125.700028 -72.69988)
					(mid 117.700044 -80.699864)
					(end 109.70006 -72.69988)
				)
			)
		)
	)
	(zone
		(layer "F.Cu")
		(hatch none 0.5)
		(connect_pads
			(clearance 0)
		)
		(min_thickness 0.25)
		(keepout
			(tracks allowed)
			(vias allowed)
			(pads allowed)
			(copperpour allowed)
			(footprints not_allowed)
		)
		(placement
			(enabled no)
			(sheetname "")
		)
		(fill
			(thermal_gap 0.5)
			(thermal_bridge_width 0.5)
			(island_removal_mode 0)
		)
		(polygon
			(pts
				(xy 293.165022 -40.120062) (xy 301.165006 -40.120062) (xy 301.165006 -13.850112) (xy 293.165022 -13.850112)
			)
		)
	)
	(zone
		(layer "F.Cu")
		(hatch none 0.5)
		(connect_pads
			(clearance 0)
		)
		(min_thickness 0.25)
		(keepout
			(tracks allowed)
			(vias allowed)
			(pads allowed)
			(copperpour allowed)
			(footprints allowed)
		)
		(placement
			(enabled no)
			(sheetname "")
		)
		(fill
			(thermal_gap 0.5)
			(thermal_bridge_width 0.5)
			(island_removal_mode 0)
		)
		(polygon
			(pts
				(xy 164.537898 -19.7358) (xy 164.537898 -19.2024) (xy 165.604698 -19.2024) (xy 165.604698 -19.7358)
			)
		)
	)
	(zone
		(layer "F.Cu")
		(hatch none 0.5)
		(connect_pads
			(clearance 0)
		)
		(min_thickness 0.25)
		(keepout
			(tracks not_allowed)
			(vias allowed)
			(pads allowed)
			(copperpour not_allowed)
			(footprints allowed)
		)
		(placement
			(enabled no)
			(sheetname "")
		)
		(fill
			(thermal_gap 0.5)
			(thermal_bridge_width 0.5)
			(island_removal_mode 0)
		)
		(polygon
			(pts
				(arc
					(start 286.964882 -5.999988)
					(mid 284.16504 -8.79983)
					(end 281.364944 -5.999988)
				)
				(arc
					(start 281.364944 -5.999988)
					(mid 284.16504 -3.199892)
					(end 286.964882 -5.999988)
				)
			)
		)
	)
	(zone
		(layer "F.Cu")
		(hatch none 0.5)
		(connect_pads
			(clearance 0)
		)
		(min_thickness 0.25)
		(keepout
			(tracks allowed)
			(vias allowed)
			(pads allowed)
			(copperpour allowed)
			(footprints not_allowed)
		)
		(placement
			(enabled no)
			(sheetname "")
		)
		(fill
			(thermal_gap 0.5)
			(thermal_bridge_width 0.5)
			(island_removal_mode 0)
		)
		(polygon
			(pts
				(arc
					(start 23.800054 -194.360038)
					(mid 15.80007 -202.360022)
					(end 7.800086 -194.360038)
				)
				(arc
					(start 7.800086 -194.360038)
					(mid 15.80007 -186.360054)
					(end 23.800054 -194.360038)
				)
			)
		)
	)
	(zone
		(layer "F.Cu")
		(hatch none 0.5)
		(connect_pads
			(clearance 0)
		)
		(min_thickness 0.25)
		(keepout
			(tracks allowed)
			(vias allowed)
			(pads allowed)
			(copperpour allowed)
			(footprints allowed)
		)
		(placement
			(enabled no)
			(sheetname "")
		)
		(fill
			(thermal_gap 0.5)
			(thermal_bridge_width 0.5)
			(island_removal_mode 0)
		)
		(polygon
			(pts
				(xy 280.159206 -47.3202) (xy 280.159206 -45.5676) (xy 281.937206 -45.5676) (xy 281.937206 -47.3202)
			)
		)
	)
	(zone
		(layer "F.Cu")
		(hatch none 0.5)
		(connect_pads
			(clearance 0)
		)
		(min_thickness 0.25)
		(keepout
			(tracks allowed)
			(vias allowed)
			(pads allowed)
			(copperpour allowed)
			(footprints allowed)
		)
		(placement
			(enabled no)
			(sheetname "")
		)
		(fill
			(thermal_gap 0.5)
			(thermal_bridge_width 0.5)
			(island_removal_mode 0)
		)
		(polygon
			(pts
				(xy 154.697176 -136.944608) (xy 154.697176 -135.593328) (xy 155.977336 -135.593328) (xy 155.977336 -136.944608)
			)
		)
	)
	(zone
		(layer "F.Cu")
		(hatch none 0.5)
		(connect_pads
			(clearance 0)
		)
		(min_thickness 0.25)
		(keepout
			(tracks allowed)
			(vias allowed)
			(pads allowed)
			(copperpour allowed)
			(footprints allowed)
		)
		(placement
			(enabled no)
			(sheetname "")
		)
		(fill
			(thermal_gap 0.5)
			(thermal_bridge_width 0.5)
			(island_removal_mode 0)
		)
		(polygon
			(pts
				(xy 191.270636 -350.781874) (xy 189.919356 -350.781874) (xy 189.919356 -349.501714) (xy 191.270636 -349.501714)
			)
		)
	)
	(zone
		(layer "F.Cu")
		(hatch none 0.5)
		(connect_pads
			(clearance 0)
		)
		(min_thickness 0.25)
		(keepout
			(tracks allowed)
			(vias allowed)
			(pads allowed)
			(copperpour allowed)
			(footprints allowed)
		)
		(placement
			(enabled no)
			(sheetname "")
		)
		(fill
			(thermal_gap 0.5)
			(thermal_bridge_width 0.5)
			(island_removal_mode 0)
		)
		(polygon
			(pts
				(xy 133.209284 -32.954468) (xy 133.209284 -31.603188) (xy 134.489444 -31.603188) (xy 134.489444 -32.954468)
			)
		)
	)
	(zone
		(layer "F.Cu")
		(hatch none 0.5)
		(connect_pads
			(clearance 0)
		)
		(min_thickness 0.25)
		(keepout
			(tracks allowed)
			(vias allowed)
			(pads allowed)
			(copperpour allowed)
			(footprints not_allowed)
		)
		(placement
			(enabled no)
			(sheetname "")
		)
		(fill
			(thermal_gap 0.5)
			(thermal_bridge_width 0.5)
			(island_removal_mode 0)
		)
		(polygon
			(pts
				(xy 209.749898 -262.400034) (xy 141.750034 -262.400034) (xy 141.750034 -329.3999) (xy 209.749898 -329.3999)
			)
		)
	)
	(zone
		(layer "F.Cu")
		(hatch none 0.5)
		(connect_pads
			(clearance 0)
		)
		(min_thickness 0.25)
		(keepout
			(tracks allowed)
			(vias allowed)
			(pads allowed)
			(copperpour allowed)
			(footprints allowed)
		)
		(placement
			(enabled no)
			(sheetname "")
		)
		(fill
			(thermal_gap 0.5)
			(thermal_bridge_width 0.5)
			(island_removal_mode 0)
		)
		(polygon
			(pts
				(xy 290.738306 -350.80575) (xy 289.387026 -350.80575) (xy 289.387026 -349.52559) (xy 290.738306 -349.52559)
			)
		)
	)
	(zone
		(layer "F.Cu")
		(hatch none 0.5)
		(connect_pads
			(clearance 0)
		)
		(min_thickness 0.25)
		(keepout
			(tracks allowed)
			(vias allowed)
			(pads allowed)
			(copperpour allowed)
			(footprints allowed)
		)
		(placement
			(enabled no)
			(sheetname "")
		)
		(fill
			(thermal_gap 0.5)
			(thermal_bridge_width 0.5)
			(island_removal_mode 0)
		)
		(polygon
			(pts
				(xy 188.161676 -350.80575) (xy 186.810396 -350.80575) (xy 186.810396 -349.52559) (xy 188.161676 -349.52559)
			)
		)
	)
	(zone
		(layer "F.Cu")
		(hatch none 0.5)
		(connect_pads
			(clearance 0)
		)
		(min_thickness 0.25)
		(keepout
			(tracks allowed)
			(vias allowed)
			(pads allowed)
			(copperpour allowed)
			(footprints allowed)
		)
		(placement
			(enabled no)
			(sheetname "")
		)
		(fill
			(thermal_gap 0.5)
			(thermal_bridge_width 0.5)
			(island_removal_mode 0)
		)
		(polygon
			(pts
				(xy 458.216 -278.765) (xy 458.216 -277.114) (xy 459.867 -277.114) (xy 459.867 -278.765)
			)
		)
	)
	(zone
		(layer "F.Cu")
		(hatch none 0.5)
		(connect_pads
			(clearance 0)
		)
		(min_thickness 0.25)
		(keepout
			(tracks allowed)
			(vias allowed)
			(pads allowed)
			(copperpour allowed)
			(footprints allowed)
		)
		(placement
			(enabled no)
			(sheetname "")
		)
		(fill
			(thermal_gap 0.5)
			(thermal_bridge_width 0.5)
			(island_removal_mode 0)
		)
		(polygon
			(pts
				(xy 20.436332 -344.659458) (xy 19.085052 -344.659458) (xy 19.085052 -343.379298) (xy 20.436332 -343.379298)
			)
		)
	)
	(zone
		(layer "F.Cu")
		(hatch none 0.5)
		(connect_pads
			(clearance 0)
		)
		(min_thickness 0.25)
		(keepout
			(tracks allowed)
			(vias allowed)
			(pads allowed)
			(copperpour allowed)
			(footprints not_allowed)
		)
		(placement
			(enabled no)
			(sheetname "")
		)
		(fill
			(thermal_gap 0.5)
			(thermal_bridge_width 0.5)
			(island_removal_mode 0)
		)
		(polygon
			(pts
				(xy 359.08996 -232.750106) (xy 359.08996 -218.250008) (xy 355.940106 -218.250008) (xy 355.940106 -232.750106)
			)
		)
	)
	(zone
		(layer "F.Cu")
		(hatch none 0.5)
		(connect_pads
			(clearance 0)
		)
		(min_thickness 0.25)
		(keepout
			(tracks allowed)
			(vias allowed)
			(pads allowed)
			(copperpour allowed)
			(footprints not_allowed)
		)
		(placement
			(enabled no)
			(sheetname "")
		)
		(fill
			(thermal_gap 0.5)
			(thermal_bridge_width 0.5)
			(island_removal_mode 0)
		)
		(polygon
			(pts
				(xy 409.26512 -40.120062) (xy 417.26485 -40.120062) (xy 417.265104 -13.850112) (xy 409.26512 -13.850112)
			)
		)
	)
	(zone
		(layer "F.Cu")
		(hatch none 0.5)
		(connect_pads
			(clearance 0)
		)
		(min_thickness 0.25)
		(keepout
			(tracks allowed)
			(vias allowed)
			(pads allowed)
			(copperpour allowed)
			(footprints allowed)
		)
		(placement
			(enabled no)
			(sheetname "")
		)
		(fill
			(thermal_gap 0.5)
			(thermal_bridge_width 0.5)
			(island_removal_mode 0)
		)
		(polygon
			(pts
				(xy 296.956226 -344.635582) (xy 295.604946 -344.635582) (xy 295.604946 -343.355422) (xy 296.956226 -343.355422)
			)
		)
	)
	(zone
		(layer "F.Cu")
		(hatch none 0.5)
		(connect_pads
			(clearance 0)
		)
		(min_thickness 0.25)
		(keepout
			(tracks allowed)
			(vias allowed)
			(pads allowed)
			(copperpour allowed)
			(footprints allowed)
		)
		(placement
			(enabled no)
			(sheetname "")
		)
		(fill
			(thermal_gap 0.5)
			(thermal_bridge_width 0.5)
			(island_removal_mode 0)
		)
		(polygon
			(pts
				(xy 160.181036 -356.928166) (xy 158.829756 -356.928166) (xy 158.829756 -355.648006) (xy 160.181036 -355.648006)
			)
		)
	)
	(zone
		(layer "F.Cu")
		(hatch none 0.5)
		(connect_pads
			(clearance 0)
		)
		(min_thickness 0.25)
		(keepout
			(tracks allowed)
			(vias allowed)
			(pads allowed)
			(copperpour allowed)
			(footprints allowed)
		)
		(placement
			(enabled no)
			(sheetname "")
		)
		(fill
			(thermal_gap 0.5)
			(thermal_bridge_width 0.5)
			(island_removal_mode 0)
		)
		(polygon
			(pts
				(xy 232.680764 -117.815614) (xy 232.680764 -114.005614) (xy 234.204764 -114.005614) (xy 234.204764 -117.815614)
			)
		)
	)
	(zone
		(layer "F.Cu")
		(hatch none 0.5)
		(connect_pads
			(clearance 0)
		)
		(min_thickness 0.25)
		(keepout
			(tracks allowed)
			(vias allowed)
			(pads allowed)
			(copperpour allowed)
			(footprints allowed)
		)
		(placement
			(enabled no)
			(sheetname "")
		)
		(fill
			(thermal_gap 0.5)
			(thermal_bridge_width 0.5)
			(island_removal_mode 0)
		)
		(polygon
			(pts
				(xy 232.312464 -86.900004) (xy 232.312464 -87.736934) (xy 232.312464 -88.227408) (xy 232.312718 -88.227662)
				(xy 233.760518 -88.227662) (xy 233.881168 -88.107012) (xy 233.881168 -87.79764) (xy 233.850942 -87.767414)
				(xy 233.850942 -86.922864) (xy 233.767884 -86.839806) (xy 232.372662 -86.839806)
			)
		)
	)
	(zone
		(layer "F.Cu")
		(hatch none 0.5)
		(connect_pads
			(clearance 0)
		)
		(min_thickness 0.25)
		(keepout
			(tracks allowed)
			(vias allowed)
			(pads allowed)
			(copperpour allowed)
			(footprints allowed)
		)
		(placement
			(enabled no)
			(sheetname "")
		)
		(fill
			(thermal_gap 0.5)
			(thermal_bridge_width 0.5)
			(island_removal_mode 0)
		)
		(polygon
			(pts
				(xy 270.797274 -125.734826) (xy 270.797274 -124.383546) (xy 272.077434 -124.383546) (xy 272.077434 -125.734826)
			)
		)
	)
	(zone
		(layer "F.Cu")
		(hatch none 0.5)
		(connect_pads
			(clearance 0)
		)
		(min_thickness 0.25)
		(keepout
			(tracks allowed)
			(vias allowed)
			(pads allowed)
			(copperpour allowed)
			(footprints allowed)
		)
		(placement
			(enabled no)
			(sheetname "")
		)
		(fill
			(thermal_gap 0.5)
			(thermal_bridge_width 0.5)
			(island_removal_mode 0)
		)
		(polygon
			(pts
				(xy 341.561928 -344.635582) (xy 340.210648 -344.635582) (xy 340.210648 -343.355422) (xy 341.561928 -343.355422)
			)
		)
	)
	(zone
		(layer "F.Cu")
		(hatch none 0.5)
		(connect_pads
			(clearance 0)
		)
		(min_thickness 0.25)
		(keepout
			(tracks allowed)
			(vias allowed)
			(pads allowed)
			(copperpour allowed)
			(footprints allowed)
		)
		(placement
			(enabled no)
			(sheetname "")
		)
		(fill
			(thermal_gap 0.5)
			(thermal_bridge_width 0.5)
			(island_removal_mode 0)
		)
		(polygon
			(pts
				(xy 238.259874 -87.27821) (xy 238.259874 -88.11514) (xy 238.259874 -88.605614) (xy 238.260128 -88.605868)
				(xy 239.707928 -88.605868) (xy 239.828578 -88.485218) (xy 239.828578 -88.175846) (xy 239.798352 -88.14562)
				(xy 239.798352 -87.30107) (xy 239.715294 -87.218012) (xy 238.320072 -87.218012)
			)
		)
	)
	(zone
		(layer "F.Cu")
		(hatch none 0.5)
		(connect_pads
			(clearance 0)
		)
		(min_thickness 0.25)
		(keepout
			(tracks not_allowed)
			(vias allowed)
			(pads allowed)
			(copperpour not_allowed)
			(footprints allowed)
		)
		(placement
			(enabled no)
			(sheetname "")
		)
		(fill
			(thermal_gap 0.5)
			(thermal_bridge_width 0.5)
			(island_removal_mode 0)
		)
		(polygon
			(pts
				(xy 253.424436 -215.467692) (xy 255.354836 -215.467692) (xy 255.354836 -212.419692) (xy 255.260094 -212.419692)
				(xy 255.260094 -212.521292) (xy 255.278636 -212.521292) (xy 255.278636 -215.340692) (xy 253.424436 -215.340692)
			)
		)
	)
	(zone
		(layer "F.Cu")
		(hatch none 0.5)
		(connect_pads
			(clearance 0)
		)
		(min_thickness 0.25)
		(keepout
			(tracks allowed)
			(vias allowed)
			(pads allowed)
			(copperpour allowed)
			(footprints allowed)
		)
		(placement
			(enabled no)
			(sheetname "")
		)
		(fill
			(thermal_gap 0.5)
			(thermal_bridge_width 0.5)
			(island_removal_mode 0)
		)
		(polygon
			(pts
				(xy 44.47413 -126.219204) (xy 46.561502 -126.219204) (xy 46.881542 -125.899164) (xy 46.881542 -118.495064)
				(xy 44.536614 -118.495064) (xy 44.458382 -118.573296) (xy 44.458382 -126.203456)
			)
		)
	)
	(zone
		(layer "F.Cu")
		(hatch none 0.5)
		(connect_pads
			(clearance 0)
		)
		(min_thickness 0.25)
		(keepout
			(tracks allowed)
			(vias allowed)
			(pads allowed)
			(copperpour allowed)
			(footprints allowed)
		)
		(placement
			(enabled no)
			(sheetname "")
		)
		(fill
			(thermal_gap 0.5)
			(thermal_bridge_width 0.5)
			(island_removal_mode 0)
		)
		(polygon
			(pts
				(xy 81.978246 -121.606056) (xy 81.978246 -120.254776) (xy 83.258406 -120.254776) (xy 83.258406 -121.606056)
			)
		)
	)
	(zone
		(layer "F.Cu")
		(hatch none 0.5)
		(connect_pads
			(clearance 0)
		)
		(min_thickness 0.25)
		(keepout
			(tracks allowed)
			(vias allowed)
			(pads allowed)
			(copperpour allowed)
			(footprints allowed)
		)
		(placement
			(enabled no)
			(sheetname "")
		)
		(fill
			(thermal_gap 0.5)
			(thermal_bridge_width 0.5)
			(island_removal_mode 0)
		)
		(polygon
			(pts
				(arc
					(start 208.037938 -219.722954)
					(mid 208.052817 -219.687033)
					(end 208.088738 -219.672154)
				)
				(arc
					(start 209.0674 -219.672154)
					(mid 209.103321 -219.687033)
					(end 209.1182 -219.722954)
				)
				(arc
					(start 209.1182 -220.647768)
					(mid 209.103321 -220.683689)
					(end 209.0674 -220.698568)
				)
				(arc
					(start 208.088738 -220.698568)
					(mid 208.052817 -220.683689)
					(end 208.037938 -220.647768)
				)
			)
		)
	)
	(zone
		(layer "F.Cu")
		(hatch none 0.5)
		(connect_pads
			(clearance 0)
		)
		(min_thickness 0.25)
		(keepout
			(tracks allowed)
			(vias allowed)
			(pads allowed)
			(copperpour allowed)
			(footprints allowed)
		)
		(placement
			(enabled no)
			(sheetname "")
		)
		(fill
			(thermal_gap 0.5)
			(thermal_bridge_width 0.5)
			(island_removal_mode 0)
		)
		(polygon
			(pts
				(xy 250.474734 -148.251672) (xy 251.364496 -148.251672) (xy 251.394722 -148.221446) (xy 251.394722 -147.127976)
				(xy 251.274072 -147.007326) (xy 250.210828 -147.007326) (xy 250.210828 -147.987766)
			)
		)
	)
	(zone
		(layer "F.Cu")
		(hatch none 0.5)
		(connect_pads
			(clearance 0)
		)
		(min_thickness 0.25)
		(keepout
			(tracks allowed)
			(vias allowed)
			(pads allowed)
			(copperpour allowed)
			(footprints allowed)
		)
		(placement
			(enabled no)
			(sheetname "")
		)
		(fill
			(thermal_gap 0.5)
			(thermal_bridge_width 0.5)
			(island_removal_mode 0)
		)
		(polygon
			(pts
				(xy 46.76013 -46.986444) (xy 47.752508 -46.986444) (xy 47.837344 -46.901608) (xy 47.837344 -46.211744)
				(xy 47.789338 -46.163738) (xy 46.740064 -46.163738) (xy 46.672246 -46.231556) (xy 46.672246 -46.89856)
			)
		)
	)
	(zone
		(layer "F.Cu")
		(hatch none 0.5)
		(connect_pads
			(clearance 0)
		)
		(min_thickness 0.25)
		(keepout
			(tracks not_allowed)
			(vias allowed)
			(pads allowed)
			(copperpour not_allowed)
			(footprints allowed)
		)
		(placement
			(enabled no)
			(sheetname "")
		)
		(fill
			(thermal_gap 0.5)
			(thermal_bridge_width 0.5)
			(island_removal_mode 0)
		)
		(polygon
			(pts
				(arc
					(start 276.899878 -378.70003)
					(mid 271.899888 -383.70002)
					(end 266.899898 -378.70003)
				)
				(arc
					(start 266.899898 -378.70003)
					(mid 271.899888 -373.70004)
					(end 276.899878 -378.70003)
				)
			)
		)
	)
	(zone
		(layer "F.Cu")
		(hatch none 0.5)
		(connect_pads
			(clearance 0)
		)
		(min_thickness 0.25)
		(keepout
			(tracks allowed)
			(vias allowed)
			(pads allowed)
			(copperpour allowed)
			(footprints allowed)
		)
		(placement
			(enabled no)
			(sheetname "")
		)
		(fill
			(thermal_gap 0.5)
			(thermal_bridge_width 0.5)
			(island_removal_mode 0)
		)
		(polygon
			(pts
				(xy 195.435982 -123.39955) (xy 195.435982 -122.04827) (xy 196.716142 -122.04827) (xy 196.716142 -123.39955)
			)
		)
	)
	(zone
		(layer "F.Cu")
		(hatch none 0.5)
		(connect_pads
			(clearance 0)
		)
		(min_thickness 0.25)
		(keepout
			(tracks allowed)
			(vias allowed)
			(pads allowed)
			(copperpour allowed)
			(footprints allowed)
		)
		(placement
			(enabled no)
			(sheetname "")
		)
		(fill
			(thermal_gap 0.5)
			(thermal_bridge_width 0.5)
			(island_removal_mode 0)
		)
		(polygon
			(pts
				(xy 213.851236 -34.76117) (xy 213.851236 -33.40989) (xy 215.131396 -33.40989) (xy 215.131396 -34.76117)
			)
		)
	)
	(zone
		(layer "F.Cu")
		(hatch none 0.5)
		(connect_pads
			(clearance 0)
		)
		(min_thickness 0.25)
		(keepout
			(tracks allowed)
			(vias allowed)
			(pads allowed)
			(copperpour allowed)
			(footprints allowed)
		)
		(placement
			(enabled no)
			(sheetname "")
		)
		(fill
			(thermal_gap 0.5)
			(thermal_bridge_width 0.5)
			(island_removal_mode 0)
		)
		(polygon
			(pts
				(xy 204.089 -22.606) (xy 204.089 -21.844) (xy 206.629 -21.844) (xy 206.629 -22.606)
			)
		)
	)
	(zone
		(layer "F.Cu")
		(hatch none 0.5)
		(connect_pads
			(clearance 0)
		)
		(min_thickness 0.25)
		(keepout
			(tracks not_allowed)
			(vias allowed)
			(pads allowed)
			(copperpour not_allowed)
			(footprints allowed)
		)
		(placement
			(enabled no)
			(sheetname "")
		)
		(fill
			(thermal_gap 0.5)
			(thermal_bridge_width 0.5)
			(island_removal_mode 0)
		)
		(polygon
			(pts
				(arc
					(start 464.399884 -407.599896)
					(mid 461.600042 -410.399738)
					(end 458.799946 -407.599896)
				)
				(arc
					(start 458.799946 -407.599896)
					(mid 461.600042 -404.7998)
					(end 464.399884 -407.599896)
				)
			)
		)
	)
	(zone
		(layer "F.Cu")
		(hatch none 0.5)
		(connect_pads
			(clearance 0)
		)
		(min_thickness 0.25)
		(keepout
			(tracks allowed)
			(vias allowed)
			(pads allowed)
			(copperpour allowed)
			(footprints allowed)
		)
		(placement
			(enabled no)
			(sheetname "")
		)
		(fill
			(thermal_gap 0.5)
			(thermal_bridge_width 0.5)
			(island_removal_mode 0)
		)
		(polygon
			(pts
				(xy 66.661538 -27.55011) (xy 69.061584 -27.55011) (xy 69.153024 -27.45867) (xy 69.153024 -26.33853)
				(xy 69.092064 -26.27757) (xy 66.646298 -26.27757) (xy 66.524378 -26.39949) (xy 66.524378 -27.41295)
			)
		)
	)
	(zone
		(layer "F.Cu")
		(hatch none 0.5)
		(connect_pads
			(clearance 0)
		)
		(min_thickness 0.25)
		(keepout
			(tracks allowed)
			(vias allowed)
			(pads allowed)
			(copperpour allowed)
			(footprints allowed)
		)
		(placement
			(enabled no)
			(sheetname "")
		)
		(fill
			(thermal_gap 0.5)
			(thermal_bridge_width 0.5)
			(island_removal_mode 0)
		)
		(polygon
			(pts
				(xy 270.797274 -136.944608) (xy 270.797274 -135.593328) (xy 272.077434 -135.593328) (xy 272.077434 -136.944608)
			)
		)
	)
	(zone
		(layer "F.Cu")
		(hatch none 0.5)
		(connect_pads
			(clearance 0)
		)
		(min_thickness 0.25)
		(keepout
			(tracks allowed)
			(vias allowed)
			(pads allowed)
			(copperpour allowed)
			(footprints not_allowed)
		)
		(placement
			(enabled no)
			(sheetname "")
		)
		(fill
			(thermal_gap 0.5)
			(thermal_bridge_width 0.5)
			(island_removal_mode 0)
		)
		(polygon
			(pts
				(arc
					(start 443.449964 -308.61)
					(mid 447.449956 -304.610008)
					(end 451.449948 -308.61)
				)
				(arc
					(start 451.449948 -308.61)
					(mid 447.449956 -312.609992)
					(end 443.449964 -308.61)
				)
			)
		)
	)
	(zone
		(layer "F.Cu")
		(hatch none 0.5)
		(connect_pads
			(clearance 0)
		)
		(min_thickness 0.25)
		(keepout
			(tracks allowed)
			(vias allowed)
			(pads allowed)
			(copperpour allowed)
			(footprints allowed)
		)
		(placement
			(enabled no)
			(sheetname "")
		)
		(fill
			(thermal_gap 0.5)
			(thermal_bridge_width 0.5)
			(island_removal_mode 0)
		)
		(polygon
			(pts
				(xy 227.041202 -267.948156) (xy 227.041202 -265.799316) (xy 228.712522 -265.799316) (xy 228.712522 -267.948156)
			)
		)
	)
	(zone
		(layer "F.Cu")
		(hatch none 0.5)
		(connect_pads
			(clearance 0)
		)
		(min_thickness 0.25)
		(keepout
			(tracks allowed)
			(vias allowed)
			(pads allowed)
			(copperpour allowed)
			(footprints allowed)
		)
		(placement
			(enabled no)
			(sheetname "")
		)
		(fill
			(thermal_gap 0.5)
			(thermal_bridge_width 0.5)
			(island_removal_mode 0)
		)
		(polygon
			(pts
				(xy 253.191518 -52.800758) (xy 253.191518 -55.718456) (xy 253.401068 -55.928006) (xy 254.01397 -55.928006)
				(xy 254.01397 -52.870608) (xy 253.94412 -52.800758)
			)
		)
	)
	(zone
		(layer "F.Cu")
		(hatch none 0.5)
		(connect_pads
			(clearance 0)
		)
		(min_thickness 0.25)
		(keepout
			(tracks allowed)
			(vias allowed)
			(pads allowed)
			(copperpour allowed)
			(footprints allowed)
		)
		(placement
			(enabled no)
			(sheetname "")
		)
		(fill
			(thermal_gap 0.5)
			(thermal_bridge_width 0.5)
			(island_removal_mode 0)
		)
		(polygon
			(pts
				(xy 140.946632 -350.781874) (xy 139.595352 -350.781874) (xy 139.595352 -349.501714) (xy 140.946632 -349.501714)
			)
		)
	)
	(zone
		(layer "F.Cu")
		(hatch none 0.5)
		(connect_pads
			(clearance 0)
		)
		(min_thickness 0.25)
		(keepout
			(tracks allowed)
			(vias allowed)
			(pads allowed)
			(copperpour allowed)
			(footprints allowed)
		)
		(placement
			(enabled no)
			(sheetname "")
		)
		(fill
			(thermal_gap 0.5)
			(thermal_bridge_width 0.5)
			(island_removal_mode 0)
		)
		(polygon
			(pts
				(xy 17.782032 -150.189692) (xy 17.782032 -148.437092) (xy 19.560032 -148.437092) (xy 19.560032 -150.189692)
			)
		)
	)
	(zone
		(layer "F.Cu")
		(hatch none 0.5)
		(connect_pads
			(clearance 0)
		)
		(min_thickness 0.25)
		(keepout
			(tracks allowed)
			(vias allowed)
			(pads allowed)
			(copperpour allowed)
			(footprints allowed)
		)
		(placement
			(enabled no)
			(sheetname "")
		)
		(fill
			(thermal_gap 0.5)
			(thermal_bridge_width 0.5)
			(island_removal_mode 0)
		)
		(polygon
			(pts
				(xy 178.834796 -356.928166) (xy 177.483516 -356.928166) (xy 177.483516 -355.648006) (xy 178.834796 -355.648006)
			)
		)
	)
	(zone
		(layer "F.Cu")
		(hatch none 0.5)
		(connect_pads
			(clearance 0)
		)
		(min_thickness 0.25)
		(keepout
			(tracks allowed)
			(vias allowed)
			(pads allowed)
			(copperpour allowed)
			(footprints not_allowed)
		)
		(placement
			(enabled no)
			(sheetname "")
		)
		(fill
			(thermal_gap 0.5)
			(thermal_bridge_width 0.5)
			(island_removal_mode 0)
		)
		(polygon
			(pts
				(xy 242.990116 -232.750106) (xy 260.809994 -232.750106) (xy 260.809994 -218.250008) (xy 242.990116 -218.250008)
			)
		)
	)
	(zone
		(layer "F.Cu")
		(hatch none 0.5)
		(connect_pads
			(clearance 0)
		)
		(min_thickness 0.25)
		(keepout
			(tracks allowed)
			(vias allowed)
			(pads allowed)
			(copperpour allowed)
			(footprints allowed)
		)
		(placement
			(enabled no)
			(sheetname "")
		)
		(fill
			(thermal_gap 0.5)
			(thermal_bridge_width 0.5)
			(island_removal_mode 0)
		)
		(polygon
			(pts
				(xy 224.121472 -149.581616) (xy 225.749358 -149.581616) (xy 225.916998 -149.413976) (xy 225.916998 -144.626076)
				(xy 225.665792 -144.37487) (xy 223.977962 -144.37487) (xy 223.690688 -144.662144) (xy 223.690688 -149.150832)
			)
		)
	)
	(zone
		(layer "F.Cu")
		(hatch none 0.5)
		(connect_pads
			(clearance 0)
		)
		(min_thickness 0.25)
		(keepout
			(tracks allowed)
			(vias allowed)
			(pads allowed)
			(copperpour allowed)
			(footprints allowed)
		)
		(placement
			(enabled no)
			(sheetname "")
		)
		(fill
			(thermal_gap 0.5)
			(thermal_bridge_width 0.5)
			(island_removal_mode 0)
		)
		(polygon
			(pts
				(xy 422.809416 -356.952042) (xy 421.458136 -356.952042) (xy 421.458136 -355.671882) (xy 422.809416 -355.671882)
			)
		)
	)
	(zone
		(layer "F.Cu")
		(hatch none 0.5)
		(connect_pads
			(clearance 0)
		)
		(min_thickness 0.25)
		(keepout
			(tracks not_allowed)
			(vias allowed)
			(pads allowed)
			(copperpour not_allowed)
			(footprints allowed)
		)
		(placement
			(enabled no)
			(sheetname "")
		)
		(fill
			(thermal_gap 0.5)
			(thermal_bridge_width 0.5)
			(island_removal_mode 0)
		)
		(polygon
			(pts
				(xy 125.620018 -23.219918) (xy 125.620018 -18.219928) (xy 121.419874 -18.219928) (xy 121.419874 -23.219918)
			)
		)
	)
	(zone
		(layer "F.Cu")
		(hatch none 0.5)
		(connect_pads
			(clearance 0)
		)
		(min_thickness 0.25)
		(keepout
			(tracks allowed)
			(vias allowed)
			(pads allowed)
			(copperpour allowed)
			(footprints not_allowed)
		)
		(placement
			(enabled no)
			(sheetname "")
		)
		(fill
			(thermal_gap 0.5)
			(thermal_bridge_width 0.5)
			(island_removal_mode 0)
		)
		(polygon
			(pts
				(arc
					(start 17.964912 -17.999964)
					(mid 25.964896 -9.99998)
					(end 33.96488 -17.999964)
				)
				(arc
					(start 33.96488 -17.999964)
					(mid 25.964896 -25.999948)
					(end 17.964912 -17.999964)
				)
			)
		)
	)
	(zone
		(layer "F.Cu")
		(hatch none 0.5)
		(connect_pads
			(clearance 0)
		)
		(min_thickness 0.25)
		(keepout
			(tracks allowed)
			(vias allowed)
			(pads allowed)
			(copperpour allowed)
			(footprints allowed)
		)
		(placement
			(enabled no)
			(sheetname "")
		)
		(fill
			(thermal_gap 0.5)
			(thermal_bridge_width 0.5)
			(island_removal_mode 0)
		)
		(polygon
			(pts
				(xy 36.564824 -102.224586) (xy 36.564824 -100.873306) (xy 37.844984 -100.873306) (xy 37.844984 -102.224586)
			)
		)
	)
	(zone
		(layer "F.Cu")
		(hatch none 0.5)
		(connect_pads
			(clearance 0)
		)
		(min_thickness 0.25)
		(keepout
			(tracks allowed)
			(vias allowed)
			(pads allowed)
			(copperpour allowed)
			(footprints allowed)
		)
		(placement
			(enabled no)
			(sheetname "")
		)
		(fill
			(thermal_gap 0.5)
			(thermal_bridge_width 0.5)
			(island_removal_mode 0)
		)
		(polygon
			(pts
				(xy 60.484258 -54.008274) (xy 57.56656 -54.008274) (xy 57.35701 -54.217824) (xy 57.35701 -54.830726)
				(xy 60.414408 -54.830726) (xy 60.484258 -54.760876)
			)
		)
	)
	(zone
		(layer "F.Cu")
		(hatch none 0.5)
		(connect_pads
			(clearance 0)
		)
		(min_thickness 0.25)
		(keepout
			(tracks allowed)
			(vias allowed)
			(pads allowed)
			(copperpour allowed)
			(footprints allowed)
		)
		(placement
			(enabled no)
			(sheetname "")
		)
		(fill
			(thermal_gap 0.5)
			(thermal_bridge_width 0.5)
			(island_removal_mode 0)
		)
		(polygon
			(pts
				(xy 175.725836 -344.659458) (xy 174.374556 -344.659458) (xy 174.374556 -343.379298) (xy 175.725836 -343.379298)
			)
		)
	)
	(zone
		(layer "F.Cu")
		(hatch none 0.5)
		(connect_pads
			(clearance 0)
		)
		(min_thickness 0.25)
		(keepout
			(tracks allowed)
			(vias allowed)
			(pads allowed)
			(copperpour allowed)
			(footprints not_allowed)
		)
		(placement
			(enabled no)
			(sheetname "")
		)
		(fill
			(thermal_gap 0.5)
			(thermal_bridge_width 0.5)
			(island_removal_mode 0)
		)
		(polygon
			(pts
				(arc
					(start 241.800126 -194.360038)
					(mid 233.800142 -202.360022)
					(end 225.799904 -194.360038)
				)
				(arc
					(start 225.799904 -194.360038)
					(mid 233.800142 -186.3598)
					(end 241.800126 -194.360038)
				)
			)
		)
	)
	(zone
		(layer "F.Cu")
		(hatch none 0.5)
		(connect_pads
			(clearance 0)
		)
		(min_thickness 0.25)
		(keepout
			(tracks allowed)
			(vias allowed)
			(pads allowed)
			(copperpour allowed)
			(footprints not_allowed)
		)
		(placement
			(enabled no)
			(sheetname "")
		)
		(fill
			(thermal_gap 0.5)
			(thermal_bridge_width 0.5)
			(island_removal_mode 0)
		)
		(polygon
			(pts
				(arc
					(start 440.799982 -84.70011)
					(mid 448.799966 -76.700126)
					(end 456.79995 -84.70011)
				)
				(arc
					(start 456.79995 -84.70011)
					(mid 448.799966 -92.700094)
					(end 440.799982 -84.70011)
				)
			)
		)
	)
	(zone
		(layer "F.Cu")
		(hatch none 0.5)
		(connect_pads
			(clearance 0)
		)
		(min_thickness 0.25)
		(keepout
			(tracks allowed)
			(vias allowed)
			(pads allowed)
			(copperpour allowed)
			(footprints allowed)
		)
		(placement
			(enabled no)
			(sheetname "")
		)
		(fill
			(thermal_gap 0.5)
			(thermal_bridge_width 0.5)
			(island_removal_mode 0)
		)
		(polygon
			(pts
				(xy 234.408218 -86.831932) (xy 234.408218 -87.668862) (xy 234.408218 -88.159336) (xy 234.408472 -88.15959)
				(xy 235.856272 -88.15959) (xy 235.976922 -88.03894) (xy 235.976922 -87.729568) (xy 235.946696 -87.699342)
				(xy 235.946696 -86.854792) (xy 235.863638 -86.771734) (xy 234.468416 -86.771734)
			)
		)
	)
	(zone
		(layer "F.Cu")
		(hatch none 0.5)
		(connect_pads
			(clearance 0)
		)
		(min_thickness 0.25)
		(keepout
			(tracks allowed)
			(vias allowed)
			(pads allowed)
			(copperpour allowed)
			(footprints allowed)
		)
		(placement
			(enabled no)
			(sheetname "")
		)
		(fill
			(thermal_gap 0.5)
			(thermal_bridge_width 0.5)
			(island_removal_mode 0)
		)
		(polygon
			(pts
				(xy 101.47935 -384.326892) (xy 100.64242 -384.326892) (xy 100.151946 -384.326892) (xy 100.151692 -384.327146)
				(xy 100.151692 -385.774946) (xy 100.272342 -385.895596) (xy 100.581714 -385.895596) (xy 100.61194 -385.86537)
				(xy 101.45649 -385.86537) (xy 101.539548 -385.782312) (xy 101.539548 -384.38709)
			)
		)
	)
	(zone
		(layer "F.Cu")
		(hatch none 0.5)
		(connect_pads
			(clearance 0)
		)
		(min_thickness 0.25)
		(keepout
			(tracks allowed)
			(vias allowed)
			(pads allowed)
			(copperpour allowed)
			(footprints allowed)
		)
		(placement
			(enabled no)
			(sheetname "")
		)
		(fill
			(thermal_gap 0.5)
			(thermal_bridge_width 0.5)
			(island_removal_mode 0)
		)
		(polygon
			(pts
				(xy 55.976266 -362.205778) (xy 55.139336 -362.205778) (xy 54.648862 -362.205778) (xy 54.648608 -362.206032)
				(xy 54.648608 -363.653832) (xy 54.769258 -363.774482) (xy 55.07863 -363.774482) (xy 55.108856 -363.744256)
				(xy 55.953406 -363.744256) (xy 56.036464 -363.661198) (xy 56.036464 -362.265976)
			)
		)
	)
	(zone
		(layer "F.Cu")
		(hatch none 0.5)
		(connect_pads
			(clearance 0)
		)
		(min_thickness 0.25)
		(keepout
			(tracks allowed)
			(vias allowed)
			(pads allowed)
			(copperpour allowed)
			(footprints not_allowed)
		)
		(placement
			(enabled no)
			(sheetname "")
		)
		(fill
			(thermal_gap 0.5)
			(thermal_bridge_width 0.5)
			(island_removal_mode 0)
		)
		(polygon
			(pts
				(xy 31.759906 -232.750106) (xy 31.759906 -218.250008) (xy 28.610052 -218.250008) (xy 28.610052 -232.750106)
			)
		)
	)
	(zone
		(layer "F.Cu")
		(hatch none 0.5)
		(connect_pads
			(clearance 0)
		)
		(min_thickness 0.25)
		(keepout
			(tracks allowed)
			(vias allowed)
			(pads allowed)
			(copperpour allowed)
			(footprints allowed)
		)
		(placement
			(enabled no)
			(sheetname "")
		)
		(fill
			(thermal_gap 0.5)
			(thermal_bridge_width 0.5)
			(island_removal_mode 0)
		)
		(polygon
			(pts
				(xy 51.525932 -356.928166) (xy 50.174652 -356.928166) (xy 50.174652 -355.648006) (xy 51.525932 -355.648006)
			)
		)
	)
	(zone
		(layer "F.Cu")
		(hatch none 0.5)
		(connect_pads
			(clearance 0)
		)
		(min_thickness 0.25)
		(keepout
			(tracks allowed)
			(vias allowed)
			(pads allowed)
			(copperpour allowed)
			(footprints not_allowed)
		)
		(placement
			(enabled no)
			(sheetname "")
		)
		(fill
			(thermal_gap 0.5)
			(thermal_bridge_width 0.5)
			(island_removal_mode 0)
		)
		(polygon
			(pts
				(arc
					(start 263.857232 -232.750106)
					(mid 251.898912 -243.750167)
					(end 239.940592 -232.750106)
				)
			)
		)
	)
	(zone
		(layer "F.Cu")
		(hatch none 0.5)
		(connect_pads
			(clearance 0)
		)
		(min_thickness 0.25)
		(keepout
			(tracks allowed)
			(vias allowed)
			(pads allowed)
			(copperpour allowed)
			(footprints allowed)
		)
		(placement
			(enabled no)
			(sheetname "")
		)
		(fill
			(thermal_gap 0.5)
			(thermal_bridge_width 0.5)
			(island_removal_mode 0)
		)
		(polygon
			(pts
				(xy 90.456766 -356.928166) (xy 89.105486 -356.928166) (xy 89.105486 -355.648006) (xy 90.456766 -355.648006)
			)
		)
	)
	(zone
		(layer "F.Cu")
		(hatch none 0.5)
		(connect_pads
			(clearance 0)
		)
		(min_thickness 0.25)
		(keepout
			(tracks allowed)
			(vias allowed)
			(pads allowed)
			(copperpour allowed)
			(footprints allowed)
		)
		(placement
			(enabled no)
			(sheetname "")
		)
		(fill
			(thermal_gap 0.5)
			(thermal_bridge_width 0.5)
			(island_removal_mode 0)
		)
		(polygon
			(pts
				(xy 151.23668 -320.012822) (xy 151.23668 -271.326102) (xy 199.90308 -271.326102) (xy 199.90308 -320.012822)
			)
		)
	)
	(zone
		(layer "F.Cu")
		(hatch none 0.5)
		(connect_pads
			(clearance 0)
		)
		(min_thickness 0.25)
		(keepout
			(tracks allowed)
			(vias allowed)
			(pads allowed)
			(copperpour allowed)
			(footprints allowed)
		)
		(placement
			(enabled no)
			(sheetname "")
		)
		(fill
			(thermal_gap 0.5)
			(thermal_bridge_width 0.5)
			(island_removal_mode 0)
		)
		(polygon
			(pts
				(xy 137.837672 -344.659458) (xy 136.486392 -344.659458) (xy 136.486392 -343.379298) (xy 137.837672 -343.379298)
			)
		)
	)
	(zone
		(layer "F.Cu")
		(hatch none 0.5)
		(connect_pads
			(clearance 0)
		)
		(min_thickness 0.25)
		(keepout
			(tracks allowed)
			(vias allowed)
			(pads allowed)
			(copperpour allowed)
			(footprints allowed)
		)
		(placement
			(enabled no)
			(sheetname "")
		)
		(fill
			(thermal_gap 0.5)
			(thermal_bridge_width 0.5)
			(island_removal_mode 0)
		)
		(polygon
			(pts
				(xy 441.463176 -344.635582) (xy 440.111896 -344.635582) (xy 440.111896 -343.355422) (xy 441.463176 -343.355422)
			)
		)
	)
	(zone
		(layer "F.Cu")
		(hatch none 0.5)
		(connect_pads
			(clearance 0)
		)
		(min_thickness 0.25)
		(keepout
			(tracks allowed)
			(vias allowed)
			(pads allowed)
			(copperpour allowed)
			(footprints allowed)
		)
		(placement
			(enabled no)
			(sheetname "")
		)
		(fill
			(thermal_gap 0.5)
			(thermal_bridge_width 0.5)
			(island_removal_mode 0)
		)
		(polygon
			(pts
				(xy 275.193506 -350.80575) (xy 273.842226 -350.80575) (xy 273.842226 -349.52559) (xy 275.193506 -349.52559)
			)
		)
	)
	(zone
		(layer "F.Cu")
		(hatch none 0.5)
		(connect_pads
			(clearance 0)
		)
		(min_thickness 0.25)
		(keepout
			(tracks allowed)
			(vias allowed)
			(pads allowed)
			(copperpour allowed)
			(footprints allowed)
		)
		(placement
			(enabled no)
			(sheetname "")
		)
		(fill
			(thermal_gap 0.5)
			(thermal_bridge_width 0.5)
			(island_removal_mode 0)
		)
		(polygon
			(pts
				(xy 101.580442 -195.874894) (xy 101.580442 -191.6811) (xy 105.786174 -191.6811) (xy 105.786174 -195.874894)
			)
		)
	)
	(zone
		(layer "F.Cu")
		(hatch none 0.5)
		(connect_pads
			(clearance 0)
		)
		(min_thickness 0.25)
		(keepout
			(tracks not_allowed)
			(vias allowed)
			(pads allowed)
			(copperpour not_allowed)
			(footprints allowed)
		)
		(placement
			(enabled no)
			(sheetname "")
		)
		(fill
			(thermal_gap 0.5)
			(thermal_bridge_width 0.5)
			(island_removal_mode 0)
		)
		(polygon
			(pts
				(arc
					(start 266.349988 -270.89989)
					(mid 261.850124 -275.399754)
					(end 257.350006 -270.89989)
				)
				(arc
					(start 257.350006 -270.89989)
					(mid 261.850124 -266.399772)
					(end 266.349988 -270.89989)
				)
			)
		)
		(polygon
			(pts
				(arc
					(start 264.199878 -270.89989)
					(mid 261.850124 -273.249644)
					(end 259.500116 -270.89989)
				)
				(arc
					(start 259.500116 -270.89989)
					(mid 261.850124 -268.549882)
					(end 264.199878 -270.89989)
				)
			)
		)
	)
	(zone
		(layer "F.Cu")
		(hatch none 0.5)
		(connect_pads
			(clearance 0)
		)
		(min_thickness 0.25)
		(keepout
			(tracks allowed)
			(vias allowed)
			(pads allowed)
			(copperpour allowed)
			(footprints allowed)
		)
		(placement
			(enabled no)
			(sheetname "")
		)
		(fill
			(thermal_gap 0.5)
			(thermal_bridge_width 0.5)
			(island_removal_mode 0)
		)
		(polygon
			(pts
				(xy 435.832504 -35.381946) (xy 437.14289 -35.381946) (xy 437.28005 -35.244786) (xy 437.28005 -27.580082)
				(xy 437.17337 -27.473402) (xy 435.497224 -27.473402) (xy 435.436264 -27.534362) (xy 435.436264 -34.985706)
			)
		)
	)
	(zone
		(layer "F.Cu")
		(hatch none 0.5)
		(connect_pads
			(clearance 0)
		)
		(min_thickness 0.25)
		(keepout
			(tracks allowed)
			(vias allowed)
			(pads allowed)
			(copperpour allowed)
			(footprints allowed)
		)
		(placement
			(enabled no)
			(sheetname "")
		)
		(fill
			(thermal_gap 0.5)
			(thermal_bridge_width 0.5)
			(island_removal_mode 0)
		)
		(polygon
			(pts
				(xy 134.728712 -350.80575) (xy 133.377432 -350.80575) (xy 133.377432 -349.52559) (xy 134.728712 -349.52559)
			)
		)
	)
	(zone
		(layer "F.Cu")
		(hatch none 0.5)
		(connect_pads
			(clearance 0)
		)
		(min_thickness 0.25)
		(keepout
			(tracks not_allowed)
			(vias allowed)
			(pads allowed)
			(copperpour not_allowed)
			(footprints allowed)
		)
		(placement
			(enabled no)
			(sheetname "")
		)
		(fill
			(thermal_gap 0.5)
			(thermal_bridge_width 0.5)
			(island_removal_mode 0)
		)
		(polygon
			(pts
				(arc
					(start 257.350006 -270.89989)
					(mid 261.850124 -266.399772)
					(end 266.349988 -270.89989)
				)
				(arc
					(start 266.349988 -270.89989)
					(mid 261.850124 -275.399754)
					(end 257.350006 -270.89989)
				)
			)
		)
	)
	(zone
		(layer "F.Cu")
		(hatch none 0.5)
		(connect_pads
			(clearance 0)
		)
		(min_thickness 0.25)
		(keepout
			(tracks allowed)
			(vias allowed)
			(pads allowed)
			(copperpour allowed)
			(footprints not_allowed)
		)
		(placement
			(enabled no)
			(sheetname "")
		)
		(fill
			(thermal_gap 0.5)
			(thermal_bridge_width 0.5)
			(island_removal_mode 0)
		)
		(polygon
			(pts
				(xy 383.819908 -23.219918) (xy 383.819908 -18.219928) (xy 379.620018 -18.219928) (xy 379.620018 -23.219918)
			)
		)
	)
	(zone
		(layer "F.Cu")
		(hatch none 0.5)
		(connect_pads
			(clearance 0)
		)
		(min_thickness 0.25)
		(keepout
			(tracks allowed)
			(vias allowed)
			(pads allowed)
			(copperpour allowed)
			(footprints not_allowed)
		)
		(placement
			(enabled no)
			(sheetname "")
		)
		(fill
			(thermal_gap 0.5)
			(thermal_bridge_width 0.5)
			(island_removal_mode 0)
		)
		(polygon
			(pts
				(xy 151.064976 -40.120062) (xy 159.06496 -40.120062) (xy 159.06496 -13.850112) (xy 151.064976 -13.850112)
			)
		)
	)
	(zone
		(layer "F.Cu")
		(hatch none 0.5)
		(connect_pads
			(clearance 0)
		)
		(min_thickness 0.25)
		(keepout
			(tracks not_allowed)
			(vias allowed)
			(pads allowed)
			(copperpour not_allowed)
			(footprints allowed)
		)
		(placement
			(enabled no)
			(sheetname "")
		)
		(fill
			(thermal_gap 0.5)
			(thermal_bridge_width 0.5)
			(island_removal_mode 0)
		)
		(polygon
			(pts
				(arc
					(start 236.599984 -194.360038)
					(mid 233.800142 -197.15988)
					(end 231.000046 -194.360038)
				)
				(arc
					(start 231.000046 -194.360038)
					(mid 233.800142 -191.559942)
					(end 236.599984 -194.360038)
				)
			)
		)
	)
	(zone
		(layer "F.Cu")
		(hatch none 0.5)
		(connect_pads
			(clearance 0)
		)
		(min_thickness 0.25)
		(keepout
			(tracks allowed)
			(vias allowed)
			(pads allowed)
			(copperpour allowed)
			(footprints not_allowed)
		)
		(placement
			(enabled no)
			(sheetname "")
		)
		(fill
			(thermal_gap 0.5)
			(thermal_bridge_width 0.5)
			(island_removal_mode 0)
		)
		(polygon
			(pts
				(xy 100.149914 -258.739894) (xy 100.149914 -278.85009) (xy 132.249926 -278.85009)
				(arc
					(start 132.249926 -276.010116)
					(mid 133.087648 -273.56063)
					(end 135.24992 -272.137124)
				)
				(xy 135.24992 -258.739894) (xy 117.700044 -245.483126)
			)
		)
	)
	(zone
		(layer "F.Cu")
		(hatch none 0.5)
		(connect_pads
			(clearance 0)
		)
		(min_thickness 0.25)
		(keepout
			(tracks allowed)
			(vias allowed)
			(pads allowed)
			(copperpour allowed)
			(footprints allowed)
		)
		(placement
			(enabled no)
			(sheetname "")
		)
		(fill
			(thermal_gap 0.5)
			(thermal_bridge_width 0.5)
			(island_removal_mode 0)
		)
		(polygon
			(pts
				(xy 332.235048 -356.952042) (xy 330.883768 -356.952042) (xy 330.883768 -355.671882) (xy 332.235048 -355.671882)
			)
		)
	)
	(zone
		(layer "F.Cu")
		(hatch none 0.5)
		(connect_pads
			(clearance 0)
		)
		(min_thickness 0.25)
		(keepout
			(tracks allowed)
			(vias allowed)
			(pads allowed)
			(copperpour allowed)
			(footprints allowed)
		)
		(placement
			(enabled no)
			(sheetname "")
		)
		(fill
			(thermal_gap 0.5)
			(thermal_bridge_width 0.5)
			(island_removal_mode 0)
		)
		(polygon
			(pts
				(xy 282.264866 -126.219204) (xy 284.352238 -126.219204) (xy 284.672278 -125.899164) (xy 284.672278 -118.495064)
				(xy 282.32735 -118.495064) (xy 282.249118 -118.573296) (xy 282.249118 -126.203456)
			)
		)
	)
	(zone
		(layer "F.Cu")
		(hatch none 0.5)
		(connect_pads
			(clearance 0)
		)
		(min_thickness 0.25)
		(keepout
			(tracks allowed)
			(vias allowed)
			(pads allowed)
			(copperpour allowed)
			(footprints allowed)
		)
		(placement
			(enabled no)
			(sheetname "")
		)
		(fill
			(thermal_gap 0.5)
			(thermal_bridge_width 0.5)
			(island_removal_mode 0)
		)
		(polygon
			(pts
				(xy 188.779912 -136.909302) (xy 190.867284 -136.909302) (xy 191.187324 -136.589262) (xy 191.187324 -129.185162)
				(xy 188.842396 -129.185162) (xy 188.764164 -129.263394) (xy 188.764164 -136.893554)
			)
		)
	)
	(zone
		(layer "F.Cu")
		(hatch none 0.5)
		(connect_pads
			(clearance 0)
		)
		(min_thickness 0.25)
		(keepout
			(tracks allowed)
			(vias allowed)
			(pads allowed)
			(copperpour allowed)
			(footprints allowed)
		)
		(placement
			(enabled no)
			(sheetname "")
		)
		(fill
			(thermal_gap 0.5)
			(thermal_bridge_width 0.5)
			(island_removal_mode 0)
		)
		(polygon
			(pts
				(xy 198.07809 -149.126194) (xy 198.07809 -147.774914) (xy 199.35825 -147.774914) (xy 199.35825 -149.126194)
			)
		)
	)
	(zone
		(layer "F.Cu")
		(hatch none 0.5)
		(connect_pads
			(clearance 0)
		)
		(min_thickness 0.25)
		(keepout
			(tracks allowed)
			(vias allowed)
			(pads allowed)
			(copperpour allowed)
			(footprints allowed)
		)
		(placement
			(enabled no)
			(sheetname "")
		)
		(fill
			(thermal_gap 0.5)
			(thermal_bridge_width 0.5)
			(island_removal_mode 0)
		)
		(polygon
			(pts
				(xy 225.59772 -307.485288) (xy 226.286314 -307.485288) (xy 226.371912 -307.39969) (xy 226.371912 -306.987448)
				(xy 226.180904 -306.79644) (xy 225.552508 -306.79644) (xy 225.486976 -306.861972) (xy 225.486976 -307.374544)
			)
		)
	)
	(zone
		(layer "F.Cu")
		(hatch none 0.5)
		(connect_pads
			(clearance 0)
		)
		(min_thickness 0.25)
		(keepout
			(tracks allowed)
			(vias allowed)
			(pads allowed)
			(copperpour allowed)
			(footprints allowed)
		)
		(placement
			(enabled no)
			(sheetname "")
		)
		(fill
			(thermal_gap 0.5)
			(thermal_bridge_width 0.5)
			(island_removal_mode 0)
		)
		(polygon
			(pts
				(xy 178.834796 -344.659458) (xy 177.483516 -344.659458) (xy 177.483516 -343.379298) (xy 178.834796 -343.379298)
			)
		)
	)
	(zone
		(layer "F.Cu")
		(hatch none 0.5)
		(connect_pads
			(clearance 0)
		)
		(min_thickness 0.25)
		(keepout
			(tracks allowed)
			(vias allowed)
			(pads allowed)
			(copperpour allowed)
			(footprints allowed)
		)
		(placement
			(enabled no)
			(sheetname "")
		)
		(fill
			(thermal_gap 0.5)
			(thermal_bridge_width 0.5)
			(island_removal_mode 0)
		)
		(polygon
			(pts
				(xy 218.139518 -103.006906) (xy 218.139518 -104.55402) (xy 218.257628 -104.67213) (xy 218.98991 -104.67213)
				(xy 219.273374 -104.388666) (xy 219.273374 -103.03637) (xy 219.24391 -103.006906)
			)
		)
	)
	(zone
		(layer "F.Cu")
		(hatch none 0.5)
		(connect_pads
			(clearance 0)
		)
		(min_thickness 0.25)
		(keepout
			(tracks allowed)
			(vias allowed)
			(pads allowed)
			(copperpour allowed)
			(footprints allowed)
		)
		(placement
			(enabled no)
			(sheetname "")
		)
		(fill
			(thermal_gap 0.5)
			(thermal_bridge_width 0.5)
			(island_removal_mode 0)
		)
		(polygon
			(pts
				(xy 117.892322 -254.354838) (xy 118.885716 -254.354838) (xy 118.997476 -254.243078) (xy 118.997476 -253.67234)
				(xy 118.698264 -253.373128) (xy 117.856254 -253.373128) (xy 117.740684 -253.488698) (xy 117.740684 -254.2032)
			)
		)
	)
	(zone
		(layer "F.Cu")
		(hatch none 0.5)
		(connect_pads
			(clearance 0)
		)
		(min_thickness 0.25)
		(keepout
			(tracks allowed)
			(vias allowed)
			(pads allowed)
			(copperpour allowed)
			(footprints not_allowed)
		)
		(placement
			(enabled no)
			(sheetname "")
		)
		(fill
			(thermal_gap 0.5)
			(thermal_bridge_width 0.5)
			(island_removal_mode 0)
		)
		(polygon
			(pts
				(xy 237.519972 -23.219918) (xy 241.720116 -23.219918) (xy 241.720116 -18.219928) (xy 237.519972 -18.219928)
			)
		)
	)
	(zone
		(layer "F.Cu")
		(hatch none 0.5)
		(connect_pads
			(clearance 0)
		)
		(min_thickness 0.25)
		(keepout
			(tracks allowed)
			(vias allowed)
			(pads allowed)
			(copperpour allowed)
			(footprints not_allowed)
		)
		(placement
			(enabled no)
			(sheetname "")
		)
		(fill
			(thermal_gap 0.5)
			(thermal_bridge_width 0.5)
			(island_removal_mode 0)
		)
		(polygon
			(pts
				(xy 435.820058 -23.219918) (xy 435.820058 -18.219928) (xy 431.619914 -18.219928) (xy 431.619914 -23.219918)
			)
		)
	)
	(zone
		(layer "F.Cu")
		(hatch none 0.5)
		(connect_pads
			(clearance 0)
		)
		(min_thickness 0.25)
		(keepout
			(tracks allowed)
			(vias allowed)
			(pads allowed)
			(copperpour allowed)
			(footprints not_allowed)
		)
		(placement
			(enabled no)
			(sheetname "")
		)
		(fill
			(thermal_gap 0.5)
			(thermal_bridge_width 0.5)
			(island_removal_mode 0)
		)
		(polygon
			(pts
				(xy 136.720072 -18.150078) (xy 136.720072 -13.150088) (xy 132.519928 -13.150088) (xy 132.519928 -18.150078)
			)
		)
	)
	(zone
		(layer "F.Cu")
		(hatch none 0.5)
		(connect_pads
			(clearance 0)
		)
		(min_thickness 0.25)
		(keepout
			(tracks not_allowed)
			(vias allowed)
			(pads allowed)
			(copperpour not_allowed)
			(footprints allowed)
		)
		(placement
			(enabled no)
			(sheetname "")
		)
		(fill
			(thermal_gap 0.5)
			(thermal_bridge_width 0.5)
			(island_removal_mode 0)
		)
		(polygon
			(pts
				(arc
					(start 317.349886 -320.900044)
					(mid 321.850004 -316.399926)
					(end 326.350122 -320.900044)
				)
				(arc
					(start 326.350122 -320.900044)
					(mid 321.850004 -325.400162)
					(end 317.349886 -320.900044)
				)
			)
		)
	)
	(zone
		(layer "F.Cu")
		(hatch none 0.5)
		(connect_pads
			(clearance 0)
		)
		(min_thickness 0.25)
		(keepout
			(tracks allowed)
			(vias allowed)
			(pads allowed)
			(copperpour allowed)
			(footprints allowed)
		)
		(placement
			(enabled no)
			(sheetname "")
		)
		(fill
			(thermal_gap 0.5)
			(thermal_bridge_width 0.5)
			(island_removal_mode 0)
		)
		(polygon
			(pts
				(xy 410.21 -22.606) (xy 410.21 -21.844) (xy 412.877 -21.844) (xy 412.877 -22.606)
			)
		)
	)
	(zone
		(layer "F.Cu")
		(hatch none 0.5)
		(connect_pads
			(clearance 0)
		)
		(min_thickness 0.25)
		(keepout
			(tracks allowed)
			(vias allowed)
			(pads allowed)
			(copperpour allowed)
			(footprints not_allowed)
		)
		(placement
			(enabled no)
			(sheetname "")
		)
		(fill
			(thermal_gap 0.5)
			(thermal_bridge_width 0.5)
			(island_removal_mode 0)
		)
		(polygon
			(pts
				(xy 224.124012 -74.04989) (xy 237.82909 -74.04989) (xy 237.82909 -54.349904) (xy 224.124012 -54.349904)
			)
		)
	)
	(zone
		(layer "F.Cu")
		(hatch none 0.5)
		(connect_pads
			(clearance 0)
		)
		(min_thickness 0.25)
		(keepout
			(tracks allowed)
			(vias allowed)
			(pads allowed)
			(copperpour allowed)
			(footprints allowed)
		)
		(placement
			(enabled no)
			(sheetname "")
		)
		(fill
			(thermal_gap 0.5)
			(thermal_bridge_width 0.5)
			(island_removal_mode 0)
		)
		(polygon
			(pts
				(xy 432.136296 -356.952042) (xy 430.785016 -356.952042) (xy 430.785016 -355.671882) (xy 432.136296 -355.671882)
			)
		)
	)
	(zone
		(layer "F.Cu")
		(hatch none 0.5)
		(connect_pads
			(clearance 0)
		)
		(min_thickness 0.25)
		(keepout
			(tracks allowed)
			(vias allowed)
			(pads allowed)
			(copperpour allowed)
			(footprints allowed)
		)
		(placement
			(enabled no)
			(sheetname "")
		)
		(fill
			(thermal_gap 0.5)
			(thermal_bridge_width 0.5)
			(island_removal_mode 0)
		)
		(polygon
			(pts
				(xy 152.055068 -113.024666) (xy 152.055068 -111.673386) (xy 153.335228 -111.673386) (xy 153.335228 -113.024666)
			)
		)
	)
	(zone
		(layer "F.Cu")
		(hatch none 0.5)
		(connect_pads
			(clearance 0)
		)
		(min_thickness 0.25)
		(keepout
			(tracks allowed)
			(vias allowed)
			(pads allowed)
			(copperpour allowed)
			(footprints not_allowed)
		)
		(placement
			(enabled no)
			(sheetname "")
		)
		(fill
			(thermal_gap 0.5)
			(thermal_bridge_width 0.5)
			(island_removal_mode 0)
		)
		(polygon
			(pts
				(arc
					(start 225.799904 -194.360038)
					(mid 233.800142 -186.3598)
					(end 241.800126 -194.360038)
				)
				(arc
					(start 241.800126 -194.360038)
					(mid 233.800142 -202.360022)
					(end 225.799904 -194.360038)
				)
			)
		)
	)
	(zone
		(layer "F.Cu")
		(hatch none 0.5)
		(connect_pads
			(clearance 0)
		)
		(min_thickness 0.25)
		(keepout
			(tracks allowed)
			(vias allowed)
			(pads allowed)
			(copperpour allowed)
			(footprints allowed)
		)
		(placement
			(enabled no)
			(sheetname "")
		)
		(fill
			(thermal_gap 0.5)
			(thermal_bridge_width 0.5)
			(island_removal_mode 0)
		)
		(polygon
			(pts
				(xy 103.251 -287.02) (xy 108.204 -287.02) (xy 108.458 -286.766) (xy 108.458 -286.004) (xy 108.204 -285.75)
				(xy 107.061 -285.75) (xy 106.807 -285.496) (xy 106.807 -284.861) (xy 107.061 -284.607) (xy 107.569 -284.607)
				(xy 107.696 -284.48) (xy 107.696 -282.829) (xy 107.442 -282.575) (xy 103.505 -282.575) (xy 103.251 -282.829)
			)
		)
	)
	(zone
		(layer "F.Cu")
		(hatch none 0.5)
		(connect_pads
			(clearance 0)
		)
		(min_thickness 0.25)
		(keepout
			(tracks allowed)
			(vias allowed)
			(pads allowed)
			(copperpour allowed)
			(footprints allowed)
		)
		(placement
			(enabled no)
			(sheetname "")
		)
		(fill
			(thermal_gap 0.5)
			(thermal_bridge_width 0.5)
			(island_removal_mode 0)
		)
		(polygon
			(pts
				(xy 381.618744 -356.952042) (xy 380.267464 -356.952042) (xy 380.267464 -355.671882) (xy 381.618744 -355.671882)
			)
		)
	)
	(zone
		(layer "F.Cu")
		(hatch none 0.5)
		(connect_pads
			(clearance 0)
		)
		(min_thickness 0.25)
		(keepout
			(tracks allowed)
			(vias allowed)
			(pads allowed)
			(copperpour allowed)
			(footprints allowed)
		)
		(placement
			(enabled no)
			(sheetname "")
		)
		(fill
			(thermal_gap 0.5)
			(thermal_bridge_width 0.5)
			(island_removal_mode 0)
		)
		(polygon
			(pts
				(xy 276.674072 -126.219204) (xy 278.761444 -126.219204) (xy 279.081484 -125.899164) (xy 279.081484 -118.495064)
				(xy 276.736556 -118.495064) (xy 276.658324 -118.573296) (xy 276.658324 -126.203456)
			)
		)
	)
	(zone
		(layer "F.Cu")
		(hatch none 0.5)
		(connect_pads
			(clearance 0)
		)
		(min_thickness 0.25)
		(keepout
			(tracks not_allowed)
			(vias allowed)
			(pads allowed)
			(copperpour not_allowed)
			(footprints allowed)
		)
		(placement
			(enabled no)
			(sheetname "")
		)
		(fill
			(thermal_gap 0.5)
			(thermal_bridge_width 0.5)
			(island_removal_mode 0)
		)
		(polygon
			(pts
				(arc
					(start 201.250042 -320.900044)
					(mid 205.75016 -316.399926)
					(end 210.250024 -320.900044)
				)
				(arc
					(start 210.250024 -320.900044)
					(mid 205.75016 -325.399908)
					(end 201.250042 -320.900044)
				)
			)
		)
	)
	(zone
		(layer "F.Cu")
		(hatch none 0.5)
		(connect_pads
			(clearance 0)
		)
		(min_thickness 0.25)
		(keepout
			(tracks allowed)
			(vias allowed)
			(pads allowed)
			(copperpour allowed)
			(footprints not_allowed)
		)
		(placement
			(enabled no)
			(sheetname "")
		)
		(fill
			(thermal_gap 0.5)
			(thermal_bridge_width 0.5)
			(island_removal_mode 0)
		)
		(polygon
			(pts
				(xy 203.620116 -23.219918) (xy 203.620116 -18.219928) (xy 199.419972 -18.219928) (xy 199.419972 -23.219918)
			)
		)
	)
	(zone
		(layer "F.Cu")
		(hatch none 0.5)
		(connect_pads
			(clearance 0)
		)
		(min_thickness 0.25)
		(keepout
			(tracks allowed)
			(vias allowed)
			(pads allowed)
			(copperpour allowed)
			(footprints allowed)
		)
		(placement
			(enabled no)
			(sheetname "")
		)
		(fill
			(thermal_gap 0.5)
			(thermal_bridge_width 0.5)
			(island_removal_mode 0)
		)
		(polygon
			(pts
				(xy 45.045884 -139.281662) (xy 46.42358 -139.281662) (xy 46.781466 -138.923776) (xy 46.781466 -132.947664)
				(xy 46.781466 -129.875026) (xy 46.661832 -129.755392) (xy 44.831508 -129.755392) (xy 44.348146 -130.238754)
				(xy 44.348146 -133.30555) (xy 44.348146 -138.583924)
			)
		)
	)
	(zone
		(layer "F.Cu")
		(hatch none 0.5)
		(connect_pads
			(clearance 0)
		)
		(min_thickness 0.25)
		(keepout
			(tracks allowed)
			(vias allowed)
			(pads allowed)
			(copperpour allowed)
			(footprints allowed)
		)
		(placement
			(enabled no)
			(sheetname "")
		)
		(fill
			(thermal_gap 0.5)
			(thermal_bridge_width 0.5)
			(island_removal_mode 0)
		)
		(polygon
			(pts
				(xy 413.507936 -356.952042) (xy 412.156656 -356.952042) (xy 412.156656 -355.671882) (xy 413.507936 -355.671882)
			)
		)
	)
	(zone
		(layer "F.Cu")
		(hatch none 0.5)
		(connect_pads
			(clearance 0)
		)
		(min_thickness 0.25)
		(keepout
			(tracks allowed)
			(vias allowed)
			(pads allowed)
			(copperpour allowed)
			(footprints allowed)
		)
		(placement
			(enabled no)
			(sheetname "")
		)
		(fill
			(thermal_gap 0.5)
			(thermal_bridge_width 0.5)
			(island_removal_mode 0)
		)
		(polygon
			(pts
				(arc
					(start 390.964674 -238.671608)
					(mid 391.000595 -238.686487)
					(end 391.015474 -238.722408)
				)
				(arc
					(start 391.015474 -239.402112)
					(mid 391.000595 -239.438033)
					(end 390.964674 -239.452912)
				)
				(arc
					(start 389.688832 -239.452912)
					(mid 389.652911 -239.438033)
					(end 389.638032 -239.402112)
				)
				(arc
					(start 389.638032 -238.722408)
					(mid 389.652911 -238.686487)
					(end 389.688832 -238.671608)
				)
			)
		)
	)
	(zone
		(layer "F.Cu")
		(hatch none 0.5)
		(connect_pads
			(clearance 0)
		)
		(min_thickness 0.25)
		(keepout
			(tracks allowed)
			(vias allowed)
			(pads allowed)
			(copperpour allowed)
			(footprints allowed)
		)
		(placement
			(enabled no)
			(sheetname "")
		)
		(fill
			(thermal_gap 0.5)
			(thermal_bridge_width 0.5)
			(island_removal_mode 0)
		)
		(polygon
			(pts
				(xy 238.448596 -85.56244) (xy 239.285526 -85.56244) (xy 239.776 -85.56244) (xy 239.776254 -85.562186)
				(xy 239.776254 -84.114386) (xy 239.655604 -83.993736) (xy 239.346232 -83.993736) (xy 239.316006 -84.023962)
				(xy 238.471456 -84.023962) (xy 238.388398 -84.10702) (xy 238.388398 -85.502242)
			)
		)
	)
	(zone
		(layer "F.Cu")
		(hatch none 0.5)
		(connect_pads
			(clearance 0)
		)
		(min_thickness 0.25)
		(keepout
			(tracks allowed)
			(vias allowed)
			(pads allowed)
			(copperpour allowed)
			(footprints allowed)
		)
		(placement
			(enabled no)
			(sheetname "")
		)
		(fill
			(thermal_gap 0.5)
			(thermal_bridge_width 0.5)
			(island_removal_mode 0)
		)
		(polygon
			(pts
				(xy 182.761636 -27.55011) (xy 185.161682 -27.55011) (xy 185.253122 -27.45867) (xy 185.253122 -26.33853)
				(xy 185.192162 -26.27757) (xy 182.746396 -26.27757) (xy 182.624476 -26.39949) (xy 182.624476 -27.41295)
			)
		)
	)
	(zone
		(layer "F.Cu")
		(hatch none 0.5)
		(connect_pads
			(clearance 0)
		)
		(min_thickness 0.25)
		(keepout
			(tracks allowed)
			(vias allowed)
			(pads allowed)
			(copperpour allowed)
			(footprints not_allowed)
		)
		(placement
			(enabled no)
			(sheetname "")
		)
		(fill
			(thermal_gap 0.5)
			(thermal_bridge_width 0.5)
			(island_removal_mode 0)
		)
		(polygon
			(pts
				(xy 403.14753 -165.34511) (xy 403.14753 -90.054938) (xy 388.112508 -90.054938) (xy 388.112508 -165.34511)
			)
		)
	)
	(zone
		(layer "F.Cu")
		(hatch none 0.5)
		(connect_pads
			(clearance 0)
		)
		(min_thickness 0.25)
		(keepout
			(tracks not_allowed)
			(vias allowed)
			(pads allowed)
			(copperpour not_allowed)
			(footprints allowed)
		)
		(placement
			(enabled no)
			(sheetname "")
		)
		(fill
			(thermal_gap 0.5)
			(thermal_bridge_width 0.5)
			(island_removal_mode 0)
		)
		(polygon
			(pts
				(xy 87.520018 -23.219918) (xy 87.520018 -18.219928) (xy 83.319874 -18.219928) (xy 83.319874 -23.219918)
			)
		)
	)
	(zone
		(layer "F.Cu")
		(hatch none 0.5)
		(connect_pads
			(clearance 0)
		)
		(min_thickness 0.25)
		(keepout
			(tracks allowed)
			(vias allowed)
			(pads allowed)
			(copperpour allowed)
			(footprints allowed)
		)
		(placement
			(enabled no)
			(sheetname "")
		)
		(fill
			(thermal_gap 0.5)
			(thermal_bridge_width 0.5)
			(island_removal_mode 0)
		)
		(polygon
			(pts
				(xy 394.054584 -344.659458) (xy 392.703304 -344.659458) (xy 392.703304 -343.379298) (xy 394.054584 -343.379298)
			)
		)
	)
	(zone
		(layer "F.Cu")
		(hatch none 0.5)
		(connect_pads
			(clearance 0)
		)
		(min_thickness 0.25)
		(keepout
			(tracks allowed)
			(vias allowed)
			(pads allowed)
			(copperpour allowed)
			(footprints allowed)
		)
		(placement
			(enabled no)
			(sheetname "")
		)
		(fill
			(thermal_gap 0.5)
			(thermal_bridge_width 0.5)
			(island_removal_mode 0)
		)
		(polygon
			(pts
				(xy 43.109134 -29.354526) (xy 43.109134 -28.003246) (xy 44.389294 -28.003246) (xy 44.389294 -29.354526)
			)
		)
	)
	(zone
		(layer "F.Cu")
		(hatch none 0.5)
		(connect_pads
			(clearance 0)
		)
		(min_thickness 0.25)
		(keepout
			(tracks allowed)
			(vias allowed)
			(pads allowed)
			(copperpour allowed)
			(footprints allowed)
		)
		(placement
			(enabled no)
			(sheetname "")
		)
		(fill
			(thermal_gap 0.5)
			(thermal_bridge_width 0.5)
			(island_removal_mode 0)
		)
		(polygon
			(pts
				(xy 306.63769 -19.7358) (xy 306.63769 -19.2024) (xy 307.70449 -19.2024) (xy 307.70449 -19.7358)
			)
		)
	)
	(zone
		(layer "F.Cu")
		(hatch none 0.5)
		(connect_pads
			(clearance 0)
		)
		(min_thickness 0.25)
		(keepout
			(tracks allowed)
			(vias allowed)
			(pads allowed)
			(copperpour allowed)
			(footprints allowed)
		)
		(placement
			(enabled no)
			(sheetname "")
		)
		(fill
			(thermal_gap 0.5)
			(thermal_bridge_width 0.5)
			(island_removal_mode 0)
		)
		(polygon
			(pts
				(arc
					(start 261.317232 -76.308966)
					(mid 261.332111 -76.273045)
					(end 261.368032 -76.258166)
				)
				(arc
					(start 262.94842 -76.258166)
					(mid 262.984341 -76.273045)
					(end 262.99922 -76.308966)
				)
				(arc
					(start 262.99922 -77.104748)
					(mid 262.984341 -77.140669)
					(end 262.94842 -77.155548)
				)
				(arc
					(start 261.368032 -77.155548)
					(mid 261.332111 -77.140669)
					(end 261.317232 -77.104748)
				)
			)
		)
	)
	(zone
		(layer "F.Cu")
		(hatch none 0.5)
		(connect_pads
			(clearance 0)
		)
		(min_thickness 0.25)
		(keepout
			(tracks allowed)
			(vias allowed)
			(pads allowed)
			(copperpour allowed)
			(footprints allowed)
		)
		(placement
			(enabled no)
			(sheetname "")
		)
		(fill
			(thermal_gap 0.5)
			(thermal_bridge_width 0.5)
			(island_removal_mode 0)
		)
		(polygon
			(pts
				(xy 281.411426 -356.952042) (xy 280.060146 -356.952042) (xy 280.060146 -355.671882) (xy 281.411426 -355.671882)
			)
		)
	)
	(zone
		(layer "F.Cu")
		(hatch none 0.5)
		(connect_pads
			(clearance 0)
		)
		(min_thickness 0.25)
		(keepout
			(tracks allowed)
			(vias allowed)
			(pads allowed)
			(copperpour allowed)
			(footprints allowed)
		)
		(placement
			(enabled no)
			(sheetname "")
		)
		(fill
			(thermal_gap 0.5)
			(thermal_bridge_width 0.5)
			(island_removal_mode 0)
		)
		(polygon
			(pts
				(xy 44.897548 -113.527078) (xy 46.70806 -113.527078) (xy 46.754542 -113.480596) (xy 46.754542 -98.737674)
				(xy 46.609254 -98.592386) (xy 44.857162 -98.592386) (xy 44.781724 -98.667824) (xy 44.781724 -113.411254)
			)
		)
	)
	(zone
		(layer "F.Cu")
		(hatch none 0.5)
		(connect_pads
			(clearance 0)
		)
		(min_thickness 0.25)
		(keepout
			(tracks allowed)
			(vias allowed)
			(pads allowed)
			(copperpour allowed)
			(footprints allowed)
		)
		(placement
			(enabled no)
			(sheetname "")
		)
		(fill
			(thermal_gap 0.5)
			(thermal_bridge_width 0.5)
			(island_removal_mode 0)
		)
		(polygon
			(pts
				(xy 46.991524 -52.800758) (xy 46.991524 -55.718456) (xy 47.201074 -55.928006) (xy 47.813976 -55.928006)
				(xy 47.813976 -52.870608) (xy 47.744126 -52.800758)
			)
		)
	)
	(zone
		(layer "F.Cu")
		(hatch none 0.5)
		(connect_pads
			(clearance 0)
		)
		(min_thickness 0.25)
		(keepout
			(tracks allowed)
			(vias allowed)
			(pads allowed)
			(copperpour allowed)
			(footprints not_allowed)
		)
		(placement
			(enabled no)
			(sheetname "")
		)
		(fill
			(thermal_gap 0.5)
			(thermal_bridge_width 0.5)
			(island_removal_mode 0)
		)
		(polygon
			(pts
				(xy 5.32003 -23.219918) (xy 9.51992 -23.219918) (xy 9.51992 -18.219928) (xy 5.32003 -18.219928)
			)
		)
	)
	(zone
		(layer "F.Cu")
		(hatch none 0.5)
		(connect_pads
			(clearance 0)
		)
		(min_thickness 0.25)
		(keepout
			(tracks allowed)
			(vias allowed)
			(pads allowed)
			(copperpour allowed)
			(footprints allowed)
		)
		(placement
			(enabled no)
			(sheetname "")
		)
		(fill
			(thermal_gap 0.5)
			(thermal_bridge_width 0.5)
			(island_removal_mode 0)
		)
		(polygon
			(pts
				(xy 230.040688 -59.03976) (xy 227.640642 -59.03976) (xy 227.549202 -59.1312) (xy 227.549202 -60.25134)
				(xy 227.610162 -60.3123) (xy 230.055928 -60.3123) (xy 230.177848 -60.19038) (xy 230.177848 -59.17692)
			)
		)
	)
	(zone
		(layer "F.Cu")
		(hatch none 0.5)
		(connect_pads
			(clearance 0)
		)
		(min_thickness 0.25)
		(keepout
			(tracks allowed)
			(vias allowed)
			(pads allowed)
			(copperpour allowed)
			(footprints allowed)
		)
		(placement
			(enabled no)
			(sheetname "")
		)
		(fill
			(thermal_gap 0.5)
			(thermal_bridge_width 0.5)
			(island_removal_mode 0)
		)
		(polygon
			(pts
				(xy 362.788708 -35.519868) (xy 364.617 -35.519868) (xy 364.853474 -35.283394) (xy 364.853474 -26.930096)
				(xy 364.617 -26.693622) (xy 362.96092 -26.693622) (xy 362.788708 -26.865834)
			)
		)
	)
	(zone
		(layer "F.Cu")
		(hatch none 0.5)
		(connect_pads
			(clearance 0)
		)
		(min_thickness 0.25)
		(keepout
			(tracks allowed)
			(vias allowed)
			(pads allowed)
			(copperpour allowed)
			(footprints not_allowed)
		)
		(placement
			(enabled no)
			(sheetname "")
		)
		(fill
			(thermal_gap 0.5)
			(thermal_bridge_width 0.5)
			(island_removal_mode 0)
		)
		(polygon
			(pts
				(xy 278.820118 -18.150078) (xy 278.820118 -13.150088) (xy 274.619974 -13.150088) (xy 274.619974 -18.150078)
			)
		)
	)
	(zone
		(layer "F.Cu")
		(hatch none 0.5)
		(connect_pads
			(clearance 0)
		)
		(min_thickness 0.25)
		(keepout
			(tracks allowed)
			(vias allowed)
			(pads allowed)
			(copperpour allowed)
			(footprints allowed)
		)
		(placement
			(enabled no)
			(sheetname "")
		)
		(fill
			(thermal_gap 0.5)
			(thermal_bridge_width 0.5)
			(island_removal_mode 0)
		)
		(polygon
			(pts
				(xy 319.799208 -350.80575) (xy 318.447928 -350.80575) (xy 318.447928 -349.52559) (xy 319.799208 -349.52559)
			)
		)
	)
	(zone
		(layer "F.Cu")
		(hatch none 0.5)
		(connect_pads
			(clearance 0)
		)
		(min_thickness 0.25)
		(keepout
			(tracks allowed)
			(vias allowed)
			(pads allowed)
			(copperpour allowed)
			(footprints allowed)
		)
		(placement
			(enabled no)
			(sheetname "")
		)
		(fill
			(thermal_gap 0.5)
			(thermal_bridge_width 0.5)
			(island_removal_mode 0)
		)
		(polygon
			(pts
				(xy 311.53608 -154.51963) (xy 311.53608 -153.16835) (xy 312.81624 -153.16835) (xy 312.81624 -154.51963)
			)
		)
	)
	(zone
		(layer "F.Cu")
		(hatch none 0.5)
		(connect_pads
			(clearance 0)
		)
		(min_thickness 0.25)
		(keepout
			(tracks allowed)
			(vias allowed)
			(pads allowed)
			(copperpour allowed)
			(footprints allowed)
		)
		(placement
			(enabled no)
			(sheetname "")
		)
		(fill
			(thermal_gap 0.5)
			(thermal_bridge_width 0.5)
			(island_removal_mode 0)
		)
		(polygon
			(pts
				(xy 268.764766 -102.224586) (xy 268.764766 -100.873306) (xy 270.044926 -100.873306) (xy 270.044926 -102.224586)
			)
		)
	)
	(zone
		(layer "F.Cu")
		(hatch none 0.5)
		(connect_pads
			(clearance 0)
		)
		(min_thickness 0.25)
		(keepout
			(tracks allowed)
			(vias allowed)
			(pads allowed)
			(copperpour allowed)
			(footprints allowed)
		)
		(placement
			(enabled no)
			(sheetname "")
		)
		(fill
			(thermal_gap 0.5)
			(thermal_bridge_width 0.5)
			(island_removal_mode 0)
		)
		(polygon
			(pts
				(xy 50.064924 -126.219204) (xy 52.152296 -126.219204) (xy 52.472336 -125.899164) (xy 52.472336 -118.495064)
				(xy 50.127408 -118.495064) (xy 50.049176 -118.573296) (xy 50.049176 -126.203456)
			)
		)
	)
	(zone
		(layer "F.Cu")
		(hatch none 0.5)
		(connect_pads
			(clearance 0)
		)
		(min_thickness 0.25)
		(keepout
			(tracks not_allowed)
			(vias allowed)
			(pads allowed)
			(copperpour not_allowed)
			(footprints allowed)
		)
		(placement
			(enabled no)
			(sheetname "")
		)
		(fill
			(thermal_gap 0.5)
			(thermal_bridge_width 0.5)
			(island_removal_mode 0)
		)
		(polygon
			(pts
				(arc
					(start 228.91496 -5.999988)
					(mid 226.115118 -8.79983)
					(end 223.315022 -5.999988)
				)
				(arc
					(start 223.315022 -5.999988)
					(mid 226.115118 -3.199892)
					(end 228.91496 -5.999988)
				)
			)
		)
	)
	(zone
		(layer "F.Cu")
		(hatch none 0.5)
		(connect_pads
			(clearance 0)
		)
		(min_thickness 0.25)
		(keepout
			(tracks allowed)
			(vias allowed)
			(pads allowed)
			(copperpour allowed)
			(footprints allowed)
		)
		(placement
			(enabled no)
			(sheetname "")
		)
		(fill
			(thermal_gap 0.5)
			(thermal_bridge_width 0.5)
			(island_removal_mode 0)
		)
		(polygon
			(pts
				(arc
					(start 235.92536 -90.24747)
					(mid 235.940239 -90.211549)
					(end 235.97616 -90.19667)
				)
				(arc
					(start 237.551722 -90.19667)
					(mid 237.587643 -90.211549)
					(end 237.602522 -90.24747)
				)
				(arc
					(start 237.602522 -92.411042)
					(mid 237.587643 -92.446963)
					(end 237.551722 -92.461842)
				)
				(arc
					(start 235.97616 -92.461842)
					(mid 235.940239 -92.446963)
					(end 235.92536 -92.411042)
				)
			)
		)
	)
	(zone
		(layer "F.Cu")
		(hatch none 0.5)
		(connect_pads
			(clearance 0)
		)
		(min_thickness 0.25)
		(keepout
			(tracks not_allowed)
			(vias allowed)
			(pads allowed)
			(copperpour not_allowed)
			(footprints allowed)
		)
		(placement
			(enabled no)
			(sheetname "")
		)
		(fill
			(thermal_gap 0.5)
			(thermal_bridge_width 0.5)
			(island_removal_mode 0)
		)
		(polygon
			(pts
				(arc
					(start 365.590074 -407.599896)
					(mid 363.590078 -409.599892)
					(end 361.590082 -407.599896)
				)
				(arc
					(start 361.590082 -407.599896)
					(mid 363.590078 -405.5999)
					(end 365.590074 -407.599896)
				)
			)
		)
	)
	(zone
		(layer "F.Cu")
		(hatch none 0.5)
		(connect_pads
			(clearance 0)
		)
		(min_thickness 0.25)
		(keepout
			(tracks allowed)
			(vias allowed)
			(pads allowed)
			(copperpour allowed)
			(footprints not_allowed)
		)
		(placement
			(enabled no)
			(sheetname "")
		)
		(fill
			(thermal_gap 0.5)
			(thermal_bridge_width 0.5)
			(island_removal_mode 0)
		)
		(polygon
			(pts
				(arc
					(start 125.700028 -194.360038)
					(mid 117.700044 -202.360022)
					(end 109.70006 -194.360038)
				)
				(arc
					(start 109.70006 -194.360038)
					(mid 117.700044 -186.360054)
					(end 125.700028 -194.360038)
				)
			)
		)
	)
	(zone
		(layer "F.Cu")
		(hatch none 0.5)
		(connect_pads
			(clearance 0)
		)
		(min_thickness 0.25)
		(keepout
			(tracks allowed)
			(vias allowed)
			(pads allowed)
			(copperpour allowed)
			(footprints allowed)
		)
		(placement
			(enabled no)
			(sheetname "")
		)
		(fill
			(thermal_gap 0.5)
			(thermal_bridge_width 0.5)
			(island_removal_mode 0)
		)
		(polygon
			(pts
				(xy 330.959968 -46.986444) (xy 331.952346 -46.986444) (xy 332.037182 -46.901608) (xy 332.037182 -46.211744)
				(xy 331.989176 -46.163738) (xy 330.939902 -46.163738) (xy 330.872084 -46.231556) (xy 330.872084 -46.89856)
			)
		)
	)
	(zone
		(layer "F.Cu")
		(hatch none 0.5)
		(connect_pads
			(clearance 0)
		)
		(min_thickness 0.25)
		(keepout
			(tracks allowed)
			(vias allowed)
			(pads allowed)
			(copperpour allowed)
			(footprints not_allowed)
		)
		(placement
			(enabled no)
			(sheetname "")
		)
		(fill
			(thermal_gap 0.5)
			(thermal_bridge_width 0.5)
			(island_removal_mode 0)
		)
		(polygon
			(pts
				(arc
					(start 443.799976 -194.360038)
					(mid 451.79996 -186.360054)
					(end 459.799944 -194.360038)
				)
				(arc
					(start 459.799944 -194.360038)
					(mid 451.79996 -202.360022)
					(end 443.799976 -194.360038)
				)
			)
		)
	)
	(zone
		(layer "F.Cu")
		(hatch none 0.5)
		(connect_pads
			(clearance 0)
		)
		(min_thickness 0.25)
		(keepout
			(tracks allowed)
			(vias allowed)
			(pads allowed)
			(copperpour allowed)
			(footprints allowed)
		)
		(placement
			(enabled no)
			(sheetname "")
		)
		(fill
			(thermal_gap 0.5)
			(thermal_bridge_width 0.5)
			(island_removal_mode 0)
		)
		(polygon
			(pts
				(xy 160.997392 -113.527078) (xy 162.807904 -113.527078) (xy 162.854386 -113.480596) (xy 162.854386 -98.737674)
				(xy 162.709098 -98.592386) (xy 160.957006 -98.592386) (xy 160.881568 -98.667824) (xy 160.881568 -113.411254)
			)
		)
	)
	(zone
		(layer "F.Cu")
		(hatch none 0.5)
		(connect_pads
			(clearance 0)
		)
		(min_thickness 0.25)
		(keepout
			(tracks not_allowed)
			(vias allowed)
			(pads allowed)
			(copperpour not_allowed)
			(footprints allowed)
		)
		(placement
			(enabled no)
			(sheetname "")
		)
		(fill
			(thermal_gap 0.5)
			(thermal_bridge_width 0.5)
			(island_removal_mode 0)
		)
		(polygon
			(pts
				(arc
					(start 108.015024 -17.999964)
					(mid 110.01502 -15.999968)
					(end 112.015016 -17.999964)
				)
				(arc
					(start 112.015016 -17.999964)
					(mid 110.01502 -19.99996)
					(end 108.015024 -17.999964)
				)
			)
		)
	)
	(zone
		(layer "F.Cu")
		(hatch none 0.5)
		(connect_pads
			(clearance 0)
		)
		(min_thickness 0.25)
		(keepout
			(tracks allowed)
			(vias allowed)
			(pads allowed)
			(copperpour allowed)
			(footprints allowed)
		)
		(placement
			(enabled no)
			(sheetname "")
		)
		(fill
			(thermal_gap 0.5)
			(thermal_bridge_width 0.5)
			(island_removal_mode 0)
		)
		(polygon
			(pts
				(xy 293.847266 -356.952042) (xy 292.495986 -356.952042) (xy 292.495986 -355.671882) (xy 293.847266 -355.671882)
			)
		)
	)
	(zone
		(layer "F.Cu")
		(hatch none 0.5)
		(connect_pads
			(clearance 0)
		)
		(min_thickness 0.25)
		(keepout
			(tracks not_allowed)
			(vias allowed)
			(pads allowed)
			(copperpour not_allowed)
			(footprints allowed)
		)
		(placement
			(enabled no)
			(sheetname "")
		)
		(fill
			(thermal_gap 0.5)
			(thermal_bridge_width 0.5)
			(island_removal_mode 0)
		)
		(polygon
			(pts
				(arc
					(start 249.100086 -297.369992)
					(mid 252.350016 -294.120062)
					(end 255.599946 -297.369992)
				)
				(arc
					(start 255.599946 -297.369992)
					(mid 252.350016 -300.619922)
					(end 249.100086 -297.369992)
				)
			)
		)
	)
	(zone
		(layer "F.Cu")
		(hatch none 0.5)
		(connect_pads
			(clearance 0)
		)
		(min_thickness 0.25)
		(keepout
			(tracks allowed)
			(vias allowed)
			(pads allowed)
			(copperpour allowed)
			(footprints allowed)
		)
		(placement
			(enabled no)
			(sheetname "")
		)
		(fill
			(thermal_gap 0.5)
			(thermal_bridge_width 0.5)
			(island_removal_mode 0)
		)
		(polygon
			(pts
				(xy 422.809416 -344.659458) (xy 421.458136 -344.659458) (xy 421.458136 -343.379298) (xy 422.809416 -343.379298)
			)
		)
	)
	(zone
		(layer "F.Cu")
		(hatch none 0.5)
		(connect_pads
			(clearance 0)
		)
		(min_thickness 0.25)
		(keepout
			(tracks not_allowed)
			(vias allowed)
			(pads allowed)
			(copperpour not_allowed)
			(footprints allowed)
		)
		(placement
			(enabled no)
			(sheetname "")
		)
		(fill
			(thermal_gap 0.5)
			(thermal_bridge_width 0.5)
			(island_removal_mode 0)
		)
		(polygon
			(pts
				(arc
					(start 365.19993 -276.010116)
					(mid 368.450114 -272.759932)
					(end 371.700044 -276.010116)
				)
				(arc
					(start 371.700044 -276.010116)
					(mid 368.450114 -279.260046)
					(end 365.19993 -276.010116)
				)
			)
		)
	)
	(zone
		(layer "F.Cu")
		(hatch none 0.5)
		(connect_pads
			(clearance 0)
		)
		(min_thickness 0.25)
		(keepout
			(tracks not_allowed)
			(vias allowed)
			(pads allowed)
			(copperpour not_allowed)
			(footprints allowed)
		)
		(placement
			(enabled no)
			(sheetname "")
		)
		(fill
			(thermal_gap 0.5)
			(thermal_bridge_width 0.5)
			(island_removal_mode 0)
		)
		(polygon
			(pts
				(xy 72.620124 -18.150078) (xy 72.620124 -13.150088) (xy 68.41998 -13.150088) (xy 68.41998 -18.150078)
			)
		)
	)
	(zone
		(layer "F.Cu")
		(hatch none 0.5)
		(connect_pads
			(clearance 0)
		)
		(min_thickness 0.25)
		(keepout
			(tracks allowed)
			(vias allowed)
			(pads allowed)
			(copperpour allowed)
			(footprints allowed)
		)
		(placement
			(enabled no)
			(sheetname "")
		)
		(fill
			(thermal_gap 0.5)
			(thermal_bridge_width 0.5)
			(island_removal_mode 0)
		)
		(polygon
			(pts
				(xy 277.951184 -34.76117) (xy 277.951184 -33.40989) (xy 279.231344 -33.40989) (xy 279.231344 -34.76117)
			)
		)
	)
	(zone
		(layer "F.Cu")
		(hatch none 0.5)
		(connect_pads
			(clearance 0)
		)
		(min_thickness 0.25)
		(keepout
			(tracks allowed)
			(vias allowed)
			(pads allowed)
			(copperpour allowed)
			(footprints allowed)
		)
		(placement
			(enabled no)
			(sheetname "")
		)
		(fill
			(thermal_gap 0.5)
			(thermal_bridge_width 0.5)
			(island_removal_mode 0)
		)
		(polygon
			(pts
				(xy 456.25512 -307.588412) (xy 456.943714 -307.588412) (xy 457.029312 -307.502814) (xy 457.029312 -307.090572)
				(xy 456.838304 -306.899564) (xy 456.209908 -306.899564) (xy 456.144376 -306.965096) (xy 456.144376 -307.477668)
			)
		)
	)
	(zone
		(layer "F.Cu")
		(hatch none 0.5)
		(connect_pads
			(clearance 0)
		)
		(min_thickness 0.25)
		(keepout
			(tracks allowed)
			(vias allowed)
			(pads allowed)
			(copperpour allowed)
			(footprints not_allowed)
		)
		(placement
			(enabled no)
			(sheetname "")
		)
		(fill
			(thermal_gap 0.5)
			(thermal_bridge_width 0.5)
			(island_removal_mode 0)
		)
		(polygon
			(pts
				(xy 444.139828 -361.790234) (xy 415.03981 -361.790234) (xy 415.03981 -417.58997) (xy 444.139828 -417.58997)
			)
		)
	)
	(zone
		(layer "F.Cu")
		(hatch none 0.5)
		(connect_pads
			(clearance 0)
		)
		(min_thickness 0.25)
		(keepout
			(tracks allowed)
			(vias allowed)
			(pads allowed)
			(copperpour allowed)
			(footprints allowed)
		)
		(placement
			(enabled no)
			(sheetname "")
		)
		(fill
			(thermal_gap 0.5)
			(thermal_bridge_width 0.5)
			(island_removal_mode 0)
		)
		(polygon
			(pts
				(xy 8.634222 -265.681714) (xy 8.634222 -263.532874) (xy 10.267442 -263.532874) (xy 10.267442 -265.681714)
			)
		)
	)
	(zone
		(layer "F.Cu")
		(hatch none 0.5)
		(connect_pads
			(clearance 0)
		)
		(min_thickness 0.25)
		(keepout
			(tracks allowed)
			(vias allowed)
			(pads allowed)
			(copperpour allowed)
			(footprints allowed)
		)
		(placement
			(enabled no)
			(sheetname "")
		)
		(fill
			(thermal_gap 0.5)
			(thermal_bridge_width 0.5)
			(island_removal_mode 0)
		)
		(polygon
			(pts
				(xy 188.161676 -344.659458) (xy 186.810396 -344.659458) (xy 186.810396 -343.379298) (xy 188.161676 -343.379298)
			)
		)
	)
	(zone
		(layer "F.Cu")
		(hatch none 0.5)
		(connect_pads
			(clearance 0)
		)
		(min_thickness 0.25)
		(keepout
			(tracks allowed)
			(vias allowed)
			(pads allowed)
			(copperpour allowed)
			(footprints allowed)
		)
		(placement
			(enabled no)
			(sheetname "")
		)
		(fill
			(thermal_gap 0.5)
			(thermal_bridge_width 0.5)
			(island_removal_mode 0)
		)
		(polygon
			(pts
				(xy 65.585086 -350.80575) (xy 64.233806 -350.80575) (xy 64.233806 -349.52559) (xy 65.585086 -349.52559)
			)
		)
	)
	(zone
		(layer "F.Cu")
		(hatch none 0.5)
		(connect_pads
			(clearance 0)
		)
		(min_thickness 0.25)
		(keepout
			(tracks allowed)
			(vias allowed)
			(pads allowed)
			(copperpour allowed)
			(footprints allowed)
		)
		(placement
			(enabled no)
			(sheetname "")
		)
		(fill
			(thermal_gap 0.5)
			(thermal_bridge_width 0.5)
			(island_removal_mode 0)
		)
		(polygon
			(pts
				(xy 185.052716 -356.90429) (xy 183.701436 -356.90429) (xy 183.701436 -355.62413) (xy 185.052716 -355.62413)
			)
		)
	)
	(zone
		(layer "F.Cu")
		(hatch none 0.5)
		(connect_pads
			(clearance 0)
		)
		(min_thickness 0.25)
		(keepout
			(tracks not_allowed)
			(vias allowed)
			(pads allowed)
			(copperpour not_allowed)
			(footprints allowed)
		)
		(placement
			(enabled no)
			(sheetname "")
		)
		(fill
			(thermal_gap 0.5)
			(thermal_bridge_width 0.5)
			(island_removal_mode 0)
		)
		(polygon
			(pts
				(arc
					(start 317.349886 -270.89989)
					(mid 321.850004 -266.399772)
					(end 326.350122 -270.89989)
				)
				(arc
					(start 326.350122 -270.89989)
					(mid 321.850004 -275.400008)
					(end 317.349886 -270.89989)
				)
			)
		)
	)
	(zone
		(layer "F.Cu")
		(hatch none 0.5)
		(connect_pads
			(clearance 0)
		)
		(min_thickness 0.25)
		(keepout
			(tracks allowed)
			(vias allowed)
			(pads allowed)
			(copperpour allowed)
			(footprints allowed)
		)
		(placement
			(enabled no)
			(sheetname "")
		)
		(fill
			(thermal_gap 0.5)
			(thermal_bridge_width 0.5)
			(island_removal_mode 0)
		)
		(polygon
			(pts
				(xy 322.908168 -350.80575) (xy 321.556888 -350.80575) (xy 321.556888 -349.52559) (xy 322.908168 -349.52559)
			)
		)
	)
	(zone
		(layer "F.Cu")
		(hatch none 0.5)
		(connect_pads
			(clearance 0)
		)
		(min_thickness 0.25)
		(keepout
			(tracks allowed)
			(vias allowed)
			(pads allowed)
			(copperpour allowed)
			(footprints allowed)
		)
		(placement
			(enabled no)
			(sheetname "")
		)
		(fill
			(thermal_gap 0.5)
			(thermal_bridge_width 0.5)
			(island_removal_mode 0)
		)
		(polygon
			(pts
				(xy 163.289996 -356.928166) (xy 161.938716 -356.928166) (xy 161.938716 -355.648006) (xy 163.289996 -355.648006)
			)
		)
	)
	(zone
		(layer "F.Cu")
		(hatch none 0.5)
		(connect_pads
			(clearance 0)
		)
		(min_thickness 0.25)
		(keepout
			(tracks allowed)
			(vias allowed)
			(pads allowed)
			(copperpour allowed)
			(footprints allowed)
		)
		(placement
			(enabled no)
			(sheetname "")
		)
		(fill
			(thermal_gap 0.5)
			(thermal_bridge_width 0.5)
			(island_removal_mode 0)
		)
		(polygon
			(pts
				(xy 427.636178 -150.919434) (xy 427.636178 -149.568154) (xy 428.916338 -149.568154) (xy 428.916338 -150.919434)
			)
		)
	)
	(zone
		(layer "F.Cu")
		(hatch none 0.5)
		(connect_pads
			(clearance 0)
		)
		(min_thickness 0.25)
		(keepout
			(tracks allowed)
			(vias allowed)
			(pads allowed)
			(copperpour allowed)
			(footprints allowed)
		)
		(placement
			(enabled no)
			(sheetname "")
		)
		(fill
			(thermal_gap 0.5)
			(thermal_bridge_width 0.5)
			(island_removal_mode 0)
		)
		(polygon
			(pts
				(xy 354.014024 -314.64123) (xy 352.363024 -314.64123) (xy 352.363024 -312.60923) (xy 354.014024 -312.60923)
			)
		)
	)
	(zone
		(layer "F.Cu")
		(hatch none 0.5)
		(connect_pads
			(clearance 0)
		)
		(min_thickness 0.25)
		(keepout
			(tracks allowed)
			(vias allowed)
			(pads allowed)
			(copperpour allowed)
			(footprints allowed)
		)
		(placement
			(enabled no)
			(sheetname "")
		)
		(fill
			(thermal_gap 0.5)
			(thermal_bridge_width 0.5)
			(island_removal_mode 0)
		)
		(polygon
			(pts
				(xy 408.784298 -54.008274) (xy 405.8666 -54.008274) (xy 405.65705 -54.217824) (xy 405.65705 -54.830726)
				(xy 408.714448 -54.830726) (xy 408.784298 -54.760876)
			)
		)
	)
	(zone
		(layer "F.Cu")
		(hatch none 0.5)
		(connect_pads
			(clearance 0)
		)
		(min_thickness 0.25)
		(keepout
			(tracks allowed)
			(vias allowed)
			(pads allowed)
			(copperpour allowed)
			(footprints not_allowed)
		)
		(placement
			(enabled no)
			(sheetname "")
		)
		(fill
			(thermal_gap 0.5)
			(thermal_bridge_width 0.5)
			(island_removal_mode 0)
		)
		(polygon
			(pts
				(arc
					(start 447.432176 -201.062336)
					(mid 444.476415 -213.189302)
					(end 454.754996 -220.270832)
				)
				(arc
					(start 454.754996 -201.794364)
					(mid 451.004421 -202.320355)
					(end 447.432176 -201.062336)
				)
			)
		)
	)
	(zone
		(layer "F.Cu")
		(hatch none 0.5)
		(connect_pads
			(clearance 0)
		)
		(min_thickness 0.25)
		(keepout
			(tracks allowed)
			(vias allowed)
			(pads allowed)
			(copperpour allowed)
			(footprints allowed)
		)
		(placement
			(enabled no)
			(sheetname "")
		)
		(fill
			(thermal_gap 0.5)
			(thermal_bridge_width 0.5)
			(island_removal_mode 0)
		)
		(polygon
			(pts
				(xy 383.852674 -35.313366) (xy 385.04876 -35.313366) (xy 385.193286 -35.16884) (xy 385.193286 -27.442922)
				(xy 383.59334 -27.442922) (xy 383.2733 -27.762962) (xy 383.2733 -34.733992)
			)
		)
	)
	(zone
		(layer "F.Cu")
		(hatch none 0.5)
		(connect_pads
			(clearance 0)
		)
		(min_thickness 0.25)
		(keepout
			(tracks allowed)
			(vias allowed)
			(pads allowed)
			(copperpour allowed)
			(footprints allowed)
		)
		(placement
			(enabled no)
			(sheetname "")
		)
		(fill
			(thermal_gap 0.5)
			(thermal_bridge_width 0.5)
			(island_removal_mode 0)
		)
		(polygon
			(pts
				(xy 89.874598 -101.405182) (xy 90.333068 -101.405182) (xy 90.368882 -101.369368) (xy 90.368882 -100.820982)
				(xy 90.207084 -100.659184) (xy 89.847674 -100.659184) (xy 89.7128 -100.794058) (xy 89.7128 -101.243384)
			)
		)
	)
	(zone
		(layer "F.Cu")
		(hatch none 0.5)
		(connect_pads
			(clearance 0)
		)
		(min_thickness 0.25)
		(keepout
			(tracks not_allowed)
			(vias allowed)
			(pads allowed)
			(copperpour not_allowed)
			(footprints allowed)
		)
		(placement
			(enabled no)
			(sheetname "")
		)
		(fill
			(thermal_gap 0.5)
			(thermal_bridge_width 0.5)
			(island_removal_mode 0)
		)
		(polygon
			(pts
				(arc
					(start 99.009962 -407.599896)
					(mid 104.009952 -402.599906)
					(end 109.009942 -407.599896)
				)
				(arc
					(start 109.009942 -407.599896)
					(mid 104.009952 -412.599886)
					(end 99.009962 -407.599896)
				)
			)
		)
	)
	(zone
		(layer "F.Cu")
		(hatch none 0.5)
		(connect_pads
			(clearance 0)
		)
		(min_thickness 0.25)
		(keepout
			(tracks not_allowed)
			(vias allowed)
			(pads allowed)
			(copperpour not_allowed)
			(footprints allowed)
		)
		(placement
			(enabled no)
			(sheetname "")
		)
		(fill
			(thermal_gap 0.5)
			(thermal_bridge_width 0.5)
			(island_removal_mode 0)
		)
		(polygon
			(pts
				(arc
					(start 366.38992 -407.599896)
					(mid 363.590078 -410.399738)
					(end 360.789982 -407.599896)
				)
				(arc
					(start 360.789982 -407.599896)
					(mid 363.590078 -404.7998)
					(end 366.38992 -407.599896)
				)
			)
		)
	)
	(zone
		(layer "F.Cu")
		(hatch none 0.5)
		(connect_pads
			(clearance 0)
		)
		(min_thickness 0.25)
		(keepout
			(tracks allowed)
			(vias allowed)
			(pads allowed)
			(copperpour allowed)
			(footprints allowed)
		)
		(placement
			(enabled no)
			(sheetname "")
		)
		(fill
			(thermal_gap 0.5)
			(thermal_bridge_width 0.5)
			(island_removal_mode 0)
		)
		(polygon
			(pts
				(xy 187.851288 -34.76117) (xy 187.851288 -33.40989) (xy 189.131448 -33.40989) (xy 189.131448 -34.76117)
			)
		)
	)
	(zone
		(layer "F.Cu")
		(hatch none 0.5)
		(connect_pads
			(clearance 0)
		)
		(min_thickness 0.25)
		(keepout
			(tracks allowed)
			(vias allowed)
			(pads allowed)
			(copperpour allowed)
			(footprints allowed)
		)
		(placement
			(enabled no)
			(sheetname "")
		)
		(fill
			(thermal_gap 0.5)
			(thermal_bridge_width 0.5)
			(island_removal_mode 0)
		)
		(polygon
			(pts
				(xy 267.339826 -320.012822) (xy 267.339826 -271.326102) (xy 316.006226 -271.326102) (xy 316.006226 -320.012822)
			)
		)
	)
	(zone
		(layer "F.Cu")
		(hatch none 0.5)
		(connect_pads
			(clearance 0)
		)
		(min_thickness 0.25)
		(keepout
			(tracks not_allowed)
			(vias allowed)
			(pads allowed)
			(copperpour not_allowed)
			(footprints allowed)
		)
		(placement
			(enabled no)
			(sheetname "")
		)
		(fill
			(thermal_gap 0.5)
			(thermal_bridge_width 0.5)
			(island_removal_mode 0)
		)
		(polygon
			(pts
				(xy 35.520122 -23.219918) (xy 35.520122 -18.219928) (xy 31.319978 -18.219928) (xy 31.319978 -23.219918)
			)
		)
	)
	(zone
		(layer "F.Cu")
		(hatch none 0.5)
		(connect_pads
			(clearance 0)
		)
		(min_thickness 0.25)
		(keepout
			(tracks allowed)
			(vias allowed)
			(pads allowed)
			(copperpour allowed)
			(footprints allowed)
		)
		(placement
			(enabled no)
			(sheetname "")
		)
		(fill
			(thermal_gap 0.5)
			(thermal_bridge_width 0.5)
			(island_removal_mode 0)
		)
		(polygon
			(pts
				(xy 255.850136 -215.464136) (xy 257.373374 -215.464136) (xy 257.562096 -215.275414) (xy 257.562096 -212.374226)
				(xy 257.543046 -212.355176) (xy 255.812544 -212.355176) (xy 255.497838 -212.669882) (xy 255.497838 -215.111838)
			)
		)
	)
	(zone
		(layer "F.Cu")
		(hatch none 0.5)
		(connect_pads
			(clearance 0)
		)
		(min_thickness 0.25)
		(keepout
			(tracks allowed)
			(vias allowed)
			(pads allowed)
			(copperpour allowed)
			(footprints not_allowed)
		)
		(placement
			(enabled no)
			(sheetname "")
		)
		(fill
			(thermal_gap 0.5)
			(thermal_bridge_width 0.5)
			(island_removal_mode 0)
		)
		(polygon
			(pts
				(xy 379.620018 -23.219918) (xy 383.819908 -23.219918) (xy 383.819908 -18.219928) (xy 379.620018 -18.219928)
			)
		)
	)
	(zone
		(layer "F.Cu")
		(hatch none 0.5)
		(connect_pads
			(clearance 0)
		)
		(min_thickness 0.25)
		(keepout
			(tracks allowed)
			(vias allowed)
			(pads allowed)
			(copperpour allowed)
			(footprints allowed)
		)
		(placement
			(enabled no)
			(sheetname "")
		)
		(fill
			(thermal_gap 0.5)
			(thermal_bridge_width 0.5)
			(island_removal_mode 0)
		)
		(polygon
			(pts
				(xy 304.96002 -46.986444) (xy 305.952398 -46.986444) (xy 306.037234 -46.901608) (xy 306.037234 -46.211744)
				(xy 305.989228 -46.163738) (xy 304.939954 -46.163738) (xy 304.872136 -46.231556) (xy 304.872136 -46.89856)
			)
		)
	)
	(zone
		(layer "F.Cu")
		(hatch none 0.5)
		(connect_pads
			(clearance 0)
		)
		(min_thickness 0.25)
		(keepout
			(tracks allowed)
			(vias allowed)
			(pads allowed)
			(copperpour allowed)
			(footprints allowed)
		)
		(placement
			(enabled no)
			(sheetname "")
		)
		(fill
			(thermal_gap 0.5)
			(thermal_bridge_width 0.5)
			(island_removal_mode 0)
		)
		(polygon
			(pts
				(xy 130.76174 -27.55011) (xy 133.161786 -27.55011) (xy 133.253226 -27.45867) (xy 133.253226 -26.33853)
				(xy 133.192266 -26.27757) (xy 130.7465 -26.27757) (xy 130.62458 -26.39949) (xy 130.62458 -27.41295)
			)
		)
	)
	(zone
		(layer "F.Cu")
		(hatch none 0.5)
		(connect_pads
			(clearance 0)
		)
		(min_thickness 0.25)
		(keepout
			(tracks allowed)
			(vias allowed)
			(pads allowed)
			(copperpour allowed)
			(footprints allowed)
		)
		(placement
			(enabled no)
			(sheetname "")
		)
		(fill
			(thermal_gap 0.5)
			(thermal_bridge_width 0.5)
			(island_removal_mode 0)
		)
		(polygon
			(pts
				(xy 21.959316 -47.3202) (xy 21.959316 -45.5676) (xy 23.737316 -45.5676) (xy 23.737316 -47.3202)
			)
		)
	)
	(zone
		(layer "F.Cu")
		(hatch none 0.5)
		(connect_pads
			(clearance 0)
		)
		(min_thickness 0.25)
		(keepout
			(tracks allowed)
			(vias allowed)
			(pads allowed)
			(copperpour allowed)
			(footprints allowed)
		)
		(placement
			(enabled no)
			(sheetname "")
		)
		(fill
			(thermal_gap 0.5)
			(thermal_bridge_width 0.5)
			(island_removal_mode 0)
		)
		(polygon
			(pts
				(xy 358.915462 -156.560012) (xy 362.725462 -156.560012) (xy 362.725462 -158.084012) (xy 358.915462 -158.084012)
			)
		)
	)
	(zone
		(layer "F.Cu")
		(hatch none 0.5)
		(connect_pads
			(clearance 0)
		)
		(min_thickness 0.25)
		(keepout
			(tracks allowed)
			(vias allowed)
			(pads allowed)
			(copperpour allowed)
			(footprints allowed)
		)
		(placement
			(enabled no)
			(sheetname "")
		)
		(fill
			(thermal_gap 0.5)
			(thermal_bridge_width 0.5)
			(island_removal_mode 0)
		)
		(polygon
			(pts
				(xy 304.88001 -136.909302) (xy 306.967382 -136.909302) (xy 307.287422 -136.589262) (xy 307.287422 -129.185162)
				(xy 304.942494 -129.185162) (xy 304.864262 -129.263394) (xy 304.864262 -136.893554)
			)
		)
	)
	(zone
		(layer "F.Cu")
		(hatch none 0.5)
		(connect_pads
			(clearance 0)
		)
		(min_thickness 0.25)
		(keepout
			(tracks allowed)
			(vias allowed)
			(pads allowed)
			(copperpour allowed)
			(footprints allowed)
		)
		(placement
			(enabled no)
			(sheetname "")
		)
		(fill
			(thermal_gap 0.5)
			(thermal_bridge_width 0.5)
			(island_removal_mode 0)
		)
		(polygon
			(pts
				(xy 19.751294 -34.76117) (xy 19.751294 -33.40989) (xy 21.031454 -33.40989) (xy 21.031454 -34.76117)
			)
		)
	)
	(zone
		(layer "F.Cu")
		(hatch none 0.5)
		(connect_pads
			(clearance 0)
		)
		(min_thickness 0.25)
		(keepout
			(tracks allowed)
			(vias allowed)
			(pads allowed)
			(copperpour allowed)
			(footprints allowed)
		)
		(placement
			(enabled no)
			(sheetname "")
		)
		(fill
			(thermal_gap 0.5)
			(thermal_bridge_width 0.5)
			(island_removal_mode 0)
		)
		(polygon
			(pts
				(xy 164.059362 -47.3202) (xy 164.059362 -45.5676) (xy 165.837362 -45.5676) (xy 165.837362 -47.3202)
			)
		)
	)
	(zone
		(layer "F.Cu")
		(hatch none 0.5)
		(connect_pads
			(clearance 0)
		)
		(min_thickness 0.25)
		(keepout
			(tracks allowed)
			(vias allowed)
			(pads allowed)
			(copperpour allowed)
			(footprints allowed)
		)
		(placement
			(enabled no)
			(sheetname "")
		)
		(fill
			(thermal_gap 0.5)
			(thermal_bridge_width 0.5)
			(island_removal_mode 0)
		)
		(polygon
			(pts
				(xy 222.353378 -383.602484) (xy 223.041972 -383.602484) (xy 223.12757 -383.516886) (xy 223.12757 -383.104644)
				(xy 222.936562 -382.913636) (xy 222.308166 -382.913636) (xy 222.242634 -382.979168) (xy 222.242634 -383.49174)
			)
		)
	)
	(zone
		(layer "F.Cu")
		(hatch none 0.5)
		(connect_pads
			(clearance 0)
		)
		(min_thickness 0.25)
		(keepout
			(tracks allowed)
			(vias allowed)
			(pads allowed)
			(copperpour allowed)
			(footprints allowed)
		)
		(placement
			(enabled no)
			(sheetname "")
		)
		(fill
			(thermal_gap 0.5)
			(thermal_bridge_width 0.5)
			(island_removal_mode 0)
		)
		(polygon
			(pts
				(xy 413.507936 -344.659458) (xy 412.156656 -344.659458) (xy 412.156656 -343.379298) (xy 413.507936 -343.379298)
			)
		)
	)
	(zone
		(layer "F.Cu")
		(hatch none 0.5)
		(connect_pads
			(clearance 0)
		)
		(min_thickness 0.25)
		(keepout
			(tracks not_allowed)
			(vias allowed)
			(pads allowed)
			(copperpour not_allowed)
			(footprints allowed)
		)
		(placement
			(enabled no)
			(sheetname "")
		)
		(fill
			(thermal_gap 0.5)
			(thermal_bridge_width 0.5)
			(island_removal_mode 0)
		)
		(polygon
			(pts
				(arc
					(start 257.599942 -98.700082)
					(mid 259.299964 -97.00006)
					(end 260.999986 -98.700082)
				)
				(arc
					(start 260.999986 -98.700082)
					(mid 259.299964 -100.400104)
					(end 257.599942 -98.700082)
				)
			)
		)
	)
	(zone
		(layer "F.Cu")
		(hatch none 0.5)
		(connect_pads
			(clearance 0)
		)
		(min_thickness 0.25)
		(keepout
			(tracks allowed)
			(vias allowed)
			(pads allowed)
			(copperpour allowed)
			(footprints not_allowed)
		)
		(placement
			(enabled no)
			(sheetname "")
		)
		(fill
			(thermal_gap 0.5)
			(thermal_bridge_width 0.5)
			(island_removal_mode 0)
		)
		(polygon
			(pts
				(xy 214.719916 -18.150078) (xy 214.719916 -13.150088) (xy 210.520026 -13.150088) (xy 210.520026 -18.150078)
			)
		)
	)
	(zone
		(layer "F.Cu")
		(hatch none 0.5)
		(connect_pads
			(clearance 0)
		)
		(min_thickness 0.25)
		(keepout
			(tracks not_allowed)
			(vias allowed)
			(pads allowed)
			(copperpour not_allowed)
			(footprints allowed)
		)
		(placement
			(enabled no)
			(sheetname "")
		)
		(fill
			(thermal_gap 0.5)
			(thermal_bridge_width 0.5)
			(island_removal_mode 0)
		)
		(polygon
			(pts
				(arc
					(start 347.89999 -194.360038)
					(mid 349.899986 -192.360042)
					(end 351.899982 -194.360038)
				)
				(arc
					(start 351.899982 -194.360038)
					(mid 349.899986 -196.360034)
					(end 347.89999 -194.360038)
				)
			)
		)
	)
	(zone
		(layer "F.Cu")
		(hatch none 0.5)
		(connect_pads
			(clearance 0)
		)
		(min_thickness 0.25)
		(keepout
			(tracks allowed)
			(vias allowed)
			(pads allowed)
			(copperpour allowed)
			(footprints allowed)
		)
		(placement
			(enabled no)
			(sheetname "")
		)
		(fill
			(thermal_gap 0.5)
			(thermal_bridge_width 0.5)
			(island_removal_mode 0)
		)
		(polygon
			(pts
				(xy 135.851392 -31.160974) (xy 135.851392 -29.809694) (xy 137.131552 -29.809694) (xy 137.131552 -31.160974)
			)
		)
	)
	(zone
		(layer "F.Cu")
		(hatch none 0.5)
		(connect_pads
			(clearance 0)
		)
		(min_thickness 0.25)
		(keepout
			(tracks allowed)
			(vias allowed)
			(pads allowed)
			(copperpour allowed)
			(footprints not_allowed)
		)
		(placement
			(enabled no)
			(sheetname "")
		)
		(fill
			(thermal_gap 0.5)
			(thermal_bridge_width 0.5)
			(island_removal_mode 0)
		)
		(polygon
			(pts
				(arc
					(start 203.700126 -378.70003)
					(mid 195.700142 -386.700014)
					(end 187.699904 -378.70003)
				)
				(arc
					(start 187.699904 -378.70003)
					(mid 195.700142 -370.699792)
					(end 203.700126 -378.70003)
				)
			)
		)
	)
	(zone
		(layer "F.Cu")
		(hatch none 0.5)
		(connect_pads
			(clearance 0)
		)
		(min_thickness 0.25)
		(keepout
			(tracks not_allowed)
			(vias allowed)
			(pads allowed)
			(copperpour not_allowed)
			(footprints allowed)
		)
		(placement
			(enabled no)
			(sheetname "")
		)
		(fill
			(thermal_gap 0.5)
			(thermal_bridge_width 0.5)
			(island_removal_mode 0)
		)
		(polygon
			(pts
				(xy 177.619914 -23.219918) (xy 177.619914 -18.219928) (xy 173.420024 -18.219928) (xy 173.420024 -23.219918)
			)
		)
	)
	(zone
		(layer "F.Cu")
		(hatch none 0.5)
		(connect_pads
			(clearance 0)
		)
		(min_thickness 0.25)
		(keepout
			(tracks allowed)
			(vias allowed)
			(pads allowed)
			(copperpour allowed)
			(footprints allowed)
		)
		(placement
			(enabled no)
			(sheetname "")
		)
		(fill
			(thermal_gap 0.5)
			(thermal_bridge_width 0.5)
			(island_removal_mode 0)
		)
		(polygon
			(pts
				(xy 125.401832 -350.80575) (xy 124.050552 -350.80575) (xy 124.050552 -349.52559) (xy 125.401832 -349.52559)
			)
		)
	)
	(zone
		(layer "F.Cu")
		(hatch none 0.5)
		(connect_pads
			(clearance 0)
		)
		(min_thickness 0.25)
		(keepout
			(tracks allowed)
			(vias allowed)
			(pads allowed)
			(copperpour allowed)
			(footprints allowed)
		)
		(placement
			(enabled no)
			(sheetname "")
		)
		(fill
			(thermal_gap 0.5)
			(thermal_bridge_width 0.5)
			(island_removal_mode 0)
		)
		(polygon
			(pts
				(xy 45.751242 -31.160974) (xy 45.751242 -29.809694) (xy 47.031402 -29.809694) (xy 47.031402 -31.160974)
			)
		)
	)
	(zone
		(layer "F.Cu")
		(hatch none 0.5)
		(connect_pads
			(clearance 0)
		)
		(min_thickness 0.25)
		(keepout
			(tracks not_allowed)
			(vias allowed)
			(pads allowed)
			(copperpour not_allowed)
			(footprints allowed)
		)
		(placement
			(enabled no)
			(sheetname "")
		)
		(fill
			(thermal_gap 0.5)
			(thermal_bridge_width 0.5)
			(island_removal_mode 0)
		)
		(polygon
			(pts
				(arc
					(start 20.964906 -17.999964)
					(mid 25.964896 -12.999974)
					(end 30.964886 -17.999964)
				)
				(arc
					(start 30.964886 -17.999964)
					(mid 25.964896 -22.999954)
					(end 20.964906 -17.999964)
				)
			)
		)
	)
	(zone
		(layer "F.Cu")
		(hatch none 0.5)
		(connect_pads
			(clearance 0)
		)
		(min_thickness 0.25)
		(keepout
			(tracks not_allowed)
			(vias allowed)
			(pads allowed)
			(copperpour not_allowed)
			(footprints allowed)
		)
		(placement
			(enabled no)
			(sheetname "")
		)
		(fill
			(thermal_gap 0.5)
			(thermal_bridge_width 0.5)
			(island_removal_mode 0)
		)
		(polygon
			(pts
				(arc
					(start 87.399876 -320.900044)
					(mid 89.650062 -318.649858)
					(end 91.899994 -320.900044)
				)
				(arc
					(start 91.899994 -320.900044)
					(mid 89.650062 -323.149976)
					(end 87.399876 -320.900044)
				)
			)
		)
	)
	(zone
		(layer "F.Cu")
		(hatch none 0.5)
		(connect_pads
			(clearance 0)
		)
		(min_thickness 0.25)
		(keepout
			(tracks allowed)
			(vias allowed)
			(pads allowed)
			(copperpour allowed)
			(footprints allowed)
		)
		(placement
			(enabled no)
			(sheetname "")
		)
		(fill
			(thermal_gap 0.5)
			(thermal_bridge_width 0.5)
			(island_removal_mode 0)
		)
		(polygon
			(pts
				(xy 114.169444 -255.532382) (xy 114.759994 -255.532382) (xy 114.851688 -255.440688) (xy 114.851688 -254.642366)
				(xy 114.708178 -254.498856) (xy 114.177572 -254.498856) (xy 114.009932 -254.666496) (xy 114.009932 -255.37287)
			)
		)
	)
	(zone
		(layer "F.Cu")
		(hatch none 0.5)
		(connect_pads
			(clearance 0)
		)
		(min_thickness 0.25)
		(keepout
			(tracks allowed)
			(vias allowed)
			(pads allowed)
			(copperpour allowed)
			(footprints allowed)
		)
		(placement
			(enabled no)
			(sheetname "")
		)
		(fill
			(thermal_gap 0.5)
			(thermal_bridge_width 0.5)
			(island_removal_mode 0)
		)
		(polygon
			(pts
				(xy 124.58446 -54.008274) (xy 121.666762 -54.008274) (xy 121.457212 -54.217824) (xy 121.457212 -54.830726)
				(xy 124.51461 -54.830726) (xy 124.58446 -54.760876)
			)
		)
	)
	(zone
		(layer "F.Cu")
		(hatch none 0.5)
		(connect_pads
			(clearance 0)
		)
		(min_thickness 0.25)
		(keepout
			(tracks allowed)
			(vias allowed)
			(pads allowed)
			(copperpour allowed)
			(footprints allowed)
		)
		(placement
			(enabled no)
			(sheetname "")
		)
		(fill
			(thermal_gap 0.5)
			(thermal_bridge_width 0.5)
			(island_removal_mode 0)
		)
		(polygon
			(pts
				(xy 19.751294 -31.160974) (xy 19.751294 -29.809694) (xy 21.031454 -29.809694) (xy 21.031454 -31.160974)
			)
		)
	)
	(zone
		(layer "F.Cu")
		(hatch none 0.5)
		(connect_pads
			(clearance 0)
		)
		(min_thickness 0.25)
		(keepout
			(tracks not_allowed)
			(vias allowed)
			(pads allowed)
			(copperpour not_allowed)
			(footprints allowed)
		)
		(placement
			(enabled no)
			(sheetname "")
		)
		(fill
			(thermal_gap 0.5)
			(thermal_bridge_width 0.5)
			(island_removal_mode 0)
		)
		(polygon
			(pts
				(arc
					(start 375.700036 -270.89989)
					(mid 377.949968 -268.649958)
					(end 380.1999 -270.89989)
				)
				(arc
					(start 380.1999 -270.89989)
					(mid 377.949968 -273.149822)
					(end 375.700036 -270.89989)
				)
			)
		)
	)
	(zone
		(layer "F.Cu")
		(hatch none 0.5)
		(connect_pads
			(clearance 0)
		)
		(min_thickness 0.25)
		(keepout
			(tracks allowed)
			(vias allowed)
			(pads allowed)
			(copperpour allowed)
			(footprints allowed)
		)
		(placement
			(enabled no)
			(sheetname "")
		)
		(fill
			(thermal_gap 0.5)
			(thermal_bridge_width 0.5)
			(island_removal_mode 0)
		)
		(polygon
			(pts
				(xy 139.656058 -230.378) (xy 139.656058 -220.599) (xy 141.688058 -220.599) (xy 141.688058 -230.378)
			)
		)
	)
	(zone
		(layer "F.Cu")
		(hatch none 0.5)
		(connect_pads
			(clearance 0)
		)
		(min_thickness 0.25)
		(keepout
			(tracks allowed)
			(vias allowed)
			(pads allowed)
			(copperpour allowed)
			(footprints allowed)
		)
		(placement
			(enabled no)
			(sheetname "")
		)
		(fill
			(thermal_gap 0.5)
			(thermal_bridge_width 0.5)
			(island_removal_mode 0)
		)
		(polygon
			(pts
				(xy 252.960124 -46.986444) (xy 253.952502 -46.986444) (xy 254.037338 -46.901608) (xy 254.037338 -46.211744)
				(xy 253.989332 -46.163738) (xy 252.940058 -46.163738) (xy 252.87224 -46.231556) (xy 252.87224 -46.89856)
			)
		)
	)
	(zone
		(layer "F.Cu")
		(hatch none 0.5)
		(connect_pads
			(clearance 0)
		)
		(min_thickness 0.25)
		(keepout
			(tracks allowed)
			(vias allowed)
			(pads allowed)
			(copperpour allowed)
			(footprints allowed)
		)
		(placement
			(enabled no)
			(sheetname "")
		)
		(fill
			(thermal_gap 0.5)
			(thermal_bridge_width 0.5)
			(island_removal_mode 0)
		)
		(polygon
			(pts
				(xy 394.054584 -356.952042) (xy 392.703304 -356.952042) (xy 392.703304 -355.671882) (xy 394.054584 -355.671882)
			)
		)
	)
	(zone
		(layer "F.Cu")
		(hatch none 0.5)
		(connect_pads
			(clearance 0)
		)
		(min_thickness 0.25)
		(keepout
			(tracks allowed)
			(vias allowed)
			(pads allowed)
			(copperpour allowed)
			(footprints allowed)
		)
		(placement
			(enabled no)
			(sheetname "")
		)
		(fill
			(thermal_gap 0.5)
			(thermal_bridge_width 0.5)
			(island_removal_mode 0)
		)
		(polygon
			(pts
				(xy 363.333538 -28.022042) (xy 365.116364 -28.022042) (xy 365.512604 -27.625802) (xy 365.512604 -25.842976)
				(xy 365.375444 -25.705816) (xy 363.226858 -25.705816) (xy 363.013498 -25.919176) (xy 362.967778 -25.919176)
				(xy 362.967778 -27.656282)
			)
		)
	)
	(zone
		(layer "F.Cu")
		(hatch none 0.5)
		(connect_pads
			(clearance 0)
		)
		(min_thickness 0.25)
		(keepout
			(tracks allowed)
			(vias allowed)
			(pads allowed)
			(copperpour allowed)
			(footprints allowed)
		)
		(placement
			(enabled no)
			(sheetname "")
		)
		(fill
			(thermal_gap 0.5)
			(thermal_bridge_width 0.5)
			(island_removal_mode 0)
		)
		(polygon
			(pts
				(xy 272.109946 -350.80575) (xy 270.758666 -350.80575) (xy 270.758666 -349.52559) (xy 272.109946 -349.52559)
			)
		)
	)
	(zone
		(layer "F.Cu")
		(hatch none 0.5)
		(connect_pads
			(clearance 0)
		)
		(min_thickness 0.25)
		(keepout
			(tracks allowed)
			(vias allowed)
			(pads allowed)
			(copperpour allowed)
			(footprints allowed)
		)
		(placement
			(enabled no)
			(sheetname "")
		)
		(fill
			(thermal_gap 0.5)
			(thermal_bridge_width 0.5)
			(island_removal_mode 0)
		)
		(polygon
			(pts
				(xy 284.520386 -344.659458) (xy 283.169106 -344.659458) (xy 283.169106 -343.379298) (xy 284.520386 -343.379298)
			)
		)
	)
	(zone
		(layer "F.Cu")
		(hatch none 0.5)
		(connect_pads
			(clearance 0)
		)
		(min_thickness 0.25)
		(keepout
			(tracks allowed)
			(vias allowed)
			(pads allowed)
			(copperpour allowed)
			(footprints allowed)
		)
		(placement
			(enabled no)
			(sheetname "")
		)
		(fill
			(thermal_gap 0.5)
			(thermal_bridge_width 0.5)
			(island_removal_mode 0)
		)
		(polygon
			(pts
				(xy 396.259304 -47.3202) (xy 396.259304 -45.5676) (xy 398.037304 -45.5676) (xy 398.037304 -47.3202)
			)
		)
	)
	(zone
		(layer "F.Cu")
		(hatch none 0.5)
		(connect_pads
			(clearance 0)
		)
		(min_thickness 0.25)
		(keepout
			(tracks allowed)
			(vias allowed)
			(pads allowed)
			(copperpour allowed)
			(footprints not_allowed)
		)
		(placement
			(enabled no)
			(sheetname "")
		)
		(fill
			(thermal_gap 0.5)
			(thermal_bridge_width 0.5)
			(island_removal_mode 0)
		)
		(polygon
			(pts
				(arc
					(start 239.940592 -218.250008)
					(mid 251.898912 -207.249947)
					(end 263.857232 -218.250008)
				)
			)
		)
	)
	(zone
		(layer "F.Cu")
		(hatch none 0.5)
		(connect_pads
			(clearance 0)
		)
		(min_thickness 0.25)
		(keepout
			(tracks allowed)
			(vias allowed)
			(pads allowed)
			(copperpour allowed)
			(footprints allowed)
		)
		(placement
			(enabled no)
			(sheetname "")
		)
		(fill
			(thermal_gap 0.5)
			(thermal_bridge_width 0.5)
			(island_removal_mode 0)
		)
		(polygon
			(pts
				(xy 82.511646 -136.416034) (xy 82.511646 -135.064754) (xy 83.791806 -135.064754) (xy 83.791806 -136.416034)
			)
		)
	)
	(zone
		(layer "F.Cu")
		(hatch none 0.5)
		(connect_pads
			(clearance 0)
		)
		(min_thickness 0.25)
		(keepout
			(tracks allowed)
			(vias allowed)
			(pads allowed)
			(copperpour allowed)
			(footprints allowed)
		)
		(placement
			(enabled no)
			(sheetname "")
		)
		(fill
			(thermal_gap 0.5)
			(thermal_bridge_width 0.5)
			(island_removal_mode 0)
		)
		(polygon
			(pts
				(xy 445.15786 -209.869786) (xy 445.15786 -208.09712) (xy 446.656714 -208.09712) (xy 446.656714 -209.869786)
			)
		)
	)
	(zone
		(layer "F.Cu")
		(hatch none 0.5)
		(connect_pads
			(clearance 0)
		)
		(min_thickness 0.25)
		(keepout
			(tracks allowed)
			(vias allowed)
			(pads allowed)
			(copperpour allowed)
			(footprints allowed)
		)
		(placement
			(enabled no)
			(sheetname "")
		)
		(fill
			(thermal_gap 0.5)
			(thermal_bridge_width 0.5)
			(island_removal_mode 0)
		)
		(polygon
			(pts
				(xy 425.918376 -350.80575) (xy 424.567096 -350.80575) (xy 424.567096 -349.52559) (xy 425.918376 -349.52559)
			)
		)
	)
	(zone
		(layer "F.Cu")
		(hatch none 0.5)
		(connect_pads
			(clearance 0)
		)
		(min_thickness 0.25)
		(keepout
			(tracks allowed)
			(vias allowed)
			(pads allowed)
			(copperpour allowed)
			(footprints allowed)
		)
		(placement
			(enabled no)
			(sheetname "")
		)
		(fill
			(thermal_gap 0.5)
			(thermal_bridge_width 0.5)
			(island_removal_mode 0)
		)
		(polygon
			(pts
				(xy 86.484206 -54.008274) (xy 83.566508 -54.008274) (xy 83.356958 -54.217824) (xy 83.356958 -54.830726)
				(xy 86.414356 -54.830726) (xy 86.484206 -54.760876)
			)
		)
	)
	(zone
		(layer "F.Cu")
		(hatch none 0.5)
		(connect_pads
			(clearance 0)
		)
		(min_thickness 0.25)
		(keepout
			(tracks allowed)
			(vias allowed)
			(pads allowed)
			(copperpour allowed)
			(footprints allowed)
		)
		(placement
			(enabled no)
			(sheetname "")
		)
		(fill
			(thermal_gap 0.5)
			(thermal_bridge_width 0.5)
			(island_removal_mode 0)
		)
		(polygon
			(pts
				(xy 198.61149 -136.416034) (xy 198.61149 -135.064754) (xy 199.89165 -135.064754) (xy 199.89165 -136.416034)
			)
		)
	)
	(zone
		(layer "F.Cu")
		(hatch none 0.5)
		(connect_pads
			(clearance 0)
		)
		(min_thickness 0.25)
		(keepout
			(tracks allowed)
			(vias allowed)
			(pads allowed)
			(copperpour allowed)
			(footprints allowed)
		)
		(placement
			(enabled no)
			(sheetname "")
		)
		(fill
			(thermal_gap 0.5)
			(thermal_bridge_width 0.5)
			(island_removal_mode 0)
		)
		(polygon
			(pts
				(xy 237.333028 -80.672686) (xy 238.169958 -80.672686) (xy 238.660432 -80.672686) (xy 238.660686 -80.672432)
				(xy 238.660686 -79.224632) (xy 238.540036 -79.103982) (xy 238.230664 -79.103982) (xy 238.200438 -79.134208)
				(xy 237.355888 -79.134208) (xy 237.27283 -79.217266) (xy 237.27283 -80.612488)
			)
		)
	)
	(zone
		(layer "F.Cu")
		(hatch none 0.5)
		(connect_pads
			(clearance 0)
		)
		(min_thickness 0.25)
		(keepout
			(tracks not_allowed)
			(vias allowed)
			(pads allowed)
			(copperpour not_allowed)
			(footprints allowed)
		)
		(placement
			(enabled no)
			(sheetname "")
		)
		(fill
			(thermal_gap 0.5)
			(thermal_bridge_width 0.5)
			(island_removal_mode 0)
		)
		(polygon
			(pts
				(arc
					(start 263.19988 -393.100052)
					(mid 268.200124 -388.099808)
					(end 273.200114 -393.100052)
				)
				(arc
					(start 273.200114 -393.100052)
					(mid 268.200124 -398.100042)
					(end 263.19988 -393.100052)
				)
			)
		)
	)
	(zone
		(layer "F.Cu")
		(hatch none 0.5)
		(connect_pads
			(clearance 0)
		)
		(min_thickness 0.25)
		(keepout
			(tracks not_allowed)
			(vias allowed)
			(pads allowed)
			(copperpour not_allowed)
			(footprints allowed)
		)
		(placement
			(enabled no)
			(sheetname "")
		)
		(fill
			(thermal_gap 0.5)
			(thermal_bridge_width 0.5)
			(island_removal_mode 0)
		)
		(polygon
			(pts
				(xy 314.79998 -396.56004) (xy 324.79996 -396.56004) (xy 324.79996 -417.378642) (xy 314.79998 -417.378642)
			)
		)
	)
	(zone
		(layer "F.Cu")
		(hatch none 0.5)
		(connect_pads
			(clearance 0)
		)
		(min_thickness 0.25)
		(keepout
			(tracks allowed)
			(vias allowed)
			(pads allowed)
			(copperpour allowed)
			(footprints allowed)
		)
		(placement
			(enabled no)
			(sheetname "")
		)
		(fill
			(thermal_gap 0.5)
			(thermal_bridge_width 0.5)
			(island_removal_mode 0)
		)
		(polygon
			(pts
				(xy 319.799208 -344.659458) (xy 318.447928 -344.659458) (xy 318.447928 -343.379298) (xy 319.799208 -343.379298)
			)
		)
	)
	(zone
		(layer "F.Cu")
		(hatch none 0.5)
		(connect_pads
			(clearance 0)
		)
		(min_thickness 0.25)
		(keepout
			(tracks allowed)
			(vias allowed)
			(pads allowed)
			(copperpour allowed)
			(footprints allowed)
		)
		(placement
			(enabled no)
			(sheetname "")
		)
		(fill
			(thermal_gap 0.5)
			(thermal_bridge_width 0.5)
			(island_removal_mode 0)
		)
		(polygon
			(pts
				(xy 79.336138 -119.799608) (xy 79.336138 -118.448328) (xy 80.616298 -118.448328) (xy 80.616298 -119.799608)
			)
		)
	)
	(zone
		(layer "F.Cu")
		(hatch none 0.5)
		(connect_pads
			(clearance 0)
		)
		(min_thickness 0.25)
		(keepout
			(tracks allowed)
			(vias allowed)
			(pads allowed)
			(copperpour allowed)
			(footprints not_allowed)
		)
		(placement
			(enabled no)
			(sheetname "")
		)
		(fill
			(thermal_gap 0.5)
			(thermal_bridge_width 0.5)
			(island_removal_mode 0)
		)
		(polygon
			(pts
				(arc
					(start 334.214978 -17.999964)
					(mid 342.214962 -9.99998)
					(end 350.214946 -17.999964)
				)
				(arc
					(start 350.214946 -17.999964)
					(mid 342.214962 -25.999948)
					(end 334.214978 -17.999964)
				)
			)
		)
	)
	(zone
		(layer "F.Cu")
		(hatch none 0.5)
		(connect_pads
			(clearance 0)
		)
		(min_thickness 0.25)
		(keepout
			(tracks allowed)
			(vias allowed)
			(pads allowed)
			(copperpour allowed)
			(footprints allowed)
		)
		(placement
			(enabled no)
			(sheetname "")
		)
		(fill
			(thermal_gap 0.5)
			(thermal_bridge_width 0.5)
			(island_removal_mode 0)
		)
		(polygon
			(pts
				(xy 233.937048 -146.242024) (xy 232.811828 -145.116804) (xy 231.50703 -145.116804) (xy 231.387396 -145.236438)
				(xy 231.387396 -149.342348) (xy 231.986074 -149.941026) (xy 231.986074 -150.138384) (xy 232.512616 -150.664926)
				(xy 233.458512 -150.664926) (xy 234.440222 -150.664926) (xy 234.73918 -150.365968) (xy 234.73918 -148.929598)
				(xy 236.36097 -148.929598) (xy 236.756194 -148.534374) (xy 236.756194 -147.56511) (xy 236.690154 -147.49907)
				(xy 235.744512 -147.49907) (xy 235.199682 -148.0439) (xy 234.73918 -148.0439) (xy 234.73918 -146.960082)
				(xy 234.021122 -146.242024)
			)
		)
	)
	(zone
		(layer "F.Cu")
		(hatch none 0.5)
		(connect_pads
			(clearance 0)
		)
		(min_thickness 0.25)
		(keepout
			(tracks not_allowed)
			(vias allowed)
			(pads allowed)
			(copperpour not_allowed)
			(footprints allowed)
		)
		(placement
			(enabled no)
			(sheetname "")
		)
		(fill
			(thermal_gap 0.5)
			(thermal_bridge_width 0.5)
			(island_removal_mode 0)
		)
		(polygon
			(pts
				(xy 394.919962 -18.150078) (xy 394.919962 -13.150088) (xy 390.720072 -13.150088) (xy 390.720072 -18.150078)
			)
		)
	)
	(zone
		(layer "F.Cu")
		(hatch none 0.5)
		(connect_pads
			(clearance 0)
		)
		(min_thickness 0.25)
		(keepout
			(tracks allowed)
			(vias allowed)
			(pads allowed)
			(copperpour allowed)
			(footprints allowed)
		)
		(placement
			(enabled no)
			(sheetname "")
		)
		(fill
			(thermal_gap 0.5)
			(thermal_bridge_width 0.5)
			(island_removal_mode 0)
		)
		(polygon
			(pts
				(xy 362.077 -230.378) (xy 362.077 -220.599) (xy 364.109 -220.599) (xy 364.109 -230.378)
			)
		)
	)
	(zone
		(layer "F.Cu")
		(hatch none 0.5)
		(connect_pads
			(clearance 0)
		)
		(min_thickness 0.25)
		(keepout
			(tracks allowed)
			(vias allowed)
			(pads allowed)
			(copperpour allowed)
			(footprints allowed)
		)
		(placement
			(enabled no)
			(sheetname "")
		)
		(fill
			(thermal_gap 0.5)
			(thermal_bridge_width 0.5)
			(island_removal_mode 0)
		)
		(polygon
			(pts
				(xy 10.615422 -156.560012) (xy 14.425422 -156.560012) (xy 14.425422 -158.084012) (xy 10.615422 -158.084012)
			)
		)
	)
	(zone
		(layer "F.Cu")
		(hatch none 0.5)
		(connect_pads
			(clearance 0)
		)
		(min_thickness 0.25)
		(keepout
			(tracks allowed)
			(vias allowed)
			(pads allowed)
			(copperpour allowed)
			(footprints allowed)
		)
		(placement
			(enabled no)
			(sheetname "")
		)
		(fill
			(thermal_gap 0.5)
			(thermal_bridge_width 0.5)
			(island_removal_mode 0)
		)
		(polygon
			(pts
				(xy 306.159154 -47.3202) (xy 306.159154 -45.5676) (xy 307.937154 -45.5676) (xy 307.937154 -47.3202)
			)
		)
	)
	(zone
		(layer "F.Cu")
		(hatch none 0.5)
		(connect_pads
			(clearance 0)
		)
		(min_thickness 0.25)
		(keepout
			(tracks not_allowed)
			(vias allowed)
			(pads allowed)
			(copperpour not_allowed)
			(footprints allowed)
		)
		(placement
			(enabled no)
			(sheetname "")
		)
		(fill
			(thermal_gap 0.5)
			(thermal_bridge_width 0.5)
			(island_removal_mode 0)
		)
		(polygon
			(pts
				(arc
					(start 10.80008 -194.360038)
					(mid 15.80007 -189.360048)
					(end 20.80006 -194.360038)
				)
				(arc
					(start 20.80006 -194.360038)
					(mid 15.80007 -199.360028)
					(end 10.80008 -194.360038)
				)
			)
		)
	)
	(zone
		(layer "F.Cu")
		(hatch none 0.5)
		(connect_pads
			(clearance 0)
		)
		(min_thickness 0.25)
		(keepout
			(tracks allowed)
			(vias allowed)
			(pads allowed)
			(copperpour allowed)
			(footprints allowed)
		)
		(placement
			(enabled no)
			(sheetname "")
		)
		(fill
			(thermal_gap 0.5)
			(thermal_bridge_width 0.5)
			(island_removal_mode 0)
		)
		(polygon
			(pts
				(xy 247.586754 -126.738126) (xy 247.586754 -123.820428) (xy 247.377204 -123.610878) (xy 246.764302 -123.610878)
				(xy 246.764302 -126.668276) (xy 246.834152 -126.738126)
			)
		)
	)
	(zone
		(layer "F.Cu")
		(hatch none 0.5)
		(connect_pads
			(clearance 0)
		)
		(min_thickness 0.25)
		(keepout
			(tracks allowed)
			(vias allowed)
			(pads allowed)
			(copperpour allowed)
			(footprints allowed)
		)
		(placement
			(enabled no)
			(sheetname "")
		)
		(fill
			(thermal_gap 0.5)
			(thermal_bridge_width 0.5)
			(island_removal_mode 0)
		)
		(polygon
			(pts
				(xy 140.946632 -356.928166) (xy 139.595352 -356.928166) (xy 139.595352 -355.648006) (xy 140.946632 -355.648006)
			)
		)
	)
	(zone
		(layer "F.Cu")
		(hatch none 0.5)
		(connect_pads
			(clearance 0)
		)
		(min_thickness 0.25)
		(keepout
			(tracks allowed)
			(vias allowed)
			(pads allowed)
			(copperpour allowed)
			(footprints allowed)
		)
		(placement
			(enabled no)
			(sheetname "")
		)
		(fill
			(thermal_gap 0.5)
			(thermal_bridge_width 0.5)
			(island_removal_mode 0)
		)
		(polygon
			(pts
				(xy 104.267 -318.544956) (xy 104.267 -316.893956) (xy 106.299 -316.893956) (xy 106.299 -318.544956)
			)
		)
	)
	(zone
		(layer "F.Cu")
		(hatch none 0.5)
		(connect_pads
			(clearance 0)
		)
		(min_thickness 0.25)
		(keepout
			(tracks allowed)
			(vias allowed)
			(pads allowed)
			(copperpour allowed)
			(footprints allowed)
		)
		(placement
			(enabled no)
			(sheetname "")
		)
		(fill
			(thermal_gap 0.5)
			(thermal_bridge_width 0.5)
			(island_removal_mode 0)
		)
		(polygon
			(pts
				(xy 267.97 -22.733) (xy 267.97 -21.971) (xy 270.891 -21.971) (xy 270.891 -22.733)
			)
		)
	)
	(zone
		(layer "F.Cu")
		(hatch none 0.5)
		(connect_pads
			(clearance 0)
		)
		(min_thickness 0.25)
		(keepout
			(tracks allowed)
			(vias allowed)
			(pads allowed)
			(copperpour allowed)
			(footprints allowed)
		)
		(placement
			(enabled no)
			(sheetname "")
		)
		(fill
			(thermal_gap 0.5)
			(thermal_bridge_width 0.5)
			(island_removal_mode 0)
		)
		(polygon
			(pts
				(xy 438.354216 -350.781874) (xy 437.002936 -350.781874) (xy 437.002936 -349.501714) (xy 438.354216 -349.501714)
			)
		)
	)
	(zone
		(layer "F.Cu")
		(hatch none 0.5)
		(connect_pads
			(clearance 0)
		)
		(min_thickness 0.25)
		(keepout
			(tracks allowed)
			(vias allowed)
			(pads allowed)
			(copperpour allowed)
			(footprints allowed)
		)
		(placement
			(enabled no)
			(sheetname "")
		)
		(fill
			(thermal_gap 0.5)
			(thermal_bridge_width 0.5)
			(island_removal_mode 0)
		)
		(polygon
			(pts
				(xy 194.379596 -350.781874) (xy 193.028316 -350.781874) (xy 193.028316 -349.501714) (xy 194.379596 -349.501714)
			)
		)
	)
	(zone
		(layer "F.Cu")
		(hatch none 0.5)
		(connect_pads
			(clearance 0)
		)
		(min_thickness 0.25)
		(keepout
			(tracks allowed)
			(vias allowed)
			(pads allowed)
			(copperpour allowed)
			(footprints not_allowed)
		)
		(placement
			(enabled no)
			(sheetname "")
		)
		(fill
			(thermal_gap 0.5)
			(thermal_bridge_width 0.5)
			(island_removal_mode 0)
		)
		(polygon
			(pts
				(arc
					(start 123.840494 -232.750106)
					(mid 135.798814 -243.750167)
					(end 147.757134 -232.750106)
				)
				(xy 147.860004 -232.750106) (xy 147.860004 -218.250008)
				(arc
					(start 147.757134 -218.250008)
					(mid 135.798814 -207.249947)
					(end 123.840494 -218.250008)
				)
				(xy 123.73991 -218.250008) (xy 123.73991 -232.750106)
			)
		)
	)
	(zone
		(layer "F.Cu")
		(hatch none 0.5)
		(connect_pads
			(clearance 0)
		)
		(min_thickness 0.25)
		(keepout
			(tracks allowed)
			(vias allowed)
			(pads allowed)
			(copperpour allowed)
			(footprints allowed)
		)
		(placement
			(enabled no)
			(sheetname "")
		)
		(fill
			(thermal_gap 0.5)
			(thermal_bridge_width 0.5)
			(island_removal_mode 0)
		)
		(polygon
			(pts
				(xy 189.09157 -52.800758) (xy 189.09157 -55.718456) (xy 189.30112 -55.928006) (xy 189.914022 -55.928006)
				(xy 189.914022 -52.870608) (xy 189.844172 -52.800758)
			)
		)
	)
	(zone
		(layer "F.Cu")
		(hatch none 0.5)
		(connect_pads
			(clearance 0)
		)
		(min_thickness 0.25)
		(keepout
			(tracks allowed)
			(vias allowed)
			(pads allowed)
			(copperpour allowed)
			(footprints not_allowed)
		)
		(placement
			(enabled no)
			(sheetname "")
		)
		(fill
			(thermal_gap 0.5)
			(thermal_bridge_width 0.5)
			(island_removal_mode 0)
		)
		(polygon
			(pts
				(arc
					(start 95.149924 -289.820096)
					(mid 99.149916 -285.820104)
					(end 103.149908 -289.820096)
				)
				(arc
					(start 103.149908 -289.820096)
					(mid 99.149916 -293.820088)
					(end 95.149924 -289.820096)
				)
			)
		)
	)
	(zone
		(layer "F.Cu")
		(hatch none 0.5)
		(connect_pads
			(clearance 0)
		)
		(min_thickness 0.25)
		(keepout
			(tracks allowed)
			(vias allowed)
			(pads allowed)
			(copperpour allowed)
			(footprints not_allowed)
		)
		(placement
			(enabled no)
			(sheetname "")
		)
		(fill
			(thermal_gap 0.5)
			(thermal_bridge_width 0.5)
			(island_removal_mode 0)
		)
		(polygon
			(pts
				(arc
					(start 7.74065 -232.750106)
					(mid 19.698959 -243.750167)
					(end 31.657036 -232.750106)
				)
				(xy 31.759906 -232.750106) (xy 31.759906 -218.250008)
				(arc
					(start 31.657036 -218.250008)
					(mid 19.698959 -207.2502)
					(end 7.74065 -218.250008)
				)
				(xy 7.640066 -218.250008) (xy 7.640066 -232.750106)
			)
		)
	)
	(zone
		(layer "F.Cu")
		(hatch none 0.5)
		(connect_pads
			(clearance 0)
		)
		(min_thickness 0.25)
		(keepout
			(tracks not_allowed)
			(vias allowed)
			(pads allowed)
			(copperpour not_allowed)
			(footprints allowed)
		)
		(placement
			(enabled no)
			(sheetname "")
		)
		(fill
			(thermal_gap 0.5)
			(thermal_bridge_width 0.5)
			(island_removal_mode 0)
		)
		(polygon
			(pts
				(xy 136.720072 -18.150078) (xy 136.720072 -13.150088) (xy 132.519928 -13.150088) (xy 132.519928 -18.150078)
			)
		)
	)
	(zone
		(layer "F.Cu")
		(hatch none 0.5)
		(connect_pads
			(clearance 0)
		)
		(min_thickness 0.25)
		(keepout
			(tracks allowed)
			(vias allowed)
			(pads allowed)
			(copperpour allowed)
			(footprints allowed)
		)
		(placement
			(enabled no)
			(sheetname "")
		)
		(fill
			(thermal_gap 0.5)
			(thermal_bridge_width 0.5)
			(island_removal_mode 0)
		)
		(polygon
			(pts
				(xy 421.060118 -46.986444) (xy 422.052496 -46.986444) (xy 422.137332 -46.901608) (xy 422.137332 -46.211744)
				(xy 422.089326 -46.163738) (xy 421.040052 -46.163738) (xy 420.972234 -46.231556) (xy 420.972234 -46.89856)
			)
		)
	)
	(zone
		(layer "F.Cu")
		(hatch none 0.5)
		(connect_pads
			(clearance 0)
		)
		(min_thickness 0.25)
		(keepout
			(tracks allowed)
			(vias allowed)
			(pads allowed)
			(copperpour allowed)
			(footprints allowed)
		)
		(placement
			(enabled no)
			(sheetname "")
		)
		(fill
			(thermal_gap 0.5)
			(thermal_bridge_width 0.5)
			(island_removal_mode 0)
		)
		(polygon
			(pts
				(xy 20.760182 -46.986444) (xy 21.75256 -46.986444) (xy 21.837396 -46.901608) (xy 21.837396 -46.211744)
				(xy 21.78939 -46.163738) (xy 20.740116 -46.163738) (xy 20.672298 -46.231556) (xy 20.672298 -46.89856)
			)
		)
	)
	(zone
		(layer "F.Cu")
		(hatch none 0.5)
		(connect_pads
			(clearance 0)
		)
		(min_thickness 0.25)
		(keepout
			(tracks allowed)
			(vias allowed)
			(pads allowed)
			(copperpour allowed)
			(footprints allowed)
		)
		(placement
			(enabled no)
			(sheetname "")
		)
		(fill
			(thermal_gap 0.5)
			(thermal_bridge_width 0.5)
			(island_removal_mode 0)
		)
		(polygon
			(pts
				(xy 403.381464 -344.635582) (xy 402.030184 -344.635582) (xy 402.030184 -343.355422) (xy 403.381464 -343.355422)
			)
		)
	)
	(zone
		(layer "F.Cu")
		(hatch none 0.5)
		(connect_pads
			(clearance 0)
		)
		(min_thickness 0.25)
		(keepout
			(tracks allowed)
			(vias allowed)
			(pads allowed)
			(copperpour allowed)
			(footprints not_allowed)
		)
		(placement
			(enabled no)
			(sheetname "")
		)
		(fill
			(thermal_gap 0.5)
			(thermal_bridge_width 0.5)
			(island_removal_mode 0)
		)
		(polygon
			(pts
				(xy 61.52007 -23.219918) (xy 61.52007 -18.219928) (xy 57.319926 -18.219928) (xy 57.319926 -23.219918)
			)
		)
	)
	(zone
		(layer "F.Cu")
		(hatch none 0.5)
		(connect_pads
			(clearance 0)
		)
		(min_thickness 0.25)
		(keepout
			(tracks not_allowed)
			(vias allowed)
			(pads allowed)
			(copperpour not_allowed)
			(footprints allowed)
		)
		(placement
			(enabled no)
			(sheetname "")
		)
		(fill
			(thermal_gap 0.5)
			(thermal_bridge_width 0.5)
			(island_removal_mode 0)
		)
		(polygon
			(pts
				(arc
					(start 466.600032 -407.599896)
					(mid 461.600042 -412.599886)
					(end 456.600052 -407.599896)
				)
				(arc
					(start 456.600052 -407.599896)
					(mid 461.600042 -402.599906)
					(end 466.600032 -407.599896)
				)
			)
		)
	)
	(zone
		(layer "F.Cu")
		(hatch none 0.5)
		(connect_pads
			(clearance 0)
		)
		(min_thickness 0.25)
		(keepout
			(tracks allowed)
			(vias allowed)
			(pads allowed)
			(copperpour allowed)
			(footprints allowed)
		)
		(placement
			(enabled no)
			(sheetname "")
		)
		(fill
			(thermal_gap 0.5)
			(thermal_bridge_width 0.5)
			(island_removal_mode 0)
		)
		(polygon
			(pts
				(xy 425.918376 -356.952042) (xy 424.567096 -356.952042) (xy 424.567096 -355.671882) (xy 425.918376 -355.671882)
			)
		)
	)
	(zone
		(layer "F.Cu")
		(hatch none 0.5)
		(connect_pads
			(clearance 0)
		)
		(min_thickness 0.25)
		(keepout
			(tracks allowed)
			(vias allowed)
			(pads allowed)
			(copperpour allowed)
			(footprints allowed)
		)
		(placement
			(enabled no)
			(sheetname "")
		)
		(fill
			(thermal_gap 0.5)
			(thermal_bridge_width 0.5)
			(island_removal_mode 0)
		)
		(polygon
			(pts
				(xy 23.545292 -356.952042) (xy 22.194012 -356.952042) (xy 22.194012 -355.671882) (xy 23.545292 -355.671882)
			)
		)
	)
	(zone
		(layer "F.Cu")
		(hatch none 0.5)
		(connect_pads
			(clearance 0)
		)
		(min_thickness 0.25)
		(keepout
			(tracks allowed)
			(vias allowed)
			(pads allowed)
			(copperpour allowed)
			(footprints not_allowed)
		)
		(placement
			(enabled no)
			(sheetname "")
		)
		(fill
			(thermal_gap 0.5)
			(thermal_bridge_width 0.5)
			(island_removal_mode 0)
		)
		(polygon
			(pts
				(xy 0.999998 -249.968766) (xy 25.649936 -264.189972) (xy 25.649936 -262.400034) (xy 93.650054 -262.400034)
				(xy 93.650054 -263.649968) (xy 117.700044 -245.483126) (xy 141.750034 -263.649968) (xy 141.750034 -262.400034)
				(xy 209.749898 -262.400034) (xy 209.749898 -263.649968) (xy 233.799888 -245.483126) (xy 257.849878 -263.649968)
				(xy 257.849878 -262.400034) (xy 325.849996 -262.400034) (xy 325.849996 -263.649968) (xy 349.899986 -245.483126)
				(xy 373.949976 -263.649968) (xy 373.949976 -262.400034) (xy 441.950094 -262.400034) (xy 441.950094 -264.189972)
				(xy 466.600032 -249.968766)
				(arc
					(start 466.600032 -246.488458)
					(mid 466.523912 -246.105775)
					(end 466.30717 -245.781322)
				)
				(arc
					(start 463.678778 -243.15293)
					(mid 463.02835 -242.179635)
					(end 462.799938 -241.031522)
				)
				(arc
					(start 462.799938 -219.8116)
					(mid 461.244098 -220.155413)
					(end 459.65491 -220.270832)
				)
				(xy 459.65491 -214.265764) (xy 454.754996 -214.265764)
				(arc
					(start 454.754996 -220.270832)
					(mid 444.476583 -213.189238)
					(end 447.432176 -201.062336)
				)
				(arc
					(start 447.432176 -201.062336)
					(mid 444.766463 -198.171633)
					(end 443.799976 -194.360038)
				)
				(arc
					(start 443.799976 -194.360038)
					(mid 451.79996 -186.360054)
					(end 459.799944 -194.360038)
				)
				(arc
					(start 459.799944 -194.360038)
					(mid 458.419615 -198.852243)
					(end 454.754996 -201.794364)
				)
				(xy 454.754996 -204.27569) (xy 459.65491 -204.27569)
				(arc
					(start 459.65491 -198.270622)
					(mid 461.244096 -198.386058)
					(end 462.799938 -198.729854)
				)
				(xy 462.799938 -107.780074) (xy 440.157616 -107.780074) (xy 440.157616 -177.9651) (xy 375.742454 -177.9651)
				(xy 375.742454 -107.780074) (xy 324.057518 -107.780074) (xy 324.057518 -177.9651) (xy 259.642356 -177.9651)
				(xy 259.642356 -107.780074) (xy 254.299974 -107.780074) (xy 254.299974 -116.19992) (xy 213.300056 -116.19992)
				(xy 213.300056 -107.780074) (xy 207.95742 -107.780074) (xy 207.95742 -177.9651) (xy 143.542258 -177.9651)
				(xy 143.542258 -107.780074) (xy 91.857576 -107.780074) (xy 91.857576 -177.9651) (xy 27.442414 -177.9651)
				(xy 27.442414 -107.780074) (xy 4.800092 -107.780074)
				(arc
					(start 4.800092 -241.031522)
					(mid 4.571629 -242.179614)
					(end 3.921252 -243.15293)
				)
				(arc
					(start 1.29286 -245.781322)
					(mid 1.076078 -246.105759)
					(end 0.999998 -246.488458)
				)
			)
		)
	)
	(zone
		(layer "F.Cu")
		(hatch none 0.5)
		(connect_pads
			(clearance 0)
		)
		(min_thickness 0.25)
		(keepout
			(tracks not_allowed)
			(vias allowed)
			(pads allowed)
			(copperpour not_allowed)
			(footprints allowed)
		)
		(placement
			(enabled no)
			(sheetname "")
		)
		(fill
			(thermal_gap 0.5)
			(thermal_bridge_width 0.5)
			(island_removal_mode 0)
		)
		(polygon
			(pts
				(arc
					(start 112.700054 -194.360038)
					(mid 117.700044 -189.360048)
					(end 122.700034 -194.360038)
				)
				(arc
					(start 122.700034 -194.360038)
					(mid 117.700044 -199.360028)
					(end 112.700054 -194.360038)
				)
			)
		)
	)
	(zone
		(layer "F.Cu")
		(hatch none 0.5)
		(connect_pads
			(clearance 0)
		)
		(min_thickness 0.25)
		(keepout
			(tracks not_allowed)
			(vias allowed)
			(pads allowed)
			(copperpour not_allowed)
			(footprints allowed)
		)
		(placement
			(enabled no)
			(sheetname "")
		)
		(fill
			(thermal_gap 0.5)
			(thermal_bridge_width 0.5)
			(island_removal_mode 0)
		)
		(polygon
			(pts
				(xy 278.820118 -18.150078) (xy 278.820118 -13.150088) (xy 274.619974 -13.150088) (xy 274.619974 -18.150078)
			)
		)
	)
	(zone
		(layer "F.Cu")
		(hatch none 0.5)
		(connect_pads
			(clearance 0)
		)
		(min_thickness 0.25)
		(keepout
			(tracks allowed)
			(vias allowed)
			(pads allowed)
			(copperpour allowed)
			(footprints allowed)
		)
		(placement
			(enabled no)
			(sheetname "")
		)
		(fill
			(thermal_gap 0.5)
			(thermal_bridge_width 0.5)
			(island_removal_mode 0)
		)
		(polygon
			(pts
				(xy 409.832556 -35.381946) (xy 411.142942 -35.381946) (xy 411.280102 -35.244786) (xy 411.280102 -27.580082)
				(xy 411.173422 -27.473402) (xy 409.497276 -27.473402) (xy 409.436316 -27.534362) (xy 409.436316 -34.985706)
			)
		)
	)
	(zone
		(layer "F.Cu")
		(hatch none 0.5)
		(connect_pads
			(clearance 0)
		)
		(min_thickness 0.25)
		(keepout
			(tracks allowed)
			(vias allowed)
			(pads allowed)
			(copperpour allowed)
			(footprints allowed)
		)
		(placement
			(enabled no)
			(sheetname "")
		)
		(fill
			(thermal_gap 0.5)
			(thermal_bridge_width 0.5)
			(island_removal_mode 0)
		)
		(polygon
			(pts
				(xy 69.235066 -117.970808) (xy 67.147694 -117.970808) (xy 66.827654 -118.290848) (xy 66.827654 -125.694948)
				(xy 69.172582 -125.694948) (xy 69.250814 -125.616716) (xy 69.250814 -117.986556)
			)
		)
	)
	(zone
		(layer "F.Cu")
		(hatch none 0.5)
		(connect_pads
			(clearance 0)
		)
		(min_thickness 0.25)
		(keepout
			(tracks not_allowed)
			(vias allowed)
			(pads allowed)
			(copperpour not_allowed)
			(footprints allowed)
		)
		(placement
			(enabled no)
			(sheetname "")
		)
		(fill
			(thermal_gap 0.5)
			(thermal_bridge_width 0.5)
			(island_removal_mode 0)
		)
		(polygon
			(pts
				(arc
					(start 213.300056 -98.700082)
					(mid 208.300066 -103.700072)
					(end 203.300076 -98.700082)
				)
				(arc
					(start 203.300076 -98.700082)
					(mid 208.300066 -93.700092)
					(end 213.300056 -98.700082)
				)
			)
		)
	)
	(zone
		(layer "F.Cu")
		(hatch none 0.5)
		(connect_pads
			(clearance 0)
		)
		(min_thickness 0.25)
		(keepout
			(tracks allowed)
			(vias allowed)
			(pads allowed)
			(copperpour allowed)
			(footprints allowed)
		)
		(placement
			(enabled no)
			(sheetname "")
		)
		(fill
			(thermal_gap 0.5)
			(thermal_bridge_width 0.5)
			(island_removal_mode 0)
		)
		(polygon
			(pts
				(xy 448.737736 -19.7358) (xy 448.737736 -19.2024) (xy 449.804536 -19.2024) (xy 449.804536 -19.7358)
			)
		)
	)
	(zone
		(layer "F.Cu")
		(hatch none 0.5)
		(connect_pads
			(clearance 0)
		)
		(min_thickness 0.25)
		(keepout
			(tracks allowed)
			(vias allowed)
			(pads allowed)
			(copperpour allowed)
			(footprints allowed)
		)
		(placement
			(enabled no)
			(sheetname "")
		)
		(fill
			(thermal_gap 0.5)
			(thermal_bridge_width 0.5)
			(island_removal_mode 0)
		)
		(polygon
			(pts
				(xy 204.621638 -370.613178) (xy 204.621638 -367.239804) (xy 208.042764 -367.239804) (xy 208.042764 -370.613178)
			)
		)
	)
	(zone
		(layer "F.Cu")
		(hatch none 0.5)
		(connect_pads
			(clearance 0)
		)
		(min_thickness 0.25)
		(keepout
			(tracks allowed)
			(vias allowed)
			(pads allowed)
			(copperpour allowed)
			(footprints not_allowed)
		)
		(placement
			(enabled no)
			(sheetname "")
		)
		(fill
			(thermal_gap 0.5)
			(thermal_bridge_width 0.5)
			(island_removal_mode 0)
		)
		(polygon
			(pts
				(arc
					(start 379.957076 -232.750106)
					(mid 367.998999 -243.749914)
					(end 356.04069 -232.750106)
				)
			)
		)
	)
	(zone
		(layer "F.Cu")
		(hatch none 0.5)
		(connect_pads
			(clearance 0)
		)
		(min_thickness 0.25)
		(keepout
			(tracks allowed)
			(vias allowed)
			(pads allowed)
			(copperpour allowed)
			(footprints allowed)
		)
		(placement
			(enabled no)
			(sheetname "")
		)
		(fill
			(thermal_gap 0.5)
			(thermal_bridge_width 0.5)
			(island_removal_mode 0)
		)
		(polygon
			(pts
				(xy 316.715648 -356.952042) (xy 315.364368 -356.952042) (xy 315.364368 -355.671882) (xy 316.715648 -355.671882)
			)
		)
	)
	(zone
		(layer "F.Cu")
		(hatch none 0.5)
		(connect_pads
			(clearance 0)
		)
		(min_thickness 0.25)
		(keepout
			(tracks allowed)
			(vias allowed)
			(pads allowed)
			(copperpour allowed)
			(footprints allowed)
		)
		(placement
			(enabled no)
			(sheetname "")
		)
		(fill
			(thermal_gap 0.5)
			(thermal_bridge_width 0.5)
			(island_removal_mode 0)
		)
		(polygon
			(pts
				(xy 71.75119 -34.76117) (xy 71.75119 -33.40989) (xy 73.03135 -33.40989) (xy 73.03135 -34.76117)
			)
		)
	)
	(zone
		(layer "F.Cu")
		(hatch none 0.5)
		(connect_pads
			(clearance 0)
		)
		(min_thickness 0.25)
		(keepout
			(tracks not_allowed)
			(vias allowed)
			(pads allowed)
			(copperpour not_allowed)
			(footprints allowed)
		)
		(placement
			(enabled no)
			(sheetname "")
		)
		(fill
			(thermal_gap 0.5)
			(thermal_bridge_width 0.5)
			(island_removal_mode 0)
		)
		(polygon
			(pts
				(arc
					(start 202.200002 -393.100052)
					(mid 199.40016 -395.899894)
					(end 196.600064 -393.100052)
				)
				(arc
					(start 196.600064 -393.100052)
					(mid 199.40016 -390.299956)
					(end 202.200002 -393.100052)
				)
			)
		)
	)
	(zone
		(layer "F.Cu")
		(hatch none 0.5)
		(connect_pads
			(clearance 0)
		)
		(min_thickness 0.25)
		(keepout
			(tracks allowed)
			(vias allowed)
			(pads allowed)
			(copperpour allowed)
			(footprints not_allowed)
		)
		(placement
			(enabled no)
			(sheetname "")
		)
		(fill
			(thermal_gap 0.5)
			(thermal_bridge_width 0.5)
			(island_removal_mode 0)
		)
		(polygon
			(pts
				(xy 373.949976 -342.399874) (xy 373.949976 -263.649968) (xy 367.450116 -258.739894) (xy 367.450116 -322.200016)
				(xy 332.35011 -322.200016) (xy 332.35011 -258.739894) (xy 325.849996 -263.649968) (xy 325.849996 -342.399874)
			)
		)
	)
	(zone
		(layer "F.Cu")
		(hatch none 0.5)
		(connect_pads
			(clearance 0)
		)
		(min_thickness 0.25)
		(keepout
			(tracks not_allowed)
			(vias allowed)
			(pads allowed)
			(copperpour not_allowed)
			(footprints allowed)
		)
		(placement
			(enabled no)
			(sheetname "")
		)
		(fill
			(thermal_gap 0.5)
			(thermal_bridge_width 0.5)
			(island_removal_mode 0)
		)
		(polygon
			(pts
				(arc
					(start 27.399996 -320.900044)
					(mid 29.650182 -318.649858)
					(end 31.900114 -320.900044)
				)
				(arc
					(start 31.900114 -320.900044)
					(mid 29.650182 -323.149976)
					(end 27.399996 -320.900044)
				)
			)
		)
	)
	(zone
		(layer "F.Cu")
		(hatch none 0.5)
		(connect_pads
			(clearance 0)
		)
		(min_thickness 0.25)
		(keepout
			(tracks not_allowed)
			(vias allowed)
			(pads allowed)
			(copperpour not_allowed)
			(footprints allowed)
		)
		(placement
			(enabled no)
			(sheetname "")
		)
		(fill
			(thermal_gap 0.5)
			(thermal_bridge_width 0.5)
			(island_removal_mode 0)
		)
		(polygon
			(pts
				(xy 9.51992 -23.219918) (xy 9.51992 -18.219928) (xy 5.32003 -18.219928) (xy 5.32003 -23.219918)
			)
		)
	)
	(zone
		(layer "F.Cu")
		(hatch none 0.5)
		(connect_pads
			(clearance 0)
		)
		(min_thickness 0.25)
		(keepout
			(tracks allowed)
			(vias allowed)
			(pads allowed)
			(copperpour allowed)
			(footprints allowed)
		)
		(placement
			(enabled no)
			(sheetname "")
		)
		(fill
			(thermal_gap 0.5)
			(thermal_bridge_width 0.5)
			(island_removal_mode 0)
		)
		(polygon
			(pts
				(xy 250.0122 -150.1902) (xy 250.0122 -148.463) (xy 251.6886 -148.463) (xy 251.6886 -150.1902)
			)
		)
	)
	(zone
		(layer "F.Cu")
		(hatch none 0.5)
		(connect_pads
			(clearance 0)
		)
		(min_thickness 0.25)
		(keepout
			(tracks allowed)
			(vias allowed)
			(pads allowed)
			(copperpour allowed)
			(footprints not_allowed)
		)
		(placement
			(enabled no)
			(sheetname "")
		)
		(fill
			(thermal_gap 0.5)
			(thermal_bridge_width 0.5)
			(island_removal_mode 0)
		)
		(polygon
			(pts
				(arc
					(start 132.249926 -276.010116)
					(mid 136.249918 -272.010124)
					(end 140.24991 -276.010116)
				)
				(arc
					(start 140.24991 -276.010116)
					(mid 136.249918 -280.010108)
					(end 132.249926 -276.010116)
				)
			)
		)
	)
	(zone
		(layer "F.Cu")
		(hatch none 0.5)
		(connect_pads
			(clearance 0)
		)
		(min_thickness 0.25)
		(keepout
			(tracks allowed)
			(vias allowed)
			(pads allowed)
			(copperpour allowed)
			(footprints allowed)
		)
		(placement
			(enabled no)
			(sheetname "")
		)
		(fill
			(thermal_gap 0.5)
			(thermal_bridge_width 0.5)
			(island_removal_mode 0)
		)
		(polygon
			(pts
				(xy 335.769458 -83.996784) (xy 340.469474 -83.996784) (xy 340.910418 -83.55584) (xy 340.910418 -82.604356)
				(xy 340.910418 -82.120486) (xy 340.581488 -81.791556) (xy 338.94268 -81.791556) (xy 338.64804 -81.496916)
				(xy 337.758786 -81.496916) (xy 336.66303 -82.592672) (xy 335.781142 -82.592672) (xy 335.746344 -82.62747)
				(xy 335.746344 -83.97367)
			)
		)
	)
	(zone
		(layer "F.Cu")
		(hatch none 0.5)
		(connect_pads
			(clearance 0)
		)
		(min_thickness 0.25)
		(keepout
			(tracks allowed)
			(vias allowed)
			(pads allowed)
			(copperpour allowed)
			(footprints allowed)
		)
		(placement
			(enabled no)
			(sheetname "")
		)
		(fill
			(thermal_gap 0.5)
			(thermal_bridge_width 0.5)
			(island_removal_mode 0)
		)
		(polygon
			(pts
				(xy 160.573974 -126.219204) (xy 162.661346 -126.219204) (xy 162.981386 -125.899164) (xy 162.981386 -118.495064)
				(xy 160.636458 -118.495064) (xy 160.558226 -118.573296) (xy 160.558226 -126.203456)
			)
		)
	)
	(zone
		(layer "F.Cu")
		(hatch none 0.5)
		(connect_pads
			(clearance 0)
		)
		(min_thickness 0.25)
		(keepout
			(tracks allowed)
			(vias allowed)
			(pads allowed)
			(copperpour allowed)
			(footprints allowed)
		)
		(placement
			(enabled no)
			(sheetname "")
		)
		(fill
			(thermal_gap 0.5)
			(thermal_bridge_width 0.5)
			(island_removal_mode 0)
		)
		(polygon
			(pts
				(xy 372.291864 -344.659458) (xy 370.940584 -344.659458) (xy 370.940584 -343.379298) (xy 372.291864 -343.379298)
			)
		)
	)
	(zone
		(layer "F.Cu")
		(hatch none 0.5)
		(connect_pads
			(clearance 0)
		)
		(min_thickness 0.25)
		(keepout
			(tracks allowed)
			(vias allowed)
			(pads allowed)
			(copperpour allowed)
			(footprints allowed)
		)
		(placement
			(enabled no)
			(sheetname "")
		)
		(fill
			(thermal_gap 0.5)
			(thermal_bridge_width 0.5)
			(island_removal_mode 0)
		)
		(polygon
			(pts
				(xy 185.20918 -32.954468) (xy 185.20918 -31.603188) (xy 186.48934 -31.603188) (xy 186.48934 -32.954468)
			)
		)
	)
	(zone
		(layer "F.Cu")
		(hatch none 0.5)
		(connect_pads
			(clearance 0)
		)
		(min_thickness 0.25)
		(keepout
			(tracks allowed)
			(vias allowed)
			(pads allowed)
			(copperpour allowed)
			(footprints allowed)
		)
		(placement
			(enabled no)
			(sheetname "")
		)
		(fill
			(thermal_gap 0.5)
			(thermal_bridge_width 0.5)
			(island_removal_mode 0)
		)
		(polygon
			(pts
				(xy 42.199052 -344.659458) (xy 40.847772 -344.659458) (xy 40.847772 -343.379298) (xy 42.199052 -343.379298)
			)
		)
	)
	(zone
		(layer "F.Cu")
		(hatch none 0.5)
		(connect_pads
			(clearance 0)
		)
		(min_thickness 0.25)
		(keepout
			(tracks allowed)
			(vias allowed)
			(pads allowed)
			(copperpour allowed)
			(footprints allowed)
		)
		(placement
			(enabled no)
			(sheetname "")
		)
		(fill
			(thermal_gap 0.5)
			(thermal_bridge_width 0.5)
			(island_removal_mode 0)
		)
		(polygon
			(pts
				(xy 195.435982 -154.51963) (xy 195.435982 -153.16835) (xy 196.716142 -153.16835) (xy 196.716142 -154.51963)
			)
		)
	)
	(zone
		(layer "F.Cu")
		(hatch none 0.5)
		(connect_pads
			(clearance 0)
		)
		(min_thickness 0.25)
		(keepout
			(tracks allowed)
			(vias allowed)
			(pads allowed)
			(copperpour allowed)
			(footprints allowed)
		)
		(placement
			(enabled no)
			(sheetname "")
		)
		(fill
			(thermal_gap 0.5)
			(thermal_bridge_width 0.5)
			(island_removal_mode 0)
		)
		(polygon
			(pts
				(xy 135.851392 -34.76117) (xy 135.851392 -33.40989) (xy 137.131552 -33.40989) (xy 137.131552 -34.76117)
			)
		)
	)
	(zone
		(layer "F.Cu")
		(hatch none 0.5)
		(connect_pads
			(clearance 0)
		)
		(min_thickness 0.25)
		(keepout
			(tracks allowed)
			(vias allowed)
			(pads allowed)
			(copperpour allowed)
			(footprints allowed)
		)
		(placement
			(enabled no)
			(sheetname "")
		)
		(fill
			(thermal_gap 0.5)
			(thermal_bridge_width 0.5)
			(island_removal_mode 0)
		)
		(polygon
			(pts
				(xy 181.943756 -350.80575) (xy 180.592476 -350.80575) (xy 180.592476 -349.52559) (xy 181.943756 -349.52559)
			)
		)
	)
	(zone
		(layer "F.Cu")
		(hatch none 0.5)
		(connect_pads
			(clearance 0)
		)
		(min_thickness 0.25)
		(keepout
			(tracks allowed)
			(vias allowed)
			(pads allowed)
			(copperpour allowed)
			(footprints allowed)
		)
		(placement
			(enabled no)
			(sheetname "")
		)
		(fill
			(thermal_gap 0.5)
			(thermal_bridge_width 0.5)
			(island_removal_mode 0)
		)
		(polygon
			(pts
				(xy 432.136296 -344.659458) (xy 430.785016 -344.659458) (xy 430.785016 -343.379298) (xy 432.136296 -343.379298)
			)
		)
	)
	(zone
		(layer "F.Cu")
		(hatch none 0.5)
		(connect_pads
			(clearance 0)
		)
		(min_thickness 0.25)
		(keepout
			(tracks allowed)
			(vias allowed)
			(pads allowed)
			(copperpour allowed)
			(footprints not_allowed)
		)
		(placement
			(enabled no)
			(sheetname "")
		)
		(fill
			(thermal_gap 0.5)
			(thermal_bridge_width 0.5)
			(island_removal_mode 0)
		)
		(polygon
			(pts
				(arc
					(start 103.149908 -289.820096)
					(mid 102.312186 -292.269582)
					(end 100.149914 -293.693088)
				)
				(xy 100.149914 -322.200016) (xy 135.24992 -322.200016) (xy 135.24992 -288.230056)
				(arc
					(start 102.82047 -288.230056)
					(mid 103.066701 -289.008185)
					(end 103.149908 -289.820096)
				)
			)
		)
	)
	(zone
		(layer "F.Cu")
		(hatch none 0.5)
		(connect_pads
			(clearance 0)
		)
		(min_thickness 0.25)
		(keepout
			(tracks allowed)
			(vias allowed)
			(pads allowed)
			(copperpour allowed)
			(footprints allowed)
		)
		(placement
			(enabled no)
			(sheetname "")
		)
		(fill
			(thermal_gap 0.5)
			(thermal_bridge_width 0.5)
			(island_removal_mode 0)
		)
		(polygon
			(pts
				(xy 132.950458 -284.544262) (xy 133.427216 -284.544262) (xy 133.688582 -284.805628) (xy 133.805168 -284.805628)
				(xy 134.013448 -284.597348) (xy 134.013448 -282.759404) (xy 133.615684 -282.36164) (xy 133.039866 -282.36164)
				(xy 132.888228 -282.513278) (xy 132.888228 -284.482032)
			)
		)
	)
	(zone
		(layer "F.Cu")
		(hatch none 0.5)
		(connect_pads
			(clearance 0)
		)
		(min_thickness 0.25)
		(keepout
			(tracks allowed)
			(vias allowed)
			(pads allowed)
			(copperpour allowed)
			(footprints allowed)
		)
		(placement
			(enabled no)
			(sheetname "")
		)
		(fill
			(thermal_gap 0.5)
			(thermal_bridge_width 0.5)
			(island_removal_mode 0)
		)
		(polygon
			(pts
				(xy 435.245256 -350.80575) (xy 433.893976 -350.80575) (xy 433.893976 -349.52559) (xy 435.245256 -349.52559)
			)
		)
	)
	(zone
		(layer "F.Cu")
		(hatch none 0.5)
		(connect_pads
			(clearance 0)
		)
		(min_thickness 0.25)
		(keepout
			(tracks not_allowed)
			(vias allowed)
			(pads allowed)
			(copperpour not_allowed)
			(footprints allowed)
		)
		(placement
			(enabled no)
			(sheetname "")
		)
		(fill
			(thermal_gap 0.5)
			(thermal_bridge_width 0.5)
			(island_removal_mode 0)
		)
		(polygon
			(pts
				(arc
					(start 203.499974 -320.900044)
					(mid 205.75016 -318.649858)
					(end 208.000092 -320.900044)
				)
				(arc
					(start 208.000092 -320.900044)
					(mid 205.75016 -323.149976)
					(end 203.499974 -320.900044)
				)
			)
		)
	)
	(zone
		(layer "F.Cu")
		(hatch none 0.5)
		(connect_pads
			(clearance 0)
		)
		(min_thickness 0.25)
		(keepout
			(tracks allowed)
			(vias allowed)
			(pads allowed)
			(copperpour allowed)
			(footprints allowed)
		)
		(placement
			(enabled no)
			(sheetname "")
		)
		(fill
			(thermal_gap 0.5)
			(thermal_bridge_width 0.5)
			(island_removal_mode 0)
		)
		(polygon
			(pts
				(xy 419.700456 -356.952042) (xy 418.349176 -356.952042) (xy 418.349176 -355.671882) (xy 419.700456 -355.671882)
			)
		)
	)
	(zone
		(layer "F.Cu")
		(hatch none 0.5)
		(connect_pads
			(clearance 0)
		)
		(min_thickness 0.25)
		(keepout
			(tracks not_allowed)
			(vias allowed)
			(pads allowed)
			(copperpour not_allowed)
			(footprints allowed)
		)
		(placement
			(enabled no)
			(sheetname "")
		)
		(fill
			(thermal_gap 0.5)
			(thermal_bridge_width 0.5)
			(island_removal_mode 0)
		)
		(polygon
			(pts
				(xy 457.065634 -249.22988) (xy 457.065634 -246.336566) (xy 457.233274 -246.336566) (xy 457.233274 -249.22988)
			)
		)
	)
	(zone
		(layer "F.Cu")
		(hatch none 0.5)
		(connect_pads
			(clearance 0)
		)
		(min_thickness 0.25)
		(keepout
			(tracks not_allowed)
			(vias allowed)
			(pads allowed)
			(copperpour not_allowed)
			(footprints allowed)
		)
		(placement
			(enabled no)
			(sheetname "")
		)
		(fill
			(thermal_gap 0.5)
			(thermal_bridge_width 0.5)
			(island_removal_mode 0)
		)
		(polygon
			(pts
				(arc
					(start 435.699916 -270.89989)
					(mid 437.950102 -268.649704)
					(end 440.200034 -270.89989)
				)
				(arc
					(start 440.200034 -270.89989)
					(mid 437.950102 -273.149822)
					(end 435.699916 -270.89989)
				)
			)
		)
	)
	(zone
		(layer "F.Cu")
		(hatch none 0.5)
		(connect_pads
			(clearance 0)
		)
		(min_thickness 0.25)
		(keepout
			(tracks allowed)
			(vias allowed)
			(pads allowed)
			(copperpour allowed)
			(footprints not_allowed)
		)
		(placement
			(enabled no)
			(sheetname "")
		)
		(fill
			(thermal_gap 0.5)
			(thermal_bridge_width 0.5)
			(island_removal_mode 0)
		)
		(polygon
			(pts
				(xy 52.559966 -361.790234) (xy 23.459948 -361.790234) (xy 23.459948 -417.58997) (xy 52.559966 -417.58997)
			)
		)
	)
	(zone
		(layer "F.Cu")
		(hatch none 0.5)
		(connect_pads
			(clearance 0)
		)
		(min_thickness 0.25)
		(keepout
			(tracks allowed)
			(vias allowed)
			(pads allowed)
			(copperpour allowed)
			(footprints allowed)
		)
		(placement
			(enabled no)
			(sheetname "")
		)
		(fill
			(thermal_gap 0.5)
			(thermal_bridge_width 0.5)
			(island_removal_mode 0)
		)
		(polygon
			(pts
				(xy 79.336138 -143.71955) (xy 79.336138 -142.36827) (xy 80.616298 -142.36827) (xy 80.616298 -143.71955)
			)
		)
	)
	(zone
		(layer "F.Cu")
		(hatch none 0.5)
		(connect_pads
			(clearance 0)
		)
		(min_thickness 0.25)
		(keepout
			(tracks allowed)
			(vias allowed)
			(pads allowed)
			(copperpour allowed)
			(footprints allowed)
		)
		(placement
			(enabled no)
			(sheetname "")
		)
		(fill
			(thermal_gap 0.5)
			(thermal_bridge_width 0.5)
			(island_removal_mode 0)
		)
		(polygon
			(pts
				(xy 161.85134 -31.160974) (xy 161.85134 -29.809694) (xy 163.1315 -29.809694) (xy 163.1315 -31.160974)
			)
		)
	)
	(zone
		(layer "F.Cu")
		(hatch none 0.5)
		(connect_pads
			(clearance 0)
		)
		(min_thickness 0.25)
		(keepout
			(tracks not_allowed)
			(vias allowed)
			(pads allowed)
			(copperpour not_allowed)
			(footprints allowed)
		)
		(placement
			(enabled no)
			(sheetname "")
		)
		(fill
			(thermal_gap 0.5)
			(thermal_bridge_width 0.5)
			(island_removal_mode 0)
		)
		(polygon
			(pts
				(arc
					(start 145.749772 -262.899906)
					(mid 153.749756 -270.89989)
					(end 145.749772 -278.899874)
				)
				(arc
					(start 145.749772 -275.675344)
					(mid 150.524972 -270.900144)
					(end 145.749772 -266.12469)
				)
			)
		)
	)
	(zone
		(layer "F.Cu")
		(hatch none 0.5)
		(connect_pads
			(clearance 0)
		)
		(min_thickness 0.25)
		(keepout
			(tracks allowed)
			(vias allowed)
			(pads allowed)
			(copperpour allowed)
			(footprints allowed)
		)
		(placement
			(enabled no)
			(sheetname "")
		)
		(fill
			(thermal_gap 0.5)
			(thermal_bridge_width 0.5)
			(island_removal_mode 0)
		)
		(polygon
			(pts
				(xy 455.168 -113.665) (xy 455.168 -109.855) (xy 456.692 -109.855) (xy 456.692 -113.665)
			)
		)
	)
	(zone
		(layer "F.Cu")
		(hatch none 0.5)
		(connect_pads
			(clearance 0)
		)
		(min_thickness 0.25)
		(keepout
			(tracks not_allowed)
			(vias allowed)
			(pads allowed)
			(copperpour not_allowed)
			(footprints allowed)
		)
		(placement
			(enabled no)
			(sheetname "")
		)
		(fill
			(thermal_gap 0.5)
			(thermal_bridge_width 0.5)
			(island_removal_mode 0)
		)
		(polygon
			(pts
				(arc
					(start 106.009948 -407.599896)
					(mid 104.009952 -409.599892)
					(end 102.009956 -407.599896)
				)
				(arc
					(start 102.009956 -407.599896)
					(mid 104.009952 -405.5999)
					(end 106.009948 -407.599896)
				)
			)
		)
	)
	(zone
		(layer "F.Cu")
		(hatch none 0.5)
		(connect_pads
			(clearance 0)
		)
		(min_thickness 0.25)
		(keepout
			(tracks allowed)
			(vias allowed)
			(pads allowed)
			(copperpour allowed)
			(footprints allowed)
		)
		(placement
			(enabled no)
			(sheetname "")
		)
		(fill
			(thermal_gap 0.5)
			(thermal_bridge_width 0.5)
			(island_removal_mode 0)
		)
		(polygon
			(pts
				(xy 278.302466 -356.952042) (xy 276.951186 -356.952042) (xy 276.951186 -355.671882) (xy 278.302466 -355.671882)
			)
		)
	)
	(zone
		(layer "F.Cu")
		(hatch none 0.5)
		(connect_pads
			(clearance 0)
		)
		(min_thickness 0.25)
		(keepout
			(tracks allowed)
			(vias allowed)
			(pads allowed)
			(copperpour allowed)
			(footprints allowed)
		)
		(placement
			(enabled no)
			(sheetname "")
		)
		(fill
			(thermal_gap 0.5)
			(thermal_bridge_width 0.5)
			(island_removal_mode 0)
		)
		(polygon
			(pts
				(xy 435.245256 -356.952042) (xy 433.893976 -356.952042) (xy 433.893976 -355.671882) (xy 435.245256 -355.671882)
			)
		)
	)
	(zone
		(layer "F.Cu")
		(hatch none 0.5)
		(connect_pads
			(clearance 0)
		)
		(min_thickness 0.25)
		(keepout
			(tracks allowed)
			(vias allowed)
			(pads allowed)
			(copperpour allowed)
			(footprints allowed)
		)
		(placement
			(enabled no)
			(sheetname "")
		)
		(fill
			(thermal_gap 0.5)
			(thermal_bridge_width 0.5)
			(island_removal_mode 0)
		)
		(polygon
			(pts
				(xy 393.197588 -113.527078) (xy 395.0081 -113.527078) (xy 395.054582 -113.480596) (xy 395.054582 -98.737674)
				(xy 394.909294 -98.592386) (xy 393.157202 -98.592386) (xy 393.081764 -98.667824) (xy 393.081764 -113.411254)
			)
		)
	)
	(zone
		(layer "F.Cu")
		(hatch none 0.5)
		(connect_pads
			(clearance 0)
		)
		(min_thickness 0.25)
		(keepout
			(tracks not_allowed)
			(vias allowed)
			(pads allowed)
			(copperpour not_allowed)
			(footprints allowed)
		)
		(placement
			(enabled no)
			(sheetname "")
		)
		(fill
			(thermal_gap 0.5)
			(thermal_bridge_width 0.5)
			(island_removal_mode 0)
		)
		(polygon
			(pts
				(arc
					(start 460.93253 -5.999988)
					(mid 455.93254 -10.999978)
					(end 450.93255 -5.999988)
				)
				(arc
					(start 450.93255 -5.999988)
					(mid 455.93254 -0.999998)
					(end 460.93253 -5.999988)
				)
			)
		)
	)
	(zone
		(layer "F.Cu")
		(hatch none 0.5)
		(connect_pads
			(clearance 0)
		)
		(min_thickness 0.25)
		(keepout
			(tracks allowed)
			(vias allowed)
			(pads allowed)
			(copperpour allowed)
			(footprints not_allowed)
		)
		(placement
			(enabled no)
			(sheetname "")
		)
		(fill
			(thermal_gap 0.5)
			(thermal_bridge_width 0.5)
			(island_removal_mode 0)
		)
		(polygon
			(pts
				(xy 216.244932 -303.980088)
				(arc
					(start 216.244932 -307.250084)
					(mid 219.541304 -308.099481)
					(end 220.989906 -311.179972)
				)
				(arc
					(start 220.989906 -311.179972)
					(mid 220.987533 -311.320011)
					(end 220.980254 -311.45988)
				)
				(xy 251.338588 -311.45988)
				(arc
					(start 251.338588 -301.239936)
					(mid 249.184175 -299.814763)
					(end 248.350024 -297.369992)
				)
				(xy 248.333514 -303.980088)
			)
		)
	)
	(zone
		(layer "F.Cu")
		(hatch none 0.5)
		(connect_pads
			(clearance 0)
		)
		(min_thickness 0.25)
		(keepout
			(tracks allowed)
			(vias allowed)
			(pads allowed)
			(copperpour allowed)
			(footprints allowed)
		)
		(placement
			(enabled no)
			(sheetname "")
		)
		(fill
			(thermal_gap 0.5)
			(thermal_bridge_width 0.5)
			(island_removal_mode 0)
		)
		(polygon
			(pts
				(xy 202.637898 -370.637054) (xy 202.637898 -369.615466) (xy 204.17028 -369.615466) (xy 204.17028 -370.637054)
			)
		)
	)
	(zone
		(layer "F.Cu")
		(hatch none 0.5)
		(connect_pads
			(clearance 0)
		)
		(min_thickness 0.25)
		(keepout
			(tracks allowed)
			(vias allowed)
			(pads allowed)
			(copperpour allowed)
			(footprints allowed)
		)
		(placement
			(enabled no)
			(sheetname "")
		)
		(fill
			(thermal_gap 0.5)
			(thermal_bridge_width 0.5)
			(island_removal_mode 0)
		)
		(polygon
			(pts
				(xy 172.616876 -344.659458) (xy 171.265596 -344.659458) (xy 171.265596 -343.379298) (xy 172.616876 -343.379298)
			)
		)
	)
	(zone
		(layer "F.Cu")
		(hatch none 0.5)
		(connect_pads
			(clearance 0)
		)
		(min_thickness 0.25)
		(keepout
			(tracks allowed)
			(vias allowed)
			(pads allowed)
			(copperpour allowed)
			(footprints allowed)
		)
		(placement
			(enabled no)
			(sheetname "")
		)
		(fill
			(thermal_gap 0.5)
			(thermal_bridge_width 0.5)
			(island_removal_mode 0)
		)
		(polygon
			(pts
				(xy 394.054584 -350.80575) (xy 392.703304 -350.80575) (xy 392.703304 -349.52559) (xy 394.054584 -349.52559)
			)
		)
	)
	(zone
		(layer "F.Cu")
		(hatch none 0.5)
		(connect_pads
			(clearance 0)
		)
		(min_thickness 0.25)
		(keepout
			(tracks not_allowed)
			(vias allowed)
			(pads allowed)
			(copperpour not_allowed)
			(footprints allowed)
		)
		(placement
			(enabled no)
			(sheetname "")
		)
		(fill
			(thermal_gap 0.5)
			(thermal_bridge_width 0.5)
			(island_removal_mode 0)
		)
		(polygon
			(pts
				(xy 98.620072 -18.150078) (xy 98.620072 -13.150088) (xy 94.419928 -13.150088) (xy 94.419928 -18.150078)
			)
		)
	)
	(zone
		(layer "F.Cu")
		(hatch none 0.5)
		(connect_pads
			(clearance 0)
		)
		(min_thickness 0.25)
		(keepout
			(tracks allowed)
			(vias allowed)
			(pads allowed)
			(copperpour allowed)
			(footprints allowed)
		)
		(placement
			(enabled no)
			(sheetname "")
		)
		(fill
			(thermal_gap 0.5)
			(thermal_bridge_width 0.5)
			(island_removal_mode 0)
		)
		(polygon
			(pts
				(xy 195.435982 -134.609586) (xy 195.435982 -133.258306) (xy 196.716142 -133.258306) (xy 196.716142 -134.609586)
			)
		)
	)
	(zone
		(layer "F.Cu")
		(hatch none 0.5)
		(connect_pads
			(clearance 0)
		)
		(min_thickness 0.25)
		(keepout
			(tracks allowed)
			(vias allowed)
			(pads allowed)
			(copperpour allowed)
			(footprints allowed)
		)
		(placement
			(enabled no)
			(sheetname "")
		)
		(fill
			(thermal_gap 0.5)
			(thermal_bridge_width 0.5)
			(island_removal_mode 0)
		)
		(polygon
			(pts
				(xy 106.49712 -386.14731) (xy 106.86796 -386.14731) (xy 107.05338 -385.96189) (xy 107.05338 -384.769868)
				(xy 107.026964 -384.743452) (xy 106.426508 -384.743452) (xy 106.426508 -386.076698)
			)
		)
	)
	(zone
		(layer "F.Cu")
		(hatch none 0.5)
		(connect_pads
			(clearance 0)
		)
		(min_thickness 0.25)
		(keepout
			(tracks not_allowed)
			(vias allowed)
			(pads allowed)
			(copperpour not_allowed)
			(footprints allowed)
		)
		(placement
			(enabled no)
			(sheetname "")
		)
		(fill
			(thermal_gap 0.5)
			(thermal_bridge_width 0.5)
			(island_removal_mode 0)
		)
		(polygon
			(pts
				(arc
					(start 5.199888 -396.500096)
					(mid 3.599942 -398.100042)
					(end 5.199888 -399.699988)
				)
				(arc
					(start 6.800088 -399.699988)
					(mid 8.400034 -398.100042)
					(end 6.800088 -396.500096)
				)
			)
		)
	)
	(zone
		(layer "F.Cu")
		(hatch none 0.5)
		(connect_pads
			(clearance 0)
		)
		(min_thickness 0.25)
		(keepout
			(tracks allowed)
			(vias allowed)
			(pads allowed)
			(copperpour allowed)
			(footprints allowed)
		)
		(placement
			(enabled no)
			(sheetname "")
		)
		(fill
			(thermal_gap 0.5)
			(thermal_bridge_width 0.5)
			(island_removal_mode 0)
		)
		(polygon
			(pts
				(xy 430.278286 -125.205998) (xy 430.278286 -123.854718) (xy 431.558446 -123.854718) (xy 431.558446 -125.205998)
			)
		)
	)
	(zone
		(layer "F.Cu")
		(hatch none 0.5)
		(connect_pads
			(clearance 0)
		)
		(min_thickness 0.25)
		(keepout
			(tracks allowed)
			(vias allowed)
			(pads allowed)
			(copperpour allowed)
			(footprints allowed)
		)
		(placement
			(enabled no)
			(sheetname "")
		)
		(fill
			(thermal_gap 0.5)
			(thermal_bridge_width 0.5)
			(island_removal_mode 0)
		)
		(polygon
			(pts
				(xy 332.235048 -344.659458) (xy 330.883768 -344.659458) (xy 330.883768 -343.379298) (xy 332.235048 -343.379298)
			)
		)
	)
	(zone
		(layer "F.Cu")
		(hatch none 0.5)
		(connect_pads
			(clearance 0)
		)
		(min_thickness 0.25)
		(keepout
			(tracks allowed)
			(vias allowed)
			(pads allowed)
			(copperpour allowed)
			(footprints not_allowed)
		)
		(placement
			(enabled no)
			(sheetname "")
		)
		(fill
			(thermal_gap 0.5)
			(thermal_bridge_width 0.5)
			(island_removal_mode 0)
		)
		(polygon
			(pts
				(arc
					(start 459.65491 -220.270832)
					(mid 461.244096 -220.155396)
					(end 462.799938 -219.8116)
				)
				(arc
					(start 462.799938 -198.729854)
					(mid 461.244098 -198.386041)
					(end 459.65491 -198.270622)
				)
			)
		)
	)
	(zone
		(layer "F.Cu")
		(hatch none 0.5)
		(connect_pads
			(clearance 0)
		)
		(min_thickness 0.25)
		(keepout
			(tracks allowed)
			(vias allowed)
			(pads allowed)
			(copperpour allowed)
			(footprints allowed)
		)
		(placement
			(enabled no)
			(sheetname "")
		)
		(fill
			(thermal_gap 0.5)
			(thermal_bridge_width 0.5)
			(island_removal_mode 0)
		)
		(polygon
			(pts
				(xy 29.763212 -350.80575) (xy 28.411932 -350.80575) (xy 28.411932 -349.52559) (xy 29.763212 -349.52559)
			)
		)
	)
	(zone
		(layer "F.Cu")
		(hatch none 0.5)
		(connect_pads
			(clearance 0)
		)
		(min_thickness 0.25)
		(keepout
			(tracks allowed)
			(vias allowed)
			(pads allowed)
			(copperpour allowed)
			(footprints allowed)
		)
		(placement
			(enabled no)
			(sheetname "")
		)
		(fill
			(thermal_gap 0.5)
			(thermal_bridge_width 0.5)
			(island_removal_mode 0)
		)
		(polygon
			(pts
				(xy 313.606688 -344.659458) (xy 312.255408 -344.659458) (xy 312.255408 -343.379298) (xy 313.606688 -343.379298)
			)
		)
	)
	(zone
		(layer "F.Cu")
		(hatch none 0.5)
		(connect_pads
			(clearance 0)
		)
		(min_thickness 0.25)
		(keepout
			(tracks allowed)
			(vias allowed)
			(pads allowed)
			(copperpour allowed)
			(footprints allowed)
		)
		(placement
			(enabled no)
			(sheetname "")
		)
		(fill
			(thermal_gap 0.5)
			(thermal_bridge_width 0.5)
			(island_removal_mode 0)
		)
		(polygon
			(pts
				(xy 227.594922 -278.641556) (xy 227.594922 -276.990556) (xy 229.245922 -276.990556) (xy 229.245922 -278.641556)
			)
		)
	)
	(zone
		(layer "F.Cu")
		(hatch none 0.5)
		(connect_pads
			(clearance 0)
		)
		(min_thickness 0.25)
		(keepout
			(tracks allowed)
			(vias allowed)
			(pads allowed)
			(copperpour allowed)
			(footprints not_allowed)
		)
		(placement
			(enabled no)
			(sheetname "")
		)
		(fill
			(thermal_gap 0.5)
			(thermal_bridge_width 0.5)
			(island_removal_mode 0)
		)
		(polygon
			(pts
				(arc
					(start 355.590094 -407.599896)
					(mid 363.590078 -399.599912)
					(end 371.590062 -407.599896)
				)
				(arc
					(start 371.590062 -407.599896)
					(mid 363.590078 -415.59988)
					(end 355.590094 -407.599896)
				)
			)
		)
	)
	(zone
		(layer "F.Cu")
		(hatch none 0.5)
		(connect_pads
			(clearance 0)
		)
		(min_thickness 0.25)
		(keepout
			(tracks allowed)
			(vias allowed)
			(pads allowed)
			(copperpour allowed)
			(footprints allowed)
		)
		(placement
			(enabled no)
			(sheetname "")
		)
		(fill
			(thermal_gap 0.5)
			(thermal_bridge_width 0.5)
			(island_removal_mode 0)
		)
		(polygon
			(pts
				(xy 378.509784 -344.659458) (xy 377.158504 -344.659458) (xy 377.158504 -343.379298) (xy 378.509784 -343.379298)
			)
		)
	)
	(zone
		(layer "F.Cu")
		(hatch none 0.5)
		(connect_pads
			(clearance 0)
		)
		(min_thickness 0.25)
		(keepout
			(tracks allowed)
			(vias allowed)
			(pads allowed)
			(copperpour allowed)
			(footprints allowed)
		)
		(placement
			(enabled no)
			(sheetname "")
		)
		(fill
			(thermal_gap 0.5)
			(thermal_bridge_width 0.5)
			(island_removal_mode 0)
		)
		(polygon
			(pts
				(xy 384.255264 -113.024666) (xy 384.255264 -111.673386) (xy 385.535424 -111.673386) (xy 385.535424 -113.024666)
			)
		)
	)
	(zone
		(layer "F.Cu")
		(hatch none 0.5)
		(connect_pads
			(clearance 0)
		)
		(min_thickness 0.25)
		(keepout
			(tracks allowed)
			(vias allowed)
			(pads allowed)
			(copperpour allowed)
			(footprints allowed)
		)
		(placement
			(enabled no)
			(sheetname "")
		)
		(fill
			(thermal_gap 0.5)
			(thermal_bridge_width 0.5)
			(island_removal_mode 0)
		)
		(polygon
			(pts
				(xy 335.344008 -356.952042) (xy 333.992728 -356.952042) (xy 333.992728 -355.671882) (xy 335.344008 -355.671882)
			)
		)
	)
	(zone
		(layer "F.Cu")
		(hatch none 0.5)
		(connect_pads
			(clearance 0)
		)
		(min_thickness 0.25)
		(keepout
			(tracks allowed)
			(vias allowed)
			(pads allowed)
			(copperpour allowed)
			(footprints allowed)
		)
		(placement
			(enabled no)
			(sheetname "")
		)
		(fill
			(thermal_gap 0.5)
			(thermal_bridge_width 0.5)
			(island_removal_mode 0)
		)
		(polygon
			(pts
				(xy 313.606688 -350.80575) (xy 312.255408 -350.80575) (xy 312.255408 -349.52559) (xy 313.606688 -349.52559)
			)
		)
	)
	(zone
		(layer "F.Cu")
		(hatch none 0.5)
		(connect_pads
			(clearance 0)
		)
		(min_thickness 0.25)
		(keepout
			(tracks allowed)
			(vias allowed)
			(pads allowed)
			(copperpour allowed)
			(footprints allowed)
		)
		(placement
			(enabled no)
			(sheetname "")
		)
		(fill
			(thermal_gap 0.5)
			(thermal_bridge_width 0.5)
			(island_removal_mode 0)
		)
		(polygon
			(pts
				(xy 338.452968 -350.80575) (xy 337.101688 -350.80575) (xy 337.101688 -349.52559) (xy 338.452968 -349.52559)
			)
		)
	)
	(zone
		(layer "F.Cu")
		(hatch none 0.5)
		(connect_pads
			(clearance 0)
		)
		(min_thickness 0.25)
		(keepout
			(tracks allowed)
			(vias allowed)
			(pads allowed)
			(copperpour allowed)
			(footprints allowed)
		)
		(placement
			(enabled no)
			(sheetname "")
		)
		(fill
			(thermal_gap 0.5)
			(thermal_bridge_width 0.5)
			(island_removal_mode 0)
		)
		(polygon
			(pts
				(xy 13.814298 -230.378) (xy 13.814298 -220.599) (xy 15.846298 -220.599) (xy 15.846298 -230.378)
			)
		)
	)
	(zone
		(layer "F.Cu")
		(hatch none 0.5)
		(connect_pads
			(clearance 0)
		)
		(min_thickness 0.25)
		(keepout
			(tracks not_allowed)
			(vias allowed)
			(pads allowed)
			(copperpour not_allowed)
			(footprints allowed)
		)
		(placement
			(enabled no)
			(sheetname "")
		)
		(fill
			(thermal_gap 0.5)
			(thermal_bridge_width 0.5)
			(island_removal_mode 0)
		)
		(polygon
			(pts
				(xy 319.71996 -23.219918) (xy 319.71996 -18.219928) (xy 315.52007 -18.219928) (xy 315.52007 -23.219918)
			)
		)
	)
	(zone
		(layer "F.Cu")
		(hatch none 0.5)
		(connect_pads
			(clearance 0)
		)
		(min_thickness 0.25)
		(keepout
			(tracks allowed)
			(vias allowed)
			(pads allowed)
			(copperpour allowed)
			(footprints allowed)
		)
		(placement
			(enabled no)
			(sheetname "")
		)
		(fill
			(thermal_gap 0.5)
			(thermal_bridge_width 0.5)
			(island_removal_mode 0)
		)
		(polygon
			(pts
				(xy 198.07809 -132.816092) (xy 198.07809 -131.464812) (xy 199.35825 -131.464812) (xy 199.35825 -132.816092)
			)
		)
	)
	(zone
		(layer "F.Cu")
		(hatch none 0.5)
		(connect_pads
			(clearance 0)
		)
		(min_thickness 0.25)
		(keepout
			(tracks allowed)
			(vias allowed)
			(pads allowed)
			(copperpour allowed)
			(footprints allowed)
		)
		(placement
			(enabled no)
			(sheetname "")
		)
		(fill
			(thermal_gap 0.5)
			(thermal_bridge_width 0.5)
			(island_removal_mode 0)
		)
		(polygon
			(pts
				(xy 38.597332 -107.618022) (xy 38.597332 -106.266742) (xy 39.877492 -106.266742) (xy 39.877492 -107.618022)
			)
		)
	)
	(zone
		(layer "F.Cu")
		(hatch none 0.5)
		(connect_pads
			(clearance 0)
		)
		(min_thickness 0.25)
		(keepout
			(tracks not_allowed)
			(vias allowed)
			(pads allowed)
			(copperpour not_allowed)
			(footprints allowed)
		)
		(placement
			(enabled no)
			(sheetname "")
		)
		(fill
			(thermal_gap 0.5)
			(thermal_bridge_width 0.5)
			(island_removal_mode 0)
		)
		(polygon
			(pts
				(arc
					(start 115.700048 -194.360038)
					(mid 117.700044 -192.360042)
					(end 119.70004 -194.360038)
				)
				(arc
					(start 119.70004 -194.360038)
					(mid 117.700044 -196.360034)
					(end 115.700048 -194.360038)
				)
			)
		)
	)
	(zone
		(layer "F.Cu")
		(hatch none 0.5)
		(connect_pads
			(clearance 0)
		)
		(min_thickness 0.25)
		(keepout
			(tracks allowed)
			(vias allowed)
			(pads allowed)
			(copperpour allowed)
			(footprints allowed)
		)
		(placement
			(enabled no)
			(sheetname "")
		)
		(fill
			(thermal_gap 0.5)
			(thermal_bridge_width 0.5)
			(island_removal_mode 0)
		)
		(polygon
			(pts
				(xy 26.654252 -356.952042) (xy 25.302972 -356.952042) (xy 25.302972 -355.671882) (xy 26.654252 -355.671882)
			)
		)
	)
	(zone
		(layer "F.Cu")
		(hatch none 0.5)
		(connect_pads
			(clearance 0)
		)
		(min_thickness 0.25)
		(keepout
			(tracks allowed)
			(vias allowed)
			(pads allowed)
			(copperpour allowed)
			(footprints allowed)
		)
		(placement
			(enabled no)
			(sheetname "")
		)
		(fill
			(thermal_gap 0.5)
			(thermal_bridge_width 0.5)
			(island_removal_mode 0)
		)
		(polygon
			(pts
				(xy 185.33491 -129.180844) (xy 183.247538 -129.180844) (xy 182.927498 -129.500884) (xy 182.927498 -136.904984)
				(xy 185.272426 -136.904984) (xy 185.350658 -136.826752) (xy 185.350658 -129.196592)
			)
		)
	)
	(zone
		(layer "F.Cu")
		(hatch none 0.5)
		(connect_pads
			(clearance 0)
		)
		(min_thickness 0.25)
		(keepout
			(tracks allowed)
			(vias allowed)
			(pads allowed)
			(copperpour allowed)
			(footprints allowed)
		)
		(placement
			(enabled no)
			(sheetname "")
		)
		(fill
			(thermal_gap 0.5)
			(thermal_bridge_width 0.5)
			(island_removal_mode 0)
		)
		(polygon
			(pts
				(xy 8.484362 -54.008274) (xy 5.566664 -54.008274) (xy 5.357114 -54.217824) (xy 5.357114 -54.830726)
				(xy 8.414512 -54.830726) (xy 8.484362 -54.760876)
			)
		)
	)
	(zone
		(layer "F.Cu")
		(hatch none 0.5)
		(connect_pads
			(clearance 0)
		)
		(min_thickness 0.25)
		(keepout
			(tracks allowed)
			(vias allowed)
			(pads allowed)
			(copperpour allowed)
			(footprints allowed)
		)
		(placement
			(enabled no)
			(sheetname "")
		)
		(fill
			(thermal_gap 0.5)
			(thermal_bridge_width 0.5)
			(island_removal_mode 0)
		)
		(polygon
			(pts
				(xy 368.051334 -34.76117) (xy 368.051334 -33.40989) (xy 369.331494 -33.40989) (xy 369.331494 -34.76117)
			)
		)
	)
	(zone
		(layer "F.Cu")
		(hatch none 0.5)
		(connect_pads
			(clearance 0)
		)
		(min_thickness 0.25)
		(keepout
			(tracks not_allowed)
			(vias allowed)
			(pads allowed)
			(copperpour not_allowed)
			(footprints allowed)
		)
		(placement
			(enabled no)
			(sheetname "")
		)
		(fill
			(thermal_gap 0.5)
			(thermal_bridge_width 0.5)
			(island_removal_mode 0)
		)
		(polygon
			(pts
				(arc
					(start 120.499886 -72.69988)
					(mid 117.700044 -75.499722)
					(end 114.899948 -72.69988)
				)
				(arc
					(start 114.899948 -72.69988)
					(mid 117.700044 -69.899784)
					(end 120.499886 -72.69988)
				)
			)
		)
	)
	(zone
		(layer "F.Cu")
		(hatch none 0.5)
		(connect_pads
			(clearance 0)
		)
		(min_thickness 0.25)
		(keepout
			(tracks allowed)
			(vias allowed)
			(pads allowed)
			(copperpour allowed)
			(footprints allowed)
		)
		(placement
			(enabled no)
			(sheetname "")
		)
		(fill
			(thermal_gap 0.5)
			(thermal_bridge_width 0.5)
			(island_removal_mode 0)
		)
		(polygon
			(pts
				(xy 314.178188 -152.726136) (xy 314.178188 -151.374856) (xy 315.458348 -151.374856) (xy 315.458348 -152.726136)
			)
		)
	)
	(zone
		(layer "F.Cu")
		(hatch none 0.5)
		(connect_pads
			(clearance 0)
		)
		(min_thickness 0.25)
		(keepout
			(tracks allowed)
			(vias allowed)
			(pads allowed)
			(copperpour allowed)
			(footprints allowed)
		)
		(placement
			(enabled no)
			(sheetname "")
		)
		(fill
			(thermal_gap 0.5)
			(thermal_bridge_width 0.5)
			(island_removal_mode 0)
		)
		(polygon
			(pts
				(xy 79.336138 -154.51963) (xy 79.336138 -153.16835) (xy 80.616298 -153.16835) (xy 80.616298 -154.51963)
			)
		)
	)
	(zone
		(layer "F.Cu")
		(hatch none 0.5)
		(connect_pads
			(clearance 0)
		)
		(min_thickness 0.25)
		(keepout
			(tracks allowed)
			(vias allowed)
			(pads allowed)
			(copperpour allowed)
			(footprints allowed)
		)
		(placement
			(enabled no)
			(sheetname "")
		)
		(fill
			(thermal_gap 0.5)
			(thermal_bridge_width 0.5)
			(island_removal_mode 0)
		)
		(polygon
			(pts
				(xy 338.452968 -344.659458) (xy 337.101688 -344.659458) (xy 337.101688 -343.379298) (xy 338.452968 -343.379298)
			)
		)
	)
	(zone
		(layer "F.Cu")
		(hatch none 0.5)
		(connect_pads
			(clearance 0)
		)
		(min_thickness 0.25)
		(keepout
			(tracks allowed)
			(vias allowed)
			(pads allowed)
			(copperpour allowed)
			(footprints allowed)
		)
		(placement
			(enabled no)
			(sheetname "")
		)
		(fill
			(thermal_gap 0.5)
			(thermal_bridge_width 0.5)
			(island_removal_mode 0)
		)
		(polygon
			(pts
				(xy 296.956226 -350.781874) (xy 295.604946 -350.781874) (xy 295.604946 -349.501714) (xy 296.956226 -349.501714)
			)
		)
	)
	(zone
		(layer "F.Cu")
		(hatch none 0.5)
		(connect_pads
			(clearance 0)
		)
		(min_thickness 0.25)
		(keepout
			(tracks allowed)
			(vias allowed)
			(pads allowed)
			(copperpour allowed)
			(footprints not_allowed)
		)
		(placement
			(enabled no)
			(sheetname "")
		)
		(fill
			(thermal_gap 0.5)
			(thermal_bridge_width 0.5)
			(island_removal_mode 0)
		)
		(polygon
			(pts
				(xy 254.299974 -81.19999) (xy 213.300056 -81.19999) (xy 213.300056 -116.19992) (xy 254.299974 -116.19992)
			)
		)
	)
	(zone
		(layer "F.Cu")
		(hatch none 0.5)
		(connect_pads
			(clearance 0)
		)
		(min_thickness 0.25)
		(keepout
			(tracks allowed)
			(vias allowed)
			(pads allowed)
			(copperpour allowed)
			(footprints allowed)
		)
		(placement
			(enabled no)
			(sheetname "")
		)
		(fill
			(thermal_gap 0.5)
			(thermal_bridge_width 0.5)
			(island_removal_mode 0)
		)
		(polygon
			(pts
				(xy 90.42527 -101.08565) (xy 90.42527 -99.33305) (xy 92.20327 -99.33305) (xy 92.20327 -101.08565)
			)
		)
	)
	(zone
		(layer "F.Cu")
		(hatch none 0.5)
		(connect_pads
			(clearance 0)
		)
		(min_thickness 0.25)
		(keepout
			(tracks allowed)
			(vias allowed)
			(pads allowed)
			(copperpour allowed)
			(footprints allowed)
		)
		(placement
			(enabled no)
			(sheetname "")
		)
		(fill
			(thermal_gap 0.5)
			(thermal_bridge_width 0.5)
			(island_removal_mode 0)
		)
		(polygon
			(pts
				(xy 166.398956 -356.928166) (xy 165.047676 -356.928166) (xy 165.047676 -355.648006) (xy 166.398956 -355.648006)
			)
		)
	)
	(zone
		(layer "F.Cu")
		(hatch none 0.5)
		(connect_pads
			(clearance 0)
		)
		(min_thickness 0.25)
		(keepout
			(tracks allowed)
			(vias allowed)
			(pads allowed)
			(copperpour allowed)
			(footprints allowed)
		)
		(placement
			(enabled no)
			(sheetname "")
		)
		(fill
			(thermal_gap 0.5)
			(thermal_bridge_width 0.5)
			(island_removal_mode 0)
		)
		(polygon
			(pts
				(xy 175.725836 -350.80575) (xy 174.374556 -350.80575) (xy 174.374556 -349.52559) (xy 175.725836 -349.52559)
			)
		)
	)
	(zone
		(layer "F.Cu")
		(hatch none 0.5)
		(connect_pads
			(clearance 0)
		)
		(min_thickness 0.25)
		(keepout
			(tracks allowed)
			(vias allowed)
			(pads allowed)
			(copperpour allowed)
			(footprints allowed)
		)
		(placement
			(enabled no)
			(sheetname "")
		)
		(fill
			(thermal_gap 0.5)
			(thermal_bridge_width 0.5)
			(island_removal_mode 0)
		)
		(polygon
			(pts
				(xy 457.962 -279.908) (xy 460.883 -279.908) (xy 461.137 -279.654) (xy 461.137 -276.606) (xy 460.756 -276.225)
				(xy 457.835 -276.225) (xy 457.327 -276.733) (xy 457.327 -279.273)
			)
		)
	)
	(zone
		(layer "F.Cu")
		(hatch none 0.5)
		(connect_pads
			(clearance 0)
		)
		(min_thickness 0.25)
		(keepout
			(tracks allowed)
			(vias allowed)
			(pads allowed)
			(copperpour allowed)
			(footprints allowed)
		)
		(placement
			(enabled no)
			(sheetname "")
		)
		(fill
			(thermal_gap 0.5)
			(thermal_bridge_width 0.5)
			(island_removal_mode 0)
		)
		(polygon
			(pts
				(xy 156.761688 -27.55011) (xy 159.161734 -27.55011) (xy 159.253174 -27.45867) (xy 159.253174 -26.33853)
				(xy 159.192214 -26.27757) (xy 156.746448 -26.27757) (xy 156.624528 -26.39949) (xy 156.624528 -27.41295)
			)
		)
	)
	(zone
		(layer "F.Cu")
		(hatch none 0.5)
		(connect_pads
			(clearance 0)
		)
		(min_thickness 0.25)
		(keepout
			(tracks allowed)
			(vias allowed)
			(pads allowed)
			(copperpour allowed)
			(footprints allowed)
		)
		(placement
			(enabled no)
			(sheetname "")
		)
		(fill
			(thermal_gap 0.5)
			(thermal_bridge_width 0.5)
			(island_removal_mode 0)
		)
		(polygon
			(pts
				(xy 118.999 -260.223) (xy 118.999 -256.54) (xy 122.555 -256.54) (xy 122.555 -260.223)
			)
		)
	)
	(zone
		(layer "F.Cu")
		(hatch none 0.5)
		(connect_pads
			(clearance 0)
		)
		(min_thickness 0.25)
		(keepout
			(tracks allowed)
			(vias allowed)
			(pads allowed)
			(copperpour allowed)
			(footprints allowed)
		)
		(placement
			(enabled no)
			(sheetname "")
		)
		(fill
			(thermal_gap 0.5)
			(thermal_bridge_width 0.5)
			(island_removal_mode 0)
		)
		(polygon
			(pts
				(xy 45.751242 -34.76117) (xy 45.751242 -33.40989) (xy 47.031402 -33.40989) (xy 47.031402 -34.76117)
			)
		)
	)
	(zone
		(layer "F.Cu")
		(hatch none 0.5)
		(connect_pads
			(clearance 0)
		)
		(min_thickness 0.25)
		(keepout
			(tracks allowed)
			(vias allowed)
			(pads allowed)
			(copperpour allowed)
			(footprints allowed)
		)
		(placement
			(enabled no)
			(sheetname "")
		)
		(fill
			(thermal_gap 0.5)
			(thermal_bridge_width 0.5)
			(island_removal_mode 0)
		)
		(polygon
			(pts
				(xy 450.918326 -210.405472) (xy 452.173848 -210.405472) (xy 452.31685 -210.26247) (xy 452.31685 -209.241644)
				(xy 451.969886 -208.89468) (xy 450.867526 -208.89468) (xy 450.724524 -209.037682) (xy 450.724524 -210.21167)
			)
		)
	)
	(zone
		(layer "F.Cu")
		(hatch none 0.5)
		(connect_pads
			(clearance 0)
		)
		(min_thickness 0.25)
		(keepout
			(tracks allowed)
			(vias allowed)
			(pads allowed)
			(copperpour allowed)
			(footprints not_allowed)
		)
		(placement
			(enabled no)
			(sheetname "")
		)
		(fill
			(thermal_gap 0.5)
			(thermal_bridge_width 0.5)
			(island_removal_mode 0)
		)
		(polygon
			(pts
				(xy 332.35011 -322.200016) (xy 367.450116 -322.200016) (xy 367.450116 -288.230056)
				(arc
					(start 335.020412 -288.230056)
					(mid 335.266791 -289.00817)
					(end 335.350104 -289.820096)
				)
				(arc
					(start 335.350104 -289.820096)
					(mid 334.512382 -292.269582)
					(end 332.35011 -293.693088)
				)
			)
		)
	)
	(zone
		(layer "F.Cu")
		(hatch none 0.5)
		(connect_pads
			(clearance 0)
		)
		(min_thickness 0.25)
		(keepout
			(tracks allowed)
			(vias allowed)
			(pads allowed)
			(copperpour allowed)
			(footprints allowed)
		)
		(placement
			(enabled no)
			(sheetname "")
		)
		(fill
			(thermal_gap 0.5)
			(thermal_bridge_width 0.5)
			(island_removal_mode 0)
		)
		(polygon
			(pts
				(xy 129.237994 -321.945) (xy 129.237994 -320.294) (xy 131.269994 -320.294) (xy 131.269994 -321.945)
			)
		)
	)
	(zone
		(layer "F.Cu")
		(hatch none 0.5)
		(connect_pads
			(clearance 0)
		)
		(min_thickness 0.25)
		(keepout
			(tracks allowed)
			(vias allowed)
			(pads allowed)
			(copperpour allowed)
			(footprints allowed)
		)
		(placement
			(enabled no)
			(sheetname "")
		)
		(fill
			(thermal_gap 0.5)
			(thermal_bridge_width 0.5)
			(island_removal_mode 0)
		)
		(polygon
			(pts
				(xy 270.797274 -107.618022) (xy 270.797274 -106.266742) (xy 272.077434 -106.266742) (xy 272.077434 -107.618022)
			)
		)
	)
	(zone
		(layer "F.Cu")
		(hatch none 0.5)
		(connect_pads
			(clearance 0)
		)
		(min_thickness 0.25)
		(keepout
			(tracks allowed)
			(vias allowed)
			(pads allowed)
			(copperpour allowed)
			(footprints allowed)
		)
		(placement
			(enabled no)
			(sheetname "")
		)
		(fill
			(thermal_gap 0.5)
			(thermal_bridge_width 0.5)
			(island_removal_mode 0)
		)
		(polygon
			(pts
				(xy 357.415338 -35.366706) (xy 359.213404 -35.366706) (xy 359.289604 -35.290506) (xy 359.289604 -27.702002)
				(xy 359.000044 -27.412442) (xy 357.628698 -27.412442) (xy 357.400098 -27.641042) (xy 357.400098 -27.846782)
				(xy 357.209598 -28.037282) (xy 357.209598 -35.160966)
			)
		)
	)
	(zone
		(layer "F.Cu")
		(hatch none 0.5)
		(connect_pads
			(clearance 0)
		)
		(min_thickness 0.25)
		(keepout
			(tracks allowed)
			(vias allowed)
			(pads allowed)
			(copperpour allowed)
			(footprints allowed)
		)
		(placement
			(enabled no)
			(sheetname "")
		)
		(fill
			(thermal_gap 0.5)
			(thermal_bridge_width 0.5)
			(island_removal_mode 0)
		)
		(polygon
			(pts
				(xy 95.10903 -32.954468) (xy 95.10903 -31.603188) (xy 96.38919 -31.603188) (xy 96.38919 -32.954468)
			)
		)
	)
	(zone
		(layer "F.Cu")
		(hatch none 0.5)
		(connect_pads
			(clearance 0)
		)
		(min_thickness 0.25)
		(keepout
			(tracks allowed)
			(vias allowed)
			(pads allowed)
			(copperpour allowed)
			(footprints allowed)
		)
		(placement
			(enabled no)
			(sheetname "")
		)
		(fill
			(thermal_gap 0.5)
			(thermal_bridge_width 0.5)
			(island_removal_mode 0)
		)
		(polygon
			(pts
				(xy 378.509784 -350.80575) (xy 377.158504 -350.80575) (xy 377.158504 -349.52559) (xy 378.509784 -349.52559)
			)
		)
	)
	(zone
		(layer "F.Cu")
		(hatch none 0.5)
		(connect_pads
			(clearance 0)
		)
		(min_thickness 0.25)
		(keepout
			(tracks allowed)
			(vias allowed)
			(pads allowed)
			(copperpour allowed)
			(footprints not_allowed)
		)
		(placement
			(enabled no)
			(sheetname "")
		)
		(fill
			(thermal_gap 0.5)
			(thermal_bridge_width 0.5)
			(island_removal_mode 0)
		)
		(polygon
			(pts
				(arc
					(start 218.11488 -5.999988)
					(mid 226.115118 2.00025)
					(end 234.115102 -5.999988)
				)
				(arc
					(start 234.115102 -5.999988)
					(mid 226.115118 -13.999972)
					(end 218.11488 -5.999988)
				)
			)
		)
	)
	(zone
		(layer "F.Cu")
		(hatch none 0.5)
		(connect_pads
			(clearance 0)
		)
		(min_thickness 0.25)
		(keepout
			(tracks allowed)
			(vias allowed)
			(pads allowed)
			(copperpour allowed)
			(footprints allowed)
		)
		(placement
			(enabled no)
			(sheetname "")
		)
		(fill
			(thermal_gap 0.5)
			(thermal_bridge_width 0.5)
			(island_removal_mode 0)
		)
		(polygon
			(pts
				(xy 55.401718 -368.828574) (xy 56.238648 -368.828574) (xy 56.729122 -368.828574) (xy 56.729376 -368.82832)
				(xy 56.729376 -367.38052) (xy 56.608726 -367.25987) (xy 56.299354 -367.25987) (xy 56.269128 -367.290096)
				(xy 55.424578 -367.290096) (xy 55.34152 -367.373154) (xy 55.34152 -368.768376)
			)
		)
	)
	(zone
		(layer "F.Cu")
		(hatch none 0.5)
		(connect_pads
			(clearance 0)
		)
		(min_thickness 0.25)
		(keepout
			(tracks allowed)
			(vias allowed)
			(pads allowed)
			(copperpour allowed)
			(footprints allowed)
		)
		(placement
			(enabled no)
			(sheetname "")
		)
		(fill
			(thermal_gap 0.5)
			(thermal_bridge_width 0.5)
			(island_removal_mode 0)
		)
		(polygon
			(pts
				(xy 306.454048 -116.118386) (xy 305.076352 -116.118386) (xy 304.718466 -116.476272) (xy 304.718466 -122.452384)
				(xy 304.718466 -125.525022) (xy 304.8381 -125.644656) (xy 306.668424 -125.644656) (xy 307.151786 -125.161294)
				(xy 307.151786 -122.094498) (xy 307.151786 -116.816124)
			)
		)
	)
	(zone
		(layer "F.Cu")
		(hatch none 0.5)
		(connect_pads
			(clearance 0)
		)
		(min_thickness 0.25)
		(keepout
			(tracks allowed)
			(vias allowed)
			(pads allowed)
			(copperpour allowed)
			(footprints allowed)
		)
		(placement
			(enabled no)
			(sheetname "")
		)
		(fill
			(thermal_gap 0.5)
			(thermal_bridge_width 0.5)
			(island_removal_mode 0)
		)
		(polygon
			(pts
				(xy 283.98724 -98.563176) (xy 282.176728 -98.563176) (xy 282.130246 -98.609658) (xy 282.130246 -113.35258)
				(xy 282.275534 -113.497868) (xy 284.027626 -113.497868) (xy 284.103064 -113.42243) (xy 284.103064 -98.679)
			)
		)
	)
	(zone
		(layer "F.Cu")
		(hatch none 0.5)
		(connect_pads
			(clearance 0)
		)
		(min_thickness 0.25)
		(keepout
			(tracks allowed)
			(vias allowed)
			(pads allowed)
			(copperpour allowed)
			(footprints allowed)
		)
		(placement
			(enabled no)
			(sheetname "")
		)
		(fill
			(thermal_gap 0.5)
			(thermal_bridge_width 0.5)
			(island_removal_mode 0)
		)
		(polygon
			(pts
				(xy 9.675622 -381.051816) (xy 9.675622 -381.888746) (xy 9.675622 -382.37922) (xy 9.675876 -382.379474)
				(xy 11.123676 -382.379474) (xy 11.244326 -382.258824) (xy 11.244326 -381.949452) (xy 11.2141 -381.919226)
				(xy 11.2141 -381.074676) (xy 11.131042 -380.991618) (xy 9.73582 -380.991618)
			)
		)
	)
	(zone
		(layer "F.Cu")
		(hatch none 0.5)
		(connect_pads
			(clearance 0)
		)
		(min_thickness 0.25)
		(keepout
			(tracks allowed)
			(vias allowed)
			(pads allowed)
			(copperpour allowed)
			(footprints allowed)
		)
		(placement
			(enabled no)
			(sheetname "")
		)
		(fill
			(thermal_gap 0.5)
			(thermal_bridge_width 0.5)
			(island_removal_mode 0)
		)
		(polygon
			(pts
				(xy 154.697176 -111.218218) (xy 154.697176 -109.866938) (xy 155.977336 -109.866938) (xy 155.977336 -111.218218)
			)
		)
	)
	(zone
		(layer "F.Cu")
		(hatch none 0.5)
		(connect_pads
			(clearance 0)
		)
		(min_thickness 0.25)
		(keepout
			(tracks allowed)
			(vias allowed)
			(pads allowed)
			(copperpour allowed)
			(footprints allowed)
		)
		(placement
			(enabled no)
			(sheetname "")
		)
		(fill
			(thermal_gap 0.5)
			(thermal_bridge_width 0.5)
			(island_removal_mode 0)
		)
		(polygon
			(pts
				(xy 185.20918 -29.354526) (xy 185.20918 -28.003246) (xy 186.48934 -28.003246) (xy 186.48934 -29.354526)
			)
		)
	)
	(zone
		(layer "F.Cu")
		(hatch none 0.5)
		(connect_pads
			(clearance 0)
		)
		(min_thickness 0.25)
		(keepout
			(tracks allowed)
			(vias allowed)
			(pads allowed)
			(copperpour allowed)
			(footprints allowed)
		)
		(placement
			(enabled no)
			(sheetname "")
		)
		(fill
			(thermal_gap 0.5)
			(thermal_bridge_width 0.5)
			(island_removal_mode 0)
		)
		(polygon
			(pts
				(xy 74.402442 -141.87297) (xy 72.59193 -141.87297) (xy 72.545448 -141.919452) (xy 72.545448 -156.662374)
				(xy 72.690736 -156.807662) (xy 74.442828 -156.807662) (xy 74.518266 -156.732224) (xy 74.518266 -141.988794)
			)
		)
	)
	(zone
		(layer "F.Cu")
		(hatch none 0.5)
		(connect_pads
			(clearance 0)
		)
		(min_thickness 0.25)
		(keepout
			(tracks allowed)
			(vias allowed)
			(pads allowed)
			(copperpour allowed)
			(footprints not_allowed)
		)
		(placement
			(enabled no)
			(sheetname "")
		)
		(fill
			(thermal_gap 0.5)
			(thermal_bridge_width 0.5)
			(island_removal_mode 0)
		)
		(polygon
			(pts
				(xy 203.065126 -40.120062) (xy 211.064856 -40.120062) (xy 211.06511 -13.850112) (xy 203.065126 -13.850112)
			)
		)
	)
	(zone
		(layer "F.Cu")
		(hatch none 0.5)
		(connect_pads
			(clearance 0)
		)
		(min_thickness 0.25)
		(keepout
			(tracks allowed)
			(vias allowed)
			(pads allowed)
			(copperpour allowed)
			(footprints allowed)
		)
		(placement
			(enabled no)
			(sheetname "")
		)
		(fill
			(thermal_gap 0.5)
			(thermal_bridge_width 0.5)
			(island_removal_mode 0)
		)
		(polygon
			(pts
				(xy 74.437748 -19.7358) (xy 74.437748 -19.2024) (xy 75.504548 -19.2024) (xy 75.504548 -19.7358)
			)
		)
	)
	(zone
		(layer "F.Cu")
		(hatch none 0.5)
		(connect_pads
			(clearance 0)
		)
		(min_thickness 0.25)
		(keepout
			(tracks allowed)
			(vias allowed)
			(pads allowed)
			(copperpour allowed)
			(footprints allowed)
		)
		(placement
			(enabled no)
			(sheetname "")
		)
		(fill
			(thermal_gap 0.5)
			(thermal_bridge_width 0.5)
			(island_removal_mode 0)
		)
		(polygon
			(pts
				(xy 120.84177 -256.509774) (xy 123.35764 -256.509774) (xy 123.734576 -256.132838) (xy 123.734576 -254.005842)
				(xy 123.491498 -253.762764) (xy 120.209818 -253.762764) (xy 120.209818 -255.877822)
			)
		)
	)
	(zone
		(layer "F.Cu")
		(hatch none 0.5)
		(connect_pads
			(clearance 0)
		)
		(min_thickness 0.25)
		(keepout
			(tracks allowed)
			(vias allowed)
			(pads allowed)
			(copperpour allowed)
			(footprints allowed)
		)
		(placement
			(enabled no)
			(sheetname "")
		)
		(fill
			(thermal_gap 0.5)
			(thermal_bridge_width 0.5)
			(island_removal_mode 0)
		)
		(polygon
			(pts
				(xy 190.35395 -116.118386) (xy 188.976254 -116.118386) (xy 188.618368 -116.476272) (xy 188.618368 -122.452384)
				(xy 188.618368 -125.525022) (xy 188.738002 -125.644656) (xy 190.568326 -125.644656) (xy 191.051688 -125.161294)
				(xy 191.051688 -122.094498) (xy 191.051688 -116.816124)
			)
		)
	)
	(zone
		(layer "F.Cu")
		(hatch none 0.5)
		(connect_pads
			(clearance 0)
		)
		(min_thickness 0.25)
		(keepout
			(tracks allowed)
			(vias allowed)
			(pads allowed)
			(copperpour allowed)
			(footprints allowed)
		)
		(placement
			(enabled no)
			(sheetname "")
		)
		(fill
			(thermal_gap 0.5)
			(thermal_bridge_width 0.5)
			(island_removal_mode 0)
		)
		(polygon
			(pts
				(xy 35.305746 -35.336226) (xy 36.753292 -35.336226) (xy 37.119052 -34.970466) (xy 37.119052 -27.580336)
				(xy 36.814252 -27.275536) (xy 35.305746 -27.275536) (xy 34.93262 -27.648662) (xy 34.93262 -34.9631)
			)
		)
	)
	(zone
		(layer "F.Cu")
		(hatch none 0.5)
		(connect_pads
			(clearance 0)
		)
		(min_thickness 0.25)
		(keepout
			(tracks allowed)
			(vias allowed)
			(pads allowed)
			(copperpour allowed)
			(footprints allowed)
		)
		(placement
			(enabled no)
			(sheetname "")
		)
		(fill
			(thermal_gap 0.5)
			(thermal_bridge_width 0.5)
			(island_removal_mode 0)
		)
		(polygon
			(pts
				(xy 69.109082 -32.954468) (xy 69.109082 -31.603188) (xy 70.389242 -31.603188) (xy 70.389242 -32.954468)
			)
		)
	)
	(zone
		(layer "F.Cu")
		(hatch none 0.5)
		(connect_pads
			(clearance 0)
		)
		(min_thickness 0.25)
		(keepout
			(tracks allowed)
			(vias allowed)
			(pads allowed)
			(copperpour allowed)
			(footprints allowed)
		)
		(placement
			(enabled no)
			(sheetname "")
		)
		(fill
			(thermal_gap 0.5)
			(thermal_bridge_width 0.5)
			(island_removal_mode 0)
		)
		(polygon
			(pts
				(xy 156.588714 -35.519868) (xy 158.417006 -35.519868) (xy 158.65348 -35.283394) (xy 158.65348 -26.930096)
				(xy 158.417006 -26.693622) (xy 156.760926 -26.693622) (xy 156.588714 -26.865834)
			)
		)
	)
	(zone
		(layer "F.Cu")
		(hatch none 0.5)
		(connect_pads
			(clearance 0)
		)
		(min_thickness 0.25)
		(keepout
			(tracks allowed)
			(vias allowed)
			(pads allowed)
			(copperpour allowed)
			(footprints allowed)
		)
		(placement
			(enabled no)
			(sheetname "")
		)
		(fill
			(thermal_gap 0.5)
			(thermal_bridge_width 0.5)
			(island_removal_mode 0)
		)
		(polygon
			(pts
				(xy 314.178188 -145.525998) (xy 314.178188 -144.174718) (xy 315.458348 -144.174718) (xy 315.458348 -145.525998)
			)
		)
	)
	(zone
		(layer "F.Cu")
		(hatch none 0.5)
		(connect_pads
			(clearance 0)
		)
		(min_thickness 0.25)
		(keepout
			(tracks allowed)
			(vias allowed)
			(pads allowed)
			(copperpour allowed)
			(footprints allowed)
		)
		(placement
			(enabled no)
			(sheetname "")
		)
		(fill
			(thermal_gap 0.5)
			(thermal_bridge_width 0.5)
			(island_removal_mode 0)
		)
		(polygon
			(pts
				(xy 112.435894 -128.527302) (xy 113.068354 -128.527302) (xy 113.23574 -128.359916) (xy 113.23574 -125.104398)
				(xy 112.845088 -124.713746) (xy 112.23117 -124.713746) (xy 112.156748 -124.788168) (xy 112.156748 -128.248156)
			)
		)
	)
	(zone
		(layer "F.Cu")
		(hatch none 0.5)
		(connect_pads
			(clearance 0)
		)
		(min_thickness 0.25)
		(keepout
			(tracks allowed)
			(vias allowed)
			(pads allowed)
			(copperpour allowed)
			(footprints allowed)
		)
		(placement
			(enabled no)
			(sheetname "")
		)
		(fill
			(thermal_gap 0.5)
			(thermal_bridge_width 0.5)
			(island_removal_mode 0)
		)
		(polygon
			(pts
				(xy 93.565726 -344.635582) (xy 92.214446 -344.635582) (xy 92.214446 -343.355422) (xy 93.565726 -343.355422)
			)
		)
	)
	(zone
		(layer "F.Cu")
		(hatch none 0.5)
		(connect_pads
			(clearance 0)
		)
		(min_thickness 0.25)
		(keepout
			(tracks allowed)
			(vias allowed)
			(pads allowed)
			(copperpour allowed)
			(footprints allowed)
		)
		(placement
			(enabled no)
			(sheetname "")
		)
		(fill
			(thermal_gap 0.5)
			(thermal_bridge_width 0.5)
			(island_removal_mode 0)
		)
		(polygon
			(pts
				(xy 45.308012 -356.952042) (xy 43.956732 -356.952042) (xy 43.956732 -355.671882) (xy 45.308012 -355.671882)
			)
		)
	)
	(zone
		(layer "F.Cu")
		(hatch none 0.5)
		(connect_pads
			(clearance 0)
		)
		(min_thickness 0.25)
		(keepout
			(tracks allowed)
			(vias allowed)
			(pads allowed)
			(copperpour allowed)
			(footprints allowed)
		)
		(placement
			(enabled no)
			(sheetname "")
		)
		(fill
			(thermal_gap 0.5)
			(thermal_bridge_width 0.5)
			(island_removal_mode 0)
		)
		(polygon
			(pts
				(xy 278.302466 -344.659458) (xy 276.951186 -344.659458) (xy 276.951186 -343.379298) (xy 278.302466 -343.379298)
			)
		)
	)
	(zone
		(layer "F.Cu")
		(hatch none 0.5)
		(connect_pads
			(clearance 0)
		)
		(min_thickness 0.25)
		(keepout
			(tracks allowed)
			(vias allowed)
			(pads allowed)
			(copperpour allowed)
			(footprints allowed)
		)
		(placement
			(enabled no)
			(sheetname "")
		)
		(fill
			(thermal_gap 0.5)
			(thermal_bridge_width 0.5)
			(island_removal_mode 0)
		)
		(polygon
			(pts
				(xy 254.637794 -19.7358) (xy 254.637794 -19.2024) (xy 255.704594 -19.2024) (xy 255.704594 -19.7358)
			)
		)
	)
	(zone
		(layer "F.Cu")
		(hatch none 0.5)
		(connect_pads
			(clearance 0)
		)
		(min_thickness 0.25)
		(keepout
			(tracks allowed)
			(vias allowed)
			(pads allowed)
			(copperpour allowed)
			(footprints allowed)
		)
		(placement
			(enabled no)
			(sheetname "")
		)
		(fill
			(thermal_gap 0.5)
			(thermal_bridge_width 0.5)
			(island_removal_mode 0)
		)
		(polygon
			(pts
				(xy 183.612536 -156.836872) (xy 185.423048 -156.836872) (xy 185.46953 -156.79039) (xy 185.46953 -142.047468)
				(xy 185.324242 -141.90218) (xy 183.57215 -141.90218) (xy 183.496712 -141.977618) (xy 183.496712 -156.721048)
			)
		)
	)
	(zone
		(layer "F.Cu")
		(hatch none 0.5)
		(connect_pads
			(clearance 0)
		)
		(min_thickness 0.25)
		(keepout
			(tracks not_allowed)
			(vias allowed)
			(pads allowed)
			(copperpour not_allowed)
			(footprints allowed)
		)
		(placement
			(enabled no)
			(sheetname "")
		)
		(fill
			(thermal_gap 0.5)
			(thermal_bridge_width 0.5)
			(island_removal_mode 0)
		)
		(polygon
			(pts
				(arc
					(start 7.999984 -407.599896)
					(mid 5.999988 -409.599892)
					(end 3.999992 -407.599896)
				)
				(arc
					(start 3.999992 -407.599896)
					(mid 5.999988 -405.5999)
					(end 7.999984 -407.599896)
				)
			)
		)
	)
	(zone
		(layer "F.Cu")
		(hatch none 0.5)
		(connect_pads
			(clearance 0)
		)
		(min_thickness 0.25)
		(keepout
			(tracks not_allowed)
			(vias allowed)
			(pads allowed)
			(copperpour not_allowed)
			(footprints allowed)
		)
		(placement
			(enabled no)
			(sheetname "")
		)
		(fill
			(thermal_gap 0.5)
			(thermal_bridge_width 0.5)
			(island_removal_mode 0)
		)
		(polygon
			(pts
				(arc
					(start 213.739984 -311.179972)
					(mid 216.990168 -307.929788)
					(end 220.240098 -311.179972)
				)
				(arc
					(start 220.240098 -311.179972)
					(mid 216.990168 -314.429902)
					(end 213.739984 -311.179972)
				)
			)
		)
	)
	(zone
		(layer "F.Cu")
		(hatch none 0.5)
		(connect_pads
			(clearance 0)
		)
		(min_thickness 0.25)
		(keepout
			(tracks not_allowed)
			(vias allowed)
			(pads allowed)
			(copperpour not_allowed)
			(footprints allowed)
		)
		(placement
			(enabled no)
			(sheetname "")
		)
		(fill
			(thermal_gap 0.5)
			(thermal_bridge_width 0.5)
			(island_removal_mode 0)
		)
		(polygon
			(pts
				(xy 314.79998 -396.54988) (xy 324.79996 -396.54988) (xy 324.79996 -417.378642) (xy 314.79998 -417.378642)
			)
		)
	)
	(zone
		(layer "F.Cu")
		(hatch none 0.5)
		(connect_pads
			(clearance 0)
		)
		(min_thickness 0.25)
		(keepout
			(tracks allowed)
			(vias allowed)
			(pads allowed)
			(copperpour allowed)
			(footprints allowed)
		)
		(placement
			(enabled no)
			(sheetname "")
		)
		(fill
			(thermal_gap 0.5)
			(thermal_bridge_width 0.5)
			(island_removal_mode 0)
		)
		(polygon
			(pts
				(xy 311.53608 -123.39955) (xy 311.53608 -122.04827) (xy 312.81624 -122.04827) (xy 312.81624 -123.39955)
			)
		)
	)
	(zone
		(layer "F.Cu")
		(hatch none 0.5)
		(connect_pads
			(clearance 0)
		)
		(min_thickness 0.25)
		(keepout
			(tracks allowed)
			(vias allowed)
			(pads allowed)
			(copperpour allowed)
			(footprints allowed)
		)
		(placement
			(enabled no)
			(sheetname "")
		)
		(fill
			(thermal_gap 0.5)
			(thermal_bridge_width 0.5)
			(island_removal_mode 0)
		)
		(polygon
			(pts
				(xy 39.090092 -344.659458) (xy 37.738812 -344.659458) (xy 37.738812 -343.379298) (xy 39.090092 -343.379298)
			)
		)
	)
	(zone
		(layer "F.Cu")
		(hatch none 0.5)
		(connect_pads
			(clearance 0)
		)
		(min_thickness 0.25)
		(keepout
			(tracks allowed)
			(vias allowed)
			(pads allowed)
			(copperpour allowed)
			(footprints allowed)
		)
		(placement
			(enabled no)
			(sheetname "")
		)
		(fill
			(thermal_gap 0.5)
			(thermal_bridge_width 0.5)
			(island_removal_mode 0)
		)
		(polygon
			(pts
				(xy 45.308012 -344.659458) (xy 43.956732 -344.659458) (xy 43.956732 -343.379298) (xy 45.308012 -343.379298)
			)
		)
	)
	(zone
		(layer "F.Cu")
		(hatch none 0.5)
		(connect_pads
			(clearance 0)
		)
		(min_thickness 0.25)
		(keepout
			(tracks allowed)
			(vias allowed)
			(pads allowed)
			(copperpour allowed)
			(footprints allowed)
		)
		(placement
			(enabled no)
			(sheetname "")
		)
		(fill
			(thermal_gap 0.5)
			(thermal_bridge_width 0.5)
			(island_removal_mode 0)
		)
		(polygon
			(pts
				(xy 35.955224 -105.824782) (xy 35.955224 -104.473502) (xy 37.235384 -104.473502) (xy 37.235384 -105.824782)
			)
		)
	)
	(zone
		(layer "F.Cu")
		(hatch none 0.5)
		(connect_pads
			(clearance 0)
		)
		(min_thickness 0.25)
		(keepout
			(tracks not_allowed)
			(vias allowed)
			(pads allowed)
			(copperpour not_allowed)
			(footprints allowed)
		)
		(placement
			(enabled no)
			(sheetname "")
		)
		(fill
			(thermal_gap 0.5)
			(thermal_bridge_width 0.5)
			(island_removal_mode 0)
		)
		(polygon
			(pts
				(arc
					(start 16.89989 -301.410116)
					(mid 20.150074 -298.159932)
					(end 23.400004 -301.410116)
				)
				(arc
					(start 23.400004 -301.410116)
					(mid 20.150074 -304.660046)
					(end 16.89989 -301.410116)
				)
			)
		)
	)
	(zone
		(layer "F.Cu")
		(hatch none 0.5)
		(connect_pads
			(clearance 0)
		)
		(min_thickness 0.25)
		(keepout
			(tracks not_allowed)
			(vias allowed)
			(pads allowed)
			(copperpour not_allowed)
			(footprints allowed)
		)
		(placement
			(enabled no)
			(sheetname "")
		)
		(fill
			(thermal_gap 0.5)
			(thermal_bridge_width 0.5)
			(island_removal_mode 0)
		)
		(polygon
			(pts
				(xy 330.820014 -18.150078) (xy 330.820014 -13.150088) (xy 326.620124 -13.150088) (xy 326.620124 -18.150078)
			)
		)
	)
	(zone
		(layer "F.Cu")
		(hatch none 0.5)
		(connect_pads
			(clearance 0)
		)
		(min_thickness 0.25)
		(keepout
			(tracks allowed)
			(vias allowed)
			(pads allowed)
			(copperpour allowed)
			(footprints allowed)
		)
		(placement
			(enabled no)
			(sheetname "")
		)
		(fill
			(thermal_gap 0.5)
			(thermal_bridge_width 0.5)
			(island_removal_mode 0)
		)
		(polygon
			(pts
				(xy 441.463176 -350.781874) (xy 440.111896 -350.781874) (xy 440.111896 -349.501714) (xy 441.463176 -349.501714)
			)
		)
	)
	(zone
		(layer "F.Cu")
		(hatch none 0.5)
		(connect_pads
			(clearance 0)
		)
		(min_thickness 0.25)
		(keepout
			(tracks not_allowed)
			(vias allowed)
			(pads allowed)
			(copperpour not_allowed)
			(footprints allowed)
		)
		(placement
			(enabled no)
			(sheetname "")
		)
		(fill
			(thermal_gap 0.5)
			(thermal_bridge_width 0.5)
			(island_removal_mode 0)
		)
		(polygon
			(pts
				(xy 324.79996 -396.54988) (xy 324.79996 -417.58997) (xy 314.79998 -417.58997) (xy 314.79998 -396.54988)
			)
		)
	)
	(zone
		(layer "F.Cu")
		(hatch none 0.5)
		(connect_pads
			(clearance 0)
		)
		(min_thickness 0.25)
		(keepout
			(tracks allowed)
			(vias allowed)
			(pads allowed)
			(copperpour allowed)
			(footprints allowed)
		)
		(placement
			(enabled no)
			(sheetname "")
		)
		(fill
			(thermal_gap 0.5)
			(thermal_bridge_width 0.5)
			(island_removal_mode 0)
		)
		(polygon
			(pts
				(xy 293.46271 -35.39744) (xy 294.986456 -35.39744) (xy 295.230042 -35.153854) (xy 295.230042 -27.366722)
				(xy 295.169082 -27.305762) (xy 293.32555 -27.305762) (xy 292.82263 -27.808682) (xy 292.82263 -34.75736)
			)
		)
	)
	(zone
		(layer "F.Cu")
		(hatch none 0.5)
		(connect_pads
			(clearance 0)
		)
		(min_thickness 0.25)
		(keepout
			(tracks allowed)
			(vias allowed)
			(pads allowed)
			(copperpour allowed)
			(footprints not_allowed)
		)
		(placement
			(enabled no)
			(sheetname "")
		)
		(fill
			(thermal_gap 0.5)
			(thermal_bridge_width 0.5)
			(island_removal_mode 0)
		)
		(polygon
			(pts
				(xy 188.719968 -18.150078) (xy 188.719968 -13.150088) (xy 184.520078 -13.150088) (xy 184.520078 -18.150078)
			)
		)
	)
	(zone
		(layer "F.Cu")
		(hatch none 0.5)
		(connect_pads
			(clearance 0)
		)
		(min_thickness 0.25)
		(keepout
			(tracks allowed)
			(vias allowed)
			(pads allowed)
			(copperpour allowed)
			(footprints allowed)
		)
		(placement
			(enabled no)
			(sheetname "")
		)
		(fill
			(thermal_gap 0.5)
			(thermal_bridge_width 0.5)
			(island_removal_mode 0)
		)
		(polygon
			(pts
				(xy 361.189778 -138.611102) (xy 361.189778 -135.693404) (xy 360.980228 -135.483854) (xy 360.367326 -135.483854)
				(xy 360.367326 -138.541252) (xy 360.437176 -138.611102)
			)
		)
	)
	(zone
		(layer "F.Cu")
		(hatch none 0.5)
		(connect_pads
			(clearance 0)
		)
		(min_thickness 0.25)
		(keepout
			(tracks allowed)
			(vias allowed)
			(pads allowed)
			(copperpour allowed)
			(footprints allowed)
		)
		(placement
			(enabled no)
			(sheetname "")
		)
		(fill
			(thermal_gap 0.5)
			(thermal_bridge_width 0.5)
			(island_removal_mode 0)
		)
		(polygon
			(pts
				(xy 42.199052 -350.80575) (xy 40.847772 -350.80575) (xy 40.847772 -349.52559) (xy 42.199052 -349.52559)
			)
		)
	)
	(zone
		(layer "F.Cu")
		(hatch none 0.5)
		(connect_pads
			(clearance 0)
		)
		(min_thickness 0.25)
		(keepout
			(tracks allowed)
			(vias allowed)
			(pads allowed)
			(copperpour allowed)
			(footprints allowed)
		)
		(placement
			(enabled no)
			(sheetname "")
		)
		(fill
			(thermal_gap 0.5)
			(thermal_bridge_width 0.5)
			(island_removal_mode 0)
		)
		(polygon
			(pts
				(xy 128.359916 -139.093702) (xy 128.992376 -139.093702) (xy 129.159762 -138.926316) (xy 129.159762 -135.670798)
				(xy 128.76911 -135.280146) (xy 128.155192 -135.280146) (xy 128.08077 -135.354568) (xy 128.08077 -138.814556)
			)
		)
	)
	(zone
		(layer "F.Cu")
		(hatch none 0.5)
		(connect_pads
			(clearance 0)
		)
		(min_thickness 0.25)
		(keepout
			(tracks allowed)
			(vias allowed)
			(pads allowed)
			(copperpour allowed)
			(footprints allowed)
		)
		(placement
			(enabled no)
			(sheetname "")
		)
		(fill
			(thermal_gap 0.5)
			(thermal_bridge_width 0.5)
			(island_removal_mode 0)
		)
		(polygon
			(pts
				(xy 357.414068 -314.64123) (xy 355.763068 -314.64123) (xy 355.763068 -312.60923) (xy 357.414068 -312.60923)
			)
		)
	)
	(zone
		(layer "F.Cu")
		(hatch none 0.5)
		(connect_pads
			(clearance 0)
		)
		(min_thickness 0.25)
		(keepout
			(tracks allowed)
			(vias allowed)
			(pads allowed)
			(copperpour allowed)
			(footprints allowed)
		)
		(placement
			(enabled no)
			(sheetname "")
		)
		(fill
			(thermal_gap 0.5)
			(thermal_bridge_width 0.5)
			(island_removal_mode 0)
		)
		(polygon
			(pts
				(xy 303.951132 -34.76117) (xy 303.951132 -33.40989) (xy 305.231292 -33.40989) (xy 305.231292 -34.76117)
			)
		)
	)
	(zone
		(layer "F.Cu")
		(hatch none 0.5)
		(connect_pads
			(clearance 0)
		)
		(min_thickness 0.25)
		(keepout
			(tracks allowed)
			(vias allowed)
			(pads allowed)
			(copperpour allowed)
			(footprints allowed)
		)
		(placement
			(enabled no)
			(sheetname "")
		)
		(fill
			(thermal_gap 0.5)
			(thermal_bridge_width 0.5)
			(island_removal_mode 0)
		)
		(polygon
			(pts
				(arc
					(start 134.468362 -208.308194)
					(mid 134.504283 -208.323073)
					(end 134.519162 -208.358994)
				)
				(arc
					(start 134.519162 -209.068924)
					(mid 134.504283 -209.104845)
					(end 134.468362 -209.119724)
				)
				(arc
					(start 133.18871 -209.119724)
					(mid 133.152789 -209.104845)
					(end 133.13791 -209.068924)
				)
				(arc
					(start 133.13791 -208.358994)
					(mid 133.152789 -208.323073)
					(end 133.18871 -208.308194)
				)
			)
		)
	)
	(zone
		(layer "F.Cu")
		(hatch none 0.5)
		(connect_pads
			(clearance 0)
		)
		(min_thickness 0.25)
		(keepout
			(tracks allowed)
			(vias allowed)
			(pads allowed)
			(copperpour allowed)
			(footprints not_allowed)
		)
		(placement
			(enabled no)
			(sheetname "")
		)
		(fill
			(thermal_gap 0.5)
			(thermal_bridge_width 0.5)
			(island_removal_mode 0)
		)
		(polygon
			(pts
				(xy 140.560044 -361.790234) (xy 111.460026 -361.790234) (xy 111.460026 -417.58997) (xy 140.560044 -417.58997)
			)
		)
	)
	(zone
		(layer "F.Cu")
		(hatch none 0.5)
		(connect_pads
			(clearance 0)
		)
		(min_thickness 0.25)
		(keepout
			(tracks allowed)
			(vias allowed)
			(pads allowed)
			(copperpour allowed)
			(footprints not_allowed)
		)
		(placement
			(enabled no)
			(sheetname "")
		)
		(fill
			(thermal_gap 0.5)
			(thermal_bridge_width 0.5)
			(island_removal_mode 0)
		)
		(polygon
			(pts
				(xy 46.619922 -18.150078) (xy 46.619922 -13.150088) (xy 42.420032 -13.150088) (xy 42.420032 -18.150078)
			)
		)
	)
	(zone
		(layer "F.Cu")
		(hatch none 0.5)
		(connect_pads
			(clearance 0)
		)
		(min_thickness 0.25)
		(keepout
			(tracks allowed)
			(vias allowed)
			(pads allowed)
			(copperpour allowed)
			(footprints allowed)
		)
		(placement
			(enabled no)
			(sheetname "")
		)
		(fill
			(thermal_gap 0.5)
			(thermal_bridge_width 0.5)
			(island_removal_mode 0)
		)
		(polygon
			(pts
				(xy 26.654252 -344.659458) (xy 25.302972 -344.659458) (xy 25.302972 -343.379298) (xy 26.654252 -343.379298)
			)
		)
	)
	(zone
		(layer "F.Cu")
		(hatch none 0.5)
		(connect_pads
			(clearance 0)
		)
		(min_thickness 0.25)
		(keepout
			(tracks allowed)
			(vias allowed)
			(pads allowed)
			(copperpour allowed)
			(footprints allowed)
		)
		(placement
			(enabled no)
			(sheetname "")
		)
		(fill
			(thermal_gap 0.5)
			(thermal_bridge_width 0.5)
			(island_removal_mode 0)
		)
		(polygon
			(pts
				(xy 270.797274 -133.344666) (xy 270.797274 -131.993386) (xy 272.077434 -131.993386) (xy 272.077434 -133.344666)
			)
		)
	)
	(zone
		(layer "F.Cu")
		(hatch none 0.5)
		(connect_pads
			(clearance 0)
		)
		(min_thickness 0.25)
		(keepout
			(tracks allowed)
			(vias allowed)
			(pads allowed)
			(copperpour allowed)
			(footprints allowed)
		)
		(placement
			(enabled no)
			(sheetname "")
		)
		(fill
			(thermal_gap 0.5)
			(thermal_bridge_width 0.5)
			(island_removal_mode 0)
		)
		(polygon
			(pts
				(xy 441.333382 -28.022042) (xy 443.116208 -28.022042) (xy 443.512448 -27.625802) (xy 443.512448 -25.842976)
				(xy 443.375288 -25.705816) (xy 441.226702 -25.705816) (xy 441.013342 -25.919176) (xy 440.967622 -25.919176)
				(xy 440.967622 -27.656282)
			)
		)
	)
	(zone
		(layer "F.Cu")
		(hatch none 0.5)
		(connect_pads
			(clearance 0)
		)
		(min_thickness 0.25)
		(keepout
			(tracks allowed)
			(vias allowed)
			(pads allowed)
			(copperpour allowed)
			(footprints allowed)
		)
		(placement
			(enabled no)
			(sheetname "")
		)
		(fill
			(thermal_gap 0.5)
			(thermal_bridge_width 0.5)
			(island_removal_mode 0)
		)
		(polygon
			(pts
				(xy 290.738306 -356.952042) (xy 289.387026 -356.952042) (xy 289.387026 -355.671882) (xy 290.738306 -355.671882)
			)
		)
	)
	(zone
		(layer "F.Cu")
		(hatch none 0.5)
		(connect_pads
			(clearance 0)
		)
		(min_thickness 0.25)
		(keepout
			(tracks allowed)
			(vias allowed)
			(pads allowed)
			(copperpour allowed)
			(footprints allowed)
		)
		(placement
			(enabled no)
			(sheetname "")
		)
		(fill
			(thermal_gap 0.5)
			(thermal_bridge_width 0.5)
			(island_removal_mode 0)
		)
		(polygon
			(pts
				(xy 420.05123 -34.76117) (xy 420.05123 -33.40989) (xy 421.33139 -33.40989) (xy 421.33139 -34.76117)
			)
		)
	)
	(zone
		(layer "F.Cu")
		(hatch none 0.5)
		(connect_pads
			(clearance 0)
		)
		(min_thickness 0.25)
		(keepout
			(tracks allowed)
			(vias allowed)
			(pads allowed)
			(copperpour allowed)
			(footprints allowed)
		)
		(placement
			(enabled no)
			(sheetname "")
		)
		(fill
			(thermal_gap 0.5)
			(thermal_bridge_width 0.5)
			(island_removal_mode 0)
		)
		(polygon
			(pts
				(xy 293.847266 -344.659458) (xy 292.495986 -344.659458) (xy 292.495986 -343.379298) (xy 293.847266 -343.379298)
			)
		)
	)
	(zone
		(layer "F.Cu")
		(hatch none 0.5)
		(connect_pads
			(clearance 0)
		)
		(min_thickness 0.25)
		(keepout
			(tracks allowed)
			(vias allowed)
			(pads allowed)
			(copperpour allowed)
			(footprints allowed)
		)
		(placement
			(enabled no)
			(sheetname "")
		)
		(fill
			(thermal_gap 0.5)
			(thermal_bridge_width 0.5)
			(island_removal_mode 0)
		)
		(polygon
			(pts
				(xy 128.510792 -356.952042) (xy 127.159512 -356.952042) (xy 127.159512 -355.671882) (xy 128.510792 -355.671882)
			)
		)
	)
	(zone
		(layer "F.Cu")
		(hatch none 0.5)
		(connect_pads
			(clearance 0)
		)
		(min_thickness 0.25)
		(keepout
			(tracks allowed)
			(vias allowed)
			(pads allowed)
			(copperpour allowed)
			(footprints not_allowed)
		)
		(placement
			(enabled no)
			(sheetname "")
		)
		(fill
			(thermal_gap 0.5)
			(thermal_bridge_width 0.5)
			(island_removal_mode 0)
		)
		(polygon
			(pts
				(xy 147.860004 -218.250008) (xy 144.709896 -218.250008) (xy 144.709896 -232.750106) (xy 147.860004 -232.750106)
			)
		)
	)
	(zone
		(layer "F.Cu")
		(hatch none 0.5)
		(connect_pads
			(clearance 0)
		)
		(min_thickness 0.25)
		(keepout
			(tracks allowed)
			(vias allowed)
			(pads allowed)
			(copperpour allowed)
			(footprints allowed)
		)
		(placement
			(enabled no)
			(sheetname "")
		)
		(fill
			(thermal_gap 0.5)
			(thermal_bridge_width 0.5)
			(island_removal_mode 0)
		)
		(polygon
			(pts
				(xy 384.255264 -123.928124) (xy 384.255264 -122.576844) (xy 385.535424 -122.576844) (xy 385.535424 -123.928124)
			)
		)
	)
	(zone
		(layer "F.Cu")
		(hatch none 0.5)
		(connect_pads
			(clearance 0)
		)
		(min_thickness 0.25)
		(keepout
			(tracks allowed)
			(vias allowed)
			(pads allowed)
			(copperpour allowed)
			(footprints allowed)
		)
		(placement
			(enabled no)
			(sheetname "")
		)
		(fill
			(thermal_gap 0.5)
			(thermal_bridge_width 0.5)
			(island_removal_mode 0)
		)
		(polygon
			(pts
				(xy 35.955224 -120.328182) (xy 35.955224 -118.976902) (xy 37.235384 -118.976902) (xy 37.235384 -120.328182)
			)
		)
	)
	(zone
		(layer "F.Cu")
		(hatch none 0.5)
		(connect_pads
			(clearance 0)
		)
		(min_thickness 0.25)
		(keepout
			(tracks allowed)
			(vias allowed)
			(pads allowed)
			(copperpour allowed)
			(footprints allowed)
		)
		(placement
			(enabled no)
			(sheetname "")
		)
		(fill
			(thermal_gap 0.5)
			(thermal_bridge_width 0.5)
			(island_removal_mode 0)
		)
		(polygon
			(pts
				(xy 398.364964 -137.42924) (xy 400.452336 -137.42924) (xy 400.772376 -137.1092) (xy 400.772376 -129.7051)
				(xy 398.427448 -129.7051) (xy 398.349216 -129.783332) (xy 398.349216 -137.413492)
			)
		)
	)
	(zone
		(layer "F.Cu")
		(hatch none 0.5)
		(connect_pads
			(clearance 0)
		)
		(min_thickness 0.25)
		(keepout
			(tracks allowed)
			(vias allowed)
			(pads allowed)
			(copperpour allowed)
			(footprints allowed)
		)
		(placement
			(enabled no)
			(sheetname "")
		)
		(fill
			(thermal_gap 0.5)
			(thermal_bridge_width 0.5)
			(island_removal_mode 0)
		)
		(polygon
			(pts
				(xy 287.629346 -350.80575) (xy 286.278066 -350.80575) (xy 286.278066 -349.52559) (xy 287.629346 -349.52559)
			)
		)
	)
	(zone
		(layer "F.Cu")
		(hatch none 0.5)
		(connect_pads
			(clearance 0)
		)
		(min_thickness 0.25)
		(keepout
			(tracks allowed)
			(vias allowed)
			(pads allowed)
			(copperpour allowed)
			(footprints allowed)
		)
		(placement
			(enabled no)
			(sheetname "")
		)
		(fill
			(thermal_gap 0.5)
			(thermal_bridge_width 0.5)
			(island_removal_mode 0)
		)
		(polygon
			(pts
				(xy 8.705342 -371.2718) (xy 8.705342 -372.10873) (xy 8.705342 -372.599204) (xy 8.705596 -372.599458)
				(xy 10.153396 -372.599458) (xy 10.274046 -372.478808) (xy 10.274046 -372.169436) (xy 10.24382 -372.13921)
				(xy 10.24382 -371.29466) (xy 10.160762 -371.211602) (xy 8.76554 -371.211602)
			)
		)
	)
	(zone
		(layer "F.Cu")
		(hatch none 0.5)
		(connect_pads
			(clearance 0)
		)
		(min_thickness 0.25)
		(keepout
			(tracks allowed)
			(vias allowed)
			(pads allowed)
			(copperpour allowed)
			(footprints not_allowed)
		)
		(placement
			(enabled no)
			(sheetname "")
		)
		(fill
			(thermal_gap 0.5)
			(thermal_bridge_width 0.5)
			(island_removal_mode 0)
		)
		(polygon
			(pts
				(xy 446.920112 -18.150078) (xy 446.920112 -13.150088) (xy 442.719968 -13.150088) (xy 442.719968 -18.150078)
			)
		)
	)
	(zone
		(layer "F.Cu")
		(hatch none 0.5)
		(connect_pads
			(clearance 0)
		)
		(min_thickness 0.25)
		(keepout
			(tracks not_allowed)
			(vias allowed)
			(pads allowed)
			(copperpour not_allowed)
			(footprints allowed)
		)
		(placement
			(enabled no)
			(sheetname "")
		)
		(fill
			(thermal_gap 0.5)
			(thermal_bridge_width 0.5)
			(island_removal_mode 0)
		)
		(polygon
			(pts
				(arc
					(start 200.699878 -378.70003)
					(mid 195.699888 -383.70002)
					(end 190.699898 -378.70003)
				)
				(arc
					(start 190.699898 -378.70003)
					(mid 195.699888 -373.70004)
					(end 200.699878 -378.70003)
				)
			)
		)
	)
	(zone
		(layer "F.Cu")
		(hatch none 0.5)
		(connect_pads
			(clearance 0)
		)
		(min_thickness 0.25)
		(keepout
			(tracks allowed)
			(vias allowed)
			(pads allowed)
			(copperpour allowed)
			(footprints allowed)
		)
		(placement
			(enabled no)
			(sheetname "")
		)
		(fill
			(thermal_gap 0.5)
			(thermal_bridge_width 0.5)
			(island_removal_mode 0)
		)
		(polygon
			(pts
				(xy 137.837672 -356.952042) (xy 136.486392 -356.952042) (xy 136.486392 -355.671882) (xy 137.837672 -355.671882)
			)
		)
	)
	(zone
		(layer "F.Cu")
		(hatch none 0.5)
		(connect_pads
			(clearance 0)
		)
		(min_thickness 0.25)
		(keepout
			(tracks not_allowed)
			(vias allowed)
			(pads allowed)
			(copperpour not_allowed)
			(footprints allowed)
		)
		(placement
			(enabled no)
			(sheetname "")
		)
		(fill
			(thermal_gap 0.5)
			(thermal_bridge_width 0.5)
			(island_removal_mode 0)
		)
		(polygon
			(pts
				(arc
					(start 23.9649 -17.999964)
					(mid 25.964896 -15.999968)
					(end 27.964892 -17.999964)
				)
				(arc
					(start 27.964892 -17.999964)
					(mid 25.964896 -19.99996)
					(end 23.9649 -17.999964)
				)
			)
		)
	)
	(zone
		(layer "F.Cu")
		(hatch none 0.5)
		(connect_pads
			(clearance 0)
		)
		(min_thickness 0.25)
		(keepout
			(tracks not_allowed)
			(vias allowed)
			(pads allowed)
			(copperpour not_allowed)
			(footprints allowed)
		)
		(placement
			(enabled no)
			(sheetname "")
		)
		(fill
			(thermal_gap 0.5)
			(thermal_bridge_width 0.5)
			(island_removal_mode 0)
		)
		(polygon
			(pts
				(arc
					(start 5.199888 -396.54988)
					(mid 3.649726 -398.100042)
					(end 5.199888 -399.64995)
				)
				(arc
					(start 6.800088 -399.64995)
					(mid 8.349996 -398.100042)
					(end 6.800088 -396.54988)
				)
			)
		)
	)
	(zone
		(layer "F.Cu")
		(hatch none 0.5)
		(connect_pads
			(clearance 0)
		)
		(min_thickness 0.25)
		(keepout
			(tracks allowed)
			(vias allowed)
			(pads allowed)
			(copperpour allowed)
			(footprints allowed)
		)
		(placement
			(enabled no)
			(sheetname "")
		)
		(fill
			(thermal_gap 0.5)
			(thermal_bridge_width 0.5)
			(island_removal_mode 0)
		)
		(polygon
			(pts
				(xy 120.16486 -312.599578) (xy 121.81586 -312.599578) (xy 121.81586 -314.631578) (xy 120.16486 -314.631578)
			)
		)
	)
	(zone
		(layer "F.Cu")
		(hatch none 0.5)
		(connect_pads
			(clearance 0)
		)
		(min_thickness 0.25)
		(keepout
			(tracks allowed)
			(vias allowed)
			(pads allowed)
			(copperpour allowed)
			(footprints allowed)
		)
		(placement
			(enabled no)
			(sheetname "")
		)
		(fill
			(thermal_gap 0.5)
			(thermal_bridge_width 0.5)
			(island_removal_mode 0)
		)
		(polygon
			(pts
				(xy 332.235048 -350.80575) (xy 330.883768 -350.80575) (xy 330.883768 -349.52559) (xy 332.235048 -349.52559)
			)
		)
	)
	(zone
		(layer "F.Cu")
		(hatch none 0.5)
		(connect_pads
			(clearance 0)
		)
		(min_thickness 0.25)
		(keepout
			(tracks allowed)
			(vias allowed)
			(pads allowed)
			(copperpour allowed)
			(footprints allowed)
		)
		(placement
			(enabled no)
			(sheetname "")
		)
		(fill
			(thermal_gap 0.5)
			(thermal_bridge_width 0.5)
			(island_removal_mode 0)
		)
		(polygon
			(pts
				(xy 87.347806 -344.659458) (xy 85.996526 -344.659458) (xy 85.996526 -343.379298) (xy 87.347806 -343.379298)
			)
		)
	)
	(zone
		(layer "F.Cu")
		(hatch none 0.5)
		(connect_pads
			(clearance 0)
		)
		(min_thickness 0.25)
		(keepout
			(tracks allowed)
			(vias allowed)
			(pads allowed)
			(copperpour allowed)
			(footprints allowed)
		)
		(placement
			(enabled no)
			(sheetname "")
		)
		(fill
			(thermal_gap 0.5)
			(thermal_bridge_width 0.5)
			(island_removal_mode 0)
		)
		(polygon
			(pts
				(xy 154.697176 -122.13463) (xy 154.697176 -120.78335) (xy 155.977336 -120.78335) (xy 155.977336 -122.13463)
			)
		)
	)
	(zone
		(layer "F.Cu")
		(hatch none 0.5)
		(connect_pads
			(clearance 0)
		)
		(min_thickness 0.25)
		(keepout
			(tracks allowed)
			(vias allowed)
			(pads allowed)
			(copperpour allowed)
			(footprints allowed)
		)
		(placement
			(enabled no)
			(sheetname "")
		)
		(fill
			(thermal_gap 0.5)
			(thermal_bridge_width 0.5)
			(island_removal_mode 0)
		)
		(polygon
			(pts
				(xy 342.197436 -88.441276) (xy 342.197436 -87.652098) (xy 343.05621 -86.793324) (xy 343.05621 -86.097364)
				(xy 341.982806 -85.02396) (xy 341.048848 -85.02396) (xy 340.85149 -85.221318) (xy 340.85149 -88.580214)
				(xy 340.85149 -88.968834) (xy 340.95055 -89.067894) (xy 342.04148 -89.067894) (xy 342.197436 -88.911938)
			)
		)
	)
	(zone
		(layer "F.Cu")
		(hatch none 0.5)
		(connect_pads
			(clearance 0)
		)
		(min_thickness 0.25)
		(keepout
			(tracks allowed)
			(vias allowed)
			(pads allowed)
			(copperpour allowed)
			(footprints allowed)
		)
		(placement
			(enabled no)
			(sheetname "")
		)
		(fill
			(thermal_gap 0.5)
			(thermal_bridge_width 0.5)
			(island_removal_mode 0)
		)
		(polygon
			(pts
				(xy 139.113768 -97.352612) (xy 140.342112 -97.352612) (xy 140.507466 -97.187258) (xy 140.507466 -87.573612)
				(xy 140.224002 -87.290148) (xy 139.279122 -87.290148) (xy 139.042902 -87.526368) (xy 139.042902 -97.281746)
			)
		)
	)
	(zone
		(layer "F.Cu")
		(hatch none 0.5)
		(connect_pads
			(clearance 0)
		)
		(min_thickness 0.25)
		(keepout
			(tracks allowed)
			(vias allowed)
			(pads allowed)
			(copperpour allowed)
			(footprints not_allowed)
		)
		(placement
			(enabled no)
			(sheetname "")
		)
		(fill
			(thermal_gap 0.5)
			(thermal_bridge_width 0.5)
			(island_removal_mode 0)
		)
		(polygon
			(pts
				(xy 409.82011 -18.219928) (xy 405.619966 -18.219928) (xy 405.619966 -23.219918) (xy 409.82011 -23.219918)
			)
		)
	)
	(zone
		(layer "F.Cu")
		(hatch none 0.5)
		(connect_pads
			(clearance 0)
		)
		(min_thickness 0.25)
		(keepout
			(tracks allowed)
			(vias allowed)
			(pads allowed)
			(copperpour allowed)
			(footprints allowed)
		)
		(placement
			(enabled no)
			(sheetname "")
		)
		(fill
			(thermal_gap 0.5)
			(thermal_bridge_width 0.5)
			(island_removal_mode 0)
		)
		(polygon
			(pts
				(xy 2.64287 -387.169406) (xy 1.80594 -387.169406) (xy 1.315466 -387.169406) (xy 1.315212 -387.16966)
				(xy 1.315212 -388.61746) (xy 1.435862 -388.73811) (xy 1.745234 -388.73811) (xy 1.77546 -388.707884)
				(xy 2.62001 -388.707884) (xy 2.703068 -388.624826) (xy 2.703068 -387.229604)
			)
		)
	)
	(zone
		(layer "F.Cu")
		(hatch none 0.5)
		(connect_pads
			(clearance 0)
		)
		(min_thickness 0.25)
		(keepout
			(tracks not_allowed)
			(vias allowed)
			(pads allowed)
			(copperpour not_allowed)
			(footprints allowed)
		)
		(placement
			(enabled no)
			(sheetname "")
		)
		(fill
			(thermal_gap 0.5)
			(thermal_bridge_width 0.5)
			(island_removal_mode 0)
		)
		(polygon
			(pts
				(arc
					(start 106.810048 -407.599896)
					(mid 104.010206 -410.399738)
					(end 101.21011 -407.599896)
				)
				(arc
					(start 101.21011 -407.599896)
					(mid 104.010206 -404.7998)
					(end 106.810048 -407.599896)
				)
			)
		)
	)
	(zone
		(layer "F.Cu")
		(hatch none 0.5)
		(connect_pads
			(clearance 0)
		)
		(min_thickness 0.25)
		(keepout
			(tracks allowed)
			(vias allowed)
			(pads allowed)
			(copperpour allowed)
			(footprints allowed)
		)
		(placement
			(enabled no)
			(sheetname "")
		)
		(fill
			(thermal_gap 0.5)
			(thermal_bridge_width 0.5)
			(island_removal_mode 0)
		)
		(polygon
			(pts
				(xy 195.435982 -131.00939) (xy 195.435982 -129.65811) (xy 196.716142 -129.65811) (xy 196.716142 -131.00939)
			)
		)
	)
	(zone
		(layer "F.Cu")
		(hatch none 0.5)
		(connect_pads
			(clearance 0)
		)
		(min_thickness 0.25)
		(keepout
			(tracks allowed)
			(vias allowed)
			(pads allowed)
			(copperpour allowed)
			(footprints allowed)
		)
		(placement
			(enabled no)
			(sheetname "")
		)
		(fill
			(thermal_gap 0.5)
			(thermal_bridge_width 0.5)
			(island_removal_mode 0)
		)
		(polygon
			(pts
				(xy 198.07809 -152.726136) (xy 198.07809 -151.374856) (xy 199.35825 -151.374856) (xy 199.35825 -152.726136)
			)
		)
	)
	(zone
		(layer "F.Cu")
		(hatch none 0.5)
		(connect_pads
			(clearance 0)
		)
		(min_thickness 0.25)
		(keepout
			(tracks allowed)
			(vias allowed)
			(pads allowed)
			(copperpour allowed)
			(footprints allowed)
		)
		(placement
			(enabled no)
			(sheetname "")
		)
		(fill
			(thermal_gap 0.5)
			(thermal_bridge_width 0.5)
			(island_removal_mode 0)
		)
		(polygon
			(pts
				(xy 438.7596 -101.0666) (xy 438.7596 -99.3902) (xy 440.436 -99.3902) (xy 440.436 -101.0666)
			)
		)
	)
	(zone
		(layer "F.Cu")
		(hatch none 0.5)
		(connect_pads
			(clearance 0)
		)
		(min_thickness 0.25)
		(keepout
			(tracks allowed)
			(vias allowed)
			(pads allowed)
			(copperpour allowed)
			(footprints allowed)
		)
		(placement
			(enabled no)
			(sheetname "")
		)
		(fill
			(thermal_gap 0.5)
			(thermal_bridge_width 0.5)
			(island_removal_mode 0)
		)
		(polygon
			(pts
				(xy 282.264866 -137.42924) (xy 284.352238 -137.42924) (xy 284.672278 -137.1092) (xy 284.672278 -129.7051)
				(xy 282.32735 -129.7051) (xy 282.249118 -129.783332) (xy 282.249118 -137.413492)
			)
		)
	)
	(zone
		(layer "F.Cu")
		(hatch none 0.5)
		(connect_pads
			(clearance 0)
		)
		(min_thickness 0.25)
		(keepout
			(tracks allowed)
			(vias allowed)
			(pads allowed)
			(copperpour allowed)
			(footprints allowed)
		)
		(placement
			(enabled no)
			(sheetname "")
		)
		(fill
			(thermal_gap 0.5)
			(thermal_bridge_width 0.5)
			(island_removal_mode 0)
		)
		(polygon
			(pts
				(xy 132.331968 -179.013612) (xy 132.331968 -177.261012) (xy 134.109968 -177.261012) (xy 134.109968 -179.013612)
			)
		)
	)
	(zone
		(layer "F.Cu")
		(hatch none 0.5)
		(connect_pads
			(clearance 0)
		)
		(min_thickness 0.25)
		(keepout
			(tracks allowed)
			(vias allowed)
			(pads allowed)
			(copperpour allowed)
			(footprints allowed)
		)
		(placement
			(enabled no)
			(sheetname "")
		)
		(fill
			(thermal_gap 0.5)
			(thermal_bridge_width 0.5)
			(island_removal_mode 0)
		)
		(polygon
			(pts
				(xy 284.520386 -350.80575) (xy 283.169106 -350.80575) (xy 283.169106 -349.52559) (xy 284.520386 -349.52559)
			)
		)
	)
	(zone
		(layer "F.Cu")
		(hatch none 0.5)
		(connect_pads
			(clearance 0)
		)
		(min_thickness 0.25)
		(keepout
			(tracks allowed)
			(vias allowed)
			(pads allowed)
			(copperpour allowed)
			(footprints allowed)
		)
		(placement
			(enabled no)
			(sheetname "")
		)
		(fill
			(thermal_gap 0.5)
			(thermal_bridge_width 0.5)
			(island_removal_mode 0)
		)
		(polygon
			(pts
				(xy 190.05931 -47.3202) (xy 190.05931 -45.5676) (xy 191.83731 -45.5676) (xy 191.83731 -47.3202)
			)
		)
	)
	(zone
		(layer "F.Cu")
		(hatch none 0.5)
		(connect_pads
			(clearance 0)
		)
		(min_thickness 0.25)
		(keepout
			(tracks allowed)
			(vias allowed)
			(pads allowed)
			(copperpour allowed)
			(footprints allowed)
		)
		(placement
			(enabled no)
			(sheetname "")
		)
		(fill
			(thermal_gap 0.5)
			(thermal_bridge_width 0.5)
			(island_removal_mode 0)
		)
		(polygon
			(pts
				(xy 178.834796 -350.80575) (xy 177.483516 -350.80575) (xy 177.483516 -349.52559) (xy 178.834796 -349.52559)
			)
		)
	)
	(zone
		(layer "F.Cu")
		(hatch none 0.5)
		(connect_pads
			(clearance 0)
		)
		(min_thickness 0.25)
		(keepout
			(tracks allowed)
			(vias allowed)
			(pads allowed)
			(copperpour allowed)
			(footprints allowed)
		)
		(placement
			(enabled no)
			(sheetname "")
		)
		(fill
			(thermal_gap 0.5)
			(thermal_bridge_width 0.5)
			(island_removal_mode 0)
		)
		(polygon
			(pts
				(xy 217.484452 -225.108516) (xy 218.527376 -225.108516) (xy 218.663012 -224.97288) (xy 218.663012 -223.168718)
				(xy 218.402154 -222.90786) (xy 217.45321 -222.90786) (xy 217.30716 -223.05391) (xy 217.30716 -224.931224)
			)
		)
	)
	(zone
		(layer "F.Cu")
		(hatch none 0.5)
		(connect_pads
			(clearance 0)
		)
		(min_thickness 0.25)
		(keepout
			(tracks not_allowed)
			(vias allowed)
			(pads allowed)
			(copperpour not_allowed)
			(footprints allowed)
		)
		(placement
			(enabled no)
			(sheetname "")
		)
		(fill
			(thermal_gap 0.5)
			(thermal_bridge_width 0.5)
			(island_removal_mode 0)
		)
		(polygon
			(pts
				(arc
					(start 340.214966 -17.999964)
					(mid 342.214962 -15.999968)
					(end 344.214958 -17.999964)
				)
				(arc
					(start 344.214958 -17.999964)
					(mid 342.214962 -19.99996)
					(end 340.214966 -17.999964)
				)
			)
		)
	)
	(zone
		(layer "F.Cu")
		(hatch none 0.5)
		(connect_pads
			(clearance 0)
		)
		(min_thickness 0.25)
		(keepout
			(tracks allowed)
			(vias allowed)
			(pads allowed)
			(copperpour allowed)
			(footprints not_allowed)
		)
		(placement
			(enabled no)
			(sheetname "")
		)
		(fill
			(thermal_gap 0.5)
			(thermal_bridge_width 0.5)
			(island_removal_mode 0)
		)
		(polygon
			(pts
				(xy 359.08996 -232.750106) (xy 376.910092 -232.750106) (xy 376.910092 -218.250008) (xy 359.08996 -218.250008)
			)
		)
	)
	(zone
		(layer "F.Cu")
		(hatch none 0.5)
		(connect_pads
			(clearance 0)
		)
		(min_thickness 0.25)
		(keepout
			(tracks allowed)
			(vias allowed)
			(pads allowed)
			(copperpour allowed)
			(footprints allowed)
		)
		(placement
			(enabled no)
			(sheetname "")
		)
		(fill
			(thermal_gap 0.5)
			(thermal_bridge_width 0.5)
			(island_removal_mode 0)
		)
		(polygon
			(pts
				(xy 84.238846 -350.80575) (xy 82.887566 -350.80575) (xy 82.887566 -349.52559) (xy 84.238846 -349.52559)
			)
		)
	)
	(zone
		(layer "F.Cu")
		(hatch none 0.5)
		(connect_pads
			(clearance 0)
		)
		(min_thickness 0.25)
		(keepout
			(tracks allowed)
			(vias allowed)
			(pads allowed)
			(copperpour allowed)
			(footprints allowed)
		)
		(placement
			(enabled no)
			(sheetname "")
		)
		(fill
			(thermal_gap 0.5)
			(thermal_bridge_width 0.5)
			(island_removal_mode 0)
		)
		(polygon
			(pts
				(xy 314.711588 -136.416034) (xy 314.711588 -135.064754) (xy 315.991748 -135.064754) (xy 315.991748 -136.416034)
			)
		)
	)
	(zone
		(layer "F.Cu")
		(hatch none 0.5)
		(connect_pads
			(clearance 0)
		)
		(min_thickness 0.25)
		(keepout
			(tracks allowed)
			(vias allowed)
			(pads allowed)
			(copperpour allowed)
			(footprints not_allowed)
		)
		(placement
			(enabled no)
			(sheetname "")
		)
		(fill
			(thermal_gap 0.5)
			(thermal_bridge_width 0.5)
			(island_removal_mode 0)
		)
		(polygon
			(pts
				(xy 125.065028 -40.120062) (xy 133.065012 -40.120062) (xy 133.065012 -13.850112) (xy 125.065028 -13.850112)
			)
		)
	)
	(zone
		(layer "F.Cu")
		(hatch none 0.5)
		(connect_pads
			(clearance 0)
		)
		(min_thickness 0.25)
		(keepout
			(tracks allowed)
			(vias allowed)
			(pads allowed)
			(copperpour allowed)
			(footprints allowed)
		)
		(placement
			(enabled no)
			(sheetname "")
		)
		(fill
			(thermal_gap 0.5)
			(thermal_bridge_width 0.5)
			(island_removal_mode 0)
		)
		(polygon
			(pts
				(xy 416.591496 -356.952042) (xy 415.240216 -356.952042) (xy 415.240216 -355.671882) (xy 416.591496 -355.671882)
			)
		)
	)
	(zone
		(layer "F.Cu")
		(hatch none 0.5)
		(connect_pads
			(clearance 0)
		)
		(min_thickness 0.25)
		(keepout
			(tracks allowed)
			(vias allowed)
			(pads allowed)
			(copperpour allowed)
			(footprints allowed)
		)
		(placement
			(enabled no)
			(sheetname "")
		)
		(fill
			(thermal_gap 0.5)
			(thermal_bridge_width 0.5)
			(island_removal_mode 0)
		)
		(polygon
			(pts
				(xy 438.354216 -356.928166) (xy 437.002936 -356.928166) (xy 437.002936 -355.648006) (xy 438.354216 -355.648006)
			)
		)
	)
	(zone
		(layer "F.Cu")
		(hatch none 0.5)
		(connect_pads
			(clearance 0)
		)
		(min_thickness 0.25)
		(keepout
			(tracks allowed)
			(vias allowed)
			(pads allowed)
			(copperpour allowed)
			(footprints allowed)
		)
		(placement
			(enabled no)
			(sheetname "")
		)
		(fill
			(thermal_gap 0.5)
			(thermal_bridge_width 0.5)
			(island_removal_mode 0)
		)
		(polygon
			(pts
				(xy 243.29136 -267.948156) (xy 243.29136 -265.799316) (xy 244.96268 -265.799316) (xy 244.96268 -267.948156)
			)
		)
	)
	(zone
		(layer "F.Cu")
		(hatch none 0.5)
		(connect_pads
			(clearance 0)
		)
		(min_thickness 0.25)
		(keepout
			(tracks allowed)
			(vias allowed)
			(pads allowed)
			(copperpour allowed)
			(footprints allowed)
		)
		(placement
			(enabled no)
			(sheetname "")
		)
		(fill
			(thermal_gap 0.5)
			(thermal_bridge_width 0.5)
			(island_removal_mode 0)
		)
		(polygon
			(pts
				(xy 300.065186 -356.928166) (xy 298.713906 -356.928166) (xy 298.713906 -355.648006) (xy 300.065186 -355.648006)
			)
		)
	)
	(zone
		(layer "F.Cu")
		(hatch none 0.5)
		(connect_pads
			(clearance 0)
		)
		(min_thickness 0.25)
		(keepout
			(tracks allowed)
			(vias allowed)
			(pads allowed)
			(copperpour allowed)
			(footprints allowed)
		)
		(placement
			(enabled no)
			(sheetname "")
		)
		(fill
			(thermal_gap 0.5)
			(thermal_bridge_width 0.5)
			(island_removal_mode 0)
		)
		(polygon
			(pts
				(xy 384.255264 -109.424724) (xy 384.255264 -108.073444) (xy 385.535424 -108.073444) (xy 385.535424 -109.424724)
			)
		)
	)
	(zone
		(layer "F.Cu")
		(hatch none 0.5)
		(connect_pads
			(clearance 0)
		)
		(min_thickness 0.25)
		(keepout
			(tracks allowed)
			(vias allowed)
			(pads allowed)
			(copperpour allowed)
			(footprints allowed)
		)
		(placement
			(enabled no)
			(sheetname "")
		)
		(fill
			(thermal_gap 0.5)
			(thermal_bridge_width 0.5)
			(island_removal_mode 0)
		)
		(polygon
			(pts
				(xy 344.670888 -344.635582) (xy 343.319608 -344.635582) (xy 343.319608 -343.355422) (xy 344.670888 -343.355422)
			)
		)
	)
	(zone
		(layer "F.Cu")
		(hatch none 0.5)
		(connect_pads
			(clearance 0)
		)
		(min_thickness 0.25)
		(keepout
			(tracks allowed)
			(vias allowed)
			(pads allowed)
			(copperpour allowed)
			(footprints allowed)
		)
		(placement
			(enabled no)
			(sheetname "")
		)
		(fill
			(thermal_gap 0.5)
			(thermal_bridge_width 0.5)
			(island_removal_mode 0)
		)
		(polygon
			(pts
				(xy 427.636178 -154.51963) (xy 427.636178 -153.16835) (xy 428.916338 -153.16835) (xy 428.916338 -154.51963)
			)
		)
	)
	(zone
		(layer "F.Cu")
		(hatch none 0.5)
		(connect_pads
			(clearance 0)
		)
		(min_thickness 0.25)
		(keepout
			(tracks not_allowed)
			(vias allowed)
			(pads allowed)
			(copperpour not_allowed)
			(footprints allowed)
		)
		(placement
			(enabled no)
			(sheetname "")
		)
		(fill
			(thermal_gap 0.5)
			(thermal_bridge_width 0.5)
			(island_removal_mode 0)
		)
		(polygon
			(pts
				(arc
					(start 344.899996 -194.360038)
					(mid 349.899986 -189.360048)
					(end 354.899976 -194.360038)
				)
				(arc
					(start 354.899976 -194.360038)
					(mid 349.899986 -199.360028)
					(end 344.899996 -194.360038)
				)
			)
		)
	)
	(zone
		(layer "F.Cu")
		(hatch none 0.5)
		(connect_pads
			(clearance 0)
		)
		(min_thickness 0.25)
		(keepout
			(tracks allowed)
			(vias allowed)
			(pads allowed)
			(copperpour allowed)
			(footprints allowed)
		)
		(placement
			(enabled no)
			(sheetname "")
		)
		(fill
			(thermal_gap 0.5)
			(thermal_bridge_width 0.5)
			(island_removal_mode 0)
		)
		(polygon
			(pts
				(xy 316.715648 -344.659458) (xy 315.364368 -344.659458) (xy 315.364368 -343.379298) (xy 316.715648 -343.379298)
			)
		)
	)
	(zone
		(layer "F.Cu")
		(hatch none 0.5)
		(connect_pads
			(clearance 0)
		)
		(min_thickness 0.25)
		(keepout
			(tracks allowed)
			(vias allowed)
			(pads allowed)
			(copperpour allowed)
			(footprints allowed)
		)
		(placement
			(enabled no)
			(sheetname "")
		)
		(fill
			(thermal_gap 0.5)
			(thermal_bridge_width 0.5)
			(island_removal_mode 0)
		)
		(polygon
			(pts
				(xy 78.020926 -356.952042) (xy 76.669646 -356.952042) (xy 76.669646 -355.671882) (xy 78.020926 -355.671882)
			)
		)
	)
	(zone
		(layer "F.Cu")
		(hatch none 0.5)
		(connect_pads
			(clearance 0)
		)
		(min_thickness 0.25)
		(keepout
			(tracks allowed)
			(vias allowed)
			(pads allowed)
			(copperpour allowed)
			(footprints allowed)
		)
		(placement
			(enabled no)
			(sheetname "")
		)
		(fill
			(thermal_gap 0.5)
			(thermal_bridge_width 0.5)
			(island_removal_mode 0)
		)
		(polygon
			(pts
				(xy 226.1108 -149.6822) (xy 226.1108 -144.6784) (xy 231.0638 -144.6784) (xy 231.0638 -149.6822)
			)
		)
	)
	(zone
		(layer "F.Cu")
		(hatch none 0.5)
		(connect_pads
			(clearance 0)
		)
		(min_thickness 0.25)
		(keepout
			(tracks allowed)
			(vias allowed)
			(pads allowed)
			(copperpour allowed)
			(footprints allowed)
		)
		(placement
			(enabled no)
			(sheetname "")
		)
		(fill
			(thermal_gap 0.5)
			(thermal_bridge_width 0.5)
			(island_removal_mode 0)
		)
		(polygon
			(pts
				(xy 131.35229 -178.00447) (xy 131.35229 -176.25187) (xy 133.13029 -176.25187) (xy 133.13029 -178.00447)
			)
		)
	)
	(zone
		(layer "F.Cu")
		(hatch none 0.5)
		(connect_pads
			(clearance 0)
		)
		(min_thickness 0.25)
		(keepout
			(tracks allowed)
			(vias allowed)
			(pads allowed)
			(copperpour allowed)
			(footprints allowed)
		)
		(placement
			(enabled no)
			(sheetname "")
		)
		(fill
			(thermal_gap 0.5)
			(thermal_bridge_width 0.5)
			(island_removal_mode 0)
		)
		(polygon
			(pts
				(xy 344.670888 -350.781874) (xy 343.319608 -350.781874) (xy 343.319608 -349.501714) (xy 344.670888 -349.501714)
			)
		)
	)
	(zone
		(layer "F.Cu")
		(hatch none 0.5)
		(connect_pads
			(clearance 0)
		)
		(min_thickness 0.25)
		(keepout
			(tracks allowed)
			(vias allowed)
			(pads allowed)
			(copperpour allowed)
			(footprints not_allowed)
		)
		(placement
			(enabled no)
			(sheetname "")
		)
		(fill
			(thermal_gap 0.5)
			(thermal_bridge_width 0.5)
			(island_removal_mode 0)
		)
		(polygon
			(pts
				(xy 304.820066 -18.150078) (xy 304.820066 -13.150088) (xy 300.619922 -13.150088) (xy 300.619922 -18.150078)
			)
		)
	)
	(zone
		(layer "F.Cu")
		(hatch none 0.5)
		(connect_pads
			(clearance 0)
		)
		(min_thickness 0.25)
		(keepout
			(tracks allowed)
			(vias allowed)
			(pads allowed)
			(copperpour allowed)
			(footprints allowed)
		)
		(placement
			(enabled no)
			(sheetname "")
		)
		(fill
			(thermal_gap 0.5)
			(thermal_bridge_width 0.5)
			(island_removal_mode 0)
		)
		(polygon
			(pts
				(xy 371.856 -230.378) (xy 371.856 -220.599) (xy 373.888 -220.599) (xy 373.888 -230.378)
			)
		)
	)
	(zone
		(layer "F.Cu")
		(hatch none 0.5)
		(connect_pads
			(clearance 0)
		)
		(min_thickness 0.25)
		(keepout
			(tracks allowed)
			(vias allowed)
			(pads allowed)
			(copperpour allowed)
			(footprints allowed)
		)
		(placement
			(enabled no)
			(sheetname "")
		)
		(fill
			(thermal_gap 0.5)
			(thermal_bridge_width 0.5)
			(island_removal_mode 0)
		)
		(polygon
			(pts
				(xy 116.074952 -356.952042) (xy 114.723672 -356.952042) (xy 114.723672 -355.671882) (xy 116.074952 -355.671882)
			)
		)
	)
	(zone
		(layer "F.Cu")
		(hatch none 0.5)
		(connect_pads
			(clearance 0)
		)
		(min_thickness 0.25)
		(keepout
			(tracks allowed)
			(vias allowed)
			(pads allowed)
			(copperpour allowed)
			(footprints not_allowed)
		)
		(placement
			(enabled no)
			(sheetname "")
		)
		(fill
			(thermal_gap 0.5)
			(thermal_bridge_width 0.5)
			(island_removal_mode 0)
		)
		(polygon
			(pts
				(xy 60.96508 -40.120062) (xy 68.96481 -40.120062) (xy 68.965064 -13.850112) (xy 60.96508 -13.850112)
			)
		)
	)
	(zone
		(layer "F.Cu")
		(hatch none 0.5)
		(connect_pads
			(clearance 0)
		)
		(min_thickness 0.25)
		(keepout
			(tracks allowed)
			(vias allowed)
			(pads allowed)
			(copperpour allowed)
			(footprints allowed)
		)
		(placement
			(enabled no)
			(sheetname "")
		)
		(fill
			(thermal_gap 0.5)
			(thermal_bridge_width 0.5)
			(island_removal_mode 0)
		)
		(polygon
			(pts
				(xy 111.166402 -83.179666) (xy 111.166402 -82.123788) (xy 110.911132 -81.868518) (xy 109.172502 -81.868518)
				(xy 108.80979 -81.505806) (xy 108.087414 -81.505806) (xy 107.724702 -81.868518) (xy 106.420158 -81.868518)
				(xy 106.362246 -81.92643) (xy 106.362246 -83.075526) (xy 106.524552 -83.237832) (xy 111.108236 -83.237832)
			)
		)
	)
	(zone
		(layer "F.Cu")
		(hatch none 0.5)
		(connect_pads
			(clearance 0)
		)
		(min_thickness 0.25)
		(keepout
			(tracks not_allowed)
			(vias allowed)
			(pads allowed)
			(copperpour not_allowed)
			(footprints allowed)
		)
		(placement
			(enabled no)
			(sheetname "")
		)
		(fill
			(thermal_gap 0.5)
			(thermal_bridge_width 0.5)
			(island_removal_mode 0)
		)
		(polygon
			(pts
				(arc
					(start 368.590068 -407.599896)
					(mid 363.590078 -412.599886)
					(end 358.590088 -407.599896)
				)
				(arc
					(start 358.590088 -407.599896)
					(mid 363.590078 -402.599906)
					(end 368.590068 -407.599896)
				)
			)
		)
	)
	(zone
		(layer "F.Cu")
		(hatch none 0.5)
		(connect_pads
			(clearance 0)
		)
		(min_thickness 0.25)
		(keepout
			(tracks allowed)
			(vias allowed)
			(pads allowed)
			(copperpour allowed)
			(footprints not_allowed)
		)
		(placement
			(enabled no)
			(sheetname "")
		)
		(fill
			(thermal_gap 0.5)
			(thermal_bridge_width 0.5)
			(island_removal_mode 0)
		)
		(polygon
			(pts
				(xy 0.999998 -322.200016) (xy 19.150076 -322.200016) (xy 19.150076 -310.330088)
				(arc
					(start 7.351522 -310.330088)
					(mid 7.46277 -310.865007)
					(end 7.500112 -311.410096)
				)
				(arc
					(start 7.500112 -311.410096)
					(mid 5.232103 -315.015671)
					(end 0.999998 -314.532518)
				)
			)
		)
	)
	(zone
		(layer "F.Cu")
		(hatch none 0.5)
		(connect_pads
			(clearance 0)
		)
		(min_thickness 0.25)
		(keepout
			(tracks allowed)
			(vias allowed)
			(pads allowed)
			(copperpour allowed)
			(footprints allowed)
		)
		(placement
			(enabled no)
			(sheetname "")
		)
		(fill
			(thermal_gap 0.5)
			(thermal_bridge_width 0.5)
			(island_removal_mode 0)
		)
		(polygon
			(pts
				(xy 326.017128 -356.952042) (xy 324.665848 -356.952042) (xy 324.665848 -355.671882) (xy 326.017128 -355.671882)
			)
		)
	)
	(zone
		(layer "F.Cu")
		(hatch none 0.5)
		(connect_pads
			(clearance 0)
		)
		(min_thickness 0.25)
		(keepout
			(tracks allowed)
			(vias allowed)
			(pads allowed)
			(copperpour allowed)
			(footprints allowed)
		)
		(placement
			(enabled no)
			(sheetname "")
		)
		(fill
			(thermal_gap 0.5)
			(thermal_bridge_width 0.5)
			(island_removal_mode 0)
		)
		(polygon
			(pts
				(xy 132.37591 -178.00447) (xy 132.37591 -176.25187) (xy 134.15391 -176.25187) (xy 134.15391 -178.00447)
			)
		)
	)
	(zone
		(layer "F.Cu")
		(hatch none 0.5)
		(connect_pads
			(clearance 0)
		)
		(min_thickness 0.25)
		(keepout
			(tracks allowed)
			(vias allowed)
			(pads allowed)
			(copperpour allowed)
			(footprints allowed)
		)
		(placement
			(enabled no)
			(sheetname "")
		)
		(fill
			(thermal_gap 0.5)
			(thermal_bridge_width 0.5)
			(island_removal_mode 0)
		)
		(polygon
			(pts
				(xy 152.019 -22.606) (xy 152.019 -21.844) (xy 154.686 -21.844) (xy 154.686 -22.606)
			)
		)
	)
	(zone
		(layer "F.Cu")
		(hatch none 0.5)
		(connect_pads
			(clearance 0)
		)
		(min_thickness 0.25)
		(keepout
			(tracks allowed)
			(vias allowed)
			(pads allowed)
			(copperpour allowed)
			(footprints allowed)
		)
		(placement
			(enabled no)
			(sheetname "")
		)
		(fill
			(thermal_gap 0.5)
			(thermal_bridge_width 0.5)
			(island_removal_mode 0)
		)
		(polygon
			(pts
				(xy 198.07809 -125.205998) (xy 198.07809 -123.854718) (xy 199.35825 -123.854718) (xy 199.35825 -125.205998)
			)
		)
	)
	(zone
		(layer "F.Cu")
		(hatch none 0.5)
		(connect_pads
			(clearance 0)
		)
		(min_thickness 0.25)
		(keepout
			(tracks allowed)
			(vias allowed)
			(pads allowed)
			(copperpour allowed)
			(footprints allowed)
		)
		(placement
			(enabled no)
			(sheetname "")
		)
		(fill
			(thermal_gap 0.5)
			(thermal_bridge_width 0.5)
			(island_removal_mode 0)
		)
		(polygon
			(pts
				(xy 242.815364 -156.560012) (xy 246.625364 -156.560012) (xy 246.625364 -158.084012) (xy 242.815364 -158.084012)
			)
		)
	)
	(zone
		(layer "F.Cu")
		(hatch none 0.5)
		(connect_pads
			(clearance 0)
		)
		(min_thickness 0.25)
		(keepout
			(tracks allowed)
			(vias allowed)
			(pads allowed)
			(copperpour allowed)
			(footprints not_allowed)
		)
		(placement
			(enabled no)
			(sheetname "")
		)
		(fill
			(thermal_gap 0.5)
			(thermal_bridge_width 0.5)
			(island_removal_mode 0)
		)
		(polygon
			(pts
				(xy 326.529954 -394.269976) (xy 313.079892 -394.269976) (xy 313.079892 -417.58997) (xy 326.529954 -417.58997)
			)
		)
	)
	(zone
		(layer "F.Cu")
		(hatch none 0.5)
		(connect_pads
			(clearance 0)
		)
		(min_thickness 0.25)
		(keepout
			(tracks not_allowed)
			(vias allowed)
			(pads allowed)
			(copperpour not_allowed)
			(footprints allowed)
		)
		(placement
			(enabled no)
			(sheetname "")
		)
		(fill
			(thermal_gap 0.5)
			(thermal_bridge_width 0.5)
			(island_removal_mode 0)
		)
		(polygon
			(pts
				(arc
					(start 8.800084 -407.599896)
					(mid 5.999988 -410.399992)
					(end 3.199892 -407.599896)
				)
				(arc
					(start 3.199892 -407.599896)
					(mid 5.999988 -404.7998)
					(end 8.800084 -407.599896)
				)
			)
		)
	)
	(zone
		(layer "F.Cu")
		(hatch none 0.5)
		(connect_pads
			(clearance 0)
		)
		(min_thickness 0.25)
		(keepout
			(tracks allowed)
			(vias allowed)
			(pads allowed)
			(copperpour allowed)
			(footprints not_allowed)
		)
		(placement
			(enabled no)
			(sheetname "")
		)
		(fill
			(thermal_gap 0.5)
			(thermal_bridge_width 0.5)
			(island_removal_mode 0)
		)
		(polygon
			(pts
				(arc
					(start 447.932556 -5.999988)
					(mid 455.93254 1.999996)
					(end 463.932524 -5.999988)
				)
				(arc
					(start 463.932524 -5.999988)
					(mid 455.93254 -13.999972)
					(end 447.932556 -5.999988)
				)
			)
		)
	)
	(zone
		(layer "F.Cu")
		(hatch none 0.5)
		(connect_pads
			(clearance 0)
		)
		(min_thickness 0.25)
		(keepout
			(tracks not_allowed)
			(vias allowed)
			(pads allowed)
			(copperpour not_allowed)
			(footprints allowed)
		)
		(placement
			(enabled no)
			(sheetname "")
		)
		(fill
			(thermal_gap 0.5)
			(thermal_bridge_width 0.5)
			(island_removal_mode 0)
		)
		(polygon
			(pts
				(arc
					(start 451.600062 -84.70011)
					(mid 448.80022 -87.499952)
					(end 446.000124 -84.70011)
				)
				(arc
					(start 446.000124 -84.70011)
					(mid 448.80022 -81.900014)
					(end 451.600062 -84.70011)
				)
			)
		)
	)
	(zone
		(layer "F.Cu")
		(hatch none 0.5)
		(connect_pads
			(clearance 0)
		)
		(min_thickness 0.25)
		(keepout
			(tracks allowed)
			(vias allowed)
			(pads allowed)
			(copperpour allowed)
			(footprints allowed)
		)
		(placement
			(enabled no)
			(sheetname "")
		)
		(fill
			(thermal_gap 0.5)
			(thermal_bridge_width 0.5)
			(island_removal_mode 0)
		)
		(polygon
			(pts
				(xy 133.209284 -29.354526) (xy 133.209284 -28.003246) (xy 134.489444 -28.003246) (xy 134.489444 -29.354526)
			)
		)
	)
	(zone
		(layer "F.Cu")
		(hatch none 0.5)
		(connect_pads
			(clearance 0)
		)
		(min_thickness 0.25)
		(keepout
			(tracks allowed)
			(vias allowed)
			(pads allowed)
			(copperpour allowed)
			(footprints not_allowed)
		)
		(placement
			(enabled no)
			(sheetname "")
		)
		(fill
			(thermal_gap 0.5)
			(thermal_bridge_width 0.5)
			(island_removal_mode 0)
		)
		(polygon
			(pts
				(xy 332.35011 -278.85009) (xy 364.450122 -278.85009)
				(arc
					(start 364.450122 -276.010116)
					(mid 365.287844 -273.56063)
					(end 367.450116 -272.137124)
				)
				(xy 367.450116 -258.739894) (xy 349.899986 -245.483126) (xy 332.35011 -258.739894)
			)
		)
	)
	(zone
		(layer "F.Cu")
		(hatch none 0.5)
		(connect_pads
			(clearance 0)
		)
		(min_thickness 0.25)
		(keepout
			(tracks allowed)
			(vias allowed)
			(pads allowed)
			(copperpour allowed)
			(footprints allowed)
		)
		(placement
			(enabled no)
			(sheetname "")
		)
		(fill
			(thermal_gap 0.5)
			(thermal_bridge_width 0.5)
			(island_removal_mode 0)
		)
		(polygon
			(pts
				(xy 90.456766 -344.635582) (xy 89.105486 -344.635582) (xy 89.105486 -343.355422) (xy 90.456766 -343.355422)
			)
		)
	)
	(zone
		(layer "F.Cu")
		(hatch none 0.5)
		(connect_pads
			(clearance 0)
		)
		(min_thickness 0.25)
		(keepout
			(tracks allowed)
			(vias allowed)
			(pads allowed)
			(copperpour allowed)
			(footprints allowed)
		)
		(placement
			(enabled no)
			(sheetname "")
		)
		(fill
			(thermal_gap 0.5)
			(thermal_bridge_width 0.5)
			(island_removal_mode 0)
		)
		(polygon
			(pts
				(xy 287.629346 -356.952042) (xy 286.278066 -356.952042) (xy 286.278066 -355.671882) (xy 287.629346 -355.671882)
			)
		)
	)
	(zone
		(layer "F.Cu")
		(hatch none 0.5)
		(connect_pads
			(clearance 0)
		)
		(min_thickness 0.25)
		(keepout
			(tracks allowed)
			(vias allowed)
			(pads allowed)
			(copperpour allowed)
			(footprints allowed)
		)
		(placement
			(enabled no)
			(sheetname "")
		)
		(fill
			(thermal_gap 0.5)
			(thermal_bridge_width 0.5)
			(island_removal_mode 0)
		)
		(polygon
			(pts
				(xy 281.411426 -344.659458) (xy 280.060146 -344.659458) (xy 280.060146 -343.379298) (xy 281.411426 -343.379298)
			)
		)
	)
	(zone
		(layer "F.Cu")
		(hatch none 0.5)
		(connect_pads
			(clearance 0)
		)
		(min_thickness 0.25)
		(keepout
			(tracks allowed)
			(vias allowed)
			(pads allowed)
			(copperpour allowed)
			(footprints allowed)
		)
		(placement
			(enabled no)
			(sheetname "")
		)
		(fill
			(thermal_gap 0.5)
			(thermal_bridge_width 0.5)
			(island_removal_mode 0)
		)
		(polygon
			(pts
				(xy 217.925142 -370.6241) (xy 217.925142 -367.27384) (xy 221.310962 -367.27384) (xy 221.310962 -370.6241)
			)
		)
	)
	(zone
		(layer "F.Cu")
		(hatch none 0.5)
		(connect_pads
			(clearance 0)
		)
		(min_thickness 0.25)
		(keepout
			(tracks allowed)
			(vias allowed)
			(pads allowed)
			(copperpour allowed)
			(footprints allowed)
		)
		(placement
			(enabled no)
			(sheetname "")
		)
		(fill
			(thermal_gap 0.5)
			(thermal_bridge_width 0.5)
			(island_removal_mode 0)
		)
		(polygon
			(pts
				(xy 79.336138 -123.39955) (xy 79.336138 -122.04827) (xy 80.616298 -122.04827) (xy 80.616298 -123.39955)
			)
		)
	)
	(zone
		(layer "F.Cu")
		(hatch none 0.5)
		(connect_pads
			(clearance 0)
		)
		(min_thickness 0.25)
		(keepout
			(tracks allowed)
			(vias allowed)
			(pads allowed)
			(copperpour allowed)
			(footprints allowed)
		)
		(placement
			(enabled no)
			(sheetname "")
		)
		(fill
			(thermal_gap 0.5)
			(thermal_bridge_width 0.5)
			(island_removal_mode 0)
		)
		(polygon
			(pts
				(xy 417.409122 -29.354526) (xy 417.409122 -28.003246) (xy 418.689282 -28.003246) (xy 418.689282 -29.354526)
			)
		)
	)
	(zone
		(layer "F.Cu")
		(hatch none 0.5)
		(connect_pads
			(clearance 0)
		)
		(min_thickness 0.25)
		(keepout
			(tracks allowed)
			(vias allowed)
			(pads allowed)
			(copperpour allowed)
			(footprints allowed)
		)
		(placement
			(enabled no)
			(sheetname "")
		)
		(fill
			(thermal_gap 0.5)
			(thermal_bridge_width 0.5)
			(island_removal_mode 0)
		)
		(polygon
			(pts
				(xy 245.08968 -138.611102) (xy 245.08968 -135.693404) (xy 244.88013 -135.483854) (xy 244.267228 -135.483854)
				(xy 244.267228 -138.541252) (xy 244.337078 -138.611102)
			)
		)
	)
	(zone
		(layer "F.Cu")
		(hatch none 0.5)
		(connect_pads
			(clearance 0)
		)
		(min_thickness 0.25)
		(keepout
			(tracks allowed)
			(vias allowed)
			(pads allowed)
			(copperpour allowed)
			(footprints not_allowed)
		)
		(placement
			(enabled no)
			(sheetname "")
		)
		(fill
			(thermal_gap 0.5)
			(thermal_bridge_width 0.5)
			(island_removal_mode 0)
		)
		(polygon
			(pts
				(xy 0.999998 -249.968766) (xy 0.999998 -302.330104)
				(arc
					(start 16.25727 -302.330104)
					(mid 16.725438 -299.343193)
					(end 19.150076 -297.537124)
				)
				(xy 19.150076 -260.439916)
			)
		)
	)
	(zone
		(layer "F.Cu")
		(hatch none 0.5)
		(connect_pads
			(clearance 0)
		)
		(min_thickness 0.25)
		(keepout
			(tracks not_allowed)
			(vias allowed)
			(pads allowed)
			(copperpour not_allowed)
			(footprints allowed)
		)
		(placement
			(enabled no)
			(sheetname "")
		)
		(fill
			(thermal_gap 0.5)
			(thermal_bridge_width 0.5)
			(island_removal_mode 0)
		)
		(polygon
			(pts
				(xy 61.52007 -23.219918) (xy 61.52007 -18.219928) (xy 57.319926 -18.219928) (xy 57.319926 -23.219918)
			)
		)
	)
	(zone
		(layer "F.Cu")
		(hatch none 0.5)
		(connect_pads
			(clearance 0)
		)
		(min_thickness 0.25)
		(keepout
			(tracks allowed)
			(vias allowed)
			(pads allowed)
			(copperpour allowed)
			(footprints allowed)
		)
		(placement
			(enabled no)
			(sheetname "")
		)
		(fill
			(thermal_gap 0.5)
			(thermal_bridge_width 0.5)
			(island_removal_mode 0)
		)
		(polygon
			(pts
				(xy 420.801546 -115.203224) (xy 422.271444 -115.203224) (xy 422.355264 -115.119404) (xy 422.355264 -114.394996)
				(xy 422.119044 -114.158776) (xy 420.833042 -114.158776) (xy 420.61257 -114.379248) (xy 420.61257 -115.014248)
			)
		)
	)
	(zone
		(layer "F.Cu")
		(hatch none 0.5)
		(connect_pads
			(clearance 0)
		)
		(min_thickness 0.25)
		(keepout
			(tracks allowed)
			(vias allowed)
			(pads allowed)
			(copperpour allowed)
			(footprints allowed)
		)
		(placement
			(enabled no)
			(sheetname "")
		)
		(fill
			(thermal_gap 0.5)
			(thermal_bridge_width 0.5)
			(island_removal_mode 0)
		)
		(polygon
			(pts
				(xy 202.584304 -54.008274) (xy 199.666606 -54.008274) (xy 199.457056 -54.217824) (xy 199.457056 -54.830726)
				(xy 202.514454 -54.830726) (xy 202.584304 -54.760876)
			)
		)
	)
	(zone
		(layer "F.Cu")
		(hatch none 0.5)
		(connect_pads
			(clearance 0)
		)
		(min_thickness 0.25)
		(keepout
			(tracks allowed)
			(vias allowed)
			(pads allowed)
			(copperpour allowed)
			(footprints allowed)
		)
		(placement
			(enabled no)
			(sheetname "")
		)
		(fill
			(thermal_gap 0.5)
			(thermal_bridge_width 0.5)
			(island_removal_mode 0)
		)
		(polygon
			(pts
				(xy 90.456766 -350.781874) (xy 89.105486 -350.781874) (xy 89.105486 -349.501714) (xy 90.456766 -349.501714)
			)
		)
	)
	(zone
		(layer "F.Cu")
		(hatch none 0.5)
		(connect_pads
			(clearance 0)
		)
		(min_thickness 0.25)
		(keepout
			(tracks allowed)
			(vias allowed)
			(pads allowed)
			(copperpour allowed)
			(footprints allowed)
		)
		(placement
			(enabled no)
			(sheetname "")
		)
		(fill
			(thermal_gap 0.5)
			(thermal_bridge_width 0.5)
			(island_removal_mode 0)
		)
		(polygon
			(pts
				(xy 119.183912 -344.659458) (xy 117.832632 -344.659458) (xy 117.832632 -343.379298) (xy 119.183912 -343.379298)
			)
		)
	)
	(zone
		(layer "F.Cu")
		(hatch none 0.5)
		(connect_pads
			(clearance 0)
		)
		(min_thickness 0.25)
		(keepout
			(tracks allowed)
			(vias allowed)
			(pads allowed)
			(copperpour allowed)
			(footprints allowed)
		)
		(placement
			(enabled no)
			(sheetname "")
		)
		(fill
			(thermal_gap 0.5)
			(thermal_bridge_width 0.5)
			(island_removal_mode 0)
		)
		(polygon
			(pts
				(xy 35.981132 -350.80575) (xy 34.629852 -350.80575) (xy 34.629852 -349.52559) (xy 35.981132 -349.52559)
			)
		)
	)
	(zone
		(layer "F.Cu")
		(hatch none 0.5)
		(connect_pads
			(clearance 0)
		)
		(min_thickness 0.25)
		(keepout
			(tracks allowed)
			(vias allowed)
			(pads allowed)
			(copperpour allowed)
			(footprints allowed)
		)
		(placement
			(enabled no)
			(sheetname "")
		)
		(fill
			(thermal_gap 0.5)
			(thermal_bridge_width 0.5)
			(island_removal_mode 0)
		)
		(polygon
			(pts
				(xy 38.597332 -111.218218) (xy 38.597332 -109.866938) (xy 39.877492 -109.866938) (xy 39.877492 -111.218218)
			)
		)
	)
	(zone
		(layer "F.Cu")
		(hatch none 0.5)
		(connect_pads
			(clearance 0)
		)
		(min_thickness 0.25)
		(keepout
			(tracks allowed)
			(vias allowed)
			(pads allowed)
			(copperpour allowed)
			(footprints allowed)
		)
		(placement
			(enabled no)
			(sheetname "")
		)
		(fill
			(thermal_gap 0.5)
			(thermal_bridge_width 0.5)
			(island_removal_mode 0)
		)
		(polygon
			(pts
				(xy 382.698752 -233.38663) (xy 384.957066 -233.38663) (xy 385.04495 -233.298746) (xy 385.04495 -231.032558)
				(xy 384.733546 -230.721154) (xy 382.618742 -230.721154) (xy 381.941324 -230.721154) (xy 381.315722 -230.721154)
				(xy 381.197612 -230.839264) (xy 381.197612 -233.217212) (xy 381.36703 -233.38663) (xy 382.227582 -233.38663)
			)
		)
	)
	(zone
		(layer "F.Cu")
		(hatch none 0.5)
		(connect_pads
			(clearance 0)
		)
		(min_thickness 0.25)
		(keepout
			(tracks allowed)
			(vias allowed)
			(pads allowed)
			(copperpour allowed)
			(footprints allowed)
		)
		(placement
			(enabled no)
			(sheetname "")
		)
		(fill
			(thermal_gap 0.5)
			(thermal_bridge_width 0.5)
			(island_removal_mode 0)
		)
		(polygon
			(pts
				(xy 422.737788 -19.7358) (xy 422.737788 -19.2024) (xy 423.804588 -19.2024) (xy 423.804588 -19.7358)
			)
		)
	)
	(zone
		(layer "F.Cu")
		(hatch none 0.5)
		(connect_pads
			(clearance 0)
		)
		(min_thickness 0.25)
		(keepout
			(tracks allowed)
			(vias allowed)
			(pads allowed)
			(copperpour allowed)
			(footprints not_allowed)
		)
		(placement
			(enabled no)
			(sheetname "")
		)
		(fill
			(thermal_gap 0.5)
			(thermal_bridge_width 0.5)
			(island_removal_mode 0)
		)
		(polygon
			(pts
				(xy 319.16497 -40.120062) (xy 327.164954 -40.120062) (xy 327.164954 -13.850112) (xy 319.16497 -13.850112)
			)
		)
	)
	(zone
		(layer "F.Cu")
		(hatch none 0.5)
		(connect_pads
			(clearance 0)
		)
		(min_thickness 0.25)
		(keepout
			(tracks allowed)
			(vias allowed)
			(pads allowed)
			(copperpour allowed)
			(footprints allowed)
		)
		(placement
			(enabled no)
			(sheetname "")
		)
		(fill
			(thermal_gap 0.5)
			(thermal_bridge_width 0.5)
			(island_removal_mode 0)
		)
		(polygon
			(pts
				(xy 34.48431 -54.008274) (xy 31.566612 -54.008274) (xy 31.357062 -54.217824) (xy 31.357062 -54.830726)
				(xy 34.41446 -54.830726) (xy 34.48431 -54.760876)
			)
		)
	)
	(zone
		(layer "F.Cu")
		(hatch none 0.5)
		(connect_pads
			(clearance 0)
		)
		(min_thickness 0.25)
		(keepout
			(tracks allowed)
			(vias allowed)
			(pads allowed)
			(copperpour allowed)
			(footprints allowed)
		)
		(placement
			(enabled no)
			(sheetname "")
		)
		(fill
			(thermal_gap 0.5)
			(thermal_bridge_width 0.5)
			(island_removal_mode 0)
		)
		(polygon
			(pts
				(xy 195.435982 -150.919434) (xy 195.435982 -149.568154) (xy 196.716142 -149.568154) (xy 196.716142 -150.919434)
			)
		)
	)
	(zone
		(layer "F.Cu")
		(hatch none 0.5)
		(connect_pads
			(clearance 0)
		)
		(min_thickness 0.25)
		(keepout
			(tracks allowed)
			(vias allowed)
			(pads allowed)
			(copperpour allowed)
			(footprints allowed)
		)
		(placement
			(enabled no)
			(sheetname "")
		)
		(fill
			(thermal_gap 0.5)
			(thermal_bridge_width 0.5)
			(island_removal_mode 0)
		)
		(polygon
			(pts
				(xy 42.199052 -356.952042) (xy 40.847772 -356.952042) (xy 40.847772 -355.671882) (xy 42.199052 -355.671882)
			)
		)
	)
	(zone
		(layer "F.Cu")
		(hatch none 0.5)
		(connect_pads
			(clearance 0)
		)
		(min_thickness 0.25)
		(keepout
			(tracks allowed)
			(vias allowed)
			(pads allowed)
			(copperpour allowed)
			(footprints not_allowed)
		)
		(placement
			(enabled no)
			(sheetname "")
		)
		(fill
			(thermal_gap 0.5)
			(thermal_bridge_width 0.5)
			(island_removal_mode 0)
		)
		(polygon
			(pts
				(xy 353.62007 -23.219918) (xy 357.81996 -23.219918) (xy 357.81996 -18.219928) (xy 353.62007 -18.219928)
			)
		)
	)
	(zone
		(layer "F.Cu")
		(hatch none 0.5)
		(connect_pads
			(clearance 0)
		)
		(min_thickness 0.25)
		(keepout
			(tracks allowed)
			(vias allowed)
			(pads allowed)
			(copperpour allowed)
			(footprints allowed)
		)
		(placement
			(enabled no)
			(sheetname "")
		)
		(fill
			(thermal_gap 0.5)
			(thermal_bridge_width 0.5)
			(island_removal_mode 0)
		)
		(polygon
			(pts
				(xy 104.060244 -386.217922) (xy 104.519476 -386.217922) (xy 104.616504 -386.120894) (xy 104.616504 -384.981958)
				(xy 104.386888 -384.752342) (xy 104.10444 -384.752342) (xy 104.024938 -384.831844) (xy 104.024938 -386.182616)
			)
		)
	)
	(zone
		(layer "F.Cu")
		(hatch none 0.5)
		(connect_pads
			(clearance 0)
		)
		(min_thickness 0.25)
		(keepout
			(tracks allowed)
			(vias allowed)
			(pads allowed)
			(copperpour allowed)
			(footprints allowed)
		)
		(placement
			(enabled no)
			(sheetname "")
		)
		(fill
			(thermal_gap 0.5)
			(thermal_bridge_width 0.5)
			(island_removal_mode 0)
		)
		(polygon
			(pts
				(xy 9.906 -22.606) (xy 9.906 -21.844) (xy 12.573 -21.844) (xy 12.573 -22.606)
			)
		)
	)
	(zone
		(layer "F.Cu")
		(hatch none 0.5)
		(connect_pads
			(clearance 0)
		)
		(min_thickness 0.25)
		(keepout
			(tracks allowed)
			(vias allowed)
			(pads allowed)
			(copperpour allowed)
			(footprints allowed)
		)
		(placement
			(enabled no)
			(sheetname "")
		)
		(fill
			(thermal_gap 0.5)
			(thermal_bridge_width 0.5)
			(island_removal_mode 0)
		)
		(polygon
			(pts
				(xy 249.309128 -29.354526) (xy 249.309128 -28.003246) (xy 250.589288 -28.003246) (xy 250.589288 -29.354526)
			)
		)
	)
	(zone
		(layer "F.Cu")
		(hatch none 0.5)
		(connect_pads
			(clearance 0)
		)
		(min_thickness 0.25)
		(keepout
			(tracks allowed)
			(vias allowed)
			(pads allowed)
			(copperpour allowed)
			(footprints allowed)
		)
		(placement
			(enabled no)
			(sheetname "")
		)
		(fill
			(thermal_gap 0.5)
			(thermal_bridge_width 0.5)
			(island_removal_mode 0)
		)
		(polygon
			(pts
				(xy 251.951236 -34.76117) (xy 251.951236 -33.40989) (xy 253.231396 -33.40989) (xy 253.231396 -34.76117)
			)
		)
	)
	(zone
		(layer "F.Cu")
		(hatch none 0.5)
		(connect_pads
			(clearance 0)
		)
		(min_thickness 0.25)
		(keepout
			(tracks not_allowed)
			(vias allowed)
			(pads allowed)
			(copperpour not_allowed)
			(footprints allowed)
		)
		(placement
			(enabled no)
			(sheetname "")
		)
		(fill
			(thermal_gap 0.5)
			(thermal_bridge_width 0.5)
			(island_removal_mode 0)
		)
		(polygon
			(pts
				(arc
					(start 255.602232 -297.372024)
					(mid 252.352302 -300.621954)
					(end 249.102372 -297.372024)
				)
				(arc
					(start 249.102372 -297.372024)
					(mid 252.352302 -294.122094)
					(end 255.602232 -297.372024)
				)
			)
		)
	)
	(zone
		(layer "F.Cu")
		(hatch none 0.5)
		(connect_pads
			(clearance 0)
		)
		(min_thickness 0.25)
		(keepout
			(tracks allowed)
			(vias allowed)
			(pads allowed)
			(copperpour allowed)
			(footprints not_allowed)
		)
		(placement
			(enabled no)
			(sheetname "")
		)
		(fill
			(thermal_gap 0.5)
			(thermal_bridge_width 0.5)
			(island_removal_mode 0)
		)
		(polygon
			(pts
				(xy 28.610052 -232.750106) (xy 28.610052 -218.250008) (xy 7.640066 -218.250008) (xy 7.640066 -232.750106)
			)
		)
	)
	(zone
		(layer "F.Cu")
		(hatch none 0.5)
		(connect_pads
			(clearance 0)
		)
		(min_thickness 0.25)
		(keepout
			(tracks not_allowed)
			(vias allowed)
			(pads allowed)
			(copperpour not_allowed)
			(footprints allowed)
		)
		(placement
			(enabled no)
			(sheetname "")
		)
		(fill
			(thermal_gap 0.5)
			(thermal_bridge_width 0.5)
			(island_removal_mode 0)
		)
		(polygon
			(pts
				(arc
					(start 328.099928 -289.820096)
					(mid 331.350112 -286.569912)
					(end 334.600042 -289.820096)
				)
				(arc
					(start 334.600042 -289.820096)
					(mid 331.350112 -293.070026)
					(end 328.099928 -289.820096)
				)
			)
		)
	)
	(zone
		(layer "F.Cu")
		(hatch none 0.5)
		(connect_pads
			(clearance 0)
		)
		(min_thickness 0.25)
		(keepout
			(tracks allowed)
			(vias allowed)
			(pads allowed)
			(copperpour allowed)
			(footprints allowed)
		)
		(placement
			(enabled no)
			(sheetname "")
		)
		(fill
			(thermal_gap 0.5)
			(thermal_bridge_width 0.5)
			(island_removal_mode 0)
		)
		(polygon
			(pts
				(xy 349.758 -89.789) (xy 349.758 -81.153) (xy 351.028 -81.153) (xy 351.028 -89.789)
			)
		)
	)
	(zone
		(layer "F.Cu")
		(hatch none 0.5)
		(connect_pads
			(clearance 0)
		)
		(min_thickness 0.25)
		(keepout
			(tracks allowed)
			(vias allowed)
			(pads allowed)
			(copperpour allowed)
			(footprints not_allowed)
		)
		(placement
			(enabled no)
			(sheetname "")
		)
		(fill
			(thermal_gap 0.5)
			(thermal_bridge_width 0.5)
			(island_removal_mode 0)
		)
		(polygon
			(pts
				(arc
					(start 279.900126 -378.70003)
					(mid 271.900142 -386.700014)
					(end 263.899904 -378.70003)
				)
				(arc
					(start 263.899904 -378.70003)
					(mid 271.900142 -370.699792)
					(end 279.900126 -378.70003)
				)
			)
		)
	)
	(zone
		(layer "F.Cu")
		(hatch none 0.5)
		(connect_pads
			(clearance 0)
		)
		(min_thickness 0.25)
		(keepout
			(tracks allowed)
			(vias allowed)
			(pads allowed)
			(copperpour allowed)
			(footprints allowed)
		)
		(placement
			(enabled no)
			(sheetname "")
		)
		(fill
			(thermal_gap 0.5)
			(thermal_bridge_width 0.5)
			(island_removal_mode 0)
		)
		(polygon
			(pts
				(xy 154.697176 -133.344666) (xy 154.697176 -131.993386) (xy 155.977336 -131.993386) (xy 155.977336 -133.344666)
			)
		)
	)
	(zone
		(layer "F.Cu")
		(hatch none 0.5)
		(connect_pads
			(clearance 0)
		)
		(min_thickness 0.25)
		(keepout
			(tracks not_allowed)
			(vias allowed)
			(pads allowed)
			(copperpour not_allowed)
			(footprints allowed)
		)
		(placement
			(enabled no)
			(sheetname "")
		)
		(fill
			(thermal_gap 0.5)
			(thermal_bridge_width 0.5)
			(island_removal_mode 0)
		)
		(polygon
			(pts
				(xy 304.820066 -18.150078) (xy 304.820066 -13.150088) (xy 300.619922 -13.150088) (xy 300.619922 -18.150078)
			)
		)
	)
	(zone
		(layer "F.Cu")
		(hatch none 0.5)
		(connect_pads
			(clearance 0)
		)
		(min_thickness 0.25)
		(keepout
			(tracks allowed)
			(vias allowed)
			(pads allowed)
			(copperpour allowed)
			(footprints allowed)
		)
		(placement
			(enabled no)
			(sheetname "")
		)
		(fill
			(thermal_gap 0.5)
			(thermal_bridge_width 0.5)
			(island_removal_mode 0)
		)
		(polygon
			(pts
				(xy 144.055592 -356.928166) (xy 142.704312 -356.928166) (xy 142.704312 -355.648006) (xy 144.055592 -355.648006)
			)
		)
	)
	(zone
		(layer "F.Cu")
		(hatch none 0.5)
		(connect_pads
			(clearance 0)
		)
		(min_thickness 0.25)
		(keepout
			(tracks allowed)
			(vias allowed)
			(pads allowed)
			(copperpour allowed)
			(footprints allowed)
		)
		(placement
			(enabled no)
			(sheetname "")
		)
		(fill
			(thermal_gap 0.5)
			(thermal_bridge_width 0.5)
			(island_removal_mode 0)
		)
		(polygon
			(pts
				(xy 130.937 -169.418) (xy 130.937 -168.91) (xy 132.08 -168.91) (xy 132.08 -169.418)
			)
		)
	)
	(zone
		(layer "F.Cu")
		(hatch none 0.5)
		(connect_pads
			(clearance 0)
		)
		(min_thickness 0.25)
		(keepout
			(tracks allowed)
			(vias allowed)
			(pads allowed)
			(copperpour allowed)
			(footprints not_allowed)
		)
		(placement
			(enabled no)
			(sheetname "")
		)
		(fill
			(thermal_gap 0.5)
			(thermal_bridge_width 0.5)
			(island_removal_mode 0)
		)
		(polygon
			(pts
				(xy 93.650054 -263.649968) (xy 93.650054 -342.399874) (xy 141.750034 -342.399874) (xy 141.750034 -263.649968)
				(xy 135.24992 -258.739894) (xy 135.24992 -322.200016) (xy 100.149914 -322.200016) (xy 100.149914 -258.739894)
			)
		)
	)
	(zone
		(layer "F.Cu")
		(hatch none 0.5)
		(connect_pads
			(clearance 0)
		)
		(min_thickness 0.25)
		(keepout
			(tracks allowed)
			(vias allowed)
			(pads allowed)
			(copperpour allowed)
			(footprints allowed)
		)
		(placement
			(enabled no)
			(sheetname "")
		)
		(fill
			(thermal_gap 0.5)
			(thermal_bridge_width 0.5)
			(island_removal_mode 0)
		)
		(polygon
			(pts
				(xy 314.178188 -125.205998) (xy 314.178188 -123.854718) (xy 315.458348 -123.854718) (xy 315.458348 -125.205998)
			)
		)
	)
	(zone
		(layer "F.Cu")
		(hatch none 0.5)
		(connect_pads
			(clearance 0)
		)
		(min_thickness 0.25)
		(keepout
			(tracks allowed)
			(vias allowed)
			(pads allowed)
			(copperpour allowed)
			(footprints allowed)
		)
		(placement
			(enabled no)
			(sheetname "")
		)
		(fill
			(thermal_gap 0.5)
			(thermal_bridge_width 0.5)
			(island_removal_mode 0)
		)
		(polygon
			(pts
				(xy 125.36043 -35.458146) (xy 126.975362 -35.458146) (xy 127.097282 -35.336226) (xy 127.097282 -27.488388)
				(xy 126.853696 -27.244802) (xy 125.32995 -27.244802) (xy 124.97943 -27.595322) (xy 124.97943 -35.077146)
			)
		)
	)
	(zone
		(layer "F.Cu")
		(hatch none 0.5)
		(connect_pads
			(clearance 0)
		)
		(min_thickness 0.25)
		(keepout
			(tracks allowed)
			(vias allowed)
			(pads allowed)
			(copperpour allowed)
			(footprints allowed)
		)
		(placement
			(enabled no)
			(sheetname "")
		)
		(fill
			(thermal_gap 0.5)
			(thermal_bridge_width 0.5)
			(island_removal_mode 0)
		)
		(polygon
			(pts
				(xy 208.58861 -35.519868) (xy 210.416902 -35.519868) (xy 210.653376 -35.283394) (xy 210.653376 -26.930096)
				(xy 210.416902 -26.693622) (xy 208.760822 -26.693622) (xy 208.58861 -26.865834)
			)
		)
	)
	(zone
		(layer "F.Cu")
		(hatch none 0.5)
		(connect_pads
			(clearance 0)
		)
		(min_thickness 0.25)
		(keepout
			(tracks allowed)
			(vias allowed)
			(pads allowed)
			(copperpour allowed)
			(footprints allowed)
		)
		(placement
			(enabled no)
			(sheetname "")
		)
		(fill
			(thermal_gap 0.5)
			(thermal_bridge_width 0.5)
			(island_removal_mode 0)
		)
		(polygon
			(pts
				(xy 38.597332 -104.01808) (xy 38.597332 -102.6668) (xy 39.877492 -102.6668) (xy 39.877492 -104.01808)
			)
		)
	)
	(zone
		(layer "F.Cu")
		(hatch none 0.5)
		(connect_pads
			(clearance 0)
		)
		(min_thickness 0.25)
		(keepout
			(tracks allowed)
			(vias allowed)
			(pads allowed)
			(copperpour allowed)
			(footprints allowed)
		)
		(placement
			(enabled no)
			(sheetname "")
		)
		(fill
			(thermal_gap 0.5)
			(thermal_bridge_width 0.5)
			(island_removal_mode 0)
		)
		(polygon
			(pts
				(xy 382.78435 -54.008274) (xy 379.866652 -54.008274) (xy 379.657102 -54.217824) (xy 379.657102 -54.830726)
				(xy 382.7145 -54.830726) (xy 382.78435 -54.760876)
			)
		)
	)
	(zone
		(layer "F.Cu")
		(hatch none 0.5)
		(connect_pads
			(clearance 0)
		)
		(min_thickness 0.25)
		(keepout
			(tracks allowed)
			(vias allowed)
			(pads allowed)
			(copperpour allowed)
			(footprints not_allowed)
		)
		(placement
			(enabled no)
			(sheetname "")
		)
		(fill
			(thermal_gap 0.5)
			(thermal_bridge_width 0.5)
			(island_removal_mode 0)
		)
		(polygon
			(pts
				(xy 39.812468 -165.34511) (xy 54.84749 -165.34511) (xy 54.84749 -90.054938) (xy 39.812468 -90.054938)
			)
		)
	)
	(zone
		(layer "F.Cu")
		(hatch none 0.5)
		(connect_pads
			(clearance 0)
		)
		(min_thickness 0.25)
		(keepout
			(tracks allowed)
			(vias allowed)
			(pads allowed)
			(copperpour allowed)
			(footprints allowed)
		)
		(placement
			(enabled no)
			(sheetname "")
		)
		(fill
			(thermal_gap 0.5)
			(thermal_bridge_width 0.5)
			(island_removal_mode 0)
		)
		(polygon
			(pts
				(xy 322.6308 -100.9904) (xy 322.6308 -99.441) (xy 324.3834 -99.441) (xy 324.3834 -100.9904)
			)
		)
	)
	(zone
		(layer "F.Cu")
		(hatch none 0.5)
		(connect_pads
			(clearance 0)
		)
		(min_thickness 0.25)
		(keepout
			(tracks not_allowed)
			(vias allowed)
			(pads allowed)
			(copperpour not_allowed)
			(footprints allowed)
		)
		(placement
			(enabled no)
			(sheetname "")
		)
		(fill
			(thermal_gap 0.5)
			(thermal_bridge_width 0.5)
			(island_removal_mode 0)
		)
		(polygon
			(pts
				(arc
					(start 270.999966 -393.100052)
					(mid 268.200124 -395.899894)
					(end 265.400028 -393.100052)
				)
				(arc
					(start 265.400028 -393.100052)
					(mid 268.200124 -390.299956)
					(end 270.999966 -393.100052)
				)
			)
		)
	)
	(zone
		(layer "F.Cu")
		(hatch none 0.5)
		(connect_pads
			(clearance 0)
		)
		(min_thickness 0.25)
		(keepout
			(tracks allowed)
			(vias allowed)
			(pads allowed)
			(copperpour allowed)
			(footprints allowed)
		)
		(placement
			(enabled no)
			(sheetname "")
		)
		(fill
			(thermal_gap 0.5)
			(thermal_bridge_width 0.5)
			(island_removal_mode 0)
		)
		(polygon
			(pts
				(xy 294.132 -22.733) (xy 294.132 -21.844) (xy 296.799 -21.844) (xy 296.799 -22.733)
			)
		)
	)
	(zone
		(layer "F.Cu")
		(hatch none 0.5)
		(connect_pads
			(clearance 0)
		)
		(min_thickness 0.25)
		(keepout
			(tracks allowed)
			(vias allowed)
			(pads allowed)
			(copperpour allowed)
			(footprints allowed)
		)
		(placement
			(enabled no)
			(sheetname "")
		)
		(fill
			(thermal_gap 0.5)
			(thermal_bridge_width 0.5)
			(island_removal_mode 0)
		)
		(polygon
			(pts
				(xy 29.763212 -356.952042) (xy 28.411932 -356.952042) (xy 28.411932 -355.671882) (xy 29.763212 -355.671882)
			)
		)
	)
	(zone
		(layer "F.Cu")
		(hatch none 0.5)
		(connect_pads
			(clearance 0)
		)
		(min_thickness 0.25)
		(keepout
			(tracks allowed)
			(vias allowed)
			(pads allowed)
			(copperpour allowed)
			(footprints not_allowed)
		)
		(placement
			(enabled no)
			(sheetname "")
		)
		(fill
			(thermal_gap 0.5)
			(thermal_bridge_width 0.5)
			(island_removal_mode 0)
		)
		(polygon
			(pts
				(xy 356.140004 -361.790234) (xy 327.039986 -361.790234) (xy 327.039986 -417.58997) (xy 356.140004 -417.58997)
			)
		)
	)
	(zone
		(layer "F.Cu")
		(hatch none 0.5)
		(connect_pads
			(clearance 0)
		)
		(min_thickness 0.25)
		(keepout
			(tracks allowed)
			(vias allowed)
			(pads allowed)
			(copperpour allowed)
			(footprints allowed)
		)
		(placement
			(enabled no)
			(sheetname "")
		)
		(fill
			(thermal_gap 0.5)
			(thermal_bridge_width 0.5)
			(island_removal_mode 0)
		)
		(polygon
			(pts
				(xy 215.091518 -52.800758) (xy 215.091518 -55.718456) (xy 215.301068 -55.928006) (xy 215.91397 -55.928006)
				(xy 215.91397 -52.870608) (xy 215.84412 -52.800758)
			)
		)
	)
	(zone
		(layer "F.Cu")
		(hatch none 0.5)
		(connect_pads
			(clearance 0)
		)
		(min_thickness 0.25)
		(keepout
			(tracks allowed)
			(vias allowed)
			(pads allowed)
			(copperpour allowed)
			(footprints not_allowed)
		)
		(placement
			(enabled no)
			(sheetname "")
		)
		(fill
			(thermal_gap 0.5)
			(thermal_bridge_width 0.5)
			(island_removal_mode 0)
		)
		(polygon
			(pts
				(xy 20.619974 -18.150078) (xy 20.619974 -13.150088) (xy 16.420084 -13.150088) (xy 16.420084 -18.150078)
			)
		)
	)
	(zone
		(layer "F.Cu")
		(hatch none 0.5)
		(connect_pads
			(clearance 0)
		)
		(min_thickness 0.25)
		(keepout
			(tracks allowed)
			(vias allowed)
			(pads allowed)
			(copperpour allowed)
			(footprints allowed)
		)
		(placement
			(enabled no)
			(sheetname "")
		)
		(fill
			(thermal_gap 0.5)
			(thermal_bridge_width 0.5)
			(island_removal_mode 0)
		)
		(polygon
			(pts
				(xy 375.400824 -350.80575) (xy 374.049544 -350.80575) (xy 374.049544 -349.52559) (xy 375.400824 -349.52559)
			)
		)
	)
	(zone
		(layer "F.Cu")
		(hatch none 0.5)
		(connect_pads
			(clearance 0)
		)
		(min_thickness 0.25)
		(keepout
			(tracks allowed)
			(vias allowed)
			(pads allowed)
			(copperpour allowed)
			(footprints allowed)
		)
		(placement
			(enabled no)
			(sheetname "")
		)
		(fill
			(thermal_gap 0.5)
			(thermal_bridge_width 0.5)
			(island_removal_mode 0)
		)
		(polygon
			(pts
				(xy 270.797274 -100.418138) (xy 270.797274 -99.066858) (xy 272.077434 -99.066858) (xy 272.077434 -100.418138)
			)
		)
	)
	(zone
		(layer "F.Cu")
		(hatch none 0.5)
		(connect_pads
			(clearance 0)
		)
		(min_thickness 0.25)
		(keepout
			(tracks allowed)
			(vias allowed)
			(pads allowed)
			(copperpour allowed)
			(footprints allowed)
		)
		(placement
			(enabled no)
			(sheetname "")
		)
		(fill
			(thermal_gap 0.5)
			(thermal_bridge_width 0.5)
			(island_removal_mode 0)
		)
		(polygon
			(pts
				(xy 169.507916 -344.659458) (xy 168.156636 -344.659458) (xy 168.156636 -343.379298) (xy 169.507916 -343.379298)
			)
		)
	)
	(zone
		(layer "F.Cu")
		(hatch none 0.5)
		(connect_pads
			(clearance 0)
		)
		(min_thickness 0.25)
		(keepout
			(tracks allowed)
			(vias allowed)
			(pads allowed)
			(copperpour allowed)
			(footprints allowed)
		)
		(placement
			(enabled no)
			(sheetname "")
		)
		(fill
			(thermal_gap 0.5)
			(thermal_bridge_width 0.5)
			(island_removal_mode 0)
		)
		(polygon
			(pts
				(xy 338.508848 -316.895988) (xy 338.508848 -318.546988) (xy 336.476848 -318.546988) (xy 336.476848 -316.895988)
			)
		)
	)
	(zone
		(layer "F.Cu")
		(hatch none 0.5)
		(connect_pads
			(clearance 0)
		)
		(min_thickness 0.25)
		(keepout
			(tracks allowed)
			(vias allowed)
			(pads allowed)
			(copperpour allowed)
			(footprints allowed)
		)
		(placement
			(enabled no)
			(sheetname "")
		)
		(fill
			(thermal_gap 0.5)
			(thermal_bridge_width 0.5)
			(island_removal_mode 0)
		)
		(polygon
			(pts
				(xy 277.951184 -31.160974) (xy 277.951184 -29.809694) (xy 279.231344 -29.809694) (xy 279.231344 -31.160974)
			)
		)
	)
	(zone
		(layer "F.Cu")
		(hatch none 0.5)
		(connect_pads
			(clearance 0)
		)
		(min_thickness 0.25)
		(keepout
			(tracks not_allowed)
			(vias allowed)
			(pads allowed)
			(copperpour not_allowed)
			(footprints allowed)
		)
		(placement
			(enabled no)
			(sheetname "")
		)
		(fill
			(thermal_gap 0.5)
			(thermal_bridge_width 0.5)
			(island_removal_mode 0)
		)
		(polygon
			(pts
				(xy 446.920112 -18.150078) (xy 446.920112 -13.150088) (xy 442.719968 -13.150088) (xy 442.719968 -18.150078)
			)
		)
	)
	(zone
		(layer "F.Cu")
		(hatch none 0.5)
		(connect_pads
			(clearance 0)
		)
		(min_thickness 0.25)
		(keepout
			(tracks allowed)
			(vias allowed)
			(pads allowed)
			(copperpour allowed)
			(footprints allowed)
		)
		(placement
			(enabled no)
			(sheetname "")
		)
		(fill
			(thermal_gap 0.5)
			(thermal_bridge_width 0.5)
			(island_removal_mode 0)
		)
		(polygon
			(pts
				(xy 152.055068 -131.538218) (xy 152.055068 -130.186938) (xy 153.335228 -130.186938) (xy 153.335228 -131.538218)
			)
		)
	)
	(zone
		(layer "F.Cu")
		(hatch none 0.5)
		(connect_pads
			(clearance 0)
		)
		(min_thickness 0.25)
		(keepout
			(tracks allowed)
			(vias allowed)
			(pads allowed)
			(copperpour allowed)
			(footprints allowed)
		)
		(placement
			(enabled no)
			(sheetname "")
		)
		(fill
			(thermal_gap 0.5)
			(thermal_bridge_width 0.5)
			(island_removal_mode 0)
		)
		(polygon
			(pts
				(xy 23.545292 -350.80575) (xy 22.194012 -350.80575) (xy 22.194012 -349.52559) (xy 23.545292 -349.52559)
			)
		)
	)
	(zone
		(layer "F.Cu")
		(hatch none 0.5)
		(connect_pads
			(clearance 0)
		)
		(min_thickness 0.25)
		(keepout
			(tracks not_allowed)
			(vias allowed)
			(pads allowed)
			(copperpour not_allowed)
			(footprints allowed)
		)
		(placement
			(enabled no)
			(sheetname "")
		)
		(fill
			(thermal_gap 0.5)
			(thermal_bridge_width 0.5)
			(island_removal_mode 0)
		)
		(polygon
			(pts
				(arc
					(start 105.01503 -17.999964)
					(mid 110.01502 -12.999974)
					(end 115.01501 -17.999964)
				)
				(arc
					(start 115.01501 -17.999964)
					(mid 110.01502 -22.999954)
					(end 105.01503 -17.999964)
				)
			)
		)
	)
	(zone
		(layer "F.Cu")
		(hatch none 0.5)
		(connect_pads
			(clearance 0)
		)
		(min_thickness 0.25)
		(keepout
			(tracks allowed)
			(vias allowed)
			(pads allowed)
			(copperpour allowed)
			(footprints allowed)
		)
		(placement
			(enabled no)
			(sheetname "")
		)
		(fill
			(thermal_gap 0.5)
			(thermal_bridge_width 0.5)
			(island_removal_mode 0)
		)
		(polygon
			(pts
				(xy 144.055592 -350.781874) (xy 142.704312 -350.781874) (xy 142.704312 -349.501714) (xy 144.055592 -349.501714)
			)
		)
	)
	(zone
		(layer "F.Cu")
		(hatch none 0.5)
		(connect_pads
			(clearance 0)
		)
		(min_thickness 0.25)
		(keepout
			(tracks allowed)
			(vias allowed)
			(pads allowed)
			(copperpour allowed)
			(footprints allowed)
		)
		(placement
			(enabled no)
			(sheetname "")
		)
		(fill
			(thermal_gap 0.5)
			(thermal_bridge_width 0.5)
			(island_removal_mode 0)
		)
		(polygon
			(pts
				(xy 311.53608 -131.00939) (xy 311.53608 -129.65811) (xy 312.81624 -129.65811) (xy 312.81624 -131.00939)
			)
		)
	)
	(zone
		(layer "F.Cu")
		(hatch none 0.5)
		(connect_pads
			(clearance 0)
		)
		(min_thickness 0.25)
		(keepout
			(tracks not_allowed)
			(vias allowed)
			(pads allowed)
			(copperpour not_allowed)
			(footprints allowed)
		)
		(placement
			(enabled no)
			(sheetname "")
		)
		(fill
			(thermal_gap 0.5)
			(thermal_bridge_width 0.5)
			(island_removal_mode 0)
		)
		(polygon
			(pts
				(xy 267.720064 -23.219918) (xy 267.720064 -18.219928) (xy 263.51992 -18.219928) (xy 263.51992 -23.219918)
			)
		)
	)
	(zone
		(layer "F.Cu")
		(hatch none 0.5)
		(connect_pads
			(clearance 0)
		)
		(min_thickness 0.25)
		(keepout
			(tracks allowed)
			(vias allowed)
			(pads allowed)
			(copperpour allowed)
			(footprints allowed)
		)
		(placement
			(enabled no)
			(sheetname "")
		)
		(fill
			(thermal_gap 0.5)
			(thermal_bridge_width 0.5)
			(island_removal_mode 0)
		)
		(polygon
			(pts
				(xy 393.6746 -140.8938) (xy 393.6746 -140.0302) (xy 395.0208 -140.0302) (xy 395.0208 -140.8938)
			)
		)
	)
	(zone
		(layer "F.Cu")
		(hatch none 0.5)
		(connect_pads
			(clearance 0)
		)
		(min_thickness 0.25)
		(keepout
			(tracks allowed)
			(vias allowed)
			(pads allowed)
			(copperpour allowed)
			(footprints allowed)
		)
		(placement
			(enabled no)
			(sheetname "")
		)
		(fill
			(thermal_gap 0.5)
			(thermal_bridge_width 0.5)
			(island_removal_mode 0)
		)
		(polygon
			(pts
				(xy 128.510792 -350.80575) (xy 127.159512 -350.80575) (xy 127.159512 -349.52559) (xy 128.510792 -349.52559)
			)
		)
	)
	(zone
		(layer "F.Cu")
		(hatch none 0.5)
		(connect_pads
			(clearance 0)
		)
		(min_thickness 0.25)
		(keepout
			(tracks allowed)
			(vias allowed)
			(pads allowed)
			(copperpour allowed)
			(footprints allowed)
		)
		(placement
			(enabled no)
			(sheetname "")
		)
		(fill
			(thermal_gap 0.5)
			(thermal_bridge_width 0.5)
			(island_removal_mode 0)
		)
		(polygon
			(pts
				(xy 343.611708 -287.02) (xy 348.564708 -287.02) (xy 348.818708 -286.766) (xy 348.818708 -286.004)
				(xy 348.564708 -285.75) (xy 347.421708 -285.75) (xy 347.167708 -285.496) (xy 347.167708 -284.861)
				(xy 347.421708 -284.607) (xy 347.929708 -284.607) (xy 348.056708 -284.48) (xy 348.056708 -282.829)
				(xy 347.802708 -282.575) (xy 343.865708 -282.575) (xy 343.611708 -282.829)
			)
		)
	)
	(zone
		(layer "F.Cu")
		(hatch none 0.5)
		(connect_pads
			(clearance 0)
		)
		(min_thickness 0.25)
		(keepout
			(tracks allowed)
			(vias allowed)
			(pads allowed)
			(copperpour allowed)
			(footprints not_allowed)
		)
		(placement
			(enabled no)
			(sheetname "")
		)
		(fill
			(thermal_gap 0.5)
			(thermal_bridge_width 0.5)
			(island_removal_mode 0)
		)
		(polygon
			(pts
				(xy 123.73991 -232.750106) (xy 144.709896 -232.750106) (xy 144.709896 -218.250008) (xy 123.73991 -218.250008)
			)
		)
	)
	(zone
		(layer "F.Cu")
		(hatch none 0.5)
		(connect_pads
			(clearance 0)
		)
		(min_thickness 0.25)
		(keepout
			(tracks allowed)
			(vias allowed)
			(pads allowed)
			(copperpour allowed)
			(footprints allowed)
		)
		(placement
			(enabled no)
			(sheetname "")
		)
		(fill
			(thermal_gap 0.5)
			(thermal_bridge_width 0.5)
			(island_removal_mode 0)
		)
		(polygon
			(pts
				(xy 185.052716 -350.80575) (xy 183.701436 -350.80575) (xy 183.701436 -349.52559) (xy 185.052716 -349.52559)
			)
		)
	)
	(zone
		(layer "F.Cu")
		(hatch none 0.5)
		(connect_pads
			(clearance 0)
		)
		(min_thickness 0.25)
		(keepout
			(tracks allowed)
			(vias allowed)
			(pads allowed)
			(copperpour allowed)
			(footprints allowed)
		)
		(placement
			(enabled no)
			(sheetname "")
		)
		(fill
			(thermal_gap 0.5)
			(thermal_bridge_width 0.5)
			(island_removal_mode 0)
		)
		(polygon
			(pts
				(xy 275.193506 -344.659458) (xy 273.842226 -344.659458) (xy 273.842226 -343.379298) (xy 275.193506 -343.379298)
			)
		)
	)
	(zone
		(layer "F.Cu")
		(hatch none 0.5)
		(connect_pads
			(clearance 0)
		)
		(min_thickness 0.25)
		(keepout
			(tracks allowed)
			(vias allowed)
			(pads allowed)
			(copperpour allowed)
			(footprints allowed)
		)
		(placement
			(enabled no)
			(sheetname "")
		)
		(fill
			(thermal_gap 0.5)
			(thermal_bridge_width 0.5)
			(island_removal_mode 0)
		)
		(polygon
			(pts
				(xy 111.411512 -287.02) (xy 116.364512 -287.02) (xy 116.618512 -286.766) (xy 116.618512 -286.004)
				(xy 116.364512 -285.75) (xy 115.221512 -285.75) (xy 114.967512 -285.496) (xy 114.967512 -284.861)
				(xy 115.221512 -284.607) (xy 115.729512 -284.607) (xy 115.856512 -284.48) (xy 115.856512 -282.829)
				(xy 115.602512 -282.575) (xy 111.665512 -282.575) (xy 111.411512 -282.829)
			)
		)
	)
	(zone
		(layer "F.Cu")
		(hatch none 0.5)
		(connect_pads
			(clearance 0)
		)
		(min_thickness 0.25)
		(keepout
			(tracks allowed)
			(vias allowed)
			(pads allowed)
			(copperpour allowed)
			(footprints allowed)
		)
		(placement
			(enabled no)
			(sheetname "")
		)
		(fill
			(thermal_gap 0.5)
			(thermal_bridge_width 0.5)
			(island_removal_mode 0)
		)
		(polygon
			(pts
				(xy 335.451196 -287.02) (xy 340.404196 -287.02) (xy 340.658196 -286.766) (xy 340.658196 -286.004)
				(xy 340.404196 -285.75) (xy 339.261196 -285.75) (xy 339.007196 -285.496) (xy 339.007196 -284.861)
				(xy 339.261196 -284.607) (xy 339.769196 -284.607) (xy 339.896196 -284.48) (xy 339.896196 -282.829)
				(xy 339.642196 -282.575) (xy 335.705196 -282.575) (xy 335.451196 -282.829)
			)
		)
	)
	(zone
		(layer "F.Cu")
		(hatch none 0.5)
		(connect_pads
			(clearance 0)
		)
		(min_thickness 0.25)
		(keepout
			(tracks allowed)
			(vias allowed)
			(pads allowed)
			(copperpour allowed)
			(footprints allowed)
		)
		(placement
			(enabled no)
			(sheetname "")
		)
		(fill
			(thermal_gap 0.5)
			(thermal_bridge_width 0.5)
			(island_removal_mode 0)
		)
		(polygon
			(pts
				(xy 152.055068 -135.13816) (xy 152.055068 -133.78688) (xy 153.335228 -133.78688) (xy 153.335228 -135.13816)
			)
		)
	)
	(zone
		(layer "F.Cu")
		(hatch none 0.5)
		(connect_pads
			(clearance 0)
		)
		(min_thickness 0.25)
		(keepout
			(tracks allowed)
			(vias allowed)
			(pads allowed)
			(copperpour allowed)
			(footprints allowed)
		)
		(placement
			(enabled no)
			(sheetname "")
		)
		(fill
			(thermal_gap 0.5)
			(thermal_bridge_width 0.5)
			(island_removal_mode 0)
		)
		(polygon
			(pts
				(xy 329.126088 -350.80575) (xy 327.774808 -350.80575) (xy 327.774808 -349.52559) (xy 329.126088 -349.52559)
			)
		)
	)
	(zone
		(layer "F.Cu")
		(hatch none 0.5)
		(connect_pads
			(clearance 0)
		)
		(min_thickness 0.25)
		(keepout
			(tracks allowed)
			(vias allowed)
			(pads allowed)
			(copperpour allowed)
			(footprints allowed)
		)
		(placement
			(enabled no)
			(sheetname "")
		)
		(fill
			(thermal_gap 0.5)
			(thermal_bridge_width 0.5)
			(island_removal_mode 0)
		)
		(polygon
			(pts
				(xy 190.502286 -141.87297) (xy 188.691774 -141.87297) (xy 188.645292 -141.919452) (xy 188.645292 -156.662374)
				(xy 188.79058 -156.807662) (xy 190.542672 -156.807662) (xy 190.61811 -156.732224) (xy 190.61811 -141.988794)
			)
		)
	)
	(zone
		(layer "F.Cu")
		(hatch none 0.5)
		(connect_pads
			(clearance 0)
		)
		(min_thickness 0.25)
		(keepout
			(tracks allowed)
			(vias allowed)
			(pads allowed)
			(copperpour allowed)
			(footprints allowed)
		)
		(placement
			(enabled no)
			(sheetname "")
		)
		(fill
			(thermal_gap 0.5)
			(thermal_bridge_width 0.5)
			(island_removal_mode 0)
		)
		(polygon
			(pts
				(xy 391.409174 -29.354526) (xy 391.409174 -28.003246) (xy 392.689334 -28.003246) (xy 392.689334 -29.354526)
			)
		)
	)
	(zone
		(layer "F.Cu")
		(hatch none 0.5)
		(connect_pads
			(clearance 0)
		)
		(min_thickness 0.25)
		(keepout
			(tracks allowed)
			(vias allowed)
			(pads allowed)
			(copperpour allowed)
			(footprints allowed)
		)
		(placement
			(enabled no)
			(sheetname "")
		)
		(fill
			(thermal_gap 0.5)
			(thermal_bridge_width 0.5)
			(island_removal_mode 0)
		)
		(polygon
			(pts
				(xy 198.07809 -145.525998) (xy 198.07809 -144.174718) (xy 199.35825 -144.174718) (xy 199.35825 -145.525998)
			)
		)
	)
	(zone
		(layer "F.Cu")
		(hatch none 0.5)
		(connect_pads
			(clearance 0)
		)
		(min_thickness 0.25)
		(keepout
			(tracks allowed)
			(vias allowed)
			(pads allowed)
			(copperpour allowed)
			(footprints allowed)
		)
		(placement
			(enabled no)
			(sheetname "")
		)
		(fill
			(thermal_gap 0.5)
			(thermal_bridge_width 0.5)
			(island_removal_mode 0)
		)
		(polygon
			(pts
				(xy 422.259252 -47.3202) (xy 422.259252 -45.5676) (xy 424.037252 -45.5676) (xy 424.037252 -47.3202)
			)
		)
	)
	(zone
		(layer "F.Cu")
		(hatch none 0.5)
		(connect_pads
			(clearance 0)
		)
		(min_thickness 0.25)
		(keepout
			(tracks allowed)
			(vias allowed)
			(pads allowed)
			(copperpour allowed)
			(footprints allowed)
		)
		(placement
			(enabled no)
			(sheetname "")
		)
		(fill
			(thermal_gap 0.5)
			(thermal_bridge_width 0.5)
			(island_removal_mode 0)
		)
		(polygon
			(pts
				(xy 233.27233 -90.16619) (xy 235.179616 -90.16619) (xy 235.274104 -90.071702) (xy 235.274104 -88.73109)
				(xy 235.014516 -88.471502) (xy 232.994708 -88.471502) (xy 232.888536 -88.577674) (xy 232.888536 -89.782396)
			)
		)
	)
	(zone
		(layer "F.Cu")
		(hatch none 0.5)
		(connect_pads
			(clearance 0)
		)
		(min_thickness 0.25)
		(keepout
			(tracks allowed)
			(vias allowed)
			(pads allowed)
			(copperpour allowed)
			(footprints allowed)
		)
		(placement
			(enabled no)
			(sheetname "")
		)
		(fill
			(thermal_gap 0.5)
			(thermal_bridge_width 0.5)
			(island_removal_mode 0)
		)
		(polygon
			(pts
				(xy 169.507916 -350.80575) (xy 168.156636 -350.80575) (xy 168.156636 -349.52559) (xy 169.507916 -349.52559)
			)
		)
	)
	(zone
		(layer "F.Cu")
		(hatch none 0.5)
		(connect_pads
			(clearance 0)
		)
		(min_thickness 0.25)
		(keepout
			(tracks allowed)
			(vias allowed)
			(pads allowed)
			(copperpour allowed)
			(footprints allowed)
		)
		(placement
			(enabled no)
			(sheetname "")
		)
		(fill
			(thermal_gap 0.5)
			(thermal_bridge_width 0.5)
			(island_removal_mode 0)
		)
		(polygon
			(pts
				(xy 122.292872 -356.952042) (xy 120.941592 -356.952042) (xy 120.941592 -355.671882) (xy 122.292872 -355.671882)
			)
		)
	)
	(zone
		(layer "F.Cu")
		(hatch none 0.5)
		(connect_pads
			(clearance 0)
		)
		(min_thickness 0.25)
		(keepout
			(tracks allowed)
			(vias allowed)
			(pads allowed)
			(copperpour allowed)
			(footprints allowed)
		)
		(placement
			(enabled no)
			(sheetname "")
		)
		(fill
			(thermal_gap 0.5)
			(thermal_bridge_width 0.5)
			(island_removal_mode 0)
		)
		(polygon
			(pts
				(xy 400.272504 -356.928166) (xy 398.921224 -356.928166) (xy 398.921224 -355.648006) (xy 400.272504 -355.648006)
			)
		)
	)
	(zone
		(layer "F.Cu")
		(hatch none 0.5)
		(connect_pads
			(clearance 0)
		)
		(min_thickness 0.25)
		(keepout
			(tracks allowed)
			(vias allowed)
			(pads allowed)
			(copperpour allowed)
			(footprints allowed)
		)
		(placement
			(enabled no)
			(sheetname "")
		)
		(fill
			(thermal_gap 0.5)
			(thermal_bridge_width 0.5)
			(island_removal_mode 0)
		)
		(polygon
			(pts
				(xy 152.664668 -102.224586) (xy 152.664668 -100.873306) (xy 153.944828 -100.873306) (xy 153.944828 -102.224586)
			)
		)
	)
	(zone
		(layer "F.Cu")
		(hatch none 0.5)
		(connect_pads
			(clearance 0)
		)
		(min_thickness 0.25)
		(keepout
			(tracks allowed)
			(vias allowed)
			(pads allowed)
			(copperpour allowed)
			(footprints not_allowed)
		)
		(placement
			(enabled no)
			(sheetname "")
		)
		(fill
			(thermal_gap 0.5)
			(thermal_bridge_width 0.5)
			(island_removal_mode 0)
		)
		(polygon
			(pts
				(xy 57.319926 -23.219918) (xy 61.52007 -23.219918) (xy 61.52007 -18.219928) (xy 57.319926 -18.219928)
			)
		)
	)
	(zone
		(layer "F.Cu")
		(hatch none 0.5)
		(connect_pads
			(clearance 0)
		)
		(min_thickness 0.25)
		(keepout
			(tracks allowed)
			(vias allowed)
			(pads allowed)
			(copperpour allowed)
			(footprints not_allowed)
		)
		(placement
			(enabled no)
			(sheetname "")
		)
		(fill
			(thermal_gap 0.5)
			(thermal_bridge_width 0.5)
			(island_removal_mode 0)
		)
		(polygon
			(pts
				(xy 257.849878 -329.3999) (xy 325.849996 -329.3999) (xy 325.849996 -262.400034) (xy 257.849878 -262.400034)
			)
		)
	)
	(zone
		(layer "F.Cu")
		(hatch none 0.5)
		(connect_pads
			(clearance 0)
		)
		(min_thickness 0.25)
		(keepout
			(tracks allowed)
			(vias allowed)
			(pads allowed)
			(copperpour allowed)
			(footprints allowed)
		)
		(placement
			(enabled no)
			(sheetname "")
		)
		(fill
			(thermal_gap 0.5)
			(thermal_bridge_width 0.5)
			(island_removal_mode 0)
		)
		(polygon
			(pts
				(xy 378.509784 -356.952042) (xy 377.158504 -356.952042) (xy 377.158504 -355.671882) (xy 378.509784 -355.671882)
			)
		)
	)
	(zone
		(layer "F.Cu")
		(hatch none 0.5)
		(connect_pads
			(clearance 0)
		)
		(min_thickness 0.25)
		(keepout
			(tracks allowed)
			(vias allowed)
			(pads allowed)
			(copperpour allowed)
			(footprints allowed)
		)
		(placement
			(enabled no)
			(sheetname "")
		)
		(fill
			(thermal_gap 0.5)
			(thermal_bridge_width 0.5)
			(island_removal_mode 0)
		)
		(polygon
			(pts
				(xy 386.897372 -133.344666) (xy 386.897372 -131.993386) (xy 388.177532 -131.993386) (xy 388.177532 -133.344666)
			)
		)
	)
	(zone
		(layer "F.Cu")
		(hatch none 0.5)
		(connect_pads
			(clearance 0)
		)
		(min_thickness 0.25)
		(keepout
			(tracks allowed)
			(vias allowed)
			(pads allowed)
			(copperpour allowed)
			(footprints allowed)
		)
		(placement
			(enabled no)
			(sheetname "")
		)
		(fill
			(thermal_gap 0.5)
			(thermal_bridge_width 0.5)
			(island_removal_mode 0)
		)
		(polygon
			(pts
				(xy 430.278286 -132.816092) (xy 430.278286 -131.464812) (xy 431.558446 -131.464812) (xy 431.558446 -132.816092)
			)
		)
	)
	(zone
		(layer "F.Cu")
		(hatch none 0.5)
		(connect_pads
			(clearance 0)
		)
		(min_thickness 0.25)
		(keepout
			(tracks allowed)
			(vias allowed)
			(pads allowed)
			(copperpour allowed)
			(footprints not_allowed)
		)
		(placement
			(enabled no)
			(sheetname "")
		)
		(fill
			(thermal_gap 0.5)
			(thermal_bridge_width 0.5)
			(island_removal_mode 0)
		)
		(polygon
			(pts
				(xy 319.71996 -23.219918) (xy 319.71996 -18.219928) (xy 315.52007 -18.219928) (xy 315.52007 -23.219918)
			)
		)
	)
	(zone
		(layer "F.Cu")
		(hatch none 0.5)
		(connect_pads
			(clearance 0)
		)
		(min_thickness 0.25)
		(keepout
			(tracks not_allowed)
			(vias allowed)
			(pads allowed)
			(copperpour not_allowed)
			(footprints allowed)
		)
		(placement
			(enabled no)
			(sheetname "")
		)
		(fill
			(thermal_gap 0.5)
			(thermal_bridge_width 0.5)
			(island_removal_mode 0)
		)
		(polygon
			(pts
				(arc
					(start 435.699916 -320.900044)
					(mid 437.950102 -318.649858)
					(end 440.200034 -320.900044)
				)
				(arc
					(start 440.200034 -320.900044)
					(mid 437.950102 -323.149976)
					(end 435.699916 -320.900044)
				)
			)
		)
	)
	(zone
		(layer "F.Cu")
		(hatch none 0.5)
		(connect_pads
			(clearance 0)
		)
		(min_thickness 0.25)
		(keepout
			(tracks not_allowed)
			(vias allowed)
			(pads allowed)
			(copperpour not_allowed)
			(footprints allowed)
		)
		(placement
			(enabled no)
			(sheetname "")
		)
		(fill
			(thermal_gap 0.5)
			(thermal_bridge_width 0.5)
			(island_removal_mode 0)
		)
		(polygon
			(pts
				(arc
					(start 18.599912 -194.360038)
					(mid 15.80007 -197.15988)
					(end 12.999974 -194.360038)
				)
				(arc
					(start 12.999974 -194.360038)
					(mid 15.80007 -191.559942)
					(end 18.599912 -194.360038)
				)
			)
		)
	)
	(zone
		(layer "F.Cu")
		(hatch none 0.5)
		(connect_pads
			(clearance 0)
		)
		(min_thickness 0.25)
		(keepout
			(tracks allowed)
			(vias allowed)
			(pads allowed)
			(copperpour allowed)
			(footprints not_allowed)
		)
		(placement
			(enabled no)
			(sheetname "")
		)
		(fill
			(thermal_gap 0.5)
			(thermal_bridge_width 0.5)
			(island_removal_mode 0)
		)
		(polygon
			(pts
				(xy 177.619914 -23.219918) (xy 177.619914 -18.219928) (xy 173.420024 -18.219928) (xy 173.420024 -23.219918)
			)
		)
	)
	(zone
		(layer "F.Cu")
		(hatch none 0.5)
		(connect_pads
			(clearance 0)
		)
		(min_thickness 0.25)
		(keepout
			(tracks allowed)
			(vias allowed)
			(pads allowed)
			(copperpour allowed)
			(footprints allowed)
		)
		(placement
			(enabled no)
			(sheetname "")
		)
		(fill
			(thermal_gap 0.5)
			(thermal_bridge_width 0.5)
			(island_removal_mode 0)
		)
		(polygon
			(pts
				(xy 390.945624 -356.952042) (xy 389.594344 -356.952042) (xy 389.594344 -355.671882) (xy 390.945624 -355.671882)
			)
		)
	)
	(zone
		(layer "F.Cu")
		(hatch none 0.5)
		(connect_pads
			(clearance 0)
		)
		(min_thickness 0.25)
		(keepout
			(tracks allowed)
			(vias allowed)
			(pads allowed)
			(copperpour allowed)
			(footprints allowed)
		)
		(placement
			(enabled no)
			(sheetname "")
		)
		(fill
			(thermal_gap 0.5)
			(thermal_bridge_width 0.5)
			(island_removal_mode 0)
		)
		(polygon
			(pts
				(xy 404.652734 -376.309636) (xy 407.33599 -376.309636) (xy 407.396188 -376.249438) (xy 407.396188 -375.109232)
				(xy 407.2763 -374.989344) (xy 405.535892 -374.989344) (xy 405.433022 -374.886474) (xy 405.433022 -374.569228)
				(xy 405.433022 -374.123712) (xy 405.227282 -373.917972) (xy 404.721568 -373.917972) (xy 404.618444 -374.021096)
				(xy 404.618444 -374.59539) (xy 404.618444 -375.040652) (xy 404.618444 -376.275346)
			)
		)
	)
	(zone
		(layer "F.Cu")
		(hatch none 0.5)
		(connect_pads
			(clearance 0)
		)
		(min_thickness 0.25)
		(keepout
			(tracks allowed)
			(vias allowed)
			(pads allowed)
			(copperpour allowed)
			(footprints allowed)
		)
		(placement
			(enabled no)
			(sheetname "")
		)
		(fill
			(thermal_gap 0.5)
			(thermal_bridge_width 0.5)
			(island_removal_mode 0)
		)
		(polygon
			(pts
				(xy 99.466654 -385.820666) (xy 99.903788 -385.820666) (xy 99.9744 -385.750054) (xy 99.9744 -384.483102)
				(xy 99.868482 -384.377184) (xy 99.369626 -384.377184) (xy 99.263708 -384.483102) (xy 99.263708 -385.61772)
			)
		)
	)
	(zone
		(layer "F.Cu")
		(hatch none 0.5)
		(connect_pads
			(clearance 0)
		)
		(min_thickness 0.25)
		(keepout
			(tracks allowed)
			(vias allowed)
			(pads allowed)
			(copperpour allowed)
			(footprints allowed)
		)
		(placement
			(enabled no)
			(sheetname "")
		)
		(fill
			(thermal_gap 0.5)
			(thermal_bridge_width 0.5)
			(island_removal_mode 0)
		)
		(polygon
			(pts
				(xy 386.897372 -107.618022) (xy 386.897372 -106.266742) (xy 388.177532 -106.266742) (xy 388.177532 -107.618022)
			)
		)
	)
	(zone
		(layer "F.Cu")
		(hatch none 0.5)
		(connect_pads
			(clearance 0)
		)
		(min_thickness 0.25)
		(keepout
			(tracks allowed)
			(vias allowed)
			(pads allowed)
			(copperpour allowed)
			(footprints allowed)
		)
		(placement
			(enabled no)
			(sheetname "")
		)
		(fill
			(thermal_gap 0.5)
			(thermal_bridge_width 0.5)
			(island_removal_mode 0)
		)
		(polygon
			(pts
				(xy 62.476126 -350.80575) (xy 61.124846 -350.80575) (xy 61.124846 -349.52559) (xy 62.476126 -349.52559)
			)
		)
	)
	(zone
		(layer "F.Cu")
		(hatch none 0.5)
		(connect_pads
			(clearance 0)
		)
		(min_thickness 0.25)
		(keepout
			(tracks allowed)
			(vias allowed)
			(pads allowed)
			(copperpour allowed)
			(footprints not_allowed)
		)
		(placement
			(enabled no)
			(sheetname "")
		)
		(fill
			(thermal_gap 0.5)
			(thermal_bridge_width 0.5)
			(island_removal_mode 0)
		)
		(polygon
			(pts
				(xy 454.754996 -214.265764) (xy 459.65491 -214.265764) (xy 459.65491 -204.27569) (xy 454.754996 -204.27569)
			)
		)
	)
	(zone
		(layer "F.Cu")
		(hatch none 0.5)
		(connect_pads
			(clearance 0)
		)
		(min_thickness 0.25)
		(keepout
			(tracks allowed)
			(vias allowed)
			(pads allowed)
			(copperpour allowed)
			(footprints allowed)
		)
		(placement
			(enabled no)
			(sheetname "")
		)
		(fill
			(thermal_gap 0.5)
			(thermal_bridge_width 0.5)
			(island_removal_mode 0)
		)
		(polygon
			(pts
				(xy 386.897372 -125.734826) (xy 386.897372 -124.383546) (xy 388.177532 -124.383546) (xy 388.177532 -125.734826)
			)
		)
	)
	(zone
		(layer "F.Cu")
		(hatch none 0.5)
		(connect_pads
			(clearance 0)
		)
		(min_thickness 0.25)
		(keepout
			(tracks allowed)
			(vias allowed)
			(pads allowed)
			(copperpour allowed)
			(footprints allowed)
		)
		(placement
			(enabled no)
			(sheetname "")
		)
		(fill
			(thermal_gap 0.5)
			(thermal_bridge_width 0.5)
			(island_removal_mode 0)
		)
		(polygon
			(pts
				(xy 365.409226 -29.354526) (xy 365.409226 -28.003246) (xy 366.689386 -28.003246) (xy 366.689386 -29.354526)
			)
		)
	)
	(zone
		(layer "F.Cu")
		(hatch none 0.5)
		(connect_pads
			(clearance 0)
		)
		(min_thickness 0.25)
		(keepout
			(tracks not_allowed)
			(vias allowed)
			(pads allowed)
			(copperpour not_allowed)
			(footprints allowed)
		)
		(placement
			(enabled no)
			(sheetname "")
		)
		(fill
			(thermal_gap 0.5)
			(thermal_bridge_width 0.5)
			(island_removal_mode 0)
		)
		(polygon
			(pts
				(arc
					(start 463.199988 -398.100042)
					(mid 461.600042 -399.699988)
					(end 460.000096 -398.100042)
				)
				(arc
					(start 460.000096 -398.100042)
					(mid 461.600042 -396.500096)
					(end 463.199988 -398.100042)
				)
			)
		)
	)
	(zone
		(layer "F.Cu")
		(hatch none 0.5)
		(connect_pads
			(clearance 0)
		)
		(min_thickness 0.25)
		(keepout
			(tracks allowed)
			(vias allowed)
			(pads allowed)
			(copperpour allowed)
			(footprints allowed)
		)
		(placement
			(enabled no)
			(sheetname "")
		)
		(fill
			(thermal_gap 0.5)
			(thermal_bridge_width 0.5)
			(island_removal_mode 0)
		)
		(polygon
			(pts
				(xy 98.391218 -200.60666) (xy 98.391218 -201.44359) (xy 98.391218 -201.934064) (xy 98.391472 -201.934318)
				(xy 99.839272 -201.934318) (xy 99.959922 -201.813668) (xy 99.959922 -201.504296) (xy 99.929696 -201.47407)
				(xy 99.929696 -200.62952) (xy 99.846638 -200.546462) (xy 98.451416 -200.546462)
			)
		)
	)
	(zone
		(layer "F.Cu")
		(hatch none 0.5)
		(connect_pads
			(clearance 0)
		)
		(min_thickness 0.25)
		(keepout
			(tracks allowed)
			(vias allowed)
			(pads allowed)
			(copperpour allowed)
			(footprints not_allowed)
		)
		(placement
			(enabled no)
			(sheetname "")
		)
		(fill
			(thermal_gap 0.5)
			(thermal_bridge_width 0.5)
			(island_removal_mode 0)
		)
		(polygon
			(pts
				(xy 409.82011 -23.219918) (xy 409.82011 -18.219928) (xy 405.619966 -18.219928) (xy 405.619966 -23.219918)
			)
		)
	)
	(zone
		(layer "F.Cu")
		(hatch none 0.5)
		(connect_pads
			(clearance 0)
		)
		(min_thickness 0.25)
		(keepout
			(tracks not_allowed)
			(vias allowed)
			(pads allowed)
			(copperpour not_allowed)
			(footprints allowed)
		)
		(placement
			(enabled no)
			(sheetname "")
		)
		(fill
			(thermal_gap 0.5)
			(thermal_bridge_width 0.5)
			(island_removal_mode 0)
		)
		(polygon
			(pts
				(arc
					(start 228.799898 -194.360038)
					(mid 233.799888 -189.360048)
					(end 238.799878 -194.360038)
				)
				(arc
					(start 238.799878 -194.360038)
					(mid 233.799888 -199.360028)
					(end 228.799898 -194.360038)
				)
			)
		)
	)
	(zone
		(layer "F.Cu")
		(hatch none 0.5)
		(connect_pads
			(clearance 0)
		)
		(min_thickness 0.25)
		(keepout
			(tracks allowed)
			(vias allowed)
			(pads allowed)
			(copperpour allowed)
			(footprints allowed)
		)
		(placement
			(enabled no)
			(sheetname "")
		)
		(fill
			(thermal_gap 0.5)
			(thermal_bridge_width 0.5)
			(island_removal_mode 0)
		)
		(polygon
			(pts
				(xy 370.259356 -47.3202) (xy 370.259356 -45.5676) (xy 372.037356 -45.5676) (xy 372.037356 -47.3202)
			)
		)
	)
	(zone
		(layer "F.Cu")
		(hatch none 0.5)
		(connect_pads
			(clearance 0)
		)
		(min_thickness 0.25)
		(keepout
			(tracks allowed)
			(vias allowed)
			(pads allowed)
			(copperpour allowed)
			(footprints allowed)
		)
		(placement
			(enabled no)
			(sheetname "")
		)
		(fill
			(thermal_gap 0.5)
			(thermal_bridge_width 0.5)
			(island_removal_mode 0)
		)
		(polygon
			(pts
				(xy 311.53608 -150.919434) (xy 311.53608 -149.568154) (xy 312.81624 -149.568154) (xy 312.81624 -150.919434)
			)
		)
	)
	(zone
		(layer "F.Cu")
		(hatch none 0.5)
		(connect_pads
			(clearance 0)
		)
		(min_thickness 0.25)
		(keepout
			(tracks allowed)
			(vias allowed)
			(pads allowed)
			(copperpour allowed)
			(footprints allowed)
		)
		(placement
			(enabled no)
			(sheetname "")
		)
		(fill
			(thermal_gap 0.5)
			(thermal_bridge_width 0.5)
			(island_removal_mode 0)
		)
		(polygon
			(pts
				(xy 191.270636 -344.659458) (xy 189.919356 -344.659458) (xy 189.919356 -343.379298) (xy 191.270636 -343.379298)
			)
		)
	)
	(zone
		(layer "F.Cu")
		(hatch none 0.5)
		(connect_pads
			(clearance 0)
		)
		(min_thickness 0.25)
		(keepout
			(tracks allowed)
			(vias allowed)
			(pads allowed)
			(copperpour allowed)
			(footprints allowed)
		)
		(placement
			(enabled no)
			(sheetname "")
		)
		(fill
			(thermal_gap 0.5)
			(thermal_bridge_width 0.5)
			(island_removal_mode 0)
		)
		(polygon
			(pts
				(xy 137.649966 -201.039476) (xy 139.90828 -201.039476) (xy 139.996164 -200.951592) (xy 139.996164 -198.685404)
				(xy 139.68476 -198.374) (xy 137.569956 -198.374) (xy 136.892538 -198.374) (xy 136.266936 -198.374)
				(xy 136.148826 -198.49211) (xy 136.148826 -200.870058) (xy 136.318244 -201.039476) (xy 137.178796 -201.039476)
			)
		)
	)
	(zone
		(layer "F.Cu")
		(hatch none 0.5)
		(connect_pads
			(clearance 0)
		)
		(min_thickness 0.25)
		(keepout
			(tracks allowed)
			(vias allowed)
			(pads allowed)
			(copperpour allowed)
			(footprints allowed)
		)
		(placement
			(enabled no)
			(sheetname "")
		)
		(fill
			(thermal_gap 0.5)
			(thermal_bridge_width 0.5)
			(island_removal_mode 0)
		)
		(polygon
			(pts
				(xy 166.164768 -126.219204) (xy 168.25214 -126.219204) (xy 168.57218 -125.899164) (xy 168.57218 -118.495064)
				(xy 166.227252 -118.495064) (xy 166.14902 -118.573296) (xy 166.14902 -126.203456)
			)
		)
	)
	(zone
		(layer "F.Cu")
		(hatch none 0.5)
		(connect_pads
			(clearance 0)
		)
		(min_thickness 0.25)
		(keepout
			(tracks allowed)
			(vias allowed)
			(pads allowed)
			(copperpour allowed)
			(footprints not_allowed)
		)
		(placement
			(enabled no)
			(sheetname "")
		)
		(fill
			(thermal_gap 0.5)
			(thermal_bridge_width 0.5)
			(island_removal_mode 0)
		)
		(polygon
			(pts
				(xy 241.165126 -40.120062) (xy 249.164856 -40.120062) (xy 249.16511 -13.850112) (xy 241.165126 -13.850112)
			)
		)
	)
	(zone
		(layer "F.Cu")
		(hatch none 0.5)
		(connect_pads
			(clearance 0)
		)
		(min_thickness 0.25)
		(keepout
			(tracks allowed)
			(vias allowed)
			(pads allowed)
			(copperpour allowed)
			(footprints not_allowed)
		)
		(placement
			(enabled no)
			(sheetname "")
		)
		(fill
			(thermal_gap 0.5)
			(thermal_bridge_width 0.5)
			(island_removal_mode 0)
		)
		(polygon
			(pts
				(xy 216.250012 -322.200016) (xy 251.350018 -322.200016) (xy 251.350018 -311.45988)
				(arc
					(start 220.980254 -311.45988)
					(mid 219.434111 -314.346526)
					(end 216.250012 -315.110876)
				)
			)
		)
	)
	(zone
		(layer "F.Cu")
		(hatch none 0.5)
		(connect_pads
			(clearance 0)
		)
		(min_thickness 0.25)
		(keepout
			(tracks not_allowed)
			(vias allowed)
			(pads allowed)
			(copperpour not_allowed)
			(footprints allowed)
		)
		(placement
			(enabled no)
			(sheetname "")
		)
		(fill
			(thermal_gap 0.5)
			(thermal_bridge_width 0.5)
			(island_removal_mode 0)
		)
		(polygon
			(pts
				(arc
					(start 87.399876 -270.89989)
					(mid 89.650062 -268.649704)
					(end 91.899994 -270.89989)
				)
				(arc
					(start 91.899994 -270.89989)
					(mid 89.650062 -273.149822)
					(end 87.399876 -270.89989)
				)
			)
		)
	)
	(zone
		(layer "F.Cu")
		(hatch none 0.5)
		(connect_pads
			(clearance 0)
		)
		(min_thickness 0.25)
		(keepout
			(tracks allowed)
			(vias allowed)
			(pads allowed)
			(copperpour allowed)
			(footprints allowed)
		)
		(placement
			(enabled no)
			(sheetname "")
		)
		(fill
			(thermal_gap 0.5)
			(thermal_bridge_width 0.5)
			(island_removal_mode 0)
		)
		(polygon
			(pts
				(xy 221.903798 -218.448128) (xy 223.924114 -218.448128) (xy 224.122234 -218.250008) (xy 224.122234 -216.428066)
				(xy 223.584008 -215.88984) (xy 222.205804 -215.88984) (xy 221.393766 -216.701878) (xy 221.393766 -217.938096)
			)
		)
	)
	(zone
		(layer "F.Cu")
		(hatch none 0.5)
		(connect_pads
			(clearance 0)
		)
		(min_thickness 0.25)
		(keepout
			(tracks allowed)
			(vias allowed)
			(pads allowed)
			(copperpour allowed)
			(footprints allowed)
		)
		(placement
			(enabled no)
			(sheetname "")
		)
		(fill
			(thermal_gap 0.5)
			(thermal_bridge_width 0.5)
			(island_removal_mode 0)
		)
		(polygon
			(pts
				(xy 324.861428 -27.55011) (xy 327.261474 -27.55011) (xy 327.352914 -27.45867) (xy 327.352914 -26.33853)
				(xy 327.291954 -26.27757) (xy 324.846188 -26.27757) (xy 324.724268 -26.39949) (xy 324.724268 -27.41295)
			)
		)
	)
	(zone
		(layer "F.Cu")
		(hatch none 0.5)
		(connect_pads
			(clearance 0)
		)
		(min_thickness 0.25)
		(keepout
			(tracks allowed)
			(vias allowed)
			(pads allowed)
			(copperpour allowed)
			(footprints not_allowed)
		)
		(placement
			(enabled no)
			(sheetname "")
		)
		(fill
			(thermal_gap 0.5)
			(thermal_bridge_width 0.5)
			(island_removal_mode 0)
		)
		(polygon
			(pts
				(xy 269.899892 -329.3999) (xy 257.849878 -329.3999) (xy 257.849878 -342.399874) (xy 253.757938 -342.399874)
				(xy 253.757938 -365.400082) (xy 207.75803 -365.400082) (xy 207.75803 -339.39988) (xy 209.749898 -339.39988)
				(xy 209.749898 -329.3999) (xy 197.699884 -329.3999)
				(arc
					(start 197.699884 -370.954046)
					(mid 203.009008 -375.447797)
					(end 202.792838 -382.400048)
				)
				(arc
					(start 264.806938 -382.400048)
					(mid 264.590778 -375.447801)
					(end 269.899892 -370.954046)
				)
			)
		)
	)
	(zone
		(layer "F.Cu")
		(hatch none 0.5)
		(connect_pads
			(clearance 0)
		)
		(min_thickness 0.25)
		(keepout
			(tracks allowed)
			(vias allowed)
			(pads allowed)
			(copperpour allowed)
			(footprints not_allowed)
		)
		(placement
			(enabled no)
			(sheetname "")
		)
		(fill
			(thermal_gap 0.5)
			(thermal_bridge_width 0.5)
			(island_removal_mode 0)
		)
		(polygon
			(pts
				(xy 435.265068 -40.120062) (xy 443.264798 -40.120062) (xy 443.265052 -13.850112) (xy 435.265068 -13.850112)
			)
		)
	)
	(zone
		(layer "F.Cu")
		(hatch none 0.5)
		(connect_pads
			(clearance 0)
		)
		(min_thickness 0.25)
		(keepout
			(tracks allowed)
			(vias allowed)
			(pads allowed)
			(copperpour allowed)
			(footprints allowed)
		)
		(placement
			(enabled no)
			(sheetname "")
		)
		(fill
			(thermal_gap 0.5)
			(thermal_bridge_width 0.5)
			(island_removal_mode 0)
		)
		(polygon
			(pts
				(xy 419.700456 -350.80575) (xy 418.349176 -350.80575) (xy 418.349176 -349.52559) (xy 419.700456 -349.52559)
			)
		)
	)
	(zone
		(layer "F.Cu")
		(hatch none 0.5)
		(connect_pads
			(clearance 0)
		)
		(min_thickness 0.25)
		(keepout
			(tracks allowed)
			(vias allowed)
			(pads allowed)
			(copperpour allowed)
			(footprints allowed)
		)
		(placement
			(enabled no)
			(sheetname "")
		)
		(fill
			(thermal_gap 0.5)
			(thermal_bridge_width 0.5)
			(island_removal_mode 0)
		)
		(polygon
			(pts
				(xy 397.163544 -350.80575) (xy 395.812264 -350.80575) (xy 395.812264 -349.52559) (xy 397.163544 -349.52559)
			)
		)
	)
	(zone
		(layer "F.Cu")
		(hatch none 0.5)
		(connect_pads
			(clearance 0)
		)
		(min_thickness 0.25)
		(keepout
			(tracks not_allowed)
			(vias allowed)
			(pads allowed)
			(copperpour not_allowed)
			(footprints allowed)
		)
		(placement
			(enabled no)
			(sheetname "")
		)
		(fill
			(thermal_gap 0.5)
			(thermal_bridge_width 0.5)
			(island_removal_mode 0)
		)
		(polygon
			(pts
				(arc
					(start 463.600038 -407.599896)
					(mid 461.600042 -409.599892)
					(end 459.600046 -407.599896)
				)
				(arc
					(start 459.600046 -407.599896)
					(mid 461.600042 -405.5999)
					(end 463.600038 -407.599896)
				)
			)
		)
	)
	(zone
		(layer "F.Cu")
		(hatch none 0.5)
		(connect_pads
			(clearance 0)
		)
		(min_thickness 0.25)
		(keepout
			(tracks allowed)
			(vias allowed)
			(pads allowed)
			(copperpour allowed)
			(footprints allowed)
		)
		(placement
			(enabled no)
			(sheetname "")
		)
		(fill
			(thermal_gap 0.5)
			(thermal_bridge_width 0.5)
			(island_removal_mode 0)
		)
		(polygon
			(pts
				(xy 61.849 -22.606) (xy 61.849 -21.717) (xy 64.643 -21.717) (xy 64.643 -22.606)
			)
		)
	)
	(zone
		(layer "F.Cu")
		(hatch none 0.5)
		(connect_pads
			(clearance 0)
		)
		(min_thickness 0.25)
		(keepout
			(tracks allowed)
			(vias allowed)
			(pads allowed)
			(copperpour allowed)
			(footprints allowed)
		)
		(placement
			(enabled no)
			(sheetname "")
		)
		(fill
			(thermal_gap 0.5)
			(thermal_bridge_width 0.5)
			(island_removal_mode 0)
		)
		(polygon
			(pts
				(xy 217.6526 -101.1682) (xy 219.202 -101.1682) (xy 219.6592 -101.6254) (xy 220.7006 -101.6254) (xy 220.98 -101.346)
				(xy 220.98 -100.4824) (xy 220.6498 -100.1522) (xy 217.7288 -100.1522) (xy 217.5256 -100.3554) (xy 217.5256 -101.0412)
			)
		)
	)
	(zone
		(layer "F.Cu")
		(hatch none 0.5)
		(connect_pads
			(clearance 0)
		)
		(min_thickness 0.25)
		(keepout
			(tracks allowed)
			(vias allowed)
			(pads allowed)
			(copperpour allowed)
			(footprints allowed)
		)
		(placement
			(enabled no)
			(sheetname "")
		)
		(fill
			(thermal_gap 0.5)
			(thermal_bridge_width 0.5)
			(island_removal_mode 0)
		)
		(polygon
			(pts
				(xy 35.981132 -356.952042) (xy 34.629852 -356.952042) (xy 34.629852 -355.671882) (xy 35.981132 -355.671882)
			)
		)
	)
	(zone
		(layer "F.Cu")
		(hatch none 0.5)
		(connect_pads
			(clearance 0)
		)
		(min_thickness 0.25)
		(keepout
			(tracks allowed)
			(vias allowed)
			(pads allowed)
			(copperpour allowed)
			(footprints allowed)
		)
		(placement
			(enabled no)
			(sheetname "")
		)
		(fill
			(thermal_gap 0.5)
			(thermal_bridge_width 0.5)
			(island_removal_mode 0)
		)
		(polygon
			(pts
				(xy 305.191414 -52.800758) (xy 305.191414 -55.718456) (xy 305.400964 -55.928006) (xy 306.013866 -55.928006)
				(xy 306.013866 -52.870608) (xy 305.944016 -52.800758)
			)
		)
	)
	(zone
		(layer "F.Cu")
		(hatch none 0.5)
		(connect_pads
			(clearance 0)
		)
		(min_thickness 0.25)
		(keepout
			(tracks allowed)
			(vias allowed)
			(pads allowed)
			(copperpour allowed)
			(footprints allowed)
		)
		(placement
			(enabled no)
			(sheetname "")
		)
		(fill
			(thermal_gap 0.5)
			(thermal_bridge_width 0.5)
			(island_removal_mode 0)
		)
		(polygon
			(pts
				(xy 254.159258 -47.3202) (xy 254.159258 -45.5676) (xy 255.937258 -45.5676) (xy 255.937258 -47.3202)
			)
		)
	)
	(zone
		(layer "F.Cu")
		(hatch none 0.5)
		(connect_pads
			(clearance 0)
		)
		(min_thickness 0.25)
		(keepout
			(tracks allowed)
			(vias allowed)
			(pads allowed)
			(copperpour allowed)
			(footprints allowed)
		)
		(placement
			(enabled no)
			(sheetname "")
		)
		(fill
			(thermal_gap 0.5)
			(thermal_bridge_width 0.5)
			(island_removal_mode 0)
		)
		(polygon
			(pts
				(xy 122.292872 -350.80575) (xy 120.941592 -350.80575) (xy 120.941592 -349.52559) (xy 122.292872 -349.52559)
			)
		)
	)
	(zone
		(layer "F.Cu")
		(hatch none 0.5)
		(connect_pads
			(clearance 0)
		)
		(min_thickness 0.25)
		(keepout
			(tracks allowed)
			(vias allowed)
			(pads allowed)
			(copperpour allowed)
			(footprints allowed)
		)
		(placement
			(enabled no)
			(sheetname "")
		)
		(fill
			(thermal_gap 0.5)
			(thermal_bridge_width 0.5)
			(island_removal_mode 0)
		)
		(polygon
			(pts
				(xy 154.697176 -100.418138) (xy 154.697176 -99.066858) (xy 155.977336 -99.066858) (xy 155.977336 -100.418138)
			)
		)
	)
	(zone
		(layer "F.Cu")
		(hatch none 0.5)
		(connect_pads
			(clearance 0)
		)
		(min_thickness 0.25)
		(keepout
			(tracks allowed)
			(vias allowed)
			(pads allowed)
			(copperpour allowed)
			(footprints allowed)
		)
		(placement
			(enabled no)
			(sheetname "")
		)
		(fill
			(thermal_gap 0.5)
			(thermal_bridge_width 0.5)
			(island_removal_mode 0)
		)
		(polygon
			(pts
				(xy 368.051334 -31.160974) (xy 368.051334 -29.809694) (xy 369.331494 -29.809694) (xy 369.331494 -31.160974)
			)
		)
	)
	(zone
		(layer "F.Cu")
		(hatch none 0.5)
		(connect_pads
			(clearance 0)
		)
		(min_thickness 0.25)
		(keepout
			(tracks allowed)
			(vias allowed)
			(pads allowed)
			(copperpour allowed)
			(footprints allowed)
		)
		(placement
			(enabled no)
			(sheetname "")
		)
		(fill
			(thermal_gap 0.5)
			(thermal_bridge_width 0.5)
			(island_removal_mode 0)
		)
		(polygon
			(pts
				(xy 185.33491 -117.970808) (xy 183.247538 -117.970808) (xy 182.927498 -118.290848) (xy 182.927498 -125.694948)
				(xy 185.272426 -125.694948) (xy 185.350658 -125.616716) (xy 185.350658 -117.986556)
			)
		)
	)
	(zone
		(layer "F.Cu")
		(hatch none 0.5)
		(connect_pads
			(clearance 0)
		)
		(min_thickness 0.25)
		(keepout
			(tracks allowed)
			(vias allowed)
			(pads allowed)
			(copperpour allowed)
			(footprints allowed)
		)
		(placement
			(enabled no)
			(sheetname "")
		)
		(fill
			(thermal_gap 0.5)
			(thermal_bridge_width 0.5)
			(island_removal_mode 0)
		)
		(polygon
			(pts
				(xy 393.345924 -139.281662) (xy 394.72362 -139.281662) (xy 395.081506 -138.923776) (xy 395.081506 -132.947664)
				(xy 395.081506 -129.875026) (xy 394.961872 -129.755392) (xy 393.131548 -129.755392) (xy 392.648186 -130.238754)
				(xy 392.648186 -133.30555) (xy 392.648186 -138.583924)
			)
		)
	)
	(zone
		(layer "F.Cu")
		(hatch none 0.5)
		(connect_pads
			(clearance 0)
		)
		(min_thickness 0.25)
		(keepout
			(tracks allowed)
			(vias allowed)
			(pads allowed)
			(copperpour allowed)
			(footprints allowed)
		)
		(placement
			(enabled no)
			(sheetname "")
		)
		(fill
			(thermal_gap 0.5)
			(thermal_bridge_width 0.5)
			(island_removal_mode 0)
		)
		(polygon
			(pts
				(xy 17.109186 -32.954468) (xy 17.109186 -31.603188) (xy 18.389346 -31.603188) (xy 18.389346 -32.954468)
			)
		)
	)
	(zone
		(layer "F.Cu")
		(hatch none 0.5)
		(connect_pads
			(clearance 0)
		)
		(min_thickness 0.25)
		(keepout
			(tracks allowed)
			(vias allowed)
			(pads allowed)
			(copperpour allowed)
			(footprints not_allowed)
		)
		(placement
			(enabled no)
			(sheetname "")
		)
		(fill
			(thermal_gap 0.5)
			(thermal_bridge_width 0.5)
			(island_removal_mode 0)
		)
		(polygon
			(pts
				(arc
					(start 341.900002 -72.69988)
					(mid 349.899986 -64.699896)
					(end 357.89997 -72.69988)
				)
				(arc
					(start 357.89997 -72.69988)
					(mid 349.899986 -80.699864)
					(end 341.900002 -72.69988)
				)
			)
		)
	)
	(zone
		(layer "F.Cu")
		(hatch none 0.5)
		(connect_pads
			(clearance 0)
		)
		(min_thickness 0.25)
		(keepout
			(tracks allowed)
			(vias allowed)
			(pads allowed)
			(copperpour allowed)
			(footprints allowed)
		)
		(placement
			(enabled no)
			(sheetname "")
		)
		(fill
			(thermal_gap 0.5)
			(thermal_bridge_width 0.5)
			(island_removal_mode 0)
		)
		(polygon
			(pts
				(xy 256.9972 -86.9188) (xy 256.9972 -81.6102) (xy 262.2804 -81.6102) (xy 262.2804 -86.9188)
			)
		)
	)
	(zone
		(layers "F.Cu" "B.Cu")
		(hatch none 0.5)
		(connect_pads
			(clearance 0)
		)
		(min_thickness 0.25)
		(keepout
			(tracks not_allowed)
			(vias allowed)
			(pads allowed)
			(copperpour not_allowed)
			(footprints allowed)
		)
		(placement
			(enabled no)
			(sheetname "")
		)
		(fill yes
			(thermal_gap 0.5)
			(thermal_bridge_width 0.5)
			(island_removal_mode 0)
		)
		(polygon
			(pts
				(arc
					(start 6.800088 -400.699986)
					(mid 9.400032 -398.100042)
					(end 6.800088 -395.500098)
				)
				(arc
					(start 5.199888 -395.500098)
					(mid 2.599944 -398.100042)
					(end 5.199888 -400.699986)
				)
			)
		)
	)
	(zone
		(layers "F.Cu" "B.Cu")
		(hatch none 0.5)
		(connect_pads
			(clearance 0)
		)
		(min_thickness 0.25)
		(keepout
			(tracks not_allowed)
			(vias allowed)
			(pads allowed)
			(copperpour not_allowed)
			(footprints allowed)
		)
		(placement
			(enabled no)
			(sheetname "")
		)
		(fill yes
			(thermal_gap 0.5)
			(thermal_bridge_width 0.5)
			(island_removal_mode 0)
		)
		(polygon
			(pts
				(arc
					(start 459.000098 -13.599922)
					(mid 461.600042 -10.999978)
					(end 464.199986 -13.599922)
				)
				(arc
					(start 464.199986 -15.200122)
					(mid 461.600042 -17.800066)
					(end 459.000098 -15.200122)
				)
			)
		)
	)
	(zone
		(layers "F.Cu" "B.Cu")
		(hatch none 0.5)
		(connect_pads
			(clearance 0)
		)
		(min_thickness 0.25)
		(keepout
			(tracks not_allowed)
			(vias allowed)
			(pads allowed)
			(copperpour not_allowed)
			(footprints allowed)
		)
		(placement
			(enabled no)
			(sheetname "")
		)
		(fill yes
			(thermal_gap 0.5)
			(thermal_bridge_width 0.5)
			(island_removal_mode 0)
		)
		(polygon
			(pts
				(xy 142.80007 -417.58997) (xy 152.80005 -417.58997) (xy 152.80005 -396.54988) (xy 142.80007 -396.54988)
			)
		)
	)
	(zone
		(layers "F.Cu" "B.Cu" "In1.Cu" "In2.Cu" "In3.Cu" "In4.Cu" "In5.Cu" "In6.Cu"
			"In7.Cu" "In8.Cu" "In9.Cu" "In10.Cu" "In11.Cu" "In12.Cu" "In13.Cu" "In14.Cu"
			"In15.Cu" "In16.Cu"
		)
		(hatch none 0.5)
		(connect_pads
			(clearance 0)
		)
		(min_thickness 0.25)
		(keepout
			(tracks not_allowed)
			(vias allowed)
			(pads allowed)
			(copperpour not_allowed)
			(footprints allowed)
		)
		(placement
			(enabled no)
			(sheetname "")
		)
		(fill
			(thermal_gap 0.5)
			(thermal_bridge_width 0.5)
			(island_removal_mode 0)
		)
		(polygon
			(pts
				(arc
					(start 298.800012 -119.567198)
					(mid 299.257212 -120.024398)
					(end 299.714412 -119.567198)
				)
				(arc
					(start 299.714412 -118.703598)
					(mid 299.257212 -118.246398)
					(end 298.800012 -118.703598)
				)
			)
		)
	)
	(zone
		(layers "F.Cu" "B.Cu" "In1.Cu" "In2.Cu" "In3.Cu" "In4.Cu" "In5.Cu" "In6.Cu"
			"In7.Cu" "In8.Cu" "In9.Cu" "In10.Cu" "In11.Cu" "In12.Cu" "In13.Cu" "In14.Cu"
			"In15.Cu" "In16.Cu"
		)
		(hatch none 0.5)
		(connect_pads
			(clearance 0)
		)
		(min_thickness 0.25)
		(keepout
			(tracks not_allowed)
			(vias allowed)
			(pads allowed)
			(copperpour not_allowed)
			(footprints allowed)
		)
		(placement
			(enabled no)
			(sheetname "")
		)
		(fill
			(thermal_gap 0.5)
			(thermal_bridge_width 0.5)
			(island_removal_mode 0)
		)
		(polygon
			(pts
				(arc
					(start 269.51051 -133.104382)
					(mid 269.96771 -133.561582)
					(end 270.42491 -133.104382)
				)
				(arc
					(start 270.42491 -132.240782)
					(mid 269.96771 -131.783582)
					(end 269.51051 -132.240782)
				)
			)
		)
	)
	(zone
		(layers "F.Cu" "B.Cu" "In1.Cu" "In2.Cu" "In3.Cu" "In4.Cu" "In5.Cu" "In6.Cu"
			"In7.Cu" "In8.Cu" "In9.Cu" "In10.Cu" "In11.Cu" "In12.Cu" "In13.Cu" "In14.Cu"
			"In15.Cu" "In16.Cu"
		)
		(hatch none 0.5)
		(connect_pads
			(clearance 0)
		)
		(min_thickness 0.25)
		(keepout
			(tracks not_allowed)
			(vias allowed)
			(pads allowed)
			(copperpour not_allowed)
			(footprints allowed)
		)
		(placement
			(enabled no)
			(sheetname "")
		)
		(fill
			(thermal_gap 0.5)
			(thermal_bridge_width 0.5)
			(island_removal_mode 0)
		)
		(polygon
			(pts
				(arc
					(start 429.375062 -150.67915)
					(mid 429.832262 -151.13635)
					(end 430.289462 -150.67915)
				)
				(arc
					(start 430.289462 -149.81555)
					(mid 429.832262 -149.35835)
					(end 429.375062 -149.81555)
				)
			)
		)
	)
	(zone
		(layers "F.Cu" "B.Cu" "In1.Cu" "In2.Cu" "In3.Cu" "In4.Cu" "In5.Cu" "In6.Cu"
			"In7.Cu" "In8.Cu" "In9.Cu" "In10.Cu" "In11.Cu" "In12.Cu" "In13.Cu" "In14.Cu"
			"In15.Cu" "In16.Cu"
		)
		(hatch none 0.5)
		(connect_pads
			(clearance 0)
		)
		(min_thickness 0.25)
		(keepout
			(tracks not_allowed)
			(vias allowed)
			(pads allowed)
			(copperpour not_allowed)
			(footprints allowed)
		)
		(placement
			(enabled no)
			(sheetname "")
		)
		(fill
			(thermal_gap 0.5)
			(thermal_bridge_width 0.5)
			(island_removal_mode 0)
		)
		(polygon
			(pts
				(arc
					(start 127.406908 -357.37673)
					(mid 127.025908 -357.75773)
					(end 127.406908 -358.13873)
				)
				(arc
					(start 128.270508 -358.13873)
					(mid 128.651508 -357.75773)
					(end 128.270508 -357.37673)
				)
			)
		)
	)
	(zone
		(layers "F.Cu" "B.Cu" "In1.Cu" "In2.Cu" "In3.Cu" "In4.Cu" "In5.Cu" "In6.Cu"
			"In7.Cu" "In8.Cu" "In9.Cu" "In10.Cu" "In11.Cu" "In12.Cu" "In13.Cu" "In14.Cu"
			"In15.Cu" "In16.Cu"
		)
		(hatch none 0.5)
		(connect_pads
			(clearance 0)
		)
		(min_thickness 0.25)
		(keepout
			(tracks not_allowed)
			(vias allowed)
			(pads allowed)
			(copperpour not_allowed)
			(footprints allowed)
		)
		(placement
			(enabled no)
			(sheetname "")
		)
		(fill
			(thermal_gap 0.5)
			(thermal_bridge_width 0.5)
			(island_removal_mode 0)
		)
		(polygon
			(pts
				(arc
					(start 287.08096 -395.92885)
					(mid 287.095839 -395.892929)
					(end 287.13176 -395.87805)
				)
				(arc
					(start 287.84804 -395.87805)
					(mid 287.883961 -395.892929)
					(end 287.89884 -395.92885)
				)
				(arc
					(start 287.89884 -398.351502)
					(mid 287.883961 -398.387423)
					(end 287.84804 -398.402302)
				)
				(arc
					(start 287.13176 -398.402302)
					(mid 287.095839 -398.387423)
					(end 287.08096 -398.351502)
				)
			)
		)
	)
	(zone
		(layers "F.Cu" "B.Cu" "In1.Cu" "In2.Cu" "In3.Cu" "In4.Cu" "In5.Cu" "In6.Cu"
			"In7.Cu" "In8.Cu" "In9.Cu" "In10.Cu" "In11.Cu" "In12.Cu" "In13.Cu" "In14.Cu"
			"In15.Cu" "In16.Cu"
		)
		(hatch none 0.5)
		(connect_pads
			(clearance 0)
		)
		(min_thickness 0.25)
		(keepout
			(tracks not_allowed)
			(vias allowed)
			(pads allowed)
			(copperpour not_allowed)
			(footprints allowed)
		)
		(placement
			(enabled no)
			(sheetname "")
		)
		(fill
			(thermal_gap 0.5)
			(thermal_bridge_width 0.5)
			(island_removal_mode 0)
		)
		(polygon
			(pts
				(arc
					(start 346.481146 -400.92884)
					(mid 346.496025 -400.892919)
					(end 346.531946 -400.87804)
				)
				(arc
					(start 347.248226 -400.87804)
					(mid 347.284147 -400.892919)
					(end 347.299026 -400.92884)
				)
				(arc
					(start 347.299026 -403.351492)
					(mid 347.284147 -403.387413)
					(end 347.248226 -403.402292)
				)
				(arc
					(start 346.531946 -403.402292)
					(mid 346.496025 -403.387413)
					(end 346.481146 -403.351492)
				)
			)
		)
	)
	(zone
		(layers "F.Cu" "B.Cu" "In1.Cu" "In2.Cu" "In3.Cu" "In4.Cu" "In5.Cu" "In6.Cu"
			"In7.Cu" "In8.Cu" "In9.Cu" "In10.Cu" "In11.Cu" "In12.Cu" "In13.Cu" "In14.Cu"
			"In15.Cu" "In16.Cu"
		)
		(hatch none 0.5)
		(connect_pads
			(clearance 0)
		)
		(min_thickness 0.25)
		(keepout
			(tracks not_allowed)
			(vias allowed)
			(pads allowed)
			(copperpour not_allowed)
			(footprints allowed)
		)
		(placement
			(enabled no)
			(sheetname "")
		)
		(fill
			(thermal_gap 0.5)
			(thermal_bridge_width 0.5)
			(island_removal_mode 0)
		)
		(polygon
			(pts
				(arc
					(start 44.204128 -342.058498)
					(mid 43.823128 -342.439498)
					(end 44.204128 -342.820498)
				)
				(arc
					(start 45.067728 -342.820498)
					(mid 45.448728 -342.439498)
					(end 45.067728 -342.058498)
				)
			)
		)
	)
	(zone
		(layers "F.Cu" "B.Cu" "In1.Cu" "In2.Cu" "In3.Cu" "In4.Cu" "In5.Cu" "In6.Cu"
			"In7.Cu" "In8.Cu" "In9.Cu" "In10.Cu" "In11.Cu" "In12.Cu" "In13.Cu" "In14.Cu"
			"In15.Cu" "In16.Cu"
		)
		(hatch none 0.5)
		(connect_pads
			(clearance 0)
		)
		(min_thickness 0.25)
		(keepout
			(tracks not_allowed)
			(vias allowed)
			(pads allowed)
			(copperpour not_allowed)
			(footprints allowed)
		)
		(placement
			(enabled no)
			(sheetname "")
		)
		(fill
			(thermal_gap 0.5)
			(thermal_bridge_width 0.5)
			(island_removal_mode 0)
		)
		(polygon
			(pts
				(arc
					(start 389.84174 -348.20479)
					(mid 389.46074 -348.58579)
					(end 389.84174 -348.96679)
				)
				(arc
					(start 390.70534 -348.96679)
					(mid 391.08634 -348.58579)
					(end 390.70534 -348.20479)
				)
			)
		)
	)
	(zone
		(layers "F.Cu" "B.Cu" "In1.Cu" "In2.Cu" "In3.Cu" "In4.Cu" "In5.Cu" "In6.Cu"
			"In7.Cu" "In8.Cu" "In9.Cu" "In10.Cu" "In11.Cu" "In12.Cu" "In13.Cu" "In14.Cu"
			"In15.Cu" "In16.Cu"
		)
		(hatch none 0.5)
		(connect_pads
			(clearance 0)
		)
		(min_thickness 0.25)
		(keepout
			(tracks not_allowed)
			(vias allowed)
			(pads allowed)
			(copperpour not_allowed)
			(footprints allowed)
		)
		(placement
			(enabled no)
			(sheetname "")
		)
		(fill
			(thermal_gap 0.5)
			(thermal_bridge_width 0.5)
			(island_removal_mode 0)
		)
		(polygon
			(pts
				(arc
					(start 440.384692 -345.084146)
					(mid 440.003692 -345.465146)
					(end 440.384692 -345.846146)
				)
				(arc
					(start 441.248292 -345.846146)
					(mid 441.629292 -345.465146)
					(end 441.248292 -345.084146)
				)
			)
		)
	)
	(zone
		(layers "F.Cu" "B.Cu" "In1.Cu" "In2.Cu" "In3.Cu" "In4.Cu" "In5.Cu" "In6.Cu"
			"In7.Cu" "In8.Cu" "In9.Cu" "In10.Cu" "In11.Cu" "In12.Cu" "In13.Cu" "In14.Cu"
			"In15.Cu" "In16.Cu"
		)
		(hatch none 0.5)
		(connect_pads
			(clearance 0)
		)
		(min_thickness 0.25)
		(keepout
			(tracks not_allowed)
			(vias allowed)
			(pads allowed)
			(copperpour not_allowed)
			(footprints allowed)
		)
		(placement
			(enabled no)
			(sheetname "")
		)
		(fill
			(thermal_gap 0.5)
			(thermal_bridge_width 0.5)
			(island_removal_mode 0)
		)
		(polygon
			(pts
				(arc
					(start 168.301162 -395.92885)
					(mid 168.316041 -395.892929)
					(end 168.351962 -395.87805)
				)
				(arc
					(start 169.068242 -395.87805)
					(mid 169.104163 -395.892929)
					(end 169.119042 -395.92885)
				)
				(arc
					(start 169.119042 -398.351502)
					(mid 169.104163 -398.387423)
					(end 169.068242 -398.402302)
				)
				(arc
					(start 168.351962 -398.402302)
					(mid 168.316041 -398.387423)
					(end 168.301162 -398.351502)
				)
			)
		)
	)
	(zone
		(layers "F.Cu" "B.Cu" "In1.Cu" "In2.Cu" "In3.Cu" "In4.Cu" "In5.Cu" "In6.Cu"
			"In7.Cu" "In8.Cu" "In9.Cu" "In10.Cu" "In11.Cu" "In12.Cu" "In13.Cu" "In14.Cu"
			"In15.Cu" "In16.Cu"
		)
		(hatch none 0.5)
		(connect_pads
			(clearance 0)
		)
		(min_thickness 0.25)
		(keepout
			(tracks not_allowed)
			(vias allowed)
			(pads allowed)
			(copperpour not_allowed)
			(footprints allowed)
		)
		(placement
			(enabled no)
			(sheetname "")
		)
		(fill
			(thermal_gap 0.5)
			(thermal_bridge_width 0.5)
			(island_removal_mode 0)
		)
		(polygon
			(pts
				(arc
					(start 395.790166 -30.92069)
					(mid 396.247366 -31.37789)
					(end 396.704566 -30.92069)
				)
				(arc
					(start 396.704566 -30.05709)
					(mid 396.247366 -29.59989)
					(end 395.790166 -30.05709)
				)
			)
		)
	)
	(zone
		(layers "F.Cu" "B.Cu" "In1.Cu" "In2.Cu" "In3.Cu" "In4.Cu" "In5.Cu" "In6.Cu"
			"In7.Cu" "In8.Cu" "In9.Cu" "In10.Cu" "In11.Cu" "In12.Cu" "In13.Cu" "In14.Cu"
			"In15.Cu" "In16.Cu"
		)
		(hatch none 0.5)
		(connect_pads
			(clearance 0)
		)
		(min_thickness 0.25)
		(keepout
			(tracks not_allowed)
			(vias allowed)
			(pads allowed)
			(copperpour not_allowed)
			(footprints allowed)
		)
		(placement
			(enabled no)
			(sheetname "")
		)
		(fill
			(thermal_gap 0.5)
			(thermal_bridge_width 0.5)
			(island_removal_mode 0)
		)
		(polygon
			(pts
				(arc
					(start 92.461842 -342.058498)
					(mid 92.080842 -342.439498)
					(end 92.461842 -342.820498)
				)
				(arc
					(start 93.325442 -342.820498)
					(mid 93.706442 -342.439498)
					(end 93.325442 -342.058498)
				)
			)
		)
	)
	(zone
		(layers "F.Cu" "B.Cu" "In1.Cu" "In2.Cu" "In3.Cu" "In4.Cu" "In5.Cu" "In6.Cu"
			"In7.Cu" "In8.Cu" "In9.Cu" "In10.Cu" "In11.Cu" "In12.Cu" "In13.Cu" "In14.Cu"
			"In15.Cu" "In16.Cu"
		)
		(hatch none 0.5)
		(connect_pads
			(clearance 0)
		)
		(min_thickness 0.25)
		(keepout
			(tracks not_allowed)
			(vias allowed)
			(pads allowed)
			(copperpour not_allowed)
			(footprints allowed)
		)
		(placement
			(enabled no)
			(sheetname "")
		)
		(fill
			(thermal_gap 0.5)
			(thermal_bridge_width 0.5)
			(island_removal_mode 0)
		)
		(polygon
			(pts
				(arc
					(start 298.080938 -371.028722)
					(mid 298.095817 -370.992801)
					(end 298.131738 -370.977922)
				)
				(arc
					(start 298.848018 -370.977922)
					(mid 298.883939 -370.992801)
					(end 298.898818 -371.028722)
				)
				(arc
					(start 298.898818 -373.451374)
					(mid 298.883939 -373.487295)
					(end 298.848018 -373.502174)
				)
				(arc
					(start 298.131738 -373.502174)
					(mid 298.095817 -373.487295)
					(end 298.080938 -373.451374)
				)
			)
		)
	)
	(zone
		(layers "F.Cu" "B.Cu" "In1.Cu" "In2.Cu" "In3.Cu" "In4.Cu" "In5.Cu" "In6.Cu"
			"In7.Cu" "In8.Cu" "In9.Cu" "In10.Cu" "In11.Cu" "In12.Cu" "In13.Cu" "In14.Cu"
			"In15.Cu" "In16.Cu"
		)
		(hatch none 0.5)
		(connect_pads
			(clearance 0)
		)
		(min_thickness 0.25)
		(keepout
			(tracks not_allowed)
			(vias allowed)
			(pads allowed)
			(copperpour not_allowed)
			(footprints allowed)
		)
		(placement
			(enabled no)
			(sheetname "")
		)
		(fill
			(thermal_gap 0.5)
			(thermal_bridge_width 0.5)
			(island_removal_mode 0)
		)
		(polygon
			(pts
				(arc
					(start 424.839892 -354.351082)
					(mid 424.458892 -354.732082)
					(end 424.839892 -355.113082)
				)
				(arc
					(start 425.703492 -355.113082)
					(mid 426.084492 -354.732082)
					(end 425.703492 -354.351082)
				)
			)
		)
	)
	(zone
		(layers "F.Cu" "B.Cu" "In1.Cu" "In2.Cu" "In3.Cu" "In4.Cu" "In5.Cu" "In6.Cu"
			"In7.Cu" "In8.Cu" "In9.Cu" "In10.Cu" "In11.Cu" "In12.Cu" "In13.Cu" "In14.Cu"
			"In15.Cu" "In16.Cu"
		)
		(hatch none 0.5)
		(connect_pads
			(clearance 0)
		)
		(min_thickness 0.25)
		(keepout
			(tracks not_allowed)
			(vias allowed)
			(pads allowed)
			(copperpour not_allowed)
			(footprints allowed)
		)
		(placement
			(enabled no)
			(sheetname "")
		)
		(fill
			(thermal_gap 0.5)
			(thermal_bridge_width 0.5)
			(island_removal_mode 0)
		)
		(polygon
			(pts
				(arc
					(start 286.754062 -122.822716)
					(mid 286.296862 -122.365516)
					(end 285.839662 -122.822716)
				)
				(arc
					(start 285.839662 -123.686316)
					(mid 286.296862 -124.143516)
					(end 286.754062 -123.686316)
				)
			)
		)
	)
	(zone
		(layers "F.Cu" "B.Cu" "In1.Cu" "In2.Cu" "In3.Cu" "In4.Cu" "In5.Cu" "In6.Cu"
			"In7.Cu" "In8.Cu" "In9.Cu" "In10.Cu" "In11.Cu" "In12.Cu" "In13.Cu" "In14.Cu"
			"In15.Cu" "In16.Cu"
		)
		(hatch none 0.5)
		(connect_pads
			(clearance 0)
		)
		(min_thickness 0.25)
		(keepout
			(tracks not_allowed)
			(vias allowed)
			(pads allowed)
			(copperpour not_allowed)
			(footprints allowed)
		)
		(placement
			(enabled no)
			(sheetname "")
		)
		(fill
			(thermal_gap 0.5)
			(thermal_bridge_width 0.5)
			(island_removal_mode 0)
		)
		(polygon
			(pts
				(arc
					(start 134.948168 -29.114242)
					(mid 135.405368 -29.571442)
					(end 135.862568 -29.114242)
				)
				(arc
					(start 135.862568 -28.250642)
					(mid 135.405368 -27.793442)
					(end 134.948168 -28.250642)
				)
			)
		)
	)
	(zone
		(layers "F.Cu" "B.Cu" "In1.Cu" "In2.Cu" "In3.Cu" "In4.Cu" "In5.Cu" "In6.Cu"
			"In7.Cu" "In8.Cu" "In9.Cu" "In10.Cu" "In11.Cu" "In12.Cu" "In13.Cu" "In14.Cu"
			"In15.Cu" "In16.Cu"
		)
		(hatch none 0.5)
		(connect_pads
			(clearance 0)
		)
		(min_thickness 0.25)
		(keepout
			(tracks not_allowed)
			(vias allowed)
			(pads allowed)
			(copperpour not_allowed)
			(footprints allowed)
		)
		(placement
			(enabled no)
			(sheetname "")
		)
		(fill
			(thermal_gap 0.5)
			(thermal_bridge_width 0.5)
			(island_removal_mode 0)
		)
		(polygon
			(pts
				(arc
					(start 82.500978 -408.728672)
					(mid 82.515857 -408.692751)
					(end 82.551778 -408.677872)
				)
				(arc
					(start 83.268058 -408.677872)
					(mid 83.303979 -408.692751)
					(end 83.318858 -408.728672)
				)
				(arc
					(start 83.318858 -411.151324)
					(mid 83.303979 -411.187245)
					(end 83.268058 -411.202124)
				)
				(arc
					(start 82.551778 -411.202124)
					(mid 82.515857 -411.187245)
					(end 82.500978 -411.151324)
				)
			)
		)
	)
	(zone
		(layers "F.Cu" "B.Cu" "In1.Cu" "In2.Cu" "In3.Cu" "In4.Cu" "In5.Cu" "In6.Cu"
			"In7.Cu" "In8.Cu" "In9.Cu" "In10.Cu" "In11.Cu" "In12.Cu" "In13.Cu" "In14.Cu"
			"In15.Cu" "In16.Cu"
		)
		(hatch none 0.5)
		(connect_pads
			(clearance 0)
		)
		(min_thickness 0.25)
		(keepout
			(tracks not_allowed)
			(vias allowed)
			(pads allowed)
			(copperpour not_allowed)
			(footprints allowed)
		)
		(placement
			(enabled no)
			(sheetname "")
		)
		(fill
			(thermal_gap 0.5)
			(thermal_bridge_width 0.5)
			(island_removal_mode 0)
		)
		(polygon
			(pts
				(arc
					(start 362.230162 -36.60013)
					(mid 360.299762 -36.60013)
					(end 362.230162 -36.60013)
				)
			)
		)
	)
	(zone
		(layers "F.Cu" "B.Cu" "In1.Cu" "In2.Cu" "In3.Cu" "In4.Cu" "In5.Cu" "In6.Cu"
			"In7.Cu" "In8.Cu" "In9.Cu" "In10.Cu" "In11.Cu" "In12.Cu" "In13.Cu" "In14.Cu"
			"In15.Cu" "In16.Cu"
		)
		(hatch none 0.5)
		(connect_pads
			(clearance 0)
		)
		(min_thickness 0.25)
		(keepout
			(tracks not_allowed)
			(vias allowed)
			(pads allowed)
			(copperpour not_allowed)
			(footprints allowed)
		)
		(placement
			(enabled no)
			(sheetname "")
		)
		(fill
			(thermal_gap 0.5)
			(thermal_bridge_width 0.5)
			(island_removal_mode 0)
		)
		(polygon
			(pts
				(arc
					(start 66.60007 -154.28722)
					(mid 67.05727 -154.74442)
					(end 67.51447 -154.28722)
				)
				(arc
					(start 67.51447 -153.42362)
					(mid 67.05727 -152.96642)
					(end 66.60007 -153.42362)
				)
			)
		)
	)
	(zone
		(layers "F.Cu" "B.Cu" "In1.Cu" "In2.Cu" "In3.Cu" "In4.Cu" "In5.Cu" "In6.Cu"
			"In7.Cu" "In8.Cu" "In9.Cu" "In10.Cu" "In11.Cu" "In12.Cu" "In13.Cu" "In14.Cu"
			"In15.Cu" "In16.Cu"
		)
		(hatch none 0.5)
		(connect_pads
			(clearance 0)
		)
		(min_thickness 0.25)
		(keepout
			(tracks not_allowed)
			(vias allowed)
			(pads allowed)
			(copperpour not_allowed)
			(footprints allowed)
		)
		(placement
			(enabled no)
			(sheetname "")
		)
		(fill
			(thermal_gap 0.5)
			(thermal_bridge_width 0.5)
			(island_removal_mode 0)
		)
		(polygon
			(pts
				(arc
					(start 339.88121 -381.628904)
					(mid 339.896089 -381.592983)
					(end 339.93201 -381.578104)
				)
				(arc
					(start 340.64829 -381.578104)
					(mid 340.684211 -381.592983)
					(end 340.69909 -381.628904)
				)
				(arc
					(start 340.69909 -384.051556)
					(mid 340.684211 -384.087477)
					(end 340.64829 -384.102356)
				)
				(arc
					(start 339.93201 -384.102356)
					(mid 339.896089 -384.087477)
					(end 339.88121 -384.051556)
				)
			)
		)
	)
	(zone
		(layers "F.Cu" "B.Cu" "In1.Cu" "In2.Cu" "In3.Cu" "In4.Cu" "In5.Cu" "In6.Cu"
			"In7.Cu" "In8.Cu" "In9.Cu" "In10.Cu" "In11.Cu" "In12.Cu" "In13.Cu" "In14.Cu"
			"In15.Cu" "In16.Cu"
		)
		(hatch none 0.5)
		(connect_pads
			(clearance 0)
		)
		(min_thickness 0.25)
		(keepout
			(tracks not_allowed)
			(vias allowed)
			(pads allowed)
			(copperpour not_allowed)
			(footprints allowed)
		)
		(placement
			(enabled no)
			(sheetname "")
		)
		(fill
			(thermal_gap 0.5)
			(thermal_bridge_width 0.5)
			(island_removal_mode 0)
		)
		(polygon
			(pts
				(arc
					(start 80.301084 -407.628852)
					(mid 80.315963 -407.592931)
					(end 80.351884 -407.578052)
				)
				(arc
					(start 81.068164 -407.578052)
					(mid 81.104085 -407.592931)
					(end 81.118964 -407.628852)
				)
				(arc
					(start 81.118964 -410.051504)
					(mid 81.104085 -410.087425)
					(end 81.068164 -410.102304)
				)
				(arc
					(start 80.351884 -410.102304)
					(mid 80.315963 -410.087425)
					(end 80.301084 -410.051504)
				)
			)
		)
	)
	(zone
		(layers "F.Cu" "B.Cu" "In1.Cu" "In2.Cu" "In3.Cu" "In4.Cu" "In5.Cu" "In6.Cu"
			"In7.Cu" "In8.Cu" "In9.Cu" "In10.Cu" "In11.Cu" "In12.Cu" "In13.Cu" "In14.Cu"
			"In15.Cu" "In16.Cu"
		)
		(hatch none 0.5)
		(connect_pads
			(clearance 0)
		)
		(min_thickness 0.25)
		(keepout
			(tracks not_allowed)
			(vias allowed)
			(pads allowed)
			(copperpour not_allowed)
			(footprints allowed)
		)
		(placement
			(enabled no)
			(sheetname "")
		)
		(fill
			(thermal_gap 0.5)
			(thermal_bridge_width 0.5)
			(island_removal_mode 0)
		)
		(polygon
			(pts
				(arc
					(start 392.9507 -348.20479)
					(mid 392.5697 -348.58579)
					(end 392.9507 -348.96679)
				)
				(arc
					(start 393.8143 -348.96679)
					(mid 394.1953 -348.58579)
					(end 393.8143 -348.20479)
				)
			)
		)
	)
	(zone
		(layers "F.Cu" "B.Cu" "In1.Cu" "In2.Cu" "In3.Cu" "In4.Cu" "In5.Cu" "In6.Cu"
			"In7.Cu" "In8.Cu" "In9.Cu" "In10.Cu" "In11.Cu" "In12.Cu" "In13.Cu" "In14.Cu"
			"In15.Cu" "In16.Cu"
		)
		(hatch none 0.5)
		(connect_pads
			(clearance 0)
		)
		(min_thickness 0.25)
		(keepout
			(tracks not_allowed)
			(vias allowed)
			(pads allowed)
			(copperpour not_allowed)
			(footprints allowed)
		)
		(placement
			(enabled no)
			(sheetname "")
		)
		(fill
			(thermal_gap 0.5)
			(thermal_bridge_width 0.5)
			(island_removal_mode 0)
		)
		(polygon
			(pts
				(arc
					(start 21.490178 -34.520886)
					(mid 21.947378 -34.978086)
					(end 22.404578 -34.520886)
				)
				(arc
					(start 22.404578 -33.657286)
					(mid 21.947378 -33.200086)
					(end 21.490178 -33.657286)
				)
			)
		)
	)
	(zone
		(layers "F.Cu" "B.Cu" "In1.Cu" "In2.Cu" "In3.Cu" "In4.Cu" "In5.Cu" "In6.Cu"
			"In7.Cu" "In8.Cu" "In9.Cu" "In10.Cu" "In11.Cu" "In12.Cu" "In13.Cu" "In14.Cu"
			"In15.Cu" "In16.Cu"
		)
		(hatch none 0.5)
		(connect_pads
			(clearance 0)
		)
		(min_thickness 0.25)
		(keepout
			(tracks not_allowed)
			(vias allowed)
			(pads allowed)
			(copperpour not_allowed)
			(footprints allowed)
		)
		(placement
			(enabled no)
			(sheetname "")
		)
		(fill
			(thermal_gap 0.5)
			(thermal_bridge_width 0.5)
			(island_removal_mode 0)
		)
		(polygon
			(pts
				(arc
					(start 82.500978 -371.028722)
					(mid 82.515857 -370.992801)
					(end 82.551778 -370.977922)
				)
				(arc
					(start 83.268058 -370.977922)
					(mid 83.303979 -370.992801)
					(end 83.318858 -371.028722)
				)
				(arc
					(start 83.318858 -373.451374)
					(mid 83.303979 -373.487295)
					(end 83.268058 -373.502174)
				)
				(arc
					(start 82.551778 -373.502174)
					(mid 82.515857 -373.487295)
					(end 82.500978 -373.451374)
				)
			)
		)
	)
	(zone
		(layers "F.Cu" "B.Cu" "In1.Cu" "In2.Cu" "In3.Cu" "In4.Cu" "In5.Cu" "In6.Cu"
			"In7.Cu" "In8.Cu" "In9.Cu" "In10.Cu" "In11.Cu" "In12.Cu" "In13.Cu" "In14.Cu"
			"In15.Cu" "In16.Cu"
		)
		(hatch none 0.5)
		(connect_pads
			(clearance 0)
		)
		(min_thickness 0.25)
		(keepout
			(tracks not_allowed)
			(vias allowed)
			(pads allowed)
			(copperpour not_allowed)
			(footprints allowed)
		)
		(placement
			(enabled no)
			(sheetname "")
		)
		(fill
			(thermal_gap 0.5)
			(thermal_bridge_width 0.5)
			(island_removal_mode 0)
		)
		(polygon
			(pts
				(arc
					(start 400.99996 -104.71277)
					(mid 400.54276 -104.25557)
					(end 400.08556 -104.71277)
				)
				(arc
					(start 400.08556 -105.57637)
					(mid 400.54276 -106.03357)
					(end 400.99996 -105.57637)
				)
			)
		)
	)
	(zone
		(layers "F.Cu" "B.Cu" "In1.Cu" "In2.Cu" "In3.Cu" "In4.Cu" "In5.Cu" "In6.Cu"
			"In7.Cu" "In8.Cu" "In9.Cu" "In10.Cu" "In11.Cu" "In12.Cu" "In13.Cu" "In14.Cu"
			"In15.Cu" "In16.Cu"
		)
		(hatch none 0.5)
		(connect_pads
			(clearance 0)
		)
		(min_thickness 0.25)
		(keepout
			(tracks not_allowed)
			(vias allowed)
			(pads allowed)
			(copperpour not_allowed)
			(footprints allowed)
		)
		(placement
			(enabled no)
			(sheetname "")
		)
		(fill
			(thermal_gap 0.5)
			(thermal_bridge_width 0.5)
			(island_removal_mode 0)
		)
		(polygon
			(pts
				(arc
					(start 399.16862 -345.084146)
					(mid 398.78762 -345.465146)
					(end 399.16862 -345.846146)
				)
				(arc
					(start 400.03222 -345.846146)
					(mid 400.41322 -345.465146)
					(end 400.03222 -345.084146)
				)
			)
		)
	)
	(zone
		(layers "F.Cu" "B.Cu" "In1.Cu" "In2.Cu" "In3.Cu" "In4.Cu" "In5.Cu" "In6.Cu"
			"In7.Cu" "In8.Cu" "In9.Cu" "In10.Cu" "In11.Cu" "In12.Cu" "In13.Cu" "In14.Cu"
			"In15.Cu" "In16.Cu"
		)
		(hatch none 0.5)
		(connect_pads
			(clearance 0)
		)
		(min_thickness 0.25)
		(keepout
			(tracks not_allowed)
			(vias allowed)
			(pads allowed)
			(copperpour not_allowed)
			(footprints allowed)
		)
		(placement
			(enabled no)
			(sheetname "")
		)
		(fill
			(thermal_gap 0.5)
			(thermal_bridge_width 0.5)
			(island_removal_mode 0)
		)
		(polygon
			(pts
				(arc
					(start 328.047604 -354.351082)
					(mid 327.666604 -354.732082)
					(end 328.047604 -355.113082)
				)
				(arc
					(start 328.911204 -355.113082)
					(mid 329.292204 -354.732082)
					(end 328.911204 -354.351082)
				)
			)
		)
	)
	(zone
		(layers "F.Cu" "B.Cu" "In1.Cu" "In2.Cu" "In3.Cu" "In4.Cu" "In5.Cu" "In6.Cu"
			"In7.Cu" "In8.Cu" "In9.Cu" "In10.Cu" "In11.Cu" "In12.Cu" "In13.Cu" "In14.Cu"
			"In15.Cu" "In16.Cu"
		)
		(hatch none 0.5)
		(connect_pads
			(clearance 0)
		)
		(min_thickness 0.25)
		(keepout
			(tracks not_allowed)
			(vias allowed)
			(pads allowed)
			(copperpour not_allowed)
			(footprints allowed)
		)
		(placement
			(enabled no)
			(sheetname "")
		)
		(fill
			(thermal_gap 0.5)
			(thermal_bridge_width 0.5)
			(island_removal_mode 0)
		)
		(polygon
			(pts
				(arc
					(start 315.611764 -354.351082)
					(mid 315.230764 -354.732082)
					(end 315.611764 -355.113082)
				)
				(arc
					(start 316.475364 -355.113082)
					(mid 316.856364 -354.732082)
					(end 316.475364 -354.351082)
				)
			)
		)
	)
	(zone
		(layers "F.Cu" "B.Cu" "In1.Cu" "In2.Cu" "In3.Cu" "In4.Cu" "In5.Cu" "In6.Cu"
			"In7.Cu" "In8.Cu" "In9.Cu" "In10.Cu" "In11.Cu" "In12.Cu" "In13.Cu" "In14.Cu"
			"In15.Cu" "In16.Cu"
		)
		(hatch none 0.5)
		(connect_pads
			(clearance 0)
		)
		(min_thickness 0.25)
		(keepout
			(tracks not_allowed)
			(vias allowed)
			(pads allowed)
			(copperpour not_allowed)
			(footprints allowed)
		)
		(placement
			(enabled no)
			(sheetname "")
		)
		(fill
			(thermal_gap 0.5)
			(thermal_bridge_width 0.5)
			(island_removal_mode 0)
		)
		(polygon
			(pts
				(arc
					(start 153.410666 -136.704324)
					(mid 153.867866 -137.161524)
					(end 154.325066 -136.704324)
				)
				(arc
					(start 154.325066 -135.840724)
					(mid 153.867866 -135.383524)
					(end 153.410666 -135.840724)
				)
			)
		)
	)
	(zone
		(layers "F.Cu" "B.Cu" "In1.Cu" "In2.Cu" "In3.Cu" "In4.Cu" "In5.Cu" "In6.Cu"
			"In7.Cu" "In8.Cu" "In9.Cu" "In10.Cu" "In11.Cu" "In12.Cu" "In13.Cu" "In14.Cu"
			"In15.Cu" "In16.Cu"
		)
		(hatch none 0.5)
		(connect_pads
			(clearance 0)
		)
		(min_thickness 0.25)
		(keepout
			(tracks not_allowed)
			(vias allowed)
			(pads allowed)
			(copperpour not_allowed)
			(footprints allowed)
		)
		(placement
			(enabled no)
			(sheetname "")
		)
		(fill
			(thermal_gap 0.5)
			(thermal_bridge_width 0.5)
			(island_removal_mode 0)
		)
		(polygon
			(pts
				(arc
					(start 390.481058 -374.928638)
					(mid 390.495937 -374.892717)
					(end 390.531858 -374.877838)
				)
				(arc
					(start 391.248138 -374.877838)
					(mid 391.284059 -374.892717)
					(end 391.298938 -374.928638)
				)
				(arc
					(start 391.298938 -377.35129)
					(mid 391.284059 -377.387211)
					(end 391.248138 -377.40209)
				)
				(arc
					(start 390.531858 -377.40209)
					(mid 390.495937 -377.387211)
					(end 390.481058 -377.35129)
				)
			)
		)
	)
	(zone
		(layers "F.Cu" "B.Cu" "In1.Cu" "In2.Cu" "In3.Cu" "In4.Cu" "In5.Cu" "In6.Cu"
			"In7.Cu" "In8.Cu" "In9.Cu" "In10.Cu" "In11.Cu" "In12.Cu" "In13.Cu" "In14.Cu"
			"In15.Cu" "In16.Cu"
		)
		(hatch none 0.5)
		(connect_pads
			(clearance 0)
		)
		(min_thickness 0.25)
		(keepout
			(tracks not_allowed)
			(vias allowed)
			(pads allowed)
			(copperpour not_allowed)
			(footprints allowed)
		)
		(placement
			(enabled no)
			(sheetname "")
		)
		(fill
			(thermal_gap 0.5)
			(thermal_bridge_width 0.5)
			(island_removal_mode 0)
		)
		(polygon
			(pts
				(arc
					(start 346.481146 -397.028924)
					(mid 346.496025 -396.993003)
					(end 346.531946 -396.978124)
				)
				(arc
					(start 347.248226 -396.978124)
					(mid 347.284147 -396.993003)
					(end 347.299026 -397.028924)
				)
				(arc
					(start 347.299026 -399.451576)
					(mid 347.284147 -399.487497)
					(end 347.248226 -399.502376)
				)
				(arc
					(start 346.531946 -399.502376)
					(mid 346.496025 -399.487497)
					(end 346.481146 -399.451576)
				)
			)
		)
	)
	(zone
		(layers "F.Cu" "B.Cu" "In1.Cu" "In2.Cu" "In3.Cu" "In4.Cu" "In5.Cu" "In6.Cu"
			"In7.Cu" "In8.Cu" "In9.Cu" "In10.Cu" "In11.Cu" "In12.Cu" "In13.Cu" "In14.Cu"
			"In15.Cu" "In16.Cu"
		)
		(hatch none 0.5)
		(connect_pads
			(clearance 0)
		)
		(min_thickness 0.25)
		(keepout
			(tracks not_allowed)
			(vias allowed)
			(pads allowed)
			(copperpour not_allowed)
			(footprints allowed)
		)
		(placement
			(enabled no)
			(sheetname "")
		)
		(fill
			(thermal_gap 0.5)
			(thermal_bridge_width 0.5)
			(island_removal_mode 0)
		)
		(polygon
			(pts
				(arc
					(start 338.864194 -78.425548)
					(mid 338.406994 -78.882748)
					(end 338.864194 -79.339948)
				)
				(arc
					(start 339.727794 -79.339948)
					(mid 340.184994 -78.882748)
					(end 339.727794 -78.425548)
				)
			)
		)
	)
	(zone
		(layers "F.Cu" "B.Cu" "In1.Cu" "In2.Cu" "In3.Cu" "In4.Cu" "In5.Cu" "In6.Cu"
			"In7.Cu" "In8.Cu" "In9.Cu" "In10.Cu" "In11.Cu" "In12.Cu" "In13.Cu" "In14.Cu"
			"In15.Cu" "In16.Cu"
		)
		(hatch none 0.5)
		(connect_pads
			(clearance 0)
		)
		(min_thickness 0.25)
		(keepout
			(tracks not_allowed)
			(vias allowed)
			(pads allowed)
			(copperpour not_allowed)
			(footprints allowed)
		)
		(placement
			(enabled no)
			(sheetname "")
		)
		(fill
			(thermal_gap 0.5)
			(thermal_bridge_width 0.5)
			(island_removal_mode 0)
		)
		(polygon
			(pts
				(arc
					(start 161.700972 -371.028722)
					(mid 161.715851 -370.992801)
					(end 161.751772 -370.977922)
				)
				(arc
					(start 162.468052 -370.977922)
					(mid 162.503973 -370.992801)
					(end 162.518852 -371.028722)
				)
				(arc
					(start 162.518852 -373.451374)
					(mid 162.503973 -373.487295)
					(end 162.468052 -373.502174)
				)
				(arc
					(start 161.751772 -373.502174)
					(mid 161.715851 -373.487295)
					(end 161.700972 -373.451374)
				)
			)
		)
	)
	(zone
		(layers "F.Cu" "B.Cu" "In1.Cu" "In2.Cu" "In3.Cu" "In4.Cu" "In5.Cu" "In6.Cu"
			"In7.Cu" "In8.Cu" "In9.Cu" "In10.Cu" "In11.Cu" "In12.Cu" "In13.Cu" "In14.Cu"
			"In15.Cu" "In16.Cu"
		)
		(hatch none 0.5)
		(connect_pads
			(clearance 0)
		)
		(min_thickness 0.25)
		(keepout
			(tracks not_allowed)
			(vias allowed)
			(pads allowed)
			(copperpour not_allowed)
			(footprints allowed)
		)
		(placement
			(enabled no)
			(sheetname "")
		)
		(fill
			(thermal_gap 0.5)
			(thermal_bridge_width 0.5)
			(island_removal_mode 0)
		)
		(polygon
			(pts
				(arc
					(start 286.754062 -119.222774)
					(mid 286.296862 -118.765574)
					(end 285.839662 -119.222774)
				)
				(arc
					(start 285.839662 -120.086374)
					(mid 286.296862 -120.543574)
					(end 286.754062 -120.086374)
				)
			)
		)
	)
	(zone
		(layers "F.Cu" "B.Cu" "In1.Cu" "In2.Cu" "In3.Cu" "In4.Cu" "In5.Cu" "In6.Cu"
			"In7.Cu" "In8.Cu" "In9.Cu" "In10.Cu" "In11.Cu" "In12.Cu" "In13.Cu" "In14.Cu"
			"In15.Cu" "In16.Cu"
		)
		(hatch none 0.5)
		(connect_pads
			(clearance 0)
		)
		(min_thickness 0.25)
		(keepout
			(tracks not_allowed)
			(vias allowed)
			(pads allowed)
			(copperpour not_allowed)
			(footprints allowed)
		)
		(placement
			(enabled no)
			(sheetname "")
		)
		(fill
			(thermal_gap 0.5)
			(thermal_bridge_width 0.5)
			(island_removal_mode 0)
		)
		(polygon
			(pts
				(arc
					(start 312.502804 -348.20479)
					(mid 312.121804 -348.58579)
					(end 312.502804 -348.96679)
				)
				(arc
					(start 313.366404 -348.96679)
					(mid 313.747404 -348.58579)
					(end 313.366404 -348.20479)
				)
			)
		)
	)
	(zone
		(layers "F.Cu" "B.Cu" "In1.Cu" "In2.Cu" "In3.Cu" "In4.Cu" "In5.Cu" "In6.Cu"
			"In7.Cu" "In8.Cu" "In9.Cu" "In10.Cu" "In11.Cu" "In12.Cu" "In13.Cu" "In14.Cu"
			"In15.Cu" "In16.Cu"
		)
		(hatch none 0.5)
		(connect_pads
			(clearance 0)
		)
		(min_thickness 0.25)
		(keepout
			(tracks not_allowed)
			(vias allowed)
			(pads allowed)
			(copperpour not_allowed)
			(footprints allowed)
		)
		(placement
			(enabled no)
			(sheetname "")
		)
		(fill
			(thermal_gap 0.5)
			(thermal_bridge_width 0.5)
			(island_removal_mode 0)
		)
		(polygon
			(pts
				(arc
					(start 118.080028 -351.230438)
					(mid 117.699028 -351.611438)
					(end 118.080028 -351.992438)
				)
				(arc
					(start 118.943628 -351.992438)
					(mid 119.324628 -351.611438)
					(end 118.943628 -351.230438)
				)
			)
		)
	)
	(zone
		(layers "F.Cu" "B.Cu" "In1.Cu" "In2.Cu" "In3.Cu" "In4.Cu" "In5.Cu" "In6.Cu"
			"In7.Cu" "In8.Cu" "In9.Cu" "In10.Cu" "In11.Cu" "In12.Cu" "In13.Cu" "In14.Cu"
			"In15.Cu" "In16.Cu"
		)
		(hatch none 0.5)
		(connect_pads
			(clearance 0)
		)
		(min_thickness 0.25)
		(keepout
			(tracks not_allowed)
			(vias allowed)
			(pads allowed)
			(copperpour not_allowed)
			(footprints allowed)
		)
		(placement
			(enabled no)
			(sheetname "")
		)
		(fill
			(thermal_gap 0.5)
			(thermal_bridge_width 0.5)
			(island_removal_mode 0)
		)
		(polygon
			(pts
				(arc
					(start 376.78487 18.460212)
					(mid 376.40387 18.841212)
					(end 376.02287 18.460212)
				)
				(arc
					(start 376.02287 17.596612)
					(mid 376.40387 17.215612)
					(end 376.78487 17.596612)
				)
			)
		)
	)
	(zone
		(layers "F.Cu" "B.Cu" "In1.Cu" "In2.Cu" "In3.Cu" "In4.Cu" "In5.Cu" "In6.Cu"
			"In7.Cu" "In8.Cu" "In9.Cu" "In10.Cu" "In11.Cu" "In12.Cu" "In13.Cu" "In14.Cu"
			"In15.Cu" "In16.Cu"
		)
		(hatch none 0.5)
		(connect_pads
			(clearance 0)
		)
		(min_thickness 0.25)
		(keepout
			(tracks not_allowed)
			(vias allowed)
			(pads allowed)
			(copperpour not_allowed)
			(footprints allowed)
		)
		(placement
			(enabled no)
			(sheetname "")
		)
		(fill
			(thermal_gap 0.5)
			(thermal_bridge_width 0.5)
			(island_removal_mode 0)
		)
		(polygon
			(pts
				(arc
					(start 377.280932 -408.728672)
					(mid 377.295811 -408.692751)
					(end 377.331732 -408.677872)
				)
				(arc
					(start 378.048012 -408.677872)
					(mid 378.083933 -408.692751)
					(end 378.098812 -408.728672)
				)
				(arc
					(start 378.098812 -411.151324)
					(mid 378.083933 -411.187245)
					(end 378.048012 -411.202124)
				)
				(arc
					(start 377.331732 -411.202124)
					(mid 377.295811 -411.187245)
					(end 377.280932 -411.151324)
				)
			)
		)
	)
	(zone
		(layers "F.Cu" "B.Cu" "In1.Cu" "In2.Cu" "In3.Cu" "In4.Cu" "In5.Cu" "In6.Cu"
			"In7.Cu" "In8.Cu" "In9.Cu" "In10.Cu" "In11.Cu" "In12.Cu" "In13.Cu" "In14.Cu"
			"In15.Cu" "In16.Cu"
		)
		(hatch none 0.5)
		(connect_pads
			(clearance 0)
		)
		(min_thickness 0.25)
		(keepout
			(tracks not_allowed)
			(vias allowed)
			(pads allowed)
			(copperpour not_allowed)
			(footprints allowed)
		)
		(placement
			(enabled no)
			(sheetname "")
		)
		(fill
			(thermal_gap 0.5)
			(thermal_bridge_width 0.5)
			(island_removal_mode 0)
		)
		(polygon
			(pts
				(arc
					(start 52.69992 -111.912908)
					(mid 52.24272 -111.455708)
					(end 51.78552 -111.912908)
				)
				(arc
					(start 51.78552 -112.776508)
					(mid 52.24272 -113.233708)
					(end 52.69992 -112.776508)
				)
			)
		)
	)
	(zone
		(layers "F.Cu" "B.Cu" "In1.Cu" "In2.Cu" "In3.Cu" "In4.Cu" "In5.Cu" "In6.Cu"
			"In7.Cu" "In8.Cu" "In9.Cu" "In10.Cu" "In11.Cu" "In12.Cu" "In13.Cu" "In14.Cu"
			"In15.Cu" "In16.Cu"
		)
		(hatch none 0.5)
		(connect_pads
			(clearance 0)
		)
		(min_thickness 0.25)
		(keepout
			(tracks not_allowed)
			(vias allowed)
			(pads allowed)
			(copperpour not_allowed)
			(footprints allowed)
		)
		(placement
			(enabled no)
			(sheetname "")
		)
		(fill
			(thermal_gap 0.5)
			(thermal_bridge_width 0.5)
			(island_removal_mode 0)
		)
		(polygon
			(pts
				(arc
					(start 381.680974 -397.028924)
					(mid 381.695853 -396.993003)
					(end 381.731774 -396.978124)
				)
				(arc
					(start 382.448054 -396.978124)
					(mid 382.483975 -396.993003)
					(end 382.498854 -397.028924)
				)
				(arc
					(start 382.498854 -399.451576)
					(mid 382.483975 -399.487497)
					(end 382.448054 -399.502376)
				)
				(arc
					(start 381.731774 -399.502376)
					(mid 381.695853 -399.487497)
					(end 381.680974 -399.451576)
				)
			)
		)
	)
	(zone
		(layers "F.Cu" "B.Cu" "In1.Cu" "In2.Cu" "In3.Cu" "In4.Cu" "In5.Cu" "In6.Cu"
			"In7.Cu" "In8.Cu" "In9.Cu" "In10.Cu" "In11.Cu" "In12.Cu" "In13.Cu" "In14.Cu"
			"In15.Cu" "In16.Cu"
		)
		(hatch none 0.5)
		(connect_pads
			(clearance 0)
		)
		(min_thickness 0.25)
		(keepout
			(tracks not_allowed)
			(vias allowed)
			(pads allowed)
			(copperpour not_allowed)
			(footprints allowed)
		)
		(placement
			(enabled no)
			(sheetname "")
		)
		(fill
			(thermal_gap 0.5)
			(thermal_bridge_width 0.5)
			(island_removal_mode 0)
		)
		(polygon
			(pts
				(arc
					(start 421.730932 -354.351082)
					(mid 421.349932 -354.732082)
					(end 421.730932 -355.113082)
				)
				(arc
					(start 422.594532 -355.113082)
					(mid 422.975532 -354.732082)
					(end 422.594532 -354.351082)
				)
			)
		)
	)
	(zone
		(layers "F.Cu" "B.Cu" "In1.Cu" "In2.Cu" "In3.Cu" "In4.Cu" "In5.Cu" "In6.Cu"
			"In7.Cu" "In8.Cu" "In9.Cu" "In10.Cu" "In11.Cu" "In12.Cu" "In13.Cu" "In14.Cu"
			"In15.Cu" "In16.Cu"
		)
		(hatch none 0.5)
		(connect_pads
			(clearance 0)
		)
		(min_thickness 0.25)
		(keepout
			(tracks not_allowed)
			(vias allowed)
			(pads allowed)
			(copperpour not_allowed)
			(footprints allowed)
		)
		(placement
			(enabled no)
			(sheetname "")
		)
		(fill
			(thermal_gap 0.5)
			(thermal_bridge_width 0.5)
			(island_removal_mode 0)
		)
		(polygon
			(pts
				(arc
					(start 19.332448 -351.230438)
					(mid 18.951448 -351.611438)
					(end 19.332448 -351.992438)
				)
				(arc
					(start 20.196048 -351.992438)
					(mid 20.577048 -351.611438)
					(end 20.196048 -351.230438)
				)
			)
		)
	)
	(zone
		(layers "F.Cu" "B.Cu" "In1.Cu" "In2.Cu" "In3.Cu" "In4.Cu" "In5.Cu" "In6.Cu"
			"In7.Cu" "In8.Cu" "In9.Cu" "In10.Cu" "In11.Cu" "In12.Cu" "In13.Cu" "In14.Cu"
			"In15.Cu" "In16.Cu"
		)
		(hatch none 0.5)
		(connect_pads
			(clearance 0)
		)
		(min_thickness 0.25)
		(keepout
			(tracks not_allowed)
			(vias allowed)
			(pads allowed)
			(copperpour not_allowed)
			(footprints allowed)
		)
		(placement
			(enabled no)
			(sheetname "")
		)
		(fill
			(thermal_gap 0.5)
			(thermal_bridge_width 0.5)
			(island_removal_mode 0)
		)
		(polygon
			(pts
				(arc
					(start 130.901186 -378.828554)
					(mid 130.916065 -378.792633)
					(end 130.951986 -378.777754)
				)
				(arc
					(start 131.668266 -378.777754)
					(mid 131.704187 -378.792633)
					(end 131.719066 -378.828554)
				)
				(arc
					(start 131.719066 -381.251206)
					(mid 131.704187 -381.287127)
					(end 131.668266 -381.302006)
				)
				(arc
					(start 130.951986 -381.302006)
					(mid 130.916065 -381.287127)
					(end 130.901186 -381.251206)
				)
			)
		)
	)
	(zone
		(layers "F.Cu" "B.Cu" "In1.Cu" "In2.Cu" "In3.Cu" "In4.Cu" "In5.Cu" "In6.Cu"
			"In7.Cu" "In8.Cu" "In9.Cu" "In10.Cu" "In11.Cu" "In12.Cu" "In13.Cu" "In14.Cu"
			"In15.Cu" "In16.Cu"
		)
		(hatch none 0.5)
		(connect_pads
			(clearance 0)
		)
		(min_thickness 0.25)
		(keepout
			(tracks not_allowed)
			(vias allowed)
			(pads allowed)
			(copperpour not_allowed)
			(footprints allowed)
		)
		(placement
			(enabled no)
			(sheetname "")
		)
		(fill
			(thermal_gap 0.5)
			(thermal_bridge_width 0.5)
			(island_removal_mode 0)
		)
		(polygon
			(pts
				(arc
					(start 54.55412 -134.032752)
					(mid 54.09692 -133.575552)
					(end 53.63972 -134.032752)
				)
				(arc
					(start 53.63972 -134.896352)
					(mid 54.09692 -135.353552)
					(end 54.55412 -134.896352)
				)
			)
		)
	)
	(zone
		(layers "F.Cu" "B.Cu" "In1.Cu" "In2.Cu" "In3.Cu" "In4.Cu" "In5.Cu" "In6.Cu"
			"In7.Cu" "In8.Cu" "In9.Cu" "In10.Cu" "In11.Cu" "In12.Cu" "In13.Cu" "In14.Cu"
			"In15.Cu" "In16.Cu"
		)
		(hatch none 0.5)
		(connect_pads
			(clearance 0)
		)
		(min_thickness 0.25)
		(keepout
			(tracks not_allowed)
			(vias allowed)
			(pads allowed)
			(copperpour not_allowed)
			(footprints allowed)
		)
		(placement
			(enabled no)
			(sheetname "")
		)
		(fill
			(thermal_gap 0.5)
			(thermal_bridge_width 0.5)
			(island_removal_mode 0)
		)
		(polygon
			(pts
				(arc
					(start 64.74587 -124.967238)
					(mid 65.20307 -125.424438)
					(end 65.66027 -124.967238)
				)
				(arc
					(start 65.66027 -124.103638)
					(mid 65.20307 -123.646438)
					(end 64.74587 -124.103638)
				)
			)
		)
	)
	(zone
		(layers "F.Cu" "B.Cu" "In1.Cu" "In2.Cu" "In3.Cu" "In4.Cu" "In5.Cu" "In6.Cu"
			"In7.Cu" "In8.Cu" "In9.Cu" "In10.Cu" "In11.Cu" "In12.Cu" "In13.Cu" "In14.Cu"
			"In15.Cu" "In16.Cu"
		)
		(hatch none 0.5)
		(connect_pads
			(clearance 0)
		)
		(min_thickness 0.25)
		(keepout
			(tracks not_allowed)
			(vias allowed)
			(pads allowed)
			(copperpour not_allowed)
			(footprints allowed)
		)
		(placement
			(enabled no)
			(sheetname "")
		)
		(fill
			(thermal_gap 0.5)
			(thermal_bridge_width 0.5)
			(island_removal_mode 0)
		)
		(polygon
			(pts
				(arc
					(start 124.30125 -377.728734)
					(mid 124.316129 -377.692813)
					(end 124.35205 -377.677934)
				)
				(arc
					(start 125.06833 -377.677934)
					(mid 125.104251 -377.692813)
					(end 125.11913 -377.728734)
				)
				(arc
					(start 125.11913 -380.151386)
					(mid 125.104251 -380.187307)
					(end 125.06833 -380.202186)
				)
				(arc
					(start 124.35205 -380.202186)
					(mid 124.316129 -380.187307)
					(end 124.30125 -380.151386)
				)
			)
		)
	)
	(zone
		(layers "F.Cu" "B.Cu" "In1.Cu" "In2.Cu" "In3.Cu" "In4.Cu" "In5.Cu" "In6.Cu"
			"In7.Cu" "In8.Cu" "In9.Cu" "In10.Cu" "In11.Cu" "In12.Cu" "In13.Cu" "In14.Cu"
			"In15.Cu" "In16.Cu"
		)
		(hatch none 0.5)
		(connect_pads
			(clearance 0)
		)
		(min_thickness 0.25)
		(keepout
			(tracks not_allowed)
			(vias allowed)
			(pads allowed)
			(copperpour not_allowed)
			(footprints allowed)
		)
		(placement
			(enabled no)
			(sheetname "")
		)
		(fill
			(thermal_gap 0.5)
			(thermal_bridge_width 0.5)
			(island_removal_mode 0)
		)
		(polygon
			(pts
				(arc
					(start 82.500978 -378.828554)
					(mid 82.515857 -378.792633)
					(end 82.551778 -378.777754)
				)
				(arc
					(start 83.268058 -378.777754)
					(mid 83.303979 -378.792633)
					(end 83.318858 -378.828554)
				)
				(arc
					(start 83.318858 -381.251206)
					(mid 83.303979 -381.287127)
					(end 83.268058 -381.302006)
				)
				(arc
					(start 82.551778 -381.302006)
					(mid 82.515857 -381.287127)
					(end 82.500978 -381.251206)
				)
			)
		)
	)
	(zone
		(layers "F.Cu" "B.Cu" "In1.Cu" "In2.Cu" "In3.Cu" "In4.Cu" "In5.Cu" "In6.Cu"
			"In7.Cu" "In8.Cu" "In9.Cu" "In10.Cu" "In11.Cu" "In12.Cu" "In13.Cu" "In14.Cu"
			"In15.Cu" "In16.Cu"
		)
		(hatch none 0.5)
		(connect_pads
			(clearance 0)
		)
		(min_thickness 0.25)
		(keepout
			(tracks not_allowed)
			(vias allowed)
			(pads allowed)
			(copperpour not_allowed)
			(footprints allowed)
		)
		(placement
			(enabled no)
			(sheetname "")
		)
		(fill
			(thermal_gap 0.5)
			(thermal_bridge_width 0.5)
			(island_removal_mode 0)
		)
		(polygon
			(pts
				(arc
					(start 269.51051 -136.704324)
					(mid 269.96771 -137.161524)
					(end 270.42491 -136.704324)
				)
				(arc
					(start 270.42491 -135.840724)
					(mid 269.96771 -135.383524)
					(end 269.51051 -135.840724)
				)
			)
		)
	)
	(zone
		(layers "F.Cu" "B.Cu" "In1.Cu" "In2.Cu" "In3.Cu" "In4.Cu" "In5.Cu" "In6.Cu"
			"In7.Cu" "In8.Cu" "In9.Cu" "In10.Cu" "In11.Cu" "In12.Cu" "In13.Cu" "In14.Cu"
			"In15.Cu" "In16.Cu"
		)
		(hatch none 0.5)
		(connect_pads
			(clearance 0)
		)
		(min_thickness 0.25)
		(keepout
			(tracks not_allowed)
			(vias allowed)
			(pads allowed)
			(copperpour not_allowed)
			(footprints allowed)
		)
		(placement
			(enabled no)
			(sheetname "")
		)
		(fill
			(thermal_gap 0.5)
			(thermal_bridge_width 0.5)
			(island_removal_mode 0)
		)
		(polygon
			(pts
				(arc
					(start 290.95319 -30.922468)
					(mid 291.41039 -31.379668)
					(end 291.86759 -30.922468)
				)
				(arc
					(start 291.86759 -30.058868)
					(mid 291.41039 -29.601668)
					(end 290.95319 -30.058868)
				)
			)
		)
	)
	(zone
		(layers "F.Cu" "B.Cu" "In1.Cu" "In2.Cu" "In3.Cu" "In4.Cu" "In5.Cu" "In6.Cu"
			"In7.Cu" "In8.Cu" "In9.Cu" "In10.Cu" "In11.Cu" "In12.Cu" "In13.Cu" "In14.Cu"
			"In15.Cu" "In16.Cu"
		)
		(hatch none 0.5)
		(connect_pads
			(clearance 0)
		)
		(min_thickness 0.25)
		(keepout
			(tracks not_allowed)
			(vias allowed)
			(pads allowed)
			(copperpour not_allowed)
			(footprints allowed)
		)
		(placement
			(enabled no)
			(sheetname "")
		)
		(fill
			(thermal_gap 0.5)
			(thermal_bridge_width 0.5)
			(island_removal_mode 0)
		)
		(polygon
			(pts
				(arc
					(start 31.768288 -357.37673)
					(mid 31.387288 -357.75773)
					(end 31.768288 -358.13873)
				)
				(arc
					(start 32.631888 -358.13873)
					(mid 33.012888 -357.75773)
					(end 32.631888 -357.37673)
				)
			)
		)
	)
	(zone
		(layers "F.Cu" "B.Cu" "In1.Cu" "In2.Cu" "In3.Cu" "In4.Cu" "In5.Cu" "In6.Cu"
			"In7.Cu" "In8.Cu" "In9.Cu" "In10.Cu" "In11.Cu" "In12.Cu" "In13.Cu" "In14.Cu"
			"In15.Cu" "In16.Cu"
		)
		(hatch none 0.5)
		(connect_pads
			(clearance 0)
		)
		(min_thickness 0.25)
		(keepout
			(tracks not_allowed)
			(vias allowed)
			(pads allowed)
			(copperpour not_allowed)
			(footprints allowed)
		)
		(placement
			(enabled no)
			(sheetname "")
		)
		(fill
			(thermal_gap 0.5)
			(thermal_bridge_width 0.5)
			(island_removal_mode 0)
		)
		(polygon
			(pts
				(arc
					(start 419.148006 -29.114242)
					(mid 419.605206 -29.571442)
					(end 420.062406 -29.114242)
				)
				(arc
					(start 420.062406 -28.250642)
					(mid 419.605206 -27.793442)
					(end 419.148006 -28.250642)
				)
			)
		)
	)
	(zone
		(layers "F.Cu" "B.Cu" "In1.Cu" "In2.Cu" "In3.Cu" "In4.Cu" "In5.Cu" "In6.Cu"
			"In7.Cu" "In8.Cu" "In9.Cu" "In10.Cu" "In11.Cu" "In12.Cu" "In13.Cu" "In14.Cu"
			"In15.Cu" "In16.Cu"
		)
		(hatch none 0.5)
		(connect_pads
			(clearance 0)
		)
		(min_thickness 0.25)
		(keepout
			(tracks not_allowed)
			(vias allowed)
			(pads allowed)
			(copperpour not_allowed)
			(footprints allowed)
		)
		(placement
			(enabled no)
			(sheetname "")
		)
		(fill
			(thermal_gap 0.5)
			(thermal_bridge_width 0.5)
			(island_removal_mode 0)
		)
		(polygon
			(pts
				(arc
					(start 425.680886 -404.828756)
					(mid 425.695765 -404.792835)
					(end 425.731686 -404.777956)
				)
				(arc
					(start 426.447966 -404.777956)
					(mid 426.483887 -404.792835)
					(end 426.498766 -404.828756)
				)
				(arc
					(start 426.498766 -407.251408)
					(mid 426.483887 -407.287329)
					(end 426.447966 -407.302208)
				)
				(arc
					(start 425.731686 -407.302208)
					(mid 425.695765 -407.287329)
					(end 425.680886 -407.251408)
				)
			)
		)
	)
	(zone
		(layers "F.Cu" "B.Cu" "In1.Cu" "In2.Cu" "In3.Cu" "In4.Cu" "In5.Cu" "In6.Cu"
			"In7.Cu" "In8.Cu" "In9.Cu" "In10.Cu" "In11.Cu" "In12.Cu" "In13.Cu" "In14.Cu"
			"In15.Cu" "In16.Cu"
		)
		(hatch none 0.5)
		(connect_pads
			(clearance 0)
		)
		(min_thickness 0.25)
		(keepout
			(tracks not_allowed)
			(vias allowed)
			(pads allowed)
			(copperpour not_allowed)
			(footprints allowed)
		)
		(placement
			(enabled no)
			(sheetname "")
		)
		(fill
			(thermal_gap 0.5)
			(thermal_bridge_width 0.5)
			(island_removal_mode 0)
		)
		(polygon
			(pts
				(arc
					(start 284.899862 -104.71277)
					(mid 284.442662 -104.25557)
					(end 283.985462 -104.71277)
				)
				(arc
					(start 283.985462 -105.57637)
					(mid 284.442662 -106.03357)
					(end 284.899862 -105.57637)
				)
			)
		)
	)
	(zone
		(layers "F.Cu" "B.Cu" "In1.Cu" "In2.Cu" "In3.Cu" "In4.Cu" "In5.Cu" "In6.Cu"
			"In7.Cu" "In8.Cu" "In9.Cu" "In10.Cu" "In11.Cu" "In12.Cu" "In13.Cu" "In14.Cu"
			"In15.Cu" "In16.Cu"
		)
		(hatch none 0.5)
		(connect_pads
			(clearance 0)
		)
		(min_thickness 0.25)
		(keepout
			(tracks not_allowed)
			(vias allowed)
			(pads allowed)
			(copperpour not_allowed)
			(footprints allowed)
		)
		(placement
			(enabled no)
			(sheetname "")
		)
		(fill
			(thermal_gap 0.5)
			(thermal_bridge_width 0.5)
			(island_removal_mode 0)
		)
		(polygon
			(pts
				(arc
					(start 128.701038 -369.928902)
					(mid 128.715917 -369.892981)
					(end 128.751838 -369.878102)
				)
				(arc
					(start 129.468118 -369.878102)
					(mid 129.504039 -369.892981)
					(end 129.518918 -369.928902)
				)
				(arc
					(start 129.518918 -372.351554)
					(mid 129.504039 -372.387475)
					(end 129.468118 -372.402354)
				)
				(arc
					(start 128.751838 -372.402354)
					(mid 128.715917 -372.387475)
					(end 128.701038 -372.351554)
				)
			)
		)
	)
	(zone
		(layers "F.Cu" "B.Cu" "In1.Cu" "In2.Cu" "In3.Cu" "In4.Cu" "In5.Cu" "In6.Cu"
			"In7.Cu" "In8.Cu" "In9.Cu" "In10.Cu" "In11.Cu" "In12.Cu" "In13.Cu" "In14.Cu"
			"In15.Cu" "In16.Cu"
		)
		(hatch none 0.5)
		(connect_pads
			(clearance 0)
		)
		(min_thickness 0.25)
		(keepout
			(tracks not_allowed)
			(vias allowed)
			(pads allowed)
			(copperpour not_allowed)
			(footprints allowed)
		)
		(placement
			(enabled no)
			(sheetname "")
		)
		(fill
			(thermal_gap 0.5)
			(thermal_bridge_width 0.5)
			(island_removal_mode 0)
		)
		(polygon
			(pts
				(arc
					(start 421.730932 -348.20479)
					(mid 421.349932 -348.58579)
					(end 421.730932 -348.96679)
				)
				(arc
					(start 422.594532 -348.96679)
					(mid 422.975532 -348.58579)
					(end 422.594532 -348.20479)
				)
			)
		)
	)
	(zone
		(layers "F.Cu" "B.Cu" "In1.Cu" "In2.Cu" "In3.Cu" "In4.Cu" "In5.Cu" "In6.Cu"
			"In7.Cu" "In8.Cu" "In9.Cu" "In10.Cu" "In11.Cu" "In12.Cu" "In13.Cu" "In14.Cu"
			"In15.Cu" "In16.Cu"
		)
		(hatch none 0.5)
		(connect_pads
			(clearance 0)
		)
		(min_thickness 0.25)
		(keepout
			(tracks not_allowed)
			(vias allowed)
			(pads allowed)
			(copperpour not_allowed)
			(footprints allowed)
		)
		(placement
			(enabled no)
			(sheetname "")
		)
		(fill
			(thermal_gap 0.5)
			(thermal_bridge_width 0.5)
			(island_removal_mode 0)
		)
		(polygon
			(pts
				(arc
					(start 312.994294 8.541512)
					(mid 312.613294 8.922512)
					(end 312.232294 8.541512)
				)
				(arc
					(start 312.232294 7.677912)
					(mid 312.613294 7.296912)
					(end 312.994294 7.677912)
				)
			)
		)
	)
	(zone
		(layers "F.Cu" "B.Cu" "In1.Cu" "In2.Cu" "In3.Cu" "In4.Cu" "In5.Cu" "In6.Cu"
			"In7.Cu" "In8.Cu" "In9.Cu" "In10.Cu" "In11.Cu" "In12.Cu" "In13.Cu" "In14.Cu"
			"In15.Cu" "In16.Cu"
		)
		(hatch none 0.5)
		(connect_pads
			(clearance 0)
		)
		(min_thickness 0.25)
		(keepout
			(tracks not_allowed)
			(vias allowed)
			(pads allowed)
			(copperpour not_allowed)
			(footprints allowed)
		)
		(placement
			(enabled no)
			(sheetname "")
		)
		(fill
			(thermal_gap 0.5)
			(thermal_bridge_width 0.5)
			(island_removal_mode 0)
		)
		(polygon
			(pts
				(arc
					(start 83.134962 -345.084146)
					(mid 82.753962 -345.465146)
					(end 83.134962 -345.846146)
				)
				(arc
					(start 83.998562 -345.846146)
					(mid 84.379562 -345.465146)
					(end 83.998562 -345.084146)
				)
			)
		)
	)
	(zone
		(layers "F.Cu" "B.Cu" "In1.Cu" "In2.Cu" "In3.Cu" "In4.Cu" "In5.Cu" "In6.Cu"
			"In7.Cu" "In8.Cu" "In9.Cu" "In10.Cu" "In11.Cu" "In12.Cu" "In13.Cu" "In14.Cu"
			"In15.Cu" "In16.Cu"
		)
		(hatch none 0.5)
		(connect_pads
			(clearance 0)
		)
		(min_thickness 0.25)
		(keepout
			(tracks not_allowed)
			(vias allowed)
			(pads allowed)
			(copperpour not_allowed)
			(footprints allowed)
		)
		(placement
			(enabled no)
			(sheetname "")
		)
		(fill
			(thermal_gap 0.5)
			(thermal_bridge_width 0.5)
			(island_removal_mode 0)
		)
		(polygon
			(pts
				(arc
					(start 293.680896 -374.928638)
					(mid 293.695775 -374.892717)
					(end 293.731696 -374.877838)
				)
				(arc
					(start 294.447976 -374.877838)
					(mid 294.483897 -374.892717)
					(end 294.498776 -374.928638)
				)
				(arc
					(start 294.498776 -377.35129)
					(mid 294.483897 -377.387211)
					(end 294.447976 -377.40209)
				)
				(arc
					(start 293.731696 -377.40209)
					(mid 293.695775 -377.387211)
					(end 293.680896 -377.35129)
				)
			)
		)
	)
	(zone
		(layers "F.Cu" "B.Cu" "In1.Cu" "In2.Cu" "In3.Cu" "In4.Cu" "In5.Cu" "In6.Cu"
			"In7.Cu" "In8.Cu" "In9.Cu" "In10.Cu" "In11.Cu" "In12.Cu" "In13.Cu" "In14.Cu"
			"In15.Cu" "In16.Cu"
		)
		(hatch none 0.5)
		(connect_pads
			(clearance 0)
		)
		(min_thickness 0.25)
		(keepout
			(tracks not_allowed)
			(vias allowed)
			(pads allowed)
			(copperpour not_allowed)
			(footprints allowed)
		)
		(placement
			(enabled no)
			(sheetname "")
		)
		(fill
			(thermal_gap 0.5)
			(thermal_bridge_width 0.5)
			(island_removal_mode 0)
		)
		(polygon
			(pts
				(arc
					(start 402.85416 -130.43281)
					(mid 402.39696 -129.97561)
					(end 401.93976 -130.43281)
				)
				(arc
					(start 401.93976 -131.29641)
					(mid 402.39696 -131.75361)
					(end 402.85416 -131.29641)
				)
			)
		)
	)
	(zone
		(layers "F.Cu" "B.Cu" "In1.Cu" "In2.Cu" "In3.Cu" "In4.Cu" "In5.Cu" "In6.Cu"
			"In7.Cu" "In8.Cu" "In9.Cu" "In10.Cu" "In11.Cu" "In12.Cu" "In13.Cu" "In14.Cu"
			"In15.Cu" "In16.Cu"
		)
		(hatch none 0.5)
		(connect_pads
			(clearance 0)
		)
		(min_thickness 0.25)
		(keepout
			(tracks not_allowed)
			(vias allowed)
			(pads allowed)
			(copperpour not_allowed)
			(footprints allowed)
		)
		(placement
			(enabled no)
			(sheetname "")
		)
		(fill
			(thermal_gap 0.5)
			(thermal_bridge_width 0.5)
			(island_removal_mode 0)
		)
		(polygon
			(pts
				(arc
					(start 27.501088 -381.628904)
					(mid 27.515967 -381.592983)
					(end 27.551888 -381.578104)
				)
				(arc
					(start 28.268168 -381.578104)
					(mid 28.304089 -381.592983)
					(end 28.318968 -381.628904)
				)
				(arc
					(start 28.318968 -384.051556)
					(mid 28.304089 -384.087477)
					(end 28.268168 -384.102356)
				)
				(arc
					(start 27.551888 -384.102356)
					(mid 27.515967 -384.087477)
					(end 27.501088 -384.051556)
				)
			)
		)
	)
	(zone
		(layers "F.Cu" "B.Cu" "In1.Cu" "In2.Cu" "In3.Cu" "In4.Cu" "In5.Cu" "In6.Cu"
			"In7.Cu" "In8.Cu" "In9.Cu" "In10.Cu" "In11.Cu" "In12.Cu" "In13.Cu" "In14.Cu"
			"In15.Cu" "In16.Cu"
		)
		(hatch none 0.5)
		(connect_pads
			(clearance 0)
		)
		(min_thickness 0.25)
		(keepout
			(tracks not_allowed)
			(vias allowed)
			(pads allowed)
			(copperpour not_allowed)
			(footprints allowed)
		)
		(placement
			(enabled no)
			(sheetname "")
		)
		(fill
			(thermal_gap 0.5)
			(thermal_bridge_width 0.5)
			(island_removal_mode 0)
		)
		(polygon
			(pts
				(arc
					(start 383.62382 -354.351082)
					(mid 383.24282 -354.732082)
					(end 383.62382 -355.113082)
				)
				(arc
					(start 384.48742 -355.113082)
					(mid 384.86842 -354.732082)
					(end 384.48742 -354.351082)
				)
			)
		)
	)
	(zone
		(layers "F.Cu" "B.Cu" "In1.Cu" "In2.Cu" "In3.Cu" "In4.Cu" "In5.Cu" "In6.Cu"
			"In7.Cu" "In8.Cu" "In9.Cu" "In10.Cu" "In11.Cu" "In12.Cu" "In13.Cu" "In14.Cu"
			"In15.Cu" "In16.Cu"
		)
		(hatch none 0.5)
		(connect_pads
			(clearance 0)
		)
		(min_thickness 0.25)
		(keepout
			(tracks not_allowed)
			(vias allowed)
			(pads allowed)
			(copperpour not_allowed)
			(footprints allowed)
		)
		(placement
			(enabled no)
			(sheetname "")
		)
		(fill
			(thermal_gap 0.5)
			(thermal_bridge_width 0.5)
			(island_removal_mode 0)
		)
		(polygon
			(pts
				(arc
					(start 385.765294 11.114532)
					(mid 385.384294 11.495532)
					(end 385.003294 11.114532)
				)
				(arc
					(start 385.003294 10.250932)
					(mid 385.384294 9.869932)
					(end 385.765294 10.250932)
				)
			)
		)
	)
	(zone
		(layers "F.Cu" "B.Cu" "In1.Cu" "In2.Cu" "In3.Cu" "In4.Cu" "In5.Cu" "In6.Cu"
			"In7.Cu" "In8.Cu" "In9.Cu" "In10.Cu" "In11.Cu" "In12.Cu" "In13.Cu" "In14.Cu"
			"In15.Cu" "In16.Cu"
		)
		(hatch none 0.5)
		(connect_pads
			(clearance 0)
		)
		(min_thickness 0.25)
		(keepout
			(tracks not_allowed)
			(vias allowed)
			(pads allowed)
			(copperpour not_allowed)
			(footprints allowed)
		)
		(placement
			(enabled no)
			(sheetname "")
		)
		(fill
			(thermal_gap 0.5)
			(thermal_bridge_width 0.5)
			(island_removal_mode 0)
		)
		(polygon
			(pts
				(arc
					(start 298.986702 -354.351082)
					(mid 298.605702 -354.732082)
					(end 298.986702 -355.113082)
				)
				(arc
					(start 299.850302 -355.113082)
					(mid 300.231302 -354.732082)
					(end 299.850302 -354.351082)
				)
			)
		)
	)
	(zone
		(layers "F.Cu" "B.Cu" "In1.Cu" "In2.Cu" "In3.Cu" "In4.Cu" "In5.Cu" "In6.Cu"
			"In7.Cu" "In8.Cu" "In9.Cu" "In10.Cu" "In11.Cu" "In12.Cu" "In13.Cu" "In14.Cu"
			"In15.Cu" "In16.Cu"
		)
		(hatch none 0.5)
		(connect_pads
			(clearance 0)
		)
		(min_thickness 0.25)
		(keepout
			(tracks not_allowed)
			(vias allowed)
			(pads allowed)
			(copperpour not_allowed)
			(footprints allowed)
		)
		(placement
			(enabled no)
			(sheetname "")
		)
		(fill
			(thermal_gap 0.5)
			(thermal_bridge_width 0.5)
			(island_removal_mode 0)
		)
		(polygon
			(pts
				(arc
					(start 419.08095 -403.728682)
					(mid 419.095829 -403.692761)
					(end 419.13175 -403.677882)
				)
				(arc
					(start 419.84803 -403.677882)
					(mid 419.883951 -403.692761)
					(end 419.89883 -403.728682)
				)
				(arc
					(start 419.89883 -406.151334)
					(mid 419.883951 -406.187255)
					(end 419.84803 -406.202134)
				)
				(arc
					(start 419.13175 -406.202134)
					(mid 419.095829 -406.187255)
					(end 419.08095 -406.151334)
				)
			)
		)
	)
	(zone
		(layers "F.Cu" "B.Cu" "In1.Cu" "In2.Cu" "In3.Cu" "In4.Cu" "In5.Cu" "In6.Cu"
			"In7.Cu" "In8.Cu" "In9.Cu" "In10.Cu" "In11.Cu" "In12.Cu" "In13.Cu" "In14.Cu"
			"In15.Cu" "In16.Cu"
		)
		(hatch none 0.5)
		(connect_pads
			(clearance 0)
		)
		(min_thickness 0.25)
		(keepout
			(tracks not_allowed)
			(vias allowed)
			(pads allowed)
			(copperpour not_allowed)
			(footprints allowed)
		)
		(placement
			(enabled no)
			(sheetname "")
		)
		(fill
			(thermal_gap 0.5)
			(thermal_bridge_width 0.5)
			(island_removal_mode 0)
		)
		(polygon
			(pts
				(arc
					(start 68.52412 -27.342846)
					(mid 68.98132 -27.800046)
					(end 69.43852 -27.342846)
				)
				(arc
					(start 69.43852 -26.479246)
					(mid 68.98132 -26.022046)
					(end 68.52412 -26.479246)
				)
			)
		)
	)
	(zone
		(layers "F.Cu" "B.Cu" "In1.Cu" "In2.Cu" "In3.Cu" "In4.Cu" "In5.Cu" "In6.Cu"
			"In7.Cu" "In8.Cu" "In9.Cu" "In10.Cu" "In11.Cu" "In12.Cu" "In13.Cu" "In14.Cu"
			"In15.Cu" "In16.Cu"
		)
		(hatch none 0.5)
		(connect_pads
			(clearance 0)
		)
		(min_thickness 0.25)
		(keepout
			(tracks not_allowed)
			(vias allowed)
			(pads allowed)
			(copperpour not_allowed)
			(footprints allowed)
		)
		(placement
			(enabled no)
			(sheetname "")
		)
		(fill
			(thermal_gap 0.5)
			(thermal_bridge_width 0.5)
			(island_removal_mode 0)
		)
		(polygon
			(pts
				(arc
					(start 80.026002 -357.37673)
					(mid 79.645002 -357.75773)
					(end 80.026002 -358.13873)
				)
				(arc
					(start 80.889602 -358.13873)
					(mid 81.270602 -357.75773)
					(end 80.889602 -357.37673)
				)
			)
		)
	)
	(zone
		(layers "F.Cu" "B.Cu" "In1.Cu" "In2.Cu" "In3.Cu" "In4.Cu" "In5.Cu" "In6.Cu"
			"In7.Cu" "In8.Cu" "In9.Cu" "In10.Cu" "In11.Cu" "In12.Cu" "In13.Cu" "In14.Cu"
			"In15.Cu" "In16.Cu"
		)
		(hatch none 0.5)
		(connect_pads
			(clearance 0)
		)
		(min_thickness 0.25)
		(keepout
			(tracks not_allowed)
			(vias allowed)
			(pads allowed)
			(copperpour not_allowed)
			(footprints allowed)
		)
		(placement
			(enabled no)
			(sheetname "")
		)
		(fill
			(thermal_gap 0.5)
			(thermal_bridge_width 0.5)
			(island_removal_mode 0)
		)
		(polygon
			(pts
				(arc
					(start 19.332448 -342.058498)
					(mid 18.951448 -342.439498)
					(end 19.332448 -342.820498)
				)
				(arc
					(start 20.196048 -342.820498)
					(mid 20.577048 -342.439498)
					(end 20.196048 -342.058498)
				)
			)
		)
	)
	(zone
		(layers "F.Cu" "B.Cu" "In1.Cu" "In2.Cu" "In3.Cu" "In4.Cu" "In5.Cu" "In6.Cu"
			"In7.Cu" "In8.Cu" "In9.Cu" "In10.Cu" "In11.Cu" "In12.Cu" "In13.Cu" "In14.Cu"
			"In15.Cu" "In16.Cu"
		)
		(hatch none 0.5)
		(connect_pads
			(clearance 0)
		)
		(min_thickness 0.25)
		(keepout
			(tracks not_allowed)
			(vias allowed)
			(pads allowed)
			(copperpour not_allowed)
			(footprints allowed)
		)
		(placement
			(enabled no)
			(sheetname "")
		)
		(fill
			(thermal_gap 0.5)
			(thermal_bridge_width 0.5)
			(island_removal_mode 0)
		)
		(polygon
			(pts
				(arc
					(start 40.70096 -407.628852)
					(mid 40.715839 -407.592931)
					(end 40.75176 -407.578052)
				)
				(arc
					(start 41.46804 -407.578052)
					(mid 41.503961 -407.592931)
					(end 41.51884 -407.628852)
				)
				(arc
					(start 41.51884 -410.051504)
					(mid 41.503961 -410.087425)
					(end 41.46804 -410.102304)
				)
				(arc
					(start 40.75176 -410.102304)
					(mid 40.715839 -410.087425)
					(end 40.70096 -410.051504)
				)
			)
		)
	)
	(zone
		(layers "F.Cu" "B.Cu" "In1.Cu" "In2.Cu" "In3.Cu" "In4.Cu" "In5.Cu" "In6.Cu"
			"In7.Cu" "In8.Cu" "In9.Cu" "In10.Cu" "In11.Cu" "In12.Cu" "In13.Cu" "In14.Cu"
			"In15.Cu" "In16.Cu"
		)
		(hatch none 0.5)
		(connect_pads
			(clearance 0)
		)
		(min_thickness 0.25)
		(keepout
			(tracks not_allowed)
			(vias allowed)
			(pads allowed)
			(copperpour not_allowed)
			(footprints allowed)
		)
		(placement
			(enabled no)
			(sheetname "")
		)
		(fill
			(thermal_gap 0.5)
			(thermal_bridge_width 0.5)
			(island_removal_mode 0)
		)
		(polygon
			(pts
				(arc
					(start 170.654218 -99.31273)
					(mid 170.197018 -98.85553)
					(end 169.739818 -99.31273)
				)
				(arc
					(start 169.739818 -100.17633)
					(mid 170.197018 -100.63353)
					(end 170.654218 -100.17633)
				)
			)
		)
	)
	(zone
		(layers "F.Cu" "B.Cu" "In1.Cu" "In2.Cu" "In3.Cu" "In4.Cu" "In5.Cu" "In6.Cu"
			"In7.Cu" "In8.Cu" "In9.Cu" "In10.Cu" "In11.Cu" "In12.Cu" "In13.Cu" "In14.Cu"
			"In15.Cu" "In16.Cu"
		)
		(hatch none 0.5)
		(connect_pads
			(clearance 0)
		)
		(min_thickness 0.25)
		(keepout
			(tracks not_allowed)
			(vias allowed)
			(pads allowed)
			(copperpour not_allowed)
			(footprints allowed)
		)
		(placement
			(enabled no)
			(sheetname "")
		)
		(fill
			(thermal_gap 0.5)
			(thermal_bridge_width 0.5)
			(island_removal_mode 0)
		)
		(polygon
			(pts
				(xy 66.524886 -394.327634)
				(arc
					(start 66.524886 -417.533836)
					(mid 66.502568 -417.587718)
					(end 66.448686 -417.610036)
				)
				(arc
					(start 53.151024 -417.610036)
					(mid 53.097142 -417.587718)
					(end 53.074824 -417.533836)
				)
				(arc
					(start 53.074824 -394.356082)
					(mid 53.097142 -394.3022)
					(end 53.151024 -394.279882)
				)
				(xy 66.477134 -394.279882)
			)
		)
	)
	(zone
		(layers "F.Cu" "B.Cu" "In1.Cu" "In2.Cu" "In3.Cu" "In4.Cu" "In5.Cu" "In6.Cu"
			"In7.Cu" "In8.Cu" "In9.Cu" "In10.Cu" "In11.Cu" "In12.Cu" "In13.Cu" "In14.Cu"
			"In15.Cu" "In16.Cu"
		)
		(hatch none 0.5)
		(connect_pads
			(clearance 0)
		)
		(min_thickness 0.25)
		(keepout
			(tracks not_allowed)
			(vias allowed)
			(pads allowed)
			(copperpour not_allowed)
			(footprints allowed)
		)
		(placement
			(enabled no)
			(sheetname "")
		)
		(fill
			(thermal_gap 0.5)
			(thermal_bridge_width 0.5)
			(island_removal_mode 0)
		)
		(polygon
			(pts
				(arc
					(start 237.62335 -148.827744)
					(mid 237.16615 -148.370544)
					(end 236.70895 -148.827744)
				)
				(arc
					(start 236.70895 -149.691344)
					(mid 237.16615 -150.148544)
					(end 237.62335 -149.691344)
				)
			)
		)
	)
	(zone
		(layers "F.Cu" "B.Cu" "In1.Cu" "In2.Cu" "In3.Cu" "In4.Cu" "In5.Cu" "In6.Cu"
			"In7.Cu" "In8.Cu" "In9.Cu" "In10.Cu" "In11.Cu" "In12.Cu" "In13.Cu" "In14.Cu"
			"In15.Cu" "In16.Cu"
		)
		(hatch none 0.5)
		(connect_pads
			(clearance 0)
		)
		(min_thickness 0.25)
		(keepout
			(tracks not_allowed)
			(vias allowed)
			(pads allowed)
			(copperpour not_allowed)
			(footprints allowed)
		)
		(placement
			(enabled no)
			(sheetname "")
		)
		(fill
			(thermal_gap 0.5)
			(thermal_bridge_width 0.5)
			(island_removal_mode 0)
		)
		(polygon
			(pts
				(arc
					(start 432.01717 -145.285714)
					(mid 432.47437 -145.742914)
					(end 432.93157 -145.285714)
				)
				(arc
					(start 432.93157 -144.422114)
					(mid 432.47437 -143.964914)
					(end 432.01717 -144.422114)
				)
			)
		)
	)
	(zone
		(layers "F.Cu" "B.Cu" "In1.Cu" "In2.Cu" "In3.Cu" "In4.Cu" "In5.Cu" "In6.Cu"
			"In7.Cu" "In8.Cu" "In9.Cu" "In10.Cu" "In11.Cu" "In12.Cu" "In13.Cu" "In14.Cu"
			"In15.Cu" "In16.Cu"
		)
		(hatch none 0.5)
		(connect_pads
			(clearance 0)
		)
		(min_thickness 0.25)
		(keepout
			(tracks not_allowed)
			(vias allowed)
			(pads allowed)
			(copperpour not_allowed)
			(footprints allowed)
		)
		(placement
			(enabled no)
			(sheetname "")
		)
		(fill
			(thermal_gap 0.5)
			(thermal_bridge_width 0.5)
			(island_removal_mode 0)
		)
		(polygon
			(pts
				(arc
					(start 29.700982 -378.828554)
					(mid 29.715861 -378.792633)
					(end 29.751782 -378.777754)
				)
				(arc
					(start 30.468062 -378.777754)
					(mid 30.503983 -378.792633)
					(end 30.518862 -378.828554)
				)
				(arc
					(start 30.518862 -381.251206)
					(mid 30.503983 -381.287127)
					(end 30.468062 -381.302006)
				)
				(arc
					(start 29.751782 -381.302006)
					(mid 29.715861 -381.287127)
					(end 29.700982 -381.251206)
				)
			)
		)
	)
	(zone
		(layers "F.Cu" "B.Cu" "In1.Cu" "In2.Cu" "In3.Cu" "In4.Cu" "In5.Cu" "In6.Cu"
			"In7.Cu" "In8.Cu" "In9.Cu" "In10.Cu" "In11.Cu" "In12.Cu" "In13.Cu" "In14.Cu"
			"In15.Cu" "In16.Cu"
		)
		(hatch none 0.5)
		(connect_pads
			(clearance 0)
		)
		(min_thickness 0.25)
		(keepout
			(tracks not_allowed)
			(vias allowed)
			(pads allowed)
			(copperpour not_allowed)
			(footprints allowed)
		)
		(placement
			(enabled no)
			(sheetname "")
		)
		(fill
			(thermal_gap 0.5)
			(thermal_bridge_width 0.5)
			(island_removal_mode 0)
		)
		(polygon
			(pts
				(arc
					(start 271.006062 -348.20479)
					(mid 270.625062 -348.58579)
					(end 271.006062 -348.96679)
				)
				(arc
					(start 271.869662 -348.96679)
					(mid 272.250662 -348.58579)
					(end 271.869662 -348.20479)
				)
			)
		)
	)
	(zone
		(layers "F.Cu" "B.Cu" "In1.Cu" "In2.Cu" "In3.Cu" "In4.Cu" "In5.Cu" "In6.Cu"
			"In7.Cu" "In8.Cu" "In9.Cu" "In10.Cu" "In11.Cu" "In12.Cu" "In13.Cu" "In14.Cu"
			"In15.Cu" "In16.Cu"
		)
		(hatch none 0.5)
		(connect_pads
			(clearance 0)
		)
		(min_thickness 0.25)
		(keepout
			(tracks not_allowed)
			(vias allowed)
			(pads allowed)
			(copperpour not_allowed)
			(footprints allowed)
		)
		(placement
			(enabled no)
			(sheetname "")
		)
		(fill
			(thermal_gap 0.5)
			(thermal_bridge_width 0.5)
			(island_removal_mode 0)
		)
		(polygon
			(pts
				(arc
					(start 343.592404 -342.058498)
					(mid 343.211404 -342.439498)
					(end 343.592404 -342.820498)
				)
				(arc
					(start 344.456004 -342.820498)
					(mid 344.837004 -342.439498)
					(end 344.456004 -342.058498)
				)
			)
		)
	)
	(zone
		(layers "F.Cu" "B.Cu" "In1.Cu" "In2.Cu" "In3.Cu" "In4.Cu" "In5.Cu" "In6.Cu"
			"In7.Cu" "In8.Cu" "In9.Cu" "In10.Cu" "In11.Cu" "In12.Cu" "In13.Cu" "In14.Cu"
			"In15.Cu" "In16.Cu"
		)
		(hatch none 0.5)
		(connect_pads
			(clearance 0)
		)
		(min_thickness 0.25)
		(keepout
			(tracks not_allowed)
			(vias allowed)
			(pads allowed)
			(copperpour not_allowed)
			(footprints allowed)
		)
		(placement
			(enabled no)
			(sheetname "")
		)
		(fill
			(thermal_gap 0.5)
			(thermal_bridge_width 0.5)
			(island_removal_mode 0)
		)
		(polygon
			(pts
				(arc
					(start 54.55412 -106.512614)
					(mid 54.09692 -106.055414)
					(end 53.63972 -106.512614)
				)
				(arc
					(start 53.63972 -107.376214)
					(mid 54.09692 -107.833414)
					(end 54.55412 -107.376214)
				)
			)
		)
	)
	(zone
		(layers "F.Cu" "B.Cu" "In1.Cu" "In2.Cu" "In3.Cu" "In4.Cu" "In5.Cu" "In6.Cu"
			"In7.Cu" "In8.Cu" "In9.Cu" "In10.Cu" "In11.Cu" "In12.Cu" "In13.Cu" "In14.Cu"
			"In15.Cu" "In16.Cu"
		)
		(hatch none 0.5)
		(connect_pads
			(clearance 0)
		)
		(min_thickness 0.25)
		(keepout
			(tracks not_allowed)
			(vias allowed)
			(pads allowed)
			(copperpour not_allowed)
			(footprints allowed)
		)
		(placement
			(enabled no)
			(sheetname "")
		)
		(fill
			(thermal_gap 0.5)
			(thermal_bridge_width 0.5)
			(island_removal_mode 0)
		)
		(polygon
			(pts
				(arc
					(start 381.680974 -382.728724)
					(mid 381.695853 -382.692803)
					(end 381.731774 -382.677924)
				)
				(arc
					(start 382.448054 -382.677924)
					(mid 382.483975 -382.692803)
					(end 382.498854 -382.728724)
				)
				(arc
					(start 382.498854 -385.151376)
					(mid 382.483975 -385.187297)
					(end 382.448054 -385.202176)
				)
				(arc
					(start 381.731774 -385.202176)
					(mid 381.695853 -385.187297)
					(end 381.680974 -385.151376)
				)
			)
		)
	)
	(zone
		(layers "F.Cu" "B.Cu" "In1.Cu" "In2.Cu" "In3.Cu" "In4.Cu" "In5.Cu" "In6.Cu"
			"In7.Cu" "In8.Cu" "In9.Cu" "In10.Cu" "In11.Cu" "In12.Cu" "In13.Cu" "In14.Cu"
			"In15.Cu" "In16.Cu"
		)
		(hatch none 0.5)
		(connect_pads
			(clearance 0)
		)
		(min_thickness 0.25)
		(keepout
			(tracks not_allowed)
			(vias allowed)
			(pads allowed)
			(copperpour not_allowed)
			(footprints allowed)
		)
		(placement
			(enabled no)
			(sheetname "")
		)
		(fill
			(thermal_gap 0.5)
			(thermal_bridge_width 0.5)
			(island_removal_mode 0)
		)
		(polygon
			(pts
				(arc
					(start 166.101014 -371.028722)
					(mid 166.115893 -370.992801)
					(end 166.151814 -370.977922)
				)
				(arc
					(start 166.868094 -370.977922)
					(mid 166.904015 -370.992801)
					(end 166.918894 -371.028722)
				)
				(arc
					(start 166.918894 -373.451374)
					(mid 166.904015 -373.487295)
					(end 166.868094 -373.502174)
				)
				(arc
					(start 166.151814 -373.502174)
					(mid 166.115893 -373.487295)
					(end 166.101014 -373.451374)
				)
			)
		)
	)
	(zone
		(layers "F.Cu" "B.Cu" "In1.Cu" "In2.Cu" "In3.Cu" "In4.Cu" "In5.Cu" "In6.Cu"
			"In7.Cu" "In8.Cu" "In9.Cu" "In10.Cu" "In11.Cu" "In12.Cu" "In13.Cu" "In14.Cu"
			"In15.Cu" "In16.Cu"
		)
		(hatch none 0.5)
		(connect_pads
			(clearance 0)
		)
		(min_thickness 0.25)
		(keepout
			(tracks not_allowed)
			(vias allowed)
			(pads allowed)
			(copperpour not_allowed)
			(footprints allowed)
		)
		(placement
			(enabled no)
			(sheetname "")
		)
		(fill
			(thermal_gap 0.5)
			(thermal_bridge_width 0.5)
			(island_removal_mode 0)
		)
		(polygon
			(pts
				(arc
					(start 161.700972 -397.028924)
					(mid 161.715851 -396.993003)
					(end 161.751772 -396.978124)
				)
				(arc
					(start 162.468052 -396.978124)
					(mid 162.503973 -396.993003)
					(end 162.518852 -397.028924)
				)
				(arc
					(start 162.518852 -399.451576)
					(mid 162.503973 -399.487497)
					(end 162.468052 -399.502376)
				)
				(arc
					(start 161.751772 -399.502376)
					(mid 161.715851 -399.487497)
					(end 161.700972 -399.451576)
				)
			)
		)
	)
	(zone
		(layers "F.Cu" "B.Cu" "In1.Cu" "In2.Cu" "In3.Cu" "In4.Cu" "In5.Cu" "In6.Cu"
			"In7.Cu" "In8.Cu" "In9.Cu" "In10.Cu" "In11.Cu" "In12.Cu" "In13.Cu" "In14.Cu"
			"In15.Cu" "In16.Cu"
		)
		(hatch none 0.5)
		(connect_pads
			(clearance 0)
		)
		(min_thickness 0.25)
		(keepout
			(tracks not_allowed)
			(vias allowed)
			(pads allowed)
			(copperpour not_allowed)
			(footprints allowed)
		)
		(placement
			(enabled no)
			(sheetname "")
		)
		(fill
			(thermal_gap 0.5)
			(thermal_bridge_width 0.5)
			(island_removal_mode 0)
		)
		(polygon
			(pts
				(arc
					(start 132.367274 -188.689234)
					(mid 132.824474 -188.232034)
					(end 132.367274 -187.774834)
				)
				(arc
					(start 131.503674 -187.774834)
					(mid 131.046474 -188.232034)
					(end 131.503674 -188.689234)
				)
			)
		)
	)
	(zone
		(layers "F.Cu" "B.Cu" "In1.Cu" "In2.Cu" "In3.Cu" "In4.Cu" "In5.Cu" "In6.Cu"
			"In7.Cu" "In8.Cu" "In9.Cu" "In10.Cu" "In11.Cu" "In12.Cu" "In13.Cu" "In14.Cu"
			"In15.Cu" "In16.Cu"
		)
		(hatch none 0.5)
		(connect_pads
			(clearance 0)
		)
		(min_thickness 0.25)
		(keepout
			(tracks not_allowed)
			(vias allowed)
			(pads allowed)
			(copperpour not_allowed)
			(footprints allowed)
		)
		(placement
			(enabled no)
			(sheetname "")
		)
		(fill
			(thermal_gap 0.5)
			(thermal_bridge_width 0.5)
			(island_removal_mode 0)
		)
		(polygon
			(pts
				(arc
					(start 335.481168 -373.828818)
					(mid 335.496047 -373.792897)
					(end 335.531968 -373.778018)
				)
				(arc
					(start 336.248248 -373.778018)
					(mid 336.284169 -373.792897)
					(end 336.299048 -373.828818)
				)
				(arc
					(start 336.299048 -376.25147)
					(mid 336.284169 -376.287391)
					(end 336.248248 -376.30227)
				)
				(arc
					(start 335.531968 -376.30227)
					(mid 335.496047 -376.287391)
					(end 335.481168 -376.25147)
				)
			)
		)
	)
	(zone
		(layers "F.Cu" "B.Cu" "In1.Cu" "In2.Cu" "In3.Cu" "In4.Cu" "In5.Cu" "In6.Cu"
			"In7.Cu" "In8.Cu" "In9.Cu" "In10.Cu" "In11.Cu" "In12.Cu" "In13.Cu" "In14.Cu"
			"In15.Cu" "In16.Cu"
		)
		(hatch none 0.5)
		(connect_pads
			(clearance 0)
		)
		(min_thickness 0.25)
		(keepout
			(tracks not_allowed)
			(vias allowed)
			(pads allowed)
			(copperpour not_allowed)
			(footprints allowed)
		)
		(placement
			(enabled no)
			(sheetname "")
		)
		(fill
			(thermal_gap 0.5)
			(thermal_bridge_width 0.5)
			(island_removal_mode 0)
		)
		(polygon
			(pts
				(arc
					(start 321.829684 -342.058498)
					(mid 321.448684 -342.439498)
					(end 321.829684 -342.820498)
				)
				(arc
					(start 322.693284 -342.820498)
					(mid 323.074284 -342.439498)
					(end 322.693284 -342.058498)
				)
			)
		)
	)
	(zone
		(layers "F.Cu" "B.Cu" "In1.Cu" "In2.Cu" "In3.Cu" "In4.Cu" "In5.Cu" "In6.Cu"
			"In7.Cu" "In8.Cu" "In9.Cu" "In10.Cu" "In11.Cu" "In12.Cu" "In13.Cu" "In14.Cu"
			"In15.Cu" "In16.Cu"
		)
		(hatch none 0.5)
		(connect_pads
			(clearance 0)
		)
		(min_thickness 0.25)
		(keepout
			(tracks not_allowed)
			(vias allowed)
			(pads allowed)
			(copperpour not_allowed)
			(footprints allowed)
		)
		(placement
			(enabled no)
			(sheetname "")
		)
		(fill
			(thermal_gap 0.5)
			(thermal_bridge_width 0.5)
			(island_removal_mode 0)
		)
		(polygon
			(pts
				(arc
					(start 114.971068 -351.230438)
					(mid 114.590068 -351.611438)
					(end 114.971068 -351.992438)
				)
				(arc
					(start 115.834668 -351.992438)
					(mid 116.215668 -351.611438)
					(end 115.834668 -351.230438)
				)
			)
		)
	)
	(zone
		(layers "F.Cu" "B.Cu" "In1.Cu" "In2.Cu" "In3.Cu" "In4.Cu" "In5.Cu" "In6.Cu"
			"In7.Cu" "In8.Cu" "In9.Cu" "In10.Cu" "In11.Cu" "In12.Cu" "In13.Cu" "In14.Cu"
			"In15.Cu" "In16.Cu"
		)
		(hatch none 0.5)
		(connect_pads
			(clearance 0)
		)
		(min_thickness 0.25)
		(keepout
			(tracks not_allowed)
			(vias allowed)
			(pads allowed)
			(copperpour not_allowed)
			(footprints allowed)
		)
		(placement
			(enabled no)
			(sheetname "")
		)
		(fill
			(thermal_gap 0.5)
			(thermal_bridge_width 0.5)
			(island_removal_mode 0)
		)
		(polygon
			(pts
				(arc
					(start 230.098346 -76.338938)
					(mid 229.641146 -76.796138)
					(end 230.098346 -77.253338)
				)
				(arc
					(start 230.961946 -77.253338)
					(mid 231.419146 -76.796138)
					(end 230.961946 -76.338938)
				)
			)
		)
	)
	(zone
		(layers "F.Cu" "B.Cu" "In1.Cu" "In2.Cu" "In3.Cu" "In4.Cu" "In5.Cu" "In6.Cu"
			"In7.Cu" "In8.Cu" "In9.Cu" "In10.Cu" "In11.Cu" "In12.Cu" "In13.Cu" "In14.Cu"
			"In15.Cu" "In16.Cu"
		)
		(hatch none 0.5)
		(connect_pads
			(clearance 0)
		)
		(min_thickness 0.25)
		(keepout
			(tracks not_allowed)
			(vias allowed)
			(pads allowed)
			(copperpour not_allowed)
			(footprints allowed)
		)
		(placement
			(enabled no)
			(sheetname "")
		)
		(fill
			(thermal_gap 0.5)
			(thermal_bridge_width 0.5)
			(island_removal_mode 0)
		)
		(polygon
			(pts
				(arc
					(start 334.265524 -348.20479)
					(mid 333.884524 -348.58579)
					(end 334.265524 -348.96679)
				)
				(arc
					(start 335.129124 -348.96679)
					(mid 335.510124 -348.58579)
					(end 335.129124 -348.20479)
				)
			)
		)
	)
	(zone
		(layers "F.Cu" "B.Cu" "In1.Cu" "In2.Cu" "In3.Cu" "In4.Cu" "In5.Cu" "In6.Cu"
			"In7.Cu" "In8.Cu" "In9.Cu" "In10.Cu" "In11.Cu" "In12.Cu" "In13.Cu" "In14.Cu"
			"In15.Cu" "In16.Cu"
		)
		(hatch none 0.5)
		(connect_pads
			(clearance 0)
		)
		(min_thickness 0.25)
		(keepout
			(tracks not_allowed)
			(vias allowed)
			(pads allowed)
			(copperpour not_allowed)
			(footprints allowed)
		)
		(placement
			(enabled no)
			(sheetname "")
		)
		(fill
			(thermal_gap 0.5)
			(thermal_bridge_width 0.5)
			(island_removal_mode 0)
		)
		(polygon
			(pts
				(arc
					(start 114.971068 -354.351082)
					(mid 114.590068 -354.732082)
					(end 114.971068 -355.113082)
				)
				(arc
					(start 115.834668 -355.113082)
					(mid 116.215668 -354.732082)
					(end 115.834668 -354.351082)
				)
			)
		)
	)
	(zone
		(layers "F.Cu" "B.Cu" "In1.Cu" "In2.Cu" "In3.Cu" "In4.Cu" "In5.Cu" "In6.Cu"
			"In7.Cu" "In8.Cu" "In9.Cu" "In10.Cu" "In11.Cu" "In12.Cu" "In13.Cu" "In14.Cu"
			"In15.Cu" "In16.Cu"
		)
		(hatch none 0.5)
		(connect_pads
			(clearance 0)
		)
		(min_thickness 0.25)
		(keepout
			(tracks not_allowed)
			(vias allowed)
			(pads allowed)
			(copperpour not_allowed)
			(footprints allowed)
		)
		(placement
			(enabled no)
			(sheetname "")
		)
		(fill
			(thermal_gap 0.5)
			(thermal_bridge_width 0.5)
			(island_removal_mode 0)
		)
		(polygon
			(pts
				(arc
					(start 130.515868 -351.230438)
					(mid 130.134868 -351.611438)
					(end 130.515868 -351.992438)
				)
				(arc
					(start 131.379468 -351.992438)
					(mid 131.760468 -351.611438)
					(end 131.379468 -351.230438)
				)
			)
		)
	)
	(zone
		(layers "F.Cu" "B.Cu" "In1.Cu" "In2.Cu" "In3.Cu" "In4.Cu" "In5.Cu" "In6.Cu"
			"In7.Cu" "In8.Cu" "In9.Cu" "In10.Cu" "In11.Cu" "In12.Cu" "In13.Cu" "In14.Cu"
			"In15.Cu" "In16.Cu"
		)
		(hatch none 0.5)
		(connect_pads
			(clearance 0)
		)
		(min_thickness 0.25)
		(keepout
			(tracks not_allowed)
			(vias allowed)
			(pads allowed)
			(copperpour not_allowed)
			(footprints allowed)
		)
		(placement
			(enabled no)
			(sheetname "")
		)
		(fill
			(thermal_gap 0.5)
			(thermal_bridge_width 0.5)
			(island_removal_mode 0)
		)
		(polygon
			(pts
				(arc
					(start 86.90102 -408.728672)
					(mid 86.915899 -408.692751)
					(end 86.95182 -408.677872)
				)
				(arc
					(start 87.6681 -408.677872)
					(mid 87.704021 -408.692751)
					(end 87.7189 -408.728672)
				)
				(arc
					(start 87.7189 -411.151324)
					(mid 87.704021 -411.187245)
					(end 87.6681 -411.202124)
				)
				(arc
					(start 86.95182 -411.202124)
					(mid 86.915899 -411.187245)
					(end 86.90102 -411.151324)
				)
			)
		)
	)
	(zone
		(layers "F.Cu" "B.Cu" "In1.Cu" "In2.Cu" "In3.Cu" "In4.Cu" "In5.Cu" "In6.Cu"
			"In7.Cu" "In8.Cu" "In9.Cu" "In10.Cu" "In11.Cu" "In12.Cu" "In13.Cu" "In14.Cu"
			"In15.Cu" "In16.Cu"
		)
		(hatch none 0.5)
		(connect_pads
			(clearance 0)
		)
		(min_thickness 0.25)
		(keepout
			(tracks not_allowed)
			(vias allowed)
			(pads allowed)
			(copperpour not_allowed)
			(footprints allowed)
		)
		(placement
			(enabled no)
			(sheetname "")
		)
		(fill
			(thermal_gap 0.5)
			(thermal_bridge_width 0.5)
			(island_removal_mode 0)
		)
		(polygon
			(pts
				(arc
					(start 421.280844 -378.828554)
					(mid 421.295723 -378.792633)
					(end 421.331644 -378.777754)
				)
				(arc
					(start 422.047924 -378.777754)
					(mid 422.083845 -378.792633)
					(end 422.098724 -378.828554)
				)
				(arc
					(start 422.098724 -381.251206)
					(mid 422.083845 -381.287127)
					(end 422.047924 -381.302006)
				)
				(arc
					(start 421.331644 -381.302006)
					(mid 421.295723 -381.287127)
					(end 421.280844 -381.251206)
				)
			)
		)
	)
	(zone
		(layers "F.Cu" "B.Cu" "In1.Cu" "In2.Cu" "In3.Cu" "In4.Cu" "In5.Cu" "In6.Cu"
			"In7.Cu" "In8.Cu" "In9.Cu" "In10.Cu" "In11.Cu" "In12.Cu" "In13.Cu" "In14.Cu"
			"In15.Cu" "In16.Cu"
		)
		(hatch none 0.5)
		(connect_pads
			(clearance 0)
		)
		(min_thickness 0.25)
		(keepout
			(tracks not_allowed)
			(vias allowed)
			(pads allowed)
			(copperpour not_allowed)
			(footprints allowed)
		)
		(placement
			(enabled no)
			(sheetname "")
		)
		(fill
			(thermal_gap 0.5)
			(thermal_bridge_width 0.5)
			(island_removal_mode 0)
		)
		(polygon
			(pts
				(arc
					(start 197.17512 -119.559324)
					(mid 197.63232 -120.016524)
					(end 198.08952 -119.559324)
				)
				(arc
					(start 198.08952 -118.695724)
					(mid 197.63232 -118.238524)
					(end 197.17512 -118.695724)
				)
			)
		)
	)
	(zone
		(layers "F.Cu" "B.Cu" "In1.Cu" "In2.Cu" "In3.Cu" "In4.Cu" "In5.Cu" "In6.Cu"
			"In7.Cu" "In8.Cu" "In9.Cu" "In10.Cu" "In11.Cu" "In12.Cu" "In13.Cu" "In14.Cu"
			"In15.Cu" "In16.Cu"
		)
		(hatch none 0.5)
		(connect_pads
			(clearance 0)
		)
		(min_thickness 0.25)
		(keepout
			(tracks not_allowed)
			(vias allowed)
			(pads allowed)
			(copperpour not_allowed)
			(footprints allowed)
		)
		(placement
			(enabled no)
			(sheetname "")
		)
		(fill
			(thermal_gap 0.5)
			(thermal_bridge_width 0.5)
			(island_removal_mode 0)
		)
		(polygon
			(pts
				(arc
					(start 177.730912 -345.084146)
					(mid 177.349912 -345.465146)
					(end 177.730912 -345.846146)
				)
				(arc
					(start 178.594512 -345.846146)
					(mid 178.975512 -345.465146)
					(end 178.594512 -345.084146)
				)
			)
		)
	)
	(zone
		(layers "F.Cu" "B.Cu" "In1.Cu" "In2.Cu" "In3.Cu" "In4.Cu" "In5.Cu" "In6.Cu"
			"In7.Cu" "In8.Cu" "In9.Cu" "In10.Cu" "In11.Cu" "In12.Cu" "In13.Cu" "In14.Cu"
			"In15.Cu" "In16.Cu"
		)
		(hatch none 0.5)
		(connect_pads
			(clearance 0)
		)
		(min_thickness 0.25)
		(keepout
			(tracks not_allowed)
			(vias allowed)
			(pads allowed)
			(copperpour not_allowed)
			(footprints allowed)
		)
		(placement
			(enabled no)
			(sheetname "")
		)
		(fill
			(thermal_gap 0.5)
			(thermal_bridge_width 0.5)
			(island_removal_mode 0)
		)
		(polygon
			(pts
				(arc
					(start 166.101014 -397.028924)
					(mid 166.115893 -396.993003)
					(end 166.151814 -396.978124)
				)
				(arc
					(start 166.868094 -396.978124)
					(mid 166.904015 -396.993003)
					(end 166.918894 -397.028924)
				)
				(arc
					(start 166.918894 -399.451576)
					(mid 166.904015 -399.487497)
					(end 166.868094 -399.502376)
				)
				(arc
					(start 166.151814 -399.502376)
					(mid 166.115893 -399.487497)
					(end 166.101014 -399.451576)
				)
			)
		)
	)
	(zone
		(layers "F.Cu" "B.Cu" "In1.Cu" "In2.Cu" "In3.Cu" "In4.Cu" "In5.Cu" "In6.Cu"
			"In7.Cu" "In8.Cu" "In9.Cu" "In10.Cu" "In11.Cu" "In12.Cu" "In13.Cu" "In14.Cu"
			"In15.Cu" "In16.Cu"
		)
		(hatch none 0.5)
		(connect_pads
			(clearance 0)
		)
		(min_thickness 0.25)
		(keepout
			(tracks not_allowed)
			(vias allowed)
			(pads allowed)
			(copperpour not_allowed)
			(footprints allowed)
		)
		(placement
			(enabled no)
			(sheetname "")
		)
		(fill
			(thermal_gap 0.5)
			(thermal_bridge_width 0.5)
			(island_removal_mode 0)
		)
		(polygon
			(pts
				(arc
					(start 424.839892 -345.084146)
					(mid 424.458892 -345.465146)
					(end 424.839892 -345.846146)
				)
				(arc
					(start 425.703492 -345.846146)
					(mid 426.084492 -345.465146)
					(end 425.703492 -345.084146)
				)
			)
		)
	)
	(zone
		(layers "F.Cu" "B.Cu" "In1.Cu" "In2.Cu" "In3.Cu" "In4.Cu" "In5.Cu" "In6.Cu"
			"In7.Cu" "In8.Cu" "In9.Cu" "In10.Cu" "In11.Cu" "In12.Cu" "In13.Cu" "In14.Cu"
			"In15.Cu" "In16.Cu"
		)
		(hatch none 0.5)
		(connect_pads
			(clearance 0)
		)
		(min_thickness 0.25)
		(keepout
			(tracks not_allowed)
			(vias allowed)
			(pads allowed)
			(copperpour not_allowed)
			(footprints allowed)
		)
		(placement
			(enabled no)
			(sheetname "")
		)
		(fill
			(thermal_gap 0.5)
			(thermal_bridge_width 0.5)
			(island_removal_mode 0)
		)
		(polygon
			(pts
				(arc
					(start 25.550368 -345.084146)
					(mid 25.169368 -345.465146)
					(end 25.550368 -345.846146)
				)
				(arc
					(start 26.413968 -345.846146)
					(mid 26.794968 -345.465146)
					(end 26.413968 -345.084146)
				)
			)
		)
	)
	(zone
		(layers "F.Cu" "B.Cu" "In1.Cu" "In2.Cu" "In3.Cu" "In4.Cu" "In5.Cu" "In6.Cu"
			"In7.Cu" "In8.Cu" "In9.Cu" "In10.Cu" "In11.Cu" "In12.Cu" "In13.Cu" "In14.Cu"
			"In15.Cu" "In16.Cu"
		)
		(hatch none 0.5)
		(connect_pads
			(clearance 0)
		)
		(min_thickness 0.25)
		(keepout
			(tracks not_allowed)
			(vias allowed)
			(pads allowed)
			(copperpour not_allowed)
			(footprints allowed)
		)
		(placement
			(enabled no)
			(sheetname "")
		)
		(fill
			(thermal_gap 0.5)
			(thermal_bridge_width 0.5)
			(island_removal_mode 0)
		)
		(polygon
			(pts
				(arc
					(start 136.733788 -342.058498)
					(mid 136.352788 -342.439498)
					(end 136.733788 -342.820498)
				)
				(arc
					(start 137.597388 -342.820498)
					(mid 137.978388 -342.439498)
					(end 137.597388 -342.058498)
				)
			)
		)
	)
	(zone
		(layers "F.Cu" "B.Cu" "In1.Cu" "In2.Cu" "In3.Cu" "In4.Cu" "In5.Cu" "In6.Cu"
			"In7.Cu" "In8.Cu" "In9.Cu" "In10.Cu" "In11.Cu" "In12.Cu" "In13.Cu" "In14.Cu"
			"In15.Cu" "In16.Cu"
		)
		(hatch none 0.5)
		(connect_pads
			(clearance 0)
		)
		(min_thickness 0.25)
		(keepout
			(tracks not_allowed)
			(vias allowed)
			(pads allowed)
			(copperpour not_allowed)
			(footprints allowed)
		)
		(placement
			(enabled no)
			(sheetname "")
		)
		(fill
			(thermal_gap 0.5)
			(thermal_bridge_width 0.5)
			(island_removal_mode 0)
		)
		(polygon
			(pts
				(arc
					(start 170.654218 -110.11281)
					(mid 170.197018 -109.65561)
					(end 169.739818 -110.11281)
				)
				(arc
					(start 169.739818 -110.97641)
					(mid 170.197018 -111.43361)
					(end 170.654218 -110.97641)
				)
			)
		)
	)
	(zone
		(layers "F.Cu" "B.Cu" "In1.Cu" "In2.Cu" "In3.Cu" "In4.Cu" "In5.Cu" "In6.Cu"
			"In7.Cu" "In8.Cu" "In9.Cu" "In10.Cu" "In11.Cu" "In12.Cu" "In13.Cu" "In14.Cu"
			"In15.Cu" "In16.Cu"
		)
		(hatch none 0.5)
		(connect_pads
			(clearance 0)
		)
		(min_thickness 0.25)
		(keepout
			(tracks not_allowed)
			(vias allowed)
			(pads allowed)
			(copperpour not_allowed)
			(footprints allowed)
		)
		(placement
			(enabled no)
			(sheetname "")
		)
		(fill
			(thermal_gap 0.5)
			(thermal_bridge_width 0.5)
			(island_removal_mode 0)
		)
		(polygon
			(pts
				(arc
					(start 312.502804 -345.084146)
					(mid 312.121804 -345.465146)
					(end 312.502804 -345.846146)
				)
				(arc
					(start 313.366404 -345.846146)
					(mid 313.747404 -345.465146)
					(end 313.366404 -345.084146)
				)
			)
		)
	)
	(zone
		(layers "F.Cu" "B.Cu" "In1.Cu" "In2.Cu" "In3.Cu" "In4.Cu" "In5.Cu" "In6.Cu"
			"In7.Cu" "In8.Cu" "In9.Cu" "In10.Cu" "In11.Cu" "In12.Cu" "In13.Cu" "In14.Cu"
			"In15.Cu" "In16.Cu"
		)
		(hatch none 0.5)
		(connect_pads
			(clearance 0)
		)
		(min_thickness 0.25)
		(keepout
			(tracks not_allowed)
			(vias allowed)
			(pads allowed)
			(copperpour not_allowed)
			(footprints allowed)
		)
		(placement
			(enabled no)
			(sheetname "")
		)
		(fill
			(thermal_gap 0.5)
			(thermal_bridge_width 0.5)
			(island_removal_mode 0)
		)
		(polygon
			(pts
				(arc
					(start 117.70106 -397.028924)
					(mid 117.715939 -396.993003)
					(end 117.75186 -396.978124)
				)
				(arc
					(start 118.46814 -396.978124)
					(mid 118.504061 -396.993003)
					(end 118.51894 -397.028924)
				)
				(arc
					(start 118.51894 -399.451576)
					(mid 118.504061 -399.487497)
					(end 118.46814 -399.502376)
				)
				(arc
					(start 117.75186 -399.502376)
					(mid 117.715939 -399.487497)
					(end 117.70106 -399.451576)
				)
			)
		)
	)
	(zone
		(layers "F.Cu" "B.Cu" "In1.Cu" "In2.Cu" "In3.Cu" "In4.Cu" "In5.Cu" "In6.Cu"
			"In7.Cu" "In8.Cu" "In9.Cu" "In10.Cu" "In11.Cu" "In12.Cu" "In13.Cu" "In14.Cu"
			"In15.Cu" "In16.Cu"
		)
		(hatch none 0.5)
		(connect_pads
			(clearance 0)
		)
		(min_thickness 0.25)
		(keepout
			(tracks not_allowed)
			(vias allowed)
			(pads allowed)
			(copperpour not_allowed)
			(footprints allowed)
		)
		(placement
			(enabled no)
			(sheetname "")
		)
		(fill
			(thermal_gap 0.5)
			(thermal_bridge_width 0.5)
			(island_removal_mode 0)
		)
		(polygon
			(pts
				(arc
					(start 235.702602 -87.843614)
					(mid 236.159802 -87.386414)
					(end 235.702602 -86.929214)
				)
				(arc
					(start 234.839002 -86.929214)
					(mid 234.381802 -87.386414)
					(end 234.839002 -87.843614)
				)
			)
		)
	)
	(zone
		(layers "F.Cu" "B.Cu" "In1.Cu" "In2.Cu" "In3.Cu" "In4.Cu" "In5.Cu" "In6.Cu"
			"In7.Cu" "In8.Cu" "In9.Cu" "In10.Cu" "In11.Cu" "In12.Cu" "In13.Cu" "In14.Cu"
			"In15.Cu" "In16.Cu"
		)
		(hatch none 0.5)
		(connect_pads
			(clearance 0)
		)
		(min_thickness 0.25)
		(keepout
			(tracks not_allowed)
			(vias allowed)
			(pads allowed)
			(copperpour not_allowed)
			(footprints allowed)
		)
		(placement
			(enabled no)
			(sheetname "")
		)
		(fill
			(thermal_gap 0.5)
			(thermal_bridge_width 0.5)
			(island_removal_mode 0)
		)
		(polygon
			(pts
				(arc
					(start 324.938644 -357.37673)
					(mid 324.557644 -357.75773)
					(end 324.938644 -358.13873)
				)
				(arc
					(start 325.802244 -358.13873)
					(mid 326.183244 -357.75773)
					(end 325.802244 -357.37673)
				)
			)
		)
	)
	(zone
		(layers "F.Cu" "B.Cu" "In1.Cu" "In2.Cu" "In3.Cu" "In4.Cu" "In5.Cu" "In6.Cu"
			"In7.Cu" "In8.Cu" "In9.Cu" "In10.Cu" "In11.Cu" "In12.Cu" "In13.Cu" "In14.Cu"
			"In15.Cu" "In16.Cu"
		)
		(hatch none 0.5)
		(connect_pads
			(clearance 0)
		)
		(min_thickness 0.25)
		(keepout
			(tracks not_allowed)
			(vias allowed)
			(pads allowed)
			(copperpour not_allowed)
			(footprints allowed)
		)
		(placement
			(enabled no)
			(sheetname "")
		)
		(fill
			(thermal_gap 0.5)
			(thermal_bridge_width 0.5)
			(island_removal_mode 0)
		)
		(polygon
			(pts
				(arc
					(start 174.901098 -408.728672)
					(mid 174.915977 -408.692751)
					(end 174.951898 -408.677872)
				)
				(arc
					(start 175.668178 -408.677872)
					(mid 175.704099 -408.692751)
					(end 175.718978 -408.728672)
				)
				(arc
					(start 175.718978 -411.151324)
					(mid 175.704099 -411.187245)
					(end 175.668178 -411.202124)
				)
				(arc
					(start 174.951898 -411.202124)
					(mid 174.915977 -411.187245)
					(end 174.901098 -411.151324)
				)
			)
		)
	)
	(zone
		(layers "F.Cu" "B.Cu" "In1.Cu" "In2.Cu" "In3.Cu" "In4.Cu" "In5.Cu" "In6.Cu"
			"In7.Cu" "In8.Cu" "In9.Cu" "In10.Cu" "In11.Cu" "In12.Cu" "In13.Cu" "In14.Cu"
			"In15.Cu" "In16.Cu"
		)
		(hatch none 0.5)
		(connect_pads
			(clearance 0)
		)
		(min_thickness 0.25)
		(keepout
			(tracks not_allowed)
			(vias allowed)
			(pads allowed)
			(copperpour not_allowed)
			(footprints allowed)
		)
		(placement
			(enabled no)
			(sheetname "")
		)
		(fill
			(thermal_gap 0.5)
			(thermal_bridge_width 0.5)
			(island_removal_mode 0)
		)
		(polygon
			(pts
				(arc
					(start 31.90113 -395.92885)
					(mid 31.916009 -395.892929)
					(end 31.95193 -395.87805)
				)
				(arc
					(start 32.66821 -395.87805)
					(mid 32.704131 -395.892929)
					(end 32.71901 -395.92885)
				)
				(arc
					(start 32.71901 -398.351502)
					(mid 32.704131 -398.387423)
					(end 32.66821 -398.402302)
				)
				(arc
					(start 31.95193 -398.402302)
					(mid 31.916009 -398.387423)
					(end 31.90113 -398.351502)
				)
			)
		)
	)
	(zone
		(layers "F.Cu" "B.Cu" "In1.Cu" "In2.Cu" "In3.Cu" "In4.Cu" "In5.Cu" "In6.Cu"
			"In7.Cu" "In8.Cu" "In9.Cu" "In10.Cu" "In11.Cu" "In12.Cu" "In13.Cu" "In14.Cu"
			"In15.Cu" "In16.Cu"
		)
		(hatch none 0.5)
		(connect_pads
			(clearance 0)
		)
		(min_thickness 0.25)
		(keepout
			(tracks not_allowed)
			(vias allowed)
			(pads allowed)
			(copperpour not_allowed)
			(footprints allowed)
		)
		(placement
			(enabled no)
			(sheetname "")
		)
		(fill
			(thermal_gap 0.5)
			(thermal_bridge_width 0.5)
			(island_removal_mode 0)
		)
		(polygon
			(pts
				(arc
					(start 335.481168 -399.828766)
					(mid 335.496047 -399.792845)
					(end 335.531968 -399.777966)
				)
				(arc
					(start 336.248248 -399.777966)
					(mid 336.284169 -399.792845)
					(end 336.299048 -399.828766)
				)
				(arc
					(start 336.299048 -402.251418)
					(mid 336.284169 -402.287339)
					(end 336.248248 -402.302218)
				)
				(arc
					(start 335.531968 -402.302218)
					(mid 335.496047 -402.287339)
					(end 335.481168 -402.251418)
				)
			)
		)
	)
	(zone
		(layers "F.Cu" "B.Cu" "In1.Cu" "In2.Cu" "In3.Cu" "In4.Cu" "In5.Cu" "In6.Cu"
			"In7.Cu" "In8.Cu" "In9.Cu" "In10.Cu" "In11.Cu" "In12.Cu" "In13.Cu" "In14.Cu"
			"In15.Cu" "In16.Cu"
		)
		(hatch none 0.5)
		(connect_pads
			(clearance 0)
		)
		(min_thickness 0.25)
		(keepout
			(tracks not_allowed)
			(vias allowed)
			(pads allowed)
			(copperpour not_allowed)
			(footprints allowed)
		)
		(placement
			(enabled no)
			(sheetname "")
		)
		(fill
			(thermal_gap 0.5)
			(thermal_bridge_width 0.5)
			(island_removal_mode 0)
		)
		(polygon
			(pts
				(arc
					(start 36.301172 -369.928902)
					(mid 36.316051 -369.892981)
					(end 36.351972 -369.878102)
				)
				(arc
					(start 37.068252 -369.878102)
					(mid 37.104173 -369.892981)
					(end 37.119052 -369.928902)
				)
				(arc
					(start 37.119052 -372.351554)
					(mid 37.104173 -372.387475)
					(end 37.068252 -372.402354)
				)
				(arc
					(start 36.351972 -372.402354)
					(mid 36.316051 -372.387475)
					(end 36.301172 -372.351554)
				)
			)
		)
	)
	(zone
		(layers "F.Cu" "B.Cu" "In1.Cu" "In2.Cu" "In3.Cu" "In4.Cu" "In5.Cu" "In6.Cu"
			"In7.Cu" "In8.Cu" "In9.Cu" "In10.Cu" "In11.Cu" "In12.Cu" "In13.Cu" "In14.Cu"
			"In15.Cu" "In16.Cu"
		)
		(hatch none 0.5)
		(connect_pads
			(clearance 0)
		)
		(min_thickness 0.25)
		(keepout
			(tracks not_allowed)
			(vias allowed)
			(pads allowed)
			(copperpour not_allowed)
			(footprints allowed)
		)
		(placement
			(enabled no)
			(sheetname "")
		)
		(fill
			(thermal_gap 0.5)
			(thermal_bridge_width 0.5)
			(island_removal_mode 0)
		)
		(polygon
			(pts
				(arc
					(start 70.847966 -32.714184)
					(mid 71.305166 -33.171384)
					(end 71.762366 -32.714184)
				)
				(arc
					(start 71.762366 -31.850584)
					(mid 71.305166 -31.393384)
					(end 70.847966 -31.850584)
				)
			)
		)
	)
	(zone
		(layers "F.Cu" "B.Cu" "In1.Cu" "In2.Cu" "In3.Cu" "In4.Cu" "In5.Cu" "In6.Cu"
			"In7.Cu" "In8.Cu" "In9.Cu" "In10.Cu" "In11.Cu" "In12.Cu" "In13.Cu" "In14.Cu"
			"In15.Cu" "In16.Cu"
		)
		(hatch none 0.5)
		(connect_pads
			(clearance 0)
		)
		(min_thickness 0.25)
		(keepout
			(tracks not_allowed)
			(vias allowed)
			(pads allowed)
			(copperpour not_allowed)
			(footprints allowed)
		)
		(placement
			(enabled no)
			(sheetname "")
		)
		(fill
			(thermal_gap 0.5)
			(thermal_bridge_width 0.5)
			(island_removal_mode 0)
		)
		(polygon
			(pts
				(arc
					(start 342.081104 -378.828554)
					(mid 342.095983 -378.792633)
					(end 342.131904 -378.777754)
				)
				(arc
					(start 342.848184 -378.777754)
					(mid 342.884105 -378.792633)
					(end 342.898984 -378.828554)
				)
				(arc
					(start 342.898984 -381.251206)
					(mid 342.884105 -381.287127)
					(end 342.848184 -381.302006)
				)
				(arc
					(start 342.131904 -381.302006)
					(mid 342.095983 -381.287127)
					(end 342.081104 -381.251206)
				)
			)
		)
	)
	(zone
		(layers "F.Cu" "B.Cu" "In1.Cu" "In2.Cu" "In3.Cu" "In4.Cu" "In5.Cu" "In6.Cu"
			"In7.Cu" "In8.Cu" "In9.Cu" "In10.Cu" "In11.Cu" "In12.Cu" "In13.Cu" "In14.Cu"
			"In15.Cu" "In16.Cu"
		)
		(hatch none 0.5)
		(connect_pads
			(clearance 0)
		)
		(min_thickness 0.25)
		(keepout
			(tracks not_allowed)
			(vias allowed)
			(pads allowed)
			(copperpour not_allowed)
			(footprints allowed)
		)
		(placement
			(enabled no)
			(sheetname "")
		)
		(fill
			(thermal_gap 0.5)
			(thermal_bridge_width 0.5)
			(island_removal_mode 0)
		)
		(polygon
			(pts
				(arc
					(start 291.481002 -395.92885)
					(mid 291.495881 -395.892929)
					(end 291.531802 -395.87805)
				)
				(arc
					(start 292.248082 -395.87805)
					(mid 292.284003 -395.892929)
					(end 292.298882 -395.92885)
				)
				(arc
					(start 292.298882 -398.351502)
					(mid 292.284003 -398.387423)
					(end 292.248082 -398.402302)
				)
				(arc
					(start 291.531802 -398.402302)
					(mid 291.495881 -398.387423)
					(end 291.481002 -398.351502)
				)
			)
		)
	)
	(zone
		(layers "F.Cu" "B.Cu" "In1.Cu" "In2.Cu" "In3.Cu" "In4.Cu" "In5.Cu" "In6.Cu"
			"In7.Cu" "In8.Cu" "In9.Cu" "In10.Cu" "In11.Cu" "In12.Cu" "In13.Cu" "In14.Cu"
			"In15.Cu" "In16.Cu"
		)
		(hatch none 0.5)
		(connect_pads
			(clearance 0)
		)
		(min_thickness 0.25)
		(keepout
			(tracks not_allowed)
			(vias allowed)
			(pads allowed)
			(copperpour not_allowed)
			(footprints allowed)
		)
		(placement
			(enabled no)
			(sheetname "")
		)
		(fill
			(thermal_gap 0.5)
			(thermal_bridge_width 0.5)
			(island_removal_mode 0)
		)
		(polygon
			(pts
				(arc
					(start 121.188988 -342.058498)
					(mid 120.807988 -342.439498)
					(end 121.188988 -342.820498)
				)
				(arc
					(start 122.052588 -342.820498)
					(mid 122.433588 -342.439498)
					(end 122.052588 -342.058498)
				)
			)
		)
	)
	(zone
		(layers "F.Cu" "B.Cu" "In1.Cu" "In2.Cu" "In3.Cu" "In4.Cu" "In5.Cu" "In6.Cu"
			"In7.Cu" "In8.Cu" "In9.Cu" "In10.Cu" "In11.Cu" "In12.Cu" "In13.Cu" "In14.Cu"
			"In15.Cu" "In16.Cu"
		)
		(hatch none 0.5)
		(connect_pads
			(clearance 0)
		)
		(min_thickness 0.25)
		(keepout
			(tracks not_allowed)
			(vias allowed)
			(pads allowed)
			(copperpour not_allowed)
			(footprints allowed)
		)
		(placement
			(enabled no)
			(sheetname "")
		)
		(fill
			(thermal_gap 0.5)
			(thermal_bridge_width 0.5)
			(island_removal_mode 0)
		)
		(polygon
			(pts
				(arc
					(start 71.501 -377.728734)
					(mid 71.515879 -377.692813)
					(end 71.5518 -377.677934)
				)
				(arc
					(start 72.26808 -377.677934)
					(mid 72.304001 -377.692813)
					(end 72.31888 -377.728734)
				)
				(arc
					(start 72.31888 -380.151386)
					(mid 72.304001 -380.187307)
					(end 72.26808 -380.202186)
				)
				(arc
					(start 71.5518 -380.202186)
					(mid 71.515879 -380.187307)
					(end 71.501 -380.151386)
				)
			)
		)
	)
	(zone
		(layers "F.Cu" "B.Cu" "In1.Cu" "In2.Cu" "In3.Cu" "In4.Cu" "In5.Cu" "In6.Cu"
			"In7.Cu" "In8.Cu" "In9.Cu" "In10.Cu" "In11.Cu" "In12.Cu" "In13.Cu" "In14.Cu"
			"In15.Cu" "In16.Cu"
		)
		(hatch none 0.5)
		(connect_pads
			(clearance 0)
		)
		(min_thickness 0.25)
		(keepout
			(tracks not_allowed)
			(vias allowed)
			(pads allowed)
			(copperpour not_allowed)
			(footprints allowed)
		)
		(placement
			(enabled no)
			(sheetname "")
		)
		(fill
			(thermal_gap 0.5)
			(thermal_bridge_width 0.5)
			(island_removal_mode 0)
		)
		(polygon
			(pts
				(arc
					(start 389.84174 -354.351082)
					(mid 389.46074 -354.732082)
					(end 389.84174 -355.113082)
				)
				(arc
					(start 390.70534 -355.113082)
					(mid 391.08634 -354.732082)
					(end 390.70534 -354.351082)
				)
			)
		)
	)
	(zone
		(layers "F.Cu" "B.Cu" "In1.Cu" "In2.Cu" "In3.Cu" "In4.Cu" "In5.Cu" "In6.Cu"
			"In7.Cu" "In8.Cu" "In9.Cu" "In10.Cu" "In11.Cu" "In12.Cu" "In13.Cu" "In14.Cu"
			"In15.Cu" "In16.Cu"
		)
		(hatch none 0.5)
		(connect_pads
			(clearance 0)
		)
		(min_thickness 0.25)
		(keepout
			(tracks not_allowed)
			(vias allowed)
			(pads allowed)
			(copperpour not_allowed)
			(footprints allowed)
		)
		(placement
			(enabled no)
			(sheetname "")
		)
		(fill
			(thermal_gap 0.5)
			(thermal_bridge_width 0.5)
			(island_removal_mode 0)
		)
		(polygon
			(pts
				(arc
					(start 180.845968 -124.967238)
					(mid 181.303168 -125.424438)
					(end 181.760368 -124.967238)
				)
				(arc
					(start 181.760368 -124.103638)
					(mid 181.303168 -123.646438)
					(end 180.845968 -124.103638)
				)
			)
		)
	)
	(zone
		(layers "F.Cu" "B.Cu" "In1.Cu" "In2.Cu" "In3.Cu" "In4.Cu" "In5.Cu" "In6.Cu"
			"In7.Cu" "In8.Cu" "In9.Cu" "In10.Cu" "In11.Cu" "In12.Cu" "In13.Cu" "In14.Cu"
			"In15.Cu" "In16.Cu"
		)
		(hatch none 0.5)
		(connect_pads
			(clearance 0)
		)
		(min_thickness 0.25)
		(keepout
			(tracks not_allowed)
			(vias allowed)
			(pads allowed)
			(copperpour not_allowed)
			(footprints allowed)
		)
		(placement
			(enabled no)
			(sheetname "")
		)
		(fill
			(thermal_gap 0.5)
			(thermal_bridge_width 0.5)
			(island_removal_mode 0)
		)
		(polygon
			(pts
				(arc
					(start 399.16862 -348.20479)
					(mid 398.78762 -348.58579)
					(end 399.16862 -348.96679)
				)
				(arc
					(start 400.03222 -348.96679)
					(mid 400.41322 -348.58579)
					(end 400.03222 -348.20479)
				)
			)
		)
	)
	(zone
		(layers "F.Cu" "B.Cu" "In1.Cu" "In2.Cu" "In3.Cu" "In4.Cu" "In5.Cu" "In6.Cu"
			"In7.Cu" "In8.Cu" "In9.Cu" "In10.Cu" "In11.Cu" "In12.Cu" "In13.Cu" "In14.Cu"
			"In15.Cu" "In16.Cu"
		)
		(hatch none 0.5)
		(connect_pads
			(clearance 0)
		)
		(min_thickness 0.25)
		(keepout
			(tracks not_allowed)
			(vias allowed)
			(pads allowed)
			(copperpour not_allowed)
			(footprints allowed)
		)
		(placement
			(enabled no)
			(sheetname "")
		)
		(fill
			(thermal_gap 0.5)
			(thermal_bridge_width 0.5)
			(island_removal_mode 0)
		)
		(polygon
			(pts
				(arc
					(start 71.501 -381.628904)
					(mid 71.515879 -381.592983)
					(end 71.5518 -381.578104)
				)
				(arc
					(start 72.26808 -381.578104)
					(mid 72.304001 -381.592983)
					(end 72.31888 -381.628904)
				)
				(arc
					(start 72.31888 -384.051556)
					(mid 72.304001 -384.087477)
					(end 72.26808 -384.102356)
				)
				(arc
					(start 71.5518 -384.102356)
					(mid 71.515879 -384.087477)
					(end 71.501 -384.051556)
				)
			)
		)
	)
	(zone
		(layers "F.Cu" "B.Cu" "In1.Cu" "In2.Cu" "In3.Cu" "In4.Cu" "In5.Cu" "In6.Cu"
			"In7.Cu" "In8.Cu" "In9.Cu" "In10.Cu" "In11.Cu" "In12.Cu" "In13.Cu" "In14.Cu"
			"In15.Cu" "In16.Cu"
		)
		(hatch none 0.5)
		(connect_pads
			(clearance 0)
		)
		(min_thickness 0.25)
		(keepout
			(tracks not_allowed)
			(vias allowed)
			(pads allowed)
			(copperpour not_allowed)
			(footprints allowed)
		)
		(placement
			(enabled no)
			(sheetname "")
		)
		(fill
			(thermal_gap 0.5)
			(thermal_bridge_width 0.5)
			(island_removal_mode 0)
		)
		(polygon
			(pts
				(arc
					(start 78.100936 -371.028722)
					(mid 78.115815 -370.992801)
					(end 78.151736 -370.977922)
				)
				(arc
					(start 78.868016 -370.977922)
					(mid 78.903937 -370.992801)
					(end 78.918816 -371.028722)
				)
				(arc
					(start 78.918816 -373.451374)
					(mid 78.903937 -373.487295)
					(end 78.868016 -373.502174)
				)
				(arc
					(start 78.151736 -373.502174)
					(mid 78.115815 -373.487295)
					(end 78.100936 -373.451374)
				)
			)
		)
	)
	(zone
		(layers "F.Cu" "B.Cu" "In1.Cu" "In2.Cu" "In3.Cu" "In4.Cu" "In5.Cu" "In6.Cu"
			"In7.Cu" "In8.Cu" "In9.Cu" "In10.Cu" "In11.Cu" "In12.Cu" "In13.Cu" "In14.Cu"
			"In15.Cu" "In16.Cu"
		)
		(hatch none 0.5)
		(connect_pads
			(clearance 0)
		)
		(min_thickness 0.25)
		(keepout
			(tracks not_allowed)
			(vias allowed)
			(pads allowed)
			(copperpour not_allowed)
			(footprints allowed)
		)
		(placement
			(enabled no)
			(sheetname "")
		)
		(fill
			(thermal_gap 0.5)
			(thermal_bridge_width 0.5)
			(island_removal_mode 0)
		)
		(polygon
			(pts
				(arc
					(start 269.51051 -121.894346)
					(mid 269.96771 -122.351546)
					(end 270.42491 -121.894346)
				)
				(arc
					(start 270.42491 -121.030746)
					(mid 269.96771 -120.573546)
					(end 269.51051 -121.030746)
				)
			)
		)
	)
	(zone
		(layers "F.Cu" "B.Cu" "In1.Cu" "In2.Cu" "In3.Cu" "In4.Cu" "In5.Cu" "In6.Cu"
			"In7.Cu" "In8.Cu" "In9.Cu" "In10.Cu" "In11.Cu" "In12.Cu" "In13.Cu" "In14.Cu"
			"In15.Cu" "In16.Cu"
		)
		(hatch none 0.5)
		(connect_pads
			(clearance 0)
		)
		(min_thickness 0.25)
		(keepout
			(tracks not_allowed)
			(vias allowed)
			(pads allowed)
			(copperpour not_allowed)
			(footprints allowed)
		)
		(placement
			(enabled no)
			(sheetname "")
		)
		(fill
			(thermal_gap 0.5)
			(thermal_bridge_width 0.5)
			(island_removal_mode 0)
		)
		(polygon
			(pts
				(arc
					(start 315.611764 -345.084146)
					(mid 315.230764 -345.465146)
					(end 315.611764 -345.846146)
				)
				(arc
					(start 316.475364 -345.846146)
					(mid 316.856364 -345.465146)
					(end 316.475364 -345.084146)
				)
			)
		)
	)
	(zone
		(layers "F.Cu" "B.Cu" "In1.Cu" "In2.Cu" "In3.Cu" "In4.Cu" "In5.Cu" "In6.Cu"
			"In7.Cu" "In8.Cu" "In9.Cu" "In10.Cu" "In11.Cu" "In12.Cu" "In13.Cu" "In14.Cu"
			"In15.Cu" "In16.Cu"
		)
		(hatch none 0.5)
		(connect_pads
			(clearance 0)
		)
		(min_thickness 0.25)
		(keepout
			(tracks not_allowed)
			(vias allowed)
			(pads allowed)
			(copperpour not_allowed)
			(footprints allowed)
		)
		(placement
			(enabled no)
			(sheetname "")
		)
		(fill
			(thermal_gap 0.5)
			(thermal_bridge_width 0.5)
			(island_removal_mode 0)
		)
		(polygon
			(pts
				(arc
					(start 302.48098 -400.92884)
					(mid 302.495859 -400.892919)
					(end 302.53178 -400.87804)
				)
				(arc
					(start 303.24806 -400.87804)
					(mid 303.283981 -400.892919)
					(end 303.29886 -400.92884)
				)
				(arc
					(start 303.29886 -403.351492)
					(mid 303.283981 -403.387413)
					(end 303.24806 -403.402292)
				)
				(arc
					(start 302.53178 -403.402292)
					(mid 302.495859 -403.387413)
					(end 302.48098 -403.351492)
				)
			)
		)
	)
	(zone
		(layers "F.Cu" "B.Cu" "In1.Cu" "In2.Cu" "In3.Cu" "In4.Cu" "In5.Cu" "In6.Cu"
			"In7.Cu" "In8.Cu" "In9.Cu" "In10.Cu" "In11.Cu" "In12.Cu" "In13.Cu" "In14.Cu"
			"In15.Cu" "In16.Cu"
		)
		(hatch none 0.5)
		(connect_pads
			(clearance 0)
		)
		(min_thickness 0.25)
		(keepout
			(tracks not_allowed)
			(vias allowed)
			(pads allowed)
			(copperpour not_allowed)
			(footprints allowed)
		)
		(placement
			(enabled no)
			(sheetname "")
		)
		(fill
			(thermal_gap 0.5)
			(thermal_bridge_width 0.5)
			(island_removal_mode 0)
		)
		(polygon
			(pts
				(arc
					(start 295.877742 -357.37673)
					(mid 295.496742 -357.75773)
					(end 295.877742 -358.13873)
				)
				(arc
					(start 296.741342 -358.13873)
					(mid 297.122342 -357.75773)
					(end 296.741342 -357.37673)
				)
			)
		)
	)
	(zone
		(layers "F.Cu" "B.Cu" "In1.Cu" "In2.Cu" "In3.Cu" "In4.Cu" "In5.Cu" "In6.Cu"
			"In7.Cu" "In8.Cu" "In9.Cu" "In10.Cu" "In11.Cu" "In12.Cu" "In13.Cu" "In14.Cu"
			"In15.Cu" "In16.Cu"
		)
		(hatch none 0.5)
		(connect_pads
			(clearance 0)
		)
		(min_thickness 0.25)
		(keepout
			(tracks not_allowed)
			(vias allowed)
			(pads allowed)
			(copperpour not_allowed)
			(footprints allowed)
		)
		(placement
			(enabled no)
			(sheetname "")
		)
		(fill
			(thermal_gap 0.5)
			(thermal_bridge_width 0.5)
			(island_removal_mode 0)
		)
		(polygon
			(pts
				(arc
					(start 150.707598 -32.722312)
					(mid 151.164798 -33.179512)
					(end 151.621998 -32.722312)
				)
				(arc
					(start 151.621998 -31.858712)
					(mid 151.164798 -31.401512)
					(end 150.707598 -31.858712)
				)
			)
		)
	)
	(zone
		(layers "F.Cu" "B.Cu" "In1.Cu" "In2.Cu" "In3.Cu" "In4.Cu" "In5.Cu" "In6.Cu"
			"In7.Cu" "In8.Cu" "In9.Cu" "In10.Cu" "In11.Cu" "In12.Cu" "In13.Cu" "In14.Cu"
			"In15.Cu" "In16.Cu"
		)
		(hatch none 0.5)
		(connect_pads
			(clearance 0)
		)
		(min_thickness 0.25)
		(keepout
			(tracks not_allowed)
			(vias allowed)
			(pads allowed)
			(copperpour not_allowed)
			(footprints allowed)
		)
		(placement
			(enabled no)
			(sheetname "")
		)
		(fill
			(thermal_gap 0.5)
			(thermal_bridge_width 0.5)
			(island_removal_mode 0)
		)
		(polygon
			(pts
				(arc
					(start 295.881044 -399.828766)
					(mid 295.895923 -399.792845)
					(end 295.931844 -399.777966)
				)
				(arc
					(start 296.648124 -399.777966)
					(mid 296.684045 -399.792845)
					(end 296.698924 -399.828766)
				)
				(arc
					(start 296.698924 -402.251418)
					(mid 296.684045 -402.287339)
					(end 296.648124 -402.302218)
				)
				(arc
					(start 295.931844 -402.302218)
					(mid 295.895923 -402.287339)
					(end 295.881044 -402.251418)
				)
			)
		)
	)
	(zone
		(layers "F.Cu" "B.Cu" "In1.Cu" "In2.Cu" "In3.Cu" "In4.Cu" "In5.Cu" "In6.Cu"
			"In7.Cu" "In8.Cu" "In9.Cu" "In10.Cu" "In11.Cu" "In12.Cu" "In13.Cu" "In14.Cu"
			"In15.Cu" "In16.Cu"
		)
		(hatch none 0.5)
		(connect_pads
			(clearance 0)
		)
		(min_thickness 0.25)
		(keepout
			(tracks not_allowed)
			(vias allowed)
			(pads allowed)
			(copperpour not_allowed)
			(footprints allowed)
		)
		(placement
			(enabled no)
			(sheetname "")
		)
		(fill
			(thermal_gap 0.5)
			(thermal_bridge_width 0.5)
			(island_removal_mode 0)
		)
		(polygon
			(pts
				(arc
					(start 400.99996 -135.83285)
					(mid 400.54276 -135.37565)
					(end 400.08556 -135.83285)
				)
				(arc
					(start 400.08556 -136.69645)
					(mid 400.54276 -137.15365)
					(end 400.99996 -136.69645)
				)
			)
		)
	)
	(zone
		(layers "F.Cu" "B.Cu" "In1.Cu" "In2.Cu" "In3.Cu" "In4.Cu" "In5.Cu" "In6.Cu"
			"In7.Cu" "In8.Cu" "In9.Cu" "In10.Cu" "In11.Cu" "In12.Cu" "In13.Cu" "In14.Cu"
			"In15.Cu" "In16.Cu"
		)
		(hatch none 0.5)
		(connect_pads
			(clearance 0)
		)
		(min_thickness 0.25)
		(keepout
			(tracks not_allowed)
			(vias allowed)
			(pads allowed)
			(copperpour not_allowed)
			(footprints allowed)
		)
		(placement
			(enabled no)
			(sheetname "")
		)
		(fill
			(thermal_gap 0.5)
			(thermal_bridge_width 0.5)
			(island_removal_mode 0)
		)
		(polygon
			(pts
				(arc
					(start 168.301162 -407.628852)
					(mid 168.316041 -407.592931)
					(end 168.351962 -407.578052)
				)
				(arc
					(start 169.068242 -407.578052)
					(mid 169.104163 -407.592931)
					(end 169.119042 -407.628852)
				)
				(arc
					(start 169.119042 -410.051504)
					(mid 169.104163 -410.087425)
					(end 169.068242 -410.102304)
				)
				(arc
					(start 168.351962 -410.102304)
					(mid 168.316041 -410.087425)
					(end 168.301162 -410.051504)
				)
			)
		)
	)
	(zone
		(layers "F.Cu" "B.Cu" "In1.Cu" "In2.Cu" "In3.Cu" "In4.Cu" "In5.Cu" "In6.Cu"
			"In7.Cu" "In8.Cu" "In9.Cu" "In10.Cu" "In11.Cu" "In12.Cu" "In13.Cu" "In14.Cu"
			"In15.Cu" "In16.Cu"
		)
		(hatch none 0.5)
		(connect_pads
			(clearance 0)
		)
		(min_thickness 0.25)
		(keepout
			(tracks not_allowed)
			(vias allowed)
			(pads allowed)
			(copperpour not_allowed)
			(footprints allowed)
		)
		(placement
			(enabled no)
			(sheetname "")
		)
		(fill
			(thermal_gap 0.5)
			(thermal_bridge_width 0.5)
			(island_removal_mode 0)
		)
		(polygon
			(pts
				(arc
					(start 324.938644 -354.351082)
					(mid 324.557644 -354.732082)
					(end 324.938644 -355.113082)
				)
				(arc
					(start 325.802244 -355.113082)
					(mid 326.183244 -354.732082)
					(end 325.802244 -354.351082)
				)
			)
		)
	)
	(zone
		(layers "F.Cu" "B.Cu" "In1.Cu" "In2.Cu" "In3.Cu" "In4.Cu" "In5.Cu" "In6.Cu"
			"In7.Cu" "In8.Cu" "In9.Cu" "In10.Cu" "In11.Cu" "In12.Cu" "In13.Cu" "In14.Cu"
			"In15.Cu" "In16.Cu"
		)
		(hatch none 0.5)
		(connect_pads
			(clearance 0)
		)
		(min_thickness 0.25)
		(keepout
			(tracks not_allowed)
			(vias allowed)
			(pads allowed)
			(copperpour not_allowed)
			(footprints allowed)
		)
		(placement
			(enabled no)
			(sheetname "")
		)
		(fill
			(thermal_gap 0.5)
			(thermal_bridge_width 0.5)
			(island_removal_mode 0)
		)
		(polygon
			(pts
				(arc
					(start 434.907436 -32.722312)
					(mid 435.364636 -33.179512)
					(end 435.821836 -32.722312)
				)
				(arc
					(start 435.821836 -31.858712)
					(mid 435.364636 -31.401512)
					(end 434.907436 -31.858712)
				)
			)
		)
	)
	(zone
		(layers "F.Cu" "B.Cu" "In1.Cu" "In2.Cu" "In3.Cu" "In4.Cu" "In5.Cu" "In6.Cu"
			"In7.Cu" "In8.Cu" "In9.Cu" "In10.Cu" "In11.Cu" "In12.Cu" "In13.Cu" "In14.Cu"
			"In15.Cu" "In16.Cu"
		)
		(hatch none 0.5)
		(connect_pads
			(clearance 0)
		)
		(min_thickness 0.25)
		(keepout
			(tracks not_allowed)
			(vias allowed)
			(pads allowed)
			(copperpour not_allowed)
			(footprints allowed)
		)
		(placement
			(enabled no)
			(sheetname "")
		)
		(fill
			(thermal_gap 0.5)
			(thermal_bridge_width 0.5)
			(island_removal_mode 0)
		)
		(polygon
			(pts
				(arc
					(start 277.223982 -351.230438)
					(mid 276.842982 -351.611438)
					(end 277.223982 -351.992438)
				)
				(arc
					(start 278.087582 -351.992438)
					(mid 278.468582 -351.611438)
					(end 278.087582 -351.230438)
				)
			)
		)
	)
	(zone
		(layers "F.Cu" "B.Cu" "In1.Cu" "In2.Cu" "In3.Cu" "In4.Cu" "In5.Cu" "In6.Cu"
			"In7.Cu" "In8.Cu" "In9.Cu" "In10.Cu" "In11.Cu" "In12.Cu" "In13.Cu" "In14.Cu"
			"In15.Cu" "In16.Cu"
		)
		(hatch none 0.5)
		(connect_pads
			(clearance 0)
		)
		(min_thickness 0.25)
		(keepout
			(tracks not_allowed)
			(vias allowed)
			(pads allowed)
			(copperpour not_allowed)
			(footprints allowed)
		)
		(placement
			(enabled no)
			(sheetname "")
		)
		(fill
			(thermal_gap 0.5)
			(thermal_bridge_width 0.5)
			(island_removal_mode 0)
		)
		(polygon
			(pts
				(arc
					(start 248.724166 -27.342846)
					(mid 249.181366 -27.800046)
					(end 249.638566 -27.342846)
				)
				(arc
					(start 249.638566 -26.479246)
					(mid 249.181366 -26.022046)
					(end 248.724166 -26.479246)
				)
			)
		)
	)
	(zone
		(layers "F.Cu" "B.Cu" "In1.Cu" "In2.Cu" "In3.Cu" "In4.Cu" "In5.Cu" "In6.Cu"
			"In7.Cu" "In8.Cu" "In9.Cu" "In10.Cu" "In11.Cu" "In12.Cu" "In13.Cu" "In14.Cu"
			"In15.Cu" "In16.Cu"
		)
		(hatch none 0.5)
		(connect_pads
			(clearance 0)
		)
		(min_thickness 0.25)
		(keepout
			(tracks not_allowed)
			(vias allowed)
			(pads allowed)
			(copperpour not_allowed)
			(footprints allowed)
		)
		(placement
			(enabled no)
			(sheetname "")
		)
		(fill
			(thermal_gap 0.5)
			(thermal_bridge_width 0.5)
			(island_removal_mode 0)
		)
		(polygon
			(pts
				(arc
					(start 180.839872 -354.351082)
					(mid 180.458872 -354.732082)
					(end 180.839872 -355.113082)
				)
				(arc
					(start 181.703472 -355.113082)
					(mid 182.084472 -354.732082)
					(end 181.703472 -354.351082)
				)
			)
		)
	)
	(zone
		(layers "F.Cu" "B.Cu" "In1.Cu" "In2.Cu" "In3.Cu" "In4.Cu" "In5.Cu" "In6.Cu"
			"In7.Cu" "In8.Cu" "In9.Cu" "In10.Cu" "In11.Cu" "In12.Cu" "In13.Cu" "In14.Cu"
			"In15.Cu" "In16.Cu"
		)
		(hatch none 0.5)
		(connect_pads
			(clearance 0)
		)
		(min_thickness 0.25)
		(keepout
			(tracks not_allowed)
			(vias allowed)
			(pads allowed)
			(copperpour not_allowed)
			(footprints allowed)
		)
		(placement
			(enabled no)
			(sheetname "")
		)
		(fill
			(thermal_gap 0.5)
			(thermal_bridge_width 0.5)
			(island_removal_mode 0)
		)
		(polygon
			(pts
				(arc
					(start 289.659822 -351.230438)
					(mid 289.278822 -351.611438)
					(end 289.659822 -351.992438)
				)
				(arc
					(start 290.523422 -351.992438)
					(mid 290.904422 -351.611438)
					(end 290.523422 -351.230438)
				)
			)
		)
	)
	(zone
		(layers "F.Cu" "B.Cu" "In1.Cu" "In2.Cu" "In3.Cu" "In4.Cu" "In5.Cu" "In6.Cu"
			"In7.Cu" "In8.Cu" "In9.Cu" "In10.Cu" "In11.Cu" "In12.Cu" "In13.Cu" "In14.Cu"
			"In15.Cu" "In16.Cu"
		)
		(hatch none 0.5)
		(connect_pads
			(clearance 0)
		)
		(min_thickness 0.25)
		(keepout
			(tracks not_allowed)
			(vias allowed)
			(pads allowed)
			(copperpour not_allowed)
			(footprints allowed)
		)
		(placement
			(enabled no)
			(sheetname "")
		)
		(fill
			(thermal_gap 0.5)
			(thermal_bridge_width 0.5)
			(island_removal_mode 0)
		)
		(polygon
			(pts
				(arc
					(start 313.274964 -147.079208)
					(mid 313.732164 -147.536408)
					(end 314.189364 -147.079208)
				)
				(arc
					(start 314.189364 -146.215608)
					(mid 313.732164 -145.758408)
					(end 313.274964 -146.215608)
				)
			)
		)
	)
	(zone
		(layers "F.Cu" "B.Cu" "In1.Cu" "In2.Cu" "In3.Cu" "In4.Cu" "In5.Cu" "In6.Cu"
			"In7.Cu" "In8.Cu" "In9.Cu" "In10.Cu" "In11.Cu" "In12.Cu" "In13.Cu" "In14.Cu"
			"In15.Cu" "In16.Cu"
		)
		(hatch none 0.5)
		(connect_pads
			(clearance 0)
		)
		(min_thickness 0.25)
		(keepout
			(tracks not_allowed)
			(vias allowed)
			(pads allowed)
			(copperpour not_allowed)
			(footprints allowed)
		)
		(placement
			(enabled no)
			(sheetname "")
		)
		(fill
			(thermal_gap 0.5)
			(thermal_bridge_width 0.5)
			(island_removal_mode 0)
		)
		(polygon
			(pts
				(arc
					(start 339.391498 20.143724)
					(mid 339.772498 19.762724)
					(end 340.153498 20.143724)
				)
				(arc
					(start 340.153498 21.007324)
					(mid 339.772498 21.388324)
					(end 339.391498 21.007324)
				)
			)
		)
	)
	(zone
		(layers "F.Cu" "B.Cu" "In1.Cu" "In2.Cu" "In3.Cu" "In4.Cu" "In5.Cu" "In6.Cu"
			"In7.Cu" "In8.Cu" "In9.Cu" "In10.Cu" "In11.Cu" "In12.Cu" "In13.Cu" "In14.Cu"
			"In15.Cu" "In16.Cu"
		)
		(hatch none 0.5)
		(connect_pads
			(clearance 0)
		)
		(min_thickness 0.25)
		(keepout
			(tracks not_allowed)
			(vias allowed)
			(pads allowed)
			(copperpour not_allowed)
			(footprints allowed)
		)
		(placement
			(enabled no)
			(sheetname "")
		)
		(fill
			(thermal_gap 0.5)
			(thermal_bridge_width 0.5)
			(island_removal_mode 0)
		)
		(polygon
			(pts
				(arc
					(start 75.901042 -369.928902)
					(mid 75.915921 -369.892981)
					(end 75.951842 -369.878102)
				)
				(arc
					(start 76.668122 -369.878102)
					(mid 76.704043 -369.892981)
					(end 76.718922 -369.928902)
				)
				(arc
					(start 76.718922 -372.351554)
					(mid 76.704043 -372.387475)
					(end 76.668122 -372.402354)
				)
				(arc
					(start 75.951842 -372.402354)
					(mid 75.915921 -372.387475)
					(end 75.901042 -372.351554)
				)
			)
		)
	)
	(zone
		(layers "F.Cu" "B.Cu" "In1.Cu" "In2.Cu" "In3.Cu" "In4.Cu" "In5.Cu" "In6.Cu"
			"In7.Cu" "In8.Cu" "In9.Cu" "In10.Cu" "In11.Cu" "In12.Cu" "In13.Cu" "In14.Cu"
			"In15.Cu" "In16.Cu"
		)
		(hatch none 0.5)
		(connect_pads
			(clearance 0)
		)
		(min_thickness 0.25)
		(keepout
			(tracks not_allowed)
			(vias allowed)
			(pads allowed)
			(copperpour not_allowed)
			(footprints allowed)
		)
		(placement
			(enabled no)
			(sheetname "")
		)
		(fill
			(thermal_gap 0.5)
			(thermal_bridge_width 0.5)
			(island_removal_mode 0)
		)
		(polygon
			(pts
				(arc
					(start 124.297948 -345.084146)
					(mid 123.916948 -345.465146)
					(end 124.297948 -345.846146)
				)
				(arc
					(start 125.161548 -345.846146)
					(mid 125.542548 -345.465146)
					(end 125.161548 -345.084146)
				)
			)
		)
	)
	(zone
		(layers "F.Cu" "B.Cu" "In1.Cu" "In2.Cu" "In3.Cu" "In4.Cu" "In5.Cu" "In6.Cu"
			"In7.Cu" "In8.Cu" "In9.Cu" "In10.Cu" "In11.Cu" "In12.Cu" "In13.Cu" "In14.Cu"
			"In15.Cu" "In16.Cu"
		)
		(hatch none 0.5)
		(connect_pads
			(clearance 0)
		)
		(min_thickness 0.25)
		(keepout
			(tracks not_allowed)
			(vias allowed)
			(pads allowed)
			(copperpour not_allowed)
			(footprints allowed)
		)
		(placement
			(enabled no)
			(sheetname "")
		)
		(fill
			(thermal_gap 0.5)
			(thermal_bridge_width 0.5)
			(island_removal_mode 0)
		)
		(polygon
			(pts
				(arc
					(start 64.481202 -342.058498)
					(mid 64.100202 -342.439498)
					(end 64.481202 -342.820498)
				)
				(arc
					(start 65.344802 -342.820498)
					(mid 65.725802 -342.439498)
					(end 65.344802 -342.058498)
				)
			)
		)
	)
	(zone
		(layers "F.Cu" "B.Cu" "In1.Cu" "In2.Cu" "In3.Cu" "In4.Cu" "In5.Cu" "In6.Cu"
			"In7.Cu" "In8.Cu" "In9.Cu" "In10.Cu" "In11.Cu" "In12.Cu" "In13.Cu" "In14.Cu"
			"In15.Cu" "In16.Cu"
		)
		(hatch none 0.5)
		(connect_pads
			(clearance 0)
		)
		(min_thickness 0.25)
		(keepout
			(tracks not_allowed)
			(vias allowed)
			(pads allowed)
			(copperpour not_allowed)
			(footprints allowed)
		)
		(placement
			(enabled no)
			(sheetname "")
		)
		(fill
			(thermal_gap 0.5)
			(thermal_bridge_width 0.5)
			(island_removal_mode 0)
		)
		(polygon
			(pts
				(arc
					(start 161.700972 -400.92884)
					(mid 161.715851 -400.892919)
					(end 161.751772 -400.87804)
				)
				(arc
					(start 162.468052 -400.87804)
					(mid 162.503973 -400.892919)
					(end 162.518852 -400.92884)
				)
				(arc
					(start 162.518852 -403.351492)
					(mid 162.503973 -403.387413)
					(end 162.468052 -403.402292)
				)
				(arc
					(start 161.751772 -403.402292)
					(mid 161.715851 -403.387413)
					(end 161.700972 -403.351492)
				)
			)
		)
	)
	(zone
		(layers "F.Cu" "B.Cu" "In1.Cu" "In2.Cu" "In3.Cu" "In4.Cu" "In5.Cu" "In6.Cu"
			"In7.Cu" "In8.Cu" "In9.Cu" "In10.Cu" "In11.Cu" "In12.Cu" "In13.Cu" "In14.Cu"
			"In15.Cu" "In16.Cu"
		)
		(hatch none 0.5)
		(connect_pads
			(clearance 0)
		)
		(min_thickness 0.25)
		(keepout
			(tracks not_allowed)
			(vias allowed)
			(pads allowed)
			(copperpour not_allowed)
			(footprints allowed)
		)
		(placement
			(enabled no)
			(sheetname "")
		)
		(fill
			(thermal_gap 0.5)
			(thermal_bridge_width 0.5)
			(island_removal_mode 0)
		)
		(polygon
			(pts
				(arc
					(start 305.974242 -95.214948)
					(mid 303.840642 -95.214948)
					(end 305.974242 -95.214948)
				)
			)
		)
	)
	(zone
		(layers "F.Cu" "B.Cu" "In1.Cu" "In2.Cu" "In3.Cu" "In4.Cu" "In5.Cu" "In6.Cu"
			"In7.Cu" "In8.Cu" "In9.Cu" "In10.Cu" "In11.Cu" "In12.Cu" "In13.Cu" "In14.Cu"
			"In15.Cu" "In16.Cu"
		)
		(hatch none 0.5)
		(connect_pads
			(clearance 0)
		)
		(min_thickness 0.25)
		(keepout
			(tracks not_allowed)
			(vias allowed)
			(pads allowed)
			(copperpour not_allowed)
			(footprints allowed)
		)
		(placement
			(enabled no)
			(sheetname "")
		)
		(fill
			(thermal_gap 0.5)
			(thermal_bridge_width 0.5)
			(island_removal_mode 0)
		)
		(polygon
			(pts
				(arc
					(start 289.280854 -382.728724)
					(mid 289.295733 -382.692803)
					(end 289.331654 -382.677924)
				)
				(arc
					(start 290.047934 -382.677924)
					(mid 290.083855 -382.692803)
					(end 290.098734 -382.728724)
				)
				(arc
					(start 290.098734 -385.151376)
					(mid 290.083855 -385.187297)
					(end 290.047934 -385.202176)
				)
				(arc
					(start 289.331654 -385.202176)
					(mid 289.295733 -385.187297)
					(end 289.280854 -385.151376)
				)
			)
		)
	)
	(zone
		(layers "F.Cu" "B.Cu" "In1.Cu" "In2.Cu" "In3.Cu" "In4.Cu" "In5.Cu" "In6.Cu"
			"In7.Cu" "In8.Cu" "In9.Cu" "In10.Cu" "In11.Cu" "In12.Cu" "In13.Cu" "In14.Cu"
			"In15.Cu" "In16.Cu"
		)
		(hatch none 0.5)
		(connect_pads
			(clearance 0)
		)
		(min_thickness 0.25)
		(keepout
			(tracks not_allowed)
			(vias allowed)
			(pads allowed)
			(copperpour not_allowed)
			(footprints allowed)
		)
		(placement
			(enabled no)
			(sheetname "")
		)
		(fill
			(thermal_gap 0.5)
			(thermal_bridge_width 0.5)
			(island_removal_mode 0)
		)
		(polygon
			(pts
				(arc
					(start 73.700894 -397.028924)
					(mid 73.715773 -396.993003)
					(end 73.751694 -396.978124)
				)
				(arc
					(start 74.467974 -396.978124)
					(mid 74.503895 -396.993003)
					(end 74.518774 -397.028924)
				)
				(arc
					(start 74.518774 -399.451576)
					(mid 74.503895 -399.487497)
					(end 74.467974 -399.502376)
				)
				(arc
					(start 73.751694 -399.502376)
					(mid 73.715773 -399.487497)
					(end 73.700894 -399.451576)
				)
			)
		)
	)
	(zone
		(layers "F.Cu" "B.Cu" "In1.Cu" "In2.Cu" "In3.Cu" "In4.Cu" "In5.Cu" "In6.Cu"
			"In7.Cu" "In8.Cu" "In9.Cu" "In10.Cu" "In11.Cu" "In12.Cu" "In13.Cu" "In14.Cu"
			"In15.Cu" "In16.Cu"
		)
		(hatch none 0.5)
		(connect_pads
			(clearance 0)
		)
		(min_thickness 0.25)
		(keepout
			(tracks not_allowed)
			(vias allowed)
			(pads allowed)
			(copperpour not_allowed)
			(footprints allowed)
		)
		(placement
			(enabled no)
			(sheetname "")
		)
		(fill
			(thermal_gap 0.5)
			(thermal_bridge_width 0.5)
			(island_removal_mode 0)
		)
		(polygon
			(pts
				(arc
					(start 168.301162 -377.728734)
					(mid 168.316041 -377.692813)
					(end 168.351962 -377.677934)
				)
				(arc
					(start 169.068242 -377.677934)
					(mid 169.104163 -377.692813)
					(end 169.119042 -377.728734)
				)
				(arc
					(start 169.119042 -380.151386)
					(mid 169.104163 -380.187307)
					(end 169.068242 -380.202186)
				)
				(arc
					(start 168.351962 -380.202186)
					(mid 168.316041 -380.187307)
					(end 168.301162 -380.151386)
				)
			)
		)
	)
	(zone
		(layers "F.Cu" "B.Cu" "In1.Cu" "In2.Cu" "In3.Cu" "In4.Cu" "In5.Cu" "In6.Cu"
			"In7.Cu" "In8.Cu" "In9.Cu" "In10.Cu" "In11.Cu" "In12.Cu" "In13.Cu" "In14.Cu"
			"In15.Cu" "In16.Cu"
		)
		(hatch none 0.5)
		(connect_pads
			(clearance 0)
		)
		(min_thickness 0.25)
		(keepout
			(tracks not_allowed)
			(vias allowed)
			(pads allowed)
			(copperpour not_allowed)
			(footprints allowed)
		)
		(placement
			(enabled no)
			(sheetname "")
		)
		(fill
			(thermal_gap 0.5)
			(thermal_bridge_width 0.5)
			(island_removal_mode 0)
		)
		(polygon
			(pts
				(arc
					(start 412.404052 -345.084146)
					(mid 412.023052 -345.465146)
					(end 412.404052 -345.846146)
				)
				(arc
					(start 413.267652 -345.846146)
					(mid 413.648652 -345.465146)
					(end 413.267652 -345.084146)
				)
			)
		)
	)
	(zone
		(layers "F.Cu" "B.Cu" "In1.Cu" "In2.Cu" "In3.Cu" "In4.Cu" "In5.Cu" "In6.Cu"
			"In7.Cu" "In8.Cu" "In9.Cu" "In10.Cu" "In11.Cu" "In12.Cu" "In13.Cu" "In14.Cu"
			"In15.Cu" "In16.Cu"
		)
		(hatch none 0.5)
		(connect_pads
			(clearance 0)
		)
		(min_thickness 0.25)
		(keepout
			(tracks not_allowed)
			(vias allowed)
			(pads allowed)
			(copperpour not_allowed)
			(footprints allowed)
		)
		(placement
			(enabled no)
			(sheetname "")
		)
		(fill
			(thermal_gap 0.5)
			(thermal_bridge_width 0.5)
			(island_removal_mode 0)
		)
		(polygon
			(pts
				(arc
					(start 44.204128 -351.230438)
					(mid 43.823128 -351.611438)
					(end 44.204128 -351.992438)
				)
				(arc
					(start 45.067728 -351.992438)
					(mid 45.448728 -351.611438)
					(end 45.067728 -351.230438)
				)
			)
		)
	)
	(zone
		(layers "F.Cu" "B.Cu" "In1.Cu" "In2.Cu" "In3.Cu" "In4.Cu" "In5.Cu" "In6.Cu"
			"In7.Cu" "In8.Cu" "In9.Cu" "In10.Cu" "In11.Cu" "In12.Cu" "In13.Cu" "In14.Cu"
			"In15.Cu" "In16.Cu"
		)
		(hatch none 0.5)
		(connect_pads
			(clearance 0)
		)
		(min_thickness 0.25)
		(keepout
			(tracks not_allowed)
			(vias allowed)
			(pads allowed)
			(copperpour not_allowed)
			(footprints allowed)
		)
		(placement
			(enabled no)
			(sheetname "")
		)
		(fill
			(thermal_gap 0.5)
			(thermal_bridge_width 0.5)
			(island_removal_mode 0)
		)
		(polygon
			(pts
				(arc
					(start 384.537204 -231.330754)
					(mid 384.994404 -230.873554)
					(end 384.537204 -230.416354)
				)
				(arc
					(start 383.673604 -230.416354)
					(mid 383.216404 -230.873554)
					(end 383.673604 -231.330754)
				)
			)
		)
	)
	(zone
		(layers "F.Cu" "B.Cu" "In1.Cu" "In2.Cu" "In3.Cu" "In4.Cu" "In5.Cu" "In6.Cu"
			"In7.Cu" "In8.Cu" "In9.Cu" "In10.Cu" "In11.Cu" "In12.Cu" "In13.Cu" "In14.Cu"
			"In15.Cu" "In16.Cu"
		)
		(hatch none 0.5)
		(connect_pads
			(clearance 0)
		)
		(min_thickness 0.25)
		(keepout
			(tracks not_allowed)
			(vias allowed)
			(pads allowed)
			(copperpour not_allowed)
			(footprints allowed)
		)
		(placement
			(enabled no)
			(sheetname "")
		)
		(fill
			(thermal_gap 0.5)
			(thermal_bridge_width 0.5)
			(island_removal_mode 0)
		)
		(polygon
			(pts
				(arc
					(start 130.515868 -348.20479)
					(mid 130.134868 -348.58579)
					(end 130.515868 -348.96679)
				)
				(arc
					(start 131.379468 -348.96679)
					(mid 131.760468 -348.58579)
					(end 131.379468 -348.20479)
				)
			)
		)
	)
	(zone
		(layers "F.Cu" "B.Cu" "In1.Cu" "In2.Cu" "In3.Cu" "In4.Cu" "In5.Cu" "In6.Cu"
			"In7.Cu" "In8.Cu" "In9.Cu" "In10.Cu" "In11.Cu" "In12.Cu" "In13.Cu" "In14.Cu"
			"In15.Cu" "In16.Cu"
		)
		(hatch none 0.5)
		(connect_pads
			(clearance 0)
		)
		(min_thickness 0.25)
		(keepout
			(tracks not_allowed)
			(vias allowed)
			(pads allowed)
			(copperpour not_allowed)
			(footprints allowed)
		)
		(placement
			(enabled no)
			(sheetname "")
		)
		(fill
			(thermal_gap 0.5)
			(thermal_bridge_width 0.5)
			(island_removal_mode 0)
		)
		(polygon
			(pts
				(arc
					(start 25.550368 -354.351082)
					(mid 25.169368 -354.732082)
					(end 25.550368 -355.113082)
				)
				(arc
					(start 26.413968 -355.113082)
					(mid 26.794968 -354.732082)
					(end 26.413968 -354.351082)
				)
			)
		)
	)
	(zone
		(layers "F.Cu" "B.Cu" "In1.Cu" "In2.Cu" "In3.Cu" "In4.Cu" "In5.Cu" "In6.Cu"
			"In7.Cu" "In8.Cu" "In9.Cu" "In10.Cu" "In11.Cu" "In12.Cu" "In13.Cu" "In14.Cu"
			"In15.Cu" "In16.Cu"
		)
		(hatch none 0.5)
		(connect_pads
			(clearance 0)
		)
		(min_thickness 0.25)
		(keepout
			(tracks not_allowed)
			(vias allowed)
			(pads allowed)
			(copperpour not_allowed)
			(footprints allowed)
		)
		(placement
			(enabled no)
			(sheetname "")
		)
		(fill
			(thermal_gap 0.5)
			(thermal_bridge_width 0.5)
			(island_removal_mode 0)
		)
		(polygon
			(pts
				(arc
					(start 331.156564 -342.058498)
					(mid 330.775564 -342.439498)
					(end 331.156564 -342.820498)
				)
				(arc
					(start 332.020164 -342.820498)
					(mid 332.401164 -342.439498)
					(end 332.020164 -342.058498)
				)
			)
		)
	)
	(zone
		(layers "F.Cu" "B.Cu" "In1.Cu" "In2.Cu" "In3.Cu" "In4.Cu" "In5.Cu" "In6.Cu"
			"In7.Cu" "In8.Cu" "In9.Cu" "In10.Cu" "In11.Cu" "In12.Cu" "In13.Cu" "In14.Cu"
			"In15.Cu" "In16.Cu"
		)
		(hatch none 0.5)
		(connect_pads
			(clearance 0)
		)
		(min_thickness 0.25)
		(keepout
			(tracks not_allowed)
			(vias allowed)
			(pads allowed)
			(copperpour not_allowed)
			(footprints allowed)
		)
		(placement
			(enabled no)
			(sheetname "")
		)
		(fill
			(thermal_gap 0.5)
			(thermal_bridge_width 0.5)
			(island_removal_mode 0)
		)
		(polygon
			(pts
				(arc
					(start 180.845968 -136.177274)
					(mid 181.303168 -136.634474)
					(end 181.760368 -136.177274)
				)
				(arc
					(start 181.760368 -135.313674)
					(mid 181.303168 -134.856474)
					(end 180.845968 -135.313674)
				)
			)
		)
	)
	(zone
		(layers "F.Cu" "B.Cu" "In1.Cu" "In2.Cu" "In3.Cu" "In4.Cu" "In5.Cu" "In6.Cu"
			"In7.Cu" "In8.Cu" "In9.Cu" "In10.Cu" "In11.Cu" "In12.Cu" "In13.Cu" "In14.Cu"
			"In15.Cu" "In16.Cu"
		)
		(hatch none 0.5)
		(connect_pads
			(clearance 0)
		)
		(min_thickness 0.25)
		(keepout
			(tracks not_allowed)
			(vias allowed)
			(pads allowed)
			(copperpour not_allowed)
			(footprints allowed)
		)
		(placement
			(enabled no)
			(sheetname "")
		)
		(fill
			(thermal_gap 0.5)
			(thermal_bridge_width 0.5)
			(island_removal_mode 0)
		)
		(polygon
			(pts
				(arc
					(start 418.621972 -351.230438)
					(mid 418.240972 -351.611438)
					(end 418.621972 -351.992438)
				)
				(arc
					(start 419.485572 -351.992438)
					(mid 419.866572 -351.611438)
					(end 419.485572 -351.230438)
				)
			)
		)
	)
	(zone
		(layers "F.Cu" "B.Cu" "In1.Cu" "In2.Cu" "In3.Cu" "In4.Cu" "In5.Cu" "In6.Cu"
			"In7.Cu" "In8.Cu" "In9.Cu" "In10.Cu" "In11.Cu" "In12.Cu" "In13.Cu" "In14.Cu"
			"In15.Cu" "In16.Cu"
		)
		(hatch none 0.5)
		(connect_pads
			(clearance 0)
		)
		(min_thickness 0.25)
		(keepout
			(tracks not_allowed)
			(vias allowed)
			(pads allowed)
			(copperpour not_allowed)
			(footprints allowed)
		)
		(placement
			(enabled no)
			(sheetname "")
		)
		(fill
			(thermal_gap 0.5)
			(thermal_bridge_width 0.5)
			(island_removal_mode 0)
		)
		(polygon
			(pts
				(arc
					(start 233.515662 -87.8713)
					(mid 233.972862 -87.4141)
					(end 233.515662 -86.9569)
				)
				(arc
					(start 232.652062 -86.9569)
					(mid 232.194862 -87.4141)
					(end 232.652062 -87.8713)
				)
			)
		)
	)
	(zone
		(layers "F.Cu" "B.Cu" "In1.Cu" "In2.Cu" "In3.Cu" "In4.Cu" "In5.Cu" "In6.Cu"
			"In7.Cu" "In8.Cu" "In9.Cu" "In10.Cu" "In11.Cu" "In12.Cu" "In13.Cu" "In14.Cu"
			"In15.Cu" "In16.Cu"
		)
		(hatch none 0.5)
		(connect_pads
			(clearance 0)
		)
		(min_thickness 0.25)
		(keepout
			(tracks not_allowed)
			(vias allowed)
			(pads allowed)
			(copperpour not_allowed)
			(footprints allowed)
		)
		(placement
			(enabled no)
			(sheetname "")
		)
		(fill
			(thermal_gap 0.5)
			(thermal_bridge_width 0.5)
			(island_removal_mode 0)
		)
		(polygon
			(pts
				(arc
					(start 44.848018 -32.714184)
					(mid 45.305218 -33.171384)
					(end 45.762418 -32.714184)
				)
				(arc
					(start 45.762418 -31.850584)
					(mid 45.305218 -31.393384)
					(end 44.848018 -31.850584)
				)
			)
		)
	)
	(zone
		(layers "F.Cu" "B.Cu" "In1.Cu" "In2.Cu" "In3.Cu" "In4.Cu" "In5.Cu" "In6.Cu"
			"In7.Cu" "In8.Cu" "In9.Cu" "In10.Cu" "In11.Cu" "In12.Cu" "In13.Cu" "In14.Cu"
			"In15.Cu" "In16.Cu"
		)
		(hatch none 0.5)
		(connect_pads
			(clearance 0)
		)
		(min_thickness 0.25)
		(keepout
			(tracks not_allowed)
			(vias allowed)
			(pads allowed)
			(copperpour not_allowed)
			(footprints allowed)
		)
		(placement
			(enabled no)
			(sheetname "")
		)
		(fill
			(thermal_gap 0.5)
			(thermal_bridge_width 0.5)
			(island_removal_mode 0)
		)
		(polygon
			(pts
				(arc
					(start 132.624322 -27.342846)
					(mid 133.081522 -27.800046)
					(end 133.538722 -27.342846)
				)
				(arc
					(start 133.538722 -26.479246)
					(mid 133.081522 -26.022046)
					(end 132.624322 -26.479246)
				)
			)
		)
	)
	(zone
		(layers "F.Cu" "B.Cu" "In1.Cu" "In2.Cu" "In3.Cu" "In4.Cu" "In5.Cu" "In6.Cu"
			"In7.Cu" "In8.Cu" "In9.Cu" "In10.Cu" "In11.Cu" "In12.Cu" "In13.Cu" "In14.Cu"
			"In15.Cu" "In16.Cu"
		)
		(hatch none 0.5)
		(connect_pads
			(clearance 0)
		)
		(min_thickness 0.25)
		(keepout
			(tracks not_allowed)
			(vias allowed)
			(pads allowed)
			(copperpour not_allowed)
			(footprints allowed)
		)
		(placement
			(enabled no)
			(sheetname "")
		)
		(fill
			(thermal_gap 0.5)
			(thermal_bridge_width 0.5)
			(island_removal_mode 0)
		)
		(polygon
			(pts
				(arc
					(start 382.9685 -131.297934)
					(mid 383.4257 -131.755134)
					(end 383.8829 -131.297934)
				)
				(arc
					(start 383.8829 -130.434334)
					(mid 383.4257 -129.977134)
					(end 382.9685 -130.434334)
				)
			)
		)
	)
	(zone
		(layers "F.Cu" "B.Cu" "In1.Cu" "In2.Cu" "In3.Cu" "In4.Cu" "In5.Cu" "In6.Cu"
			"In7.Cu" "In8.Cu" "In9.Cu" "In10.Cu" "In11.Cu" "In12.Cu" "In13.Cu" "In14.Cu"
			"In15.Cu" "In16.Cu"
		)
		(hatch none 0.5)
		(connect_pads
			(clearance 0)
		)
		(min_thickness 0.25)
		(keepout
			(tracks not_allowed)
			(vias allowed)
			(pads allowed)
			(copperpour not_allowed)
			(footprints allowed)
		)
		(placement
			(enabled no)
			(sheetname "")
		)
		(fill
			(thermal_gap 0.5)
			(thermal_bridge_width 0.5)
			(island_removal_mode 0)
		)
		(polygon
			(pts
				(arc
					(start 78.100936 -397.028924)
					(mid 78.115815 -396.993003)
					(end 78.151736 -396.978124)
				)
				(arc
					(start 78.868016 -396.978124)
					(mid 78.903937 -396.993003)
					(end 78.918816 -397.028924)
				)
				(arc
					(start 78.918816 -399.451576)
					(mid 78.903937 -399.487497)
					(end 78.868016 -399.502376)
				)
				(arc
					(start 78.151736 -399.502376)
					(mid 78.115815 -399.487497)
					(end 78.100936 -399.451576)
				)
			)
		)
	)
	(zone
		(layers "F.Cu" "B.Cu" "In1.Cu" "In2.Cu" "In3.Cu" "In4.Cu" "In5.Cu" "In6.Cu"
			"In7.Cu" "In8.Cu" "In9.Cu" "In10.Cu" "In11.Cu" "In12.Cu" "In13.Cu" "In14.Cu"
			"In15.Cu" "In16.Cu"
		)
		(hatch none 0.5)
		(connect_pads
			(clearance 0)
		)
		(min_thickness 0.25)
		(keepout
			(tracks not_allowed)
			(vias allowed)
			(pads allowed)
			(copperpour not_allowed)
			(footprints allowed)
		)
		(placement
			(enabled no)
			(sheetname "")
		)
		(fill
			(thermal_gap 0.5)
			(thermal_bridge_width 0.5)
			(island_removal_mode 0)
		)
		(polygon
			(pts
				(arc
					(start 83.71713 -145.285714)
					(mid 84.17433 -145.742914)
					(end 84.63153 -145.285714)
				)
				(arc
					(start 84.63153 -144.422114)
					(mid 84.17433 -143.964914)
					(end 83.71713 -144.422114)
				)
			)
		)
	)
	(zone
		(layers "F.Cu" "B.Cu" "In1.Cu" "In2.Cu" "In3.Cu" "In4.Cu" "In5.Cu" "In6.Cu"
			"In7.Cu" "In8.Cu" "In9.Cu" "In10.Cu" "In11.Cu" "In12.Cu" "In13.Cu" "In14.Cu"
			"In15.Cu" "In16.Cu"
		)
		(hatch none 0.5)
		(connect_pads
			(clearance 0)
		)
		(min_thickness 0.25)
		(keepout
			(tracks not_allowed)
			(vias allowed)
			(pads allowed)
			(copperpour not_allowed)
			(footprints allowed)
		)
		(placement
			(enabled no)
			(sheetname "")
		)
		(fill
			(thermal_gap 0.5)
			(thermal_bridge_width 0.5)
			(island_removal_mode 0)
		)
		(polygon
			(pts
				(arc
					(start 228.892608 -78.374494)
					(mid 228.435408 -77.917294)
					(end 227.978208 -78.374494)
				)
				(arc
					(start 227.978208 -79.238094)
					(mid 228.435408 -79.695294)
					(end 228.892608 -79.238094)
				)
			)
		)
	)
	(zone
		(layers "F.Cu" "B.Cu" "In1.Cu" "In2.Cu" "In3.Cu" "In4.Cu" "In5.Cu" "In6.Cu"
			"In7.Cu" "In8.Cu" "In9.Cu" "In10.Cu" "In11.Cu" "In12.Cu" "In13.Cu" "In14.Cu"
			"In15.Cu" "In16.Cu"
		)
		(hatch none 0.5)
		(connect_pads
			(clearance 0)
		)
		(min_thickness 0.25)
		(keepout
			(tracks not_allowed)
			(vias allowed)
			(pads allowed)
			(copperpour not_allowed)
			(footprints allowed)
		)
		(placement
			(enabled no)
			(sheetname "")
		)
		(fill
			(thermal_gap 0.5)
			(thermal_bridge_width 0.5)
			(island_removal_mode 0)
		)
		(polygon
			(pts
				(arc
					(start 200.853294 -30.922468)
					(mid 201.310494 -31.379668)
					(end 201.767694 -30.922468)
				)
				(arc
					(start 201.767694 -30.058868)
					(mid 201.310494 -29.601668)
					(end 200.853294 -30.058868)
				)
			)
		)
	)
	(zone
		(layers "F.Cu" "B.Cu" "In1.Cu" "In2.Cu" "In3.Cu" "In4.Cu" "In5.Cu" "In6.Cu"
			"In7.Cu" "In8.Cu" "In9.Cu" "In10.Cu" "In11.Cu" "In12.Cu" "In13.Cu" "In14.Cu"
			"In15.Cu" "In16.Cu"
		)
		(hatch none 0.5)
		(connect_pads
			(clearance 0)
		)
		(min_thickness 0.25)
		(keepout
			(tracks not_allowed)
			(vias allowed)
			(pads allowed)
			(copperpour not_allowed)
			(footprints allowed)
		)
		(placement
			(enabled no)
			(sheetname "")
		)
		(fill
			(thermal_gap 0.5)
			(thermal_bridge_width 0.5)
			(island_removal_mode 0)
		)
		(polygon
			(pts
				(arc
					(start 78.100936 -408.728672)
					(mid 78.115815 -408.692751)
					(end 78.151736 -408.677872)
				)
				(arc
					(start 78.868016 -408.677872)
					(mid 78.903937 -408.692751)
					(end 78.918816 -408.728672)
				)
				(arc
					(start 78.918816 -411.151324)
					(mid 78.903937 -411.187245)
					(end 78.868016 -411.202124)
				)
				(arc
					(start 78.151736 -411.202124)
					(mid 78.115815 -411.187245)
					(end 78.100936 -411.151324)
				)
			)
		)
	)
	(zone
		(layers "F.Cu" "B.Cu" "In1.Cu" "In2.Cu" "In3.Cu" "In4.Cu" "In5.Cu" "In6.Cu"
			"In7.Cu" "In8.Cu" "In9.Cu" "In10.Cu" "In11.Cu" "In12.Cu" "In13.Cu" "In14.Cu"
			"In15.Cu" "In16.Cu"
		)
		(hatch none 0.5)
		(connect_pads
			(clearance 0)
		)
		(min_thickness 0.25)
		(keepout
			(tracks not_allowed)
			(vias allowed)
			(pads allowed)
			(copperpour not_allowed)
			(footprints allowed)
		)
		(placement
			(enabled no)
			(sheetname "")
		)
		(fill
			(thermal_gap 0.5)
			(thermal_bridge_width 0.5)
			(island_removal_mode 0)
		)
		(polygon
			(pts
				(arc
					(start 29.700982 -382.728724)
					(mid 29.715861 -382.692803)
					(end 29.751782 -382.677924)
				)
				(arc
					(start 30.468062 -382.677924)
					(mid 30.503983 -382.692803)
					(end 30.518862 -382.728724)
				)
				(arc
					(start 30.518862 -385.151376)
					(mid 30.503983 -385.187297)
					(end 30.468062 -385.202176)
				)
				(arc
					(start 29.751782 -385.202176)
					(mid 29.715861 -385.187297)
					(end 29.700982 -385.151376)
				)
			)
		)
	)
	(zone
		(layers "F.Cu" "B.Cu" "In1.Cu" "In2.Cu" "In3.Cu" "In4.Cu" "In5.Cu" "In6.Cu"
			"In7.Cu" "In8.Cu" "In9.Cu" "In10.Cu" "In11.Cu" "In12.Cu" "In13.Cu" "In14.Cu"
			"In15.Cu" "In16.Cu"
		)
		(hatch none 0.5)
		(connect_pads
			(clearance 0)
		)
		(min_thickness 0.25)
		(keepout
			(tracks not_allowed)
			(vias allowed)
			(pads allowed)
			(copperpour not_allowed)
			(footprints allowed)
		)
		(placement
			(enabled no)
			(sheetname "")
		)
		(fill
			(thermal_gap 0.5)
			(thermal_bridge_width 0.5)
			(island_removal_mode 0)
		)
		(polygon
			(pts
				(arc
					(start 321.829684 -354.351082)
					(mid 321.448684 -354.732082)
					(end 321.829684 -355.113082)
				)
				(arc
					(start 322.693284 -355.113082)
					(mid 323.074284 -354.732082)
					(end 322.693284 -354.351082)
				)
			)
		)
	)
	(zone
		(layers "F.Cu" "B.Cu" "In1.Cu" "In2.Cu" "In3.Cu" "In4.Cu" "In5.Cu" "In6.Cu"
			"In7.Cu" "In8.Cu" "In9.Cu" "In10.Cu" "In11.Cu" "In12.Cu" "In13.Cu" "In14.Cu"
			"In15.Cu" "In16.Cu"
		)
		(hatch none 0.5)
		(connect_pads
			(clearance 0)
		)
		(min_thickness 0.25)
		(keepout
			(tracks not_allowed)
			(vias allowed)
			(pads allowed)
			(copperpour not_allowed)
			(footprints allowed)
		)
		(placement
			(enabled no)
			(sheetname "")
		)
		(fill
			(thermal_gap 0.5)
			(thermal_bridge_width 0.5)
			(island_removal_mode 0)
		)
		(polygon
			(pts
				(arc
					(start 425.680886 -378.828554)
					(mid 425.695765 -378.792633)
					(end 425.731686 -378.777754)
				)
				(arc
					(start 426.447966 -378.777754)
					(mid 426.483887 -378.792633)
					(end 426.498766 -378.828554)
				)
				(arc
					(start 426.498766 -381.251206)
					(mid 426.483887 -381.287127)
					(end 426.447966 -381.302006)
				)
				(arc
					(start 425.731686 -381.302006)
					(mid 425.695765 -381.287127)
					(end 425.680886 -381.251206)
				)
			)
		)
	)
	(zone
		(layers "F.Cu" "B.Cu" "In1.Cu" "In2.Cu" "In3.Cu" "In4.Cu" "In5.Cu" "In6.Cu"
			"In7.Cu" "In8.Cu" "In9.Cu" "In10.Cu" "In11.Cu" "In12.Cu" "In13.Cu" "In14.Cu"
			"In15.Cu" "In16.Cu"
		)
		(hatch none 0.5)
		(connect_pads
			(clearance 0)
		)
		(min_thickness 0.25)
		(keepout
			(tracks not_allowed)
			(vias allowed)
			(pads allowed)
			(copperpour not_allowed)
			(footprints allowed)
		)
		(placement
			(enabled no)
			(sheetname "")
		)
		(fill
			(thermal_gap 0.5)
			(thermal_bridge_width 0.5)
			(island_removal_mode 0)
		)
		(polygon
			(pts
				(arc
					(start 318.807338 -32.722312)
					(mid 319.264538 -33.179512)
					(end 319.721738 -32.722312)
				)
				(arc
					(start 319.721738 -31.858712)
					(mid 319.264538 -31.401512)
					(end 318.807338 -31.858712)
				)
			)
		)
	)
	(zone
		(layers "F.Cu" "B.Cu" "In1.Cu" "In2.Cu" "In3.Cu" "In4.Cu" "In5.Cu" "In6.Cu"
			"In7.Cu" "In8.Cu" "In9.Cu" "In10.Cu" "In11.Cu" "In12.Cu" "In13.Cu" "In14.Cu"
			"In15.Cu" "In16.Cu"
		)
		(hatch none 0.5)
		(connect_pads
			(clearance 0)
		)
		(min_thickness 0.25)
		(keepout
			(tracks not_allowed)
			(vias allowed)
			(pads allowed)
			(copperpour not_allowed)
			(footprints allowed)
		)
		(placement
			(enabled no)
			(sheetname "")
		)
		(fill
			(thermal_gap 0.5)
			(thermal_bridge_width 0.5)
			(island_removal_mode 0)
		)
		(polygon
			(pts
				(arc
					(start 64.481202 -357.37673)
					(mid 64.100202 -357.75773)
					(end 64.481202 -358.13873)
				)
				(arc
					(start 65.344802 -358.13873)
					(mid 65.725802 -357.75773)
					(end 65.344802 -357.37673)
				)
			)
		)
	)
	(zone
		(layers "F.Cu" "B.Cu" "In1.Cu" "In2.Cu" "In3.Cu" "In4.Cu" "In5.Cu" "In6.Cu"
			"In7.Cu" "In8.Cu" "In9.Cu" "In10.Cu" "In11.Cu" "In12.Cu" "In13.Cu" "In14.Cu"
			"In15.Cu" "In16.Cu"
		)
		(hatch none 0.5)
		(connect_pads
			(clearance 0)
		)
		(min_thickness 0.25)
		(keepout
			(tracks not_allowed)
			(vias allowed)
			(pads allowed)
			(copperpour not_allowed)
			(footprints allowed)
		)
		(placement
			(enabled no)
			(sheetname "")
		)
		(fill
			(thermal_gap 0.5)
			(thermal_bridge_width 0.5)
			(island_removal_mode 0)
		)
		(polygon
			(pts
				(arc
					(start 183.948832 -345.084146)
					(mid 183.567832 -345.465146)
					(end 183.948832 -345.846146)
				)
				(arc
					(start 184.812432 -345.846146)
					(mid 185.193432 -345.465146)
					(end 184.812432 -345.084146)
				)
			)
		)
	)
	(zone
		(layers "F.Cu" "B.Cu" "In1.Cu" "In2.Cu" "In3.Cu" "In4.Cu" "In5.Cu" "In6.Cu"
			"In7.Cu" "In8.Cu" "In9.Cu" "In10.Cu" "In11.Cu" "In12.Cu" "In13.Cu" "In14.Cu"
			"In15.Cu" "In16.Cu"
		)
		(hatch none 0.5)
		(connect_pads
			(clearance 0)
		)
		(min_thickness 0.25)
		(keepout
			(tracks not_allowed)
			(vias allowed)
			(pads allowed)
			(copperpour not_allowed)
			(footprints allowed)
		)
		(placement
			(enabled no)
			(sheetname "")
		)
		(fill
			(thermal_gap 0.5)
			(thermal_bridge_width 0.5)
			(island_removal_mode 0)
		)
		(polygon
			(pts
				(arc
					(start 302.48098 -404.828756)
					(mid 302.495859 -404.792835)
					(end 302.53178 -404.777956)
				)
				(arc
					(start 303.24806 -404.777956)
					(mid 303.283981 -404.792835)
					(end 303.29886 -404.828756)
				)
				(arc
					(start 303.29886 -407.251408)
					(mid 303.283981 -407.287329)
					(end 303.24806 -407.302208)
				)
				(arc
					(start 302.53178 -407.302208)
					(mid 302.495859 -407.287329)
					(end 302.48098 -407.251408)
				)
			)
		)
	)
	(zone
		(layers "F.Cu" "B.Cu" "In1.Cu" "In2.Cu" "In3.Cu" "In4.Cu" "In5.Cu" "In6.Cu"
			"In7.Cu" "In8.Cu" "In9.Cu" "In10.Cu" "In11.Cu" "In12.Cu" "In13.Cu" "In14.Cu"
			"In15.Cu" "In16.Cu"
		)
		(hatch none 0.5)
		(connect_pads
			(clearance 0)
		)
		(min_thickness 0.25)
		(keepout
			(tracks not_allowed)
			(vias allowed)
			(pads allowed)
			(copperpour not_allowed)
			(footprints allowed)
		)
		(placement
			(enabled no)
			(sheetname "")
		)
		(fill
			(thermal_gap 0.5)
			(thermal_bridge_width 0.5)
			(island_removal_mode 0)
		)
		(polygon
			(pts
				(arc
					(start 296.945812 -132.577332)
					(mid 297.403012 -133.034532)
					(end 297.860212 -132.577332)
				)
				(arc
					(start 297.860212 -131.713732)
					(mid 297.403012 -131.256532)
					(end 296.945812 -131.713732)
				)
			)
		)
	)
	(zone
		(layers "F.Cu" "B.Cu" "In1.Cu" "In2.Cu" "In3.Cu" "In4.Cu" "In5.Cu" "In6.Cu"
			"In7.Cu" "In8.Cu" "In9.Cu" "In10.Cu" "In11.Cu" "In12.Cu" "In13.Cu" "In14.Cu"
			"In15.Cu" "In16.Cu"
		)
		(hatch none 0.5)
		(connect_pads
			(clearance 0)
		)
		(min_thickness 0.25)
		(keepout
			(tracks not_allowed)
			(vias allowed)
			(pads allowed)
			(copperpour not_allowed)
			(footprints allowed)
		)
		(placement
			(enabled no)
			(sheetname "")
		)
		(fill
			(thermal_gap 0.5)
			(thermal_bridge_width 0.5)
			(island_removal_mode 0)
		)
		(polygon
			(pts
				(arc
					(start 388.23011 -36.60013)
					(mid 386.29971 -36.60013)
					(end 388.23011 -36.60013)
				)
			)
		)
	)
	(zone
		(layers "F.Cu" "B.Cu" "In1.Cu" "In2.Cu" "In3.Cu" "In4.Cu" "In5.Cu" "In6.Cu"
			"In7.Cu" "In8.Cu" "In9.Cu" "In10.Cu" "In11.Cu" "In12.Cu" "In13.Cu" "In14.Cu"
			"In15.Cu" "In16.Cu"
		)
		(hatch none 0.5)
		(connect_pads
			(clearance 0)
		)
		(min_thickness 0.25)
		(keepout
			(tracks not_allowed)
			(vias allowed)
			(pads allowed)
			(copperpour not_allowed)
			(footprints allowed)
		)
		(placement
			(enabled no)
			(sheetname "")
		)
		(fill
			(thermal_gap 0.5)
			(thermal_bridge_width 0.5)
			(island_removal_mode 0)
		)
		(polygon
			(pts
				(arc
					(start 197.17512 -130.769106)
					(mid 197.63232 -131.226306)
					(end 198.08952 -130.769106)
				)
				(arc
					(start 198.08952 -129.905506)
					(mid 197.63232 -129.448306)
					(end 197.17512 -129.905506)
				)
			)
		)
	)
	(zone
		(layers "F.Cu" "B.Cu" "In1.Cu" "In2.Cu" "In3.Cu" "In4.Cu" "In5.Cu" "In6.Cu"
			"In7.Cu" "In8.Cu" "In9.Cu" "In10.Cu" "In11.Cu" "In12.Cu" "In13.Cu" "In14.Cu"
			"In15.Cu" "In16.Cu"
		)
		(hatch none 0.5)
		(connect_pads
			(clearance 0)
		)
		(min_thickness 0.25)
		(keepout
			(tracks not_allowed)
			(vias allowed)
			(pads allowed)
			(copperpour not_allowed)
			(footprints allowed)
		)
		(placement
			(enabled no)
			(sheetname "")
		)
		(fill
			(thermal_gap 0.5)
			(thermal_bridge_width 0.5)
			(island_removal_mode 0)
		)
		(polygon
			(pts
				(arc
					(start 392.9507 -354.351082)
					(mid 392.5697 -354.732082)
					(end 392.9507 -355.113082)
				)
				(arc
					(start 393.8143 -355.113082)
					(mid 394.1953 -354.732082)
					(end 393.8143 -354.351082)
				)
			)
		)
	)
	(zone
		(layers "F.Cu" "B.Cu" "In1.Cu" "In2.Cu" "In3.Cu" "In4.Cu" "In5.Cu" "In6.Cu"
			"In7.Cu" "In8.Cu" "In9.Cu" "In10.Cu" "In11.Cu" "In12.Cu" "In13.Cu" "In14.Cu"
			"In15.Cu" "In16.Cu"
		)
		(hatch none 0.5)
		(connect_pads
			(clearance 0)
		)
		(min_thickness 0.25)
		(keepout
			(tracks not_allowed)
			(vias allowed)
			(pads allowed)
			(copperpour not_allowed)
			(footprints allowed)
		)
		(placement
			(enabled no)
			(sheetname "")
		)
		(fill
			(thermal_gap 0.5)
			(thermal_bridge_width 0.5)
			(island_removal_mode 0)
		)
		(polygon
			(pts
				(arc
					(start 47.30115 -404.828756)
					(mid 47.316029 -404.792835)
					(end 47.35195 -404.777956)
				)
				(arc
					(start 48.06823 -404.777956)
					(mid 48.104151 -404.792835)
					(end 48.11903 -404.828756)
				)
				(arc
					(start 48.11903 -407.251408)
					(mid 48.104151 -407.287329)
					(end 48.06823 -407.302208)
				)
				(arc
					(start 47.35195 -407.302208)
					(mid 47.316029 -407.287329)
					(end 47.30115 -407.251408)
				)
			)
		)
	)
	(zone
		(layers "F.Cu" "B.Cu" "In1.Cu" "In2.Cu" "In3.Cu" "In4.Cu" "In5.Cu" "In6.Cu"
			"In7.Cu" "In8.Cu" "In9.Cu" "In10.Cu" "In11.Cu" "In12.Cu" "In13.Cu" "In14.Cu"
			"In15.Cu" "In16.Cu"
		)
		(hatch none 0.5)
		(connect_pads
			(clearance 0)
		)
		(min_thickness 0.25)
		(keepout
			(tracks not_allowed)
			(vias allowed)
			(pads allowed)
			(copperpour not_allowed)
			(footprints allowed)
		)
		(placement
			(enabled no)
			(sheetname "")
		)
		(fill
			(thermal_gap 0.5)
			(thermal_bridge_width 0.5)
			(island_removal_mode 0)
		)
		(polygon
			(pts
				(arc
					(start 47.30115 -382.728724)
					(mid 47.316029 -382.692803)
					(end 47.35195 -382.677924)
				)
				(arc
					(start 48.06823 -382.677924)
					(mid 48.104151 -382.692803)
					(end 48.11903 -382.728724)
				)
				(arc
					(start 48.11903 -385.151376)
					(mid 48.104151 -385.187297)
					(end 48.06823 -385.202176)
				)
				(arc
					(start 47.35195 -385.202176)
					(mid 47.316029 -385.187297)
					(end 47.30115 -385.151376)
				)
			)
		)
	)
	(zone
		(layers "F.Cu" "B.Cu" "In1.Cu" "In2.Cu" "In3.Cu" "In4.Cu" "In5.Cu" "In6.Cu"
			"In7.Cu" "In8.Cu" "In9.Cu" "In10.Cu" "In11.Cu" "In12.Cu" "In13.Cu" "In14.Cu"
			"In15.Cu" "In16.Cu"
		)
		(hatch none 0.5)
		(connect_pads
			(clearance 0)
		)
		(min_thickness 0.25)
		(keepout
			(tracks not_allowed)
			(vias allowed)
			(pads allowed)
			(copperpour not_allowed)
			(footprints allowed)
		)
		(placement
			(enabled no)
			(sheetname "")
		)
		(fill
			(thermal_gap 0.5)
			(thermal_bridge_width 0.5)
			(island_removal_mode 0)
		)
		(polygon
			(pts
				(arc
					(start 237.5408 -80.183482)
					(mid 237.998 -80.640682)
					(end 238.4552 -80.183482)
				)
				(arc
					(start 238.4552 -79.319882)
					(mid 237.998 -78.862682)
					(end 237.5408 -79.319882)
				)
			)
		)
	)
	(zone
		(layers "F.Cu" "B.Cu" "In1.Cu" "In2.Cu" "In3.Cu" "In4.Cu" "In5.Cu" "In6.Cu"
			"In7.Cu" "In8.Cu" "In9.Cu" "In10.Cu" "In11.Cu" "In12.Cu" "In13.Cu" "In14.Cu"
			"In15.Cu" "In16.Cu"
		)
		(hatch none 0.5)
		(connect_pads
			(clearance 0)
		)
		(min_thickness 0.25)
		(keepout
			(tracks not_allowed)
			(vias allowed)
			(pads allowed)
			(copperpour not_allowed)
			(footprints allowed)
		)
		(placement
			(enabled no)
			(sheetname "")
		)
		(fill
			(thermal_gap 0.5)
			(thermal_bridge_width 0.5)
			(island_removal_mode 0)
		)
		(polygon
			(pts
				(arc
					(start 82.500978 -400.92884)
					(mid 82.515857 -400.892919)
					(end 82.551778 -400.87804)
				)
				(arc
					(start 83.268058 -400.87804)
					(mid 83.303979 -400.892919)
					(end 83.318858 -400.92884)
				)
				(arc
					(start 83.318858 -403.351492)
					(mid 83.303979 -403.387413)
					(end 83.268058 -403.402292)
				)
				(arc
					(start 82.551778 -403.402292)
					(mid 82.515857 -403.387413)
					(end 82.500978 -403.351492)
				)
			)
		)
	)
	(zone
		(layers "F.Cu" "B.Cu" "In1.Cu" "In2.Cu" "In3.Cu" "In4.Cu" "In5.Cu" "In6.Cu"
			"In7.Cu" "In8.Cu" "In9.Cu" "In10.Cu" "In11.Cu" "In12.Cu" "In13.Cu" "In14.Cu"
			"In15.Cu" "In16.Cu"
		)
		(hatch none 0.5)
		(connect_pads
			(clearance 0)
		)
		(min_thickness 0.25)
		(keepout
			(tracks not_allowed)
			(vias allowed)
			(pads allowed)
			(copperpour not_allowed)
			(footprints allowed)
		)
		(placement
			(enabled no)
			(sheetname "")
		)
		(fill
			(thermal_gap 0.5)
			(thermal_bridge_width 0.5)
			(island_removal_mode 0)
		)
		(polygon
			(pts
				(arc
					(start 142.18158 -180.901086)
					(mid 142.63878 -181.358286)
					(end 143.09598 -180.901086)
				)
				(arc
					(start 143.09598 -180.037486)
					(mid 142.63878 -179.580286)
					(end 142.18158 -180.037486)
				)
			)
		)
	)
	(zone
		(layers "F.Cu" "B.Cu" "In1.Cu" "In2.Cu" "In3.Cu" "In4.Cu" "In5.Cu" "In6.Cu"
			"In7.Cu" "In8.Cu" "In9.Cu" "In10.Cu" "In11.Cu" "In12.Cu" "In13.Cu" "In14.Cu"
			"In15.Cu" "In16.Cu"
		)
		(hatch none 0.5)
		(connect_pads
			(clearance 0)
		)
		(min_thickness 0.25)
		(keepout
			(tracks not_allowed)
			(vias allowed)
			(pads allowed)
			(copperpour not_allowed)
			(footprints allowed)
		)
		(placement
			(enabled no)
			(sheetname "")
		)
		(fill
			(thermal_gap 0.5)
			(thermal_bridge_width 0.5)
			(island_removal_mode 0)
		)
		(polygon
			(pts
				(arc
					(start 34.101024 -374.928638)
					(mid 34.115903 -374.892717)
					(end 34.151824 -374.877838)
				)
				(arc
					(start 34.868104 -374.877838)
					(mid 34.904025 -374.892717)
					(end 34.918904 -374.928638)
				)
				(arc
					(start 34.918904 -377.35129)
					(mid 34.904025 -377.387211)
					(end 34.868104 -377.40209)
				)
				(arc
					(start 34.151824 -377.40209)
					(mid 34.115903 -377.387211)
					(end 34.101024 -377.35129)
				)
			)
		)
	)
	(zone
		(layers "F.Cu" "B.Cu" "In1.Cu" "In2.Cu" "In3.Cu" "In4.Cu" "In5.Cu" "In6.Cu"
			"In7.Cu" "In8.Cu" "In9.Cu" "In10.Cu" "In11.Cu" "In12.Cu" "In13.Cu" "In14.Cu"
			"In15.Cu" "In16.Cu"
		)
		(hatch none 0.5)
		(connect_pads
			(clearance 0)
		)
		(min_thickness 0.25)
		(keepout
			(tracks not_allowed)
			(vias allowed)
			(pads allowed)
			(copperpour not_allowed)
			(footprints allowed)
		)
		(placement
			(enabled no)
			(sheetname "")
		)
		(fill
			(thermal_gap 0.5)
			(thermal_bridge_width 0.5)
			(island_removal_mode 0)
		)
		(polygon
			(pts
				(arc
					(start 19.332448 -345.084146)
					(mid 18.951448 -345.465146)
					(end 19.332448 -345.846146)
				)
				(arc
					(start 20.196048 -345.846146)
					(mid 20.577048 -345.465146)
					(end 20.196048 -345.084146)
				)
			)
		)
	)
	(zone
		(layers "F.Cu" "B.Cu" "In1.Cu" "In2.Cu" "In3.Cu" "In4.Cu" "In5.Cu" "In6.Cu"
			"In7.Cu" "In8.Cu" "In9.Cu" "In10.Cu" "In11.Cu" "In12.Cu" "In13.Cu" "In14.Cu"
			"In15.Cu" "In16.Cu"
		)
		(hatch none 0.5)
		(connect_pads
			(clearance 0)
		)
		(min_thickness 0.25)
		(keepout
			(tracks not_allowed)
			(vias allowed)
			(pads allowed)
			(copperpour not_allowed)
			(footprints allowed)
		)
		(placement
			(enabled no)
			(sheetname "")
		)
		(fill
			(thermal_gap 0.5)
			(thermal_bridge_width 0.5)
			(island_removal_mode 0)
		)
		(polygon
			(pts
				(arc
					(start 434.48097 -378.828554)
					(mid 434.495849 -378.792633)
					(end 434.53177 -378.777754)
				)
				(arc
					(start 435.24805 -378.777754)
					(mid 435.283971 -378.792633)
					(end 435.29885 -378.828554)
				)
				(arc
					(start 435.29885 -381.251206)
					(mid 435.283971 -381.287127)
					(end 435.24805 -381.302006)
				)
				(arc
					(start 434.53177 -381.302006)
					(mid 434.495849 -381.287127)
					(end 434.48097 -381.251206)
				)
			)
		)
	)
	(zone
		(layers "F.Cu" "B.Cu" "In1.Cu" "In2.Cu" "In3.Cu" "In4.Cu" "In5.Cu" "In6.Cu"
			"In7.Cu" "In8.Cu" "In9.Cu" "In10.Cu" "In11.Cu" "In12.Cu" "In13.Cu" "In14.Cu"
			"In15.Cu" "In16.Cu"
		)
		(hatch none 0.5)
		(connect_pads
			(clearance 0)
		)
		(min_thickness 0.25)
		(keepout
			(tracks not_allowed)
			(vias allowed)
			(pads allowed)
			(copperpour not_allowed)
			(footprints allowed)
		)
		(placement
			(enabled no)
			(sheetname "")
		)
		(fill
			(thermal_gap 0.5)
			(thermal_bridge_width 0.5)
			(island_removal_mode 0)
		)
		(polygon
			(pts
				(arc
					(start 374.29694 -345.084146)
					(mid 373.91594 -345.465146)
					(end 374.29694 -345.846146)
				)
				(arc
					(start 375.16054 -345.846146)
					(mid 375.54154 -345.465146)
					(end 375.16054 -345.084146)
				)
			)
		)
	)
	(zone
		(layers "F.Cu" "B.Cu" "In1.Cu" "In2.Cu" "In3.Cu" "In4.Cu" "In5.Cu" "In6.Cu"
			"In7.Cu" "In8.Cu" "In9.Cu" "In10.Cu" "In11.Cu" "In12.Cu" "In13.Cu" "In14.Cu"
			"In15.Cu" "In16.Cu"
		)
		(hatch none 0.5)
		(connect_pads
			(clearance 0)
		)
		(min_thickness 0.25)
		(keepout
			(tracks not_allowed)
			(vias allowed)
			(pads allowed)
			(copperpour not_allowed)
			(footprints allowed)
		)
		(placement
			(enabled no)
			(sheetname "")
		)
		(fill
			(thermal_gap 0.5)
			(thermal_bridge_width 0.5)
			(island_removal_mode 0)
		)
		(polygon
			(pts
				(arc
					(start 377.4059 -345.084146)
					(mid 377.0249 -345.465146)
					(end 377.4059 -345.846146)
				)
				(arc
					(start 378.2695 -345.846146)
					(mid 378.6505 -345.465146)
					(end 378.2695 -345.084146)
				)
			)
		)
	)
	(zone
		(layers "F.Cu" "B.Cu" "In1.Cu" "In2.Cu" "In3.Cu" "In4.Cu" "In5.Cu" "In6.Cu"
			"In7.Cu" "In8.Cu" "In9.Cu" "In10.Cu" "In11.Cu" "In12.Cu" "In13.Cu" "In14.Cu"
			"In15.Cu" "In16.Cu"
		)
		(hatch none 0.5)
		(connect_pads
			(clearance 0)
		)
		(min_thickness 0.25)
		(keepout
			(tracks not_allowed)
			(vias allowed)
			(pads allowed)
			(copperpour not_allowed)
			(footprints allowed)
		)
		(placement
			(enabled no)
			(sheetname "")
		)
		(fill
			(thermal_gap 0.5)
			(thermal_bridge_width 0.5)
			(island_removal_mode 0)
		)
		(polygon
			(pts
				(arc
					(start 19.332448 -348.20479)
					(mid 18.951448 -348.58579)
					(end 19.332448 -348.96679)
				)
				(arc
					(start 20.196048 -348.96679)
					(mid 20.577048 -348.58579)
					(end 20.196048 -348.20479)
				)
			)
		)
	)
	(zone
		(layers "F.Cu" "B.Cu" "In1.Cu" "In2.Cu" "In3.Cu" "In4.Cu" "In5.Cu" "In6.Cu"
			"In7.Cu" "In8.Cu" "In9.Cu" "In10.Cu" "In11.Cu" "In12.Cu" "In13.Cu" "In14.Cu"
			"In15.Cu" "In16.Cu"
		)
		(hatch none 0.5)
		(connect_pads
			(clearance 0)
		)
		(min_thickness 0.25)
		(keepout
			(tracks not_allowed)
			(vias allowed)
			(pads allowed)
			(copperpour not_allowed)
			(footprints allowed)
		)
		(placement
			(enabled no)
			(sheetname "")
		)
		(fill
			(thermal_gap 0.5)
			(thermal_bridge_width 0.5)
			(island_removal_mode 0)
		)
		(polygon
			(pts
				(arc
					(start 75.901042 -373.828818)
					(mid 75.915921 -373.792897)
					(end 75.951842 -373.778018)
				)
				(arc
					(start 76.668122 -373.778018)
					(mid 76.704043 -373.792897)
					(end 76.718922 -373.828818)
				)
				(arc
					(start 76.718922 -376.25147)
					(mid 76.704043 -376.287391)
					(end 76.668122 -376.30227)
				)
				(arc
					(start 75.951842 -376.30227)
					(mid 75.915921 -376.287391)
					(end 75.901042 -376.25147)
				)
			)
		)
	)
	(zone
		(layers "F.Cu" "B.Cu" "In1.Cu" "In2.Cu" "In3.Cu" "In4.Cu" "In5.Cu" "In6.Cu"
			"In7.Cu" "In8.Cu" "In9.Cu" "In10.Cu" "In11.Cu" "In12.Cu" "In13.Cu" "In14.Cu"
			"In15.Cu" "In16.Cu"
		)
		(hatch none 0.5)
		(connect_pads
			(clearance 0)
		)
		(min_thickness 0.25)
		(keepout
			(tracks not_allowed)
			(vias allowed)
			(pads allowed)
			(copperpour not_allowed)
			(footprints allowed)
		)
		(placement
			(enabled no)
			(sheetname "")
		)
		(fill
			(thermal_gap 0.5)
			(thermal_bridge_width 0.5)
			(island_removal_mode 0)
		)
		(polygon
			(pts
				(arc
					(start 166.101014 -382.728724)
					(mid 166.115893 -382.692803)
					(end 166.151814 -382.677924)
				)
				(arc
					(start 166.868094 -382.677924)
					(mid 166.904015 -382.692803)
					(end 166.918894 -382.728724)
				)
				(arc
					(start 166.918894 -385.151376)
					(mid 166.904015 -385.187297)
					(end 166.868094 -385.202176)
				)
				(arc
					(start 166.151814 -385.202176)
					(mid 166.115893 -385.187297)
					(end 166.101014 -385.151376)
				)
			)
		)
	)
	(zone
		(layers "F.Cu" "B.Cu" "In1.Cu" "In2.Cu" "In3.Cu" "In4.Cu" "In5.Cu" "In6.Cu"
			"In7.Cu" "In8.Cu" "In9.Cu" "In10.Cu" "In11.Cu" "In12.Cu" "In13.Cu" "In14.Cu"
			"In15.Cu" "In16.Cu"
		)
		(hatch none 0.5)
		(connect_pads
			(clearance 0)
		)
		(min_thickness 0.25)
		(keepout
			(tracks not_allowed)
			(vias allowed)
			(pads allowed)
			(copperpour not_allowed)
			(footprints allowed)
		)
		(placement
			(enabled no)
			(sheetname "")
		)
		(fill
			(thermal_gap 0.5)
			(thermal_bridge_width 0.5)
			(island_removal_mode 0)
		)
		(polygon
			(pts
				(arc
					(start 440.384692 -342.058498)
					(mid 440.003692 -342.439498)
					(end 440.384692 -342.820498)
				)
				(arc
					(start 441.248292 -342.820498)
					(mid 441.629292 -342.439498)
					(end 441.248292 -342.058498)
				)
			)
		)
	)
	(zone
		(layers "F.Cu" "B.Cu" "In1.Cu" "In2.Cu" "In3.Cu" "In4.Cu" "In5.Cu" "In6.Cu"
			"In7.Cu" "In8.Cu" "In9.Cu" "In10.Cu" "In11.Cu" "In12.Cu" "In13.Cu" "In14.Cu"
			"In15.Cu" "In16.Cu"
		)
		(hatch none 0.5)
		(connect_pads
			(clearance 0)
		)
		(min_thickness 0.25)
		(keepout
			(tracks not_allowed)
			(vias allowed)
			(pads allowed)
			(copperpour not_allowed)
			(footprints allowed)
		)
		(placement
			(enabled no)
			(sheetname "")
		)
		(fill
			(thermal_gap 0.5)
			(thermal_bridge_width 0.5)
			(island_removal_mode 0)
		)
		(polygon
			(pts
				(arc
					(start 287.08096 -403.728682)
					(mid 287.095839 -403.692761)
					(end 287.13176 -403.677882)
				)
				(arc
					(start 287.84804 -403.677882)
					(mid 287.883961 -403.692761)
					(end 287.89884 -403.728682)
				)
				(arc
					(start 287.89884 -406.151334)
					(mid 287.883961 -406.187255)
					(end 287.84804 -406.202134)
				)
				(arc
					(start 287.13176 -406.202134)
					(mid 287.095839 -406.187255)
					(end 287.08096 -406.151334)
				)
			)
		)
	)
	(zone
		(layers "F.Cu" "B.Cu" "In1.Cu" "In2.Cu" "In3.Cu" "In4.Cu" "In5.Cu" "In6.Cu"
			"In7.Cu" "In8.Cu" "In9.Cu" "In10.Cu" "In11.Cu" "In12.Cu" "In13.Cu" "In14.Cu"
			"In15.Cu" "In16.Cu"
		)
		(hatch none 0.5)
		(connect_pads
			(clearance 0)
		)
		(min_thickness 0.25)
		(keepout
			(tracks not_allowed)
			(vias allowed)
			(pads allowed)
			(copperpour not_allowed)
			(footprints allowed)
		)
		(placement
			(enabled no)
			(sheetname "")
		)
		(fill
			(thermal_gap 0.5)
			(thermal_bridge_width 0.5)
			(island_removal_mode 0)
		)
		(polygon
			(pts
				(arc
					(start 367.14811 -29.114242)
					(mid 367.60531 -29.571442)
					(end 368.06251 -29.114242)
				)
				(arc
					(start 368.06251 -28.250642)
					(mid 367.60531 -27.793442)
					(end 367.14811 -28.250642)
				)
			)
		)
	)
	(zone
		(layers "F.Cu" "B.Cu" "In1.Cu" "In2.Cu" "In3.Cu" "In4.Cu" "In5.Cu" "In6.Cu"
			"In7.Cu" "In8.Cu" "In9.Cu" "In10.Cu" "In11.Cu" "In12.Cu" "In13.Cu" "In14.Cu"
			"In15.Cu" "In16.Cu"
		)
		(hatch none 0.5)
		(connect_pads
			(clearance 0)
		)
		(min_thickness 0.25)
		(keepout
			(tracks not_allowed)
			(vias allowed)
			(pads allowed)
			(copperpour not_allowed)
			(footprints allowed)
		)
		(placement
			(enabled no)
			(sheetname "")
		)
		(fill
			(thermal_gap 0.5)
			(thermal_bridge_width 0.5)
			(island_removal_mode 0)
		)
		(polygon
			(pts
				(arc
					(start 414.90011 -150.687278)
					(mid 415.35731 -151.144478)
					(end 415.81451 -150.687278)
				)
				(arc
					(start 415.81451 -149.823678)
					(mid 415.35731 -149.366478)
					(end 414.90011 -149.823678)
				)
			)
		)
	)
	(zone
		(layers "F.Cu" "B.Cu" "In1.Cu" "In2.Cu" "In3.Cu" "In4.Cu" "In5.Cu" "In6.Cu"
			"In7.Cu" "In8.Cu" "In9.Cu" "In10.Cu" "In11.Cu" "In12.Cu" "In13.Cu" "In14.Cu"
			"In15.Cu" "In16.Cu"
		)
		(hatch none 0.5)
		(connect_pads
			(clearance 0)
		)
		(min_thickness 0.25)
		(keepout
			(tracks not_allowed)
			(vias allowed)
			(pads allowed)
			(copperpour not_allowed)
			(footprints allowed)
		)
		(placement
			(enabled no)
			(sheetname "")
		)
		(fill
			(thermal_gap 0.5)
			(thermal_bridge_width 0.5)
			(island_removal_mode 0)
		)
		(polygon
			(pts
				(arc
					(start 248.948956 -308.568852)
					(mid 248.186956 -308.568852)
					(end 248.948956 -308.568852)
				)
			)
		)
	)
	(zone
		(layers "F.Cu" "B.Cu" "In1.Cu" "In2.Cu" "In3.Cu" "In4.Cu" "In5.Cu" "In6.Cu"
			"In7.Cu" "In8.Cu" "In9.Cu" "In10.Cu" "In11.Cu" "In12.Cu" "In13.Cu" "In14.Cu"
			"In15.Cu" "In16.Cu"
		)
		(hatch none 0.5)
		(connect_pads
			(clearance 0)
		)
		(min_thickness 0.25)
		(keepout
			(tracks not_allowed)
			(vias allowed)
			(pads allowed)
			(copperpour not_allowed)
			(footprints allowed)
		)
		(placement
			(enabled no)
			(sheetname "")
		)
		(fill
			(thermal_gap 0.5)
			(thermal_bridge_width 0.5)
			(island_removal_mode 0)
		)
		(polygon
			(pts
				(arc
					(start 102.232206 -359.53065)
					(mid 101.775006 -359.98785)
					(end 102.232206 -360.44505)
				)
				(arc
					(start 103.095806 -360.44505)
					(mid 103.553006 -359.98785)
					(end 103.095806 -359.53065)
				)
			)
		)
	)
	(zone
		(layers "F.Cu" "B.Cu" "In1.Cu" "In2.Cu" "In3.Cu" "In4.Cu" "In5.Cu" "In6.Cu"
			"In7.Cu" "In8.Cu" "In9.Cu" "In10.Cu" "In11.Cu" "In12.Cu" "In13.Cu" "In14.Cu"
			"In15.Cu" "In16.Cu"
		)
		(hatch none 0.5)
		(connect_pads
			(clearance 0)
		)
		(min_thickness 0.25)
		(keepout
			(tracks not_allowed)
			(vias allowed)
			(pads allowed)
			(copperpour not_allowed)
			(footprints allowed)
		)
		(placement
			(enabled no)
			(sheetname "")
		)
		(fill
			(thermal_gap 0.5)
			(thermal_bridge_width 0.5)
			(island_removal_mode 0)
		)
		(polygon
			(pts
				(arc
					(start 427.948852 -345.084146)
					(mid 427.567852 -345.465146)
					(end 427.948852 -345.846146)
				)
				(arc
					(start 428.812452 -345.846146)
					(mid 429.193452 -345.465146)
					(end 428.812452 -345.084146)
				)
			)
		)
	)
	(zone
		(layers "F.Cu" "B.Cu" "In1.Cu" "In2.Cu" "In3.Cu" "In4.Cu" "In5.Cu" "In6.Cu"
			"In7.Cu" "In8.Cu" "In9.Cu" "In10.Cu" "In11.Cu" "In12.Cu" "In13.Cu" "In14.Cu"
			"In15.Cu" "In16.Cu"
		)
		(hatch none 0.5)
		(connect_pads
			(clearance 0)
		)
		(min_thickness 0.25)
		(keepout
			(tracks not_allowed)
			(vias allowed)
			(pads allowed)
			(copperpour not_allowed)
			(footprints allowed)
		)
		(placement
			(enabled no)
			(sheetname "")
		)
		(fill
			(thermal_gap 0.5)
			(thermal_bridge_width 0.5)
			(island_removal_mode 0)
		)
		(polygon
			(pts
				(arc
					(start 92.461842 -357.37673)
					(mid 92.080842 -357.75773)
					(end 92.461842 -358.13873)
				)
				(arc
					(start 93.325442 -358.13873)
					(mid 93.706442 -357.75773)
					(end 93.325442 -357.37673)
				)
			)
		)
	)
	(zone
		(layers "F.Cu" "B.Cu" "In1.Cu" "In2.Cu" "In3.Cu" "In4.Cu" "In5.Cu" "In6.Cu"
			"In7.Cu" "In8.Cu" "In9.Cu" "In10.Cu" "In11.Cu" "In12.Cu" "In13.Cu" "In14.Cu"
			"In15.Cu" "In16.Cu"
		)
		(hatch none 0.5)
		(connect_pads
			(clearance 0)
		)
		(min_thickness 0.25)
		(keepout
			(tracks not_allowed)
			(vias allowed)
			(pads allowed)
			(copperpour not_allowed)
			(footprints allowed)
		)
		(placement
			(enabled no)
			(sheetname "")
		)
		(fill
			(thermal_gap 0.5)
			(thermal_bridge_width 0.5)
			(island_removal_mode 0)
		)
		(polygon
			(pts
				(arc
					(start 54.729126 -367.653062)
					(mid 54.348126 -367.272062)
					(end 53.967126 -367.653062)
				)
				(arc
					(start 53.967126 -368.516662)
					(mid 54.348126 -368.897662)
					(end 54.729126 -368.516662)
				)
			)
		)
	)
	(zone
		(layers "F.Cu" "B.Cu" "In1.Cu" "In2.Cu" "In3.Cu" "In4.Cu" "In5.Cu" "In6.Cu"
			"In7.Cu" "In8.Cu" "In9.Cu" "In10.Cu" "In11.Cu" "In12.Cu" "In13.Cu" "In14.Cu"
			"In15.Cu" "In16.Cu"
		)
		(hatch none 0.5)
		(connect_pads
			(clearance 0)
		)
		(min_thickness 0.25)
		(keepout
			(tracks not_allowed)
			(vias allowed)
			(pads allowed)
			(copperpour not_allowed)
			(footprints allowed)
		)
		(placement
			(enabled no)
			(sheetname "")
		)
		(fill
			(thermal_gap 0.5)
			(thermal_bridge_width 0.5)
			(island_removal_mode 0)
		)
		(polygon
			(pts
				(arc
					(start 295.881044 -403.728682)
					(mid 295.895923 -403.692761)
					(end 295.931844 -403.677882)
				)
				(arc
					(start 296.648124 -403.677882)
					(mid 296.684045 -403.692761)
					(end 296.698924 -403.728682)
				)
				(arc
					(start 296.698924 -406.151334)
					(mid 296.684045 -406.187255)
					(end 296.648124 -406.202134)
				)
				(arc
					(start 295.931844 -406.202134)
					(mid 295.895923 -406.187255)
					(end 295.881044 -406.151334)
				)
			)
		)
	)
	(zone
		(layers "F.Cu" "B.Cu" "In1.Cu" "In2.Cu" "In3.Cu" "In4.Cu" "In5.Cu" "In6.Cu"
			"In7.Cu" "In8.Cu" "In9.Cu" "In10.Cu" "In11.Cu" "In12.Cu" "In13.Cu" "In14.Cu"
			"In15.Cu" "In16.Cu"
		)
		(hatch none 0.5)
		(connect_pads
			(clearance 0)
		)
		(min_thickness 0.25)
		(keepout
			(tracks not_allowed)
			(vias allowed)
			(pads allowed)
			(copperpour not_allowed)
			(footprints allowed)
		)
		(placement
			(enabled no)
			(sheetname "")
		)
		(fill
			(thermal_gap 0.5)
			(thermal_bridge_width 0.5)
			(island_removal_mode 0)
		)
		(polygon
			(pts
				(arc
					(start 117.70106 -382.728724)
					(mid 117.715939 -382.692803)
					(end 117.75186 -382.677924)
				)
				(arc
					(start 118.46814 -382.677924)
					(mid 118.504061 -382.692803)
					(end 118.51894 -382.728724)
				)
				(arc
					(start 118.51894 -385.151376)
					(mid 118.504061 -385.187297)
					(end 118.46814 -385.202176)
				)
				(arc
					(start 117.75186 -385.202176)
					(mid 117.715939 -385.187297)
					(end 117.70106 -385.151376)
				)
			)
		)
	)
	(zone
		(layers "F.Cu" "B.Cu" "In1.Cu" "In2.Cu" "In3.Cu" "In4.Cu" "In5.Cu" "In6.Cu"
			"In7.Cu" "In8.Cu" "In9.Cu" "In10.Cu" "In11.Cu" "In12.Cu" "In13.Cu" "In14.Cu"
			"In15.Cu" "In16.Cu"
		)
		(hatch none 0.5)
		(connect_pads
			(clearance 0)
		)
		(min_thickness 0.25)
		(keepout
			(tracks not_allowed)
			(vias allowed)
			(pads allowed)
			(copperpour not_allowed)
			(footprints allowed)
		)
		(placement
			(enabled no)
			(sheetname "")
		)
		(fill
			(thermal_gap 0.5)
			(thermal_bridge_width 0.5)
			(island_removal_mode 0)
		)
		(polygon
			(pts
				(arc
					(start 375.081038 -377.728734)
					(mid 375.095917 -377.692813)
					(end 375.131838 -377.677934)
				)
				(arc
					(start 375.848118 -377.677934)
					(mid 375.884039 -377.692813)
					(end 375.898918 -377.728734)
				)
				(arc
					(start 375.898918 -380.151386)
					(mid 375.884039 -380.187307)
					(end 375.848118 -380.202186)
				)
				(arc
					(start 375.131838 -380.202186)
					(mid 375.095917 -380.187307)
					(end 375.081038 -380.151386)
				)
			)
		)
	)
	(zone
		(layers "F.Cu" "B.Cu" "In1.Cu" "In2.Cu" "In3.Cu" "In4.Cu" "In5.Cu" "In6.Cu"
			"In7.Cu" "In8.Cu" "In9.Cu" "In10.Cu" "In11.Cu" "In12.Cu" "In13.Cu" "In14.Cu"
			"In15.Cu" "In16.Cu"
		)
		(hatch none 0.5)
		(connect_pads
			(clearance 0)
		)
		(min_thickness 0.25)
		(keepout
			(tracks not_allowed)
			(vias allowed)
			(pads allowed)
			(copperpour not_allowed)
			(footprints allowed)
		)
		(placement
			(enabled no)
			(sheetname "")
		)
		(fill
			(thermal_gap 0.5)
			(thermal_bridge_width 0.5)
			(island_removal_mode 0)
		)
		(polygon
			(pts
				(arc
					(start 58.753248 -30.922468)
					(mid 59.210448 -31.379668)
					(end 59.667648 -30.922468)
				)
				(arc
					(start 59.667648 -30.058868)
					(mid 59.210448 -29.601668)
					(end 58.753248 -30.058868)
				)
			)
		)
	)
	(zone
		(layers "F.Cu" "B.Cu" "In1.Cu" "In2.Cu" "In3.Cu" "In4.Cu" "In5.Cu" "In6.Cu"
			"In7.Cu" "In8.Cu" "In9.Cu" "In10.Cu" "In11.Cu" "In12.Cu" "In13.Cu" "In14.Cu"
			"In15.Cu" "In16.Cu"
		)
		(hatch none 0.5)
		(connect_pads
			(clearance 0)
		)
		(min_thickness 0.25)
		(keepout
			(tracks not_allowed)
			(vias allowed)
			(pads allowed)
			(copperpour not_allowed)
			(footprints allowed)
		)
		(placement
			(enabled no)
			(sheetname "")
		)
		(fill
			(thermal_gap 0.5)
			(thermal_bridge_width 0.5)
			(island_removal_mode 0)
		)
		(polygon
			(pts
				(arc
					(start 409.295092 -348.20479)
					(mid 408.914092 -348.58579)
					(end 409.295092 -348.96679)
				)
				(arc
					(start 410.158692 -348.96679)
					(mid 410.539692 -348.58579)
					(end 410.158692 -348.20479)
				)
			)
		)
	)
	(zone
		(layers "F.Cu" "B.Cu" "In1.Cu" "In2.Cu" "In3.Cu" "In4.Cu" "In5.Cu" "In6.Cu"
			"In7.Cu" "In8.Cu" "In9.Cu" "In10.Cu" "In11.Cu" "In12.Cu" "In13.Cu" "In14.Cu"
			"In15.Cu" "In16.Cu"
		)
		(hatch none 0.5)
		(connect_pads
			(clearance 0)
		)
		(min_thickness 0.25)
		(keepout
			(tracks not_allowed)
			(vias allowed)
			(pads allowed)
			(copperpour not_allowed)
			(footprints allowed)
		)
		(placement
			(enabled no)
			(sheetname "")
		)
		(fill
			(thermal_gap 0.5)
			(thermal_bridge_width 0.5)
			(island_removal_mode 0)
		)
		(polygon
			(pts
				(arc
					(start 183.948832 -342.058498)
					(mid 183.567832 -342.439498)
					(end 183.948832 -342.820498)
				)
				(arc
					(start 184.812432 -342.820498)
					(mid 185.193432 -342.439498)
					(end 184.812432 -342.058498)
				)
			)
		)
	)
	(zone
		(layers "F.Cu" "B.Cu" "In1.Cu" "In2.Cu" "In3.Cu" "In4.Cu" "In5.Cu" "In6.Cu"
			"In7.Cu" "In8.Cu" "In9.Cu" "In10.Cu" "In11.Cu" "In12.Cu" "In13.Cu" "In14.Cu"
			"In15.Cu" "In16.Cu"
		)
		(hatch none 0.5)
		(connect_pads
			(clearance 0)
		)
		(min_thickness 0.25)
		(keepout
			(tracks not_allowed)
			(vias allowed)
			(pads allowed)
			(copperpour not_allowed)
			(footprints allowed)
		)
		(placement
			(enabled no)
			(sheetname "")
		)
		(fill
			(thermal_gap 0.5)
			(thermal_bridge_width 0.5)
			(island_removal_mode 0)
		)
		(polygon
			(pts
				(arc
					(start 76.917042 -345.084146)
					(mid 76.536042 -345.465146)
					(end 76.917042 -345.846146)
				)
				(arc
					(start 77.780642 -345.846146)
					(mid 78.161642 -345.465146)
					(end 77.780642 -345.084146)
				)
			)
		)
	)
	(zone
		(layers "F.Cu" "B.Cu" "In1.Cu" "In2.Cu" "In3.Cu" "In4.Cu" "In5.Cu" "In6.Cu"
			"In7.Cu" "In8.Cu" "In9.Cu" "In10.Cu" "In11.Cu" "In12.Cu" "In13.Cu" "In14.Cu"
			"In15.Cu" "In16.Cu"
		)
		(hatch none 0.5)
		(connect_pads
			(clearance 0)
		)
		(min_thickness 0.25)
		(keepout
			(tracks not_allowed)
			(vias allowed)
			(pads allowed)
			(copperpour not_allowed)
			(footprints allowed)
		)
		(placement
			(enabled no)
			(sheetname "")
		)
		(fill
			(thermal_gap 0.5)
			(thermal_bridge_width 0.5)
			(island_removal_mode 0)
		)
		(polygon
			(pts
				(arc
					(start 331.156564 -348.20479)
					(mid 330.775564 -348.58579)
					(end 331.156564 -348.96679)
				)
				(arc
					(start 332.020164 -348.96679)
					(mid 332.401164 -348.58579)
					(end 332.020164 -348.20479)
				)
			)
		)
	)
	(zone
		(layers "F.Cu" "B.Cu" "In1.Cu" "In2.Cu" "In3.Cu" "In4.Cu" "In5.Cu" "In6.Cu"
			"In7.Cu" "In8.Cu" "In9.Cu" "In10.Cu" "In11.Cu" "In12.Cu" "In13.Cu" "In14.Cu"
			"In15.Cu" "In16.Cu"
		)
		(hatch none 0.5)
		(connect_pads
			(clearance 0)
		)
		(min_thickness 0.25)
		(keepout
			(tracks not_allowed)
			(vias allowed)
			(pads allowed)
			(copperpour not_allowed)
			(footprints allowed)
		)
		(placement
			(enabled no)
			(sheetname "")
		)
		(fill
			(thermal_gap 0.5)
			(thermal_bridge_width 0.5)
			(island_removal_mode 0)
		)
		(polygon
			(pts
				(arc
					(start 41.095168 -342.058498)
					(mid 40.714168 -342.439498)
					(end 41.095168 -342.820498)
				)
				(arc
					(start 41.958768 -342.820498)
					(mid 42.339768 -342.439498)
					(end 41.958768 -342.058498)
				)
			)
		)
	)
	(zone
		(layers "F.Cu" "B.Cu" "In1.Cu" "In2.Cu" "In3.Cu" "In4.Cu" "In5.Cu" "In6.Cu"
			"In7.Cu" "In8.Cu" "In9.Cu" "In10.Cu" "In11.Cu" "In12.Cu" "In13.Cu" "In14.Cu"
			"In15.Cu" "In16.Cu"
		)
		(hatch none 0.5)
		(connect_pads
			(clearance 0)
		)
		(min_thickness 0.25)
		(keepout
			(tracks not_allowed)
			(vias allowed)
			(pads allowed)
			(copperpour not_allowed)
			(footprints allowed)
		)
		(placement
			(enabled no)
			(sheetname "")
		)
		(fill
			(thermal_gap 0.5)
			(thermal_bridge_width 0.5)
			(island_removal_mode 0)
		)
		(polygon
			(pts
				(arc
					(start 171.512992 -357.37673)
					(mid 171.131992 -357.75773)
					(end 171.512992 -358.13873)
				)
				(arc
					(start 172.376592 -358.13873)
					(mid 172.757592 -357.75773)
					(end 172.376592 -357.37673)
				)
			)
		)
	)
	(zone
		(layers "F.Cu" "B.Cu" "In1.Cu" "In2.Cu" "In3.Cu" "In4.Cu" "In5.Cu" "In6.Cu"
			"In7.Cu" "In8.Cu" "In9.Cu" "In10.Cu" "In11.Cu" "In12.Cu" "In13.Cu" "In14.Cu"
			"In15.Cu" "In16.Cu"
		)
		(hatch none 0.5)
		(connect_pads
			(clearance 0)
		)
		(min_thickness 0.25)
		(keepout
			(tracks not_allowed)
			(vias allowed)
			(pads allowed)
			(copperpour not_allowed)
			(footprints allowed)
		)
		(placement
			(enabled no)
			(sheetname "")
		)
		(fill
			(thermal_gap 0.5)
			(thermal_bridge_width 0.5)
			(island_removal_mode 0)
		)
		(polygon
			(pts
				(arc
					(start 34.6075 -32.722312)
					(mid 35.0647 -33.179512)
					(end 35.5219 -32.722312)
				)
				(arc
					(start 35.5219 -31.858712)
					(mid 35.0647 -31.401512)
					(end 34.6075 -31.858712)
				)
			)
		)
	)
	(zone
		(layers "F.Cu" "B.Cu" "In1.Cu" "In2.Cu" "In3.Cu" "In4.Cu" "In5.Cu" "In6.Cu"
			"In7.Cu" "In8.Cu" "In9.Cu" "In10.Cu" "In11.Cu" "In12.Cu" "In13.Cu" "In14.Cu"
			"In15.Cu" "In16.Cu"
		)
		(hatch none 0.5)
		(connect_pads
			(clearance 0)
		)
		(min_thickness 0.25)
		(keepout
			(tracks not_allowed)
			(vias allowed)
			(pads allowed)
			(copperpour not_allowed)
			(footprints allowed)
		)
		(placement
			(enabled no)
			(sheetname "")
		)
		(fill
			(thermal_gap 0.5)
			(thermal_bridge_width 0.5)
			(island_removal_mode 0)
		)
		(polygon
			(pts
				(arc
					(start 76.917042 -357.37673)
					(mid 76.536042 -357.75773)
					(end 76.917042 -358.13873)
				)
				(arc
					(start 77.780642 -358.13873)
					(mid 78.161642 -357.75773)
					(end 77.780642 -357.37673)
				)
			)
		)
	)
	(zone
		(layers "F.Cu" "B.Cu" "In1.Cu" "In2.Cu" "In3.Cu" "In4.Cu" "In5.Cu" "In6.Cu"
			"In7.Cu" "In8.Cu" "In9.Cu" "In10.Cu" "In11.Cu" "In12.Cu" "In13.Cu" "In14.Cu"
			"In15.Cu" "In16.Cu"
		)
		(hatch none 0.5)
		(connect_pads
			(clearance 0)
		)
		(min_thickness 0.25)
		(keepout
			(tracks not_allowed)
			(vias allowed)
			(pads allowed)
			(copperpour not_allowed)
			(footprints allowed)
		)
		(placement
			(enabled no)
			(sheetname "")
		)
		(fill
			(thermal_gap 0.5)
			(thermal_bridge_width 0.5)
			(island_removal_mode 0)
		)
		(polygon
			(pts
				(arc
					(start 379.48108 -377.728734)
					(mid 379.495959 -377.692813)
					(end 379.53188 -377.677934)
				)
				(arc
					(start 380.24816 -377.677934)
					(mid 380.284081 -377.692813)
					(end 380.29896 -377.728734)
				)
				(arc
					(start 380.29896 -380.151386)
					(mid 380.284081 -380.187307)
					(end 380.24816 -380.202186)
				)
				(arc
					(start 379.53188 -380.202186)
					(mid 379.495959 -380.187307)
					(end 379.48108 -380.151386)
				)
			)
		)
	)
	(zone
		(layers "F.Cu" "B.Cu" "In1.Cu" "In2.Cu" "In3.Cu" "In4.Cu" "In5.Cu" "In6.Cu"
			"In7.Cu" "In8.Cu" "In9.Cu" "In10.Cu" "In11.Cu" "In12.Cu" "In13.Cu" "In14.Cu"
			"In15.Cu" "In16.Cu"
		)
		(hatch none 0.5)
		(connect_pads
			(clearance 0)
		)
		(min_thickness 0.25)
		(keepout
			(tracks not_allowed)
			(vias allowed)
			(pads allowed)
			(copperpour not_allowed)
			(footprints allowed)
		)
		(placement
			(enabled no)
			(sheetname "")
		)
		(fill
			(thermal_gap 0.5)
			(thermal_bridge_width 0.5)
			(island_removal_mode 0)
		)
		(polygon
			(pts
				(arc
					(start 280.332942 -348.20479)
					(mid 279.951942 -348.58579)
					(end 280.332942 -348.96679)
				)
				(arc
					(start 281.196542 -348.96679)
					(mid 281.577542 -348.58579)
					(end 281.196542 -348.20479)
				)
			)
		)
	)
	(zone
		(layers "F.Cu" "B.Cu" "In1.Cu" "In2.Cu" "In3.Cu" "In4.Cu" "In5.Cu" "In6.Cu"
			"In7.Cu" "In8.Cu" "In9.Cu" "In10.Cu" "In11.Cu" "In12.Cu" "In13.Cu" "In14.Cu"
			"In15.Cu" "In16.Cu"
		)
		(hatch none 0.5)
		(connect_pads
			(clearance 0)
		)
		(min_thickness 0.25)
		(keepout
			(tracks not_allowed)
			(vias allowed)
			(pads allowed)
			(copperpour not_allowed)
			(footprints allowed)
		)
		(placement
			(enabled no)
			(sheetname "")
		)
		(fill
			(thermal_gap 0.5)
			(thermal_bridge_width 0.5)
			(island_removal_mode 0)
		)
		(polygon
			(pts
				(arc
					(start 423.480992 -399.828766)
					(mid 423.495871 -399.792845)
					(end 423.531792 -399.777966)
				)
				(arc
					(start 424.248072 -399.777966)
					(mid 424.283993 -399.792845)
					(end 424.298872 -399.828766)
				)
				(arc
					(start 424.298872 -402.251418)
					(mid 424.283993 -402.287339)
					(end 424.248072 -402.302218)
				)
				(arc
					(start 423.531792 -402.302218)
					(mid 423.495871 -402.287339)
					(end 423.480992 -402.251418)
				)
			)
		)
	)
	(zone
		(layers "F.Cu" "B.Cu" "In1.Cu" "In2.Cu" "In3.Cu" "In4.Cu" "In5.Cu" "In6.Cu"
			"In7.Cu" "In8.Cu" "In9.Cu" "In10.Cu" "In11.Cu" "In12.Cu" "In13.Cu" "In14.Cu"
			"In15.Cu" "In16.Cu"
		)
		(hatch none 0.5)
		(connect_pads
			(clearance 0)
		)
		(min_thickness 0.25)
		(keepout
			(tracks not_allowed)
			(vias allowed)
			(pads allowed)
			(copperpour not_allowed)
			(footprints allowed)
		)
		(placement
			(enabled no)
			(sheetname "")
		)
		(fill
			(thermal_gap 0.5)
			(thermal_bridge_width 0.5)
			(island_removal_mode 0)
		)
		(polygon
			(pts
				(arc
					(start 124.70765 -29.12237)
					(mid 125.16485 -29.57957)
					(end 125.62205 -29.12237)
				)
				(arc
					(start 125.62205 -28.25877)
					(mid 125.16485 -27.80157)
					(end 124.70765 -28.25877)
				)
			)
		)
	)
	(zone
		(layers "F.Cu" "B.Cu" "In1.Cu" "In2.Cu" "In3.Cu" "In4.Cu" "In5.Cu" "In6.Cu"
			"In7.Cu" "In8.Cu" "In9.Cu" "In10.Cu" "In11.Cu" "In12.Cu" "In13.Cu" "In14.Cu"
			"In15.Cu" "In16.Cu"
		)
		(hatch none 0.5)
		(connect_pads
			(clearance 0)
		)
		(min_thickness 0.25)
		(keepout
			(tracks not_allowed)
			(vias allowed)
			(pads allowed)
			(copperpour not_allowed)
			(footprints allowed)
		)
		(placement
			(enabled no)
			(sheetname "")
		)
		(fill
			(thermal_gap 0.5)
			(thermal_bridge_width 0.5)
			(island_removal_mode 0)
		)
		(polygon
			(pts
				(arc
					(start 400.99996 -132.232908)
					(mid 400.54276 -131.775708)
					(end 400.08556 -132.232908)
				)
				(arc
					(start 400.08556 -133.096508)
					(mid 400.54276 -133.553708)
					(end 400.99996 -133.096508)
				)
			)
		)
	)
	(zone
		(layers "F.Cu" "B.Cu" "In1.Cu" "In2.Cu" "In3.Cu" "In4.Cu" "In5.Cu" "In6.Cu"
			"In7.Cu" "In8.Cu" "In9.Cu" "In10.Cu" "In11.Cu" "In12.Cu" "In13.Cu" "In14.Cu"
			"In15.Cu" "In16.Cu"
		)
		(hatch none 0.5)
		(connect_pads
			(clearance 0)
		)
		(min_thickness 0.25)
		(keepout
			(tracks not_allowed)
			(vias allowed)
			(pads allowed)
			(copperpour not_allowed)
			(footprints allowed)
		)
		(placement
			(enabled no)
			(sheetname "")
		)
		(fill
			(thermal_gap 0.5)
			(thermal_bridge_width 0.5)
			(island_removal_mode 0)
		)
		(polygon
			(pts
				(arc
					(start 437.275732 -345.084146)
					(mid 436.894732 -345.465146)
					(end 437.275732 -345.846146)
				)
				(arc
					(start 438.139332 -345.846146)
					(mid 438.520332 -345.465146)
					(end 438.139332 -345.084146)
				)
			)
		)
	)
	(zone
		(layers "F.Cu" "B.Cu" "In1.Cu" "In2.Cu" "In3.Cu" "In4.Cu" "In5.Cu" "In6.Cu"
			"In7.Cu" "In8.Cu" "In9.Cu" "In10.Cu" "In11.Cu" "In12.Cu" "In13.Cu" "In14.Cu"
			"In15.Cu" "In16.Cu"
		)
		(hatch none 0.5)
		(connect_pads
			(clearance 0)
		)
		(min_thickness 0.25)
		(keepout
			(tracks not_allowed)
			(vias allowed)
			(pads allowed)
			(copperpour not_allowed)
			(footprints allowed)
		)
		(placement
			(enabled no)
			(sheetname "")
		)
		(fill
			(thermal_gap 0.5)
			(thermal_bridge_width 0.5)
			(island_removal_mode 0)
		)
		(polygon
			(pts
				(arc
					(start 233.585512 -85.885782)
					(mid 234.042712 -85.428582)
					(end 233.585512 -84.971382)
				)
				(arc
					(start 232.721912 -84.971382)
					(mid 232.264712 -85.428582)
					(end 232.721912 -85.885782)
				)
			)
		)
	)
	(zone
		(layers "F.Cu" "B.Cu" "In1.Cu" "In2.Cu" "In3.Cu" "In4.Cu" "In5.Cu" "In6.Cu"
			"In7.Cu" "In8.Cu" "In9.Cu" "In10.Cu" "In11.Cu" "In12.Cu" "In13.Cu" "In14.Cu"
			"In15.Cu" "In16.Cu"
		)
		(hatch none 0.5)
		(connect_pads
			(clearance 0)
		)
		(min_thickness 0.25)
		(keepout
			(tracks not_allowed)
			(vias allowed)
			(pads allowed)
			(copperpour not_allowed)
			(footprints allowed)
		)
		(placement
			(enabled no)
			(sheetname "")
		)
		(fill
			(thermal_gap 0.5)
			(thermal_bridge_width 0.5)
			(island_removal_mode 0)
		)
		(polygon
			(pts
				(arc
					(start 375.081038 -373.828818)
					(mid 375.095917 -373.792897)
					(end 375.131838 -373.778018)
				)
				(arc
					(start 375.848118 -373.778018)
					(mid 375.884039 -373.792897)
					(end 375.898918 -373.828818)
				)
				(arc
					(start 375.898918 -376.25147)
					(mid 375.884039 -376.287391)
					(end 375.848118 -376.30227)
				)
				(arc
					(start 375.131838 -376.30227)
					(mid 375.095917 -376.287391)
					(end 375.081038 -376.25147)
				)
			)
		)
	)
	(zone
		(layers "F.Cu" "B.Cu" "In1.Cu" "In2.Cu" "In3.Cu" "In4.Cu" "In5.Cu" "In6.Cu"
			"In7.Cu" "In8.Cu" "In9.Cu" "In10.Cu" "In11.Cu" "In12.Cu" "In13.Cu" "In14.Cu"
			"In15.Cu" "In16.Cu"
		)
		(hatch none 0.5)
		(connect_pads
			(clearance 0)
		)
		(min_thickness 0.25)
		(keepout
			(tracks not_allowed)
			(vias allowed)
			(pads allowed)
			(copperpour not_allowed)
			(footprints allowed)
		)
		(placement
			(enabled no)
			(sheetname "")
		)
		(fill
			(thermal_gap 0.5)
			(thermal_bridge_width 0.5)
			(island_removal_mode 0)
		)
		(polygon
			(pts
				(arc
					(start 182.700168 -147.087336)
					(mid 183.157368 -147.544536)
					(end 183.614568 -147.087336)
				)
				(arc
					(start 183.614568 -146.223736)
					(mid 183.157368 -145.766536)
					(end 182.700168 -146.223736)
				)
			)
		)
	)
	(zone
		(layers "F.Cu" "B.Cu" "In1.Cu" "In2.Cu" "In3.Cu" "In4.Cu" "In5.Cu" "In6.Cu"
			"In7.Cu" "In8.Cu" "In9.Cu" "In10.Cu" "In11.Cu" "In12.Cu" "In13.Cu" "In14.Cu"
			"In15.Cu" "In16.Cu"
		)
		(hatch none 0.5)
		(connect_pads
			(clearance 0)
		)
		(min_thickness 0.25)
		(keepout
			(tracks not_allowed)
			(vias allowed)
			(pads allowed)
			(copperpour not_allowed)
			(footprints allowed)
		)
		(placement
			(enabled no)
			(sheetname "")
		)
		(fill
			(thermal_gap 0.5)
			(thermal_bridge_width 0.5)
			(island_removal_mode 0)
		)
		(polygon
			(pts
				(arc
					(start 40.70096 -381.628904)
					(mid 40.715839 -381.592983)
					(end 40.75176 -381.578104)
				)
				(arc
					(start 41.46804 -381.578104)
					(mid 41.503961 -381.592983)
					(end 41.51884 -381.628904)
				)
				(arc
					(start 41.51884 -384.051556)
					(mid 41.503961 -384.087477)
					(end 41.46804 -384.102356)
				)
				(arc
					(start 40.75176 -384.102356)
					(mid 40.715839 -384.087477)
					(end 40.70096 -384.051556)
				)
			)
		)
	)
	(zone
		(layers "F.Cu" "B.Cu" "In1.Cu" "In2.Cu" "In3.Cu" "In4.Cu" "In5.Cu" "In6.Cu"
			"In7.Cu" "In8.Cu" "In9.Cu" "In10.Cu" "In11.Cu" "In12.Cu" "In13.Cu" "In14.Cu"
			"In15.Cu" "In16.Cu"
		)
		(hatch none 0.5)
		(connect_pads
			(clearance 0)
		)
		(min_thickness 0.25)
		(keepout
			(tracks not_allowed)
			(vias allowed)
			(pads allowed)
			(copperpour not_allowed)
			(footprints allowed)
		)
		(placement
			(enabled no)
			(sheetname "")
		)
		(fill
			(thermal_gap 0.5)
			(thermal_bridge_width 0.5)
			(island_removal_mode 0)
		)
		(polygon
			(pts
				(arc
					(start 315.611764 -342.058498)
					(mid 315.230764 -342.439498)
					(end 315.611764 -342.820498)
				)
				(arc
					(start 316.475364 -342.820498)
					(mid 316.856364 -342.439498)
					(end 316.475364 -342.058498)
				)
			)
		)
	)
	(zone
		(layers "F.Cu" "B.Cu" "In1.Cu" "In2.Cu" "In3.Cu" "In4.Cu" "In5.Cu" "In6.Cu"
			"In7.Cu" "In8.Cu" "In9.Cu" "In10.Cu" "In11.Cu" "In12.Cu" "In13.Cu" "In14.Cu"
			"In15.Cu" "In16.Cu"
		)
		(hatch none 0.5)
		(connect_pads
			(clearance 0)
		)
		(min_thickness 0.25)
		(keepout
			(tracks not_allowed)
			(vias allowed)
			(pads allowed)
			(copperpour not_allowed)
			(footprints allowed)
		)
		(placement
			(enabled no)
			(sheetname "")
		)
		(fill
			(thermal_gap 0.5)
			(thermal_bridge_width 0.5)
			(island_removal_mode 0)
		)
		(polygon
			(pts
				(arc
					(start 44.848018 -29.114242)
					(mid 45.305218 -29.571442)
					(end 45.762418 -29.114242)
				)
				(arc
					(start 45.762418 -28.250642)
					(mid 45.305218 -27.793442)
					(end 44.848018 -28.250642)
				)
			)
		)
	)
	(zone
		(layers "F.Cu" "B.Cu" "In1.Cu" "In2.Cu" "In3.Cu" "In4.Cu" "In5.Cu" "In6.Cu"
			"In7.Cu" "In8.Cu" "In9.Cu" "In10.Cu" "In11.Cu" "In12.Cu" "In13.Cu" "In14.Cu"
			"In15.Cu" "In16.Cu"
		)
		(name "Route Keepin")
		(hatch none 0.5)
		(connect_pads
			(clearance 0)
		)
		(min_thickness 0.25)
		(keepout
			(tracks allowed)
			(vias allowed)
			(pads allowed)
			(copperpour allowed)
			(footprints allowed)
		)
		(placement
			(enabled no)
			(sheetname "")
		)
		(fill
			(thermal_gap 0.5)
			(thermal_bridge_width 0.5)
			(island_removal_mode 0)
		)
		(polygon
			(pts
				(arc
					(start 465.600034 -418.094668)
					(mid 466.664015 -417.653953)
					(end 467.10473 -416.589972)
				)
				(arc
					(start 467.10473 -246.488204)
					(mid 466.990143 -245.912518)
					(end 466.66404 -245.424452)
				)
				(arc
					(start 464.035648 -242.79606)
					(mid 463.494623 -241.986498)
					(end 463.304636 -241.031522)
				)
				(arc
					(start 463.304636 -87.588344)
					(mid 463.494662 -86.633489)
					(end 464.035648 -85.82406)
				)
				(arc
					(start 466.66404 -83.195414)
					(mid 466.990147 -82.70736)
					(end 467.10473 -82.131662)
				)
				(arc
					(start 467.10473 -1.999996)
					(mid 466.664015 -0.936015)
					(end 465.600034 -0.4953)
				)
				(arc
					(start 446.265046 -0.4953)
					(mid 445.201065 -0.936015)
					(end 444.76035 -1.999996)
				)
				(arc
					(start 444.76035 -11.850116)
					(mid 444.322387 -12.907451)
					(end 443.265052 -13.345414)
				)
				(arc
					(start 435.265068 -13.345414)
					(mid 434.207733 -12.907451)
					(end 433.76977 -11.850116)
				)
				(arc
					(start 433.76977 -1.999996)
					(mid 433.329055 -0.936015)
					(end 432.265074 -0.4953)
				)
				(arc
					(start 420.265098 -0.4953)
					(mid 419.201117 -0.936015)
					(end 418.760402 -1.999996)
				)
				(arc
					(start 418.760402 -11.850116)
					(mid 418.322439 -12.907451)
					(end 417.265104 -13.345414)
				)
				(arc
					(start 409.26512 -13.345414)
					(mid 408.207785 -12.907451)
					(end 407.769822 -11.850116)
				)
				(arc
					(start 407.769822 -1.999996)
					(mid 407.329107 -0.936015)
					(end 406.265126 -0.4953)
				)
				(arc
					(start 394.264896 -0.4953)
					(mid 393.200915 -0.936015)
					(end 392.7602 -1.999996)
				)
				(arc
					(start 392.7602 -11.850116)
					(mid 392.322237 -12.907451)
					(end 391.264902 -13.345414)
				)
				(arc
					(start 383.264918 -13.345414)
					(mid 382.207583 -12.907451)
					(end 381.76962 -11.850116)
				)
				(arc
					(start 381.76962 -1.999996)
					(mid 381.328905 -0.936015)
					(end 380.264924 -0.4953)
				)
				(arc
					(start 368.264948 -0.4953)
					(mid 367.200967 -0.936015)
					(end 366.760252 -1.999996)
				)
				(arc
					(start 366.760252 -11.850116)
					(mid 366.322289 -12.907451)
					(end 365.264954 -13.345414)
				)
				(arc
					(start 357.26497 -13.345414)
					(mid 356.207635 -12.907451)
					(end 355.769672 -11.850116)
				)
				(arc
					(start 355.769672 -1.999996)
					(mid 355.328957 -0.936015)
					(end 354.264976 -0.4953)
				)
				(arc
					(start 330.164948 -0.4953)
					(mid 329.100967 -0.936015)
					(end 328.660252 -1.999996)
				)
				(arc
					(start 328.660252 -11.850116)
					(mid 328.222289 -12.907451)
					(end 327.164954 -13.345414)
				)
				(arc
					(start 319.16497 -13.345414)
					(mid 318.107635 -12.907451)
					(end 317.669672 -11.850116)
				)
				(arc
					(start 317.669672 -1.999996)
					(mid 317.228957 -0.936015)
					(end 316.164976 -0.4953)
				)
				(arc
					(start 304.165 -0.4953)
					(mid 303.101019 -0.936015)
					(end 302.660304 -1.999996)
				)
				(arc
					(start 302.660304 -11.850116)
					(mid 302.222341 -12.907451)
					(end 301.165006 -13.345414)
				)
				(arc
					(start 293.165022 -13.345414)
					(mid 292.107687 -12.907451)
					(end 291.669724 -11.850116)
				)
				(arc
					(start 291.669724 -1.999996)
					(mid 291.229009 -0.936015)
					(end 290.165028 -0.4953)
				)
				(arc
					(start 278.165052 -0.4953)
					(mid 277.101071 -0.936015)
					(end 276.660356 -1.999996)
				)
				(arc
					(start 276.660356 -11.850116)
					(mid 276.222393 -12.907451)
					(end 275.165058 -13.345414)
				)
				(arc
					(start 267.165074 -13.345414)
					(mid 266.107739 -12.907451)
					(end 265.669776 -11.850116)
				)
				(arc
					(start 265.669776 -1.999996)
					(mid 265.229061 -0.936015)
					(end 264.16508 -0.4953)
				)
				(arc
					(start 252.165104 -0.4953)
					(mid 251.101123 -0.936015)
					(end 250.660408 -1.999996)
				)
				(arc
					(start 250.660408 -11.850116)
					(mid 250.222445 -12.907451)
					(end 249.16511 -13.345414)
				)
				(arc
					(start 241.164872 -13.345414)
					(mid 240.107701 -12.907362)
					(end 239.669574 -11.850116)
				)
				(arc
					(start 239.669574 -1.999996)
					(mid 239.228859 -0.936015)
					(end 238.164878 -0.4953)
				)
				(arc
					(start 214.065104 -0.4953)
					(mid 213.001123 -0.936015)
					(end 212.560408 -1.999996)
				)
				(arc
					(start 212.560408 -11.850116)
					(mid 212.122445 -12.907451)
					(end 211.06511 -13.345414)
				)
				(arc
					(start 203.064872 -13.345414)
					(mid 202.007701 -12.907362)
					(end 201.569574 -11.850116)
				)
				(arc
					(start 201.569574 -1.999996)
					(mid 201.128859 -0.936015)
					(end 200.064878 -0.4953)
				)
				(arc
					(start 188.064902 -0.4953)
					(mid 187.000921 -0.936015)
					(end 186.560206 -1.999996)
				)
				(arc
					(start 186.560206 -11.850116)
					(mid 186.122243 -12.907451)
					(end 185.064908 -13.345414)
				)
				(arc
					(start 177.064924 -13.345414)
					(mid 176.007589 -12.907451)
					(end 175.569626 -11.850116)
				)
				(arc
					(start 175.569626 -1.999996)
					(mid 175.128911 -0.936015)
					(end 174.06493 -0.4953)
				)
				(arc
					(start 162.064954 -0.4953)
					(mid 161.000973 -0.936015)
					(end 160.560258 -1.999996)
				)
				(arc
					(start 160.560258 -11.850116)
					(mid 160.122295 -12.907451)
					(end 159.06496 -13.345414)
				)
				(arc
					(start 151.064976 -13.345414)
					(mid 150.007641 -12.907451)
					(end 149.569678 -11.850116)
				)
				(arc
					(start 149.569678 -1.999996)
					(mid 149.128963 -0.936015)
					(end 148.064982 -0.4953)
				)
				(arc
					(start 136.065006 -0.4953)
					(mid 135.001025 -0.936015)
					(end 134.56031 -1.999996)
				)
				(arc
					(start 134.56031 -11.850116)
					(mid 134.122347 -12.907451)
					(end 133.065012 -13.345414)
				)
				(arc
					(start 125.065028 -13.345414)
					(mid 124.007693 -12.907451)
					(end 123.56973 -11.850116)
				)
				(arc
					(start 123.56973 -1.999996)
					(mid 123.129015 -0.936015)
					(end 122.065034 -0.4953)
				)
				(arc
					(start 97.965006 -0.4953)
					(mid 96.901025 -0.936015)
					(end 96.46031 -1.999996)
				)
				(arc
					(start 96.46031 -11.850116)
					(mid 96.022347 -12.907451)
					(end 94.965012 -13.345414)
				)
				(arc
					(start 86.965028 -13.345414)
					(mid 85.907693 -12.907451)
					(end 85.46973 -11.850116)
				)
				(arc
					(start 85.46973 -1.999996)
					(mid 85.029015 -0.936015)
					(end 83.965034 -0.4953)
				)
				(arc
					(start 71.965058 -0.4953)
					(mid 70.901077 -0.936015)
					(end 70.460362 -1.999996)
				)
				(arc
					(start 70.460362 -11.850116)
					(mid 70.022399 -12.907451)
					(end 68.965064 -13.345414)
				)
				(arc
					(start 60.96508 -13.345414)
					(mid 59.907745 -12.907451)
					(end 59.469782 -11.850116)
				)
				(arc
					(start 59.469782 -1.999996)
					(mid 59.029067 -0.936015)
					(end 57.965086 -0.4953)
				)
				(arc
					(start 45.96511 -0.4953)
					(mid 44.901129 -0.936015)
					(end 44.460414 -1.999996)
				)
				(arc
					(start 44.460414 -11.850116)
					(mid 44.022451 -12.907451)
					(end 42.965116 -13.345414)
				)
				(arc
					(start 34.964878 -13.345414)
					(mid 33.907543 -12.907451)
					(end 33.46958 -11.850116)
				)
				(arc
					(start 33.46958 -1.999996)
					(mid 33.028865 -0.936015)
					(end 31.964884 -0.4953)
				)
				(arc
					(start 19.964908 -0.4953)
					(mid 18.900927 -0.936015)
					(end 18.460212 -1.999996)
				)
				(arc
					(start 18.460212 -11.850116)
					(mid 18.022249 -12.907451)
					(end 16.964914 -13.345414)
				)
				(arc
					(start 8.96493 -13.345414)
					(mid 7.907595 -12.907451)
					(end 7.469632 -11.850116)
				)
				(arc
					(start 7.469632 -1.999996)
					(mid 7.028917 -0.936015)
					(end 5.964936 -0.4953)
				)
				(xy 3.879088 -0.4953) (xy 3.879088 2.324608) (xy 4.031488 2.477008) (xy 7.939786 2.477008) (xy 10.446004 -0.02921)
				(xy 10.446004 -9.472676) (xy 11.346688 -10.37336) (xy 14.593824 -10.37336) (xy 15.480284 -9.4869)
				(xy 15.480284 0.094234) (xy 17.863058 2.477008) (xy 33.938464 2.477008) (xy 36.437316 -0.021844)
				(xy 36.437316 -9.508998) (xy 37.301678 -10.37336) (xy 40.599614 -10.37336) (xy 41.486328 -9.486646)
				(xy 41.486328 0.12319) (xy 43.789346 2.426208) (xy 59.973464 2.426208) (xy 62.443106 -0.043434)
				(xy 62.443106 -9.501632) (xy 63.314834 -10.37336) (xy 66.613024 -10.37336) (xy 67.542664 -9.44372)
				(xy 67.542664 0) (xy 70.019672 2.477008) (xy 85.957156 2.477008) (xy 88.448896 -0.014732) (xy 88.448896 -9.487154)
				(xy 89.335356 -10.373614) (xy 92.603828 -10.373614) (xy 93.476064 -9.501378) (xy 93.476064 -0.021844)
				(xy 95.982282 2.484374) (xy 124.014484 2.484374) (xy 126.527814 -0.028956) (xy 126.527814 -9.479788)
				(xy 127.406908 -10.358882) (xy 130.711956 -10.358882) (xy 131.583938 -9.4869) (xy 131.583938 -0.014732)
				(xy 134.083044 2.484374) (xy 150.049484 2.484374) (xy 152.555448 -0.02159) (xy 152.555448 -9.487154)
				(xy 153.434542 -10.366248) (xy 156.710634 -10.366248) (xy 157.611318 -9.465564) (xy 157.611318 0.028956)
				(xy 160.066736 2.484374) (xy 176.047908 2.484374) (xy 178.54676 -0.014478) (xy 178.54676 -9.487154)
				(xy 179.432966 -10.37336) (xy 182.716424 -10.37336) (xy 183.588406 -9.501378) (xy 183.588406 0.108712)
				(xy 185.978546 2.498852) (xy 202.039474 2.498852) (xy 204.55255 -0.014224) (xy 204.55255 -9.494266)
				(xy 205.424278 -10.365994) (xy 208.67878 -10.365994) (xy 209.601308 -9.443466) (xy 209.601308 0.115824)
				(xy 211.962492 2.477008) (xy 240.132616 2.477008) (xy 242.660932 -0.051308) (xy 242.660932 -9.487408)
				(xy 243.553996 -10.380472) (xy 246.77243 -10.380472) (xy 247.694704 -9.458198) (xy 247.694704 0.137668)
				(xy 250.048522 2.491486) (xy 266.145772 2.491486) (xy 268.644624 -0.007366) (xy 268.644624 -9.49452)
				(xy 269.53083 -10.380726) (xy 272.777966 -10.380726) (xy 273.678904 -9.479788) (xy 273.678904 0.072644)
				(xy 276.068536 2.462276) (xy 292.137338 2.462276) (xy 294.635936 -0.036322) (xy 294.635936 -9.494266)
				(xy 295.51503 -10.37336) (xy 298.798742 -10.37336) (xy 299.684694 -9.487408) (xy 299.684694 0.057912)
				(xy 302.125634 2.498852) (xy 318.128396 2.498852) (xy 320.64198 -0.014732) (xy 320.64198 -9.465564)
				(xy 321.542664 -10.366248) (xy 324.782688 -10.366248) (xy 325.676006 -9.47293) (xy 325.676006 0.028702)
				(xy 328.124058 2.476754) (xy 356.272592 2.476754) (xy 358.742742 0.006604) (xy 358.742742 -9.472422)
				(xy 359.650792 -10.380472) (xy 362.890562 -10.380472) (xy 363.792008 -9.479026) (xy 363.792008 0.186182)
				(xy 366.094518 2.488692) (xy 382.248156 2.488692) (xy 384.753866 -0.017018) (xy 384.753866 -9.561322)
				(xy 385.567174 -10.37463) (xy 388.959344 -10.37463) (xy 389.79475 -9.539224) (xy 389.79475 -0.017018)
				(xy 392.293094 2.481326) (xy 408.229054 2.481326) (xy 410.747972 -0.037592) (xy 410.747972 -9.536176)
				(xy 411.571948 -10.360152) (xy 414.932876 -10.360152) (xy 415.797492 -9.495536) (xy 415.797492 0.09652)
				(xy 418.182552 2.48158) (xy 434.261006 2.48158) (xy 436.737506 0.00508) (xy 436.737506 -9.524746)
				(xy 437.616346 -10.403586) (xy 440.97194 -10.403586) (xy 441.783724 -9.591802) (xy 441.783724 -0.004572)
				(xy 444.25489 2.466594) (xy 466.277198 2.466594) (xy 467.105492 3.294888) (xy 467.105492 24.772366)
				(xy 466.204808 25.67305) (xy 160.964372 25.67305) (xy 160.957006 25.680416) (xy 159.475424 25.680416)
				(xy 158.608776 24.813768) (xy 158.608776 8.396478) (xy 156.09316 5.880862) (xy 17.478248 5.880862)
				(xy 15.037562 8.321548) (xy 15.037562 24.794718) (xy 14.122654 25.709626) (xy 1.397 25.709626) (xy 0.438404 24.75103)
				(xy 0.438404 3.295142) (xy 1.280922 2.452624) (xy 3.663188 2.452624) (xy 3.750564 2.365248) (xy 3.750564 -0.4953)
				(arc
					(start 1.999996 -0.4953)
					(mid 0.936015 -0.936015)
					(end 0.4953 -1.999996)
				)
				(arc
					(start 0.4953 -82.131662)
					(mid 0.609819 -82.707387)
					(end 0.93599 -83.195414)
				)
				(arc
					(start 3.564382 -85.82406)
					(mid 4.105329 -86.633505)
					(end 4.295394 -87.588344)
				)
				(arc
					(start 4.295394 -241.031522)
					(mid 4.105349 -241.986474)
					(end 3.564382 -242.79606)
				)
				(arc
					(start 0.93599 -245.424452)
					(mid 0.609854 -245.912505)
					(end 0.4953 -246.488204)
				)
				(arc
					(start 0.4953 -416.589972)
					(mid 0.936015 -417.653953)
					(end 1.999996 -418.094668)
				)
				(xy 7.072122 -418.094668) (xy 7.072122 -420.617396) (xy 6.948424 -420.741094) (xy 1.522984 -420.741094)
				(xy 0.321818 -421.94226) (xy 0.321818 -461.082644) (xy 1.382014 -462.14284) (xy 466.278214 -462.14284)
				(xy 467.285324 -461.13573) (xy 467.285324 -421.871648) (xy 466.313266 -420.89959) (xy 447.264282 -420.89959)
				(xy 446.380616 -421.783256) (xy 446.380616 -429.187356) (xy 444.08344 -431.484532) (xy 371.068092 -431.484532)
				(xy 368.780568 -429.197008) (xy 368.780568 -421.977058) (xy 367.845086 -421.041576) (xy 359.245154 -421.041576)
				(xy 358.37368 -421.91305) (xy 358.37368 -429.07458) (xy 355.904038 -431.544222) (xy 283.140404 -431.544222)
				(xy 280.816304 -429.220122) (xy 280.816304 -421.94226) (xy 279.91562 -421.041576) (xy 276.196806 -421.041576)
				(xy 275.325332 -421.91305) (xy 275.325332 -430.55667) (xy 272.8849 -432.997102) (xy 202.34402 -432.997102)
				(xy 199.917812 -430.570894) (xy 199.917812 -422.000426) (xy 198.97344 -421.056054) (xy 187.722764 -421.056054)
				(xy 186.836558 -421.94226) (xy 186.836558 -428.921926) (xy 184.22874 -431.529744) (xy 111.465106 -431.529744)
				(xy 109.21365 -429.278288) (xy 109.21365 -422.000426) (xy 108.269278 -421.056054) (xy 99.756722 -421.056054)
				(xy 98.84156 -421.971216) (xy 98.84156 -429.089312) (xy 96.35744 -431.573432) (xy 23.708868 -431.573432)
				(xy 21.230336 -429.0949) (xy 21.230336 -421.932354) (xy 20.32508 -421.027098) (xy 7.563866 -421.027098)
				(xy 7.287768 -420.751) (xy 7.287768 -418.143436) (xy 7.336536 -418.094668)
				(arc
					(start 200.481184 -418.094668)
					(mid 201.091023 -417.965547)
					(end 201.596244 -417.600384)
				)
				(arc
					(start 201.596244 -417.600384)
					(mid 202.433806 -416.99494)
					(end 203.444856 -416.780726)
				)
				(arc
					(start 271.794986 -416.780726)
					(mid 272.806071 -416.994861)
					(end 273.643598 -417.600384)
				)
				(arc
					(start 273.643598 -417.600384)
					(mid 274.148794 -417.965602)
					(end 274.758658 -418.094668)
				)
			)
		)
	)
	(zone
		(layers "F.Cu" "B.Cu" "In1.Cu" "In2.Cu" "In3.Cu" "In4.Cu" "In5.Cu" "In6.Cu"
			"In7.Cu" "In8.Cu" "In9.Cu" "In10.Cu" "In11.Cu" "In12.Cu" "In13.Cu" "In14.Cu"
			"In15.Cu" "In16.Cu"
		)
		(hatch none 0.5)
		(connect_pads
			(clearance 0)
		)
		(min_thickness 0.25)
		(keepout
			(tracks not_allowed)
			(vias allowed)
			(pads allowed)
			(copperpour not_allowed)
			(footprints allowed)
		)
		(placement
			(enabled no)
			(sheetname "")
		)
		(fill
			(thermal_gap 0.5)
			(thermal_bridge_width 0.5)
			(island_removal_mode 0)
		)
		(polygon
			(pts
				(arc
					(start 126.501144 -382.728724)
					(mid 126.516023 -382.692803)
					(end 126.551944 -382.677924)
				)
				(arc
					(start 127.268224 -382.677924)
					(mid 127.304145 -382.692803)
					(end 127.319024 -382.728724)
				)
				(arc
					(start 127.319024 -385.151376)
					(mid 127.304145 -385.187297)
					(end 127.268224 -385.202176)
				)
				(arc
					(start 126.551944 -385.202176)
					(mid 126.516023 -385.187297)
					(end 126.501144 -385.151376)
				)
			)
		)
	)
	(zone
		(layers "F.Cu" "B.Cu" "In1.Cu" "In2.Cu" "In3.Cu" "In4.Cu" "In5.Cu" "In6.Cu"
			"In7.Cu" "In8.Cu" "In9.Cu" "In10.Cu" "In11.Cu" "In12.Cu" "In13.Cu" "In14.Cu"
			"In15.Cu" "In16.Cu"
		)
		(hatch none 0.5)
		(connect_pads
			(clearance 0)
		)
		(min_thickness 0.25)
		(keepout
			(tracks not_allowed)
			(vias allowed)
			(pads allowed)
			(copperpour not_allowed)
			(footprints allowed)
		)
		(placement
			(enabled no)
			(sheetname "")
		)
		(fill
			(thermal_gap 0.5)
			(thermal_bridge_width 0.5)
			(island_removal_mode 0)
		)
		(polygon
			(pts
				(arc
					(start 431.057812 -351.230438)
					(mid 430.676812 -351.611438)
					(end 431.057812 -351.992438)
				)
				(arc
					(start 431.921412 -351.992438)
					(mid 432.302412 -351.611438)
					(end 431.921412 -351.230438)
				)
			)
		)
	)
	(zone
		(layers "F.Cu" "B.Cu" "In1.Cu" "In2.Cu" "In3.Cu" "In4.Cu" "In5.Cu" "In6.Cu"
			"In7.Cu" "In8.Cu" "In9.Cu" "In10.Cu" "In11.Cu" "In12.Cu" "In13.Cu" "In14.Cu"
			"In15.Cu" "In16.Cu"
		)
		(hatch none 0.5)
		(connect_pads
			(clearance 0)
		)
		(min_thickness 0.25)
		(keepout
			(tracks not_allowed)
			(vias allowed)
			(pads allowed)
			(copperpour not_allowed)
			(footprints allowed)
		)
		(placement
			(enabled no)
			(sheetname "")
		)
		(fill
			(thermal_gap 0.5)
			(thermal_bridge_width 0.5)
			(island_removal_mode 0)
		)
		(polygon
			(pts
				(arc
					(start 313.274964 -123.159266)
					(mid 313.732164 -123.616466)
					(end 314.189364 -123.159266)
				)
				(arc
					(start 314.189364 -122.295666)
					(mid 313.732164 -121.838466)
					(end 313.274964 -122.295666)
				)
			)
		)
	)
	(zone
		(layers "F.Cu" "B.Cu" "In1.Cu" "In2.Cu" "In3.Cu" "In4.Cu" "In5.Cu" "In6.Cu"
			"In7.Cu" "In8.Cu" "In9.Cu" "In10.Cu" "In11.Cu" "In12.Cu" "In13.Cu" "In14.Cu"
			"In15.Cu" "In16.Cu"
		)
		(hatch none 0.5)
		(connect_pads
			(clearance 0)
		)
		(min_thickness 0.25)
		(keepout
			(tracks not_allowed)
			(vias allowed)
			(pads allowed)
			(copperpour not_allowed)
			(footprints allowed)
		)
		(placement
			(enabled no)
			(sheetname "")
		)
		(fill
			(thermal_gap 0.5)
			(thermal_bridge_width 0.5)
			(island_removal_mode 0)
		)
		(polygon
			(pts
				(arc
					(start 343.592404 -354.351082)
					(mid 343.211404 -354.732082)
					(end 343.592404 -355.113082)
				)
				(arc
					(start 344.456004 -355.113082)
					(mid 344.837004 -354.732082)
					(end 344.456004 -354.351082)
				)
			)
		)
	)
	(zone
		(layers "F.Cu" "B.Cu" "In1.Cu" "In2.Cu" "In3.Cu" "In4.Cu" "In5.Cu" "In6.Cu"
			"In7.Cu" "In8.Cu" "In9.Cu" "In10.Cu" "In11.Cu" "In12.Cu" "In13.Cu" "In14.Cu"
			"In15.Cu" "In16.Cu"
		)
		(hatch none 0.5)
		(connect_pads
			(clearance 0)
		)
		(min_thickness 0.25)
		(keepout
			(tracks not_allowed)
			(vias allowed)
			(pads allowed)
			(copperpour not_allowed)
			(footprints allowed)
		)
		(placement
			(enabled no)
			(sheetname "")
		)
		(fill
			(thermal_gap 0.5)
			(thermal_bridge_width 0.5)
			(island_removal_mode 0)
		)
		(polygon
			(pts
				(arc
					(start 434.48097 -371.028722)
					(mid 434.495849 -370.992801)
					(end 434.53177 -370.977922)
				)
				(arc
					(start 435.24805 -370.977922)
					(mid 435.283971 -370.992801)
					(end 435.29885 -371.028722)
				)
				(arc
					(start 435.29885 -373.451374)
					(mid 435.283971 -373.487295)
					(end 435.24805 -373.502174)
				)
				(arc
					(start 434.53177 -373.502174)
					(mid 434.495849 -373.487295)
					(end 434.48097 -373.451374)
				)
			)
		)
	)
	(zone
		(layers "F.Cu" "B.Cu" "In1.Cu" "In2.Cu" "In3.Cu" "In4.Cu" "In5.Cu" "In6.Cu"
			"In7.Cu" "In8.Cu" "In9.Cu" "In10.Cu" "In11.Cu" "In12.Cu" "In13.Cu" "In14.Cu"
			"In15.Cu" "In16.Cu"
		)
		(hatch none 0.5)
		(connect_pads
			(clearance 0)
		)
		(min_thickness 0.25)
		(keepout
			(tracks not_allowed)
			(vias allowed)
			(pads allowed)
			(copperpour not_allowed)
			(footprints allowed)
		)
		(placement
			(enabled no)
			(sheetname "")
		)
		(fill
			(thermal_gap 0.5)
			(thermal_bridge_width 0.5)
			(island_removal_mode 0)
		)
		(polygon
			(pts
				(arc
					(start 34.877248 -351.230438)
					(mid 34.496248 -351.611438)
					(end 34.877248 -351.992438)
				)
				(arc
					(start 35.740848 -351.992438)
					(mid 36.121848 -351.611438)
					(end 35.740848 -351.230438)
				)
			)
		)
	)
	(zone
		(layers "F.Cu" "B.Cu" "In1.Cu" "In2.Cu" "In3.Cu" "In4.Cu" "In5.Cu" "In6.Cu"
			"In7.Cu" "In8.Cu" "In9.Cu" "In10.Cu" "In11.Cu" "In12.Cu" "In13.Cu" "In14.Cu"
			"In15.Cu" "In16.Cu"
		)
		(hatch none 0.5)
		(connect_pads
			(clearance 0)
		)
		(min_thickness 0.25)
		(keepout
			(tracks not_allowed)
			(vias allowed)
			(pads allowed)
			(copperpour not_allowed)
			(footprints allowed)
		)
		(placement
			(enabled no)
			(sheetname "")
		)
		(fill
			(thermal_gap 0.5)
			(thermal_bridge_width 0.5)
			(island_removal_mode 0)
		)
		(polygon
			(pts
				(arc
					(start 280.332942 -351.230438)
					(mid 279.951942 -351.611438)
					(end 280.332942 -351.992438)
				)
				(arc
					(start 281.196542 -351.992438)
					(mid 281.577542 -351.611438)
					(end 281.196542 -351.230438)
				)
			)
		)
	)
	(zone
		(layers "F.Cu" "B.Cu" "In1.Cu" "In2.Cu" "In3.Cu" "In4.Cu" "In5.Cu" "In6.Cu"
			"In7.Cu" "In8.Cu" "In9.Cu" "In10.Cu" "In11.Cu" "In12.Cu" "In13.Cu" "In14.Cu"
			"In15.Cu" "In16.Cu"
		)
		(hatch none 0.5)
		(connect_pads
			(clearance 0)
		)
		(min_thickness 0.25)
		(keepout
			(tracks not_allowed)
			(vias allowed)
			(pads allowed)
			(copperpour not_allowed)
			(footprints allowed)
		)
		(placement
			(enabled no)
			(sheetname "")
		)
		(fill
			(thermal_gap 0.5)
			(thermal_bridge_width 0.5)
			(island_removal_mode 0)
		)
		(polygon
			(pts
				(arc
					(start 168.404032 -357.37673)
					(mid 168.023032 -357.75773)
					(end 168.404032 -358.13873)
				)
				(arc
					(start 169.267632 -358.13873)
					(mid 169.648632 -357.75773)
					(end 169.267632 -357.37673)
				)
			)
		)
	)
	(zone
		(layers "F.Cu" "B.Cu" "In1.Cu" "In2.Cu" "In3.Cu" "In4.Cu" "In5.Cu" "In6.Cu"
			"In7.Cu" "In8.Cu" "In9.Cu" "In10.Cu" "In11.Cu" "In12.Cu" "In13.Cu" "In14.Cu"
			"In15.Cu" "In16.Cu"
		)
		(hatch none 0.5)
		(connect_pads
			(clearance 0)
		)
		(min_thickness 0.25)
		(keepout
			(tracks not_allowed)
			(vias allowed)
			(pads allowed)
			(copperpour not_allowed)
			(footprints allowed)
		)
		(placement
			(enabled no)
			(sheetname "")
		)
		(fill
			(thermal_gap 0.5)
			(thermal_bridge_width 0.5)
			(island_removal_mode 0)
		)
		(polygon
			(pts
				(arc
					(start 163.90112 -407.628852)
					(mid 163.915999 -407.592931)
					(end 163.95192 -407.578052)
				)
				(arc
					(start 164.6682 -407.578052)
					(mid 164.704121 -407.592931)
					(end 164.719 -407.628852)
				)
				(arc
					(start 164.719 -410.051504)
					(mid 164.704121 -410.087425)
					(end 164.6682 -410.102304)
				)
				(arc
					(start 163.95192 -410.102304)
					(mid 163.915999 -410.087425)
					(end 163.90112 -410.051504)
				)
			)
		)
	)
	(zone
		(layers "F.Cu" "B.Cu" "In1.Cu" "In2.Cu" "In3.Cu" "In4.Cu" "In5.Cu" "In6.Cu"
			"In7.Cu" "In8.Cu" "In9.Cu" "In10.Cu" "In11.Cu" "In12.Cu" "In13.Cu" "In14.Cu"
			"In15.Cu" "In16.Cu"
		)
		(hatch none 0.5)
		(connect_pads
			(clearance 0)
		)
		(min_thickness 0.25)
		(keepout
			(tracks not_allowed)
			(vias allowed)
			(pads allowed)
			(copperpour not_allowed)
			(footprints allowed)
		)
		(placement
			(enabled no)
			(sheetname "")
		)
		(fill
			(thermal_gap 0.5)
			(thermal_bridge_width 0.5)
			(island_removal_mode 0)
		)
		(polygon
			(pts
				(arc
					(start 34.66846 -105.584498)
					(mid 35.12566 -106.041698)
					(end 35.58286 -105.584498)
				)
				(arc
					(start 35.58286 -104.720898)
					(mid 35.12566 -104.263698)
					(end 34.66846 -104.720898)
				)
			)
		)
	)
	(zone
		(layers "F.Cu" "B.Cu" "In1.Cu" "In2.Cu" "In3.Cu" "In4.Cu" "In5.Cu" "In6.Cu"
			"In7.Cu" "In8.Cu" "In9.Cu" "In10.Cu" "In11.Cu" "In12.Cu" "In13.Cu" "In14.Cu"
			"In15.Cu" "In16.Cu"
		)
		(hatch none 0.5)
		(connect_pads
			(clearance 0)
		)
		(min_thickness 0.25)
		(keepout
			(tracks not_allowed)
			(vias allowed)
			(pads allowed)
			(copperpour not_allowed)
			(footprints allowed)
		)
		(placement
			(enabled no)
			(sheetname "")
		)
		(fill
			(thermal_gap 0.5)
			(thermal_bridge_width 0.5)
			(island_removal_mode 0)
		)
		(polygon
			(pts
				(arc
					(start 298.130214 -36.60013)
					(mid 296.199814 -36.60013)
					(end 298.130214 -36.60013)
				)
			)
		)
	)
	(zone
		(layers "F.Cu" "B.Cu" "In1.Cu" "In2.Cu" "In3.Cu" "In4.Cu" "In5.Cu" "In6.Cu"
			"In7.Cu" "In8.Cu" "In9.Cu" "In10.Cu" "In11.Cu" "In12.Cu" "In13.Cu" "In14.Cu"
			"In15.Cu" "In16.Cu"
		)
		(hatch none 0.5)
		(connect_pads
			(clearance 0)
		)
		(min_thickness 0.25)
		(keepout
			(tracks not_allowed)
			(vias allowed)
			(pads allowed)
			(copperpour not_allowed)
			(footprints allowed)
		)
		(placement
			(enabled no)
			(sheetname "")
		)
		(fill
			(thermal_gap 0.5)
			(thermal_bridge_width 0.5)
			(island_removal_mode 0)
		)
		(polygon
			(pts
				(arc
					(start 126.501144 -397.028924)
					(mid 126.516023 -396.993003)
					(end 126.551944 -396.978124)
				)
				(arc
					(start 127.268224 -396.978124)
					(mid 127.304145 -396.993003)
					(end 127.319024 -397.028924)
				)
				(arc
					(start 127.319024 -399.451576)
					(mid 127.304145 -399.487497)
					(end 127.268224 -399.502376)
				)
				(arc
					(start 126.551944 -399.502376)
					(mid 126.516023 -399.487497)
					(end 126.501144 -399.451576)
				)
			)
		)
	)
	(zone
		(layers "F.Cu" "B.Cu" "In1.Cu" "In2.Cu" "In3.Cu" "In4.Cu" "In5.Cu" "In6.Cu"
			"In7.Cu" "In8.Cu" "In9.Cu" "In10.Cu" "In11.Cu" "In12.Cu" "In13.Cu" "In14.Cu"
			"In15.Cu" "In16.Cu"
		)
		(hatch none 0.5)
		(connect_pads
			(clearance 0)
		)
		(min_thickness 0.25)
		(keepout
			(tracks not_allowed)
			(vias allowed)
			(pads allowed)
			(copperpour not_allowed)
			(footprints allowed)
		)
		(placement
			(enabled no)
			(sheetname "")
		)
		(fill
			(thermal_gap 0.5)
			(thermal_bridge_width 0.5)
			(island_removal_mode 0)
		)
		(polygon
			(pts
				(arc
					(start 37.310568 -121.894346)
					(mid 37.767768 -122.351546)
					(end 38.224968 -121.894346)
				)
				(arc
					(start 38.224968 -121.030746)
					(mid 37.767768 -120.573546)
					(end 37.310568 -121.030746)
				)
			)
		)
	)
	(zone
		(layers "F.Cu" "B.Cu" "In1.Cu" "In2.Cu" "In3.Cu" "In4.Cu" "In5.Cu" "In6.Cu"
			"In7.Cu" "In8.Cu" "In9.Cu" "In10.Cu" "In11.Cu" "In12.Cu" "In13.Cu" "In14.Cu"
			"In15.Cu" "In16.Cu"
		)
		(hatch none 0.5)
		(connect_pads
			(clearance 0)
		)
		(min_thickness 0.25)
		(keepout
			(tracks not_allowed)
			(vias allowed)
			(pads allowed)
			(copperpour not_allowed)
			(footprints allowed)
		)
		(placement
			(enabled no)
			(sheetname "")
		)
		(fill
			(thermal_gap 0.5)
			(thermal_bridge_width 0.5)
			(island_removal_mode 0)
		)
		(polygon
			(pts
				(arc
					(start 133.624828 -354.351082)
					(mid 133.243828 -354.732082)
					(end 133.624828 -355.113082)
				)
				(arc
					(start 134.488428 -355.113082)
					(mid 134.869428 -354.732082)
					(end 134.488428 -354.351082)
				)
			)
		)
	)
	(zone
		(layers "F.Cu" "B.Cu" "In1.Cu" "In2.Cu" "In3.Cu" "In4.Cu" "In5.Cu" "In6.Cu"
			"In7.Cu" "In8.Cu" "In9.Cu" "In10.Cu" "In11.Cu" "In12.Cu" "In13.Cu" "In14.Cu"
			"In15.Cu" "In16.Cu"
		)
		(hatch none 0.5)
		(connect_pads
			(clearance 0)
		)
		(min_thickness 0.25)
		(keepout
			(tracks not_allowed)
			(vias allowed)
			(pads allowed)
			(copperpour not_allowed)
			(footprints allowed)
		)
		(placement
			(enabled no)
			(sheetname "")
		)
		(fill
			(thermal_gap 0.5)
			(thermal_bridge_width 0.5)
			(island_removal_mode 0)
		)
		(polygon
			(pts
				(arc
					(start 342.081104 -382.728724)
					(mid 342.095983 -382.692803)
					(end 342.131904 -382.677924)
				)
				(arc
					(start 342.848184 -382.677924)
					(mid 342.884105 -382.692803)
					(end 342.898984 -382.728724)
				)
				(arc
					(start 342.898984 -385.151376)
					(mid 342.884105 -385.187297)
					(end 342.848184 -385.202176)
				)
				(arc
					(start 342.131904 -385.202176)
					(mid 342.095983 -385.187297)
					(end 342.081104 -385.151376)
				)
			)
		)
	)
	(zone
		(layers "F.Cu" "B.Cu" "In1.Cu" "In2.Cu" "In3.Cu" "In4.Cu" "In5.Cu" "In6.Cu"
			"In7.Cu" "In8.Cu" "In9.Cu" "In10.Cu" "In11.Cu" "In12.Cu" "In13.Cu" "In14.Cu"
			"In15.Cu" "In16.Cu"
		)
		(hatch none 0.5)
		(connect_pads
			(clearance 0)
		)
		(min_thickness 0.25)
		(keepout
			(tracks not_allowed)
			(vias allowed)
			(pads allowed)
			(copperpour not_allowed)
			(footprints allowed)
		)
		(placement
			(enabled no)
			(sheetname "")
		)
		(fill
			(thermal_gap 0.5)
			(thermal_bridge_width 0.5)
			(island_removal_mode 0)
		)
		(polygon
			(pts
				(arc
					(start 129.977896 -188.68009)
					(mid 130.435096 -188.22289)
					(end 129.977896 -187.76569)
				)
				(arc
					(start 129.114296 -187.76569)
					(mid 128.657096 -188.22289)
					(end 129.114296 -188.68009)
				)
			)
		)
	)
	(zone
		(layers "F.Cu" "B.Cu" "In1.Cu" "In2.Cu" "In3.Cu" "In4.Cu" "In5.Cu" "In6.Cu"
			"In7.Cu" "In8.Cu" "In9.Cu" "In10.Cu" "In11.Cu" "In12.Cu" "In13.Cu" "In14.Cu"
			"In15.Cu" "In16.Cu"
		)
		(hatch none 0.5)
		(connect_pads
			(clearance 0)
		)
		(min_thickness 0.25)
		(keepout
			(tracks not_allowed)
			(vias allowed)
			(pads allowed)
			(copperpour not_allowed)
			(footprints allowed)
		)
		(placement
			(enabled no)
			(sheetname "")
		)
		(fill
			(thermal_gap 0.5)
			(thermal_bridge_width 0.5)
			(island_removal_mode 0)
		)
		(polygon
			(pts
				(arc
					(start 292.768782 -357.37673)
					(mid 292.387782 -357.75773)
					(end 292.768782 -358.13873)
				)
				(arc
					(start 293.632382 -358.13873)
					(mid 294.013382 -357.75773)
					(end 293.632382 -357.37673)
				)
			)
		)
	)
	(zone
		(layers "F.Cu" "B.Cu" "In1.Cu" "In2.Cu" "In3.Cu" "In4.Cu" "In5.Cu" "In6.Cu"
			"In7.Cu" "In8.Cu" "In9.Cu" "In10.Cu" "In11.Cu" "In12.Cu" "In13.Cu" "In14.Cu"
			"In15.Cu" "In16.Cu"
		)
		(hatch none 0.5)
		(connect_pads
			(clearance 0)
		)
		(min_thickness 0.25)
		(keepout
			(tracks not_allowed)
			(vias allowed)
			(pads allowed)
			(copperpour not_allowed)
			(footprints allowed)
		)
		(placement
			(enabled no)
			(sheetname "")
		)
		(fill
			(thermal_gap 0.5)
			(thermal_bridge_width 0.5)
			(island_removal_mode 0)
		)
		(polygon
			(pts
				(arc
					(start 52.69992 -108.312712)
					(mid 52.24272 -107.855512)
					(end 51.78552 -108.312712)
				)
				(arc
					(start 51.78552 -109.176312)
					(mid 52.24272 -109.633512)
					(end 52.69992 -109.176312)
				)
			)
		)
	)
	(zone
		(layers "F.Cu" "B.Cu" "In1.Cu" "In2.Cu" "In3.Cu" "In4.Cu" "In5.Cu" "In6.Cu"
			"In7.Cu" "In8.Cu" "In9.Cu" "In10.Cu" "In11.Cu" "In12.Cu" "In13.Cu" "In14.Cu"
			"In15.Cu" "In16.Cu"
		)
		(hatch none 0.5)
		(connect_pads
			(clearance 0)
		)
		(min_thickness 0.25)
		(keepout
			(tracks not_allowed)
			(vias allowed)
			(pads allowed)
			(copperpour not_allowed)
			(footprints allowed)
		)
		(placement
			(enabled no)
			(sheetname "")
		)
		(fill
			(thermal_gap 0.5)
			(thermal_bridge_width 0.5)
			(island_removal_mode 0)
		)
		(polygon
			(pts
				(arc
					(start 445.147954 -32.714184)
					(mid 445.605154 -33.171384)
					(end 446.062354 -32.714184)
				)
				(arc
					(start 446.062354 -31.850584)
					(mid 445.605154 -31.393384)
					(end 445.147954 -31.850584)
				)
			)
		)
	)
	(zone
		(layers "F.Cu" "B.Cu" "In1.Cu" "In2.Cu" "In3.Cu" "In4.Cu" "In5.Cu" "In6.Cu"
			"In7.Cu" "In8.Cu" "In9.Cu" "In10.Cu" "In11.Cu" "In12.Cu" "In13.Cu" "In14.Cu"
			"In15.Cu" "In16.Cu"
		)
		(hatch none 0.5)
		(connect_pads
			(clearance 0)
		)
		(min_thickness 0.25)
		(keepout
			(tracks not_allowed)
			(vias allowed)
			(pads allowed)
			(copperpour not_allowed)
			(footprints allowed)
		)
		(placement
			(enabled no)
			(sheetname "")
		)
		(fill
			(thermal_gap 0.5)
			(thermal_bridge_width 0.5)
			(island_removal_mode 0)
		)
		(polygon
			(pts
				(arc
					(start 324.938644 -351.230438)
					(mid 324.557644 -351.611438)
					(end 324.938644 -351.992438)
				)
				(arc
					(start 325.802244 -351.992438)
					(mid 326.183244 -351.611438)
					(end 325.802244 -351.230438)
				)
			)
		)
	)
	(zone
		(layers "F.Cu" "B.Cu" "In1.Cu" "In2.Cu" "In3.Cu" "In4.Cu" "In5.Cu" "In6.Cu"
			"In7.Cu" "In8.Cu" "In9.Cu" "In10.Cu" "In11.Cu" "In12.Cu" "In13.Cu" "In14.Cu"
			"In15.Cu" "In16.Cu"
		)
		(hatch none 0.5)
		(connect_pads
			(clearance 0)
		)
		(min_thickness 0.25)
		(keepout
			(tracks not_allowed)
			(vias allowed)
			(pads allowed)
			(copperpour not_allowed)
			(footprints allowed)
		)
		(placement
			(enabled no)
			(sheetname "")
		)
		(fill
			(thermal_gap 0.5)
			(thermal_bridge_width 0.5)
			(island_removal_mode 0)
		)
		(polygon
			(pts
				(arc
					(start 418.621972 -354.351082)
					(mid 418.240972 -354.732082)
					(end 418.621972 -355.113082)
				)
				(arc
					(start 419.485572 -355.113082)
					(mid 419.866572 -354.732082)
					(end 419.485572 -354.351082)
				)
			)
		)
	)
	(zone
		(layers "F.Cu" "B.Cu" "In1.Cu" "In2.Cu" "In3.Cu" "In4.Cu" "In5.Cu" "In6.Cu"
			"In7.Cu" "In8.Cu" "In9.Cu" "In10.Cu" "In11.Cu" "In12.Cu" "In13.Cu" "In14.Cu"
			"In15.Cu" "In16.Cu"
		)
		(hatch none 0.5)
		(connect_pads
			(clearance 0)
		)
		(min_thickness 0.25)
		(keepout
			(tracks not_allowed)
			(vias allowed)
			(pads allowed)
			(copperpour not_allowed)
			(footprints allowed)
		)
		(placement
			(enabled no)
			(sheetname "")
		)
		(fill
			(thermal_gap 0.5)
			(thermal_bridge_width 0.5)
			(island_removal_mode 0)
		)
		(polygon
			(pts
				(arc
					(start 91.301062 -408.728672)
					(mid 91.315941 -408.692751)
					(end 91.351862 -408.677872)
				)
				(arc
					(start 92.068142 -408.677872)
					(mid 92.104063 -408.692751)
					(end 92.118942 -408.728672)
				)
				(arc
					(start 92.118942 -411.151324)
					(mid 92.104063 -411.187245)
					(end 92.068142 -411.202124)
				)
				(arc
					(start 91.351862 -411.202124)
					(mid 91.315941 -411.187245)
					(end 91.301062 -411.151324)
				)
			)
		)
	)
	(zone
		(layers "F.Cu" "B.Cu" "In1.Cu" "In2.Cu" "In3.Cu" "In4.Cu" "In5.Cu" "In6.Cu"
			"In7.Cu" "In8.Cu" "In9.Cu" "In10.Cu" "In11.Cu" "In12.Cu" "In13.Cu" "In14.Cu"
			"In15.Cu" "In16.Cu"
		)
		(hatch none 0.5)
		(connect_pads
			(clearance 0)
		)
		(min_thickness 0.25)
		(keepout
			(tracks not_allowed)
			(vias allowed)
			(pads allowed)
			(copperpour not_allowed)
			(footprints allowed)
		)
		(placement
			(enabled no)
			(sheetname "")
		)
		(fill
			(thermal_gap 0.5)
			(thermal_bridge_width 0.5)
			(island_removal_mode 0)
		)
		(polygon
			(pts
				(arc
					(start 369.790218 -34.520886)
					(mid 370.247418 -34.978086)
					(end 370.704618 -34.520886)
				)
				(arc
					(start 370.704618 -33.657286)
					(mid 370.247418 -33.200086)
					(end 369.790218 -33.657286)
				)
			)
		)
	)
	(zone
		(layers "F.Cu" "B.Cu" "In1.Cu" "In2.Cu" "In3.Cu" "In4.Cu" "In5.Cu" "In6.Cu"
			"In7.Cu" "In8.Cu" "In9.Cu" "In10.Cu" "In11.Cu" "In12.Cu" "In13.Cu" "In14.Cu"
			"In15.Cu" "In16.Cu"
		)
		(hatch none 0.5)
		(connect_pads
			(clearance 0)
		)
		(min_thickness 0.25)
		(keepout
			(tracks not_allowed)
			(vias allowed)
			(pads allowed)
			(copperpour not_allowed)
			(footprints allowed)
		)
		(placement
			(enabled no)
			(sheetname "")
		)
		(fill
			(thermal_gap 0.5)
			(thermal_bridge_width 0.5)
			(island_removal_mode 0)
		)
		(polygon
			(pts
				(arc
					(start 43.974766 -289.104578)
					(mid 44.304966 -288.774378)
					(end 43.974766 -288.444178)
				)
				(arc
					(start 43.024806 -288.444178)
					(mid 42.694606 -288.774378)
					(end 43.024806 -289.104578)
				)
			)
		)
	)
	(zone
		(layers "F.Cu" "B.Cu" "In1.Cu" "In2.Cu" "In3.Cu" "In4.Cu" "In5.Cu" "In6.Cu"
			"In7.Cu" "In8.Cu" "In9.Cu" "In10.Cu" "In11.Cu" "In12.Cu" "In13.Cu" "In14.Cu"
			"In15.Cu" "In16.Cu"
		)
		(hatch none 0.5)
		(connect_pads
			(clearance 0)
		)
		(min_thickness 0.25)
		(keepout
			(tracks not_allowed)
			(vias allowed)
			(pads allowed)
			(copperpour not_allowed)
			(footprints allowed)
		)
		(placement
			(enabled no)
			(sheetname "")
		)
		(fill
			(thermal_gap 0.5)
			(thermal_bridge_width 0.5)
			(island_removal_mode 0)
		)
		(polygon
			(pts
				(arc
					(start 291.481002 -373.828818)
					(mid 291.495881 -373.792897)
					(end 291.531802 -373.778018)
				)
				(arc
					(start 292.248082 -373.778018)
					(mid 292.284003 -373.792897)
					(end 292.298882 -373.828818)
				)
				(arc
					(start 292.298882 -376.25147)
					(mid 292.284003 -376.287391)
					(end 292.248082 -376.30227)
				)
				(arc
					(start 291.531802 -376.30227)
					(mid 291.495881 -376.287391)
					(end 291.481002 -376.25147)
				)
			)
		)
	)
	(zone
		(layers "F.Cu" "B.Cu" "In1.Cu" "In2.Cu" "In3.Cu" "In4.Cu" "In5.Cu" "In6.Cu"
			"In7.Cu" "In8.Cu" "In9.Cu" "In10.Cu" "In11.Cu" "In12.Cu" "In13.Cu" "In14.Cu"
			"In15.Cu" "In16.Cu"
		)
		(hatch none 0.5)
		(connect_pads
			(clearance 0)
		)
		(min_thickness 0.25)
		(keepout
			(tracks not_allowed)
			(vias allowed)
			(pads allowed)
			(copperpour not_allowed)
			(footprints allowed)
		)
		(placement
			(enabled no)
			(sheetname "")
		)
		(fill
			(thermal_gap 0.5)
			(thermal_bridge_width 0.5)
			(island_removal_mode 0)
		)
		(polygon
			(pts
				(arc
					(start 266.868402 -123.68784)
					(mid 267.325602 -124.14504)
					(end 267.782802 -123.68784)
				)
				(arc
					(start 267.782802 -122.82424)
					(mid 267.325602 -122.36704)
					(end 266.868402 -122.82424)
				)
			)
		)
	)
	(zone
		(layers "F.Cu" "B.Cu" "In1.Cu" "In2.Cu" "In3.Cu" "In4.Cu" "In5.Cu" "In6.Cu"
			"In7.Cu" "In8.Cu" "In9.Cu" "In10.Cu" "In11.Cu" "In12.Cu" "In13.Cu" "In14.Cu"
			"In15.Cu" "In16.Cu"
		)
		(hatch none 0.5)
		(connect_pads
			(clearance 0)
		)
		(min_thickness 0.25)
		(keepout
			(tracks not_allowed)
			(vias allowed)
			(pads allowed)
			(copperpour not_allowed)
			(footprints allowed)
		)
		(placement
			(enabled no)
			(sheetname "")
		)
		(fill
			(thermal_gap 0.5)
			(thermal_bridge_width 0.5)
			(island_removal_mode 0)
		)
		(polygon
			(pts
				(xy 414.524952 -394.353796)
				(arc
					(start 414.524952 -417.533836)
					(mid 414.502634 -417.587718)
					(end 414.448752 -417.610036)
				)
				(arc
					(start 401.15109 -417.610036)
					(mid 401.097208 -417.587718)
					(end 401.07489 -417.533836)
				)
				(arc
					(start 401.07489 -394.356082)
					(mid 401.097208 -394.3022)
					(end 401.15109 -394.279882)
				)
				(arc
					(start 414.419288 -394.279882)
					(mid 414.448585 -394.285633)
					(end 414.47339 -394.302234)
				)
			)
		)
	)
	(zone
		(layers "F.Cu" "B.Cu" "In1.Cu" "In2.Cu" "In3.Cu" "In4.Cu" "In5.Cu" "In6.Cu"
			"In7.Cu" "In8.Cu" "In9.Cu" "In10.Cu" "In11.Cu" "In12.Cu" "In13.Cu" "In14.Cu"
			"In15.Cu" "In16.Cu"
		)
		(hatch none 0.5)
		(connect_pads
			(clearance 0)
		)
		(min_thickness 0.25)
		(keepout
			(tracks not_allowed)
			(vias allowed)
			(pads allowed)
			(copperpour not_allowed)
			(footprints allowed)
		)
		(placement
			(enabled no)
			(sheetname "")
		)
		(fill
			(thermal_gap 0.5)
			(thermal_bridge_width 0.5)
			(island_removal_mode 0)
		)
		(polygon
			(pts
				(arc
					(start 346.481146 -408.728672)
					(mid 346.496025 -408.692751)
					(end 346.531946 -408.677872)
				)
				(arc
					(start 347.248226 -408.677872)
					(mid 347.284147 -408.692751)
					(end 347.299026 -408.728672)
				)
				(arc
					(start 347.299026 -411.151324)
					(mid 347.284147 -411.187245)
					(end 347.248226 -411.202124)
				)
				(arc
					(start 346.531946 -411.202124)
					(mid 346.496025 -411.187245)
					(end 346.481146 -411.151324)
				)
			)
		)
	)
	(zone
		(layers "F.Cu" "B.Cu" "In1.Cu" "In2.Cu" "In3.Cu" "In4.Cu" "In5.Cu" "In6.Cu"
			"In7.Cu" "In8.Cu" "In9.Cu" "In10.Cu" "In11.Cu" "In12.Cu" "In13.Cu" "In14.Cu"
			"In15.Cu" "In16.Cu"
		)
		(hatch none 0.5)
		(connect_pads
			(clearance 0)
		)
		(min_thickness 0.25)
		(keepout
			(tracks not_allowed)
			(vias allowed)
			(pads allowed)
			(copperpour not_allowed)
			(footprints allowed)
		)
		(placement
			(enabled no)
			(sheetname "")
		)
		(fill
			(thermal_gap 0.5)
			(thermal_bridge_width 0.5)
			(island_removal_mode 0)
		)
		(polygon
			(pts
				(arc
					(start 315.917072 -132.575808)
					(mid 316.374272 -133.033008)
					(end 316.831472 -132.575808)
				)
				(arc
					(start 316.831472 -131.712208)
					(mid 316.374272 -131.255008)
					(end 315.917072 -131.712208)
				)
			)
		)
	)
	(zone
		(layers "F.Cu" "B.Cu" "In1.Cu" "In2.Cu" "In3.Cu" "In4.Cu" "In5.Cu" "In6.Cu"
			"In7.Cu" "In8.Cu" "In9.Cu" "In10.Cu" "In11.Cu" "In12.Cu" "In13.Cu" "In14.Cu"
			"In15.Cu" "In16.Cu"
		)
		(hatch none 0.5)
		(connect_pads
			(clearance 0)
		)
		(min_thickness 0.25)
		(keepout
			(tracks not_allowed)
			(vias allowed)
			(pads allowed)
			(copperpour not_allowed)
			(footprints allowed)
		)
		(placement
			(enabled no)
			(sheetname "")
		)
		(fill
			(thermal_gap 0.5)
			(thermal_bridge_width 0.5)
			(island_removal_mode 0)
		)
		(polygon
			(pts
				(xy 401.07489 -417.365434) (xy 414.524952 -417.365434) (xy 414.524952 -394.353796) (xy 414.451038 -394.279882)
				(xy 401.07489 -394.279882)
			)
		)
	)
	(zone
		(layers "F.Cu" "B.Cu" "In1.Cu" "In2.Cu" "In3.Cu" "In4.Cu" "In5.Cu" "In6.Cu"
			"In7.Cu" "In8.Cu" "In9.Cu" "In10.Cu" "In11.Cu" "In12.Cu" "In13.Cu" "In14.Cu"
			"In15.Cu" "In16.Cu"
		)
		(hatch none 0.5)
		(connect_pads
			(clearance 0)
		)
		(min_thickness 0.25)
		(keepout
			(tracks not_allowed)
			(vias allowed)
			(pads allowed)
			(copperpour not_allowed)
			(footprints allowed)
		)
		(placement
			(enabled no)
			(sheetname "")
		)
		(fill
			(thermal_gap 0.5)
			(thermal_bridge_width 0.5)
			(island_removal_mode 0)
		)
		(polygon
			(pts
				(arc
					(start 168.800018 -121.022872)
					(mid 168.342818 -120.565672)
					(end 167.885618 -121.022872)
				)
				(arc
					(start 167.885618 -121.886472)
					(mid 168.342818 -122.343672)
					(end 168.800018 -121.886472)
				)
			)
		)
	)
	(zone
		(layers "F.Cu" "B.Cu" "In1.Cu" "In2.Cu" "In3.Cu" "In4.Cu" "In5.Cu" "In6.Cu"
			"In7.Cu" "In8.Cu" "In9.Cu" "In10.Cu" "In11.Cu" "In12.Cu" "In13.Cu" "In14.Cu"
			"In15.Cu" "In16.Cu"
		)
		(hatch none 0.5)
		(connect_pads
			(clearance 0)
		)
		(min_thickness 0.25)
		(keepout
			(tracks not_allowed)
			(vias allowed)
			(pads allowed)
			(copperpour not_allowed)
			(footprints allowed)
		)
		(placement
			(enabled no)
			(sheetname "")
		)
		(fill
			(thermal_gap 0.5)
			(thermal_bridge_width 0.5)
			(island_removal_mode 0)
		)
		(polygon
			(pts
				(arc
					(start 84.700872 -369.928902)
					(mid 84.715751 -369.892981)
					(end 84.751672 -369.878102)
				)
				(arc
					(start 85.467952 -369.878102)
					(mid 85.503873 -369.892981)
					(end 85.518752 -369.928902)
				)
				(arc
					(start 85.518752 -372.351554)
					(mid 85.503873 -372.387475)
					(end 85.467952 -372.402354)
				)
				(arc
					(start 84.751672 -372.402354)
					(mid 84.715751 -372.387475)
					(end 84.700872 -372.351554)
				)
			)
		)
	)
	(zone
		(layers "F.Cu" "B.Cu" "In1.Cu" "In2.Cu" "In3.Cu" "In4.Cu" "In5.Cu" "In6.Cu"
			"In7.Cu" "In8.Cu" "In9.Cu" "In10.Cu" "In11.Cu" "In12.Cu" "In13.Cu" "In14.Cu"
			"In15.Cu" "In16.Cu"
		)
		(hatch none 0.5)
		(connect_pads
			(clearance 0)
		)
		(min_thickness 0.25)
		(keepout
			(tracks not_allowed)
			(vias allowed)
			(pads allowed)
			(copperpour not_allowed)
			(footprints allowed)
		)
		(placement
			(enabled no)
			(sheetname "")
		)
		(fill
			(thermal_gap 0.5)
			(thermal_bridge_width 0.5)
			(island_removal_mode 0)
		)
		(polygon
			(pts
				(arc
					(start 199.817228 -132.575808)
					(mid 200.274428 -133.033008)
					(end 200.731628 -132.575808)
				)
				(arc
					(start 200.731628 -131.712208)
					(mid 200.274428 -131.255008)
					(end 199.817228 -131.712208)
				)
			)
		)
	)
	(zone
		(layers "F.Cu" "B.Cu" "In1.Cu" "In2.Cu" "In3.Cu" "In4.Cu" "In5.Cu" "In6.Cu"
			"In7.Cu" "In8.Cu" "In9.Cu" "In10.Cu" "In11.Cu" "In12.Cu" "In13.Cu" "In14.Cu"
			"In15.Cu" "In16.Cu"
		)
		(hatch none 0.5)
		(connect_pads
			(clearance 0)
		)
		(min_thickness 0.25)
		(keepout
			(tracks not_allowed)
			(vias allowed)
			(pads allowed)
			(copperpour not_allowed)
			(footprints allowed)
		)
		(placement
			(enabled no)
			(sheetname "")
		)
		(fill
			(thermal_gap 0.5)
			(thermal_bridge_width 0.5)
			(island_removal_mode 0)
		)
		(polygon
			(pts
				(arc
					(start 38.501066 -382.728724)
					(mid 38.515945 -382.692803)
					(end 38.551866 -382.677924)
				)
				(arc
					(start 39.268146 -382.677924)
					(mid 39.304067 -382.692803)
					(end 39.318946 -382.728724)
				)
				(arc
					(start 39.318946 -385.151376)
					(mid 39.304067 -385.187297)
					(end 39.268146 -385.202176)
				)
				(arc
					(start 38.551866 -385.202176)
					(mid 38.515945 -385.187297)
					(end 38.501066 -385.151376)
				)
			)
		)
	)
	(zone
		(layers "F.Cu" "B.Cu" "In1.Cu" "In2.Cu" "In3.Cu" "In4.Cu" "In5.Cu" "In6.Cu"
			"In7.Cu" "In8.Cu" "In9.Cu" "In10.Cu" "In11.Cu" "In12.Cu" "In13.Cu" "In14.Cu"
			"In15.Cu" "In16.Cu"
		)
		(hatch none 0.5)
		(connect_pads
			(clearance 0)
		)
		(min_thickness 0.25)
		(keepout
			(tracks not_allowed)
			(vias allowed)
			(pads allowed)
			(copperpour not_allowed)
			(footprints allowed)
		)
		(placement
			(enabled no)
			(sheetname "")
		)
		(fill
			(thermal_gap 0.5)
			(thermal_bridge_width 0.5)
			(island_removal_mode 0)
		)
		(polygon
			(pts
				(arc
					(start 390.481058 -404.828756)
					(mid 390.495937 -404.792835)
					(end 390.531858 -404.777956)
				)
				(arc
					(start 391.248138 -404.777956)
					(mid 391.284059 -404.792835)
					(end 391.298938 -404.828756)
				)
				(arc
					(start 391.298938 -407.251408)
					(mid 391.284059 -407.287329)
					(end 391.248138 -407.302208)
				)
				(arc
					(start 390.531858 -407.302208)
					(mid 390.495937 -407.287329)
					(end 390.481058 -407.251408)
				)
			)
		)
	)
	(zone
		(layers "F.Cu" "B.Cu" "In1.Cu" "In2.Cu" "In3.Cu" "In4.Cu" "In5.Cu" "In6.Cu"
			"In7.Cu" "In8.Cu" "In9.Cu" "In10.Cu" "In11.Cu" "In12.Cu" "In13.Cu" "In14.Cu"
			"In15.Cu" "In16.Cu"
		)
		(hatch none 0.5)
		(connect_pads
			(clearance 0)
		)
		(min_thickness 0.25)
		(keepout
			(tracks not_allowed)
			(vias allowed)
			(pads allowed)
			(copperpour not_allowed)
			(footprints allowed)
		)
		(placement
			(enabled no)
			(sheetname "")
		)
		(fill
			(thermal_gap 0.5)
			(thermal_bridge_width 0.5)
			(island_removal_mode 0)
		)
		(polygon
			(pts
				(arc
					(start 92.461842 -351.230438)
					(mid 92.080842 -351.611438)
					(end 92.461842 -351.992438)
				)
				(arc
					(start 93.325442 -351.992438)
					(mid 93.706442 -351.611438)
					(end 93.325442 -351.230438)
				)
			)
		)
	)
	(zone
		(layers "F.Cu" "B.Cu" "In1.Cu" "In2.Cu" "In3.Cu" "In4.Cu" "In5.Cu" "In6.Cu"
			"In7.Cu" "In8.Cu" "In9.Cu" "In10.Cu" "In11.Cu" "In12.Cu" "In13.Cu" "In14.Cu"
			"In15.Cu" "In16.Cu"
		)
		(hatch none 0.5)
		(connect_pads
			(clearance 0)
		)
		(min_thickness 0.25)
		(keepout
			(tracks not_allowed)
			(vias allowed)
			(pads allowed)
			(copperpour not_allowed)
			(footprints allowed)
		)
		(placement
			(enabled no)
			(sheetname "")
		)
		(fill
			(thermal_gap 0.5)
			(thermal_bridge_width 0.5)
			(island_removal_mode 0)
		)
		(polygon
			(pts
				(arc
					(start 330.478384 -87.324184)
					(mid 330.935584 -87.781384)
					(end 331.392784 -87.324184)
				)
				(arc
					(start 331.392784 -86.460584)
					(mid 330.935584 -86.003384)
					(end 330.478384 -86.460584)
				)
			)
		)
	)
	(zone
		(layers "F.Cu" "B.Cu" "In1.Cu" "In2.Cu" "In3.Cu" "In4.Cu" "In5.Cu" "In6.Cu"
			"In7.Cu" "In8.Cu" "In9.Cu" "In10.Cu" "In11.Cu" "In12.Cu" "In13.Cu" "In14.Cu"
			"In15.Cu" "In16.Cu"
		)
		(hatch none 0.5)
		(connect_pads
			(clearance 0)
		)
		(min_thickness 0.25)
		(keepout
			(tracks not_allowed)
			(vias allowed)
			(pads allowed)
			(copperpour not_allowed)
			(footprints allowed)
		)
		(placement
			(enabled no)
			(sheetname "")
		)
		(fill
			(thermal_gap 0.5)
			(thermal_bridge_width 0.5)
			(island_removal_mode 0)
		)
		(polygon
			(pts
				(arc
					(start 6.800088 -400.15795)
					(mid 8.857996 -398.100042)
					(end 6.800088 -396.04188)
				)
				(arc
					(start 5.199888 -396.04188)
					(mid 3.141726 -398.100042)
					(end 5.199888 -400.15795)
				)
			)
		)
	)
	(zone
		(layers "F.Cu" "B.Cu" "In1.Cu" "In2.Cu" "In3.Cu" "In4.Cu" "In5.Cu" "In6.Cu"
			"In7.Cu" "In8.Cu" "In9.Cu" "In10.Cu" "In11.Cu" "In12.Cu" "In13.Cu" "In14.Cu"
			"In15.Cu" "In16.Cu"
		)
		(hatch none 0.5)
		(connect_pads
			(clearance 0)
		)
		(min_thickness 0.25)
		(keepout
			(tracks not_allowed)
			(vias allowed)
			(pads allowed)
			(copperpour not_allowed)
			(footprints allowed)
		)
		(placement
			(enabled no)
			(sheetname "")
		)
		(fill
			(thermal_gap 0.5)
			(thermal_bridge_width 0.5)
			(island_removal_mode 0)
		)
		(polygon
			(pts
				(arc
					(start 40.70096 -377.728734)
					(mid 40.715839 -377.692813)
					(end 40.75176 -377.677934)
				)
				(arc
					(start 41.46804 -377.677934)
					(mid 41.503961 -377.692813)
					(end 41.51884 -377.728734)
				)
				(arc
					(start 41.51884 -380.151386)
					(mid 41.503961 -380.187307)
					(end 41.46804 -380.202186)
				)
				(arc
					(start 40.75176 -380.202186)
					(mid 40.715839 -380.187307)
					(end 40.70096 -380.151386)
				)
			)
		)
	)
	(zone
		(layers "F.Cu" "B.Cu" "In1.Cu" "In2.Cu" "In3.Cu" "In4.Cu" "In5.Cu" "In6.Cu"
			"In7.Cu" "In8.Cu" "In9.Cu" "In10.Cu" "In11.Cu" "In12.Cu" "In13.Cu" "In14.Cu"
			"In15.Cu" "In16.Cu"
		)
		(hatch none 0.5)
		(connect_pads
			(clearance 0)
		)
		(min_thickness 0.25)
		(keepout
			(tracks not_allowed)
			(vias allowed)
			(pads allowed)
			(copperpour not_allowed)
			(footprints allowed)
		)
		(placement
			(enabled no)
			(sheetname "")
		)
		(fill
			(thermal_gap 0.5)
			(thermal_bridge_width 0.5)
			(island_removal_mode 0)
		)
		(polygon
			(pts
				(arc
					(start 96.847914 -32.714184)
					(mid 97.305114 -33.171384)
					(end 97.762314 -32.714184)
				)
				(arc
					(start 97.762314 -31.850584)
					(mid 97.305114 -31.393384)
					(end 96.847914 -31.850584)
				)
			)
		)
	)
	(zone
		(layers "F.Cu" "B.Cu" "In1.Cu" "In2.Cu" "In3.Cu" "In4.Cu" "In5.Cu" "In6.Cu"
			"In7.Cu" "In8.Cu" "In9.Cu" "In10.Cu" "In11.Cu" "In12.Cu" "In13.Cu" "In14.Cu"
			"In15.Cu" "In16.Cu"
		)
		(hatch none 0.5)
		(connect_pads
			(clearance 0)
		)
		(min_thickness 0.25)
		(keepout
			(tracks not_allowed)
			(vias allowed)
			(pads allowed)
			(copperpour not_allowed)
			(footprints allowed)
		)
		(placement
			(enabled no)
			(sheetname "")
		)
		(fill
			(thermal_gap 0.5)
			(thermal_bridge_width 0.5)
			(island_removal_mode 0)
		)
		(polygon
			(pts
				(arc
					(start 34.101024 -408.728672)
					(mid 34.115903 -408.692751)
					(end 34.151824 -408.677872)
				)
				(arc
					(start 34.868104 -408.677872)
					(mid 34.904025 -408.692751)
					(end 34.918904 -408.728672)
				)
				(arc
					(start 34.918904 -411.151324)
					(mid 34.904025 -411.187245)
					(end 34.868104 -411.202124)
				)
				(arc
					(start 34.151824 -411.202124)
					(mid 34.115903 -411.187245)
					(end 34.101024 -411.151324)
				)
			)
		)
	)
	(zone
		(layers "F.Cu" "B.Cu" "In1.Cu" "In2.Cu" "In3.Cu" "In4.Cu" "In5.Cu" "In6.Cu"
			"In7.Cu" "In8.Cu" "In9.Cu" "In10.Cu" "In11.Cu" "In12.Cu" "In13.Cu" "In14.Cu"
			"In15.Cu" "In16.Cu"
		)
		(hatch none 0.5)
		(connect_pads
			(clearance 0)
		)
		(min_thickness 0.25)
		(keepout
			(tracks not_allowed)
			(vias allowed)
			(pads allowed)
			(copperpour not_allowed)
			(footprints allowed)
		)
		(placement
			(enabled no)
			(sheetname "")
		)
		(fill
			(thermal_gap 0.5)
			(thermal_bridge_width 0.5)
			(island_removal_mode 0)
		)
		(polygon
			(pts
				(arc
					(start 346.481146 -404.828756)
					(mid 346.496025 -404.792835)
					(end 346.531946 -404.777956)
				)
				(arc
					(start 347.248226 -404.777956)
					(mid 347.284147 -404.792835)
					(end 347.299026 -404.828756)
				)
				(arc
					(start 347.299026 -407.251408)
					(mid 347.284147 -407.287329)
					(end 347.248226 -407.302208)
				)
				(arc
					(start 346.531946 -407.302208)
					(mid 346.496025 -407.287329)
					(end 346.481146 -407.251408)
				)
			)
		)
	)
	(zone
		(layers "F.Cu" "B.Cu" "In1.Cu" "In2.Cu" "In3.Cu" "In4.Cu" "In5.Cu" "In6.Cu"
			"In7.Cu" "In8.Cu" "In9.Cu" "In10.Cu" "In11.Cu" "In12.Cu" "In13.Cu" "In14.Cu"
			"In15.Cu" "In16.Cu"
		)
		(hatch none 0.5)
		(connect_pads
			(clearance 0)
		)
		(min_thickness 0.25)
		(keepout
			(tracks not_allowed)
			(vias allowed)
			(pads allowed)
			(copperpour not_allowed)
			(footprints allowed)
		)
		(placement
			(enabled no)
			(sheetname "")
		)
		(fill
			(thermal_gap 0.5)
			(thermal_bridge_width 0.5)
			(island_removal_mode 0)
		)
		(polygon
			(pts
				(arc
					(start 298.080938 -382.728724)
					(mid 298.095817 -382.692803)
					(end 298.131738 -382.677924)
				)
				(arc
					(start 298.848018 -382.677924)
					(mid 298.883939 -382.692803)
					(end 298.898818 -382.728724)
				)
				(arc
					(start 298.898818 -385.151376)
					(mid 298.883939 -385.187297)
					(end 298.848018 -385.202176)
				)
				(arc
					(start 298.131738 -385.202176)
					(mid 298.095817 -385.187297)
					(end 298.080938 -385.151376)
				)
			)
		)
	)
	(zone
		(layers "F.Cu" "B.Cu" "In1.Cu" "In2.Cu" "In3.Cu" "In4.Cu" "In5.Cu" "In6.Cu"
			"In7.Cu" "In8.Cu" "In9.Cu" "In10.Cu" "In11.Cu" "In12.Cu" "In13.Cu" "In14.Cu"
			"In15.Cu" "In16.Cu"
		)
		(hatch none 0.5)
		(connect_pads
			(clearance 0)
		)
		(min_thickness 0.25)
		(keepout
			(tracks not_allowed)
			(vias allowed)
			(pads allowed)
			(copperpour not_allowed)
			(footprints allowed)
		)
		(placement
			(enabled no)
			(sheetname "")
		)
		(fill
			(thermal_gap 0.5)
			(thermal_bridge_width 0.5)
			(island_removal_mode 0)
		)
		(polygon
			(pts
				(arc
					(start 114.971068 -357.37673)
					(mid 114.590068 -357.75773)
					(end 114.971068 -358.13873)
				)
				(arc
					(start 115.834668 -358.13873)
					(mid 116.215668 -357.75773)
					(end 115.834668 -357.37673)
				)
			)
		)
	)
	(zone
		(layers "F.Cu" "B.Cu" "In1.Cu" "In2.Cu" "In3.Cu" "In4.Cu" "In5.Cu" "In6.Cu"
			"In7.Cu" "In8.Cu" "In9.Cu" "In10.Cu" "In11.Cu" "In12.Cu" "In13.Cu" "In14.Cu"
			"In15.Cu" "In16.Cu"
		)
		(hatch none 0.5)
		(connect_pads
			(clearance 0)
		)
		(min_thickness 0.25)
		(keepout
			(tracks not_allowed)
			(vias allowed)
			(pads allowed)
			(copperpour not_allowed)
			(footprints allowed)
		)
		(placement
			(enabled no)
			(sheetname "")
		)
		(fill
			(thermal_gap 0.5)
			(thermal_bridge_width 0.5)
			(island_removal_mode 0)
		)
		(polygon
			(pts
				(arc
					(start 190.166752 -351.230438)
					(mid 189.785752 -351.611438)
					(end 190.166752 -351.992438)
				)
				(arc
					(start 191.030352 -351.992438)
					(mid 191.411352 -351.611438)
					(end 191.030352 -351.230438)
				)
			)
		)
	)
	(zone
		(layers "F.Cu" "B.Cu" "In1.Cu" "In2.Cu" "In3.Cu" "In4.Cu" "In5.Cu" "In6.Cu"
			"In7.Cu" "In8.Cu" "In9.Cu" "In10.Cu" "In11.Cu" "In12.Cu" "In13.Cu" "In14.Cu"
			"In15.Cu" "In16.Cu"
		)
		(hatch none 0.5)
		(connect_pads
			(clearance 0)
		)
		(min_thickness 0.25)
		(keepout
			(tracks not_allowed)
			(vias allowed)
			(pads allowed)
			(copperpour not_allowed)
			(footprints allowed)
		)
		(placement
			(enabled no)
			(sheetname "")
		)
		(fill
			(thermal_gap 0.5)
			(thermal_bridge_width 0.5)
			(island_removal_mode 0)
		)
		(polygon
			(pts
				(arc
					(start 329.047856 -29.114242)
					(mid 329.505056 -29.571442)
					(end 329.962256 -29.114242)
				)
				(arc
					(start 329.962256 -28.250642)
					(mid 329.505056 -27.793442)
					(end 329.047856 -28.250642)
				)
			)
		)
	)
	(zone
		(layers "F.Cu" "B.Cu" "In1.Cu" "In2.Cu" "In3.Cu" "In4.Cu" "In5.Cu" "In6.Cu"
			"In7.Cu" "In8.Cu" "In9.Cu" "In10.Cu" "In11.Cu" "In12.Cu" "In13.Cu" "In14.Cu"
			"In15.Cu" "In16.Cu"
		)
		(hatch none 0.5)
		(connect_pads
			(clearance 0)
		)
		(min_thickness 0.25)
		(keepout
			(tracks not_allowed)
			(vias allowed)
			(pads allowed)
			(copperpour not_allowed)
			(footprints allowed)
		)
		(placement
			(enabled no)
			(sheetname "")
		)
		(fill
			(thermal_gap 0.5)
			(thermal_bridge_width 0.5)
			(island_removal_mode 0)
		)
		(polygon
			(pts
				(arc
					(start 434.48097 -400.92884)
					(mid 434.495849 -400.892919)
					(end 434.53177 -400.87804)
				)
				(arc
					(start 435.24805 -400.87804)
					(mid 435.283971 -400.892919)
					(end 435.29885 -400.92884)
				)
				(arc
					(start 435.29885 -403.351492)
					(mid 435.283971 -403.387413)
					(end 435.24805 -403.402292)
				)
				(arc
					(start 434.53177 -403.402292)
					(mid 434.495849 -403.387413)
					(end 434.48097 -403.351492)
				)
			)
		)
	)
	(zone
		(layers "F.Cu" "B.Cu" "In1.Cu" "In2.Cu" "In3.Cu" "In4.Cu" "In5.Cu" "In6.Cu"
			"In7.Cu" "In8.Cu" "In9.Cu" "In10.Cu" "In11.Cu" "In12.Cu" "In13.Cu" "In14.Cu"
			"In15.Cu" "In16.Cu"
		)
		(hatch none 0.5)
		(connect_pads
			(clearance 0)
		)
		(min_thickness 0.25)
		(keepout
			(tracks not_allowed)
			(vias allowed)
			(pads allowed)
			(copperpour not_allowed)
			(footprints allowed)
		)
		(placement
			(enabled no)
			(sheetname "")
		)
		(fill
			(thermal_gap 0.5)
			(thermal_bridge_width 0.5)
			(island_removal_mode 0)
		)
		(polygon
			(pts
				(arc
					(start 67.590162 -345.084146)
					(mid 67.209162 -345.465146)
					(end 67.590162 -345.846146)
				)
				(arc
					(start 68.453762 -345.846146)
					(mid 68.834762 -345.465146)
					(end 68.453762 -345.084146)
				)
			)
		)
	)
	(zone
		(layers "F.Cu" "B.Cu" "In1.Cu" "In2.Cu" "In3.Cu" "In4.Cu" "In5.Cu" "In6.Cu"
			"In7.Cu" "In8.Cu" "In9.Cu" "In10.Cu" "In11.Cu" "In12.Cu" "In13.Cu" "In14.Cu"
			"In15.Cu" "In16.Cu"
		)
		(hatch none 0.5)
		(connect_pads
			(clearance 0)
		)
		(min_thickness 0.25)
		(keepout
			(tracks not_allowed)
			(vias allowed)
			(pads allowed)
			(copperpour not_allowed)
			(footprints allowed)
		)
		(placement
			(enabled no)
			(sheetname "")
		)
		(fill
			(thermal_gap 0.5)
			(thermal_bridge_width 0.5)
			(island_removal_mode 0)
		)
		(polygon
			(pts
				(arc
					(start 50.422048 -345.084146)
					(mid 50.041048 -345.465146)
					(end 50.422048 -345.846146)
				)
				(arc
					(start 51.285648 -345.846146)
					(mid 51.666648 -345.465146)
					(end 51.285648 -345.084146)
				)
			)
		)
	)
	(zone
		(layers "F.Cu" "B.Cu" "In1.Cu" "In2.Cu" "In3.Cu" "In4.Cu" "In5.Cu" "In6.Cu"
			"In7.Cu" "In8.Cu" "In9.Cu" "In10.Cu" "In11.Cu" "In12.Cu" "In13.Cu" "In14.Cu"
			"In15.Cu" "In16.Cu"
		)
		(hatch none 0.5)
		(connect_pads
			(clearance 0)
		)
		(min_thickness 0.25)
		(keepout
			(tracks not_allowed)
			(vias allowed)
			(pads allowed)
			(copperpour not_allowed)
			(footprints allowed)
		)
		(placement
			(enabled no)
			(sheetname "")
		)
		(fill
			(thermal_gap 0.5)
			(thermal_bridge_width 0.5)
			(island_removal_mode 0)
		)
		(polygon
			(pts
				(arc
					(start 89.352882 -348.20479)
					(mid 88.971882 -348.58579)
					(end 89.352882 -348.96679)
				)
				(arc
					(start 90.216482 -348.96679)
					(mid 90.597482 -348.58579)
					(end 90.216482 -348.20479)
				)
			)
		)
	)
	(zone
		(layers "F.Cu" "B.Cu" "In1.Cu" "In2.Cu" "In3.Cu" "In4.Cu" "In5.Cu" "In6.Cu"
			"In7.Cu" "In8.Cu" "In9.Cu" "In10.Cu" "In11.Cu" "In12.Cu" "In13.Cu" "In14.Cu"
			"In15.Cu" "In16.Cu"
		)
		(hatch none 0.5)
		(connect_pads
			(clearance 0)
		)
		(min_thickness 0.25)
		(keepout
			(tracks not_allowed)
			(vias allowed)
			(pads allowed)
			(copperpour not_allowed)
			(footprints allowed)
		)
		(placement
			(enabled no)
			(sheetname "")
		)
		(fill
			(thermal_gap 0.5)
			(thermal_bridge_width 0.5)
			(island_removal_mode 0)
		)
		(polygon
			(pts
				(arc
					(start 271.006062 -351.230438)
					(mid 270.625062 -351.611438)
					(end 271.006062 -351.992438)
				)
				(arc
					(start 271.869662 -351.992438)
					(mid 272.250662 -351.611438)
					(end 271.869662 -351.230438)
				)
			)
		)
	)
	(zone
		(layers "F.Cu" "B.Cu" "In1.Cu" "In2.Cu" "In3.Cu" "In4.Cu" "In5.Cu" "In6.Cu"
			"In7.Cu" "In8.Cu" "In9.Cu" "In10.Cu" "In11.Cu" "In12.Cu" "In13.Cu" "In14.Cu"
			"In15.Cu" "In16.Cu"
		)
		(hatch none 0.5)
		(connect_pads
			(clearance 0)
		)
		(min_thickness 0.25)
		(keepout
			(tracks not_allowed)
			(vias allowed)
			(pads allowed)
			(copperpour not_allowed)
			(footprints allowed)
		)
		(placement
			(enabled no)
			(sheetname "")
		)
		(fill
			(thermal_gap 0.5)
			(thermal_bridge_width 0.5)
			(island_removal_mode 0)
		)
		(polygon
			(pts
				(arc
					(start 383.62382 -357.37673)
					(mid 383.24282 -357.75773)
					(end 383.62382 -358.13873)
				)
				(arc
					(start 384.48742 -358.13873)
					(mid 384.86842 -357.75773)
					(end 384.48742 -357.37673)
				)
			)
		)
	)
	(zone
		(layers "F.Cu" "B.Cu" "In1.Cu" "In2.Cu" "In3.Cu" "In4.Cu" "In5.Cu" "In6.Cu"
			"In7.Cu" "In8.Cu" "In9.Cu" "In10.Cu" "In11.Cu" "In12.Cu" "In13.Cu" "In14.Cu"
			"In15.Cu" "In16.Cu"
		)
		(hatch none 0.5)
		(connect_pads
			(clearance 0)
		)
		(min_thickness 0.25)
		(keepout
			(tracks not_allowed)
			(vias allowed)
			(pads allowed)
			(copperpour not_allowed)
			(footprints allowed)
		)
		(placement
			(enabled no)
			(sheetname "")
		)
		(fill
			(thermal_gap 0.5)
			(thermal_bridge_width 0.5)
			(island_removal_mode 0)
		)
		(polygon
			(pts
				(arc
					(start 163.90112 -395.92885)
					(mid 163.915999 -395.892929)
					(end 163.95192 -395.87805)
				)
				(arc
					(start 164.6682 -395.87805)
					(mid 164.704121 -395.892929)
					(end 164.719 -395.92885)
				)
				(arc
					(start 164.719 -398.351502)
					(mid 164.704121 -398.387423)
					(end 164.6682 -398.402302)
				)
				(arc
					(start 163.95192 -398.402302)
					(mid 163.915999 -398.387423)
					(end 163.90112 -398.351502)
				)
			)
		)
	)
	(zone
		(layers "F.Cu" "B.Cu" "In1.Cu" "In2.Cu" "In3.Cu" "In4.Cu" "In5.Cu" "In6.Cu"
			"In7.Cu" "In8.Cu" "In9.Cu" "In10.Cu" "In11.Cu" "In12.Cu" "In13.Cu" "In14.Cu"
			"In15.Cu" "In16.Cu"
		)
		(hatch none 0.5)
		(connect_pads
			(clearance 0)
		)
		(min_thickness 0.25)
		(keepout
			(tracks not_allowed)
			(vias allowed)
			(pads allowed)
			(copperpour not_allowed)
			(footprints allowed)
		)
		(placement
			(enabled no)
			(sheetname "")
		)
		(fill
			(thermal_gap 0.5)
			(thermal_bridge_width 0.5)
			(island_removal_mode 0)
		)
		(polygon
			(pts
				(arc
					(start 432.280822 -399.828766)
					(mid 432.295701 -399.792845)
					(end 432.331622 -399.777966)
				)
				(arc
					(start 433.047902 -399.777966)
					(mid 433.083823 -399.792845)
					(end 433.098702 -399.828766)
				)
				(arc
					(start 433.098702 -402.251418)
					(mid 433.083823 -402.287339)
					(end 433.047902 -402.302218)
				)
				(arc
					(start 432.331622 -402.302218)
					(mid 432.295701 -402.287339)
					(end 432.280822 -402.251418)
				)
			)
		)
	)
	(zone
		(layers "F.Cu" "B.Cu" "In1.Cu" "In2.Cu" "In3.Cu" "In4.Cu" "In5.Cu" "In6.Cu"
			"In7.Cu" "In8.Cu" "In9.Cu" "In10.Cu" "In11.Cu" "In12.Cu" "In13.Cu" "In14.Cu"
			"In15.Cu" "In16.Cu"
		)
		(hatch none 0.5)
		(connect_pads
			(clearance 0)
		)
		(min_thickness 0.25)
		(keepout
			(tracks not_allowed)
			(vias allowed)
			(pads allowed)
			(copperpour not_allowed)
			(footprints allowed)
		)
		(placement
			(enabled no)
			(sheetname "")
		)
		(fill
			(thermal_gap 0.5)
			(thermal_bridge_width 0.5)
			(island_removal_mode 0)
		)
		(polygon
			(pts
				(arc
					(start 414.90011 -123.16714)
					(mid 415.35731 -123.62434)
					(end 415.81451 -123.16714)
				)
				(arc
					(start 415.81451 -122.30354)
					(mid 415.35731 -121.84634)
					(end 414.90011 -122.30354)
				)
			)
		)
	)
	(zone
		(layers "F.Cu" "B.Cu" "In1.Cu" "In2.Cu" "In3.Cu" "In4.Cu" "In5.Cu" "In6.Cu"
			"In7.Cu" "In8.Cu" "In9.Cu" "In10.Cu" "In11.Cu" "In12.Cu" "In13.Cu" "In14.Cu"
			"In15.Cu" "In16.Cu"
		)
		(hatch none 0.5)
		(connect_pads
			(clearance 0)
		)
		(min_thickness 0.25)
		(keepout
			(tracks not_allowed)
			(vias allowed)
			(pads allowed)
			(copperpour not_allowed)
			(footprints allowed)
		)
		(placement
			(enabled no)
			(sheetname "")
		)
		(fill
			(thermal_gap 0.5)
			(thermal_bridge_width 0.5)
			(island_removal_mode 0)
		)
		(polygon
			(pts
				(arc
					(start 303.047908 -32.714184)
					(mid 303.505108 -33.171384)
					(end 303.962308 -32.714184)
				)
				(arc
					(start 303.962308 -31.850584)
					(mid 303.505108 -31.393384)
					(end 303.047908 -31.850584)
				)
			)
		)
	)
	(zone
		(layers "F.Cu" "B.Cu" "In1.Cu" "In2.Cu" "In3.Cu" "In4.Cu" "In5.Cu" "In6.Cu"
			"In7.Cu" "In8.Cu" "In9.Cu" "In10.Cu" "In11.Cu" "In12.Cu" "In13.Cu" "In14.Cu"
			"In15.Cu" "In16.Cu"
		)
		(hatch none 0.5)
		(connect_pads
			(clearance 0)
		)
		(min_thickness 0.25)
		(keepout
			(tracks not_allowed)
			(vias allowed)
			(pads allowed)
			(copperpour not_allowed)
			(footprints allowed)
		)
		(placement
			(enabled no)
			(sheetname "")
		)
		(fill
			(thermal_gap 0.5)
			(thermal_bridge_width 0.5)
			(island_removal_mode 0)
		)
		(polygon
			(pts
				(arc
					(start 29.700982 -397.028924)
					(mid 29.715861 -396.993003)
					(end 29.751782 -396.978124)
				)
				(arc
					(start 30.468062 -396.978124)
					(mid 30.503983 -396.993003)
					(end 30.518862 -397.028924)
				)
				(arc
					(start 30.518862 -399.451576)
					(mid 30.503983 -399.487497)
					(end 30.468062 -399.502376)
				)
				(arc
					(start 29.751782 -399.502376)
					(mid 29.715861 -399.487497)
					(end 29.700982 -399.451576)
				)
			)
		)
	)
	(zone
		(layers "F.Cu" "B.Cu" "In1.Cu" "In2.Cu" "In3.Cu" "In4.Cu" "In5.Cu" "In6.Cu"
			"In7.Cu" "In8.Cu" "In9.Cu" "In10.Cu" "In11.Cu" "In12.Cu" "In13.Cu" "In14.Cu"
			"In15.Cu" "In16.Cu"
		)
		(hatch none 0.5)
		(connect_pads
			(clearance 0)
		)
		(min_thickness 0.25)
		(keepout
			(tracks not_allowed)
			(vias allowed)
			(pads allowed)
			(copperpour not_allowed)
			(footprints allowed)
		)
		(placement
			(enabled no)
			(sheetname "")
		)
		(fill
			(thermal_gap 0.5)
			(thermal_bridge_width 0.5)
			(island_removal_mode 0)
		)
		(polygon
			(pts
				(arc
					(start 293.680896 -408.728672)
					(mid 293.695775 -408.692751)
					(end 293.731696 -408.677872)
				)
				(arc
					(start 294.447976 -408.677872)
					(mid 294.483897 -408.692751)
					(end 294.498776 -408.728672)
				)
				(arc
					(start 294.498776 -411.151324)
					(mid 294.483897 -411.187245)
					(end 294.447976 -411.202124)
				)
				(arc
					(start 293.731696 -411.202124)
					(mid 293.695775 -411.187245)
					(end 293.680896 -411.151324)
				)
			)
		)
	)
	(zone
		(layers "F.Cu" "B.Cu" "In1.Cu" "In2.Cu" "In3.Cu" "In4.Cu" "In5.Cu" "In6.Cu"
			"In7.Cu" "In8.Cu" "In9.Cu" "In10.Cu" "In11.Cu" "In12.Cu" "In13.Cu" "In14.Cu"
			"In15.Cu" "In16.Cu"
		)
		(hatch none 0.5)
		(connect_pads
			(clearance 0)
		)
		(min_thickness 0.25)
		(keepout
			(tracks not_allowed)
			(vias allowed)
			(pads allowed)
			(copperpour not_allowed)
			(footprints allowed)
		)
		(placement
			(enabled no)
			(sheetname "")
		)
		(fill
			(thermal_gap 0.5)
			(thermal_bridge_width 0.5)
			(island_removal_mode 0)
		)
		(polygon
			(pts
				(arc
					(start 117.70106 -404.828756)
					(mid 117.715939 -404.792835)
					(end 117.75186 -404.777956)
				)
				(arc
					(start 118.46814 -404.777956)
					(mid 118.504061 -404.792835)
					(end 118.51894 -404.828756)
				)
				(arc
					(start 118.51894 -407.251408)
					(mid 118.504061 -407.287329)
					(end 118.46814 -407.302208)
				)
				(arc
					(start 117.75186 -407.302208)
					(mid 117.715939 -407.287329)
					(end 117.70106 -407.251408)
				)
			)
		)
	)
	(zone
		(layers "F.Cu" "B.Cu" "In1.Cu" "In2.Cu" "In3.Cu" "In4.Cu" "In5.Cu" "In6.Cu"
			"In7.Cu" "In8.Cu" "In9.Cu" "In10.Cu" "In11.Cu" "In12.Cu" "In13.Cu" "In14.Cu"
			"In15.Cu" "In16.Cu"
		)
		(hatch none 0.5)
		(connect_pads
			(clearance 0)
		)
		(min_thickness 0.25)
		(keepout
			(tracks not_allowed)
			(vias allowed)
			(pads allowed)
			(copperpour not_allowed)
			(footprints allowed)
		)
		(placement
			(enabled no)
			(sheetname "")
		)
		(fill
			(thermal_gap 0.5)
			(thermal_bridge_width 0.5)
			(island_removal_mode 0)
		)
		(polygon
			(pts
				(arc
					(start 434.166772 -342.058498)
					(mid 433.785772 -342.439498)
					(end 434.166772 -342.820498)
				)
				(arc
					(start 435.030372 -342.820498)
					(mid 435.411372 -342.439498)
					(end 435.030372 -342.058498)
				)
			)
		)
	)
	(zone
		(layers "F.Cu" "B.Cu" "In1.Cu" "In2.Cu" "In3.Cu" "In4.Cu" "In5.Cu" "In6.Cu"
			"In7.Cu" "In8.Cu" "In9.Cu" "In10.Cu" "In11.Cu" "In12.Cu" "In13.Cu" "In14.Cu"
			"In15.Cu" "In16.Cu"
		)
		(hatch none 0.5)
		(connect_pads
			(clearance 0)
		)
		(min_thickness 0.25)
		(keepout
			(tracks not_allowed)
			(vias allowed)
			(pads allowed)
			(copperpour not_allowed)
			(footprints allowed)
		)
		(placement
			(enabled no)
			(sheetname "")
		)
		(fill
			(thermal_gap 0.5)
			(thermal_bridge_width 0.5)
			(island_removal_mode 0)
		)
		(polygon
			(pts
				(arc
					(start 315.917072 -124.965714)
					(mid 316.374272 -125.422914)
					(end 316.831472 -124.965714)
				)
				(arc
					(start 316.831472 -124.102114)
					(mid 316.374272 -123.644914)
					(end 315.917072 -124.102114)
				)
			)
		)
	)
	(zone
		(layers "F.Cu" "B.Cu" "In1.Cu" "In2.Cu" "In3.Cu" "In4.Cu" "In5.Cu" "In6.Cu"
			"In7.Cu" "In8.Cu" "In9.Cu" "In10.Cu" "In11.Cu" "In12.Cu" "In13.Cu" "In14.Cu"
			"In15.Cu" "In16.Cu"
		)
		(hatch none 0.5)
		(connect_pads
			(clearance 0)
		)
		(min_thickness 0.25)
		(keepout
			(tracks not_allowed)
			(vias allowed)
			(pads allowed)
			(copperpour not_allowed)
			(footprints allowed)
		)
		(placement
			(enabled no)
			(sheetname "")
		)
		(fill
			(thermal_gap 0.5)
			(thermal_bridge_width 0.5)
			(island_removal_mode 0)
		)
		(polygon
			(pts
				(arc
					(start 89.352882 -342.058498)
					(mid 88.971882 -342.439498)
					(end 89.352882 -342.820498)
				)
				(arc
					(start 90.216482 -342.820498)
					(mid 90.597482 -342.439498)
					(end 90.216482 -342.058498)
				)
			)
		)
	)
	(zone
		(layers "F.Cu" "B.Cu" "In1.Cu" "In2.Cu" "In3.Cu" "In4.Cu" "In5.Cu" "In6.Cu"
			"In7.Cu" "In8.Cu" "In9.Cu" "In10.Cu" "In11.Cu" "In12.Cu" "In13.Cu" "In14.Cu"
			"In15.Cu" "In16.Cu"
		)
		(hatch none 0.5)
		(connect_pads
			(clearance 0)
		)
		(min_thickness 0.25)
		(keepout
			(tracks not_allowed)
			(vias allowed)
			(pads allowed)
			(copperpour not_allowed)
			(footprints allowed)
		)
		(placement
			(enabled no)
			(sheetname "")
		)
		(fill
			(thermal_gap 0.5)
			(thermal_bridge_width 0.5)
			(island_removal_mode 0)
		)
		(polygon
			(pts
				(arc
					(start 385.610608 -125.494542)
					(mid 386.067808 -125.951742)
					(end 386.525008 -125.494542)
				)
				(arc
					(start 386.525008 -124.630942)
					(mid 386.067808 -124.173742)
					(end 385.610608 -124.630942)
				)
			)
		)
	)
	(zone
		(layers "F.Cu" "B.Cu" "In1.Cu" "In2.Cu" "In3.Cu" "In4.Cu" "In5.Cu" "In6.Cu"
			"In7.Cu" "In8.Cu" "In9.Cu" "In10.Cu" "In11.Cu" "In12.Cu" "In13.Cu" "In14.Cu"
			"In15.Cu" "In16.Cu"
		)
		(hatch none 0.5)
		(connect_pads
			(clearance 0)
		)
		(min_thickness 0.25)
		(keepout
			(tracks not_allowed)
			(vias allowed)
			(pads allowed)
			(copperpour not_allowed)
			(footprints allowed)
		)
		(placement
			(enabled no)
			(sheetname "")
		)
		(fill
			(thermal_gap 0.5)
			(thermal_bridge_width 0.5)
			(island_removal_mode 0)
		)
		(polygon
			(pts
				(arc
					(start 388.28091 -395.92885)
					(mid 388.295789 -395.892929)
					(end 388.33171 -395.87805)
				)
				(arc
					(start 389.04799 -395.87805)
					(mid 389.083911 -395.892929)
					(end 389.09879 -395.92885)
				)
				(arc
					(start 389.09879 -398.351502)
					(mid 389.083911 -398.387423)
					(end 389.04799 -398.402302)
				)
				(arc
					(start 388.33171 -398.402302)
					(mid 388.295789 -398.387423)
					(end 388.28091 -398.351502)
				)
			)
		)
	)
	(zone
		(layers "F.Cu" "B.Cu" "In1.Cu" "In2.Cu" "In3.Cu" "In4.Cu" "In5.Cu" "In6.Cu"
			"In7.Cu" "In8.Cu" "In9.Cu" "In10.Cu" "In11.Cu" "In12.Cu" "In13.Cu" "In14.Cu"
			"In15.Cu" "In16.Cu"
		)
		(hatch none 0.5)
		(connect_pads
			(clearance 0)
		)
		(min_thickness 0.25)
		(keepout
			(tracks not_allowed)
			(vias allowed)
			(pads allowed)
			(copperpour not_allowed)
			(footprints allowed)
		)
		(placement
			(enabled no)
			(sheetname "")
		)
		(fill
			(thermal_gap 0.5)
			(thermal_bridge_width 0.5)
			(island_removal_mode 0)
		)
		(polygon
			(pts
				(arc
					(start 286.550862 -354.351082)
					(mid 286.169862 -354.732082)
					(end 286.550862 -355.113082)
				)
				(arc
					(start 287.414462 -355.113082)
					(mid 287.795462 -354.732082)
					(end 287.414462 -354.351082)
				)
			)
		)
	)
	(zone
		(layers "F.Cu" "B.Cu" "In1.Cu" "In2.Cu" "In3.Cu" "In4.Cu" "In5.Cu" "In6.Cu"
			"In7.Cu" "In8.Cu" "In9.Cu" "In10.Cu" "In11.Cu" "In12.Cu" "In13.Cu" "In14.Cu"
			"In15.Cu" "In16.Cu"
		)
		(hatch none 0.5)
		(connect_pads
			(clearance 0)
		)
		(min_thickness 0.25)
		(keepout
			(tracks not_allowed)
			(vias allowed)
			(pads allowed)
			(copperpour not_allowed)
			(footprints allowed)
		)
		(placement
			(enabled no)
			(sheetname "")
		)
		(fill
			(thermal_gap 0.5)
			(thermal_bridge_width 0.5)
			(island_removal_mode 0)
		)
		(polygon
			(pts
				(arc
					(start 124.30125 -395.92885)
					(mid 124.316129 -395.892929)
					(end 124.35205 -395.87805)
				)
				(arc
					(start 125.06833 -395.87805)
					(mid 125.104251 -395.892929)
					(end 125.11913 -395.92885)
				)
				(arc
					(start 125.11913 -398.351502)
					(mid 125.104251 -398.387423)
					(end 125.06833 -398.402302)
				)
				(arc
					(start 124.35205 -398.402302)
					(mid 124.316129 -398.387423)
					(end 124.30125 -398.351502)
				)
			)
		)
	)
	(zone
		(layers "F.Cu" "B.Cu" "In1.Cu" "In2.Cu" "In3.Cu" "In4.Cu" "In5.Cu" "In6.Cu"
			"In7.Cu" "In8.Cu" "In9.Cu" "In10.Cu" "In11.Cu" "In12.Cu" "In13.Cu" "In14.Cu"
			"In15.Cu" "In16.Cu"
		)
		(hatch none 0.5)
		(connect_pads
			(clearance 0)
		)
		(min_thickness 0.25)
		(keepout
			(tracks not_allowed)
			(vias allowed)
			(pads allowed)
			(copperpour not_allowed)
			(footprints allowed)
		)
		(placement
			(enabled no)
			(sheetname "")
		)
		(fill
			(thermal_gap 0.5)
			(thermal_bridge_width 0.5)
			(island_removal_mode 0)
		)
		(polygon
			(pts
				(arc
					(start 117.70106 -400.92884)
					(mid 117.715939 -400.892919)
					(end 117.75186 -400.87804)
				)
				(arc
					(start 118.46814 -400.87804)
					(mid 118.504061 -400.892919)
					(end 118.51894 -400.92884)
				)
				(arc
					(start 118.51894 -403.351492)
					(mid 118.504061 -403.387413)
					(end 118.46814 -403.402292)
				)
				(arc
					(start 117.75186 -403.402292)
					(mid 117.715939 -403.387413)
					(end 117.70106 -403.351492)
				)
			)
		)
	)
	(zone
		(layers "F.Cu" "B.Cu" "In1.Cu" "In2.Cu" "In3.Cu" "In4.Cu" "In5.Cu" "In6.Cu"
			"In7.Cu" "In8.Cu" "In9.Cu" "In10.Cu" "In11.Cu" "In12.Cu" "In13.Cu" "In14.Cu"
			"In15.Cu" "In16.Cu"
		)
		(hatch none 0.5)
		(connect_pads
			(clearance 0)
		)
		(min_thickness 0.25)
		(keepout
			(tracks not_allowed)
			(vias allowed)
			(pads allowed)
			(copperpour not_allowed)
			(footprints allowed)
		)
		(placement
			(enabled no)
			(sheetname "")
		)
		(fill
			(thermal_gap 0.5)
			(thermal_bridge_width 0.5)
			(island_removal_mode 0)
		)
		(polygon
			(pts
				(arc
					(start 47.30115 -408.728672)
					(mid 47.316029 -408.692751)
					(end 47.35195 -408.677872)
				)
				(arc
					(start 48.06823 -408.677872)
					(mid 48.104151 -408.692751)
					(end 48.11903 -408.728672)
				)
				(arc
					(start 48.11903 -411.151324)
					(mid 48.104151 -411.187245)
					(end 48.06823 -411.202124)
				)
				(arc
					(start 47.35195 -411.202124)
					(mid 47.316029 -411.187245)
					(end 47.30115 -411.151324)
				)
			)
		)
	)
	(zone
		(layers "F.Cu" "B.Cu" "In1.Cu" "In2.Cu" "In3.Cu" "In4.Cu" "In5.Cu" "In6.Cu"
			"In7.Cu" "In8.Cu" "In9.Cu" "In10.Cu" "In11.Cu" "In12.Cu" "In13.Cu" "In14.Cu"
			"In15.Cu" "In16.Cu"
		)
		(hatch none 0.5)
		(connect_pads
			(clearance 0)
		)
		(min_thickness 0.25)
		(keepout
			(tracks not_allowed)
			(vias allowed)
			(pads allowed)
			(copperpour not_allowed)
			(footprints allowed)
		)
		(placement
			(enabled no)
			(sheetname "")
		)
		(fill
			(thermal_gap 0.5)
			(thermal_bridge_width 0.5)
			(island_removal_mode 0)
		)
		(polygon
			(pts
				(arc
					(start 418.621972 -357.37673)
					(mid 418.240972 -357.75773)
					(end 418.621972 -358.13873)
				)
				(arc
					(start 419.485572 -358.13873)
					(mid 419.866572 -357.75773)
					(end 419.485572 -357.37673)
				)
			)
		)
	)
	(zone
		(layers "F.Cu" "B.Cu" "In1.Cu" "In2.Cu" "In3.Cu" "In4.Cu" "In5.Cu" "In6.Cu"
			"In7.Cu" "In8.Cu" "In9.Cu" "In10.Cu" "In11.Cu" "In12.Cu" "In13.Cu" "In14.Cu"
			"In15.Cu" "In16.Cu"
		)
		(hatch none 0.5)
		(connect_pads
			(clearance 0)
		)
		(min_thickness 0.25)
		(keepout
			(tracks not_allowed)
			(vias allowed)
			(pads allowed)
			(copperpour not_allowed)
			(footprints allowed)
		)
		(placement
			(enabled no)
			(sheetname "")
		)
		(fill
			(thermal_gap 0.5)
			(thermal_bridge_width 0.5)
			(island_removal_mode 0)
		)
		(polygon
			(pts
				(arc
					(start 159.501078 -369.928902)
					(mid 159.515957 -369.892981)
					(end 159.551878 -369.878102)
				)
				(arc
					(start 160.268158 -369.878102)
					(mid 160.304079 -369.892981)
					(end 160.318958 -369.928902)
				)
				(arc
					(start 160.318958 -372.351554)
					(mid 160.304079 -372.387475)
					(end 160.268158 -372.402354)
				)
				(arc
					(start 159.551878 -372.402354)
					(mid 159.515957 -372.387475)
					(end 159.501078 -372.351554)
				)
			)
		)
	)
	(zone
		(layers "F.Cu" "B.Cu" "In1.Cu" "In2.Cu" "In3.Cu" "In4.Cu" "In5.Cu" "In6.Cu"
			"In7.Cu" "In8.Cu" "In9.Cu" "In10.Cu" "In11.Cu" "In12.Cu" "In13.Cu" "In14.Cu"
			"In15.Cu" "In16.Cu"
		)
		(hatch none 0.5)
		(connect_pads
			(clearance 0)
		)
		(min_thickness 0.25)
		(keepout
			(tracks not_allowed)
			(vias allowed)
			(pads allowed)
			(copperpour not_allowed)
			(footprints allowed)
		)
		(placement
			(enabled no)
			(sheetname "")
		)
		(fill
			(thermal_gap 0.5)
			(thermal_bridge_width 0.5)
			(island_removal_mode 0)
		)
		(polygon
			(pts
				(arc
					(start 412.404052 -354.351082)
					(mid 412.023052 -354.732082)
					(end 412.404052 -355.113082)
				)
				(arc
					(start 413.267652 -355.113082)
					(mid 413.648652 -354.732082)
					(end 413.267652 -354.351082)
				)
			)
		)
	)
	(zone
		(layers "F.Cu" "B.Cu" "In1.Cu" "In2.Cu" "In3.Cu" "In4.Cu" "In5.Cu" "In6.Cu"
			"In7.Cu" "In8.Cu" "In9.Cu" "In10.Cu" "In11.Cu" "In12.Cu" "In13.Cu" "In14.Cu"
			"In15.Cu" "In16.Cu"
		)
		(hatch none 0.5)
		(connect_pads
			(clearance 0)
		)
		(min_thickness 0.25)
		(keepout
			(tracks not_allowed)
			(vias allowed)
			(pads allowed)
			(copperpour not_allowed)
			(footprints allowed)
		)
		(placement
			(enabled no)
			(sheetname "")
		)
		(fill
			(thermal_gap 0.5)
			(thermal_bridge_width 0.5)
			(island_removal_mode 0)
		)
		(polygon
			(pts
				(arc
					(start 139.842748 -354.351082)
					(mid 139.461748 -354.732082)
					(end 139.842748 -355.113082)
				)
				(arc
					(start 140.706348 -355.113082)
					(mid 141.087348 -354.732082)
					(end 140.706348 -354.351082)
				)
			)
		)
	)
	(zone
		(layers "F.Cu" "B.Cu" "In1.Cu" "In2.Cu" "In3.Cu" "In4.Cu" "In5.Cu" "In6.Cu"
			"In7.Cu" "In8.Cu" "In9.Cu" "In10.Cu" "In11.Cu" "In12.Cu" "In13.Cu" "In14.Cu"
			"In15.Cu" "In16.Cu"
		)
		(hatch none 0.5)
		(connect_pads
			(clearance 0)
		)
		(min_thickness 0.25)
		(keepout
			(tracks not_allowed)
			(vias allowed)
			(pads allowed)
			(copperpour not_allowed)
			(footprints allowed)
		)
		(placement
			(enabled no)
			(sheetname "")
		)
		(fill
			(thermal_gap 0.5)
			(thermal_bridge_width 0.5)
			(island_removal_mode 0)
		)
		(polygon
			(pts
				(arc
					(start 83.134962 -348.20479)
					(mid 82.753962 -348.58579)
					(end 83.134962 -348.96679)
				)
				(arc
					(start 83.998562 -348.96679)
					(mid 84.379562 -348.58579)
					(end 83.998562 -348.20479)
				)
			)
		)
	)
	(zone
		(layers "F.Cu" "B.Cu" "In1.Cu" "In2.Cu" "In3.Cu" "In4.Cu" "In5.Cu" "In6.Cu"
			"In7.Cu" "In8.Cu" "In9.Cu" "In10.Cu" "In11.Cu" "In12.Cu" "In13.Cu" "In14.Cu"
			"In15.Cu" "In16.Cu"
		)
		(hatch none 0.5)
		(connect_pads
			(clearance 0)
		)
		(min_thickness 0.25)
		(keepout
			(tracks not_allowed)
			(vias allowed)
			(pads allowed)
			(copperpour not_allowed)
			(footprints allowed)
		)
		(placement
			(enabled no)
			(sheetname "")
		)
		(fill
			(thermal_gap 0.5)
			(thermal_bridge_width 0.5)
			(island_removal_mode 0)
		)
		(polygon
			(pts
				(arc
					(start 433.053236 -34.52241)
					(mid 433.510436 -34.97961)
					(end 433.967636 -34.52241)
				)
				(arc
					(start 433.967636 -33.65881)
					(mid 433.510436 -33.20161)
					(end 433.053236 -33.65881)
				)
			)
		)
	)
	(zone
		(layers "F.Cu" "B.Cu" "In1.Cu" "In2.Cu" "In3.Cu" "In4.Cu" "In5.Cu" "In6.Cu"
			"In7.Cu" "In8.Cu" "In9.Cu" "In10.Cu" "In11.Cu" "In12.Cu" "In13.Cu" "In14.Cu"
			"In15.Cu" "In16.Cu"
		)
		(hatch none 0.5)
		(connect_pads
			(clearance 0)
		)
		(min_thickness 0.25)
		(keepout
			(tracks not_allowed)
			(vias allowed)
			(pads allowed)
			(copperpour not_allowed)
			(footprints allowed)
		)
		(placement
			(enabled no)
			(sheetname "")
		)
		(fill
			(thermal_gap 0.5)
			(thermal_bridge_width 0.5)
			(island_removal_mode 0)
		)
		(polygon
			(pts
				(arc
					(start 41.095168 -354.351082)
					(mid 40.714168 -354.732082)
					(end 41.095168 -355.113082)
				)
				(arc
					(start 41.958768 -355.113082)
					(mid 42.339768 -354.732082)
					(end 41.958768 -354.351082)
				)
			)
		)
	)
	(zone
		(layers "F.Cu" "B.Cu" "In1.Cu" "In2.Cu" "In3.Cu" "In4.Cu" "In5.Cu" "In6.Cu"
			"In7.Cu" "In8.Cu" "In9.Cu" "In10.Cu" "In11.Cu" "In12.Cu" "In13.Cu" "In14.Cu"
			"In15.Cu" "In16.Cu"
		)
		(hatch none 0.5)
		(connect_pads
			(clearance 0)
		)
		(min_thickness 0.25)
		(keepout
			(tracks not_allowed)
			(vias allowed)
			(pads allowed)
			(copperpour not_allowed)
			(footprints allowed)
		)
		(placement
			(enabled no)
			(sheetname "")
		)
		(fill
			(thermal_gap 0.5)
			(thermal_bridge_width 0.5)
			(island_removal_mode 0)
		)
		(polygon
			(pts
				(arc
					(start 127.406908 -345.084146)
					(mid 127.025908 -345.465146)
					(end 127.406908 -345.846146)
				)
				(arc
					(start 128.270508 -345.846146)
					(mid 128.651508 -345.465146)
					(end 128.270508 -345.084146)
				)
			)
		)
	)
	(zone
		(layers "F.Cu" "B.Cu" "In1.Cu" "In2.Cu" "In3.Cu" "In4.Cu" "In5.Cu" "In6.Cu"
			"In7.Cu" "In8.Cu" "In9.Cu" "In10.Cu" "In11.Cu" "In12.Cu" "In13.Cu" "In14.Cu"
			"In15.Cu" "In16.Cu"
		)
		(hatch none 0.5)
		(connect_pads
			(clearance 0)
		)
		(min_thickness 0.25)
		(keepout
			(tracks not_allowed)
			(vias allowed)
			(pads allowed)
			(copperpour not_allowed)
			(footprints allowed)
		)
		(placement
			(enabled no)
			(sheetname "")
		)
		(fill
			(thermal_gap 0.5)
			(thermal_bridge_width 0.5)
			(island_removal_mode 0)
		)
		(polygon
			(pts
				(arc
					(start 291.481002 -369.928902)
					(mid 291.495881 -369.892981)
					(end 291.531802 -369.878102)
				)
				(arc
					(start 292.248082 -369.878102)
					(mid 292.284003 -369.892981)
					(end 292.298882 -369.928902)
				)
				(arc
					(start 292.298882 -372.351554)
					(mid 292.284003 -372.387475)
					(end 292.248082 -372.402354)
				)
				(arc
					(start 291.531802 -372.402354)
					(mid 291.495881 -372.387475)
					(end 291.481002 -372.351554)
				)
			)
		)
	)
	(zone
		(layers "F.Cu" "B.Cu" "In1.Cu" "In2.Cu" "In3.Cu" "In4.Cu" "In5.Cu" "In6.Cu"
			"In7.Cu" "In8.Cu" "In9.Cu" "In10.Cu" "In11.Cu" "In12.Cu" "In13.Cu" "In14.Cu"
			"In15.Cu" "In16.Cu"
		)
		(hatch none 0.5)
		(connect_pads
			(clearance 0)
		)
		(min_thickness 0.25)
		(keepout
			(tracks not_allowed)
			(vias allowed)
			(pads allowed)
			(copperpour not_allowed)
			(footprints allowed)
		)
		(placement
			(enabled no)
			(sheetname "")
		)
		(fill
			(thermal_gap 0.5)
			(thermal_bridge_width 0.5)
			(island_removal_mode 0)
		)
		(polygon
			(pts
				(arc
					(start 271.006062 -354.351082)
					(mid 270.625062 -354.732082)
					(end 271.006062 -355.113082)
				)
				(arc
					(start 271.869662 -355.113082)
					(mid 272.250662 -354.732082)
					(end 271.869662 -354.351082)
				)
			)
		)
	)
	(zone
		(layers "F.Cu" "B.Cu" "In1.Cu" "In2.Cu" "In3.Cu" "In4.Cu" "In5.Cu" "In6.Cu"
			"In7.Cu" "In8.Cu" "In9.Cu" "In10.Cu" "In11.Cu" "In12.Cu" "In13.Cu" "In14.Cu"
			"In15.Cu" "In16.Cu"
		)
		(hatch none 0.5)
		(connect_pads
			(clearance 0)
		)
		(min_thickness 0.25)
		(keepout
			(tracks not_allowed)
			(vias allowed)
			(pads allowed)
			(copperpour not_allowed)
			(footprints allowed)
		)
		(placement
			(enabled no)
			(sheetname "")
		)
		(fill
			(thermal_gap 0.5)
			(thermal_bridge_width 0.5)
			(island_removal_mode 0)
		)
		(polygon
			(pts
				(arc
					(start 335.481168 -369.928902)
					(mid 335.496047 -369.892981)
					(end 335.531968 -369.878102)
				)
				(arc
					(start 336.248248 -369.878102)
					(mid 336.284169 -369.892981)
					(end 336.299048 -369.928902)
				)
				(arc
					(start 336.299048 -372.351554)
					(mid 336.284169 -372.387475)
					(end 336.248248 -372.402354)
				)
				(arc
					(start 335.531968 -372.402354)
					(mid 335.496047 -372.387475)
					(end 335.481168 -372.351554)
				)
			)
		)
	)
	(zone
		(layers "F.Cu" "B.Cu" "In1.Cu" "In2.Cu" "In3.Cu" "In4.Cu" "In5.Cu" "In6.Cu"
			"In7.Cu" "In8.Cu" "In9.Cu" "In10.Cu" "In11.Cu" "In12.Cu" "In13.Cu" "In14.Cu"
			"In15.Cu" "In16.Cu"
		)
		(hatch none 0.5)
		(connect_pads
			(clearance 0)
		)
		(min_thickness 0.25)
		(keepout
			(tracks not_allowed)
			(vias allowed)
			(pads allowed)
			(copperpour not_allowed)
			(footprints allowed)
		)
		(placement
			(enabled no)
			(sheetname "")
		)
		(fill
			(thermal_gap 0.5)
			(thermal_bridge_width 0.5)
			(island_removal_mode 0)
		)
		(polygon
			(pts
				(arc
					(start 84.753196 -34.52241)
					(mid 85.210396 -34.97961)
					(end 85.667596 -34.52241)
				)
				(arc
					(start 85.667596 -33.65881)
					(mid 85.210396 -33.20161)
					(end 84.753196 -33.65881)
				)
			)
		)
	)
	(zone
		(layers "F.Cu" "B.Cu" "In1.Cu" "In2.Cu" "In3.Cu" "In4.Cu" "In5.Cu" "In6.Cu"
			"In7.Cu" "In8.Cu" "In9.Cu" "In10.Cu" "In11.Cu" "In12.Cu" "In13.Cu" "In14.Cu"
			"In15.Cu" "In16.Cu"
		)
		(hatch none 0.5)
		(connect_pads
			(clearance 0)
		)
		(min_thickness 0.25)
		(keepout
			(tracks not_allowed)
			(vias allowed)
			(pads allowed)
			(copperpour not_allowed)
			(footprints allowed)
		)
		(placement
			(enabled no)
			(sheetname "")
		)
		(fill
			(thermal_gap 0.5)
			(thermal_bridge_width 0.5)
			(island_removal_mode 0)
		)
		(polygon
			(pts
				(arc
					(start 136.733788 -351.230438)
					(mid 136.352788 -351.611438)
					(end 136.733788 -351.992438)
				)
				(arc
					(start 137.597388 -351.992438)
					(mid 137.978388 -351.611438)
					(end 137.597388 -351.230438)
				)
			)
		)
	)
	(zone
		(layers "F.Cu" "B.Cu" "In1.Cu" "In2.Cu" "In3.Cu" "In4.Cu" "In5.Cu" "In6.Cu"
			"In7.Cu" "In8.Cu" "In9.Cu" "In10.Cu" "In11.Cu" "In12.Cu" "In13.Cu" "In14.Cu"
			"In15.Cu" "In16.Cu"
		)
		(hatch none 0.5)
		(connect_pads
			(clearance 0)
		)
		(min_thickness 0.25)
		(keepout
			(tracks not_allowed)
			(vias allowed)
			(pads allowed)
			(copperpour not_allowed)
			(footprints allowed)
		)
		(placement
			(enabled no)
			(sheetname "")
		)
		(fill
			(thermal_gap 0.5)
			(thermal_bridge_width 0.5)
			(island_removal_mode 0)
		)
		(polygon
			(pts
				(arc
					(start 182.700168 -130.777234)
					(mid 183.157368 -131.234434)
					(end 183.614568 -130.777234)
				)
				(arc
					(start 183.614568 -129.913634)
					(mid 183.157368 -129.456434)
					(end 182.700168 -129.913634)
				)
			)
		)
	)
	(zone
		(layers "F.Cu" "B.Cu" "In1.Cu" "In2.Cu" "In3.Cu" "In4.Cu" "In5.Cu" "In6.Cu"
			"In7.Cu" "In8.Cu" "In9.Cu" "In10.Cu" "In11.Cu" "In12.Cu" "In13.Cu" "In14.Cu"
			"In15.Cu" "In16.Cu"
		)
		(hatch none 0.5)
		(connect_pads
			(clearance 0)
		)
		(min_thickness 0.25)
		(keepout
			(tracks not_allowed)
			(vias allowed)
			(pads allowed)
			(copperpour not_allowed)
			(footprints allowed)
		)
		(placement
			(enabled no)
			(sheetname "")
		)
		(fill
			(thermal_gap 0.5)
			(thermal_bridge_width 0.5)
			(island_removal_mode 0)
		)
		(polygon
			(pts
				(arc
					(start 105.004362 -380.877572)
					(mid 105.461562 -381.334772)
					(end 105.918762 -380.877572)
				)
				(arc
					(start 105.918762 -380.013972)
					(mid 105.461562 -379.556772)
					(end 105.004362 -380.013972)
				)
			)
		)
	)
	(zone
		(layers "F.Cu" "B.Cu" "In1.Cu" "In2.Cu" "In3.Cu" "In4.Cu" "In5.Cu" "In6.Cu"
			"In7.Cu" "In8.Cu" "In9.Cu" "In10.Cu" "In11.Cu" "In12.Cu" "In13.Cu" "In14.Cu"
			"In15.Cu" "In16.Cu"
		)
		(hatch none 0.5)
		(connect_pads
			(clearance 0)
		)
		(min_thickness 0.25)
		(keepout
			(tracks not_allowed)
			(vias allowed)
			(pads allowed)
			(copperpour not_allowed)
			(footprints allowed)
		)
		(placement
			(enabled no)
			(sheetname "")
		)
		(fill
			(thermal_gap 0.5)
			(thermal_bridge_width 0.5)
			(island_removal_mode 0)
		)
		(polygon
			(pts
				(arc
					(start 80.026002 -342.058498)
					(mid 79.645002 -342.439498)
					(end 80.026002 -342.820498)
				)
				(arc
					(start 80.889602 -342.820498)
					(mid 81.270602 -342.439498)
					(end 80.889602 -342.058498)
				)
			)
		)
	)
	(zone
		(layers "F.Cu" "B.Cu" "In1.Cu" "In2.Cu" "In3.Cu" "In4.Cu" "In5.Cu" "In6.Cu"
			"In7.Cu" "In8.Cu" "In9.Cu" "In10.Cu" "In11.Cu" "In12.Cu" "In13.Cu" "In14.Cu"
			"In15.Cu" "In16.Cu"
		)
		(hatch none 0.5)
		(connect_pads
			(clearance 0)
		)
		(min_thickness 0.25)
		(keepout
			(tracks not_allowed)
			(vias allowed)
			(pads allowed)
			(copperpour not_allowed)
			(footprints allowed)
		)
		(placement
			(enabled no)
			(sheetname "")
		)
		(fill
			(thermal_gap 0.5)
			(thermal_bridge_width 0.5)
			(island_removal_mode 0)
		)
		(polygon
			(pts
				(arc
					(start 119.901208 -381.628904)
					(mid 119.916087 -381.592983)
					(end 119.952008 -381.578104)
				)
				(arc
					(start 120.668288 -381.578104)
					(mid 120.704209 -381.592983)
					(end 120.719088 -381.628904)
				)
				(arc
					(start 120.719088 -384.051556)
					(mid 120.704209 -384.087477)
					(end 120.668288 -384.102356)
				)
				(arc
					(start 119.952008 -384.102356)
					(mid 119.916087 -384.087477)
					(end 119.901208 -384.051556)
				)
			)
		)
	)
	(zone
		(layers "F.Cu" "B.Cu" "In1.Cu" "In2.Cu" "In3.Cu" "In4.Cu" "In5.Cu" "In6.Cu"
			"In7.Cu" "In8.Cu" "In9.Cu" "In10.Cu" "In11.Cu" "In12.Cu" "In13.Cu" "In14.Cu"
			"In15.Cu" "In16.Cu"
		)
		(hatch none 0.5)
		(connect_pads
			(clearance 0)
		)
		(min_thickness 0.25)
		(keepout
			(tracks not_allowed)
			(vias allowed)
			(pads allowed)
			(copperpour not_allowed)
			(footprints allowed)
		)
		(placement
			(enabled no)
			(sheetname "")
		)
		(fill
			(thermal_gap 0.5)
			(thermal_bridge_width 0.5)
			(island_removal_mode 0)
		)
		(polygon
			(pts
				(arc
					(start 202.707494 -29.12237)
					(mid 203.164694 -29.57957)
					(end 203.621894 -29.12237)
				)
				(arc
					(start 203.621894 -28.25877)
					(mid 203.164694 -27.80157)
					(end 202.707494 -28.25877)
				)
			)
		)
	)
	(zone
		(layers "F.Cu" "B.Cu" "In1.Cu" "In2.Cu" "In3.Cu" "In4.Cu" "In5.Cu" "In6.Cu"
			"In7.Cu" "In8.Cu" "In9.Cu" "In10.Cu" "In11.Cu" "In12.Cu" "In13.Cu" "In14.Cu"
			"In15.Cu" "In16.Cu"
		)
		(hatch none 0.5)
		(connect_pads
			(clearance 0)
		)
		(min_thickness 0.25)
		(keepout
			(tracks not_allowed)
			(vias allowed)
			(pads allowed)
			(copperpour not_allowed)
			(footprints allowed)
		)
		(placement
			(enabled no)
			(sheetname "")
		)
		(fill
			(thermal_gap 0.5)
			(thermal_bridge_width 0.5)
			(island_removal_mode 0)
		)
		(polygon
			(pts
				(arc
					(start 92.461842 -345.084146)
					(mid 92.080842 -345.465146)
					(end 92.461842 -345.846146)
				)
				(arc
					(start 93.325442 -345.846146)
					(mid 93.706442 -345.465146)
					(end 93.325442 -345.084146)
				)
			)
		)
	)
	(zone
		(layers "F.Cu" "B.Cu" "In1.Cu" "In2.Cu" "In3.Cu" "In4.Cu" "In5.Cu" "In6.Cu"
			"In7.Cu" "In8.Cu" "In9.Cu" "In10.Cu" "In11.Cu" "In12.Cu" "In13.Cu" "In14.Cu"
			"In15.Cu" "In16.Cu"
		)
		(hatch none 0.5)
		(connect_pads
			(clearance 0)
		)
		(min_thickness 0.25)
		(keepout
			(tracks not_allowed)
			(vias allowed)
			(pads allowed)
			(copperpour not_allowed)
			(footprints allowed)
		)
		(placement
			(enabled no)
			(sheetname "")
		)
		(fill
			(thermal_gap 0.5)
			(thermal_bridge_width 0.5)
			(island_removal_mode 0)
		)
		(polygon
			(pts
				(arc
					(start 284.899862 -111.912908)
					(mid 284.442662 -111.455708)
					(end 283.985462 -111.912908)
				)
				(arc
					(start 283.985462 -112.776508)
					(mid 284.442662 -113.233708)
					(end 284.899862 -112.776508)
				)
			)
		)
	)
	(zone
		(layers "F.Cu" "B.Cu" "In1.Cu" "In2.Cu" "In3.Cu" "In4.Cu" "In5.Cu" "In6.Cu"
			"In7.Cu" "In8.Cu" "In9.Cu" "In10.Cu" "In11.Cu" "In12.Cu" "In13.Cu" "In14.Cu"
			"In15.Cu" "In16.Cu"
		)
		(hatch none 0.5)
		(connect_pads
			(clearance 0)
		)
		(min_thickness 0.25)
		(keepout
			(tracks not_allowed)
			(vias allowed)
			(pads allowed)
			(copperpour not_allowed)
			(footprints allowed)
		)
		(placement
			(enabled no)
			(sheetname "")
		)
		(fill
			(thermal_gap 0.5)
			(thermal_bridge_width 0.5)
			(island_removal_mode 0)
		)
		(polygon
			(pts
				(arc
					(start 119.901208 -395.92885)
					(mid 119.916087 -395.892929)
					(end 119.952008 -395.87805)
				)
				(arc
					(start 120.668288 -395.87805)
					(mid 120.704209 -395.892929)
					(end 120.719088 -395.92885)
				)
				(arc
					(start 120.719088 -398.351502)
					(mid 120.704209 -398.387423)
					(end 120.668288 -398.402302)
				)
				(arc
					(start 119.952008 -398.402302)
					(mid 119.916087 -398.387423)
					(end 119.901208 -398.351502)
				)
			)
		)
	)
	(zone
		(layers "F.Cu" "B.Cu" "In1.Cu" "In2.Cu" "In3.Cu" "In4.Cu" "In5.Cu" "In6.Cu"
			"In7.Cu" "In8.Cu" "In9.Cu" "In10.Cu" "In11.Cu" "In12.Cu" "In13.Cu" "In14.Cu"
			"In15.Cu" "In16.Cu"
		)
		(hatch none 0.5)
		(connect_pads
			(clearance 0)
		)
		(min_thickness 0.25)
		(keepout
			(tracks not_allowed)
			(vias allowed)
			(pads allowed)
			(copperpour not_allowed)
			(footprints allowed)
		)
		(placement
			(enabled no)
			(sheetname "")
		)
		(fill
			(thermal_gap 0.5)
			(thermal_bridge_width 0.5)
			(island_removal_mode 0)
		)
		(polygon
			(pts
				(arc
					(start 37.986208 -342.058498)
					(mid 37.605208 -342.439498)
					(end 37.986208 -342.820498)
				)
				(arc
					(start 38.849808 -342.820498)
					(mid 39.230808 -342.439498)
					(end 38.849808 -342.058498)
				)
			)
		)
	)
	(zone
		(layers "F.Cu" "B.Cu" "In1.Cu" "In2.Cu" "In3.Cu" "In4.Cu" "In5.Cu" "In6.Cu"
			"In7.Cu" "In8.Cu" "In9.Cu" "In10.Cu" "In11.Cu" "In12.Cu" "In13.Cu" "In14.Cu"
			"In15.Cu" "In16.Cu"
		)
		(hatch none 0.5)
		(connect_pads
			(clearance 0)
		)
		(min_thickness 0.25)
		(keepout
			(tracks not_allowed)
			(vias allowed)
			(pads allowed)
			(copperpour not_allowed)
			(footprints allowed)
		)
		(placement
			(enabled no)
			(sheetname "")
		)
		(fill
			(thermal_gap 0.5)
			(thermal_bridge_width 0.5)
			(island_removal_mode 0)
		)
		(polygon
			(pts
				(arc
					(start 199.817228 -152.485852)
					(mid 200.274428 -152.943052)
					(end 200.731628 -152.485852)
				)
				(arc
					(start 200.731628 -151.622252)
					(mid 200.274428 -151.165052)
					(end 199.817228 -151.622252)
				)
			)
		)
	)
	(zone
		(layers "F.Cu" "B.Cu" "In1.Cu" "In2.Cu" "In3.Cu" "In4.Cu" "In5.Cu" "In6.Cu"
			"In7.Cu" "In8.Cu" "In9.Cu" "In10.Cu" "In11.Cu" "In12.Cu" "In13.Cu" "In14.Cu"
			"In15.Cu" "In16.Cu"
		)
		(hatch none 0.5)
		(connect_pads
			(clearance 0)
		)
		(min_thickness 0.25)
		(keepout
			(tracks not_allowed)
			(vias allowed)
			(pads allowed)
			(copperpour not_allowed)
			(footprints allowed)
		)
		(placement
			(enabled no)
			(sheetname "")
		)
		(fill
			(thermal_gap 0.5)
			(thermal_bridge_width 0.5)
			(island_removal_mode 0)
		)
		(polygon
			(pts
				(arc
					(start 130.901186 -397.028924)
					(mid 130.916065 -396.993003)
					(end 130.951986 -396.978124)
				)
				(arc
					(start 131.668266 -396.978124)
					(mid 131.704187 -396.993003)
					(end 131.719066 -397.028924)
				)
				(arc
					(start 131.719066 -399.451576)
					(mid 131.704187 -399.487497)
					(end 131.668266 -399.502376)
				)
				(arc
					(start 130.951986 -399.502376)
					(mid 130.916065 -399.487497)
					(end 130.901186 -399.451576)
				)
			)
		)
	)
	(zone
		(layers "F.Cu" "B.Cu" "In1.Cu" "In2.Cu" "In3.Cu" "In4.Cu" "In5.Cu" "In6.Cu"
			"In7.Cu" "In8.Cu" "In9.Cu" "In10.Cu" "In11.Cu" "In12.Cu" "In13.Cu" "In14.Cu"
			"In15.Cu" "In16.Cu"
		)
		(hatch none 0.5)
		(connect_pads
			(clearance 0)
		)
		(min_thickness 0.25)
		(keepout
			(tracks not_allowed)
			(vias allowed)
			(pads allowed)
			(copperpour not_allowed)
			(footprints allowed)
		)
		(placement
			(enabled no)
			(sheetname "")
		)
		(fill
			(thermal_gap 0.5)
			(thermal_bridge_width 0.5)
			(island_removal_mode 0)
		)
		(polygon
			(pts
				(arc
					(start 335.481168 -407.628852)
					(mid 335.496047 -407.592931)
					(end 335.531968 -407.578052)
				)
				(arc
					(start 336.248248 -407.578052)
					(mid 336.284169 -407.592931)
					(end 336.299048 -407.628852)
				)
				(arc
					(start 336.299048 -410.051504)
					(mid 336.284169 -410.087425)
					(end 336.248248 -410.102304)
				)
				(arc
					(start 335.531968 -410.102304)
					(mid 335.496047 -410.087425)
					(end 335.481168 -410.051504)
				)
			)
		)
	)
	(zone
		(layers "F.Cu" "B.Cu" "In1.Cu" "In2.Cu" "In3.Cu" "In4.Cu" "In5.Cu" "In6.Cu"
			"In7.Cu" "In8.Cu" "In9.Cu" "In10.Cu" "In11.Cu" "In12.Cu" "In13.Cu" "In14.Cu"
			"In15.Cu" "In16.Cu"
		)
		(hatch none 0.5)
		(connect_pads
			(clearance 0)
		)
		(min_thickness 0.25)
		(keepout
			(tracks not_allowed)
			(vias allowed)
			(pads allowed)
			(copperpour not_allowed)
			(footprints allowed)
		)
		(placement
			(enabled no)
			(sheetname "")
		)
		(fill
			(thermal_gap 0.5)
			(thermal_bridge_width 0.5)
			(island_removal_mode 0)
		)
		(polygon
			(pts
				(arc
					(start 34.101024 -382.728724)
					(mid 34.115903 -382.692803)
					(end 34.151824 -382.677924)
				)
				(arc
					(start 34.868104 -382.677924)
					(mid 34.904025 -382.692803)
					(end 34.918904 -382.728724)
				)
				(arc
					(start 34.918904 -385.151376)
					(mid 34.904025 -385.187297)
					(end 34.868104 -385.202176)
				)
				(arc
					(start 34.151824 -385.202176)
					(mid 34.115903 -385.187297)
					(end 34.101024 -385.151376)
				)
			)
		)
	)
	(zone
		(layers "F.Cu" "B.Cu" "In1.Cu" "In2.Cu" "In3.Cu" "In4.Cu" "In5.Cu" "In6.Cu"
			"In7.Cu" "In8.Cu" "In9.Cu" "In10.Cu" "In11.Cu" "In12.Cu" "In13.Cu" "In14.Cu"
			"In15.Cu" "In16.Cu"
		)
		(hatch none 0.5)
		(connect_pads
			(clearance 0)
		)
		(min_thickness 0.25)
		(keepout
			(tracks not_allowed)
			(vias allowed)
			(pads allowed)
			(copperpour not_allowed)
			(footprints allowed)
		)
		(placement
			(enabled no)
			(sheetname "")
		)
		(fill
			(thermal_gap 0.5)
			(thermal_bridge_width 0.5)
			(island_removal_mode 0)
		)
		(polygon
			(pts
				(arc
					(start 434.48097 -404.828756)
					(mid 434.495849 -404.792835)
					(end 434.53177 -404.777956)
				)
				(arc
					(start 435.24805 -404.777956)
					(mid 435.283971 -404.792835)
					(end 435.29885 -404.828756)
				)
				(arc
					(start 435.29885 -407.251408)
					(mid 435.283971 -407.287329)
					(end 435.24805 -407.302208)
				)
				(arc
					(start 434.53177 -407.302208)
					(mid 434.495849 -407.287329)
					(end 434.48097 -407.251408)
				)
			)
		)
	)
	(zone
		(layers "F.Cu" "B.Cu" "In1.Cu" "In2.Cu" "In3.Cu" "In4.Cu" "In5.Cu" "In6.Cu"
			"In7.Cu" "In8.Cu" "In9.Cu" "In10.Cu" "In11.Cu" "In12.Cu" "In13.Cu" "In14.Cu"
			"In15.Cu" "In16.Cu"
		)
		(hatch none 0.5)
		(connect_pads
			(clearance 0)
		)
		(min_thickness 0.25)
		(keepout
			(tracks not_allowed)
			(vias allowed)
			(pads allowed)
			(copperpour not_allowed)
			(footprints allowed)
		)
		(placement
			(enabled no)
			(sheetname "")
		)
		(fill
			(thermal_gap 0.5)
			(thermal_bridge_width 0.5)
			(island_removal_mode 0)
		)
		(polygon
			(pts
				(arc
					(start 402.85416 -99.31273)
					(mid 402.39696 -98.85553)
					(end 401.93976 -99.31273)
				)
				(arc
					(start 401.93976 -100.17633)
					(mid 402.39696 -100.63353)
					(end 402.85416 -100.17633)
				)
			)
		)
	)
	(zone
		(layers "F.Cu" "B.Cu" "In1.Cu" "In2.Cu" "In3.Cu" "In4.Cu" "In5.Cu" "In6.Cu"
			"In7.Cu" "In8.Cu" "In9.Cu" "In10.Cu" "In11.Cu" "In12.Cu" "In13.Cu" "In14.Cu"
			"In15.Cu" "In16.Cu"
		)
		(hatch none 0.5)
		(connect_pads
			(clearance 0)
		)
		(min_thickness 0.25)
		(keepout
			(tracks not_allowed)
			(vias allowed)
			(pads allowed)
			(copperpour not_allowed)
			(footprints allowed)
		)
		(placement
			(enabled no)
			(sheetname "")
		)
		(fill
			(thermal_gap 0.5)
			(thermal_bridge_width 0.5)
			(island_removal_mode 0)
		)
		(polygon
			(pts
				(arc
					(start 202.707494 -32.722312)
					(mid 203.164694 -33.179512)
					(end 203.621894 -32.722312)
				)
				(arc
					(start 203.621894 -31.858712)
					(mid 203.164694 -31.401512)
					(end 202.707494 -31.858712)
				)
			)
		)
	)
	(zone
		(layers "F.Cu" "B.Cu" "In1.Cu" "In2.Cu" "In3.Cu" "In4.Cu" "In5.Cu" "In6.Cu"
			"In7.Cu" "In8.Cu" "In9.Cu" "In10.Cu" "In11.Cu" "In12.Cu" "In13.Cu" "In14.Cu"
			"In15.Cu" "In16.Cu"
		)
		(hatch none 0.5)
		(connect_pads
			(clearance 0)
		)
		(min_thickness 0.25)
		(keepout
			(tracks not_allowed)
			(vias allowed)
			(pads allowed)
			(copperpour not_allowed)
			(footprints allowed)
		)
		(placement
			(enabled no)
			(sheetname "")
		)
		(fill
			(thermal_gap 0.5)
			(thermal_bridge_width 0.5)
			(island_removal_mode 0)
		)
		(polygon
			(pts
				(arc
					(start 119.901208 -399.828766)
					(mid 119.916087 -399.792845)
					(end 119.952008 -399.777966)
				)
				(arc
					(start 120.668288 -399.777966)
					(mid 120.704209 -399.792845)
					(end 120.719088 -399.828766)
				)
				(arc
					(start 120.719088 -402.251418)
					(mid 120.704209 -402.287339)
					(end 120.668288 -402.302218)
				)
				(arc
					(start 119.952008 -402.302218)
					(mid 119.916087 -402.287339)
					(end 119.901208 -402.251418)
				)
			)
		)
	)
	(zone
		(layers "F.Cu" "B.Cu" "In1.Cu" "In2.Cu" "In3.Cu" "In4.Cu" "In5.Cu" "In6.Cu"
			"In7.Cu" "In8.Cu" "In9.Cu" "In10.Cu" "In11.Cu" "In12.Cu" "In13.Cu" "In14.Cu"
			"In15.Cu" "In16.Cu"
		)
		(hatch none 0.5)
		(connect_pads
			(clearance 0)
		)
		(min_thickness 0.25)
		(keepout
			(tracks not_allowed)
			(vias allowed)
			(pads allowed)
			(copperpour not_allowed)
			(footprints allowed)
		)
		(placement
			(enabled no)
			(sheetname "")
		)
		(fill
			(thermal_gap 0.5)
			(thermal_bridge_width 0.5)
			(island_removal_mode 0)
		)
		(polygon
			(pts
				(arc
					(start 390.481058 -408.728672)
					(mid 390.495937 -408.692751)
					(end 390.531858 -408.677872)
				)
				(arc
					(start 391.248138 -408.677872)
					(mid 391.284059 -408.692751)
					(end 391.298938 -408.728672)
				)
				(arc
					(start 391.298938 -411.151324)
					(mid 391.284059 -411.187245)
					(end 391.248138 -411.202124)
				)
				(arc
					(start 390.531858 -411.202124)
					(mid 390.495937 -411.187245)
					(end 390.481058 -411.151324)
				)
			)
		)
	)
	(zone
		(layers "F.Cu" "B.Cu" "In1.Cu" "In2.Cu" "In3.Cu" "In4.Cu" "In5.Cu" "In6.Cu"
			"In7.Cu" "In8.Cu" "In9.Cu" "In10.Cu" "In11.Cu" "In12.Cu" "In13.Cu" "In14.Cu"
			"In15.Cu" "In16.Cu"
		)
		(hatch none 0.5)
		(connect_pads
			(clearance 0)
		)
		(min_thickness 0.25)
		(keepout
			(tracks not_allowed)
			(vias allowed)
			(pads allowed)
			(copperpour not_allowed)
			(footprints allowed)
		)
		(placement
			(enabled no)
			(sheetname "")
		)
		(fill
			(thermal_gap 0.5)
			(thermal_bridge_width 0.5)
			(island_removal_mode 0)
		)
		(polygon
			(pts
				(arc
					(start 420.324534 -160.1851)
					(mid 418.190426 -160.1851)
					(end 420.324534 -160.1851)
				)
			)
		)
	)
	(zone
		(layers "F.Cu" "B.Cu" "In1.Cu" "In2.Cu" "In3.Cu" "In4.Cu" "In5.Cu" "In6.Cu"
			"In7.Cu" "In8.Cu" "In9.Cu" "In10.Cu" "In11.Cu" "In12.Cu" "In13.Cu" "In14.Cu"
			"In15.Cu" "In16.Cu"
		)
		(hatch none 0.5)
		(connect_pads
			(clearance 0)
		)
		(min_thickness 0.25)
		(keepout
			(tracks not_allowed)
			(vias allowed)
			(pads allowed)
			(copperpour not_allowed)
			(footprints allowed)
		)
		(placement
			(enabled no)
			(sheetname "")
		)
		(fill
			(thermal_gap 0.5)
			(thermal_bridge_width 0.5)
			(island_removal_mode 0)
		)
		(polygon
			(pts
				(arc
					(start 180.839872 -348.20479)
					(mid 180.458872 -348.58579)
					(end 180.839872 -348.96679)
				)
				(arc
					(start 181.703472 -348.96679)
					(mid 182.084472 -348.58579)
					(end 181.703472 -348.20479)
				)
			)
		)
	)
	(zone
		(layers "F.Cu" "B.Cu" "In1.Cu" "In2.Cu" "In3.Cu" "In4.Cu" "In5.Cu" "In6.Cu"
			"In7.Cu" "In8.Cu" "In9.Cu" "In10.Cu" "In11.Cu" "In12.Cu" "In13.Cu" "In14.Cu"
			"In15.Cu" "In16.Cu"
		)
		(hatch none 0.5)
		(connect_pads
			(clearance 0)
		)
		(min_thickness 0.25)
		(keepout
			(tracks not_allowed)
			(vias allowed)
			(pads allowed)
			(copperpour not_allowed)
			(footprints allowed)
		)
		(placement
			(enabled no)
			(sheetname "")
		)
		(fill
			(thermal_gap 0.5)
			(thermal_bridge_width 0.5)
			(island_removal_mode 0)
		)
		(polygon
			(pts
				(arc
					(start 423.480992 -395.92885)
					(mid 423.495871 -395.892929)
					(end 423.531792 -395.87805)
				)
				(arc
					(start 424.248072 -395.87805)
					(mid 424.283993 -395.892929)
					(end 424.298872 -395.92885)
				)
				(arc
					(start 424.298872 -398.351502)
					(mid 424.283993 -398.387423)
					(end 424.248072 -398.402302)
				)
				(arc
					(start 423.531792 -398.402302)
					(mid 423.495871 -398.387423)
					(end 423.480992 -398.351502)
				)
			)
		)
	)
	(zone
		(layers "F.Cu" "B.Cu" "In1.Cu" "In2.Cu" "In3.Cu" "In4.Cu" "In5.Cu" "In6.Cu"
			"In7.Cu" "In8.Cu" "In9.Cu" "In10.Cu" "In11.Cu" "In12.Cu" "In13.Cu" "In14.Cu"
			"In15.Cu" "In16.Cu"
		)
		(hatch none 0.5)
		(connect_pads
			(clearance 0)
		)
		(min_thickness 0.25)
		(keepout
			(tracks not_allowed)
			(vias allowed)
			(pads allowed)
			(copperpour not_allowed)
			(footprints allowed)
		)
		(placement
			(enabled no)
			(sheetname "")
		)
		(fill
			(thermal_gap 0.5)
			(thermal_bridge_width 0.5)
			(island_removal_mode 0)
		)
		(polygon
			(pts
				(arc
					(start 80.301084 -377.728734)
					(mid 80.315963 -377.692813)
					(end 80.351884 -377.677934)
				)
				(arc
					(start 81.068164 -377.677934)
					(mid 81.104085 -377.692813)
					(end 81.118964 -377.728734)
				)
				(arc
					(start 81.118964 -380.151386)
					(mid 81.104085 -380.187307)
					(end 81.068164 -380.202186)
				)
				(arc
					(start 80.351884 -380.202186)
					(mid 80.315963 -380.187307)
					(end 80.301084 -380.151386)
				)
			)
		)
	)
	(zone
		(layers "F.Cu" "B.Cu" "In1.Cu" "In2.Cu" "In3.Cu" "In4.Cu" "In5.Cu" "In6.Cu"
			"In7.Cu" "In8.Cu" "In9.Cu" "In10.Cu" "In11.Cu" "In12.Cu" "In13.Cu" "In14.Cu"
			"In15.Cu" "In16.Cu"
		)
		(hatch none 0.5)
		(connect_pads
			(clearance 0)
		)
		(min_thickness 0.25)
		(keepout
			(tracks not_allowed)
			(vias allowed)
			(pads allowed)
			(copperpour not_allowed)
			(footprints allowed)
		)
		(placement
			(enabled no)
			(sheetname "")
		)
		(fill
			(thermal_gap 0.5)
			(thermal_bridge_width 0.5)
			(island_removal_mode 0)
		)
		(polygon
			(pts
				(arc
					(start 458.028294 8.607552)
					(mid 457.647294 8.988552)
					(end 457.266294 8.607552)
				)
				(arc
					(start 457.266294 7.743952)
					(mid 457.647294 7.362952)
					(end 458.028294 7.743952)
				)
			)
		)
	)
	(zone
		(layers "F.Cu" "B.Cu" "In1.Cu" "In2.Cu" "In3.Cu" "In4.Cu" "In5.Cu" "In6.Cu"
			"In7.Cu" "In8.Cu" "In9.Cu" "In10.Cu" "In11.Cu" "In12.Cu" "In13.Cu" "In14.Cu"
			"In15.Cu" "In16.Cu"
		)
		(hatch none 0.5)
		(connect_pads
			(clearance 0)
		)
		(min_thickness 0.25)
		(keepout
			(tracks not_allowed)
			(vias allowed)
			(pads allowed)
			(copperpour not_allowed)
			(footprints allowed)
		)
		(placement
			(enabled no)
			(sheetname "")
		)
		(fill
			(thermal_gap 0.5)
			(thermal_bridge_width 0.5)
			(island_removal_mode 0)
		)
		(polygon
			(pts
				(arc
					(start 414.90011 -134.377176)
					(mid 415.35731 -134.834376)
					(end 415.81451 -134.377176)
				)
				(arc
					(start 415.81451 -133.513576)
					(mid 415.35731 -133.056376)
					(end 414.90011 -133.513576)
				)
			)
		)
	)
	(zone
		(layers "F.Cu" "B.Cu" "In1.Cu" "In2.Cu" "In3.Cu" "In4.Cu" "In5.Cu" "In6.Cu"
			"In7.Cu" "In8.Cu" "In9.Cu" "In10.Cu" "In11.Cu" "In12.Cu" "In13.Cu" "In14.Cu"
			"In15.Cu" "In16.Cu"
		)
		(hatch none 0.5)
		(connect_pads
			(clearance 0)
		)
		(min_thickness 0.25)
		(keepout
			(tracks not_allowed)
			(vias allowed)
			(pads allowed)
			(copperpour not_allowed)
			(footprints allowed)
		)
		(placement
			(enabled no)
			(sheetname "")
		)
		(fill
			(thermal_gap 0.5)
			(thermal_bridge_width 0.5)
			(island_removal_mode 0)
		)
		(polygon
			(pts
				(arc
					(start 390.481058 -382.728724)
					(mid 390.495937 -382.692803)
					(end 390.531858 -382.677924)
				)
				(arc
					(start 391.248138 -382.677924)
					(mid 391.284059 -382.692803)
					(end 391.298938 -382.728724)
				)
				(arc
					(start 391.298938 -385.151376)
					(mid 391.284059 -385.187297)
					(end 391.248138 -385.202176)
				)
				(arc
					(start 390.531858 -385.202176)
					(mid 390.495937 -385.187297)
					(end 390.481058 -385.151376)
				)
			)
		)
	)
	(zone
		(layers "F.Cu" "B.Cu" "In1.Cu" "In2.Cu" "In3.Cu" "In4.Cu" "In5.Cu" "In6.Cu"
			"In7.Cu" "In8.Cu" "In9.Cu" "In10.Cu" "In11.Cu" "In12.Cu" "In13.Cu" "In14.Cu"
			"In15.Cu" "In16.Cu"
		)
		(hatch none 0.5)
		(connect_pads
			(clearance 0)
		)
		(min_thickness 0.25)
		(keepout
			(tracks not_allowed)
			(vias allowed)
			(pads allowed)
			(copperpour not_allowed)
			(footprints allowed)
		)
		(placement
			(enabled no)
			(sheetname "")
		)
		(fill
			(thermal_gap 0.5)
			(thermal_bridge_width 0.5)
			(island_removal_mode 0)
		)
		(polygon
			(pts
				(arc
					(start 276.173184 -138.496548)
					(mid 276.630384 -138.953748)
					(end 277.087584 -138.496548)
				)
				(arc
					(start 277.087584 -137.632948)
					(mid 276.630384 -137.175748)
					(end 276.173184 -137.632948)
				)
			)
		)
	)
	(zone
		(layers "F.Cu" "B.Cu" "In1.Cu" "In2.Cu" "In3.Cu" "In4.Cu" "In5.Cu" "In6.Cu"
			"In7.Cu" "In8.Cu" "In9.Cu" "In10.Cu" "In11.Cu" "In12.Cu" "In13.Cu" "In14.Cu"
			"In15.Cu" "In16.Cu"
		)
		(hatch none 0.5)
		(connect_pads
			(clearance 0)
		)
		(min_thickness 0.25)
		(keepout
			(tracks not_allowed)
			(vias allowed)
			(pads allowed)
			(copperpour not_allowed)
			(footprints allowed)
		)
		(placement
			(enabled no)
			(sheetname "")
		)
		(fill
			(thermal_gap 0.5)
			(thermal_bridge_width 0.5)
			(island_removal_mode 0)
		)
		(polygon
			(pts
				(arc
					(start 269.52448 -297.65498)
					(mid 269.85468 -297.32478)
					(end 269.52448 -296.99458)
				)
				(arc
					(start 268.57452 -296.99458)
					(mid 268.24432 -297.32478)
					(end 268.57452 -297.65498)
				)
			)
		)
	)
	(zone
		(layers "F.Cu" "B.Cu" "In1.Cu" "In2.Cu" "In3.Cu" "In4.Cu" "In5.Cu" "In6.Cu"
			"In7.Cu" "In8.Cu" "In9.Cu" "In10.Cu" "In11.Cu" "In12.Cu" "In13.Cu" "In14.Cu"
			"In15.Cu" "In16.Cu"
		)
		(hatch none 0.5)
		(connect_pads
			(clearance 0)
		)
		(min_thickness 0.25)
		(keepout
			(tracks not_allowed)
			(vias allowed)
			(pads allowed)
			(copperpour not_allowed)
			(footprints allowed)
		)
		(placement
			(enabled no)
			(sheetname "")
		)
		(fill
			(thermal_gap 0.5)
			(thermal_bridge_width 0.5)
			(island_removal_mode 0)
		)
		(polygon
			(pts
				(arc
					(start 121.188988 -354.351082)
					(mid 120.807988 -354.732082)
					(end 121.188988 -355.113082)
				)
				(arc
					(start 122.052588 -355.113082)
					(mid 122.433588 -354.732082)
					(end 122.052588 -354.351082)
				)
			)
		)
	)
	(zone
		(layers "F.Cu" "B.Cu" "In1.Cu" "In2.Cu" "In3.Cu" "In4.Cu" "In5.Cu" "In6.Cu"
			"In7.Cu" "In8.Cu" "In9.Cu" "In10.Cu" "In11.Cu" "In12.Cu" "In13.Cu" "In14.Cu"
			"In15.Cu" "In16.Cu"
		)
		(hatch none 0.5)
		(connect_pads
			(clearance 0)
		)
		(min_thickness 0.25)
		(keepout
			(tracks not_allowed)
			(vias allowed)
			(pads allowed)
			(copperpour not_allowed)
			(footprints allowed)
		)
		(placement
			(enabled no)
			(sheetname "")
		)
		(fill
			(thermal_gap 0.5)
			(thermal_bridge_width 0.5)
			(island_removal_mode 0)
		)
		(polygon
			(pts
				(arc
					(start 298.080938 -404.828756)
					(mid 298.095817 -404.792835)
					(end 298.131738 -404.777956)
				)
				(arc
					(start 298.848018 -404.777956)
					(mid 298.883939 -404.792835)
					(end 298.898818 -404.828756)
				)
				(arc
					(start 298.898818 -407.251408)
					(mid 298.883939 -407.287329)
					(end 298.848018 -407.302208)
				)
				(arc
					(start 298.131738 -407.302208)
					(mid 298.095817 -407.287329)
					(end 298.080938 -407.251408)
				)
			)
		)
	)
	(zone
		(layers "F.Cu" "B.Cu" "In1.Cu" "In2.Cu" "In3.Cu" "In4.Cu" "In5.Cu" "In6.Cu"
			"In7.Cu" "In8.Cu" "In9.Cu" "In10.Cu" "In11.Cu" "In12.Cu" "In13.Cu" "In14.Cu"
			"In15.Cu" "In16.Cu"
		)
		(hatch none 0.5)
		(connect_pads
			(clearance 0)
		)
		(min_thickness 0.25)
		(keepout
			(tracks not_allowed)
			(vias allowed)
			(pads allowed)
			(copperpour not_allowed)
			(footprints allowed)
		)
		(placement
			(enabled no)
			(sheetname "")
		)
		(fill
			(thermal_gap 0.5)
			(thermal_bridge_width 0.5)
			(island_removal_mode 0)
		)
		(polygon
			(pts
				(arc
					(start 298.080938 -408.728672)
					(mid 298.095817 -408.692751)
					(end 298.131738 -408.677872)
				)
				(arc
					(start 298.848018 -408.677872)
					(mid 298.883939 -408.692751)
					(end 298.898818 -408.728672)
				)
				(arc
					(start 298.898818 -411.151324)
					(mid 298.883939 -411.187245)
					(end 298.848018 -411.202124)
				)
				(arc
					(start 298.131738 -411.202124)
					(mid 298.095817 -411.187245)
					(end 298.080938 -411.151324)
				)
			)
		)
	)
	(zone
		(layers "F.Cu" "B.Cu" "In1.Cu" "In2.Cu" "In3.Cu" "In4.Cu" "In5.Cu" "In6.Cu"
			"In7.Cu" "In8.Cu" "In9.Cu" "In10.Cu" "In11.Cu" "In12.Cu" "In13.Cu" "In14.Cu"
			"In15.Cu" "In16.Cu"
		)
		(hatch none 0.5)
		(connect_pads
			(clearance 0)
		)
		(min_thickness 0.25)
		(keepout
			(tracks not_allowed)
			(vias allowed)
			(pads allowed)
			(copperpour not_allowed)
			(footprints allowed)
		)
		(placement
			(enabled no)
			(sheetname "")
		)
		(fill
			(thermal_gap 0.5)
			(thermal_bridge_width 0.5)
			(island_removal_mode 0)
		)
		(polygon
			(pts
				(arc
					(start 280.332942 -342.058498)
					(mid 279.951942 -342.439498)
					(end 280.332942 -342.820498)
				)
				(arc
					(start 281.196542 -342.820498)
					(mid 281.577542 -342.439498)
					(end 281.196542 -342.058498)
				)
			)
		)
	)
	(zone
		(layers "F.Cu" "B.Cu" "In1.Cu" "In2.Cu" "In3.Cu" "In4.Cu" "In5.Cu" "In6.Cu"
			"In7.Cu" "In8.Cu" "In9.Cu" "In10.Cu" "In11.Cu" "In12.Cu" "In13.Cu" "In14.Cu"
			"In15.Cu" "In16.Cu"
		)
		(hatch none 0.5)
		(connect_pads
			(clearance 0)
		)
		(min_thickness 0.25)
		(keepout
			(tracks not_allowed)
			(vias allowed)
			(pads allowed)
			(copperpour not_allowed)
			(footprints allowed)
		)
		(placement
			(enabled no)
			(sheetname "")
		)
		(fill
			(thermal_gap 0.5)
			(thermal_bridge_width 0.5)
			(island_removal_mode 0)
		)
		(polygon
			(pts
				(arc
					(start 64.74587 -121.367296)
					(mid 65.20307 -121.824496)
					(end 65.66027 -121.367296)
				)
				(arc
					(start 65.66027 -120.503696)
					(mid 65.20307 -120.046496)
					(end 64.74587 -120.503696)
				)
			)
		)
	)
	(zone
		(layers "F.Cu" "B.Cu" "In1.Cu" "In2.Cu" "In3.Cu" "In4.Cu" "In5.Cu" "In6.Cu"
			"In7.Cu" "In8.Cu" "In9.Cu" "In10.Cu" "In11.Cu" "In12.Cu" "In13.Cu" "In14.Cu"
			"In15.Cu" "In16.Cu"
		)
		(hatch none 0.5)
		(connect_pads
			(clearance 0)
		)
		(min_thickness 0.25)
		(keepout
			(tracks not_allowed)
			(vias allowed)
			(pads allowed)
			(copperpour not_allowed)
			(footprints allowed)
		)
		(placement
			(enabled no)
			(sheetname "")
		)
		(fill
			(thermal_gap 0.5)
			(thermal_bridge_width 0.5)
			(island_removal_mode 0)
		)
		(polygon
			(pts
				(arc
					(start 139.842748 -351.230438)
					(mid 139.461748 -351.611438)
					(end 139.842748 -351.992438)
				)
				(arc
					(start 140.706348 -351.992438)
					(mid 141.087348 -351.611438)
					(end 140.706348 -351.230438)
				)
			)
		)
	)
	(zone
		(layers "F.Cu" "B.Cu" "In1.Cu" "In2.Cu" "In3.Cu" "In4.Cu" "In5.Cu" "In6.Cu"
			"In7.Cu" "In8.Cu" "In9.Cu" "In10.Cu" "In11.Cu" "In12.Cu" "In13.Cu" "In14.Cu"
			"In15.Cu" "In16.Cu"
		)
		(hatch none 0.5)
		(connect_pads
			(clearance 0)
		)
		(min_thickness 0.25)
		(keepout
			(tracks not_allowed)
			(vias allowed)
			(pads allowed)
			(copperpour not_allowed)
			(footprints allowed)
		)
		(placement
			(enabled no)
			(sheetname "")
		)
		(fill
			(thermal_gap 0.5)
			(thermal_bridge_width 0.5)
			(island_removal_mode 0)
		)
		(polygon
			(pts
				(arc
					(start 165.295072 -342.058498)
					(mid 164.914072 -342.439498)
					(end 165.295072 -342.820498)
				)
				(arc
					(start 166.158672 -342.820498)
					(mid 166.539672 -342.439498)
					(end 166.158672 -342.058498)
				)
			)
		)
	)
	(zone
		(layers "F.Cu" "B.Cu" "In1.Cu" "In2.Cu" "In3.Cu" "In4.Cu" "In5.Cu" "In6.Cu"
			"In7.Cu" "In8.Cu" "In9.Cu" "In10.Cu" "In11.Cu" "In12.Cu" "In13.Cu" "In14.Cu"
			"In15.Cu" "In16.Cu"
		)
		(hatch none 0.5)
		(connect_pads
			(clearance 0)
		)
		(min_thickness 0.25)
		(keepout
			(tracks not_allowed)
			(vias allowed)
			(pads allowed)
			(copperpour not_allowed)
			(footprints allowed)
		)
		(placement
			(enabled no)
			(sheetname "")
		)
		(fill
			(thermal_gap 0.5)
			(thermal_bridge_width 0.5)
			(island_removal_mode 0)
		)
		(polygon
			(pts
				(arc
					(start 291.481002 -381.628904)
					(mid 291.495881 -381.592983)
					(end 291.531802 -381.578104)
				)
				(arc
					(start 292.248082 -381.578104)
					(mid 292.284003 -381.592983)
					(end 292.298882 -381.628904)
				)
				(arc
					(start 292.298882 -384.051556)
					(mid 292.284003 -384.087477)
					(end 292.248082 -384.102356)
				)
				(arc
					(start 291.531802 -384.102356)
					(mid 291.495881 -384.087477)
					(end 291.481002 -384.051556)
				)
			)
		)
	)
	(zone
		(layers "F.Cu" "B.Cu" "In1.Cu" "In2.Cu" "In3.Cu" "In4.Cu" "In5.Cu" "In6.Cu"
			"In7.Cu" "In8.Cu" "In9.Cu" "In10.Cu" "In11.Cu" "In12.Cu" "In13.Cu" "In14.Cu"
			"In15.Cu" "In16.Cu"
		)
		(hatch none 0.5)
		(connect_pads
			(clearance 0)
		)
		(min_thickness 0.25)
		(keepout
			(tracks not_allowed)
			(vias allowed)
			(pads allowed)
			(copperpour not_allowed)
			(footprints allowed)
		)
		(placement
			(enabled no)
			(sheetname "")
		)
		(fill
			(thermal_gap 0.5)
			(thermal_bridge_width 0.5)
			(island_removal_mode 0)
		)
		(polygon
			(pts
				(arc
					(start 18.401538 -305.19751)
					(mid 17.639538 -305.19751)
					(end 18.401538 -305.19751)
				)
			)
		)
	)
	(zone
		(layers "F.Cu" "B.Cu" "In1.Cu" "In2.Cu" "In3.Cu" "In4.Cu" "In5.Cu" "In6.Cu"
			"In7.Cu" "In8.Cu" "In9.Cu" "In10.Cu" "In11.Cu" "In12.Cu" "In13.Cu" "In14.Cu"
			"In15.Cu" "In16.Cu"
		)
		(hatch none 0.5)
		(connect_pads
			(clearance 0)
		)
		(min_thickness 0.25)
		(keepout
			(tracks not_allowed)
			(vias allowed)
			(pads allowed)
			(copperpour not_allowed)
			(footprints allowed)
		)
		(placement
			(enabled no)
			(sheetname "")
		)
		(fill
			(thermal_gap 0.5)
			(thermal_bridge_width 0.5)
			(island_removal_mode 0)
		)
		(polygon
			(pts
				(arc
					(start 42.901108 -400.92884)
					(mid 42.915987 -400.892919)
					(end 42.951908 -400.87804)
				)
				(arc
					(start 43.668188 -400.87804)
					(mid 43.704109 -400.892919)
					(end 43.718988 -400.92884)
				)
				(arc
					(start 43.718988 -403.351492)
					(mid 43.704109 -403.387413)
					(end 43.668188 -403.402292)
				)
				(arc
					(start 42.951908 -403.402292)
					(mid 42.915987 -403.387413)
					(end 42.901108 -403.351492)
				)
			)
		)
	)
	(zone
		(layers "F.Cu" "B.Cu" "In1.Cu" "In2.Cu" "In3.Cu" "In4.Cu" "In5.Cu" "In6.Cu"
			"In7.Cu" "In8.Cu" "In9.Cu" "In10.Cu" "In11.Cu" "In12.Cu" "In13.Cu" "In14.Cu"
			"In15.Cu" "In16.Cu"
		)
		(hatch none 0.5)
		(connect_pads
			(clearance 0)
		)
		(min_thickness 0.25)
		(keepout
			(tracks not_allowed)
			(vias allowed)
			(pads allowed)
			(copperpour not_allowed)
			(footprints allowed)
		)
		(placement
			(enabled no)
			(sheetname "")
		)
		(fill
			(thermal_gap 0.5)
			(thermal_bridge_width 0.5)
			(island_removal_mode 0)
		)
		(polygon
			(pts
				(arc
					(start 421.790114 -34.520886)
					(mid 422.247314 -34.978086)
					(end 422.704514 -34.520886)
				)
				(arc
					(start 422.704514 -33.657286)
					(mid 422.247314 -33.200086)
					(end 421.790114 -33.657286)
				)
			)
		)
	)
	(zone
		(layers "F.Cu" "B.Cu" "In1.Cu" "In2.Cu" "In3.Cu" "In4.Cu" "In5.Cu" "In6.Cu"
			"In7.Cu" "In8.Cu" "In9.Cu" "In10.Cu" "In11.Cu" "In12.Cu" "In13.Cu" "In14.Cu"
			"In15.Cu" "In16.Cu"
		)
		(hatch none 0.5)
		(connect_pads
			(clearance 0)
		)
		(min_thickness 0.25)
		(keepout
			(tracks not_allowed)
			(vias allowed)
			(pads allowed)
			(copperpour not_allowed)
			(footprints allowed)
		)
		(placement
			(enabled no)
			(sheetname "")
		)
		(fill
			(thermal_gap 0.5)
			(thermal_bridge_width 0.5)
			(island_removal_mode 0)
		)
		(polygon
			(pts
				(arc
					(start 300.280832 -395.92885)
					(mid 300.295711 -395.892929)
					(end 300.331632 -395.87805)
				)
				(arc
					(start 301.047912 -395.87805)
					(mid 301.083833 -395.892929)
					(end 301.098712 -395.92885)
				)
				(arc
					(start 301.098712 -398.351502)
					(mid 301.083833 -398.387423)
					(end 301.047912 -398.402302)
				)
				(arc
					(start 300.331632 -398.402302)
					(mid 300.295711 -398.387423)
					(end 300.280832 -398.351502)
				)
			)
		)
	)
	(zone
		(layers "F.Cu" "B.Cu" "In1.Cu" "In2.Cu" "In3.Cu" "In4.Cu" "In5.Cu" "In6.Cu"
			"In7.Cu" "In8.Cu" "In9.Cu" "In10.Cu" "In11.Cu" "In12.Cu" "In13.Cu" "In14.Cu"
			"In15.Cu" "In16.Cu"
		)
		(hatch none 0.5)
		(connect_pads
			(clearance 0)
		)
		(min_thickness 0.25)
		(keepout
			(tracks not_allowed)
			(vias allowed)
			(pads allowed)
			(copperpour not_allowed)
			(footprints allowed)
		)
		(placement
			(enabled no)
			(sheetname "")
		)
		(fill
			(thermal_gap 0.5)
			(thermal_bridge_width 0.5)
			(island_removal_mode 0)
		)
		(polygon
			(pts
				(arc
					(start 305.690016 -34.520886)
					(mid 306.147216 -34.978086)
					(end 306.604416 -34.520886)
				)
				(arc
					(start 306.604416 -33.657286)
					(mid 306.147216 -33.200086)
					(end 305.690016 -33.657286)
				)
			)
		)
	)
	(zone
		(layers "F.Cu" "B.Cu" "In1.Cu" "In2.Cu" "In3.Cu" "In4.Cu" "In5.Cu" "In6.Cu"
			"In7.Cu" "In8.Cu" "In9.Cu" "In10.Cu" "In11.Cu" "In12.Cu" "In13.Cu" "In14.Cu"
			"In15.Cu" "In16.Cu"
		)
		(hatch none 0.5)
		(connect_pads
			(clearance 0)
		)
		(min_thickness 0.25)
		(keepout
			(tracks not_allowed)
			(vias allowed)
			(pads allowed)
			(copperpour not_allowed)
			(footprints allowed)
		)
		(placement
			(enabled no)
			(sheetname "")
		)
		(fill
			(thermal_gap 0.5)
			(thermal_bridge_width 0.5)
			(island_removal_mode 0)
		)
		(polygon
			(pts
				(arc
					(start 283.441902 -354.351082)
					(mid 283.060902 -354.732082)
					(end 283.441902 -355.113082)
				)
				(arc
					(start 284.305502 -355.113082)
					(mid 284.686502 -354.732082)
					(end 284.305502 -354.351082)
				)
			)
		)
	)
	(zone
		(layers "F.Cu" "B.Cu" "In1.Cu" "In2.Cu" "In3.Cu" "In4.Cu" "In5.Cu" "In6.Cu"
			"In7.Cu" "In8.Cu" "In9.Cu" "In10.Cu" "In11.Cu" "In12.Cu" "In13.Cu" "In14.Cu"
			"In15.Cu" "In16.Cu"
		)
		(hatch none 0.5)
		(connect_pads
			(clearance 0)
		)
		(min_thickness 0.25)
		(keepout
			(tracks not_allowed)
			(vias allowed)
			(pads allowed)
			(copperpour not_allowed)
			(footprints allowed)
		)
		(placement
			(enabled no)
			(sheetname "")
		)
		(fill
			(thermal_gap 0.5)
			(thermal_bridge_width 0.5)
			(island_removal_mode 0)
		)
		(polygon
			(pts
				(arc
					(start 174.621952 -351.230438)
					(mid 174.240952 -351.611438)
					(end 174.621952 -351.992438)
				)
				(arc
					(start 175.485552 -351.992438)
					(mid 175.866552 -351.611438)
					(end 175.485552 -351.230438)
				)
			)
		)
	)
	(zone
		(layers "F.Cu" "B.Cu" "In1.Cu" "In2.Cu" "In3.Cu" "In4.Cu" "In5.Cu" "In6.Cu"
			"In7.Cu" "In8.Cu" "In9.Cu" "In10.Cu" "In11.Cu" "In12.Cu" "In13.Cu" "In14.Cu"
			"In15.Cu" "In16.Cu"
		)
		(hatch none 0.5)
		(connect_pads
			(clearance 0)
		)
		(min_thickness 0.25)
		(keepout
			(tracks not_allowed)
			(vias allowed)
			(pads allowed)
			(copperpour not_allowed)
			(footprints allowed)
		)
		(placement
			(enabled no)
			(sheetname "")
		)
		(fill
			(thermal_gap 0.5)
			(thermal_bridge_width 0.5)
			(island_removal_mode 0)
		)
		(polygon
			(pts
				(arc
					(start 142.951708 -345.084146)
					(mid 142.570708 -345.465146)
					(end 142.951708 -345.846146)
				)
				(arc
					(start 143.815308 -345.846146)
					(mid 144.196308 -345.465146)
					(end 143.815308 -345.084146)
				)
			)
		)
	)
	(zone
		(layers "F.Cu" "B.Cu" "In1.Cu" "In2.Cu" "In3.Cu" "In4.Cu" "In5.Cu" "In6.Cu"
			"In7.Cu" "In8.Cu" "In9.Cu" "In10.Cu" "In11.Cu" "In12.Cu" "In13.Cu" "In14.Cu"
			"In15.Cu" "In16.Cu"
		)
		(hatch none 0.5)
		(connect_pads
			(clearance 0)
		)
		(min_thickness 0.25)
		(keepout
			(tracks not_allowed)
			(vias allowed)
			(pads allowed)
			(copperpour not_allowed)
			(footprints allowed)
		)
		(placement
			(enabled no)
			(sheetname "")
		)
		(fill
			(thermal_gap 0.5)
			(thermal_bridge_width 0.5)
			(island_removal_mode 0)
		)
		(polygon
			(pts
				(arc
					(start 36.301172 -395.92885)
					(mid 36.316051 -395.892929)
					(end 36.351972 -395.87805)
				)
				(arc
					(start 37.068252 -395.87805)
					(mid 37.104173 -395.892929)
					(end 37.119052 -395.92885)
				)
				(arc
					(start 37.119052 -398.351502)
					(mid 37.104173 -398.387423)
					(end 37.068252 -398.402302)
				)
				(arc
					(start 36.351972 -398.402302)
					(mid 36.316051 -398.387423)
					(end 36.301172 -398.351502)
				)
			)
		)
	)
	(zone
		(layers "F.Cu" "B.Cu" "In1.Cu" "In2.Cu" "In3.Cu" "In4.Cu" "In5.Cu" "In6.Cu"
			"In7.Cu" "In8.Cu" "In9.Cu" "In10.Cu" "In11.Cu" "In12.Cu" "In13.Cu" "In14.Cu"
			"In15.Cu" "In16.Cu"
		)
		(hatch none 0.5)
		(connect_pads
			(clearance 0)
		)
		(min_thickness 0.25)
		(keepout
			(tracks not_allowed)
			(vias allowed)
			(pads allowed)
			(copperpour not_allowed)
			(footprints allowed)
		)
		(placement
			(enabled no)
			(sheetname "")
		)
		(fill
			(thermal_gap 0.5)
			(thermal_bridge_width 0.5)
			(island_removal_mode 0)
		)
		(polygon
			(pts
				(arc
					(start 196.384672 -345.084146)
					(mid 196.003672 -345.465146)
					(end 196.384672 -345.846146)
				)
				(arc
					(start 197.248272 -345.846146)
					(mid 197.629272 -345.465146)
					(end 197.248272 -345.084146)
				)
			)
		)
	)
	(zone
		(layers "F.Cu" "B.Cu" "In1.Cu" "In2.Cu" "In3.Cu" "In4.Cu" "In5.Cu" "In6.Cu"
			"In7.Cu" "In8.Cu" "In9.Cu" "In10.Cu" "In11.Cu" "In12.Cu" "In13.Cu" "In14.Cu"
			"In15.Cu" "In16.Cu"
		)
		(hatch none 0.5)
		(connect_pads
			(clearance 0)
		)
		(min_thickness 0.25)
		(keepout
			(tracks not_allowed)
			(vias allowed)
			(pads allowed)
			(copperpour not_allowed)
			(footprints allowed)
		)
		(placement
			(enabled no)
			(sheetname "")
		)
		(fill
			(thermal_gap 0.5)
			(thermal_bridge_width 0.5)
			(island_removal_mode 0)
		)
		(polygon
			(pts
				(arc
					(start 126.501144 -371.028722)
					(mid 126.516023 -370.992801)
					(end 126.551944 -370.977922)
				)
				(arc
					(start 127.268224 -370.977922)
					(mid 127.304145 -370.992801)
					(end 127.319024 -371.028722)
				)
				(arc
					(start 127.319024 -373.451374)
					(mid 127.304145 -373.487295)
					(end 127.268224 -373.502174)
				)
				(arc
					(start 126.551944 -373.502174)
					(mid 126.516023 -373.487295)
					(end 126.501144 -373.451374)
				)
			)
		)
	)
	(zone
		(layers "F.Cu" "B.Cu" "In1.Cu" "In2.Cu" "In3.Cu" "In4.Cu" "In5.Cu" "In6.Cu"
			"In7.Cu" "In8.Cu" "In9.Cu" "In10.Cu" "In11.Cu" "In12.Cu" "In13.Cu" "In14.Cu"
			"In15.Cu" "In16.Cu"
		)
		(hatch none 0.5)
		(connect_pads
			(clearance 0)
		)
		(min_thickness 0.25)
		(keepout
			(tracks not_allowed)
			(vias allowed)
			(pads allowed)
			(copperpour not_allowed)
			(footprints allowed)
		)
		(placement
			(enabled no)
			(sheetname "")
		)
		(fill
			(thermal_gap 0.5)
			(thermal_bridge_width 0.5)
			(island_removal_mode 0)
		)
		(polygon
			(pts
				(arc
					(start 124.70765 -32.722312)
					(mid 125.16485 -33.179512)
					(end 125.62205 -32.722312)
				)
				(arc
					(start 125.62205 -31.858712)
					(mid 125.16485 -31.401512)
					(end 124.70765 -31.858712)
				)
			)
		)
	)
	(zone
		(layers "F.Cu" "B.Cu" "In1.Cu" "In2.Cu" "In3.Cu" "In4.Cu" "In5.Cu" "In6.Cu"
			"In7.Cu" "In8.Cu" "In9.Cu" "In10.Cu" "In11.Cu" "In12.Cu" "In13.Cu" "In14.Cu"
			"In15.Cu" "In16.Cu"
		)
		(hatch none 0.5)
		(connect_pads
			(clearance 0)
		)
		(min_thickness 0.25)
		(keepout
			(tracks not_allowed)
			(vias allowed)
			(pads allowed)
			(copperpour not_allowed)
			(footprints allowed)
		)
		(placement
			(enabled no)
			(sheetname "")
		)
		(fill
			(thermal_gap 0.5)
			(thermal_bridge_width 0.5)
			(island_removal_mode 0)
		)
		(polygon
			(pts
				(arc
					(start 347.55709 -89.281)
					(mid 347.09989 -88.8238)
					(end 346.64269 -89.281)
				)
				(arc
					(start 346.64269 -90.1446)
					(mid 347.09989 -90.6018)
					(end 347.55709 -90.1446)
				)
			)
		)
	)
	(zone
		(layers "F.Cu" "B.Cu" "In1.Cu" "In2.Cu" "In3.Cu" "In4.Cu" "In5.Cu" "In6.Cu"
			"In7.Cu" "In8.Cu" "In9.Cu" "In10.Cu" "In11.Cu" "In12.Cu" "In13.Cu" "In14.Cu"
			"In15.Cu" "In16.Cu"
		)
		(hatch none 0.5)
		(connect_pads
			(clearance 0)
		)
		(min_thickness 0.25)
		(keepout
			(tracks not_allowed)
			(vias allowed)
			(pads allowed)
			(copperpour not_allowed)
			(footprints allowed)
		)
		(placement
			(enabled no)
			(sheetname "")
		)
		(fill
			(thermal_gap 0.5)
			(thermal_bridge_width 0.5)
			(island_removal_mode 0)
		)
		(polygon
			(pts
				(arc
					(start 86.243922 -351.230438)
					(mid 85.862922 -351.611438)
					(end 86.243922 -351.992438)
				)
				(arc
					(start 87.107522 -351.992438)
					(mid 87.488522 -351.611438)
					(end 87.107522 -351.230438)
				)
			)
		)
	)
	(zone
		(layers "F.Cu" "B.Cu" "In1.Cu" "In2.Cu" "In3.Cu" "In4.Cu" "In5.Cu" "In6.Cu"
			"In7.Cu" "In8.Cu" "In9.Cu" "In10.Cu" "In11.Cu" "In12.Cu" "In13.Cu" "In14.Cu"
			"In15.Cu" "In16.Cu"
		)
		(hatch none 0.5)
		(connect_pads
			(clearance 0)
		)
		(min_thickness 0.25)
		(keepout
			(tracks not_allowed)
			(vias allowed)
			(pads allowed)
			(copperpour not_allowed)
			(footprints allowed)
		)
		(placement
			(enabled no)
			(sheetname "")
		)
		(fill
			(thermal_gap 0.5)
			(thermal_bridge_width 0.5)
			(island_removal_mode 0)
		)
		(polygon
			(pts
				(arc
					(start 199.817228 -121.365772)
					(mid 200.274428 -121.822972)
					(end 200.731628 -121.365772)
				)
				(arc
					(start 200.731628 -120.502172)
					(mid 200.274428 -120.044972)
					(end 199.817228 -120.502172)
				)
			)
		)
	)
	(zone
		(layers "F.Cu" "B.Cu" "In1.Cu" "In2.Cu" "In3.Cu" "In4.Cu" "In5.Cu" "In6.Cu"
			"In7.Cu" "In8.Cu" "In9.Cu" "In10.Cu" "In11.Cu" "In12.Cu" "In13.Cu" "In14.Cu"
			"In15.Cu" "In16.Cu"
		)
		(hatch none 0.5)
		(connect_pads
			(clearance 0)
		)
		(min_thickness 0.25)
		(keepout
			(tracks not_allowed)
			(vias allowed)
			(pads allowed)
			(copperpour not_allowed)
			(footprints allowed)
		)
		(placement
			(enabled no)
			(sheetname "")
		)
		(fill
			(thermal_gap 0.5)
			(thermal_bridge_width 0.5)
			(island_removal_mode 0)
		)
		(polygon
			(pts
				(arc
					(start 335.481168 -377.728734)
					(mid 335.496047 -377.692813)
					(end 335.531968 -377.677934)
				)
				(arc
					(start 336.248248 -377.677934)
					(mid 336.284169 -377.692813)
					(end 336.299048 -377.728734)
				)
				(arc
					(start 336.299048 -380.151386)
					(mid 336.284169 -380.187307)
					(end 336.248248 -380.202186)
				)
				(arc
					(start 335.531968 -380.202186)
					(mid 335.496047 -380.187307)
					(end 335.481168 -380.151386)
				)
			)
		)
	)
	(zone
		(layers "F.Cu" "B.Cu" "In1.Cu" "In2.Cu" "In3.Cu" "In4.Cu" "In5.Cu" "In6.Cu"
			"In7.Cu" "In8.Cu" "In9.Cu" "In10.Cu" "In11.Cu" "In12.Cu" "In13.Cu" "In14.Cu"
			"In15.Cu" "In16.Cu"
		)
		(hatch none 0.5)
		(connect_pads
			(clearance 0)
		)
		(min_thickness 0.25)
		(keepout
			(tracks not_allowed)
			(vias allowed)
			(pads allowed)
			(copperpour not_allowed)
			(footprints allowed)
		)
		(placement
			(enabled no)
			(sheetname "")
		)
		(fill
			(thermal_gap 0.5)
			(thermal_bridge_width 0.5)
			(island_removal_mode 0)
		)
		(polygon
			(pts
				(arc
					(start 287.08096 -407.628852)
					(mid 287.095839 -407.592931)
					(end 287.13176 -407.578052)
				)
				(arc
					(start 287.84804 -407.578052)
					(mid 287.883961 -407.592931)
					(end 287.89884 -407.628852)
				)
				(arc
					(start 287.89884 -410.051504)
					(mid 287.883961 -410.087425)
					(end 287.84804 -410.102304)
				)
				(arc
					(start 287.13176 -410.102304)
					(mid 287.095839 -410.087425)
					(end 287.08096 -410.051504)
				)
			)
		)
	)
	(zone
		(layers "F.Cu" "B.Cu" "In1.Cu" "In2.Cu" "In3.Cu" "In4.Cu" "In5.Cu" "In6.Cu"
			"In7.Cu" "In8.Cu" "In9.Cu" "In10.Cu" "In11.Cu" "In12.Cu" "In13.Cu" "In14.Cu"
			"In15.Cu" "In16.Cu"
		)
		(hatch none 0.5)
		(connect_pads
			(clearance 0)
		)
		(min_thickness 0.25)
		(keepout
			(tracks not_allowed)
			(vias allowed)
			(pads allowed)
			(copperpour not_allowed)
			(footprints allowed)
		)
		(placement
			(enabled no)
			(sheetname "")
		)
		(fill
			(thermal_gap 0.5)
			(thermal_bridge_width 0.5)
			(island_removal_mode 0)
		)
		(polygon
			(pts
				(arc
					(start 274.115022 -345.084146)
					(mid 273.734022 -345.465146)
					(end 274.115022 -345.846146)
				)
				(arc
					(start 274.978622 -345.846146)
					(mid 275.359622 -345.465146)
					(end 274.978622 -345.084146)
				)
			)
		)
	)
	(zone
		(layers "F.Cu" "B.Cu" "In1.Cu" "In2.Cu" "In3.Cu" "In4.Cu" "In5.Cu" "In6.Cu"
			"In7.Cu" "In8.Cu" "In9.Cu" "In10.Cu" "In11.Cu" "In12.Cu" "In13.Cu" "In14.Cu"
			"In15.Cu" "In16.Cu"
		)
		(hatch none 0.5)
		(connect_pads
			(clearance 0)
		)
		(min_thickness 0.25)
		(keepout
			(tracks not_allowed)
			(vias allowed)
			(pads allowed)
			(copperpour not_allowed)
			(footprints allowed)
		)
		(placement
			(enabled no)
			(sheetname "")
		)
		(fill
			(thermal_gap 0.5)
			(thermal_bridge_width 0.5)
			(island_removal_mode 0)
		)
		(polygon
			(pts
				(arc
					(start 182.700168 -143.48714)
					(mid 183.157368 -143.94434)
					(end 183.614568 -143.48714)
				)
				(arc
					(start 183.614568 -142.62354)
					(mid 183.157368 -142.16634)
					(end 182.700168 -142.62354)
				)
			)
		)
	)
	(zone
		(layers "F.Cu" "B.Cu" "In1.Cu" "In2.Cu" "In3.Cu" "In4.Cu" "In5.Cu" "In6.Cu"
			"In7.Cu" "In8.Cu" "In9.Cu" "In10.Cu" "In11.Cu" "In12.Cu" "In13.Cu" "In14.Cu"
			"In15.Cu" "In16.Cu"
		)
		(hatch none 0.5)
		(connect_pads
			(clearance 0)
		)
		(min_thickness 0.25)
		(keepout
			(tracks not_allowed)
			(vias allowed)
			(pads allowed)
			(copperpour not_allowed)
			(footprints allowed)
		)
		(placement
			(enabled no)
			(sheetname "")
		)
		(fill
			(thermal_gap 0.5)
			(thermal_bridge_width 0.5)
			(island_removal_mode 0)
		)
		(polygon
			(pts
				(arc
					(start 117.70106 -371.028722)
					(mid 117.715939 -370.992801)
					(end 117.75186 -370.977922)
				)
				(arc
					(start 118.46814 -370.977922)
					(mid 118.504061 -370.992801)
					(end 118.51894 -371.028722)
				)
				(arc
					(start 118.51894 -373.451374)
					(mid 118.504061 -373.487295)
					(end 118.46814 -373.502174)
				)
				(arc
					(start 117.75186 -373.502174)
					(mid 117.715939 -373.487295)
					(end 117.70106 -373.451374)
				)
			)
		)
	)
	(zone
		(layers "F.Cu" "B.Cu" "In1.Cu" "In2.Cu" "In3.Cu" "In4.Cu" "In5.Cu" "In6.Cu"
			"In7.Cu" "In8.Cu" "In9.Cu" "In10.Cu" "In11.Cu" "In12.Cu" "In13.Cu" "In14.Cu"
			"In15.Cu" "In16.Cu"
		)
		(hatch none 0.5)
		(connect_pads
			(clearance 0)
		)
		(min_thickness 0.25)
		(keepout
			(tracks not_allowed)
			(vias allowed)
			(pads allowed)
			(copperpour not_allowed)
			(footprints allowed)
		)
		(placement
			(enabled no)
			(sheetname "")
		)
		(fill
			(thermal_gap 0.5)
			(thermal_bridge_width 0.5)
			(island_removal_mode 0)
		)
		(polygon
			(pts
				(arc
					(start 31.768288 -351.230438)
					(mid 31.387288 -351.611438)
					(end 31.768288 -351.992438)
				)
				(arc
					(start 32.631888 -351.992438)
					(mid 33.012888 -351.611438)
					(end 32.631888 -351.230438)
				)
			)
		)
	)
	(zone
		(layers "F.Cu" "B.Cu" "In1.Cu" "In2.Cu" "In3.Cu" "In4.Cu" "In5.Cu" "In6.Cu"
			"In7.Cu" "In8.Cu" "In9.Cu" "In10.Cu" "In11.Cu" "In12.Cu" "In13.Cu" "In14.Cu"
			"In15.Cu" "In16.Cu"
		)
		(hatch none 0.5)
		(connect_pads
			(clearance 0)
		)
		(min_thickness 0.25)
		(keepout
			(tracks not_allowed)
			(vias allowed)
			(pads allowed)
			(copperpour not_allowed)
			(footprints allowed)
		)
		(placement
			(enabled no)
			(sheetname "")
		)
		(fill
			(thermal_gap 0.5)
			(thermal_bridge_width 0.5)
			(island_removal_mode 0)
		)
		(polygon
			(pts
				(arc
					(start 122.101102 -397.028924)
					(mid 122.115981 -396.993003)
					(end 122.151902 -396.978124)
				)
				(arc
					(start 122.868182 -396.978124)
					(mid 122.904103 -396.993003)
					(end 122.918982 -397.028924)
				)
				(arc
					(start 122.918982 -399.451576)
					(mid 122.904103 -399.487497)
					(end 122.868182 -399.502376)
				)
				(arc
					(start 122.151902 -399.502376)
					(mid 122.115981 -399.487497)
					(end 122.101102 -399.451576)
				)
			)
		)
	)
	(zone
		(layers "F.Cu" "B.Cu" "In1.Cu" "In2.Cu" "In3.Cu" "In4.Cu" "In5.Cu" "In6.Cu"
			"In7.Cu" "In8.Cu" "In9.Cu" "In10.Cu" "In11.Cu" "In12.Cu" "In13.Cu" "In14.Cu"
			"In15.Cu" "In16.Cu"
		)
		(hatch none 0.5)
		(connect_pads
			(clearance 0)
		)
		(min_thickness 0.25)
		(keepout
			(tracks not_allowed)
			(vias allowed)
			(pads allowed)
			(copperpour not_allowed)
			(footprints allowed)
		)
		(placement
			(enabled no)
			(sheetname "")
		)
		(fill
			(thermal_gap 0.5)
			(thermal_bridge_width 0.5)
			(island_removal_mode 0)
		)
		(polygon
			(pts
				(arc
					(start 117.70106 -408.728672)
					(mid 117.715939 -408.692751)
					(end 117.75186 -408.677872)
				)
				(arc
					(start 118.46814 -408.677872)
					(mid 118.504061 -408.692751)
					(end 118.51894 -408.728672)
				)
				(arc
					(start 118.51894 -411.151324)
					(mid 118.504061 -411.187245)
					(end 118.46814 -411.202124)
				)
				(arc
					(start 117.75186 -411.202124)
					(mid 117.715939 -411.187245)
					(end 117.70106 -411.151324)
				)
			)
		)
	)
	(zone
		(layers "F.Cu" "B.Cu" "In1.Cu" "In2.Cu" "In3.Cu" "In4.Cu" "In5.Cu" "In6.Cu"
			"In7.Cu" "In8.Cu" "In9.Cu" "In10.Cu" "In11.Cu" "In12.Cu" "In13.Cu" "In14.Cu"
			"In15.Cu" "In16.Cu"
		)
		(hatch none 0.5)
		(connect_pads
			(clearance 0)
		)
		(min_thickness 0.25)
		(keepout
			(tracks not_allowed)
			(vias allowed)
			(pads allowed)
			(copperpour not_allowed)
			(footprints allowed)
		)
		(placement
			(enabled no)
			(sheetname "")
		)
		(fill
			(thermal_gap 0.5)
			(thermal_bridge_width 0.5)
			(island_removal_mode 0)
		)
		(polygon
			(pts
				(arc
					(start 396.05966 -345.084146)
					(mid 395.67866 -345.465146)
					(end 396.05966 -345.846146)
				)
				(arc
					(start 396.92326 -345.846146)
					(mid 397.30426 -345.465146)
					(end 396.92326 -345.084146)
				)
			)
		)
	)
	(zone
		(layers "F.Cu" "B.Cu" "In1.Cu" "In2.Cu" "In3.Cu" "In4.Cu" "In5.Cu" "In6.Cu"
			"In7.Cu" "In8.Cu" "In9.Cu" "In10.Cu" "In11.Cu" "In12.Cu" "In13.Cu" "In14.Cu"
			"In15.Cu" "In16.Cu"
		)
		(hatch none 0.5)
		(connect_pads
			(clearance 0)
		)
		(min_thickness 0.25)
		(keepout
			(tracks not_allowed)
			(vias allowed)
			(pads allowed)
			(copperpour not_allowed)
			(footprints allowed)
		)
		(placement
			(enabled no)
			(sheetname "")
		)
		(fill
			(thermal_gap 0.5)
			(thermal_bridge_width 0.5)
			(island_removal_mode 0)
		)
		(polygon
			(pts
				(arc
					(start 47.490126 -30.92069)
					(mid 47.947326 -31.37789)
					(end 48.404526 -30.92069)
				)
				(arc
					(start 48.404526 -30.05709)
					(mid 47.947326 -29.59989)
					(end 47.490126 -30.05709)
				)
			)
		)
	)
	(zone
		(layers "F.Cu" "B.Cu" "In1.Cu" "In2.Cu" "In3.Cu" "In4.Cu" "In5.Cu" "In6.Cu"
			"In7.Cu" "In8.Cu" "In9.Cu" "In10.Cu" "In11.Cu" "In12.Cu" "In13.Cu" "In14.Cu"
			"In15.Cu" "In16.Cu"
		)
		(hatch none 0.5)
		(connect_pads
			(clearance 0)
		)
		(min_thickness 0.25)
		(keepout
			(tracks not_allowed)
			(vias allowed)
			(pads allowed)
			(copperpour not_allowed)
			(footprints allowed)
		)
		(placement
			(enabled no)
			(sheetname "")
		)
		(fill
			(thermal_gap 0.5)
			(thermal_bridge_width 0.5)
			(island_removal_mode 0)
		)
		(polygon
			(pts
				(arc
					(start 86.90102 -400.92884)
					(mid 86.915899 -400.892919)
					(end 86.95182 -400.87804)
				)
				(arc
					(start 87.6681 -400.87804)
					(mid 87.704021 -400.892919)
					(end 87.7189 -400.92884)
				)
				(arc
					(start 87.7189 -403.351492)
					(mid 87.704021 -403.387413)
					(end 87.6681 -403.402292)
				)
				(arc
					(start 86.95182 -403.402292)
					(mid 86.915899 -403.387413)
					(end 86.90102 -403.351492)
				)
			)
		)
	)
	(zone
		(layers "F.Cu" "B.Cu" "In1.Cu" "In2.Cu" "In3.Cu" "In4.Cu" "In5.Cu" "In6.Cu"
			"In7.Cu" "In8.Cu" "In9.Cu" "In10.Cu" "In11.Cu" "In12.Cu" "In13.Cu" "In14.Cu"
			"In15.Cu" "In16.Cu"
		)
		(hatch none 0.5)
		(connect_pads
			(clearance 0)
		)
		(min_thickness 0.25)
		(keepout
			(tracks not_allowed)
			(vias allowed)
			(pads allowed)
			(copperpour not_allowed)
			(footprints allowed)
		)
		(placement
			(enabled no)
			(sheetname "")
		)
		(fill
			(thermal_gap 0.5)
			(thermal_bridge_width 0.5)
			(island_removal_mode 0)
		)
		(polygon
			(pts
				(arc
					(start 34.101024 -378.828554)
					(mid 34.115903 -378.792633)
					(end 34.151824 -378.777754)
				)
				(arc
					(start 34.868104 -378.777754)
					(mid 34.904025 -378.792633)
					(end 34.918904 -378.828554)
				)
				(arc
					(start 34.918904 -381.251206)
					(mid 34.904025 -381.287127)
					(end 34.868104 -381.302006)
				)
				(arc
					(start 34.151824 -381.302006)
					(mid 34.115903 -381.287127)
					(end 34.101024 -381.251206)
				)
			)
		)
	)
	(zone
		(layers "F.Cu" "B.Cu" "In1.Cu" "In2.Cu" "In3.Cu" "In4.Cu" "In5.Cu" "In6.Cu"
			"In7.Cu" "In8.Cu" "In9.Cu" "In10.Cu" "In11.Cu" "In12.Cu" "In13.Cu" "In14.Cu"
			"In15.Cu" "In16.Cu"
		)
		(hatch none 0.5)
		(connect_pads
			(clearance 0)
		)
		(min_thickness 0.25)
		(keepout
			(tracks not_allowed)
			(vias allowed)
			(pads allowed)
			(copperpour not_allowed)
			(footprints allowed)
		)
		(placement
			(enabled no)
			(sheetname "")
		)
		(fill
			(thermal_gap 0.5)
			(thermal_bridge_width 0.5)
			(island_removal_mode 0)
		)
		(polygon
			(pts
				(arc
					(start 115.501166 -381.628904)
					(mid 115.516045 -381.592983)
					(end 115.551966 -381.578104)
				)
				(arc
					(start 116.268246 -381.578104)
					(mid 116.304167 -381.592983)
					(end 116.319046 -381.628904)
				)
				(arc
					(start 116.319046 -384.051556)
					(mid 116.304167 -384.087477)
					(end 116.268246 -384.102356)
				)
				(arc
					(start 115.551966 -384.102356)
					(mid 115.516045 -384.087477)
					(end 115.501166 -384.051556)
				)
			)
		)
	)
	(zone
		(layers "F.Cu" "B.Cu" "In1.Cu" "In2.Cu" "In3.Cu" "In4.Cu" "In5.Cu" "In6.Cu"
			"In7.Cu" "In8.Cu" "In9.Cu" "In10.Cu" "In11.Cu" "In12.Cu" "In13.Cu" "In14.Cu"
			"In15.Cu" "In16.Cu"
		)
		(hatch none 0.5)
		(connect_pads
			(clearance 0)
		)
		(min_thickness 0.25)
		(keepout
			(tracks not_allowed)
			(vias allowed)
			(pads allowed)
			(copperpour not_allowed)
			(footprints allowed)
		)
		(placement
			(enabled no)
			(sheetname "")
		)
		(fill
			(thermal_gap 0.5)
			(thermal_bridge_width 0.5)
			(island_removal_mode 0)
		)
		(polygon
			(pts
				(arc
					(start 333.28102 -374.928638)
					(mid 333.295899 -374.892717)
					(end 333.33182 -374.877838)
				)
				(arc
					(start 334.0481 -374.877838)
					(mid 334.084021 -374.892717)
					(end 334.0989 -374.928638)
				)
				(arc
					(start 334.0989 -377.35129)
					(mid 334.084021 -377.387211)
					(end 334.0481 -377.40209)
				)
				(arc
					(start 333.33182 -377.40209)
					(mid 333.295899 -377.387211)
					(end 333.28102 -377.35129)
				)
			)
		)
	)
	(zone
		(layers "F.Cu" "B.Cu" "In1.Cu" "In2.Cu" "In3.Cu" "In4.Cu" "In5.Cu" "In6.Cu"
			"In7.Cu" "In8.Cu" "In9.Cu" "In10.Cu" "In11.Cu" "In12.Cu" "In13.Cu" "In14.Cu"
			"In15.Cu" "In16.Cu"
		)
		(hatch none 0.5)
		(connect_pads
			(clearance 0)
		)
		(min_thickness 0.25)
		(keepout
			(tracks not_allowed)
			(vias allowed)
			(pads allowed)
			(copperpour not_allowed)
			(footprints allowed)
		)
		(placement
			(enabled no)
			(sheetname "")
		)
		(fill
			(thermal_gap 0.5)
			(thermal_bridge_width 0.5)
			(island_removal_mode 0)
		)
		(polygon
			(pts
				(arc
					(start 83.71713 -152.485852)
					(mid 84.17433 -152.943052)
					(end 84.63153 -152.485852)
				)
				(arc
					(start 84.63153 -151.622252)
					(mid 84.17433 -151.165052)
					(end 83.71713 -151.622252)
				)
			)
		)
	)
	(zone
		(layers "F.Cu" "B.Cu" "In1.Cu" "In2.Cu" "In3.Cu" "In4.Cu" "In5.Cu" "In6.Cu"
			"In7.Cu" "In8.Cu" "In9.Cu" "In10.Cu" "In11.Cu" "In12.Cu" "In13.Cu" "In14.Cu"
			"In15.Cu" "In16.Cu"
		)
		(hatch none 0.5)
		(connect_pads
			(clearance 0)
		)
		(min_thickness 0.25)
		(keepout
			(tracks not_allowed)
			(vias allowed)
			(pads allowed)
			(copperpour not_allowed)
			(footprints allowed)
		)
		(placement
			(enabled no)
			(sheetname "")
		)
		(fill
			(thermal_gap 0.5)
			(thermal_bridge_width 0.5)
			(island_removal_mode 0)
		)
		(polygon
			(pts
				(arc
					(start 386.081016 -400.92884)
					(mid 386.095895 -400.892919)
					(end 386.131816 -400.87804)
				)
				(arc
					(start 386.848096 -400.87804)
					(mid 386.884017 -400.892919)
					(end 386.898896 -400.92884)
				)
				(arc
					(start 386.898896 -403.351492)
					(mid 386.884017 -403.387413)
					(end 386.848096 -403.402292)
				)
				(arc
					(start 386.131816 -403.402292)
					(mid 386.095895 -403.387413)
					(end 386.081016 -403.351492)
				)
			)
		)
	)
	(zone
		(layers "F.Cu" "B.Cu" "In1.Cu" "In2.Cu" "In3.Cu" "In4.Cu" "In5.Cu" "In6.Cu"
			"In7.Cu" "In8.Cu" "In9.Cu" "In10.Cu" "In11.Cu" "In12.Cu" "In13.Cu" "In14.Cu"
			"In15.Cu" "In16.Cu"
		)
		(hatch none 0.5)
		(connect_pads
			(clearance 0)
		)
		(min_thickness 0.25)
		(keepout
			(tracks not_allowed)
			(vias allowed)
			(pads allowed)
			(copperpour not_allowed)
			(footprints allowed)
		)
		(placement
			(enabled no)
			(sheetname "")
		)
		(fill
			(thermal_gap 0.5)
			(thermal_bridge_width 0.5)
			(island_removal_mode 0)
		)
		(polygon
			(pts
				(arc
					(start 293.680896 -404.828756)
					(mid 293.695775 -404.792835)
					(end 293.731696 -404.777956)
				)
				(arc
					(start 294.447976 -404.777956)
					(mid 294.483897 -404.792835)
					(end 294.498776 -404.828756)
				)
				(arc
					(start 294.498776 -407.251408)
					(mid 294.483897 -407.287329)
					(end 294.447976 -407.302208)
				)
				(arc
					(start 293.731696 -407.302208)
					(mid 293.695775 -407.287329)
					(end 293.680896 -407.251408)
				)
			)
		)
	)
	(zone
		(layers "F.Cu" "B.Cu" "In1.Cu" "In2.Cu" "In3.Cu" "In4.Cu" "In5.Cu" "In6.Cu"
			"In7.Cu" "In8.Cu" "In9.Cu" "In10.Cu" "In11.Cu" "In12.Cu" "In13.Cu" "In14.Cu"
			"In15.Cu" "In16.Cu"
		)
		(hatch none 0.5)
		(connect_pads
			(clearance 0)
		)
		(min_thickness 0.25)
		(keepout
			(tracks not_allowed)
			(vias allowed)
			(pads allowed)
			(copperpour not_allowed)
			(footprints allowed)
		)
		(placement
			(enabled no)
			(sheetname "")
		)
		(fill
			(thermal_gap 0.5)
			(thermal_bridge_width 0.5)
			(island_removal_mode 0)
		)
		(polygon
			(pts
				(arc
					(start 277.04796 -29.114242)
					(mid 277.50516 -29.571442)
					(end 277.96236 -29.114242)
				)
				(arc
					(start 277.96236 -28.250642)
					(mid 277.50516 -27.793442)
					(end 277.04796 -28.250642)
				)
			)
		)
	)
	(zone
		(layers "F.Cu" "B.Cu" "In1.Cu" "In2.Cu" "In3.Cu" "In4.Cu" "In5.Cu" "In6.Cu"
			"In7.Cu" "In8.Cu" "In9.Cu" "In10.Cu" "In11.Cu" "In12.Cu" "In13.Cu" "In14.Cu"
			"In15.Cu" "In16.Cu"
		)
		(hatch none 0.5)
		(connect_pads
			(clearance 0)
		)
		(min_thickness 0.25)
		(keepout
			(tracks not_allowed)
			(vias allowed)
			(pads allowed)
			(copperpour not_allowed)
			(footprints allowed)
		)
		(placement
			(enabled no)
			(sheetname "")
		)
		(fill
			(thermal_gap 0.5)
			(thermal_bridge_width 0.5)
			(island_removal_mode 0)
		)
		(polygon
			(pts
				(arc
					(start 34.66846 -134.897876)
					(mid 35.12566 -135.355076)
					(end 35.58286 -134.897876)
				)
				(arc
					(start 35.58286 -134.034276)
					(mid 35.12566 -133.577076)
					(end 34.66846 -134.034276)
				)
			)
		)
	)
	(zone
		(layers "F.Cu" "B.Cu" "In1.Cu" "In2.Cu" "In3.Cu" "In4.Cu" "In5.Cu" "In6.Cu"
			"In7.Cu" "In8.Cu" "In9.Cu" "In10.Cu" "In11.Cu" "In12.Cu" "In13.Cu" "In14.Cu"
			"In15.Cu" "In16.Cu"
		)
		(hatch none 0.5)
		(connect_pads
			(clearance 0)
		)
		(min_thickness 0.25)
		(keepout
			(tracks not_allowed)
			(vias allowed)
			(pads allowed)
			(copperpour not_allowed)
			(footprints allowed)
		)
		(placement
			(enabled no)
			(sheetname "")
		)
		(fill
			(thermal_gap 0.5)
			(thermal_bridge_width 0.5)
			(island_removal_mode 0)
		)
		(polygon
			(pts
				(arc
					(start 153.424636 -297.65498)
					(mid 153.754836 -297.32478)
					(end 153.424636 -296.99458)
				)
				(arc
					(start 152.474676 -296.99458)
					(mid 152.144476 -297.32478)
					(end 152.474676 -297.65498)
				)
			)
		)
	)
	(zone
		(layers "F.Cu" "B.Cu" "In1.Cu" "In2.Cu" "In3.Cu" "In4.Cu" "In5.Cu" "In6.Cu"
			"In7.Cu" "In8.Cu" "In9.Cu" "In10.Cu" "In11.Cu" "In12.Cu" "In13.Cu" "In14.Cu"
			"In15.Cu" "In16.Cu"
		)
		(hatch none 0.5)
		(connect_pads
			(clearance 0)
		)
		(min_thickness 0.25)
		(keepout
			(tracks not_allowed)
			(vias allowed)
			(pads allowed)
			(copperpour not_allowed)
			(footprints allowed)
		)
		(placement
			(enabled no)
			(sheetname "")
		)
		(fill
			(thermal_gap 0.5)
			(thermal_bridge_width 0.5)
			(island_removal_mode 0)
		)
		(polygon
			(pts
				(arc
					(start 80.026002 -354.351082)
					(mid 79.645002 -354.732082)
					(end 80.026002 -355.113082)
				)
				(arc
					(start 80.889602 -355.113082)
					(mid 81.270602 -354.732082)
					(end 80.889602 -354.351082)
				)
			)
		)
	)
	(zone
		(layers "F.Cu" "B.Cu" "In1.Cu" "In2.Cu" "In3.Cu" "In4.Cu" "In5.Cu" "In6.Cu"
			"In7.Cu" "In8.Cu" "In9.Cu" "In10.Cu" "In11.Cu" "In12.Cu" "In13.Cu" "In14.Cu"
			"In15.Cu" "In16.Cu"
		)
		(hatch none 0.5)
		(connect_pads
			(clearance 0)
		)
		(min_thickness 0.25)
		(keepout
			(tracks not_allowed)
			(vias allowed)
			(pads allowed)
			(copperpour not_allowed)
			(footprints allowed)
		)
		(placement
			(enabled no)
			(sheetname "")
		)
		(fill
			(thermal_gap 0.5)
			(thermal_bridge_width 0.5)
			(island_removal_mode 0)
		)
		(polygon
			(pts
				(arc
					(start 172.70095 -403.728682)
					(mid 172.715829 -403.692761)
					(end 172.75175 -403.677882)
				)
				(arc
					(start 173.46803 -403.677882)
					(mid 173.503951 -403.692761)
					(end 173.51883 -403.728682)
				)
				(arc
					(start 173.51883 -406.151334)
					(mid 173.503951 -406.187255)
					(end 173.46803 -406.202134)
				)
				(arc
					(start 172.75175 -406.202134)
					(mid 172.715829 -406.187255)
					(end 172.70095 -406.151334)
				)
			)
		)
	)
	(zone
		(layers "F.Cu" "B.Cu" "In1.Cu" "In2.Cu" "In3.Cu" "In4.Cu" "In5.Cu" "In6.Cu"
			"In7.Cu" "In8.Cu" "In9.Cu" "In10.Cu" "In11.Cu" "In12.Cu" "In13.Cu" "In14.Cu"
			"In15.Cu" "In16.Cu"
		)
		(hatch none 0.5)
		(connect_pads
			(clearance 0)
		)
		(min_thickness 0.25)
		(keepout
			(tracks not_allowed)
			(vias allowed)
			(pads allowed)
			(copperpour not_allowed)
			(footprints allowed)
		)
		(placement
			(enabled no)
			(sheetname "")
		)
		(fill
			(thermal_gap 0.5)
			(thermal_bridge_width 0.5)
			(island_removal_mode 0)
		)
		(polygon
			(pts
				(arc
					(start 31.768288 -345.084146)
					(mid 31.387288 -345.465146)
					(end 31.768288 -345.846146)
				)
				(arc
					(start 32.631888 -345.846146)
					(mid 33.012888 -345.465146)
					(end 32.631888 -345.084146)
				)
			)
		)
	)
	(zone
		(layers "F.Cu" "B.Cu" "In1.Cu" "In2.Cu" "In3.Cu" "In4.Cu" "In5.Cu" "In6.Cu"
			"In7.Cu" "In8.Cu" "In9.Cu" "In10.Cu" "In11.Cu" "In12.Cu" "In13.Cu" "In14.Cu"
			"In15.Cu" "In16.Cu"
		)
		(hatch none 0.5)
		(connect_pads
			(clearance 0)
		)
		(min_thickness 0.25)
		(keepout
			(tracks not_allowed)
			(vias allowed)
			(pads allowed)
			(copperpour not_allowed)
			(footprints allowed)
		)
		(placement
			(enabled no)
			(sheetname "")
		)
		(fill
			(thermal_gap 0.5)
			(thermal_bridge_width 0.5)
			(island_removal_mode 0)
		)
		(polygon
			(pts
				(arc
					(start 130.515868 -342.058498)
					(mid 130.134868 -342.439498)
					(end 130.515868 -342.820498)
				)
				(arc
					(start 131.379468 -342.820498)
					(mid 131.760468 -342.439498)
					(end 131.379468 -342.058498)
				)
			)
		)
	)
	(zone
		(layers "F.Cu" "B.Cu" "In1.Cu" "In2.Cu" "In3.Cu" "In4.Cu" "In5.Cu" "In6.Cu"
			"In7.Cu" "In8.Cu" "In9.Cu" "In10.Cu" "In11.Cu" "In12.Cu" "In13.Cu" "In14.Cu"
			"In15.Cu" "In16.Cu"
		)
		(hatch none 0.5)
		(connect_pads
			(clearance 0)
		)
		(min_thickness 0.25)
		(keepout
			(tracks not_allowed)
			(vias allowed)
			(pads allowed)
			(copperpour not_allowed)
			(footprints allowed)
		)
		(placement
			(enabled no)
			(sheetname "")
		)
		(fill
			(thermal_gap 0.5)
			(thermal_bridge_width 0.5)
			(island_removal_mode 0)
		)
		(polygon
			(pts
				(arc
					(start 437.275732 -351.230438)
					(mid 436.894732 -351.611438)
					(end 437.275732 -351.992438)
				)
				(arc
					(start 438.139332 -351.992438)
					(mid 438.520332 -351.611438)
					(end 438.139332 -351.230438)
				)
			)
		)
	)
	(zone
		(layers "F.Cu" "B.Cu" "In1.Cu" "In2.Cu" "In3.Cu" "In4.Cu" "In5.Cu" "In6.Cu"
			"In7.Cu" "In8.Cu" "In9.Cu" "In10.Cu" "In11.Cu" "In12.Cu" "In13.Cu" "In14.Cu"
			"In15.Cu" "In16.Cu"
		)
		(hatch none 0.5)
		(connect_pads
			(clearance 0)
		)
		(min_thickness 0.25)
		(keepout
			(tracks not_allowed)
			(vias allowed)
			(pads allowed)
			(copperpour not_allowed)
			(footprints allowed)
		)
		(placement
			(enabled no)
			(sheetname "")
		)
		(fill
			(thermal_gap 0.5)
			(thermal_bridge_width 0.5)
			(island_removal_mode 0)
		)
		(polygon
			(pts
				(arc
					(start 421.790114 -30.92069)
					(mid 422.247314 -31.37789)
					(end 422.704514 -30.92069)
				)
				(arc
					(start 422.704514 -30.05709)
					(mid 422.247314 -29.59989)
					(end 421.790114 -30.05709)
				)
			)
		)
	)
	(zone
		(layers "F.Cu" "B.Cu" "In1.Cu" "In2.Cu" "In3.Cu" "In4.Cu" "In5.Cu" "In6.Cu"
			"In7.Cu" "In8.Cu" "In9.Cu" "In10.Cu" "In11.Cu" "In12.Cu" "In13.Cu" "In14.Cu"
			"In15.Cu" "In16.Cu"
		)
		(hatch none 0.5)
		(connect_pads
			(clearance 0)
		)
		(min_thickness 0.25)
		(keepout
			(tracks not_allowed)
			(vias allowed)
			(pads allowed)
			(copperpour not_allowed)
			(footprints allowed)
		)
		(placement
			(enabled no)
			(sheetname "")
		)
		(fill
			(thermal_gap 0.5)
			(thermal_bridge_width 0.5)
			(island_removal_mode 0)
		)
		(polygon
			(pts
				(arc
					(start 388.28091 -373.828818)
					(mid 388.295789 -373.792897)
					(end 388.33171 -373.778018)
				)
				(arc
					(start 389.04799 -373.778018)
					(mid 389.083911 -373.792897)
					(end 389.09879 -373.828818)
				)
				(arc
					(start 389.09879 -376.25147)
					(mid 389.083911 -376.287391)
					(end 389.04799 -376.30227)
				)
				(arc
					(start 388.33171 -376.30227)
					(mid 388.295789 -376.287391)
					(end 388.28091 -376.25147)
				)
			)
		)
	)
	(zone
		(layers "F.Cu" "B.Cu" "In1.Cu" "In2.Cu" "In3.Cu" "In4.Cu" "In5.Cu" "In6.Cu"
			"In7.Cu" "In8.Cu" "In9.Cu" "In10.Cu" "In11.Cu" "In12.Cu" "In13.Cu" "In14.Cu"
			"In15.Cu" "In16.Cu"
		)
		(hatch none 0.5)
		(connect_pads
			(clearance 0)
		)
		(min_thickness 0.25)
		(keepout
			(tracks not_allowed)
			(vias allowed)
			(pads allowed)
			(copperpour not_allowed)
			(footprints allowed)
		)
		(placement
			(enabled no)
			(sheetname "")
		)
		(fill
			(thermal_gap 0.5)
			(thermal_bridge_width 0.5)
			(island_removal_mode 0)
		)
		(polygon
			(pts
				(arc
					(start 80.301084 -373.828818)
					(mid 80.315963 -373.792897)
					(end 80.351884 -373.778018)
				)
				(arc
					(start 81.068164 -373.778018)
					(mid 81.104085 -373.792897)
					(end 81.118964 -373.828818)
				)
				(arc
					(start 81.118964 -376.25147)
					(mid 81.104085 -376.287391)
					(end 81.068164 -376.30227)
				)
				(arc
					(start 80.351884 -376.30227)
					(mid 80.315963 -376.287391)
					(end 80.301084 -376.25147)
				)
			)
		)
	)
	(zone
		(layers "F.Cu" "B.Cu" "In1.Cu" "In2.Cu" "In3.Cu" "In4.Cu" "In5.Cu" "In6.Cu"
			"In7.Cu" "In8.Cu" "In9.Cu" "In10.Cu" "In11.Cu" "In12.Cu" "In13.Cu" "In14.Cu"
			"In15.Cu" "In16.Cu"
		)
		(hatch none 0.5)
		(connect_pads
			(clearance 0)
		)
		(min_thickness 0.25)
		(keepout
			(tracks not_allowed)
			(vias allowed)
			(pads allowed)
			(copperpour not_allowed)
			(footprints allowed)
		)
		(placement
			(enabled no)
			(sheetname "")
		)
		(fill
			(thermal_gap 0.5)
			(thermal_bridge_width 0.5)
			(island_removal_mode 0)
		)
		(polygon
			(pts
				(arc
					(start 100.448618 -385.583938)
					(mid 100.905818 -386.041138)
					(end 101.363018 -385.583938)
				)
				(arc
					(start 101.363018 -384.720338)
					(mid 100.905818 -384.263138)
					(end 100.448618 -384.720338)
				)
			)
		)
	)
	(zone
		(layers "F.Cu" "B.Cu" "In1.Cu" "In2.Cu" "In3.Cu" "In4.Cu" "In5.Cu" "In6.Cu"
			"In7.Cu" "In8.Cu" "In9.Cu" "In10.Cu" "In11.Cu" "In12.Cu" "In13.Cu" "In14.Cu"
			"In15.Cu" "In16.Cu"
		)
		(hatch none 0.5)
		(connect_pads
			(clearance 0)
		)
		(min_thickness 0.25)
		(keepout
			(tracks not_allowed)
			(vias allowed)
			(pads allowed)
			(copperpour not_allowed)
			(footprints allowed)
		)
		(placement
			(enabled no)
			(sheetname "")
		)
		(fill
			(thermal_gap 0.5)
			(thermal_bridge_width 0.5)
			(island_removal_mode 0)
		)
		(polygon
			(pts
				(arc
					(start 43.973242 -138.496548)
					(mid 44.430442 -138.953748)
					(end 44.887642 -138.496548)
				)
				(arc
					(start 44.887642 -137.632948)
					(mid 44.430442 -137.175748)
					(end 43.973242 -137.632948)
				)
			)
		)
	)
	(zone
		(layers "F.Cu" "B.Cu" "In1.Cu" "In2.Cu" "In3.Cu" "In4.Cu" "In5.Cu" "In6.Cu"
			"In7.Cu" "In8.Cu" "In9.Cu" "In10.Cu" "In11.Cu" "In12.Cu" "In13.Cu" "In14.Cu"
			"In15.Cu" "In16.Cu"
		)
		(hatch none 0.5)
		(connect_pads
			(clearance 0)
		)
		(min_thickness 0.25)
		(keepout
			(tracks not_allowed)
			(vias allowed)
			(pads allowed)
			(copperpour not_allowed)
			(footprints allowed)
		)
		(placement
			(enabled no)
			(sheetname "")
		)
		(fill
			(thermal_gap 0.5)
			(thermal_bridge_width 0.5)
			(island_removal_mode 0)
		)
		(polygon
			(pts
				(arc
					(start 139.842748 -357.37673)
					(mid 139.461748 -357.75773)
					(end 139.842748 -358.13873)
				)
				(arc
					(start 140.706348 -358.13873)
					(mid 141.087348 -357.75773)
					(end 140.706348 -357.37673)
				)
			)
		)
	)
	(zone
		(layers "F.Cu" "B.Cu" "In1.Cu" "In2.Cu" "In3.Cu" "In4.Cu" "In5.Cu" "In6.Cu"
			"In7.Cu" "In8.Cu" "In9.Cu" "In10.Cu" "In11.Cu" "In12.Cu" "In13.Cu" "In14.Cu"
			"In15.Cu" "In16.Cu"
		)
		(hatch none 0.5)
		(connect_pads
			(clearance 0)
		)
		(min_thickness 0.25)
		(keepout
			(tracks not_allowed)
			(vias allowed)
			(pads allowed)
			(copperpour not_allowed)
			(footprints allowed)
		)
		(placement
			(enabled no)
			(sheetname "")
		)
		(fill
			(thermal_gap 0.5)
			(thermal_bridge_width 0.5)
			(island_removal_mode 0)
		)
		(polygon
			(pts
				(arc
					(start 390.481058 -397.028924)
					(mid 390.495937 -396.993003)
					(end 390.531858 -396.978124)
				)
				(arc
					(start 391.248138 -396.978124)
					(mid 391.284059 -396.993003)
					(end 391.298938 -397.028924)
				)
				(arc
					(start 391.298938 -399.451576)
					(mid 391.284059 -399.487497)
					(end 391.248138 -399.502376)
				)
				(arc
					(start 390.531858 -399.502376)
					(mid 390.495937 -399.487497)
					(end 390.481058 -399.451576)
				)
			)
		)
	)
	(zone
		(layers "F.Cu" "B.Cu" "In1.Cu" "In2.Cu" "In3.Cu" "In4.Cu" "In5.Cu" "In6.Cu"
			"In7.Cu" "In8.Cu" "In9.Cu" "In10.Cu" "In11.Cu" "In12.Cu" "In13.Cu" "In14.Cu"
			"In15.Cu" "In16.Cu"
		)
		(hatch none 0.5)
		(connect_pads
			(clearance 0)
		)
		(min_thickness 0.25)
		(keepout
			(tracks not_allowed)
			(vias allowed)
			(pads allowed)
			(copperpour not_allowed)
			(footprints allowed)
		)
		(placement
			(enabled no)
			(sheetname "")
		)
		(fill
			(thermal_gap 0.5)
			(thermal_bridge_width 0.5)
			(island_removal_mode 0)
		)
		(polygon
			(pts
				(arc
					(start 166.101014 -378.828554)
					(mid 166.115893 -378.792633)
					(end 166.151814 -378.777754)
				)
				(arc
					(start 166.868094 -378.777754)
					(mid 166.904015 -378.792633)
					(end 166.918894 -378.828554)
				)
				(arc
					(start 166.918894 -381.251206)
					(mid 166.904015 -381.287127)
					(end 166.868094 -381.302006)
				)
				(arc
					(start 166.151814 -381.302006)
					(mid 166.115893 -381.287127)
					(end 166.101014 -381.251206)
				)
			)
		)
	)
	(zone
		(layers "F.Cu" "B.Cu" "In1.Cu" "In2.Cu" "In3.Cu" "In4.Cu" "In5.Cu" "In6.Cu"
			"In7.Cu" "In8.Cu" "In9.Cu" "In10.Cu" "In11.Cu" "In12.Cu" "In13.Cu" "In14.Cu"
			"In15.Cu" "In16.Cu"
		)
		(hatch none 0.5)
		(connect_pads
			(clearance 0)
		)
		(min_thickness 0.25)
		(keepout
			(tracks not_allowed)
			(vias allowed)
			(pads allowed)
			(copperpour not_allowed)
			(footprints allowed)
		)
		(placement
			(enabled no)
			(sheetname "")
		)
		(fill
			(thermal_gap 0.5)
			(thermal_bridge_width 0.5)
			(island_removal_mode 0)
		)
		(polygon
			(pts
				(arc
					(start 324.938644 -345.084146)
					(mid 324.557644 -345.465146)
					(end 324.938644 -345.846146)
				)
				(arc
					(start 325.802244 -345.846146)
					(mid 326.183244 -345.465146)
					(end 325.802244 -345.084146)
				)
			)
		)
	)
	(zone
		(layers "F.Cu" "B.Cu" "In1.Cu" "In2.Cu" "In3.Cu" "In4.Cu" "In5.Cu" "In6.Cu"
			"In7.Cu" "In8.Cu" "In9.Cu" "In10.Cu" "In11.Cu" "In12.Cu" "In13.Cu" "In14.Cu"
			"In15.Cu" "In16.Cu"
		)
		(hatch none 0.5)
		(connect_pads
			(clearance 0)
		)
		(min_thickness 0.25)
		(keepout
			(tracks not_allowed)
			(vias allowed)
			(pads allowed)
			(copperpour not_allowed)
			(footprints allowed)
		)
		(placement
			(enabled no)
			(sheetname "")
		)
		(fill
			(thermal_gap 0.5)
			(thermal_bridge_width 0.5)
			(island_removal_mode 0)
		)
		(polygon
			(pts
				(arc
					(start 295.877742 -342.058498)
					(mid 295.496742 -342.439498)
					(end 295.877742 -342.820498)
				)
				(arc
					(start 296.741342 -342.820498)
					(mid 297.122342 -342.439498)
					(end 296.741342 -342.058498)
				)
			)
		)
	)
	(zone
		(layers "F.Cu" "B.Cu" "In1.Cu" "In2.Cu" "In3.Cu" "In4.Cu" "In5.Cu" "In6.Cu"
			"In7.Cu" "In8.Cu" "In9.Cu" "In10.Cu" "In11.Cu" "In12.Cu" "In13.Cu" "In14.Cu"
			"In15.Cu" "In16.Cu"
		)
		(hatch none 0.5)
		(connect_pads
			(clearance 0)
		)
		(min_thickness 0.25)
		(keepout
			(tracks not_allowed)
			(vias allowed)
			(pads allowed)
			(copperpour not_allowed)
			(footprints allowed)
		)
		(placement
			(enabled no)
			(sheetname "")
		)
		(fill
			(thermal_gap 0.5)
			(thermal_bridge_width 0.5)
			(island_removal_mode 0)
		)
		(polygon
			(pts
				(arc
					(start 430.080928 -371.028722)
					(mid 430.095807 -370.992801)
					(end 430.131728 -370.977922)
				)
				(arc
					(start 430.848008 -370.977922)
					(mid 430.883929 -370.992801)
					(end 430.898808 -371.028722)
				)
				(arc
					(start 430.898808 -373.451374)
					(mid 430.883929 -373.487295)
					(end 430.848008 -373.502174)
				)
				(arc
					(start 430.131728 -373.502174)
					(mid 430.095807 -373.487295)
					(end 430.080928 -373.451374)
				)
			)
		)
	)
	(zone
		(layers "F.Cu" "B.Cu" "In1.Cu" "In2.Cu" "In3.Cu" "In4.Cu" "In5.Cu" "In6.Cu"
			"In7.Cu" "In8.Cu" "In9.Cu" "In10.Cu" "In11.Cu" "In12.Cu" "In13.Cu" "In14.Cu"
			"In15.Cu" "In16.Cu"
		)
		(hatch none 0.5)
		(connect_pads
			(clearance 0)
		)
		(min_thickness 0.25)
		(keepout
			(tracks not_allowed)
			(vias allowed)
			(pads allowed)
			(copperpour not_allowed)
			(footprints allowed)
		)
		(placement
			(enabled no)
			(sheetname "")
		)
		(fill
			(thermal_gap 0.5)
			(thermal_bridge_width 0.5)
			(island_removal_mode 0)
		)
		(polygon
			(pts
				(arc
					(start 409.295092 -351.230438)
					(mid 408.914092 -351.611438)
					(end 409.295092 -351.992438)
				)
				(arc
					(start 410.158692 -351.992438)
					(mid 410.539692 -351.611438)
					(end 410.158692 -351.230438)
				)
			)
		)
	)
	(zone
		(layers "F.Cu" "B.Cu" "In1.Cu" "In2.Cu" "In3.Cu" "In4.Cu" "In5.Cu" "In6.Cu"
			"In7.Cu" "In8.Cu" "In9.Cu" "In10.Cu" "In11.Cu" "In12.Cu" "In13.Cu" "In14.Cu"
			"In15.Cu" "In16.Cu"
		)
		(hatch none 0.5)
		(connect_pads
			(clearance 0)
		)
		(min_thickness 0.25)
		(keepout
			(tracks not_allowed)
			(vias allowed)
			(pads allowed)
			(copperpour not_allowed)
			(footprints allowed)
		)
		(placement
			(enabled no)
			(sheetname "")
		)
		(fill
			(thermal_gap 0.5)
			(thermal_bridge_width 0.5)
			(island_removal_mode 0)
		)
		(polygon
			(pts
				(arc
					(start 124.30125 -369.928902)
					(mid 124.316129 -369.892981)
					(end 124.35205 -369.878102)
				)
				(arc
					(start 125.06833 -369.878102)
					(mid 125.104251 -369.892981)
					(end 125.11913 -369.928902)
				)
				(arc
					(start 125.11913 -372.351554)
					(mid 125.104251 -372.387475)
					(end 125.06833 -372.402354)
				)
				(arc
					(start 124.35205 -372.402354)
					(mid 124.316129 -372.387475)
					(end 124.30125 -372.351554)
				)
			)
		)
	)
	(zone
		(layers "F.Cu" "B.Cu" "In1.Cu" "In2.Cu" "In3.Cu" "In4.Cu" "In5.Cu" "In6.Cu"
			"In7.Cu" "In8.Cu" "In9.Cu" "In10.Cu" "In11.Cu" "In12.Cu" "In13.Cu" "In14.Cu"
			"In15.Cu" "In16.Cu"
		)
		(hatch none 0.5)
		(connect_pads
			(clearance 0)
		)
		(min_thickness 0.25)
		(keepout
			(tracks not_allowed)
			(vias allowed)
			(pads allowed)
			(copperpour not_allowed)
			(footprints allowed)
		)
		(placement
			(enabled no)
			(sheetname "")
		)
		(fill
			(thermal_gap 0.5)
			(thermal_bridge_width 0.5)
			(island_removal_mode 0)
		)
		(polygon
			(pts
				(arc
					(start 124.113798 -178.131724)
					(mid 123.656598 -177.674524)
					(end 123.199398 -178.131724)
				)
				(arc
					(start 123.199398 -178.995324)
					(mid 123.656598 -179.452524)
					(end 124.113798 -178.995324)
				)
			)
		)
	)
	(zone
		(layers "F.Cu" "B.Cu" "In1.Cu" "In2.Cu" "In3.Cu" "In4.Cu" "In5.Cu" "In6.Cu"
			"In7.Cu" "In8.Cu" "In9.Cu" "In10.Cu" "In11.Cu" "In12.Cu" "In13.Cu" "In14.Cu"
			"In15.Cu" "In16.Cu"
		)
		(hatch none 0.5)
		(connect_pads
			(clearance 0)
		)
		(min_thickness 0.25)
		(keepout
			(tracks not_allowed)
			(vias allowed)
			(pads allowed)
			(copperpour not_allowed)
			(footprints allowed)
		)
		(placement
			(enabled no)
			(sheetname "")
		)
		(fill
			(thermal_gap 0.5)
			(thermal_bridge_width 0.5)
			(island_removal_mode 0)
		)
		(polygon
			(pts
				(arc
					(start 174.901098 -400.92884)
					(mid 174.915977 -400.892919)
					(end 174.951898 -400.87804)
				)
				(arc
					(start 175.668178 -400.87804)
					(mid 175.704099 -400.892919)
					(end 175.718978 -400.92884)
				)
				(arc
					(start 175.718978 -403.351492)
					(mid 175.704099 -403.387413)
					(end 175.668178 -403.402292)
				)
				(arc
					(start 174.951898 -403.402292)
					(mid 174.915977 -403.387413)
					(end 174.901098 -403.351492)
				)
			)
		)
	)
	(zone
		(layers "F.Cu" "B.Cu" "In1.Cu" "In2.Cu" "In3.Cu" "In4.Cu" "In5.Cu" "In6.Cu"
			"In7.Cu" "In8.Cu" "In9.Cu" "In10.Cu" "In11.Cu" "In12.Cu" "In13.Cu" "In14.Cu"
			"In15.Cu" "In16.Cu"
		)
		(hatch none 0.5)
		(connect_pads
			(clearance 0)
		)
		(min_thickness 0.25)
		(keepout
			(tracks not_allowed)
			(vias allowed)
			(pads allowed)
			(copperpour not_allowed)
			(footprints allowed)
		)
		(placement
			(enabled no)
			(sheetname "")
		)
		(fill
			(thermal_gap 0.5)
			(thermal_bridge_width 0.5)
			(island_removal_mode 0)
		)
		(polygon
			(pts
				(arc
					(start 163.90112 -399.828766)
					(mid 163.915999 -399.792845)
					(end 163.95192 -399.777966)
				)
				(arc
					(start 164.6682 -399.777966)
					(mid 164.704121 -399.792845)
					(end 164.719 -399.828766)
				)
				(arc
					(start 164.719 -402.251418)
					(mid 164.704121 -402.287339)
					(end 164.6682 -402.302218)
				)
				(arc
					(start 163.95192 -402.302218)
					(mid 163.915999 -402.287339)
					(end 163.90112 -402.251418)
				)
			)
		)
	)
	(zone
		(layers "F.Cu" "B.Cu" "In1.Cu" "In2.Cu" "In3.Cu" "In4.Cu" "In5.Cu" "In6.Cu"
			"In7.Cu" "In8.Cu" "In9.Cu" "In10.Cu" "In11.Cu" "In12.Cu" "In13.Cu" "In14.Cu"
			"In15.Cu" "In16.Cu"
		)
		(hatch none 0.5)
		(connect_pads
			(clearance 0)
		)
		(min_thickness 0.25)
		(keepout
			(tracks not_allowed)
			(vias allowed)
			(pads allowed)
			(copperpour not_allowed)
			(footprints allowed)
		)
		(placement
			(enabled no)
			(sheetname "")
		)
		(fill
			(thermal_gap 0.5)
			(thermal_bridge_width 0.5)
			(island_removal_mode 0)
		)
		(polygon
			(pts
				(arc
					(start 75.901042 -403.728682)
					(mid 75.915921 -403.692761)
					(end 75.951842 -403.677882)
				)
				(arc
					(start 76.668122 -403.677882)
					(mid 76.704043 -403.692761)
					(end 76.718922 -403.728682)
				)
				(arc
					(start 76.718922 -406.151334)
					(mid 76.704043 -406.187255)
					(end 76.668122 -406.202134)
				)
				(arc
					(start 75.951842 -406.202134)
					(mid 75.915921 -406.187255)
					(end 75.901042 -406.151334)
				)
			)
		)
	)
	(zone
		(layers "F.Cu" "B.Cu" "In1.Cu" "In2.Cu" "In3.Cu" "In4.Cu" "In5.Cu" "In6.Cu"
			"In7.Cu" "In8.Cu" "In9.Cu" "In10.Cu" "In11.Cu" "In12.Cu" "In13.Cu" "In14.Cu"
			"In15.Cu" "In16.Cu"
		)
		(hatch none 0.5)
		(connect_pads
			(clearance 0)
		)
		(min_thickness 0.25)
		(keepout
			(tracks not_allowed)
			(vias allowed)
			(pads allowed)
			(copperpour not_allowed)
			(footprints allowed)
		)
		(placement
			(enabled no)
			(sheetname "")
		)
		(fill
			(thermal_gap 0.5)
			(thermal_bridge_width 0.5)
			(island_removal_mode 0)
		)
		(polygon
			(pts
				(arc
					(start 437.275732 -357.37673)
					(mid 436.894732 -357.75773)
					(end 437.275732 -358.13873)
				)
				(arc
					(start 438.139332 -358.13873)
					(mid 438.520332 -357.75773)
					(end 438.139332 -357.37673)
				)
			)
		)
	)
	(zone
		(layers "F.Cu" "B.Cu" "In1.Cu" "In2.Cu" "In3.Cu" "In4.Cu" "In5.Cu" "In6.Cu"
			"In7.Cu" "In8.Cu" "In9.Cu" "In10.Cu" "In11.Cu" "In12.Cu" "In13.Cu" "In14.Cu"
			"In15.Cu" "In16.Cu"
		)
		(hatch none 0.5)
		(connect_pads
			(clearance 0)
		)
		(min_thickness 0.25)
		(keepout
			(tracks not_allowed)
			(vias allowed)
			(pads allowed)
			(copperpour not_allowed)
			(footprints allowed)
		)
		(placement
			(enabled no)
			(sheetname "")
		)
		(fill
			(thermal_gap 0.5)
			(thermal_bridge_width 0.5)
			(island_removal_mode 0)
		)
		(polygon
			(pts
				(arc
					(start 83.134962 -357.37673)
					(mid 82.753962 -357.75773)
					(end 83.134962 -358.13873)
				)
				(arc
					(start 83.998562 -358.13873)
					(mid 84.379562 -357.75773)
					(end 83.998562 -357.37673)
				)
			)
		)
	)
	(zone
		(layers "F.Cu" "B.Cu" "In1.Cu" "In2.Cu" "In3.Cu" "In4.Cu" "In5.Cu" "In6.Cu"
			"In7.Cu" "In8.Cu" "In9.Cu" "In10.Cu" "In11.Cu" "In12.Cu" "In13.Cu" "In14.Cu"
			"In15.Cu" "In16.Cu"
		)
		(hatch none 0.5)
		(connect_pads
			(clearance 0)
		)
		(min_thickness 0.25)
		(keepout
			(tracks not_allowed)
			(vias allowed)
			(pads allowed)
			(copperpour not_allowed)
			(footprints allowed)
		)
		(placement
			(enabled no)
			(sheetname "")
		)
		(fill
			(thermal_gap 0.5)
			(thermal_bridge_width 0.5)
			(island_removal_mode 0)
		)
		(polygon
			(pts
				(arc
					(start 127.37973 -195.238878)
					(mid 126.92253 -195.696078)
					(end 127.37973 -196.153278)
				)
				(arc
					(start 128.24333 -196.153278)
					(mid 128.70053 -195.696078)
					(end 128.24333 -195.238878)
				)
			)
		)
	)
	(zone
		(layers "F.Cu" "B.Cu" "In1.Cu" "In2.Cu" "In3.Cu" "In4.Cu" "In5.Cu" "In6.Cu"
			"In7.Cu" "In8.Cu" "In9.Cu" "In10.Cu" "In11.Cu" "In12.Cu" "In13.Cu" "In14.Cu"
			"In15.Cu" "In16.Cu"
		)
		(hatch none 0.5)
		(connect_pads
			(clearance 0)
		)
		(min_thickness 0.25)
		(keepout
			(tracks not_allowed)
			(vias allowed)
			(pads allowed)
			(copperpour not_allowed)
			(footprints allowed)
		)
		(placement
			(enabled no)
			(sheetname "")
		)
		(fill
			(thermal_gap 0.5)
			(thermal_bridge_width 0.5)
			(island_removal_mode 0)
		)
		(polygon
			(pts
				(arc
					(start 64.481202 -354.351082)
					(mid 64.100202 -354.732082)
					(end 64.481202 -355.113082)
				)
				(arc
					(start 65.344802 -355.113082)
					(mid 65.725802 -354.732082)
					(end 65.344802 -354.351082)
				)
			)
		)
	)
	(zone
		(layers "F.Cu" "B.Cu" "In1.Cu" "In2.Cu" "In3.Cu" "In4.Cu" "In5.Cu" "In6.Cu"
			"In7.Cu" "In8.Cu" "In9.Cu" "In10.Cu" "In11.Cu" "In12.Cu" "In13.Cu" "In14.Cu"
			"In15.Cu" "In16.Cu"
		)
		(hatch none 0.5)
		(connect_pads
			(clearance 0)
		)
		(min_thickness 0.25)
		(keepout
			(tracks not_allowed)
			(vias allowed)
			(pads allowed)
			(copperpour not_allowed)
			(footprints allowed)
		)
		(placement
			(enabled no)
			(sheetname "")
		)
		(fill
			(thermal_gap 0.5)
			(thermal_bridge_width 0.5)
			(island_removal_mode 0)
		)
		(polygon
			(pts
				(arc
					(start 159.501078 -373.828818)
					(mid 159.515957 -373.792897)
					(end 159.551878 -373.778018)
				)
				(arc
					(start 160.268158 -373.778018)
					(mid 160.304079 -373.792897)
					(end 160.318958 -373.828818)
				)
				(arc
					(start 160.318958 -376.25147)
					(mid 160.304079 -376.287391)
					(end 160.268158 -376.30227)
				)
				(arc
					(start 159.551878 -376.30227)
					(mid 159.515957 -376.287391)
					(end 159.501078 -376.25147)
				)
			)
		)
	)
	(zone
		(layers "F.Cu" "B.Cu" "In1.Cu" "In2.Cu" "In3.Cu" "In4.Cu" "In5.Cu" "In6.Cu"
			"In7.Cu" "In8.Cu" "In9.Cu" "In10.Cu" "In11.Cu" "In12.Cu" "In13.Cu" "In14.Cu"
			"In15.Cu" "In16.Cu"
		)
		(hatch none 0.5)
		(connect_pads
			(clearance 0)
		)
		(min_thickness 0.25)
		(keepout
			(tracks not_allowed)
			(vias allowed)
			(pads allowed)
			(copperpour not_allowed)
			(footprints allowed)
		)
		(placement
			(enabled no)
			(sheetname "")
		)
		(fill
			(thermal_gap 0.5)
			(thermal_bridge_width 0.5)
			(island_removal_mode 0)
		)
		(polygon
			(pts
				(arc
					(start 78.100936 -382.728724)
					(mid 78.115815 -382.692803)
					(end 78.151736 -382.677924)
				)
				(arc
					(start 78.868016 -382.677924)
					(mid 78.903937 -382.692803)
					(end 78.918816 -382.728724)
				)
				(arc
					(start 78.918816 -385.151376)
					(mid 78.903937 -385.187297)
					(end 78.868016 -385.202176)
				)
				(arc
					(start 78.151736 -385.202176)
					(mid 78.115815 -385.187297)
					(end 78.100936 -385.151376)
				)
			)
		)
	)
	(zone
		(layers "F.Cu" "B.Cu" "In1.Cu" "In2.Cu" "In3.Cu" "In4.Cu" "In5.Cu" "In6.Cu"
			"In7.Cu" "In8.Cu" "In9.Cu" "In10.Cu" "In11.Cu" "In12.Cu" "In13.Cu" "In14.Cu"
			"In15.Cu" "In16.Cu"
		)
		(hatch none 0.5)
		(connect_pads
			(clearance 0)
		)
		(min_thickness 0.25)
		(keepout
			(tracks not_allowed)
			(vias allowed)
			(pads allowed)
			(copperpour not_allowed)
			(footprints allowed)
		)
		(placement
			(enabled no)
			(sheetname "")
		)
		(fill
			(thermal_gap 0.5)
			(thermal_bridge_width 0.5)
			(island_removal_mode 0)
		)
		(polygon
			(pts
				(arc
					(start 174.853346 -30.922468)
					(mid 175.310546 -31.379668)
					(end 175.767746 -30.922468)
				)
				(arc
					(start 175.767746 -30.058868)
					(mid 175.310546 -29.601668)
					(end 174.853346 -30.058868)
				)
			)
		)
	)
	(zone
		(layers "F.Cu" "B.Cu" "In1.Cu" "In2.Cu" "In3.Cu" "In4.Cu" "In5.Cu" "In6.Cu"
			"In7.Cu" "In8.Cu" "In9.Cu" "In10.Cu" "In11.Cu" "In12.Cu" "In13.Cu" "In14.Cu"
			"In15.Cu" "In16.Cu"
		)
		(hatch none 0.5)
		(connect_pads
			(clearance 0)
		)
		(min_thickness 0.25)
		(keepout
			(tracks not_allowed)
			(vias allowed)
			(pads allowed)
			(copperpour not_allowed)
			(footprints allowed)
		)
		(placement
			(enabled no)
			(sheetname "")
		)
		(fill
			(thermal_gap 0.5)
			(thermal_bridge_width 0.5)
			(island_removal_mode 0)
		)
		(polygon
			(pts
				(arc
					(start 180.845968 -121.367296)
					(mid 181.303168 -121.824496)
					(end 181.760368 -121.367296)
				)
				(arc
					(start 181.760368 -120.503696)
					(mid 181.303168 -120.046496)
					(end 180.845968 -120.503696)
				)
			)
		)
	)
	(zone
		(layers "F.Cu" "B.Cu" "In1.Cu" "In2.Cu" "In3.Cu" "In4.Cu" "In5.Cu" "In6.Cu"
			"In7.Cu" "In8.Cu" "In9.Cu" "In10.Cu" "In11.Cu" "In12.Cu" "In13.Cu" "In14.Cu"
			"In15.Cu" "In16.Cu"
		)
		(hatch none 0.5)
		(connect_pads
			(clearance 0)
		)
		(min_thickness 0.25)
		(keepout
			(tracks not_allowed)
			(vias allowed)
			(pads allowed)
			(copperpour not_allowed)
			(footprints allowed)
		)
		(placement
			(enabled no)
			(sheetname "")
		)
		(fill
			(thermal_gap 0.5)
			(thermal_bridge_width 0.5)
			(island_removal_mode 0)
		)
		(polygon
			(pts
				(arc
					(start 289.659822 -354.351082)
					(mid 289.278822 -354.732082)
					(end 289.659822 -355.113082)
				)
				(arc
					(start 290.523422 -355.113082)
					(mid 290.904422 -354.732082)
					(end 290.523422 -354.351082)
				)
			)
		)
	)
	(zone
		(layers "F.Cu" "B.Cu" "In1.Cu" "In2.Cu" "In3.Cu" "In4.Cu" "In5.Cu" "In6.Cu"
			"In7.Cu" "In8.Cu" "In9.Cu" "In10.Cu" "In11.Cu" "In12.Cu" "In13.Cu" "In14.Cu"
			"In15.Cu" "In16.Cu"
		)
		(hatch none 0.5)
		(connect_pads
			(clearance 0)
		)
		(min_thickness 0.25)
		(keepout
			(tracks not_allowed)
			(vias allowed)
			(pads allowed)
			(copperpour not_allowed)
			(footprints allowed)
		)
		(placement
			(enabled no)
			(sheetname "")
		)
		(fill
			(thermal_gap 0.5)
			(thermal_bridge_width 0.5)
			(island_removal_mode 0)
		)
		(polygon
			(pts
				(arc
					(start 159.501078 -381.628904)
					(mid 159.515957 -381.592983)
					(end 159.551878 -381.578104)
				)
				(arc
					(start 160.268158 -381.578104)
					(mid 160.304079 -381.592983)
					(end 160.318958 -381.628904)
				)
				(arc
					(start 160.318958 -384.051556)
					(mid 160.304079 -384.087477)
					(end 160.268158 -384.102356)
				)
				(arc
					(start 159.551878 -384.102356)
					(mid 159.515957 -384.087477)
					(end 159.501078 -384.051556)
				)
			)
		)
	)
	(zone
		(layers "F.Cu" "B.Cu" "In1.Cu" "In2.Cu" "In3.Cu" "In4.Cu" "In5.Cu" "In6.Cu"
			"In7.Cu" "In8.Cu" "In9.Cu" "In10.Cu" "In11.Cu" "In12.Cu" "In13.Cu" "In14.Cu"
			"In15.Cu" "In16.Cu"
		)
		(hatch none 0.5)
		(connect_pads
			(clearance 0)
		)
		(min_thickness 0.25)
		(keepout
			(tracks not_allowed)
			(vias allowed)
			(pads allowed)
			(copperpour not_allowed)
			(footprints allowed)
		)
		(placement
			(enabled no)
			(sheetname "")
		)
		(fill
			(thermal_gap 0.5)
			(thermal_bridge_width 0.5)
			(island_removal_mode 0)
		)
		(polygon
			(pts
				(arc
					(start 84.700872 -403.728682)
					(mid 84.715751 -403.692761)
					(end 84.751672 -403.677882)
				)
				(arc
					(start 85.467952 -403.677882)
					(mid 85.503873 -403.692761)
					(end 85.518752 -403.728682)
				)
				(arc
					(start 85.518752 -406.151334)
					(mid 85.503873 -406.187255)
					(end 85.467952 -406.202134)
				)
				(arc
					(start 84.751672 -406.202134)
					(mid 84.715751 -406.187255)
					(end 84.700872 -406.151334)
				)
			)
		)
	)
	(zone
		(layers "F.Cu" "B.Cu" "In1.Cu" "In2.Cu" "In3.Cu" "In4.Cu" "In5.Cu" "In6.Cu"
			"In7.Cu" "In8.Cu" "In9.Cu" "In10.Cu" "In11.Cu" "In12.Cu" "In13.Cu" "In14.Cu"
			"In15.Cu" "In16.Cu"
		)
		(hatch none 0.5)
		(connect_pads
			(clearance 0)
		)
		(min_thickness 0.25)
		(keepout
			(tracks not_allowed)
			(vias allowed)
			(pads allowed)
			(copperpour not_allowed)
			(footprints allowed)
		)
		(placement
			(enabled no)
			(sheetname "")
		)
		(fill
			(thermal_gap 0.5)
			(thermal_bridge_width 0.5)
			(island_removal_mode 0)
		)
		(polygon
			(pts
				(arc
					(start 409.295092 -342.058498)
					(mid 408.914092 -342.439498)
					(end 409.295092 -342.820498)
				)
				(arc
					(start 410.158692 -342.820498)
					(mid 410.539692 -342.439498)
					(end 410.158692 -342.058498)
				)
			)
		)
	)
	(zone
		(layers "F.Cu" "B.Cu" "In1.Cu" "In2.Cu" "In3.Cu" "In4.Cu" "In5.Cu" "In6.Cu"
			"In7.Cu" "In8.Cu" "In9.Cu" "In10.Cu" "In11.Cu" "In12.Cu" "In13.Cu" "In14.Cu"
			"In15.Cu" "In16.Cu"
		)
		(hatch none 0.5)
		(connect_pads
			(clearance 0)
		)
		(min_thickness 0.25)
		(keepout
			(tracks not_allowed)
			(vias allowed)
			(pads allowed)
			(copperpour not_allowed)
			(footprints allowed)
		)
		(placement
			(enabled no)
			(sheetname "")
		)
		(fill
			(thermal_gap 0.5)
			(thermal_bridge_width 0.5)
			(island_removal_mode 0)
		)
		(polygon
			(pts
				(arc
					(start 446.203324 -208.517236)
					(mid 445.746124 -208.060036)
					(end 445.288924 -208.517236)
				)
				(arc
					(start 445.288924 -209.380836)
					(mid 445.746124 -209.838036)
					(end 446.203324 -209.380836)
				)
			)
		)
	)
	(zone
		(layers "F.Cu" "B.Cu" "In1.Cu" "In2.Cu" "In3.Cu" "In4.Cu" "In5.Cu" "In6.Cu"
			"In7.Cu" "In8.Cu" "In9.Cu" "In10.Cu" "In11.Cu" "In12.Cu" "In13.Cu" "In14.Cu"
			"In15.Cu" "In16.Cu"
		)
		(hatch none 0.5)
		(connect_pads
			(clearance 0)
		)
		(min_thickness 0.25)
		(keepout
			(tracks not_allowed)
			(vias allowed)
			(pads allowed)
			(copperpour not_allowed)
			(footprints allowed)
		)
		(placement
			(enabled no)
			(sheetname "")
		)
		(fill
			(thermal_gap 0.5)
			(thermal_bridge_width 0.5)
			(island_removal_mode 0)
		)
		(polygon
			(pts
				(arc
					(start 298.800012 -154.28722)
					(mid 299.257212 -154.74442)
					(end 299.714412 -154.28722)
				)
				(arc
					(start 299.714412 -153.42362)
					(mid 299.257212 -152.96642)
					(end 298.800012 -153.42362)
				)
			)
		)
	)
	(zone
		(layers "F.Cu" "B.Cu" "In1.Cu" "In2.Cu" "In3.Cu" "In4.Cu" "In5.Cu" "In6.Cu"
			"In7.Cu" "In8.Cu" "In9.Cu" "In10.Cu" "In11.Cu" "In12.Cu" "In13.Cu" "In14.Cu"
			"In15.Cu" "In16.Cu"
		)
		(hatch none 0.5)
		(connect_pads
			(clearance 0)
		)
		(min_thickness 0.25)
		(keepout
			(tracks not_allowed)
			(vias allowed)
			(pads allowed)
			(copperpour not_allowed)
			(footprints allowed)
		)
		(placement
			(enabled no)
			(sheetname "")
		)
		(fill
			(thermal_gap 0.5)
			(thermal_bridge_width 0.5)
			(island_removal_mode 0)
		)
		(polygon
			(pts
				(arc
					(start 117.5385 -86.495382)
					(mid 117.0813 -86.038182)
					(end 116.6241 -86.495382)
				)
				(arc
					(start 116.6241 -87.358982)
					(mid 117.0813 -87.816182)
					(end 117.5385 -87.358982)
				)
			)
		)
	)
	(zone
		(layers "F.Cu" "B.Cu" "In1.Cu" "In2.Cu" "In3.Cu" "In4.Cu" "In5.Cu" "In6.Cu"
			"In7.Cu" "In8.Cu" "In9.Cu" "In10.Cu" "In11.Cu" "In12.Cu" "In13.Cu" "In14.Cu"
			"In15.Cu" "In16.Cu"
		)
		(hatch none 0.5)
		(connect_pads
			(clearance 0)
		)
		(min_thickness 0.25)
		(keepout
			(tracks not_allowed)
			(vias allowed)
			(pads allowed)
			(copperpour not_allowed)
			(footprints allowed)
		)
		(placement
			(enabled no)
			(sheetname "")
		)
		(fill
			(thermal_gap 0.5)
			(thermal_bridge_width 0.5)
			(island_removal_mode 0)
		)
		(polygon
			(pts
				(arc
					(start 298.800012 -147.087336)
					(mid 299.257212 -147.544536)
					(end 299.714412 -147.087336)
				)
				(arc
					(start 299.714412 -146.223736)
					(mid 299.257212 -145.766536)
					(end 298.800012 -146.223736)
				)
			)
		)
	)
	(zone
		(layers "F.Cu" "B.Cu" "In1.Cu" "In2.Cu" "In3.Cu" "In4.Cu" "In5.Cu" "In6.Cu"
			"In7.Cu" "In8.Cu" "In9.Cu" "In10.Cu" "In11.Cu" "In12.Cu" "In13.Cu" "In14.Cu"
			"In15.Cu" "In16.Cu"
		)
		(hatch none 0.5)
		(connect_pads
			(clearance 0)
		)
		(min_thickness 0.25)
		(keepout
			(tracks not_allowed)
			(vias allowed)
			(pads allowed)
			(copperpour not_allowed)
			(footprints allowed)
		)
		(placement
			(enabled no)
			(sheetname "")
		)
		(fill
			(thermal_gap 0.5)
			(thermal_bridge_width 0.5)
			(island_removal_mode 0)
		)
		(polygon
			(pts
				(arc
					(start 174.901098 -371.028722)
					(mid 174.915977 -370.992801)
					(end 174.951898 -370.977922)
				)
				(arc
					(start 175.668178 -370.977922)
					(mid 175.704099 -370.992801)
					(end 175.718978 -371.028722)
				)
				(arc
					(start 175.718978 -373.451374)
					(mid 175.704099 -373.487295)
					(end 175.668178 -373.502174)
				)
				(arc
					(start 174.951898 -373.502174)
					(mid 174.915977 -373.487295)
					(end 174.901098 -373.451374)
				)
			)
		)
	)
	(zone
		(layers "F.Cu" "B.Cu" "In1.Cu" "In2.Cu" "In3.Cu" "In4.Cu" "In5.Cu" "In6.Cu"
			"In7.Cu" "In8.Cu" "In9.Cu" "In10.Cu" "In11.Cu" "In12.Cu" "In13.Cu" "In14.Cu"
			"In15.Cu" "In16.Cu"
		)
		(hatch none 0.5)
		(connect_pads
			(clearance 0)
		)
		(min_thickness 0.25)
		(keepout
			(tracks not_allowed)
			(vias allowed)
			(pads allowed)
			(copperpour not_allowed)
			(footprints allowed)
		)
		(placement
			(enabled no)
			(sheetname "")
		)
		(fill
			(thermal_gap 0.5)
			(thermal_bridge_width 0.5)
			(island_removal_mode 0)
		)
		(polygon
			(pts
				(arc
					(start 346.79509 -87.281004)
					(mid 346.33789 -86.823804)
					(end 345.88069 -87.281004)
				)
				(arc
					(start 345.88069 -88.144604)
					(mid 346.33789 -88.601804)
					(end 346.79509 -88.144604)
				)
			)
		)
	)
	(zone
		(layers "F.Cu" "B.Cu" "In1.Cu" "In2.Cu" "In3.Cu" "In4.Cu" "In5.Cu" "In6.Cu"
			"In7.Cu" "In8.Cu" "In9.Cu" "In10.Cu" "In11.Cu" "In12.Cu" "In13.Cu" "In14.Cu"
			"In15.Cu" "In16.Cu"
		)
		(hatch none 0.5)
		(connect_pads
			(clearance 0)
		)
		(min_thickness 0.25)
		(keepout
			(tracks not_allowed)
			(vias allowed)
			(pads allowed)
			(copperpour not_allowed)
			(footprints allowed)
		)
		(placement
			(enabled no)
			(sheetname "")
		)
		(fill
			(thermal_gap 0.5)
			(thermal_bridge_width 0.5)
			(island_removal_mode 0)
		)
		(polygon
			(pts
				(arc
					(start 124.297948 -348.20479)
					(mid 123.916948 -348.58579)
					(end 124.297948 -348.96679)
				)
				(arc
					(start 125.161548 -348.96679)
					(mid 125.542548 -348.58579)
					(end 125.161548 -348.20479)
				)
			)
		)
	)
	(zone
		(layers "F.Cu" "B.Cu" "In1.Cu" "In2.Cu" "In3.Cu" "In4.Cu" "In5.Cu" "In6.Cu"
			"In7.Cu" "In8.Cu" "In9.Cu" "In10.Cu" "In11.Cu" "In12.Cu" "In13.Cu" "In14.Cu"
			"In15.Cu" "In16.Cu"
		)
		(hatch none 0.5)
		(connect_pads
			(clearance 0)
		)
		(min_thickness 0.25)
		(keepout
			(tracks not_allowed)
			(vias allowed)
			(pads allowed)
			(copperpour not_allowed)
			(footprints allowed)
		)
		(placement
			(enabled no)
			(sheetname "")
		)
		(fill
			(thermal_gap 0.5)
			(thermal_bridge_width 0.5)
			(island_removal_mode 0)
		)
		(polygon
			(pts
				(arc
					(start 130.515868 -357.37673)
					(mid 130.134868 -357.75773)
					(end 130.515868 -358.13873)
				)
				(arc
					(start 131.379468 -358.13873)
					(mid 131.760468 -357.75773)
					(end 131.379468 -357.37673)
				)
			)
		)
	)
	(zone
		(layers "F.Cu" "B.Cu" "In1.Cu" "In2.Cu" "In3.Cu" "In4.Cu" "In5.Cu" "In6.Cu"
			"In7.Cu" "In8.Cu" "In9.Cu" "In10.Cu" "In11.Cu" "In12.Cu" "In13.Cu" "In14.Cu"
			"In15.Cu" "In16.Cu"
		)
		(hatch none 0.5)
		(connect_pads
			(clearance 0)
		)
		(min_thickness 0.25)
		(keepout
			(tracks not_allowed)
			(vias allowed)
			(pads allowed)
			(copperpour not_allowed)
			(footprints allowed)
		)
		(placement
			(enabled no)
			(sheetname "")
		)
		(fill
			(thermal_gap 0.5)
			(thermal_bridge_width 0.5)
			(island_removal_mode 0)
		)
		(polygon
			(pts
				(arc
					(start 312.502804 -351.230438)
					(mid 312.121804 -351.611438)
					(end 312.502804 -351.992438)
				)
				(arc
					(start 313.366404 -351.992438)
					(mid 313.747404 -351.611438)
					(end 313.366404 -351.230438)
				)
			)
		)
	)
	(zone
		(layers "F.Cu" "B.Cu" "In1.Cu" "In2.Cu" "In3.Cu" "In4.Cu" "In5.Cu" "In6.Cu"
			"In7.Cu" "In8.Cu" "In9.Cu" "In10.Cu" "In11.Cu" "In12.Cu" "In13.Cu" "In14.Cu"
			"In15.Cu" "In16.Cu"
		)
		(hatch none 0.5)
		(connect_pads
			(clearance 0)
		)
		(min_thickness 0.25)
		(keepout
			(tracks not_allowed)
			(vias allowed)
			(pads allowed)
			(copperpour not_allowed)
			(footprints allowed)
		)
		(placement
			(enabled no)
			(sheetname "")
		)
		(fill
			(thermal_gap 0.5)
			(thermal_bridge_width 0.5)
			(island_removal_mode 0)
		)
		(polygon
			(pts
				(arc
					(start 177.730912 -357.37673)
					(mid 177.349912 -357.75773)
					(end 177.730912 -358.13873)
				)
				(arc
					(start 178.594512 -358.13873)
					(mid 178.975512 -357.75773)
					(end 178.594512 -357.37673)
				)
			)
		)
	)
	(zone
		(layers "F.Cu" "B.Cu" "In1.Cu" "In2.Cu" "In3.Cu" "In4.Cu" "In5.Cu" "In6.Cu"
			"In7.Cu" "In8.Cu" "In9.Cu" "In10.Cu" "In11.Cu" "In12.Cu" "In13.Cu" "In14.Cu"
			"In15.Cu" "In16.Cu"
		)
		(hatch none 0.5)
		(connect_pads
			(clearance 0)
		)
		(min_thickness 0.25)
		(keepout
			(tracks not_allowed)
			(vias allowed)
			(pads allowed)
			(copperpour not_allowed)
			(footprints allowed)
		)
		(placement
			(enabled no)
			(sheetname "")
		)
		(fill
			(thermal_gap 0.5)
			(thermal_bridge_width 0.5)
			(island_removal_mode 0)
		)
		(polygon
			(pts
				(arc
					(start 37.310568 -110.977934)
					(mid 37.767768 -111.435134)
					(end 38.224968 -110.977934)
				)
				(arc
					(start 38.224968 -110.114334)
					(mid 37.767768 -109.657134)
					(end 37.310568 -110.114334)
				)
			)
		)
	)
	(zone
		(layers "F.Cu" "B.Cu" "In1.Cu" "In2.Cu" "In3.Cu" "In4.Cu" "In5.Cu" "In6.Cu"
			"In7.Cu" "In8.Cu" "In9.Cu" "In10.Cu" "In11.Cu" "In12.Cu" "In13.Cu" "In14.Cu"
			"In15.Cu" "In16.Cu"
		)
		(hatch none 0.5)
		(connect_pads
			(clearance 0)
		)
		(min_thickness 0.25)
		(keepout
			(tracks not_allowed)
			(vias allowed)
			(pads allowed)
			(copperpour not_allowed)
			(footprints allowed)
		)
		(placement
			(enabled no)
			(sheetname "")
		)
		(fill
			(thermal_gap 0.5)
			(thermal_bridge_width 0.5)
			(island_removal_mode 0)
		)
		(polygon
			(pts
				(arc
					(start 423.480992 -373.828818)
					(mid 423.495871 -373.792897)
					(end 423.531792 -373.778018)
				)
				(arc
					(start 424.248072 -373.778018)
					(mid 424.283993 -373.792897)
					(end 424.298872 -373.828818)
				)
				(arc
					(start 424.298872 -376.25147)
					(mid 424.283993 -376.287391)
					(end 424.248072 -376.30227)
				)
				(arc
					(start 423.531792 -376.30227)
					(mid 423.495871 -376.287391)
					(end 423.480992 -376.25147)
				)
			)
		)
	)
	(zone
		(layers "F.Cu" "B.Cu" "In1.Cu" "In2.Cu" "In3.Cu" "In4.Cu" "In5.Cu" "In6.Cu"
			"In7.Cu" "In8.Cu" "In9.Cu" "In10.Cu" "In11.Cu" "In12.Cu" "In13.Cu" "In14.Cu"
			"In15.Cu" "In16.Cu"
		)
		(hatch none 0.5)
		(connect_pads
			(clearance 0)
		)
		(min_thickness 0.25)
		(keepout
			(tracks not_allowed)
			(vias allowed)
			(pads allowed)
			(copperpour not_allowed)
			(footprints allowed)
		)
		(placement
			(enabled no)
			(sheetname "")
		)
		(fill
			(thermal_gap 0.5)
			(thermal_bridge_width 0.5)
			(island_removal_mode 0)
		)
		(polygon
			(pts
				(arc
					(start 379.48108 -407.628852)
					(mid 379.495959 -407.592931)
					(end 379.53188 -407.578052)
				)
				(arc
					(start 380.24816 -407.578052)
					(mid 380.284081 -407.592931)
					(end 380.29896 -407.628852)
				)
				(arc
					(start 380.29896 -410.051504)
					(mid 380.284081 -410.087425)
					(end 380.24816 -410.102304)
				)
				(arc
					(start 379.53188 -410.102304)
					(mid 379.495959 -410.087425)
					(end 379.48108 -410.051504)
				)
			)
		)
	)
	(zone
		(layers "F.Cu" "B.Cu" "In1.Cu" "In2.Cu" "In3.Cu" "In4.Cu" "In5.Cu" "In6.Cu"
			"In7.Cu" "In8.Cu" "In9.Cu" "In10.Cu" "In11.Cu" "In12.Cu" "In13.Cu" "In14.Cu"
			"In15.Cu" "In16.Cu"
		)
		(hatch none 0.5)
		(connect_pads
			(clearance 0)
		)
		(min_thickness 0.25)
		(keepout
			(tracks not_allowed)
			(vias allowed)
			(pads allowed)
			(copperpour not_allowed)
			(footprints allowed)
		)
		(placement
			(enabled no)
			(sheetname "")
		)
		(fill
			(thermal_gap 0.5)
			(thermal_bridge_width 0.5)
			(island_removal_mode 0)
		)
		(polygon
			(pts
				(arc
					(start 292.80739 -29.12237)
					(mid 293.26459 -29.57957)
					(end 293.72179 -29.12237)
				)
				(arc
					(start 293.72179 -28.25877)
					(mid 293.26459 -27.80157)
					(end 292.80739 -28.25877)
				)
			)
		)
	)
	(zone
		(layers "F.Cu" "B.Cu" "In1.Cu" "In2.Cu" "In3.Cu" "In4.Cu" "In5.Cu" "In6.Cu"
			"In7.Cu" "In8.Cu" "In9.Cu" "In10.Cu" "In11.Cu" "In12.Cu" "In13.Cu" "In14.Cu"
			"In15.Cu" "In16.Cu"
		)
		(hatch none 0.5)
		(connect_pads
			(clearance 0)
		)
		(min_thickness 0.25)
		(keepout
			(tracks not_allowed)
			(vias allowed)
			(pads allowed)
			(copperpour not_allowed)
			(footprints allowed)
		)
		(placement
			(enabled no)
			(sheetname "")
		)
		(fill
			(thermal_gap 0.5)
			(thermal_bridge_width 0.5)
			(island_removal_mode 0)
		)
		(polygon
			(pts
				(arc
					(start 121.188988 -351.230438)
					(mid 120.807988 -351.611438)
					(end 121.188988 -351.992438)
				)
				(arc
					(start 122.052588 -351.992438)
					(mid 122.433588 -351.611438)
					(end 122.052588 -351.230438)
				)
			)
		)
	)
	(zone
		(layers "F.Cu" "B.Cu" "In1.Cu" "In2.Cu" "In3.Cu" "In4.Cu" "In5.Cu" "In6.Cu"
			"In7.Cu" "In8.Cu" "In9.Cu" "In10.Cu" "In11.Cu" "In12.Cu" "In13.Cu" "In14.Cu"
			"In15.Cu" "In16.Cu"
		)
		(hatch none 0.5)
		(connect_pads
			(clearance 0)
		)
		(min_thickness 0.25)
		(keepout
			(tracks not_allowed)
			(vias allowed)
			(pads allowed)
			(copperpour not_allowed)
			(footprints allowed)
		)
		(placement
			(enabled no)
			(sheetname "")
		)
		(fill
			(thermal_gap 0.5)
			(thermal_bridge_width 0.5)
			(island_removal_mode 0)
		)
		(polygon
			(pts
				(arc
					(start 75.901042 -381.628904)
					(mid 75.915921 -381.592983)
					(end 75.951842 -381.578104)
				)
				(arc
					(start 76.668122 -381.578104)
					(mid 76.704043 -381.592983)
					(end 76.718922 -381.628904)
				)
				(arc
					(start 76.718922 -384.051556)
					(mid 76.704043 -384.087477)
					(end 76.668122 -384.102356)
				)
				(arc
					(start 75.951842 -384.102356)
					(mid 75.915921 -384.087477)
					(end 75.901042 -384.051556)
				)
			)
		)
	)
	(zone
		(layers "F.Cu" "B.Cu" "In1.Cu" "In2.Cu" "In3.Cu" "In4.Cu" "In5.Cu" "In6.Cu"
			"In7.Cu" "In8.Cu" "In9.Cu" "In10.Cu" "In11.Cu" "In12.Cu" "In13.Cu" "In14.Cu"
			"In15.Cu" "In16.Cu"
		)
		(hatch none 0.5)
		(connect_pads
			(clearance 0)
		)
		(min_thickness 0.25)
		(keepout
			(tracks not_allowed)
			(vias allowed)
			(pads allowed)
			(copperpour not_allowed)
			(footprints allowed)
		)
		(placement
			(enabled no)
			(sheetname "")
		)
		(fill
			(thermal_gap 0.5)
			(thermal_bridge_width 0.5)
			(island_removal_mode 0)
		)
		(polygon
			(pts
				(arc
					(start 70.699122 -354.351082)
					(mid 70.318122 -354.732082)
					(end 70.699122 -355.113082)
				)
				(arc
					(start 71.562722 -355.113082)
					(mid 71.943722 -354.732082)
					(end 71.562722 -354.351082)
				)
			)
		)
	)
	(zone
		(layers "F.Cu" "B.Cu" "In1.Cu" "In2.Cu" "In3.Cu" "In4.Cu" "In5.Cu" "In6.Cu"
			"In7.Cu" "In8.Cu" "In9.Cu" "In10.Cu" "In11.Cu" "In12.Cu" "In13.Cu" "In14.Cu"
			"In15.Cu" "In16.Cu"
		)
		(hatch none 0.5)
		(connect_pads
			(clearance 0)
		)
		(min_thickness 0.25)
		(keepout
			(tracks not_allowed)
			(vias allowed)
			(pads allowed)
			(copperpour not_allowed)
			(footprints allowed)
		)
		(placement
			(enabled no)
			(sheetname "")
		)
		(fill
			(thermal_gap 0.5)
			(thermal_bridge_width 0.5)
			(island_removal_mode 0)
		)
		(polygon
			(pts
				(arc
					(start 16.524224 -27.342846)
					(mid 16.981424 -27.800046)
					(end 17.438624 -27.342846)
				)
				(arc
					(start 17.438624 -26.479246)
					(mid 16.981424 -26.022046)
					(end 16.524224 -26.479246)
				)
			)
		)
	)
	(zone
		(layers "F.Cu" "B.Cu" "In1.Cu" "In2.Cu" "In3.Cu" "In4.Cu" "In5.Cu" "In6.Cu"
			"In7.Cu" "In8.Cu" "In9.Cu" "In10.Cu" "In11.Cu" "In12.Cu" "In13.Cu" "In14.Cu"
			"In15.Cu" "In16.Cu"
		)
		(hatch none 0.5)
		(connect_pads
			(clearance 0)
		)
		(min_thickness 0.25)
		(keepout
			(tracks not_allowed)
			(vias allowed)
			(pads allowed)
			(copperpour not_allowed)
			(footprints allowed)
		)
		(placement
			(enabled no)
			(sheetname "")
		)
		(fill
			(thermal_gap 0.5)
			(thermal_bridge_width 0.5)
			(island_removal_mode 0)
		)
		(polygon
			(pts
				(arc
					(start 36.301172 -377.728734)
					(mid 36.316051 -377.692813)
					(end 36.351972 -377.677934)
				)
				(arc
					(start 37.068252 -377.677934)
					(mid 37.104173 -377.692813)
					(end 37.119052 -377.728734)
				)
				(arc
					(start 37.119052 -380.151386)
					(mid 37.104173 -380.187307)
					(end 37.068252 -380.202186)
				)
				(arc
					(start 36.351972 -380.202186)
					(mid 36.316051 -380.187307)
					(end 36.301172 -380.151386)
				)
			)
		)
	)
	(zone
		(layers "F.Cu" "B.Cu" "In1.Cu" "In2.Cu" "In3.Cu" "In4.Cu" "In5.Cu" "In6.Cu"
			"In7.Cu" "In8.Cu" "In9.Cu" "In10.Cu" "In11.Cu" "In12.Cu" "In13.Cu" "In14.Cu"
			"In15.Cu" "In16.Cu"
		)
		(hatch none 0.5)
		(connect_pads
			(clearance 0)
		)
		(min_thickness 0.25)
		(keepout
			(tracks not_allowed)
			(vias allowed)
			(pads allowed)
			(copperpour not_allowed)
			(footprints allowed)
		)
		(placement
			(enabled no)
			(sheetname "")
		)
		(fill
			(thermal_gap 0.5)
			(thermal_bridge_width 0.5)
			(island_removal_mode 0)
		)
		(polygon
			(pts
				(arc
					(start 141.54658 -182.933086)
					(mid 142.00378 -183.390286)
					(end 142.46098 -182.933086)
				)
				(arc
					(start 142.46098 -182.069486)
					(mid 142.00378 -181.612286)
					(end 141.54658 -182.069486)
				)
			)
		)
	)
	(zone
		(layers "F.Cu" "B.Cu" "In1.Cu" "In2.Cu" "In3.Cu" "In4.Cu" "In5.Cu" "In6.Cu"
			"In7.Cu" "In8.Cu" "In9.Cu" "In10.Cu" "In11.Cu" "In12.Cu" "In13.Cu" "In14.Cu"
			"In15.Cu" "In16.Cu"
		)
		(hatch none 0.5)
		(connect_pads
			(clearance 0)
		)
		(min_thickness 0.25)
		(keepout
			(tracks not_allowed)
			(vias allowed)
			(pads allowed)
			(copperpour not_allowed)
			(footprints allowed)
		)
		(placement
			(enabled no)
			(sheetname "")
		)
		(fill
			(thermal_gap 0.5)
			(thermal_bridge_width 0.5)
			(island_removal_mode 0)
		)
		(polygon
			(pts
				(arc
					(start 190.575438 -117.758718)
					(mid 191.032638 -118.215918)
					(end 191.489838 -117.758718)
				)
				(arc
					(start 191.489838 -116.895118)
					(mid 191.032638 -116.437918)
					(end 190.575438 -116.895118)
				)
			)
		)
	)
	(zone
		(layers "F.Cu" "B.Cu" "In1.Cu" "In2.Cu" "In3.Cu" "In4.Cu" "In5.Cu" "In6.Cu"
			"In7.Cu" "In8.Cu" "In9.Cu" "In10.Cu" "In11.Cu" "In12.Cu" "In13.Cu" "In14.Cu"
			"In15.Cu" "In16.Cu"
		)
		(hatch none 0.5)
		(connect_pads
			(clearance 0)
		)
		(min_thickness 0.25)
		(keepout
			(tracks not_allowed)
			(vias allowed)
			(pads allowed)
			(copperpour not_allowed)
			(footprints allowed)
		)
		(placement
			(enabled no)
			(sheetname "")
		)
		(fill
			(thermal_gap 0.5)
			(thermal_bridge_width 0.5)
			(island_removal_mode 0)
		)
		(polygon
			(pts
				(arc
					(start 25.550368 -348.20479)
					(mid 25.169368 -348.58579)
					(end 25.550368 -348.96679)
				)
				(arc
					(start 26.413968 -348.96679)
					(mid 26.794968 -348.58579)
					(end 26.413968 -348.20479)
				)
			)
		)
	)
	(zone
		(layers "F.Cu" "B.Cu" "In1.Cu" "In2.Cu" "In3.Cu" "In4.Cu" "In5.Cu" "In6.Cu"
			"In7.Cu" "In8.Cu" "In9.Cu" "In10.Cu" "In11.Cu" "In12.Cu" "In13.Cu" "In14.Cu"
			"In15.Cu" "In16.Cu"
		)
		(hatch none 0.5)
		(connect_pads
			(clearance 0)
		)
		(min_thickness 0.25)
		(keepout
			(tracks not_allowed)
			(vias allowed)
			(pads allowed)
			(copperpour not_allowed)
			(footprints allowed)
		)
		(placement
			(enabled no)
			(sheetname "")
		)
		(fill
			(thermal_gap 0.5)
			(thermal_bridge_width 0.5)
			(island_removal_mode 0)
		)
		(polygon
			(pts
				(arc
					(start 238.953294 -30.922468)
					(mid 239.410494 -31.379668)
					(end 239.867694 -30.922468)
				)
				(arc
					(start 239.867694 -30.058868)
					(mid 239.410494 -29.601668)
					(end 238.953294 -30.058868)
				)
			)
		)
	)
	(zone
		(layers "F.Cu" "B.Cu" "In1.Cu" "In2.Cu" "In3.Cu" "In4.Cu" "In5.Cu" "In6.Cu"
			"In7.Cu" "In8.Cu" "In9.Cu" "In10.Cu" "In11.Cu" "In12.Cu" "In13.Cu" "In14.Cu"
			"In15.Cu" "In16.Cu"
		)
		(hatch none 0.5)
		(connect_pads
			(clearance 0)
		)
		(min_thickness 0.25)
		(keepout
			(tracks not_allowed)
			(vias allowed)
			(pads allowed)
			(copperpour not_allowed)
			(footprints allowed)
		)
		(placement
			(enabled no)
			(sheetname "")
		)
		(fill
			(thermal_gap 0.5)
			(thermal_bridge_width 0.5)
			(island_removal_mode 0)
		)
		(polygon
			(pts
				(arc
					(start 300.280832 -399.828766)
					(mid 300.295711 -399.792845)
					(end 300.331632 -399.777966)
				)
				(arc
					(start 301.047912 -399.777966)
					(mid 301.083833 -399.792845)
					(end 301.098712 -399.828766)
				)
				(arc
					(start 301.098712 -402.251418)
					(mid 301.083833 -402.287339)
					(end 301.047912 -402.302218)
				)
				(arc
					(start 300.331632 -402.302218)
					(mid 300.295711 -402.287339)
					(end 300.280832 -402.251418)
				)
			)
		)
	)
	(zone
		(layers "F.Cu" "B.Cu" "In1.Cu" "In2.Cu" "In3.Cu" "In4.Cu" "In5.Cu" "In6.Cu"
			"In7.Cu" "In8.Cu" "In9.Cu" "In10.Cu" "In11.Cu" "In12.Cu" "In13.Cu" "In14.Cu"
			"In15.Cu" "In16.Cu"
		)
		(hatch none 0.5)
		(connect_pads
			(clearance 0)
		)
		(min_thickness 0.25)
		(keepout
			(tracks not_allowed)
			(vias allowed)
			(pads allowed)
			(copperpour not_allowed)
			(footprints allowed)
		)
		(placement
			(enabled no)
			(sheetname "")
		)
		(fill
			(thermal_gap 0.5)
			(thermal_bridge_width 0.5)
			(island_removal_mode 0)
		)
		(polygon
			(pts
				(arc
					(start 83.71713 -132.575808)
					(mid 84.17433 -133.033008)
					(end 84.63153 -132.575808)
				)
				(arc
					(start 84.63153 -131.712208)
					(mid 84.17433 -131.255008)
					(end 83.71713 -131.712208)
				)
			)
		)
	)
	(zone
		(layers "F.Cu" "B.Cu" "In1.Cu" "In2.Cu" "In3.Cu" "In4.Cu" "In5.Cu" "In6.Cu"
			"In7.Cu" "In8.Cu" "In9.Cu" "In10.Cu" "In11.Cu" "In12.Cu" "In13.Cu" "In14.Cu"
			"In15.Cu" "In16.Cu"
		)
		(hatch none 0.5)
		(connect_pads
			(clearance 0)
		)
		(min_thickness 0.25)
		(keepout
			(tracks not_allowed)
			(vias allowed)
			(pads allowed)
			(copperpour not_allowed)
			(footprints allowed)
		)
		(placement
			(enabled no)
			(sheetname "")
		)
		(fill
			(thermal_gap 0.5)
			(thermal_bridge_width 0.5)
			(island_removal_mode 0)
		)
		(polygon
			(pts
				(arc
					(start 122.101102 -382.728724)
					(mid 122.115981 -382.692803)
					(end 122.151902 -382.677924)
				)
				(arc
					(start 122.868182 -382.677924)
					(mid 122.904103 -382.692803)
					(end 122.918982 -382.728724)
				)
				(arc
					(start 122.918982 -385.151376)
					(mid 122.904103 -385.187297)
					(end 122.868182 -385.202176)
				)
				(arc
					(start 122.151902 -385.202176)
					(mid 122.115981 -385.187297)
					(end 122.101102 -385.151376)
				)
			)
		)
	)
	(zone
		(layers "F.Cu" "B.Cu" "In1.Cu" "In2.Cu" "In3.Cu" "In4.Cu" "In5.Cu" "In6.Cu"
			"In7.Cu" "In8.Cu" "In9.Cu" "In10.Cu" "In11.Cu" "In12.Cu" "In13.Cu" "In14.Cu"
			"In15.Cu" "In16.Cu"
		)
		(hatch none 0.5)
		(connect_pads
			(clearance 0)
		)
		(min_thickness 0.25)
		(keepout
			(tracks not_allowed)
			(vias allowed)
			(pads allowed)
			(copperpour not_allowed)
			(footprints allowed)
		)
		(placement
			(enabled no)
			(sheetname "")
		)
		(fill
			(thermal_gap 0.5)
			(thermal_bridge_width 0.5)
			(island_removal_mode 0)
		)
		(polygon
			(pts
				(arc
					(start 84.700872 -399.828766)
					(mid 84.715751 -399.792845)
					(end 84.751672 -399.777966)
				)
				(arc
					(start 85.467952 -399.777966)
					(mid 85.503873 -399.792845)
					(end 85.518752 -399.828766)
				)
				(arc
					(start 85.518752 -402.251418)
					(mid 85.503873 -402.287339)
					(end 85.467952 -402.302218)
				)
				(arc
					(start 84.751672 -402.302218)
					(mid 84.715751 -402.287339)
					(end 84.700872 -402.251418)
				)
			)
		)
	)
	(zone
		(layers "F.Cu" "B.Cu" "In1.Cu" "In2.Cu" "In3.Cu" "In4.Cu" "In5.Cu" "In6.Cu"
			"In7.Cu" "In8.Cu" "In9.Cu" "In10.Cu" "In11.Cu" "In12.Cu" "In13.Cu" "In14.Cu"
			"In15.Cu" "In16.Cu"
		)
		(hatch none 0.5)
		(connect_pads
			(clearance 0)
		)
		(min_thickness 0.25)
		(keepout
			(tracks not_allowed)
			(vias allowed)
			(pads allowed)
			(copperpour not_allowed)
			(footprints allowed)
		)
		(placement
			(enabled no)
			(sheetname "")
		)
		(fill
			(thermal_gap 0.5)
			(thermal_bridge_width 0.5)
			(island_removal_mode 0)
		)
		(polygon
			(pts
				(arc
					(start 421.730932 -351.230438)
					(mid 421.349932 -351.611438)
					(end 421.730932 -351.992438)
				)
				(arc
					(start 422.594532 -351.992438)
					(mid 422.975532 -351.611438)
					(end 422.594532 -351.230438)
				)
			)
		)
	)
	(zone
		(layers "F.Cu" "B.Cu" "In1.Cu" "In2.Cu" "In3.Cu" "In4.Cu" "In5.Cu" "In6.Cu"
			"In7.Cu" "In8.Cu" "In9.Cu" "In10.Cu" "In11.Cu" "In12.Cu" "In13.Cu" "In14.Cu"
			"In15.Cu" "In16.Cu"
		)
		(hatch none 0.5)
		(connect_pads
			(clearance 0)
		)
		(min_thickness 0.25)
		(keepout
			(tracks not_allowed)
			(vias allowed)
			(pads allowed)
			(copperpour not_allowed)
			(footprints allowed)
		)
		(placement
			(enabled no)
			(sheetname "")
		)
		(fill
			(thermal_gap 0.5)
			(thermal_bridge_width 0.5)
			(island_removal_mode 0)
		)
		(polygon
			(pts
				(arc
					(start 412.404052 -348.20479)
					(mid 412.023052 -348.58579)
					(end 412.404052 -348.96679)
				)
				(arc
					(start 413.267652 -348.96679)
					(mid 413.648652 -348.58579)
					(end 413.267652 -348.20479)
				)
			)
		)
	)
	(zone
		(layers "F.Cu" "B.Cu" "In1.Cu" "In2.Cu" "In3.Cu" "In4.Cu" "In5.Cu" "In6.Cu"
			"In7.Cu" "In8.Cu" "In9.Cu" "In10.Cu" "In11.Cu" "In12.Cu" "In13.Cu" "In14.Cu"
			"In15.Cu" "In16.Cu"
		)
		(hatch none 0.5)
		(connect_pads
			(clearance 0)
		)
		(min_thickness 0.25)
		(keepout
			(tracks not_allowed)
			(vias allowed)
			(pads allowed)
			(copperpour not_allowed)
			(footprints allowed)
		)
		(placement
			(enabled no)
			(sheetname "")
		)
		(fill
			(thermal_gap 0.5)
			(thermal_bridge_width 0.5)
			(island_removal_mode 0)
		)
		(polygon
			(pts
				(arc
					(start 239.45342 -82.764376)
					(mid 239.91062 -82.307176)
					(end 239.45342 -81.849976)
				)
				(arc
					(start 238.58982 -81.849976)
					(mid 238.13262 -82.307176)
					(end 238.58982 -82.764376)
				)
			)
		)
	)
	(zone
		(layers "F.Cu" "B.Cu" "In1.Cu" "In2.Cu" "In3.Cu" "In4.Cu" "In5.Cu" "In6.Cu"
			"In7.Cu" "In8.Cu" "In9.Cu" "In10.Cu" "In11.Cu" "In12.Cu" "In13.Cu" "In14.Cu"
			"In15.Cu" "In16.Cu"
		)
		(hatch none 0.5)
		(connect_pads
			(clearance 0)
		)
		(min_thickness 0.25)
		(keepout
			(tracks not_allowed)
			(vias allowed)
			(pads allowed)
			(copperpour not_allowed)
			(footprints allowed)
		)
		(placement
			(enabled no)
			(sheetname "")
		)
		(fill
			(thermal_gap 0.5)
			(thermal_bridge_width 0.5)
			(island_removal_mode 0)
		)
		(polygon
			(pts
				(arc
					(start 302.48098 -382.728724)
					(mid 302.495859 -382.692803)
					(end 302.53178 -382.677924)
				)
				(arc
					(start 303.24806 -382.677924)
					(mid 303.283981 -382.692803)
					(end 303.29886 -382.728724)
				)
				(arc
					(start 303.29886 -385.151376)
					(mid 303.283981 -385.187297)
					(end 303.24806 -385.202176)
				)
				(arc
					(start 302.53178 -385.202176)
					(mid 302.495859 -385.187297)
					(end 302.48098 -385.151376)
				)
			)
		)
	)
	(zone
		(layers "F.Cu" "B.Cu" "In1.Cu" "In2.Cu" "In3.Cu" "In4.Cu" "In5.Cu" "In6.Cu"
			"In7.Cu" "In8.Cu" "In9.Cu" "In10.Cu" "In11.Cu" "In12.Cu" "In13.Cu" "In14.Cu"
			"In15.Cu" "In16.Cu"
		)
		(hatch none 0.5)
		(connect_pads
			(clearance 0)
		)
		(min_thickness 0.25)
		(keepout
			(tracks not_allowed)
			(vias allowed)
			(pads allowed)
			(copperpour not_allowed)
			(footprints allowed)
		)
		(placement
			(enabled no)
			(sheetname "")
		)
		(fill
			(thermal_gap 0.5)
			(thermal_bridge_width 0.5)
			(island_removal_mode 0)
		)
		(polygon
			(pts
				(arc
					(start 289.280854 -374.928638)
					(mid 289.295733 -374.892717)
					(end 289.331654 -374.877838)
				)
				(arc
					(start 290.047934 -374.877838)
					(mid 290.083855 -374.892717)
					(end 290.098734 -374.928638)
				)
				(arc
					(start 290.098734 -377.35129)
					(mid 290.083855 -377.387211)
					(end 290.047934 -377.40209)
				)
				(arc
					(start 289.331654 -377.40209)
					(mid 289.295733 -377.387211)
					(end 289.280854 -377.35129)
				)
			)
		)
	)
	(zone
		(layers "F.Cu" "B.Cu" "In1.Cu" "In2.Cu" "In3.Cu" "In4.Cu" "In5.Cu" "In6.Cu"
			"In7.Cu" "In8.Cu" "In9.Cu" "In10.Cu" "In11.Cu" "In12.Cu" "In13.Cu" "In14.Cu"
			"In15.Cu" "In16.Cu"
		)
		(hatch none 0.5)
		(connect_pads
			(clearance 0)
		)
		(min_thickness 0.25)
		(keepout
			(tracks not_allowed)
			(vias allowed)
			(pads allowed)
			(copperpour not_allowed)
			(footprints allowed)
		)
		(placement
			(enabled no)
			(sheetname "")
		)
		(fill
			(thermal_gap 0.5)
			(thermal_bridge_width 0.5)
			(island_removal_mode 0)
		)
		(polygon
			(pts
				(arc
					(start 45.101002 -369.928902)
					(mid 45.115881 -369.892981)
					(end 45.151802 -369.878102)
				)
				(arc
					(start 45.868082 -369.878102)
					(mid 45.904003 -369.892981)
					(end 45.918882 -369.928902)
				)
				(arc
					(start 45.918882 -372.351554)
					(mid 45.904003 -372.387475)
					(end 45.868082 -372.402354)
				)
				(arc
					(start 45.151802 -372.402354)
					(mid 45.115881 -372.387475)
					(end 45.101002 -372.351554)
				)
			)
		)
	)
	(zone
		(layers "F.Cu" "B.Cu" "In1.Cu" "In2.Cu" "In3.Cu" "In4.Cu" "In5.Cu" "In6.Cu"
			"In7.Cu" "In8.Cu" "In9.Cu" "In10.Cu" "In11.Cu" "In12.Cu" "In13.Cu" "In14.Cu"
			"In15.Cu" "In16.Cu"
		)
		(hatch none 0.5)
		(connect_pads
			(clearance 0)
		)
		(min_thickness 0.25)
		(keepout
			(tracks not_allowed)
			(vias allowed)
			(pads allowed)
			(copperpour not_allowed)
			(footprints allowed)
		)
		(placement
			(enabled no)
			(sheetname "")
		)
		(fill
			(thermal_gap 0.5)
			(thermal_bridge_width 0.5)
			(island_removal_mode 0)
		)
		(polygon
			(pts
				(arc
					(start 300.280832 -403.728682)
					(mid 300.295711 -403.692761)
					(end 300.331632 -403.677882)
				)
				(arc
					(start 301.047912 -403.677882)
					(mid 301.083833 -403.692761)
					(end 301.098712 -403.728682)
				)
				(arc
					(start 301.098712 -406.151334)
					(mid 301.083833 -406.187255)
					(end 301.047912 -406.202134)
				)
				(arc
					(start 300.331632 -406.202134)
					(mid 300.295711 -406.187255)
					(end 300.280832 -406.151334)
				)
			)
		)
	)
	(zone
		(layers "F.Cu" "B.Cu" "In1.Cu" "In2.Cu" "In3.Cu" "In4.Cu" "In5.Cu" "In6.Cu"
			"In7.Cu" "In8.Cu" "In9.Cu" "In10.Cu" "In11.Cu" "In12.Cu" "In13.Cu" "In14.Cu"
			"In15.Cu" "In16.Cu"
		)
		(hatch none 0.5)
		(connect_pads
			(clearance 0)
		)
		(min_thickness 0.25)
		(keepout
			(tracks not_allowed)
			(vias allowed)
			(pads allowed)
			(copperpour not_allowed)
			(footprints allowed)
		)
		(placement
			(enabled no)
			(sheetname "")
		)
		(fill
			(thermal_gap 0.5)
			(thermal_bridge_width 0.5)
			(island_removal_mode 0)
		)
		(polygon
			(pts
				(arc
					(start 298.986702 -357.37673)
					(mid 298.605702 -357.75773)
					(end 298.986702 -358.13873)
				)
				(arc
					(start 299.850302 -358.13873)
					(mid 300.231302 -357.75773)
					(end 299.850302 -357.37673)
				)
			)
		)
	)
	(zone
		(layers "F.Cu" "B.Cu" "In1.Cu" "In2.Cu" "In3.Cu" "In4.Cu" "In5.Cu" "In6.Cu"
			"In7.Cu" "In8.Cu" "In9.Cu" "In10.Cu" "In11.Cu" "In12.Cu" "In13.Cu" "In14.Cu"
			"In15.Cu" "In16.Cu"
		)
		(hatch none 0.5)
		(connect_pads
			(clearance 0)
		)
		(min_thickness 0.25)
		(keepout
			(tracks not_allowed)
			(vias allowed)
			(pads allowed)
			(copperpour not_allowed)
			(footprints allowed)
		)
		(placement
			(enabled no)
			(sheetname "")
		)
		(fill
			(thermal_gap 0.5)
			(thermal_bridge_width 0.5)
			(island_removal_mode 0)
		)
		(polygon
			(pts
				(arc
					(start 266.807442 -32.722312)
					(mid 267.264642 -33.179512)
					(end 267.721842 -32.722312)
				)
				(arc
					(start 267.721842 -31.858712)
					(mid 267.264642 -31.401512)
					(end 266.807442 -31.858712)
				)
			)
		)
	)
	(zone
		(layers "F.Cu" "B.Cu" "In1.Cu" "In2.Cu" "In3.Cu" "In4.Cu" "In5.Cu" "In6.Cu"
			"In7.Cu" "In8.Cu" "In9.Cu" "In10.Cu" "In11.Cu" "In12.Cu" "In13.Cu" "In14.Cu"
			"In15.Cu" "In16.Cu"
		)
		(hatch none 0.5)
		(connect_pads
			(clearance 0)
		)
		(min_thickness 0.25)
		(keepout
			(tracks not_allowed)
			(vias allowed)
			(pads allowed)
			(copperpour not_allowed)
			(footprints allowed)
		)
		(placement
			(enabled no)
			(sheetname "")
		)
		(fill
			(thermal_gap 0.5)
			(thermal_bridge_width 0.5)
			(island_removal_mode 0)
		)
		(polygon
			(pts
				(arc
					(start 81.075022 -130.769106)
					(mid 81.532222 -131.226306)
					(end 81.989422 -130.769106)
				)
				(arc
					(start 81.989422 -129.905506)
					(mid 81.532222 -129.448306)
					(end 81.075022 -129.905506)
				)
			)
		)
	)
	(zone
		(layers "F.Cu" "B.Cu" "In1.Cu" "In2.Cu" "In3.Cu" "In4.Cu" "In5.Cu" "In6.Cu"
			"In7.Cu" "In8.Cu" "In9.Cu" "In10.Cu" "In11.Cu" "In12.Cu" "In13.Cu" "In14.Cu"
			"In15.Cu" "In16.Cu"
		)
		(hatch none 0.5)
		(connect_pads
			(clearance 0)
		)
		(min_thickness 0.25)
		(keepout
			(tracks not_allowed)
			(vias allowed)
			(pads allowed)
			(copperpour not_allowed)
			(footprints allowed)
		)
		(placement
			(enabled no)
			(sheetname "")
		)
		(fill
			(thermal_gap 0.5)
			(thermal_bridge_width 0.5)
			(island_removal_mode 0)
		)
		(polygon
			(pts
				(arc
					(start 293.680896 -378.828554)
					(mid 293.695775 -378.792633)
					(end 293.731696 -378.777754)
				)
				(arc
					(start 294.447976 -378.777754)
					(mid 294.483897 -378.792633)
					(end 294.498776 -378.828554)
				)
				(arc
					(start 294.498776 -381.251206)
					(mid 294.483897 -381.287127)
					(end 294.447976 -381.302006)
				)
				(arc
					(start 293.731696 -381.302006)
					(mid 293.695775 -381.287127)
					(end 293.680896 -381.251206)
				)
			)
		)
	)
	(zone
		(layers "F.Cu" "B.Cu" "In1.Cu" "In2.Cu" "In3.Cu" "In4.Cu" "In5.Cu" "In6.Cu"
			"In7.Cu" "In8.Cu" "In9.Cu" "In10.Cu" "In11.Cu" "In12.Cu" "In13.Cu" "In14.Cu"
			"In15.Cu" "In16.Cu"
		)
		(hatch none 0.5)
		(connect_pads
			(clearance 0)
		)
		(min_thickness 0.25)
		(keepout
			(tracks not_allowed)
			(vias allowed)
			(pads allowed)
			(copperpour not_allowed)
			(footprints allowed)
		)
		(placement
			(enabled no)
			(sheetname "")
		)
		(fill
			(thermal_gap 0.5)
			(thermal_bridge_width 0.5)
			(island_removal_mode 0)
		)
		(polygon
			(pts
				(arc
					(start 170.654218 -106.512614)
					(mid 170.197018 -106.055414)
					(end 169.739818 -106.512614)
				)
				(arc
					(start 169.739818 -107.376214)
					(mid 170.197018 -107.833414)
					(end 170.654218 -107.376214)
				)
			)
		)
	)
	(zone
		(layers "F.Cu" "B.Cu" "In1.Cu" "In2.Cu" "In3.Cu" "In4.Cu" "In5.Cu" "In6.Cu"
			"In7.Cu" "In8.Cu" "In9.Cu" "In10.Cu" "In11.Cu" "In12.Cu" "In13.Cu" "In14.Cu"
			"In15.Cu" "In16.Cu"
		)
		(hatch none 0.5)
		(connect_pads
			(clearance 0)
		)
		(min_thickness 0.25)
		(keepout
			(tracks not_allowed)
			(vias allowed)
			(pads allowed)
			(copperpour not_allowed)
			(footprints allowed)
		)
		(placement
			(enabled no)
			(sheetname "")
		)
		(fill
			(thermal_gap 0.5)
			(thermal_bridge_width 0.5)
			(island_removal_mode 0)
		)
		(polygon
			(pts
				(arc
					(start 239.445546 -88.433402)
					(mid 239.902746 -87.976202)
					(end 239.445546 -87.519002)
				)
				(arc
					(start 238.581946 -87.519002)
					(mid 238.124746 -87.976202)
					(end 238.581946 -88.433402)
				)
			)
		)
	)
	(zone
		(layers "F.Cu" "B.Cu" "In1.Cu" "In2.Cu" "In3.Cu" "In4.Cu" "In5.Cu" "In6.Cu"
			"In7.Cu" "In8.Cu" "In9.Cu" "In10.Cu" "In11.Cu" "In12.Cu" "In13.Cu" "In14.Cu"
			"In15.Cu" "In16.Cu"
		)
		(hatch none 0.5)
		(connect_pads
			(clearance 0)
		)
		(min_thickness 0.25)
		(keepout
			(tracks not_allowed)
			(vias allowed)
			(pads allowed)
			(copperpour not_allowed)
			(footprints allowed)
		)
		(placement
			(enabled no)
			(sheetname "")
		)
		(fill
			(thermal_gap 0.5)
			(thermal_bridge_width 0.5)
			(island_removal_mode 0)
		)
		(polygon
			(pts
				(arc
					(start 81.075022 -123.159266)
					(mid 81.532222 -123.616466)
					(end 81.989422 -123.159266)
				)
				(arc
					(start 81.989422 -122.295666)
					(mid 81.532222 -121.838466)
					(end 81.075022 -122.295666)
				)
			)
		)
	)
	(zone
		(layers "F.Cu" "B.Cu" "In1.Cu" "In2.Cu" "In3.Cu" "In4.Cu" "In5.Cu" "In6.Cu"
			"In7.Cu" "In8.Cu" "In9.Cu" "In10.Cu" "In11.Cu" "In12.Cu" "In13.Cu" "In14.Cu"
			"In15.Cu" "In16.Cu"
		)
		(hatch none 0.5)
		(connect_pads
			(clearance 0)
		)
		(min_thickness 0.25)
		(keepout
			(tracks not_allowed)
			(vias allowed)
			(pads allowed)
			(copperpour not_allowed)
			(footprints allowed)
		)
		(placement
			(enabled no)
			(sheetname "")
		)
		(fill
			(thermal_gap 0.5)
			(thermal_bridge_width 0.5)
			(island_removal_mode 0)
		)
		(polygon
			(pts
				(arc
					(start 199.817228 -136.17575)
					(mid 200.274428 -136.63295)
					(end 200.731628 -136.17575)
				)
				(arc
					(start 200.731628 -135.31215)
					(mid 200.274428 -134.85495)
					(end 199.817228 -135.31215)
				)
			)
		)
	)
	(zone
		(layers "F.Cu" "B.Cu" "In1.Cu" "In2.Cu" "In3.Cu" "In4.Cu" "In5.Cu" "In6.Cu"
			"In7.Cu" "In8.Cu" "In9.Cu" "In10.Cu" "In11.Cu" "In12.Cu" "In13.Cu" "In14.Cu"
			"In15.Cu" "In16.Cu"
		)
		(hatch none 0.5)
		(connect_pads
			(clearance 0)
		)
		(min_thickness 0.25)
		(keepout
			(tracks not_allowed)
			(vias allowed)
			(pads allowed)
			(copperpour not_allowed)
			(footprints allowed)
		)
		(placement
			(enabled no)
			(sheetname "")
		)
		(fill
			(thermal_gap 0.5)
			(thermal_bridge_width 0.5)
			(island_removal_mode 0)
		)
		(polygon
			(pts
				(arc
					(start 279.690068 -30.92069)
					(mid 280.147268 -31.37789)
					(end 280.604468 -30.92069)
				)
				(arc
					(start 280.604468 -30.05709)
					(mid 280.147268 -29.59989)
					(end 279.690068 -30.05709)
				)
			)
		)
	)
	(zone
		(layers "F.Cu" "B.Cu" "In1.Cu" "In2.Cu" "In3.Cu" "In4.Cu" "In5.Cu" "In6.Cu"
			"In7.Cu" "In8.Cu" "In9.Cu" "In10.Cu" "In11.Cu" "In12.Cu" "In13.Cu" "In14.Cu"
			"In15.Cu" "In16.Cu"
		)
		(hatch none 0.5)
		(connect_pads
			(clearance 0)
		)
		(min_thickness 0.25)
		(keepout
			(tracks not_allowed)
			(vias allowed)
			(pads allowed)
			(copperpour not_allowed)
			(footprints allowed)
		)
		(placement
			(enabled no)
			(sheetname "")
		)
		(fill
			(thermal_gap 0.5)
			(thermal_bridge_width 0.5)
			(island_removal_mode 0)
		)
		(polygon
			(pts
				(arc
					(start 385.610608 -110.977934)
					(mid 386.067808 -111.435134)
					(end 386.525008 -110.977934)
				)
				(arc
					(start 386.525008 -110.114334)
					(mid 386.067808 -109.657134)
					(end 385.610608 -110.114334)
				)
			)
		)
	)
	(zone
		(layers "F.Cu" "B.Cu" "In1.Cu" "In2.Cu" "In3.Cu" "In4.Cu" "In5.Cu" "In6.Cu"
			"In7.Cu" "In8.Cu" "In9.Cu" "In10.Cu" "In11.Cu" "In12.Cu" "In13.Cu" "In14.Cu"
			"In15.Cu" "In16.Cu"
		)
		(hatch none 0.5)
		(connect_pads
			(clearance 0)
		)
		(min_thickness 0.25)
		(keepout
			(tracks not_allowed)
			(vias allowed)
			(pads allowed)
			(copperpour not_allowed)
			(footprints allowed)
		)
		(placement
			(enabled no)
			(sheetname "")
		)
		(fill
			(thermal_gap 0.5)
			(thermal_bridge_width 0.5)
			(island_removal_mode 0)
		)
		(polygon
			(pts
				(arc
					(start 277.223982 -345.084146)
					(mid 276.842982 -345.465146)
					(end 277.223982 -345.846146)
				)
				(arc
					(start 278.087582 -345.846146)
					(mid 278.468582 -345.465146)
					(end 278.087582 -345.084146)
				)
			)
		)
	)
	(zone
		(layers "F.Cu" "B.Cu" "In1.Cu" "In2.Cu" "In3.Cu" "In4.Cu" "In5.Cu" "In6.Cu"
			"In7.Cu" "In8.Cu" "In9.Cu" "In10.Cu" "In11.Cu" "In12.Cu" "In13.Cu" "In14.Cu"
			"In15.Cu" "In16.Cu"
		)
		(hatch none 0.5)
		(connect_pads
			(clearance 0)
		)
		(min_thickness 0.25)
		(keepout
			(tracks not_allowed)
			(vias allowed)
			(pads allowed)
			(copperpour not_allowed)
			(footprints allowed)
		)
		(placement
			(enabled no)
			(sheetname "")
		)
		(fill
			(thermal_gap 0.5)
			(thermal_bridge_width 0.5)
			(island_removal_mode 0)
		)
		(polygon
			(pts
				(arc
					(start 343.592404 -348.20479)
					(mid 343.211404 -348.58579)
					(end 343.592404 -348.96679)
				)
				(arc
					(start 344.456004 -348.96679)
					(mid 344.837004 -348.58579)
					(end 344.456004 -348.20479)
				)
			)
		)
	)
	(zone
		(layers "F.Cu" "B.Cu" "In1.Cu" "In2.Cu" "In3.Cu" "In4.Cu" "In5.Cu" "In6.Cu"
			"In7.Cu" "In8.Cu" "In9.Cu" "In10.Cu" "In11.Cu" "In12.Cu" "In13.Cu" "In14.Cu"
			"In15.Cu" "In16.Cu"
		)
		(hatch none 0.5)
		(connect_pads
			(clearance 0)
		)
		(min_thickness 0.25)
		(keepout
			(tracks not_allowed)
			(vias allowed)
			(pads allowed)
			(copperpour not_allowed)
			(footprints allowed)
		)
		(placement
			(enabled no)
			(sheetname "")
		)
		(fill
			(thermal_gap 0.5)
			(thermal_bridge_width 0.5)
			(island_removal_mode 0)
		)
		(polygon
			(pts
				(arc
					(start 337.681062 -397.028924)
					(mid 337.695941 -396.993003)
					(end 337.731862 -396.978124)
				)
				(arc
					(start 338.448142 -396.978124)
					(mid 338.484063 -396.993003)
					(end 338.498942 -397.028924)
				)
				(arc
					(start 338.498942 -399.451576)
					(mid 338.484063 -399.487497)
					(end 338.448142 -399.502376)
				)
				(arc
					(start 337.731862 -399.502376)
					(mid 337.695941 -399.487497)
					(end 337.681062 -399.451576)
				)
			)
		)
	)
	(zone
		(layers "F.Cu" "B.Cu" "In1.Cu" "In2.Cu" "In3.Cu" "In4.Cu" "In5.Cu" "In6.Cu"
			"In7.Cu" "In8.Cu" "In9.Cu" "In10.Cu" "In11.Cu" "In12.Cu" "In13.Cu" "In14.Cu"
			"In15.Cu" "In16.Cu"
		)
		(hatch none 0.5)
		(connect_pads
			(clearance 0)
		)
		(min_thickness 0.25)
		(keepout
			(tracks not_allowed)
			(vias allowed)
			(pads allowed)
			(copperpour not_allowed)
			(footprints allowed)
		)
		(placement
			(enabled no)
			(sheetname "")
		)
		(fill
			(thermal_gap 0.5)
			(thermal_bridge_width 0.5)
			(island_removal_mode 0)
		)
		(polygon
			(pts
				(arc
					(start 176.707546 -29.12237)
					(mid 177.164746 -29.57957)
					(end 177.621946 -29.12237)
				)
				(arc
					(start 177.621946 -28.25877)
					(mid 177.164746 -27.80157)
					(end 176.707546 -28.25877)
				)
			)
		)
	)
	(zone
		(layers "F.Cu" "B.Cu" "In1.Cu" "In2.Cu" "In3.Cu" "In4.Cu" "In5.Cu" "In6.Cu"
			"In7.Cu" "In8.Cu" "In9.Cu" "In10.Cu" "In11.Cu" "In12.Cu" "In13.Cu" "In14.Cu"
			"In15.Cu" "In16.Cu"
		)
		(hatch none 0.5)
		(connect_pads
			(clearance 0)
		)
		(min_thickness 0.25)
		(keepout
			(tracks not_allowed)
			(vias allowed)
			(pads allowed)
			(copperpour not_allowed)
			(footprints allowed)
		)
		(placement
			(enabled no)
			(sheetname "")
		)
		(fill
			(thermal_gap 0.5)
			(thermal_bridge_width 0.5)
			(island_removal_mode 0)
		)
		(polygon
			(pts
				(arc
					(start 94.524068 -27.342846)
					(mid 94.981268 -27.800046)
					(end 95.438468 -27.342846)
				)
				(arc
					(start 95.438468 -26.479246)
					(mid 94.981268 -26.022046)
					(end 94.524068 -26.479246)
				)
			)
		)
	)
	(zone
		(layers "F.Cu" "B.Cu" "In1.Cu" "In2.Cu" "In3.Cu" "In4.Cu" "In5.Cu" "In6.Cu"
			"In7.Cu" "In8.Cu" "In9.Cu" "In10.Cu" "In11.Cu" "In12.Cu" "In13.Cu" "In14.Cu"
			"In15.Cu" "In16.Cu"
		)
		(hatch none 0.5)
		(connect_pads
			(clearance 0)
		)
		(min_thickness 0.25)
		(keepout
			(tracks not_allowed)
			(vias allowed)
			(pads allowed)
			(copperpour not_allowed)
			(footprints allowed)
		)
		(placement
			(enabled no)
			(sheetname "")
		)
		(fill
			(thermal_gap 0.5)
			(thermal_bridge_width 0.5)
			(island_removal_mode 0)
		)
		(polygon
			(pts
				(arc
					(start 86.90102 -397.028924)
					(mid 86.915899 -396.993003)
					(end 86.95182 -396.978124)
				)
				(arc
					(start 87.6681 -396.978124)
					(mid 87.704021 -396.993003)
					(end 87.7189 -397.028924)
				)
				(arc
					(start 87.7189 -399.451576)
					(mid 87.704021 -399.487497)
					(end 87.6681 -399.502376)
				)
				(arc
					(start 86.95182 -399.502376)
					(mid 86.915899 -399.487497)
					(end 86.90102 -399.451576)
				)
			)
		)
	)
	(zone
		(layers "F.Cu" "B.Cu" "In1.Cu" "In2.Cu" "In3.Cu" "In4.Cu" "In5.Cu" "In6.Cu"
			"In7.Cu" "In8.Cu" "In9.Cu" "In10.Cu" "In11.Cu" "In12.Cu" "In13.Cu" "In14.Cu"
			"In15.Cu" "In16.Cu"
		)
		(hatch none 0.5)
		(connect_pads
			(clearance 0)
		)
		(min_thickness 0.25)
		(keepout
			(tracks not_allowed)
			(vias allowed)
			(pads allowed)
			(copperpour not_allowed)
			(footprints allowed)
		)
		(placement
			(enabled no)
			(sheetname "")
		)
		(fill
			(thermal_gap 0.5)
			(thermal_bridge_width 0.5)
			(island_removal_mode 0)
		)
		(polygon
			(pts
				(arc
					(start 105.093262 -384.832098)
					(mid 104.636062 -385.289298)
					(end 105.093262 -385.746498)
				)
				(arc
					(start 105.956862 -385.746498)
					(mid 106.414062 -385.289298)
					(end 105.956862 -384.832098)
				)
			)
		)
	)
	(zone
		(layers "F.Cu" "B.Cu" "In1.Cu" "In2.Cu" "In3.Cu" "In4.Cu" "In5.Cu" "In6.Cu"
			"In7.Cu" "In8.Cu" "In9.Cu" "In10.Cu" "In11.Cu" "In12.Cu" "In13.Cu" "In14.Cu"
			"In15.Cu" "In16.Cu"
		)
		(hatch none 0.5)
		(connect_pads
			(clearance 0)
		)
		(min_thickness 0.25)
		(keepout
			(tracks not_allowed)
			(vias allowed)
			(pads allowed)
			(copperpour not_allowed)
			(footprints allowed)
		)
		(placement
			(enabled no)
			(sheetname "")
		)
		(fill
			(thermal_gap 0.5)
			(thermal_bridge_width 0.5)
			(island_removal_mode 0)
		)
		(polygon
			(pts
				(arc
					(start 284.899862 -121.022872)
					(mid 284.442662 -120.565672)
					(end 283.985462 -121.022872)
				)
				(arc
					(start 283.985462 -121.886472)
					(mid 284.442662 -122.343672)
					(end 284.899862 -121.886472)
				)
			)
		)
	)
	(zone
		(layers "F.Cu" "B.Cu" "In1.Cu" "In2.Cu" "In3.Cu" "In4.Cu" "In5.Cu" "In6.Cu"
			"In7.Cu" "In8.Cu" "In9.Cu" "In10.Cu" "In11.Cu" "In12.Cu" "In13.Cu" "In14.Cu"
			"In15.Cu" "In16.Cu"
		)
		(hatch none 0.5)
		(connect_pads
			(clearance 0)
		)
		(min_thickness 0.25)
		(keepout
			(tracks not_allowed)
			(vias allowed)
			(pads allowed)
			(copperpour not_allowed)
			(footprints allowed)
		)
		(placement
			(enabled no)
			(sheetname "")
		)
		(fill
			(thermal_gap 0.5)
			(thermal_bridge_width 0.5)
			(island_removal_mode 0)
		)
		(polygon
			(pts
				(arc
					(start 300.280832 -381.628904)
					(mid 300.295711 -381.592983)
					(end 300.331632 -381.578104)
				)
				(arc
					(start 301.047912 -381.578104)
					(mid 301.083833 -381.592983)
					(end 301.098712 -381.628904)
				)
				(arc
					(start 301.098712 -384.051556)
					(mid 301.083833 -384.087477)
					(end 301.047912 -384.102356)
				)
				(arc
					(start 300.331632 -384.102356)
					(mid 300.295711 -384.087477)
					(end 300.280832 -384.051556)
				)
			)
		)
	)
	(zone
		(layers "F.Cu" "B.Cu" "In1.Cu" "In2.Cu" "In3.Cu" "In4.Cu" "In5.Cu" "In6.Cu"
			"In7.Cu" "In8.Cu" "In9.Cu" "In10.Cu" "In11.Cu" "In12.Cu" "In13.Cu" "In14.Cu"
			"In15.Cu" "In16.Cu"
		)
		(hatch none 0.5)
		(connect_pads
			(clearance 0)
		)
		(min_thickness 0.25)
		(keepout
			(tracks not_allowed)
			(vias allowed)
			(pads allowed)
			(copperpour not_allowed)
			(footprints allowed)
		)
		(placement
			(enabled no)
			(sheetname "")
		)
		(fill
			(thermal_gap 0.5)
			(thermal_bridge_width 0.5)
			(island_removal_mode 0)
		)
		(polygon
			(pts
				(arc
					(start 333.28102 -397.028924)
					(mid 333.295899 -396.993003)
					(end 333.33182 -396.978124)
				)
				(arc
					(start 334.0481 -396.978124)
					(mid 334.084021 -396.993003)
					(end 334.0989 -397.028924)
				)
				(arc
					(start 334.0989 -399.451576)
					(mid 334.084021 -399.487497)
					(end 334.0481 -399.502376)
				)
				(arc
					(start 333.33182 -399.502376)
					(mid 333.295899 -399.487497)
					(end 333.28102 -399.451576)
				)
			)
		)
	)
	(zone
		(layers "F.Cu" "B.Cu" "In1.Cu" "In2.Cu" "In3.Cu" "In4.Cu" "In5.Cu" "In6.Cu"
			"In7.Cu" "In8.Cu" "In9.Cu" "In10.Cu" "In11.Cu" "In12.Cu" "In13.Cu" "In14.Cu"
			"In15.Cu" "In16.Cu"
		)
		(hatch none 0.5)
		(connect_pads
			(clearance 0)
		)
		(min_thickness 0.25)
		(keepout
			(tracks not_allowed)
			(vias allowed)
			(pads allowed)
			(copperpour not_allowed)
			(footprints allowed)
		)
		(placement
			(enabled no)
			(sheetname "")
		)
		(fill
			(thermal_gap 0.5)
			(thermal_bridge_width 0.5)
			(island_removal_mode 0)
		)
		(polygon
			(pts
				(arc
					(start 331.156564 -345.084146)
					(mid 330.775564 -345.465146)
					(end 331.156564 -345.846146)
				)
				(arc
					(start 332.020164 -345.846146)
					(mid 332.401164 -345.465146)
					(end 332.020164 -345.084146)
				)
			)
		)
	)
	(zone
		(layers "F.Cu" "B.Cu" "In1.Cu" "In2.Cu" "In3.Cu" "In4.Cu" "In5.Cu" "In6.Cu"
			"In7.Cu" "In8.Cu" "In9.Cu" "In10.Cu" "In11.Cu" "In12.Cu" "In13.Cu" "In14.Cu"
			"In15.Cu" "In16.Cu"
		)
		(hatch none 0.5)
		(connect_pads
			(clearance 0)
		)
		(min_thickness 0.25)
		(keepout
			(tracks not_allowed)
			(vias allowed)
			(pads allowed)
			(copperpour not_allowed)
			(footprints allowed)
		)
		(placement
			(enabled no)
			(sheetname "")
		)
		(fill
			(thermal_gap 0.5)
			(thermal_bridge_width 0.5)
			(island_removal_mode 0)
		)
		(polygon
			(pts
				(arc
					(start 174.621952 -357.37673)
					(mid 174.240952 -357.75773)
					(end 174.621952 -358.13873)
				)
				(arc
					(start 175.485552 -358.13873)
					(mid 175.866552 -357.75773)
					(end 175.485552 -357.37673)
				)
			)
		)
	)
	(zone
		(layers "F.Cu" "B.Cu" "In1.Cu" "In2.Cu" "In3.Cu" "In4.Cu" "In5.Cu" "In6.Cu"
			"In7.Cu" "In8.Cu" "In9.Cu" "In10.Cu" "In11.Cu" "In12.Cu" "In13.Cu" "In14.Cu"
			"In15.Cu" "In16.Cu"
		)
		(hatch none 0.5)
		(connect_pads
			(clearance 0)
		)
		(min_thickness 0.25)
		(keepout
			(tracks not_allowed)
			(vias allowed)
			(pads allowed)
			(copperpour not_allowed)
			(footprints allowed)
		)
		(placement
			(enabled no)
			(sheetname "")
		)
		(fill
			(thermal_gap 0.5)
			(thermal_bridge_width 0.5)
			(island_removal_mode 0)
		)
		(polygon
			(pts
				(arc
					(start 163.590224 -30.92069)
					(mid 164.047424 -31.37789)
					(end 164.504624 -30.92069)
				)
				(arc
					(start 164.504624 -30.05709)
					(mid 164.047424 -29.59989)
					(end 163.590224 -30.05709)
				)
			)
		)
	)
	(zone
		(layers "F.Cu" "B.Cu" "In1.Cu" "In2.Cu" "In3.Cu" "In4.Cu" "In5.Cu" "In6.Cu"
			"In7.Cu" "In8.Cu" "In9.Cu" "In10.Cu" "In11.Cu" "In12.Cu" "In13.Cu" "In14.Cu"
			"In15.Cu" "In16.Cu"
		)
		(hatch none 0.5)
		(connect_pads
			(clearance 0)
		)
		(min_thickness 0.25)
		(keepout
			(tracks not_allowed)
			(vias allowed)
			(pads allowed)
			(copperpour not_allowed)
			(footprints allowed)
		)
		(placement
			(enabled no)
			(sheetname "")
		)
		(fill
			(thermal_gap 0.5)
			(thermal_bridge_width 0.5)
			(island_removal_mode 0)
		)
		(polygon
			(pts
				(arc
					(start 9.09955 -371.613684)
					(mid 8.64235 -372.070884)
					(end 9.09955 -372.528084)
				)
				(arc
					(start 9.96315 -372.528084)
					(mid 10.42035 -372.070884)
					(end 9.96315 -371.613684)
				)
			)
		)
	)
	(zone
		(layers "F.Cu" "B.Cu" "In1.Cu" "In2.Cu" "In3.Cu" "In4.Cu" "In5.Cu" "In6.Cu"
			"In7.Cu" "In8.Cu" "In9.Cu" "In10.Cu" "In11.Cu" "In12.Cu" "In13.Cu" "In14.Cu"
			"In15.Cu" "In16.Cu"
		)
		(hatch none 0.5)
		(connect_pads
			(clearance 0)
		)
		(min_thickness 0.25)
		(keepout
			(tracks not_allowed)
			(vias allowed)
			(pads allowed)
			(copperpour not_allowed)
			(footprints allowed)
		)
		(placement
			(enabled no)
			(sheetname "")
		)
		(fill
			(thermal_gap 0.5)
			(thermal_bridge_width 0.5)
			(island_removal_mode 0)
		)
		(polygon
			(pts
				(arc
					(start 153.410666 -103.777796)
					(mid 153.867866 -104.234996)
					(end 154.325066 -103.777796)
				)
				(arc
					(start 154.325066 -102.914196)
					(mid 153.867866 -102.456996)
					(end 153.410666 -102.914196)
				)
			)
		)
	)
	(zone
		(layers "F.Cu" "B.Cu" "In1.Cu" "In2.Cu" "In3.Cu" "In4.Cu" "In5.Cu" "In6.Cu"
			"In7.Cu" "In8.Cu" "In9.Cu" "In10.Cu" "In11.Cu" "In12.Cu" "In13.Cu" "In14.Cu"
			"In15.Cu" "In16.Cu"
		)
		(hatch none 0.5)
		(connect_pads
			(clearance 0)
		)
		(min_thickness 0.25)
		(keepout
			(tracks not_allowed)
			(vias allowed)
			(pads allowed)
			(copperpour not_allowed)
			(footprints allowed)
		)
		(placement
			(enabled no)
			(sheetname "")
		)
		(fill
			(thermal_gap 0.5)
			(thermal_bridge_width 0.5)
			(island_removal_mode 0)
		)
		(polygon
			(pts
				(arc
					(start 346.481146 -378.828554)
					(mid 346.496025 -378.792633)
					(end 346.531946 -378.777754)
				)
				(arc
					(start 347.248226 -378.777754)
					(mid 347.284147 -378.792633)
					(end 347.299026 -378.828554)
				)
				(arc
					(start 347.299026 -381.251206)
					(mid 347.284147 -381.287127)
					(end 347.248226 -381.302006)
				)
				(arc
					(start 346.531946 -381.302006)
					(mid 346.496025 -381.287127)
					(end 346.481146 -381.251206)
				)
			)
		)
	)
	(zone
		(layers "F.Cu" "B.Cu" "In1.Cu" "In2.Cu" "In3.Cu" "In4.Cu" "In5.Cu" "In6.Cu"
			"In7.Cu" "In8.Cu" "In9.Cu" "In10.Cu" "In11.Cu" "In12.Cu" "In13.Cu" "In14.Cu"
			"In15.Cu" "In16.Cu"
		)
		(hatch none 0.5)
		(connect_pads
			(clearance 0)
		)
		(min_thickness 0.25)
		(keepout
			(tracks not_allowed)
			(vias allowed)
			(pads allowed)
			(copperpour not_allowed)
			(footprints allowed)
		)
		(placement
			(enabled no)
			(sheetname "")
		)
		(fill
			(thermal_gap 0.5)
			(thermal_bridge_width 0.5)
			(island_removal_mode 0)
		)
		(polygon
			(pts
				(arc
					(start 177.730912 -351.230438)
					(mid 177.349912 -351.611438)
					(end 177.730912 -351.992438)
				)
				(arc
					(start 178.594512 -351.992438)
					(mid 178.975512 -351.611438)
					(end 178.594512 -351.230438)
				)
			)
		)
	)
	(zone
		(layers "F.Cu" "B.Cu" "In1.Cu" "In2.Cu" "In3.Cu" "In4.Cu" "In5.Cu" "In6.Cu"
			"In7.Cu" "In8.Cu" "In9.Cu" "In10.Cu" "In11.Cu" "In12.Cu" "In13.Cu" "In14.Cu"
			"In15.Cu" "In16.Cu"
		)
		(hatch none 0.5)
		(connect_pads
			(clearance 0)
		)
		(min_thickness 0.25)
		(keepout
			(tracks not_allowed)
			(vias allowed)
			(pads allowed)
			(copperpour not_allowed)
			(footprints allowed)
		)
		(placement
			(enabled no)
			(sheetname "")
		)
		(fill
			(thermal_gap 0.5)
			(thermal_bridge_width 0.5)
			(island_removal_mode 0)
		)
		(polygon
			(pts
				(arc
					(start 115.501166 -407.628852)
					(mid 115.516045 -407.592931)
					(end 115.551966 -407.578052)
				)
				(arc
					(start 116.268246 -407.578052)
					(mid 116.304167 -407.592931)
					(end 116.319046 -407.628852)
				)
				(arc
					(start 116.319046 -410.051504)
					(mid 116.304167 -410.087425)
					(end 116.268246 -410.102304)
				)
				(arc
					(start 115.551966 -410.102304)
					(mid 115.516045 -410.087425)
					(end 115.501166 -410.051504)
				)
			)
		)
	)
	(zone
		(layers "F.Cu" "B.Cu" "In1.Cu" "In2.Cu" "In3.Cu" "In4.Cu" "In5.Cu" "In6.Cu"
			"In7.Cu" "In8.Cu" "In9.Cu" "In10.Cu" "In11.Cu" "In12.Cu" "In13.Cu" "In14.Cu"
			"In15.Cu" "In16.Cu"
		)
		(hatch none 0.5)
		(connect_pads
			(clearance 0)
		)
		(min_thickness 0.25)
		(keepout
			(tracks not_allowed)
			(vias allowed)
			(pads allowed)
			(copperpour not_allowed)
			(footprints allowed)
		)
		(placement
			(enabled no)
			(sheetname "")
		)
		(fill
			(thermal_gap 0.5)
			(thermal_bridge_width 0.5)
			(island_removal_mode 0)
		)
		(polygon
			(pts
				(arc
					(start 284.899862 -108.312712)
					(mid 284.442662 -107.855512)
					(end 283.985462 -108.312712)
				)
				(arc
					(start 283.985462 -109.176312)
					(mid 284.442662 -109.633512)
					(end 284.899862 -109.176312)
				)
			)
		)
	)
	(zone
		(layers "F.Cu" "B.Cu" "In1.Cu" "In2.Cu" "In3.Cu" "In4.Cu" "In5.Cu" "In6.Cu"
			"In7.Cu" "In8.Cu" "In9.Cu" "In10.Cu" "In11.Cu" "In12.Cu" "In13.Cu" "In14.Cu"
			"In15.Cu" "In16.Cu"
		)
		(hatch none 0.5)
		(connect_pads
			(clearance 0)
		)
		(min_thickness 0.25)
		(keepout
			(tracks not_allowed)
			(vias allowed)
			(pads allowed)
			(copperpour not_allowed)
			(footprints allowed)
		)
		(placement
			(enabled no)
			(sheetname "")
		)
		(fill
			(thermal_gap 0.5)
			(thermal_bridge_width 0.5)
			(island_removal_mode 0)
		)
		(polygon
			(pts
				(arc
					(start 416.82416 -27.342846)
					(mid 417.28136 -27.800046)
					(end 417.73856 -27.342846)
				)
				(arc
					(start 417.73856 -26.479246)
					(mid 417.28136 -26.022046)
					(end 416.82416 -26.479246)
				)
			)
		)
	)
	(zone
		(layers "F.Cu" "B.Cu" "In1.Cu" "In2.Cu" "In3.Cu" "In4.Cu" "In5.Cu" "In6.Cu"
			"In7.Cu" "In8.Cu" "In9.Cu" "In10.Cu" "In11.Cu" "In12.Cu" "In13.Cu" "In14.Cu"
			"In15.Cu" "In16.Cu"
		)
		(hatch none 0.5)
		(connect_pads
			(clearance 0)
		)
		(min_thickness 0.25)
		(keepout
			(tracks not_allowed)
			(vias allowed)
			(pads allowed)
			(copperpour not_allowed)
			(footprints allowed)
		)
		(placement
			(enabled no)
			(sheetname "")
		)
		(fill
			(thermal_gap 0.5)
			(thermal_bridge_width 0.5)
			(island_removal_mode 0)
		)
		(polygon
			(pts
				(arc
					(start 50.422048 -354.351082)
					(mid 50.041048 -354.732082)
					(end 50.422048 -355.113082)
				)
				(arc
					(start 51.285648 -355.113082)
					(mid 51.666648 -354.732082)
					(end 51.285648 -354.351082)
				)
			)
		)
	)
	(zone
		(layers "F.Cu" "B.Cu" "In1.Cu" "In2.Cu" "In3.Cu" "In4.Cu" "In5.Cu" "In6.Cu"
			"In7.Cu" "In8.Cu" "In9.Cu" "In10.Cu" "In11.Cu" "In12.Cu" "In13.Cu" "In14.Cu"
			"In15.Cu" "In16.Cu"
		)
		(hatch none 0.5)
		(connect_pads
			(clearance 0)
		)
		(min_thickness 0.25)
		(keepout
			(tracks not_allowed)
			(vias allowed)
			(pads allowed)
			(copperpour not_allowed)
			(footprints allowed)
		)
		(placement
			(enabled no)
			(sheetname "")
		)
		(fill
			(thermal_gap 0.5)
			(thermal_bridge_width 0.5)
			(island_removal_mode 0)
		)
		(polygon
			(pts
				(arc
					(start 389.84174 -351.230438)
					(mid 389.46074 -351.611438)
					(end 389.84174 -351.992438)
				)
				(arc
					(start 390.70534 -351.992438)
					(mid 391.08634 -351.611438)
					(end 390.70534 -351.230438)
				)
			)
		)
	)
	(zone
		(layers "F.Cu" "B.Cu" "In1.Cu" "In2.Cu" "In3.Cu" "In4.Cu" "In5.Cu" "In6.Cu"
			"In7.Cu" "In8.Cu" "In9.Cu" "In10.Cu" "In11.Cu" "In12.Cu" "In13.Cu" "In14.Cu"
			"In15.Cu" "In16.Cu"
		)
		(hatch none 0.5)
		(connect_pads
			(clearance 0)
		)
		(min_thickness 0.25)
		(keepout
			(tracks not_allowed)
			(vias allowed)
			(pads allowed)
			(copperpour not_allowed)
			(footprints allowed)
		)
		(placement
			(enabled no)
			(sheetname "")
		)
		(fill
			(thermal_gap 0.5)
			(thermal_bridge_width 0.5)
			(island_removal_mode 0)
		)
		(polygon
			(pts
				(arc
					(start 256.827782 -341.196422)
					(mid 256.370582 -340.739222)
					(end 255.913382 -341.196422)
				)
				(arc
					(start 255.913382 -342.060022)
					(mid 256.370582 -342.517222)
					(end 256.827782 -342.060022)
				)
			)
		)
	)
	(zone
		(layers "F.Cu" "B.Cu" "In1.Cu" "In2.Cu" "In3.Cu" "In4.Cu" "In5.Cu" "In6.Cu"
			"In7.Cu" "In8.Cu" "In9.Cu" "In10.Cu" "In11.Cu" "In12.Cu" "In13.Cu" "In14.Cu"
			"In15.Cu" "In16.Cu"
		)
		(hatch none 0.5)
		(connect_pads
			(clearance 0)
		)
		(min_thickness 0.25)
		(keepout
			(tracks not_allowed)
			(vias allowed)
			(pads allowed)
			(copperpour not_allowed)
			(footprints allowed)
		)
		(placement
			(enabled no)
			(sheetname "")
		)
		(fill
			(thermal_gap 0.5)
			(thermal_bridge_width 0.5)
			(island_removal_mode 0)
		)
		(polygon
			(pts
				(arc
					(start 89.100914 -395.92885)
					(mid 89.115793 -395.892929)
					(end 89.151714 -395.87805)
				)
				(arc
					(start 89.867994 -395.87805)
					(mid 89.903915 -395.892929)
					(end 89.918794 -395.92885)
				)
				(arc
					(start 89.918794 -398.351502)
					(mid 89.903915 -398.387423)
					(end 89.867994 -398.402302)
				)
				(arc
					(start 89.151714 -398.402302)
					(mid 89.115793 -398.387423)
					(end 89.100914 -398.351502)
				)
			)
		)
	)
	(zone
		(layers "F.Cu" "B.Cu" "In1.Cu" "In2.Cu" "In3.Cu" "In4.Cu" "In5.Cu" "In6.Cu"
			"In7.Cu" "In8.Cu" "In9.Cu" "In10.Cu" "In11.Cu" "In12.Cu" "In13.Cu" "In14.Cu"
			"In15.Cu" "In16.Cu"
		)
		(hatch none 0.5)
		(connect_pads
			(clearance 0)
		)
		(min_thickness 0.25)
		(keepout
			(tracks not_allowed)
			(vias allowed)
			(pads allowed)
			(copperpour not_allowed)
			(footprints allowed)
		)
		(placement
			(enabled no)
			(sheetname "")
		)
		(fill
			(thermal_gap 0.5)
			(thermal_bridge_width 0.5)
			(island_removal_mode 0)
		)
		(polygon
			(pts
				(arc
					(start 183.948832 -351.230438)
					(mid 183.567832 -351.611438)
					(end 183.948832 -351.992438)
				)
				(arc
					(start 184.812432 -351.992438)
					(mid 185.193432 -351.611438)
					(end 184.812432 -351.230438)
				)
			)
		)
	)
	(zone
		(layers "F.Cu" "B.Cu" "In1.Cu" "In2.Cu" "In3.Cu" "In4.Cu" "In5.Cu" "In6.Cu"
			"In7.Cu" "In8.Cu" "In9.Cu" "In10.Cu" "In11.Cu" "In12.Cu" "In13.Cu" "In14.Cu"
			"In15.Cu" "In16.Cu"
		)
		(hatch none 0.5)
		(connect_pads
			(clearance 0)
		)
		(min_thickness 0.25)
		(keepout
			(tracks not_allowed)
			(vias allowed)
			(pads allowed)
			(copperpour not_allowed)
			(footprints allowed)
		)
		(placement
			(enabled no)
			(sheetname "")
		)
		(fill
			(thermal_gap 0.5)
			(thermal_bridge_width 0.5)
			(island_removal_mode 0)
		)
		(polygon
			(pts
				(arc
					(start 34.66846 -131.297934)
					(mid 35.12566 -131.755134)
					(end 35.58286 -131.297934)
				)
				(arc
					(start 35.58286 -130.434334)
					(mid 35.12566 -129.977134)
					(end 34.66846 -130.434334)
				)
			)
		)
	)
	(zone
		(layers "F.Cu" "B.Cu" "In1.Cu" "In2.Cu" "In3.Cu" "In4.Cu" "In5.Cu" "In6.Cu"
			"In7.Cu" "In8.Cu" "In9.Cu" "In10.Cu" "In11.Cu" "In12.Cu" "In13.Cu" "In14.Cu"
			"In15.Cu" "In16.Cu"
		)
		(hatch none 0.5)
		(connect_pads
			(clearance 0)
		)
		(min_thickness 0.25)
		(keepout
			(tracks not_allowed)
			(vias allowed)
			(pads allowed)
			(copperpour not_allowed)
			(footprints allowed)
		)
		(placement
			(enabled no)
			(sheetname "")
		)
		(fill
			(thermal_gap 0.5)
			(thermal_bridge_width 0.5)
			(island_removal_mode 0)
		)
		(polygon
			(pts
				(arc
					(start 78.100936 -374.928638)
					(mid 78.115815 -374.892717)
					(end 78.151736 -374.877838)
				)
				(arc
					(start 78.868016 -374.877838)
					(mid 78.903937 -374.892717)
					(end 78.918816 -374.928638)
				)
				(arc
					(start 78.918816 -377.35129)
					(mid 78.903937 -377.387211)
					(end 78.868016 -377.40209)
				)
				(arc
					(start 78.151736 -377.40209)
					(mid 78.115815 -377.387211)
					(end 78.100936 -377.35129)
				)
			)
		)
	)
	(zone
		(layers "F.Cu" "B.Cu" "In1.Cu" "In2.Cu" "In3.Cu" "In4.Cu" "In5.Cu" "In6.Cu"
			"In7.Cu" "In8.Cu" "In9.Cu" "In10.Cu" "In11.Cu" "In12.Cu" "In13.Cu" "In14.Cu"
			"In15.Cu" "In16.Cu"
		)
		(hatch none 0.5)
		(connect_pads
			(clearance 0)
		)
		(min_thickness 0.25)
		(keepout
			(tracks not_allowed)
			(vias allowed)
			(pads allowed)
			(copperpour not_allowed)
			(footprints allowed)
		)
		(placement
			(enabled no)
			(sheetname "")
		)
		(fill
			(thermal_gap 0.5)
			(thermal_bridge_width 0.5)
			(island_removal_mode 0)
		)
		(polygon
			(pts
				(arc
					(start 431.057812 -342.058498)
					(mid 430.676812 -342.439498)
					(end 431.057812 -342.820498)
				)
				(arc
					(start 431.921412 -342.820498)
					(mid 432.302412 -342.439498)
					(end 431.921412 -342.058498)
				)
			)
		)
	)
	(zone
		(layers "F.Cu" "B.Cu" "In1.Cu" "In2.Cu" "In3.Cu" "In4.Cu" "In5.Cu" "In6.Cu"
			"In7.Cu" "In8.Cu" "In9.Cu" "In10.Cu" "In11.Cu" "In12.Cu" "In13.Cu" "In14.Cu"
			"In15.Cu" "In16.Cu"
		)
		(hatch none 0.5)
		(connect_pads
			(clearance 0)
		)
		(min_thickness 0.25)
		(keepout
			(tracks not_allowed)
			(vias allowed)
			(pads allowed)
			(copperpour not_allowed)
			(footprints allowed)
		)
		(placement
			(enabled no)
			(sheetname "")
		)
		(fill
			(thermal_gap 0.5)
			(thermal_bridge_width 0.5)
			(island_removal_mode 0)
		)
		(polygon
			(pts
				(arc
					(start 99.490022 -34.520886)
					(mid 99.947222 -34.978086)
					(end 100.404422 -34.520886)
				)
				(arc
					(start 100.404422 -33.657286)
					(mid 99.947222 -33.200086)
					(end 99.490022 -33.657286)
				)
			)
		)
	)
	(zone
		(layers "F.Cu" "B.Cu" "In1.Cu" "In2.Cu" "In3.Cu" "In4.Cu" "In5.Cu" "In6.Cu"
			"In7.Cu" "In8.Cu" "In9.Cu" "In10.Cu" "In11.Cu" "In12.Cu" "In13.Cu" "In14.Cu"
			"In15.Cu" "In16.Cu"
		)
		(hatch none 0.5)
		(connect_pads
			(clearance 0)
		)
		(min_thickness 0.25)
		(keepout
			(tracks not_allowed)
			(vias allowed)
			(pads allowed)
			(copperpour not_allowed)
			(footprints allowed)
		)
		(placement
			(enabled no)
			(sheetname "")
		)
		(fill
			(thermal_gap 0.5)
			(thermal_bridge_width 0.5)
			(island_removal_mode 0)
		)
		(polygon
			(pts
				(arc
					(start 170.654218 -102.912672)
					(mid 170.197018 -102.455472)
					(end 169.739818 -102.912672)
				)
				(arc
					(start 169.739818 -103.776272)
					(mid 170.197018 -104.233472)
					(end 170.654218 -103.776272)
				)
			)
		)
	)
	(zone
		(layers "F.Cu" "B.Cu" "In1.Cu" "In2.Cu" "In3.Cu" "In4.Cu" "In5.Cu" "In6.Cu"
			"In7.Cu" "In8.Cu" "In9.Cu" "In10.Cu" "In11.Cu" "In12.Cu" "In13.Cu" "In14.Cu"
			"In15.Cu" "In16.Cu"
		)
		(hatch none 0.5)
		(connect_pads
			(clearance 0)
		)
		(min_thickness 0.25)
		(keepout
			(tracks not_allowed)
			(vias allowed)
			(pads allowed)
			(copperpour not_allowed)
			(footprints allowed)
		)
		(placement
			(enabled no)
			(sheetname "")
		)
		(fill
			(thermal_gap 0.5)
			(thermal_bridge_width 0.5)
			(island_removal_mode 0)
		)
		(polygon
			(pts
				(arc
					(start 73.808082 -345.084146)
					(mid 73.427082 -345.465146)
					(end 73.808082 -345.846146)
				)
				(arc
					(start 74.671682 -345.846146)
					(mid 75.052682 -345.465146)
					(end 74.671682 -345.084146)
				)
			)
		)
	)
	(zone
		(layers "F.Cu" "B.Cu" "In1.Cu" "In2.Cu" "In3.Cu" "In4.Cu" "In5.Cu" "In6.Cu"
			"In7.Cu" "In8.Cu" "In9.Cu" "In10.Cu" "In11.Cu" "In12.Cu" "In13.Cu" "In14.Cu"
			"In15.Cu" "In16.Cu"
		)
		(hatch none 0.5)
		(connect_pads
			(clearance 0)
		)
		(min_thickness 0.25)
		(keepout
			(tracks not_allowed)
			(vias allowed)
			(pads allowed)
			(copperpour not_allowed)
			(footprints allowed)
		)
		(placement
			(enabled no)
			(sheetname "")
		)
		(fill
			(thermal_gap 0.5)
			(thermal_bridge_width 0.5)
			(island_removal_mode 0)
		)
		(polygon
			(pts
				(arc
					(start 437.275732 -342.058498)
					(mid 436.894732 -342.439498)
					(end 437.275732 -342.820498)
				)
				(arc
					(start 438.139332 -342.820498)
					(mid 438.520332 -342.439498)
					(end 438.139332 -342.058498)
				)
			)
		)
	)
	(zone
		(layers "F.Cu" "B.Cu" "In1.Cu" "In2.Cu" "In3.Cu" "In4.Cu" "In5.Cu" "In6.Cu"
			"In7.Cu" "In8.Cu" "In9.Cu" "In10.Cu" "In11.Cu" "In12.Cu" "In13.Cu" "In14.Cu"
			"In15.Cu" "In16.Cu"
		)
		(hatch none 0.5)
		(connect_pads
			(clearance 0)
		)
		(min_thickness 0.25)
		(keepout
			(tracks not_allowed)
			(vias allowed)
			(pads allowed)
			(copperpour not_allowed)
			(footprints allowed)
		)
		(placement
			(enabled no)
			(sheetname "")
		)
		(fill
			(thermal_gap 0.5)
			(thermal_bridge_width 0.5)
			(island_removal_mode 0)
		)
		(polygon
			(pts
				(arc
					(start 168.404032 -354.351082)
					(mid 168.023032 -354.732082)
					(end 168.404032 -355.113082)
				)
				(arc
					(start 169.267632 -355.113082)
					(mid 169.648632 -354.732082)
					(end 169.267632 -354.351082)
				)
			)
		)
	)
	(zone
		(layers "F.Cu" "B.Cu" "In1.Cu" "In2.Cu" "In3.Cu" "In4.Cu" "In5.Cu" "In6.Cu"
			"In7.Cu" "In8.Cu" "In9.Cu" "In10.Cu" "In11.Cu" "In12.Cu" "In13.Cu" "In14.Cu"
			"In15.Cu" "In16.Cu"
		)
		(hatch none 0.5)
		(connect_pads
			(clearance 0)
		)
		(min_thickness 0.25)
		(keepout
			(tracks not_allowed)
			(vias allowed)
			(pads allowed)
			(copperpour not_allowed)
			(footprints allowed)
		)
		(placement
			(enabled no)
			(sheetname "")
		)
		(fill
			(thermal_gap 0.5)
			(thermal_bridge_width 0.5)
			(island_removal_mode 0)
		)
		(polygon
			(pts
				(arc
					(start 326.72401 -27.342846)
					(mid 327.18121 -27.800046)
					(end 327.63841 -27.342846)
				)
				(arc
					(start 327.63841 -26.479246)
					(mid 327.18121 -26.022046)
					(end 326.72401 -26.479246)
				)
			)
		)
	)
	(zone
		(layers "F.Cu" "B.Cu" "In1.Cu" "In2.Cu" "In3.Cu" "In4.Cu" "In5.Cu" "In6.Cu"
			"In7.Cu" "In8.Cu" "In9.Cu" "In10.Cu" "In11.Cu" "In12.Cu" "In13.Cu" "In14.Cu"
			"In15.Cu" "In16.Cu"
		)
		(hatch none 0.5)
		(connect_pads
			(clearance 0)
		)
		(min_thickness 0.25)
		(keepout
			(tracks not_allowed)
			(vias allowed)
			(pads allowed)
			(copperpour not_allowed)
			(footprints allowed)
		)
		(placement
			(enabled no)
			(sheetname "")
		)
		(fill
			(thermal_gap 0.5)
			(thermal_bridge_width 0.5)
			(island_removal_mode 0)
		)
		(polygon
			(pts
				(arc
					(start 424.839892 -351.230438)
					(mid 424.458892 -351.611438)
					(end 424.839892 -351.992438)
				)
				(arc
					(start 425.703492 -351.992438)
					(mid 426.084492 -351.611438)
					(end 425.703492 -351.230438)
				)
			)
		)
	)
	(zone
		(layers "F.Cu" "B.Cu" "In1.Cu" "In2.Cu" "In3.Cu" "In4.Cu" "In5.Cu" "In6.Cu"
			"In7.Cu" "In8.Cu" "In9.Cu" "In10.Cu" "In11.Cu" "In12.Cu" "In13.Cu" "In14.Cu"
			"In15.Cu" "In16.Cu"
		)
		(hatch none 0.5)
		(connect_pads
			(clearance 0)
		)
		(min_thickness 0.25)
		(keepout
			(tracks not_allowed)
			(vias allowed)
			(pads allowed)
			(copperpour not_allowed)
			(footprints allowed)
		)
		(placement
			(enabled no)
			(sheetname "")
		)
		(fill
			(thermal_gap 0.5)
			(thermal_bridge_width 0.5)
			(island_removal_mode 0)
		)
		(polygon
			(pts
				(arc
					(start 27.501088 -407.628852)
					(mid 27.515967 -407.592931)
					(end 27.551888 -407.578052)
				)
				(arc
					(start 28.268168 -407.578052)
					(mid 28.304089 -407.592931)
					(end 28.318968 -407.628852)
				)
				(arc
					(start 28.318968 -410.051504)
					(mid 28.304089 -410.087425)
					(end 28.268168 -410.102304)
				)
				(arc
					(start 27.551888 -410.102304)
					(mid 27.515967 -410.087425)
					(end 27.501088 -410.051504)
				)
			)
		)
	)
	(zone
		(layers "F.Cu" "B.Cu" "In1.Cu" "In2.Cu" "In3.Cu" "In4.Cu" "In5.Cu" "In6.Cu"
			"In7.Cu" "In8.Cu" "In9.Cu" "In10.Cu" "In11.Cu" "In12.Cu" "In13.Cu" "In14.Cu"
			"In15.Cu" "In16.Cu"
		)
		(hatch none 0.5)
		(connect_pads
			(clearance 0)
		)
		(min_thickness 0.25)
		(keepout
			(tracks not_allowed)
			(vias allowed)
			(pads allowed)
			(copperpour not_allowed)
			(footprints allowed)
		)
		(placement
			(enabled no)
			(sheetname "")
		)
		(fill
			(thermal_gap 0.5)
			(thermal_bridge_width 0.5)
			(island_removal_mode 0)
		)
		(polygon
			(pts
				(arc
					(start 172.70095 -381.628904)
					(mid 172.715829 -381.592983)
					(end 172.75175 -381.578104)
				)
				(arc
					(start 173.46803 -381.578104)
					(mid 173.503951 -381.592983)
					(end 173.51883 -381.628904)
				)
				(arc
					(start 173.51883 -384.051556)
					(mid 173.503951 -384.087477)
					(end 173.46803 -384.102356)
				)
				(arc
					(start 172.75175 -384.102356)
					(mid 172.715829 -384.087477)
					(end 172.70095 -384.051556)
				)
			)
		)
	)
	(zone
		(layers "F.Cu" "B.Cu" "In1.Cu" "In2.Cu" "In3.Cu" "In4.Cu" "In5.Cu" "In6.Cu"
			"In7.Cu" "In8.Cu" "In9.Cu" "In10.Cu" "In11.Cu" "In12.Cu" "In13.Cu" "In14.Cu"
			"In15.Cu" "In16.Cu"
		)
		(hatch none 0.5)
		(connect_pads
			(clearance 0)
		)
		(min_thickness 0.25)
		(keepout
			(tracks not_allowed)
			(vias allowed)
			(pads allowed)
			(copperpour not_allowed)
			(footprints allowed)
		)
		(placement
			(enabled no)
			(sheetname "")
		)
		(fill
			(thermal_gap 0.5)
			(thermal_bridge_width 0.5)
			(island_removal_mode 0)
		)
		(polygon
			(pts
				(arc
					(start 80.026002 -348.20479)
					(mid 79.645002 -348.58579)
					(end 80.026002 -348.96679)
				)
				(arc
					(start 80.889602 -348.96679)
					(mid 81.270602 -348.58579)
					(end 80.889602 -348.20479)
				)
			)
		)
	)
	(zone
		(layers "F.Cu" "B.Cu" "In1.Cu" "In2.Cu" "In3.Cu" "In4.Cu" "In5.Cu" "In6.Cu"
			"In7.Cu" "In8.Cu" "In9.Cu" "In10.Cu" "In11.Cu" "In12.Cu" "In13.Cu" "In14.Cu"
			"In15.Cu" "In16.Cu"
		)
		(hatch none 0.5)
		(connect_pads
			(clearance 0)
		)
		(min_thickness 0.25)
		(keepout
			(tracks not_allowed)
			(vias allowed)
			(pads allowed)
			(copperpour not_allowed)
			(footprints allowed)
		)
		(placement
			(enabled no)
			(sheetname "")
		)
		(fill
			(thermal_gap 0.5)
			(thermal_bridge_width 0.5)
			(island_removal_mode 0)
		)
		(polygon
			(pts
				(arc
					(start 139.842748 -345.084146)
					(mid 139.461748 -345.465146)
					(end 139.842748 -345.846146)
				)
				(arc
					(start 140.706348 -345.846146)
					(mid 141.087348 -345.465146)
					(end 140.706348 -345.084146)
				)
			)
		)
	)
	(zone
		(layers "F.Cu" "B.Cu" "In1.Cu" "In2.Cu" "In3.Cu" "In4.Cu" "In5.Cu" "In6.Cu"
			"In7.Cu" "In8.Cu" "In9.Cu" "In10.Cu" "In11.Cu" "In12.Cu" "In13.Cu" "In14.Cu"
			"In15.Cu" "In16.Cu"
		)
		(hatch none 0.5)
		(connect_pads
			(clearance 0)
		)
		(min_thickness 0.25)
		(keepout
			(tracks not_allowed)
			(vias allowed)
			(pads allowed)
			(copperpour not_allowed)
			(footprints allowed)
		)
		(placement
			(enabled no)
			(sheetname "")
		)
		(fill
			(thermal_gap 0.5)
			(thermal_bridge_width 0.5)
			(island_removal_mode 0)
		)
		(polygon
			(pts
				(arc
					(start 337.681062 -371.028722)
					(mid 337.695941 -370.992801)
					(end 337.731862 -370.977922)
				)
				(arc
					(start 338.448142 -370.977922)
					(mid 338.484063 -370.992801)
					(end 338.498942 -371.028722)
				)
				(arc
					(start 338.498942 -373.451374)
					(mid 338.484063 -373.487295)
					(end 338.448142 -373.502174)
				)
				(arc
					(start 337.731862 -373.502174)
					(mid 337.695941 -373.487295)
					(end 337.681062 -373.451374)
				)
			)
		)
	)
	(zone
		(layers "F.Cu" "B.Cu" "In1.Cu" "In2.Cu" "In3.Cu" "In4.Cu" "In5.Cu" "In6.Cu"
			"In7.Cu" "In8.Cu" "In9.Cu" "In10.Cu" "In11.Cu" "In12.Cu" "In13.Cu" "In14.Cu"
			"In15.Cu" "In16.Cu"
		)
		(hatch none 0.5)
		(connect_pads
			(clearance 0)
		)
		(min_thickness 0.25)
		(keepout
			(tracks not_allowed)
			(vias allowed)
			(pads allowed)
			(copperpour not_allowed)
			(footprints allowed)
		)
		(placement
			(enabled no)
			(sheetname "")
		)
		(fill
			(thermal_gap 0.5)
			(thermal_bridge_width 0.5)
			(island_removal_mode 0)
		)
		(polygon
			(pts
				(arc
					(start 83.134962 -354.351082)
					(mid 82.753962 -354.732082)
					(end 83.134962 -355.113082)
				)
				(arc
					(start 83.998562 -355.113082)
					(mid 84.379562 -354.732082)
					(end 83.998562 -354.351082)
				)
			)
		)
	)
	(zone
		(layers "F.Cu" "B.Cu" "In1.Cu" "In2.Cu" "In3.Cu" "In4.Cu" "In5.Cu" "In6.Cu"
			"In7.Cu" "In8.Cu" "In9.Cu" "In10.Cu" "In11.Cu" "In12.Cu" "In13.Cu" "In14.Cu"
			"In15.Cu" "In16.Cu"
		)
		(hatch none 0.5)
		(connect_pads
			(clearance 0)
		)
		(min_thickness 0.25)
		(keepout
			(tracks not_allowed)
			(vias allowed)
			(pads allowed)
			(copperpour not_allowed)
			(footprints allowed)
		)
		(placement
			(enabled no)
			(sheetname "")
		)
		(fill
			(thermal_gap 0.5)
			(thermal_bridge_width 0.5)
			(island_removal_mode 0)
		)
		(polygon
			(pts
				(arc
					(start 422.07434 -95.214948)
					(mid 419.94074 -95.214948)
					(end 422.07434 -95.214948)
				)
			)
		)
	)
	(zone
		(layers "F.Cu" "B.Cu" "In1.Cu" "In2.Cu" "In3.Cu" "In4.Cu" "In5.Cu" "In6.Cu"
			"In7.Cu" "In8.Cu" "In9.Cu" "In10.Cu" "In11.Cu" "In12.Cu" "In13.Cu" "In14.Cu"
			"In15.Cu" "In16.Cu"
		)
		(hatch none 0.5)
		(connect_pads
			(clearance 0)
		)
		(min_thickness 0.25)
		(keepout
			(tracks not_allowed)
			(vias allowed)
			(pads allowed)
			(copperpour not_allowed)
			(footprints allowed)
		)
		(placement
			(enabled no)
			(sheetname "")
		)
		(fill
			(thermal_gap 0.5)
			(thermal_bridge_width 0.5)
			(island_removal_mode 0)
		)
		(polygon
			(pts
				(arc
					(start 197.17512 -123.159266)
					(mid 197.63232 -123.616466)
					(end 198.08952 -123.159266)
				)
				(arc
					(start 198.08952 -122.295666)
					(mid 197.63232 -121.838466)
					(end 197.17512 -122.295666)
				)
			)
		)
	)
	(zone
		(layers "F.Cu" "B.Cu" "In1.Cu" "In2.Cu" "In3.Cu" "In4.Cu" "In5.Cu" "In6.Cu"
			"In7.Cu" "In8.Cu" "In9.Cu" "In10.Cu" "In11.Cu" "In12.Cu" "In13.Cu" "In14.Cu"
			"In15.Cu" "In16.Cu"
		)
		(hatch none 0.5)
		(connect_pads
			(clearance 0)
		)
		(min_thickness 0.25)
		(keepout
			(tracks not_allowed)
			(vias allowed)
			(pads allowed)
			(copperpour not_allowed)
			(footprints allowed)
		)
		(placement
			(enabled no)
			(sheetname "")
		)
		(fill
			(thermal_gap 0.5)
			(thermal_bridge_width 0.5)
			(island_removal_mode 0)
		)
		(polygon
			(pts
				(arc
					(start 292.768782 -351.230438)
					(mid 292.387782 -351.611438)
					(end 292.768782 -351.992438)
				)
				(arc
					(start 293.632382 -351.992438)
					(mid 294.013382 -351.611438)
					(end 293.632382 -351.230438)
				)
			)
		)
	)
	(zone
		(layers "F.Cu" "B.Cu" "In1.Cu" "In2.Cu" "In3.Cu" "In4.Cu" "In5.Cu" "In6.Cu"
			"In7.Cu" "In8.Cu" "In9.Cu" "In10.Cu" "In11.Cu" "In12.Cu" "In13.Cu" "In14.Cu"
			"In15.Cu" "In16.Cu"
		)
		(hatch none 0.5)
		(connect_pads
			(clearance 0)
		)
		(min_thickness 0.25)
		(keepout
			(tracks not_allowed)
			(vias allowed)
			(pads allowed)
			(copperpour not_allowed)
			(footprints allowed)
		)
		(placement
			(enabled no)
			(sheetname "")
		)
		(fill
			(thermal_gap 0.5)
			(thermal_bridge_width 0.5)
			(island_removal_mode 0)
		)
		(polygon
			(pts
				(arc
					(start 287.08096 -399.828766)
					(mid 287.095839 -399.792845)
					(end 287.13176 -399.777966)
				)
				(arc
					(start 287.84804 -399.777966)
					(mid 287.883961 -399.792845)
					(end 287.89884 -399.828766)
				)
				(arc
					(start 287.89884 -402.251418)
					(mid 287.883961 -402.287339)
					(end 287.84804 -402.302218)
				)
				(arc
					(start 287.13176 -402.302218)
					(mid 287.095839 -402.287339)
					(end 287.08096 -402.251418)
				)
			)
		)
	)
	(zone
		(layers "F.Cu" "B.Cu" "In1.Cu" "In2.Cu" "In3.Cu" "In4.Cu" "In5.Cu" "In6.Cu"
			"In7.Cu" "In8.Cu" "In9.Cu" "In10.Cu" "In11.Cu" "In12.Cu" "In13.Cu" "In14.Cu"
			"In15.Cu" "In16.Cu"
		)
		(hatch none 0.5)
		(connect_pads
			(clearance 0)
		)
		(min_thickness 0.25)
		(keepout
			(tracks not_allowed)
			(vias allowed)
			(pads allowed)
			(copperpour not_allowed)
			(footprints allowed)
		)
		(placement
			(enabled no)
			(sheetname "")
		)
		(fill
			(thermal_gap 0.5)
			(thermal_bridge_width 0.5)
			(island_removal_mode 0)
		)
		(polygon
			(pts
				(arc
					(start 182.700168 -119.567198)
					(mid 183.157368 -120.024398)
					(end 183.614568 -119.567198)
				)
				(arc
					(start 183.614568 -118.703598)
					(mid 183.157368 -118.246398)
					(end 182.700168 -118.703598)
				)
			)
		)
	)
	(zone
		(layers "F.Cu" "B.Cu" "In1.Cu" "In2.Cu" "In3.Cu" "In4.Cu" "In5.Cu" "In6.Cu"
			"In7.Cu" "In8.Cu" "In9.Cu" "In10.Cu" "In11.Cu" "In12.Cu" "In13.Cu" "In14.Cu"
			"In15.Cu" "In16.Cu"
		)
		(hatch none 0.5)
		(connect_pads
			(clearance 0)
		)
		(min_thickness 0.25)
		(keepout
			(tracks not_allowed)
			(vias allowed)
			(pads allowed)
			(copperpour not_allowed)
			(footprints allowed)
		)
		(placement
			(enabled no)
			(sheetname "")
		)
		(fill
			(thermal_gap 0.5)
			(thermal_bridge_width 0.5)
			(island_removal_mode 0)
		)
		(polygon
			(pts
				(arc
					(start 128.701038 -381.628904)
					(mid 128.715917 -381.592983)
					(end 128.751838 -381.578104)
				)
				(arc
					(start 129.468118 -381.578104)
					(mid 129.504039 -381.592983)
					(end 129.518918 -381.628904)
				)
				(arc
					(start 129.518918 -384.051556)
					(mid 129.504039 -384.087477)
					(end 129.468118 -384.102356)
				)
				(arc
					(start 128.751838 -384.102356)
					(mid 128.715917 -384.087477)
					(end 128.701038 -384.051556)
				)
			)
		)
	)
	(zone
		(layers "F.Cu" "B.Cu" "In1.Cu" "In2.Cu" "In3.Cu" "In4.Cu" "In5.Cu" "In6.Cu"
			"In7.Cu" "In8.Cu" "In9.Cu" "In10.Cu" "In11.Cu" "In12.Cu" "In13.Cu" "In14.Cu"
			"In15.Cu" "In16.Cu"
		)
		(hatch none 0.5)
		(connect_pads
			(clearance 0)
		)
		(min_thickness 0.25)
		(keepout
			(tracks not_allowed)
			(vias allowed)
			(pads allowed)
			(copperpour not_allowed)
			(footprints allowed)
		)
		(placement
			(enabled no)
			(sheetname "")
		)
		(fill
			(thermal_gap 0.5)
			(thermal_bridge_width 0.5)
			(island_removal_mode 0)
		)
		(polygon
			(pts
				(arc
					(start 313.274964 -143.479266)
					(mid 313.732164 -143.936466)
					(end 314.189364 -143.479266)
				)
				(arc
					(start 314.189364 -142.615666)
					(mid 313.732164 -142.158466)
					(end 313.274964 -142.615666)
				)
			)
		)
	)
	(zone
		(layers "F.Cu" "B.Cu" "In1.Cu" "In2.Cu" "In3.Cu" "In4.Cu" "In5.Cu" "In6.Cu"
			"In7.Cu" "In8.Cu" "In9.Cu" "In10.Cu" "In11.Cu" "In12.Cu" "In13.Cu" "In14.Cu"
			"In15.Cu" "In16.Cu"
		)
		(hatch none 0.5)
		(connect_pads
			(clearance 0)
		)
		(min_thickness 0.25)
		(keepout
			(tracks not_allowed)
			(vias allowed)
			(pads allowed)
			(copperpour not_allowed)
			(footprints allowed)
		)
		(placement
			(enabled no)
			(sheetname "")
		)
		(fill
			(thermal_gap 0.5)
			(thermal_bridge_width 0.5)
			(island_removal_mode 0)
		)
		(polygon
			(pts
				(arc
					(start 153.410666 -107.377738)
					(mid 153.867866 -107.834938)
					(end 154.325066 -107.377738)
				)
				(arc
					(start 154.325066 -106.514138)
					(mid 153.867866 -106.056938)
					(end 153.410666 -106.514138)
				)
			)
		)
	)
	(zone
		(layers "F.Cu" "B.Cu" "In1.Cu" "In2.Cu" "In3.Cu" "In4.Cu" "In5.Cu" "In6.Cu"
			"In7.Cu" "In8.Cu" "In9.Cu" "In10.Cu" "In11.Cu" "In12.Cu" "In13.Cu" "In14.Cu"
			"In15.Cu" "In16.Cu"
		)
		(hatch none 0.5)
		(connect_pads
			(clearance 0)
		)
		(min_thickness 0.25)
		(keepout
			(tracks not_allowed)
			(vias allowed)
			(pads allowed)
			(copperpour not_allowed)
			(footprints allowed)
		)
		(placement
			(enabled no)
			(sheetname "")
		)
		(fill
			(thermal_gap 0.5)
			(thermal_bridge_width 0.5)
			(island_removal_mode 0)
		)
		(polygon
			(pts
				(arc
					(start 41.095168 -357.37673)
					(mid 40.714168 -357.75773)
					(end 41.095168 -358.13873)
				)
				(arc
					(start 41.958768 -358.13873)
					(mid 42.339768 -357.75773)
					(end 41.958768 -357.37673)
				)
			)
		)
	)
	(zone
		(layers "F.Cu" "B.Cu" "In1.Cu" "In2.Cu" "In3.Cu" "In4.Cu" "In5.Cu" "In6.Cu"
			"In7.Cu" "In8.Cu" "In9.Cu" "In10.Cu" "In11.Cu" "In12.Cu" "In13.Cu" "In14.Cu"
			"In15.Cu" "In16.Cu"
		)
		(hatch none 0.5)
		(connect_pads
			(clearance 0)
		)
		(min_thickness 0.25)
		(keepout
			(tracks not_allowed)
			(vias allowed)
			(pads allowed)
			(copperpour not_allowed)
			(footprints allowed)
		)
		(placement
			(enabled no)
			(sheetname "")
		)
		(fill
			(thermal_gap 0.5)
			(thermal_bridge_width 0.5)
			(island_removal_mode 0)
		)
		(polygon
			(pts
				(arc
					(start 231.015032 -157.433264)
					(mid 230.557832 -157.890464)
					(end 231.015032 -158.347664)
				)
				(arc
					(start 231.878632 -158.347664)
					(mid 232.335832 -157.890464)
					(end 231.878632 -157.433264)
				)
			)
		)
	)
	(zone
		(layers "F.Cu" "B.Cu" "In1.Cu" "In2.Cu" "In3.Cu" "In4.Cu" "In5.Cu" "In6.Cu"
			"In7.Cu" "In8.Cu" "In9.Cu" "In10.Cu" "In11.Cu" "In12.Cu" "In13.Cu" "In14.Cu"
			"In15.Cu" "In16.Cu"
		)
		(hatch none 0.5)
		(connect_pads
			(clearance 0)
		)
		(min_thickness 0.25)
		(keepout
			(tracks not_allowed)
			(vias allowed)
			(pads allowed)
			(copperpour not_allowed)
			(footprints allowed)
		)
		(placement
			(enabled no)
			(sheetname "")
		)
		(fill
			(thermal_gap 0.5)
			(thermal_bridge_width 0.5)
			(island_removal_mode 0)
		)
		(polygon
			(pts
				(arc
					(start 344.280998 -373.828818)
					(mid 344.295877 -373.792897)
					(end 344.331798 -373.778018)
				)
				(arc
					(start 345.048078 -373.778018)
					(mid 345.083999 -373.792897)
					(end 345.098878 -373.828818)
				)
				(arc
					(start 345.098878 -376.25147)
					(mid 345.083999 -376.287391)
					(end 345.048078 -376.30227)
				)
				(arc
					(start 344.331798 -376.30227)
					(mid 344.295877 -376.287391)
					(end 344.280998 -376.25147)
				)
			)
		)
	)
	(zone
		(layers "F.Cu" "B.Cu" "In1.Cu" "In2.Cu" "In3.Cu" "In4.Cu" "In5.Cu" "In6.Cu"
			"In7.Cu" "In8.Cu" "In9.Cu" "In10.Cu" "In11.Cu" "In12.Cu" "In13.Cu" "In14.Cu"
			"In15.Cu" "In16.Cu"
		)
		(hatch none 0.5)
		(connect_pads
			(clearance 0)
		)
		(min_thickness 0.25)
		(keepout
			(tracks not_allowed)
			(vias allowed)
			(pads allowed)
			(copperpour not_allowed)
			(footprints allowed)
		)
		(placement
			(enabled no)
			(sheetname "")
		)
		(fill
			(thermal_gap 0.5)
			(thermal_bridge_width 0.5)
			(island_removal_mode 0)
		)
		(polygon
			(pts
				(arc
					(start 375.081038 -403.728682)
					(mid 375.095917 -403.692761)
					(end 375.131838 -403.677882)
				)
				(arc
					(start 375.848118 -403.677882)
					(mid 375.884039 -403.692761)
					(end 375.898918 -403.728682)
				)
				(arc
					(start 375.898918 -406.151334)
					(mid 375.884039 -406.187255)
					(end 375.848118 -406.202134)
				)
				(arc
					(start 375.131838 -406.202134)
					(mid 375.095917 -406.187255)
					(end 375.081038 -406.151334)
				)
			)
		)
	)
	(zone
		(layers "F.Cu" "B.Cu" "In1.Cu" "In2.Cu" "In3.Cu" "In4.Cu" "In5.Cu" "In6.Cu"
			"In7.Cu" "In8.Cu" "In9.Cu" "In10.Cu" "In11.Cu" "In12.Cu" "In13.Cu" "In14.Cu"
			"In15.Cu" "In16.Cu"
		)
		(hatch none 0.5)
		(connect_pads
			(clearance 0)
		)
		(min_thickness 0.25)
		(keepout
			(tracks not_allowed)
			(vias allowed)
			(pads allowed)
			(copperpour not_allowed)
			(footprints allowed)
		)
		(placement
			(enabled no)
			(sheetname "")
		)
		(fill
			(thermal_gap 0.5)
			(thermal_bridge_width 0.5)
			(island_removal_mode 0)
		)
		(polygon
			(pts
				(arc
					(start 81.075022 -134.369302)
					(mid 81.532222 -134.826502)
					(end 81.989422 -134.369302)
				)
				(arc
					(start 81.989422 -133.505702)
					(mid 81.532222 -133.048502)
					(end 81.075022 -133.505702)
				)
			)
		)
	)
	(zone
		(layers "F.Cu" "B.Cu" "In1.Cu" "In2.Cu" "In3.Cu" "In4.Cu" "In5.Cu" "In6.Cu"
			"In7.Cu" "In8.Cu" "In9.Cu" "In10.Cu" "In11.Cu" "In12.Cu" "In13.Cu" "In14.Cu"
			"In15.Cu" "In16.Cu"
		)
		(hatch none 0.5)
		(connect_pads
			(clearance 0)
		)
		(min_thickness 0.25)
		(keepout
			(tracks not_allowed)
			(vias allowed)
			(pads allowed)
			(copperpour not_allowed)
			(footprints allowed)
		)
		(placement
			(enabled no)
			(sheetname "")
		)
		(fill
			(thermal_gap 0.5)
			(thermal_bridge_width 0.5)
			(island_removal_mode 0)
		)
		(polygon
			(pts
				(arc
					(start 160.948116 -29.114242)
					(mid 161.405316 -29.571442)
					(end 161.862516 -29.114242)
				)
				(arc
					(start 161.862516 -28.250642)
					(mid 161.405316 -27.793442)
					(end 160.948116 -28.250642)
				)
			)
		)
	)
	(zone
		(layers "F.Cu" "B.Cu" "In1.Cu" "In2.Cu" "In3.Cu" "In4.Cu" "In5.Cu" "In6.Cu"
			"In7.Cu" "In8.Cu" "In9.Cu" "In10.Cu" "In11.Cu" "In12.Cu" "In13.Cu" "In14.Cu"
			"In15.Cu" "In16.Cu"
		)
		(hatch none 0.5)
		(connect_pads
			(clearance 0)
		)
		(min_thickness 0.25)
		(keepout
			(tracks not_allowed)
			(vias allowed)
			(pads allowed)
			(copperpour not_allowed)
			(footprints allowed)
		)
		(placement
			(enabled no)
			(sheetname "")
		)
		(fill
			(thermal_gap 0.5)
			(thermal_bridge_width 0.5)
			(island_removal_mode 0)
		)
		(polygon
			(pts
				(arc
					(start 431.057812 -345.084146)
					(mid 430.676812 -345.465146)
					(end 431.057812 -345.846146)
				)
				(arc
					(start 431.921412 -345.846146)
					(mid 432.302412 -345.465146)
					(end 431.921412 -345.084146)
				)
			)
		)
	)
	(zone
		(layers "F.Cu" "B.Cu" "In1.Cu" "In2.Cu" "In3.Cu" "In4.Cu" "In5.Cu" "In6.Cu"
			"In7.Cu" "In8.Cu" "In9.Cu" "In10.Cu" "In11.Cu" "In12.Cu" "In13.Cu" "In14.Cu"
			"In15.Cu" "In16.Cu"
		)
		(hatch none 0.5)
		(connect_pads
			(clearance 0)
		)
		(min_thickness 0.25)
		(keepout
			(tracks not_allowed)
			(vias allowed)
			(pads allowed)
			(copperpour not_allowed)
			(footprints allowed)
		)
		(placement
			(enabled no)
			(sheetname "")
		)
		(fill
			(thermal_gap 0.5)
			(thermal_bridge_width 0.5)
			(island_removal_mode 0)
		)
		(polygon
			(pts
				(arc
					(start 374.29694 -348.20479)
					(mid 373.91594 -348.58579)
					(end 374.29694 -348.96679)
				)
				(arc
					(start 375.16054 -348.96679)
					(mid 375.54154 -348.58579)
					(end 375.16054 -348.20479)
				)
			)
		)
	)
	(zone
		(layers "F.Cu" "B.Cu" "In1.Cu" "In2.Cu" "In3.Cu" "In4.Cu" "In5.Cu" "In6.Cu"
			"In7.Cu" "In8.Cu" "In9.Cu" "In10.Cu" "In11.Cu" "In12.Cu" "In13.Cu" "In14.Cu"
			"In15.Cu" "In16.Cu"
		)
		(hatch none 0.5)
		(connect_pads
			(clearance 0)
		)
		(min_thickness 0.25)
		(keepout
			(tracks not_allowed)
			(vias allowed)
			(pads allowed)
			(copperpour not_allowed)
			(footprints allowed)
		)
		(placement
			(enabled no)
			(sheetname "")
		)
		(fill
			(thermal_gap 0.5)
			(thermal_bridge_width 0.5)
			(island_removal_mode 0)
		)
		(polygon
			(pts
				(arc
					(start 73.700894 -378.828554)
					(mid 73.715773 -378.792633)
					(end 73.751694 -378.777754)
				)
				(arc
					(start 74.467974 -378.777754)
					(mid 74.503895 -378.792633)
					(end 74.518774 -378.828554)
				)
				(arc
					(start 74.518774 -381.251206)
					(mid 74.503895 -381.287127)
					(end 74.467974 -381.302006)
				)
				(arc
					(start 73.751694 -381.302006)
					(mid 73.715773 -381.287127)
					(end 73.700894 -381.251206)
				)
			)
		)
	)
	(zone
		(layers "F.Cu" "B.Cu" "In1.Cu" "In2.Cu" "In3.Cu" "In4.Cu" "In5.Cu" "In6.Cu"
			"In7.Cu" "In8.Cu" "In9.Cu" "In10.Cu" "In11.Cu" "In12.Cu" "In13.Cu" "In14.Cu"
			"In15.Cu" "In16.Cu"
		)
		(hatch none 0.5)
		(connect_pads
			(clearance 0)
		)
		(min_thickness 0.25)
		(keepout
			(tracks not_allowed)
			(vias allowed)
			(pads allowed)
			(copperpour not_allowed)
			(footprints allowed)
		)
		(placement
			(enabled no)
			(sheetname "")
		)
		(fill
			(thermal_gap 0.5)
			(thermal_bridge_width 0.5)
			(island_removal_mode 0)
		)
		(polygon
			(pts
				(arc
					(start 389.84174 -357.37673)
					(mid 389.46074 -357.75773)
					(end 389.84174 -358.13873)
				)
				(arc
					(start 390.70534 -358.13873)
					(mid 391.08634 -357.75773)
					(end 390.70534 -357.37673)
				)
			)
		)
	)
	(zone
		(layers "F.Cu" "B.Cu" "In1.Cu" "In2.Cu" "In3.Cu" "In4.Cu" "In5.Cu" "In6.Cu"
			"In7.Cu" "In8.Cu" "In9.Cu" "In10.Cu" "In11.Cu" "In12.Cu" "In13.Cu" "In14.Cu"
			"In15.Cu" "In16.Cu"
		)
		(hatch none 0.5)
		(connect_pads
			(clearance 0)
		)
		(min_thickness 0.25)
		(keepout
			(tracks not_allowed)
			(vias allowed)
			(pads allowed)
			(copperpour not_allowed)
			(footprints allowed)
		)
		(placement
			(enabled no)
			(sheetname "")
		)
		(fill
			(thermal_gap 0.5)
			(thermal_bridge_width 0.5)
			(island_removal_mode 0)
		)
		(polygon
			(pts
				(arc
					(start 295.881044 -373.828818)
					(mid 295.895923 -373.792897)
					(end 295.931844 -373.778018)
				)
				(arc
					(start 296.648124 -373.778018)
					(mid 296.684045 -373.792897)
					(end 296.698924 -373.828818)
				)
				(arc
					(start 296.698924 -376.25147)
					(mid 296.684045 -376.287391)
					(end 296.648124 -376.30227)
				)
				(arc
					(start 295.931844 -376.30227)
					(mid 295.895923 -376.287391)
					(end 295.881044 -376.25147)
				)
			)
		)
	)
	(zone
		(layers "F.Cu" "B.Cu" "In1.Cu" "In2.Cu" "In3.Cu" "In4.Cu" "In5.Cu" "In6.Cu"
			"In7.Cu" "In8.Cu" "In9.Cu" "In10.Cu" "In11.Cu" "In12.Cu" "In13.Cu" "In14.Cu"
			"In15.Cu" "In16.Cu"
		)
		(hatch none 0.5)
		(connect_pads
			(clearance 0)
		)
		(min_thickness 0.25)
		(keepout
			(tracks not_allowed)
			(vias allowed)
			(pads allowed)
			(copperpour not_allowed)
			(footprints allowed)
		)
		(placement
			(enabled no)
			(sheetname "")
		)
		(fill
			(thermal_gap 0.5)
			(thermal_bridge_width 0.5)
			(island_removal_mode 0)
		)
		(polygon
			(pts
				(arc
					(start 117.70106 -378.828554)
					(mid 117.715939 -378.792633)
					(end 117.75186 -378.777754)
				)
				(arc
					(start 118.46814 -378.777754)
					(mid 118.504061 -378.792633)
					(end 118.51894 -378.828554)
				)
				(arc
					(start 118.51894 -381.251206)
					(mid 118.504061 -381.287127)
					(end 118.46814 -381.302006)
				)
				(arc
					(start 117.75186 -381.302006)
					(mid 117.715939 -381.287127)
					(end 117.70106 -381.251206)
				)
			)
		)
	)
	(zone
		(layers "F.Cu" "B.Cu" "In1.Cu" "In2.Cu" "In3.Cu" "In4.Cu" "In5.Cu" "In6.Cu"
			"In7.Cu" "In8.Cu" "In9.Cu" "In10.Cu" "In11.Cu" "In12.Cu" "In13.Cu" "In14.Cu"
			"In15.Cu" "In16.Cu"
		)
		(hatch none 0.5)
		(connect_pads
			(clearance 0)
		)
		(min_thickness 0.25)
		(keepout
			(tracks not_allowed)
			(vias allowed)
			(pads allowed)
			(copperpour not_allowed)
			(footprints allowed)
		)
		(placement
			(enabled no)
			(sheetname "")
		)
		(fill
			(thermal_gap 0.5)
			(thermal_bridge_width 0.5)
			(island_removal_mode 0)
		)
		(polygon
			(pts
				(arc
					(start 111.862108 -348.20479)
					(mid 111.481108 -348.58579)
					(end 111.862108 -348.96679)
				)
				(arc
					(start 112.725708 -348.96679)
					(mid 113.106708 -348.58579)
					(end 112.725708 -348.20479)
				)
			)
		)
	)
	(zone
		(layers "F.Cu" "B.Cu" "In1.Cu" "In2.Cu" "In3.Cu" "In4.Cu" "In5.Cu" "In6.Cu"
			"In7.Cu" "In8.Cu" "In9.Cu" "In10.Cu" "In11.Cu" "In12.Cu" "In13.Cu" "In14.Cu"
			"In15.Cu" "In16.Cu"
		)
		(hatch none 0.5)
		(connect_pads
			(clearance 0)
		)
		(min_thickness 0.25)
		(keepout
			(tracks not_allowed)
			(vias allowed)
			(pads allowed)
			(copperpour not_allowed)
			(footprints allowed)
		)
		(placement
			(enabled no)
			(sheetname "")
		)
		(fill
			(thermal_gap 0.5)
			(thermal_bridge_width 0.5)
			(island_removal_mode 0)
		)
		(polygon
			(pts
				(arc
					(start 212.948012 -29.114242)
					(mid 213.405212 -29.571442)
					(end 213.862412 -29.114242)
				)
				(arc
					(start 213.862412 -28.250642)
					(mid 213.405212 -27.793442)
					(end 212.948012 -28.250642)
				)
			)
		)
	)
	(zone
		(layers "F.Cu" "B.Cu" "In1.Cu" "In2.Cu" "In3.Cu" "In4.Cu" "In5.Cu" "In6.Cu"
			"In7.Cu" "In8.Cu" "In9.Cu" "In10.Cu" "In11.Cu" "In12.Cu" "In13.Cu" "In14.Cu"
			"In15.Cu" "In16.Cu"
		)
		(hatch none 0.5)
		(connect_pads
			(clearance 0)
		)
		(min_thickness 0.25)
		(keepout
			(tracks not_allowed)
			(vias allowed)
			(pads allowed)
			(copperpour not_allowed)
			(footprints allowed)
		)
		(placement
			(enabled no)
			(sheetname "")
		)
		(fill
			(thermal_gap 0.5)
			(thermal_bridge_width 0.5)
			(island_removal_mode 0)
		)
		(polygon
			(pts
				(arc
					(start 290.95319 -34.52241)
					(mid 291.41039 -34.97961)
					(end 291.86759 -34.52241)
				)
				(arc
					(start 291.86759 -33.65881)
					(mid 291.41039 -33.20161)
					(end 290.95319 -33.65881)
				)
			)
		)
	)
	(zone
		(layers "F.Cu" "B.Cu" "In1.Cu" "In2.Cu" "In3.Cu" "In4.Cu" "In5.Cu" "In6.Cu"
			"In7.Cu" "In8.Cu" "In9.Cu" "In10.Cu" "In11.Cu" "In12.Cu" "In13.Cu" "In14.Cu"
			"In15.Cu" "In16.Cu"
		)
		(hatch none 0.5)
		(connect_pads
			(clearance 0)
		)
		(min_thickness 0.25)
		(keepout
			(tracks not_allowed)
			(vias allowed)
			(pads allowed)
			(copperpour not_allowed)
			(footprints allowed)
		)
		(placement
			(enabled no)
			(sheetname "")
		)
		(fill
			(thermal_gap 0.5)
			(thermal_bridge_width 0.5)
			(island_removal_mode 0)
		)
		(polygon
			(pts
				(arc
					(start 286.754062 -130.43281)
					(mid 286.296862 -129.97561)
					(end 285.839662 -130.43281)
				)
				(arc
					(start 285.839662 -131.29641)
					(mid 286.296862 -131.75361)
					(end 286.754062 -131.29641)
				)
			)
		)
	)
	(zone
		(layers "F.Cu" "B.Cu" "In1.Cu" "In2.Cu" "In3.Cu" "In4.Cu" "In5.Cu" "In6.Cu"
			"In7.Cu" "In8.Cu" "In9.Cu" "In10.Cu" "In11.Cu" "In12.Cu" "In13.Cu" "In14.Cu"
			"In15.Cu" "In16.Cu"
		)
		(hatch none 0.5)
		(connect_pads
			(clearance 0)
		)
		(min_thickness 0.25)
		(keepout
			(tracks not_allowed)
			(vias allowed)
			(pads allowed)
			(copperpour not_allowed)
			(footprints allowed)
		)
		(placement
			(enabled no)
			(sheetname "")
		)
		(fill
			(thermal_gap 0.5)
			(thermal_bridge_width 0.5)
			(island_removal_mode 0)
		)
		(polygon
			(pts
				(arc
					(start 215.59012 -34.520886)
					(mid 216.04732 -34.978086)
					(end 216.50452 -34.520886)
				)
				(arc
					(start 216.50452 -33.657286)
					(mid 216.04732 -33.200086)
					(end 215.59012 -33.657286)
				)
			)
		)
	)
	(zone
		(layers "F.Cu" "B.Cu" "In1.Cu" "In2.Cu" "In3.Cu" "In4.Cu" "In5.Cu" "In6.Cu"
			"In7.Cu" "In8.Cu" "In9.Cu" "In10.Cu" "In11.Cu" "In12.Cu" "In13.Cu" "In14.Cu"
			"In15.Cu" "In16.Cu"
		)
		(hatch none 0.5)
		(connect_pads
			(clearance 0)
		)
		(min_thickness 0.25)
		(keepout
			(tracks not_allowed)
			(vias allowed)
			(pads allowed)
			(copperpour not_allowed)
			(footprints allowed)
		)
		(placement
			(enabled no)
			(sheetname "")
		)
		(fill
			(thermal_gap 0.5)
			(thermal_bridge_width 0.5)
			(island_removal_mode 0)
		)
		(polygon
			(pts
				(arc
					(start 434.48097 -374.928638)
					(mid 434.495849 -374.892717)
					(end 434.53177 -374.877838)
				)
				(arc
					(start 435.24805 -374.877838)
					(mid 435.283971 -374.892717)
					(end 435.29885 -374.928638)
				)
				(arc
					(start 435.29885 -377.35129)
					(mid 435.283971 -377.387211)
					(end 435.24805 -377.40209)
				)
				(arc
					(start 434.53177 -377.40209)
					(mid 434.495849 -377.387211)
					(end 434.48097 -377.35129)
				)
			)
		)
	)
	(zone
		(layers "F.Cu" "B.Cu" "In1.Cu" "In2.Cu" "In3.Cu" "In4.Cu" "In5.Cu" "In6.Cu"
			"In7.Cu" "In8.Cu" "In9.Cu" "In10.Cu" "In11.Cu" "In12.Cu" "In13.Cu" "In14.Cu"
			"In15.Cu" "In16.Cu"
		)
		(hatch none 0.5)
		(connect_pads
			(clearance 0)
		)
		(min_thickness 0.25)
		(keepout
			(tracks not_allowed)
			(vias allowed)
			(pads allowed)
			(copperpour not_allowed)
			(footprints allowed)
		)
		(placement
			(enabled no)
			(sheetname "")
		)
		(fill
			(thermal_gap 0.5)
			(thermal_bridge_width 0.5)
			(island_removal_mode 0)
		)
		(polygon
			(pts
				(arc
					(start 386.081016 -378.828554)
					(mid 386.095895 -378.792633)
					(end 386.131816 -378.777754)
				)
				(arc
					(start 386.848096 -378.777754)
					(mid 386.884017 -378.792633)
					(end 386.898896 -378.828554)
				)
				(arc
					(start 386.898896 -381.251206)
					(mid 386.884017 -381.287127)
					(end 386.848096 -381.302006)
				)
				(arc
					(start 386.131816 -381.302006)
					(mid 386.095895 -381.287127)
					(end 386.081016 -381.251206)
				)
			)
		)
	)
	(zone
		(layers "F.Cu" "B.Cu" "In1.Cu" "In2.Cu" "In3.Cu" "In4.Cu" "In5.Cu" "In6.Cu"
			"In7.Cu" "In8.Cu" "In9.Cu" "In10.Cu" "In11.Cu" "In12.Cu" "In13.Cu" "In14.Cu"
			"In15.Cu" "In16.Cu"
		)
		(hatch none 0.5)
		(connect_pads
			(clearance 0)
		)
		(min_thickness 0.25)
		(keepout
			(tracks not_allowed)
			(vias allowed)
			(pads allowed)
			(copperpour not_allowed)
			(footprints allowed)
		)
		(placement
			(enabled no)
			(sheetname "")
		)
		(fill
			(thermal_gap 0.5)
			(thermal_bridge_width 0.5)
			(island_removal_mode 0)
		)
		(polygon
			(pts
				(arc
					(start 286.550862 -357.37673)
					(mid 286.169862 -357.75773)
					(end 286.550862 -358.13873)
				)
				(arc
					(start 287.414462 -358.13873)
					(mid 287.795462 -357.75773)
					(end 287.414462 -357.37673)
				)
			)
		)
	)
	(zone
		(layers "F.Cu" "B.Cu" "In1.Cu" "In2.Cu" "In3.Cu" "In4.Cu" "In5.Cu" "In6.Cu"
			"In7.Cu" "In8.Cu" "In9.Cu" "In10.Cu" "In11.Cu" "In12.Cu" "In13.Cu" "In14.Cu"
			"In15.Cu" "In16.Cu"
		)
		(hatch none 0.5)
		(connect_pads
			(clearance 0)
		)
		(min_thickness 0.25)
		(keepout
			(tracks not_allowed)
			(vias allowed)
			(pads allowed)
			(copperpour not_allowed)
			(footprints allowed)
		)
		(placement
			(enabled no)
			(sheetname "")
		)
		(fill
			(thermal_gap 0.5)
			(thermal_bridge_width 0.5)
			(island_removal_mode 0)
		)
		(polygon
			(pts
				(arc
					(start 37.310568 -107.377738)
					(mid 37.767768 -107.834938)
					(end 38.224968 -107.377738)
				)
				(arc
					(start 38.224968 -106.514138)
					(mid 37.767768 -106.056938)
					(end 37.310568 -106.514138)
				)
			)
		)
	)
	(zone
		(layers "F.Cu" "B.Cu" "In1.Cu" "In2.Cu" "In3.Cu" "In4.Cu" "In5.Cu" "In6.Cu"
			"In7.Cu" "In8.Cu" "In9.Cu" "In10.Cu" "In11.Cu" "In12.Cu" "In13.Cu" "In14.Cu"
			"In15.Cu" "In16.Cu"
		)
		(hatch none 0.5)
		(connect_pads
			(clearance 0)
		)
		(min_thickness 0.25)
		(keepout
			(tracks not_allowed)
			(vias allowed)
			(pads allowed)
			(copperpour not_allowed)
			(footprints allowed)
		)
		(placement
			(enabled no)
			(sheetname "")
		)
		(fill
			(thermal_gap 0.5)
			(thermal_bridge_width 0.5)
			(island_removal_mode 0)
		)
		(polygon
			(pts
				(arc
					(start 315.611764 -351.230438)
					(mid 315.230764 -351.611438)
					(end 315.611764 -351.992438)
				)
				(arc
					(start 316.475364 -351.992438)
					(mid 316.856364 -351.611438)
					(end 316.475364 -351.230438)
				)
			)
		)
	)
	(zone
		(layers "F.Cu" "B.Cu" "In1.Cu" "In2.Cu" "In3.Cu" "In4.Cu" "In5.Cu" "In6.Cu"
			"In7.Cu" "In8.Cu" "In9.Cu" "In10.Cu" "In11.Cu" "In12.Cu" "In13.Cu" "In14.Cu"
			"In15.Cu" "In16.Cu"
		)
		(hatch none 0.5)
		(connect_pads
			(clearance 0)
		)
		(min_thickness 0.25)
		(keepout
			(tracks not_allowed)
			(vias allowed)
			(pads allowed)
			(copperpour not_allowed)
			(footprints allowed)
		)
		(placement
			(enabled no)
			(sheetname "")
		)
		(fill
			(thermal_gap 0.5)
			(thermal_bridge_width 0.5)
			(island_removal_mode 0)
		)
		(polygon
			(pts
				(arc
					(start 298.800012 -130.777234)
					(mid 299.257212 -131.234434)
					(end 299.714412 -130.777234)
				)
				(arc
					(start 299.714412 -129.913634)
					(mid 299.257212 -129.456434)
					(end 298.800012 -129.913634)
				)
			)
		)
	)
	(zone
		(layers "F.Cu" "B.Cu" "In1.Cu" "In2.Cu" "In3.Cu" "In4.Cu" "In5.Cu" "In6.Cu"
			"In7.Cu" "In8.Cu" "In9.Cu" "In10.Cu" "In11.Cu" "In12.Cu" "In13.Cu" "In14.Cu"
			"In15.Cu" "In16.Cu"
		)
		(hatch none 0.5)
		(connect_pads
			(clearance 0)
		)
		(min_thickness 0.25)
		(keepout
			(tracks not_allowed)
			(vias allowed)
			(pads allowed)
			(copperpour not_allowed)
			(footprints allowed)
		)
		(placement
			(enabled no)
			(sheetname "")
		)
		(fill
			(thermal_gap 0.5)
			(thermal_bridge_width 0.5)
			(island_removal_mode 0)
		)
		(polygon
			(pts
				(arc
					(start 159.501078 -399.828766)
					(mid 159.515957 -399.792845)
					(end 159.551878 -399.777966)
				)
				(arc
					(start 160.268158 -399.777966)
					(mid 160.304079 -399.792845)
					(end 160.318958 -399.828766)
				)
				(arc
					(start 160.318958 -402.251418)
					(mid 160.304079 -402.287339)
					(end 160.268158 -402.302218)
				)
				(arc
					(start 159.551878 -402.302218)
					(mid 159.515957 -402.287339)
					(end 159.501078 -402.251418)
				)
			)
		)
	)
	(zone
		(layers "F.Cu" "B.Cu" "In1.Cu" "In2.Cu" "In3.Cu" "In4.Cu" "In5.Cu" "In6.Cu"
			"In7.Cu" "In8.Cu" "In9.Cu" "In10.Cu" "In11.Cu" "In12.Cu" "In13.Cu" "In14.Cu"
			"In15.Cu" "In16.Cu"
		)
		(hatch none 0.5)
		(connect_pads
			(clearance 0)
		)
		(min_thickness 0.25)
		(keepout
			(tracks not_allowed)
			(vias allowed)
			(pads allowed)
			(copperpour not_allowed)
			(footprints allowed)
		)
		(placement
			(enabled no)
			(sheetname "")
		)
		(fill
			(thermal_gap 0.5)
			(thermal_bridge_width 0.5)
			(island_removal_mode 0)
		)
		(polygon
			(pts
				(arc
					(start 313.274964 -150.67915)
					(mid 313.732164 -151.13635)
					(end 314.189364 -150.67915)
				)
				(arc
					(start 314.189364 -149.81555)
					(mid 313.732164 -149.35835)
					(end 313.274964 -149.81555)
				)
			)
		)
	)
	(zone
		(layers "F.Cu" "B.Cu" "In1.Cu" "In2.Cu" "In3.Cu" "In4.Cu" "In5.Cu" "In6.Cu"
			"In7.Cu" "In8.Cu" "In9.Cu" "In10.Cu" "In11.Cu" "In12.Cu" "In13.Cu" "In14.Cu"
			"In15.Cu" "In16.Cu"
		)
		(hatch none 0.5)
		(connect_pads
			(clearance 0)
		)
		(min_thickness 0.25)
		(keepout
			(tracks not_allowed)
			(vias allowed)
			(pads allowed)
			(copperpour not_allowed)
			(footprints allowed)
		)
		(placement
			(enabled no)
			(sheetname "")
		)
		(fill
			(thermal_gap 0.5)
			(thermal_bridge_width 0.5)
			(island_removal_mode 0)
		)
		(polygon
			(pts
				(arc
					(start 6.753352 -34.52241)
					(mid 7.210552 -34.97961)
					(end 7.667752 -34.52241)
				)
				(arc
					(start 7.667752 -33.65881)
					(mid 7.210552 -33.20161)
					(end 6.753352 -33.65881)
				)
			)
		)
	)
	(zone
		(layers "F.Cu" "B.Cu" "In1.Cu" "In2.Cu" "In3.Cu" "In4.Cu" "In5.Cu" "In6.Cu"
			"In7.Cu" "In8.Cu" "In9.Cu" "In10.Cu" "In11.Cu" "In12.Cu" "In13.Cu" "In14.Cu"
			"In15.Cu" "In16.Cu"
		)
		(hatch none 0.5)
		(connect_pads
			(clearance 0)
		)
		(min_thickness 0.25)
		(keepout
			(tracks not_allowed)
			(vias allowed)
			(pads allowed)
			(copperpour not_allowed)
			(footprints allowed)
		)
		(placement
			(enabled no)
			(sheetname "")
		)
		(fill
			(thermal_gap 0.5)
			(thermal_bridge_width 0.5)
			(island_removal_mode 0)
		)
		(polygon
			(pts
				(arc
					(start 280.332942 -354.351082)
					(mid 279.951942 -354.732082)
					(end 280.332942 -355.113082)
				)
				(arc
					(start 281.196542 -355.113082)
					(mid 281.577542 -354.732082)
					(end 281.196542 -354.351082)
				)
			)
		)
	)
	(zone
		(layers "F.Cu" "B.Cu" "In1.Cu" "In2.Cu" "In3.Cu" "In4.Cu" "In5.Cu" "In6.Cu"
			"In7.Cu" "In8.Cu" "In9.Cu" "In10.Cu" "In11.Cu" "In12.Cu" "In13.Cu" "In14.Cu"
			"In15.Cu" "In16.Cu"
		)
		(hatch none 0.5)
		(connect_pads
			(clearance 0)
		)
		(min_thickness 0.25)
		(keepout
			(tracks not_allowed)
			(vias allowed)
			(pads allowed)
			(copperpour not_allowed)
			(footprints allowed)
		)
		(placement
			(enabled no)
			(sheetname "")
		)
		(fill
			(thermal_gap 0.5)
			(thermal_bridge_width 0.5)
			(island_removal_mode 0)
		)
		(polygon
			(pts
				(arc
					(start 128.701038 -403.728682)
					(mid 128.715917 -403.692761)
					(end 128.751838 -403.677882)
				)
				(arc
					(start 129.468118 -403.677882)
					(mid 129.504039 -403.692761)
					(end 129.518918 -403.728682)
				)
				(arc
					(start 129.518918 -406.151334)
					(mid 129.504039 -406.187255)
					(end 129.468118 -406.202134)
				)
				(arc
					(start 128.751838 -406.202134)
					(mid 128.715917 -406.187255)
					(end 128.701038 -406.151334)
				)
			)
		)
	)
	(zone
		(layers "F.Cu" "B.Cu" "In1.Cu" "In2.Cu" "In3.Cu" "In4.Cu" "In5.Cu" "In6.Cu"
			"In7.Cu" "In8.Cu" "In9.Cu" "In10.Cu" "In11.Cu" "In12.Cu" "In13.Cu" "In14.Cu"
			"In15.Cu" "In16.Cu"
		)
		(hatch none 0.5)
		(connect_pads
			(clearance 0)
		)
		(min_thickness 0.25)
		(keepout
			(tracks not_allowed)
			(vias allowed)
			(pads allowed)
			(copperpour not_allowed)
			(footprints allowed)
		)
		(placement
			(enabled no)
			(sheetname "")
		)
		(fill
			(thermal_gap 0.5)
			(thermal_bridge_width 0.5)
			(island_removal_mode 0)
		)
		(polygon
			(pts
				(arc
					(start 289.280854 -371.028722)
					(mid 289.295733 -370.992801)
					(end 289.331654 -370.977922)
				)
				(arc
					(start 290.047934 -370.977922)
					(mid 290.083855 -370.992801)
					(end 290.098734 -371.028722)
				)
				(arc
					(start 290.098734 -373.451374)
					(mid 290.083855 -373.487295)
					(end 290.047934 -373.502174)
				)
				(arc
					(start 289.331654 -373.502174)
					(mid 289.295733 -373.487295)
					(end 289.280854 -373.451374)
				)
			)
		)
	)
	(zone
		(layers "F.Cu" "B.Cu" "In1.Cu" "In2.Cu" "In3.Cu" "In4.Cu" "In5.Cu" "In6.Cu"
			"In7.Cu" "In8.Cu" "In9.Cu" "In10.Cu" "In11.Cu" "In12.Cu" "In13.Cu" "In14.Cu"
			"In15.Cu" "In16.Cu"
		)
		(hatch none 0.5)
		(connect_pads
			(clearance 0)
		)
		(min_thickness 0.25)
		(keepout
			(tracks not_allowed)
			(vias allowed)
			(pads allowed)
			(copperpour not_allowed)
			(footprints allowed)
		)
		(placement
			(enabled no)
			(sheetname "")
		)
		(fill
			(thermal_gap 0.5)
			(thermal_bridge_width 0.5)
			(island_removal_mode 0)
		)
		(polygon
			(pts
				(arc
					(start 383.62382 -351.230438)
					(mid 383.24282 -351.611438)
					(end 383.62382 -351.992438)
				)
				(arc
					(start 384.48742 -351.992438)
					(mid 384.86842 -351.611438)
					(end 384.48742 -351.230438)
				)
			)
		)
	)
	(zone
		(layers "F.Cu" "B.Cu" "In1.Cu" "In2.Cu" "In3.Cu" "In4.Cu" "In5.Cu" "In6.Cu"
			"In7.Cu" "In8.Cu" "In9.Cu" "In10.Cu" "In11.Cu" "In12.Cu" "In13.Cu" "In14.Cu"
			"In15.Cu" "In16.Cu"
		)
		(hatch none 0.5)
		(connect_pads
			(clearance 0)
		)
		(min_thickness 0.25)
		(keepout
			(tracks not_allowed)
			(vias allowed)
			(pads allowed)
			(copperpour not_allowed)
			(footprints allowed)
		)
		(placement
			(enabled no)
			(sheetname "")
		)
		(fill
			(thermal_gap 0.5)
			(thermal_bridge_width 0.5)
			(island_removal_mode 0)
		)
		(polygon
			(pts
				(arc
					(start 383.5781 -101.984302)
					(mid 384.0353 -102.441502)
					(end 384.4925 -101.984302)
				)
				(arc
					(start 384.4925 -101.120702)
					(mid 384.0353 -100.663502)
					(end 383.5781 -101.120702)
				)
			)
		)
	)
	(zone
		(layers "F.Cu" "B.Cu" "In1.Cu" "In2.Cu" "In3.Cu" "In4.Cu" "In5.Cu" "In6.Cu"
			"In7.Cu" "In8.Cu" "In9.Cu" "In10.Cu" "In11.Cu" "In12.Cu" "In13.Cu" "In14.Cu"
			"In15.Cu" "In16.Cu"
		)
		(hatch none 0.5)
		(connect_pads
			(clearance 0)
		)
		(min_thickness 0.25)
		(keepout
			(tracks not_allowed)
			(vias allowed)
			(pads allowed)
			(copperpour not_allowed)
			(footprints allowed)
		)
		(placement
			(enabled no)
			(sheetname "")
		)
		(fill
			(thermal_gap 0.5)
			(thermal_bridge_width 0.5)
			(island_removal_mode 0)
		)
		(polygon
			(pts
				(arc
					(start 158.62427 -27.342846)
					(mid 159.08147 -27.800046)
					(end 159.53867 -27.342846)
				)
				(arc
					(start 159.53867 -26.479246)
					(mid 159.08147 -26.022046)
					(end 158.62427 -26.479246)
				)
			)
		)
	)
	(zone
		(layers "F.Cu" "B.Cu" "In1.Cu" "In2.Cu" "In3.Cu" "In4.Cu" "In5.Cu" "In6.Cu"
			"In7.Cu" "In8.Cu" "In9.Cu" "In10.Cu" "In11.Cu" "In12.Cu" "In13.Cu" "In14.Cu"
			"In15.Cu" "In16.Cu"
		)
		(hatch none 0.5)
		(connect_pads
			(clearance 0)
		)
		(min_thickness 0.25)
		(keepout
			(tracks not_allowed)
			(vias allowed)
			(pads allowed)
			(copperpour not_allowed)
			(footprints allowed)
		)
		(placement
			(enabled no)
			(sheetname "")
		)
		(fill
			(thermal_gap 0.5)
			(thermal_bridge_width 0.5)
			(island_removal_mode 0)
		)
		(polygon
			(pts
				(arc
					(start 25.550368 -351.230438)
					(mid 25.169368 -351.611438)
					(end 25.550368 -351.992438)
				)
				(arc
					(start 26.413968 -351.992438)
					(mid 26.794968 -351.611438)
					(end 26.413968 -351.230438)
				)
			)
		)
	)
	(zone
		(layers "F.Cu" "B.Cu" "In1.Cu" "In2.Cu" "In3.Cu" "In4.Cu" "In5.Cu" "In6.Cu"
			"In7.Cu" "In8.Cu" "In9.Cu" "In10.Cu" "In11.Cu" "In12.Cu" "In13.Cu" "In14.Cu"
			"In15.Cu" "In16.Cu"
		)
		(hatch none 0.5)
		(connect_pads
			(clearance 0)
		)
		(min_thickness 0.25)
		(keepout
			(tracks not_allowed)
			(vias allowed)
			(pads allowed)
			(copperpour not_allowed)
			(footprints allowed)
		)
		(placement
			(enabled no)
			(sheetname "")
		)
		(fill
			(thermal_gap 0.5)
			(thermal_bridge_width 0.5)
			(island_removal_mode 0)
		)
		(polygon
			(pts
				(arc
					(start 413.04591 -148.887434)
					(mid 413.50311 -149.344634)
					(end 413.96031 -148.887434)
				)
				(arc
					(start 413.96031 -148.023834)
					(mid 413.50311 -147.566634)
					(end 413.04591 -148.023834)
				)
			)
		)
	)
	(zone
		(layers "F.Cu" "B.Cu" "In1.Cu" "In2.Cu" "In3.Cu" "In4.Cu" "In5.Cu" "In6.Cu"
			"In7.Cu" "In8.Cu" "In9.Cu" "In10.Cu" "In11.Cu" "In12.Cu" "In13.Cu" "In14.Cu"
			"In15.Cu" "In16.Cu"
		)
		(hatch none 0.5)
		(connect_pads
			(clearance 0)
		)
		(min_thickness 0.25)
		(keepout
			(tracks not_allowed)
			(vias allowed)
			(pads allowed)
			(copperpour not_allowed)
			(footprints allowed)
		)
		(placement
			(enabled no)
			(sheetname "")
		)
		(fill
			(thermal_gap 0.5)
			(thermal_bridge_width 0.5)
			(island_removal_mode 0)
		)
		(polygon
			(pts
				(arc
					(start 274.115022 -351.230438)
					(mid 273.734022 -351.611438)
					(end 274.115022 -351.992438)
				)
				(arc
					(start 274.978622 -351.992438)
					(mid 275.359622 -351.611438)
					(end 274.978622 -351.230438)
				)
			)
		)
	)
	(zone
		(layers "F.Cu" "B.Cu" "In1.Cu" "In2.Cu" "In3.Cu" "In4.Cu" "In5.Cu" "In6.Cu"
			"In7.Cu" "In8.Cu" "In9.Cu" "In10.Cu" "In11.Cu" "In12.Cu" "In13.Cu" "In14.Cu"
			"In15.Cu" "In16.Cu"
		)
		(hatch none 0.5)
		(connect_pads
			(clearance 0)
		)
		(min_thickness 0.25)
		(keepout
			(tracks not_allowed)
			(vias allowed)
			(pads allowed)
			(copperpour not_allowed)
			(footprints allowed)
		)
		(placement
			(enabled no)
			(sheetname "")
		)
		(fill
			(thermal_gap 0.5)
			(thermal_bridge_width 0.5)
			(island_removal_mode 0)
		)
		(polygon
			(pts
				(arc
					(start 421.730932 -342.058498)
					(mid 421.349932 -342.439498)
					(end 421.730932 -342.820498)
				)
				(arc
					(start 422.594532 -342.820498)
					(mid 422.975532 -342.439498)
					(end 422.594532 -342.058498)
				)
			)
		)
	)
	(zone
		(layers "F.Cu" "B.Cu" "In1.Cu" "In2.Cu" "In3.Cu" "In4.Cu" "In5.Cu" "In6.Cu"
			"In7.Cu" "In8.Cu" "In9.Cu" "In10.Cu" "In11.Cu" "In12.Cu" "In13.Cu" "In14.Cu"
			"In15.Cu" "In16.Cu"
		)
		(hatch none 0.5)
		(connect_pads
			(clearance 0)
		)
		(min_thickness 0.25)
		(keepout
			(tracks not_allowed)
			(vias allowed)
			(pads allowed)
			(copperpour not_allowed)
			(footprints allowed)
		)
		(placement
			(enabled no)
			(sheetname "")
		)
		(fill
			(thermal_gap 0.5)
			(thermal_bridge_width 0.5)
			(island_removal_mode 0)
		)
		(polygon
			(pts
				(arc
					(start 266.868402 -120.087898)
					(mid 267.325602 -120.545098)
					(end 267.782802 -120.087898)
				)
				(arc
					(start 267.782802 -119.224298)
					(mid 267.325602 -118.767098)
					(end 266.868402 -119.224298)
				)
			)
		)
	)
	(zone
		(layers "F.Cu" "B.Cu" "In1.Cu" "In2.Cu" "In3.Cu" "In4.Cu" "In5.Cu" "In6.Cu"
			"In7.Cu" "In8.Cu" "In9.Cu" "In10.Cu" "In11.Cu" "In12.Cu" "In13.Cu" "In14.Cu"
			"In15.Cu" "In16.Cu"
		)
		(hatch none 0.5)
		(connect_pads
			(clearance 0)
		)
		(min_thickness 0.25)
		(keepout
			(tracks not_allowed)
			(vias allowed)
			(pads allowed)
			(copperpour not_allowed)
			(footprints allowed)
		)
		(placement
			(enabled no)
			(sheetname "")
		)
		(fill
			(thermal_gap 0.5)
			(thermal_bridge_width 0.5)
			(island_removal_mode 0)
		)
		(polygon
			(pts
				(arc
					(start 37.986208 -354.351082)
					(mid 37.605208 -354.732082)
					(end 37.986208 -355.113082)
				)
				(arc
					(start 38.849808 -355.113082)
					(mid 39.230808 -354.732082)
					(end 38.849808 -354.351082)
				)
			)
		)
	)
	(zone
		(layers "F.Cu" "B.Cu" "In1.Cu" "In2.Cu" "In3.Cu" "In4.Cu" "In5.Cu" "In6.Cu"
			"In7.Cu" "In8.Cu" "In9.Cu" "In10.Cu" "In11.Cu" "In12.Cu" "In13.Cu" "In14.Cu"
			"In15.Cu" "In16.Cu"
		)
		(hatch none 0.5)
		(connect_pads
			(clearance 0)
		)
		(min_thickness 0.25)
		(keepout
			(tracks not_allowed)
			(vias allowed)
			(pads allowed)
			(copperpour not_allowed)
			(footprints allowed)
		)
		(placement
			(enabled no)
			(sheetname "")
		)
		(fill
			(thermal_gap 0.5)
			(thermal_bridge_width 0.5)
			(island_removal_mode 0)
		)
		(polygon
			(pts
				(arc
					(start 333.28102 -400.92884)
					(mid 333.295899 -400.892919)
					(end 333.33182 -400.87804)
				)
				(arc
					(start 334.0481 -400.87804)
					(mid 334.084021 -400.892919)
					(end 334.0989 -400.92884)
				)
				(arc
					(start 334.0989 -403.351492)
					(mid 334.084021 -403.387413)
					(end 334.0481 -403.402292)
				)
				(arc
					(start 333.33182 -403.402292)
					(mid 333.295899 -403.387413)
					(end 333.28102 -403.351492)
				)
			)
		)
	)
	(zone
		(layers "F.Cu" "B.Cu" "In1.Cu" "In2.Cu" "In3.Cu" "In4.Cu" "In5.Cu" "In6.Cu"
			"In7.Cu" "In8.Cu" "In9.Cu" "In10.Cu" "In11.Cu" "In12.Cu" "In13.Cu" "In14.Cu"
			"In15.Cu" "In16.Cu"
		)
		(hatch none 0.5)
		(connect_pads
			(clearance 0)
		)
		(min_thickness 0.25)
		(keepout
			(tracks not_allowed)
			(vias allowed)
			(pads allowed)
			(copperpour not_allowed)
			(footprints allowed)
		)
		(placement
			(enabled no)
			(sheetname "")
		)
		(fill
			(thermal_gap 0.5)
			(thermal_bridge_width 0.5)
			(island_removal_mode 0)
		)
		(polygon
			(pts
				(arc
					(start 64.481202 -348.20479)
					(mid 64.100202 -348.58579)
					(end 64.481202 -348.96679)
				)
				(arc
					(start 65.344802 -348.96679)
					(mid 65.725802 -348.58579)
					(end 65.344802 -348.20479)
				)
			)
		)
	)
	(zone
		(layers "F.Cu" "B.Cu" "In1.Cu" "In2.Cu" "In3.Cu" "In4.Cu" "In5.Cu" "In6.Cu"
			"In7.Cu" "In8.Cu" "In9.Cu" "In10.Cu" "In11.Cu" "In12.Cu" "In13.Cu" "In14.Cu"
			"In15.Cu" "In16.Cu"
		)
		(hatch none 0.5)
		(connect_pads
			(clearance 0)
		)
		(min_thickness 0.25)
		(keepout
			(tracks not_allowed)
			(vias allowed)
			(pads allowed)
			(copperpour not_allowed)
			(footprints allowed)
		)
		(placement
			(enabled no)
			(sheetname "")
		)
		(fill
			(thermal_gap 0.5)
			(thermal_bridge_width 0.5)
			(island_removal_mode 0)
		)
		(polygon
			(pts
				(arc
					(start 380.51486 -348.20479)
					(mid 380.13386 -348.58579)
					(end 380.51486 -348.96679)
				)
				(arc
					(start 381.37846 -348.96679)
					(mid 381.75946 -348.58579)
					(end 381.37846 -348.20479)
				)
			)
		)
	)
	(zone
		(layers "F.Cu" "B.Cu" "In1.Cu" "In2.Cu" "In3.Cu" "In4.Cu" "In5.Cu" "In6.Cu"
			"In7.Cu" "In8.Cu" "In9.Cu" "In10.Cu" "In11.Cu" "In12.Cu" "In13.Cu" "In14.Cu"
			"In15.Cu" "In16.Cu"
		)
		(hatch none 0.5)
		(connect_pads
			(clearance 0)
		)
		(min_thickness 0.25)
		(keepout
			(tracks not_allowed)
			(vias allowed)
			(pads allowed)
			(copperpour not_allowed)
			(footprints allowed)
		)
		(placement
			(enabled no)
			(sheetname "")
		)
		(fill
			(thermal_gap 0.5)
			(thermal_bridge_width 0.5)
			(island_removal_mode 0)
		)
		(polygon
			(pts
				(arc
					(start 383.881122 -403.728682)
					(mid 383.896001 -403.692761)
					(end 383.931922 -403.677882)
				)
				(arc
					(start 384.648202 -403.677882)
					(mid 384.684123 -403.692761)
					(end 384.699002 -403.728682)
				)
				(arc
					(start 384.699002 -406.151334)
					(mid 384.684123 -406.187255)
					(end 384.648202 -406.202134)
				)
				(arc
					(start 383.931922 -406.202134)
					(mid 383.896001 -406.187255)
					(end 383.881122 -406.151334)
				)
			)
		)
	)
	(zone
		(layers "F.Cu" "B.Cu" "In1.Cu" "In2.Cu" "In3.Cu" "In4.Cu" "In5.Cu" "In6.Cu"
			"In7.Cu" "In8.Cu" "In9.Cu" "In10.Cu" "In11.Cu" "In12.Cu" "In13.Cu" "In14.Cu"
			"In15.Cu" "In16.Cu"
		)
		(hatch none 0.5)
		(connect_pads
			(clearance 0)
		)
		(min_thickness 0.25)
		(keepout
			(tracks not_allowed)
			(vias allowed)
			(pads allowed)
			(copperpour not_allowed)
			(footprints allowed)
		)
		(placement
			(enabled no)
			(sheetname "")
		)
		(fill
			(thermal_gap 0.5)
			(thermal_bridge_width 0.5)
			(island_removal_mode 0)
		)
		(polygon
			(pts
				(arc
					(start 383.881122 -369.928902)
					(mid 383.896001 -369.892981)
					(end 383.931922 -369.878102)
				)
				(arc
					(start 384.648202 -369.878102)
					(mid 384.684123 -369.892981)
					(end 384.699002 -369.928902)
				)
				(arc
					(start 384.699002 -372.351554)
					(mid 384.684123 -372.387475)
					(end 384.648202 -372.402354)
				)
				(arc
					(start 383.931922 -372.402354)
					(mid 383.896001 -372.387475)
					(end 383.881122 -372.351554)
				)
			)
		)
	)
	(zone
		(layers "F.Cu" "B.Cu" "In1.Cu" "In2.Cu" "In3.Cu" "In4.Cu" "In5.Cu" "In6.Cu"
			"In7.Cu" "In8.Cu" "In9.Cu" "In10.Cu" "In11.Cu" "In12.Cu" "In13.Cu" "In14.Cu"
			"In15.Cu" "In16.Cu"
		)
		(hatch none 0.5)
		(connect_pads
			(clearance 0)
		)
		(min_thickness 0.25)
		(keepout
			(tracks not_allowed)
			(vias allowed)
			(pads allowed)
			(copperpour not_allowed)
			(footprints allowed)
		)
		(placement
			(enabled no)
			(sheetname "")
		)
		(fill
			(thermal_gap 0.5)
			(thermal_bridge_width 0.5)
			(island_removal_mode 0)
		)
		(polygon
			(pts
				(arc
					(start 124.30125 -399.828766)
					(mid 124.316129 -399.792845)
					(end 124.35205 -399.777966)
				)
				(arc
					(start 125.06833 -399.777966)
					(mid 125.104251 -399.792845)
					(end 125.11913 -399.828766)
				)
				(arc
					(start 125.11913 -402.251418)
					(mid 125.104251 -402.287339)
					(end 125.06833 -402.302218)
				)
				(arc
					(start 124.35205 -402.302218)
					(mid 124.316129 -402.287339)
					(end 124.30125 -402.251418)
				)
			)
		)
	)
	(zone
		(layers "F.Cu" "B.Cu" "In1.Cu" "In2.Cu" "In3.Cu" "In4.Cu" "In5.Cu" "In6.Cu"
			"In7.Cu" "In8.Cu" "In9.Cu" "In10.Cu" "In11.Cu" "In12.Cu" "In13.Cu" "In14.Cu"
			"In15.Cu" "In16.Cu"
		)
		(hatch none 0.5)
		(connect_pads
			(clearance 0)
		)
		(min_thickness 0.25)
		(keepout
			(tracks not_allowed)
			(vias allowed)
			(pads allowed)
			(copperpour not_allowed)
			(footprints allowed)
		)
		(placement
			(enabled no)
			(sheetname "")
		)
		(fill
			(thermal_gap 0.5)
			(thermal_bridge_width 0.5)
			(island_removal_mode 0)
		)
		(polygon
			(pts
				(arc
					(start 27.501088 -377.728734)
					(mid 27.515967 -377.692813)
					(end 27.551888 -377.677934)
				)
				(arc
					(start 28.268168 -377.677934)
					(mid 28.304089 -377.692813)
					(end 28.318968 -377.728734)
				)
				(arc
					(start 28.318968 -380.151386)
					(mid 28.304089 -380.187307)
					(end 28.268168 -380.202186)
				)
				(arc
					(start 27.551888 -380.202186)
					(mid 27.515967 -380.187307)
					(end 27.501088 -380.151386)
				)
			)
		)
	)
	(zone
		(layers "F.Cu" "B.Cu" "In1.Cu" "In2.Cu" "In3.Cu" "In4.Cu" "In5.Cu" "In6.Cu"
			"In7.Cu" "In8.Cu" "In9.Cu" "In10.Cu" "In11.Cu" "In12.Cu" "In13.Cu" "In14.Cu"
			"In15.Cu" "In16.Cu"
		)
		(hatch none 0.5)
		(connect_pads
			(clearance 0)
		)
		(min_thickness 0.25)
		(keepout
			(tracks not_allowed)
			(vias allowed)
			(pads allowed)
			(copperpour not_allowed)
			(footprints allowed)
		)
		(placement
			(enabled no)
			(sheetname "")
		)
		(fill
			(thermal_gap 0.5)
			(thermal_bridge_width 0.5)
			(island_removal_mode 0)
		)
		(polygon
			(pts
				(arc
					(start 339.88121 -373.828818)
					(mid 339.896089 -373.792897)
					(end 339.93201 -373.778018)
				)
				(arc
					(start 340.64829 -373.778018)
					(mid 340.684211 -373.792897)
					(end 340.69909 -373.828818)
				)
				(arc
					(start 340.69909 -376.25147)
					(mid 340.684211 -376.287391)
					(end 340.64829 -376.30227)
				)
				(arc
					(start 339.93201 -376.30227)
					(mid 339.896089 -376.287391)
					(end 339.88121 -376.25147)
				)
			)
		)
	)
	(zone
		(layers "F.Cu" "B.Cu" "In1.Cu" "In2.Cu" "In3.Cu" "In4.Cu" "In5.Cu" "In6.Cu"
			"In7.Cu" "In8.Cu" "In9.Cu" "In10.Cu" "In11.Cu" "In12.Cu" "In13.Cu" "In14.Cu"
			"In15.Cu" "In16.Cu"
		)
		(hatch none 0.5)
		(connect_pads
			(clearance 0)
		)
		(min_thickness 0.25)
		(keepout
			(tracks not_allowed)
			(vias allowed)
			(pads allowed)
			(copperpour not_allowed)
			(footprints allowed)
		)
		(placement
			(enabled no)
			(sheetname "")
		)
		(fill
			(thermal_gap 0.5)
			(thermal_bridge_width 0.5)
			(island_removal_mode 0)
		)
		(polygon
			(pts
				(arc
					(start 130.901186 -374.928638)
					(mid 130.916065 -374.892717)
					(end 130.951986 -374.877838)
				)
				(arc
					(start 131.668266 -374.877838)
					(mid 131.704187 -374.892717)
					(end 131.719066 -374.928638)
				)
				(arc
					(start 131.719066 -377.35129)
					(mid 131.704187 -377.387211)
					(end 131.668266 -377.40209)
				)
				(arc
					(start 130.951986 -377.40209)
					(mid 130.916065 -377.387211)
					(end 130.901186 -377.35129)
				)
			)
		)
	)
	(zone
		(layers "F.Cu" "B.Cu" "In1.Cu" "In2.Cu" "In3.Cu" "In4.Cu" "In5.Cu" "In6.Cu"
			"In7.Cu" "In8.Cu" "In9.Cu" "In10.Cu" "In11.Cu" "In12.Cu" "In13.Cu" "In14.Cu"
			"In15.Cu" "In16.Cu"
		)
		(hatch none 0.5)
		(connect_pads
			(clearance 0)
		)
		(min_thickness 0.25)
		(keepout
			(tracks not_allowed)
			(vias allowed)
			(pads allowed)
			(copperpour not_allowed)
			(footprints allowed)
		)
		(placement
			(enabled no)
			(sheetname "")
		)
		(fill
			(thermal_gap 0.5)
			(thermal_bridge_width 0.5)
			(island_removal_mode 0)
		)
		(polygon
			(pts
				(arc
					(start 8.607552 -29.12237)
					(mid 9.064752 -29.57957)
					(end 9.521952 -29.12237)
				)
				(arc
					(start 9.521952 -28.25877)
					(mid 9.064752 -27.80157)
					(end 8.607552 -28.25877)
				)
			)
		)
	)
	(zone
		(layers "F.Cu" "B.Cu" "In1.Cu" "In2.Cu" "In3.Cu" "In4.Cu" "In5.Cu" "In6.Cu"
			"In7.Cu" "In8.Cu" "In9.Cu" "In10.Cu" "In11.Cu" "In12.Cu" "In13.Cu" "In14.Cu"
			"In15.Cu" "In16.Cu"
		)
		(hatch none 0.5)
		(connect_pads
			(clearance 0)
		)
		(min_thickness 0.25)
		(keepout
			(tracks not_allowed)
			(vias allowed)
			(pads allowed)
			(copperpour not_allowed)
			(footprints allowed)
		)
		(placement
			(enabled no)
			(sheetname "")
		)
		(fill
			(thermal_gap 0.5)
			(thermal_bridge_width 0.5)
			(island_removal_mode 0)
		)
		(polygon
			(pts
				(arc
					(start 321.829684 -345.084146)
					(mid 321.448684 -345.465146)
					(end 321.829684 -345.846146)
				)
				(arc
					(start 322.693284 -345.846146)
					(mid 323.074284 -345.465146)
					(end 322.693284 -345.084146)
				)
			)
		)
	)
	(zone
		(layers "F.Cu" "B.Cu" "In1.Cu" "In2.Cu" "In3.Cu" "In4.Cu" "In5.Cu" "In6.Cu"
			"In7.Cu" "In8.Cu" "In9.Cu" "In10.Cu" "In11.Cu" "In12.Cu" "In13.Cu" "In14.Cu"
			"In15.Cu" "In16.Cu"
		)
		(hatch none 0.5)
		(connect_pads
			(clearance 0)
		)
		(min_thickness 0.25)
		(keepout
			(tracks not_allowed)
			(vias allowed)
			(pads allowed)
			(copperpour not_allowed)
			(footprints allowed)
		)
		(placement
			(enabled no)
			(sheetname "")
		)
		(fill
			(thermal_gap 0.5)
			(thermal_bridge_width 0.5)
			(island_removal_mode 0)
		)
		(polygon
			(pts
				(arc
					(start 266.868402 -105.584498)
					(mid 267.325602 -106.041698)
					(end 267.782802 -105.584498)
				)
				(arc
					(start 267.782802 -104.720898)
					(mid 267.325602 -104.263698)
					(end 266.868402 -104.720898)
				)
			)
		)
	)
	(zone
		(layers "F.Cu" "B.Cu" "In1.Cu" "In2.Cu" "In3.Cu" "In4.Cu" "In5.Cu" "In6.Cu"
			"In7.Cu" "In8.Cu" "In9.Cu" "In10.Cu" "In11.Cu" "In12.Cu" "In13.Cu" "In14.Cu"
			"In15.Cu" "In16.Cu"
		)
		(hatch none 0.5)
		(connect_pads
			(clearance 0)
		)
		(min_thickness 0.25)
		(keepout
			(tracks not_allowed)
			(vias allowed)
			(pads allowed)
			(copperpour not_allowed)
			(footprints allowed)
		)
		(placement
			(enabled no)
			(sheetname "")
		)
		(fill
			(thermal_gap 0.5)
			(thermal_bridge_width 0.5)
			(island_removal_mode 0)
		)
		(polygon
			(pts
				(arc
					(start 190.166752 -345.084146)
					(mid 189.785752 -345.465146)
					(end 190.166752 -345.846146)
				)
				(arc
					(start 191.030352 -345.846146)
					(mid 191.411352 -345.465146)
					(end 191.030352 -345.084146)
				)
			)
		)
	)
	(zone
		(layers "F.Cu" "B.Cu" "In1.Cu" "In2.Cu" "In3.Cu" "In4.Cu" "In5.Cu" "In6.Cu"
			"In7.Cu" "In8.Cu" "In9.Cu" "In10.Cu" "In11.Cu" "In12.Cu" "In13.Cu" "In14.Cu"
			"In15.Cu" "In16.Cu"
		)
		(hatch none 0.5)
		(connect_pads
			(clearance 0)
		)
		(min_thickness 0.25)
		(keepout
			(tracks not_allowed)
			(vias allowed)
			(pads allowed)
			(copperpour not_allowed)
			(footprints allowed)
		)
		(placement
			(enabled no)
			(sheetname "")
		)
		(fill
			(thermal_gap 0.5)
			(thermal_bridge_width 0.5)
			(island_removal_mode 0)
		)
		(polygon
			(pts
				(arc
					(start 41.095168 -351.230438)
					(mid 40.714168 -351.611438)
					(end 41.095168 -351.992438)
				)
				(arc
					(start 41.958768 -351.992438)
					(mid 42.339768 -351.611438)
					(end 41.958768 -351.230438)
				)
			)
		)
	)
	(zone
		(layers "F.Cu" "B.Cu" "In1.Cu" "In2.Cu" "In3.Cu" "In4.Cu" "In5.Cu" "In6.Cu"
			"In7.Cu" "In8.Cu" "In9.Cu" "In10.Cu" "In11.Cu" "In12.Cu" "In13.Cu" "In14.Cu"
			"In15.Cu" "In16.Cu"
		)
		(hatch none 0.5)
		(connect_pads
			(clearance 0)
		)
		(min_thickness 0.25)
		(keepout
			(tracks not_allowed)
			(vias allowed)
			(pads allowed)
			(copperpour not_allowed)
			(footprints allowed)
		)
		(placement
			(enabled no)
			(sheetname "")
		)
		(fill
			(thermal_gap 0.5)
			(thermal_bridge_width 0.5)
			(island_removal_mode 0)
		)
		(polygon
			(pts
				(arc
					(start 298.080938 -397.028924)
					(mid 298.095817 -396.993003)
					(end 298.131738 -396.978124)
				)
				(arc
					(start 298.848018 -396.978124)
					(mid 298.883939 -396.993003)
					(end 298.898818 -397.028924)
				)
				(arc
					(start 298.898818 -399.451576)
					(mid 298.883939 -399.487497)
					(end 298.848018 -399.502376)
				)
				(arc
					(start 298.131738 -399.502376)
					(mid 298.095817 -399.487497)
					(end 298.080938 -399.451576)
				)
			)
		)
	)
	(zone
		(layers "F.Cu" "B.Cu" "In1.Cu" "In2.Cu" "In3.Cu" "In4.Cu" "In5.Cu" "In6.Cu"
			"In7.Cu" "In8.Cu" "In9.Cu" "In10.Cu" "In11.Cu" "In12.Cu" "In13.Cu" "In14.Cu"
			"In15.Cu" "In16.Cu"
		)
		(hatch none 0.5)
		(connect_pads
			(clearance 0)
		)
		(min_thickness 0.25)
		(keepout
			(tracks not_allowed)
			(vias allowed)
			(pads allowed)
			(copperpour not_allowed)
			(footprints allowed)
		)
		(placement
			(enabled no)
			(sheetname "")
		)
		(fill
			(thermal_gap 0.5)
			(thermal_bridge_width 0.5)
			(island_removal_mode 0)
		)
		(polygon
			(pts
				(arc
					(start 34.877248 -342.058498)
					(mid 34.496248 -342.439498)
					(end 34.877248 -342.820498)
				)
				(arc
					(start 35.740848 -342.820498)
					(mid 36.121848 -342.439498)
					(end 35.740848 -342.058498)
				)
			)
		)
	)
	(zone
		(layers "F.Cu" "B.Cu" "In1.Cu" "In2.Cu" "In3.Cu" "In4.Cu" "In5.Cu" "In6.Cu"
			"In7.Cu" "In8.Cu" "In9.Cu" "In10.Cu" "In11.Cu" "In12.Cu" "In13.Cu" "In14.Cu"
			"In15.Cu" "In16.Cu"
		)
		(hatch none 0.5)
		(connect_pads
			(clearance 0)
		)
		(min_thickness 0.25)
		(keepout
			(tracks not_allowed)
			(vias allowed)
			(pads allowed)
			(copperpour not_allowed)
			(footprints allowed)
		)
		(placement
			(enabled no)
			(sheetname "")
		)
		(fill
			(thermal_gap 0.5)
			(thermal_bridge_width 0.5)
			(island_removal_mode 0)
		)
		(polygon
			(pts
				(arc
					(start 269.51051 -125.494542)
					(mid 269.96771 -125.951742)
					(end 270.42491 -125.494542)
				)
				(arc
					(start 270.42491 -124.630942)
					(mid 269.96771 -124.173742)
					(end 269.51051 -124.630942)
				)
			)
		)
	)
	(zone
		(layers "F.Cu" "B.Cu" "In1.Cu" "In2.Cu" "In3.Cu" "In4.Cu" "In5.Cu" "In6.Cu"
			"In7.Cu" "In8.Cu" "In9.Cu" "In10.Cu" "In11.Cu" "In12.Cu" "In13.Cu" "In14.Cu"
			"In15.Cu" "In16.Cu"
		)
		(hatch none 0.5)
		(connect_pads
			(clearance 0)
		)
		(min_thickness 0.25)
		(keepout
			(tracks not_allowed)
			(vias allowed)
			(pads allowed)
			(copperpour not_allowed)
			(footprints allowed)
		)
		(placement
			(enabled no)
			(sheetname "")
		)
		(fill
			(thermal_gap 0.5)
			(thermal_bridge_width 0.5)
			(island_removal_mode 0)
		)
		(polygon
			(pts
				(arc
					(start 272.130266 -36.60013)
					(mid 270.199866 -36.60013)
					(end 272.130266 -36.60013)
				)
			)
		)
	)
	(zone
		(layers "F.Cu" "B.Cu" "In1.Cu" "In2.Cu" "In3.Cu" "In4.Cu" "In5.Cu" "In6.Cu"
			"In7.Cu" "In8.Cu" "In9.Cu" "In10.Cu" "In11.Cu" "In12.Cu" "In13.Cu" "In14.Cu"
			"In15.Cu" "In16.Cu"
		)
		(hatch none 0.5)
		(connect_pads
			(clearance 0)
		)
		(min_thickness 0.25)
		(keepout
			(tracks not_allowed)
			(vias allowed)
			(pads allowed)
			(copperpour not_allowed)
			(footprints allowed)
		)
		(placement
			(enabled no)
			(sheetname "")
		)
		(fill
			(thermal_gap 0.5)
			(thermal_bridge_width 0.5)
			(island_removal_mode 0)
		)
		(polygon
			(pts
				(arc
					(start 170.501056 -397.028924)
					(mid 170.515935 -396.993003)
					(end 170.551856 -396.978124)
				)
				(arc
					(start 171.268136 -396.978124)
					(mid 171.304057 -396.993003)
					(end 171.318936 -397.028924)
				)
				(arc
					(start 171.318936 -399.451576)
					(mid 171.304057 -399.487497)
					(end 171.268136 -399.502376)
				)
				(arc
					(start 170.551856 -399.502376)
					(mid 170.515935 -399.487497)
					(end 170.501056 -399.451576)
				)
			)
		)
	)
	(zone
		(layers "F.Cu" "B.Cu" "In1.Cu" "In2.Cu" "In3.Cu" "In4.Cu" "In5.Cu" "In6.Cu"
			"In7.Cu" "In8.Cu" "In9.Cu" "In10.Cu" "In11.Cu" "In12.Cu" "In13.Cu" "In14.Cu"
			"In15.Cu" "In16.Cu"
		)
		(hatch none 0.5)
		(connect_pads
			(clearance 0)
		)
		(min_thickness 0.25)
		(keepout
			(tracks not_allowed)
			(vias allowed)
			(pads allowed)
			(copperpour not_allowed)
			(footprints allowed)
		)
		(placement
			(enabled no)
			(sheetname "")
		)
		(fill
			(thermal_gap 0.5)
			(thermal_bridge_width 0.5)
			(island_removal_mode 0)
		)
		(polygon
			(pts
				(arc
					(start 339.88121 -395.92885)
					(mid 339.896089 -395.892929)
					(end 339.93201 -395.87805)
				)
				(arc
					(start 340.64829 -395.87805)
					(mid 340.684211 -395.892929)
					(end 340.69909 -395.92885)
				)
				(arc
					(start 340.69909 -398.351502)
					(mid 340.684211 -398.387423)
					(end 340.64829 -398.402302)
				)
				(arc
					(start 339.93201 -398.402302)
					(mid 339.896089 -398.387423)
					(end 339.88121 -398.351502)
				)
			)
		)
	)
	(zone
		(layers "F.Cu" "B.Cu" "In1.Cu" "In2.Cu" "In3.Cu" "In4.Cu" "In5.Cu" "In6.Cu"
			"In7.Cu" "In8.Cu" "In9.Cu" "In10.Cu" "In11.Cu" "In12.Cu" "In13.Cu" "In14.Cu"
			"In15.Cu" "In16.Cu"
		)
		(hatch none 0.5)
		(connect_pads
			(clearance 0)
		)
		(min_thickness 0.25)
		(keepout
			(tracks not_allowed)
			(vias allowed)
			(pads allowed)
			(copperpour not_allowed)
			(footprints allowed)
		)
		(placement
			(enabled no)
			(sheetname "")
		)
		(fill
			(thermal_gap 0.5)
			(thermal_bridge_width 0.5)
			(island_removal_mode 0)
		)
		(polygon
			(pts
				(arc
					(start 109.60735 -76.87818)
					(mid 109.15015 -77.33538)
					(end 109.60735 -77.79258)
				)
				(arc
					(start 110.47095 -77.79258)
					(mid 110.92815 -77.33538)
					(end 110.47095 -76.87818)
				)
			)
		)
	)
	(zone
		(layers "F.Cu" "B.Cu" "In1.Cu" "In2.Cu" "In3.Cu" "In4.Cu" "In5.Cu" "In6.Cu"
			"In7.Cu" "In8.Cu" "In9.Cu" "In10.Cu" "In11.Cu" "In12.Cu" "In13.Cu" "In14.Cu"
			"In15.Cu" "In16.Cu"
		)
		(hatch none 0.5)
		(connect_pads
			(clearance 0)
		)
		(min_thickness 0.25)
		(keepout
			(tracks not_allowed)
			(vias allowed)
			(pads allowed)
			(copperpour not_allowed)
			(footprints allowed)
		)
		(placement
			(enabled no)
			(sheetname "")
		)
		(fill
			(thermal_gap 0.5)
			(thermal_bridge_width 0.5)
			(island_removal_mode 0)
		)
		(polygon
			(pts
				(arc
					(start 34.6075 -29.12237)
					(mid 35.0647 -29.57957)
					(end 35.5219 -29.12237)
				)
				(arc
					(start 35.5219 -28.25877)
					(mid 35.0647 -27.80157)
					(end 34.6075 -28.25877)
				)
			)
		)
	)
	(zone
		(layers "F.Cu" "B.Cu" "In1.Cu" "In2.Cu" "In3.Cu" "In4.Cu" "In5.Cu" "In6.Cu"
			"In7.Cu" "In8.Cu" "In9.Cu" "In10.Cu" "In11.Cu" "In12.Cu" "In13.Cu" "In14.Cu"
			"In15.Cu" "In16.Cu"
		)
		(hatch none 0.5)
		(connect_pads
			(clearance 0)
		)
		(min_thickness 0.25)
		(keepout
			(tracks not_allowed)
			(vias allowed)
			(pads allowed)
			(copperpour not_allowed)
			(footprints allowed)
		)
		(placement
			(enabled no)
			(sheetname "")
		)
		(fill
			(thermal_gap 0.5)
			(thermal_bridge_width 0.5)
			(island_removal_mode 0)
		)
		(polygon
			(pts
				(arc
					(start 342.081104 -374.928638)
					(mid 342.095983 -374.892717)
					(end 342.131904 -374.877838)
				)
				(arc
					(start 342.848184 -374.877838)
					(mid 342.884105 -374.892717)
					(end 342.898984 -374.928638)
				)
				(arc
					(start 342.898984 -377.35129)
					(mid 342.884105 -377.387211)
					(end 342.848184 -377.40209)
				)
				(arc
					(start 342.131904 -377.40209)
					(mid 342.095983 -377.387211)
					(end 342.081104 -377.35129)
				)
			)
		)
	)
	(zone
		(layers "F.Cu" "B.Cu" "In1.Cu" "In2.Cu" "In3.Cu" "In4.Cu" "In5.Cu" "In6.Cu"
			"In7.Cu" "In8.Cu" "In9.Cu" "In10.Cu" "In11.Cu" "In12.Cu" "In13.Cu" "In14.Cu"
			"In15.Cu" "In16.Cu"
		)
		(hatch none 0.5)
		(connect_pads
			(clearance 0)
		)
		(min_thickness 0.25)
		(keepout
			(tracks not_allowed)
			(vias allowed)
			(pads allowed)
			(copperpour not_allowed)
			(footprints allowed)
		)
		(placement
			(enabled no)
			(sheetname "")
		)
		(fill
			(thermal_gap 0.5)
			(thermal_bridge_width 0.5)
			(island_removal_mode 0)
		)
		(polygon
			(pts
				(arc
					(start 42.524172 -27.342846)
					(mid 42.981372 -27.800046)
					(end 43.438572 -27.342846)
				)
				(arc
					(start 43.438572 -26.479246)
					(mid 42.981372 -26.022046)
					(end 42.524172 -26.479246)
				)
			)
		)
	)
	(zone
		(layers "F.Cu" "B.Cu" "In1.Cu" "In2.Cu" "In3.Cu" "In4.Cu" "In5.Cu" "In6.Cu"
			"In7.Cu" "In8.Cu" "In9.Cu" "In10.Cu" "In11.Cu" "In12.Cu" "In13.Cu" "In14.Cu"
			"In15.Cu" "In16.Cu"
		)
		(hatch none 0.5)
		(connect_pads
			(clearance 0)
		)
		(min_thickness 0.25)
		(keepout
			(tracks not_allowed)
			(vias allowed)
			(pads allowed)
			(copperpour not_allowed)
			(footprints allowed)
		)
		(placement
			(enabled no)
			(sheetname "")
		)
		(fill
			(thermal_gap 0.5)
			(thermal_bridge_width 0.5)
			(island_removal_mode 0)
		)
		(polygon
			(pts
				(arc
					(start 196.384672 -342.058498)
					(mid 196.003672 -342.439498)
					(end 196.384672 -342.820498)
				)
				(arc
					(start 197.248272 -342.820498)
					(mid 197.629272 -342.439498)
					(end 197.248272 -342.058498)
				)
			)
		)
	)
	(zone
		(layers "F.Cu" "B.Cu" "In1.Cu" "In2.Cu" "In3.Cu" "In4.Cu" "In5.Cu" "In6.Cu"
			"In7.Cu" "In8.Cu" "In9.Cu" "In10.Cu" "In11.Cu" "In12.Cu" "In13.Cu" "In14.Cu"
			"In15.Cu" "In16.Cu"
		)
		(hatch none 0.5)
		(connect_pads
			(clearance 0)
		)
		(min_thickness 0.25)
		(keepout
			(tracks not_allowed)
			(vias allowed)
			(pads allowed)
			(copperpour not_allowed)
			(footprints allowed)
		)
		(placement
			(enabled no)
			(sheetname "")
		)
		(fill
			(thermal_gap 0.5)
			(thermal_bridge_width 0.5)
			(island_removal_mode 0)
		)
		(polygon
			(pts
				(arc
					(start 427.881034 -369.928902)
					(mid 427.895913 -369.892981)
					(end 427.931834 -369.878102)
				)
				(arc
					(start 428.648114 -369.878102)
					(mid 428.684035 -369.892981)
					(end 428.698914 -369.928902)
				)
				(arc
					(start 428.698914 -372.351554)
					(mid 428.684035 -372.387475)
					(end 428.648114 -372.402354)
				)
				(arc
					(start 427.931834 -372.402354)
					(mid 427.895913 -372.387475)
					(end 427.881034 -372.351554)
				)
			)
		)
	)
	(zone
		(layers "F.Cu" "B.Cu" "In1.Cu" "In2.Cu" "In3.Cu" "In4.Cu" "In5.Cu" "In6.Cu"
			"In7.Cu" "In8.Cu" "In9.Cu" "In10.Cu" "In11.Cu" "In12.Cu" "In13.Cu" "In14.Cu"
			"In15.Cu" "In16.Cu"
		)
		(hatch none 0.5)
		(connect_pads
			(clearance 0)
		)
		(min_thickness 0.25)
		(keepout
			(tracks not_allowed)
			(vias allowed)
			(pads allowed)
			(copperpour not_allowed)
			(footprints allowed)
		)
		(placement
			(enabled no)
			(sheetname "")
		)
		(fill
			(thermal_gap 0.5)
			(thermal_bridge_width 0.5)
			(island_removal_mode 0)
		)
		(polygon
			(pts
				(arc
					(start 390.481058 -378.828554)
					(mid 390.495937 -378.792633)
					(end 390.531858 -378.777754)
				)
				(arc
					(start 391.248138 -378.777754)
					(mid 391.284059 -378.792633)
					(end 391.298938 -378.828554)
				)
				(arc
					(start 391.298938 -381.251206)
					(mid 391.284059 -381.287127)
					(end 391.248138 -381.302006)
				)
				(arc
					(start 390.531858 -381.302006)
					(mid 390.495937 -381.287127)
					(end 390.481058 -381.251206)
				)
			)
		)
	)
	(zone
		(layers "F.Cu" "B.Cu" "In1.Cu" "In2.Cu" "In3.Cu" "In4.Cu" "In5.Cu" "In6.Cu"
			"In7.Cu" "In8.Cu" "In9.Cu" "In10.Cu" "In11.Cu" "In12.Cu" "In13.Cu" "In14.Cu"
			"In15.Cu" "In16.Cu"
		)
		(hatch none 0.5)
		(connect_pads
			(clearance 0)
		)
		(min_thickness 0.25)
		(keepout
			(tracks not_allowed)
			(vias allowed)
			(pads allowed)
			(copperpour not_allowed)
			(footprints allowed)
		)
		(placement
			(enabled no)
			(sheetname "")
		)
		(fill
			(thermal_gap 0.5)
			(thermal_bridge_width 0.5)
			(island_removal_mode 0)
		)
		(polygon
			(pts
				(arc
					(start 283.441902 -345.084146)
					(mid 283.060902 -345.465146)
					(end 283.441902 -345.846146)
				)
				(arc
					(start 284.305502 -345.846146)
					(mid 284.686502 -345.465146)
					(end 284.305502 -345.084146)
				)
			)
		)
	)
	(zone
		(layers "F.Cu" "B.Cu" "In1.Cu" "In2.Cu" "In3.Cu" "In4.Cu" "In5.Cu" "In6.Cu"
			"In7.Cu" "In8.Cu" "In9.Cu" "In10.Cu" "In11.Cu" "In12.Cu" "In13.Cu" "In14.Cu"
			"In15.Cu" "In16.Cu"
		)
		(hatch none 0.5)
		(connect_pads
			(clearance 0)
		)
		(min_thickness 0.25)
		(keepout
			(tracks not_allowed)
			(vias allowed)
			(pads allowed)
			(copperpour not_allowed)
			(footprints allowed)
		)
		(placement
			(enabled no)
			(sheetname "")
		)
		(fill
			(thermal_gap 0.5)
			(thermal_bridge_width 0.5)
			(island_removal_mode 0)
		)
		(polygon
			(pts
				(arc
					(start 148.853398 -30.922468)
					(mid 149.310598 -31.379668)
					(end 149.767798 -30.922468)
				)
				(arc
					(start 149.767798 -30.058868)
					(mid 149.310598 -29.601668)
					(end 148.853398 -30.058868)
				)
			)
		)
	)
	(zone
		(layers "F.Cu" "B.Cu" "In1.Cu" "In2.Cu" "In3.Cu" "In4.Cu" "In5.Cu" "In6.Cu"
			"In7.Cu" "In8.Cu" "In9.Cu" "In10.Cu" "In11.Cu" "In12.Cu" "In13.Cu" "In14.Cu"
			"In15.Cu" "In16.Cu"
		)
		(hatch none 0.5)
		(connect_pads
			(clearance 0)
		)
		(min_thickness 0.25)
		(keepout
			(tracks not_allowed)
			(vias allowed)
			(pads allowed)
			(copperpour not_allowed)
			(footprints allowed)
		)
		(placement
			(enabled no)
			(sheetname "")
		)
		(fill
			(thermal_gap 0.5)
			(thermal_bridge_width 0.5)
			(island_removal_mode 0)
		)
		(polygon
			(pts
				(arc
					(start 396.05966 -342.058498)
					(mid 395.67866 -342.439498)
					(end 396.05966 -342.820498)
				)
				(arc
					(start 396.92326 -342.820498)
					(mid 397.30426 -342.439498)
					(end 396.92326 -342.058498)
				)
			)
		)
	)
	(zone
		(layers "F.Cu" "B.Cu" "In1.Cu" "In2.Cu" "In3.Cu" "In4.Cu" "In5.Cu" "In6.Cu"
			"In7.Cu" "In8.Cu" "In9.Cu" "In10.Cu" "In11.Cu" "In12.Cu" "In13.Cu" "In14.Cu"
			"In15.Cu" "In16.Cu"
		)
		(hatch none 0.5)
		(connect_pads
			(clearance 0)
		)
		(min_thickness 0.25)
		(keepout
			(tracks not_allowed)
			(vias allowed)
			(pads allowed)
			(copperpour not_allowed)
			(footprints allowed)
		)
		(placement
			(enabled no)
			(sheetname "")
		)
		(fill
			(thermal_gap 0.5)
			(thermal_bridge_width 0.5)
			(island_removal_mode 0)
		)
		(polygon
			(pts
				(arc
					(start 437.275732 -354.351082)
					(mid 436.894732 -354.732082)
					(end 437.275732 -355.113082)
				)
				(arc
					(start 438.139332 -355.113082)
					(mid 438.520332 -354.732082)
					(end 438.139332 -354.351082)
				)
			)
		)
	)
	(zone
		(layers "F.Cu" "B.Cu" "In1.Cu" "In2.Cu" "In3.Cu" "In4.Cu" "In5.Cu" "In6.Cu"
			"In7.Cu" "In8.Cu" "In9.Cu" "In10.Cu" "In11.Cu" "In12.Cu" "In13.Cu" "In14.Cu"
			"In15.Cu" "In16.Cu"
		)
		(hatch none 0.5)
		(connect_pads
			(clearance 0)
		)
		(min_thickness 0.25)
		(keepout
			(tracks not_allowed)
			(vias allowed)
			(pads allowed)
			(copperpour not_allowed)
			(footprints allowed)
		)
		(placement
			(enabled no)
			(sheetname "")
		)
		(fill
			(thermal_gap 0.5)
			(thermal_bridge_width 0.5)
			(island_removal_mode 0)
		)
		(polygon
			(pts
				(arc
					(start 331.081126 -369.928902)
					(mid 331.096005 -369.892981)
					(end 331.131926 -369.878102)
				)
				(arc
					(start 331.848206 -369.878102)
					(mid 331.884127 -369.892981)
					(end 331.899006 -369.928902)
				)
				(arc
					(start 331.899006 -372.351554)
					(mid 331.884127 -372.387475)
					(end 331.848206 -372.402354)
				)
				(arc
					(start 331.131926 -372.402354)
					(mid 331.096005 -372.387475)
					(end 331.081126 -372.351554)
				)
			)
		)
	)
	(zone
		(layers "F.Cu" "B.Cu" "In1.Cu" "In2.Cu" "In3.Cu" "In4.Cu" "In5.Cu" "In6.Cu"
			"In7.Cu" "In8.Cu" "In9.Cu" "In10.Cu" "In11.Cu" "In12.Cu" "In13.Cu" "In14.Cu"
			"In15.Cu" "In16.Cu"
		)
		(hatch none 0.5)
		(connect_pads
			(clearance 0)
		)
		(min_thickness 0.25)
		(keepout
			(tracks not_allowed)
			(vias allowed)
			(pads allowed)
			(copperpour not_allowed)
			(footprints allowed)
		)
		(placement
			(enabled no)
			(sheetname "")
		)
		(fill
			(thermal_gap 0.5)
			(thermal_bridge_width 0.5)
			(island_removal_mode 0)
		)
		(polygon
			(pts
				(arc
					(start 343.592404 -357.37673)
					(mid 343.211404 -357.75773)
					(end 343.592404 -358.13873)
				)
				(arc
					(start 344.456004 -358.13873)
					(mid 344.837004 -357.75773)
					(end 344.456004 -357.37673)
				)
			)
		)
	)
	(zone
		(layers "F.Cu" "B.Cu" "In1.Cu" "In2.Cu" "In3.Cu" "In4.Cu" "In5.Cu" "In6.Cu"
			"In7.Cu" "In8.Cu" "In9.Cu" "In10.Cu" "In11.Cu" "In12.Cu" "In13.Cu" "In14.Cu"
			"In15.Cu" "In16.Cu"
		)
		(hatch none 0.5)
		(connect_pads
			(clearance 0)
		)
		(min_thickness 0.25)
		(keepout
			(tracks not_allowed)
			(vias allowed)
			(pads allowed)
			(copperpour not_allowed)
			(footprints allowed)
		)
		(placement
			(enabled no)
			(sheetname "")
		)
		(fill
			(thermal_gap 0.5)
			(thermal_bridge_width 0.5)
			(island_removal_mode 0)
		)
		(polygon
			(pts
				(arc
					(start 274.115022 -354.351082)
					(mid 273.734022 -354.732082)
					(end 274.115022 -355.113082)
				)
				(arc
					(start 274.978622 -355.113082)
					(mid 275.359622 -354.732082)
					(end 274.978622 -354.351082)
				)
			)
		)
	)
	(zone
		(layers "F.Cu" "B.Cu" "In1.Cu" "In2.Cu" "In3.Cu" "In4.Cu" "In5.Cu" "In6.Cu"
			"In7.Cu" "In8.Cu" "In9.Cu" "In10.Cu" "In11.Cu" "In12.Cu" "In13.Cu" "In14.Cu"
			"In15.Cu" "In16.Cu"
		)
		(hatch none 0.5)
		(connect_pads
			(clearance 0)
		)
		(min_thickness 0.25)
		(keepout
			(tracks not_allowed)
			(vias allowed)
			(pads allowed)
			(copperpour not_allowed)
			(footprints allowed)
		)
		(placement
			(enabled no)
			(sheetname "")
		)
		(fill
			(thermal_gap 0.5)
			(thermal_bridge_width 0.5)
			(island_removal_mode 0)
		)
		(polygon
			(pts
				(arc
					(start 47.313088 -354.351082)
					(mid 46.932088 -354.732082)
					(end 47.313088 -355.113082)
				)
				(arc
					(start 48.176688 -355.113082)
					(mid 48.557688 -354.732082)
					(end 48.176688 -354.351082)
				)
			)
		)
	)
	(zone
		(layers "F.Cu" "B.Cu" "In1.Cu" "In2.Cu" "In3.Cu" "In4.Cu" "In5.Cu" "In6.Cu"
			"In7.Cu" "In8.Cu" "In9.Cu" "In10.Cu" "In11.Cu" "In12.Cu" "In13.Cu" "In14.Cu"
			"In15.Cu" "In16.Cu"
		)
		(hatch none 0.5)
		(connect_pads
			(clearance 0)
		)
		(min_thickness 0.25)
		(keepout
			(tracks not_allowed)
			(vias allowed)
			(pads allowed)
			(copperpour not_allowed)
			(footprints allowed)
		)
		(placement
			(enabled no)
			(sheetname "")
		)
		(fill
			(thermal_gap 0.5)
			(thermal_bridge_width 0.5)
			(island_removal_mode 0)
		)
		(polygon
			(pts
				(arc
					(start 392.9507 -342.058498)
					(mid 392.5697 -342.439498)
					(end 392.9507 -342.820498)
				)
				(arc
					(start 393.8143 -342.820498)
					(mid 394.1953 -342.439498)
					(end 393.8143 -342.058498)
				)
			)
		)
	)
	(zone
		(layers "F.Cu" "B.Cu" "In1.Cu" "In2.Cu" "In3.Cu" "In4.Cu" "In5.Cu" "In6.Cu"
			"In7.Cu" "In8.Cu" "In9.Cu" "In10.Cu" "In11.Cu" "In12.Cu" "In13.Cu" "In14.Cu"
			"In15.Cu" "In16.Cu"
		)
		(hatch none 0.5)
		(connect_pads
			(clearance 0)
		)
		(min_thickness 0.25)
		(keepout
			(tracks not_allowed)
			(vias allowed)
			(pads allowed)
			(copperpour not_allowed)
			(footprints allowed)
		)
		(placement
			(enabled no)
			(sheetname "")
		)
		(fill
			(thermal_gap 0.5)
			(thermal_bridge_width 0.5)
			(island_removal_mode 0)
		)
		(polygon
			(pts
				(arc
					(start 427.948852 -351.230438)
					(mid 427.567852 -351.611438)
					(end 427.948852 -351.992438)
				)
				(arc
					(start 428.812452 -351.992438)
					(mid 429.193452 -351.611438)
					(end 428.812452 -351.230438)
				)
			)
		)
	)
	(zone
		(layers "F.Cu" "B.Cu" "In1.Cu" "In2.Cu" "In3.Cu" "In4.Cu" "In5.Cu" "In6.Cu"
			"In7.Cu" "In8.Cu" "In9.Cu" "In10.Cu" "In11.Cu" "In12.Cu" "In13.Cu" "In14.Cu"
			"In15.Cu" "In16.Cu"
		)
		(hatch none 0.5)
		(connect_pads
			(clearance 0)
		)
		(min_thickness 0.25)
		(keepout
			(tracks not_allowed)
			(vias allowed)
			(pads allowed)
			(copperpour not_allowed)
			(footprints allowed)
		)
		(placement
			(enabled no)
			(sheetname "")
		)
		(fill
			(thermal_gap 0.5)
			(thermal_bridge_width 0.5)
			(island_removal_mode 0)
		)
		(polygon
			(pts
				(arc
					(start 364.824264 -27.342846)
					(mid 365.281464 -27.800046)
					(end 365.738664 -27.342846)
				)
				(arc
					(start 365.738664 -26.479246)
					(mid 365.281464 -26.022046)
					(end 364.824264 -26.479246)
				)
			)
		)
	)
	(zone
		(layers "F.Cu" "B.Cu" "In1.Cu" "In2.Cu" "In3.Cu" "In4.Cu" "In5.Cu" "In6.Cu"
			"In7.Cu" "In8.Cu" "In9.Cu" "In10.Cu" "In11.Cu" "In12.Cu" "In13.Cu" "In14.Cu"
			"In15.Cu" "In16.Cu"
		)
		(hatch none 0.5)
		(connect_pads
			(clearance 0)
		)
		(min_thickness 0.25)
		(keepout
			(tracks not_allowed)
			(vias allowed)
			(pads allowed)
			(copperpour not_allowed)
			(footprints allowed)
		)
		(placement
			(enabled no)
			(sheetname "")
		)
		(fill
			(thermal_gap 0.5)
			(thermal_bridge_width 0.5)
			(island_removal_mode 0)
		)
		(polygon
			(pts
				(arc
					(start 402.27758 -354.351082)
					(mid 401.89658 -354.732082)
					(end 402.27758 -355.113082)
				)
				(arc
					(start 403.14118 -355.113082)
					(mid 403.52218 -354.732082)
					(end 403.14118 -354.351082)
				)
			)
		)
	)
	(zone
		(layers "F.Cu" "B.Cu" "In1.Cu" "In2.Cu" "In3.Cu" "In4.Cu" "In5.Cu" "In6.Cu"
			"In7.Cu" "In8.Cu" "In9.Cu" "In10.Cu" "In11.Cu" "In12.Cu" "In13.Cu" "In14.Cu"
			"In15.Cu" "In16.Cu"
		)
		(hatch none 0.5)
		(connect_pads
			(clearance 0)
		)
		(min_thickness 0.25)
		(keepout
			(tracks not_allowed)
			(vias allowed)
			(pads allowed)
			(copperpour not_allowed)
			(footprints allowed)
		)
		(placement
			(enabled no)
			(sheetname "")
		)
		(fill
			(thermal_gap 0.5)
			(thermal_bridge_width 0.5)
			(island_removal_mode 0)
		)
		(polygon
			(pts
				(arc
					(start 73.700894 -400.92884)
					(mid 73.715773 -400.892919)
					(end 73.751694 -400.87804)
				)
				(arc
					(start 74.467974 -400.87804)
					(mid 74.503895 -400.892919)
					(end 74.518774 -400.92884)
				)
				(arc
					(start 74.518774 -403.351492)
					(mid 74.503895 -403.387413)
					(end 74.467974 -403.402292)
				)
				(arc
					(start 73.751694 -403.402292)
					(mid 73.715773 -403.387413)
					(end 73.700894 -403.351492)
				)
			)
		)
	)
	(zone
		(layers "F.Cu" "B.Cu" "In1.Cu" "In2.Cu" "In3.Cu" "In4.Cu" "In5.Cu" "In6.Cu"
			"In7.Cu" "In8.Cu" "In9.Cu" "In10.Cu" "In11.Cu" "In12.Cu" "In13.Cu" "In14.Cu"
			"In15.Cu" "In16.Cu"
		)
		(hatch none 0.5)
		(connect_pads
			(clearance 0)
		)
		(min_thickness 0.25)
		(keepout
			(tracks not_allowed)
			(vias allowed)
			(pads allowed)
			(copperpour not_allowed)
			(footprints allowed)
		)
		(placement
			(enabled no)
			(sheetname "")
		)
		(fill
			(thermal_gap 0.5)
			(thermal_bridge_width 0.5)
			(island_removal_mode 0)
		)
		(polygon
			(pts
				(arc
					(start 31.90113 -399.828766)
					(mid 31.916009 -399.792845)
					(end 31.95193 -399.777966)
				)
				(arc
					(start 32.66821 -399.777966)
					(mid 32.704131 -399.792845)
					(end 32.71901 -399.828766)
				)
				(arc
					(start 32.71901 -402.251418)
					(mid 32.704131 -402.287339)
					(end 32.66821 -402.302218)
				)
				(arc
					(start 31.95193 -402.302218)
					(mid 31.916009 -402.287339)
					(end 31.90113 -402.251418)
				)
			)
		)
	)
	(zone
		(layers "F.Cu" "B.Cu" "In1.Cu" "In2.Cu" "In3.Cu" "In4.Cu" "In5.Cu" "In6.Cu"
			"In7.Cu" "In8.Cu" "In9.Cu" "In10.Cu" "In11.Cu" "In12.Cu" "In13.Cu" "In14.Cu"
			"In15.Cu" "In16.Cu"
		)
		(hatch none 0.5)
		(connect_pads
			(clearance 0)
		)
		(min_thickness 0.25)
		(keepout
			(tracks not_allowed)
			(vias allowed)
			(pads allowed)
			(copperpour not_allowed)
			(footprints allowed)
		)
		(placement
			(enabled no)
			(sheetname "")
		)
		(fill
			(thermal_gap 0.5)
			(thermal_bridge_width 0.5)
			(island_removal_mode 0)
		)
		(polygon
			(pts
				(arc
					(start 37.986208 -345.084146)
					(mid 37.605208 -345.465146)
					(end 37.986208 -345.846146)
				)
				(arc
					(start 38.849808 -345.846146)
					(mid 39.230808 -345.465146)
					(end 38.849808 -345.084146)
				)
			)
		)
	)
	(zone
		(layers "F.Cu" "B.Cu" "In1.Cu" "In2.Cu" "In3.Cu" "In4.Cu" "In5.Cu" "In6.Cu"
			"In7.Cu" "In8.Cu" "In9.Cu" "In10.Cu" "In11.Cu" "In12.Cu" "In13.Cu" "In14.Cu"
			"In15.Cu" "In16.Cu"
		)
		(hatch none 0.5)
		(connect_pads
			(clearance 0)
		)
		(min_thickness 0.25)
		(keepout
			(tracks not_allowed)
			(vias allowed)
			(pads allowed)
			(copperpour not_allowed)
			(footprints allowed)
		)
		(placement
			(enabled no)
			(sheetname "")
		)
		(fill
			(thermal_gap 0.5)
			(thermal_bridge_width 0.5)
			(island_removal_mode 0)
		)
		(polygon
			(pts
				(arc
					(start 193.275712 -351.230438)
					(mid 192.894712 -351.611438)
					(end 193.275712 -351.992438)
				)
				(arc
					(start 194.139312 -351.992438)
					(mid 194.520312 -351.611438)
					(end 194.139312 -351.230438)
				)
			)
		)
	)
	(zone
		(layers "F.Cu" "B.Cu" "In1.Cu" "In2.Cu" "In3.Cu" "In4.Cu" "In5.Cu" "In6.Cu"
			"In7.Cu" "In8.Cu" "In9.Cu" "In10.Cu" "In11.Cu" "In12.Cu" "In13.Cu" "In14.Cu"
			"In15.Cu" "In16.Cu"
		)
		(hatch none 0.5)
		(connect_pads
			(clearance 0)
		)
		(min_thickness 0.25)
		(keepout
			(tracks not_allowed)
			(vias allowed)
			(pads allowed)
			(copperpour not_allowed)
			(footprints allowed)
		)
		(placement
			(enabled no)
			(sheetname "")
		)
		(fill
			(thermal_gap 0.5)
			(thermal_bridge_width 0.5)
			(island_removal_mode 0)
		)
		(polygon
			(pts
				(arc
					(start 54.55412 -122.822716)
					(mid 54.09692 -122.365516)
					(end 53.63972 -122.822716)
				)
				(arc
					(start 53.63972 -123.686316)
					(mid 54.09692 -124.143516)
					(end 54.55412 -123.686316)
				)
			)
		)
	)
	(zone
		(layers "F.Cu" "B.Cu" "In1.Cu" "In2.Cu" "In3.Cu" "In4.Cu" "In5.Cu" "In6.Cu"
			"In7.Cu" "In8.Cu" "In9.Cu" "In10.Cu" "In11.Cu" "In12.Cu" "In13.Cu" "In14.Cu"
			"In15.Cu" "In16.Cu"
		)
		(hatch none 0.5)
		(connect_pads
			(clearance 0)
		)
		(min_thickness 0.25)
		(keepout
			(tracks not_allowed)
			(vias allowed)
			(pads allowed)
			(copperpour not_allowed)
			(footprints allowed)
		)
		(placement
			(enabled no)
			(sheetname "")
		)
		(fill
			(thermal_gap 0.5)
			(thermal_bridge_width 0.5)
			(island_removal_mode 0)
		)
		(polygon
			(pts
				(arc
					(start 122.101102 -400.92884)
					(mid 122.115981 -400.892919)
					(end 122.151902 -400.87804)
				)
				(arc
					(start 122.868182 -400.87804)
					(mid 122.904103 -400.892919)
					(end 122.918982 -400.92884)
				)
				(arc
					(start 122.918982 -403.351492)
					(mid 122.904103 -403.387413)
					(end 122.868182 -403.402292)
				)
				(arc
					(start 122.151902 -403.402292)
					(mid 122.115981 -403.387413)
					(end 122.101102 -403.351492)
				)
			)
		)
	)
	(zone
		(layers "F.Cu" "B.Cu" "In1.Cu" "In2.Cu" "In3.Cu" "In4.Cu" "In5.Cu" "In6.Cu"
			"In7.Cu" "In8.Cu" "In9.Cu" "In10.Cu" "In11.Cu" "In12.Cu" "In13.Cu" "In14.Cu"
			"In15.Cu" "In16.Cu"
		)
		(hatch none 0.5)
		(connect_pads
			(clearance 0)
		)
		(min_thickness 0.25)
		(keepout
			(tracks not_allowed)
			(vias allowed)
			(pads allowed)
			(copperpour not_allowed)
			(footprints allowed)
		)
		(placement
			(enabled no)
			(sheetname "")
		)
		(fill
			(thermal_gap 0.5)
			(thermal_bridge_width 0.5)
			(island_removal_mode 0)
		)
		(polygon
			(pts
				(arc
					(start 331.081126 -381.628904)
					(mid 331.096005 -381.592983)
					(end 331.131926 -381.578104)
				)
				(arc
					(start 331.848206 -381.578104)
					(mid 331.884127 -381.592983)
					(end 331.899006 -381.628904)
				)
				(arc
					(start 331.899006 -384.051556)
					(mid 331.884127 -384.087477)
					(end 331.848206 -384.102356)
				)
				(arc
					(start 331.131926 -384.102356)
					(mid 331.096005 -384.087477)
					(end 331.081126 -384.051556)
				)
			)
		)
	)
	(zone
		(layers "F.Cu" "B.Cu" "In1.Cu" "In2.Cu" "In3.Cu" "In4.Cu" "In5.Cu" "In6.Cu"
			"In7.Cu" "In8.Cu" "In9.Cu" "In10.Cu" "In11.Cu" "In12.Cu" "In13.Cu" "In14.Cu"
			"In15.Cu" "In16.Cu"
		)
		(hatch none 0.5)
		(connect_pads
			(clearance 0)
		)
		(min_thickness 0.25)
		(keepout
			(tracks not_allowed)
			(vias allowed)
			(pads allowed)
			(copperpour not_allowed)
			(footprints allowed)
		)
		(placement
			(enabled no)
			(sheetname "")
		)
		(fill
			(thermal_gap 0.5)
			(thermal_bridge_width 0.5)
			(island_removal_mode 0)
		)
		(polygon
			(pts
				(arc
					(start 42.901108 -382.728724)
					(mid 42.915987 -382.692803)
					(end 42.951908 -382.677924)
				)
				(arc
					(start 43.668188 -382.677924)
					(mid 43.704109 -382.692803)
					(end 43.718988 -382.728724)
				)
				(arc
					(start 43.718988 -385.151376)
					(mid 43.704109 -385.187297)
					(end 43.668188 -385.202176)
				)
				(arc
					(start 42.951908 -385.202176)
					(mid 42.915987 -385.187297)
					(end 42.901108 -385.151376)
				)
			)
		)
	)
	(zone
		(layers "F.Cu" "B.Cu" "In1.Cu" "In2.Cu" "In3.Cu" "In4.Cu" "In5.Cu" "In6.Cu"
			"In7.Cu" "In8.Cu" "In9.Cu" "In10.Cu" "In11.Cu" "In12.Cu" "In13.Cu" "In14.Cu"
			"In15.Cu" "In16.Cu"
		)
		(hatch none 0.5)
		(connect_pads
			(clearance 0)
		)
		(min_thickness 0.25)
		(keepout
			(tracks not_allowed)
			(vias allowed)
			(pads allowed)
			(copperpour not_allowed)
			(footprints allowed)
		)
		(placement
			(enabled no)
			(sheetname "")
		)
		(fill
			(thermal_gap 0.5)
			(thermal_bridge_width 0.5)
			(island_removal_mode 0)
		)
		(polygon
			(pts
				(arc
					(start 64.481202 -351.230438)
					(mid 64.100202 -351.611438)
					(end 64.481202 -351.992438)
				)
				(arc
					(start 65.344802 -351.992438)
					(mid 65.725802 -351.611438)
					(end 65.344802 -351.230438)
				)
			)
		)
	)
	(zone
		(layers "F.Cu" "B.Cu" "In1.Cu" "In2.Cu" "In3.Cu" "In4.Cu" "In5.Cu" "In6.Cu"
			"In7.Cu" "In8.Cu" "In9.Cu" "In10.Cu" "In11.Cu" "In12.Cu" "In13.Cu" "In14.Cu"
			"In15.Cu" "In16.Cu"
		)
		(hatch none 0.5)
		(connect_pads
			(clearance 0)
		)
		(min_thickness 0.25)
		(keepout
			(tracks not_allowed)
			(vias allowed)
			(pads allowed)
			(copperpour not_allowed)
			(footprints allowed)
		)
		(placement
			(enabled no)
			(sheetname "")
		)
		(fill
			(thermal_gap 0.5)
			(thermal_bridge_width 0.5)
			(island_removal_mode 0)
		)
		(polygon
			(pts
				(arc
					(start 427.881034 -381.628904)
					(mid 427.895913 -381.592983)
					(end 427.931834 -381.578104)
				)
				(arc
					(start 428.648114 -381.578104)
					(mid 428.684035 -381.592983)
					(end 428.698914 -381.628904)
				)
				(arc
					(start 428.698914 -384.051556)
					(mid 428.684035 -384.087477)
					(end 428.648114 -384.102356)
				)
				(arc
					(start 427.931834 -384.102356)
					(mid 427.895913 -384.087477)
					(end 427.881034 -384.051556)
				)
			)
		)
	)
	(zone
		(layers "F.Cu" "B.Cu" "In1.Cu" "In2.Cu" "In3.Cu" "In4.Cu" "In5.Cu" "In6.Cu"
			"In7.Cu" "In8.Cu" "In9.Cu" "In10.Cu" "In11.Cu" "In12.Cu" "In13.Cu" "In14.Cu"
			"In15.Cu" "In16.Cu"
		)
		(hatch none 0.5)
		(connect_pads
			(clearance 0)
		)
		(min_thickness 0.25)
		(keepout
			(tracks not_allowed)
			(vias allowed)
			(pads allowed)
			(copperpour not_allowed)
			(footprints allowed)
		)
		(placement
			(enabled no)
			(sheetname "")
		)
		(fill
			(thermal_gap 0.5)
			(thermal_bridge_width 0.5)
			(island_removal_mode 0)
		)
		(polygon
			(pts
				(arc
					(start 337.681062 -374.928638)
					(mid 337.695941 -374.892717)
					(end 337.731862 -374.877838)
				)
				(arc
					(start 338.448142 -374.877838)
					(mid 338.484063 -374.892717)
					(end 338.498942 -374.928638)
				)
				(arc
					(start 338.498942 -377.35129)
					(mid 338.484063 -377.387211)
					(end 338.448142 -377.40209)
				)
				(arc
					(start 337.731862 -377.40209)
					(mid 337.695941 -377.387211)
					(end 337.681062 -377.35129)
				)
			)
		)
	)
	(zone
		(layers "F.Cu" "B.Cu" "In1.Cu" "In2.Cu" "In3.Cu" "In4.Cu" "In5.Cu" "In6.Cu"
			"In7.Cu" "In8.Cu" "In9.Cu" "In10.Cu" "In11.Cu" "In12.Cu" "In13.Cu" "In14.Cu"
			"In15.Cu" "In16.Cu"
		)
		(hatch none 0.5)
		(connect_pads
			(clearance 0)
		)
		(min_thickness 0.25)
		(keepout
			(tracks not_allowed)
			(vias allowed)
			(pads allowed)
			(copperpour not_allowed)
			(footprints allowed)
		)
		(placement
			(enabled no)
			(sheetname "")
		)
		(fill
			(thermal_gap 0.5)
			(thermal_bridge_width 0.5)
			(island_removal_mode 0)
		)
		(polygon
			(pts
				(arc
					(start 377.280932 -382.728724)
					(mid 377.295811 -382.692803)
					(end 377.331732 -382.677924)
				)
				(arc
					(start 378.048012 -382.677924)
					(mid 378.083933 -382.692803)
					(end 378.098812 -382.728724)
				)
				(arc
					(start 378.098812 -385.151376)
					(mid 378.083933 -385.187297)
					(end 378.048012 -385.202176)
				)
				(arc
					(start 377.331732 -385.202176)
					(mid 377.295811 -385.187297)
					(end 377.280932 -385.151376)
				)
			)
		)
	)
	(zone
		(layers "F.Cu" "B.Cu" "In1.Cu" "In2.Cu" "In3.Cu" "In4.Cu" "In5.Cu" "In6.Cu"
			"In7.Cu" "In8.Cu" "In9.Cu" "In10.Cu" "In11.Cu" "In12.Cu" "In13.Cu" "In14.Cu"
			"In15.Cu" "In16.Cu"
		)
		(hatch none 0.5)
		(connect_pads
			(clearance 0)
		)
		(min_thickness 0.25)
		(keepout
			(tracks not_allowed)
			(vias allowed)
			(pads allowed)
			(copperpour not_allowed)
			(footprints allowed)
		)
		(placement
			(enabled no)
			(sheetname "")
		)
		(fill
			(thermal_gap 0.5)
			(thermal_bridge_width 0.5)
			(island_removal_mode 0)
		)
		(polygon
			(pts
				(arc
					(start 168.301162 -403.728682)
					(mid 168.316041 -403.692761)
					(end 168.351962 -403.677882)
				)
				(arc
					(start 169.068242 -403.677882)
					(mid 169.104163 -403.692761)
					(end 169.119042 -403.728682)
				)
				(arc
					(start 169.119042 -406.151334)
					(mid 169.104163 -406.187255)
					(end 169.068242 -406.202134)
				)
				(arc
					(start 168.351962 -406.202134)
					(mid 168.316041 -406.187255)
					(end 168.301162 -406.151334)
				)
			)
		)
	)
	(zone
		(layers "F.Cu" "B.Cu" "In1.Cu" "In2.Cu" "In3.Cu" "In4.Cu" "In5.Cu" "In6.Cu"
			"In7.Cu" "In8.Cu" "In9.Cu" "In10.Cu" "In11.Cu" "In12.Cu" "In13.Cu" "In14.Cu"
			"In15.Cu" "In16.Cu"
		)
		(hatch none 0.5)
		(connect_pads
			(clearance 0)
		)
		(min_thickness 0.25)
		(keepout
			(tracks not_allowed)
			(vias allowed)
			(pads allowed)
			(copperpour not_allowed)
			(footprints allowed)
		)
		(placement
			(enabled no)
			(sheetname "")
		)
		(fill
			(thermal_gap 0.5)
			(thermal_bridge_width 0.5)
			(island_removal_mode 0)
		)
		(polygon
			(pts
				(arc
					(start 333.28102 -371.028722)
					(mid 333.295899 -370.992801)
					(end 333.33182 -370.977922)
				)
				(arc
					(start 334.0481 -370.977922)
					(mid 334.084021 -370.992801)
					(end 334.0989 -371.028722)
				)
				(arc
					(start 334.0989 -373.451374)
					(mid 334.084021 -373.487295)
					(end 334.0481 -373.502174)
				)
				(arc
					(start 333.33182 -373.502174)
					(mid 333.295899 -373.487295)
					(end 333.28102 -373.451374)
				)
			)
		)
	)
	(zone
		(layers "F.Cu" "B.Cu" "In1.Cu" "In2.Cu" "In3.Cu" "In4.Cu" "In5.Cu" "In6.Cu"
			"In7.Cu" "In8.Cu" "In9.Cu" "In10.Cu" "In11.Cu" "In12.Cu" "In13.Cu" "In14.Cu"
			"In15.Cu" "In16.Cu"
		)
		(hatch none 0.5)
		(connect_pads
			(clearance 0)
		)
		(min_thickness 0.25)
		(keepout
			(tracks not_allowed)
			(vias allowed)
			(pads allowed)
			(copperpour not_allowed)
			(footprints allowed)
		)
		(placement
			(enabled no)
			(sheetname "")
		)
		(fill
			(thermal_gap 0.5)
			(thermal_bridge_width 0.5)
			(island_removal_mode 0)
		)
		(polygon
			(pts
				(arc
					(start 402.85416 -110.11281)
					(mid 402.39696 -109.65561)
					(end 401.93976 -110.11281)
				)
				(arc
					(start 401.93976 -110.97641)
					(mid 402.39696 -111.43361)
					(end 402.85416 -110.97641)
				)
			)
		)
	)
	(zone
		(layers "F.Cu" "B.Cu" "In1.Cu" "In2.Cu" "In3.Cu" "In4.Cu" "In5.Cu" "In6.Cu"
			"In7.Cu" "In8.Cu" "In9.Cu" "In10.Cu" "In11.Cu" "In12.Cu" "In13.Cu" "In14.Cu"
			"In15.Cu" "In16.Cu"
		)
		(hatch none 0.5)
		(connect_pads
			(clearance 0)
		)
		(min_thickness 0.25)
		(keepout
			(tracks not_allowed)
			(vias allowed)
			(pads allowed)
			(copperpour not_allowed)
			(footprints allowed)
		)
		(placement
			(enabled no)
			(sheetname "")
		)
		(fill
			(thermal_gap 0.5)
			(thermal_bridge_width 0.5)
			(island_removal_mode 0)
		)
		(polygon
			(pts
				(arc
					(start 150.707598 -29.12237)
					(mid 151.164798 -29.57957)
					(end 151.621998 -29.12237)
				)
				(arc
					(start 151.621998 -28.25877)
					(mid 151.164798 -27.80157)
					(end 150.707598 -28.25877)
				)
			)
		)
	)
	(zone
		(layers "F.Cu" "B.Cu" "In1.Cu" "In2.Cu" "In3.Cu" "In4.Cu" "In5.Cu" "In6.Cu"
			"In7.Cu" "In8.Cu" "In9.Cu" "In10.Cu" "In11.Cu" "In12.Cu" "In13.Cu" "In14.Cu"
			"In15.Cu" "In16.Cu"
		)
		(hatch none 0.5)
		(connect_pads
			(clearance 0)
		)
		(min_thickness 0.25)
		(keepout
			(tracks not_allowed)
			(vias allowed)
			(pads allowed)
			(copperpour not_allowed)
			(footprints allowed)
		)
		(placement
			(enabled no)
			(sheetname "")
		)
		(fill
			(thermal_gap 0.5)
			(thermal_bridge_width 0.5)
			(island_removal_mode 0)
		)
		(polygon
			(pts
				(arc
					(start 383.881122 -399.828766)
					(mid 383.896001 -399.792845)
					(end 383.931922 -399.777966)
				)
				(arc
					(start 384.648202 -399.777966)
					(mid 384.684123 -399.792845)
					(end 384.699002 -399.828766)
				)
				(arc
					(start 384.699002 -402.251418)
					(mid 384.684123 -402.287339)
					(end 384.648202 -402.302218)
				)
				(arc
					(start 383.931922 -402.302218)
					(mid 383.896001 -402.287339)
					(end 383.881122 -402.251418)
				)
			)
		)
	)
	(zone
		(layers "F.Cu" "B.Cu" "In1.Cu" "In2.Cu" "In3.Cu" "In4.Cu" "In5.Cu" "In6.Cu"
			"In7.Cu" "In8.Cu" "In9.Cu" "In10.Cu" "In11.Cu" "In12.Cu" "In13.Cu" "In14.Cu"
			"In15.Cu" "In16.Cu"
		)
		(hatch none 0.5)
		(connect_pads
			(clearance 0)
		)
		(min_thickness 0.25)
		(keepout
			(tracks not_allowed)
			(vias allowed)
			(pads allowed)
			(copperpour not_allowed)
			(footprints allowed)
		)
		(placement
			(enabled no)
			(sheetname "")
		)
		(fill
			(thermal_gap 0.5)
			(thermal_bridge_width 0.5)
			(island_removal_mode 0)
		)
		(polygon
			(pts
				(arc
					(start 393.148058 -32.714184)
					(mid 393.605258 -33.171384)
					(end 394.062458 -32.714184)
				)
				(arc
					(start 394.062458 -31.850584)
					(mid 393.605258 -31.393384)
					(end 393.148058 -31.850584)
				)
			)
		)
	)
	(zone
		(layers "F.Cu" "B.Cu" "In1.Cu" "In2.Cu" "In3.Cu" "In4.Cu" "In5.Cu" "In6.Cu"
			"In7.Cu" "In8.Cu" "In9.Cu" "In10.Cu" "In11.Cu" "In12.Cu" "In13.Cu" "In14.Cu"
			"In15.Cu" "In16.Cu"
		)
		(hatch none 0.5)
		(connect_pads
			(clearance 0)
		)
		(min_thickness 0.25)
		(keepout
			(tracks not_allowed)
			(vias allowed)
			(pads allowed)
			(copperpour not_allowed)
			(footprints allowed)
		)
		(placement
			(enabled no)
			(sheetname "")
		)
		(fill
			(thermal_gap 0.5)
			(thermal_bridge_width 0.5)
			(island_removal_mode 0)
		)
		(polygon
			(pts
				(arc
					(start 96.847914 -29.114242)
					(mid 97.305114 -29.571442)
					(end 97.762314 -29.114242)
				)
				(arc
					(start 97.762314 -28.250642)
					(mid 97.305114 -27.793442)
					(end 96.847914 -28.250642)
				)
			)
		)
	)
	(zone
		(layers "F.Cu" "B.Cu" "In1.Cu" "In2.Cu" "In3.Cu" "In4.Cu" "In5.Cu" "In6.Cu"
			"In7.Cu" "In8.Cu" "In9.Cu" "In10.Cu" "In11.Cu" "In12.Cu" "In13.Cu" "In14.Cu"
			"In15.Cu" "In16.Cu"
		)
		(hatch none 0.5)
		(connect_pads
			(clearance 0)
		)
		(min_thickness 0.25)
		(keepout
			(tracks not_allowed)
			(vias allowed)
			(pads allowed)
			(copperpour not_allowed)
			(footprints allowed)
		)
		(placement
			(enabled no)
			(sheetname "")
		)
		(fill
			(thermal_gap 0.5)
			(thermal_bridge_width 0.5)
			(island_removal_mode 0)
		)
		(polygon
			(pts
				(arc
					(start 182.700168 -154.28722)
					(mid 183.157368 -154.74442)
					(end 183.614568 -154.28722)
				)
				(arc
					(start 183.614568 -153.42362)
					(mid 183.157368 -152.96642)
					(end 182.700168 -153.42362)
				)
			)
		)
	)
	(zone
		(layers "F.Cu" "B.Cu" "In1.Cu" "In2.Cu" "In3.Cu" "In4.Cu" "In5.Cu" "In6.Cu"
			"In7.Cu" "In8.Cu" "In9.Cu" "In10.Cu" "In11.Cu" "In12.Cu" "In13.Cu" "In14.Cu"
			"In15.Cu" "In16.Cu"
		)
		(hatch none 0.5)
		(connect_pads
			(clearance 0)
		)
		(min_thickness 0.25)
		(keepout
			(tracks not_allowed)
			(vias allowed)
			(pads allowed)
			(copperpour not_allowed)
			(footprints allowed)
		)
		(placement
			(enabled no)
			(sheetname "")
		)
		(fill
			(thermal_gap 0.5)
			(thermal_bridge_width 0.5)
			(island_removal_mode 0)
		)
		(polygon
			(pts
				(arc
					(start 298.800012 -134.377176)
					(mid 299.257212 -134.834376)
					(end 299.714412 -134.377176)
				)
				(arc
					(start 299.714412 -133.513576)
					(mid 299.257212 -133.056376)
					(end 298.800012 -133.513576)
				)
			)
		)
	)
	(zone
		(layers "F.Cu" "B.Cu" "In1.Cu" "In2.Cu" "In3.Cu" "In4.Cu" "In5.Cu" "In6.Cu"
			"In7.Cu" "In8.Cu" "In9.Cu" "In10.Cu" "In11.Cu" "In12.Cu" "In13.Cu" "In14.Cu"
			"In15.Cu" "In16.Cu"
		)
		(hatch none 0.5)
		(connect_pads
			(clearance 0)
		)
		(min_thickness 0.25)
		(keepout
			(tracks not_allowed)
			(vias allowed)
			(pads allowed)
			(copperpour not_allowed)
			(footprints allowed)
		)
		(placement
			(enabled no)
			(sheetname "")
		)
		(fill
			(thermal_gap 0.5)
			(thermal_bridge_width 0.5)
			(island_removal_mode 0)
		)
		(polygon
			(pts
				(arc
					(start 119.901208 -403.728682)
					(mid 119.916087 -403.692761)
					(end 119.952008 -403.677882)
				)
				(arc
					(start 120.668288 -403.677882)
					(mid 120.704209 -403.692761)
					(end 120.719088 -403.728682)
				)
				(arc
					(start 120.719088 -406.151334)
					(mid 120.704209 -406.187255)
					(end 120.668288 -406.202134)
				)
				(arc
					(start 119.952008 -406.202134)
					(mid 119.916087 -406.187255)
					(end 119.901208 -406.151334)
				)
			)
		)
	)
	(zone
		(layers "F.Cu" "B.Cu" "In1.Cu" "In2.Cu" "In3.Cu" "In4.Cu" "In5.Cu" "In6.Cu"
			"In7.Cu" "In8.Cu" "In9.Cu" "In10.Cu" "In11.Cu" "In12.Cu" "In13.Cu" "In14.Cu"
			"In15.Cu" "In16.Cu"
		)
		(hatch none 0.5)
		(connect_pads
			(clearance 0)
		)
		(min_thickness 0.25)
		(keepout
			(tracks not_allowed)
			(vias allowed)
			(pads allowed)
			(copperpour not_allowed)
			(footprints allowed)
		)
		(placement
			(enabled no)
			(sheetname "")
		)
		(fill
			(thermal_gap 0.5)
			(thermal_bridge_width 0.5)
			(island_removal_mode 0)
		)
		(polygon
			(pts
				(arc
					(start 432.01717 -148.88591)
					(mid 432.47437 -149.34311)
					(end 432.93157 -148.88591)
				)
				(arc
					(start 432.93157 -148.02231)
					(mid 432.47437 -147.56511)
					(end 432.01717 -148.02231)
				)
			)
		)
	)
	(zone
		(layers "F.Cu" "B.Cu" "In1.Cu" "In2.Cu" "In3.Cu" "In4.Cu" "In5.Cu" "In6.Cu"
			"In7.Cu" "In8.Cu" "In9.Cu" "In10.Cu" "In11.Cu" "In12.Cu" "In13.Cu" "In14.Cu"
			"In15.Cu" "In16.Cu"
		)
		(hatch none 0.5)
		(connect_pads
			(clearance 0)
		)
		(min_thickness 0.25)
		(keepout
			(tracks not_allowed)
			(vias allowed)
			(pads allowed)
			(copperpour not_allowed)
			(footprints allowed)
		)
		(placement
			(enabled no)
			(sheetname "")
		)
		(fill
			(thermal_gap 0.5)
			(thermal_bridge_width 0.5)
			(island_removal_mode 0)
		)
		(polygon
			(pts
				(arc
					(start 163.90112 -403.728682)
					(mid 163.915999 -403.692761)
					(end 163.95192 -403.677882)
				)
				(arc
					(start 164.6682 -403.677882)
					(mid 164.704121 -403.692761)
					(end 164.719 -403.728682)
				)
				(arc
					(start 164.719 -406.151334)
					(mid 164.704121 -406.187255)
					(end 164.6682 -406.202134)
				)
				(arc
					(start 163.95192 -406.202134)
					(mid 163.915999 -406.187255)
					(end 163.90112 -406.151334)
				)
			)
		)
	)
	(zone
		(layers "F.Cu" "B.Cu" "In1.Cu" "In2.Cu" "In3.Cu" "In4.Cu" "In5.Cu" "In6.Cu"
			"In7.Cu" "In8.Cu" "In9.Cu" "In10.Cu" "In11.Cu" "In12.Cu" "In13.Cu" "In14.Cu"
			"In15.Cu" "In16.Cu"
		)
		(hatch none 0.5)
		(connect_pads
			(clearance 0)
		)
		(min_thickness 0.25)
		(keepout
			(tracks not_allowed)
			(vias allowed)
			(pads allowed)
			(copperpour not_allowed)
			(footprints allowed)
		)
		(placement
			(enabled no)
			(sheetname "")
		)
		(fill
			(thermal_gap 0.5)
			(thermal_bridge_width 0.5)
			(island_removal_mode 0)
		)
		(polygon
			(pts
				(arc
					(start 38.501066 -397.028924)
					(mid 38.515945 -396.993003)
					(end 38.551866 -396.978124)
				)
				(arc
					(start 39.268146 -396.978124)
					(mid 39.304067 -396.993003)
					(end 39.318946 -397.028924)
				)
				(arc
					(start 39.318946 -399.451576)
					(mid 39.304067 -399.487497)
					(end 39.268146 -399.502376)
				)
				(arc
					(start 38.551866 -399.502376)
					(mid 38.515945 -399.487497)
					(end 38.501066 -399.451576)
				)
			)
		)
	)
	(zone
		(layers "F.Cu" "B.Cu" "In1.Cu" "In2.Cu" "In3.Cu" "In4.Cu" "In5.Cu" "In6.Cu"
			"In7.Cu" "In8.Cu" "In9.Cu" "In10.Cu" "In11.Cu" "In12.Cu" "In13.Cu" "In14.Cu"
			"In15.Cu" "In16.Cu"
		)
		(hatch none 0.5)
		(connect_pads
			(clearance 0)
		)
		(min_thickness 0.25)
		(keepout
			(tracks not_allowed)
			(vias allowed)
			(pads allowed)
			(copperpour not_allowed)
			(footprints allowed)
		)
		(placement
			(enabled no)
			(sheetname "")
		)
		(fill
			(thermal_gap 0.5)
			(thermal_bridge_width 0.5)
			(island_removal_mode 0)
		)
		(polygon
			(pts
				(arc
					(start 321.829684 -348.20479)
					(mid 321.448684 -348.58579)
					(end 321.829684 -348.96679)
				)
				(arc
					(start 322.693284 -348.96679)
					(mid 323.074284 -348.58579)
					(end 322.693284 -348.20479)
				)
			)
		)
	)
	(zone
		(layers "F.Cu" "B.Cu" "In1.Cu" "In2.Cu" "In3.Cu" "In4.Cu" "In5.Cu" "In6.Cu"
			"In7.Cu" "In8.Cu" "In9.Cu" "In10.Cu" "In11.Cu" "In12.Cu" "In13.Cu" "In14.Cu"
			"In15.Cu" "In16.Cu"
		)
		(hatch none 0.5)
		(connect_pads
			(clearance 0)
		)
		(min_thickness 0.25)
		(keepout
			(tracks not_allowed)
			(vias allowed)
			(pads allowed)
			(copperpour not_allowed)
			(footprints allowed)
		)
		(placement
			(enabled no)
			(sheetname "")
		)
		(fill
			(thermal_gap 0.5)
			(thermal_bridge_width 0.5)
			(island_removal_mode 0)
		)
		(polygon
			(pts
				(arc
					(start 44.204128 -345.084146)
					(mid 43.823128 -345.465146)
					(end 44.204128 -345.846146)
				)
				(arc
					(start 45.067728 -345.846146)
					(mid 45.448728 -345.465146)
					(end 45.067728 -345.084146)
				)
			)
		)
	)
	(zone
		(layers "F.Cu" "B.Cu" "In1.Cu" "In2.Cu" "In3.Cu" "In4.Cu" "In5.Cu" "In6.Cu"
			"In7.Cu" "In8.Cu" "In9.Cu" "In10.Cu" "In11.Cu" "In12.Cu" "In13.Cu" "In14.Cu"
			"In15.Cu" "In16.Cu"
		)
		(hatch none 0.5)
		(connect_pads
			(clearance 0)
		)
		(min_thickness 0.25)
		(keepout
			(tracks not_allowed)
			(vias allowed)
			(pads allowed)
			(copperpour not_allowed)
			(footprints allowed)
		)
		(placement
			(enabled no)
			(sheetname "")
		)
		(fill
			(thermal_gap 0.5)
			(thermal_bridge_width 0.5)
			(island_removal_mode 0)
		)
		(polygon
			(pts
				(arc
					(start 292.768782 -342.058498)
					(mid 292.387782 -342.439498)
					(end 292.768782 -342.820498)
				)
				(arc
					(start 293.632382 -342.820498)
					(mid 294.013382 -342.439498)
					(end 293.632382 -342.058498)
				)
			)
		)
	)
	(zone
		(layers "F.Cu" "B.Cu" "In1.Cu" "In2.Cu" "In3.Cu" "In4.Cu" "In5.Cu" "In6.Cu"
			"In7.Cu" "In8.Cu" "In9.Cu" "In10.Cu" "In11.Cu" "In12.Cu" "In13.Cu" "In14.Cu"
			"In15.Cu" "In16.Cu"
		)
		(hatch none 0.5)
		(connect_pads
			(clearance 0)
		)
		(min_thickness 0.25)
		(keepout
			(tracks not_allowed)
			(vias allowed)
			(pads allowed)
			(copperpour not_allowed)
			(footprints allowed)
		)
		(placement
			(enabled no)
			(sheetname "")
		)
		(fill
			(thermal_gap 0.5)
			(thermal_bridge_width 0.5)
			(island_removal_mode 0)
		)
		(polygon
			(pts
				(arc
					(start 318.720724 -354.351082)
					(mid 318.339724 -354.732082)
					(end 318.720724 -355.113082)
				)
				(arc
					(start 319.584324 -355.113082)
					(mid 319.965324 -354.732082)
					(end 319.584324 -354.351082)
				)
			)
		)
	)
	(zone
		(layers "F.Cu" "B.Cu" "In1.Cu" "In2.Cu" "In3.Cu" "In4.Cu" "In5.Cu" "In6.Cu"
			"In7.Cu" "In8.Cu" "In9.Cu" "In10.Cu" "In11.Cu" "In12.Cu" "In13.Cu" "In14.Cu"
			"In15.Cu" "In16.Cu"
		)
		(hatch none 0.5)
		(connect_pads
			(clearance 0)
		)
		(min_thickness 0.25)
		(keepout
			(tracks not_allowed)
			(vias allowed)
			(pads allowed)
			(copperpour not_allowed)
			(footprints allowed)
		)
		(placement
			(enabled no)
			(sheetname "")
		)
		(fill
			(thermal_gap 0.5)
			(thermal_bridge_width 0.5)
			(island_removal_mode 0)
		)
		(polygon
			(pts
				(arc
					(start 119.901208 -377.728734)
					(mid 119.916087 -377.692813)
					(end 119.952008 -377.677934)
				)
				(arc
					(start 120.668288 -377.677934)
					(mid 120.704209 -377.692813)
					(end 120.719088 -377.728734)
				)
				(arc
					(start 120.719088 -380.151386)
					(mid 120.704209 -380.187307)
					(end 120.668288 -380.202186)
				)
				(arc
					(start 119.952008 -380.202186)
					(mid 119.916087 -380.187307)
					(end 119.901208 -380.151386)
				)
			)
		)
	)
	(zone
		(layers "F.Cu" "B.Cu" "In1.Cu" "In2.Cu" "In3.Cu" "In4.Cu" "In5.Cu" "In6.Cu"
			"In7.Cu" "In8.Cu" "In9.Cu" "In10.Cu" "In11.Cu" "In12.Cu" "In13.Cu" "In14.Cu"
			"In15.Cu" "In16.Cu"
		)
		(hatch none 0.5)
		(connect_pads
			(clearance 0)
		)
		(min_thickness 0.25)
		(keepout
			(tracks not_allowed)
			(vias allowed)
			(pads allowed)
			(copperpour not_allowed)
			(footprints allowed)
		)
		(placement
			(enabled no)
			(sheetname "")
		)
		(fill
			(thermal_gap 0.5)
			(thermal_bridge_width 0.5)
			(island_removal_mode 0)
		)
		(polygon
			(pts
				(arc
					(start 431.057812 -354.351082)
					(mid 430.676812 -354.732082)
					(end 431.057812 -355.113082)
				)
				(arc
					(start 431.921412 -355.113082)
					(mid 432.302412 -354.732082)
					(end 431.921412 -354.351082)
				)
			)
		)
	)
	(zone
		(layers "F.Cu" "B.Cu" "In1.Cu" "In2.Cu" "In3.Cu" "In4.Cu" "In5.Cu" "In6.Cu"
			"In7.Cu" "In8.Cu" "In9.Cu" "In10.Cu" "In11.Cu" "In12.Cu" "In13.Cu" "In14.Cu"
			"In15.Cu" "In16.Cu"
		)
		(hatch none 0.5)
		(connect_pads
			(clearance 0)
		)
		(min_thickness 0.25)
		(keepout
			(tracks not_allowed)
			(vias allowed)
			(pads allowed)
			(copperpour not_allowed)
			(footprints allowed)
		)
		(placement
			(enabled no)
			(sheetname "")
		)
		(fill
			(thermal_gap 0.5)
			(thermal_bridge_width 0.5)
			(island_removal_mode 0)
		)
		(polygon
			(pts
				(arc
					(start 37.324538 -297.65498)
					(mid 37.654738 -297.32478)
					(end 37.324538 -296.99458)
				)
				(arc
					(start 36.374578 -296.99458)
					(mid 36.044378 -297.32478)
					(end 36.374578 -297.65498)
				)
			)
		)
	)
	(zone
		(layers "F.Cu" "B.Cu" "In1.Cu" "In2.Cu" "In3.Cu" "In4.Cu" "In5.Cu" "In6.Cu"
			"In7.Cu" "In8.Cu" "In9.Cu" "In10.Cu" "In11.Cu" "In12.Cu" "In13.Cu" "In14.Cu"
			"In15.Cu" "In16.Cu"
		)
		(hatch none 0.5)
		(connect_pads
			(clearance 0)
		)
		(min_thickness 0.25)
		(keepout
			(tracks not_allowed)
			(vias allowed)
			(pads allowed)
			(copperpour not_allowed)
			(footprints allowed)
		)
		(placement
			(enabled no)
			(sheetname "")
		)
		(fill
			(thermal_gap 0.5)
			(thermal_bridge_width 0.5)
			(island_removal_mode 0)
		)
		(polygon
			(pts
				(arc
					(start 134.87019 -188.821822)
					(mid 135.32739 -188.364622)
					(end 134.87019 -187.907422)
				)
				(arc
					(start 134.00659 -187.907422)
					(mid 133.54939 -188.364622)
					(end 134.00659 -188.821822)
				)
			)
		)
	)
	(zone
		(layers "F.Cu" "B.Cu" "In1.Cu" "In2.Cu" "In3.Cu" "In4.Cu" "In5.Cu" "In6.Cu"
			"In7.Cu" "In8.Cu" "In9.Cu" "In10.Cu" "In11.Cu" "In12.Cu" "In13.Cu" "In14.Cu"
			"In15.Cu" "In16.Cu"
		)
		(hatch none 0.5)
		(connect_pads
			(clearance 0)
		)
		(min_thickness 0.25)
		(keepout
			(tracks not_allowed)
			(vias allowed)
			(pads allowed)
			(copperpour not_allowed)
			(footprints allowed)
		)
		(placement
			(enabled no)
			(sheetname "")
		)
		(fill
			(thermal_gap 0.5)
			(thermal_bridge_width 0.5)
			(island_removal_mode 0)
		)
		(polygon
			(pts
				(arc
					(start 432.280822 -377.728734)
					(mid 432.295701 -377.692813)
					(end 432.331622 -377.677934)
				)
				(arc
					(start 433.047902 -377.677934)
					(mid 433.083823 -377.692813)
					(end 433.098702 -377.728734)
				)
				(arc
					(start 433.098702 -380.151386)
					(mid 433.083823 -380.187307)
					(end 433.047902 -380.202186)
				)
				(arc
					(start 432.331622 -380.202186)
					(mid 432.295701 -380.187307)
					(end 432.280822 -380.151386)
				)
			)
		)
	)
	(zone
		(layers "F.Cu" "B.Cu" "In1.Cu" "In2.Cu" "In3.Cu" "In4.Cu" "In5.Cu" "In6.Cu"
			"In7.Cu" "In8.Cu" "In9.Cu" "In10.Cu" "In11.Cu" "In12.Cu" "In13.Cu" "In14.Cu"
			"In15.Cu" "In16.Cu"
		)
		(hatch none 0.5)
		(connect_pads
			(clearance 0)
		)
		(min_thickness 0.25)
		(keepout
			(tracks not_allowed)
			(vias allowed)
			(pads allowed)
			(copperpour not_allowed)
			(footprints allowed)
		)
		(placement
			(enabled no)
			(sheetname "")
		)
		(fill
			(thermal_gap 0.5)
			(thermal_bridge_width 0.5)
			(island_removal_mode 0)
		)
		(polygon
			(pts
				(arc
					(start 36.301172 -381.628904)
					(mid 36.316051 -381.592983)
					(end 36.351972 -381.578104)
				)
				(arc
					(start 37.068252 -381.578104)
					(mid 37.104173 -381.592983)
					(end 37.119052 -381.628904)
				)
				(arc
					(start 37.119052 -384.051556)
					(mid 37.104173 -384.087477)
					(end 37.068252 -384.102356)
				)
				(arc
					(start 36.351972 -384.102356)
					(mid 36.316051 -384.087477)
					(end 36.301172 -384.051556)
				)
			)
		)
	)
	(zone
		(layers "F.Cu" "B.Cu" "In1.Cu" "In2.Cu" "In3.Cu" "In4.Cu" "In5.Cu" "In6.Cu"
			"In7.Cu" "In8.Cu" "In9.Cu" "In10.Cu" "In11.Cu" "In12.Cu" "In13.Cu" "In14.Cu"
			"In15.Cu" "In16.Cu"
		)
		(hatch none 0.5)
		(connect_pads
			(clearance 0)
		)
		(min_thickness 0.25)
		(keepout
			(tracks not_allowed)
			(vias allowed)
			(pads allowed)
			(copperpour not_allowed)
			(footprints allowed)
		)
		(placement
			(enabled no)
			(sheetname "")
		)
		(fill
			(thermal_gap 0.5)
			(thermal_bridge_width 0.5)
			(island_removal_mode 0)
		)
		(polygon
			(pts
				(arc
					(start 407.053288 -30.922468)
					(mid 407.510488 -31.379668)
					(end 407.967688 -30.922468)
				)
				(arc
					(start 407.967688 -30.058868)
					(mid 407.510488 -29.601668)
					(end 407.053288 -30.058868)
				)
			)
		)
	)
	(zone
		(layers "F.Cu" "B.Cu" "In1.Cu" "In2.Cu" "In3.Cu" "In4.Cu" "In5.Cu" "In6.Cu"
			"In7.Cu" "In8.Cu" "In9.Cu" "In10.Cu" "In11.Cu" "In12.Cu" "In13.Cu" "In14.Cu"
			"In15.Cu" "In16.Cu"
		)
		(hatch none 0.5)
		(connect_pads
			(clearance 0)
		)
		(min_thickness 0.25)
		(keepout
			(tracks not_allowed)
			(vias allowed)
			(pads allowed)
			(copperpour not_allowed)
			(footprints allowed)
		)
		(placement
			(enabled no)
			(sheetname "")
		)
		(fill
			(thermal_gap 0.5)
			(thermal_bridge_width 0.5)
			(island_removal_mode 0)
		)
		(polygon
			(pts
				(arc
					(start 283.441902 -348.20479)
					(mid 283.060902 -348.58579)
					(end 283.441902 -348.96679)
				)
				(arc
					(start 284.305502 -348.96679)
					(mid 284.686502 -348.58579)
					(end 284.305502 -348.20479)
				)
			)
		)
	)
	(zone
		(layers "F.Cu" "B.Cu" "In1.Cu" "In2.Cu" "In3.Cu" "In4.Cu" "In5.Cu" "In6.Cu"
			"In7.Cu" "In8.Cu" "In9.Cu" "In10.Cu" "In11.Cu" "In12.Cu" "In13.Cu" "In14.Cu"
			"In15.Cu" "In16.Cu"
		)
		(hatch none 0.5)
		(connect_pads
			(clearance 0)
		)
		(min_thickness 0.25)
		(keepout
			(tracks not_allowed)
			(vias allowed)
			(pads allowed)
			(copperpour not_allowed)
			(footprints allowed)
		)
		(placement
			(enabled no)
			(sheetname "")
		)
		(fill
			(thermal_gap 0.5)
			(thermal_bridge_width 0.5)
			(island_removal_mode 0)
		)
		(polygon
			(pts
				(arc
					(start 421.280844 -374.928638)
					(mid 421.295723 -374.892717)
					(end 421.331644 -374.877838)
				)
				(arc
					(start 422.047924 -374.877838)
					(mid 422.083845 -374.892717)
					(end 422.098724 -374.928638)
				)
				(arc
					(start 422.098724 -377.35129)
					(mid 422.083845 -377.387211)
					(end 422.047924 -377.40209)
				)
				(arc
					(start 421.331644 -377.40209)
					(mid 421.295723 -377.387211)
					(end 421.280844 -377.35129)
				)
			)
		)
	)
	(zone
		(layers "F.Cu" "B.Cu" "In1.Cu" "In2.Cu" "In3.Cu" "In4.Cu" "In5.Cu" "In6.Cu"
			"In7.Cu" "In8.Cu" "In9.Cu" "In10.Cu" "In11.Cu" "In12.Cu" "In13.Cu" "In14.Cu"
			"In15.Cu" "In16.Cu"
		)
		(hatch none 0.5)
		(connect_pads
			(clearance 0)
		)
		(min_thickness 0.25)
		(keepout
			(tracks not_allowed)
			(vias allowed)
			(pads allowed)
			(copperpour not_allowed)
			(footprints allowed)
		)
		(placement
			(enabled no)
			(sheetname "")
		)
		(fill
			(thermal_gap 0.5)
			(thermal_bridge_width 0.5)
			(island_removal_mode 0)
		)
		(polygon
			(pts
				(arc
					(start 37.986208 -348.20479)
					(mid 37.605208 -348.58579)
					(end 37.986208 -348.96679)
				)
				(arc
					(start 38.849808 -348.96679)
					(mid 39.230808 -348.58579)
					(end 38.849808 -348.20479)
				)
			)
		)
	)
	(zone
		(layers "F.Cu" "B.Cu" "In1.Cu" "In2.Cu" "In3.Cu" "In4.Cu" "In5.Cu" "In6.Cu"
			"In7.Cu" "In8.Cu" "In9.Cu" "In10.Cu" "In11.Cu" "In12.Cu" "In13.Cu" "In14.Cu"
			"In15.Cu" "In16.Cu"
		)
		(hatch none 0.5)
		(connect_pads
			(clearance 0)
		)
		(min_thickness 0.25)
		(keepout
			(tracks not_allowed)
			(vias allowed)
			(pads allowed)
			(copperpour not_allowed)
			(footprints allowed)
		)
		(placement
			(enabled no)
			(sheetname "")
		)
		(fill
			(thermal_gap 0.5)
			(thermal_bridge_width 0.5)
			(island_removal_mode 0)
		)
		(polygon
			(pts
				(arc
					(start 295.877742 -354.351082)
					(mid 295.496742 -354.732082)
					(end 295.877742 -355.113082)
				)
				(arc
					(start 296.741342 -355.113082)
					(mid 297.122342 -354.732082)
					(end 296.741342 -354.351082)
				)
			)
		)
	)
	(zone
		(layers "F.Cu" "B.Cu" "In1.Cu" "In2.Cu" "In3.Cu" "In4.Cu" "In5.Cu" "In6.Cu"
			"In7.Cu" "In8.Cu" "In9.Cu" "In10.Cu" "In11.Cu" "In12.Cu" "In13.Cu" "In14.Cu"
			"In15.Cu" "In16.Cu"
		)
		(hatch none 0.5)
		(connect_pads
			(clearance 0)
		)
		(min_thickness 0.25)
		(keepout
			(tracks not_allowed)
			(vias allowed)
			(pads allowed)
			(copperpour not_allowed)
			(footprints allowed)
		)
		(placement
			(enabled no)
			(sheetname "")
		)
		(fill
			(thermal_gap 0.5)
			(thermal_bridge_width 0.5)
			(island_removal_mode 0)
		)
		(polygon
			(pts
				(arc
					(start 432.01717 -152.485852)
					(mid 432.47437 -152.943052)
					(end 432.93157 -152.485852)
				)
				(arc
					(start 432.93157 -151.622252)
					(mid 432.47437 -151.165052)
					(end 432.01717 -151.622252)
				)
			)
		)
	)
	(zone
		(layers "F.Cu" "B.Cu" "In1.Cu" "In2.Cu" "In3.Cu" "In4.Cu" "In5.Cu" "In6.Cu"
			"In7.Cu" "In8.Cu" "In9.Cu" "In10.Cu" "In11.Cu" "In12.Cu" "In13.Cu" "In14.Cu"
			"In15.Cu" "In16.Cu"
		)
		(hatch none 0.5)
		(connect_pads
			(clearance 0)
		)
		(min_thickness 0.25)
		(keepout
			(tracks not_allowed)
			(vias allowed)
			(pads allowed)
			(copperpour not_allowed)
			(footprints allowed)
		)
		(placement
			(enabled no)
			(sheetname "")
		)
		(fill
			(thermal_gap 0.5)
			(thermal_bridge_width 0.5)
			(island_removal_mode 0)
		)
		(polygon
			(pts
				(arc
					(start 379.48108 -395.92885)
					(mid 379.495959 -395.892929)
					(end 379.53188 -395.87805)
				)
				(arc
					(start 380.24816 -395.87805)
					(mid 380.284081 -395.892929)
					(end 380.29896 -395.92885)
				)
				(arc
					(start 380.29896 -398.351502)
					(mid 380.284081 -398.387423)
					(end 380.24816 -398.402302)
				)
				(arc
					(start 379.53188 -398.402302)
					(mid 379.495959 -398.387423)
					(end 379.48108 -398.351502)
				)
			)
		)
	)
	(zone
		(layers "F.Cu" "B.Cu" "In1.Cu" "In2.Cu" "In3.Cu" "In4.Cu" "In5.Cu" "In6.Cu"
			"In7.Cu" "In8.Cu" "In9.Cu" "In10.Cu" "In11.Cu" "In12.Cu" "In13.Cu" "In14.Cu"
			"In15.Cu" "In16.Cu"
		)
		(hatch none 0.5)
		(connect_pads
			(clearance 0)
		)
		(min_thickness 0.25)
		(keepout
			(tracks not_allowed)
			(vias allowed)
			(pads allowed)
			(copperpour not_allowed)
			(footprints allowed)
		)
		(placement
			(enabled no)
			(sheetname "")
		)
		(fill
			(thermal_gap 0.5)
			(thermal_bridge_width 0.5)
			(island_removal_mode 0)
		)
		(polygon
			(pts
				(arc
					(start 401.494498 7.718044)
					(mid 401.875498 7.337044)
					(end 402.256498 7.718044)
				)
				(arc
					(start 402.256498 8.581644)
					(mid 401.875498 8.962644)
					(end 401.494498 8.581644)
				)
			)
		)
	)
	(zone
		(layers "F.Cu" "B.Cu" "In1.Cu" "In2.Cu" "In3.Cu" "In4.Cu" "In5.Cu" "In6.Cu"
			"In7.Cu" "In8.Cu" "In9.Cu" "In10.Cu" "In11.Cu" "In12.Cu" "In13.Cu" "In14.Cu"
			"In15.Cu" "In16.Cu"
		)
		(hatch none 0.5)
		(connect_pads
			(clearance 0)
		)
		(min_thickness 0.25)
		(keepout
			(tracks not_allowed)
			(vias allowed)
			(pads allowed)
			(copperpour not_allowed)
			(footprints allowed)
		)
		(placement
			(enabled no)
			(sheetname "")
		)
		(fill
			(thermal_gap 0.5)
			(thermal_bridge_width 0.5)
			(island_removal_mode 0)
		)
		(polygon
			(pts
				(arc
					(start 413.04591 -121.367296)
					(mid 413.50311 -121.824496)
					(end 413.96031 -121.367296)
				)
				(arc
					(start 413.96031 -120.503696)
					(mid 413.50311 -120.046496)
					(end 413.04591 -120.503696)
				)
			)
		)
	)
	(zone
		(layers "F.Cu" "B.Cu" "In1.Cu" "In2.Cu" "In3.Cu" "In4.Cu" "In5.Cu" "In6.Cu"
			"In7.Cu" "In8.Cu" "In9.Cu" "In10.Cu" "In11.Cu" "In12.Cu" "In13.Cu" "In14.Cu"
			"In15.Cu" "In16.Cu"
		)
		(hatch none 0.5)
		(connect_pads
			(clearance 0)
		)
		(min_thickness 0.25)
		(keepout
			(tracks not_allowed)
			(vias allowed)
			(pads allowed)
			(copperpour not_allowed)
			(footprints allowed)
		)
		(placement
			(enabled no)
			(sheetname "")
		)
		(fill
			(thermal_gap 0.5)
			(thermal_bridge_width 0.5)
			(island_removal_mode 0)
		)
		(polygon
			(pts
				(arc
					(start 390.824212 -27.342846)
					(mid 391.281412 -27.800046)
					(end 391.738612 -27.342846)
				)
				(arc
					(start 391.738612 -26.479246)
					(mid 391.281412 -26.022046)
					(end 390.824212 -26.479246)
				)
			)
		)
	)
	(zone
		(layers "F.Cu" "B.Cu" "In1.Cu" "In2.Cu" "In3.Cu" "In4.Cu" "In5.Cu" "In6.Cu"
			"In7.Cu" "In8.Cu" "In9.Cu" "In10.Cu" "In11.Cu" "In12.Cu" "In13.Cu" "In14.Cu"
			"In15.Cu" "In16.Cu"
		)
		(hatch none 0.5)
		(connect_pads
			(clearance 0)
		)
		(min_thickness 0.25)
		(keepout
			(tracks not_allowed)
			(vias allowed)
			(pads allowed)
			(copperpour not_allowed)
			(footprints allowed)
		)
		(placement
			(enabled no)
			(sheetname "")
		)
		(fill
			(thermal_gap 0.5)
			(thermal_bridge_width 0.5)
			(island_removal_mode 0)
		)
		(polygon
			(pts
				(arc
					(start 432.280822 -381.628904)
					(mid 432.295701 -381.592983)
					(end 432.331622 -381.578104)
				)
				(arc
					(start 433.047902 -381.578104)
					(mid 433.083823 -381.592983)
					(end 433.098702 -381.628904)
				)
				(arc
					(start 433.098702 -384.051556)
					(mid 433.083823 -384.087477)
					(end 433.047902 -384.102356)
				)
				(arc
					(start 432.331622 -384.102356)
					(mid 432.295701 -384.087477)
					(end 432.280822 -384.051556)
				)
			)
		)
	)
	(zone
		(layers "F.Cu" "B.Cu" "In1.Cu" "In2.Cu" "In3.Cu" "In4.Cu" "In5.Cu" "In6.Cu"
			"In7.Cu" "In8.Cu" "In9.Cu" "In10.Cu" "In11.Cu" "In12.Cu" "In13.Cu" "In14.Cu"
			"In15.Cu" "In16.Cu"
		)
		(hatch none 0.5)
		(connect_pads
			(clearance 0)
		)
		(min_thickness 0.25)
		(keepout
			(tracks not_allowed)
			(vias allowed)
			(pads allowed)
			(copperpour not_allowed)
			(footprints allowed)
		)
		(placement
			(enabled no)
			(sheetname "")
		)
		(fill
			(thermal_gap 0.5)
			(thermal_bridge_width 0.5)
			(island_removal_mode 0)
		)
		(polygon
			(pts
				(arc
					(start 135.703056 -167.578024)
					(mid 135.245856 -168.035224)
					(end 135.703056 -168.492424)
				)
				(arc
					(start 136.566656 -168.492424)
					(mid 137.023856 -168.035224)
					(end 136.566656 -167.578024)
				)
			)
		)
	)
	(zone
		(layers "F.Cu" "B.Cu" "In1.Cu" "In2.Cu" "In3.Cu" "In4.Cu" "In5.Cu" "In6.Cu"
			"In7.Cu" "In8.Cu" "In9.Cu" "In10.Cu" "In11.Cu" "In12.Cu" "In13.Cu" "In14.Cu"
			"In15.Cu" "In16.Cu"
		)
		(hatch none 0.5)
		(connect_pads
			(clearance 0)
		)
		(min_thickness 0.25)
		(keepout
			(tracks not_allowed)
			(vias allowed)
			(pads allowed)
			(copperpour not_allowed)
			(footprints allowed)
		)
		(placement
			(enabled no)
			(sheetname "")
		)
		(fill
			(thermal_gap 0.5)
			(thermal_bridge_width 0.5)
			(island_removal_mode 0)
		)
		(polygon
			(pts
				(arc
					(start 38.501066 -378.828554)
					(mid 38.515945 -378.792633)
					(end 38.551866 -378.777754)
				)
				(arc
					(start 39.268146 -378.777754)
					(mid 39.304067 -378.792633)
					(end 39.318946 -378.828554)
				)
				(arc
					(start 39.318946 -381.251206)
					(mid 39.304067 -381.287127)
					(end 39.268146 -381.302006)
				)
				(arc
					(start 38.551866 -381.302006)
					(mid 38.515945 -381.287127)
					(end 38.501066 -381.251206)
				)
			)
		)
	)
	(zone
		(layers "F.Cu" "B.Cu" "In1.Cu" "In2.Cu" "In3.Cu" "In4.Cu" "In5.Cu" "In6.Cu"
			"In7.Cu" "In8.Cu" "In9.Cu" "In10.Cu" "In11.Cu" "In12.Cu" "In13.Cu" "In14.Cu"
			"In15.Cu" "In16.Cu"
		)
		(hatch none 0.5)
		(connect_pads
			(clearance 0)
		)
		(min_thickness 0.25)
		(keepout
			(tracks not_allowed)
			(vias allowed)
			(pads allowed)
			(copperpour not_allowed)
			(footprints allowed)
		)
		(placement
			(enabled no)
			(sheetname "")
		)
		(fill
			(thermal_gap 0.5)
			(thermal_bridge_width 0.5)
			(island_removal_mode 0)
		)
		(polygon
			(pts
				(arc
					(start 170.654218 -122.822716)
					(mid 170.197018 -122.365516)
					(end 169.739818 -122.822716)
				)
				(arc
					(start 169.739818 -123.686316)
					(mid 170.197018 -124.143516)
					(end 170.654218 -123.686316)
				)
			)
		)
	)
	(zone
		(layers "F.Cu" "B.Cu" "In1.Cu" "In2.Cu" "In3.Cu" "In4.Cu" "In5.Cu" "In6.Cu"
			"In7.Cu" "In8.Cu" "In9.Cu" "In10.Cu" "In11.Cu" "In12.Cu" "In13.Cu" "In14.Cu"
			"In15.Cu" "In16.Cu"
		)
		(hatch none 0.5)
		(connect_pads
			(clearance 0)
		)
		(min_thickness 0.25)
		(keepout
			(tracks not_allowed)
			(vias allowed)
			(pads allowed)
			(copperpour not_allowed)
			(footprints allowed)
		)
		(placement
			(enabled no)
			(sheetname "")
		)
		(fill
			(thermal_gap 0.5)
			(thermal_bridge_width 0.5)
			(island_removal_mode 0)
		)
		(polygon
			(pts
				(arc
					(start 71.501 -373.828818)
					(mid 71.515879 -373.792897)
					(end 71.5518 -373.778018)
				)
				(arc
					(start 72.26808 -373.778018)
					(mid 72.304001 -373.792897)
					(end 72.31888 -373.828818)
				)
				(arc
					(start 72.31888 -376.25147)
					(mid 72.304001 -376.287391)
					(end 72.26808 -376.30227)
				)
				(arc
					(start 71.5518 -376.30227)
					(mid 71.515879 -376.287391)
					(end 71.501 -376.25147)
				)
			)
		)
	)
	(zone
		(layers "F.Cu" "B.Cu" "In1.Cu" "In2.Cu" "In3.Cu" "In4.Cu" "In5.Cu" "In6.Cu"
			"In7.Cu" "In8.Cu" "In9.Cu" "In10.Cu" "In11.Cu" "In12.Cu" "In13.Cu" "In14.Cu"
			"In15.Cu" "In16.Cu"
		)
		(hatch none 0.5)
		(connect_pads
			(clearance 0)
		)
		(min_thickness 0.25)
		(keepout
			(tracks not_allowed)
			(vias allowed)
			(pads allowed)
			(copperpour not_allowed)
			(footprints allowed)
		)
		(placement
			(enabled no)
			(sheetname "")
		)
		(fill
			(thermal_gap 0.5)
			(thermal_bridge_width 0.5)
			(island_removal_mode 0)
		)
		(polygon
			(pts
				(arc
					(start 159.501078 -395.92885)
					(mid 159.515957 -395.892929)
					(end 159.551878 -395.87805)
				)
				(arc
					(start 160.268158 -395.87805)
					(mid 160.304079 -395.892929)
					(end 160.318958 -395.92885)
				)
				(arc
					(start 160.318958 -398.351502)
					(mid 160.304079 -398.387423)
					(end 160.268158 -398.402302)
				)
				(arc
					(start 159.551878 -398.402302)
					(mid 159.515957 -398.387423)
					(end 159.501078 -398.351502)
				)
			)
		)
	)
	(zone
		(layers "F.Cu" "B.Cu" "In1.Cu" "In2.Cu" "In3.Cu" "In4.Cu" "In5.Cu" "In6.Cu"
			"In7.Cu" "In8.Cu" "In9.Cu" "In10.Cu" "In11.Cu" "In12.Cu" "In13.Cu" "In14.Cu"
			"In15.Cu" "In16.Cu"
		)
		(hatch none 0.5)
		(connect_pads
			(clearance 0)
		)
		(min_thickness 0.25)
		(keepout
			(tracks not_allowed)
			(vias allowed)
			(pads allowed)
			(copperpour not_allowed)
			(footprints allowed)
		)
		(placement
			(enabled no)
			(sheetname "")
		)
		(fill
			(thermal_gap 0.5)
			(thermal_bridge_width 0.5)
			(island_removal_mode 0)
		)
		(polygon
			(pts
				(arc
					(start 83.134962 -342.058498)
					(mid 82.753962 -342.439498)
					(end 83.134962 -342.820498)
				)
				(arc
					(start 83.998562 -342.820498)
					(mid 84.379562 -342.439498)
					(end 83.998562 -342.058498)
				)
			)
		)
	)
	(zone
		(layers "F.Cu" "B.Cu" "In1.Cu" "In2.Cu" "In3.Cu" "In4.Cu" "In5.Cu" "In6.Cu"
			"In7.Cu" "In8.Cu" "In9.Cu" "In10.Cu" "In11.Cu" "In12.Cu" "In13.Cu" "In14.Cu"
			"In15.Cu" "In16.Cu"
		)
		(hatch none 0.5)
		(connect_pads
			(clearance 0)
		)
		(min_thickness 0.25)
		(keepout
			(tracks not_allowed)
			(vias allowed)
			(pads allowed)
			(copperpour not_allowed)
			(footprints allowed)
		)
		(placement
			(enabled no)
			(sheetname "")
		)
		(fill
			(thermal_gap 0.5)
			(thermal_bridge_width 0.5)
			(island_removal_mode 0)
		)
		(polygon
			(pts
				(arc
					(start 432.280822 -403.728682)
					(mid 432.295701 -403.692761)
					(end 432.331622 -403.677882)
				)
				(arc
					(start 433.047902 -403.677882)
					(mid 433.083823 -403.692761)
					(end 433.098702 -403.728682)
				)
				(arc
					(start 433.098702 -406.151334)
					(mid 433.083823 -406.187255)
					(end 433.047902 -406.202134)
				)
				(arc
					(start 432.331622 -406.202134)
					(mid 432.295701 -406.187255)
					(end 432.280822 -406.151334)
				)
			)
		)
	)
	(zone
		(layers "F.Cu" "B.Cu" "In1.Cu" "In2.Cu" "In3.Cu" "In4.Cu" "In5.Cu" "In6.Cu"
			"In7.Cu" "In8.Cu" "In9.Cu" "In10.Cu" "In11.Cu" "In12.Cu" "In13.Cu" "In14.Cu"
			"In15.Cu" "In16.Cu"
		)
		(hatch none 0.5)
		(connect_pads
			(clearance 0)
		)
		(min_thickness 0.25)
		(keepout
			(tracks not_allowed)
			(vias allowed)
			(pads allowed)
			(copperpour not_allowed)
			(footprints allowed)
		)
		(placement
			(enabled no)
			(sheetname "")
		)
		(fill
			(thermal_gap 0.5)
			(thermal_bridge_width 0.5)
			(island_removal_mode 0)
		)
		(polygon
			(pts
				(arc
					(start 86.90102 -382.728724)
					(mid 86.915899 -382.692803)
					(end 86.95182 -382.677924)
				)
				(arc
					(start 87.6681 -382.677924)
					(mid 87.704021 -382.692803)
					(end 87.7189 -382.728724)
				)
				(arc
					(start 87.7189 -385.151376)
					(mid 87.704021 -385.187297)
					(end 87.6681 -385.202176)
				)
				(arc
					(start 86.95182 -385.202176)
					(mid 86.915899 -385.187297)
					(end 86.90102 -385.151376)
				)
			)
		)
	)
	(zone
		(layers "F.Cu" "B.Cu" "In1.Cu" "In2.Cu" "In3.Cu" "In4.Cu" "In5.Cu" "In6.Cu"
			"In7.Cu" "In8.Cu" "In9.Cu" "In10.Cu" "In11.Cu" "In12.Cu" "In13.Cu" "In14.Cu"
			"In15.Cu" "In16.Cu"
		)
		(hatch none 0.5)
		(connect_pads
			(clearance 0)
		)
		(min_thickness 0.25)
		(keepout
			(tracks not_allowed)
			(vias allowed)
			(pads allowed)
			(copperpour not_allowed)
			(footprints allowed)
		)
		(placement
			(enabled no)
			(sheetname "")
		)
		(fill
			(thermal_gap 0.5)
			(thermal_bridge_width 0.5)
			(island_removal_mode 0)
		)
		(polygon
			(pts
				(arc
					(start 60.607448 -29.12237)
					(mid 61.064648 -29.57957)
					(end 61.521848 -29.12237)
				)
				(arc
					(start 61.521848 -28.25877)
					(mid 61.064648 -27.80157)
					(end 60.607448 -28.25877)
				)
			)
		)
	)
	(zone
		(layers "F.Cu" "B.Cu" "In1.Cu" "In2.Cu" "In3.Cu" "In4.Cu" "In5.Cu" "In6.Cu"
			"In7.Cu" "In8.Cu" "In9.Cu" "In10.Cu" "In11.Cu" "In12.Cu" "In13.Cu" "In14.Cu"
			"In15.Cu" "In16.Cu"
		)
		(hatch none 0.5)
		(connect_pads
			(clearance 0)
		)
		(min_thickness 0.25)
		(keepout
			(tracks not_allowed)
			(vias allowed)
			(pads allowed)
			(copperpour not_allowed)
			(footprints allowed)
		)
		(placement
			(enabled no)
			(sheetname "")
		)
		(fill
			(thermal_gap 0.5)
			(thermal_bridge_width 0.5)
			(island_removal_mode 0)
		)
		(polygon
			(pts
				(arc
					(start 111.862108 -342.058498)
					(mid 111.481108 -342.439498)
					(end 111.862108 -342.820498)
				)
				(arc
					(start 112.725708 -342.820498)
					(mid 113.106708 -342.439498)
					(end 112.725708 -342.058498)
				)
			)
		)
	)
	(zone
		(layers "F.Cu" "B.Cu" "In1.Cu" "In2.Cu" "In3.Cu" "In4.Cu" "In5.Cu" "In6.Cu"
			"In7.Cu" "In8.Cu" "In9.Cu" "In10.Cu" "In11.Cu" "In12.Cu" "In13.Cu" "In14.Cu"
			"In15.Cu" "In16.Cu"
		)
		(hatch none 0.5)
		(connect_pads
			(clearance 0)
		)
		(min_thickness 0.25)
		(keepout
			(tracks not_allowed)
			(vias allowed)
			(pads allowed)
			(copperpour not_allowed)
			(footprints allowed)
		)
		(placement
			(enabled no)
			(sheetname "")
		)
		(fill
			(thermal_gap 0.5)
			(thermal_bridge_width 0.5)
			(island_removal_mode 0)
		)
		(polygon
			(pts
				(arc
					(start 92.461842 -348.20479)
					(mid 92.080842 -348.58579)
					(end 92.461842 -348.96679)
				)
				(arc
					(start 93.325442 -348.96679)
					(mid 93.706442 -348.58579)
					(end 93.325442 -348.20479)
				)
			)
		)
	)
	(zone
		(layers "F.Cu" "B.Cu" "In1.Cu" "In2.Cu" "In3.Cu" "In4.Cu" "In5.Cu" "In6.Cu"
			"In7.Cu" "In8.Cu" "In9.Cu" "In10.Cu" "In11.Cu" "In12.Cu" "In13.Cu" "In14.Cu"
			"In15.Cu" "In16.Cu"
		)
		(hatch none 0.5)
		(connect_pads
			(clearance 0)
		)
		(min_thickness 0.25)
		(keepout
			(tracks not_allowed)
			(vias allowed)
			(pads allowed)
			(copperpour not_allowed)
			(footprints allowed)
		)
		(placement
			(enabled no)
			(sheetname "")
		)
		(fill
			(thermal_gap 0.5)
			(thermal_bridge_width 0.5)
			(island_removal_mode 0)
		)
		(polygon
			(pts
				(arc
					(start 343.592404 -345.084146)
					(mid 343.211404 -345.465146)
					(end 343.592404 -345.846146)
				)
				(arc
					(start 344.456004 -345.846146)
					(mid 344.837004 -345.465146)
					(end 344.456004 -345.084146)
				)
			)
		)
	)
	(zone
		(layers "F.Cu" "B.Cu" "In1.Cu" "In2.Cu" "In3.Cu" "In4.Cu" "In5.Cu" "In6.Cu"
			"In7.Cu" "In8.Cu" "In9.Cu" "In10.Cu" "In11.Cu" "In12.Cu" "In13.Cu" "In14.Cu"
			"In15.Cu" "In16.Cu"
		)
		(hatch none 0.5)
		(connect_pads
			(clearance 0)
		)
		(min_thickness 0.25)
		(keepout
			(tracks not_allowed)
			(vias allowed)
			(pads allowed)
			(copperpour not_allowed)
			(footprints allowed)
		)
		(placement
			(enabled no)
			(sheetname "")
		)
		(fill
			(thermal_gap 0.5)
			(thermal_bridge_width 0.5)
			(island_removal_mode 0)
		)
		(polygon
			(pts
				(arc
					(start 366.68964 -333.374492)
					(mid 367.14684 -332.917292)
					(end 366.68964 -332.460092)
				)
				(arc
					(start 365.82604 -332.460092)
					(mid 365.36884 -332.917292)
					(end 365.82604 -333.374492)
				)
			)
		)
	)
	(zone
		(layers "F.Cu" "B.Cu" "In1.Cu" "In2.Cu" "In3.Cu" "In4.Cu" "In5.Cu" "In6.Cu"
			"In7.Cu" "In8.Cu" "In9.Cu" "In10.Cu" "In11.Cu" "In12.Cu" "In13.Cu" "In14.Cu"
			"In15.Cu" "In16.Cu"
		)
		(hatch none 0.5)
		(connect_pads
			(clearance 0)
		)
		(min_thickness 0.25)
		(keepout
			(tracks not_allowed)
			(vias allowed)
			(pads allowed)
			(copperpour not_allowed)
			(footprints allowed)
		)
		(placement
			(enabled no)
			(sheetname "")
		)
		(fill
			(thermal_gap 0.5)
			(thermal_bridge_width 0.5)
			(island_removal_mode 0)
		)
		(polygon
			(pts
				(arc
					(start 274.115022 -342.058498)
					(mid 273.734022 -342.439498)
					(end 274.115022 -342.820498)
				)
				(arc
					(start 274.978622 -342.820498)
					(mid 275.359622 -342.439498)
					(end 274.978622 -342.058498)
				)
			)
		)
	)
	(zone
		(layers "F.Cu" "B.Cu" "In1.Cu" "In2.Cu" "In3.Cu" "In4.Cu" "In5.Cu" "In6.Cu"
			"In7.Cu" "In8.Cu" "In9.Cu" "In10.Cu" "In11.Cu" "In12.Cu" "In13.Cu" "In14.Cu"
			"In15.Cu" "In16.Cu"
		)
		(hatch none 0.5)
		(connect_pads
			(clearance 0)
		)
		(min_thickness 0.25)
		(keepout
			(tracks not_allowed)
			(vias allowed)
			(pads allowed)
			(copperpour not_allowed)
			(footprints allowed)
		)
		(placement
			(enabled no)
			(sheetname "")
		)
		(fill
			(thermal_gap 0.5)
			(thermal_bridge_width 0.5)
			(island_removal_mode 0)
		)
		(polygon
			(pts
				(arc
					(start 286.754062 -99.31273)
					(mid 286.296862 -98.85553)
					(end 285.839662 -99.31273)
				)
				(arc
					(start 285.839662 -100.17633)
					(mid 286.296862 -100.63353)
					(end 286.754062 -100.17633)
				)
			)
		)
	)
	(zone
		(layers "F.Cu" "B.Cu" "In1.Cu" "In2.Cu" "In3.Cu" "In4.Cu" "In5.Cu" "In6.Cu"
			"In7.Cu" "In8.Cu" "In9.Cu" "In10.Cu" "In11.Cu" "In12.Cu" "In13.Cu" "In14.Cu"
			"In15.Cu" "In16.Cu"
		)
		(hatch none 0.5)
		(connect_pads
			(clearance 0)
		)
		(min_thickness 0.25)
		(keepout
			(tracks not_allowed)
			(vias allowed)
			(pads allowed)
			(copperpour not_allowed)
			(footprints allowed)
		)
		(placement
			(enabled no)
			(sheetname "")
		)
		(fill
			(thermal_gap 0.5)
			(thermal_bridge_width 0.5)
			(island_removal_mode 0)
		)
		(polygon
			(pts
				(arc
					(start 328.047604 -351.230438)
					(mid 327.666604 -351.611438)
					(end 328.047604 -351.992438)
				)
				(arc
					(start 328.911204 -351.992438)
					(mid 329.292204 -351.611438)
					(end 328.911204 -351.230438)
				)
			)
		)
	)
	(zone
		(layers "F.Cu" "B.Cu" "In1.Cu" "In2.Cu" "In3.Cu" "In4.Cu" "In5.Cu" "In6.Cu"
			"In7.Cu" "In8.Cu" "In9.Cu" "In10.Cu" "In11.Cu" "In12.Cu" "In13.Cu" "In14.Cu"
			"In15.Cu" "In16.Cu"
		)
		(hatch none 0.5)
		(connect_pads
			(clearance 0)
		)
		(min_thickness 0.25)
		(keepout
			(tracks not_allowed)
			(vias allowed)
			(pads allowed)
			(copperpour not_allowed)
			(footprints allowed)
		)
		(placement
			(enabled no)
			(sheetname "")
		)
		(fill
			(thermal_gap 0.5)
			(thermal_bridge_width 0.5)
			(island_removal_mode 0)
		)
		(polygon
			(pts
				(arc
					(start 42.901108 -404.828756)
					(mid 42.915987 -404.792835)
					(end 42.951908 -404.777956)
				)
				(arc
					(start 43.668188 -404.777956)
					(mid 43.704109 -404.792835)
					(end 43.718988 -404.828756)
				)
				(arc
					(start 43.718988 -407.251408)
					(mid 43.704109 -407.287329)
					(end 43.668188 -407.302208)
				)
				(arc
					(start 42.951908 -407.302208)
					(mid 42.915987 -407.287329)
					(end 42.901108 -407.251408)
				)
			)
		)
	)
	(zone
		(layers "F.Cu" "B.Cu" "In1.Cu" "In2.Cu" "In3.Cu" "In4.Cu" "In5.Cu" "In6.Cu"
			"In7.Cu" "In8.Cu" "In9.Cu" "In10.Cu" "In11.Cu" "In12.Cu" "In13.Cu" "In14.Cu"
			"In15.Cu" "In16.Cu"
		)
		(hatch none 0.5)
		(connect_pads
			(clearance 0)
		)
		(min_thickness 0.25)
		(keepout
			(tracks not_allowed)
			(vias allowed)
			(pads allowed)
			(copperpour not_allowed)
			(footprints allowed)
		)
		(placement
			(enabled no)
			(sheetname "")
		)
		(fill
			(thermal_gap 0.5)
			(thermal_bridge_width 0.5)
			(island_removal_mode 0)
		)
		(polygon
			(pts
				(arc
					(start 293.680896 -382.728724)
					(mid 293.695775 -382.692803)
					(end 293.731696 -382.677924)
				)
				(arc
					(start 294.447976 -382.677924)
					(mid 294.483897 -382.692803)
					(end 294.498776 -382.728724)
				)
				(arc
					(start 294.498776 -385.151376)
					(mid 294.483897 -385.187297)
					(end 294.447976 -385.202176)
				)
				(arc
					(start 293.731696 -385.202176)
					(mid 293.695775 -385.187297)
					(end 293.680896 -385.151376)
				)
			)
		)
	)
	(zone
		(layers "F.Cu" "B.Cu" "In1.Cu" "In2.Cu" "In3.Cu" "In4.Cu" "In5.Cu" "In6.Cu"
			"In7.Cu" "In8.Cu" "In9.Cu" "In10.Cu" "In11.Cu" "In12.Cu" "In13.Cu" "In14.Cu"
			"In15.Cu" "In16.Cu"
		)
		(hatch none 0.5)
		(connect_pads
			(clearance 0)
		)
		(min_thickness 0.25)
		(keepout
			(tracks not_allowed)
			(vias allowed)
			(pads allowed)
			(copperpour not_allowed)
			(footprints allowed)
		)
		(placement
			(enabled no)
			(sheetname "")
		)
		(fill
			(thermal_gap 0.5)
			(thermal_bridge_width 0.5)
			(island_removal_mode 0)
		)
		(polygon
			(pts
				(arc
					(start 344.280998 -403.728682)
					(mid 344.295877 -403.692761)
					(end 344.331798 -403.677882)
				)
				(arc
					(start 345.048078 -403.677882)
					(mid 345.083999 -403.692761)
					(end 345.098878 -403.728682)
				)
				(arc
					(start 345.098878 -406.151334)
					(mid 345.083999 -406.187255)
					(end 345.048078 -406.202134)
				)
				(arc
					(start 344.331798 -406.202134)
					(mid 344.295877 -406.187255)
					(end 344.280998 -406.151334)
				)
			)
		)
	)
	(zone
		(layers "F.Cu" "B.Cu" "In1.Cu" "In2.Cu" "In3.Cu" "In4.Cu" "In5.Cu" "In6.Cu"
			"In7.Cu" "In8.Cu" "In9.Cu" "In10.Cu" "In11.Cu" "In12.Cu" "In13.Cu" "In14.Cu"
			"In15.Cu" "In16.Cu"
		)
		(hatch none 0.5)
		(connect_pads
			(clearance 0)
		)
		(min_thickness 0.25)
		(keepout
			(tracks not_allowed)
			(vias allowed)
			(pads allowed)
			(copperpour not_allowed)
			(footprints allowed)
		)
		(placement
			(enabled no)
			(sheetname "")
		)
		(fill
			(thermal_gap 0.5)
			(thermal_bridge_width 0.5)
			(island_removal_mode 0)
		)
		(polygon
			(pts
				(arc
					(start 253.69012 -34.520886)
					(mid 254.14732 -34.978086)
					(end 254.60452 -34.520886)
				)
				(arc
					(start 254.60452 -33.657286)
					(mid 254.14732 -33.200086)
					(end 253.69012 -33.657286)
				)
			)
		)
	)
	(zone
		(layers "F.Cu" "B.Cu" "In1.Cu" "In2.Cu" "In3.Cu" "In4.Cu" "In5.Cu" "In6.Cu"
			"In7.Cu" "In8.Cu" "In9.Cu" "In10.Cu" "In11.Cu" "In12.Cu" "In13.Cu" "In14.Cu"
			"In15.Cu" "In16.Cu"
		)
		(hatch none 0.5)
		(connect_pads
			(clearance 0)
		)
		(min_thickness 0.25)
		(keepout
			(tracks not_allowed)
			(vias allowed)
			(pads allowed)
			(copperpour not_allowed)
			(footprints allowed)
		)
		(placement
			(enabled no)
			(sheetname "")
		)
		(fill
			(thermal_gap 0.5)
			(thermal_bridge_width 0.5)
			(island_removal_mode 0)
		)
		(polygon
			(pts
				(arc
					(start 315.917072 -156.085794)
					(mid 316.374272 -156.542994)
					(end 316.831472 -156.085794)
				)
				(arc
					(start 316.831472 -155.222194)
					(mid 316.374272 -154.764994)
					(end 315.917072 -155.222194)
				)
			)
		)
	)
	(zone
		(layers "F.Cu" "B.Cu" "In1.Cu" "In2.Cu" "In3.Cu" "In4.Cu" "In5.Cu" "In6.Cu"
			"In7.Cu" "In8.Cu" "In9.Cu" "In10.Cu" "In11.Cu" "In12.Cu" "In13.Cu" "In14.Cu"
			"In15.Cu" "In16.Cu"
		)
		(hatch none 0.5)
		(connect_pads
			(clearance 0)
		)
		(min_thickness 0.25)
		(keepout
			(tracks not_allowed)
			(vias allowed)
			(pads allowed)
			(copperpour not_allowed)
			(footprints allowed)
		)
		(placement
			(enabled no)
			(sheetname "")
		)
		(fill
			(thermal_gap 0.5)
			(thermal_bridge_width 0.5)
			(island_removal_mode 0)
		)
		(polygon
			(pts
				(arc
					(start 70.699122 -351.230438)
					(mid 70.318122 -351.611438)
					(end 70.699122 -351.992438)
				)
				(arc
					(start 71.562722 -351.992438)
					(mid 71.943722 -351.611438)
					(end 71.562722 -351.230438)
				)
			)
		)
	)
	(zone
		(layers "F.Cu" "B.Cu" "In1.Cu" "In2.Cu" "In3.Cu" "In4.Cu" "In5.Cu" "In6.Cu"
			"In7.Cu" "In8.Cu" "In9.Cu" "In10.Cu" "In11.Cu" "In12.Cu" "In13.Cu" "In14.Cu"
			"In15.Cu" "In16.Cu"
		)
		(hatch none 0.5)
		(connect_pads
			(clearance 0)
		)
		(min_thickness 0.25)
		(keepout
			(tracks not_allowed)
			(vias allowed)
			(pads allowed)
			(copperpour not_allowed)
			(footprints allowed)
		)
		(placement
			(enabled no)
			(sheetname "")
		)
		(fill
			(thermal_gap 0.5)
			(thermal_bridge_width 0.5)
			(island_removal_mode 0)
		)
		(polygon
			(pts
				(arc
					(start 396.05966 -354.351082)
					(mid 395.67866 -354.732082)
					(end 396.05966 -355.113082)
				)
				(arc
					(start 396.92326 -355.113082)
					(mid 397.30426 -354.732082)
					(end 396.92326 -354.351082)
				)
			)
		)
	)
	(zone
		(layers "F.Cu" "B.Cu" "In1.Cu" "In2.Cu" "In3.Cu" "In4.Cu" "In5.Cu" "In6.Cu"
			"In7.Cu" "In8.Cu" "In9.Cu" "In10.Cu" "In11.Cu" "In12.Cu" "In13.Cu" "In14.Cu"
			"In15.Cu" "In16.Cu"
		)
		(hatch none 0.5)
		(connect_pads
			(clearance 0)
		)
		(min_thickness 0.25)
		(keepout
			(tracks not_allowed)
			(vias allowed)
			(pads allowed)
			(copperpour not_allowed)
			(footprints allowed)
		)
		(placement
			(enabled no)
			(sheetname "")
		)
		(fill
			(thermal_gap 0.5)
			(thermal_bridge_width 0.5)
			(island_removal_mode 0)
		)
		(polygon
			(pts
				(arc
					(start 124.297948 -354.351082)
					(mid 123.916948 -354.732082)
					(end 124.297948 -355.113082)
				)
				(arc
					(start 125.161548 -355.113082)
					(mid 125.542548 -354.732082)
					(end 125.161548 -354.351082)
				)
			)
		)
	)
	(zone
		(layers "F.Cu" "B.Cu" "In1.Cu" "In2.Cu" "In3.Cu" "In4.Cu" "In5.Cu" "In6.Cu"
			"In7.Cu" "In8.Cu" "In9.Cu" "In10.Cu" "In11.Cu" "In12.Cu" "In13.Cu" "In14.Cu"
			"In15.Cu" "In16.Cu"
		)
		(hatch none 0.5)
		(connect_pads
			(clearance 0)
		)
		(min_thickness 0.25)
		(keepout
			(tracks not_allowed)
			(vias allowed)
			(pads allowed)
			(copperpour not_allowed)
			(footprints allowed)
		)
		(placement
			(enabled no)
			(sheetname "")
		)
		(fill
			(thermal_gap 0.5)
			(thermal_bridge_width 0.5)
			(island_removal_mode 0)
		)
		(polygon
			(pts
				(arc
					(start 340.483444 -354.351082)
					(mid 340.102444 -354.732082)
					(end 340.483444 -355.113082)
				)
				(arc
					(start 341.347044 -355.113082)
					(mid 341.728044 -354.732082)
					(end 341.347044 -354.351082)
				)
			)
		)
	)
	(zone
		(layers "F.Cu" "B.Cu" "In1.Cu" "In2.Cu" "In3.Cu" "In4.Cu" "In5.Cu" "In6.Cu"
			"In7.Cu" "In8.Cu" "In9.Cu" "In10.Cu" "In11.Cu" "In12.Cu" "In13.Cu" "In14.Cu"
			"In15.Cu" "In16.Cu"
		)
		(hatch none 0.5)
		(connect_pads
			(clearance 0)
		)
		(min_thickness 0.25)
		(keepout
			(tracks not_allowed)
			(vias allowed)
			(pads allowed)
			(copperpour not_allowed)
			(footprints allowed)
		)
		(placement
			(enabled no)
			(sheetname "")
		)
		(fill
			(thermal_gap 0.5)
			(thermal_bridge_width 0.5)
			(island_removal_mode 0)
		)
		(polygon
			(pts
				(arc
					(start 382.90754 -29.12237)
					(mid 383.36474 -29.57957)
					(end 383.82194 -29.12237)
				)
				(arc
					(start 383.82194 -28.25877)
					(mid 383.36474 -27.80157)
					(end 382.90754 -28.25877)
				)
			)
		)
	)
	(zone
		(layers "F.Cu" "B.Cu" "In1.Cu" "In2.Cu" "In3.Cu" "In4.Cu" "In5.Cu" "In6.Cu"
			"In7.Cu" "In8.Cu" "In9.Cu" "In10.Cu" "In11.Cu" "In12.Cu" "In13.Cu" "In14.Cu"
			"In15.Cu" "In16.Cu"
		)
		(hatch none 0.5)
		(connect_pads
			(clearance 0)
		)
		(min_thickness 0.25)
		(keepout
			(tracks not_allowed)
			(vias allowed)
			(pads allowed)
			(copperpour not_allowed)
			(footprints allowed)
		)
		(placement
			(enabled no)
			(sheetname "")
		)
		(fill
			(thermal_gap 0.5)
			(thermal_bridge_width 0.5)
			(island_removal_mode 0)
		)
		(polygon
			(pts
				(arc
					(start 128.701038 -395.92885)
					(mid 128.715917 -395.892929)
					(end 128.751838 -395.87805)
				)
				(arc
					(start 129.468118 -395.87805)
					(mid 129.504039 -395.892929)
					(end 129.518918 -395.92885)
				)
				(arc
					(start 129.518918 -398.351502)
					(mid 129.504039 -398.387423)
					(end 129.468118 -398.402302)
				)
				(arc
					(start 128.751838 -398.402302)
					(mid 128.715917 -398.387423)
					(end 128.701038 -398.351502)
				)
			)
		)
	)
	(zone
		(layers "F.Cu" "B.Cu" "In1.Cu" "In2.Cu" "In3.Cu" "In4.Cu" "In5.Cu" "In6.Cu"
			"In7.Cu" "In8.Cu" "In9.Cu" "In10.Cu" "In11.Cu" "In12.Cu" "In13.Cu" "In14.Cu"
			"In15.Cu" "In16.Cu"
		)
		(hatch none 0.5)
		(connect_pads
			(clearance 0)
		)
		(min_thickness 0.25)
		(keepout
			(tracks not_allowed)
			(vias allowed)
			(pads allowed)
			(copperpour not_allowed)
			(footprints allowed)
		)
		(placement
			(enabled no)
			(sheetname "")
		)
		(fill
			(thermal_gap 0.5)
			(thermal_bridge_width 0.5)
			(island_removal_mode 0)
		)
		(polygon
			(pts
				(arc
					(start 286.754062 -102.912672)
					(mid 286.296862 -102.455472)
					(end 285.839662 -102.912672)
				)
				(arc
					(start 285.839662 -103.776272)
					(mid 286.296862 -104.233472)
					(end 286.754062 -103.776272)
				)
			)
		)
	)
	(zone
		(layers "F.Cu" "B.Cu" "In1.Cu" "In2.Cu" "In3.Cu" "In4.Cu" "In5.Cu" "In6.Cu"
			"In7.Cu" "In8.Cu" "In9.Cu" "In10.Cu" "In11.Cu" "In12.Cu" "In13.Cu" "In14.Cu"
			"In15.Cu" "In16.Cu"
		)
		(hatch none 0.5)
		(connect_pads
			(clearance 0)
		)
		(min_thickness 0.25)
		(keepout
			(tracks not_allowed)
			(vias allowed)
			(pads allowed)
			(copperpour not_allowed)
			(footprints allowed)
		)
		(placement
			(enabled no)
			(sheetname "")
		)
		(fill
			(thermal_gap 0.5)
			(thermal_bridge_width 0.5)
			(island_removal_mode 0)
		)
		(polygon
			(pts
				(arc
					(start 240.279428 -224.774252)
					(mid 239.822228 -225.231452)
					(end 240.279428 -225.688652)
				)
				(arc
					(start 241.143028 -225.688652)
					(mid 241.600228 -225.231452)
					(end 241.143028 -224.774252)
				)
			)
		)
	)
	(zone
		(layers "F.Cu" "B.Cu" "In1.Cu" "In2.Cu" "In3.Cu" "In4.Cu" "In5.Cu" "In6.Cu"
			"In7.Cu" "In8.Cu" "In9.Cu" "In10.Cu" "In11.Cu" "In12.Cu" "In13.Cu" "In14.Cu"
			"In15.Cu" "In16.Cu"
		)
		(hatch none 0.5)
		(connect_pads
			(clearance 0)
		)
		(min_thickness 0.25)
		(keepout
			(tracks not_allowed)
			(vias allowed)
			(pads allowed)
			(copperpour not_allowed)
			(footprints allowed)
		)
		(placement
			(enabled no)
			(sheetname "")
		)
		(fill
			(thermal_gap 0.5)
			(thermal_bridge_width 0.5)
			(island_removal_mode 0)
		)
		(polygon
			(pts
				(arc
					(start 269.51051 -107.377738)
					(mid 269.96771 -107.834938)
					(end 270.42491 -107.377738)
				)
				(arc
					(start 270.42491 -106.514138)
					(mid 269.96771 -106.056938)
					(end 269.51051 -106.514138)
				)
			)
		)
	)
	(zone
		(layers "F.Cu" "B.Cu" "In1.Cu" "In2.Cu" "In3.Cu" "In4.Cu" "In5.Cu" "In6.Cu"
			"In7.Cu" "In8.Cu" "In9.Cu" "In10.Cu" "In11.Cu" "In12.Cu" "In13.Cu" "In14.Cu"
			"In15.Cu" "In16.Cu"
		)
		(hatch none 0.5)
		(connect_pads
			(clearance 0)
		)
		(min_thickness 0.25)
		(keepout
			(tracks not_allowed)
			(vias allowed)
			(pads allowed)
			(copperpour not_allowed)
			(footprints allowed)
		)
		(placement
			(enabled no)
			(sheetname "")
		)
		(fill
			(thermal_gap 0.5)
			(thermal_bridge_width 0.5)
			(island_removal_mode 0)
		)
		(polygon
			(pts
				(arc
					(start 153.424636 -299.555154)
					(mid 153.754836 -299.224954)
					(end 153.424636 -298.894754)
				)
				(arc
					(start 152.474676 -298.894754)
					(mid 152.144476 -299.224954)
					(end 152.474676 -299.555154)
				)
			)
		)
	)
	(zone
		(layers "F.Cu" "B.Cu" "In1.Cu" "In2.Cu" "In3.Cu" "In4.Cu" "In5.Cu" "In6.Cu"
			"In7.Cu" "In8.Cu" "In9.Cu" "In10.Cu" "In11.Cu" "In12.Cu" "In13.Cu" "In14.Cu"
			"In15.Cu" "In16.Cu"
		)
		(hatch none 0.5)
		(connect_pads
			(clearance 0)
		)
		(min_thickness 0.25)
		(keepout
			(tracks not_allowed)
			(vias allowed)
			(pads allowed)
			(copperpour not_allowed)
			(footprints allowed)
		)
		(placement
			(enabled no)
			(sheetname "")
		)
		(fill
			(thermal_gap 0.5)
			(thermal_bridge_width 0.5)
			(island_removal_mode 0)
		)
		(polygon
			(pts
				(arc
					(start 80.026002 -345.084146)
					(mid 79.645002 -345.465146)
					(end 80.026002 -345.846146)
				)
				(arc
					(start 80.889602 -345.846146)
					(mid 81.270602 -345.465146)
					(end 80.889602 -345.084146)
				)
			)
		)
	)
	(zone
		(layers "F.Cu" "B.Cu" "In1.Cu" "In2.Cu" "In3.Cu" "In4.Cu" "In5.Cu" "In6.Cu"
			"In7.Cu" "In8.Cu" "In9.Cu" "In10.Cu" "In11.Cu" "In12.Cu" "In13.Cu" "In14.Cu"
			"In15.Cu" "In16.Cu"
		)
		(hatch none 0.5)
		(connect_pads
			(clearance 0)
		)
		(min_thickness 0.25)
		(keepout
			(tracks not_allowed)
			(vias allowed)
			(pads allowed)
			(copperpour not_allowed)
			(footprints allowed)
		)
		(placement
			(enabled no)
			(sheetname "")
		)
		(fill
			(thermal_gap 0.5)
			(thermal_bridge_width 0.5)
			(island_removal_mode 0)
		)
		(polygon
			(pts
				(arc
					(start 40.649906 -299.07992)
					(mid 40.980106 -298.74972)
					(end 40.649906 -298.41952)
				)
				(arc
					(start 39.699946 -298.41952)
					(mid 39.369746 -298.74972)
					(end 39.699946 -299.07992)
				)
			)
		)
	)
	(zone
		(layers "F.Cu" "B.Cu" "In1.Cu" "In2.Cu" "In3.Cu" "In4.Cu" "In5.Cu" "In6.Cu"
			"In7.Cu" "In8.Cu" "In9.Cu" "In10.Cu" "In11.Cu" "In12.Cu" "In13.Cu" "In14.Cu"
			"In15.Cu" "In16.Cu"
		)
		(hatch none 0.5)
		(connect_pads
			(clearance 0)
		)
		(min_thickness 0.25)
		(keepout
			(tracks not_allowed)
			(vias allowed)
			(pads allowed)
			(copperpour not_allowed)
			(footprints allowed)
		)
		(placement
			(enabled no)
			(sheetname "")
		)
		(fill
			(thermal_gap 0.5)
			(thermal_bridge_width 0.5)
			(island_removal_mode 0)
		)
		(polygon
			(pts
				(arc
					(start 269.51051 -100.177854)
					(mid 269.96771 -100.635054)
					(end 270.42491 -100.177854)
				)
				(arc
					(start 270.42491 -99.314254)
					(mid 269.96771 -98.857054)
					(end 269.51051 -99.314254)
				)
			)
		)
	)
	(zone
		(layers "F.Cu" "B.Cu" "In1.Cu" "In2.Cu" "In3.Cu" "In4.Cu" "In5.Cu" "In6.Cu"
			"In7.Cu" "In8.Cu" "In9.Cu" "In10.Cu" "In11.Cu" "In12.Cu" "In13.Cu" "In14.Cu"
			"In15.Cu" "In16.Cu"
		)
		(hatch none 0.5)
		(connect_pads
			(clearance 0)
		)
		(min_thickness 0.25)
		(keepout
			(tracks not_allowed)
			(vias allowed)
			(pads allowed)
			(copperpour not_allowed)
			(footprints allowed)
		)
		(placement
			(enabled no)
			(sheetname "")
		)
		(fill
			(thermal_gap 0.5)
			(thermal_bridge_width 0.5)
			(island_removal_mode 0)
		)
		(polygon
			(pts
				(arc
					(start 150.768558 -105.584498)
					(mid 151.225758 -106.041698)
					(end 151.682958 -105.584498)
				)
				(arc
					(start 151.682958 -104.720898)
					(mid 151.225758 -104.263698)
					(end 150.768558 -104.720898)
				)
			)
		)
	)
	(zone
		(layers "F.Cu" "B.Cu" "In1.Cu" "In2.Cu" "In3.Cu" "In4.Cu" "In5.Cu" "In6.Cu"
			"In7.Cu" "In8.Cu" "In9.Cu" "In10.Cu" "In11.Cu" "In12.Cu" "In13.Cu" "In14.Cu"
			"In15.Cu" "In16.Cu"
		)
		(hatch none 0.5)
		(connect_pads
			(clearance 0)
		)
		(min_thickness 0.25)
		(keepout
			(tracks not_allowed)
			(vias allowed)
			(pads allowed)
			(copperpour not_allowed)
			(footprints allowed)
		)
		(placement
			(enabled no)
			(sheetname "")
		)
		(fill
			(thermal_gap 0.5)
			(thermal_bridge_width 0.5)
			(island_removal_mode 0)
		)
		(polygon
			(pts
				(arc
					(start 34.66846 -120.087898)
					(mid 35.12566 -120.545098)
					(end 35.58286 -120.087898)
				)
				(arc
					(start 35.58286 -119.224298)
					(mid 35.12566 -118.767098)
					(end 34.66846 -119.224298)
				)
			)
		)
	)
	(zone
		(layers "F.Cu" "B.Cu" "In1.Cu" "In2.Cu" "In3.Cu" "In4.Cu" "In5.Cu" "In6.Cu"
			"In7.Cu" "In8.Cu" "In9.Cu" "In10.Cu" "In11.Cu" "In12.Cu" "In13.Cu" "In14.Cu"
			"In15.Cu" "In16.Cu"
		)
		(hatch none 0.5)
		(connect_pads
			(clearance 0)
		)
		(min_thickness 0.25)
		(keepout
			(tracks not_allowed)
			(vias allowed)
			(pads allowed)
			(copperpour not_allowed)
			(footprints allowed)
		)
		(placement
			(enabled no)
			(sheetname "")
		)
		(fill
			(thermal_gap 0.5)
			(thermal_bridge_width 0.5)
			(island_removal_mode 0)
		)
		(polygon
			(pts
				(arc
					(start 421.730932 -345.084146)
					(mid 421.349932 -345.465146)
					(end 421.730932 -345.846146)
				)
				(arc
					(start 422.594532 -345.846146)
					(mid 422.975532 -345.465146)
					(end 422.594532 -345.084146)
				)
			)
		)
	)
	(zone
		(layers "F.Cu" "B.Cu" "In1.Cu" "In2.Cu" "In3.Cu" "In4.Cu" "In5.Cu" "In6.Cu"
			"In7.Cu" "In8.Cu" "In9.Cu" "In10.Cu" "In11.Cu" "In12.Cu" "In13.Cu" "In14.Cu"
			"In15.Cu" "In16.Cu"
		)
		(hatch none 0.5)
		(connect_pads
			(clearance 0)
		)
		(min_thickness 0.25)
		(keepout
			(tracks not_allowed)
			(vias allowed)
			(pads allowed)
			(copperpour not_allowed)
			(footprints allowed)
		)
		(placement
			(enabled no)
			(sheetname "")
		)
		(fill
			(thermal_gap 0.5)
			(thermal_bridge_width 0.5)
			(island_removal_mode 0)
		)
		(polygon
			(pts
				(arc
					(start 298.800012 -143.48714)
					(mid 299.257212 -143.94434)
					(end 299.714412 -143.48714)
				)
				(arc
					(start 299.714412 -142.62354)
					(mid 299.257212 -142.16634)
					(end 298.800012 -142.62354)
				)
			)
		)
	)
	(zone
		(layers "F.Cu" "B.Cu" "In1.Cu" "In2.Cu" "In3.Cu" "In4.Cu" "In5.Cu" "In6.Cu"
			"In7.Cu" "In8.Cu" "In9.Cu" "In10.Cu" "In11.Cu" "In12.Cu" "In13.Cu" "In14.Cu"
			"In15.Cu" "In16.Cu"
		)
		(hatch none 0.5)
		(connect_pads
			(clearance 0)
		)
		(min_thickness 0.25)
		(keepout
			(tracks not_allowed)
			(vias allowed)
			(pads allowed)
			(copperpour not_allowed)
			(footprints allowed)
		)
		(placement
			(enabled no)
			(sheetname "")
		)
		(fill
			(thermal_gap 0.5)
			(thermal_bridge_width 0.5)
			(island_removal_mode 0)
		)
		(polygon
			(pts
				(arc
					(start 168.404032 -342.058498)
					(mid 168.023032 -342.439498)
					(end 168.404032 -342.820498)
				)
				(arc
					(start 169.267632 -342.820498)
					(mid 169.648632 -342.439498)
					(end 169.267632 -342.058498)
				)
			)
		)
	)
	(zone
		(layers "F.Cu" "B.Cu" "In1.Cu" "In2.Cu" "In3.Cu" "In4.Cu" "In5.Cu" "In6.Cu"
			"In7.Cu" "In8.Cu" "In9.Cu" "In10.Cu" "In11.Cu" "In12.Cu" "In13.Cu" "In14.Cu"
			"In15.Cu" "In16.Cu"
		)
		(hatch none 0.5)
		(connect_pads
			(clearance 0)
		)
		(min_thickness 0.25)
		(keepout
			(tracks not_allowed)
			(vias allowed)
			(pads allowed)
			(copperpour not_allowed)
			(footprints allowed)
		)
		(placement
			(enabled no)
			(sheetname "")
		)
		(fill
			(thermal_gap 0.5)
			(thermal_bridge_width 0.5)
			(island_removal_mode 0)
		)
		(polygon
			(pts
				(arc
					(start 385.610608 -136.704324)
					(mid 386.067808 -137.161524)
					(end 386.525008 -136.704324)
				)
				(arc
					(start 386.525008 -135.840724)
					(mid 386.067808 -135.383524)
					(end 385.610608 -135.840724)
				)
			)
		)
	)
	(zone
		(layers "F.Cu" "B.Cu" "In1.Cu" "In2.Cu" "In3.Cu" "In4.Cu" "In5.Cu" "In6.Cu"
			"In7.Cu" "In8.Cu" "In9.Cu" "In10.Cu" "In11.Cu" "In12.Cu" "In13.Cu" "In14.Cu"
			"In15.Cu" "In16.Cu"
		)
		(hatch none 0.5)
		(connect_pads
			(clearance 0)
		)
		(min_thickness 0.25)
		(keepout
			(tracks not_allowed)
			(vias allowed)
			(pads allowed)
			(copperpour not_allowed)
			(footprints allowed)
		)
		(placement
			(enabled no)
			(sheetname "")
		)
		(fill
			(thermal_gap 0.5)
			(thermal_bridge_width 0.5)
			(island_removal_mode 0)
		)
		(polygon
			(pts
				(arc
					(start 121.188988 -345.084146)
					(mid 120.807988 -345.465146)
					(end 121.188988 -345.846146)
				)
				(arc
					(start 122.052588 -345.846146)
					(mid 122.433588 -345.465146)
					(end 122.052588 -345.084146)
				)
			)
		)
	)
	(zone
		(layers "F.Cu" "B.Cu" "In1.Cu" "In2.Cu" "In3.Cu" "In4.Cu" "In5.Cu" "In6.Cu"
			"In7.Cu" "In8.Cu" "In9.Cu" "In10.Cu" "In11.Cu" "In12.Cu" "In13.Cu" "In14.Cu"
			"In15.Cu" "In16.Cu"
		)
		(hatch none 0.5)
		(connect_pads
			(clearance 0)
		)
		(min_thickness 0.25)
		(keepout
			(tracks not_allowed)
			(vias allowed)
			(pads allowed)
			(copperpour not_allowed)
			(footprints allowed)
		)
		(placement
			(enabled no)
			(sheetname "")
		)
		(fill
			(thermal_gap 0.5)
			(thermal_bridge_width 0.5)
			(island_removal_mode 0)
		)
		(polygon
			(pts
				(arc
					(start 318.720724 -348.20479)
					(mid 318.339724 -348.58579)
					(end 318.720724 -348.96679)
				)
				(arc
					(start 319.584324 -348.96679)
					(mid 319.965324 -348.58579)
					(end 319.584324 -348.20479)
				)
			)
		)
	)
	(zone
		(layers "F.Cu" "B.Cu" "In1.Cu" "In2.Cu" "In3.Cu" "In4.Cu" "In5.Cu" "In6.Cu"
			"In7.Cu" "In8.Cu" "In9.Cu" "In10.Cu" "In11.Cu" "In12.Cu" "In13.Cu" "In14.Cu"
			"In15.Cu" "In16.Cu"
		)
		(hatch none 0.5)
		(connect_pads
			(clearance 0)
		)
		(min_thickness 0.25)
		(keepout
			(tracks not_allowed)
			(vias allowed)
			(pads allowed)
			(copperpour not_allowed)
			(footprints allowed)
		)
		(placement
			(enabled no)
			(sheetname "")
		)
		(fill
			(thermal_gap 0.5)
			(thermal_bridge_width 0.5)
			(island_removal_mode 0)
		)
		(polygon
			(pts
				(arc
					(start 172.70095 -369.928902)
					(mid 172.715829 -369.892981)
					(end 172.75175 -369.878102)
				)
				(arc
					(start 173.46803 -369.878102)
					(mid 173.503951 -369.892981)
					(end 173.51883 -369.928902)
				)
				(arc
					(start 173.51883 -372.351554)
					(mid 173.503951 -372.387475)
					(end 173.46803 -372.402354)
				)
				(arc
					(start 172.75175 -372.402354)
					(mid 172.715829 -372.387475)
					(end 172.70095 -372.351554)
				)
			)
		)
	)
	(zone
		(layers "F.Cu" "B.Cu" "In1.Cu" "In2.Cu" "In3.Cu" "In4.Cu" "In5.Cu" "In6.Cu"
			"In7.Cu" "In8.Cu" "In9.Cu" "In10.Cu" "In11.Cu" "In12.Cu" "In13.Cu" "In14.Cu"
			"In15.Cu" "In16.Cu"
		)
		(hatch none 0.5)
		(connect_pads
			(clearance 0)
		)
		(min_thickness 0.25)
		(keepout
			(tracks not_allowed)
			(vias allowed)
			(pads allowed)
			(copperpour not_allowed)
			(footprints allowed)
		)
		(placement
			(enabled no)
			(sheetname "")
		)
		(fill
			(thermal_gap 0.5)
			(thermal_bridge_width 0.5)
			(island_removal_mode 0)
		)
		(polygon
			(pts
				(arc
					(start 45.101002 -399.828766)
					(mid 45.115881 -399.792845)
					(end 45.151802 -399.777966)
				)
				(arc
					(start 45.868082 -399.777966)
					(mid 45.904003 -399.792845)
					(end 45.918882 -399.828766)
				)
				(arc
					(start 45.918882 -402.251418)
					(mid 45.904003 -402.287339)
					(end 45.868082 -402.302218)
				)
				(arc
					(start 45.151802 -402.302218)
					(mid 45.115881 -402.287339)
					(end 45.101002 -402.251418)
				)
			)
		)
	)
	(zone
		(layers "F.Cu" "B.Cu" "In1.Cu" "In2.Cu" "In3.Cu" "In4.Cu" "In5.Cu" "In6.Cu"
			"In7.Cu" "In8.Cu" "In9.Cu" "In10.Cu" "In11.Cu" "In12.Cu" "In13.Cu" "In14.Cu"
			"In15.Cu" "In16.Cu"
		)
		(hatch none 0.5)
		(connect_pads
			(clearance 0)
		)
		(min_thickness 0.25)
		(keepout
			(tracks not_allowed)
			(vias allowed)
			(pads allowed)
			(copperpour not_allowed)
			(footprints allowed)
		)
		(placement
			(enabled no)
			(sheetname "")
		)
		(fill
			(thermal_gap 0.5)
			(thermal_bridge_width 0.5)
			(island_removal_mode 0)
		)
		(polygon
			(pts
				(arc
					(start 124.30125 -403.728682)
					(mid 124.316129 -403.692761)
					(end 124.35205 -403.677882)
				)
				(arc
					(start 125.06833 -403.677882)
					(mid 125.104251 -403.692761)
					(end 125.11913 -403.728682)
				)
				(arc
					(start 125.11913 -406.151334)
					(mid 125.104251 -406.187255)
					(end 125.06833 -406.202134)
				)
				(arc
					(start 124.35205 -406.202134)
					(mid 124.316129 -406.187255)
					(end 124.30125 -406.151334)
				)
			)
		)
	)
	(zone
		(layers "F.Cu" "B.Cu" "In1.Cu" "In2.Cu" "In3.Cu" "In4.Cu" "In5.Cu" "In6.Cu"
			"In7.Cu" "In8.Cu" "In9.Cu" "In10.Cu" "In11.Cu" "In12.Cu" "In13.Cu" "In14.Cu"
			"In15.Cu" "In16.Cu"
		)
		(hatch none 0.5)
		(connect_pads
			(clearance 0)
		)
		(min_thickness 0.25)
		(keepout
			(tracks not_allowed)
			(vias allowed)
			(pads allowed)
			(copperpour not_allowed)
			(footprints allowed)
		)
		(placement
			(enabled no)
			(sheetname "")
		)
		(fill
			(thermal_gap 0.5)
			(thermal_bridge_width 0.5)
			(island_removal_mode 0)
		)
		(polygon
			(pts
				(arc
					(start 280.332942 -357.37673)
					(mid 279.951942 -357.75773)
					(end 280.332942 -358.13873)
				)
				(arc
					(start 281.196542 -358.13873)
					(mid 281.577542 -357.75773)
					(end 281.196542 -357.37673)
				)
			)
		)
	)
	(zone
		(layers "F.Cu" "B.Cu" "In1.Cu" "In2.Cu" "In3.Cu" "In4.Cu" "In5.Cu" "In6.Cu"
			"In7.Cu" "In8.Cu" "In9.Cu" "In10.Cu" "In11.Cu" "In12.Cu" "In13.Cu" "In14.Cu"
			"In15.Cu" "In16.Cu"
		)
		(hatch none 0.5)
		(connect_pads
			(clearance 0)
		)
		(min_thickness 0.25)
		(keepout
			(tracks not_allowed)
			(vias allowed)
			(pads allowed)
			(copperpour not_allowed)
			(footprints allowed)
		)
		(placement
			(enabled no)
			(sheetname "")
		)
		(fill
			(thermal_gap 0.5)
			(thermal_bridge_width 0.5)
			(island_removal_mode 0)
		)
		(polygon
			(pts
				(arc
					(start 396.05966 -348.20479)
					(mid 395.67866 -348.58579)
					(end 396.05966 -348.96679)
				)
				(arc
					(start 396.92326 -348.96679)
					(mid 397.30426 -348.58579)
					(end 396.92326 -348.20479)
				)
			)
		)
	)
	(zone
		(layers "F.Cu" "B.Cu" "In1.Cu" "In2.Cu" "In3.Cu" "In4.Cu" "In5.Cu" "In6.Cu"
			"In7.Cu" "In8.Cu" "In9.Cu" "In10.Cu" "In11.Cu" "In12.Cu" "In13.Cu" "In14.Cu"
			"In15.Cu" "In16.Cu"
		)
		(hatch none 0.5)
		(connect_pads
			(clearance 0)
		)
		(min_thickness 0.25)
		(keepout
			(tracks not_allowed)
			(vias allowed)
			(pads allowed)
			(copperpour not_allowed)
			(footprints allowed)
		)
		(placement
			(enabled no)
			(sheetname "")
		)
		(fill
			(thermal_gap 0.5)
			(thermal_bridge_width 0.5)
			(island_removal_mode 0)
		)
		(polygon
			(pts
				(arc
					(start 331.081126 -373.828818)
					(mid 331.096005 -373.792897)
					(end 331.131926 -373.778018)
				)
				(arc
					(start 331.848206 -373.778018)
					(mid 331.884127 -373.792897)
					(end 331.899006 -373.828818)
				)
				(arc
					(start 331.899006 -376.25147)
					(mid 331.884127 -376.287391)
					(end 331.848206 -376.30227)
				)
				(arc
					(start 331.131926 -376.30227)
					(mid 331.096005 -376.287391)
					(end 331.081126 -376.25147)
				)
			)
		)
	)
	(zone
		(layers "F.Cu" "B.Cu" "In1.Cu" "In2.Cu" "In3.Cu" "In4.Cu" "In5.Cu" "In6.Cu"
			"In7.Cu" "In8.Cu" "In9.Cu" "In10.Cu" "In11.Cu" "In12.Cu" "In13.Cu" "In14.Cu"
			"In15.Cu" "In16.Cu"
		)
		(hatch none 0.5)
		(connect_pads
			(clearance 0)
		)
		(min_thickness 0.25)
		(keepout
			(tracks not_allowed)
			(vias allowed)
			(pads allowed)
			(copperpour not_allowed)
			(footprints allowed)
		)
		(placement
			(enabled no)
			(sheetname "")
		)
		(fill
			(thermal_gap 0.5)
			(thermal_bridge_width 0.5)
			(island_removal_mode 0)
		)
		(polygon
			(pts
				(arc
					(start 61.372242 -348.20479)
					(mid 60.991242 -348.58579)
					(end 61.372242 -348.96679)
				)
				(arc
					(start 62.235842 -348.96679)
					(mid 62.616842 -348.58579)
					(end 62.235842 -348.20479)
				)
			)
		)
	)
	(zone
		(layers "F.Cu" "B.Cu" "In1.Cu" "In2.Cu" "In3.Cu" "In4.Cu" "In5.Cu" "In6.Cu"
			"In7.Cu" "In8.Cu" "In9.Cu" "In10.Cu" "In11.Cu" "In12.Cu" "In13.Cu" "In14.Cu"
			"In15.Cu" "In16.Cu"
		)
		(hatch none 0.5)
		(connect_pads
			(clearance 0)
		)
		(min_thickness 0.25)
		(keepout
			(tracks not_allowed)
			(vias allowed)
			(pads allowed)
			(copperpour not_allowed)
			(footprints allowed)
		)
		(placement
			(enabled no)
			(sheetname "")
		)
		(fill
			(thermal_gap 0.5)
			(thermal_bridge_width 0.5)
			(island_removal_mode 0)
		)
		(polygon
			(pts
				(arc
					(start 337.374484 -348.20479)
					(mid 336.993484 -348.58579)
					(end 337.374484 -348.96679)
				)
				(arc
					(start 338.238084 -348.96679)
					(mid 338.619084 -348.58579)
					(end 338.238084 -348.20479)
				)
			)
		)
	)
	(zone
		(layers "F.Cu" "B.Cu" "In1.Cu" "In2.Cu" "In3.Cu" "In4.Cu" "In5.Cu" "In6.Cu"
			"In7.Cu" "In8.Cu" "In9.Cu" "In10.Cu" "In11.Cu" "In12.Cu" "In13.Cu" "In14.Cu"
			"In15.Cu" "In16.Cu"
		)
		(hatch none 0.5)
		(connect_pads
			(clearance 0)
		)
		(min_thickness 0.25)
		(keepout
			(tracks not_allowed)
			(vias allowed)
			(pads allowed)
			(copperpour not_allowed)
			(footprints allowed)
		)
		(placement
			(enabled no)
			(sheetname "")
		)
		(fill
			(thermal_gap 0.5)
			(thermal_bridge_width 0.5)
			(island_removal_mode 0)
		)
		(polygon
			(pts
				(arc
					(start 331.156564 -351.230438)
					(mid 330.775564 -351.611438)
					(end 331.156564 -351.992438)
				)
				(arc
					(start 332.020164 -351.992438)
					(mid 332.401164 -351.611438)
					(end 332.020164 -351.230438)
				)
			)
		)
	)
	(zone
		(layers "F.Cu" "B.Cu" "In1.Cu" "In2.Cu" "In3.Cu" "In4.Cu" "In5.Cu" "In6.Cu"
			"In7.Cu" "In8.Cu" "In9.Cu" "In10.Cu" "In11.Cu" "In12.Cu" "In13.Cu" "In14.Cu"
			"In15.Cu" "In16.Cu"
		)
		(hatch none 0.5)
		(connect_pads
			(clearance 0)
		)
		(min_thickness 0.25)
		(keepout
			(tracks not_allowed)
			(vias allowed)
			(pads allowed)
			(copperpour not_allowed)
			(footprints allowed)
		)
		(placement
			(enabled no)
			(sheetname "")
		)
		(fill
			(thermal_gap 0.5)
			(thermal_bridge_width 0.5)
			(island_removal_mode 0)
		)
		(polygon
			(pts
				(arc
					(start 130.901186 -371.028722)
					(mid 130.916065 -370.992801)
					(end 130.951986 -370.977922)
				)
				(arc
					(start 131.668266 -370.977922)
					(mid 131.704187 -370.992801)
					(end 131.719066 -371.028722)
				)
				(arc
					(start 131.719066 -373.451374)
					(mid 131.704187 -373.487295)
					(end 131.668266 -373.502174)
				)
				(arc
					(start 130.951986 -373.502174)
					(mid 130.916065 -373.487295)
					(end 130.901186 -373.451374)
				)
			)
		)
	)
	(zone
		(layers "F.Cu" "B.Cu" "In1.Cu" "In2.Cu" "In3.Cu" "In4.Cu" "In5.Cu" "In6.Cu"
			"In7.Cu" "In8.Cu" "In9.Cu" "In10.Cu" "In11.Cu" "In12.Cu" "In13.Cu" "In14.Cu"
			"In15.Cu" "In16.Cu"
		)
		(hatch none 0.5)
		(connect_pads
			(clearance 0)
		)
		(min_thickness 0.25)
		(keepout
			(tracks not_allowed)
			(vias allowed)
			(pads allowed)
			(copperpour not_allowed)
			(footprints allowed)
		)
		(placement
			(enabled no)
			(sheetname "")
		)
		(fill
			(thermal_gap 0.5)
			(thermal_bridge_width 0.5)
			(island_removal_mode 0)
		)
		(polygon
			(pts
				(arc
					(start 122.101102 -371.028722)
					(mid 122.115981 -370.992801)
					(end 122.151902 -370.977922)
				)
				(arc
					(start 122.868182 -370.977922)
					(mid 122.904103 -370.992801)
					(end 122.918982 -371.028722)
				)
				(arc
					(start 122.918982 -373.451374)
					(mid 122.904103 -373.487295)
					(end 122.868182 -373.502174)
				)
				(arc
					(start 122.151902 -373.502174)
					(mid 122.115981 -373.487295)
					(end 122.101102 -373.451374)
				)
			)
		)
	)
	(zone
		(layers "F.Cu" "B.Cu" "In1.Cu" "In2.Cu" "In3.Cu" "In4.Cu" "In5.Cu" "In6.Cu"
			"In7.Cu" "In8.Cu" "In9.Cu" "In10.Cu" "In11.Cu" "In12.Cu" "In13.Cu" "In14.Cu"
			"In15.Cu" "In16.Cu"
		)
		(hatch none 0.5)
		(connect_pads
			(clearance 0)
		)
		(min_thickness 0.25)
		(keepout
			(tracks not_allowed)
			(vias allowed)
			(pads allowed)
			(copperpour not_allowed)
			(footprints allowed)
		)
		(placement
			(enabled no)
			(sheetname "")
		)
		(fill
			(thermal_gap 0.5)
			(thermal_bridge_width 0.5)
			(island_removal_mode 0)
		)
		(polygon
			(pts
				(arc
					(start 98.80981 -200.97115)
					(mid 98.42881 -201.35215)
					(end 98.80981 -201.73315)
				)
				(arc
					(start 99.67341 -201.73315)
					(mid 100.05441 -201.35215)
					(end 99.67341 -200.97115)
				)
			)
		)
	)
	(zone
		(layers "F.Cu" "B.Cu" "In1.Cu" "In2.Cu" "In3.Cu" "In4.Cu" "In5.Cu" "In6.Cu"
			"In7.Cu" "In8.Cu" "In9.Cu" "In10.Cu" "In11.Cu" "In12.Cu" "In13.Cu" "In14.Cu"
			"In15.Cu" "In16.Cu"
		)
		(hatch none 0.5)
		(connect_pads
			(clearance 0)
		)
		(min_thickness 0.25)
		(keepout
			(tracks not_allowed)
			(vias allowed)
			(pads allowed)
			(copperpour not_allowed)
			(footprints allowed)
		)
		(placement
			(enabled no)
			(sheetname "")
		)
		(fill
			(thermal_gap 0.5)
			(thermal_bridge_width 0.5)
			(island_removal_mode 0)
		)
		(polygon
			(pts
				(arc
					(start 70.699122 -345.084146)
					(mid 70.318122 -345.465146)
					(end 70.699122 -345.846146)
				)
				(arc
					(start 71.562722 -345.846146)
					(mid 71.943722 -345.465146)
					(end 71.562722 -345.084146)
				)
			)
		)
	)
	(zone
		(layers "F.Cu" "B.Cu" "In1.Cu" "In2.Cu" "In3.Cu" "In4.Cu" "In5.Cu" "In6.Cu"
			"In7.Cu" "In8.Cu" "In9.Cu" "In10.Cu" "In11.Cu" "In12.Cu" "In13.Cu" "In14.Cu"
			"In15.Cu" "In16.Cu"
		)
		(hatch none 0.5)
		(connect_pads
			(clearance 0)
		)
		(min_thickness 0.25)
		(keepout
			(tracks not_allowed)
			(vias allowed)
			(pads allowed)
			(copperpour not_allowed)
			(footprints allowed)
		)
		(placement
			(enabled no)
			(sheetname "")
		)
		(fill
			(thermal_gap 0.5)
			(thermal_bridge_width 0.5)
			(island_removal_mode 0)
		)
		(polygon
			(pts
				(arc
					(start 66.60007 -150.687278)
					(mid 67.05727 -151.144478)
					(end 67.51447 -150.687278)
				)
				(arc
					(start 67.51447 -149.823678)
					(mid 67.05727 -149.366478)
					(end 66.60007 -149.823678)
				)
			)
		)
	)
	(zone
		(layers "F.Cu" "B.Cu" "In1.Cu" "In2.Cu" "In3.Cu" "In4.Cu" "In5.Cu" "In6.Cu"
			"In7.Cu" "In8.Cu" "In9.Cu" "In10.Cu" "In11.Cu" "In12.Cu" "In13.Cu" "In14.Cu"
			"In15.Cu" "In16.Cu"
		)
		(hatch none 0.5)
		(connect_pads
			(clearance 0)
		)
		(min_thickness 0.25)
		(keepout
			(tracks not_allowed)
			(vias allowed)
			(pads allowed)
			(copperpour not_allowed)
			(footprints allowed)
		)
		(placement
			(enabled no)
			(sheetname "")
		)
		(fill
			(thermal_gap 0.5)
			(thermal_bridge_width 0.5)
			(island_removal_mode 0)
		)
		(polygon
			(pts
				(arc
					(start 187.057792 -351.230438)
					(mid 186.676792 -351.611438)
					(end 187.057792 -351.992438)
				)
				(arc
					(start 187.921392 -351.992438)
					(mid 188.302392 -351.611438)
					(end 187.921392 -351.230438)
				)
			)
		)
	)
	(zone
		(layers "F.Cu" "B.Cu" "In1.Cu" "In2.Cu" "In3.Cu" "In4.Cu" "In5.Cu" "In6.Cu"
			"In7.Cu" "In8.Cu" "In9.Cu" "In10.Cu" "In11.Cu" "In12.Cu" "In13.Cu" "In14.Cu"
			"In15.Cu" "In16.Cu"
		)
		(hatch none 0.5)
		(connect_pads
			(clearance 0)
		)
		(min_thickness 0.25)
		(keepout
			(tracks not_allowed)
			(vias allowed)
			(pads allowed)
			(copperpour not_allowed)
			(footprints allowed)
		)
		(placement
			(enabled no)
			(sheetname "")
		)
		(fill
			(thermal_gap 0.5)
			(thermal_bridge_width 0.5)
			(island_removal_mode 0)
		)
		(polygon
			(pts
				(arc
					(start 122.85345 -30.922468)
					(mid 123.31065 -31.379668)
					(end 123.76785 -30.922468)
				)
				(arc
					(start 123.76785 -30.058868)
					(mid 123.31065 -29.601668)
					(end 122.85345 -30.058868)
				)
			)
		)
	)
	(zone
		(layers "F.Cu" "B.Cu" "In1.Cu" "In2.Cu" "In3.Cu" "In4.Cu" "In5.Cu" "In6.Cu"
			"In7.Cu" "In8.Cu" "In9.Cu" "In10.Cu" "In11.Cu" "In12.Cu" "In13.Cu" "In14.Cu"
			"In15.Cu" "In16.Cu"
		)
		(hatch none 0.5)
		(connect_pads
			(clearance 0)
		)
		(min_thickness 0.25)
		(keepout
			(tracks not_allowed)
			(vias allowed)
			(pads allowed)
			(copperpour not_allowed)
			(footprints allowed)
		)
		(placement
			(enabled no)
			(sheetname "")
		)
		(fill
			(thermal_gap 0.5)
			(thermal_bridge_width 0.5)
			(island_removal_mode 0)
		)
		(polygon
			(pts
				(arc
					(start 183.948832 -357.352854)
					(mid 183.567832 -357.733854)
					(end 183.948832 -358.114854)
				)
				(arc
					(start 184.812432 -358.114854)
					(mid 185.193432 -357.733854)
					(end 184.812432 -357.352854)
				)
			)
		)
	)
	(zone
		(layers "F.Cu" "B.Cu" "In1.Cu" "In2.Cu" "In3.Cu" "In4.Cu" "In5.Cu" "In6.Cu"
			"In7.Cu" "In8.Cu" "In9.Cu" "In10.Cu" "In11.Cu" "In12.Cu" "In13.Cu" "In14.Cu"
			"In15.Cu" "In16.Cu"
		)
		(hatch none 0.5)
		(connect_pads
			(clearance 0)
		)
		(min_thickness 0.25)
		(keepout
			(tracks not_allowed)
			(vias allowed)
			(pads allowed)
			(copperpour not_allowed)
			(footprints allowed)
		)
		(placement
			(enabled no)
			(sheetname "")
		)
		(fill
			(thermal_gap 0.5)
			(thermal_bridge_width 0.5)
			(island_removal_mode 0)
		)
		(polygon
			(pts
				(arc
					(start 70.847966 -29.114242)
					(mid 71.305166 -29.571442)
					(end 71.762366 -29.114242)
				)
				(arc
					(start 71.762366 -28.250642)
					(mid 71.305166 -27.793442)
					(end 70.847966 -28.250642)
				)
			)
		)
	)
	(zone
		(layers "F.Cu" "B.Cu" "In1.Cu" "In2.Cu" "In3.Cu" "In4.Cu" "In5.Cu" "In6.Cu"
			"In7.Cu" "In8.Cu" "In9.Cu" "In10.Cu" "In11.Cu" "In12.Cu" "In13.Cu" "In14.Cu"
			"In15.Cu" "In16.Cu"
		)
		(hatch none 0.5)
		(connect_pads
			(clearance 0)
		)
		(min_thickness 0.25)
		(keepout
			(tracks not_allowed)
			(vias allowed)
			(pads allowed)
			(copperpour not_allowed)
			(footprints allowed)
		)
		(placement
			(enabled no)
			(sheetname "")
		)
		(fill
			(thermal_gap 0.5)
			(thermal_bridge_width 0.5)
			(island_removal_mode 0)
		)
		(polygon
			(pts
				(arc
					(start 82.500978 -404.828756)
					(mid 82.515857 -404.792835)
					(end 82.551778 -404.777956)
				)
				(arc
					(start 83.268058 -404.777956)
					(mid 83.303979 -404.792835)
					(end 83.318858 -404.828756)
				)
				(arc
					(start 83.318858 -407.251408)
					(mid 83.303979 -407.287329)
					(end 83.268058 -407.302208)
				)
				(arc
					(start 82.551778 -407.302208)
					(mid 82.515857 -407.287329)
					(end 82.500978 -407.251408)
				)
			)
		)
	)
	(zone
		(layers "F.Cu" "B.Cu" "In1.Cu" "In2.Cu" "In3.Cu" "In4.Cu" "In5.Cu" "In6.Cu"
			"In7.Cu" "In8.Cu" "In9.Cu" "In10.Cu" "In11.Cu" "In12.Cu" "In13.Cu" "In14.Cu"
			"In15.Cu" "In16.Cu"
		)
		(hatch none 0.5)
		(connect_pads
			(clearance 0)
		)
		(min_thickness 0.25)
		(keepout
			(tracks not_allowed)
			(vias allowed)
			(pads allowed)
			(copperpour not_allowed)
			(footprints allowed)
		)
		(placement
			(enabled no)
			(sheetname "")
		)
		(fill
			(thermal_gap 0.5)
			(thermal_bridge_width 0.5)
			(island_removal_mode 0)
		)
		(polygon
			(pts
				(arc
					(start 83.71713 -148.88591)
					(mid 84.17433 -149.34311)
					(end 84.63153 -148.88591)
				)
				(arc
					(start 84.63153 -148.02231)
					(mid 84.17433 -147.56511)
					(end 83.71713 -148.02231)
				)
			)
		)
	)
	(zone
		(layers "F.Cu" "B.Cu" "In1.Cu" "In2.Cu" "In3.Cu" "In4.Cu" "In5.Cu" "In6.Cu"
			"In7.Cu" "In8.Cu" "In9.Cu" "In10.Cu" "In11.Cu" "In12.Cu" "In13.Cu" "In14.Cu"
			"In15.Cu" "In16.Cu"
		)
		(hatch none 0.5)
		(connect_pads
			(clearance 0)
		)
		(min_thickness 0.25)
		(keepout
			(tracks not_allowed)
			(vias allowed)
			(pads allowed)
			(copperpour not_allowed)
			(footprints allowed)
		)
		(placement
			(enabled no)
			(sheetname "")
		)
		(fill
			(thermal_gap 0.5)
			(thermal_bridge_width 0.5)
			(island_removal_mode 0)
		)
		(polygon
			(pts
				(arc
					(start 302.48098 -397.028924)
					(mid 302.495859 -396.993003)
					(end 302.53178 -396.978124)
				)
				(arc
					(start 303.24806 -396.978124)
					(mid 303.283981 -396.993003)
					(end 303.29886 -397.028924)
				)
				(arc
					(start 303.29886 -399.451576)
					(mid 303.283981 -399.487497)
					(end 303.24806 -399.502376)
				)
				(arc
					(start 302.53178 -399.502376)
					(mid 302.495859 -399.487497)
					(end 302.48098 -399.451576)
				)
			)
		)
	)
	(zone
		(layers "F.Cu" "B.Cu" "In1.Cu" "In2.Cu" "In3.Cu" "In4.Cu" "In5.Cu" "In6.Cu"
			"In7.Cu" "In8.Cu" "In9.Cu" "In10.Cu" "In11.Cu" "In12.Cu" "In13.Cu" "In14.Cu"
			"In15.Cu" "In16.Cu"
		)
		(hatch none 0.5)
		(connect_pads
			(clearance 0)
		)
		(min_thickness 0.25)
		(keepout
			(tracks not_allowed)
			(vias allowed)
			(pads allowed)
			(copperpour not_allowed)
			(footprints allowed)
		)
		(placement
			(enabled no)
			(sheetname "")
		)
		(fill
			(thermal_gap 0.5)
			(thermal_bridge_width 0.5)
			(island_removal_mode 0)
		)
		(polygon
			(pts
				(arc
					(start 312.994294 11.081512)
					(mid 312.613294 11.462512)
					(end 312.232294 11.081512)
				)
				(arc
					(start 312.232294 10.217912)
					(mid 312.613294 9.836912)
					(end 312.994294 10.217912)
				)
			)
		)
	)
	(zone
		(layers "F.Cu" "B.Cu" "In1.Cu" "In2.Cu" "In3.Cu" "In4.Cu" "In5.Cu" "In6.Cu"
			"In7.Cu" "In8.Cu" "In9.Cu" "In10.Cu" "In11.Cu" "In12.Cu" "In13.Cu" "In14.Cu"
			"In15.Cu" "In16.Cu"
		)
		(hatch none 0.5)
		(connect_pads
			(clearance 0)
		)
		(min_thickness 0.25)
		(keepout
			(tracks not_allowed)
			(vias allowed)
			(pads allowed)
			(copperpour not_allowed)
			(footprints allowed)
		)
		(placement
			(enabled no)
			(sheetname "")
		)
		(fill
			(thermal_gap 0.5)
			(thermal_bridge_width 0.5)
			(island_removal_mode 0)
		)
		(polygon
			(pts
				(arc
					(start 335.481168 -381.628904)
					(mid 335.496047 -381.592983)
					(end 335.531968 -381.578104)
				)
				(arc
					(start 336.248248 -381.578104)
					(mid 336.284169 -381.592983)
					(end 336.299048 -381.628904)
				)
				(arc
					(start 336.299048 -384.051556)
					(mid 336.284169 -384.087477)
					(end 336.248248 -384.102356)
				)
				(arc
					(start 335.531968 -384.102356)
					(mid 335.496047 -384.087477)
					(end 335.481168 -384.051556)
				)
			)
		)
	)
	(zone
		(layers "F.Cu" "B.Cu" "In1.Cu" "In2.Cu" "In3.Cu" "In4.Cu" "In5.Cu" "In6.Cu"
			"In7.Cu" "In8.Cu" "In9.Cu" "In10.Cu" "In11.Cu" "In12.Cu" "In13.Cu" "In14.Cu"
			"In15.Cu" "In16.Cu"
		)
		(hatch none 0.5)
		(connect_pads
			(clearance 0)
		)
		(min_thickness 0.25)
		(keepout
			(tracks not_allowed)
			(vias allowed)
			(pads allowed)
			(copperpour not_allowed)
			(footprints allowed)
		)
		(placement
			(enabled no)
			(sheetname "")
		)
		(fill
			(thermal_gap 0.5)
			(thermal_bridge_width 0.5)
			(island_removal_mode 0)
		)
		(polygon
			(pts
				(arc
					(start 84.753196 -30.922468)
					(mid 85.210396 -31.379668)
					(end 85.667596 -30.922468)
				)
				(arc
					(start 85.667596 -30.058868)
					(mid 85.210396 -29.601668)
					(end 84.753196 -30.058868)
				)
			)
		)
	)
	(zone
		(layers "F.Cu" "B.Cu" "In1.Cu" "In2.Cu" "In3.Cu" "In4.Cu" "In5.Cu" "In6.Cu"
			"In7.Cu" "In8.Cu" "In9.Cu" "In10.Cu" "In11.Cu" "In12.Cu" "In13.Cu" "In14.Cu"
			"In15.Cu" "In16.Cu"
		)
		(hatch none 0.5)
		(connect_pads
			(clearance 0)
		)
		(min_thickness 0.25)
		(keepout
			(tracks not_allowed)
			(vias allowed)
			(pads allowed)
			(copperpour not_allowed)
			(footprints allowed)
		)
		(placement
			(enabled no)
			(sheetname "")
		)
		(fill
			(thermal_gap 0.5)
			(thermal_bridge_width 0.5)
			(island_removal_mode 0)
		)
		(polygon
			(pts
				(arc
					(start 399.16862 -357.37673)
					(mid 398.78762 -357.75773)
					(end 399.16862 -358.13873)
				)
				(arc
					(start 400.03222 -358.13873)
					(mid 400.41322 -357.75773)
					(end 400.03222 -357.37673)
				)
			)
		)
	)
	(zone
		(layers "F.Cu" "B.Cu" "In1.Cu" "In2.Cu" "In3.Cu" "In4.Cu" "In5.Cu" "In6.Cu"
			"In7.Cu" "In8.Cu" "In9.Cu" "In10.Cu" "In11.Cu" "In12.Cu" "In13.Cu" "In14.Cu"
			"In15.Cu" "In16.Cu"
		)
		(hatch none 0.5)
		(connect_pads
			(clearance 0)
		)
		(min_thickness 0.25)
		(keepout
			(tracks not_allowed)
			(vias allowed)
			(pads allowed)
			(copperpour not_allowed)
			(footprints allowed)
		)
		(placement
			(enabled no)
			(sheetname "")
		)
		(fill
			(thermal_gap 0.5)
			(thermal_bridge_width 0.5)
			(island_removal_mode 0)
		)
		(polygon
			(pts
				(arc
					(start 228.771704 -157.412944)
					(mid 228.314504 -157.870144)
					(end 228.771704 -158.327344)
				)
				(arc
					(start 229.635304 -158.327344)
					(mid 230.092504 -157.870144)
					(end 229.635304 -157.412944)
				)
			)
		)
	)
	(zone
		(layers "F.Cu" "B.Cu" "In1.Cu" "In2.Cu" "In3.Cu" "In4.Cu" "In5.Cu" "In6.Cu"
			"In7.Cu" "In8.Cu" "In9.Cu" "In10.Cu" "In11.Cu" "In12.Cu" "In13.Cu" "In14.Cu"
			"In15.Cu" "In16.Cu"
		)
		(hatch none 0.5)
		(connect_pads
			(clearance 0)
		)
		(min_thickness 0.25)
		(keepout
			(tracks not_allowed)
			(vias allowed)
			(pads allowed)
			(copperpour not_allowed)
			(footprints allowed)
		)
		(placement
			(enabled no)
			(sheetname "")
		)
		(fill
			(thermal_gap 0.5)
			(thermal_bridge_width 0.5)
			(island_removal_mode 0)
		)
		(polygon
			(pts
				(arc
					(start 377.4059 -354.351082)
					(mid 377.0249 -354.732082)
					(end 377.4059 -355.113082)
				)
				(arc
					(start 378.2695 -355.113082)
					(mid 378.6505 -354.732082)
					(end 378.2695 -354.351082)
				)
			)
		)
	)
	(zone
		(layers "F.Cu" "B.Cu" "In1.Cu" "In2.Cu" "In3.Cu" "In4.Cu" "In5.Cu" "In6.Cu"
			"In7.Cu" "In8.Cu" "In9.Cu" "In10.Cu" "In11.Cu" "In12.Cu" "In13.Cu" "In14.Cu"
			"In15.Cu" "In16.Cu"
		)
		(hatch none 0.5)
		(connect_pads
			(clearance 0)
		)
		(min_thickness 0.25)
		(keepout
			(tracks not_allowed)
			(vias allowed)
			(pads allowed)
			(copperpour not_allowed)
			(footprints allowed)
		)
		(placement
			(enabled no)
			(sheetname "")
		)
		(fill
			(thermal_gap 0.5)
			(thermal_bridge_width 0.5)
			(island_removal_mode 0)
		)
		(polygon
			(pts
				(arc
					(start 38.501066 -408.728672)
					(mid 38.515945 -408.692751)
					(end 38.551866 -408.677872)
				)
				(arc
					(start 39.268146 -408.677872)
					(mid 39.304067 -408.692751)
					(end 39.318946 -408.728672)
				)
				(arc
					(start 39.318946 -411.151324)
					(mid 39.304067 -411.187245)
					(end 39.268146 -411.202124)
				)
				(arc
					(start 38.551866 -411.202124)
					(mid 38.515945 -411.187245)
					(end 38.501066 -411.151324)
				)
			)
		)
	)
	(zone
		(layers "F.Cu" "B.Cu" "In1.Cu" "In2.Cu" "In3.Cu" "In4.Cu" "In5.Cu" "In6.Cu"
			"In7.Cu" "In8.Cu" "In9.Cu" "In10.Cu" "In11.Cu" "In12.Cu" "In13.Cu" "In14.Cu"
			"In15.Cu" "In16.Cu"
		)
		(hatch none 0.5)
		(connect_pads
			(clearance 0)
		)
		(min_thickness 0.25)
		(keepout
			(tracks not_allowed)
			(vias allowed)
			(pads allowed)
			(copperpour not_allowed)
			(footprints allowed)
		)
		(placement
			(enabled no)
			(sheetname "")
		)
		(fill
			(thermal_gap 0.5)
			(thermal_bridge_width 0.5)
			(island_removal_mode 0)
		)
		(polygon
			(pts
				(arc
					(start 75.901042 -399.828766)
					(mid 75.915921 -399.792845)
					(end 75.951842 -399.777966)
				)
				(arc
					(start 76.668122 -399.777966)
					(mid 76.704043 -399.792845)
					(end 76.718922 -399.828766)
				)
				(arc
					(start 76.718922 -402.251418)
					(mid 76.704043 -402.287339)
					(end 76.668122 -402.302218)
				)
				(arc
					(start 75.951842 -402.302218)
					(mid 75.915921 -402.287339)
					(end 75.901042 -402.251418)
				)
			)
		)
	)
	(zone
		(layers "F.Cu" "B.Cu" "In1.Cu" "In2.Cu" "In3.Cu" "In4.Cu" "In5.Cu" "In6.Cu"
			"In7.Cu" "In8.Cu" "In9.Cu" "In10.Cu" "In11.Cu" "In12.Cu" "In13.Cu" "In14.Cu"
			"In15.Cu" "In16.Cu"
		)
		(hatch none 0.5)
		(connect_pads
			(clearance 0)
		)
		(min_thickness 0.25)
		(keepout
			(tracks not_allowed)
			(vias allowed)
			(pads allowed)
			(copperpour not_allowed)
			(footprints allowed)
		)
		(placement
			(enabled no)
			(sheetname "")
		)
		(fill
			(thermal_gap 0.5)
			(thermal_bridge_width 0.5)
			(island_removal_mode 0)
		)
		(polygon
			(pts
				(arc
					(start 386.73278 -348.20479)
					(mid 386.35178 -348.58579)
					(end 386.73278 -348.96679)
				)
				(arc
					(start 387.59638 -348.96679)
					(mid 387.97738 -348.58579)
					(end 387.59638 -348.20479)
				)
			)
		)
	)
	(zone
		(layers "F.Cu" "B.Cu" "In1.Cu" "In2.Cu" "In3.Cu" "In4.Cu" "In5.Cu" "In6.Cu"
			"In7.Cu" "In8.Cu" "In9.Cu" "In10.Cu" "In11.Cu" "In12.Cu" "In13.Cu" "In14.Cu"
			"In15.Cu" "In16.Cu"
		)
		(hatch none 0.5)
		(connect_pads
			(clearance 0)
		)
		(min_thickness 0.25)
		(keepout
			(tracks not_allowed)
			(vias allowed)
			(pads allowed)
			(copperpour not_allowed)
			(footprints allowed)
		)
		(placement
			(enabled no)
			(sheetname "")
		)
		(fill
			(thermal_gap 0.5)
			(thermal_bridge_width 0.5)
			(island_removal_mode 0)
		)
		(polygon
			(pts
				(arc
					(start 67.590162 -348.20479)
					(mid 67.209162 -348.58579)
					(end 67.590162 -348.96679)
				)
				(arc
					(start 68.453762 -348.96679)
					(mid 68.834762 -348.58579)
					(end 68.453762 -348.20479)
				)
			)
		)
	)
	(zone
		(layers "F.Cu" "B.Cu" "In1.Cu" "In2.Cu" "In3.Cu" "In4.Cu" "In5.Cu" "In6.Cu"
			"In7.Cu" "In8.Cu" "In9.Cu" "In10.Cu" "In11.Cu" "In12.Cu" "In13.Cu" "In14.Cu"
			"In15.Cu" "In16.Cu"
		)
		(hatch none 0.5)
		(connect_pads
			(clearance 0)
		)
		(min_thickness 0.25)
		(keepout
			(tracks not_allowed)
			(vias allowed)
			(pads allowed)
			(copperpour not_allowed)
			(footprints allowed)
		)
		(placement
			(enabled no)
			(sheetname "")
		)
		(fill
			(thermal_gap 0.5)
			(thermal_bridge_width 0.5)
			(island_removal_mode 0)
		)
		(polygon
			(pts
				(arc
					(start 31.90113 -373.828818)
					(mid 31.916009 -373.792897)
					(end 31.95193 -373.778018)
				)
				(arc
					(start 32.66821 -373.778018)
					(mid 32.704131 -373.792897)
					(end 32.71901 -373.828818)
				)
				(arc
					(start 32.71901 -376.25147)
					(mid 32.704131 -376.287391)
					(end 32.66821 -376.30227)
				)
				(arc
					(start 31.95193 -376.30227)
					(mid 31.916009 -376.287391)
					(end 31.90113 -376.25147)
				)
			)
		)
	)
	(zone
		(layers "F.Cu" "B.Cu" "In1.Cu" "In2.Cu" "In3.Cu" "In4.Cu" "In5.Cu" "In6.Cu"
			"In7.Cu" "In8.Cu" "In9.Cu" "In10.Cu" "In11.Cu" "In12.Cu" "In13.Cu" "In14.Cu"
			"In15.Cu" "In16.Cu"
		)
		(hatch none 0.5)
		(connect_pads
			(clearance 0)
		)
		(min_thickness 0.25)
		(keepout
			(tracks not_allowed)
			(vias allowed)
			(pads allowed)
			(copperpour not_allowed)
			(footprints allowed)
		)
		(placement
			(enabled no)
			(sheetname "")
		)
		(fill
			(thermal_gap 0.5)
			(thermal_bridge_width 0.5)
			(island_removal_mode 0)
		)
		(polygon
			(pts
				(arc
					(start 257.520186 -173.495716)
					(mid 257.977386 -173.952916)
					(end 258.434586 -173.495716)
				)
				(arc
					(start 258.434586 -172.632116)
					(mid 257.977386 -172.174916)
					(end 257.520186 -172.632116)
				)
			)
		)
	)
	(zone
		(layers "F.Cu" "B.Cu" "In1.Cu" "In2.Cu" "In3.Cu" "In4.Cu" "In5.Cu" "In6.Cu"
			"In7.Cu" "In8.Cu" "In9.Cu" "In10.Cu" "In11.Cu" "In12.Cu" "In13.Cu" "In14.Cu"
			"In15.Cu" "In16.Cu"
		)
		(hatch none 0.5)
		(connect_pads
			(clearance 0)
		)
		(min_thickness 0.25)
		(keepout
			(tracks not_allowed)
			(vias allowed)
			(pads allowed)
			(copperpour not_allowed)
			(footprints allowed)
		)
		(placement
			(enabled no)
			(sheetname "")
		)
		(fill
			(thermal_gap 0.5)
			(thermal_bridge_width 0.5)
			(island_removal_mode 0)
		)
		(polygon
			(pts
				(arc
					(start 171.512992 -351.230438)
					(mid 171.131992 -351.611438)
					(end 171.512992 -351.992438)
				)
				(arc
					(start 172.376592 -351.992438)
					(mid 172.757592 -351.611438)
					(end 172.376592 -351.230438)
				)
			)
		)
	)
	(zone
		(layers "F.Cu" "B.Cu" "In1.Cu" "In2.Cu" "In3.Cu" "In4.Cu" "In5.Cu" "In6.Cu"
			"In7.Cu" "In8.Cu" "In9.Cu" "In10.Cu" "In11.Cu" "In12.Cu" "In13.Cu" "In14.Cu"
			"In15.Cu" "In16.Cu"
		)
		(hatch none 0.5)
		(connect_pads
			(clearance 0)
		)
		(min_thickness 0.25)
		(keepout
			(tracks not_allowed)
			(vias allowed)
			(pads allowed)
			(copperpour not_allowed)
			(footprints allowed)
		)
		(placement
			(enabled no)
			(sheetname "")
		)
		(fill
			(thermal_gap 0.5)
			(thermal_bridge_width 0.5)
			(island_removal_mode 0)
		)
		(polygon
			(pts
				(arc
					(start 86.90102 -378.828554)
					(mid 86.915899 -378.792633)
					(end 86.95182 -378.777754)
				)
				(arc
					(start 87.6681 -378.777754)
					(mid 87.704021 -378.792633)
					(end 87.7189 -378.828554)
				)
				(arc
					(start 87.7189 -381.251206)
					(mid 87.704021 -381.287127)
					(end 87.6681 -381.302006)
				)
				(arc
					(start 86.95182 -381.302006)
					(mid 86.915899 -381.287127)
					(end 86.90102 -381.251206)
				)
			)
		)
	)
	(zone
		(layers "F.Cu" "B.Cu" "In1.Cu" "In2.Cu" "In3.Cu" "In4.Cu" "In5.Cu" "In6.Cu"
			"In7.Cu" "In8.Cu" "In9.Cu" "In10.Cu" "In11.Cu" "In12.Cu" "In13.Cu" "In14.Cu"
			"In15.Cu" "In16.Cu"
		)
		(hatch none 0.5)
		(connect_pads
			(clearance 0)
		)
		(min_thickness 0.25)
		(keepout
			(tracks not_allowed)
			(vias allowed)
			(pads allowed)
			(copperpour not_allowed)
			(footprints allowed)
		)
		(placement
			(enabled no)
			(sheetname "")
		)
		(fill
			(thermal_gap 0.5)
			(thermal_bridge_width 0.5)
			(island_removal_mode 0)
		)
		(polygon
			(pts
				(arc
					(start 375.081038 -369.928902)
					(mid 375.095917 -369.892981)
					(end 375.131838 -369.878102)
				)
				(arc
					(start 375.848118 -369.878102)
					(mid 375.884039 -369.892981)
					(end 375.898918 -369.928902)
				)
				(arc
					(start 375.898918 -372.351554)
					(mid 375.884039 -372.387475)
					(end 375.848118 -372.402354)
				)
				(arc
					(start 375.131838 -372.402354)
					(mid 375.095917 -372.387475)
					(end 375.081038 -372.351554)
				)
			)
		)
	)
	(zone
		(layers "F.Cu" "B.Cu" "In1.Cu" "In2.Cu" "In3.Cu" "In4.Cu" "In5.Cu" "In6.Cu"
			"In7.Cu" "In8.Cu" "In9.Cu" "In10.Cu" "In11.Cu" "In12.Cu" "In13.Cu" "In14.Cu"
			"In15.Cu" "In16.Cu"
		)
		(hatch none 0.5)
		(connect_pads
			(clearance 0)
		)
		(min_thickness 0.25)
		(keepout
			(tracks not_allowed)
			(vias allowed)
			(pads allowed)
			(copperpour not_allowed)
			(footprints allowed)
		)
		(placement
			(enabled no)
			(sheetname "")
		)
		(fill
			(thermal_gap 0.5)
			(thermal_bridge_width 0.5)
			(island_removal_mode 0)
		)
		(polygon
			(pts
				(arc
					(start 126.501144 -400.92884)
					(mid 126.516023 -400.892919)
					(end 126.551944 -400.87804)
				)
				(arc
					(start 127.268224 -400.87804)
					(mid 127.304145 -400.892919)
					(end 127.319024 -400.92884)
				)
				(arc
					(start 127.319024 -403.351492)
					(mid 127.304145 -403.387413)
					(end 127.268224 -403.402292)
				)
				(arc
					(start 126.551944 -403.402292)
					(mid 126.516023 -403.387413)
					(end 126.501144 -403.351492)
				)
			)
		)
	)
	(zone
		(layers "F.Cu" "B.Cu" "In1.Cu" "In2.Cu" "In3.Cu" "In4.Cu" "In5.Cu" "In6.Cu"
			"In7.Cu" "In8.Cu" "In9.Cu" "In10.Cu" "In11.Cu" "In12.Cu" "In13.Cu" "In14.Cu"
			"In15.Cu" "In16.Cu"
		)
		(hatch none 0.5)
		(connect_pads
			(clearance 0)
		)
		(min_thickness 0.25)
		(keepout
			(tracks not_allowed)
			(vias allowed)
			(pads allowed)
			(copperpour not_allowed)
			(footprints allowed)
		)
		(placement
			(enabled no)
			(sheetname "")
		)
		(fill
			(thermal_gap 0.5)
			(thermal_bridge_width 0.5)
			(island_removal_mode 0)
		)
		(polygon
			(pts
				(arc
					(start 311.63387 21.000212)
					(mid 311.25287 21.381212)
					(end 310.87187 21.000212)
				)
				(arc
					(start 310.87187 20.136612)
					(mid 311.25287 19.755612)
					(end 311.63387 20.136612)
				)
			)
		)
	)
	(zone
		(layers "F.Cu" "B.Cu" "In1.Cu" "In2.Cu" "In3.Cu" "In4.Cu" "In5.Cu" "In6.Cu"
			"In7.Cu" "In8.Cu" "In9.Cu" "In10.Cu" "In11.Cu" "In12.Cu" "In13.Cu" "In14.Cu"
			"In15.Cu" "In16.Cu"
		)
		(hatch none 0.5)
		(connect_pads
			(clearance 0)
		)
		(min_thickness 0.25)
		(keepout
			(tracks not_allowed)
			(vias allowed)
			(pads allowed)
			(copperpour not_allowed)
			(footprints allowed)
		)
		(placement
			(enabled no)
			(sheetname "")
		)
		(fill
			(thermal_gap 0.5)
			(thermal_bridge_width 0.5)
			(island_removal_mode 0)
		)
		(polygon
			(pts
				(arc
					(start 313.274964 -154.279346)
					(mid 313.732164 -154.736546)
					(end 314.189364 -154.279346)
				)
				(arc
					(start 314.189364 -153.415746)
					(mid 313.732164 -152.958546)
					(end 313.274964 -153.415746)
				)
			)
		)
	)
	(zone
		(layers "F.Cu" "B.Cu" "In1.Cu" "In2.Cu" "In3.Cu" "In4.Cu" "In5.Cu" "In6.Cu"
			"In7.Cu" "In8.Cu" "In9.Cu" "In10.Cu" "In11.Cu" "In12.Cu" "In13.Cu" "In14.Cu"
			"In15.Cu" "In16.Cu"
		)
		(hatch none 0.5)
		(connect_pads
			(clearance 0)
		)
		(min_thickness 0.25)
		(keepout
			(tracks not_allowed)
			(vias allowed)
			(pads allowed)
			(copperpour not_allowed)
			(footprints allowed)
		)
		(placement
			(enabled no)
			(sheetname "")
		)
		(fill
			(thermal_gap 0.5)
			(thermal_bridge_width 0.5)
			(island_removal_mode 0)
		)
		(polygon
			(pts
				(arc
					(start 266.807442 -29.12237)
					(mid 267.264642 -29.57957)
					(end 267.721842 -29.12237)
				)
				(arc
					(start 267.721842 -28.25877)
					(mid 267.264642 -27.80157)
					(end 266.807442 -28.25877)
				)
			)
		)
	)
	(zone
		(layers "F.Cu" "B.Cu" "In1.Cu" "In2.Cu" "In3.Cu" "In4.Cu" "In5.Cu" "In6.Cu"
			"In7.Cu" "In8.Cu" "In9.Cu" "In10.Cu" "In11.Cu" "In12.Cu" "In13.Cu" "In14.Cu"
			"In15.Cu" "In16.Cu"
		)
		(hatch none 0.5)
		(connect_pads
			(clearance 0)
		)
		(min_thickness 0.25)
		(keepout
			(tracks not_allowed)
			(vias allowed)
			(pads allowed)
			(copperpour not_allowed)
			(footprints allowed)
		)
		(placement
			(enabled no)
			(sheetname "")
		)
		(fill
			(thermal_gap 0.5)
			(thermal_bridge_width 0.5)
			(island_removal_mode 0)
		)
		(polygon
			(pts
				(arc
					(start 114.971068 -345.084146)
					(mid 114.590068 -345.465146)
					(end 114.971068 -345.846146)
				)
				(arc
					(start 115.834668 -345.846146)
					(mid 116.215668 -345.465146)
					(end 115.834668 -345.084146)
				)
			)
		)
	)
	(zone
		(layers "F.Cu" "B.Cu" "In1.Cu" "In2.Cu" "In3.Cu" "In4.Cu" "In5.Cu" "In6.Cu"
			"In7.Cu" "In8.Cu" "In9.Cu" "In10.Cu" "In11.Cu" "In12.Cu" "In13.Cu" "In14.Cu"
			"In15.Cu" "In16.Cu"
		)
		(hatch none 0.5)
		(connect_pads
			(clearance 0)
		)
		(min_thickness 0.25)
		(keepout
			(tracks not_allowed)
			(vias allowed)
			(pads allowed)
			(copperpour not_allowed)
			(footprints allowed)
		)
		(placement
			(enabled no)
			(sheetname "")
		)
		(fill
			(thermal_gap 0.5)
			(thermal_bridge_width 0.5)
			(island_removal_mode 0)
		)
		(polygon
			(pts
				(arc
					(start 81.075022 -147.079208)
					(mid 81.532222 -147.536408)
					(end 81.989422 -147.079208)
				)
				(arc
					(start 81.989422 -146.215608)
					(mid 81.532222 -145.758408)
					(end 81.075022 -146.215608)
				)
			)
		)
	)
	(zone
		(layers "F.Cu" "B.Cu" "In1.Cu" "In2.Cu" "In3.Cu" "In4.Cu" "In5.Cu" "In6.Cu"
			"In7.Cu" "In8.Cu" "In9.Cu" "In10.Cu" "In11.Cu" "In12.Cu" "In13.Cu" "In14.Cu"
			"In15.Cu" "In16.Cu"
		)
		(hatch none 0.5)
		(connect_pads
			(clearance 0)
		)
		(min_thickness 0.25)
		(keepout
			(tracks not_allowed)
			(vias allowed)
			(pads allowed)
			(copperpour not_allowed)
			(footprints allowed)
		)
		(placement
			(enabled no)
			(sheetname "")
		)
		(fill
			(thermal_gap 0.5)
			(thermal_bridge_width 0.5)
			(island_removal_mode 0)
		)
		(polygon
			(pts
				(arc
					(start 80.301084 -399.828766)
					(mid 80.315963 -399.792845)
					(end 80.351884 -399.777966)
				)
				(arc
					(start 81.068164 -399.777966)
					(mid 81.104085 -399.792845)
					(end 81.118964 -399.828766)
				)
				(arc
					(start 81.118964 -402.251418)
					(mid 81.104085 -402.287339)
					(end 81.068164 -402.302218)
				)
				(arc
					(start 80.351884 -402.302218)
					(mid 80.315963 -402.287339)
					(end 80.301084 -402.251418)
				)
			)
		)
	)
	(zone
		(layers "F.Cu" "B.Cu" "In1.Cu" "In2.Cu" "In3.Cu" "In4.Cu" "In5.Cu" "In6.Cu"
			"In7.Cu" "In8.Cu" "In9.Cu" "In10.Cu" "In11.Cu" "In12.Cu" "In13.Cu" "In14.Cu"
			"In15.Cu" "In16.Cu"
		)
		(hatch none 0.5)
		(connect_pads
			(clearance 0)
		)
		(min_thickness 0.25)
		(keepout
			(tracks not_allowed)
			(vias allowed)
			(pads allowed)
			(copperpour not_allowed)
			(footprints allowed)
		)
		(placement
			(enabled no)
			(sheetname "")
		)
		(fill
			(thermal_gap 0.5)
			(thermal_bridge_width 0.5)
			(island_removal_mode 0)
		)
		(polygon
			(pts
				(arc
					(start 188.124592 -160.1851)
					(mid 185.990484 -160.1851)
					(end 188.124592 -160.1851)
				)
			)
		)
	)
	(zone
		(layers "F.Cu" "B.Cu" "In1.Cu" "In2.Cu" "In3.Cu" "In4.Cu" "In5.Cu" "In6.Cu"
			"In7.Cu" "In8.Cu" "In9.Cu" "In10.Cu" "In11.Cu" "In12.Cu" "In13.Cu" "In14.Cu"
			"In15.Cu" "In16.Cu"
		)
		(hatch none 0.5)
		(connect_pads
			(clearance 0)
		)
		(min_thickness 0.25)
		(keepout
			(tracks not_allowed)
			(vias allowed)
			(pads allowed)
			(copperpour not_allowed)
			(footprints allowed)
		)
		(placement
			(enabled no)
			(sheetname "")
		)
		(fill
			(thermal_gap 0.5)
			(thermal_bridge_width 0.5)
			(island_removal_mode 0)
		)
		(polygon
			(pts
				(arc
					(start 430.080928 -374.928638)
					(mid 430.095807 -374.892717)
					(end 430.131728 -374.877838)
				)
				(arc
					(start 430.848008 -374.877838)
					(mid 430.883929 -374.892717)
					(end 430.898808 -374.928638)
				)
				(arc
					(start 430.898808 -377.35129)
					(mid 430.883929 -377.387211)
					(end 430.848008 -377.40209)
				)
				(arc
					(start 430.131728 -377.40209)
					(mid 430.095807 -377.387211)
					(end 430.080928 -377.35129)
				)
			)
		)
	)
	(zone
		(layers "F.Cu" "B.Cu" "In1.Cu" "In2.Cu" "In3.Cu" "In4.Cu" "In5.Cu" "In6.Cu"
			"In7.Cu" "In8.Cu" "In9.Cu" "In10.Cu" "In11.Cu" "In12.Cu" "In13.Cu" "In14.Cu"
			"In15.Cu" "In16.Cu"
		)
		(hatch none 0.5)
		(connect_pads
			(clearance 0)
		)
		(min_thickness 0.25)
		(keepout
			(tracks not_allowed)
			(vias allowed)
			(pads allowed)
			(copperpour not_allowed)
			(footprints allowed)
		)
		(placement
			(enabled no)
			(sheetname "")
		)
		(fill
			(thermal_gap 0.5)
			(thermal_bridge_width 0.5)
			(island_removal_mode 0)
		)
		(polygon
			(pts
				(arc
					(start 286.550862 -348.20479)
					(mid 286.169862 -348.58579)
					(end 286.550862 -348.96679)
				)
				(arc
					(start 287.414462 -348.96679)
					(mid 287.795462 -348.58579)
					(end 287.414462 -348.20479)
				)
			)
		)
	)
	(zone
		(layers "F.Cu" "B.Cu" "In1.Cu" "In2.Cu" "In3.Cu" "In4.Cu" "In5.Cu" "In6.Cu"
			"In7.Cu" "In8.Cu" "In9.Cu" "In10.Cu" "In11.Cu" "In12.Cu" "In13.Cu" "In14.Cu"
			"In15.Cu" "In16.Cu"
		)
		(hatch none 0.5)
		(connect_pads
			(clearance 0)
		)
		(min_thickness 0.25)
		(keepout
			(tracks not_allowed)
			(vias allowed)
			(pads allowed)
			(copperpour not_allowed)
			(footprints allowed)
		)
		(placement
			(enabled no)
			(sheetname "")
		)
		(fill
			(thermal_gap 0.5)
			(thermal_bridge_width 0.5)
			(island_removal_mode 0)
		)
		(polygon
			(pts
				(arc
					(start 60.607448 -32.722312)
					(mid 61.064648 -33.179512)
					(end 61.521848 -32.722312)
				)
				(arc
					(start 61.521848 -31.858712)
					(mid 61.064648 -31.401512)
					(end 60.607448 -31.858712)
				)
			)
		)
	)
	(zone
		(layers "F.Cu" "B.Cu" "In1.Cu" "In2.Cu" "In3.Cu" "In4.Cu" "In5.Cu" "In6.Cu"
			"In7.Cu" "In8.Cu" "In9.Cu" "In10.Cu" "In11.Cu" "In12.Cu" "In13.Cu" "In14.Cu"
			"In15.Cu" "In16.Cu"
		)
		(hatch none 0.5)
		(connect_pads
			(clearance 0)
		)
		(min_thickness 0.25)
		(keepout
			(tracks not_allowed)
			(vias allowed)
			(pads allowed)
			(copperpour not_allowed)
			(footprints allowed)
		)
		(placement
			(enabled no)
			(sheetname "")
		)
		(fill
			(thermal_gap 0.5)
			(thermal_bridge_width 0.5)
			(island_removal_mode 0)
		)
		(polygon
			(pts
				(arc
					(start 402.85416 -134.032752)
					(mid 402.39696 -133.575552)
					(end 401.93976 -134.032752)
				)
				(arc
					(start 401.93976 -134.896352)
					(mid 402.39696 -135.353552)
					(end 402.85416 -134.896352)
				)
			)
		)
	)
	(zone
		(layers "F.Cu" "B.Cu" "In1.Cu" "In2.Cu" "In3.Cu" "In4.Cu" "In5.Cu" "In6.Cu"
			"In7.Cu" "In8.Cu" "In9.Cu" "In10.Cu" "In11.Cu" "In12.Cu" "In13.Cu" "In14.Cu"
			"In15.Cu" "In16.Cu"
		)
		(hatch none 0.5)
		(connect_pads
			(clearance 0)
		)
		(min_thickness 0.25)
		(keepout
			(tracks not_allowed)
			(vias allowed)
			(pads allowed)
			(copperpour not_allowed)
			(footprints allowed)
		)
		(placement
			(enabled no)
			(sheetname "")
		)
		(fill
			(thermal_gap 0.5)
			(thermal_bridge_width 0.5)
			(island_removal_mode 0)
		)
		(polygon
			(pts
				(arc
					(start 419.08095 -407.628852)
					(mid 419.095829 -407.592931)
					(end 419.13175 -407.578052)
				)
				(arc
					(start 419.84803 -407.578052)
					(mid 419.883951 -407.592931)
					(end 419.89883 -407.628852)
				)
				(arc
					(start 419.89883 -410.051504)
					(mid 419.883951 -410.087425)
					(end 419.84803 -410.102304)
				)
				(arc
					(start 419.13175 -410.102304)
					(mid 419.095829 -410.087425)
					(end 419.08095 -410.051504)
				)
			)
		)
	)
	(zone
		(layers "F.Cu" "B.Cu" "In1.Cu" "In2.Cu" "In3.Cu" "In4.Cu" "In5.Cu" "In6.Cu"
			"In7.Cu" "In8.Cu" "In9.Cu" "In10.Cu" "In11.Cu" "In12.Cu" "In13.Cu" "In14.Cu"
			"In15.Cu" "In16.Cu"
		)
		(hatch none 0.5)
		(connect_pads
			(clearance 0)
		)
		(min_thickness 0.25)
		(keepout
			(tracks not_allowed)
			(vias allowed)
			(pads allowed)
			(copperpour not_allowed)
			(footprints allowed)
		)
		(placement
			(enabled no)
			(sheetname "")
		)
		(fill
			(thermal_gap 0.5)
			(thermal_bridge_width 0.5)
			(island_removal_mode 0)
		)
		(polygon
			(pts
				(arc
					(start 91.301062 -404.828756)
					(mid 91.315941 -404.792835)
					(end 91.351862 -404.777956)
				)
				(arc
					(start 92.068142 -404.777956)
					(mid 92.104063 -404.792835)
					(end 92.118942 -404.828756)
				)
				(arc
					(start 92.118942 -407.251408)
					(mid 92.104063 -407.287329)
					(end 92.068142 -407.302208)
				)
				(arc
					(start 91.351862 -407.302208)
					(mid 91.315941 -407.287329)
					(end 91.301062 -407.251408)
				)
			)
		)
	)
	(zone
		(layers "F.Cu" "B.Cu" "In1.Cu" "In2.Cu" "In3.Cu" "In4.Cu" "In5.Cu" "In6.Cu"
			"In7.Cu" "In8.Cu" "In9.Cu" "In10.Cu" "In11.Cu" "In12.Cu" "In13.Cu" "In14.Cu"
			"In15.Cu" "In16.Cu"
		)
		(hatch none 0.5)
		(connect_pads
			(clearance 0)
		)
		(min_thickness 0.25)
		(keepout
			(tracks not_allowed)
			(vias allowed)
			(pads allowed)
			(copperpour not_allowed)
			(footprints allowed)
		)
		(placement
			(enabled no)
			(sheetname "")
		)
		(fill
			(thermal_gap 0.5)
			(thermal_bridge_width 0.5)
			(island_removal_mode 0)
		)
		(polygon
			(pts
				(arc
					(start 440.384692 -357.37673)
					(mid 440.003692 -357.75773)
					(end 440.384692 -358.13873)
				)
				(arc
					(start 441.248292 -358.13873)
					(mid 441.629292 -357.75773)
					(end 441.248292 -357.37673)
				)
			)
		)
	)
	(zone
		(layers "F.Cu" "B.Cu" "In1.Cu" "In2.Cu" "In3.Cu" "In4.Cu" "In5.Cu" "In6.Cu"
			"In7.Cu" "In8.Cu" "In9.Cu" "In10.Cu" "In11.Cu" "In12.Cu" "In13.Cu" "In14.Cu"
			"In15.Cu" "In16.Cu"
		)
		(hatch none 0.5)
		(connect_pads
			(clearance 0)
		)
		(min_thickness 0.25)
		(keepout
			(tracks not_allowed)
			(vias allowed)
			(pads allowed)
			(copperpour not_allowed)
			(footprints allowed)
		)
		(placement
			(enabled no)
			(sheetname "")
		)
		(fill
			(thermal_gap 0.5)
			(thermal_bridge_width 0.5)
			(island_removal_mode 0)
		)
		(polygon
			(pts
				(arc
					(start 166.101014 -408.728672)
					(mid 166.115893 -408.692751)
					(end 166.151814 -408.677872)
				)
				(arc
					(start 166.868094 -408.677872)
					(mid 166.904015 -408.692751)
					(end 166.918894 -408.728672)
				)
				(arc
					(start 166.918894 -411.151324)
					(mid 166.904015 -411.187245)
					(end 166.868094 -411.202124)
				)
				(arc
					(start 166.151814 -411.202124)
					(mid 166.115893 -411.187245)
					(end 166.101014 -411.151324)
				)
			)
		)
	)
	(zone
		(layers "F.Cu" "B.Cu" "In1.Cu" "In2.Cu" "In3.Cu" "In4.Cu" "In5.Cu" "In6.Cu"
			"In7.Cu" "In8.Cu" "In9.Cu" "In10.Cu" "In11.Cu" "In12.Cu" "In13.Cu" "In14.Cu"
			"In15.Cu" "In16.Cu"
		)
		(hatch none 0.5)
		(connect_pads
			(clearance 0)
		)
		(min_thickness 0.25)
		(keepout
			(tracks not_allowed)
			(vias allowed)
			(pads allowed)
			(copperpour not_allowed)
			(footprints allowed)
		)
		(placement
			(enabled no)
			(sheetname "")
		)
		(fill
			(thermal_gap 0.5)
			(thermal_bridge_width 0.5)
			(island_removal_mode 0)
		)
		(polygon
			(pts
				(arc
					(start 423.480992 -403.728682)
					(mid 423.495871 -403.692761)
					(end 423.531792 -403.677882)
				)
				(arc
					(start 424.248072 -403.677882)
					(mid 424.283993 -403.692761)
					(end 424.298872 -403.728682)
				)
				(arc
					(start 424.298872 -406.151334)
					(mid 424.283993 -406.187255)
					(end 424.248072 -406.202134)
				)
				(arc
					(start 423.531792 -406.202134)
					(mid 423.495871 -406.187255)
					(end 423.480992 -406.151334)
				)
			)
		)
	)
	(zone
		(layers "F.Cu" "B.Cu" "In1.Cu" "In2.Cu" "In3.Cu" "In4.Cu" "In5.Cu" "In6.Cu"
			"In7.Cu" "In8.Cu" "In9.Cu" "In10.Cu" "In11.Cu" "In12.Cu" "In13.Cu" "In14.Cu"
			"In15.Cu" "In16.Cu"
		)
		(hatch none 0.5)
		(connect_pads
			(clearance 0)
		)
		(min_thickness 0.25)
		(keepout
			(tracks not_allowed)
			(vias allowed)
			(pads allowed)
			(copperpour not_allowed)
			(footprints allowed)
		)
		(placement
			(enabled no)
			(sheetname "")
		)
		(fill
			(thermal_gap 0.5)
			(thermal_bridge_width 0.5)
			(island_removal_mode 0)
		)
		(polygon
			(pts
				(arc
					(start 267.897102 -348.20479)
					(mid 267.516102 -348.58579)
					(end 267.897102 -348.96679)
				)
				(arc
					(start 268.760702 -348.96679)
					(mid 269.141702 -348.58579)
					(end 268.760702 -348.20479)
				)
			)
		)
	)
	(zone
		(layers "F.Cu" "B.Cu" "In1.Cu" "In2.Cu" "In3.Cu" "In4.Cu" "In5.Cu" "In6.Cu"
			"In7.Cu" "In8.Cu" "In9.Cu" "In10.Cu" "In11.Cu" "In12.Cu" "In13.Cu" "In14.Cu"
			"In15.Cu" "In16.Cu"
		)
		(hatch none 0.5)
		(connect_pads
			(clearance 0)
		)
		(min_thickness 0.25)
		(keepout
			(tracks not_allowed)
			(vias allowed)
			(pads allowed)
			(copperpour not_allowed)
			(footprints allowed)
		)
		(placement
			(enabled no)
			(sheetname "")
		)
		(fill
			(thermal_gap 0.5)
			(thermal_bridge_width 0.5)
			(island_removal_mode 0)
		)
		(polygon
			(pts
				(arc
					(start 429.375062 -130.769106)
					(mid 429.832262 -131.226306)
					(end 430.289462 -130.769106)
				)
				(arc
					(start 430.289462 -129.905506)
					(mid 429.832262 -129.448306)
					(end 429.375062 -129.905506)
				)
			)
		)
	)
	(zone
		(layers "F.Cu" "B.Cu" "In1.Cu" "In2.Cu" "In3.Cu" "In4.Cu" "In5.Cu" "In6.Cu"
			"In7.Cu" "In8.Cu" "In9.Cu" "In10.Cu" "In11.Cu" "In12.Cu" "In13.Cu" "In14.Cu"
			"In15.Cu" "In16.Cu"
		)
		(hatch none 0.5)
		(connect_pads
			(clearance 0)
		)
		(min_thickness 0.25)
		(keepout
			(tracks not_allowed)
			(vias allowed)
			(pads allowed)
			(copperpour not_allowed)
			(footprints allowed)
		)
		(placement
			(enabled no)
			(sheetname "")
		)
		(fill
			(thermal_gap 0.5)
			(thermal_bridge_width 0.5)
			(island_removal_mode 0)
		)
		(polygon
			(pts
				(arc
					(start 421.280844 -382.728724)
					(mid 421.295723 -382.692803)
					(end 421.331644 -382.677924)
				)
				(arc
					(start 422.047924 -382.677924)
					(mid 422.083845 -382.692803)
					(end 422.098724 -382.728724)
				)
				(arc
					(start 422.098724 -385.151376)
					(mid 422.083845 -385.187297)
					(end 422.047924 -385.202176)
				)
				(arc
					(start 421.331644 -385.202176)
					(mid 421.295723 -385.187297)
					(end 421.280844 -385.151376)
				)
			)
		)
	)
	(zone
		(layers "F.Cu" "B.Cu" "In1.Cu" "In2.Cu" "In3.Cu" "In4.Cu" "In5.Cu" "In6.Cu"
			"In7.Cu" "In8.Cu" "In9.Cu" "In10.Cu" "In11.Cu" "In12.Cu" "In13.Cu" "In14.Cu"
			"In15.Cu" "In16.Cu"
		)
		(hatch none 0.5)
		(connect_pads
			(clearance 0)
		)
		(min_thickness 0.25)
		(keepout
			(tracks not_allowed)
			(vias allowed)
			(pads allowed)
			(copperpour not_allowed)
			(footprints allowed)
		)
		(placement
			(enabled no)
			(sheetname "")
		)
		(fill
			(thermal_gap 0.5)
			(thermal_bridge_width 0.5)
			(island_removal_mode 0)
		)
		(polygon
			(pts
				(arc
					(start 337.681062 -382.728724)
					(mid 337.695941 -382.692803)
					(end 337.731862 -382.677924)
				)
				(arc
					(start 338.448142 -382.677924)
					(mid 338.484063 -382.692803)
					(end 338.498942 -382.728724)
				)
				(arc
					(start 338.498942 -385.151376)
					(mid 338.484063 -385.187297)
					(end 338.448142 -385.202176)
				)
				(arc
					(start 337.731862 -385.202176)
					(mid 337.695941 -385.187297)
					(end 337.681062 -385.151376)
				)
			)
		)
	)
	(zone
		(layers "F.Cu" "B.Cu" "In1.Cu" "In2.Cu" "In3.Cu" "In4.Cu" "In5.Cu" "In6.Cu"
			"In7.Cu" "In8.Cu" "In9.Cu" "In10.Cu" "In11.Cu" "In12.Cu" "In13.Cu" "In14.Cu"
			"In15.Cu" "In16.Cu"
		)
		(hatch none 0.5)
		(connect_pads
			(clearance 0)
		)
		(min_thickness 0.25)
		(keepout
			(tracks not_allowed)
			(vias allowed)
			(pads allowed)
			(copperpour not_allowed)
			(footprints allowed)
		)
		(placement
			(enabled no)
			(sheetname "")
		)
		(fill
			(thermal_gap 0.5)
			(thermal_bridge_width 0.5)
			(island_removal_mode 0)
		)
		(polygon
			(pts
				(arc
					(start 293.680896 -400.92884)
					(mid 293.695775 -400.892919)
					(end 293.731696 -400.87804)
				)
				(arc
					(start 294.447976 -400.87804)
					(mid 294.483897 -400.892919)
					(end 294.498776 -400.92884)
				)
				(arc
					(start 294.498776 -403.351492)
					(mid 294.483897 -403.387413)
					(end 294.447976 -403.402292)
				)
				(arc
					(start 293.731696 -403.402292)
					(mid 293.695775 -403.387413)
					(end 293.680896 -403.351492)
				)
			)
		)
	)
	(zone
		(layers "F.Cu" "B.Cu" "In1.Cu" "In2.Cu" "In3.Cu" "In4.Cu" "In5.Cu" "In6.Cu"
			"In7.Cu" "In8.Cu" "In9.Cu" "In10.Cu" "In11.Cu" "In12.Cu" "In13.Cu" "In14.Cu"
			"In15.Cu" "In16.Cu"
		)
		(hatch none 0.5)
		(connect_pads
			(clearance 0)
		)
		(min_thickness 0.25)
		(keepout
			(tracks not_allowed)
			(vias allowed)
			(pads allowed)
			(copperpour not_allowed)
			(footprints allowed)
		)
		(placement
			(enabled no)
			(sheetname "")
		)
		(fill
			(thermal_gap 0.5)
			(thermal_bridge_width 0.5)
			(island_removal_mode 0)
		)
		(polygon
			(pts
				(arc
					(start 136.733788 -357.37673)
					(mid 136.352788 -357.75773)
					(end 136.733788 -358.13873)
				)
				(arc
					(start 137.597388 -358.13873)
					(mid 137.978388 -357.75773)
					(end 137.597388 -357.37673)
				)
			)
		)
	)
	(zone
		(layers "F.Cu" "B.Cu" "In1.Cu" "In2.Cu" "In3.Cu" "In4.Cu" "In5.Cu" "In6.Cu"
			"In7.Cu" "In8.Cu" "In9.Cu" "In10.Cu" "In11.Cu" "In12.Cu" "In13.Cu" "In14.Cu"
			"In15.Cu" "In16.Cu"
		)
		(hatch none 0.5)
		(connect_pads
			(clearance 0)
		)
		(min_thickness 0.25)
		(keepout
			(tracks not_allowed)
			(vias allowed)
			(pads allowed)
			(copperpour not_allowed)
			(footprints allowed)
		)
		(placement
			(enabled no)
			(sheetname "")
		)
		(fill
			(thermal_gap 0.5)
			(thermal_bridge_width 0.5)
			(island_removal_mode 0)
		)
		(polygon
			(pts
				(arc
					(start 381.680974 -400.92884)
					(mid 381.695853 -400.892919)
					(end 381.731774 -400.87804)
				)
				(arc
					(start 382.448054 -400.87804)
					(mid 382.483975 -400.892919)
					(end 382.498854 -400.92884)
				)
				(arc
					(start 382.498854 -403.351492)
					(mid 382.483975 -403.387413)
					(end 382.448054 -403.402292)
				)
				(arc
					(start 381.731774 -403.402292)
					(mid 381.695853 -403.387413)
					(end 381.680974 -403.351492)
				)
			)
		)
	)
	(zone
		(layers "F.Cu" "B.Cu" "In1.Cu" "In2.Cu" "In3.Cu" "In4.Cu" "In5.Cu" "In6.Cu"
			"In7.Cu" "In8.Cu" "In9.Cu" "In10.Cu" "In11.Cu" "In12.Cu" "In13.Cu" "In14.Cu"
			"In15.Cu" "In16.Cu"
		)
		(hatch none 0.5)
		(connect_pads
			(clearance 0)
		)
		(min_thickness 0.25)
		(keepout
			(tracks not_allowed)
			(vias allowed)
			(pads allowed)
			(copperpour not_allowed)
			(footprints allowed)
		)
		(placement
			(enabled no)
			(sheetname "")
		)
		(fill
			(thermal_gap 0.5)
			(thermal_bridge_width 0.5)
			(island_removal_mode 0)
		)
		(polygon
			(pts
				(arc
					(start 291.481002 -377.728734)
					(mid 291.495881 -377.692813)
					(end 291.531802 -377.677934)
				)
				(arc
					(start 292.248082 -377.677934)
					(mid 292.284003 -377.692813)
					(end 292.298882 -377.728734)
				)
				(arc
					(start 292.298882 -380.151386)
					(mid 292.284003 -380.187307)
					(end 292.248082 -380.202186)
				)
				(arc
					(start 291.531802 -380.202186)
					(mid 291.495881 -380.187307)
					(end 291.481002 -380.151386)
				)
			)
		)
	)
	(zone
		(layers "F.Cu" "B.Cu" "In1.Cu" "In2.Cu" "In3.Cu" "In4.Cu" "In5.Cu" "In6.Cu"
			"In7.Cu" "In8.Cu" "In9.Cu" "In10.Cu" "In11.Cu" "In12.Cu" "In13.Cu" "In14.Cu"
			"In15.Cu" "In16.Cu"
		)
		(hatch none 0.5)
		(connect_pads
			(clearance 0)
		)
		(min_thickness 0.25)
		(keepout
			(tracks not_allowed)
			(vias allowed)
			(pads allowed)
			(copperpour not_allowed)
			(footprints allowed)
		)
		(placement
			(enabled no)
			(sheetname "")
		)
		(fill
			(thermal_gap 0.5)
			(thermal_bridge_width 0.5)
			(island_removal_mode 0)
		)
		(polygon
			(pts
				(arc
					(start 71.501 -395.92885)
					(mid 71.515879 -395.892929)
					(end 71.5518 -395.87805)
				)
				(arc
					(start 72.26808 -395.87805)
					(mid 72.304001 -395.892929)
					(end 72.31888 -395.92885)
				)
				(arc
					(start 72.31888 -398.351502)
					(mid 72.304001 -398.387423)
					(end 72.26808 -398.402302)
				)
				(arc
					(start 71.5518 -398.402302)
					(mid 71.515879 -398.387423)
					(end 71.501 -398.351502)
				)
			)
		)
	)
	(zone
		(layers "F.Cu" "B.Cu" "In1.Cu" "In2.Cu" "In3.Cu" "In4.Cu" "In5.Cu" "In6.Cu"
			"In7.Cu" "In8.Cu" "In9.Cu" "In10.Cu" "In11.Cu" "In12.Cu" "In13.Cu" "In14.Cu"
			"In15.Cu" "In16.Cu"
		)
		(hatch none 0.5)
		(connect_pads
			(clearance 0)
		)
		(min_thickness 0.25)
		(keepout
			(tracks not_allowed)
			(vias allowed)
			(pads allowed)
			(copperpour not_allowed)
			(footprints allowed)
		)
		(placement
			(enabled no)
			(sheetname "")
		)
		(fill
			(thermal_gap 0.5)
			(thermal_bridge_width 0.5)
			(island_removal_mode 0)
		)
		(polygon
			(pts
				(arc
					(start 239.470438 -84.305902)
					(mid 239.013238 -83.848702)
					(end 238.556038 -84.305902)
				)
				(arc
					(start 238.556038 -85.169502)
					(mid 239.013238 -85.626702)
					(end 239.470438 -85.169502)
				)
			)
		)
	)
	(zone
		(layers "F.Cu" "B.Cu" "In1.Cu" "In2.Cu" "In3.Cu" "In4.Cu" "In5.Cu" "In6.Cu"
			"In7.Cu" "In8.Cu" "In9.Cu" "In10.Cu" "In11.Cu" "In12.Cu" "In13.Cu" "In14.Cu"
			"In15.Cu" "In16.Cu"
		)
		(hatch none 0.5)
		(connect_pads
			(clearance 0)
		)
		(min_thickness 0.25)
		(keepout
			(tracks not_allowed)
			(vias allowed)
			(pads allowed)
			(copperpour not_allowed)
			(footprints allowed)
		)
		(placement
			(enabled no)
			(sheetname "")
		)
		(fill
			(thermal_gap 0.5)
			(thermal_bridge_width 0.5)
			(island_removal_mode 0)
		)
		(polygon
			(pts
				(arc
					(start 80.026002 -351.230438)
					(mid 79.645002 -351.611438)
					(end 80.026002 -351.992438)
				)
				(arc
					(start 80.889602 -351.992438)
					(mid 81.270602 -351.611438)
					(end 80.889602 -351.230438)
				)
			)
		)
	)
	(zone
		(layers "F.Cu" "B.Cu" "In1.Cu" "In2.Cu" "In3.Cu" "In4.Cu" "In5.Cu" "In6.Cu"
			"In7.Cu" "In8.Cu" "In9.Cu" "In10.Cu" "In11.Cu" "In12.Cu" "In13.Cu" "In14.Cu"
			"In15.Cu" "In16.Cu"
		)
		(hatch none 0.5)
		(connect_pads
			(clearance 0)
		)
		(min_thickness 0.25)
		(keepout
			(tracks not_allowed)
			(vias allowed)
			(pads allowed)
			(copperpour not_allowed)
			(footprints allowed)
		)
		(placement
			(enabled no)
			(sheetname "")
		)
		(fill
			(thermal_gap 0.5)
			(thermal_bridge_width 0.5)
			(island_removal_mode 0)
		)
		(polygon
			(pts
				(arc
					(start 84.700872 -381.628904)
					(mid 84.715751 -381.592983)
					(end 84.751672 -381.578104)
				)
				(arc
					(start 85.467952 -381.578104)
					(mid 85.503873 -381.592983)
					(end 85.518752 -381.628904)
				)
				(arc
					(start 85.518752 -384.051556)
					(mid 85.503873 -384.087477)
					(end 85.467952 -384.102356)
				)
				(arc
					(start 84.751672 -384.102356)
					(mid 84.715751 -384.087477)
					(end 84.700872 -384.051556)
				)
			)
		)
	)
	(zone
		(layers "F.Cu" "B.Cu" "In1.Cu" "In2.Cu" "In3.Cu" "In4.Cu" "In5.Cu" "In6.Cu"
			"In7.Cu" "In8.Cu" "In9.Cu" "In10.Cu" "In11.Cu" "In12.Cu" "In13.Cu" "In14.Cu"
			"In15.Cu" "In16.Cu"
		)
		(hatch none 0.5)
		(connect_pads
			(clearance 0)
		)
		(min_thickness 0.25)
		(keepout
			(tracks not_allowed)
			(vias allowed)
			(pads allowed)
			(copperpour not_allowed)
			(footprints allowed)
		)
		(placement
			(enabled no)
			(sheetname "")
		)
		(fill
			(thermal_gap 0.5)
			(thermal_bridge_width 0.5)
			(island_removal_mode 0)
		)
		(polygon
			(pts
				(arc
					(start 86.90102 -404.828756)
					(mid 86.915899 -404.792835)
					(end 86.95182 -404.777956)
				)
				(arc
					(start 87.6681 -404.777956)
					(mid 87.704021 -404.792835)
					(end 87.7189 -404.828756)
				)
				(arc
					(start 87.7189 -407.251408)
					(mid 87.704021 -407.287329)
					(end 87.6681 -407.302208)
				)
				(arc
					(start 86.95182 -407.302208)
					(mid 86.915899 -407.287329)
					(end 86.90102 -407.251408)
				)
			)
		)
	)
	(zone
		(layers "F.Cu" "B.Cu" "In1.Cu" "In2.Cu" "In3.Cu" "In4.Cu" "In5.Cu" "In6.Cu"
			"In7.Cu" "In8.Cu" "In9.Cu" "In10.Cu" "In11.Cu" "In12.Cu" "In13.Cu" "In14.Cu"
			"In15.Cu" "In16.Cu"
		)
		(hatch none 0.5)
		(connect_pads
			(clearance 0)
		)
		(min_thickness 0.25)
		(keepout
			(tracks not_allowed)
			(vias allowed)
			(pads allowed)
			(copperpour not_allowed)
			(footprints allowed)
		)
		(placement
			(enabled no)
			(sheetname "")
		)
		(fill
			(thermal_gap 0.5)
			(thermal_bridge_width 0.5)
			(island_removal_mode 0)
		)
		(polygon
			(pts
				(arc
					(start 418.621972 -342.058498)
					(mid 418.240972 -342.439498)
					(end 418.621972 -342.820498)
				)
				(arc
					(start 419.485572 -342.820498)
					(mid 419.866572 -342.439498)
					(end 419.485572 -342.058498)
				)
			)
		)
	)
	(zone
		(layers "F.Cu" "B.Cu" "In1.Cu" "In2.Cu" "In3.Cu" "In4.Cu" "In5.Cu" "In6.Cu"
			"In7.Cu" "In8.Cu" "In9.Cu" "In10.Cu" "In11.Cu" "In12.Cu" "In13.Cu" "In14.Cu"
			"In15.Cu" "In16.Cu"
		)
		(hatch none 0.5)
		(connect_pads
			(clearance 0)
		)
		(min_thickness 0.25)
		(keepout
			(tracks not_allowed)
			(vias allowed)
			(pads allowed)
			(copperpour not_allowed)
			(footprints allowed)
		)
		(placement
			(enabled no)
			(sheetname "")
		)
		(fill
			(thermal_gap 0.5)
			(thermal_bridge_width 0.5)
			(island_removal_mode 0)
		)
		(polygon
			(pts
				(arc
					(start 163.90112 -381.628904)
					(mid 163.915999 -381.592983)
					(end 163.95192 -381.578104)
				)
				(arc
					(start 164.6682 -381.578104)
					(mid 164.704121 -381.592983)
					(end 164.719 -381.628904)
				)
				(arc
					(start 164.719 -384.051556)
					(mid 164.704121 -384.087477)
					(end 164.6682 -384.102356)
				)
				(arc
					(start 163.95192 -384.102356)
					(mid 163.915999 -384.087477)
					(end 163.90112 -384.051556)
				)
			)
		)
	)
	(zone
		(layers "F.Cu" "B.Cu" "In1.Cu" "In2.Cu" "In3.Cu" "In4.Cu" "In5.Cu" "In6.Cu"
			"In7.Cu" "In8.Cu" "In9.Cu" "In10.Cu" "In11.Cu" "In12.Cu" "In13.Cu" "In14.Cu"
			"In15.Cu" "In16.Cu"
		)
		(hatch none 0.5)
		(connect_pads
			(clearance 0)
		)
		(min_thickness 0.25)
		(keepout
			(tracks not_allowed)
			(vias allowed)
			(pads allowed)
			(copperpour not_allowed)
			(footprints allowed)
		)
		(placement
			(enabled no)
			(sheetname "")
		)
		(fill
			(thermal_gap 0.5)
			(thermal_bridge_width 0.5)
			(island_removal_mode 0)
		)
		(polygon
			(pts
				(arc
					(start 430.080928 -400.92884)
					(mid 430.095807 -400.892919)
					(end 430.131728 -400.87804)
				)
				(arc
					(start 430.848008 -400.87804)
					(mid 430.883929 -400.892919)
					(end 430.898808 -400.92884)
				)
				(arc
					(start 430.898808 -403.351492)
					(mid 430.883929 -403.387413)
					(end 430.848008 -403.402292)
				)
				(arc
					(start 430.131728 -403.402292)
					(mid 430.095807 -403.387413)
					(end 430.080928 -403.351492)
				)
			)
		)
	)
	(zone
		(layers "F.Cu" "B.Cu" "In1.Cu" "In2.Cu" "In3.Cu" "In4.Cu" "In5.Cu" "In6.Cu"
			"In7.Cu" "In8.Cu" "In9.Cu" "In10.Cu" "In11.Cu" "In12.Cu" "In13.Cu" "In14.Cu"
			"In15.Cu" "In16.Cu"
		)
		(hatch none 0.5)
		(connect_pads
			(clearance 0)
		)
		(min_thickness 0.25)
		(keepout
			(tracks not_allowed)
			(vias allowed)
			(pads allowed)
			(copperpour not_allowed)
			(footprints allowed)
		)
		(placement
			(enabled no)
			(sheetname "")
		)
		(fill
			(thermal_gap 0.5)
			(thermal_bridge_width 0.5)
			(island_removal_mode 0)
		)
		(polygon
			(pts
				(arc
					(start 386.73278 -351.230438)
					(mid 386.35178 -351.611438)
					(end 386.73278 -351.992438)
				)
				(arc
					(start 387.59638 -351.992438)
					(mid 387.97738 -351.611438)
					(end 387.59638 -351.230438)
				)
			)
		)
	)
	(zone
		(layers "F.Cu" "B.Cu" "In1.Cu" "In2.Cu" "In3.Cu" "In4.Cu" "In5.Cu" "In6.Cu"
			"In7.Cu" "In8.Cu" "In9.Cu" "In10.Cu" "In11.Cu" "In12.Cu" "In13.Cu" "In14.Cu"
			"In15.Cu" "In16.Cu"
		)
		(hatch none 0.5)
		(connect_pads
			(clearance 0)
		)
		(min_thickness 0.25)
		(keepout
			(tracks not_allowed)
			(vias allowed)
			(pads allowed)
			(copperpour not_allowed)
			(footprints allowed)
		)
		(placement
			(enabled no)
			(sheetname "")
		)
		(fill
			(thermal_gap 0.5)
			(thermal_bridge_width 0.5)
			(island_removal_mode 0)
		)
		(polygon
			(pts
				(arc
					(start 73.700894 -374.928638)
					(mid 73.715773 -374.892717)
					(end 73.751694 -374.877838)
				)
				(arc
					(start 74.467974 -374.877838)
					(mid 74.503895 -374.892717)
					(end 74.518774 -374.928638)
				)
				(arc
					(start 74.518774 -377.35129)
					(mid 74.503895 -377.387211)
					(end 74.467974 -377.40209)
				)
				(arc
					(start 73.751694 -377.40209)
					(mid 73.715773 -377.387211)
					(end 73.700894 -377.35129)
				)
			)
		)
	)
	(zone
		(layers "F.Cu" "B.Cu" "In1.Cu" "In2.Cu" "In3.Cu" "In4.Cu" "In5.Cu" "In6.Cu"
			"In7.Cu" "In8.Cu" "In9.Cu" "In10.Cu" "In11.Cu" "In12.Cu" "In13.Cu" "In14.Cu"
			"In15.Cu" "In16.Cu"
		)
		(hatch none 0.5)
		(connect_pads
			(clearance 0)
		)
		(min_thickness 0.25)
		(keepout
			(tracks not_allowed)
			(vias allowed)
			(pads allowed)
			(copperpour not_allowed)
			(footprints allowed)
		)
		(placement
			(enabled no)
			(sheetname "")
		)
		(fill
			(thermal_gap 0.5)
			(thermal_bridge_width 0.5)
			(island_removal_mode 0)
		)
		(polygon
			(pts
				(arc
					(start 381.680974 -408.728672)
					(mid 381.695853 -408.692751)
					(end 381.731774 -408.677872)
				)
				(arc
					(start 382.448054 -408.677872)
					(mid 382.483975 -408.692751)
					(end 382.498854 -408.728672)
				)
				(arc
					(start 382.498854 -411.151324)
					(mid 382.483975 -411.187245)
					(end 382.448054 -411.202124)
				)
				(arc
					(start 381.731774 -411.202124)
					(mid 381.695853 -411.187245)
					(end 381.680974 -411.151324)
				)
			)
		)
	)
	(zone
		(layers "F.Cu" "B.Cu" "In1.Cu" "In2.Cu" "In3.Cu" "In4.Cu" "In5.Cu" "In6.Cu"
			"In7.Cu" "In8.Cu" "In9.Cu" "In10.Cu" "In11.Cu" "In12.Cu" "In13.Cu" "In14.Cu"
			"In15.Cu" "In16.Cu"
		)
		(hatch none 0.5)
		(connect_pads
			(clearance 0)
		)
		(min_thickness 0.25)
		(keepout
			(tracks not_allowed)
			(vias allowed)
			(pads allowed)
			(copperpour not_allowed)
			(footprints allowed)
		)
		(placement
			(enabled no)
			(sheetname "")
		)
		(fill
			(thermal_gap 0.5)
			(thermal_bridge_width 0.5)
			(island_removal_mode 0)
		)
		(polygon
			(pts
				(arc
					(start 414.90011 -130.777234)
					(mid 415.35731 -131.234434)
					(end 415.81451 -130.777234)
				)
				(arc
					(start 415.81451 -129.913634)
					(mid 415.35731 -129.456434)
					(end 414.90011 -129.913634)
				)
			)
		)
	)
	(zone
		(layers "F.Cu" "B.Cu" "In1.Cu" "In2.Cu" "In3.Cu" "In4.Cu" "In5.Cu" "In6.Cu"
			"In7.Cu" "In8.Cu" "In9.Cu" "In10.Cu" "In11.Cu" "In12.Cu" "In13.Cu" "In14.Cu"
			"In15.Cu" "In16.Cu"
		)
		(hatch none 0.5)
		(connect_pads
			(clearance 0)
		)
		(min_thickness 0.25)
		(keepout
			(tracks not_allowed)
			(vias allowed)
			(pads allowed)
			(copperpour not_allowed)
			(footprints allowed)
		)
		(placement
			(enabled no)
			(sheetname "")
		)
		(fill
			(thermal_gap 0.5)
			(thermal_bridge_width 0.5)
			(island_removal_mode 0)
		)
		(polygon
			(pts
				(arc
					(start 171.512992 -342.058498)
					(mid 171.131992 -342.439498)
					(end 171.512992 -342.820498)
				)
				(arc
					(start 172.376592 -342.820498)
					(mid 172.757592 -342.439498)
					(end 172.376592 -342.058498)
				)
			)
		)
	)
	(zone
		(layers "F.Cu" "B.Cu" "In1.Cu" "In2.Cu" "In3.Cu" "In4.Cu" "In5.Cu" "In6.Cu"
			"In7.Cu" "In8.Cu" "In9.Cu" "In10.Cu" "In11.Cu" "In12.Cu" "In13.Cu" "In14.Cu"
			"In15.Cu" "In16.Cu"
		)
		(hatch none 0.5)
		(connect_pads
			(clearance 0)
		)
		(min_thickness 0.25)
		(keepout
			(tracks not_allowed)
			(vias allowed)
			(pads allowed)
			(copperpour not_allowed)
			(footprints allowed)
		)
		(placement
			(enabled no)
			(sheetname "")
		)
		(fill
			(thermal_gap 0.5)
			(thermal_bridge_width 0.5)
			(island_removal_mode 0)
		)
		(polygon
			(pts
				(arc
					(start 170.501056 -378.828554)
					(mid 170.515935 -378.792633)
					(end 170.551856 -378.777754)
				)
				(arc
					(start 171.268136 -378.777754)
					(mid 171.304057 -378.792633)
					(end 171.318936 -378.828554)
				)
				(arc
					(start 171.318936 -381.251206)
					(mid 171.304057 -381.287127)
					(end 171.268136 -381.302006)
				)
				(arc
					(start 170.551856 -381.302006)
					(mid 170.515935 -381.287127)
					(end 170.501056 -381.251206)
				)
			)
		)
	)
	(zone
		(layers "F.Cu" "B.Cu" "In1.Cu" "In2.Cu" "In3.Cu" "In4.Cu" "In5.Cu" "In6.Cu"
			"In7.Cu" "In8.Cu" "In9.Cu" "In10.Cu" "In11.Cu" "In12.Cu" "In13.Cu" "In14.Cu"
			"In15.Cu" "In16.Cu"
		)
		(hatch none 0.5)
		(connect_pads
			(clearance 0)
		)
		(min_thickness 0.25)
		(keepout
			(tracks not_allowed)
			(vias allowed)
			(pads allowed)
			(copperpour not_allowed)
			(footprints allowed)
		)
		(placement
			(enabled no)
			(sheetname "")
		)
		(fill
			(thermal_gap 0.5)
			(thermal_bridge_width 0.5)
			(island_removal_mode 0)
		)
		(polygon
			(pts
				(arc
					(start 269.51051 -110.977934)
					(mid 269.96771 -111.435134)
					(end 270.42491 -110.977934)
				)
				(arc
					(start 270.42491 -110.114334)
					(mid 269.96771 -109.657134)
					(end 269.51051 -110.114334)
				)
			)
		)
	)
	(zone
		(layers "F.Cu" "B.Cu" "In1.Cu" "In2.Cu" "In3.Cu" "In4.Cu" "In5.Cu" "In6.Cu"
			"In7.Cu" "In8.Cu" "In9.Cu" "In10.Cu" "In11.Cu" "In12.Cu" "In13.Cu" "In14.Cu"
			"In15.Cu" "In16.Cu"
		)
		(hatch none 0.5)
		(connect_pads
			(clearance 0)
		)
		(min_thickness 0.25)
		(keepout
			(tracks not_allowed)
			(vias allowed)
			(pads allowed)
			(copperpour not_allowed)
			(footprints allowed)
		)
		(placement
			(enabled no)
			(sheetname "")
		)
		(fill
			(thermal_gap 0.5)
			(thermal_bridge_width 0.5)
			(island_removal_mode 0)
		)
		(polygon
			(pts
				(arc
					(start 105.607358 -76.87818)
					(mid 105.150158 -77.33538)
					(end 105.607358 -77.79258)
				)
				(arc
					(start 106.470958 -77.79258)
					(mid 106.928158 -77.33538)
					(end 106.470958 -76.87818)
				)
			)
		)
	)
	(zone
		(layers "F.Cu" "B.Cu" "In1.Cu" "In2.Cu" "In3.Cu" "In4.Cu" "In5.Cu" "In6.Cu"
			"In7.Cu" "In8.Cu" "In9.Cu" "In10.Cu" "In11.Cu" "In12.Cu" "In13.Cu" "In14.Cu"
			"In15.Cu" "In16.Cu"
		)
		(hatch none 0.5)
		(connect_pads
			(clearance 0)
		)
		(min_thickness 0.25)
		(keepout
			(tracks not_allowed)
			(vias allowed)
			(pads allowed)
			(copperpour not_allowed)
			(footprints allowed)
		)
		(placement
			(enabled no)
			(sheetname "")
		)
		(fill
			(thermal_gap 0.5)
			(thermal_bridge_width 0.5)
			(island_removal_mode 0)
		)
		(polygon
			(pts
				(arc
					(start 42.901108 -408.728672)
					(mid 42.915987 -408.692751)
					(end 42.951908 -408.677872)
				)
				(arc
					(start 43.668188 -408.677872)
					(mid 43.704109 -408.692751)
					(end 43.718988 -408.728672)
				)
				(arc
					(start 43.718988 -411.151324)
					(mid 43.704109 -411.187245)
					(end 43.668188 -411.202124)
				)
				(arc
					(start 42.951908 -411.202124)
					(mid 42.915987 -411.187245)
					(end 42.901108 -411.151324)
				)
			)
		)
	)
	(zone
		(layers "F.Cu" "B.Cu" "In1.Cu" "In2.Cu" "In3.Cu" "In4.Cu" "In5.Cu" "In6.Cu"
			"In7.Cu" "In8.Cu" "In9.Cu" "In10.Cu" "In11.Cu" "In12.Cu" "In13.Cu" "In14.Cu"
			"In15.Cu" "In16.Cu"
		)
		(hatch none 0.5)
		(connect_pads
			(clearance 0)
		)
		(min_thickness 0.25)
		(keepout
			(tracks not_allowed)
			(vias allowed)
			(pads allowed)
			(copperpour not_allowed)
			(footprints allowed)
		)
		(placement
			(enabled no)
			(sheetname "")
		)
		(fill
			(thermal_gap 0.5)
			(thermal_bridge_width 0.5)
			(island_removal_mode 0)
		)
		(polygon
			(pts
				(arc
					(start 47.313088 -348.20479)
					(mid 46.932088 -348.58579)
					(end 47.313088 -348.96679)
				)
				(arc
					(start 48.176688 -348.96679)
					(mid 48.557688 -348.58579)
					(end 48.176688 -348.20479)
				)
			)
		)
	)
	(zone
		(layers "F.Cu" "B.Cu" "In1.Cu" "In2.Cu" "In3.Cu" "In4.Cu" "In5.Cu" "In6.Cu"
			"In7.Cu" "In8.Cu" "In9.Cu" "In10.Cu" "In11.Cu" "In12.Cu" "In13.Cu" "In14.Cu"
			"In15.Cu" "In16.Cu"
		)
		(hatch none 0.5)
		(connect_pads
			(clearance 0)
		)
		(min_thickness 0.25)
		(keepout
			(tracks not_allowed)
			(vias allowed)
			(pads allowed)
			(copperpour not_allowed)
			(footprints allowed)
		)
		(placement
			(enabled no)
			(sheetname "")
		)
		(fill
			(thermal_gap 0.5)
			(thermal_bridge_width 0.5)
			(island_removal_mode 0)
		)
		(polygon
			(pts
				(arc
					(start 432.01717 -136.17575)
					(mid 432.47437 -136.63295)
					(end 432.93157 -136.17575)
				)
				(arc
					(start 432.93157 -135.31215)
					(mid 432.47437 -134.85495)
					(end 432.01717 -135.31215)
				)
			)
		)
	)
	(zone
		(layers "F.Cu" "B.Cu" "In1.Cu" "In2.Cu" "In3.Cu" "In4.Cu" "In5.Cu" "In6.Cu"
			"In7.Cu" "In8.Cu" "In9.Cu" "In10.Cu" "In11.Cu" "In12.Cu" "In13.Cu" "In14.Cu"
			"In15.Cu" "In16.Cu"
		)
		(hatch none 0.5)
		(connect_pads
			(clearance 0)
		)
		(min_thickness 0.25)
		(keepout
			(tracks not_allowed)
			(vias allowed)
			(pads allowed)
			(copperpour not_allowed)
			(footprints allowed)
		)
		(placement
			(enabled no)
			(sheetname "")
		)
		(fill
			(thermal_gap 0.5)
			(thermal_bridge_width 0.5)
			(island_removal_mode 0)
		)
		(polygon
			(pts
				(arc
					(start 119.901208 -373.828818)
					(mid 119.916087 -373.792897)
					(end 119.952008 -373.778018)
				)
				(arc
					(start 120.668288 -373.778018)
					(mid 120.704209 -373.792897)
					(end 120.719088 -373.828818)
				)
				(arc
					(start 120.719088 -376.25147)
					(mid 120.704209 -376.287391)
					(end 120.668288 -376.30227)
				)
				(arc
					(start 119.952008 -376.30227)
					(mid 119.916087 -376.287391)
					(end 119.901208 -376.25147)
				)
			)
		)
	)
	(zone
		(layers "F.Cu" "B.Cu" "In1.Cu" "In2.Cu" "In3.Cu" "In4.Cu" "In5.Cu" "In6.Cu"
			"In7.Cu" "In8.Cu" "In9.Cu" "In10.Cu" "In11.Cu" "In12.Cu" "In13.Cu" "In14.Cu"
			"In15.Cu" "In16.Cu"
		)
		(hatch none 0.5)
		(connect_pads
			(clearance 0)
		)
		(min_thickness 0.25)
		(keepout
			(tracks not_allowed)
			(vias allowed)
			(pads allowed)
			(copperpour not_allowed)
			(footprints allowed)
		)
		(placement
			(enabled no)
			(sheetname "")
		)
		(fill
			(thermal_gap 0.5)
			(thermal_bridge_width 0.5)
			(island_removal_mode 0)
		)
		(polygon
			(pts
				(arc
					(start 386.081016 -374.928638)
					(mid 386.095895 -374.892717)
					(end 386.131816 -374.877838)
				)
				(arc
					(start 386.848096 -374.877838)
					(mid 386.884017 -374.892717)
					(end 386.898896 -374.928638)
				)
				(arc
					(start 386.898896 -377.35129)
					(mid 386.884017 -377.387211)
					(end 386.848096 -377.40209)
				)
				(arc
					(start 386.131816 -377.40209)
					(mid 386.095895 -377.387211)
					(end 386.081016 -377.35129)
				)
			)
		)
	)
	(zone
		(layers "F.Cu" "B.Cu" "In1.Cu" "In2.Cu" "In3.Cu" "In4.Cu" "In5.Cu" "In6.Cu"
			"In7.Cu" "In8.Cu" "In9.Cu" "In10.Cu" "In11.Cu" "In12.Cu" "In13.Cu" "In14.Cu"
			"In15.Cu" "In16.Cu"
		)
		(hatch none 0.5)
		(connect_pads
			(clearance 0)
		)
		(min_thickness 0.25)
		(keepout
			(tracks not_allowed)
			(vias allowed)
			(pads allowed)
			(copperpour not_allowed)
			(footprints allowed)
		)
		(placement
			(enabled no)
			(sheetname "")
		)
		(fill
			(thermal_gap 0.5)
			(thermal_bridge_width 0.5)
			(island_removal_mode 0)
		)
		(polygon
			(pts
				(arc
					(start 397.70939 -95.214948)
					(mid 395.57579 -95.214948)
					(end 397.70939 -95.214948)
				)
			)
		)
	)
	(zone
		(layers "F.Cu" "B.Cu" "In1.Cu" "In2.Cu" "In3.Cu" "In4.Cu" "In5.Cu" "In6.Cu"
			"In7.Cu" "In8.Cu" "In9.Cu" "In10.Cu" "In11.Cu" "In12.Cu" "In13.Cu" "In14.Cu"
			"In15.Cu" "In16.Cu"
		)
		(hatch none 0.5)
		(connect_pads
			(clearance 0)
		)
		(min_thickness 0.25)
		(keepout
			(tracks not_allowed)
			(vias allowed)
			(pads allowed)
			(copperpour not_allowed)
			(footprints allowed)
		)
		(placement
			(enabled no)
			(sheetname "")
		)
		(fill
			(thermal_gap 0.5)
			(thermal_bridge_width 0.5)
			(island_removal_mode 0)
		)
		(polygon
			(pts
				(arc
					(start 193.275712 -348.20479)
					(mid 192.894712 -348.58579)
					(end 193.275712 -348.96679)
				)
				(arc
					(start 194.139312 -348.96679)
					(mid 194.520312 -348.58579)
					(end 194.139312 -348.20479)
				)
			)
		)
	)
	(zone
		(layers "F.Cu" "B.Cu" "In1.Cu" "In2.Cu" "In3.Cu" "In4.Cu" "In5.Cu" "In6.Cu"
			"In7.Cu" "In8.Cu" "In9.Cu" "In10.Cu" "In11.Cu" "In12.Cu" "In13.Cu" "In14.Cu"
			"In15.Cu" "In16.Cu"
		)
		(hatch none 0.5)
		(connect_pads
			(clearance 0)
		)
		(min_thickness 0.25)
		(keepout
			(tracks not_allowed)
			(vias allowed)
			(pads allowed)
			(copperpour not_allowed)
			(footprints allowed)
		)
		(placement
			(enabled no)
			(sheetname "")
		)
		(fill
			(thermal_gap 0.5)
			(thermal_bridge_width 0.5)
			(island_removal_mode 0)
		)
		(polygon
			(pts
				(arc
					(start 61.372242 -351.230438)
					(mid 60.991242 -351.611438)
					(end 61.372242 -351.992438)
				)
				(arc
					(start 62.235842 -351.992438)
					(mid 62.616842 -351.611438)
					(end 62.235842 -351.230438)
				)
			)
		)
	)
	(zone
		(layers "F.Cu" "B.Cu" "In1.Cu" "In2.Cu" "In3.Cu" "In4.Cu" "In5.Cu" "In6.Cu"
			"In7.Cu" "In8.Cu" "In9.Cu" "In10.Cu" "In11.Cu" "In12.Cu" "In13.Cu" "In14.Cu"
			"In15.Cu" "In16.Cu"
		)
		(hatch none 0.5)
		(connect_pads
			(clearance 0)
		)
		(min_thickness 0.25)
		(keepout
			(tracks not_allowed)
			(vias allowed)
			(pads allowed)
			(copperpour not_allowed)
			(footprints allowed)
		)
		(placement
			(enabled no)
			(sheetname "")
		)
		(fill
			(thermal_gap 0.5)
			(thermal_bridge_width 0.5)
			(island_removal_mode 0)
		)
		(polygon
			(pts
				(arc
					(start 64.74587 -148.887434)
					(mid 65.20307 -149.344634)
					(end 65.66027 -148.887434)
				)
				(arc
					(start 65.66027 -148.023834)
					(mid 65.20307 -147.566634)
					(end 64.74587 -148.023834)
				)
			)
		)
	)
	(zone
		(layers "F.Cu" "B.Cu" "In1.Cu" "In2.Cu" "In3.Cu" "In4.Cu" "In5.Cu" "In6.Cu"
			"In7.Cu" "In8.Cu" "In9.Cu" "In10.Cu" "In11.Cu" "In12.Cu" "In13.Cu" "In14.Cu"
			"In15.Cu" "In16.Cu"
		)
		(hatch none 0.5)
		(connect_pads
			(clearance 0)
		)
		(min_thickness 0.25)
		(keepout
			(tracks not_allowed)
			(vias allowed)
			(pads allowed)
			(copperpour not_allowed)
			(footprints allowed)
		)
		(placement
			(enabled no)
			(sheetname "")
		)
		(fill
			(thermal_gap 0.5)
			(thermal_bridge_width 0.5)
			(island_removal_mode 0)
		)
		(polygon
			(pts
				(arc
					(start 324.938644 -342.058498)
					(mid 324.557644 -342.439498)
					(end 324.938644 -342.820498)
				)
				(arc
					(start 325.802244 -342.820498)
					(mid 326.183244 -342.439498)
					(end 325.802244 -342.058498)
				)
			)
		)
	)
	(zone
		(layers "F.Cu" "B.Cu" "In1.Cu" "In2.Cu" "In3.Cu" "In4.Cu" "In5.Cu" "In6.Cu"
			"In7.Cu" "In8.Cu" "In9.Cu" "In10.Cu" "In11.Cu" "In12.Cu" "In13.Cu" "In14.Cu"
			"In15.Cu" "In16.Cu"
		)
		(hatch none 0.5)
		(connect_pads
			(clearance 0)
		)
		(min_thickness 0.25)
		(keepout
			(tracks not_allowed)
			(vias allowed)
			(pads allowed)
			(copperpour not_allowed)
			(footprints allowed)
		)
		(placement
			(enabled no)
			(sheetname "")
		)
		(fill
			(thermal_gap 0.5)
			(thermal_bridge_width 0.5)
			(island_removal_mode 0)
		)
		(polygon
			(pts
				(arc
					(start 277.223982 -357.37673)
					(mid 276.842982 -357.75773)
					(end 277.223982 -358.13873)
				)
				(arc
					(start 278.087582 -358.13873)
					(mid 278.468582 -357.75773)
					(end 278.087582 -357.37673)
				)
			)
		)
	)
	(zone
		(layers "F.Cu" "B.Cu" "In1.Cu" "In2.Cu" "In3.Cu" "In4.Cu" "In5.Cu" "In6.Cu"
			"In7.Cu" "In8.Cu" "In9.Cu" "In10.Cu" "In11.Cu" "In12.Cu" "In13.Cu" "In14.Cu"
			"In15.Cu" "In16.Cu"
		)
		(hatch none 0.5)
		(connect_pads
			(clearance 0)
		)
		(min_thickness 0.25)
		(keepout
			(tracks not_allowed)
			(vias allowed)
			(pads allowed)
			(copperpour not_allowed)
			(footprints allowed)
		)
		(placement
			(enabled no)
			(sheetname "")
		)
		(fill
			(thermal_gap 0.5)
			(thermal_bridge_width 0.5)
			(island_removal_mode 0)
		)
		(polygon
			(pts
				(arc
					(start 298.800012 -123.16714)
					(mid 299.257212 -123.62434)
					(end 299.714412 -123.16714)
				)
				(arc
					(start 299.714412 -122.30354)
					(mid 299.257212 -121.84634)
					(end 298.800012 -122.30354)
				)
			)
		)
	)
	(zone
		(layers "F.Cu" "B.Cu" "In1.Cu" "In2.Cu" "In3.Cu" "In4.Cu" "In5.Cu" "In6.Cu"
			"In7.Cu" "In8.Cu" "In9.Cu" "In10.Cu" "In11.Cu" "In12.Cu" "In13.Cu" "In14.Cu"
			"In15.Cu" "In16.Cu"
		)
		(hatch none 0.5)
		(connect_pads
			(clearance 0)
		)
		(min_thickness 0.25)
		(keepout
			(tracks not_allowed)
			(vias allowed)
			(pads allowed)
			(copperpour not_allowed)
			(footprints allowed)
		)
		(placement
			(enabled no)
			(sheetname "")
		)
		(fill
			(thermal_gap 0.5)
			(thermal_bridge_width 0.5)
			(island_removal_mode 0)
		)
		(polygon
			(pts
				(arc
					(start 174.901098 -378.828554)
					(mid 174.915977 -378.792633)
					(end 174.951898 -378.777754)
				)
				(arc
					(start 175.668178 -378.777754)
					(mid 175.704099 -378.792633)
					(end 175.718978 -378.828554)
				)
				(arc
					(start 175.718978 -381.251206)
					(mid 175.704099 -381.287127)
					(end 175.668178 -381.302006)
				)
				(arc
					(start 174.951898 -381.302006)
					(mid 174.915977 -381.287127)
					(end 174.901098 -381.251206)
				)
			)
		)
	)
	(zone
		(layers "F.Cu" "B.Cu" "In1.Cu" "In2.Cu" "In3.Cu" "In4.Cu" "In5.Cu" "In6.Cu"
			"In7.Cu" "In8.Cu" "In9.Cu" "In10.Cu" "In11.Cu" "In12.Cu" "In13.Cu" "In14.Cu"
			"In15.Cu" "In16.Cu"
		)
		(hatch none 0.5)
		(connect_pads
			(clearance 0)
		)
		(min_thickness 0.25)
		(keepout
			(tracks not_allowed)
			(vias allowed)
			(pads allowed)
			(copperpour not_allowed)
			(footprints allowed)
		)
		(placement
			(enabled no)
			(sheetname "")
		)
		(fill
			(thermal_gap 0.5)
			(thermal_bridge_width 0.5)
			(island_removal_mode 0)
		)
		(polygon
			(pts
				(arc
					(start 419.08095 -377.728734)
					(mid 419.095829 -377.692813)
					(end 419.13175 -377.677934)
				)
				(arc
					(start 419.84803 -377.677934)
					(mid 419.883951 -377.692813)
					(end 419.89883 -377.728734)
				)
				(arc
					(start 419.89883 -380.151386)
					(mid 419.883951 -380.187307)
					(end 419.84803 -380.202186)
				)
				(arc
					(start 419.13175 -380.202186)
					(mid 419.095829 -380.187307)
					(end 419.08095 -380.151386)
				)
			)
		)
	)
	(zone
		(layers "F.Cu" "B.Cu" "In1.Cu" "In2.Cu" "In3.Cu" "In4.Cu" "In5.Cu" "In6.Cu"
			"In7.Cu" "In8.Cu" "In9.Cu" "In10.Cu" "In11.Cu" "In12.Cu" "In13.Cu" "In14.Cu"
			"In15.Cu" "In16.Cu"
		)
		(hatch none 0.5)
		(connect_pads
			(clearance 0)
		)
		(min_thickness 0.25)
		(keepout
			(tracks not_allowed)
			(vias allowed)
			(pads allowed)
			(copperpour not_allowed)
			(footprints allowed)
		)
		(placement
			(enabled no)
			(sheetname "")
		)
		(fill
			(thermal_gap 0.5)
			(thermal_bridge_width 0.5)
			(island_removal_mode 0)
		)
		(polygon
			(pts
				(arc
					(start 427.881034 -403.728682)
					(mid 427.895913 -403.692761)
					(end 427.931834 -403.677882)
				)
				(arc
					(start 428.648114 -403.677882)
					(mid 428.684035 -403.692761)
					(end 428.698914 -403.728682)
				)
				(arc
					(start 428.698914 -406.151334)
					(mid 428.684035 -406.187255)
					(end 428.648114 -406.202134)
				)
				(arc
					(start 427.931834 -406.202134)
					(mid 427.895913 -406.187255)
					(end 427.881034 -406.151334)
				)
			)
		)
	)
	(zone
		(layers "F.Cu" "B.Cu" "In1.Cu" "In2.Cu" "In3.Cu" "In4.Cu" "In5.Cu" "In6.Cu"
			"In7.Cu" "In8.Cu" "In9.Cu" "In10.Cu" "In11.Cu" "In12.Cu" "In13.Cu" "In14.Cu"
			"In15.Cu" "In16.Cu"
		)
		(hatch none 0.5)
		(connect_pads
			(clearance 0)
		)
		(min_thickness 0.25)
		(keepout
			(tracks not_allowed)
			(vias allowed)
			(pads allowed)
			(copperpour not_allowed)
			(footprints allowed)
		)
		(placement
			(enabled no)
			(sheetname "")
		)
		(fill
			(thermal_gap 0.5)
			(thermal_bridge_width 0.5)
			(island_removal_mode 0)
		)
		(polygon
			(pts
				(arc
					(start 346.481146 -382.728724)
					(mid 346.496025 -382.692803)
					(end 346.531946 -382.677924)
				)
				(arc
					(start 347.248226 -382.677924)
					(mid 347.284147 -382.692803)
					(end 347.299026 -382.728724)
				)
				(arc
					(start 347.299026 -385.151376)
					(mid 347.284147 -385.187297)
					(end 347.248226 -385.202176)
				)
				(arc
					(start 346.531946 -385.202176)
					(mid 346.496025 -385.187297)
					(end 346.481146 -385.151376)
				)
			)
		)
	)
	(zone
		(layers "F.Cu" "B.Cu" "In1.Cu" "In2.Cu" "In3.Cu" "In4.Cu" "In5.Cu" "In6.Cu"
			"In7.Cu" "In8.Cu" "In9.Cu" "In10.Cu" "In11.Cu" "In12.Cu" "In13.Cu" "In14.Cu"
			"In15.Cu" "In16.Cu"
		)
		(hatch none 0.5)
		(connect_pads
			(clearance 0)
		)
		(min_thickness 0.25)
		(keepout
			(tracks not_allowed)
			(vias allowed)
			(pads allowed)
			(copperpour not_allowed)
			(footprints allowed)
		)
		(placement
			(enabled no)
			(sheetname "")
		)
		(fill
			(thermal_gap 0.5)
			(thermal_bridge_width 0.5)
			(island_removal_mode 0)
		)
		(polygon
			(pts
				(arc
					(start 121.188988 -348.20479)
					(mid 120.807988 -348.58579)
					(end 121.188988 -348.96679)
				)
				(arc
					(start 122.052588 -348.96679)
					(mid 122.433588 -348.58579)
					(end 122.052588 -348.20479)
				)
			)
		)
	)
	(zone
		(layers "F.Cu" "B.Cu" "In1.Cu" "In2.Cu" "In3.Cu" "In4.Cu" "In5.Cu" "In6.Cu"
			"In7.Cu" "In8.Cu" "In9.Cu" "In10.Cu" "In11.Cu" "In12.Cu" "In13.Cu" "In14.Cu"
			"In15.Cu" "In16.Cu"
		)
		(hatch none 0.5)
		(connect_pads
			(clearance 0)
		)
		(min_thickness 0.25)
		(keepout
			(tracks not_allowed)
			(vias allowed)
			(pads allowed)
			(copperpour not_allowed)
			(footprints allowed)
		)
		(placement
			(enabled no)
			(sheetname "")
		)
		(fill
			(thermal_gap 0.5)
			(thermal_bridge_width 0.5)
			(island_removal_mode 0)
		)
		(polygon
			(pts
				(arc
					(start 148.853398 -34.52241)
					(mid 149.310598 -34.97961)
					(end 149.767798 -34.52241)
				)
				(arc
					(start 149.767798 -33.65881)
					(mid 149.310598 -33.20161)
					(end 148.853398 -33.65881)
				)
			)
		)
	)
	(zone
		(layers "F.Cu" "B.Cu" "In1.Cu" "In2.Cu" "In3.Cu" "In4.Cu" "In5.Cu" "In6.Cu"
			"In7.Cu" "In8.Cu" "In9.Cu" "In10.Cu" "In11.Cu" "In12.Cu" "In13.Cu" "In14.Cu"
			"In15.Cu" "In16.Cu"
		)
		(hatch none 0.5)
		(connect_pads
			(clearance 0)
		)
		(min_thickness 0.25)
		(keepout
			(tracks not_allowed)
			(vias allowed)
			(pads allowed)
			(copperpour not_allowed)
			(footprints allowed)
		)
		(placement
			(enabled no)
			(sheetname "")
		)
		(fill
			(thermal_gap 0.5)
			(thermal_bridge_width 0.5)
			(island_removal_mode 0)
		)
		(polygon
			(pts
				(arc
					(start 400.99996 -108.312712)
					(mid 400.54276 -107.855512)
					(end 400.08556 -108.312712)
				)
				(arc
					(start 400.08556 -109.176312)
					(mid 400.54276 -109.633512)
					(end 400.99996 -109.176312)
				)
			)
		)
	)
	(zone
		(layers "F.Cu" "B.Cu" "In1.Cu" "In2.Cu" "In3.Cu" "In4.Cu" "In5.Cu" "In6.Cu"
			"In7.Cu" "In8.Cu" "In9.Cu" "In10.Cu" "In11.Cu" "In12.Cu" "In13.Cu" "In14.Cu"
			"In15.Cu" "In16.Cu"
		)
		(hatch none 0.5)
		(connect_pads
			(clearance 0)
		)
		(min_thickness 0.25)
		(keepout
			(tracks not_allowed)
			(vias allowed)
			(pads allowed)
			(copperpour not_allowed)
			(footprints allowed)
		)
		(placement
			(enabled no)
			(sheetname "")
		)
		(fill
			(thermal_gap 0.5)
			(thermal_bridge_width 0.5)
			(island_removal_mode 0)
		)
		(polygon
			(pts
				(arc
					(start 47.313088 -357.37673)
					(mid 46.932088 -357.75773)
					(end 47.313088 -358.13873)
				)
				(arc
					(start 48.176688 -358.13873)
					(mid 48.557688 -357.75773)
					(end 48.176688 -357.37673)
				)
			)
		)
	)
	(zone
		(layers "F.Cu" "B.Cu" "In1.Cu" "In2.Cu" "In3.Cu" "In4.Cu" "In5.Cu" "In6.Cu"
			"In7.Cu" "In8.Cu" "In9.Cu" "In10.Cu" "In11.Cu" "In12.Cu" "In13.Cu" "In14.Cu"
			"In15.Cu" "In16.Cu"
		)
		(hatch none 0.5)
		(connect_pads
			(clearance 0)
		)
		(min_thickness 0.25)
		(keepout
			(tracks not_allowed)
			(vias allowed)
			(pads allowed)
			(copperpour not_allowed)
			(footprints allowed)
		)
		(placement
			(enabled no)
			(sheetname "")
		)
		(fill
			(thermal_gap 0.5)
			(thermal_bridge_width 0.5)
			(island_removal_mode 0)
		)
		(polygon
			(pts
				(arc
					(start 318.720724 -342.058498)
					(mid 318.339724 -342.439498)
					(end 318.720724 -342.820498)
				)
				(arc
					(start 319.584324 -342.820498)
					(mid 319.965324 -342.439498)
					(end 319.584324 -342.058498)
				)
			)
		)
	)
	(zone
		(layers "F.Cu" "B.Cu" "In1.Cu" "In2.Cu" "In3.Cu" "In4.Cu" "In5.Cu" "In6.Cu"
			"In7.Cu" "In8.Cu" "In9.Cu" "In10.Cu" "In11.Cu" "In12.Cu" "In13.Cu" "In14.Cu"
			"In15.Cu" "In16.Cu"
		)
		(hatch none 0.5)
		(connect_pads
			(clearance 0)
		)
		(min_thickness 0.25)
		(keepout
			(tracks not_allowed)
			(vias allowed)
			(pads allowed)
			(copperpour not_allowed)
			(footprints allowed)
		)
		(placement
			(enabled no)
			(sheetname "")
		)
		(fill
			(thermal_gap 0.5)
			(thermal_bridge_width 0.5)
			(island_removal_mode 0)
		)
		(polygon
			(pts
				(arc
					(start 385.610608 -100.177854)
					(mid 386.067808 -100.635054)
					(end 386.525008 -100.177854)
				)
				(arc
					(start 386.525008 -99.314254)
					(mid 386.067808 -98.857054)
					(end 385.610608 -99.314254)
				)
			)
		)
	)
	(zone
		(layers "F.Cu" "B.Cu" "In1.Cu" "In2.Cu" "In3.Cu" "In4.Cu" "In5.Cu" "In6.Cu"
			"In7.Cu" "In8.Cu" "In9.Cu" "In10.Cu" "In11.Cu" "In12.Cu" "In13.Cu" "In14.Cu"
			"In15.Cu" "In16.Cu"
		)
		(hatch none 0.5)
		(connect_pads
			(clearance 0)
		)
		(min_thickness 0.25)
		(keepout
			(tracks not_allowed)
			(vias allowed)
			(pads allowed)
			(copperpour not_allowed)
			(footprints allowed)
		)
		(placement
			(enabled no)
			(sheetname "")
		)
		(fill
			(thermal_gap 0.5)
			(thermal_bridge_width 0.5)
			(island_removal_mode 0)
		)
		(polygon
			(pts
				(arc
					(start 374.29694 -342.058498)
					(mid 373.91594 -342.439498)
					(end 374.29694 -342.820498)
				)
				(arc
					(start 375.16054 -342.820498)
					(mid 375.54154 -342.439498)
					(end 375.16054 -342.058498)
				)
			)
		)
	)
	(zone
		(layers "F.Cu" "B.Cu" "In1.Cu" "In2.Cu" "In3.Cu" "In4.Cu" "In5.Cu" "In6.Cu"
			"In7.Cu" "In8.Cu" "In9.Cu" "In10.Cu" "In11.Cu" "In12.Cu" "In13.Cu" "In14.Cu"
			"In15.Cu" "In16.Cu"
		)
		(hatch none 0.5)
		(connect_pads
			(clearance 0)
		)
		(min_thickness 0.25)
		(keepout
			(tracks not_allowed)
			(vias allowed)
			(pads allowed)
			(copperpour not_allowed)
			(footprints allowed)
		)
		(placement
			(enabled no)
			(sheetname "")
		)
		(fill
			(thermal_gap 0.5)
			(thermal_bridge_width 0.5)
			(island_removal_mode 0)
		)
		(polygon
			(pts
				(arc
					(start 28.659328 -357.37673)
					(mid 28.278328 -357.75773)
					(end 28.659328 -358.13873)
				)
				(arc
					(start 29.522928 -358.13873)
					(mid 29.903928 -357.75773)
					(end 29.522928 -357.37673)
				)
			)
		)
	)
	(zone
		(layers "F.Cu" "B.Cu" "In1.Cu" "In2.Cu" "In3.Cu" "In4.Cu" "In5.Cu" "In6.Cu"
			"In7.Cu" "In8.Cu" "In9.Cu" "In10.Cu" "In11.Cu" "In12.Cu" "In13.Cu" "In14.Cu"
			"In15.Cu" "In16.Cu"
		)
		(hatch none 0.5)
		(connect_pads
			(clearance 0)
		)
		(min_thickness 0.25)
		(keepout
			(tracks not_allowed)
			(vias allowed)
			(pads allowed)
			(copperpour not_allowed)
			(footprints allowed)
		)
		(placement
			(enabled no)
			(sheetname "")
		)
		(fill
			(thermal_gap 0.5)
			(thermal_bridge_width 0.5)
			(island_removal_mode 0)
		)
		(polygon
			(pts
				(arc
					(start 174.621952 -348.20479)
					(mid 174.240952 -348.58579)
					(end 174.621952 -348.96679)
				)
				(arc
					(start 175.485552 -348.96679)
					(mid 175.866552 -348.58579)
					(end 175.485552 -348.20479)
				)
			)
		)
	)
	(zone
		(layers "F.Cu" "B.Cu" "In1.Cu" "In2.Cu" "In3.Cu" "In4.Cu" "In5.Cu" "In6.Cu"
			"In7.Cu" "In8.Cu" "In9.Cu" "In10.Cu" "In11.Cu" "In12.Cu" "In13.Cu" "In14.Cu"
			"In15.Cu" "In16.Cu"
		)
		(hatch none 0.5)
		(connect_pads
			(clearance 0)
		)
		(min_thickness 0.25)
		(keepout
			(tracks not_allowed)
			(vias allowed)
			(pads allowed)
			(copperpour not_allowed)
			(footprints allowed)
		)
		(placement
			(enabled no)
			(sheetname "")
		)
		(fill
			(thermal_gap 0.5)
			(thermal_bridge_width 0.5)
			(island_removal_mode 0)
		)
		(polygon
			(pts
				(arc
					(start 99.843082 -86.811358)
					(mid 100.300282 -87.268558)
					(end 100.757482 -86.811358)
				)
				(arc
					(start 100.757482 -85.947758)
					(mid 100.300282 -85.490558)
					(end 99.843082 -85.947758)
				)
			)
		)
	)
	(zone
		(layers "F.Cu" "B.Cu" "In1.Cu" "In2.Cu" "In3.Cu" "In4.Cu" "In5.Cu" "In6.Cu"
			"In7.Cu" "In8.Cu" "In9.Cu" "In10.Cu" "In11.Cu" "In12.Cu" "In13.Cu" "In14.Cu"
			"In15.Cu" "In16.Cu"
		)
		(hatch none 0.5)
		(connect_pads
			(clearance 0)
		)
		(min_thickness 0.25)
		(keepout
			(tracks not_allowed)
			(vias allowed)
			(pads allowed)
			(copperpour not_allowed)
			(footprints allowed)
		)
		(placement
			(enabled no)
			(sheetname "")
		)
		(fill
			(thermal_gap 0.5)
			(thermal_bridge_width 0.5)
			(island_removal_mode 0)
		)
		(polygon
			(pts
				(arc
					(start 434.907436 -29.12237)
					(mid 435.364636 -29.57957)
					(end 435.821836 -29.12237)
				)
				(arc
					(start 435.821836 -28.25877)
					(mid 435.364636 -27.80157)
					(end 434.907436 -28.25877)
				)
			)
		)
	)
	(zone
		(layers "F.Cu" "B.Cu" "In1.Cu" "In2.Cu" "In3.Cu" "In4.Cu" "In5.Cu" "In6.Cu"
			"In7.Cu" "In8.Cu" "In9.Cu" "In10.Cu" "In11.Cu" "In12.Cu" "In13.Cu" "In14.Cu"
			"In15.Cu" "In16.Cu"
		)
		(hatch none 0.5)
		(connect_pads
			(clearance 0)
		)
		(min_thickness 0.25)
		(keepout
			(tracks not_allowed)
			(vias allowed)
			(pads allowed)
			(copperpour not_allowed)
			(footprints allowed)
		)
		(placement
			(enabled no)
			(sheetname "")
		)
		(fill
			(thermal_gap 0.5)
			(thermal_bridge_width 0.5)
			(island_removal_mode 0)
		)
		(polygon
			(pts
				(arc
					(start 296.945812 -145.287238)
					(mid 297.403012 -145.744438)
					(end 297.860212 -145.287238)
				)
				(arc
					(start 297.860212 -144.423638)
					(mid 297.403012 -143.966438)
					(end 296.945812 -144.423638)
				)
			)
		)
	)
	(zone
		(layers "F.Cu" "B.Cu" "In1.Cu" "In2.Cu" "In3.Cu" "In4.Cu" "In5.Cu" "In6.Cu"
			"In7.Cu" "In8.Cu" "In9.Cu" "In10.Cu" "In11.Cu" "In12.Cu" "In13.Cu" "In14.Cu"
			"In15.Cu" "In16.Cu"
		)
		(hatch none 0.5)
		(connect_pads
			(clearance 0)
		)
		(min_thickness 0.25)
		(keepout
			(tracks not_allowed)
			(vias allowed)
			(pads allowed)
			(copperpour not_allowed)
			(footprints allowed)
		)
		(placement
			(enabled no)
			(sheetname "")
		)
		(fill
			(thermal_gap 0.5)
			(thermal_bridge_width 0.5)
			(island_removal_mode 0)
		)
		(polygon
			(pts
				(arc
					(start 136.733788 -345.084146)
					(mid 136.352788 -345.465146)
					(end 136.733788 -345.846146)
				)
				(arc
					(start 137.597388 -345.846146)
					(mid 137.978388 -345.465146)
					(end 137.597388 -345.084146)
				)
			)
		)
	)
	(zone
		(layers "F.Cu" "B.Cu" "In1.Cu" "In2.Cu" "In3.Cu" "In4.Cu" "In5.Cu" "In6.Cu"
			"In7.Cu" "In8.Cu" "In9.Cu" "In10.Cu" "In11.Cu" "In12.Cu" "In13.Cu" "In14.Cu"
			"In15.Cu" "In16.Cu"
		)
		(hatch none 0.5)
		(connect_pads
			(clearance 0)
		)
		(min_thickness 0.25)
		(keepout
			(tracks not_allowed)
			(vias allowed)
			(pads allowed)
			(copperpour not_allowed)
			(footprints allowed)
		)
		(placement
			(enabled no)
			(sheetname "")
		)
		(fill
			(thermal_gap 0.5)
			(thermal_bridge_width 0.5)
			(island_removal_mode 0)
		)
		(polygon
			(pts
				(arc
					(start 386.081016 -382.728724)
					(mid 386.095895 -382.692803)
					(end 386.131816 -382.677924)
				)
				(arc
					(start 386.848096 -382.677924)
					(mid 386.884017 -382.692803)
					(end 386.898896 -382.728724)
				)
				(arc
					(start 386.898896 -385.151376)
					(mid 386.884017 -385.187297)
					(end 386.848096 -385.202176)
				)
				(arc
					(start 386.131816 -385.202176)
					(mid 386.095895 -385.187297)
					(end 386.081016 -385.151376)
				)
			)
		)
	)
	(zone
		(layers "F.Cu" "B.Cu" "In1.Cu" "In2.Cu" "In3.Cu" "In4.Cu" "In5.Cu" "In6.Cu"
			"In7.Cu" "In8.Cu" "In9.Cu" "In10.Cu" "In11.Cu" "In12.Cu" "In13.Cu" "In14.Cu"
			"In15.Cu" "In16.Cu"
		)
		(hatch none 0.5)
		(connect_pads
			(clearance 0)
		)
		(min_thickness 0.25)
		(keepout
			(tracks not_allowed)
			(vias allowed)
			(pads allowed)
			(copperpour not_allowed)
			(footprints allowed)
		)
		(placement
			(enabled no)
			(sheetname "")
		)
		(fill
			(thermal_gap 0.5)
			(thermal_bridge_width 0.5)
			(island_removal_mode 0)
		)
		(polygon
			(pts
				(arc
					(start 71.501 -403.728682)
					(mid 71.515879 -403.692761)
					(end 71.5518 -403.677882)
				)
				(arc
					(start 72.26808 -403.677882)
					(mid 72.304001 -403.692761)
					(end 72.31888 -403.728682)
				)
				(arc
					(start 72.31888 -406.151334)
					(mid 72.304001 -406.187255)
					(end 72.26808 -406.202134)
				)
				(arc
					(start 71.5518 -406.202134)
					(mid 71.515879 -406.187255)
					(end 71.501 -406.151334)
				)
			)
		)
	)
	(zone
		(layers "F.Cu" "B.Cu" "In1.Cu" "In2.Cu" "In3.Cu" "In4.Cu" "In5.Cu" "In6.Cu"
			"In7.Cu" "In8.Cu" "In9.Cu" "In10.Cu" "In11.Cu" "In12.Cu" "In13.Cu" "In14.Cu"
			"In15.Cu" "In16.Cu"
		)
		(hatch none 0.5)
		(connect_pads
			(clearance 0)
		)
		(min_thickness 0.25)
		(keepout
			(tracks not_allowed)
			(vias allowed)
			(pads allowed)
			(copperpour not_allowed)
			(footprints allowed)
		)
		(placement
			(enabled no)
			(sheetname "")
		)
		(fill
			(thermal_gap 0.5)
			(thermal_bridge_width 0.5)
			(island_removal_mode 0)
		)
		(polygon
			(pts
				(arc
					(start 432.280822 -369.928902)
					(mid 432.295701 -369.892981)
					(end 432.331622 -369.878102)
				)
				(arc
					(start 433.047902 -369.878102)
					(mid 433.083823 -369.892981)
					(end 433.098702 -369.928902)
				)
				(arc
					(start 433.098702 -372.351554)
					(mid 433.083823 -372.387475)
					(end 433.047902 -372.402354)
				)
				(arc
					(start 432.331622 -372.402354)
					(mid 432.295701 -372.387475)
					(end 432.280822 -372.351554)
				)
			)
		)
	)
	(zone
		(layers "F.Cu" "B.Cu" "In1.Cu" "In2.Cu" "In3.Cu" "In4.Cu" "In5.Cu" "In6.Cu"
			"In7.Cu" "In8.Cu" "In9.Cu" "In10.Cu" "In11.Cu" "In12.Cu" "In13.Cu" "In14.Cu"
			"In15.Cu" "In16.Cu"
		)
		(hatch none 0.5)
		(connect_pads
			(clearance 0)
		)
		(min_thickness 0.25)
		(keepout
			(tracks not_allowed)
			(vias allowed)
			(pads allowed)
			(copperpour not_allowed)
			(footprints allowed)
		)
		(placement
			(enabled no)
			(sheetname "")
		)
		(fill
			(thermal_gap 0.5)
			(thermal_bridge_width 0.5)
			(island_removal_mode 0)
		)
		(polygon
			(pts
				(arc
					(start 377.4059 -342.058498)
					(mid 377.0249 -342.439498)
					(end 377.4059 -342.820498)
				)
				(arc
					(start 378.2695 -342.820498)
					(mid 378.6505 -342.439498)
					(end 378.2695 -342.058498)
				)
			)
		)
	)
	(zone
		(layers "F.Cu" "B.Cu" "In1.Cu" "In2.Cu" "In3.Cu" "In4.Cu" "In5.Cu" "In6.Cu"
			"In7.Cu" "In8.Cu" "In9.Cu" "In10.Cu" "In11.Cu" "In12.Cu" "In13.Cu" "In14.Cu"
			"In15.Cu" "In16.Cu"
		)
		(hatch none 0.5)
		(connect_pads
			(clearance 0)
		)
		(min_thickness 0.25)
		(keepout
			(tracks not_allowed)
			(vias allowed)
			(pads allowed)
			(copperpour not_allowed)
			(footprints allowed)
		)
		(placement
			(enabled no)
			(sheetname "")
		)
		(fill
			(thermal_gap 0.5)
			(thermal_bridge_width 0.5)
			(island_removal_mode 0)
		)
		(polygon
			(pts
				(arc
					(start 333.28102 -404.828756)
					(mid 333.295899 -404.792835)
					(end 333.33182 -404.777956)
				)
				(arc
					(start 334.0481 -404.777956)
					(mid 334.084021 -404.792835)
					(end 334.0989 -404.828756)
				)
				(arc
					(start 334.0989 -407.251408)
					(mid 334.084021 -407.287329)
					(end 334.0481 -407.302208)
				)
				(arc
					(start 333.33182 -407.302208)
					(mid 333.295899 -407.287329)
					(end 333.28102 -407.251408)
				)
			)
		)
	)
	(zone
		(layers "F.Cu" "B.Cu" "In1.Cu" "In2.Cu" "In3.Cu" "In4.Cu" "In5.Cu" "In6.Cu"
			"In7.Cu" "In8.Cu" "In9.Cu" "In10.Cu" "In11.Cu" "In12.Cu" "In13.Cu" "In14.Cu"
			"In15.Cu" "In16.Cu"
		)
		(hatch none 0.5)
		(connect_pads
			(clearance 0)
		)
		(min_thickness 0.25)
		(keepout
			(tracks not_allowed)
			(vias allowed)
			(pads allowed)
			(copperpour not_allowed)
			(footprints allowed)
		)
		(placement
			(enabled no)
			(sheetname "")
		)
		(fill
			(thermal_gap 0.5)
			(thermal_bridge_width 0.5)
			(island_removal_mode 0)
		)
		(polygon
			(pts
				(arc
					(start 382.9685 -112.784382)
					(mid 383.4257 -113.241582)
					(end 383.8829 -112.784382)
				)
				(arc
					(start 383.8829 -111.920782)
					(mid 383.4257 -111.463582)
					(end 382.9685 -111.920782)
				)
			)
		)
	)
	(zone
		(layers "F.Cu" "B.Cu" "In1.Cu" "In2.Cu" "In3.Cu" "In4.Cu" "In5.Cu" "In6.Cu"
			"In7.Cu" "In8.Cu" "In9.Cu" "In10.Cu" "In11.Cu" "In12.Cu" "In13.Cu" "In14.Cu"
			"In15.Cu" "In16.Cu"
		)
		(hatch none 0.5)
		(connect_pads
			(clearance 0)
		)
		(min_thickness 0.25)
		(keepout
			(tracks not_allowed)
			(vias allowed)
			(pads allowed)
			(copperpour not_allowed)
			(footprints allowed)
		)
		(placement
			(enabled no)
			(sheetname "")
		)
		(fill
			(thermal_gap 0.5)
			(thermal_bridge_width 0.5)
			(island_removal_mode 0)
		)
		(polygon
			(pts
				(arc
					(start 342.081104 -408.728672)
					(mid 342.095983 -408.692751)
					(end 342.131904 -408.677872)
				)
				(arc
					(start 342.848184 -408.677872)
					(mid 342.884105 -408.692751)
					(end 342.898984 -408.728672)
				)
				(arc
					(start 342.898984 -411.151324)
					(mid 342.884105 -411.187245)
					(end 342.848184 -411.202124)
				)
				(arc
					(start 342.131904 -411.202124)
					(mid 342.095983 -411.187245)
					(end 342.081104 -411.151324)
				)
			)
		)
	)
	(zone
		(layers "F.Cu" "B.Cu" "In1.Cu" "In2.Cu" "In3.Cu" "In4.Cu" "In5.Cu" "In6.Cu"
			"In7.Cu" "In8.Cu" "In9.Cu" "In10.Cu" "In11.Cu" "In12.Cu" "In13.Cu" "In14.Cu"
			"In15.Cu" "In16.Cu"
		)
		(hatch none 0.5)
		(connect_pads
			(clearance 0)
		)
		(min_thickness 0.25)
		(keepout
			(tracks not_allowed)
			(vias allowed)
			(pads allowed)
			(copperpour not_allowed)
			(footprints allowed)
		)
		(placement
			(enabled no)
			(sheetname "")
		)
		(fill
			(thermal_gap 0.5)
			(thermal_bridge_width 0.5)
			(island_removal_mode 0)
		)
		(polygon
			(pts
				(arc
					(start 286.754062 -106.512614)
					(mid 286.296862 -106.055414)
					(end 285.839662 -106.512614)
				)
				(arc
					(start 285.839662 -107.376214)
					(mid 286.296862 -107.833414)
					(end 286.754062 -107.376214)
				)
			)
		)
	)
	(zone
		(layers "F.Cu" "B.Cu" "In1.Cu" "In2.Cu" "In3.Cu" "In4.Cu" "In5.Cu" "In6.Cu"
			"In7.Cu" "In8.Cu" "In9.Cu" "In10.Cu" "In11.Cu" "In12.Cu" "In13.Cu" "In14.Cu"
			"In15.Cu" "In16.Cu"
		)
		(hatch none 0.5)
		(connect_pads
			(clearance 0)
		)
		(min_thickness 0.25)
		(keepout
			(tracks not_allowed)
			(vias allowed)
			(pads allowed)
			(copperpour not_allowed)
			(footprints allowed)
		)
		(placement
			(enabled no)
			(sheetname "")
		)
		(fill
			(thermal_gap 0.5)
			(thermal_bridge_width 0.5)
			(island_removal_mode 0)
		)
		(polygon
			(pts
				(arc
					(start 419.08095 -399.828766)
					(mid 419.095829 -399.792845)
					(end 419.13175 -399.777966)
				)
				(arc
					(start 419.84803 -399.777966)
					(mid 419.883951 -399.792845)
					(end 419.89883 -399.828766)
				)
				(arc
					(start 419.89883 -402.251418)
					(mid 419.883951 -402.287339)
					(end 419.84803 -402.302218)
				)
				(arc
					(start 419.13175 -402.302218)
					(mid 419.095829 -402.287339)
					(end 419.08095 -402.251418)
				)
			)
		)
	)
	(zone
		(layers "F.Cu" "B.Cu" "In1.Cu" "In2.Cu" "In3.Cu" "In4.Cu" "In5.Cu" "In6.Cu"
			"In7.Cu" "In8.Cu" "In9.Cu" "In10.Cu" "In11.Cu" "In12.Cu" "In13.Cu" "In14.Cu"
			"In15.Cu" "In16.Cu"
		)
		(hatch none 0.5)
		(connect_pads
			(clearance 0)
		)
		(min_thickness 0.25)
		(keepout
			(tracks not_allowed)
			(vias allowed)
			(pads allowed)
			(copperpour not_allowed)
			(footprints allowed)
		)
		(placement
			(enabled no)
			(sheetname "")
		)
		(fill
			(thermal_gap 0.5)
			(thermal_bridge_width 0.5)
			(island_removal_mode 0)
		)
		(polygon
			(pts
				(arc
					(start 139.842748 -348.20479)
					(mid 139.461748 -348.58579)
					(end 139.842748 -348.96679)
				)
				(arc
					(start 140.706348 -348.96679)
					(mid 141.087348 -348.58579)
					(end 140.706348 -348.20479)
				)
			)
		)
	)
	(zone
		(layers "F.Cu" "B.Cu" "In1.Cu" "In2.Cu" "In3.Cu" "In4.Cu" "In5.Cu" "In6.Cu"
			"In7.Cu" "In8.Cu" "In9.Cu" "In10.Cu" "In11.Cu" "In12.Cu" "In13.Cu" "In14.Cu"
			"In15.Cu" "In16.Cu"
		)
		(hatch none 0.5)
		(connect_pads
			(clearance 0)
		)
		(min_thickness 0.25)
		(keepout
			(tracks not_allowed)
			(vias allowed)
			(pads allowed)
			(copperpour not_allowed)
			(footprints allowed)
		)
		(placement
			(enabled no)
			(sheetname "")
		)
		(fill
			(thermal_gap 0.5)
			(thermal_bridge_width 0.5)
			(island_removal_mode 0)
		)
		(polygon
			(pts
				(arc
					(start 153.410666 -100.177854)
					(mid 153.867866 -100.635054)
					(end 154.325066 -100.177854)
				)
				(arc
					(start 154.325066 -99.314254)
					(mid 153.867866 -98.857054)
					(end 153.410666 -99.314254)
				)
			)
		)
	)
	(zone
		(layers "F.Cu" "B.Cu" "In1.Cu" "In2.Cu" "In3.Cu" "In4.Cu" "In5.Cu" "In6.Cu"
			"In7.Cu" "In8.Cu" "In9.Cu" "In10.Cu" "In11.Cu" "In12.Cu" "In13.Cu" "In14.Cu"
			"In15.Cu" "In16.Cu"
		)
		(hatch none 0.5)
		(connect_pads
			(clearance 0)
		)
		(min_thickness 0.25)
		(keepout
			(tracks not_allowed)
			(vias allowed)
			(pads allowed)
			(copperpour not_allowed)
			(footprints allowed)
		)
		(placement
			(enabled no)
			(sheetname "")
		)
		(fill
			(thermal_gap 0.5)
			(thermal_bridge_width 0.5)
			(island_removal_mode 0)
		)
		(polygon
			(pts
				(arc
					(start 208.030318 -36.60013)
					(mid 206.099918 -36.60013)
					(end 208.030318 -36.60013)
				)
			)
		)
	)
	(zone
		(layers "F.Cu" "B.Cu" "In1.Cu" "In2.Cu" "In3.Cu" "In4.Cu" "In5.Cu" "In6.Cu"
			"In7.Cu" "In8.Cu" "In9.Cu" "In10.Cu" "In11.Cu" "In12.Cu" "In13.Cu" "In14.Cu"
			"In15.Cu" "In16.Cu"
		)
		(hatch none 0.5)
		(connect_pads
			(clearance 0)
		)
		(min_thickness 0.25)
		(keepout
			(tracks not_allowed)
			(vias allowed)
			(pads allowed)
			(copperpour not_allowed)
			(footprints allowed)
		)
		(placement
			(enabled no)
			(sheetname "")
		)
		(fill
			(thermal_gap 0.5)
			(thermal_bridge_width 0.5)
			(island_removal_mode 0)
		)
		(polygon
			(pts
				(arc
					(start 115.501166 -399.828766)
					(mid 115.516045 -399.792845)
					(end 115.551966 -399.777966)
				)
				(arc
					(start 116.268246 -399.777966)
					(mid 116.304167 -399.792845)
					(end 116.319046 -399.828766)
				)
				(arc
					(start 116.319046 -402.251418)
					(mid 116.304167 -402.287339)
					(end 116.268246 -402.302218)
				)
				(arc
					(start 115.551966 -402.302218)
					(mid 115.516045 -402.287339)
					(end 115.501166 -402.251418)
				)
			)
		)
	)
	(zone
		(layers "F.Cu" "B.Cu" "In1.Cu" "In2.Cu" "In3.Cu" "In4.Cu" "In5.Cu" "In6.Cu"
			"In7.Cu" "In8.Cu" "In9.Cu" "In10.Cu" "In11.Cu" "In12.Cu" "In13.Cu" "In14.Cu"
			"In15.Cu" "In16.Cu"
		)
		(hatch none 0.5)
		(connect_pads
			(clearance 0)
		)
		(min_thickness 0.25)
		(keepout
			(tracks not_allowed)
			(vias allowed)
			(pads allowed)
			(copperpour not_allowed)
			(footprints allowed)
		)
		(placement
			(enabled no)
			(sheetname "")
		)
		(fill
			(thermal_gap 0.5)
			(thermal_bridge_width 0.5)
			(island_removal_mode 0)
		)
		(polygon
			(pts
				(arc
					(start 298.986702 -342.058498)
					(mid 298.605702 -342.439498)
					(end 298.986702 -342.820498)
				)
				(arc
					(start 299.850302 -342.820498)
					(mid 300.231302 -342.439498)
					(end 299.850302 -342.058498)
				)
			)
		)
	)
	(zone
		(layers "F.Cu" "B.Cu" "In1.Cu" "In2.Cu" "In3.Cu" "In4.Cu" "In5.Cu" "In6.Cu"
			"In7.Cu" "In8.Cu" "In9.Cu" "In10.Cu" "In11.Cu" "In12.Cu" "In13.Cu" "In14.Cu"
			"In15.Cu" "In16.Cu"
		)
		(hatch none 0.5)
		(connect_pads
			(clearance 0)
		)
		(min_thickness 0.25)
		(keepout
			(tracks not_allowed)
			(vias allowed)
			(pads allowed)
			(copperpour not_allowed)
			(footprints allowed)
		)
		(placement
			(enabled no)
			(sheetname "")
		)
		(fill
			(thermal_gap 0.5)
			(thermal_bridge_width 0.5)
			(island_removal_mode 0)
		)
		(polygon
			(pts
				(arc
					(start 176.707546 -32.722312)
					(mid 177.164746 -33.179512)
					(end 177.621946 -32.722312)
				)
				(arc
					(start 177.621946 -31.858712)
					(mid 177.164746 -31.401512)
					(end 176.707546 -31.858712)
				)
			)
		)
	)
	(zone
		(layers "F.Cu" "B.Cu" "In1.Cu" "In2.Cu" "In3.Cu" "In4.Cu" "In5.Cu" "In6.Cu"
			"In7.Cu" "In8.Cu" "In9.Cu" "In10.Cu" "In11.Cu" "In12.Cu" "In13.Cu" "In14.Cu"
			"In15.Cu" "In16.Cu"
		)
		(hatch none 0.5)
		(connect_pads
			(clearance 0)
		)
		(min_thickness 0.25)
		(keepout
			(tracks not_allowed)
			(vias allowed)
			(pads allowed)
			(copperpour not_allowed)
			(footprints allowed)
		)
		(placement
			(enabled no)
			(sheetname "")
		)
		(fill
			(thermal_gap 0.5)
			(thermal_bridge_width 0.5)
			(island_removal_mode 0)
		)
		(polygon
			(pts
				(arc
					(start 425.680886 -382.728724)
					(mid 425.695765 -382.692803)
					(end 425.731686 -382.677924)
				)
				(arc
					(start 426.447966 -382.677924)
					(mid 426.483887 -382.692803)
					(end 426.498766 -382.728724)
				)
				(arc
					(start 426.498766 -385.151376)
					(mid 426.483887 -385.187297)
					(end 426.447966 -385.202176)
				)
				(arc
					(start 425.731686 -385.202176)
					(mid 425.695765 -385.187297)
					(end 425.680886 -385.151376)
				)
			)
		)
	)
	(zone
		(layers "F.Cu" "B.Cu" "In1.Cu" "In2.Cu" "In3.Cu" "In4.Cu" "In5.Cu" "In6.Cu"
			"In7.Cu" "In8.Cu" "In9.Cu" "In10.Cu" "In11.Cu" "In12.Cu" "In13.Cu" "In14.Cu"
			"In15.Cu" "In16.Cu"
		)
		(hatch none 0.5)
		(connect_pads
			(clearance 0)
		)
		(min_thickness 0.25)
		(keepout
			(tracks not_allowed)
			(vias allowed)
			(pads allowed)
			(copperpour not_allowed)
			(footprints allowed)
		)
		(placement
			(enabled no)
			(sheetname "")
		)
		(fill
			(thermal_gap 0.5)
			(thermal_bridge_width 0.5)
			(island_removal_mode 0)
		)
		(polygon
			(pts
				(arc
					(start 331.081126 -407.628852)
					(mid 331.096005 -407.592931)
					(end 331.131926 -407.578052)
				)
				(arc
					(start 331.848206 -407.578052)
					(mid 331.884127 -407.592931)
					(end 331.899006 -407.628852)
				)
				(arc
					(start 331.899006 -410.051504)
					(mid 331.884127 -410.087425)
					(end 331.848206 -410.102304)
				)
				(arc
					(start 331.131926 -410.102304)
					(mid 331.096005 -410.087425)
					(end 331.081126 -410.051504)
				)
			)
		)
	)
	(zone
		(layers "F.Cu" "B.Cu" "In1.Cu" "In2.Cu" "In3.Cu" "In4.Cu" "In5.Cu" "In6.Cu"
			"In7.Cu" "In8.Cu" "In9.Cu" "In10.Cu" "In11.Cu" "In12.Cu" "In13.Cu" "In14.Cu"
			"In15.Cu" "In16.Cu"
		)
		(hatch none 0.5)
		(connect_pads
			(clearance 0)
		)
		(min_thickness 0.25)
		(keepout
			(tracks not_allowed)
			(vias allowed)
			(pads allowed)
			(copperpour not_allowed)
			(footprints allowed)
		)
		(placement
			(enabled no)
			(sheetname "")
		)
		(fill
			(thermal_gap 0.5)
			(thermal_bridge_width 0.5)
			(island_removal_mode 0)
		)
		(polygon
			(pts
				(arc
					(start 434.48097 -382.728724)
					(mid 434.495849 -382.692803)
					(end 434.53177 -382.677924)
				)
				(arc
					(start 435.24805 -382.677924)
					(mid 435.283971 -382.692803)
					(end 435.29885 -382.728724)
				)
				(arc
					(start 435.29885 -385.151376)
					(mid 435.283971 -385.187297)
					(end 435.24805 -385.202176)
				)
				(arc
					(start 434.53177 -385.202176)
					(mid 434.495849 -385.187297)
					(end 434.48097 -385.151376)
				)
			)
		)
	)
	(zone
		(layers "F.Cu" "B.Cu" "In1.Cu" "In2.Cu" "In3.Cu" "In4.Cu" "In5.Cu" "In6.Cu"
			"In7.Cu" "In8.Cu" "In9.Cu" "In10.Cu" "In11.Cu" "In12.Cu" "In13.Cu" "In14.Cu"
			"In15.Cu" "In16.Cu"
		)
		(hatch none 0.5)
		(connect_pads
			(clearance 0)
		)
		(min_thickness 0.25)
		(keepout
			(tracks not_allowed)
			(vias allowed)
			(pads allowed)
			(copperpour not_allowed)
			(footprints allowed)
		)
		(placement
			(enabled no)
			(sheetname "")
		)
		(fill
			(thermal_gap 0.5)
			(thermal_bridge_width 0.5)
			(island_removal_mode 0)
		)
		(polygon
			(pts
				(arc
					(start 172.70095 -377.728734)
					(mid 172.715829 -377.692813)
					(end 172.75175 -377.677934)
				)
				(arc
					(start 173.46803 -377.677934)
					(mid 173.503951 -377.692813)
					(end 173.51883 -377.728734)
				)
				(arc
					(start 173.51883 -380.151386)
					(mid 173.503951 -380.187307)
					(end 173.46803 -380.202186)
				)
				(arc
					(start 172.75175 -380.202186)
					(mid 172.715829 -380.187307)
					(end 172.70095 -380.151386)
				)
			)
		)
	)
	(zone
		(layers "F.Cu" "B.Cu" "In1.Cu" "In2.Cu" "In3.Cu" "In4.Cu" "In5.Cu" "In6.Cu"
			"In7.Cu" "In8.Cu" "In9.Cu" "In10.Cu" "In11.Cu" "In12.Cu" "In13.Cu" "In14.Cu"
			"In15.Cu" "In16.Cu"
		)
		(hatch none 0.5)
		(connect_pads
			(clearance 0)
		)
		(min_thickness 0.25)
		(keepout
			(tracks not_allowed)
			(vias allowed)
			(pads allowed)
			(copperpour not_allowed)
			(footprints allowed)
		)
		(placement
			(enabled no)
			(sheetname "")
		)
		(fill
			(thermal_gap 0.5)
			(thermal_bridge_width 0.5)
			(island_removal_mode 0)
		)
		(polygon
			(pts
				(arc
					(start 339.88121 -377.728734)
					(mid 339.896089 -377.692813)
					(end 339.93201 -377.677934)
				)
				(arc
					(start 340.64829 -377.677934)
					(mid 340.684211 -377.692813)
					(end 340.69909 -377.728734)
				)
				(arc
					(start 340.69909 -380.151386)
					(mid 340.684211 -380.187307)
					(end 340.64829 -380.202186)
				)
				(arc
					(start 339.93201 -380.202186)
					(mid 339.896089 -380.187307)
					(end 339.88121 -380.151386)
				)
			)
		)
	)
	(zone
		(layers "F.Cu" "B.Cu" "In1.Cu" "In2.Cu" "In3.Cu" "In4.Cu" "In5.Cu" "In6.Cu"
			"In7.Cu" "In8.Cu" "In9.Cu" "In10.Cu" "In11.Cu" "In12.Cu" "In13.Cu" "In14.Cu"
			"In15.Cu" "In16.Cu"
		)
		(hatch none 0.5)
		(connect_pads
			(clearance 0)
		)
		(min_thickness 0.25)
		(keepout
			(tracks not_allowed)
			(vias allowed)
			(pads allowed)
			(copperpour not_allowed)
			(footprints allowed)
		)
		(placement
			(enabled no)
			(sheetname "")
		)
		(fill
			(thermal_gap 0.5)
			(thermal_bridge_width 0.5)
			(island_removal_mode 0)
		)
		(polygon
			(pts
				(arc
					(start 312.502804 -342.058498)
					(mid 312.121804 -342.439498)
					(end 312.502804 -342.820498)
				)
				(arc
					(start 313.366404 -342.820498)
					(mid 313.747404 -342.439498)
					(end 313.366404 -342.058498)
				)
			)
		)
	)
	(zone
		(layers "F.Cu" "B.Cu" "In1.Cu" "In2.Cu" "In3.Cu" "In4.Cu" "In5.Cu" "In6.Cu"
			"In7.Cu" "In8.Cu" "In9.Cu" "In10.Cu" "In11.Cu" "In12.Cu" "In13.Cu" "In14.Cu"
			"In15.Cu" "In16.Cu"
		)
		(hatch none 0.5)
		(connect_pads
			(clearance 0)
		)
		(min_thickness 0.25)
		(keepout
			(tracks not_allowed)
			(vias allowed)
			(pads allowed)
			(copperpour not_allowed)
			(footprints allowed)
		)
		(placement
			(enabled no)
			(sheetname "")
		)
		(fill
			(thermal_gap 0.5)
			(thermal_bridge_width 0.5)
			(island_removal_mode 0)
		)
		(polygon
			(pts
				(arc
					(start 66.60007 -130.777234)
					(mid 67.05727 -131.234434)
					(end 67.51447 -130.777234)
				)
				(arc
					(start 67.51447 -129.913634)
					(mid 67.05727 -129.456434)
					(end 66.60007 -129.913634)
				)
			)
		)
	)
	(zone
		(layers "F.Cu" "B.Cu" "In1.Cu" "In2.Cu" "In3.Cu" "In4.Cu" "In5.Cu" "In6.Cu"
			"In7.Cu" "In8.Cu" "In9.Cu" "In10.Cu" "In11.Cu" "In12.Cu" "In13.Cu" "In14.Cu"
			"In15.Cu" "In16.Cu"
		)
		(hatch none 0.5)
		(connect_pads
			(clearance 0)
		)
		(min_thickness 0.25)
		(keepout
			(tracks not_allowed)
			(vias allowed)
			(pads allowed)
			(copperpour not_allowed)
			(footprints allowed)
		)
		(placement
			(enabled no)
			(sheetname "")
		)
		(fill
			(thermal_gap 0.5)
			(thermal_bridge_width 0.5)
			(island_removal_mode 0)
		)
		(polygon
			(pts
				(arc
					(start 246.130318 -36.60013)
					(mid 244.199918 -36.60013)
					(end 246.130318 -36.60013)
				)
			)
		)
	)
	(zone
		(layers "F.Cu" "B.Cu" "In1.Cu" "In2.Cu" "In3.Cu" "In4.Cu" "In5.Cu" "In6.Cu"
			"In7.Cu" "In8.Cu" "In9.Cu" "In10.Cu" "In11.Cu" "In12.Cu" "In13.Cu" "In14.Cu"
			"In15.Cu" "In16.Cu"
		)
		(hatch none 0.5)
		(connect_pads
			(clearance 0)
		)
		(min_thickness 0.25)
		(keepout
			(tracks not_allowed)
			(vias allowed)
			(pads allowed)
			(copperpour not_allowed)
			(footprints allowed)
		)
		(placement
			(enabled no)
			(sheetname "")
		)
		(fill
			(thermal_gap 0.5)
			(thermal_bridge_width 0.5)
			(island_removal_mode 0)
		)
		(polygon
			(pts
				(arc
					(start 381.680974 -374.928638)
					(mid 381.695853 -374.892717)
					(end 381.731774 -374.877838)
				)
				(arc
					(start 382.448054 -374.877838)
					(mid 382.483975 -374.892717)
					(end 382.498854 -374.928638)
				)
				(arc
					(start 382.498854 -377.35129)
					(mid 382.483975 -377.387211)
					(end 382.448054 -377.40209)
				)
				(arc
					(start 381.731774 -377.40209)
					(mid 381.695853 -377.387211)
					(end 381.680974 -377.35129)
				)
			)
		)
	)
	(zone
		(layers "F.Cu" "B.Cu" "In1.Cu" "In2.Cu" "In3.Cu" "In4.Cu" "In5.Cu" "In6.Cu"
			"In7.Cu" "In8.Cu" "In9.Cu" "In10.Cu" "In11.Cu" "In12.Cu" "In13.Cu" "In14.Cu"
			"In15.Cu" "In16.Cu"
		)
		(hatch none 0.5)
		(connect_pads
			(clearance 0)
		)
		(min_thickness 0.25)
		(keepout
			(tracks not_allowed)
			(vias allowed)
			(pads allowed)
			(copperpour not_allowed)
			(footprints allowed)
		)
		(placement
			(enabled no)
			(sheetname "")
		)
		(fill
			(thermal_gap 0.5)
			(thermal_bridge_width 0.5)
			(island_removal_mode 0)
		)
		(polygon
			(pts
				(arc
					(start 442.824108 -27.342846)
					(mid 443.281308 -27.800046)
					(end 443.738508 -27.342846)
				)
				(arc
					(start 443.738508 -26.479246)
					(mid 443.281308 -26.022046)
					(end 442.824108 -26.479246)
				)
			)
		)
	)
	(zone
		(layers "F.Cu" "B.Cu" "In1.Cu" "In2.Cu" "In3.Cu" "In4.Cu" "In5.Cu" "In6.Cu"
			"In7.Cu" "In8.Cu" "In9.Cu" "In10.Cu" "In11.Cu" "In12.Cu" "In13.Cu" "In14.Cu"
			"In15.Cu" "In16.Cu"
		)
		(hatch none 0.5)
		(connect_pads
			(clearance 0)
		)
		(min_thickness 0.25)
		(keepout
			(tracks not_allowed)
			(vias allowed)
			(pads allowed)
			(copperpour not_allowed)
			(footprints allowed)
		)
		(placement
			(enabled no)
			(sheetname "")
		)
		(fill
			(thermal_gap 0.5)
			(thermal_bridge_width 0.5)
			(island_removal_mode 0)
		)
		(polygon
			(pts
				(arc
					(start 430.080928 -404.828756)
					(mid 430.095807 -404.792835)
					(end 430.131728 -404.777956)
				)
				(arc
					(start 430.848008 -404.777956)
					(mid 430.883929 -404.792835)
					(end 430.898808 -404.828756)
				)
				(arc
					(start 430.898808 -407.251408)
					(mid 430.883929 -407.287329)
					(end 430.848008 -407.302208)
				)
				(arc
					(start 430.131728 -407.302208)
					(mid 430.095807 -407.287329)
					(end 430.080928 -407.251408)
				)
			)
		)
	)
	(zone
		(layers "F.Cu" "B.Cu" "In1.Cu" "In2.Cu" "In3.Cu" "In4.Cu" "In5.Cu" "In6.Cu"
			"In7.Cu" "In8.Cu" "In9.Cu" "In10.Cu" "In11.Cu" "In12.Cu" "In13.Cu" "In14.Cu"
			"In15.Cu" "In16.Cu"
		)
		(hatch none 0.5)
		(connect_pads
			(clearance 0)
		)
		(min_thickness 0.25)
		(keepout
			(tracks not_allowed)
			(vias allowed)
			(pads allowed)
			(copperpour not_allowed)
			(footprints allowed)
		)
		(placement
			(enabled no)
			(sheetname "")
		)
		(fill
			(thermal_gap 0.5)
			(thermal_bridge_width 0.5)
			(island_removal_mode 0)
		)
		(polygon
			(pts
				(arc
					(start 429.375062 -123.159266)
					(mid 429.832262 -123.616466)
					(end 430.289462 -123.159266)
				)
				(arc
					(start 430.289462 -122.295666)
					(mid 429.832262 -121.838466)
					(end 429.375062 -122.295666)
				)
			)
		)
	)
	(zone
		(layers "F.Cu" "B.Cu" "In1.Cu" "In2.Cu" "In3.Cu" "In4.Cu" "In5.Cu" "In6.Cu"
			"In7.Cu" "In8.Cu" "In9.Cu" "In10.Cu" "In11.Cu" "In12.Cu" "In13.Cu" "In14.Cu"
			"In15.Cu" "In16.Cu"
		)
		(hatch none 0.5)
		(connect_pads
			(clearance 0)
		)
		(min_thickness 0.25)
		(keepout
			(tracks not_allowed)
			(vias allowed)
			(pads allowed)
			(copperpour not_allowed)
			(footprints allowed)
		)
		(placement
			(enabled no)
			(sheetname "")
		)
		(fill
			(thermal_gap 0.5)
			(thermal_bridge_width 0.5)
			(island_removal_mode 0)
		)
		(polygon
			(pts
				(arc
					(start 331.081126 -395.92885)
					(mid 331.096005 -395.892929)
					(end 331.131926 -395.87805)
				)
				(arc
					(start 331.848206 -395.87805)
					(mid 331.884127 -395.892929)
					(end 331.899006 -395.92885)
				)
				(arc
					(start 331.899006 -398.351502)
					(mid 331.884127 -398.387423)
					(end 331.848206 -398.402302)
				)
				(arc
					(start 331.131926 -398.402302)
					(mid 331.096005 -398.387423)
					(end 331.081126 -398.351502)
				)
			)
		)
	)
	(zone
		(layers "F.Cu" "B.Cu" "In1.Cu" "In2.Cu" "In3.Cu" "In4.Cu" "In5.Cu" "In6.Cu"
			"In7.Cu" "In8.Cu" "In9.Cu" "In10.Cu" "In11.Cu" "In12.Cu" "In13.Cu" "In14.Cu"
			"In15.Cu" "In16.Cu"
		)
		(hatch none 0.5)
		(connect_pads
			(clearance 0)
		)
		(min_thickness 0.25)
		(keepout
			(tracks not_allowed)
			(vias allowed)
			(pads allowed)
			(copperpour not_allowed)
			(footprints allowed)
		)
		(placement
			(enabled no)
			(sheetname "")
		)
		(fill
			(thermal_gap 0.5)
			(thermal_bridge_width 0.5)
			(island_removal_mode 0)
		)
		(polygon
			(pts
				(arc
					(start 434.166772 -351.230438)
					(mid 433.785772 -351.611438)
					(end 434.166772 -351.992438)
				)
				(arc
					(start 435.030372 -351.992438)
					(mid 435.411372 -351.611438)
					(end 435.030372 -351.230438)
				)
			)
		)
	)
	(zone
		(layers "F.Cu" "B.Cu" "In1.Cu" "In2.Cu" "In3.Cu" "In4.Cu" "In5.Cu" "In6.Cu"
			"In7.Cu" "In8.Cu" "In9.Cu" "In10.Cu" "In11.Cu" "In12.Cu" "In13.Cu" "In14.Cu"
			"In15.Cu" "In16.Cu"
		)
		(hatch none 0.5)
		(connect_pads
			(clearance 0)
		)
		(min_thickness 0.25)
		(keepout
			(tracks not_allowed)
			(vias allowed)
			(pads allowed)
			(copperpour not_allowed)
			(footprints allowed)
		)
		(placement
			(enabled no)
			(sheetname "")
		)
		(fill
			(thermal_gap 0.5)
			(thermal_bridge_width 0.5)
			(island_removal_mode 0)
		)
		(polygon
			(pts
				(arc
					(start 388.949946 -299.07992)
					(mid 389.280146 -298.74972)
					(end 388.949946 -298.41952)
				)
				(arc
					(start 387.999986 -298.41952)
					(mid 387.669786 -298.74972)
					(end 387.999986 -299.07992)
				)
			)
		)
	)
	(zone
		(layers "F.Cu" "B.Cu" "In1.Cu" "In2.Cu" "In3.Cu" "In4.Cu" "In5.Cu" "In6.Cu"
			"In7.Cu" "In8.Cu" "In9.Cu" "In10.Cu" "In11.Cu" "In12.Cu" "In13.Cu" "In14.Cu"
			"In15.Cu" "In16.Cu"
		)
		(hatch none 0.5)
		(connect_pads
			(clearance 0)
		)
		(min_thickness 0.25)
		(keepout
			(tracks not_allowed)
			(vias allowed)
			(pads allowed)
			(copperpour not_allowed)
			(footprints allowed)
		)
		(placement
			(enabled no)
			(sheetname "")
		)
		(fill
			(thermal_gap 0.5)
			(thermal_bridge_width 0.5)
			(island_removal_mode 0)
		)
		(polygon
			(pts
				(arc
					(start 189.874398 -95.214948)
					(mid 187.740798 -95.214948)
					(end 189.874398 -95.214948)
				)
			)
		)
	)
	(zone
		(layers "F.Cu" "B.Cu" "In1.Cu" "In2.Cu" "In3.Cu" "In4.Cu" "In5.Cu" "In6.Cu"
			"In7.Cu" "In8.Cu" "In9.Cu" "In10.Cu" "In11.Cu" "In12.Cu" "In13.Cu" "In14.Cu"
			"In15.Cu" "In16.Cu"
		)
		(hatch none 0.5)
		(connect_pads
			(clearance 0)
		)
		(min_thickness 0.25)
		(keepout
			(tracks not_allowed)
			(vias allowed)
			(pads allowed)
			(copperpour not_allowed)
			(footprints allowed)
		)
		(placement
			(enabled no)
			(sheetname "")
		)
		(fill
			(thermal_gap 0.5)
			(thermal_bridge_width 0.5)
			(island_removal_mode 0)
		)
		(polygon
			(pts
				(arc
					(start 45.101002 -381.628904)
					(mid 45.115881 -381.592983)
					(end 45.151802 -381.578104)
				)
				(arc
					(start 45.868082 -381.578104)
					(mid 45.904003 -381.592983)
					(end 45.918882 -381.628904)
				)
				(arc
					(start 45.918882 -384.051556)
					(mid 45.904003 -384.087477)
					(end 45.868082 -384.102356)
				)
				(arc
					(start 45.151802 -384.102356)
					(mid 45.115881 -384.087477)
					(end 45.101002 -384.051556)
				)
			)
		)
	)
	(zone
		(layers "F.Cu" "B.Cu" "In1.Cu" "In2.Cu" "In3.Cu" "In4.Cu" "In5.Cu" "In6.Cu"
			"In7.Cu" "In8.Cu" "In9.Cu" "In10.Cu" "In11.Cu" "In12.Cu" "In13.Cu" "In14.Cu"
			"In15.Cu" "In16.Cu"
		)
		(hatch none 0.5)
		(connect_pads
			(clearance 0)
		)
		(min_thickness 0.25)
		(keepout
			(tracks not_allowed)
			(vias allowed)
			(pads allowed)
			(copperpour not_allowed)
			(footprints allowed)
		)
		(placement
			(enabled no)
			(sheetname "")
		)
		(fill
			(thermal_gap 0.5)
			(thermal_bridge_width 0.5)
			(island_removal_mode 0)
		)
		(polygon
			(pts
				(arc
					(start 159.077152 -357.37673)
					(mid 158.696152 -357.75773)
					(end 159.077152 -358.13873)
				)
				(arc
					(start 159.940752 -358.13873)
					(mid 160.321752 -357.75773)
					(end 159.940752 -357.37673)
				)
			)
		)
	)
	(zone
		(layers "F.Cu" "B.Cu" "In1.Cu" "In2.Cu" "In3.Cu" "In4.Cu" "In5.Cu" "In6.Cu"
			"In7.Cu" "In8.Cu" "In9.Cu" "In10.Cu" "In11.Cu" "In12.Cu" "In13.Cu" "In14.Cu"
			"In15.Cu" "In16.Cu"
		)
		(hatch none 0.5)
		(connect_pads
			(clearance 0)
		)
		(min_thickness 0.25)
		(keepout
			(tracks not_allowed)
			(vias allowed)
			(pads allowed)
			(copperpour not_allowed)
			(footprints allowed)
		)
		(placement
			(enabled no)
			(sheetname "")
		)
		(fill
			(thermal_gap 0.5)
			(thermal_bridge_width 0.5)
			(island_removal_mode 0)
		)
		(polygon
			(pts
				(arc
					(start 180.845968 -156.087318)
					(mid 181.303168 -156.544518)
					(end 181.760368 -156.087318)
				)
				(arc
					(start 181.760368 -155.223718)
					(mid 181.303168 -154.766518)
					(end 180.845968 -155.223718)
				)
			)
		)
	)
	(zone
		(layers "F.Cu" "B.Cu" "In1.Cu" "In2.Cu" "In3.Cu" "In4.Cu" "In5.Cu" "In6.Cu"
			"In7.Cu" "In8.Cu" "In9.Cu" "In10.Cu" "In11.Cu" "In12.Cu" "In13.Cu" "In14.Cu"
			"In15.Cu" "In16.Cu"
		)
		(hatch none 0.5)
		(connect_pads
			(clearance 0)
		)
		(min_thickness 0.25)
		(keepout
			(tracks not_allowed)
			(vias allowed)
			(pads allowed)
			(copperpour not_allowed)
			(footprints allowed)
		)
		(placement
			(enabled no)
			(sheetname "")
		)
		(fill
			(thermal_gap 0.5)
			(thermal_bridge_width 0.5)
			(island_removal_mode 0)
		)
		(polygon
			(pts
				(arc
					(start 150.768558 -134.897876)
					(mid 151.225758 -135.355076)
					(end 151.682958 -134.897876)
				)
				(arc
					(start 151.682958 -134.034276)
					(mid 151.225758 -133.577076)
					(end 150.768558 -134.034276)
				)
			)
		)
	)
	(zone
		(layers "F.Cu" "B.Cu" "In1.Cu" "In2.Cu" "In3.Cu" "In4.Cu" "In5.Cu" "In6.Cu"
			"In7.Cu" "In8.Cu" "In9.Cu" "In10.Cu" "In11.Cu" "In12.Cu" "In13.Cu" "In14.Cu"
			"In15.Cu" "In16.Cu"
		)
		(hatch none 0.5)
		(connect_pads
			(clearance 0)
		)
		(min_thickness 0.25)
		(keepout
			(tracks not_allowed)
			(vias allowed)
			(pads allowed)
			(copperpour not_allowed)
			(footprints allowed)
		)
		(placement
			(enabled no)
			(sheetname "")
		)
		(fill
			(thermal_gap 0.5)
			(thermal_bridge_width 0.5)
			(island_removal_mode 0)
		)
		(polygon
			(pts
				(arc
					(start 437.275732 -348.20479)
					(mid 436.894732 -348.58579)
					(end 437.275732 -348.96679)
				)
				(arc
					(start 438.139332 -348.96679)
					(mid 438.520332 -348.58579)
					(end 438.139332 -348.20479)
				)
			)
		)
	)
	(zone
		(layers "F.Cu" "B.Cu" "In1.Cu" "In2.Cu" "In3.Cu" "In4.Cu" "In5.Cu" "In6.Cu"
			"In7.Cu" "In8.Cu" "In9.Cu" "In10.Cu" "In11.Cu" "In12.Cu" "In13.Cu" "In14.Cu"
			"In15.Cu" "In16.Cu"
		)
		(hatch none 0.5)
		(connect_pads
			(clearance 0)
		)
		(min_thickness 0.25)
		(keepout
			(tracks not_allowed)
			(vias allowed)
			(pads allowed)
			(copperpour not_allowed)
			(footprints allowed)
		)
		(placement
			(enabled no)
			(sheetname "")
		)
		(fill
			(thermal_gap 0.5)
			(thermal_bridge_width 0.5)
			(island_removal_mode 0)
		)
		(polygon
			(pts
				(arc
					(start 133.671056 -168.213024)
					(mid 133.213856 -168.670224)
					(end 133.671056 -169.127424)
				)
				(arc
					(start 134.534656 -169.127424)
					(mid 134.991856 -168.670224)
					(end 134.534656 -168.213024)
				)
			)
		)
	)
	(zone
		(layers "F.Cu" "B.Cu" "In1.Cu" "In2.Cu" "In3.Cu" "In4.Cu" "In5.Cu" "In6.Cu"
			"In7.Cu" "In8.Cu" "In9.Cu" "In10.Cu" "In11.Cu" "In12.Cu" "In13.Cu" "In14.Cu"
			"In15.Cu" "In16.Cu"
		)
		(hatch none 0.5)
		(connect_pads
			(clearance 0)
		)
		(min_thickness 0.25)
		(keepout
			(tracks not_allowed)
			(vias allowed)
			(pads allowed)
			(copperpour not_allowed)
			(footprints allowed)
		)
		(placement
			(enabled no)
			(sheetname "")
		)
		(fill
			(thermal_gap 0.5)
			(thermal_bridge_width 0.5)
			(island_removal_mode 0)
		)
		(polygon
			(pts
				(arc
					(start 54.55412 -130.43281)
					(mid 54.09692 -129.97561)
					(end 53.63972 -130.43281)
				)
				(arc
					(start 53.63972 -131.29641)
					(mid 54.09692 -131.75361)
					(end 54.55412 -131.29641)
				)
			)
		)
	)
	(zone
		(layers "F.Cu" "B.Cu" "In1.Cu" "In2.Cu" "In3.Cu" "In4.Cu" "In5.Cu" "In6.Cu"
			"In7.Cu" "In8.Cu" "In9.Cu" "In10.Cu" "In11.Cu" "In12.Cu" "In13.Cu" "In14.Cu"
			"In15.Cu" "In16.Cu"
		)
		(hatch none 0.5)
		(connect_pads
			(clearance 0)
		)
		(min_thickness 0.25)
		(keepout
			(tracks not_allowed)
			(vias allowed)
			(pads allowed)
			(copperpour not_allowed)
			(footprints allowed)
		)
		(placement
			(enabled no)
			(sheetname "")
		)
		(fill
			(thermal_gap 0.5)
			(thermal_bridge_width 0.5)
			(island_removal_mode 0)
		)
		(polygon
			(pts
				(arc
					(start 340.483444 -345.084146)
					(mid 340.102444 -345.465146)
					(end 340.483444 -345.846146)
				)
				(arc
					(start 341.347044 -345.846146)
					(mid 341.728044 -345.465146)
					(end 341.347044 -345.084146)
				)
			)
		)
	)
	(zone
		(layers "F.Cu" "B.Cu" "In1.Cu" "In2.Cu" "In3.Cu" "In4.Cu" "In5.Cu" "In6.Cu"
			"In7.Cu" "In8.Cu" "In9.Cu" "In10.Cu" "In11.Cu" "In12.Cu" "In13.Cu" "In14.Cu"
			"In15.Cu" "In16.Cu"
		)
		(hatch none 0.5)
		(connect_pads
			(clearance 0)
		)
		(min_thickness 0.25)
		(keepout
			(tracks not_allowed)
			(vias allowed)
			(pads allowed)
			(copperpour not_allowed)
			(footprints allowed)
		)
		(placement
			(enabled no)
			(sheetname "")
		)
		(fill
			(thermal_gap 0.5)
			(thermal_bridge_width 0.5)
			(island_removal_mode 0)
		)
		(polygon
			(pts
				(arc
					(start 277.223982 -354.351082)
					(mid 276.842982 -354.732082)
					(end 277.223982 -355.113082)
				)
				(arc
					(start 278.087582 -355.113082)
					(mid 278.468582 -354.732082)
					(end 278.087582 -354.351082)
				)
			)
		)
	)
	(zone
		(layers "F.Cu" "B.Cu" "In1.Cu" "In2.Cu" "In3.Cu" "In4.Cu" "In5.Cu" "In6.Cu"
			"In7.Cu" "In8.Cu" "In9.Cu" "In10.Cu" "In11.Cu" "In12.Cu" "In13.Cu" "In14.Cu"
			"In15.Cu" "In16.Cu"
		)
		(hatch none 0.5)
		(connect_pads
			(clearance 0)
		)
		(min_thickness 0.25)
		(keepout
			(tracks not_allowed)
			(vias allowed)
			(pads allowed)
			(copperpour not_allowed)
			(footprints allowed)
		)
		(placement
			(enabled no)
			(sheetname "")
		)
		(fill
			(thermal_gap 0.5)
			(thermal_bridge_width 0.5)
			(island_removal_mode 0)
		)
		(polygon
			(pts
				(arc
					(start 432.01717 -124.965714)
					(mid 432.47437 -125.422914)
					(end 432.93157 -124.965714)
				)
				(arc
					(start 432.93157 -124.102114)
					(mid 432.47437 -123.644914)
					(end 432.01717 -124.102114)
				)
			)
		)
	)
	(zone
		(layers "F.Cu" "B.Cu" "In1.Cu" "In2.Cu" "In3.Cu" "In4.Cu" "In5.Cu" "In6.Cu"
			"In7.Cu" "In8.Cu" "In9.Cu" "In10.Cu" "In11.Cu" "In12.Cu" "In13.Cu" "In14.Cu"
			"In15.Cu" "In16.Cu"
		)
		(hatch none 0.5)
		(connect_pads
			(clearance 0)
		)
		(min_thickness 0.25)
		(keepout
			(tracks not_allowed)
			(vias allowed)
			(pads allowed)
			(copperpour not_allowed)
			(footprints allowed)
		)
		(placement
			(enabled no)
			(sheetname "")
		)
		(fill
			(thermal_gap 0.5)
			(thermal_bridge_width 0.5)
			(island_removal_mode 0)
		)
		(polygon
			(pts
				(arc
					(start 67.590162 -357.37673)
					(mid 67.209162 -357.75773)
					(end 67.590162 -358.13873)
				)
				(arc
					(start 68.453762 -358.13873)
					(mid 68.834762 -357.75773)
					(end 68.453762 -357.37673)
				)
			)
		)
	)
	(zone
		(layers "F.Cu" "B.Cu" "In1.Cu" "In2.Cu" "In3.Cu" "In4.Cu" "In5.Cu" "In6.Cu"
			"In7.Cu" "In8.Cu" "In9.Cu" "In10.Cu" "In11.Cu" "In12.Cu" "In13.Cu" "In14.Cu"
			"In15.Cu" "In16.Cu"
		)
		(hatch none 0.5)
		(connect_pads
			(clearance 0)
		)
		(min_thickness 0.25)
		(keepout
			(tracks not_allowed)
			(vias allowed)
			(pads allowed)
			(copperpour not_allowed)
			(footprints allowed)
		)
		(placement
			(enabled no)
			(sheetname "")
		)
		(fill
			(thermal_gap 0.5)
			(thermal_bridge_width 0.5)
			(island_removal_mode 0)
		)
		(polygon
			(pts
				(arc
					(start 251.048012 -32.714184)
					(mid 251.505212 -33.171384)
					(end 251.962412 -32.714184)
				)
				(arc
					(start 251.962412 -31.850584)
					(mid 251.505212 -31.393384)
					(end 251.048012 -31.850584)
				)
			)
		)
	)
	(zone
		(layers "F.Cu" "B.Cu" "In1.Cu" "In2.Cu" "In3.Cu" "In4.Cu" "In5.Cu" "In6.Cu"
			"In7.Cu" "In8.Cu" "In9.Cu" "In10.Cu" "In11.Cu" "In12.Cu" "In13.Cu" "In14.Cu"
			"In15.Cu" "In16.Cu"
		)
		(hatch none 0.5)
		(connect_pads
			(clearance 0)
		)
		(min_thickness 0.25)
		(keepout
			(tracks not_allowed)
			(vias allowed)
			(pads allowed)
			(copperpour not_allowed)
			(footprints allowed)
		)
		(placement
			(enabled no)
			(sheetname "")
		)
		(fill
			(thermal_gap 0.5)
			(thermal_bridge_width 0.5)
			(island_removal_mode 0)
		)
		(polygon
			(pts
				(arc
					(start 118.080028 -348.20479)
					(mid 117.699028 -348.58579)
					(end 118.080028 -348.96679)
				)
				(arc
					(start 118.943628 -348.96679)
					(mid 119.324628 -348.58579)
					(end 118.943628 -348.20479)
				)
			)
		)
	)
	(zone
		(layers "F.Cu" "B.Cu" "In1.Cu" "In2.Cu" "In3.Cu" "In4.Cu" "In5.Cu" "In6.Cu"
			"In7.Cu" "In8.Cu" "In9.Cu" "In10.Cu" "In11.Cu" "In12.Cu" "In13.Cu" "In14.Cu"
			"In15.Cu" "In16.Cu"
		)
		(hatch none 0.5)
		(connect_pads
			(clearance 0)
		)
		(min_thickness 0.25)
		(keepout
			(tracks not_allowed)
			(vias allowed)
			(pads allowed)
			(copperpour not_allowed)
			(footprints allowed)
		)
		(placement
			(enabled no)
			(sheetname "")
		)
		(fill
			(thermal_gap 0.5)
			(thermal_bridge_width 0.5)
			(island_removal_mode 0)
		)
		(polygon
			(pts
				(arc
					(start 114.971068 -348.20479)
					(mid 114.590068 -348.58579)
					(end 114.971068 -348.96679)
				)
				(arc
					(start 115.834668 -348.96679)
					(mid 116.215668 -348.58579)
					(end 115.834668 -348.20479)
				)
			)
		)
	)
	(zone
		(layers "F.Cu" "B.Cu" "In1.Cu" "In2.Cu" "In3.Cu" "In4.Cu" "In5.Cu" "In6.Cu"
			"In7.Cu" "In8.Cu" "In9.Cu" "In10.Cu" "In11.Cu" "In12.Cu" "In13.Cu" "In14.Cu"
			"In15.Cu" "In16.Cu"
		)
		(hatch none 0.5)
		(connect_pads
			(clearance 0)
		)
		(min_thickness 0.25)
		(keepout
			(tracks not_allowed)
			(vias allowed)
			(pads allowed)
			(copperpour not_allowed)
			(footprints allowed)
		)
		(placement
			(enabled no)
			(sheetname "")
		)
		(fill
			(thermal_gap 0.5)
			(thermal_bridge_width 0.5)
			(island_removal_mode 0)
		)
		(polygon
			(pts
				(arc
					(start 190.166752 -348.20479)
					(mid 189.785752 -348.58579)
					(end 190.166752 -348.96679)
				)
				(arc
					(start 191.030352 -348.96679)
					(mid 191.411352 -348.58579)
					(end 191.030352 -348.20479)
				)
			)
		)
	)
	(zone
		(layers "F.Cu" "B.Cu" "In1.Cu" "In2.Cu" "In3.Cu" "In4.Cu" "In5.Cu" "In6.Cu"
			"In7.Cu" "In8.Cu" "In9.Cu" "In10.Cu" "In11.Cu" "In12.Cu" "In13.Cu" "In14.Cu"
			"In15.Cu" "In16.Cu"
		)
		(hatch none 0.5)
		(connect_pads
			(clearance 0)
		)
		(min_thickness 0.25)
		(keepout
			(tracks not_allowed)
			(vias allowed)
			(pads allowed)
			(copperpour not_allowed)
			(footprints allowed)
		)
		(placement
			(enabled no)
			(sheetname "")
		)
		(fill
			(thermal_gap 0.5)
			(thermal_bridge_width 0.5)
			(island_removal_mode 0)
		)
		(polygon
			(pts
				(arc
					(start 400.99996 -111.912908)
					(mid 400.54276 -111.455708)
					(end 400.08556 -111.912908)
				)
				(arc
					(start 400.08556 -112.776508)
					(mid 400.54276 -113.233708)
					(end 400.99996 -112.776508)
				)
			)
		)
	)
	(zone
		(layers "F.Cu" "B.Cu" "In1.Cu" "In2.Cu" "In3.Cu" "In4.Cu" "In5.Cu" "In6.Cu"
			"In7.Cu" "In8.Cu" "In9.Cu" "In10.Cu" "In11.Cu" "In12.Cu" "In13.Cu" "In14.Cu"
			"In15.Cu" "In16.Cu"
		)
		(hatch none 0.5)
		(connect_pads
			(clearance 0)
		)
		(min_thickness 0.25)
		(keepout
			(tracks not_allowed)
			(vias allowed)
			(pads allowed)
			(copperpour not_allowed)
			(footprints allowed)
		)
		(placement
			(enabled no)
			(sheetname "")
		)
		(fill
			(thermal_gap 0.5)
			(thermal_bridge_width 0.5)
			(island_removal_mode 0)
		)
		(polygon
			(pts
				(arc
					(start 412.404052 -351.230438)
					(mid 412.023052 -351.611438)
					(end 412.404052 -351.992438)
				)
				(arc
					(start 413.267652 -351.992438)
					(mid 413.648652 -351.611438)
					(end 413.267652 -351.230438)
				)
			)
		)
	)
	(zone
		(layers "F.Cu" "B.Cu" "In1.Cu" "In2.Cu" "In3.Cu" "In4.Cu" "In5.Cu" "In6.Cu"
			"In7.Cu" "In8.Cu" "In9.Cu" "In10.Cu" "In11.Cu" "In12.Cu" "In13.Cu" "In14.Cu"
			"In15.Cu" "In16.Cu"
		)
		(hatch none 0.5)
		(connect_pads
			(clearance 0)
		)
		(min_thickness 0.25)
		(keepout
			(tracks not_allowed)
			(vias allowed)
			(pads allowed)
			(copperpour not_allowed)
			(footprints allowed)
		)
		(placement
			(enabled no)
			(sheetname "")
		)
		(fill
			(thermal_gap 0.5)
			(thermal_bridge_width 0.5)
			(island_removal_mode 0)
		)
		(polygon
			(pts
				(arc
					(start 71.501 -407.628852)
					(mid 71.515879 -407.592931)
					(end 71.5518 -407.578052)
				)
				(arc
					(start 72.26808 -407.578052)
					(mid 72.304001 -407.592931)
					(end 72.31888 -407.628852)
				)
				(arc
					(start 72.31888 -410.051504)
					(mid 72.304001 -410.087425)
					(end 72.26808 -410.102304)
				)
				(arc
					(start 71.5518 -410.102304)
					(mid 71.515879 -410.087425)
					(end 71.501 -410.051504)
				)
			)
		)
	)
	(zone
		(layers "F.Cu" "B.Cu" "In1.Cu" "In2.Cu" "In3.Cu" "In4.Cu" "In5.Cu" "In6.Cu"
			"In7.Cu" "In8.Cu" "In9.Cu" "In10.Cu" "In11.Cu" "In12.Cu" "In13.Cu" "In14.Cu"
			"In15.Cu" "In16.Cu"
		)
		(hatch none 0.5)
		(connect_pads
			(clearance 0)
		)
		(min_thickness 0.25)
		(keepout
			(tracks not_allowed)
			(vias allowed)
			(pads allowed)
			(copperpour not_allowed)
			(footprints allowed)
		)
		(placement
			(enabled no)
			(sheetname "")
		)
		(fill
			(thermal_gap 0.5)
			(thermal_bridge_width 0.5)
			(island_removal_mode 0)
		)
		(polygon
			(pts
				(arc
					(start 182.700168 -123.16714)
					(mid 183.157368 -123.62434)
					(end 183.614568 -123.16714)
				)
				(arc
					(start 183.614568 -122.30354)
					(mid 183.157368 -121.84634)
					(end 182.700168 -122.30354)
				)
			)
		)
	)
	(zone
		(layers "F.Cu" "B.Cu" "In1.Cu" "In2.Cu" "In3.Cu" "In4.Cu" "In5.Cu" "In6.Cu"
			"In7.Cu" "In8.Cu" "In9.Cu" "In10.Cu" "In11.Cu" "In12.Cu" "In13.Cu" "In14.Cu"
			"In15.Cu" "In16.Cu"
		)
		(hatch none 0.5)
		(connect_pads
			(clearance 0)
		)
		(min_thickness 0.25)
		(keepout
			(tracks not_allowed)
			(vias allowed)
			(pads allowed)
			(copperpour not_allowed)
			(footprints allowed)
		)
		(placement
			(enabled no)
			(sheetname "")
		)
		(fill
			(thermal_gap 0.5)
			(thermal_bridge_width 0.5)
			(island_removal_mode 0)
		)
		(polygon
			(pts
				(arc
					(start 291.481002 -399.828766)
					(mid 291.495881 -399.792845)
					(end 291.531802 -399.777966)
				)
				(arc
					(start 292.248082 -399.777966)
					(mid 292.284003 -399.792845)
					(end 292.298882 -399.828766)
				)
				(arc
					(start 292.298882 -402.251418)
					(mid 292.284003 -402.287339)
					(end 292.248082 -402.302218)
				)
				(arc
					(start 291.531802 -402.302218)
					(mid 291.495881 -402.287339)
					(end 291.481002 -402.251418)
				)
			)
		)
	)
	(zone
		(layers "F.Cu" "B.Cu" "In1.Cu" "In2.Cu" "In3.Cu" "In4.Cu" "In5.Cu" "In6.Cu"
			"In7.Cu" "In8.Cu" "In9.Cu" "In10.Cu" "In11.Cu" "In12.Cu" "In13.Cu" "In14.Cu"
			"In15.Cu" "In16.Cu"
		)
		(hatch none 0.5)
		(connect_pads
			(clearance 0)
		)
		(min_thickness 0.25)
		(keepout
			(tracks not_allowed)
			(vias allowed)
			(pads allowed)
			(copperpour not_allowed)
			(footprints allowed)
		)
		(placement
			(enabled no)
			(sheetname "")
		)
		(fill
			(thermal_gap 0.5)
			(thermal_bridge_width 0.5)
			(island_removal_mode 0)
		)
		(polygon
			(pts
				(arc
					(start 271.006062 -357.37673)
					(mid 270.625062 -357.75773)
					(end 271.006062 -358.13873)
				)
				(arc
					(start 271.869662 -358.13873)
					(mid 272.250662 -357.75773)
					(end 271.869662 -357.37673)
				)
			)
		)
	)
	(zone
		(layers "F.Cu" "B.Cu" "In1.Cu" "In2.Cu" "In3.Cu" "In4.Cu" "In5.Cu" "In6.Cu"
			"In7.Cu" "In8.Cu" "In9.Cu" "In10.Cu" "In11.Cu" "In12.Cu" "In13.Cu" "In14.Cu"
			"In15.Cu" "In16.Cu"
		)
		(hatch none 0.5)
		(connect_pads
			(clearance 0)
		)
		(min_thickness 0.25)
		(keepout
			(tracks not_allowed)
			(vias allowed)
			(pads allowed)
			(copperpour not_allowed)
			(footprints allowed)
		)
		(placement
			(enabled no)
			(sheetname "")
		)
		(fill
			(thermal_gap 0.5)
			(thermal_bridge_width 0.5)
			(island_removal_mode 0)
		)
		(polygon
			(pts
				(arc
					(start 34.101024 -397.028924)
					(mid 34.115903 -396.993003)
					(end 34.151824 -396.978124)
				)
				(arc
					(start 34.868104 -396.978124)
					(mid 34.904025 -396.993003)
					(end 34.918904 -397.028924)
				)
				(arc
					(start 34.918904 -399.451576)
					(mid 34.904025 -399.487497)
					(end 34.868104 -399.502376)
				)
				(arc
					(start 34.151824 -399.502376)
					(mid 34.115903 -399.487497)
					(end 34.101024 -399.451576)
				)
			)
		)
	)
	(zone
		(layers "F.Cu" "B.Cu" "In1.Cu" "In2.Cu" "In3.Cu" "In4.Cu" "In5.Cu" "In6.Cu"
			"In7.Cu" "In8.Cu" "In9.Cu" "In10.Cu" "In11.Cu" "In12.Cu" "In13.Cu" "In14.Cu"
			"In15.Cu" "In16.Cu"
		)
		(hatch none 0.5)
		(connect_pads
			(clearance 0)
		)
		(min_thickness 0.25)
		(keepout
			(tracks not_allowed)
			(vias allowed)
			(pads allowed)
			(copperpour not_allowed)
			(footprints allowed)
		)
		(placement
			(enabled no)
			(sheetname "")
		)
		(fill
			(thermal_gap 0.5)
			(thermal_bridge_width 0.5)
			(island_removal_mode 0)
		)
		(polygon
			(pts
				(arc
					(start 36.301172 -407.628852)
					(mid 36.316051 -407.592931)
					(end 36.351972 -407.578052)
				)
				(arc
					(start 37.068252 -407.578052)
					(mid 37.104173 -407.592931)
					(end 37.119052 -407.628852)
				)
				(arc
					(start 37.119052 -410.051504)
					(mid 37.104173 -410.087425)
					(end 37.068252 -410.102304)
				)
				(arc
					(start 36.351972 -410.102304)
					(mid 36.316051 -410.087425)
					(end 36.301172 -410.051504)
				)
			)
		)
	)
	(zone
		(layers "F.Cu" "B.Cu" "In1.Cu" "In2.Cu" "In3.Cu" "In4.Cu" "In5.Cu" "In6.Cu"
			"In7.Cu" "In8.Cu" "In9.Cu" "In10.Cu" "In11.Cu" "In12.Cu" "In13.Cu" "In14.Cu"
			"In15.Cu" "In16.Cu"
		)
		(hatch none 0.5)
		(connect_pads
			(clearance 0)
		)
		(min_thickness 0.25)
		(keepout
			(tracks not_allowed)
			(vias allowed)
			(pads allowed)
			(copperpour not_allowed)
			(footprints allowed)
		)
		(placement
			(enabled no)
			(sheetname "")
		)
		(fill
			(thermal_gap 0.5)
			(thermal_bridge_width 0.5)
			(island_removal_mode 0)
		)
		(polygon
			(pts
				(arc
					(start 172.70095 -399.828766)
					(mid 172.715829 -399.792845)
					(end 172.75175 -399.777966)
				)
				(arc
					(start 173.46803 -399.777966)
					(mid 173.503951 -399.792845)
					(end 173.51883 -399.828766)
				)
				(arc
					(start 173.51883 -402.251418)
					(mid 173.503951 -402.287339)
					(end 173.46803 -402.302218)
				)
				(arc
					(start 172.75175 -402.302218)
					(mid 172.715829 -402.287339)
					(end 172.70095 -402.251418)
				)
			)
		)
	)
	(zone
		(layers "F.Cu" "B.Cu" "In1.Cu" "In2.Cu" "In3.Cu" "In4.Cu" "In5.Cu" "In6.Cu"
			"In7.Cu" "In8.Cu" "In9.Cu" "In10.Cu" "In11.Cu" "In12.Cu" "In13.Cu" "In14.Cu"
			"In15.Cu" "In16.Cu"
		)
		(hatch none 0.5)
		(connect_pads
			(clearance 0)
		)
		(min_thickness 0.25)
		(keepout
			(tracks not_allowed)
			(vias allowed)
			(pads allowed)
			(copperpour not_allowed)
			(footprints allowed)
		)
		(placement
			(enabled no)
			(sheetname "")
		)
		(fill
			(thermal_gap 0.5)
			(thermal_bridge_width 0.5)
			(island_removal_mode 0)
		)
		(polygon
			(pts
				(arc
					(start 121.188988 -357.37673)
					(mid 120.807988 -357.75773)
					(end 121.188988 -358.13873)
				)
				(arc
					(start 122.052588 -358.13873)
					(mid 122.433588 -357.75773)
					(end 122.052588 -357.37673)
				)
			)
		)
	)
	(zone
		(layers "F.Cu" "B.Cu" "In1.Cu" "In2.Cu" "In3.Cu" "In4.Cu" "In5.Cu" "In6.Cu"
			"In7.Cu" "In8.Cu" "In9.Cu" "In10.Cu" "In11.Cu" "In12.Cu" "In13.Cu" "In14.Cu"
			"In15.Cu" "In16.Cu"
		)
		(hatch none 0.5)
		(connect_pads
			(clearance 0)
		)
		(min_thickness 0.25)
		(keepout
			(tracks not_allowed)
			(vias allowed)
			(pads allowed)
			(copperpour not_allowed)
			(footprints allowed)
		)
		(placement
			(enabled no)
			(sheetname "")
		)
		(fill
			(thermal_gap 0.5)
			(thermal_bridge_width 0.5)
			(island_removal_mode 0)
		)
		(polygon
			(pts
				(arc
					(start 86.90102 -371.028722)
					(mid 86.915899 -370.992801)
					(end 86.95182 -370.977922)
				)
				(arc
					(start 87.6681 -370.977922)
					(mid 87.704021 -370.992801)
					(end 87.7189 -371.028722)
				)
				(arc
					(start 87.7189 -373.451374)
					(mid 87.704021 -373.487295)
					(end 87.6681 -373.502174)
				)
				(arc
					(start 86.95182 -373.502174)
					(mid 86.915899 -373.487295)
					(end 86.90102 -373.451374)
				)
			)
		)
	)
	(zone
		(layers "F.Cu" "B.Cu" "In1.Cu" "In2.Cu" "In3.Cu" "In4.Cu" "In5.Cu" "In6.Cu"
			"In7.Cu" "In8.Cu" "In9.Cu" "In10.Cu" "In11.Cu" "In12.Cu" "In13.Cu" "In14.Cu"
			"In15.Cu" "In16.Cu"
		)
		(hatch none 0.5)
		(connect_pads
			(clearance 0)
		)
		(min_thickness 0.25)
		(keepout
			(tracks not_allowed)
			(vias allowed)
			(pads allowed)
			(copperpour not_allowed)
			(footprints allowed)
		)
		(placement
			(enabled no)
			(sheetname "")
		)
		(fill
			(thermal_gap 0.5)
			(thermal_bridge_width 0.5)
			(island_removal_mode 0)
		)
		(polygon
			(pts
				(arc
					(start 291.481002 -403.728682)
					(mid 291.495881 -403.692761)
					(end 291.531802 -403.677882)
				)
				(arc
					(start 292.248082 -403.677882)
					(mid 292.284003 -403.692761)
					(end 292.298882 -403.728682)
				)
				(arc
					(start 292.298882 -406.151334)
					(mid 292.284003 -406.187255)
					(end 292.248082 -406.202134)
				)
				(arc
					(start 291.531802 -406.202134)
					(mid 291.495881 -406.187255)
					(end 291.481002 -406.151334)
				)
			)
		)
	)
	(zone
		(layers "F.Cu" "B.Cu" "In1.Cu" "In2.Cu" "In3.Cu" "In4.Cu" "In5.Cu" "In6.Cu"
			"In7.Cu" "In8.Cu" "In9.Cu" "In10.Cu" "In11.Cu" "In12.Cu" "In13.Cu" "In14.Cu"
			"In15.Cu" "In16.Cu"
		)
		(hatch none 0.5)
		(connect_pads
			(clearance 0)
		)
		(min_thickness 0.25)
		(keepout
			(tracks not_allowed)
			(vias allowed)
			(pads allowed)
			(copperpour not_allowed)
			(footprints allowed)
		)
		(placement
			(enabled no)
			(sheetname "")
		)
		(fill
			(thermal_gap 0.5)
			(thermal_bridge_width 0.5)
			(island_removal_mode 0)
		)
		(polygon
			(pts
				(arc
					(start 168.301162 -369.928902)
					(mid 168.316041 -369.892981)
					(end 168.351962 -369.878102)
				)
				(arc
					(start 169.068242 -369.878102)
					(mid 169.104163 -369.892981)
					(end 169.119042 -369.928902)
				)
				(arc
					(start 169.119042 -372.351554)
					(mid 169.104163 -372.387475)
					(end 169.068242 -372.402354)
				)
				(arc
					(start 168.351962 -372.402354)
					(mid 168.316041 -372.387475)
					(end 168.301162 -372.351554)
				)
			)
		)
	)
	(zone
		(layers "F.Cu" "B.Cu" "In1.Cu" "In2.Cu" "In3.Cu" "In4.Cu" "In5.Cu" "In6.Cu"
			"In7.Cu" "In8.Cu" "In9.Cu" "In10.Cu" "In11.Cu" "In12.Cu" "In13.Cu" "In14.Cu"
			"In15.Cu" "In16.Cu"
		)
		(hatch none 0.5)
		(connect_pads
			(clearance 0)
		)
		(min_thickness 0.25)
		(keepout
			(tracks not_allowed)
			(vias allowed)
			(pads allowed)
			(copperpour not_allowed)
			(footprints allowed)
		)
		(placement
			(enabled no)
			(sheetname "")
		)
		(fill
			(thermal_gap 0.5)
			(thermal_bridge_width 0.5)
			(island_removal_mode 0)
		)
		(polygon
			(pts
				(arc
					(start 371.18798 -342.058498)
					(mid 370.80698 -342.439498)
					(end 371.18798 -342.820498)
				)
				(arc
					(start 372.05158 -342.820498)
					(mid 372.43258 -342.439498)
					(end 372.05158 -342.058498)
				)
			)
		)
	)
	(zone
		(layers "F.Cu" "B.Cu" "In1.Cu" "In2.Cu" "In3.Cu" "In4.Cu" "In5.Cu" "In6.Cu"
			"In7.Cu" "In8.Cu" "In9.Cu" "In10.Cu" "In11.Cu" "In12.Cu" "In13.Cu" "In14.Cu"
			"In15.Cu" "In16.Cu"
		)
		(hatch none 0.5)
		(connect_pads
			(clearance 0)
		)
		(min_thickness 0.25)
		(keepout
			(tracks not_allowed)
			(vias allowed)
			(pads allowed)
			(copperpour not_allowed)
			(footprints allowed)
		)
		(placement
			(enabled no)
			(sheetname "")
		)
		(fill
			(thermal_gap 0.5)
			(thermal_bridge_width 0.5)
			(island_removal_mode 0)
		)
		(polygon
			(pts
				(arc
					(start 161.700972 -408.728672)
					(mid 161.715851 -408.692751)
					(end 161.751772 -408.677872)
				)
				(arc
					(start 162.468052 -408.677872)
					(mid 162.503973 -408.692751)
					(end 162.518852 -408.728672)
				)
				(arc
					(start 162.518852 -411.151324)
					(mid 162.503973 -411.187245)
					(end 162.468052 -411.202124)
				)
				(arc
					(start 161.751772 -411.202124)
					(mid 161.715851 -411.187245)
					(end 161.700972 -411.151324)
				)
			)
		)
	)
	(zone
		(layers "F.Cu" "B.Cu" "In1.Cu" "In2.Cu" "In3.Cu" "In4.Cu" "In5.Cu" "In6.Cu"
			"In7.Cu" "In8.Cu" "In9.Cu" "In10.Cu" "In11.Cu" "In12.Cu" "In13.Cu" "In14.Cu"
			"In15.Cu" "In16.Cu"
		)
		(hatch none 0.5)
		(connect_pads
			(clearance 0)
		)
		(min_thickness 0.25)
		(keepout
			(tracks not_allowed)
			(vias allowed)
			(pads allowed)
			(copperpour not_allowed)
			(footprints allowed)
		)
		(placement
			(enabled no)
			(sheetname "")
		)
		(fill
			(thermal_gap 0.5)
			(thermal_bridge_width 0.5)
			(island_removal_mode 0)
		)
		(polygon
			(pts
				(arc
					(start 165.295072 -348.20479)
					(mid 164.914072 -348.58579)
					(end 165.295072 -348.96679)
				)
				(arc
					(start 166.158672 -348.96679)
					(mid 166.539672 -348.58579)
					(end 166.158672 -348.20479)
				)
			)
		)
	)
	(zone
		(layers "F.Cu" "B.Cu" "In1.Cu" "In2.Cu" "In3.Cu" "In4.Cu" "In5.Cu" "In6.Cu"
			"In7.Cu" "In8.Cu" "In9.Cu" "In10.Cu" "In11.Cu" "In12.Cu" "In13.Cu" "In14.Cu"
			"In15.Cu" "In16.Cu"
		)
		(hatch none 0.5)
		(connect_pads
			(clearance 0)
		)
		(min_thickness 0.25)
		(keepout
			(tracks not_allowed)
			(vias allowed)
			(pads allowed)
			(copperpour not_allowed)
			(footprints allowed)
		)
		(placement
			(enabled no)
			(sheetname "")
		)
		(fill
			(thermal_gap 0.5)
			(thermal_bridge_width 0.5)
			(island_removal_mode 0)
		)
		(polygon
			(pts
				(xy 53.074824 -417.288472) (xy 66.524886 -417.288472) (xy 66.524886 -394.327634) (xy 66.477134 -394.279882)
				(xy 53.074824 -394.279882)
			)
		)
	)
	(zone
		(layers "F.Cu" "B.Cu" "In1.Cu" "In2.Cu" "In3.Cu" "In4.Cu" "In5.Cu" "In6.Cu"
			"In7.Cu" "In8.Cu" "In9.Cu" "In10.Cu" "In11.Cu" "In12.Cu" "In13.Cu" "In14.Cu"
			"In15.Cu" "In16.Cu"
		)
		(hatch none 0.5)
		(connect_pads
			(clearance 0)
		)
		(min_thickness 0.25)
		(keepout
			(tracks not_allowed)
			(vias allowed)
			(pads allowed)
			(copperpour not_allowed)
			(footprints allowed)
		)
		(placement
			(enabled no)
			(sheetname "")
		)
		(fill
			(thermal_gap 0.5)
			(thermal_bridge_width 0.5)
			(island_removal_mode 0)
		)
		(polygon
			(pts
				(arc
					(start 142.951708 -348.20479)
					(mid 142.570708 -348.58579)
					(end 142.951708 -348.96679)
				)
				(arc
					(start 143.815308 -348.96679)
					(mid 144.196308 -348.58579)
					(end 143.815308 -348.20479)
				)
			)
		)
	)
	(zone
		(layers "F.Cu" "B.Cu" "In1.Cu" "In2.Cu" "In3.Cu" "In4.Cu" "In5.Cu" "In6.Cu"
			"In7.Cu" "In8.Cu" "In9.Cu" "In10.Cu" "In11.Cu" "In12.Cu" "In13.Cu" "In14.Cu"
			"In15.Cu" "In16.Cu"
		)
		(hatch none 0.5)
		(connect_pads
			(clearance 0)
		)
		(min_thickness 0.25)
		(keepout
			(tracks not_allowed)
			(vias allowed)
			(pads allowed)
			(copperpour not_allowed)
			(footprints allowed)
		)
		(placement
			(enabled no)
			(sheetname "")
		)
		(fill
			(thermal_gap 0.5)
			(thermal_bridge_width 0.5)
			(island_removal_mode 0)
		)
		(polygon
			(pts
				(arc
					(start 133.624828 -357.37673)
					(mid 133.243828 -357.75773)
					(end 133.624828 -358.13873)
				)
				(arc
					(start 134.488428 -358.13873)
					(mid 134.869428 -357.75773)
					(end 134.488428 -357.37673)
				)
			)
		)
	)
	(zone
		(layers "F.Cu" "B.Cu" "In1.Cu" "In2.Cu" "In3.Cu" "In4.Cu" "In5.Cu" "In6.Cu"
			"In7.Cu" "In8.Cu" "In9.Cu" "In10.Cu" "In11.Cu" "In12.Cu" "In13.Cu" "In14.Cu"
			"In15.Cu" "In16.Cu"
		)
		(hatch none 0.5)
		(connect_pads
			(clearance 0)
		)
		(min_thickness 0.25)
		(keepout
			(tracks not_allowed)
			(vias allowed)
			(pads allowed)
			(copperpour not_allowed)
			(footprints allowed)
		)
		(placement
			(enabled no)
			(sheetname "")
		)
		(fill
			(thermal_gap 0.5)
			(thermal_bridge_width 0.5)
			(island_removal_mode 0)
		)
		(polygon
			(pts
				(arc
					(start 41.095168 -348.20479)
					(mid 40.714168 -348.58579)
					(end 41.095168 -348.96679)
				)
				(arc
					(start 41.958768 -348.96679)
					(mid 42.339768 -348.58579)
					(end 41.958768 -348.20479)
				)
			)
		)
	)
	(zone
		(layers "F.Cu" "B.Cu" "In1.Cu" "In2.Cu" "In3.Cu" "In4.Cu" "In5.Cu" "In6.Cu"
			"In7.Cu" "In8.Cu" "In9.Cu" "In10.Cu" "In11.Cu" "In12.Cu" "In13.Cu" "In14.Cu"
			"In15.Cu" "In16.Cu"
		)
		(hatch none 0.5)
		(connect_pads
			(clearance 0)
		)
		(min_thickness 0.25)
		(keepout
			(tracks not_allowed)
			(vias allowed)
			(pads allowed)
			(copperpour not_allowed)
			(footprints allowed)
		)
		(placement
			(enabled no)
			(sheetname "")
		)
		(fill
			(thermal_gap 0.5)
			(thermal_bridge_width 0.5)
			(island_removal_mode 0)
		)
		(polygon
			(pts
				(arc
					(start 151.378158 -101.984302)
					(mid 151.835358 -102.441502)
					(end 152.292558 -101.984302)
				)
				(arc
					(start 152.292558 -101.120702)
					(mid 151.835358 -100.663502)
					(end 151.378158 -101.120702)
				)
			)
		)
	)
	(zone
		(layers "F.Cu" "B.Cu" "In1.Cu" "In2.Cu" "In3.Cu" "In4.Cu" "In5.Cu" "In6.Cu"
			"In7.Cu" "In8.Cu" "In9.Cu" "In10.Cu" "In11.Cu" "In12.Cu" "In13.Cu" "In14.Cu"
			"In15.Cu" "In16.Cu"
		)
		(hatch none 0.5)
		(connect_pads
			(clearance 0)
		)
		(min_thickness 0.25)
		(keepout
			(tracks not_allowed)
			(vias allowed)
			(pads allowed)
			(copperpour not_allowed)
			(footprints allowed)
		)
		(placement
			(enabled no)
			(sheetname "")
		)
		(fill
			(thermal_gap 0.5)
			(thermal_bridge_width 0.5)
			(island_removal_mode 0)
		)
		(polygon
			(pts
				(arc
					(start 423.690034 -116.895626)
					(mid 423.232834 -116.438426)
					(end 422.775634 -116.895626)
				)
				(arc
					(start 422.775634 -117.759226)
					(mid 423.232834 -118.216426)
					(end 423.690034 -117.759226)
				)
			)
		)
	)
	(zone
		(layers "F.Cu" "B.Cu" "In1.Cu" "In2.Cu" "In3.Cu" "In4.Cu" "In5.Cu" "In6.Cu"
			"In7.Cu" "In8.Cu" "In9.Cu" "In10.Cu" "In11.Cu" "In12.Cu" "In13.Cu" "In14.Cu"
			"In15.Cu" "In16.Cu"
		)
		(hatch none 0.5)
		(connect_pads
			(clearance 0)
		)
		(min_thickness 0.25)
		(keepout
			(tracks not_allowed)
			(vias allowed)
			(pads allowed)
			(copperpour not_allowed)
			(footprints allowed)
		)
		(placement
			(enabled no)
			(sheetname "")
		)
		(fill
			(thermal_gap 0.5)
			(thermal_bridge_width 0.5)
			(island_removal_mode 0)
		)
		(polygon
			(pts
				(arc
					(start 27.501088 -369.928902)
					(mid 27.515967 -369.892981)
					(end 27.551888 -369.878102)
				)
				(arc
					(start 28.268168 -369.878102)
					(mid 28.304089 -369.892981)
					(end 28.318968 -369.928902)
				)
				(arc
					(start 28.318968 -372.351554)
					(mid 28.304089 -372.387475)
					(end 28.268168 -372.402354)
				)
				(arc
					(start 27.551888 -372.402354)
					(mid 27.515967 -372.387475)
					(end 27.501088 -372.351554)
				)
			)
		)
	)
	(zone
		(layers "F.Cu" "B.Cu" "In1.Cu" "In2.Cu" "In3.Cu" "In4.Cu" "In5.Cu" "In6.Cu"
			"In7.Cu" "In8.Cu" "In9.Cu" "In10.Cu" "In11.Cu" "In12.Cu" "In13.Cu" "In14.Cu"
			"In15.Cu" "In16.Cu"
		)
		(hatch none 0.5)
		(connect_pads
			(clearance 0)
		)
		(min_thickness 0.25)
		(keepout
			(tracks not_allowed)
			(vias allowed)
			(pads allowed)
			(copperpour not_allowed)
			(footprints allowed)
		)
		(placement
			(enabled no)
			(sheetname "")
		)
		(fill
			(thermal_gap 0.5)
			(thermal_bridge_width 0.5)
			(island_removal_mode 0)
		)
		(polygon
			(pts
				(arc
					(start 315.917072 -145.285714)
					(mid 316.374272 -145.742914)
					(end 316.831472 -145.285714)
				)
				(arc
					(start 316.831472 -144.422114)
					(mid 316.374272 -143.964914)
					(end 315.917072 -144.422114)
				)
			)
		)
	)
	(zone
		(layers "F.Cu" "B.Cu" "In1.Cu" "In2.Cu" "In3.Cu" "In4.Cu" "In5.Cu" "In6.Cu"
			"In7.Cu" "In8.Cu" "In9.Cu" "In10.Cu" "In11.Cu" "In12.Cu" "In13.Cu" "In14.Cu"
			"In15.Cu" "In16.Cu"
		)
		(hatch none 0.5)
		(connect_pads
			(clearance 0)
		)
		(min_thickness 0.25)
		(keepout
			(tracks not_allowed)
			(vias allowed)
			(pads allowed)
			(copperpour not_allowed)
			(footprints allowed)
		)
		(placement
			(enabled no)
			(sheetname "")
		)
		(fill
			(thermal_gap 0.5)
			(thermal_bridge_width 0.5)
			(island_removal_mode 0)
		)
		(polygon
			(pts
				(arc
					(start 283.441902 -351.230438)
					(mid 283.060902 -351.611438)
					(end 283.441902 -351.992438)
				)
				(arc
					(start 284.305502 -351.992438)
					(mid 284.686502 -351.611438)
					(end 284.305502 -351.230438)
				)
			)
		)
	)
	(zone
		(layers "F.Cu" "B.Cu" "In1.Cu" "In2.Cu" "In3.Cu" "In4.Cu" "In5.Cu" "In6.Cu"
			"In7.Cu" "In8.Cu" "In9.Cu" "In10.Cu" "In11.Cu" "In12.Cu" "In13.Cu" "In14.Cu"
			"In15.Cu" "In16.Cu"
		)
		(hatch none 0.5)
		(connect_pads
			(clearance 0)
		)
		(min_thickness 0.25)
		(keepout
			(tracks not_allowed)
			(vias allowed)
			(pads allowed)
			(copperpour not_allowed)
			(footprints allowed)
		)
		(placement
			(enabled no)
			(sheetname "")
		)
		(fill
			(thermal_gap 0.5)
			(thermal_bridge_width 0.5)
			(island_removal_mode 0)
		)
		(polygon
			(pts
				(arc
					(start 429.375062 -143.479266)
					(mid 429.832262 -143.936466)
					(end 430.289462 -143.479266)
				)
				(arc
					(start 430.289462 -142.615666)
					(mid 429.832262 -142.158466)
					(end 429.375062 -142.615666)
				)
			)
		)
	)
	(zone
		(layers "F.Cu" "B.Cu" "In1.Cu" "In2.Cu" "In3.Cu" "In4.Cu" "In5.Cu" "In6.Cu"
			"In7.Cu" "In8.Cu" "In9.Cu" "In10.Cu" "In11.Cu" "In12.Cu" "In13.Cu" "In14.Cu"
			"In15.Cu" "In16.Cu"
		)
		(hatch none 0.5)
		(connect_pads
			(clearance 0)
		)
		(min_thickness 0.25)
		(keepout
			(tracks not_allowed)
			(vias allowed)
			(pads allowed)
			(copperpour not_allowed)
			(footprints allowed)
		)
		(placement
			(enabled no)
			(sheetname "")
		)
		(fill
			(thermal_gap 0.5)
			(thermal_bridge_width 0.5)
			(island_removal_mode 0)
		)
		(polygon
			(pts
				(arc
					(start 70.699122 -357.37673)
					(mid 70.318122 -357.75773)
					(end 70.699122 -358.13873)
				)
				(arc
					(start 71.562722 -358.13873)
					(mid 71.943722 -357.75773)
					(end 71.562722 -357.37673)
				)
			)
		)
	)
	(zone
		(layers "F.Cu" "B.Cu" "In1.Cu" "In2.Cu" "In3.Cu" "In4.Cu" "In5.Cu" "In6.Cu"
			"In7.Cu" "In8.Cu" "In9.Cu" "In10.Cu" "In11.Cu" "In12.Cu" "In13.Cu" "In14.Cu"
			"In15.Cu" "In16.Cu"
		)
		(hatch none 0.5)
		(connect_pads
			(clearance 0)
		)
		(min_thickness 0.25)
		(keepout
			(tracks not_allowed)
			(vias allowed)
			(pads allowed)
			(copperpour not_allowed)
			(footprints allowed)
		)
		(placement
			(enabled no)
			(sheetname "")
		)
		(fill
			(thermal_gap 0.5)
			(thermal_bridge_width 0.5)
			(island_removal_mode 0)
		)
		(polygon
			(pts
				(arc
					(start 139.440666 -198.904352)
					(mid 139.464621 -198.906629)
					(end 139.488672 -198.9074)
				)
				(arc
					(start 139.488672 -198.9074)
					(mid 139.869672 -198.5264)
					(end 139.488672 -198.1454)
				)
				(xy 139.474702 -198.145654)
				(arc
					(start 138.636502 -198.145654)
					(mid 138.244584 -198.544488)
					(end 138.67257 -198.904352)
				)
			)
		)
	)
	(zone
		(layers "F.Cu" "B.Cu" "In1.Cu" "In2.Cu" "In3.Cu" "In4.Cu" "In5.Cu" "In6.Cu"
			"In7.Cu" "In8.Cu" "In9.Cu" "In10.Cu" "In11.Cu" "In12.Cu" "In13.Cu" "In14.Cu"
			"In15.Cu" "In16.Cu"
		)
		(hatch none 0.5)
		(connect_pads
			(clearance 0)
		)
		(min_thickness 0.25)
		(keepout
			(tracks not_allowed)
			(vias allowed)
			(pads allowed)
			(copperpour not_allowed)
			(footprints allowed)
		)
		(placement
			(enabled no)
			(sheetname "")
		)
		(fill
			(thermal_gap 0.5)
			(thermal_bridge_width 0.5)
			(island_removal_mode 0)
		)
		(polygon
			(pts
				(arc
					(start 313.274964 -119.559324)
					(mid 313.732164 -120.016524)
					(end 314.189364 -119.559324)
				)
				(arc
					(start 314.189364 -118.695724)
					(mid 313.732164 -118.238524)
					(end 313.274964 -118.695724)
				)
			)
		)
	)
	(zone
		(layers "F.Cu" "B.Cu" "In1.Cu" "In2.Cu" "In3.Cu" "In4.Cu" "In5.Cu" "In6.Cu"
			"In7.Cu" "In8.Cu" "In9.Cu" "In10.Cu" "In11.Cu" "In12.Cu" "In13.Cu" "In14.Cu"
			"In15.Cu" "In16.Cu"
		)
		(hatch none 0.5)
		(connect_pads
			(clearance 0)
		)
		(min_thickness 0.25)
		(keepout
			(tracks not_allowed)
			(vias allowed)
			(pads allowed)
			(copperpour not_allowed)
			(footprints allowed)
		)
		(placement
			(enabled no)
			(sheetname "")
		)
		(fill
			(thermal_gap 0.5)
			(thermal_bridge_width 0.5)
			(island_removal_mode 0)
		)
		(polygon
			(pts
				(arc
					(start 124.297948 -351.230438)
					(mid 123.916948 -351.611438)
					(end 124.297948 -351.992438)
				)
				(arc
					(start 125.161548 -351.992438)
					(mid 125.542548 -351.611438)
					(end 125.161548 -351.230438)
				)
			)
		)
	)
	(zone
		(layers "F.Cu" "B.Cu" "In1.Cu" "In2.Cu" "In3.Cu" "In4.Cu" "In5.Cu" "In6.Cu"
			"In7.Cu" "In8.Cu" "In9.Cu" "In10.Cu" "In11.Cu" "In12.Cu" "In13.Cu" "In14.Cu"
			"In15.Cu" "In16.Cu"
		)
		(hatch none 0.5)
		(connect_pads
			(clearance 0)
		)
		(min_thickness 0.25)
		(keepout
			(tracks not_allowed)
			(vias allowed)
			(pads allowed)
			(copperpour not_allowed)
			(footprints allowed)
		)
		(placement
			(enabled no)
			(sheetname "")
		)
		(fill
			(thermal_gap 0.5)
			(thermal_bridge_width 0.5)
			(island_removal_mode 0)
		)
		(polygon
			(pts
				(arc
					(start 232.698798 -308.568852)
					(mid 231.936798 -308.568852)
					(end 232.698798 -308.568852)
				)
			)
		)
	)
	(zone
		(layers "F.Cu" "B.Cu" "In1.Cu" "In2.Cu" "In3.Cu" "In4.Cu" "In5.Cu" "In6.Cu"
			"In7.Cu" "In8.Cu" "In9.Cu" "In10.Cu" "In11.Cu" "In12.Cu" "In13.Cu" "In14.Cu"
			"In15.Cu" "In16.Cu"
		)
		(hatch none 0.5)
		(connect_pads
			(clearance 0)
		)
		(min_thickness 0.25)
		(keepout
			(tracks not_allowed)
			(vias allowed)
			(pads allowed)
			(copperpour not_allowed)
			(footprints allowed)
		)
		(placement
			(enabled no)
			(sheetname "")
		)
		(fill
			(thermal_gap 0.5)
			(thermal_bridge_width 0.5)
			(island_removal_mode 0)
		)
		(polygon
			(pts
				(arc
					(start 180.839872 -357.37673)
					(mid 180.458872 -357.75773)
					(end 180.839872 -358.13873)
				)
				(arc
					(start 181.703472 -358.13873)
					(mid 182.084472 -357.75773)
					(end 181.703472 -357.37673)
				)
			)
		)
	)
	(zone
		(layers "F.Cu" "B.Cu" "In1.Cu" "In2.Cu" "In3.Cu" "In4.Cu" "In5.Cu" "In6.Cu"
			"In7.Cu" "In8.Cu" "In9.Cu" "In10.Cu" "In11.Cu" "In12.Cu" "In13.Cu" "In14.Cu"
			"In15.Cu" "In16.Cu"
		)
		(hatch none 0.5)
		(connect_pads
			(clearance 0)
		)
		(min_thickness 0.25)
		(keepout
			(tracks not_allowed)
			(vias allowed)
			(pads allowed)
			(copperpour not_allowed)
			(footprints allowed)
		)
		(placement
			(enabled no)
			(sheetname "")
		)
		(fill
			(thermal_gap 0.5)
			(thermal_bridge_width 0.5)
			(island_removal_mode 0)
		)
		(polygon
			(pts
				(arc
					(start 331.156564 -354.351082)
					(mid 330.775564 -354.732082)
					(end 331.156564 -355.113082)
				)
				(arc
					(start 332.020164 -355.113082)
					(mid 332.401164 -354.732082)
					(end 332.020164 -354.351082)
				)
			)
		)
	)
	(zone
		(layers "F.Cu" "B.Cu" "In1.Cu" "In2.Cu" "In3.Cu" "In4.Cu" "In5.Cu" "In6.Cu"
			"In7.Cu" "In8.Cu" "In9.Cu" "In10.Cu" "In11.Cu" "In12.Cu" "In13.Cu" "In14.Cu"
			"In15.Cu" "In16.Cu"
		)
		(hatch none 0.5)
		(connect_pads
			(clearance 0)
		)
		(min_thickness 0.25)
		(keepout
			(tracks not_allowed)
			(vias allowed)
			(pads allowed)
			(copperpour not_allowed)
			(footprints allowed)
		)
		(placement
			(enabled no)
			(sheetname "")
		)
		(fill
			(thermal_gap 0.5)
			(thermal_bridge_width 0.5)
			(island_removal_mode 0)
		)
		(polygon
			(pts
				(arc
					(start 162.186112 -354.351082)
					(mid 161.805112 -354.732082)
					(end 162.186112 -355.113082)
				)
				(arc
					(start 163.049712 -355.113082)
					(mid 163.430712 -354.732082)
					(end 163.049712 -354.351082)
				)
			)
		)
	)
	(zone
		(layers "F.Cu" "B.Cu" "In1.Cu" "In2.Cu" "In3.Cu" "In4.Cu" "In5.Cu" "In6.Cu"
			"In7.Cu" "In8.Cu" "In9.Cu" "In10.Cu" "In11.Cu" "In12.Cu" "In13.Cu" "In14.Cu"
			"In15.Cu" "In16.Cu"
		)
		(hatch none 0.5)
		(connect_pads
			(clearance 0)
		)
		(min_thickness 0.25)
		(keepout
			(tracks not_allowed)
			(vias allowed)
			(pads allowed)
			(copperpour not_allowed)
			(footprints allowed)
		)
		(placement
			(enabled no)
			(sheetname "")
		)
		(fill
			(thermal_gap 0.5)
			(thermal_bridge_width 0.5)
			(island_removal_mode 0)
		)
		(polygon
			(pts
				(arc
					(start 295.881044 -395.92885)
					(mid 295.895923 -395.892929)
					(end 295.931844 -395.87805)
				)
				(arc
					(start 296.648124 -395.87805)
					(mid 296.684045 -395.892929)
					(end 296.698924 -395.92885)
				)
				(arc
					(start 296.698924 -398.351502)
					(mid 296.684045 -398.387423)
					(end 296.648124 -398.402302)
				)
				(arc
					(start 295.931844 -398.402302)
					(mid 295.895923 -398.387423)
					(end 295.881044 -398.351502)
				)
			)
		)
	)
	(zone
		(layers "F.Cu" "B.Cu" "In1.Cu" "In2.Cu" "In3.Cu" "In4.Cu" "In5.Cu" "In6.Cu"
			"In7.Cu" "In8.Cu" "In9.Cu" "In10.Cu" "In11.Cu" "In12.Cu" "In13.Cu" "In14.Cu"
			"In15.Cu" "In16.Cu"
		)
		(hatch none 0.5)
		(connect_pads
			(clearance 0)
		)
		(min_thickness 0.25)
		(keepout
			(tracks not_allowed)
			(vias allowed)
			(pads allowed)
			(copperpour not_allowed)
			(footprints allowed)
		)
		(placement
			(enabled no)
			(sheetname "")
		)
		(fill
			(thermal_gap 0.5)
			(thermal_bridge_width 0.5)
			(island_removal_mode 0)
		)
		(polygon
			(pts
				(arc
					(start 402.85416 -106.512614)
					(mid 402.39696 -106.055414)
					(end 401.93976 -106.512614)
				)
				(arc
					(start 401.93976 -107.376214)
					(mid 402.39696 -107.833414)
					(end 402.85416 -107.376214)
				)
			)
		)
	)
	(zone
		(layers "F.Cu" "B.Cu" "In1.Cu" "In2.Cu" "In3.Cu" "In4.Cu" "In5.Cu" "In6.Cu"
			"In7.Cu" "In8.Cu" "In9.Cu" "In10.Cu" "In11.Cu" "In12.Cu" "In13.Cu" "In14.Cu"
			"In15.Cu" "In16.Cu"
		)
		(hatch none 0.5)
		(connect_pads
			(clearance 0)
		)
		(min_thickness 0.25)
		(keepout
			(tracks not_allowed)
			(vias allowed)
			(pads allowed)
			(copperpour not_allowed)
			(footprints allowed)
		)
		(placement
			(enabled no)
			(sheetname "")
		)
		(fill
			(thermal_gap 0.5)
			(thermal_bridge_width 0.5)
			(island_removal_mode 0)
		)
		(polygon
			(pts
				(arc
					(start 168.404032 -351.230438)
					(mid 168.023032 -351.611438)
					(end 168.404032 -351.992438)
				)
				(arc
					(start 169.267632 -351.992438)
					(mid 169.648632 -351.611438)
					(end 169.267632 -351.230438)
				)
			)
		)
	)
	(zone
		(layers "F.Cu" "B.Cu" "In1.Cu" "In2.Cu" "In3.Cu" "In4.Cu" "In5.Cu" "In6.Cu"
			"In7.Cu" "In8.Cu" "In9.Cu" "In10.Cu" "In11.Cu" "In12.Cu" "In13.Cu" "In14.Cu"
			"In15.Cu" "In16.Cu"
		)
		(hatch none 0.5)
		(connect_pads
			(clearance 0)
		)
		(min_thickness 0.25)
		(keepout
			(tracks not_allowed)
			(vias allowed)
			(pads allowed)
			(copperpour not_allowed)
			(footprints allowed)
		)
		(placement
			(enabled no)
			(sheetname "")
		)
		(fill
			(thermal_gap 0.5)
			(thermal_bridge_width 0.5)
			(island_removal_mode 0)
		)
		(polygon
			(pts
				(arc
					(start 407.053288 -34.52241)
					(mid 407.510488 -34.97961)
					(end 407.967688 -34.52241)
				)
				(arc
					(start 407.967688 -33.65881)
					(mid 407.510488 -33.20161)
					(end 407.053288 -33.65881)
				)
			)
		)
	)
	(zone
		(layers "F.Cu" "B.Cu" "In1.Cu" "In2.Cu" "In3.Cu" "In4.Cu" "In5.Cu" "In6.Cu"
			"In7.Cu" "In8.Cu" "In9.Cu" "In10.Cu" "In11.Cu" "In12.Cu" "In13.Cu" "In14.Cu"
			"In15.Cu" "In16.Cu"
		)
		(hatch none 0.5)
		(connect_pads
			(clearance 0)
		)
		(min_thickness 0.25)
		(keepout
			(tracks not_allowed)
			(vias allowed)
			(pads allowed)
			(copperpour not_allowed)
			(footprints allowed)
		)
		(placement
			(enabled no)
			(sheetname "")
		)
		(fill
			(thermal_gap 0.5)
			(thermal_bridge_width 0.5)
			(island_removal_mode 0)
		)
		(polygon
			(pts
				(arc
					(start 162.186112 -348.20479)
					(mid 161.805112 -348.58579)
					(end 162.186112 -348.96679)
				)
				(arc
					(start 163.049712 -348.96679)
					(mid 163.430712 -348.58579)
					(end 163.049712 -348.20479)
				)
			)
		)
	)
	(zone
		(layers "F.Cu" "B.Cu" "In1.Cu" "In2.Cu" "In3.Cu" "In4.Cu" "In5.Cu" "In6.Cu"
			"In7.Cu" "In8.Cu" "In9.Cu" "In10.Cu" "In11.Cu" "In12.Cu" "In13.Cu" "In14.Cu"
			"In15.Cu" "In16.Cu"
		)
		(hatch none 0.5)
		(connect_pads
			(clearance 0)
		)
		(min_thickness 0.25)
		(keepout
			(tracks not_allowed)
			(vias allowed)
			(pads allowed)
			(copperpour not_allowed)
			(footprints allowed)
		)
		(placement
			(enabled no)
			(sheetname "")
		)
		(fill
			(thermal_gap 0.5)
			(thermal_bridge_width 0.5)
			(island_removal_mode 0)
		)
		(polygon
			(pts
				(arc
					(start 66.60007 -123.16714)
					(mid 67.05727 -123.62434)
					(end 67.51447 -123.16714)
				)
				(arc
					(start 67.51447 -122.30354)
					(mid 67.05727 -121.84634)
					(end 66.60007 -122.30354)
				)
			)
		)
	)
	(zone
		(layers "F.Cu" "B.Cu" "In1.Cu" "In2.Cu" "In3.Cu" "In4.Cu" "In5.Cu" "In6.Cu"
			"In7.Cu" "In8.Cu" "In9.Cu" "In10.Cu" "In11.Cu" "In12.Cu" "In13.Cu" "In14.Cu"
			"In15.Cu" "In16.Cu"
		)
		(hatch none 0.5)
		(connect_pads
			(clearance 0)
		)
		(min_thickness 0.25)
		(keepout
			(tracks not_allowed)
			(vias allowed)
			(pads allowed)
			(copperpour not_allowed)
			(footprints allowed)
		)
		(placement
			(enabled no)
			(sheetname "")
		)
		(fill
			(thermal_gap 0.5)
			(thermal_bridge_width 0.5)
			(island_removal_mode 0)
		)
		(polygon
			(pts
				(arc
					(start 119.901208 -369.928902)
					(mid 119.916087 -369.892981)
					(end 119.952008 -369.878102)
				)
				(arc
					(start 120.668288 -369.878102)
					(mid 120.704209 -369.892981)
					(end 120.719088 -369.928902)
				)
				(arc
					(start 120.719088 -372.351554)
					(mid 120.704209 -372.387475)
					(end 120.668288 -372.402354)
				)
				(arc
					(start 119.952008 -372.402354)
					(mid 119.916087 -372.387475)
					(end 119.901208 -372.351554)
				)
			)
		)
	)
	(zone
		(layers "F.Cu" "B.Cu" "In1.Cu" "In2.Cu" "In3.Cu" "In4.Cu" "In5.Cu" "In6.Cu"
			"In7.Cu" "In8.Cu" "In9.Cu" "In10.Cu" "In11.Cu" "In12.Cu" "In13.Cu" "In14.Cu"
			"In15.Cu" "In16.Cu"
		)
		(hatch none 0.5)
		(connect_pads
			(clearance 0)
		)
		(min_thickness 0.25)
		(keepout
			(tracks not_allowed)
			(vias allowed)
			(pads allowed)
			(copperpour not_allowed)
			(footprints allowed)
		)
		(placement
			(enabled no)
			(sheetname "")
		)
		(fill
			(thermal_gap 0.5)
			(thermal_bridge_width 0.5)
			(island_removal_mode 0)
		)
		(polygon
			(pts
				(arc
					(start 284.899862 -132.232908)
					(mid 284.442662 -131.775708)
					(end 283.985462 -132.232908)
				)
				(arc
					(start 283.985462 -133.096508)
					(mid 284.442662 -133.553708)
					(end 284.899862 -133.096508)
				)
			)
		)
	)
	(zone
		(layers "F.Cu" "B.Cu" "In1.Cu" "In2.Cu" "In3.Cu" "In4.Cu" "In5.Cu" "In6.Cu"
			"In7.Cu" "In8.Cu" "In9.Cu" "In10.Cu" "In11.Cu" "In12.Cu" "In13.Cu" "In14.Cu"
			"In15.Cu" "In16.Cu"
		)
		(hatch none 0.5)
		(connect_pads
			(clearance 0)
		)
		(min_thickness 0.25)
		(keepout
			(tracks not_allowed)
			(vias allowed)
			(pads allowed)
			(copperpour not_allowed)
			(footprints allowed)
		)
		(placement
			(enabled no)
			(sheetname "")
		)
		(fill
			(thermal_gap 0.5)
			(thermal_bridge_width 0.5)
			(island_removal_mode 0)
		)
		(polygon
			(pts
				(arc
					(start 45.101002 -395.92885)
					(mid 45.115881 -395.892929)
					(end 45.151802 -395.87805)
				)
				(arc
					(start 45.868082 -395.87805)
					(mid 45.904003 -395.892929)
					(end 45.918882 -395.92885)
				)
				(arc
					(start 45.918882 -398.351502)
					(mid 45.904003 -398.387423)
					(end 45.868082 -398.402302)
				)
				(arc
					(start 45.151802 -398.402302)
					(mid 45.115881 -398.387423)
					(end 45.101002 -398.351502)
				)
			)
		)
	)
	(zone
		(layers "F.Cu" "B.Cu" "In1.Cu" "In2.Cu" "In3.Cu" "In4.Cu" "In5.Cu" "In6.Cu"
			"In7.Cu" "In8.Cu" "In9.Cu" "In10.Cu" "In11.Cu" "In12.Cu" "In13.Cu" "In14.Cu"
			"In15.Cu" "In16.Cu"
		)
		(hatch none 0.5)
		(connect_pads
			(clearance 0)
		)
		(min_thickness 0.25)
		(keepout
			(tracks not_allowed)
			(vias allowed)
			(pads allowed)
			(copperpour not_allowed)
			(footprints allowed)
		)
		(placement
			(enabled no)
			(sheetname "")
		)
		(fill
			(thermal_gap 0.5)
			(thermal_bridge_width 0.5)
			(island_removal_mode 0)
		)
		(polygon
			(pts
				(arc
					(start 25.550368 -342.058498)
					(mid 25.169368 -342.439498)
					(end 25.550368 -342.820498)
				)
				(arc
					(start 26.413968 -342.820498)
					(mid 26.794968 -342.439498)
					(end 26.413968 -342.058498)
				)
			)
		)
	)
	(zone
		(layers "F.Cu" "B.Cu" "In1.Cu" "In2.Cu" "In3.Cu" "In4.Cu" "In5.Cu" "In6.Cu"
			"In7.Cu" "In8.Cu" "In9.Cu" "In10.Cu" "In11.Cu" "In12.Cu" "In13.Cu" "In14.Cu"
			"In15.Cu" "In16.Cu"
		)
		(hatch none 0.5)
		(connect_pads
			(clearance 0)
		)
		(min_thickness 0.25)
		(keepout
			(tracks not_allowed)
			(vias allowed)
			(pads allowed)
			(copperpour not_allowed)
			(footprints allowed)
		)
		(placement
			(enabled no)
			(sheetname "")
		)
		(fill
			(thermal_gap 0.5)
			(thermal_bridge_width 0.5)
			(island_removal_mode 0)
		)
		(polygon
			(pts
				(arc
					(start 130.515868 -345.084146)
					(mid 130.134868 -345.465146)
					(end 130.515868 -345.846146)
				)
				(arc
					(start 131.379468 -345.846146)
					(mid 131.760468 -345.465146)
					(end 131.379468 -345.084146)
				)
			)
		)
	)
	(zone
		(layers "F.Cu" "B.Cu" "In1.Cu" "In2.Cu" "In3.Cu" "In4.Cu" "In5.Cu" "In6.Cu"
			"In7.Cu" "In8.Cu" "In9.Cu" "In10.Cu" "In11.Cu" "In12.Cu" "In13.Cu" "In14.Cu"
			"In15.Cu" "In16.Cu"
		)
		(hatch none 0.5)
		(connect_pads
			(clearance 0)
		)
		(min_thickness 0.25)
		(keepout
			(tracks not_allowed)
			(vias allowed)
			(pads allowed)
			(copperpour not_allowed)
			(footprints allowed)
		)
		(placement
			(enabled no)
			(sheetname "")
		)
		(fill
			(thermal_gap 0.5)
			(thermal_bridge_width 0.5)
			(island_removal_mode 0)
		)
		(polygon
			(pts
				(arc
					(start 42.901108 -371.028722)
					(mid 42.915987 -370.992801)
					(end 42.951908 -370.977922)
				)
				(arc
					(start 43.668188 -370.977922)
					(mid 43.704109 -370.992801)
					(end 43.718988 -371.028722)
				)
				(arc
					(start 43.718988 -373.451374)
					(mid 43.704109 -373.487295)
					(end 43.668188 -373.502174)
				)
				(arc
					(start 42.951908 -373.502174)
					(mid 42.915987 -373.487295)
					(end 42.901108 -373.451374)
				)
			)
		)
	)
	(zone
		(layers "F.Cu" "B.Cu" "In1.Cu" "In2.Cu" "In3.Cu" "In4.Cu" "In5.Cu" "In6.Cu"
			"In7.Cu" "In8.Cu" "In9.Cu" "In10.Cu" "In11.Cu" "In12.Cu" "In13.Cu" "In14.Cu"
			"In15.Cu" "In16.Cu"
		)
		(hatch none 0.5)
		(connect_pads
			(clearance 0)
		)
		(min_thickness 0.25)
		(keepout
			(tracks not_allowed)
			(vias allowed)
			(pads allowed)
			(copperpour not_allowed)
			(footprints allowed)
		)
		(placement
			(enabled no)
			(sheetname "")
		)
		(fill
			(thermal_gap 0.5)
			(thermal_bridge_width 0.5)
			(island_removal_mode 0)
		)
		(polygon
			(pts
				(arc
					(start 289.659822 -345.084146)
					(mid 289.278822 -345.465146)
					(end 289.659822 -345.846146)
				)
				(arc
					(start 290.523422 -345.846146)
					(mid 290.904422 -345.465146)
					(end 290.523422 -345.084146)
				)
			)
		)
	)
	(zone
		(layers "F.Cu" "B.Cu" "In1.Cu" "In2.Cu" "In3.Cu" "In4.Cu" "In5.Cu" "In6.Cu"
			"In7.Cu" "In8.Cu" "In9.Cu" "In10.Cu" "In11.Cu" "In12.Cu" "In13.Cu" "In14.Cu"
			"In15.Cu" "In16.Cu"
		)
		(hatch none 0.5)
		(connect_pads
			(clearance 0)
		)
		(min_thickness 0.25)
		(keepout
			(tracks not_allowed)
			(vias allowed)
			(pads allowed)
			(copperpour not_allowed)
			(footprints allowed)
		)
		(placement
			(enabled no)
			(sheetname "")
		)
		(fill
			(thermal_gap 0.5)
			(thermal_bridge_width 0.5)
			(island_removal_mode 0)
		)
		(polygon
			(pts
				(arc
					(start 141.024102 -394.305282)
					(mid 141.04642 -394.2514)
					(end 141.100302 -394.229082)
				)
				(xy 154.425904 -394.229082) (xy 154.575764 -394.378942)
				(arc
					(start 154.575764 -417.371276)
					(mid 154.553446 -417.425158)
					(end 154.499564 -417.447476)
				)
				(arc
					(start 141.100302 -417.447476)
					(mid 141.04642 -417.425158)
					(end 141.024102 -417.371276)
				)
			)
		)
	)
	(zone
		(layers "F.Cu" "B.Cu" "In1.Cu" "In2.Cu" "In3.Cu" "In4.Cu" "In5.Cu" "In6.Cu"
			"In7.Cu" "In8.Cu" "In9.Cu" "In10.Cu" "In11.Cu" "In12.Cu" "In13.Cu" "In14.Cu"
			"In15.Cu" "In16.Cu"
		)
		(hatch none 0.5)
		(connect_pads
			(clearance 0)
		)
		(min_thickness 0.25)
		(keepout
			(tracks not_allowed)
			(vias allowed)
			(pads allowed)
			(copperpour not_allowed)
			(footprints allowed)
		)
		(placement
			(enabled no)
			(sheetname "")
		)
		(fill
			(thermal_gap 0.5)
			(thermal_bridge_width 0.5)
			(island_removal_mode 0)
		)
		(polygon
			(pts
				(arc
					(start 180.839872 -342.058498)
					(mid 180.458872 -342.439498)
					(end 180.839872 -342.820498)
				)
				(arc
					(start 181.703472 -342.820498)
					(mid 182.084472 -342.439498)
					(end 181.703472 -342.058498)
				)
			)
		)
	)
	(zone
		(layers "F.Cu" "B.Cu" "In1.Cu" "In2.Cu" "In3.Cu" "In4.Cu" "In5.Cu" "In6.Cu"
			"In7.Cu" "In8.Cu" "In9.Cu" "In10.Cu" "In11.Cu" "In12.Cu" "In13.Cu" "In14.Cu"
			"In15.Cu" "In16.Cu"
		)
		(hatch none 0.5)
		(connect_pads
			(clearance 0)
		)
		(min_thickness 0.25)
		(keepout
			(tracks not_allowed)
			(vias allowed)
			(pads allowed)
			(copperpour not_allowed)
			(footprints allowed)
		)
		(placement
			(enabled no)
			(sheetname "")
		)
		(fill
			(thermal_gap 0.5)
			(thermal_bridge_width 0.5)
			(island_removal_mode 0)
		)
		(polygon
			(pts
				(arc
					(start 302.48098 -371.028722)
					(mid 302.495859 -370.992801)
					(end 302.53178 -370.977922)
				)
				(arc
					(start 303.24806 -370.977922)
					(mid 303.283981 -370.992801)
					(end 303.29886 -371.028722)
				)
				(arc
					(start 303.29886 -373.451374)
					(mid 303.283981 -373.487295)
					(end 303.24806 -373.502174)
				)
				(arc
					(start 302.53178 -373.502174)
					(mid 302.495859 -373.487295)
					(end 302.48098 -373.451374)
				)
			)
		)
	)
	(zone
		(layers "F.Cu" "B.Cu" "In1.Cu" "In2.Cu" "In3.Cu" "In4.Cu" "In5.Cu" "In6.Cu"
			"In7.Cu" "In8.Cu" "In9.Cu" "In10.Cu" "In11.Cu" "In12.Cu" "In13.Cu" "In14.Cu"
			"In15.Cu" "In16.Cu"
		)
		(hatch none 0.5)
		(connect_pads
			(clearance 0)
		)
		(min_thickness 0.25)
		(keepout
			(tracks not_allowed)
			(vias allowed)
			(pads allowed)
			(copperpour not_allowed)
			(footprints allowed)
		)
		(placement
			(enabled no)
			(sheetname "")
		)
		(fill
			(thermal_gap 0.5)
			(thermal_bridge_width 0.5)
			(island_removal_mode 0)
		)
		(polygon
			(pts
				(arc
					(start 419.08095 -395.92885)
					(mid 419.095829 -395.892929)
					(end 419.13175 -395.87805)
				)
				(arc
					(start 419.84803 -395.87805)
					(mid 419.883951 -395.892929)
					(end 419.89883 -395.92885)
				)
				(arc
					(start 419.89883 -398.351502)
					(mid 419.883951 -398.387423)
					(end 419.84803 -398.402302)
				)
				(arc
					(start 419.13175 -398.402302)
					(mid 419.095829 -398.387423)
					(end 419.08095 -398.351502)
				)
			)
		)
	)
	(zone
		(layers "F.Cu" "B.Cu" "In1.Cu" "In2.Cu" "In3.Cu" "In4.Cu" "In5.Cu" "In6.Cu"
			"In7.Cu" "In8.Cu" "In9.Cu" "In10.Cu" "In11.Cu" "In12.Cu" "In13.Cu" "In14.Cu"
			"In15.Cu" "In16.Cu"
		)
		(hatch none 0.5)
		(connect_pads
			(clearance 0)
		)
		(min_thickness 0.25)
		(keepout
			(tracks not_allowed)
			(vias allowed)
			(pads allowed)
			(copperpour not_allowed)
			(footprints allowed)
		)
		(placement
			(enabled no)
			(sheetname "")
		)
		(fill
			(thermal_gap 0.5)
			(thermal_bridge_width 0.5)
			(island_removal_mode 0)
		)
		(polygon
			(pts
				(arc
					(start 337.681062 -378.828554)
					(mid 337.695941 -378.792633)
					(end 337.731862 -378.777754)
				)
				(arc
					(start 338.448142 -378.777754)
					(mid 338.484063 -378.792633)
					(end 338.498942 -378.828554)
				)
				(arc
					(start 338.498942 -381.251206)
					(mid 338.484063 -381.287127)
					(end 338.448142 -381.302006)
				)
				(arc
					(start 337.731862 -381.302006)
					(mid 337.695941 -381.287127)
					(end 337.681062 -381.251206)
				)
			)
		)
	)
	(zone
		(layers "F.Cu" "B.Cu" "In1.Cu" "In2.Cu" "In3.Cu" "In4.Cu" "In5.Cu" "In6.Cu"
			"In7.Cu" "In8.Cu" "In9.Cu" "In10.Cu" "In11.Cu" "In12.Cu" "In13.Cu" "In14.Cu"
			"In15.Cu" "In16.Cu"
		)
		(hatch none 0.5)
		(connect_pads
			(clearance 0)
		)
		(min_thickness 0.25)
		(keepout
			(tracks not_allowed)
			(vias allowed)
			(pads allowed)
			(copperpour not_allowed)
			(footprints allowed)
		)
		(placement
			(enabled no)
			(sheetname "")
		)
		(fill
			(thermal_gap 0.5)
			(thermal_bridge_width 0.5)
			(island_removal_mode 0)
		)
		(polygon
			(pts
				(arc
					(start 177.730912 -354.351082)
					(mid 177.349912 -354.732082)
					(end 177.730912 -355.113082)
				)
				(arc
					(start 178.594512 -355.113082)
					(mid 178.975512 -354.732082)
					(end 178.594512 -354.351082)
				)
			)
		)
	)
	(zone
		(layers "F.Cu" "B.Cu" "In1.Cu" "In2.Cu" "In3.Cu" "In4.Cu" "In5.Cu" "In6.Cu"
			"In7.Cu" "In8.Cu" "In9.Cu" "In10.Cu" "In11.Cu" "In12.Cu" "In13.Cu" "In14.Cu"
			"In15.Cu" "In16.Cu"
		)
		(hatch none 0.5)
		(connect_pads
			(clearance 0)
		)
		(min_thickness 0.25)
		(keepout
			(tracks not_allowed)
			(vias allowed)
			(pads allowed)
			(copperpour not_allowed)
			(footprints allowed)
		)
		(placement
			(enabled no)
			(sheetname "")
		)
		(fill
			(thermal_gap 0.5)
			(thermal_bridge_width 0.5)
			(island_removal_mode 0)
		)
		(polygon
			(pts
				(arc
					(start 427.948852 -348.20479)
					(mid 427.567852 -348.58579)
					(end 427.948852 -348.96679)
				)
				(arc
					(start 428.812452 -348.96679)
					(mid 429.193452 -348.58579)
					(end 428.812452 -348.20479)
				)
			)
		)
	)
	(zone
		(layers "F.Cu" "B.Cu" "In1.Cu" "In2.Cu" "In3.Cu" "In4.Cu" "In5.Cu" "In6.Cu"
			"In7.Cu" "In8.Cu" "In9.Cu" "In10.Cu" "In11.Cu" "In12.Cu" "In13.Cu" "In14.Cu"
			"In15.Cu" "In16.Cu"
		)
		(hatch none 0.5)
		(connect_pads
			(clearance 0)
		)
		(min_thickness 0.25)
		(keepout
			(tracks not_allowed)
			(vias allowed)
			(pads allowed)
			(copperpour not_allowed)
			(footprints allowed)
		)
		(placement
			(enabled no)
			(sheetname "")
		)
		(fill
			(thermal_gap 0.5)
			(thermal_bridge_width 0.5)
			(island_removal_mode 0)
		)
		(polygon
			(pts
				(arc
					(start 124.297948 -342.058498)
					(mid 123.916948 -342.439498)
					(end 124.297948 -342.820498)
				)
				(arc
					(start 125.161548 -342.820498)
					(mid 125.542548 -342.439498)
					(end 125.161548 -342.058498)
				)
			)
		)
	)
	(zone
		(layers "F.Cu" "B.Cu" "In1.Cu" "In2.Cu" "In3.Cu" "In4.Cu" "In5.Cu" "In6.Cu"
			"In7.Cu" "In8.Cu" "In9.Cu" "In10.Cu" "In11.Cu" "In12.Cu" "In13.Cu" "In14.Cu"
			"In15.Cu" "In16.Cu"
		)
		(hatch none 0.5)
		(connect_pads
			(clearance 0)
		)
		(min_thickness 0.25)
		(keepout
			(tracks not_allowed)
			(vias allowed)
			(pads allowed)
			(copperpour not_allowed)
			(footprints allowed)
		)
		(placement
			(enabled no)
			(sheetname "")
		)
		(fill
			(thermal_gap 0.5)
			(thermal_bridge_width 0.5)
			(island_removal_mode 0)
		)
		(polygon
			(pts
				(arc
					(start 58.753248 -34.52241)
					(mid 59.210448 -34.97961)
					(end 59.667648 -34.52241)
				)
				(arc
					(start 59.667648 -33.65881)
					(mid 59.210448 -33.20161)
					(end 58.753248 -33.65881)
				)
			)
		)
	)
	(zone
		(layers "F.Cu" "B.Cu" "In1.Cu" "In2.Cu" "In3.Cu" "In4.Cu" "In5.Cu" "In6.Cu"
			"In7.Cu" "In8.Cu" "In9.Cu" "In10.Cu" "In11.Cu" "In12.Cu" "In13.Cu" "In14.Cu"
			"In15.Cu" "In16.Cu"
		)
		(hatch none 0.5)
		(connect_pads
			(clearance 0)
		)
		(min_thickness 0.25)
		(keepout
			(tracks not_allowed)
			(vias allowed)
			(pads allowed)
			(copperpour not_allowed)
			(footprints allowed)
		)
		(placement
			(enabled no)
			(sheetname "")
		)
		(fill
			(thermal_gap 0.5)
			(thermal_bridge_width 0.5)
			(island_removal_mode 0)
		)
		(polygon
			(pts
				(arc
					(start 126.501144 -404.828756)
					(mid 126.516023 -404.792835)
					(end 126.551944 -404.777956)
				)
				(arc
					(start 127.268224 -404.777956)
					(mid 127.304145 -404.792835)
					(end 127.319024 -404.828756)
				)
				(arc
					(start 127.319024 -407.251408)
					(mid 127.304145 -407.287329)
					(end 127.268224 -407.302208)
				)
				(arc
					(start 126.551944 -407.302208)
					(mid 126.516023 -407.287329)
					(end 126.501144 -407.251408)
				)
			)
		)
	)
	(zone
		(layers "F.Cu" "B.Cu" "In1.Cu" "In2.Cu" "In3.Cu" "In4.Cu" "In5.Cu" "In6.Cu"
			"In7.Cu" "In8.Cu" "In9.Cu" "In10.Cu" "In11.Cu" "In12.Cu" "In13.Cu" "In14.Cu"
			"In15.Cu" "In16.Cu"
		)
		(hatch none 0.5)
		(connect_pads
			(clearance 0)
		)
		(min_thickness 0.25)
		(keepout
			(tracks not_allowed)
			(vias allowed)
			(pads allowed)
			(copperpour not_allowed)
			(footprints allowed)
		)
		(placement
			(enabled no)
			(sheetname "")
		)
		(fill
			(thermal_gap 0.5)
			(thermal_bridge_width 0.5)
			(island_removal_mode 0)
		)
		(polygon
			(pts
				(arc
					(start 2.484628 -387.51129)
					(mid 2.027428 -387.05409)
					(end 1.570228 -387.51129)
				)
				(arc
					(start 1.570228 -388.37489)
					(mid 2.027428 -388.83209)
					(end 2.484628 -388.37489)
				)
			)
		)
	)
	(zone
		(layers "F.Cu" "B.Cu" "In1.Cu" "In2.Cu" "In3.Cu" "In4.Cu" "In5.Cu" "In6.Cu"
			"In7.Cu" "In8.Cu" "In9.Cu" "In10.Cu" "In11.Cu" "In12.Cu" "In13.Cu" "In14.Cu"
			"In15.Cu" "In16.Cu"
		)
		(hatch none 0.5)
		(connect_pads
			(clearance 0)
		)
		(min_thickness 0.25)
		(keepout
			(tracks not_allowed)
			(vias allowed)
			(pads allowed)
			(copperpour not_allowed)
			(footprints allowed)
		)
		(placement
			(enabled no)
			(sheetname "")
		)
		(fill
			(thermal_gap 0.5)
			(thermal_bridge_width 0.5)
			(island_removal_mode 0)
		)
		(polygon
			(pts
				(arc
					(start 22.441408 -348.20479)
					(mid 22.060408 -348.58579)
					(end 22.441408 -348.96679)
				)
				(arc
					(start 23.305008 -348.96679)
					(mid 23.686008 -348.58579)
					(end 23.305008 -348.20479)
				)
			)
		)
	)
	(zone
		(layers "F.Cu" "B.Cu" "In1.Cu" "In2.Cu" "In3.Cu" "In4.Cu" "In5.Cu" "In6.Cu"
			"In7.Cu" "In8.Cu" "In9.Cu" "In10.Cu" "In11.Cu" "In12.Cu" "In13.Cu" "In14.Cu"
			"In15.Cu" "In16.Cu"
		)
		(hatch none 0.5)
		(connect_pads
			(clearance 0)
		)
		(min_thickness 0.25)
		(keepout
			(tracks not_allowed)
			(vias allowed)
			(pads allowed)
			(copperpour not_allowed)
			(footprints allowed)
		)
		(placement
			(enabled no)
			(sheetname "")
		)
		(fill
			(thermal_gap 0.5)
			(thermal_bridge_width 0.5)
			(island_removal_mode 0)
		)
		(polygon
			(pts
				(arc
					(start 388.28091 -377.728734)
					(mid 388.295789 -377.692813)
					(end 388.33171 -377.677934)
				)
				(arc
					(start 389.04799 -377.677934)
					(mid 389.083911 -377.692813)
					(end 389.09879 -377.728734)
				)
				(arc
					(start 389.09879 -380.151386)
					(mid 389.083911 -380.187307)
					(end 389.04799 -380.202186)
				)
				(arc
					(start 388.33171 -380.202186)
					(mid 388.295789 -380.187307)
					(end 388.28091 -380.151386)
				)
			)
		)
	)
	(zone
		(layers "F.Cu" "B.Cu" "In1.Cu" "In2.Cu" "In3.Cu" "In4.Cu" "In5.Cu" "In6.Cu"
			"In7.Cu" "In8.Cu" "In9.Cu" "In10.Cu" "In11.Cu" "In12.Cu" "In13.Cu" "In14.Cu"
			"In15.Cu" "In16.Cu"
		)
		(hatch none 0.5)
		(connect_pads
			(clearance 0)
		)
		(min_thickness 0.25)
		(keepout
			(tracks not_allowed)
			(vias allowed)
			(pads allowed)
			(copperpour not_allowed)
			(footprints allowed)
		)
		(placement
			(enabled no)
			(sheetname "")
		)
		(fill
			(thermal_gap 0.5)
			(thermal_bridge_width 0.5)
			(island_removal_mode 0)
		)
		(polygon
			(pts
				(arc
					(start 404.034498 20.143724)
					(mid 404.415498 19.762724)
					(end 404.796498 20.143724)
				)
				(arc
					(start 404.796498 21.007324)
					(mid 404.415498 21.388324)
					(end 404.034498 21.007324)
				)
			)
		)
	)
	(zone
		(layers "F.Cu" "B.Cu" "In1.Cu" "In2.Cu" "In3.Cu" "In4.Cu" "In5.Cu" "In6.Cu"
			"In7.Cu" "In8.Cu" "In9.Cu" "In10.Cu" "In11.Cu" "In12.Cu" "In13.Cu" "In14.Cu"
			"In15.Cu" "In16.Cu"
		)
		(hatch none 0.5)
		(connect_pads
			(clearance 0)
		)
		(min_thickness 0.25)
		(keepout
			(tracks not_allowed)
			(vias allowed)
			(pads allowed)
			(copperpour not_allowed)
			(footprints allowed)
		)
		(placement
			(enabled no)
			(sheetname "")
		)
		(fill
			(thermal_gap 0.5)
			(thermal_bridge_width 0.5)
			(island_removal_mode 0)
		)
		(polygon
			(pts
				(arc
					(start 76.917042 -342.058498)
					(mid 76.536042 -342.439498)
					(end 76.917042 -342.820498)
				)
				(arc
					(start 77.780642 -342.820498)
					(mid 78.161642 -342.439498)
					(end 77.780642 -342.058498)
				)
			)
		)
	)
	(zone
		(layers "F.Cu" "B.Cu" "In1.Cu" "In2.Cu" "In3.Cu" "In4.Cu" "In5.Cu" "In6.Cu"
			"In7.Cu" "In8.Cu" "In9.Cu" "In10.Cu" "In11.Cu" "In12.Cu" "In13.Cu" "In14.Cu"
			"In15.Cu" "In16.Cu"
		)
		(hatch none 0.5)
		(connect_pads
			(clearance 0)
		)
		(min_thickness 0.25)
		(keepout
			(tracks not_allowed)
			(vias allowed)
			(pads allowed)
			(copperpour not_allowed)
			(footprints allowed)
		)
		(placement
			(enabled no)
			(sheetname "")
		)
		(fill
			(thermal_gap 0.5)
			(thermal_bridge_width 0.5)
			(island_removal_mode 0)
		)
		(polygon
			(pts
				(arc
					(start 434.166772 -354.351082)
					(mid 433.785772 -354.732082)
					(end 434.166772 -355.113082)
				)
				(arc
					(start 435.030372 -355.113082)
					(mid 435.411372 -354.732082)
					(end 435.030372 -354.351082)
				)
			)
		)
	)
	(zone
		(layers "F.Cu" "B.Cu" "In1.Cu" "In2.Cu" "In3.Cu" "In4.Cu" "In5.Cu" "In6.Cu"
			"In7.Cu" "In8.Cu" "In9.Cu" "In10.Cu" "In11.Cu" "In12.Cu" "In13.Cu" "In14.Cu"
			"In15.Cu" "In16.Cu"
		)
		(hatch none 0.5)
		(connect_pads
			(clearance 0)
		)
		(min_thickness 0.25)
		(keepout
			(tracks not_allowed)
			(vias allowed)
			(pads allowed)
			(copperpour not_allowed)
			(footprints allowed)
		)
		(placement
			(enabled no)
			(sheetname "")
		)
		(fill
			(thermal_gap 0.5)
			(thermal_bridge_width 0.5)
			(island_removal_mode 0)
		)
		(polygon
			(pts
				(arc
					(start 337.374484 -342.058498)
					(mid 336.993484 -342.439498)
					(end 337.374484 -342.820498)
				)
				(arc
					(start 338.238084 -342.820498)
					(mid 338.619084 -342.439498)
					(end 338.238084 -342.058498)
				)
			)
		)
	)
	(zone
		(layers "F.Cu" "B.Cu" "In1.Cu" "In2.Cu" "In3.Cu" "In4.Cu" "In5.Cu" "In6.Cu"
			"In7.Cu" "In8.Cu" "In9.Cu" "In10.Cu" "In11.Cu" "In12.Cu" "In13.Cu" "In14.Cu"
			"In15.Cu" "In16.Cu"
		)
		(hatch none 0.5)
		(connect_pads
			(clearance 0)
		)
		(min_thickness 0.25)
		(keepout
			(tracks not_allowed)
			(vias allowed)
			(pads allowed)
			(copperpour not_allowed)
			(footprints allowed)
		)
		(placement
			(enabled no)
			(sheetname "")
		)
		(fill
			(thermal_gap 0.5)
			(thermal_bridge_width 0.5)
			(island_removal_mode 0)
		)
		(polygon
			(pts
				(arc
					(start 269.51051 -103.777796)
					(mid 269.96771 -104.234996)
					(end 270.42491 -103.777796)
				)
				(arc
					(start 270.42491 -102.914196)
					(mid 269.96771 -102.456996)
					(end 269.51051 -102.914196)
				)
			)
		)
	)
	(zone
		(layers "F.Cu" "B.Cu" "In1.Cu" "In2.Cu" "In3.Cu" "In4.Cu" "In5.Cu" "In6.Cu"
			"In7.Cu" "In8.Cu" "In9.Cu" "In10.Cu" "In11.Cu" "In12.Cu" "In13.Cu" "In14.Cu"
			"In15.Cu" "In16.Cu"
		)
		(hatch none 0.5)
		(connect_pads
			(clearance 0)
		)
		(min_thickness 0.25)
		(keepout
			(tracks not_allowed)
			(vias allowed)
			(pads allowed)
			(copperpour not_allowed)
			(footprints allowed)
		)
		(placement
			(enabled no)
			(sheetname "")
		)
		(fill
			(thermal_gap 0.5)
			(thermal_bridge_width 0.5)
			(island_removal_mode 0)
		)
		(polygon
			(pts
				(arc
					(start 383.881122 -395.92885)
					(mid 383.896001 -395.892929)
					(end 383.931922 -395.87805)
				)
				(arc
					(start 384.648202 -395.87805)
					(mid 384.684123 -395.892929)
					(end 384.699002 -395.92885)
				)
				(arc
					(start 384.699002 -398.351502)
					(mid 384.684123 -398.387423)
					(end 384.648202 -398.402302)
				)
				(arc
					(start 383.931922 -398.402302)
					(mid 383.896001 -398.387423)
					(end 383.881122 -398.351502)
				)
			)
		)
	)
	(zone
		(layers "F.Cu" "B.Cu" "In1.Cu" "In2.Cu" "In3.Cu" "In4.Cu" "In5.Cu" "In6.Cu"
			"In7.Cu" "In8.Cu" "In9.Cu" "In10.Cu" "In11.Cu" "In12.Cu" "In13.Cu" "In14.Cu"
			"In15.Cu" "In16.Cu"
		)
		(hatch none 0.5)
		(connect_pads
			(clearance 0)
		)
		(min_thickness 0.25)
		(keepout
			(tracks not_allowed)
			(vias allowed)
			(pads allowed)
			(copperpour not_allowed)
			(footprints allowed)
		)
		(placement
			(enabled no)
			(sheetname "")
		)
		(fill
			(thermal_gap 0.5)
			(thermal_bridge_width 0.5)
			(island_removal_mode 0)
		)
		(polygon
			(pts
				(arc
					(start 419.148006 -32.714184)
					(mid 419.605206 -33.171384)
					(end 420.062406 -32.714184)
				)
				(arc
					(start 420.062406 -31.850584)
					(mid 419.605206 -31.393384)
					(end 419.148006 -31.850584)
				)
			)
		)
	)
	(zone
		(layers "F.Cu" "B.Cu" "In1.Cu" "In2.Cu" "In3.Cu" "In4.Cu" "In5.Cu" "In6.Cu"
			"In7.Cu" "In8.Cu" "In9.Cu" "In10.Cu" "In11.Cu" "In12.Cu" "In13.Cu" "In14.Cu"
			"In15.Cu" "In16.Cu"
		)
		(hatch none 0.5)
		(connect_pads
			(clearance 0)
		)
		(min_thickness 0.25)
		(keepout
			(tracks not_allowed)
			(vias allowed)
			(pads allowed)
			(copperpour not_allowed)
			(footprints allowed)
		)
		(placement
			(enabled no)
			(sheetname "")
		)
		(fill
			(thermal_gap 0.5)
			(thermal_bridge_width 0.5)
			(island_removal_mode 0)
		)
		(polygon
			(pts
				(arc
					(start 86.90102 -374.928638)
					(mid 86.915899 -374.892717)
					(end 86.95182 -374.877838)
				)
				(arc
					(start 87.6681 -374.877838)
					(mid 87.704021 -374.892717)
					(end 87.7189 -374.928638)
				)
				(arc
					(start 87.7189 -377.35129)
					(mid 87.704021 -377.387211)
					(end 87.6681 -377.40209)
				)
				(arc
					(start 86.95182 -377.40209)
					(mid 86.915899 -377.387211)
					(end 86.90102 -377.35129)
				)
			)
		)
	)
	(zone
		(layers "F.Cu" "B.Cu" "In1.Cu" "In2.Cu" "In3.Cu" "In4.Cu" "In5.Cu" "In6.Cu"
			"In7.Cu" "In8.Cu" "In9.Cu" "In10.Cu" "In11.Cu" "In12.Cu" "In13.Cu" "In14.Cu"
			"In15.Cu" "In16.Cu"
		)
		(hatch none 0.5)
		(connect_pads
			(clearance 0)
		)
		(min_thickness 0.25)
		(keepout
			(tracks not_allowed)
			(vias allowed)
			(pads allowed)
			(copperpour not_allowed)
			(footprints allowed)
		)
		(placement
			(enabled no)
			(sheetname "")
		)
		(fill
			(thermal_gap 0.5)
			(thermal_bridge_width 0.5)
			(island_removal_mode 0)
		)
		(polygon
			(pts
				(arc
					(start 313.274964 -134.369302)
					(mid 313.732164 -134.826502)
					(end 314.189364 -134.369302)
				)
				(arc
					(start 314.189364 -133.505702)
					(mid 313.732164 -133.048502)
					(end 313.274964 -133.505702)
				)
			)
		)
	)
	(zone
		(layers "F.Cu" "B.Cu" "In1.Cu" "In2.Cu" "In3.Cu" "In4.Cu" "In5.Cu" "In6.Cu"
			"In7.Cu" "In8.Cu" "In9.Cu" "In10.Cu" "In11.Cu" "In12.Cu" "In13.Cu" "In14.Cu"
			"In15.Cu" "In16.Cu"
		)
		(hatch none 0.5)
		(connect_pads
			(clearance 0)
		)
		(min_thickness 0.25)
		(keepout
			(tracks not_allowed)
			(vias allowed)
			(pads allowed)
			(copperpour not_allowed)
			(footprints allowed)
		)
		(placement
			(enabled no)
			(sheetname "")
		)
		(fill
			(thermal_gap 0.5)
			(thermal_bridge_width 0.5)
			(island_removal_mode 0)
		)
		(polygon
			(pts
				(arc
					(start 99.490022 -30.92069)
					(mid 99.947222 -31.37789)
					(end 100.404422 -30.92069)
				)
				(arc
					(start 100.404422 -30.05709)
					(mid 99.947222 -29.59989)
					(end 99.490022 -30.05709)
				)
			)
		)
	)
	(zone
		(layers "F.Cu" "B.Cu" "In1.Cu" "In2.Cu" "In3.Cu" "In4.Cu" "In5.Cu" "In6.Cu"
			"In7.Cu" "In8.Cu" "In9.Cu" "In10.Cu" "In11.Cu" "In12.Cu" "In13.Cu" "In14.Cu"
			"In15.Cu" "In16.Cu"
		)
		(hatch none 0.5)
		(connect_pads
			(clearance 0)
		)
		(min_thickness 0.25)
		(keepout
			(tracks not_allowed)
			(vias allowed)
			(pads allowed)
			(copperpour not_allowed)
			(footprints allowed)
		)
		(placement
			(enabled no)
			(sheetname "")
		)
		(fill
			(thermal_gap 0.5)
			(thermal_bridge_width 0.5)
			(island_removal_mode 0)
		)
		(polygon
			(pts
				(arc
					(start 371.18798 -348.20479)
					(mid 370.80698 -348.58579)
					(end 371.18798 -348.96679)
				)
				(arc
					(start 372.05158 -348.96679)
					(mid 372.43258 -348.58579)
					(end 372.05158 -348.20479)
				)
			)
		)
	)
	(zone
		(layers "F.Cu" "B.Cu" "In1.Cu" "In2.Cu" "In3.Cu" "In4.Cu" "In5.Cu" "In6.Cu"
			"In7.Cu" "In8.Cu" "In9.Cu" "In10.Cu" "In11.Cu" "In12.Cu" "In13.Cu" "In14.Cu"
			"In15.Cu" "In16.Cu"
		)
		(hatch none 0.5)
		(connect_pads
			(clearance 0)
		)
		(min_thickness 0.25)
		(keepout
			(tracks not_allowed)
			(vias allowed)
			(pads allowed)
			(copperpour not_allowed)
			(footprints allowed)
		)
		(placement
			(enabled no)
			(sheetname "")
		)
		(fill
			(thermal_gap 0.5)
			(thermal_bridge_width 0.5)
			(island_removal_mode 0)
		)
		(polygon
			(pts
				(arc
					(start 315.611764 -348.20479)
					(mid 315.230764 -348.58579)
					(end 315.611764 -348.96679)
				)
				(arc
					(start 316.475364 -348.96679)
					(mid 316.856364 -348.58579)
					(end 316.475364 -348.20479)
				)
			)
		)
	)
	(zone
		(layers "F.Cu" "B.Cu" "In1.Cu" "In2.Cu" "In3.Cu" "In4.Cu" "In5.Cu" "In6.Cu"
			"In7.Cu" "In8.Cu" "In9.Cu" "In10.Cu" "In11.Cu" "In12.Cu" "In13.Cu" "In14.Cu"
			"In15.Cu" "In16.Cu"
		)
		(hatch none 0.5)
		(connect_pads
			(clearance 0)
		)
		(min_thickness 0.25)
		(keepout
			(tracks not_allowed)
			(vias allowed)
			(pads allowed)
			(copperpour not_allowed)
			(footprints allowed)
		)
		(placement
			(enabled no)
			(sheetname "")
		)
		(fill
			(thermal_gap 0.5)
			(thermal_bridge_width 0.5)
			(island_removal_mode 0)
		)
		(polygon
			(pts
				(arc
					(start 28.659328 -345.084146)
					(mid 28.278328 -345.465146)
					(end 28.659328 -345.846146)
				)
				(arc
					(start 29.522928 -345.846146)
					(mid 29.903928 -345.465146)
					(end 29.522928 -345.084146)
				)
			)
		)
	)
	(zone
		(layers "F.Cu" "B.Cu" "In1.Cu" "In2.Cu" "In3.Cu" "In4.Cu" "In5.Cu" "In6.Cu"
			"In7.Cu" "In8.Cu" "In9.Cu" "In10.Cu" "In11.Cu" "In12.Cu" "In13.Cu" "In14.Cu"
			"In15.Cu" "In16.Cu"
		)
		(hatch none 0.5)
		(connect_pads
			(clearance 0)
		)
		(min_thickness 0.25)
		(keepout
			(tracks not_allowed)
			(vias allowed)
			(pads allowed)
			(copperpour not_allowed)
			(footprints allowed)
		)
		(placement
			(enabled no)
			(sheetname "")
		)
		(fill
			(thermal_gap 0.5)
			(thermal_bridge_width 0.5)
			(island_removal_mode 0)
		)
		(polygon
			(pts
				(arc
					(start 42.901108 -378.828554)
					(mid 42.915987 -378.792633)
					(end 42.951908 -378.777754)
				)
				(arc
					(start 43.668188 -378.777754)
					(mid 43.704109 -378.792633)
					(end 43.718988 -378.828554)
				)
				(arc
					(start 43.718988 -381.251206)
					(mid 43.704109 -381.287127)
					(end 43.668188 -381.302006)
				)
				(arc
					(start 42.951908 -381.302006)
					(mid 42.915987 -381.287127)
					(end 42.901108 -381.251206)
				)
			)
		)
	)
	(zone
		(layers "F.Cu" "B.Cu" "In1.Cu" "In2.Cu" "In3.Cu" "In4.Cu" "In5.Cu" "In6.Cu"
			"In7.Cu" "In8.Cu" "In9.Cu" "In10.Cu" "In11.Cu" "In12.Cu" "In13.Cu" "In14.Cu"
			"In15.Cu" "In16.Cu"
		)
		(hatch none 0.5)
		(connect_pads
			(clearance 0)
		)
		(min_thickness 0.25)
		(keepout
			(tracks not_allowed)
			(vias allowed)
			(pads allowed)
			(copperpour not_allowed)
			(footprints allowed)
		)
		(placement
			(enabled no)
			(sheetname "")
		)
		(fill
			(thermal_gap 0.5)
			(thermal_bridge_width 0.5)
			(island_removal_mode 0)
		)
		(polygon
			(pts
				(arc
					(start 388.28091 -381.628904)
					(mid 388.295789 -381.592983)
					(end 388.33171 -381.578104)
				)
				(arc
					(start 389.04799 -381.578104)
					(mid 389.083911 -381.592983)
					(end 389.09879 -381.628904)
				)
				(arc
					(start 389.09879 -384.051556)
					(mid 389.083911 -384.087477)
					(end 389.04799 -384.102356)
				)
				(arc
					(start 388.33171 -384.102356)
					(mid 388.295789 -384.087477)
					(end 388.28091 -384.051556)
				)
			)
		)
	)
	(zone
		(layers "F.Cu" "B.Cu" "In1.Cu" "In2.Cu" "In3.Cu" "In4.Cu" "In5.Cu" "In6.Cu"
			"In7.Cu" "In8.Cu" "In9.Cu" "In10.Cu" "In11.Cu" "In12.Cu" "In13.Cu" "In14.Cu"
			"In15.Cu" "In16.Cu"
		)
		(hatch none 0.5)
		(connect_pads
			(clearance 0)
		)
		(min_thickness 0.25)
		(keepout
			(tracks not_allowed)
			(vias allowed)
			(pads allowed)
			(copperpour not_allowed)
			(footprints allowed)
		)
		(placement
			(enabled no)
			(sheetname "")
		)
		(fill
			(thermal_gap 0.5)
			(thermal_bridge_width 0.5)
			(island_removal_mode 0)
		)
		(polygon
			(pts
				(arc
					(start 37.324792 -289.104578)
					(mid 37.654992 -288.774378)
					(end 37.324792 -288.444178)
				)
				(arc
					(start 36.374832 -288.444178)
					(mid 36.044632 -288.774378)
					(end 36.374832 -289.104578)
				)
			)
		)
	)
	(zone
		(layers "F.Cu" "B.Cu" "In1.Cu" "In2.Cu" "In3.Cu" "In4.Cu" "In5.Cu" "In6.Cu"
			"In7.Cu" "In8.Cu" "In9.Cu" "In10.Cu" "In11.Cu" "In12.Cu" "In13.Cu" "In14.Cu"
			"In15.Cu" "In16.Cu"
		)
		(hatch none 0.5)
		(connect_pads
			(clearance 0)
		)
		(min_thickness 0.25)
		(keepout
			(tracks not_allowed)
			(vias allowed)
			(pads allowed)
			(copperpour not_allowed)
			(footprints allowed)
		)
		(placement
			(enabled no)
			(sheetname "")
		)
		(fill
			(thermal_gap 0.5)
			(thermal_bridge_width 0.5)
			(island_removal_mode 0)
		)
		(polygon
			(pts
				(arc
					(start 115.501166 -377.728734)
					(mid 115.516045 -377.692813)
					(end 115.551966 -377.677934)
				)
				(arc
					(start 116.268246 -377.677934)
					(mid 116.304167 -377.692813)
					(end 116.319046 -377.728734)
				)
				(arc
					(start 116.319046 -380.151386)
					(mid 116.304167 -380.187307)
					(end 116.268246 -380.202186)
				)
				(arc
					(start 115.551966 -380.202186)
					(mid 115.516045 -380.187307)
					(end 115.501166 -380.151386)
				)
			)
		)
	)
	(zone
		(layers "F.Cu" "B.Cu" "In1.Cu" "In2.Cu" "In3.Cu" "In4.Cu" "In5.Cu" "In6.Cu"
			"In7.Cu" "In8.Cu" "In9.Cu" "In10.Cu" "In11.Cu" "In12.Cu" "In13.Cu" "In14.Cu"
			"In15.Cu" "In16.Cu"
		)
		(hatch none 0.5)
		(connect_pads
			(clearance 0)
		)
		(min_thickness 0.25)
		(keepout
			(tracks not_allowed)
			(vias allowed)
			(pads allowed)
			(copperpour not_allowed)
			(footprints allowed)
		)
		(placement
			(enabled no)
			(sheetname "")
		)
		(fill
			(thermal_gap 0.5)
			(thermal_bridge_width 0.5)
			(island_removal_mode 0)
		)
		(polygon
			(pts
				(arc
					(start 402.27758 -345.084146)
					(mid 401.89658 -345.465146)
					(end 402.27758 -345.846146)
				)
				(arc
					(start 403.14118 -345.846146)
					(mid 403.52218 -345.465146)
					(end 403.14118 -345.084146)
				)
			)
		)
	)
	(zone
		(layers "F.Cu" "B.Cu" "In1.Cu" "In2.Cu" "In3.Cu" "In4.Cu" "In5.Cu" "In6.Cu"
			"In7.Cu" "In8.Cu" "In9.Cu" "In10.Cu" "In11.Cu" "In12.Cu" "In13.Cu" "In14.Cu"
			"In15.Cu" "In16.Cu"
		)
		(hatch none 0.5)
		(connect_pads
			(clearance 0)
		)
		(min_thickness 0.25)
		(keepout
			(tracks not_allowed)
			(vias allowed)
			(pads allowed)
			(copperpour not_allowed)
			(footprints allowed)
		)
		(placement
			(enabled no)
			(sheetname "")
		)
		(fill
			(thermal_gap 0.5)
			(thermal_bridge_width 0.5)
			(island_removal_mode 0)
		)
		(polygon
			(pts
				(arc
					(start 425.680886 -374.928638)
					(mid 425.695765 -374.892717)
					(end 425.731686 -374.877838)
				)
				(arc
					(start 426.447966 -374.877838)
					(mid 426.483887 -374.892717)
					(end 426.498766 -374.928638)
				)
				(arc
					(start 426.498766 -377.35129)
					(mid 426.483887 -377.387211)
					(end 426.447966 -377.40209)
				)
				(arc
					(start 425.731686 -377.40209)
					(mid 425.695765 -377.387211)
					(end 425.680886 -377.35129)
				)
			)
		)
	)
	(zone
		(layers "F.Cu" "B.Cu" "In1.Cu" "In2.Cu" "In3.Cu" "In4.Cu" "In5.Cu" "In6.Cu"
			"In7.Cu" "In8.Cu" "In9.Cu" "In10.Cu" "In11.Cu" "In12.Cu" "In13.Cu" "In14.Cu"
			"In15.Cu" "In16.Cu"
		)
		(hatch none 0.5)
		(connect_pads
			(clearance 0)
		)
		(min_thickness 0.25)
		(keepout
			(tracks not_allowed)
			(vias allowed)
			(pads allowed)
			(copperpour not_allowed)
			(footprints allowed)
		)
		(placement
			(enabled no)
			(sheetname "")
		)
		(fill
			(thermal_gap 0.5)
			(thermal_bridge_width 0.5)
			(island_removal_mode 0)
		)
		(polygon
			(pts
				(arc
					(start 273.951954 -84.24037)
					(mid 274.409154 -84.69757)
					(end 274.866354 -84.24037)
				)
				(arc
					(start 274.866354 -83.37677)
					(mid 274.409154 -82.91957)
					(end 273.951954 -83.37677)
				)
			)
		)
	)
	(zone
		(layers "F.Cu" "B.Cu" "In1.Cu" "In2.Cu" "In3.Cu" "In4.Cu" "In5.Cu" "In6.Cu"
			"In7.Cu" "In8.Cu" "In9.Cu" "In10.Cu" "In11.Cu" "In12.Cu" "In13.Cu" "In14.Cu"
			"In15.Cu" "In16.Cu"
		)
		(hatch none 0.5)
		(connect_pads
			(clearance 0)
		)
		(min_thickness 0.25)
		(keepout
			(tracks not_allowed)
			(vias allowed)
			(pads allowed)
			(copperpour not_allowed)
			(footprints allowed)
		)
		(placement
			(enabled no)
			(sheetname "")
		)
		(fill
			(thermal_gap 0.5)
			(thermal_bridge_width 0.5)
			(island_removal_mode 0)
		)
		(polygon
			(pts
				(arc
					(start 277.223982 -342.058498)
					(mid 276.842982 -342.439498)
					(end 277.223982 -342.820498)
				)
				(arc
					(start 278.087582 -342.820498)
					(mid 278.468582 -342.439498)
					(end 278.087582 -342.058498)
				)
			)
		)
	)
	(zone
		(layers "F.Cu" "B.Cu" "In1.Cu" "In2.Cu" "In3.Cu" "In4.Cu" "In5.Cu" "In6.Cu"
			"In7.Cu" "In8.Cu" "In9.Cu" "In10.Cu" "In11.Cu" "In12.Cu" "In13.Cu" "In14.Cu"
			"In15.Cu" "In16.Cu"
		)
		(hatch none 0.5)
		(connect_pads
			(clearance 0)
		)
		(min_thickness 0.25)
		(keepout
			(tracks not_allowed)
			(vias allowed)
			(pads allowed)
			(copperpour not_allowed)
			(footprints allowed)
		)
		(placement
			(enabled no)
			(sheetname "")
		)
		(fill
			(thermal_gap 0.5)
			(thermal_bridge_width 0.5)
			(island_removal_mode 0)
		)
		(polygon
			(pts
				(arc
					(start 375.081038 -399.828766)
					(mid 375.095917 -399.792845)
					(end 375.131838 -399.777966)
				)
				(arc
					(start 375.848118 -399.777966)
					(mid 375.884039 -399.792845)
					(end 375.898918 -399.828766)
				)
				(arc
					(start 375.898918 -402.251418)
					(mid 375.884039 -402.287339)
					(end 375.848118 -402.302218)
				)
				(arc
					(start 375.131838 -402.302218)
					(mid 375.095917 -402.287339)
					(end 375.081038 -402.251418)
				)
			)
		)
	)
	(zone
		(layers "F.Cu" "B.Cu" "In1.Cu" "In2.Cu" "In3.Cu" "In4.Cu" "In5.Cu" "In6.Cu"
			"In7.Cu" "In8.Cu" "In9.Cu" "In10.Cu" "In11.Cu" "In12.Cu" "In13.Cu" "In14.Cu"
			"In15.Cu" "In16.Cu"
		)
		(hatch none 0.5)
		(connect_pads
			(clearance 0)
		)
		(min_thickness 0.25)
		(keepout
			(tracks not_allowed)
			(vias allowed)
			(pads allowed)
			(copperpour not_allowed)
			(footprints allowed)
		)
		(placement
			(enabled no)
			(sheetname "")
		)
		(fill
			(thermal_gap 0.5)
			(thermal_bridge_width 0.5)
			(island_removal_mode 0)
		)
		(polygon
			(pts
				(arc
					(start 183.948832 -354.327206)
					(mid 183.567832 -354.708206)
					(end 183.948832 -355.089206)
				)
				(arc
					(start 184.812432 -355.089206)
					(mid 185.193432 -354.708206)
					(end 184.812432 -354.327206)
				)
			)
		)
	)
	(zone
		(layers "F.Cu" "B.Cu" "In1.Cu" "In2.Cu" "In3.Cu" "In4.Cu" "In5.Cu" "In6.Cu"
			"In7.Cu" "In8.Cu" "In9.Cu" "In10.Cu" "In11.Cu" "In12.Cu" "In13.Cu" "In14.Cu"
			"In15.Cu" "In16.Cu"
		)
		(hatch none 0.5)
		(connect_pads
			(clearance 0)
		)
		(min_thickness 0.25)
		(keepout
			(tracks not_allowed)
			(vias allowed)
			(pads allowed)
			(copperpour not_allowed)
			(footprints allowed)
		)
		(placement
			(enabled no)
			(sheetname "")
		)
		(fill
			(thermal_gap 0.5)
			(thermal_bridge_width 0.5)
			(island_removal_mode 0)
		)
		(polygon
			(pts
				(arc
					(start 313.274964 -130.769106)
					(mid 313.732164 -131.226306)
					(end 314.189364 -130.769106)
				)
				(arc
					(start 314.189364 -129.905506)
					(mid 313.732164 -129.448306)
					(end 313.274964 -129.905506)
				)
			)
		)
	)
	(zone
		(layers "F.Cu" "B.Cu" "In1.Cu" "In2.Cu" "In3.Cu" "In4.Cu" "In5.Cu" "In6.Cu"
			"In7.Cu" "In8.Cu" "In9.Cu" "In10.Cu" "In11.Cu" "In12.Cu" "In13.Cu" "In14.Cu"
			"In15.Cu" "In16.Cu"
		)
		(hatch none 0.5)
		(connect_pads
			(clearance 0)
		)
		(min_thickness 0.25)
		(keepout
			(tracks not_allowed)
			(vias allowed)
			(pads allowed)
			(copperpour not_allowed)
			(footprints allowed)
		)
		(placement
			(enabled no)
			(sheetname "")
		)
		(fill
			(thermal_gap 0.5)
			(thermal_bridge_width 0.5)
			(island_removal_mode 0)
		)
		(polygon
			(pts
				(arc
					(start 431.057812 -348.20479)
					(mid 430.676812 -348.58579)
					(end 431.057812 -348.96679)
				)
				(arc
					(start 431.921412 -348.96679)
					(mid 432.302412 -348.58579)
					(end 431.921412 -348.20479)
				)
			)
		)
	)
	(zone
		(layers "F.Cu" "B.Cu" "In1.Cu" "In2.Cu" "In3.Cu" "In4.Cu" "In5.Cu" "In6.Cu"
			"In7.Cu" "In8.Cu" "In9.Cu" "In10.Cu" "In11.Cu" "In12.Cu" "In13.Cu" "In14.Cu"
			"In15.Cu" "In16.Cu"
		)
		(hatch none 0.5)
		(connect_pads
			(clearance 0)
		)
		(min_thickness 0.25)
		(keepout
			(tracks not_allowed)
			(vias allowed)
			(pads allowed)
			(copperpour not_allowed)
			(footprints allowed)
		)
		(placement
			(enabled no)
			(sheetname "")
		)
		(fill
			(thermal_gap 0.5)
			(thermal_bridge_width 0.5)
			(island_removal_mode 0)
		)
		(polygon
			(pts
				(arc
					(start 386.081016 -397.028924)
					(mid 386.095895 -396.993003)
					(end 386.131816 -396.978124)
				)
				(arc
					(start 386.848096 -396.978124)
					(mid 386.884017 -396.993003)
					(end 386.898896 -397.028924)
				)
				(arc
					(start 386.898896 -399.451576)
					(mid 386.884017 -399.487497)
					(end 386.848096 -399.502376)
				)
				(arc
					(start 386.131816 -399.502376)
					(mid 386.095895 -399.487497)
					(end 386.081016 -399.451576)
				)
			)
		)
	)
	(zone
		(layers "F.Cu" "B.Cu" "In1.Cu" "In2.Cu" "In3.Cu" "In4.Cu" "In5.Cu" "In6.Cu"
			"In7.Cu" "In8.Cu" "In9.Cu" "In10.Cu" "In11.Cu" "In12.Cu" "In13.Cu" "In14.Cu"
			"In15.Cu" "In16.Cu"
		)
		(hatch none 0.5)
		(connect_pads
			(clearance 0)
		)
		(min_thickness 0.25)
		(keepout
			(tracks not_allowed)
			(vias allowed)
			(pads allowed)
			(copperpour not_allowed)
			(footprints allowed)
		)
		(placement
			(enabled no)
			(sheetname "")
		)
		(fill
			(thermal_gap 0.5)
			(thermal_bridge_width 0.5)
			(island_removal_mode 0)
		)
		(polygon
			(pts
				(arc
					(start 385.610608 -121.894346)
					(mid 386.067808 -122.351546)
					(end 386.525008 -121.894346)
				)
				(arc
					(start 386.525008 -121.030746)
					(mid 386.067808 -120.573546)
					(end 385.610608 -121.030746)
				)
			)
		)
	)
	(zone
		(layers "F.Cu" "B.Cu" "In1.Cu" "In2.Cu" "In3.Cu" "In4.Cu" "In5.Cu" "In6.Cu"
			"In7.Cu" "In8.Cu" "In9.Cu" "In10.Cu" "In11.Cu" "In12.Cu" "In13.Cu" "In14.Cu"
			"In15.Cu" "In16.Cu"
		)
		(hatch none 0.5)
		(connect_pads
			(clearance 0)
		)
		(min_thickness 0.25)
		(keepout
			(tracks not_allowed)
			(vias allowed)
			(pads allowed)
			(copperpour not_allowed)
			(footprints allowed)
		)
		(placement
			(enabled no)
			(sheetname "")
		)
		(fill
			(thermal_gap 0.5)
			(thermal_bridge_width 0.5)
			(island_removal_mode 0)
		)
		(polygon
			(pts
				(arc
					(start 93.574108 -333.950056)
					(mid 94.031308 -334.407256)
					(end 94.488508 -333.950056)
				)
				(arc
					(start 94.488508 -333.086456)
					(mid 94.031308 -332.629256)
					(end 93.574108 -333.086456)
				)
			)
		)
	)
	(zone
		(layers "F.Cu" "B.Cu" "In1.Cu" "In2.Cu" "In3.Cu" "In4.Cu" "In5.Cu" "In6.Cu"
			"In7.Cu" "In8.Cu" "In9.Cu" "In10.Cu" "In11.Cu" "In12.Cu" "In13.Cu" "In14.Cu"
			"In15.Cu" "In16.Cu"
		)
		(hatch none 0.5)
		(connect_pads
			(clearance 0)
		)
		(min_thickness 0.25)
		(keepout
			(tracks not_allowed)
			(vias allowed)
			(pads allowed)
			(copperpour not_allowed)
			(footprints allowed)
		)
		(placement
			(enabled no)
			(sheetname "")
		)
		(fill
			(thermal_gap 0.5)
			(thermal_bridge_width 0.5)
			(island_removal_mode 0)
		)
		(polygon
			(pts
				(arc
					(start 37.310568 -125.494542)
					(mid 37.767768 -125.951742)
					(end 38.224968 -125.494542)
				)
				(arc
					(start 38.224968 -124.630942)
					(mid 37.767768 -124.173742)
					(end 37.310568 -124.630942)
				)
			)
		)
	)
	(zone
		(layers "F.Cu" "B.Cu" "In1.Cu" "In2.Cu" "In3.Cu" "In4.Cu" "In5.Cu" "In6.Cu"
			"In7.Cu" "In8.Cu" "In9.Cu" "In10.Cu" "In11.Cu" "In12.Cu" "In13.Cu" "In14.Cu"
			"In15.Cu" "In16.Cu"
		)
		(hatch none 0.5)
		(connect_pads
			(clearance 0)
		)
		(min_thickness 0.25)
		(keepout
			(tracks not_allowed)
			(vias allowed)
			(pads allowed)
			(copperpour not_allowed)
			(footprints allowed)
		)
		(placement
			(enabled no)
			(sheetname "")
		)
		(fill
			(thermal_gap 0.5)
			(thermal_bridge_width 0.5)
			(island_removal_mode 0)
		)
		(polygon
			(pts
				(arc
					(start 118.3005 -84.495386)
					(mid 117.8433 -84.038186)
					(end 117.3861 -84.495386)
				)
				(arc
					(start 117.3861 -85.358986)
					(mid 117.8433 -85.816186)
					(end 118.3005 -85.358986)
				)
			)
		)
	)
	(zone
		(layers "F.Cu" "B.Cu" "In1.Cu" "In2.Cu" "In3.Cu" "In4.Cu" "In5.Cu" "In6.Cu"
			"In7.Cu" "In8.Cu" "In9.Cu" "In10.Cu" "In11.Cu" "In12.Cu" "In13.Cu" "In14.Cu"
			"In15.Cu" "In16.Cu"
		)
		(hatch none 0.5)
		(connect_pads
			(clearance 0)
		)
		(min_thickness 0.25)
		(keepout
			(tracks not_allowed)
			(vias allowed)
			(pads allowed)
			(copperpour not_allowed)
			(footprints allowed)
		)
		(placement
			(enabled no)
			(sheetname "")
		)
		(fill
			(thermal_gap 0.5)
			(thermal_bridge_width 0.5)
			(island_removal_mode 0)
		)
		(polygon
			(pts
				(arc
					(start 78.100936 -400.92884)
					(mid 78.115815 -400.892919)
					(end 78.151736 -400.87804)
				)
				(arc
					(start 78.868016 -400.87804)
					(mid 78.903937 -400.892919)
					(end 78.918816 -400.92884)
				)
				(arc
					(start 78.918816 -403.351492)
					(mid 78.903937 -403.387413)
					(end 78.868016 -403.402292)
				)
				(arc
					(start 78.151736 -403.402292)
					(mid 78.115815 -403.387413)
					(end 78.100936 -403.351492)
				)
			)
		)
	)
	(zone
		(layers "F.Cu" "B.Cu" "In1.Cu" "In2.Cu" "In3.Cu" "In4.Cu" "In5.Cu" "In6.Cu"
			"In7.Cu" "In8.Cu" "In9.Cu" "In10.Cu" "In11.Cu" "In12.Cu" "In13.Cu" "In14.Cu"
			"In15.Cu" "In16.Cu"
		)
		(hatch none 0.5)
		(connect_pads
			(clearance 0)
		)
		(min_thickness 0.25)
		(keepout
			(tracks not_allowed)
			(vias allowed)
			(pads allowed)
			(copperpour not_allowed)
			(footprints allowed)
		)
		(placement
			(enabled no)
			(sheetname "")
		)
		(fill
			(thermal_gap 0.5)
			(thermal_bridge_width 0.5)
			(island_removal_mode 0)
		)
		(polygon
			(pts
				(arc
					(start 388.28091 -399.828766)
					(mid 388.295789 -399.792845)
					(end 388.33171 -399.777966)
				)
				(arc
					(start 389.04799 -399.777966)
					(mid 389.083911 -399.792845)
					(end 389.09879 -399.828766)
				)
				(arc
					(start 389.09879 -402.251418)
					(mid 389.083911 -402.287339)
					(end 389.04799 -402.302218)
				)
				(arc
					(start 388.33171 -402.302218)
					(mid 388.295789 -402.287339)
					(end 388.28091 -402.251418)
				)
			)
		)
	)
	(zone
		(layers "F.Cu" "B.Cu" "In1.Cu" "In2.Cu" "In3.Cu" "In4.Cu" "In5.Cu" "In6.Cu"
			"In7.Cu" "In8.Cu" "In9.Cu" "In10.Cu" "In11.Cu" "In12.Cu" "In13.Cu" "In14.Cu"
			"In15.Cu" "In16.Cu"
		)
		(hatch none 0.5)
		(connect_pads
			(clearance 0)
		)
		(min_thickness 0.25)
		(keepout
			(tracks not_allowed)
			(vias allowed)
			(pads allowed)
			(copperpour not_allowed)
			(footprints allowed)
		)
		(placement
			(enabled no)
			(sheetname "")
		)
		(fill
			(thermal_gap 0.5)
			(thermal_bridge_width 0.5)
			(island_removal_mode 0)
		)
		(polygon
			(pts
				(arc
					(start 295.877742 -348.20479)
					(mid 295.496742 -348.58579)
					(end 295.877742 -348.96679)
				)
				(arc
					(start 296.741342 -348.96679)
					(mid 297.122342 -348.58579)
					(end 296.741342 -348.20479)
				)
			)
		)
	)
	(zone
		(layers "F.Cu" "B.Cu" "In1.Cu" "In2.Cu" "In3.Cu" "In4.Cu" "In5.Cu" "In6.Cu"
			"In7.Cu" "In8.Cu" "In9.Cu" "In10.Cu" "In11.Cu" "In12.Cu" "In13.Cu" "In14.Cu"
			"In15.Cu" "In16.Cu"
		)
		(hatch none 0.5)
		(connect_pads
			(clearance 0)
		)
		(min_thickness 0.25)
		(keepout
			(tracks not_allowed)
			(vias allowed)
			(pads allowed)
			(copperpour not_allowed)
			(footprints allowed)
		)
		(placement
			(enabled no)
			(sheetname "")
		)
		(fill
			(thermal_gap 0.5)
			(thermal_bridge_width 0.5)
			(island_removal_mode 0)
		)
		(polygon
			(pts
				(arc
					(start 127.406908 -342.058498)
					(mid 127.025908 -342.439498)
					(end 127.406908 -342.820498)
				)
				(arc
					(start 128.270508 -342.820498)
					(mid 128.651508 -342.439498)
					(end 128.270508 -342.058498)
				)
			)
		)
	)
	(zone
		(layers "F.Cu" "B.Cu" "In1.Cu" "In2.Cu" "In3.Cu" "In4.Cu" "In5.Cu" "In6.Cu"
			"In7.Cu" "In8.Cu" "In9.Cu" "In10.Cu" "In11.Cu" "In12.Cu" "In13.Cu" "In14.Cu"
			"In15.Cu" "In16.Cu"
		)
		(hatch none 0.5)
		(connect_pads
			(clearance 0)
		)
		(min_thickness 0.25)
		(keepout
			(tracks not_allowed)
			(vias allowed)
			(pads allowed)
			(copperpour not_allowed)
			(footprints allowed)
		)
		(placement
			(enabled no)
			(sheetname "")
		)
		(fill
			(thermal_gap 0.5)
			(thermal_bridge_width 0.5)
			(island_removal_mode 0)
		)
		(polygon
			(pts
				(arc
					(start 83.71713 -121.365772)
					(mid 84.17433 -121.822972)
					(end 84.63153 -121.365772)
				)
				(arc
					(start 84.63153 -120.502172)
					(mid 84.17433 -120.044972)
					(end 83.71713 -120.502172)
				)
			)
		)
	)
	(zone
		(layers "F.Cu" "B.Cu" "In1.Cu" "In2.Cu" "In3.Cu" "In4.Cu" "In5.Cu" "In6.Cu"
			"In7.Cu" "In8.Cu" "In9.Cu" "In10.Cu" "In11.Cu" "In12.Cu" "In13.Cu" "In14.Cu"
			"In15.Cu" "In16.Cu"
		)
		(hatch none 0.5)
		(connect_pads
			(clearance 0)
		)
		(min_thickness 0.25)
		(keepout
			(tracks not_allowed)
			(vias allowed)
			(pads allowed)
			(copperpour not_allowed)
			(footprints allowed)
		)
		(placement
			(enabled no)
			(sheetname "")
		)
		(fill
			(thermal_gap 0.5)
			(thermal_bridge_width 0.5)
			(island_removal_mode 0)
		)
		(polygon
			(pts
				(arc
					(start 73.808082 -354.351082)
					(mid 73.427082 -354.732082)
					(end 73.808082 -355.113082)
				)
				(arc
					(start 74.671682 -355.113082)
					(mid 75.052682 -354.732082)
					(end 74.671682 -354.351082)
				)
			)
		)
	)
	(zone
		(layers "F.Cu" "B.Cu" "In1.Cu" "In2.Cu" "In3.Cu" "In4.Cu" "In5.Cu" "In6.Cu"
			"In7.Cu" "In8.Cu" "In9.Cu" "In10.Cu" "In11.Cu" "In12.Cu" "In13.Cu" "In14.Cu"
			"In15.Cu" "In16.Cu"
		)
		(hatch none 0.5)
		(connect_pads
			(clearance 0)
		)
		(min_thickness 0.25)
		(keepout
			(tracks not_allowed)
			(vias allowed)
			(pads allowed)
			(copperpour not_allowed)
			(footprints allowed)
		)
		(placement
			(enabled no)
			(sheetname "")
		)
		(fill
			(thermal_gap 0.5)
			(thermal_bridge_width 0.5)
			(island_removal_mode 0)
		)
		(polygon
			(pts
				(arc
					(start 321.829684 -357.37673)
					(mid 321.448684 -357.75773)
					(end 321.829684 -358.13873)
				)
				(arc
					(start 322.693284 -358.13873)
					(mid 323.074284 -357.75773)
					(end 322.693284 -357.37673)
				)
			)
		)
	)
	(zone
		(layers "F.Cu" "B.Cu" "In1.Cu" "In2.Cu" "In3.Cu" "In4.Cu" "In5.Cu" "In6.Cu"
			"In7.Cu" "In8.Cu" "In9.Cu" "In10.Cu" "In11.Cu" "In12.Cu" "In13.Cu" "In14.Cu"
			"In15.Cu" "In16.Cu"
		)
		(hatch none 0.5)
		(connect_pads
			(clearance 0)
		)
		(min_thickness 0.25)
		(keepout
			(tracks not_allowed)
			(vias allowed)
			(pads allowed)
			(copperpour not_allowed)
			(footprints allowed)
		)
		(placement
			(enabled no)
			(sheetname "")
		)
		(fill
			(thermal_gap 0.5)
			(thermal_bridge_width 0.5)
			(island_removal_mode 0)
		)
		(polygon
			(pts
				(arc
					(start 190.166752 -342.058498)
					(mid 189.785752 -342.439498)
					(end 190.166752 -342.820498)
				)
				(arc
					(start 191.030352 -342.820498)
					(mid 191.411352 -342.439498)
					(end 191.030352 -342.058498)
				)
			)
		)
	)
	(zone
		(layers "F.Cu" "B.Cu" "In1.Cu" "In2.Cu" "In3.Cu" "In4.Cu" "In5.Cu" "In6.Cu"
			"In7.Cu" "In8.Cu" "In9.Cu" "In10.Cu" "In11.Cu" "In12.Cu" "In13.Cu" "In14.Cu"
			"In15.Cu" "In16.Cu"
		)
		(hatch none 0.5)
		(connect_pads
			(clearance 0)
		)
		(min_thickness 0.25)
		(keepout
			(tracks not_allowed)
			(vias allowed)
			(pads allowed)
			(copperpour not_allowed)
			(footprints allowed)
		)
		(placement
			(enabled no)
			(sheetname "")
		)
		(fill
			(thermal_gap 0.5)
			(thermal_bridge_width 0.5)
			(island_removal_mode 0)
		)
		(polygon
			(pts
				(arc
					(start 367.14811 -32.714184)
					(mid 367.60531 -33.171384)
					(end 368.06251 -32.714184)
				)
				(arc
					(start 368.06251 -31.850584)
					(mid 367.60531 -31.393384)
					(end 367.14811 -31.850584)
				)
			)
		)
	)
	(zone
		(layers "F.Cu" "B.Cu" "In1.Cu" "In2.Cu" "In3.Cu" "In4.Cu" "In5.Cu" "In6.Cu"
			"In7.Cu" "In8.Cu" "In9.Cu" "In10.Cu" "In11.Cu" "In12.Cu" "In13.Cu" "In14.Cu"
			"In15.Cu" "In16.Cu"
		)
		(hatch none 0.5)
		(connect_pads
			(clearance 0)
		)
		(min_thickness 0.25)
		(keepout
			(tracks not_allowed)
			(vias allowed)
			(pads allowed)
			(copperpour not_allowed)
			(footprints allowed)
		)
		(placement
			(enabled no)
			(sheetname "")
		)
		(fill
			(thermal_gap 0.5)
			(thermal_bridge_width 0.5)
			(island_removal_mode 0)
		)
		(polygon
			(pts
				(arc
					(start 440.384692 -354.351082)
					(mid 440.003692 -354.732082)
					(end 440.384692 -355.113082)
				)
				(arc
					(start 441.248292 -355.113082)
					(mid 441.629292 -354.732082)
					(end 441.248292 -354.351082)
				)
			)
		)
	)
	(zone
		(layers "F.Cu" "B.Cu" "In1.Cu" "In2.Cu" "In3.Cu" "In4.Cu" "In5.Cu" "In6.Cu"
			"In7.Cu" "In8.Cu" "In9.Cu" "In10.Cu" "In11.Cu" "In12.Cu" "In13.Cu" "In14.Cu"
			"In15.Cu" "In16.Cu"
		)
		(hatch none 0.5)
		(connect_pads
			(clearance 0)
		)
		(min_thickness 0.25)
		(keepout
			(tracks not_allowed)
			(vias allowed)
			(pads allowed)
			(copperpour not_allowed)
			(footprints allowed)
		)
		(placement
			(enabled no)
			(sheetname "")
		)
		(fill
			(thermal_gap 0.5)
			(thermal_bridge_width 0.5)
			(island_removal_mode 0)
		)
		(polygon
			(pts
				(arc
					(start 421.280844 -408.728672)
					(mid 421.295723 -408.692751)
					(end 421.331644 -408.677872)
				)
				(arc
					(start 422.047924 -408.677872)
					(mid 422.083845 -408.692751)
					(end 422.098724 -408.728672)
				)
				(arc
					(start 422.098724 -411.151324)
					(mid 422.083845 -411.187245)
					(end 422.047924 -411.202124)
				)
				(arc
					(start 421.331644 -411.202124)
					(mid 421.295723 -411.187245)
					(end 421.280844 -411.151324)
				)
			)
		)
	)
	(zone
		(layers "F.Cu" "B.Cu" "In1.Cu" "In2.Cu" "In3.Cu" "In4.Cu" "In5.Cu" "In6.Cu"
			"In7.Cu" "In8.Cu" "In9.Cu" "In10.Cu" "In11.Cu" "In12.Cu" "In13.Cu" "In14.Cu"
			"In15.Cu" "In16.Cu"
		)
		(hatch none 0.5)
		(connect_pads
			(clearance 0)
		)
		(min_thickness 0.25)
		(keepout
			(tracks not_allowed)
			(vias allowed)
			(pads allowed)
			(copperpour not_allowed)
			(footprints allowed)
		)
		(placement
			(enabled no)
			(sheetname "")
		)
		(fill
			(thermal_gap 0.5)
			(thermal_bridge_width 0.5)
			(island_removal_mode 0)
		)
		(polygon
			(pts
				(arc
					(start 174.853346 -34.52241)
					(mid 175.310546 -34.97961)
					(end 175.767746 -34.52241)
				)
				(arc
					(start 175.767746 -33.65881)
					(mid 175.310546 -33.20161)
					(end 174.853346 -33.65881)
				)
			)
		)
	)
	(zone
		(layers "F.Cu" "B.Cu" "In1.Cu" "In2.Cu" "In3.Cu" "In4.Cu" "In5.Cu" "In6.Cu"
			"In7.Cu" "In8.Cu" "In9.Cu" "In10.Cu" "In11.Cu" "In12.Cu" "In13.Cu" "In14.Cu"
			"In15.Cu" "In16.Cu"
		)
		(hatch none 0.5)
		(connect_pads
			(clearance 0)
		)
		(min_thickness 0.25)
		(keepout
			(tracks not_allowed)
			(vias allowed)
			(pads allowed)
			(copperpour not_allowed)
			(footprints allowed)
		)
		(placement
			(enabled no)
			(sheetname "")
		)
		(fill
			(thermal_gap 0.5)
			(thermal_bridge_width 0.5)
			(island_removal_mode 0)
		)
		(polygon
			(pts
				(arc
					(start 124.30125 -381.628904)
					(mid 124.316129 -381.592983)
					(end 124.35205 -381.578104)
				)
				(arc
					(start 125.06833 -381.578104)
					(mid 125.104251 -381.592983)
					(end 125.11913 -381.628904)
				)
				(arc
					(start 125.11913 -384.051556)
					(mid 125.104251 -384.087477)
					(end 125.06833 -384.102356)
				)
				(arc
					(start 124.35205 -384.102356)
					(mid 124.316129 -384.087477)
					(end 124.30125 -384.051556)
				)
			)
		)
	)
	(zone
		(layers "F.Cu" "B.Cu" "In1.Cu" "In2.Cu" "In3.Cu" "In4.Cu" "In5.Cu" "In6.Cu"
			"In7.Cu" "In8.Cu" "In9.Cu" "In10.Cu" "In11.Cu" "In12.Cu" "In13.Cu" "In14.Cu"
			"In15.Cu" "In16.Cu"
		)
		(hatch none 0.5)
		(connect_pads
			(clearance 0)
		)
		(min_thickness 0.25)
		(keepout
			(tracks not_allowed)
			(vias allowed)
			(pads allowed)
			(copperpour not_allowed)
			(footprints allowed)
		)
		(placement
			(enabled no)
			(sheetname "")
		)
		(fill
			(thermal_gap 0.5)
			(thermal_bridge_width 0.5)
			(island_removal_mode 0)
		)
		(polygon
			(pts
				(arc
					(start 324.129908 -36.60013)
					(mid 322.199508 -36.60013)
					(end 324.129908 -36.60013)
				)
			)
		)
	)
	(zone
		(layers "F.Cu" "B.Cu" "In1.Cu" "In2.Cu" "In3.Cu" "In4.Cu" "In5.Cu" "In6.Cu"
			"In7.Cu" "In8.Cu" "In9.Cu" "In10.Cu" "In11.Cu" "In12.Cu" "In13.Cu" "In14.Cu"
			"In15.Cu" "In16.Cu"
		)
		(hatch none 0.5)
		(connect_pads
			(clearance 0)
		)
		(min_thickness 0.25)
		(keepout
			(tracks not_allowed)
			(vias allowed)
			(pads allowed)
			(copperpour not_allowed)
			(footprints allowed)
		)
		(placement
			(enabled no)
			(sheetname "")
		)
		(fill
			(thermal_gap 0.5)
			(thermal_bridge_width 0.5)
			(island_removal_mode 0)
		)
		(polygon
			(pts
				(arc
					(start 337.374484 -351.230438)
					(mid 336.993484 -351.611438)
					(end 337.374484 -351.992438)
				)
				(arc
					(start 338.238084 -351.992438)
					(mid 338.619084 -351.611438)
					(end 338.238084 -351.230438)
				)
			)
		)
	)
	(zone
		(layers "F.Cu" "B.Cu" "In1.Cu" "In2.Cu" "In3.Cu" "In4.Cu" "In5.Cu" "In6.Cu"
			"In7.Cu" "In8.Cu" "In9.Cu" "In10.Cu" "In11.Cu" "In12.Cu" "In13.Cu" "In14.Cu"
			"In15.Cu" "In16.Cu"
		)
		(hatch none 0.5)
		(connect_pads
			(clearance 0)
		)
		(min_thickness 0.25)
		(keepout
			(tracks not_allowed)
			(vias allowed)
			(pads allowed)
			(copperpour not_allowed)
			(footprints allowed)
		)
		(placement
			(enabled no)
			(sheetname "")
		)
		(fill
			(thermal_gap 0.5)
			(thermal_bridge_width 0.5)
			(island_removal_mode 0)
		)
		(polygon
			(pts
				(arc
					(start 292.80739 -32.722312)
					(mid 293.26459 -33.179512)
					(end 293.72179 -32.722312)
				)
				(arc
					(start 293.72179 -31.858712)
					(mid 293.26459 -31.401512)
					(end 292.80739 -31.858712)
				)
			)
		)
	)
	(zone
		(layers "F.Cu" "B.Cu" "In1.Cu" "In2.Cu" "In3.Cu" "In4.Cu" "In5.Cu" "In6.Cu"
			"In7.Cu" "In8.Cu" "In9.Cu" "In10.Cu" "In11.Cu" "In12.Cu" "In13.Cu" "In14.Cu"
			"In15.Cu" "In16.Cu"
		)
		(hatch none 0.5)
		(connect_pads
			(clearance 0)
		)
		(min_thickness 0.25)
		(keepout
			(tracks not_allowed)
			(vias allowed)
			(pads allowed)
			(copperpour not_allowed)
			(footprints allowed)
		)
		(placement
			(enabled no)
			(sheetname "")
		)
		(fill
			(thermal_gap 0.5)
			(thermal_bridge_width 0.5)
			(island_removal_mode 0)
		)
		(polygon
			(pts
				(arc
					(start 28.659328 -354.351082)
					(mid 28.278328 -354.732082)
					(end 28.659328 -355.113082)
				)
				(arc
					(start 29.522928 -355.113082)
					(mid 29.903928 -354.732082)
					(end 29.522928 -354.351082)
				)
			)
		)
	)
	(zone
		(layers "F.Cu" "B.Cu" "In1.Cu" "In2.Cu" "In3.Cu" "In4.Cu" "In5.Cu" "In6.Cu"
			"In7.Cu" "In8.Cu" "In9.Cu" "In10.Cu" "In11.Cu" "In12.Cu" "In13.Cu" "In14.Cu"
			"In15.Cu" "In16.Cu"
		)
		(hatch none 0.5)
		(connect_pads
			(clearance 0)
		)
		(min_thickness 0.25)
		(keepout
			(tracks not_allowed)
			(vias allowed)
			(pads allowed)
			(copperpour not_allowed)
			(footprints allowed)
		)
		(placement
			(enabled no)
			(sheetname "")
		)
		(fill
			(thermal_gap 0.5)
			(thermal_bridge_width 0.5)
			(island_removal_mode 0)
		)
		(polygon
			(pts
				(arc
					(start 165.509448 -95.214948)
					(mid 163.375848 -95.214948)
					(end 165.509448 -95.214948)
				)
			)
		)
	)
	(zone
		(layers "F.Cu" "B.Cu" "In1.Cu" "In2.Cu" "In3.Cu" "In4.Cu" "In5.Cu" "In6.Cu"
			"In7.Cu" "In8.Cu" "In9.Cu" "In10.Cu" "In11.Cu" "In12.Cu" "In13.Cu" "In14.Cu"
			"In15.Cu" "In16.Cu"
		)
		(hatch none 0.5)
		(connect_pads
			(clearance 0)
		)
		(min_thickness 0.25)
		(keepout
			(tracks not_allowed)
			(vias allowed)
			(pads allowed)
			(copperpour not_allowed)
			(footprints allowed)
		)
		(placement
			(enabled no)
			(sheetname "")
		)
		(fill
			(thermal_gap 0.5)
			(thermal_bridge_width 0.5)
			(island_removal_mode 0)
		)
		(polygon
			(pts
				(arc
					(start 274.724114 -27.342846)
					(mid 275.181314 -27.800046)
					(end 275.638514 -27.342846)
				)
				(arc
					(start 275.638514 -26.479246)
					(mid 275.181314 -26.022046)
					(end 274.724114 -26.479246)
				)
			)
		)
	)
	(zone
		(layers "F.Cu" "B.Cu" "In1.Cu" "In2.Cu" "In3.Cu" "In4.Cu" "In5.Cu" "In6.Cu"
			"In7.Cu" "In8.Cu" "In9.Cu" "In10.Cu" "In11.Cu" "In12.Cu" "In13.Cu" "In14.Cu"
			"In15.Cu" "In16.Cu"
		)
		(hatch none 0.5)
		(connect_pads
			(clearance 0)
		)
		(min_thickness 0.25)
		(keepout
			(tracks not_allowed)
			(vias allowed)
			(pads allowed)
			(copperpour not_allowed)
			(footprints allowed)
		)
		(placement
			(enabled no)
			(sheetname "")
		)
		(fill
			(thermal_gap 0.5)
			(thermal_bridge_width 0.5)
			(island_removal_mode 0)
		)
		(polygon
			(pts
				(arc
					(start 84.700872 -373.828818)
					(mid 84.715751 -373.792897)
					(end 84.751672 -373.778018)
				)
				(arc
					(start 85.467952 -373.778018)
					(mid 85.503873 -373.792897)
					(end 85.518752 -373.828818)
				)
				(arc
					(start 85.518752 -376.25147)
					(mid 85.503873 -376.287391)
					(end 85.467952 -376.30227)
				)
				(arc
					(start 84.751672 -376.30227)
					(mid 84.715751 -376.287391)
					(end 84.700872 -376.25147)
				)
			)
		)
	)
	(zone
		(layers "F.Cu" "B.Cu" "In1.Cu" "In2.Cu" "In3.Cu" "In4.Cu" "In5.Cu" "In6.Cu"
			"In7.Cu" "In8.Cu" "In9.Cu" "In10.Cu" "In11.Cu" "In12.Cu" "In13.Cu" "In14.Cu"
			"In15.Cu" "In16.Cu"
		)
		(hatch none 0.5)
		(connect_pads
			(clearance 0)
		)
		(min_thickness 0.25)
		(keepout
			(tracks not_allowed)
			(vias allowed)
			(pads allowed)
			(copperpour not_allowed)
			(footprints allowed)
		)
		(placement
			(enabled no)
			(sheetname "")
		)
		(fill
			(thermal_gap 0.5)
			(thermal_bridge_width 0.5)
			(island_removal_mode 0)
		)
		(polygon
			(pts
				(arc
					(start 139.842748 -342.058498)
					(mid 139.461748 -342.439498)
					(end 139.842748 -342.820498)
				)
				(arc
					(start 140.706348 -342.820498)
					(mid 141.087348 -342.439498)
					(end 140.706348 -342.058498)
				)
			)
		)
	)
	(zone
		(layers "F.Cu" "B.Cu" "In1.Cu" "In2.Cu" "In3.Cu" "In4.Cu" "In5.Cu" "In6.Cu"
			"In7.Cu" "In8.Cu" "In9.Cu" "In10.Cu" "In11.Cu" "In12.Cu" "In13.Cu" "In14.Cu"
			"In15.Cu" "In16.Cu"
		)
		(hatch none 0.5)
		(connect_pads
			(clearance 0)
		)
		(min_thickness 0.25)
		(keepout
			(tracks not_allowed)
			(vias allowed)
			(pads allowed)
			(copperpour not_allowed)
			(footprints allowed)
		)
		(placement
			(enabled no)
			(sheetname "")
		)
		(fill
			(thermal_gap 0.5)
			(thermal_bridge_width 0.5)
			(island_removal_mode 0)
		)
		(polygon
			(pts
				(arc
					(start 371.18798 -351.230438)
					(mid 370.80698 -351.611438)
					(end 371.18798 -351.992438)
				)
				(arc
					(start 372.05158 -351.992438)
					(mid 372.43258 -351.611438)
					(end 372.05158 -351.230438)
				)
			)
		)
	)
	(zone
		(layers "F.Cu" "B.Cu" "In1.Cu" "In2.Cu" "In3.Cu" "In4.Cu" "In5.Cu" "In6.Cu"
			"In7.Cu" "In8.Cu" "In9.Cu" "In10.Cu" "In11.Cu" "In12.Cu" "In13.Cu" "In14.Cu"
			"In15.Cu" "In16.Cu"
		)
		(hatch none 0.5)
		(connect_pads
			(clearance 0)
		)
		(min_thickness 0.25)
		(keepout
			(tracks not_allowed)
			(vias allowed)
			(pads allowed)
			(copperpour not_allowed)
			(footprints allowed)
		)
		(placement
			(enabled no)
			(sheetname "")
		)
		(fill
			(thermal_gap 0.5)
			(thermal_bridge_width 0.5)
			(island_removal_mode 0)
		)
		(polygon
			(pts
				(arc
					(start 342.081104 -400.92884)
					(mid 342.095983 -400.892919)
					(end 342.131904 -400.87804)
				)
				(arc
					(start 342.848184 -400.87804)
					(mid 342.884105 -400.892919)
					(end 342.898984 -400.92884)
				)
				(arc
					(start 342.898984 -403.351492)
					(mid 342.884105 -403.387413)
					(end 342.848184 -403.402292)
				)
				(arc
					(start 342.131904 -403.402292)
					(mid 342.095983 -403.387413)
					(end 342.081104 -403.351492)
				)
			)
		)
	)
	(zone
		(layers "F.Cu" "B.Cu" "In1.Cu" "In2.Cu" "In3.Cu" "In4.Cu" "In5.Cu" "In6.Cu"
			"In7.Cu" "In8.Cu" "In9.Cu" "In10.Cu" "In11.Cu" "In12.Cu" "In13.Cu" "In14.Cu"
			"In15.Cu" "In16.Cu"
		)
		(hatch none 0.5)
		(connect_pads
			(clearance 0)
		)
		(min_thickness 0.25)
		(keepout
			(tracks not_allowed)
			(vias allowed)
			(pads allowed)
			(copperpour not_allowed)
			(footprints allowed)
		)
		(placement
			(enabled no)
			(sheetname "")
		)
		(fill
			(thermal_gap 0.5)
			(thermal_bridge_width 0.5)
			(island_removal_mode 0)
		)
		(polygon
			(pts
				(arc
					(start 414.90011 -143.48714)
					(mid 415.35731 -143.94434)
					(end 415.81451 -143.48714)
				)
				(arc
					(start 415.81451 -142.62354)
					(mid 415.35731 -142.16634)
					(end 414.90011 -142.62354)
				)
			)
		)
	)
	(zone
		(layers "F.Cu" "B.Cu" "In1.Cu" "In2.Cu" "In3.Cu" "In4.Cu" "In5.Cu" "In6.Cu"
			"In7.Cu" "In8.Cu" "In9.Cu" "In10.Cu" "In11.Cu" "In12.Cu" "In13.Cu" "In14.Cu"
			"In15.Cu" "In16.Cu"
		)
		(hatch none 0.5)
		(connect_pads
			(clearance 0)
		)
		(min_thickness 0.25)
		(keepout
			(tracks not_allowed)
			(vias allowed)
			(pads allowed)
			(copperpour not_allowed)
			(footprints allowed)
		)
		(placement
			(enabled no)
			(sheetname "")
		)
		(fill
			(thermal_gap 0.5)
			(thermal_bridge_width 0.5)
			(island_removal_mode 0)
		)
		(polygon
			(pts
				(arc
					(start 296.945812 -136.177274)
					(mid 297.403012 -136.634474)
					(end 297.860212 -136.177274)
				)
				(arc
					(start 297.860212 -135.313674)
					(mid 297.403012 -134.856474)
					(end 296.945812 -135.313674)
				)
			)
		)
	)
	(zone
		(layers "F.Cu" "B.Cu" "In1.Cu" "In2.Cu" "In3.Cu" "In4.Cu" "In5.Cu" "In6.Cu"
			"In7.Cu" "In8.Cu" "In9.Cu" "In10.Cu" "In11.Cu" "In12.Cu" "In13.Cu" "In14.Cu"
			"In15.Cu" "In16.Cu"
		)
		(hatch none 0.5)
		(connect_pads
			(clearance 0)
		)
		(min_thickness 0.25)
		(keepout
			(tracks not_allowed)
			(vias allowed)
			(pads allowed)
			(copperpour not_allowed)
			(footprints allowed)
		)
		(placement
			(enabled no)
			(sheetname "")
		)
		(fill
			(thermal_gap 0.5)
			(thermal_bridge_width 0.5)
			(island_removal_mode 0)
		)
		(polygon
			(pts
				(arc
					(start 84.700872 -377.728734)
					(mid 84.715751 -377.692813)
					(end 84.751672 -377.677934)
				)
				(arc
					(start 85.467952 -377.677934)
					(mid 85.503873 -377.692813)
					(end 85.518752 -377.728734)
				)
				(arc
					(start 85.518752 -380.151386)
					(mid 85.503873 -380.187307)
					(end 85.467952 -380.202186)
				)
				(arc
					(start 84.751672 -380.202186)
					(mid 84.715751 -380.187307)
					(end 84.700872 -380.151386)
				)
			)
		)
	)
	(zone
		(layers "F.Cu" "B.Cu" "In1.Cu" "In2.Cu" "In3.Cu" "In4.Cu" "In5.Cu" "In6.Cu"
			"In7.Cu" "In8.Cu" "In9.Cu" "In10.Cu" "In11.Cu" "In12.Cu" "In13.Cu" "In14.Cu"
			"In15.Cu" "In16.Cu"
		)
		(hatch none 0.5)
		(connect_pads
			(clearance 0)
		)
		(min_thickness 0.25)
		(keepout
			(tracks not_allowed)
			(vias allowed)
			(pads allowed)
			(copperpour not_allowed)
			(footprints allowed)
		)
		(placement
			(enabled no)
			(sheetname "")
		)
		(fill
			(thermal_gap 0.5)
			(thermal_bridge_width 0.5)
			(island_removal_mode 0)
		)
		(polygon
			(pts
				(arc
					(start 264.953242 -30.922468)
					(mid 265.410442 -31.379668)
					(end 265.867642 -30.922468)
				)
				(arc
					(start 265.867642 -30.058868)
					(mid 265.410442 -29.601668)
					(end 264.953242 -30.058868)
				)
			)
		)
	)
	(zone
		(layers "F.Cu" "B.Cu" "In1.Cu" "In2.Cu" "In3.Cu" "In4.Cu" "In5.Cu" "In6.Cu"
			"In7.Cu" "In8.Cu" "In9.Cu" "In10.Cu" "In11.Cu" "In12.Cu" "In13.Cu" "In14.Cu"
			"In15.Cu" "In16.Cu"
		)
		(hatch none 0.5)
		(connect_pads
			(clearance 0)
		)
		(min_thickness 0.25)
		(keepout
			(tracks not_allowed)
			(vias allowed)
			(pads allowed)
			(copperpour not_allowed)
			(footprints allowed)
		)
		(placement
			(enabled no)
			(sheetname "")
		)
		(fill
			(thermal_gap 0.5)
			(thermal_bridge_width 0.5)
			(island_removal_mode 0)
		)
		(polygon
			(pts
				(arc
					(start 91.301062 -382.728724)
					(mid 91.315941 -382.692803)
					(end 91.351862 -382.677924)
				)
				(arc
					(start 92.068142 -382.677924)
					(mid 92.104063 -382.692803)
					(end 92.118942 -382.728724)
				)
				(arc
					(start 92.118942 -385.151376)
					(mid 92.104063 -385.187297)
					(end 92.068142 -385.202176)
				)
				(arc
					(start 91.351862 -385.202176)
					(mid 91.315941 -385.187297)
					(end 91.301062 -385.151376)
				)
			)
		)
	)
	(zone
		(layers "F.Cu" "B.Cu" "In1.Cu" "In2.Cu" "In3.Cu" "In4.Cu" "In5.Cu" "In6.Cu"
			"In7.Cu" "In8.Cu" "In9.Cu" "In10.Cu" "In11.Cu" "In12.Cu" "In13.Cu" "In14.Cu"
			"In15.Cu" "In16.Cu"
		)
		(hatch none 0.5)
		(connect_pads
			(clearance 0)
		)
		(min_thickness 0.25)
		(keepout
			(tracks not_allowed)
			(vias allowed)
			(pads allowed)
			(copperpour not_allowed)
			(footprints allowed)
		)
		(placement
			(enabled no)
			(sheetname "")
		)
		(fill
			(thermal_gap 0.5)
			(thermal_bridge_width 0.5)
			(island_removal_mode 0)
		)
		(polygon
			(pts
				(arc
					(start 240.807494 -32.722312)
					(mid 241.264694 -33.179512)
					(end 241.721894 -32.722312)
				)
				(arc
					(start 241.721894 -31.858712)
					(mid 241.264694 -31.401512)
					(end 240.807494 -31.858712)
				)
			)
		)
	)
	(zone
		(layers "F.Cu" "B.Cu" "In1.Cu" "In2.Cu" "In3.Cu" "In4.Cu" "In5.Cu" "In6.Cu"
			"In7.Cu" "In8.Cu" "In9.Cu" "In10.Cu" "In11.Cu" "In12.Cu" "In13.Cu" "In14.Cu"
			"In15.Cu" "In16.Cu"
		)
		(hatch none 0.5)
		(connect_pads
			(clearance 0)
		)
		(min_thickness 0.25)
		(keepout
			(tracks not_allowed)
			(vias allowed)
			(pads allowed)
			(copperpour not_allowed)
			(footprints allowed)
		)
		(placement
			(enabled no)
			(sheetname "")
		)
		(fill
			(thermal_gap 0.5)
			(thermal_bridge_width 0.5)
			(island_removal_mode 0)
		)
		(polygon
			(pts
				(arc
					(start 142.951708 -357.37673)
					(mid 142.570708 -357.75773)
					(end 142.951708 -358.13873)
				)
				(arc
					(start 143.815308 -358.13873)
					(mid 144.196308 -357.75773)
					(end 143.815308 -357.37673)
				)
			)
		)
	)
	(zone
		(layers "F.Cu" "B.Cu" "In1.Cu" "In2.Cu" "In3.Cu" "In4.Cu" "In5.Cu" "In6.Cu"
			"In7.Cu" "In8.Cu" "In9.Cu" "In10.Cu" "In11.Cu" "In12.Cu" "In13.Cu" "In14.Cu"
			"In15.Cu" "In16.Cu"
		)
		(hatch none 0.5)
		(connect_pads
			(clearance 0)
		)
		(min_thickness 0.25)
		(keepout
			(tracks not_allowed)
			(vias allowed)
			(pads allowed)
			(copperpour not_allowed)
			(footprints allowed)
		)
		(placement
			(enabled no)
			(sheetname "")
		)
		(fill
			(thermal_gap 0.5)
			(thermal_bridge_width 0.5)
			(island_removal_mode 0)
		)
		(polygon
			(pts
				(arc
					(start 174.621952 -342.058498)
					(mid 174.240952 -342.439498)
					(end 174.621952 -342.820498)
				)
				(arc
					(start 175.485552 -342.820498)
					(mid 175.866552 -342.439498)
					(end 175.485552 -342.058498)
				)
			)
		)
	)
	(zone
		(layers "F.Cu" "B.Cu" "In1.Cu" "In2.Cu" "In3.Cu" "In4.Cu" "In5.Cu" "In6.Cu"
			"In7.Cu" "In8.Cu" "In9.Cu" "In10.Cu" "In11.Cu" "In12.Cu" "In13.Cu" "In14.Cu"
			"In15.Cu" "In16.Cu"
		)
		(hatch none 0.5)
		(connect_pads
			(clearance 0)
		)
		(min_thickness 0.25)
		(keepout
			(tracks not_allowed)
			(vias allowed)
			(pads allowed)
			(copperpour not_allowed)
			(footprints allowed)
		)
		(placement
			(enabled no)
			(sheetname "")
		)
		(fill
			(thermal_gap 0.5)
			(thermal_bridge_width 0.5)
			(island_removal_mode 0)
		)
		(polygon
			(pts
				(arc
					(start 150.768558 -120.087898)
					(mid 151.225758 -120.545098)
					(end 151.682958 -120.087898)
				)
				(arc
					(start 151.682958 -119.224298)
					(mid 151.225758 -118.767098)
					(end 150.768558 -119.224298)
				)
			)
		)
	)
	(zone
		(layers "F.Cu" "B.Cu" "In1.Cu" "In2.Cu" "In3.Cu" "In4.Cu" "In5.Cu" "In6.Cu"
			"In7.Cu" "In8.Cu" "In9.Cu" "In10.Cu" "In11.Cu" "In12.Cu" "In13.Cu" "In14.Cu"
			"In15.Cu" "In16.Cu"
		)
		(hatch none 0.5)
		(connect_pads
			(clearance 0)
		)
		(min_thickness 0.25)
		(keepout
			(tracks not_allowed)
			(vias allowed)
			(pads allowed)
			(copperpour not_allowed)
			(footprints allowed)
		)
		(placement
			(enabled no)
			(sheetname "")
		)
		(fill
			(thermal_gap 0.5)
			(thermal_bridge_width 0.5)
			(island_removal_mode 0)
		)
		(polygon
			(pts
				(arc
					(start 50.422048 -351.230438)
					(mid 50.041048 -351.611438)
					(end 50.422048 -351.992438)
				)
				(arc
					(start 51.285648 -351.992438)
					(mid 51.666648 -351.611438)
					(end 51.285648 -351.230438)
				)
			)
		)
	)
	(zone
		(layers "F.Cu" "B.Cu" "In1.Cu" "In2.Cu" "In3.Cu" "In4.Cu" "In5.Cu" "In6.Cu"
			"In7.Cu" "In8.Cu" "In9.Cu" "In10.Cu" "In11.Cu" "In12.Cu" "In13.Cu" "In14.Cu"
			"In15.Cu" "In16.Cu"
		)
		(hatch none 0.5)
		(connect_pads
			(clearance 0)
		)
		(min_thickness 0.25)
		(keepout
			(tracks not_allowed)
			(vias allowed)
			(pads allowed)
			(copperpour not_allowed)
			(footprints allowed)
		)
		(placement
			(enabled no)
			(sheetname "")
		)
		(fill
			(thermal_gap 0.5)
			(thermal_bridge_width 0.5)
			(island_removal_mode 0)
		)
		(polygon
			(pts
				(arc
					(start 193.275712 -345.084146)
					(mid 192.894712 -345.465146)
					(end 193.275712 -345.846146)
				)
				(arc
					(start 194.139312 -345.846146)
					(mid 194.520312 -345.465146)
					(end 194.139312 -345.084146)
				)
			)
		)
	)
	(zone
		(layers "F.Cu" "B.Cu" "In1.Cu" "In2.Cu" "In3.Cu" "In4.Cu" "In5.Cu" "In6.Cu"
			"In7.Cu" "In8.Cu" "In9.Cu" "In10.Cu" "In11.Cu" "In12.Cu" "In13.Cu" "In14.Cu"
			"In15.Cu" "In16.Cu"
		)
		(hatch none 0.5)
		(connect_pads
			(clearance 0)
		)
		(min_thickness 0.25)
		(keepout
			(tracks not_allowed)
			(vias allowed)
			(pads allowed)
			(copperpour not_allowed)
			(footprints allowed)
		)
		(placement
			(enabled no)
			(sheetname "")
		)
		(fill
			(thermal_gap 0.5)
			(thermal_bridge_width 0.5)
			(island_removal_mode 0)
		)
		(polygon
			(pts
				(arc
					(start 419.08095 -369.928902)
					(mid 419.095829 -369.892981)
					(end 419.13175 -369.878102)
				)
				(arc
					(start 419.84803 -369.878102)
					(mid 419.883951 -369.892981)
					(end 419.89883 -369.928902)
				)
				(arc
					(start 419.89883 -372.351554)
					(mid 419.883951 -372.387475)
					(end 419.84803 -372.402354)
				)
				(arc
					(start 419.13175 -372.402354)
					(mid 419.095829 -372.387475)
					(end 419.08095 -372.351554)
				)
			)
		)
	)
	(zone
		(layers "F.Cu" "B.Cu" "In1.Cu" "In2.Cu" "In3.Cu" "In4.Cu" "In5.Cu" "In6.Cu"
			"In7.Cu" "In8.Cu" "In9.Cu" "In10.Cu" "In11.Cu" "In12.Cu" "In13.Cu" "In14.Cu"
			"In15.Cu" "In16.Cu"
		)
		(hatch none 0.5)
		(connect_pads
			(clearance 0)
		)
		(min_thickness 0.25)
		(keepout
			(tracks not_allowed)
			(vias allowed)
			(pads allowed)
			(copperpour not_allowed)
			(footprints allowed)
		)
		(placement
			(enabled no)
			(sheetname "")
		)
		(fill
			(thermal_gap 0.5)
			(thermal_bridge_width 0.5)
			(island_removal_mode 0)
		)
		(polygon
			(pts
				(arc
					(start 302.48098 -378.828554)
					(mid 302.495859 -378.792633)
					(end 302.53178 -378.777754)
				)
				(arc
					(start 303.24806 -378.777754)
					(mid 303.283981 -378.792633)
					(end 303.29886 -378.828554)
				)
				(arc
					(start 303.29886 -381.251206)
					(mid 303.283981 -381.287127)
					(end 303.24806 -381.302006)
				)
				(arc
					(start 302.53178 -381.302006)
					(mid 302.495859 -381.287127)
					(end 302.48098 -381.251206)
				)
			)
		)
	)
	(zone
		(layers "F.Cu" "B.Cu" "In1.Cu" "In2.Cu" "In3.Cu" "In4.Cu" "In5.Cu" "In6.Cu"
			"In7.Cu" "In8.Cu" "In9.Cu" "In10.Cu" "In11.Cu" "In12.Cu" "In13.Cu" "In14.Cu"
			"In15.Cu" "In16.Cu"
		)
		(hatch none 0.5)
		(connect_pads
			(clearance 0)
		)
		(min_thickness 0.25)
		(keepout
			(tracks not_allowed)
			(vias allowed)
			(pads allowed)
			(copperpour not_allowed)
			(footprints allowed)
		)
		(placement
			(enabled no)
			(sheetname "")
		)
		(fill
			(thermal_gap 0.5)
			(thermal_bridge_width 0.5)
			(island_removal_mode 0)
		)
		(polygon
			(pts
				(arc
					(start 128.701038 -373.828818)
					(mid 128.715917 -373.792897)
					(end 128.751838 -373.778018)
				)
				(arc
					(start 129.468118 -373.778018)
					(mid 129.504039 -373.792897)
					(end 129.518918 -373.828818)
				)
				(arc
					(start 129.518918 -376.25147)
					(mid 129.504039 -376.287391)
					(end 129.468118 -376.30227)
				)
				(arc
					(start 128.751838 -376.30227)
					(mid 128.715917 -376.287391)
					(end 128.701038 -376.25147)
				)
			)
		)
	)
	(zone
		(layers "F.Cu" "B.Cu" "In1.Cu" "In2.Cu" "In3.Cu" "In4.Cu" "In5.Cu" "In6.Cu"
			"In7.Cu" "In8.Cu" "In9.Cu" "In10.Cu" "In11.Cu" "In12.Cu" "In13.Cu" "In14.Cu"
			"In15.Cu" "In16.Cu"
		)
		(hatch none 0.5)
		(connect_pads
			(clearance 0)
		)
		(min_thickness 0.25)
		(keepout
			(tracks not_allowed)
			(vias allowed)
			(pads allowed)
			(copperpour not_allowed)
			(footprints allowed)
		)
		(placement
			(enabled no)
			(sheetname "")
		)
		(fill
			(thermal_gap 0.5)
			(thermal_bridge_width 0.5)
			(island_removal_mode 0)
		)
		(polygon
			(pts
				(arc
					(start 427.881034 -395.92885)
					(mid 427.895913 -395.892929)
					(end 427.931834 -395.87805)
				)
				(arc
					(start 428.648114 -395.87805)
					(mid 428.684035 -395.892929)
					(end 428.698914 -395.92885)
				)
				(arc
					(start 428.698914 -398.351502)
					(mid 428.684035 -398.387423)
					(end 428.648114 -398.402302)
				)
				(arc
					(start 427.931834 -398.402302)
					(mid 427.895913 -398.387423)
					(end 427.881034 -398.351502)
				)
			)
		)
	)
	(zone
		(layers "F.Cu" "B.Cu" "In1.Cu" "In2.Cu" "In3.Cu" "In4.Cu" "In5.Cu" "In6.Cu"
			"In7.Cu" "In8.Cu" "In9.Cu" "In10.Cu" "In11.Cu" "In12.Cu" "In13.Cu" "In14.Cu"
			"In15.Cu" "In16.Cu"
		)
		(hatch none 0.5)
		(connect_pads
			(clearance 0)
		)
		(min_thickness 0.25)
		(keepout
			(tracks not_allowed)
			(vias allowed)
			(pads allowed)
			(copperpour not_allowed)
			(footprints allowed)
		)
		(placement
			(enabled no)
			(sheetname "")
		)
		(fill
			(thermal_gap 0.5)
			(thermal_bridge_width 0.5)
			(island_removal_mode 0)
		)
		(polygon
			(pts
				(arc
					(start 142.951708 -342.058498)
					(mid 142.570708 -342.439498)
					(end 142.951708 -342.820498)
				)
				(arc
					(start 143.815308 -342.820498)
					(mid 144.196308 -342.439498)
					(end 143.815308 -342.058498)
				)
			)
		)
	)
	(zone
		(layers "F.Cu" "B.Cu" "In1.Cu" "In2.Cu" "In3.Cu" "In4.Cu" "In5.Cu" "In6.Cu"
			"In7.Cu" "In8.Cu" "In9.Cu" "In10.Cu" "In11.Cu" "In12.Cu" "In13.Cu" "In14.Cu"
			"In15.Cu" "In16.Cu"
		)
		(hatch none 0.5)
		(connect_pads
			(clearance 0)
		)
		(min_thickness 0.25)
		(keepout
			(tracks not_allowed)
			(vias allowed)
			(pads allowed)
			(copperpour not_allowed)
			(footprints allowed)
		)
		(placement
			(enabled no)
			(sheetname "")
		)
		(fill
			(thermal_gap 0.5)
			(thermal_bridge_width 0.5)
			(island_removal_mode 0)
		)
		(polygon
			(pts
				(arc
					(start 279.690068 -34.520886)
					(mid 280.147268 -34.978086)
					(end 280.604468 -34.520886)
				)
				(arc
					(start 280.604468 -33.657286)
					(mid 280.147268 -33.200086)
					(end 279.690068 -33.657286)
				)
			)
		)
	)
	(zone
		(layers "F.Cu" "B.Cu" "In1.Cu" "In2.Cu" "In3.Cu" "In4.Cu" "In5.Cu" "In6.Cu"
			"In7.Cu" "In8.Cu" "In9.Cu" "In10.Cu" "In11.Cu" "In12.Cu" "In13.Cu" "In14.Cu"
			"In15.Cu" "In16.Cu"
		)
		(hatch none 0.5)
		(connect_pads
			(clearance 0)
		)
		(min_thickness 0.25)
		(keepout
			(tracks not_allowed)
			(vias allowed)
			(pads allowed)
			(copperpour not_allowed)
			(footprints allowed)
		)
		(placement
			(enabled no)
			(sheetname "")
		)
		(fill
			(thermal_gap 0.5)
			(thermal_bridge_width 0.5)
			(island_removal_mode 0)
		)
		(polygon
			(pts
				(arc
					(start 182.700168 -134.377176)
					(mid 183.157368 -134.834376)
					(end 183.614568 -134.377176)
				)
				(arc
					(start 183.614568 -133.513576)
					(mid 183.157368 -133.056376)
					(end 182.700168 -133.513576)
				)
			)
		)
	)
	(zone
		(layers "F.Cu" "B.Cu" "In1.Cu" "In2.Cu" "In3.Cu" "In4.Cu" "In5.Cu" "In6.Cu"
			"In7.Cu" "In8.Cu" "In9.Cu" "In10.Cu" "In11.Cu" "In12.Cu" "In13.Cu" "In14.Cu"
			"In15.Cu" "In16.Cu"
		)
		(hatch none 0.5)
		(connect_pads
			(clearance 0)
		)
		(min_thickness 0.25)
		(keepout
			(tracks not_allowed)
			(vias allowed)
			(pads allowed)
			(copperpour not_allowed)
			(footprints allowed)
		)
		(placement
			(enabled no)
			(sheetname "")
		)
		(fill
			(thermal_gap 0.5)
			(thermal_bridge_width 0.5)
			(island_removal_mode 0)
		)
		(polygon
			(pts
				(arc
					(start 267.897102 -351.230438)
					(mid 267.516102 -351.611438)
					(end 267.897102 -351.992438)
				)
				(arc
					(start 268.760702 -351.992438)
					(mid 269.141702 -351.611438)
					(end 268.760702 -351.230438)
				)
			)
		)
	)
	(zone
		(layers "F.Cu" "B.Cu" "In1.Cu" "In2.Cu" "In3.Cu" "In4.Cu" "In5.Cu" "In6.Cu"
			"In7.Cu" "In8.Cu" "In9.Cu" "In10.Cu" "In11.Cu" "In12.Cu" "In13.Cu" "In14.Cu"
			"In15.Cu" "In16.Cu"
		)
		(hatch none 0.5)
		(connect_pads
			(clearance 0)
		)
		(min_thickness 0.25)
		(keepout
			(tracks not_allowed)
			(vias allowed)
			(pads allowed)
			(copperpour not_allowed)
			(footprints allowed)
		)
		(placement
			(enabled no)
			(sheetname "")
		)
		(fill
			(thermal_gap 0.5)
			(thermal_bridge_width 0.5)
			(island_removal_mode 0)
		)
		(polygon
			(pts
				(arc
					(start 396.05966 -357.37673)
					(mid 395.67866 -357.75773)
					(end 396.05966 -358.13873)
				)
				(arc
					(start 396.92326 -358.13873)
					(mid 397.30426 -357.75773)
					(end 396.92326 -357.37673)
				)
			)
		)
	)
	(zone
		(layers "F.Cu" "B.Cu" "In1.Cu" "In2.Cu" "In3.Cu" "In4.Cu" "In5.Cu" "In6.Cu"
			"In7.Cu" "In8.Cu" "In9.Cu" "In10.Cu" "In11.Cu" "In12.Cu" "In13.Cu" "In14.Cu"
			"In15.Cu" "In16.Cu"
		)
		(hatch none 0.5)
		(connect_pads
			(clearance 0)
		)
		(min_thickness 0.25)
		(keepout
			(tracks not_allowed)
			(vias allowed)
			(pads allowed)
			(copperpour not_allowed)
			(footprints allowed)
		)
		(placement
			(enabled no)
			(sheetname "")
		)
		(fill
			(thermal_gap 0.5)
			(thermal_bridge_width 0.5)
			(island_removal_mode 0)
		)
		(polygon
			(pts
				(arc
					(start 300.280832 -407.628852)
					(mid 300.295711 -407.592931)
					(end 300.331632 -407.578052)
				)
				(arc
					(start 301.047912 -407.578052)
					(mid 301.083833 -407.592931)
					(end 301.098712 -407.628852)
				)
				(arc
					(start 301.098712 -410.051504)
					(mid 301.083833 -410.087425)
					(end 301.047912 -410.102304)
				)
				(arc
					(start 300.331632 -410.102304)
					(mid 300.295711 -410.087425)
					(end 300.280832 -410.051504)
				)
			)
		)
	)
	(zone
		(layers "F.Cu" "B.Cu" "In1.Cu" "In2.Cu" "In3.Cu" "In4.Cu" "In5.Cu" "In6.Cu"
			"In7.Cu" "In8.Cu" "In9.Cu" "In10.Cu" "In11.Cu" "In12.Cu" "In13.Cu" "In14.Cu"
			"In15.Cu" "In16.Cu"
		)
		(hatch none 0.5)
		(connect_pads
			(clearance 0)
		)
		(min_thickness 0.25)
		(keepout
			(tracks not_allowed)
			(vias allowed)
			(pads allowed)
			(copperpour not_allowed)
			(footprints allowed)
		)
		(placement
			(enabled no)
			(sheetname "")
		)
		(fill
			(thermal_gap 0.5)
			(thermal_bridge_width 0.5)
			(island_removal_mode 0)
		)
		(polygon
			(pts
				(arc
					(start 50.422048 -357.37673)
					(mid 50.041048 -357.75773)
					(end 50.422048 -358.13873)
				)
				(arc
					(start 51.285648 -358.13873)
					(mid 51.666648 -357.75773)
					(end 51.285648 -357.37673)
				)
			)
		)
	)
	(zone
		(layers "F.Cu" "B.Cu" "In1.Cu" "In2.Cu" "In3.Cu" "In4.Cu" "In5.Cu" "In6.Cu"
			"In7.Cu" "In8.Cu" "In9.Cu" "In10.Cu" "In11.Cu" "In12.Cu" "In13.Cu" "In14.Cu"
			"In15.Cu" "In16.Cu"
		)
		(hatch none 0.5)
		(connect_pads
			(clearance 0)
		)
		(min_thickness 0.25)
		(keepout
			(tracks not_allowed)
			(vias allowed)
			(pads allowed)
			(copperpour not_allowed)
			(footprints allowed)
		)
		(placement
			(enabled no)
			(sheetname "")
		)
		(fill
			(thermal_gap 0.5)
			(thermal_bridge_width 0.5)
			(island_removal_mode 0)
		)
		(polygon
			(pts
				(arc
					(start 47.313088 -345.084146)
					(mid 46.932088 -345.465146)
					(end 47.313088 -345.846146)
				)
				(arc
					(start 48.176688 -345.846146)
					(mid 48.557688 -345.465146)
					(end 48.176688 -345.084146)
				)
			)
		)
	)
	(zone
		(layers "F.Cu" "B.Cu" "In1.Cu" "In2.Cu" "In3.Cu" "In4.Cu" "In5.Cu" "In6.Cu"
			"In7.Cu" "In8.Cu" "In9.Cu" "In10.Cu" "In11.Cu" "In12.Cu" "In13.Cu" "In14.Cu"
			"In15.Cu" "In16.Cu"
		)
		(hatch none 0.5)
		(connect_pads
			(clearance 0)
		)
		(min_thickness 0.25)
		(keepout
			(tracks not_allowed)
			(vias allowed)
			(pads allowed)
			(copperpour not_allowed)
			(footprints allowed)
		)
		(placement
			(enabled no)
			(sheetname "")
		)
		(fill
			(thermal_gap 0.5)
			(thermal_bridge_width 0.5)
			(island_removal_mode 0)
		)
		(polygon
			(pts
				(arc
					(start 111.862108 -351.230438)
					(mid 111.481108 -351.611438)
					(end 111.862108 -351.992438)
				)
				(arc
					(start 112.725708 -351.992438)
					(mid 113.106708 -351.611438)
					(end 112.725708 -351.230438)
				)
			)
		)
	)
	(zone
		(layers "F.Cu" "B.Cu" "In1.Cu" "In2.Cu" "In3.Cu" "In4.Cu" "In5.Cu" "In6.Cu"
			"In7.Cu" "In8.Cu" "In9.Cu" "In10.Cu" "In11.Cu" "In12.Cu" "In13.Cu" "In14.Cu"
			"In15.Cu" "In16.Cu"
		)
		(hatch none 0.5)
		(connect_pads
			(clearance 0)
		)
		(min_thickness 0.25)
		(keepout
			(tracks not_allowed)
			(vias allowed)
			(pads allowed)
			(copperpour not_allowed)
			(footprints allowed)
		)
		(placement
			(enabled no)
			(sheetname "")
		)
		(fill
			(thermal_gap 0.5)
			(thermal_bridge_width 0.5)
			(island_removal_mode 0)
		)
		(polygon
			(pts
				(arc
					(start 371.18798 -345.084146)
					(mid 370.80698 -345.465146)
					(end 371.18798 -345.846146)
				)
				(arc
					(start 372.05158 -345.846146)
					(mid 372.43258 -345.465146)
					(end 372.05158 -345.084146)
				)
			)
		)
	)
	(zone
		(layers "F.Cu" "B.Cu" "In1.Cu" "In2.Cu" "In3.Cu" "In4.Cu" "In5.Cu" "In6.Cu"
			"In7.Cu" "In8.Cu" "In9.Cu" "In10.Cu" "In11.Cu" "In12.Cu" "In13.Cu" "In14.Cu"
			"In15.Cu" "In16.Cu"
		)
		(hatch none 0.5)
		(connect_pads
			(clearance 0)
		)
		(min_thickness 0.25)
		(keepout
			(tracks not_allowed)
			(vias allowed)
			(pads allowed)
			(copperpour not_allowed)
			(footprints allowed)
		)
		(placement
			(enabled no)
			(sheetname "")
		)
		(fill
			(thermal_gap 0.5)
			(thermal_bridge_width 0.5)
			(island_removal_mode 0)
		)
		(polygon
			(pts
				(arc
					(start 182.030116 -36.60013)
					(mid 180.099716 -36.60013)
					(end 182.030116 -36.60013)
				)
			)
		)
	)
	(zone
		(layers "F.Cu" "B.Cu" "In1.Cu" "In2.Cu" "In3.Cu" "In4.Cu" "In5.Cu" "In6.Cu"
			"In7.Cu" "In8.Cu" "In9.Cu" "In10.Cu" "In11.Cu" "In12.Cu" "In13.Cu" "In14.Cu"
			"In15.Cu" "In16.Cu"
		)
		(hatch none 0.5)
		(connect_pads
			(clearance 0)
		)
		(min_thickness 0.25)
		(keepout
			(tracks not_allowed)
			(vias allowed)
			(pads allowed)
			(copperpour not_allowed)
			(footprints allowed)
		)
		(placement
			(enabled no)
			(sheetname "")
		)
		(fill
			(thermal_gap 0.5)
			(thermal_bridge_width 0.5)
			(island_removal_mode 0)
		)
		(polygon
			(pts
				(arc
					(start 118.080028 -342.058498)
					(mid 117.699028 -342.439498)
					(end 118.080028 -342.820498)
				)
				(arc
					(start 118.943628 -342.820498)
					(mid 119.324628 -342.439498)
					(end 118.943628 -342.058498)
				)
			)
		)
	)
	(zone
		(layers "F.Cu" "B.Cu" "In1.Cu" "In2.Cu" "In3.Cu" "In4.Cu" "In5.Cu" "In6.Cu"
			"In7.Cu" "In8.Cu" "In9.Cu" "In10.Cu" "In11.Cu" "In12.Cu" "In13.Cu" "In14.Cu"
			"In15.Cu" "In16.Cu"
		)
		(hatch none 0.5)
		(connect_pads
			(clearance 0)
		)
		(min_thickness 0.25)
		(keepout
			(tracks not_allowed)
			(vias allowed)
			(pads allowed)
			(copperpour not_allowed)
			(footprints allowed)
		)
		(placement
			(enabled no)
			(sheetname "")
		)
		(fill
			(thermal_gap 0.5)
			(thermal_bridge_width 0.5)
			(island_removal_mode 0)
		)
		(polygon
			(pts
				(arc
					(start 28.659328 -348.20479)
					(mid 28.278328 -348.58579)
					(end 28.659328 -348.96679)
				)
				(arc
					(start 29.522928 -348.96679)
					(mid 29.903928 -348.58579)
					(end 29.522928 -348.20479)
				)
			)
		)
	)
	(zone
		(layers "F.Cu" "B.Cu" "In1.Cu" "In2.Cu" "In3.Cu" "In4.Cu" "In5.Cu" "In6.Cu"
			"In7.Cu" "In8.Cu" "In9.Cu" "In10.Cu" "In11.Cu" "In12.Cu" "In13.Cu" "In14.Cu"
			"In15.Cu" "In16.Cu"
		)
		(hatch none 0.5)
		(connect_pads
			(clearance 0)
		)
		(min_thickness 0.25)
		(keepout
			(tracks not_allowed)
			(vias allowed)
			(pads allowed)
			(copperpour not_allowed)
			(footprints allowed)
		)
		(placement
			(enabled no)
			(sheetname "")
		)
		(fill
			(thermal_gap 0.5)
			(thermal_bridge_width 0.5)
			(island_removal_mode 0)
		)
		(polygon
			(pts
				(arc
					(start 61.372242 -342.058498)
					(mid 60.991242 -342.439498)
					(end 61.372242 -342.820498)
				)
				(arc
					(start 62.235842 -342.820498)
					(mid 62.616842 -342.439498)
					(end 62.235842 -342.058498)
				)
			)
		)
	)
	(zone
		(layers "F.Cu" "B.Cu" "In1.Cu" "In2.Cu" "In3.Cu" "In4.Cu" "In5.Cu" "In6.Cu"
			"In7.Cu" "In8.Cu" "In9.Cu" "In10.Cu" "In11.Cu" "In12.Cu" "In13.Cu" "In14.Cu"
			"In15.Cu" "In16.Cu"
		)
		(hatch none 0.5)
		(connect_pads
			(clearance 0)
		)
		(min_thickness 0.25)
		(keepout
			(tracks not_allowed)
			(vias allowed)
			(pads allowed)
			(copperpour not_allowed)
			(footprints allowed)
		)
		(placement
			(enabled no)
			(sheetname "")
		)
		(fill
			(thermal_gap 0.5)
			(thermal_bridge_width 0.5)
			(island_removal_mode 0)
		)
		(polygon
			(pts
				(arc
					(start 295.881044 -377.728734)
					(mid 295.895923 -377.692813)
					(end 295.931844 -377.677934)
				)
				(arc
					(start 296.648124 -377.677934)
					(mid 296.684045 -377.692813)
					(end 296.698924 -377.728734)
				)
				(arc
					(start 296.698924 -380.151386)
					(mid 296.684045 -380.187307)
					(end 296.648124 -380.202186)
				)
				(arc
					(start 295.931844 -380.202186)
					(mid 295.895923 -380.187307)
					(end 295.881044 -380.151386)
				)
			)
		)
	)
	(zone
		(layers "F.Cu" "B.Cu" "In1.Cu" "In2.Cu" "In3.Cu" "In4.Cu" "In5.Cu" "In6.Cu"
			"In7.Cu" "In8.Cu" "In9.Cu" "In10.Cu" "In11.Cu" "In12.Cu" "In13.Cu" "In14.Cu"
			"In15.Cu" "In16.Cu"
		)
		(hatch none 0.5)
		(connect_pads
			(clearance 0)
		)
		(min_thickness 0.25)
		(keepout
			(tracks not_allowed)
			(vias allowed)
			(pads allowed)
			(copperpour not_allowed)
			(footprints allowed)
		)
		(placement
			(enabled no)
			(sheetname "")
		)
		(fill
			(thermal_gap 0.5)
			(thermal_bridge_width 0.5)
			(island_removal_mode 0)
		)
		(polygon
			(pts
				(arc
					(start 83.71713 -124.965714)
					(mid 84.17433 -125.422914)
					(end 84.63153 -124.965714)
				)
				(arc
					(start 84.63153 -124.102114)
					(mid 84.17433 -123.644914)
					(end 83.71713 -124.102114)
				)
			)
		)
	)
	(zone
		(layers "F.Cu" "B.Cu" "In1.Cu" "In2.Cu" "In3.Cu" "In4.Cu" "In5.Cu" "In6.Cu"
			"In7.Cu" "In8.Cu" "In9.Cu" "In10.Cu" "In11.Cu" "In12.Cu" "In13.Cu" "In14.Cu"
			"In15.Cu" "In16.Cu"
		)
		(hatch none 0.5)
		(connect_pads
			(clearance 0)
		)
		(min_thickness 0.25)
		(keepout
			(tracks not_allowed)
			(vias allowed)
			(pads allowed)
			(copperpour not_allowed)
			(footprints allowed)
		)
		(placement
			(enabled no)
			(sheetname "")
		)
		(fill
			(thermal_gap 0.5)
			(thermal_bridge_width 0.5)
			(island_removal_mode 0)
		)
		(polygon
			(pts
				(arc
					(start 31.90113 -403.728682)
					(mid 31.916009 -403.692761)
					(end 31.95193 -403.677882)
				)
				(arc
					(start 32.66821 -403.677882)
					(mid 32.704131 -403.692761)
					(end 32.71901 -403.728682)
				)
				(arc
					(start 32.71901 -406.151334)
					(mid 32.704131 -406.187255)
					(end 32.66821 -406.202134)
				)
				(arc
					(start 31.95193 -406.202134)
					(mid 31.916009 -406.187255)
					(end 31.90113 -406.151334)
				)
			)
		)
	)
	(zone
		(layers "F.Cu" "B.Cu" "In1.Cu" "In2.Cu" "In3.Cu" "In4.Cu" "In5.Cu" "In6.Cu"
			"In7.Cu" "In8.Cu" "In9.Cu" "In10.Cu" "In11.Cu" "In12.Cu" "In13.Cu" "In14.Cu"
			"In15.Cu" "In16.Cu"
		)
		(hatch none 0.5)
		(connect_pads
			(clearance 0)
		)
		(min_thickness 0.25)
		(keepout
			(tracks not_allowed)
			(vias allowed)
			(pads allowed)
			(copperpour not_allowed)
			(footprints allowed)
		)
		(placement
			(enabled no)
			(sheetname "")
		)
		(fill
			(thermal_gap 0.5)
			(thermal_bridge_width 0.5)
			(island_removal_mode 0)
		)
		(polygon
			(pts
				(arc
					(start 429.375062 -147.079208)
					(mid 429.832262 -147.536408)
					(end 430.289462 -147.079208)
				)
				(arc
					(start 430.289462 -146.215608)
					(mid 429.832262 -145.758408)
					(end 429.375062 -146.215608)
				)
			)
		)
	)
	(zone
		(layers "F.Cu" "B.Cu" "In1.Cu" "In2.Cu" "In3.Cu" "In4.Cu" "In5.Cu" "In6.Cu"
			"In7.Cu" "In8.Cu" "In9.Cu" "In10.Cu" "In11.Cu" "In12.Cu" "In13.Cu" "In14.Cu"
			"In15.Cu" "In16.Cu"
		)
		(hatch none 0.5)
		(connect_pads
			(clearance 0)
		)
		(min_thickness 0.25)
		(keepout
			(tracks not_allowed)
			(vias allowed)
			(pads allowed)
			(copperpour not_allowed)
			(footprints allowed)
		)
		(placement
			(enabled no)
			(sheetname "")
		)
		(fill
			(thermal_gap 0.5)
			(thermal_bridge_width 0.5)
			(island_removal_mode 0)
		)
		(polygon
			(pts
				(arc
					(start 142.951708 -351.230438)
					(mid 142.570708 -351.611438)
					(end 142.951708 -351.992438)
				)
				(arc
					(start 143.815308 -351.992438)
					(mid 144.196308 -351.611438)
					(end 143.815308 -351.230438)
				)
			)
		)
	)
	(zone
		(layers "F.Cu" "B.Cu" "In1.Cu" "In2.Cu" "In3.Cu" "In4.Cu" "In5.Cu" "In6.Cu"
			"In7.Cu" "In8.Cu" "In9.Cu" "In10.Cu" "In11.Cu" "In12.Cu" "In13.Cu" "In14.Cu"
			"In15.Cu" "In16.Cu"
		)
		(hatch none 0.5)
		(connect_pads
			(clearance 0)
		)
		(min_thickness 0.25)
		(keepout
			(tracks not_allowed)
			(vias allowed)
			(pads allowed)
			(copperpour not_allowed)
			(footprints allowed)
		)
		(placement
			(enabled no)
			(sheetname "")
		)
		(fill
			(thermal_gap 0.5)
			(thermal_bridge_width 0.5)
			(island_removal_mode 0)
		)
		(polygon
			(pts
				(arc
					(start 130.515868 -354.351082)
					(mid 130.134868 -354.732082)
					(end 130.515868 -355.113082)
				)
				(arc
					(start 131.379468 -355.113082)
					(mid 131.760468 -354.732082)
					(end 131.379468 -354.351082)
				)
			)
		)
	)
	(zone
		(layers "F.Cu" "B.Cu" "In1.Cu" "In2.Cu" "In3.Cu" "In4.Cu" "In5.Cu" "In6.Cu"
			"In7.Cu" "In8.Cu" "In9.Cu" "In10.Cu" "In11.Cu" "In12.Cu" "In13.Cu" "In14.Cu"
			"In15.Cu" "In16.Cu"
		)
		(hatch none 0.5)
		(connect_pads
			(clearance 0)
		)
		(min_thickness 0.25)
		(keepout
			(tracks not_allowed)
			(vias allowed)
			(pads allowed)
			(copperpour not_allowed)
			(footprints allowed)
		)
		(placement
			(enabled no)
			(sheetname "")
		)
		(fill
			(thermal_gap 0.5)
			(thermal_bridge_width 0.5)
			(island_removal_mode 0)
		)
		(polygon
			(pts
				(arc
					(start 168.301162 -373.828818)
					(mid 168.316041 -373.792897)
					(end 168.351962 -373.778018)
				)
				(arc
					(start 169.068242 -373.778018)
					(mid 169.104163 -373.792897)
					(end 169.119042 -373.828818)
				)
				(arc
					(start 169.119042 -376.25147)
					(mid 169.104163 -376.287391)
					(end 169.068242 -376.30227)
				)
				(arc
					(start 168.351962 -376.30227)
					(mid 168.316041 -376.287391)
					(end 168.301162 -376.25147)
				)
			)
		)
	)
	(zone
		(layers "F.Cu" "B.Cu" "In1.Cu" "In2.Cu" "In3.Cu" "In4.Cu" "In5.Cu" "In6.Cu"
			"In7.Cu" "In8.Cu" "In9.Cu" "In10.Cu" "In11.Cu" "In12.Cu" "In13.Cu" "In14.Cu"
			"In15.Cu" "In16.Cu"
		)
		(hatch none 0.5)
		(connect_pads
			(clearance 0)
		)
		(min_thickness 0.25)
		(keepout
			(tracks not_allowed)
			(vias allowed)
			(pads allowed)
			(copperpour not_allowed)
			(footprints allowed)
		)
		(placement
			(enabled no)
			(sheetname "")
		)
		(fill
			(thermal_gap 0.5)
			(thermal_bridge_width 0.5)
			(island_removal_mode 0)
		)
		(polygon
			(pts
				(arc
					(start 344.280998 -377.728734)
					(mid 344.295877 -377.692813)
					(end 344.331798 -377.677934)
				)
				(arc
					(start 345.048078 -377.677934)
					(mid 345.083999 -377.692813)
					(end 345.098878 -377.728734)
				)
				(arc
					(start 345.098878 -380.151386)
					(mid 345.083999 -380.187307)
					(end 345.048078 -380.202186)
				)
				(arc
					(start 344.331798 -380.202186)
					(mid 344.295877 -380.187307)
					(end 344.280998 -380.151386)
				)
			)
		)
	)
	(zone
		(layers "F.Cu" "B.Cu" "In1.Cu" "In2.Cu" "In3.Cu" "In4.Cu" "In5.Cu" "In6.Cu"
			"In7.Cu" "In8.Cu" "In9.Cu" "In10.Cu" "In11.Cu" "In12.Cu" "In13.Cu" "In14.Cu"
			"In15.Cu" "In16.Cu"
		)
		(hatch none 0.5)
		(connect_pads
			(clearance 0)
		)
		(min_thickness 0.25)
		(keepout
			(tracks not_allowed)
			(vias allowed)
			(pads allowed)
			(copperpour not_allowed)
			(footprints allowed)
		)
		(placement
			(enabled no)
			(sheetname "")
		)
		(fill
			(thermal_gap 0.5)
			(thermal_bridge_width 0.5)
			(island_removal_mode 0)
		)
		(polygon
			(pts
				(arc
					(start 130.901186 -408.728672)
					(mid 130.916065 -408.692751)
					(end 130.951986 -408.677872)
				)
				(arc
					(start 131.668266 -408.677872)
					(mid 131.704187 -408.692751)
					(end 131.719066 -408.728672)
				)
				(arc
					(start 131.719066 -411.151324)
					(mid 131.704187 -411.187245)
					(end 131.668266 -411.202124)
				)
				(arc
					(start 130.951986 -411.202124)
					(mid 130.916065 -411.187245)
					(end 130.901186 -411.151324)
				)
			)
		)
	)
	(zone
		(layers "F.Cu" "B.Cu" "In1.Cu" "In2.Cu" "In3.Cu" "In4.Cu" "In5.Cu" "In6.Cu"
			"In7.Cu" "In8.Cu" "In9.Cu" "In10.Cu" "In11.Cu" "In12.Cu" "In13.Cu" "In14.Cu"
			"In15.Cu" "In16.Cu"
		)
		(hatch none 0.5)
		(connect_pads
			(clearance 0)
		)
		(min_thickness 0.25)
		(keepout
			(tracks not_allowed)
			(vias allowed)
			(pads allowed)
			(copperpour not_allowed)
			(footprints allowed)
		)
		(placement
			(enabled no)
			(sheetname "")
		)
		(fill
			(thermal_gap 0.5)
			(thermal_bridge_width 0.5)
			(island_removal_mode 0)
		)
		(polygon
			(pts
				(arc
					(start 337.681062 -408.728672)
					(mid 337.695941 -408.692751)
					(end 337.731862 -408.677872)
				)
				(arc
					(start 338.448142 -408.677872)
					(mid 338.484063 -408.692751)
					(end 338.498942 -408.728672)
				)
				(arc
					(start 338.498942 -411.151324)
					(mid 338.484063 -411.187245)
					(end 338.448142 -411.202124)
				)
				(arc
					(start 337.731862 -411.202124)
					(mid 337.695941 -411.187245)
					(end 337.681062 -411.151324)
				)
			)
		)
	)
	(zone
		(layers "F.Cu" "B.Cu" "In1.Cu" "In2.Cu" "In3.Cu" "In4.Cu" "In5.Cu" "In6.Cu"
			"In7.Cu" "In8.Cu" "In9.Cu" "In10.Cu" "In11.Cu" "In12.Cu" "In13.Cu" "In14.Cu"
			"In15.Cu" "In16.Cu"
		)
		(hatch none 0.5)
		(connect_pads
			(clearance 0)
		)
		(min_thickness 0.25)
		(keepout
			(tracks not_allowed)
			(vias allowed)
			(pads allowed)
			(copperpour not_allowed)
			(footprints allowed)
		)
		(placement
			(enabled no)
			(sheetname "")
		)
		(fill
			(thermal_gap 0.5)
			(thermal_bridge_width 0.5)
			(island_removal_mode 0)
		)
		(polygon
			(pts
				(arc
					(start 427.948852 -354.351082)
					(mid 427.567852 -354.732082)
					(end 427.948852 -355.113082)
				)
				(arc
					(start 428.812452 -355.113082)
					(mid 429.193452 -354.732082)
					(end 428.812452 -354.351082)
				)
			)
		)
	)
	(zone
		(layers "F.Cu" "B.Cu" "In1.Cu" "In2.Cu" "In3.Cu" "In4.Cu" "In5.Cu" "In6.Cu"
			"In7.Cu" "In8.Cu" "In9.Cu" "In10.Cu" "In11.Cu" "In12.Cu" "In13.Cu" "In14.Cu"
			"In15.Cu" "In16.Cu"
		)
		(hatch none 0.5)
		(connect_pads
			(clearance 0)
		)
		(min_thickness 0.25)
		(keepout
			(tracks not_allowed)
			(vias allowed)
			(pads allowed)
			(copperpour not_allowed)
			(footprints allowed)
		)
		(placement
			(enabled no)
			(sheetname "")
		)
		(fill
			(thermal_gap 0.5)
			(thermal_bridge_width 0.5)
			(island_removal_mode 0)
		)
		(polygon
			(pts
				(arc
					(start 342.081104 -397.028924)
					(mid 342.095983 -396.993003)
					(end 342.131904 -396.978124)
				)
				(arc
					(start 342.848184 -396.978124)
					(mid 342.884105 -396.993003)
					(end 342.898984 -397.028924)
				)
				(arc
					(start 342.898984 -399.451576)
					(mid 342.884105 -399.487497)
					(end 342.848184 -399.502376)
				)
				(arc
					(start 342.131904 -399.502376)
					(mid 342.095983 -399.487497)
					(end 342.081104 -399.451576)
				)
			)
		)
	)
	(zone
		(layers "F.Cu" "B.Cu" "In1.Cu" "In2.Cu" "In3.Cu" "In4.Cu" "In5.Cu" "In6.Cu"
			"In7.Cu" "In8.Cu" "In9.Cu" "In10.Cu" "In11.Cu" "In12.Cu" "In13.Cu" "In14.Cu"
			"In15.Cu" "In16.Cu"
		)
		(hatch none 0.5)
		(connect_pads
			(clearance 0)
		)
		(min_thickness 0.25)
		(keepout
			(tracks not_allowed)
			(vias allowed)
			(pads allowed)
			(copperpour not_allowed)
			(footprints allowed)
		)
		(placement
			(enabled no)
			(sheetname "")
		)
		(fill
			(thermal_gap 0.5)
			(thermal_bridge_width 0.5)
			(island_removal_mode 0)
		)
		(polygon
			(pts
				(arc
					(start 396.05966 -351.230438)
					(mid 395.67866 -351.611438)
					(end 396.05966 -351.992438)
				)
				(arc
					(start 396.92326 -351.992438)
					(mid 397.30426 -351.611438)
					(end 396.92326 -351.230438)
				)
			)
		)
	)
	(zone
		(layers "F.Cu" "B.Cu" "In1.Cu" "In2.Cu" "In3.Cu" "In4.Cu" "In5.Cu" "In6.Cu"
			"In7.Cu" "In8.Cu" "In9.Cu" "In10.Cu" "In11.Cu" "In12.Cu" "In13.Cu" "In14.Cu"
			"In15.Cu" "In16.Cu"
		)
		(hatch none 0.5)
		(connect_pads
			(clearance 0)
		)
		(min_thickness 0.25)
		(keepout
			(tracks not_allowed)
			(vias allowed)
			(pads allowed)
			(copperpour not_allowed)
			(footprints allowed)
		)
		(placement
			(enabled no)
			(sheetname "")
		)
		(fill
			(thermal_gap 0.5)
			(thermal_bridge_width 0.5)
			(island_removal_mode 0)
		)
		(polygon
			(pts
				(arc
					(start 28.659328 -351.230438)
					(mid 28.278328 -351.611438)
					(end 28.659328 -351.992438)
				)
				(arc
					(start 29.522928 -351.992438)
					(mid 29.903928 -351.611438)
					(end 29.522928 -351.230438)
				)
			)
		)
	)
	(zone
		(layers "F.Cu" "B.Cu" "In1.Cu" "In2.Cu" "In3.Cu" "In4.Cu" "In5.Cu" "In6.Cu"
			"In7.Cu" "In8.Cu" "In9.Cu" "In10.Cu" "In11.Cu" "In12.Cu" "In13.Cu" "In14.Cu"
			"In15.Cu" "In16.Cu"
		)
		(hatch none 0.5)
		(connect_pads
			(clearance 0)
		)
		(min_thickness 0.25)
		(keepout
			(tracks not_allowed)
			(vias allowed)
			(pads allowed)
			(copperpour not_allowed)
			(footprints allowed)
		)
		(placement
			(enabled no)
			(sheetname "")
		)
		(fill
			(thermal_gap 0.5)
			(thermal_bridge_width 0.5)
			(island_removal_mode 0)
		)
		(polygon
			(pts
				(arc
					(start 37.986208 -351.230438)
					(mid 37.605208 -351.611438)
					(end 37.986208 -351.992438)
				)
				(arc
					(start 38.849808 -351.992438)
					(mid 39.230808 -351.611438)
					(end 38.849808 -351.230438)
				)
			)
		)
	)
	(zone
		(layers "F.Cu" "B.Cu" "In1.Cu" "In2.Cu" "In3.Cu" "In4.Cu" "In5.Cu" "In6.Cu"
			"In7.Cu" "In8.Cu" "In9.Cu" "In10.Cu" "In11.Cu" "In12.Cu" "In13.Cu" "In14.Cu"
			"In15.Cu" "In16.Cu"
		)
		(hatch none 0.5)
		(connect_pads
			(clearance 0)
		)
		(min_thickness 0.25)
		(keepout
			(tracks not_allowed)
			(vias allowed)
			(pads allowed)
			(copperpour not_allowed)
			(footprints allowed)
		)
		(placement
			(enabled no)
			(sheetname "")
		)
		(fill
			(thermal_gap 0.5)
			(thermal_bridge_width 0.5)
			(island_removal_mode 0)
		)
		(polygon
			(pts
				(arc
					(start 418.621972 -348.20479)
					(mid 418.240972 -348.58579)
					(end 418.621972 -348.96679)
				)
				(arc
					(start 419.485572 -348.96679)
					(mid 419.866572 -348.58579)
					(end 419.485572 -348.20479)
				)
			)
		)
	)
	(zone
		(layers "F.Cu" "B.Cu" "In1.Cu" "In2.Cu" "In3.Cu" "In4.Cu" "In5.Cu" "In6.Cu"
			"In7.Cu" "In8.Cu" "In9.Cu" "In10.Cu" "In11.Cu" "In12.Cu" "In13.Cu" "In14.Cu"
			"In15.Cu" "In16.Cu"
		)
		(hatch none 0.5)
		(connect_pads
			(clearance 0)
		)
		(min_thickness 0.25)
		(keepout
			(tracks not_allowed)
			(vias allowed)
			(pads allowed)
			(copperpour not_allowed)
			(footprints allowed)
		)
		(placement
			(enabled no)
			(sheetname "")
		)
		(fill
			(thermal_gap 0.5)
			(thermal_bridge_width 0.5)
			(island_removal_mode 0)
		)
		(polygon
			(pts
				(arc
					(start 447.790062 -30.92069)
					(mid 448.247262 -31.37789)
					(end 448.704462 -30.92069)
				)
				(arc
					(start 448.704462 -30.05709)
					(mid 448.247262 -29.59989)
					(end 447.790062 -30.05709)
				)
			)
		)
	)
	(zone
		(layers "F.Cu" "B.Cu" "In1.Cu" "In2.Cu" "In3.Cu" "In4.Cu" "In5.Cu" "In6.Cu"
			"In7.Cu" "In8.Cu" "In9.Cu" "In10.Cu" "In11.Cu" "In12.Cu" "In13.Cu" "In14.Cu"
			"In15.Cu" "In16.Cu"
		)
		(hatch none 0.5)
		(connect_pads
			(clearance 0)
		)
		(min_thickness 0.25)
		(keepout
			(tracks not_allowed)
			(vias allowed)
			(pads allowed)
			(copperpour not_allowed)
			(footprints allowed)
		)
		(placement
			(enabled no)
			(sheetname "")
		)
		(fill
			(thermal_gap 0.5)
			(thermal_bridge_width 0.5)
			(island_removal_mode 0)
		)
		(polygon
			(pts
				(arc
					(start 76.917042 -354.351082)
					(mid 76.536042 -354.732082)
					(end 76.917042 -355.113082)
				)
				(arc
					(start 77.780642 -355.113082)
					(mid 78.161642 -354.732082)
					(end 77.780642 -354.351082)
				)
			)
		)
	)
	(zone
		(layers "F.Cu" "B.Cu" "In1.Cu" "In2.Cu" "In3.Cu" "In4.Cu" "In5.Cu" "In6.Cu"
			"In7.Cu" "In8.Cu" "In9.Cu" "In10.Cu" "In11.Cu" "In12.Cu" "In13.Cu" "In14.Cu"
			"In15.Cu" "In16.Cu"
		)
		(hatch none 0.5)
		(connect_pads
			(clearance 0)
		)
		(min_thickness 0.25)
		(keepout
			(tracks not_allowed)
			(vias allowed)
			(pads allowed)
			(copperpour not_allowed)
			(footprints allowed)
		)
		(placement
			(enabled no)
			(sheetname "")
		)
		(fill
			(thermal_gap 0.5)
			(thermal_bridge_width 0.5)
			(island_removal_mode 0)
		)
		(polygon
			(pts
				(arc
					(start 83.134962 -351.230438)
					(mid 82.753962 -351.611438)
					(end 83.134962 -351.992438)
				)
				(arc
					(start 83.998562 -351.992438)
					(mid 84.379562 -351.611438)
					(end 83.998562 -351.230438)
				)
			)
		)
	)
	(zone
		(layers "F.Cu" "B.Cu" "In1.Cu" "In2.Cu" "In3.Cu" "In4.Cu" "In5.Cu" "In6.Cu"
			"In7.Cu" "In8.Cu" "In9.Cu" "In10.Cu" "In11.Cu" "In12.Cu" "In13.Cu" "In14.Cu"
			"In15.Cu" "In16.Cu"
		)
		(hatch none 0.5)
		(connect_pads
			(clearance 0)
		)
		(min_thickness 0.25)
		(keepout
			(tracks not_allowed)
			(vias allowed)
			(pads allowed)
			(copperpour not_allowed)
			(footprints allowed)
		)
		(placement
			(enabled no)
			(sheetname "")
		)
		(fill
			(thermal_gap 0.5)
			(thermal_bridge_width 0.5)
			(island_removal_mode 0)
		)
		(polygon
			(pts
				(arc
					(start 118.080028 -357.37673)
					(mid 117.699028 -357.75773)
					(end 118.080028 -358.13873)
				)
				(arc
					(start 118.943628 -358.13873)
					(mid 119.324628 -357.75773)
					(end 118.943628 -357.37673)
				)
			)
		)
	)
	(zone
		(layers "F.Cu" "B.Cu" "In1.Cu" "In2.Cu" "In3.Cu" "In4.Cu" "In5.Cu" "In6.Cu"
			"In7.Cu" "In8.Cu" "In9.Cu" "In10.Cu" "In11.Cu" "In12.Cu" "In13.Cu" "In14.Cu"
			"In15.Cu" "In16.Cu"
		)
		(hatch none 0.5)
		(connect_pads
			(clearance 0)
		)
		(min_thickness 0.25)
		(keepout
			(tracks not_allowed)
			(vias allowed)
			(pads allowed)
			(copperpour not_allowed)
			(footprints allowed)
		)
		(placement
			(enabled no)
			(sheetname "")
		)
		(fill
			(thermal_gap 0.5)
			(thermal_bridge_width 0.5)
			(island_removal_mode 0)
		)
		(polygon
			(pts
				(arc
					(start 415.513012 -357.37673)
					(mid 415.132012 -357.75773)
					(end 415.513012 -358.13873)
				)
				(arc
					(start 416.376612 -358.13873)
					(mid 416.757612 -357.75773)
					(end 416.376612 -357.37673)
				)
			)
		)
	)
	(zone
		(layers "F.Cu" "B.Cu" "In1.Cu" "In2.Cu" "In3.Cu" "In4.Cu" "In5.Cu" "In6.Cu"
			"In7.Cu" "In8.Cu" "In9.Cu" "In10.Cu" "In11.Cu" "In12.Cu" "In13.Cu" "In14.Cu"
			"In15.Cu" "In16.Cu"
		)
		(hatch none 0.5)
		(connect_pads
			(clearance 0)
		)
		(min_thickness 0.25)
		(keepout
			(tracks not_allowed)
			(vias allowed)
			(pads allowed)
			(copperpour not_allowed)
			(footprints allowed)
		)
		(placement
			(enabled no)
			(sheetname "")
		)
		(fill
			(thermal_gap 0.5)
			(thermal_bridge_width 0.5)
			(island_removal_mode 0)
		)
		(polygon
			(pts
				(arc
					(start 34.101024 -404.828756)
					(mid 34.115903 -404.792835)
					(end 34.151824 -404.777956)
				)
				(arc
					(start 34.868104 -404.777956)
					(mid 34.904025 -404.792835)
					(end 34.918904 -404.828756)
				)
				(arc
					(start 34.918904 -407.251408)
					(mid 34.904025 -407.287329)
					(end 34.868104 -407.302208)
				)
				(arc
					(start 34.151824 -407.302208)
					(mid 34.115903 -407.287329)
					(end 34.101024 -407.251408)
				)
			)
		)
	)
	(zone
		(layers "F.Cu" "B.Cu" "In1.Cu" "In2.Cu" "In3.Cu" "In4.Cu" "In5.Cu" "In6.Cu"
			"In7.Cu" "In8.Cu" "In9.Cu" "In10.Cu" "In11.Cu" "In12.Cu" "In13.Cu" "In14.Cu"
			"In15.Cu" "In16.Cu"
		)
		(hatch none 0.5)
		(connect_pads
			(clearance 0)
		)
		(min_thickness 0.25)
		(keepout
			(tracks not_allowed)
			(vias allowed)
			(pads allowed)
			(copperpour not_allowed)
			(footprints allowed)
		)
		(placement
			(enabled no)
			(sheetname "")
		)
		(fill
			(thermal_gap 0.5)
			(thermal_bridge_width 0.5)
			(island_removal_mode 0)
		)
		(polygon
			(pts
				(arc
					(start 227.351336 -59.26836)
					(mid 226.894136 -58.81116)
					(end 226.436936 -59.26836)
				)
				(arc
					(start 226.436936 -60.13196)
					(mid 226.894136 -60.58916)
					(end 227.351336 -60.13196)
				)
			)
		)
	)
	(zone
		(layers "F.Cu" "B.Cu" "In1.Cu" "In2.Cu" "In3.Cu" "In4.Cu" "In5.Cu" "In6.Cu"
			"In7.Cu" "In8.Cu" "In9.Cu" "In10.Cu" "In11.Cu" "In12.Cu" "In13.Cu" "In14.Cu"
			"In15.Cu" "In16.Cu"
		)
		(hatch none 0.5)
		(connect_pads
			(clearance 0)
		)
		(min_thickness 0.25)
		(keepout
			(tracks not_allowed)
			(vias allowed)
			(pads allowed)
			(copperpour not_allowed)
			(footprints allowed)
		)
		(placement
			(enabled no)
			(sheetname "")
		)
		(fill
			(thermal_gap 0.5)
			(thermal_bridge_width 0.5)
			(island_removal_mode 0)
		)
		(polygon
			(pts
				(arc
					(start 126.501144 -378.828554)
					(mid 126.516023 -378.792633)
					(end 126.551944 -378.777754)
				)
				(arc
					(start 127.268224 -378.777754)
					(mid 127.304145 -378.792633)
					(end 127.319024 -378.828554)
				)
				(arc
					(start 127.319024 -381.251206)
					(mid 127.304145 -381.287127)
					(end 127.268224 -381.302006)
				)
				(arc
					(start 126.551944 -381.302006)
					(mid 126.516023 -381.287127)
					(end 126.501144 -381.251206)
				)
			)
		)
	)
	(zone
		(layers "F.Cu" "B.Cu" "In1.Cu" "In2.Cu" "In3.Cu" "In4.Cu" "In5.Cu" "In6.Cu"
			"In7.Cu" "In8.Cu" "In9.Cu" "In10.Cu" "In11.Cu" "In12.Cu" "In13.Cu" "In14.Cu"
			"In15.Cu" "In16.Cu"
		)
		(hatch none 0.5)
		(connect_pads
			(clearance 0)
		)
		(min_thickness 0.25)
		(keepout
			(tracks not_allowed)
			(vias allowed)
			(pads allowed)
			(copperpour not_allowed)
			(footprints allowed)
		)
		(placement
			(enabled no)
			(sheetname "")
		)
		(fill
			(thermal_gap 0.5)
			(thermal_bridge_width 0.5)
			(island_removal_mode 0)
		)
		(polygon
			(pts
				(arc
					(start 54.89575 -365.310166)
					(mid 54.43855 -365.767366)
					(end 54.89575 -366.224566)
				)
				(arc
					(start 55.75935 -366.224566)
					(mid 56.21655 -365.767366)
					(end 55.75935 -365.310166)
				)
			)
		)
	)
	(zone
		(layers "F.Cu" "B.Cu" "In1.Cu" "In2.Cu" "In3.Cu" "In4.Cu" "In5.Cu" "In6.Cu"
			"In7.Cu" "In8.Cu" "In9.Cu" "In10.Cu" "In11.Cu" "In12.Cu" "In13.Cu" "In14.Cu"
			"In15.Cu" "In16.Cu"
		)
		(hatch none 0.5)
		(connect_pads
			(clearance 0)
		)
		(min_thickness 0.25)
		(keepout
			(tracks not_allowed)
			(vias allowed)
			(pads allowed)
			(copperpour not_allowed)
			(footprints allowed)
		)
		(placement
			(enabled no)
			(sheetname "")
		)
		(fill
			(thermal_gap 0.5)
			(thermal_bridge_width 0.5)
			(island_removal_mode 0)
		)
		(polygon
			(pts
				(arc
					(start 424.839892 -342.058498)
					(mid 424.458892 -342.439498)
					(end 424.839892 -342.820498)
				)
				(arc
					(start 425.703492 -342.820498)
					(mid 426.084492 -342.439498)
					(end 425.703492 -342.058498)
				)
			)
		)
	)
	(zone
		(layers "F.Cu" "B.Cu" "In1.Cu" "In2.Cu" "In3.Cu" "In4.Cu" "In5.Cu" "In6.Cu"
			"In7.Cu" "In8.Cu" "In9.Cu" "In10.Cu" "In11.Cu" "In12.Cu" "In13.Cu" "In14.Cu"
			"In15.Cu" "In16.Cu"
		)
		(hatch none 0.5)
		(connect_pads
			(clearance 0)
		)
		(min_thickness 0.25)
		(keepout
			(tracks not_allowed)
			(vias allowed)
			(pads allowed)
			(copperpour not_allowed)
			(footprints allowed)
		)
		(placement
			(enabled no)
			(sheetname "")
		)
		(fill
			(thermal_gap 0.5)
			(thermal_bridge_width 0.5)
			(island_removal_mode 0)
		)
		(polygon
			(pts
				(arc
					(start 279.859232 -160.1851)
					(mid 277.725632 -160.1851)
					(end 279.859232 -160.1851)
				)
			)
		)
	)
	(zone
		(layers "F.Cu" "B.Cu" "In1.Cu" "In2.Cu" "In3.Cu" "In4.Cu" "In5.Cu" "In6.Cu"
			"In7.Cu" "In8.Cu" "In9.Cu" "In10.Cu" "In11.Cu" "In12.Cu" "In13.Cu" "In14.Cu"
			"In15.Cu" "In16.Cu"
		)
		(hatch none 0.5)
		(connect_pads
			(clearance 0)
		)
		(min_thickness 0.25)
		(keepout
			(tracks not_allowed)
			(vias allowed)
			(pads allowed)
			(copperpour not_allowed)
			(footprints allowed)
		)
		(placement
			(enabled no)
			(sheetname "")
		)
		(fill
			(thermal_gap 0.5)
			(thermal_bridge_width 0.5)
			(island_removal_mode 0)
		)
		(polygon
			(pts
				(arc
					(start 237.627414 -151.050498)
					(mid 237.170214 -150.593298)
					(end 236.713014 -151.050498)
				)
				(arc
					(start 236.713014 -151.914098)
					(mid 237.170214 -152.371298)
					(end 237.627414 -151.914098)
				)
			)
		)
	)
	(zone
		(layers "F.Cu" "B.Cu" "In1.Cu" "In2.Cu" "In3.Cu" "In4.Cu" "In5.Cu" "In6.Cu"
			"In7.Cu" "In8.Cu" "In9.Cu" "In10.Cu" "In11.Cu" "In12.Cu" "In13.Cu" "In14.Cu"
			"In15.Cu" "In16.Cu"
		)
		(hatch none 0.5)
		(connect_pads
			(clearance 0)
		)
		(min_thickness 0.25)
		(keepout
			(tracks not_allowed)
			(vias allowed)
			(pads allowed)
			(copperpour not_allowed)
			(footprints allowed)
		)
		(placement
			(enabled no)
			(sheetname "")
		)
		(fill
			(thermal_gap 0.5)
			(thermal_bridge_width 0.5)
			(island_removal_mode 0)
		)
		(polygon
			(pts
				(arc
					(start 172.70095 -373.828818)
					(mid 172.715829 -373.792897)
					(end 172.75175 -373.778018)
				)
				(arc
					(start 173.46803 -373.778018)
					(mid 173.503951 -373.792897)
					(end 173.51883 -373.828818)
				)
				(arc
					(start 173.51883 -376.25147)
					(mid 173.503951 -376.287391)
					(end 173.46803 -376.30227)
				)
				(arc
					(start 172.75175 -376.30227)
					(mid 172.715829 -376.287391)
					(end 172.70095 -376.25147)
				)
			)
		)
	)
	(zone
		(layers "F.Cu" "B.Cu" "In1.Cu" "In2.Cu" "In3.Cu" "In4.Cu" "In5.Cu" "In6.Cu"
			"In7.Cu" "In8.Cu" "In9.Cu" "In10.Cu" "In11.Cu" "In12.Cu" "In13.Cu" "In14.Cu"
			"In15.Cu" "In16.Cu"
		)
		(hatch none 0.5)
		(connect_pads
			(clearance 0)
		)
		(min_thickness 0.25)
		(keepout
			(tracks not_allowed)
			(vias allowed)
			(pads allowed)
			(copperpour not_allowed)
			(footprints allowed)
		)
		(placement
			(enabled no)
			(sheetname "")
		)
		(fill
			(thermal_gap 0.5)
			(thermal_bridge_width 0.5)
			(island_removal_mode 0)
		)
		(polygon
			(pts
				(arc
					(start 84.700872 -395.92885)
					(mid 84.715751 -395.892929)
					(end 84.751672 -395.87805)
				)
				(arc
					(start 85.467952 -395.87805)
					(mid 85.503873 -395.892929)
					(end 85.518752 -395.92885)
				)
				(arc
					(start 85.518752 -398.351502)
					(mid 85.503873 -398.387423)
					(end 85.467952 -398.402302)
				)
				(arc
					(start 84.751672 -398.402302)
					(mid 84.715751 -398.387423)
					(end 84.700872 -398.351502)
				)
			)
		)
	)
	(zone
		(layers "F.Cu" "B.Cu" "In1.Cu" "In2.Cu" "In3.Cu" "In4.Cu" "In5.Cu" "In6.Cu"
			"In7.Cu" "In8.Cu" "In9.Cu" "In10.Cu" "In11.Cu" "In12.Cu" "In13.Cu" "In14.Cu"
			"In15.Cu" "In16.Cu"
		)
		(hatch none 0.5)
		(connect_pads
			(clearance 0)
		)
		(min_thickness 0.25)
		(keepout
			(tracks not_allowed)
			(vias allowed)
			(pads allowed)
			(copperpour not_allowed)
			(footprints allowed)
		)
		(placement
			(enabled no)
			(sheetname "")
		)
		(fill
			(thermal_gap 0.5)
			(thermal_bridge_width 0.5)
			(island_removal_mode 0)
		)
		(polygon
			(pts
				(arc
					(start 47.313088 -351.230438)
					(mid 46.932088 -351.611438)
					(end 47.313088 -351.992438)
				)
				(arc
					(start 48.176688 -351.992438)
					(mid 48.557688 -351.611438)
					(end 48.176688 -351.230438)
				)
			)
		)
	)
	(zone
		(layers "F.Cu" "B.Cu" "In1.Cu" "In2.Cu" "In3.Cu" "In4.Cu" "In5.Cu" "In6.Cu"
			"In7.Cu" "In8.Cu" "In9.Cu" "In10.Cu" "In11.Cu" "In12.Cu" "In13.Cu" "In14.Cu"
			"In15.Cu" "In16.Cu"
		)
		(hatch none 0.5)
		(connect_pads
			(clearance 0)
		)
		(min_thickness 0.25)
		(keepout
			(tracks not_allowed)
			(vias allowed)
			(pads allowed)
			(copperpour not_allowed)
			(footprints allowed)
		)
		(placement
			(enabled no)
			(sheetname "")
		)
		(fill
			(thermal_gap 0.5)
			(thermal_bridge_width 0.5)
			(island_removal_mode 0)
		)
		(polygon
			(pts
				(arc
					(start 34.66846 -112.784382)
					(mid 35.12566 -113.241582)
					(end 35.58286 -112.784382)
				)
				(arc
					(start 35.58286 -111.920782)
					(mid 35.12566 -111.463582)
					(end 34.66846 -111.920782)
				)
			)
		)
	)
	(zone
		(layers "F.Cu" "B.Cu" "In1.Cu" "In2.Cu" "In3.Cu" "In4.Cu" "In5.Cu" "In6.Cu"
			"In7.Cu" "In8.Cu" "In9.Cu" "In10.Cu" "In11.Cu" "In12.Cu" "In13.Cu" "In14.Cu"
			"In15.Cu" "In16.Cu"
		)
		(hatch none 0.5)
		(connect_pads
			(clearance 0)
		)
		(min_thickness 0.25)
		(keepout
			(tracks not_allowed)
			(vias allowed)
			(pads allowed)
			(copperpour not_allowed)
			(footprints allowed)
		)
		(placement
			(enabled no)
			(sheetname "")
		)
		(fill
			(thermal_gap 0.5)
			(thermal_bridge_width 0.5)
			(island_removal_mode 0)
		)
		(polygon
			(pts
				(arc
					(start 383.881122 -381.628904)
					(mid 383.896001 -381.592983)
					(end 383.931922 -381.578104)
				)
				(arc
					(start 384.648202 -381.578104)
					(mid 384.684123 -381.592983)
					(end 384.699002 -381.628904)
				)
				(arc
					(start 384.699002 -384.051556)
					(mid 384.684123 -384.087477)
					(end 384.648202 -384.102356)
				)
				(arc
					(start 383.931922 -384.102356)
					(mid 383.896001 -384.087477)
					(end 383.881122 -384.051556)
				)
			)
		)
	)
	(zone
		(layers "F.Cu" "B.Cu" "In1.Cu" "In2.Cu" "In3.Cu" "In4.Cu" "In5.Cu" "In6.Cu"
			"In7.Cu" "In8.Cu" "In9.Cu" "In10.Cu" "In11.Cu" "In12.Cu" "In13.Cu" "In14.Cu"
			"In15.Cu" "In16.Cu"
		)
		(hatch none 0.5)
		(connect_pads
			(clearance 0)
		)
		(min_thickness 0.25)
		(keepout
			(tracks not_allowed)
			(vias allowed)
			(pads allowed)
			(copperpour not_allowed)
			(footprints allowed)
		)
		(placement
			(enabled no)
			(sheetname "")
		)
		(fill
			(thermal_gap 0.5)
			(thermal_bridge_width 0.5)
			(island_removal_mode 0)
		)
		(polygon
			(pts
				(arc
					(start 186.948064 -32.714184)
					(mid 187.405264 -33.171384)
					(end 187.862464 -32.714184)
				)
				(arc
					(start 187.862464 -31.850584)
					(mid 187.405264 -31.393384)
					(end 186.948064 -31.850584)
				)
			)
		)
	)
	(zone
		(layers "F.Cu" "B.Cu" "In1.Cu" "In2.Cu" "In3.Cu" "In4.Cu" "In5.Cu" "In6.Cu"
			"In7.Cu" "In8.Cu" "In9.Cu" "In10.Cu" "In11.Cu" "In12.Cu" "In13.Cu" "In14.Cu"
			"In15.Cu" "In16.Cu"
		)
		(hatch none 0.5)
		(connect_pads
			(clearance 0)
		)
		(min_thickness 0.25)
		(keepout
			(tracks not_allowed)
			(vias allowed)
			(pads allowed)
			(copperpour not_allowed)
			(footprints allowed)
		)
		(placement
			(enabled no)
			(sheetname "")
		)
		(fill
			(thermal_gap 0.5)
			(thermal_bridge_width 0.5)
			(island_removal_mode 0)
		)
		(polygon
			(pts
				(arc
					(start 52.69992 -121.022872)
					(mid 52.24272 -120.565672)
					(end 51.78552 -121.022872)
				)
				(arc
					(start 51.78552 -121.886472)
					(mid 52.24272 -122.343672)
					(end 52.69992 -121.886472)
				)
			)
		)
	)
	(zone
		(layers "F.Cu" "B.Cu" "In1.Cu" "In2.Cu" "In3.Cu" "In4.Cu" "In5.Cu" "In6.Cu"
			"In7.Cu" "In8.Cu" "In9.Cu" "In10.Cu" "In11.Cu" "In12.Cu" "In13.Cu" "In14.Cu"
			"In15.Cu" "In16.Cu"
		)
		(hatch none 0.5)
		(connect_pads
			(clearance 0)
		)
		(min_thickness 0.25)
		(keepout
			(tracks not_allowed)
			(vias allowed)
			(pads allowed)
			(copperpour not_allowed)
			(footprints allowed)
		)
		(placement
			(enabled no)
			(sheetname "")
		)
		(fill
			(thermal_gap 0.5)
			(thermal_bridge_width 0.5)
			(island_removal_mode 0)
		)
		(polygon
			(pts
				(arc
					(start 421.280844 -400.92884)
					(mid 421.295723 -400.892919)
					(end 421.331644 -400.87804)
				)
				(arc
					(start 422.047924 -400.87804)
					(mid 422.083845 -400.892919)
					(end 422.098724 -400.92884)
				)
				(arc
					(start 422.098724 -403.351492)
					(mid 422.083845 -403.387413)
					(end 422.047924 -403.402292)
				)
				(arc
					(start 421.331644 -403.402292)
					(mid 421.295723 -403.387413)
					(end 421.280844 -403.351492)
				)
			)
		)
	)
	(zone
		(layers "F.Cu" "B.Cu" "In1.Cu" "In2.Cu" "In3.Cu" "In4.Cu" "In5.Cu" "In6.Cu"
			"In7.Cu" "In8.Cu" "In9.Cu" "In10.Cu" "In11.Cu" "In12.Cu" "In13.Cu" "In14.Cu"
			"In15.Cu" "In16.Cu"
		)
		(hatch none 0.5)
		(connect_pads
			(clearance 0)
		)
		(min_thickness 0.25)
		(keepout
			(tracks not_allowed)
			(vias allowed)
			(pads allowed)
			(copperpour not_allowed)
			(footprints allowed)
		)
		(placement
			(enabled no)
			(sheetname "")
		)
		(fill
			(thermal_gap 0.5)
			(thermal_bridge_width 0.5)
			(island_removal_mode 0)
		)
		(polygon
			(pts
				(arc
					(start 421.280844 -404.828756)
					(mid 421.295723 -404.792835)
					(end 421.331644 -404.777956)
				)
				(arc
					(start 422.047924 -404.777956)
					(mid 422.083845 -404.792835)
					(end 422.098724 -404.828756)
				)
				(arc
					(start 422.098724 -407.251408)
					(mid 422.083845 -407.287329)
					(end 422.047924 -407.302208)
				)
				(arc
					(start 421.331644 -407.302208)
					(mid 421.295723 -407.287329)
					(end 421.280844 -407.251408)
				)
			)
		)
	)
	(zone
		(layers "F.Cu" "B.Cu" "In1.Cu" "In2.Cu" "In3.Cu" "In4.Cu" "In5.Cu" "In6.Cu"
			"In7.Cu" "In8.Cu" "In9.Cu" "In10.Cu" "In11.Cu" "In12.Cu" "In13.Cu" "In14.Cu"
			"In15.Cu" "In16.Cu"
		)
		(hatch none 0.5)
		(connect_pads
			(clearance 0)
		)
		(min_thickness 0.25)
		(keepout
			(tracks not_allowed)
			(vias allowed)
			(pads allowed)
			(copperpour not_allowed)
			(footprints allowed)
		)
		(placement
			(enabled no)
			(sheetname "")
		)
		(fill
			(thermal_gap 0.5)
			(thermal_bridge_width 0.5)
			(island_removal_mode 0)
		)
		(polygon
			(pts
				(arc
					(start 377.4059 -348.20479)
					(mid 377.0249 -348.58579)
					(end 377.4059 -348.96679)
				)
				(arc
					(start 378.2695 -348.96679)
					(mid 378.6505 -348.58579)
					(end 378.2695 -348.20479)
				)
			)
		)
	)
	(zone
		(layers "F.Cu" "B.Cu" "In1.Cu" "In2.Cu" "In3.Cu" "In4.Cu" "In5.Cu" "In6.Cu"
			"In7.Cu" "In8.Cu" "In9.Cu" "In10.Cu" "In11.Cu" "In12.Cu" "In13.Cu" "In14.Cu"
			"In15.Cu" "In16.Cu"
		)
		(hatch none 0.5)
		(connect_pads
			(clearance 0)
		)
		(min_thickness 0.25)
		(keepout
			(tracks not_allowed)
			(vias allowed)
			(pads allowed)
			(copperpour not_allowed)
			(footprints allowed)
		)
		(placement
			(enabled no)
			(sheetname "")
		)
		(fill
			(thermal_gap 0.5)
			(thermal_bridge_width 0.5)
			(island_removal_mode 0)
		)
		(polygon
			(pts
				(arc
					(start 306.675536 -117.758718)
					(mid 307.132736 -118.215918)
					(end 307.589936 -117.758718)
				)
				(arc
					(start 307.589936 -116.895118)
					(mid 307.132736 -116.437918)
					(end 306.675536 -116.895118)
				)
			)
		)
	)
	(zone
		(layers "F.Cu" "B.Cu" "In1.Cu" "In2.Cu" "In3.Cu" "In4.Cu" "In5.Cu" "In6.Cu"
			"In7.Cu" "In8.Cu" "In9.Cu" "In10.Cu" "In11.Cu" "In12.Cu" "In13.Cu" "In14.Cu"
			"In15.Cu" "In16.Cu"
		)
		(hatch none 0.5)
		(connect_pads
			(clearance 0)
		)
		(min_thickness 0.25)
		(keepout
			(tracks not_allowed)
			(vias allowed)
			(pads allowed)
			(copperpour not_allowed)
			(footprints allowed)
		)
		(placement
			(enabled no)
			(sheetname "")
		)
		(fill
			(thermal_gap 0.5)
			(thermal_bridge_width 0.5)
			(island_removal_mode 0)
		)
		(polygon
			(pts
				(arc
					(start 292.768782 -345.084146)
					(mid 292.387782 -345.465146)
					(end 292.768782 -345.846146)
				)
				(arc
					(start 293.632382 -345.846146)
					(mid 294.013382 -345.465146)
					(end 293.632382 -345.084146)
				)
			)
		)
	)
	(zone
		(layers "F.Cu" "B.Cu" "In1.Cu" "In2.Cu" "In3.Cu" "In4.Cu" "In5.Cu" "In6.Cu"
			"In7.Cu" "In8.Cu" "In9.Cu" "In10.Cu" "In11.Cu" "In12.Cu" "In13.Cu" "In14.Cu"
			"In15.Cu" "In16.Cu"
		)
		(hatch none 0.5)
		(connect_pads
			(clearance 0)
		)
		(min_thickness 0.25)
		(keepout
			(tracks not_allowed)
			(vias allowed)
			(pads allowed)
			(copperpour not_allowed)
			(footprints allowed)
		)
		(placement
			(enabled no)
			(sheetname "")
		)
		(fill
			(thermal_gap 0.5)
			(thermal_bridge_width 0.5)
			(island_removal_mode 0)
		)
		(polygon
			(pts
				(arc
					(start 18.84807 -32.714184)
					(mid 19.30527 -33.171384)
					(end 19.76247 -32.714184)
				)
				(arc
					(start 19.76247 -31.850584)
					(mid 19.30527 -31.393384)
					(end 18.84807 -31.850584)
				)
			)
		)
	)
	(zone
		(layers "F.Cu" "B.Cu" "In1.Cu" "In2.Cu" "In3.Cu" "In4.Cu" "In5.Cu" "In6.Cu"
			"In7.Cu" "In8.Cu" "In9.Cu" "In10.Cu" "In11.Cu" "In12.Cu" "In13.Cu" "In14.Cu"
			"In15.Cu" "In16.Cu"
		)
		(hatch none 0.5)
		(connect_pads
			(clearance 0)
		)
		(min_thickness 0.25)
		(keepout
			(tracks not_allowed)
			(vias allowed)
			(pads allowed)
			(copperpour not_allowed)
			(footprints allowed)
		)
		(placement
			(enabled no)
			(sheetname "")
		)
		(fill
			(thermal_gap 0.5)
			(thermal_bridge_width 0.5)
			(island_removal_mode 0)
		)
		(polygon
			(pts
				(arc
					(start 379.48108 -373.828818)
					(mid 379.495959 -373.792897)
					(end 379.53188 -373.778018)
				)
				(arc
					(start 380.24816 -373.778018)
					(mid 380.284081 -373.792897)
					(end 380.29896 -373.828818)
				)
				(arc
					(start 380.29896 -376.25147)
					(mid 380.284081 -376.287391)
					(end 380.24816 -376.30227)
				)
				(arc
					(start 379.53188 -376.30227)
					(mid 379.495959 -376.287391)
					(end 379.48108 -376.25147)
				)
			)
		)
	)
	(zone
		(layers "F.Cu" "B.Cu" "In1.Cu" "In2.Cu" "In3.Cu" "In4.Cu" "In5.Cu" "In6.Cu"
			"In7.Cu" "In8.Cu" "In9.Cu" "In10.Cu" "In11.Cu" "In12.Cu" "In13.Cu" "In14.Cu"
			"In15.Cu" "In16.Cu"
		)
		(hatch none 0.5)
		(connect_pads
			(clearance 0)
		)
		(min_thickness 0.25)
		(keepout
			(tracks not_allowed)
			(vias allowed)
			(pads allowed)
			(copperpour not_allowed)
			(footprints allowed)
		)
		(placement
			(enabled no)
			(sheetname "")
		)
		(fill
			(thermal_gap 0.5)
			(thermal_bridge_width 0.5)
			(island_removal_mode 0)
		)
		(polygon
			(pts
				(arc
					(start 392.9507 -345.084146)
					(mid 392.5697 -345.465146)
					(end 392.9507 -345.846146)
				)
				(arc
					(start 393.8143 -345.846146)
					(mid 394.1953 -345.465146)
					(end 393.8143 -345.084146)
				)
			)
		)
	)
	(zone
		(layers "F.Cu" "B.Cu" "In1.Cu" "In2.Cu" "In3.Cu" "In4.Cu" "In5.Cu" "In6.Cu"
			"In7.Cu" "In8.Cu" "In9.Cu" "In10.Cu" "In11.Cu" "In12.Cu" "In13.Cu" "In14.Cu"
			"In15.Cu" "In16.Cu"
		)
		(hatch none 0.5)
		(connect_pads
			(clearance 0)
		)
		(min_thickness 0.25)
		(keepout
			(tracks not_allowed)
			(vias allowed)
			(pads allowed)
			(copperpour not_allowed)
			(footprints allowed)
		)
		(placement
			(enabled no)
			(sheetname "")
		)
		(fill
			(thermal_gap 0.5)
			(thermal_bridge_width 0.5)
			(island_removal_mode 0)
		)
		(polygon
			(pts
				(arc
					(start 73.700894 -404.828756)
					(mid 73.715773 -404.792835)
					(end 73.751694 -404.777956)
				)
				(arc
					(start 74.467974 -404.777956)
					(mid 74.503895 -404.792835)
					(end 74.518774 -404.828756)
				)
				(arc
					(start 74.518774 -407.251408)
					(mid 74.503895 -407.287329)
					(end 74.467974 -407.302208)
				)
				(arc
					(start 73.751694 -407.302208)
					(mid 73.715773 -407.287329)
					(end 73.700894 -407.251408)
				)
			)
		)
	)
	(zone
		(layers "F.Cu" "B.Cu" "In1.Cu" "In2.Cu" "In3.Cu" "In4.Cu" "In5.Cu" "In6.Cu"
			"In7.Cu" "In8.Cu" "In9.Cu" "In10.Cu" "In11.Cu" "In12.Cu" "In13.Cu" "In14.Cu"
			"In15.Cu" "In16.Cu"
		)
		(hatch none 0.5)
		(connect_pads
			(clearance 0)
		)
		(min_thickness 0.25)
		(keepout
			(tracks not_allowed)
			(vias allowed)
			(pads allowed)
			(copperpour not_allowed)
			(footprints allowed)
		)
		(placement
			(enabled no)
			(sheetname "")
		)
		(fill
			(thermal_gap 0.5)
			(thermal_bridge_width 0.5)
			(island_removal_mode 0)
		)
		(polygon
			(pts
				(arc
					(start 400.99996 -101.112828)
					(mid 400.54276 -100.655628)
					(end 400.08556 -101.112828)
				)
				(arc
					(start 400.08556 -101.976428)
					(mid 400.54276 -102.433628)
					(end 400.99996 -101.976428)
				)
			)
		)
	)
	(zone
		(layers "F.Cu" "B.Cu" "In1.Cu" "In2.Cu" "In3.Cu" "In4.Cu" "In5.Cu" "In6.Cu"
			"In7.Cu" "In8.Cu" "In9.Cu" "In10.Cu" "In11.Cu" "In12.Cu" "In13.Cu" "In14.Cu"
			"In15.Cu" "In16.Cu"
		)
		(hatch none 0.5)
		(connect_pads
			(clearance 0)
		)
		(min_thickness 0.25)
		(keepout
			(tracks not_allowed)
			(vias allowed)
			(pads allowed)
			(copperpour not_allowed)
			(footprints allowed)
		)
		(placement
			(enabled no)
			(sheetname "")
		)
		(fill
			(thermal_gap 0.5)
			(thermal_bridge_width 0.5)
			(island_removal_mode 0)
		)
		(polygon
			(pts
				(arc
					(start 334.265524 -351.230438)
					(mid 333.884524 -351.611438)
					(end 334.265524 -351.992438)
				)
				(arc
					(start 335.129124 -351.992438)
					(mid 335.510124 -351.611438)
					(end 335.129124 -351.230438)
				)
			)
		)
	)
	(zone
		(layers "F.Cu" "B.Cu" "In1.Cu" "In2.Cu" "In3.Cu" "In4.Cu" "In5.Cu" "In6.Cu"
			"In7.Cu" "In8.Cu" "In9.Cu" "In10.Cu" "In11.Cu" "In12.Cu" "In13.Cu" "In14.Cu"
			"In15.Cu" "In16.Cu"
		)
		(hatch none 0.5)
		(connect_pads
			(clearance 0)
		)
		(min_thickness 0.25)
		(keepout
			(tracks not_allowed)
			(vias allowed)
			(pads allowed)
			(copperpour not_allowed)
			(footprints allowed)
		)
		(placement
			(enabled no)
			(sheetname "")
		)
		(fill
			(thermal_gap 0.5)
			(thermal_bridge_width 0.5)
			(island_removal_mode 0)
		)
		(polygon
			(pts
				(arc
					(start 300.724062 -27.342846)
					(mid 301.181262 -27.800046)
					(end 301.638462 -27.342846)
				)
				(arc
					(start 301.638462 -26.479246)
					(mid 301.181262 -26.022046)
					(end 300.724062 -26.479246)
				)
			)
		)
	)
	(zone
		(layers "F.Cu" "B.Cu" "In1.Cu" "In2.Cu" "In3.Cu" "In4.Cu" "In5.Cu" "In6.Cu"
			"In7.Cu" "In8.Cu" "In9.Cu" "In10.Cu" "In11.Cu" "In12.Cu" "In13.Cu" "In14.Cu"
			"In15.Cu" "In16.Cu"
		)
		(hatch none 0.5)
		(connect_pads
			(clearance 0)
		)
		(min_thickness 0.25)
		(keepout
			(tracks not_allowed)
			(vias allowed)
			(pads allowed)
			(copperpour not_allowed)
			(footprints allowed)
		)
		(placement
			(enabled no)
			(sheetname "")
		)
		(fill
			(thermal_gap 0.5)
			(thermal_bridge_width 0.5)
			(island_removal_mode 0)
		)
		(polygon
			(pts
				(arc
					(start 413.04591 -156.087318)
					(mid 413.50311 -156.544518)
					(end 413.96031 -156.087318)
				)
				(arc
					(start 413.96031 -155.223718)
					(mid 413.50311 -154.766518)
					(end 413.04591 -155.223718)
				)
			)
		)
	)
	(zone
		(layers "F.Cu" "B.Cu" "In1.Cu" "In2.Cu" "In3.Cu" "In4.Cu" "In5.Cu" "In6.Cu"
			"In7.Cu" "In8.Cu" "In9.Cu" "In10.Cu" "In11.Cu" "In12.Cu" "In13.Cu" "In14.Cu"
			"In15.Cu" "In16.Cu"
		)
		(hatch none 0.5)
		(connect_pads
			(clearance 0)
		)
		(min_thickness 0.25)
		(keepout
			(tracks not_allowed)
			(vias allowed)
			(pads allowed)
			(copperpour not_allowed)
			(footprints allowed)
		)
		(placement
			(enabled no)
			(sheetname "")
		)
		(fill
			(thermal_gap 0.5)
			(thermal_bridge_width 0.5)
			(island_removal_mode 0)
		)
		(polygon
			(pts
				(arc
					(start 432.01717 -121.365772)
					(mid 432.47437 -121.822972)
					(end 432.93157 -121.365772)
				)
				(arc
					(start 432.93157 -120.502172)
					(mid 432.47437 -120.044972)
					(end 432.01717 -120.502172)
				)
			)
		)
	)
	(zone
		(layers "F.Cu" "B.Cu" "In1.Cu" "In2.Cu" "In3.Cu" "In4.Cu" "In5.Cu" "In6.Cu"
			"In7.Cu" "In8.Cu" "In9.Cu" "In10.Cu" "In11.Cu" "In12.Cu" "In13.Cu" "In14.Cu"
			"In15.Cu" "In16.Cu"
		)
		(hatch none 0.5)
		(connect_pads
			(clearance 0)
		)
		(min_thickness 0.25)
		(keepout
			(tracks not_allowed)
			(vias allowed)
			(pads allowed)
			(copperpour not_allowed)
			(footprints allowed)
		)
		(placement
			(enabled no)
			(sheetname "")
		)
		(fill
			(thermal_gap 0.5)
			(thermal_bridge_width 0.5)
			(island_removal_mode 0)
		)
		(polygon
			(pts
				(arc
					(start 388.28091 -369.928902)
					(mid 388.295789 -369.892981)
					(end 388.33171 -369.878102)
				)
				(arc
					(start 389.04799 -369.878102)
					(mid 389.083911 -369.892981)
					(end 389.09879 -369.928902)
				)
				(arc
					(start 389.09879 -372.351554)
					(mid 389.083911 -372.387475)
					(end 389.04799 -372.402354)
				)
				(arc
					(start 388.33171 -372.402354)
					(mid 388.295789 -372.387475)
					(end 388.28091 -372.351554)
				)
			)
		)
	)
	(zone
		(layers "F.Cu" "B.Cu" "In1.Cu" "In2.Cu" "In3.Cu" "In4.Cu" "In5.Cu" "In6.Cu"
			"In7.Cu" "In8.Cu" "In9.Cu" "In10.Cu" "In11.Cu" "In12.Cu" "In13.Cu" "In14.Cu"
			"In15.Cu" "In16.Cu"
		)
		(hatch none 0.5)
		(connect_pads
			(clearance 0)
		)
		(min_thickness 0.25)
		(keepout
			(tracks not_allowed)
			(vias allowed)
			(pads allowed)
			(copperpour not_allowed)
			(footprints allowed)
		)
		(placement
			(enabled no)
			(sheetname "")
		)
		(fill
			(thermal_gap 0.5)
			(thermal_bridge_width 0.5)
			(island_removal_mode 0)
		)
		(polygon
			(pts
				(arc
					(start 434.48097 -397.028924)
					(mid 434.495849 -396.993003)
					(end 434.53177 -396.978124)
				)
				(arc
					(start 435.24805 -396.978124)
					(mid 435.283971 -396.993003)
					(end 435.29885 -397.028924)
				)
				(arc
					(start 435.29885 -399.451576)
					(mid 435.283971 -399.487497)
					(end 435.24805 -399.502376)
				)
				(arc
					(start 434.53177 -399.502376)
					(mid 434.495849 -399.487497)
					(end 434.48097 -399.451576)
				)
			)
		)
	)
	(zone
		(layers "F.Cu" "B.Cu" "In1.Cu" "In2.Cu" "In3.Cu" "In4.Cu" "In5.Cu" "In6.Cu"
			"In7.Cu" "In8.Cu" "In9.Cu" "In10.Cu" "In11.Cu" "In12.Cu" "In13.Cu" "In14.Cu"
			"In15.Cu" "In16.Cu"
		)
		(hatch none 0.5)
		(connect_pads
			(clearance 0)
		)
		(min_thickness 0.25)
		(keepout
			(tracks not_allowed)
			(vias allowed)
			(pads allowed)
			(copperpour not_allowed)
			(footprints allowed)
		)
		(placement
			(enabled no)
			(sheetname "")
		)
		(fill
			(thermal_gap 0.5)
			(thermal_bridge_width 0.5)
			(island_removal_mode 0)
		)
		(polygon
			(pts
				(arc
					(start 64.74587 -152.487376)
					(mid 65.20307 -152.944576)
					(end 65.66027 -152.487376)
				)
				(arc
					(start 65.66027 -151.623776)
					(mid 65.20307 -151.166576)
					(end 64.74587 -151.623776)
				)
			)
		)
	)
	(zone
		(layers "F.Cu" "B.Cu" "In1.Cu" "In2.Cu" "In3.Cu" "In4.Cu" "In5.Cu" "In6.Cu"
			"In7.Cu" "In8.Cu" "In9.Cu" "In10.Cu" "In11.Cu" "In12.Cu" "In13.Cu" "In14.Cu"
			"In15.Cu" "In16.Cu"
		)
		(hatch none 0.5)
		(connect_pads
			(clearance 0)
		)
		(min_thickness 0.25)
		(keepout
			(tracks not_allowed)
			(vias allowed)
			(pads allowed)
			(copperpour not_allowed)
			(footprints allowed)
		)
		(placement
			(enabled no)
			(sheetname "")
		)
		(fill
			(thermal_gap 0.5)
			(thermal_bridge_width 0.5)
			(island_removal_mode 0)
		)
		(polygon
			(pts
				(arc
					(start 402.85416 -119.222774)
					(mid 402.39696 -118.765574)
					(end 401.93976 -119.222774)
				)
				(arc
					(start 401.93976 -120.086374)
					(mid 402.39696 -120.543574)
					(end 402.85416 -120.086374)
				)
			)
		)
	)
	(zone
		(layers "F.Cu" "B.Cu" "In1.Cu" "In2.Cu" "In3.Cu" "In4.Cu" "In5.Cu" "In6.Cu"
			"In7.Cu" "In8.Cu" "In9.Cu" "In10.Cu" "In11.Cu" "In12.Cu" "In13.Cu" "In14.Cu"
			"In15.Cu" "In16.Cu"
		)
		(hatch none 0.5)
		(connect_pads
			(clearance 0)
		)
		(min_thickness 0.25)
		(keepout
			(tracks not_allowed)
			(vias allowed)
			(pads allowed)
			(copperpour not_allowed)
			(footprints allowed)
		)
		(placement
			(enabled no)
			(sheetname "")
		)
		(fill
			(thermal_gap 0.5)
			(thermal_bridge_width 0.5)
			(island_removal_mode 0)
		)
		(polygon
			(pts
				(arc
					(start 73.490074 -30.92069)
					(mid 73.947274 -31.37789)
					(end 74.404474 -30.92069)
				)
				(arc
					(start 74.404474 -30.05709)
					(mid 73.947274 -29.59989)
					(end 73.490074 -30.05709)
				)
			)
		)
	)
	(zone
		(layers "F.Cu" "B.Cu" "In1.Cu" "In2.Cu" "In3.Cu" "In4.Cu" "In5.Cu" "In6.Cu"
			"In7.Cu" "In8.Cu" "In9.Cu" "In10.Cu" "In11.Cu" "In12.Cu" "In13.Cu" "In14.Cu"
			"In15.Cu" "In16.Cu"
		)
		(hatch none 0.5)
		(connect_pads
			(clearance 0)
		)
		(min_thickness 0.25)
		(keepout
			(tracks not_allowed)
			(vias allowed)
			(pads allowed)
			(copperpour not_allowed)
			(footprints allowed)
		)
		(placement
			(enabled no)
			(sheetname "")
		)
		(fill
			(thermal_gap 0.5)
			(thermal_bridge_width 0.5)
			(island_removal_mode 0)
		)
		(polygon
			(pts
				(arc
					(start 122.101102 -378.828554)
					(mid 122.115981 -378.792633)
					(end 122.151902 -378.777754)
				)
				(arc
					(start 122.868182 -378.777754)
					(mid 122.904103 -378.792633)
					(end 122.918982 -378.828554)
				)
				(arc
					(start 122.918982 -381.251206)
					(mid 122.904103 -381.287127)
					(end 122.868182 -381.302006)
				)
				(arc
					(start 122.151902 -381.302006)
					(mid 122.115981 -381.287127)
					(end 122.101102 -381.251206)
				)
			)
		)
	)
	(zone
		(layers "F.Cu" "B.Cu" "In1.Cu" "In2.Cu" "In3.Cu" "In4.Cu" "In5.Cu" "In6.Cu"
			"In7.Cu" "In8.Cu" "In9.Cu" "In10.Cu" "In11.Cu" "In12.Cu" "In13.Cu" "In14.Cu"
			"In15.Cu" "In16.Cu"
		)
		(hatch none 0.5)
		(connect_pads
			(clearance 0)
		)
		(min_thickness 0.25)
		(keepout
			(tracks not_allowed)
			(vias allowed)
			(pads allowed)
			(copperpour not_allowed)
			(footprints allowed)
		)
		(placement
			(enabled no)
			(sheetname "")
		)
		(fill
			(thermal_gap 0.5)
			(thermal_bridge_width 0.5)
			(island_removal_mode 0)
		)
		(polygon
			(pts
				(arc
					(start 136.90219 -187.551822)
					(mid 137.35939 -187.094622)
					(end 136.90219 -186.637422)
				)
				(arc
					(start 136.03859 -186.637422)
					(mid 135.58139 -187.094622)
					(end 136.03859 -187.551822)
				)
			)
		)
	)
	(zone
		(layers "F.Cu" "B.Cu" "In1.Cu" "In2.Cu" "In3.Cu" "In4.Cu" "In5.Cu" "In6.Cu"
			"In7.Cu" "In8.Cu" "In9.Cu" "In10.Cu" "In11.Cu" "In12.Cu" "In13.Cu" "In14.Cu"
			"In15.Cu" "In16.Cu"
		)
		(hatch none 0.5)
		(connect_pads
			(clearance 0)
		)
		(min_thickness 0.25)
		(keepout
			(tracks not_allowed)
			(vias allowed)
			(pads allowed)
			(copperpour not_allowed)
			(footprints allowed)
		)
		(placement
			(enabled no)
			(sheetname "")
		)
		(fill
			(thermal_gap 0.5)
			(thermal_bridge_width 0.5)
			(island_removal_mode 0)
		)
		(polygon
			(pts
				(arc
					(start 106.002836 -375.6406)
					(mid 106.460036 -375.1834)
					(end 106.002836 -374.7262)
				)
				(arc
					(start 105.139236 -374.7262)
					(mid 104.682036 -375.1834)
					(end 105.139236 -375.6406)
				)
			)
		)
	)
	(zone
		(layers "F.Cu" "B.Cu" "In1.Cu" "In2.Cu" "In3.Cu" "In4.Cu" "In5.Cu" "In6.Cu"
			"In7.Cu" "In8.Cu" "In9.Cu" "In10.Cu" "In11.Cu" "In12.Cu" "In13.Cu" "In14.Cu"
			"In15.Cu" "In16.Cu"
		)
		(hatch none 0.5)
		(connect_pads
			(clearance 0)
		)
		(min_thickness 0.25)
		(keepout
			(tracks not_allowed)
			(vias allowed)
			(pads allowed)
			(copperpour not_allowed)
			(footprints allowed)
		)
		(placement
			(enabled no)
			(sheetname "")
		)
		(fill
			(thermal_gap 0.5)
			(thermal_bridge_width 0.5)
			(island_removal_mode 0)
		)
		(polygon
			(pts
				(arc
					(start 423.480992 -369.928902)
					(mid 423.495871 -369.892981)
					(end 423.531792 -369.878102)
				)
				(arc
					(start 424.248072 -369.878102)
					(mid 424.283993 -369.892981)
					(end 424.298872 -369.928902)
				)
				(arc
					(start 424.298872 -372.351554)
					(mid 424.283993 -372.387475)
					(end 424.248072 -372.402354)
				)
				(arc
					(start 423.531792 -372.402354)
					(mid 423.495871 -372.387475)
					(end 423.480992 -372.351554)
				)
			)
		)
	)
	(zone
		(layers "F.Cu" "B.Cu" "In1.Cu" "In2.Cu" "In3.Cu" "In4.Cu" "In5.Cu" "In6.Cu"
			"In7.Cu" "In8.Cu" "In9.Cu" "In10.Cu" "In11.Cu" "In12.Cu" "In13.Cu" "In14.Cu"
			"In15.Cu" "In16.Cu"
		)
		(hatch none 0.5)
		(connect_pads
			(clearance 0)
		)
		(min_thickness 0.25)
		(keepout
			(tracks not_allowed)
			(vias allowed)
			(pads allowed)
			(copperpour not_allowed)
			(footprints allowed)
		)
		(placement
			(enabled no)
			(sheetname "")
		)
		(fill
			(thermal_gap 0.5)
			(thermal_bridge_width 0.5)
			(island_removal_mode 0)
		)
		(polygon
			(pts
				(arc
					(start 340.483444 -348.20479)
					(mid 340.102444 -348.58579)
					(end 340.483444 -348.96679)
				)
				(arc
					(start 341.347044 -348.96679)
					(mid 341.728044 -348.58579)
					(end 341.347044 -348.20479)
				)
			)
		)
	)
	(zone
		(layers "F.Cu" "B.Cu" "In1.Cu" "In2.Cu" "In3.Cu" "In4.Cu" "In5.Cu" "In6.Cu"
			"In7.Cu" "In8.Cu" "In9.Cu" "In10.Cu" "In11.Cu" "In12.Cu" "In13.Cu" "In14.Cu"
			"In15.Cu" "In16.Cu"
		)
		(hatch none 0.5)
		(connect_pads
			(clearance 0)
		)
		(min_thickness 0.25)
		(keepout
			(tracks not_allowed)
			(vias allowed)
			(pads allowed)
			(copperpour not_allowed)
			(footprints allowed)
		)
		(placement
			(enabled no)
			(sheetname "")
		)
		(fill
			(thermal_gap 0.5)
			(thermal_bridge_width 0.5)
			(island_removal_mode 0)
		)
		(polygon
			(pts
				(arc
					(start 171.512992 -354.351082)
					(mid 171.131992 -354.732082)
					(end 171.512992 -355.113082)
				)
				(arc
					(start 172.376592 -355.113082)
					(mid 172.757592 -354.732082)
					(end 172.376592 -354.351082)
				)
			)
		)
	)
	(zone
		(layers "F.Cu" "B.Cu" "In1.Cu" "In2.Cu" "In3.Cu" "In4.Cu" "In5.Cu" "In6.Cu"
			"In7.Cu" "In8.Cu" "In9.Cu" "In10.Cu" "In11.Cu" "In12.Cu" "In13.Cu" "In14.Cu"
			"In15.Cu" "In16.Cu"
		)
		(hatch none 0.5)
		(connect_pads
			(clearance 0)
		)
		(min_thickness 0.25)
		(keepout
			(tracks not_allowed)
			(vias allowed)
			(pads allowed)
			(copperpour not_allowed)
			(footprints allowed)
		)
		(placement
			(enabled no)
			(sheetname "")
		)
		(fill
			(thermal_gap 0.5)
			(thermal_bridge_width 0.5)
			(island_removal_mode 0)
		)
		(polygon
			(pts
				(arc
					(start 174.901098 -397.028924)
					(mid 174.915977 -396.993003)
					(end 174.951898 -396.978124)
				)
				(arc
					(start 175.668178 -396.978124)
					(mid 175.704099 -396.993003)
					(end 175.718978 -397.028924)
				)
				(arc
					(start 175.718978 -399.451576)
					(mid 175.704099 -399.487497)
					(end 175.668178 -399.502376)
				)
				(arc
					(start 174.951898 -399.502376)
					(mid 174.915977 -399.487497)
					(end 174.901098 -399.451576)
				)
			)
		)
	)
	(zone
		(layers "F.Cu" "B.Cu" "In1.Cu" "In2.Cu" "In3.Cu" "In4.Cu" "In5.Cu" "In6.Cu"
			"In7.Cu" "In8.Cu" "In9.Cu" "In10.Cu" "In11.Cu" "In12.Cu" "In13.Cu" "In14.Cu"
			"In15.Cu" "In16.Cu"
		)
		(hatch none 0.5)
		(connect_pads
			(clearance 0)
		)
		(min_thickness 0.25)
		(keepout
			(tracks not_allowed)
			(vias allowed)
			(pads allowed)
			(copperpour not_allowed)
			(footprints allowed)
		)
		(placement
			(enabled no)
			(sheetname "")
		)
		(fill
			(thermal_gap 0.5)
			(thermal_bridge_width 0.5)
			(island_removal_mode 0)
		)
		(polygon
			(pts
				(arc
					(start 165.295072 -354.351082)
					(mid 164.914072 -354.732082)
					(end 165.295072 -355.113082)
				)
				(arc
					(start 166.158672 -355.113082)
					(mid 166.539672 -354.732082)
					(end 166.158672 -354.351082)
				)
			)
		)
	)
	(zone
		(layers "F.Cu" "B.Cu" "In1.Cu" "In2.Cu" "In3.Cu" "In4.Cu" "In5.Cu" "In6.Cu"
			"In7.Cu" "In8.Cu" "In9.Cu" "In10.Cu" "In11.Cu" "In12.Cu" "In13.Cu" "In14.Cu"
			"In15.Cu" "In16.Cu"
		)
		(hatch none 0.5)
		(connect_pads
			(clearance 0)
		)
		(min_thickness 0.25)
		(keepout
			(tracks not_allowed)
			(vias allowed)
			(pads allowed)
			(copperpour not_allowed)
			(footprints allowed)
		)
		(placement
			(enabled no)
			(sheetname "")
		)
		(fill
			(thermal_gap 0.5)
			(thermal_bridge_width 0.5)
			(island_removal_mode 0)
		)
		(polygon
			(pts
				(arc
					(start 389.84174 -342.058498)
					(mid 389.46074 -342.439498)
					(end 389.84174 -342.820498)
				)
				(arc
					(start 390.70534 -342.820498)
					(mid 391.08634 -342.439498)
					(end 390.70534 -342.058498)
				)
			)
		)
	)
	(zone
		(layers "F.Cu" "B.Cu" "In1.Cu" "In2.Cu" "In3.Cu" "In4.Cu" "In5.Cu" "In6.Cu"
			"In7.Cu" "In8.Cu" "In9.Cu" "In10.Cu" "In11.Cu" "In12.Cu" "In13.Cu" "In14.Cu"
			"In15.Cu" "In16.Cu"
		)
		(hatch none 0.5)
		(connect_pads
			(clearance 0)
		)
		(min_thickness 0.25)
		(keepout
			(tracks not_allowed)
			(vias allowed)
			(pads allowed)
			(copperpour not_allowed)
			(footprints allowed)
		)
		(placement
			(enabled no)
			(sheetname "")
		)
		(fill
			(thermal_gap 0.5)
			(thermal_bridge_width 0.5)
			(island_removal_mode 0)
		)
		(polygon
			(pts
				(arc
					(start 337.681062 -404.828756)
					(mid 337.695941 -404.792835)
					(end 337.731862 -404.777956)
				)
				(arc
					(start 338.448142 -404.777956)
					(mid 338.484063 -404.792835)
					(end 338.498942 -404.828756)
				)
				(arc
					(start 338.498942 -407.251408)
					(mid 338.484063 -407.287329)
					(end 338.448142 -407.302208)
				)
				(arc
					(start 337.731862 -407.302208)
					(mid 337.695941 -407.287329)
					(end 337.681062 -407.251408)
				)
			)
		)
	)
	(zone
		(layers "F.Cu" "B.Cu" "In1.Cu" "In2.Cu" "In3.Cu" "In4.Cu" "In5.Cu" "In6.Cu"
			"In7.Cu" "In8.Cu" "In9.Cu" "In10.Cu" "In11.Cu" "In12.Cu" "In13.Cu" "In14.Cu"
			"In15.Cu" "In16.Cu"
		)
		(hatch none 0.5)
		(connect_pads
			(clearance 0)
		)
		(min_thickness 0.25)
		(keepout
			(tracks not_allowed)
			(vias allowed)
			(pads allowed)
			(copperpour not_allowed)
			(footprints allowed)
		)
		(placement
			(enabled no)
			(sheetname "")
		)
		(fill
			(thermal_gap 0.5)
			(thermal_bridge_width 0.5)
			(island_removal_mode 0)
		)
		(polygon
			(pts
				(arc
					(start 199.817228 -156.085794)
					(mid 200.274428 -156.542994)
					(end 200.731628 -156.085794)
				)
				(arc
					(start 200.731628 -155.222194)
					(mid 200.274428 -154.764994)
					(end 199.817228 -155.222194)
				)
			)
		)
	)
	(zone
		(layers "F.Cu" "B.Cu" "In1.Cu" "In2.Cu" "In3.Cu" "In4.Cu" "In5.Cu" "In6.Cu"
			"In7.Cu" "In8.Cu" "In9.Cu" "In10.Cu" "In11.Cu" "In12.Cu" "In13.Cu" "In14.Cu"
			"In15.Cu" "In16.Cu"
		)
		(hatch none 0.5)
		(connect_pads
			(clearance 0)
		)
		(min_thickness 0.25)
		(keepout
			(tracks not_allowed)
			(vias allowed)
			(pads allowed)
			(copperpour not_allowed)
			(footprints allowed)
		)
		(placement
			(enabled no)
			(sheetname "")
		)
		(fill
			(thermal_gap 0.5)
			(thermal_bridge_width 0.5)
			(island_removal_mode 0)
		)
		(polygon
			(pts
				(arc
					(start 334.265524 -354.351082)
					(mid 333.884524 -354.732082)
					(end 334.265524 -355.113082)
				)
				(arc
					(start 335.129124 -355.113082)
					(mid 335.510124 -354.732082)
					(end 335.129124 -354.351082)
				)
			)
		)
	)
	(zone
		(layers "F.Cu" "B.Cu" "In1.Cu" "In2.Cu" "In3.Cu" "In4.Cu" "In5.Cu" "In6.Cu"
			"In7.Cu" "In8.Cu" "In9.Cu" "In10.Cu" "In11.Cu" "In12.Cu" "In13.Cu" "In14.Cu"
			"In15.Cu" "In16.Cu"
		)
		(hatch none 0.5)
		(connect_pads
			(clearance 0)
		)
		(min_thickness 0.25)
		(keepout
			(tracks not_allowed)
			(vias allowed)
			(pads allowed)
			(copperpour not_allowed)
			(footprints allowed)
		)
		(placement
			(enabled no)
			(sheetname "")
		)
		(fill
			(thermal_gap 0.5)
			(thermal_bridge_width 0.5)
			(island_removal_mode 0)
		)
		(polygon
			(pts
				(arc
					(start 334.265524 -342.058498)
					(mid 333.884524 -342.439498)
					(end 334.265524 -342.820498)
				)
				(arc
					(start 335.129124 -342.820498)
					(mid 335.510124 -342.439498)
					(end 335.129124 -342.058498)
				)
			)
		)
	)
	(zone
		(layers "F.Cu" "B.Cu" "In1.Cu" "In2.Cu" "In3.Cu" "In4.Cu" "In5.Cu" "In6.Cu"
			"In7.Cu" "In8.Cu" "In9.Cu" "In10.Cu" "In11.Cu" "In12.Cu" "In13.Cu" "In14.Cu"
			"In15.Cu" "In16.Cu"
		)
		(hatch none 0.5)
		(connect_pads
			(clearance 0)
		)
		(min_thickness 0.25)
		(keepout
			(tracks not_allowed)
			(vias allowed)
			(pads allowed)
			(copperpour not_allowed)
			(footprints allowed)
		)
		(placement
			(enabled no)
			(sheetname "")
		)
		(fill
			(thermal_gap 0.5)
			(thermal_bridge_width 0.5)
			(island_removal_mode 0)
		)
		(polygon
			(pts
				(arc
					(start 64.74587 -145.287238)
					(mid 65.20307 -145.744438)
					(end 65.66027 -145.287238)
				)
				(arc
					(start 65.66027 -144.423638)
					(mid 65.20307 -143.966438)
					(end 64.74587 -144.423638)
				)
			)
		)
	)
	(zone
		(layers "F.Cu" "B.Cu" "In1.Cu" "In2.Cu" "In3.Cu" "In4.Cu" "In5.Cu" "In6.Cu"
			"In7.Cu" "In8.Cu" "In9.Cu" "In10.Cu" "In11.Cu" "In12.Cu" "In13.Cu" "In14.Cu"
			"In15.Cu" "In16.Cu"
		)
		(hatch none 0.5)
		(connect_pads
			(clearance 0)
		)
		(min_thickness 0.25)
		(keepout
			(tracks not_allowed)
			(vias allowed)
			(pads allowed)
			(copperpour not_allowed)
			(footprints allowed)
		)
		(placement
			(enabled no)
			(sheetname "")
		)
		(fill
			(thermal_gap 0.5)
			(thermal_bridge_width 0.5)
			(island_removal_mode 0)
		)
		(polygon
			(pts
				(arc
					(start 168.800018 -108.312712)
					(mid 168.342818 -107.855512)
					(end 167.885618 -108.312712)
				)
				(arc
					(start 167.885618 -109.176312)
					(mid 168.342818 -109.633512)
					(end 168.800018 -109.176312)
				)
			)
		)
	)
	(zone
		(layers "F.Cu" "B.Cu" "In1.Cu" "In2.Cu" "In3.Cu" "In4.Cu" "In5.Cu" "In6.Cu"
			"In7.Cu" "In8.Cu" "In9.Cu" "In10.Cu" "In11.Cu" "In12.Cu" "In13.Cu" "In14.Cu"
			"In15.Cu" "In16.Cu"
		)
		(hatch none 0.5)
		(connect_pads
			(clearance 0)
		)
		(min_thickness 0.25)
		(keepout
			(tracks not_allowed)
			(vias allowed)
			(pads allowed)
			(copperpour not_allowed)
			(footprints allowed)
		)
		(placement
			(enabled no)
			(sheetname "")
		)
		(fill
			(thermal_gap 0.5)
			(thermal_bridge_width 0.5)
			(island_removal_mode 0)
		)
		(polygon
			(pts
				(arc
					(start 124.297948 -357.37673)
					(mid 123.916948 -357.75773)
					(end 124.297948 -358.13873)
				)
				(arc
					(start 125.161548 -358.13873)
					(mid 125.542548 -357.75773)
					(end 125.161548 -357.37673)
				)
			)
		)
	)
	(zone
		(layers "F.Cu" "B.Cu" "In1.Cu" "In2.Cu" "In3.Cu" "In4.Cu" "In5.Cu" "In6.Cu"
			"In7.Cu" "In8.Cu" "In9.Cu" "In10.Cu" "In11.Cu" "In12.Cu" "In13.Cu" "In14.Cu"
			"In15.Cu" "In16.Cu"
		)
		(hatch none 0.5)
		(connect_pads
			(clearance 0)
		)
		(min_thickness 0.25)
		(keepout
			(tracks not_allowed)
			(vias allowed)
			(pads allowed)
			(copperpour not_allowed)
			(footprints allowed)
		)
		(placement
			(enabled no)
			(sheetname "")
		)
		(fill
			(thermal_gap 0.5)
			(thermal_bridge_width 0.5)
			(island_removal_mode 0)
		)
		(polygon
			(pts
				(arc
					(start 346.79509 -83.281012)
					(mid 346.33789 -82.823812)
					(end 345.88069 -83.281012)
				)
				(arc
					(start 345.88069 -84.144612)
					(mid 346.33789 -84.601812)
					(end 346.79509 -84.144612)
				)
			)
		)
	)
	(zone
		(layers "F.Cu" "B.Cu" "In1.Cu" "In2.Cu" "In3.Cu" "In4.Cu" "In5.Cu" "In6.Cu"
			"In7.Cu" "In8.Cu" "In9.Cu" "In10.Cu" "In11.Cu" "In12.Cu" "In13.Cu" "In14.Cu"
			"In15.Cu" "In16.Cu"
		)
		(hatch none 0.5)
		(connect_pads
			(clearance 0)
		)
		(min_thickness 0.25)
		(keepout
			(tracks not_allowed)
			(vias allowed)
			(pads allowed)
			(copperpour not_allowed)
			(footprints allowed)
		)
		(placement
			(enabled no)
			(sheetname "")
		)
		(fill
			(thermal_gap 0.5)
			(thermal_bridge_width 0.5)
			(island_removal_mode 0)
		)
		(polygon
			(pts
				(arc
					(start 284.899862 -124.622814)
					(mid 284.442662 -124.165614)
					(end 283.985462 -124.622814)
				)
				(arc
					(start 283.985462 -125.486414)
					(mid 284.442662 -125.943614)
					(end 284.899862 -125.486414)
				)
			)
		)
	)
	(zone
		(layers "F.Cu" "B.Cu" "In1.Cu" "In2.Cu" "In3.Cu" "In4.Cu" "In5.Cu" "In6.Cu"
			"In7.Cu" "In8.Cu" "In9.Cu" "In10.Cu" "In11.Cu" "In12.Cu" "In13.Cu" "In14.Cu"
			"In15.Cu" "In16.Cu"
		)
		(hatch none 0.5)
		(connect_pads
			(clearance 0)
		)
		(min_thickness 0.25)
		(keepout
			(tracks not_allowed)
			(vias allowed)
			(pads allowed)
			(copperpour not_allowed)
			(footprints allowed)
		)
		(placement
			(enabled no)
			(sheetname "")
		)
		(fill
			(thermal_gap 0.5)
			(thermal_bridge_width 0.5)
			(island_removal_mode 0)
		)
		(polygon
			(pts
				(arc
					(start 91.301062 -397.028924)
					(mid 91.315941 -396.993003)
					(end 91.351862 -396.978124)
				)
				(arc
					(start 92.068142 -396.978124)
					(mid 92.104063 -396.993003)
					(end 92.118942 -397.028924)
				)
				(arc
					(start 92.118942 -399.451576)
					(mid 92.104063 -399.487497)
					(end 92.068142 -399.502376)
				)
				(arc
					(start 91.351862 -399.502376)
					(mid 91.315941 -399.487497)
					(end 91.301062 -399.451576)
				)
			)
		)
	)
	(zone
		(layers "F.Cu" "B.Cu" "In1.Cu" "In2.Cu" "In3.Cu" "In4.Cu" "In5.Cu" "In6.Cu"
			"In7.Cu" "In8.Cu" "In9.Cu" "In10.Cu" "In11.Cu" "In12.Cu" "In13.Cu" "In14.Cu"
			"In15.Cu" "In16.Cu"
		)
		(hatch none 0.5)
		(connect_pads
			(clearance 0)
		)
		(min_thickness 0.25)
		(keepout
			(tracks not_allowed)
			(vias allowed)
			(pads allowed)
			(copperpour not_allowed)
			(footprints allowed)
		)
		(placement
			(enabled no)
			(sheetname "")
		)
		(fill
			(thermal_gap 0.5)
			(thermal_bridge_width 0.5)
			(island_removal_mode 0)
		)
		(polygon
			(pts
				(arc
					(start 170.501056 -404.828756)
					(mid 170.515935 -404.792835)
					(end 170.551856 -404.777956)
				)
				(arc
					(start 171.268136 -404.777956)
					(mid 171.304057 -404.792835)
					(end 171.318936 -404.828756)
				)
				(arc
					(start 171.318936 -407.251408)
					(mid 171.304057 -407.287329)
					(end 171.268136 -407.302208)
				)
				(arc
					(start 170.551856 -407.302208)
					(mid 170.515935 -407.287329)
					(end 170.501056 -407.251408)
				)
			)
		)
	)
	(zone
		(layers "F.Cu" "B.Cu" "In1.Cu" "In2.Cu" "In3.Cu" "In4.Cu" "In5.Cu" "In6.Cu"
			"In7.Cu" "In8.Cu" "In9.Cu" "In10.Cu" "In11.Cu" "In12.Cu" "In13.Cu" "In14.Cu"
			"In15.Cu" "In16.Cu"
		)
		(hatch none 0.5)
		(connect_pads
			(clearance 0)
		)
		(min_thickness 0.25)
		(keepout
			(tracks not_allowed)
			(vias allowed)
			(pads allowed)
			(copperpour not_allowed)
			(footprints allowed)
		)
		(placement
			(enabled no)
			(sheetname "")
		)
		(fill
			(thermal_gap 0.5)
			(thermal_bridge_width 0.5)
			(island_removal_mode 0)
		)
		(polygon
			(pts
				(arc
					(start 233.599228 -82.503518)
					(mid 233.142028 -82.046318)
					(end 232.684828 -82.503518)
				)
				(arc
					(start 232.684828 -83.367118)
					(mid 233.142028 -83.824318)
					(end 233.599228 -83.367118)
				)
			)
		)
	)
	(zone
		(layers "F.Cu" "B.Cu" "In1.Cu" "In2.Cu" "In3.Cu" "In4.Cu" "In5.Cu" "In6.Cu"
			"In7.Cu" "In8.Cu" "In9.Cu" "In10.Cu" "In11.Cu" "In12.Cu" "In13.Cu" "In14.Cu"
			"In15.Cu" "In16.Cu"
		)
		(hatch none 0.5)
		(connect_pads
			(clearance 0)
		)
		(min_thickness 0.25)
		(keepout
			(tracks not_allowed)
			(vias allowed)
			(pads allowed)
			(copperpour not_allowed)
			(footprints allowed)
		)
		(placement
			(enabled no)
			(sheetname "")
		)
		(fill
			(thermal_gap 0.5)
			(thermal_bridge_width 0.5)
			(island_removal_mode 0)
		)
		(polygon
			(pts
				(arc
					(start 32.7533 -30.922468)
					(mid 33.2105 -31.379668)
					(end 33.6677 -30.922468)
				)
				(arc
					(start 33.6677 -30.058868)
					(mid 33.2105 -29.601668)
					(end 32.7533 -30.058868)
				)
			)
		)
	)
	(zone
		(layers "F.Cu" "B.Cu" "In1.Cu" "In2.Cu" "In3.Cu" "In4.Cu" "In5.Cu" "In6.Cu"
			"In7.Cu" "In8.Cu" "In9.Cu" "In10.Cu" "In11.Cu" "In12.Cu" "In13.Cu" "In14.Cu"
			"In15.Cu" "In16.Cu"
		)
		(hatch none 0.5)
		(connect_pads
			(clearance 0)
		)
		(min_thickness 0.25)
		(keepout
			(tracks not_allowed)
			(vias allowed)
			(pads allowed)
			(copperpour not_allowed)
			(footprints allowed)
		)
		(placement
			(enabled no)
			(sheetname "")
		)
		(fill
			(thermal_gap 0.5)
			(thermal_bridge_width 0.5)
			(island_removal_mode 0)
		)
		(polygon
			(pts
				(arc
					(start 315.917072 -152.485852)
					(mid 316.374272 -152.943052)
					(end 316.831472 -152.485852)
				)
				(arc
					(start 316.831472 -151.622252)
					(mid 316.374272 -151.165052)
					(end 315.917072 -151.622252)
				)
			)
		)
	)
	(zone
		(layers "F.Cu" "B.Cu" "In1.Cu" "In2.Cu" "In3.Cu" "In4.Cu" "In5.Cu" "In6.Cu"
			"In7.Cu" "In8.Cu" "In9.Cu" "In10.Cu" "In11.Cu" "In12.Cu" "In13.Cu" "In14.Cu"
			"In15.Cu" "In16.Cu"
		)
		(hatch none 0.5)
		(connect_pads
			(clearance 0)
		)
		(min_thickness 0.25)
		(keepout
			(tracks not_allowed)
			(vias allowed)
			(pads allowed)
			(copperpour not_allowed)
			(footprints allowed)
		)
		(placement
			(enabled no)
			(sheetname "")
		)
		(fill
			(thermal_gap 0.5)
			(thermal_bridge_width 0.5)
			(island_removal_mode 0)
		)
		(polygon
			(pts
				(arc
					(start 328.047604 -342.058498)
					(mid 327.666604 -342.439498)
					(end 328.047604 -342.820498)
				)
				(arc
					(start 328.911204 -342.820498)
					(mid 329.292204 -342.439498)
					(end 328.911204 -342.058498)
				)
			)
		)
	)
	(zone
		(layers "F.Cu" "B.Cu" "In1.Cu" "In2.Cu" "In3.Cu" "In4.Cu" "In5.Cu" "In6.Cu"
			"In7.Cu" "In8.Cu" "In9.Cu" "In10.Cu" "In11.Cu" "In12.Cu" "In13.Cu" "In14.Cu"
			"In15.Cu" "In16.Cu"
		)
		(hatch none 0.5)
		(connect_pads
			(clearance 0)
		)
		(min_thickness 0.25)
		(keepout
			(tracks allowed)
			(vias allowed)
			(pads allowed)
			(copperpour allowed)
			(footprints not_allowed)
		)
		(placement
			(enabled no)
			(sheetname "")
		)
		(fill yes
			(thermal_gap 0.5)
			(thermal_bridge_width 0.5)
			(island_removal_mode 0)
		)
		(polygon
			(pts
				(arc
					(start 464.16595 -13.599922)
					(mid 461.600042 -11.034014)
					(end 459.03388 -13.599922)
				)
				(arc
					(start 459.03388 -15.200122)
					(mid 461.600042 -17.766284)
					(end 464.16595 -15.200122)
				)
			)
		)
	)
	(zone
		(layers "F.Cu" "B.Cu" "In1.Cu" "In2.Cu" "In3.Cu" "In4.Cu" "In5.Cu" "In6.Cu"
			"In7.Cu" "In8.Cu" "In9.Cu" "In10.Cu" "In11.Cu" "In12.Cu" "In13.Cu" "In14.Cu"
			"In15.Cu" "In16.Cu"
		)
		(hatch none 0.5)
		(connect_pads
			(clearance 0)
		)
		(min_thickness 0.25)
		(keepout
			(tracks not_allowed)
			(vias allowed)
			(pads allowed)
			(copperpour not_allowed)
			(footprints allowed)
		)
		(placement
			(enabled no)
			(sheetname "")
		)
		(fill
			(thermal_gap 0.5)
			(thermal_bridge_width 0.5)
			(island_removal_mode 0)
		)
		(polygon
			(pts
				(arc
					(start 50.422048 -348.20479)
					(mid 50.041048 -348.58579)
					(end 50.422048 -348.96679)
				)
				(arc
					(start 51.285648 -348.96679)
					(mid 51.666648 -348.58579)
					(end 51.285648 -348.20479)
				)
			)
		)
	)
	(zone
		(layers "F.Cu" "B.Cu" "In1.Cu" "In2.Cu" "In3.Cu" "In4.Cu" "In5.Cu" "In6.Cu"
			"In7.Cu" "In8.Cu" "In9.Cu" "In10.Cu" "In11.Cu" "In12.Cu" "In13.Cu" "In14.Cu"
			"In15.Cu" "In16.Cu"
		)
		(hatch none 0.5)
		(connect_pads
			(clearance 0)
		)
		(min_thickness 0.25)
		(keepout
			(tracks not_allowed)
			(vias allowed)
			(pads allowed)
			(copperpour not_allowed)
			(footprints allowed)
		)
		(placement
			(enabled no)
			(sheetname "")
		)
		(fill
			(thermal_gap 0.5)
			(thermal_bridge_width 0.5)
			(island_removal_mode 0)
		)
		(polygon
			(pts
				(arc
					(start 58.102246 -370.447062)
					(mid 57.721246 -370.066062)
					(end 57.340246 -370.447062)
				)
				(arc
					(start 57.340246 -371.310662)
					(mid 57.721246 -371.691662)
					(end 58.102246 -371.310662)
				)
			)
		)
	)
	(zone
		(layers "F.Cu" "B.Cu" "In1.Cu" "In2.Cu" "In3.Cu" "In4.Cu" "In5.Cu" "In6.Cu"
			"In7.Cu" "In8.Cu" "In9.Cu" "In10.Cu" "In11.Cu" "In12.Cu" "In13.Cu" "In14.Cu"
			"In15.Cu" "In16.Cu"
		)
		(hatch none 0.5)
		(connect_pads
			(clearance 0)
		)
		(min_thickness 0.25)
		(keepout
			(tracks not_allowed)
			(vias allowed)
			(pads allowed)
			(copperpour not_allowed)
			(footprints allowed)
		)
		(placement
			(enabled no)
			(sheetname "")
		)
		(fill
			(thermal_gap 0.5)
			(thermal_bridge_width 0.5)
			(island_removal_mode 0)
		)
		(polygon
			(pts
				(arc
					(start 162.186112 -351.230438)
					(mid 161.805112 -351.611438)
					(end 162.186112 -351.992438)
				)
				(arc
					(start 163.049712 -351.992438)
					(mid 163.430712 -351.611438)
					(end 163.049712 -351.230438)
				)
			)
		)
	)
	(zone
		(layers "F.Cu" "B.Cu" "In1.Cu" "In2.Cu" "In3.Cu" "In4.Cu" "In5.Cu" "In6.Cu"
			"In7.Cu" "In8.Cu" "In9.Cu" "In10.Cu" "In11.Cu" "In12.Cu" "In13.Cu" "In14.Cu"
			"In15.Cu" "In16.Cu"
		)
		(hatch none 0.5)
		(connect_pads
			(clearance 0)
		)
		(min_thickness 0.25)
		(keepout
			(tracks not_allowed)
			(vias allowed)
			(pads allowed)
			(copperpour not_allowed)
			(footprints allowed)
		)
		(placement
			(enabled no)
			(sheetname "")
		)
		(fill
			(thermal_gap 0.5)
			(thermal_bridge_width 0.5)
			(island_removal_mode 0)
		)
		(polygon
			(pts
				(arc
					(start 334.265524 -357.37673)
					(mid 333.884524 -357.75773)
					(end 334.265524 -358.13873)
				)
				(arc
					(start 335.129124 -358.13873)
					(mid 335.510124 -357.75773)
					(end 335.129124 -357.37673)
				)
			)
		)
	)
	(zone
		(layers "F.Cu" "B.Cu" "In1.Cu" "In2.Cu" "In3.Cu" "In4.Cu" "In5.Cu" "In6.Cu"
			"In7.Cu" "In8.Cu" "In9.Cu" "In10.Cu" "In11.Cu" "In12.Cu" "In13.Cu" "In14.Cu"
			"In15.Cu" "In16.Cu"
		)
		(hatch none 0.5)
		(connect_pads
			(clearance 0)
		)
		(min_thickness 0.25)
		(keepout
			(tracks not_allowed)
			(vias allowed)
			(pads allowed)
			(copperpour not_allowed)
			(footprints allowed)
		)
		(placement
			(enabled no)
			(sheetname "")
		)
		(fill
			(thermal_gap 0.5)
			(thermal_bridge_width 0.5)
			(island_removal_mode 0)
		)
		(polygon
			(pts
				(arc
					(start 432.01717 -132.575808)
					(mid 432.47437 -133.033008)
					(end 432.93157 -132.575808)
				)
				(arc
					(start 432.93157 -131.712208)
					(mid 432.47437 -131.255008)
					(end 432.01717 -131.712208)
				)
			)
		)
	)
	(zone
		(layers "F.Cu" "B.Cu" "In1.Cu" "In2.Cu" "In3.Cu" "In4.Cu" "In5.Cu" "In6.Cu"
			"In7.Cu" "In8.Cu" "In9.Cu" "In10.Cu" "In11.Cu" "In12.Cu" "In13.Cu" "In14.Cu"
			"In15.Cu" "In16.Cu"
		)
		(hatch none 0.5)
		(connect_pads
			(clearance 0)
		)
		(min_thickness 0.25)
		(keepout
			(tracks not_allowed)
			(vias allowed)
			(pads allowed)
			(copperpour not_allowed)
			(footprints allowed)
		)
		(placement
			(enabled no)
			(sheetname "")
		)
		(fill
			(thermal_gap 0.5)
			(thermal_bridge_width 0.5)
			(island_removal_mode 0)
		)
		(polygon
			(pts
				(arc
					(start 47.490126 -34.520886)
					(mid 47.947326 -34.978086)
					(end 48.404526 -34.520886)
				)
				(arc
					(start 48.404526 -33.657286)
					(mid 47.947326 -33.200086)
					(end 47.490126 -33.657286)
				)
			)
		)
	)
	(zone
		(layers "F.Cu" "B.Cu" "In1.Cu" "In2.Cu" "In3.Cu" "In4.Cu" "In5.Cu" "In6.Cu"
			"In7.Cu" "In8.Cu" "In9.Cu" "In10.Cu" "In11.Cu" "In12.Cu" "In13.Cu" "In14.Cu"
			"In15.Cu" "In16.Cu"
		)
		(hatch none 0.5)
		(connect_pads
			(clearance 0)
		)
		(min_thickness 0.25)
		(keepout
			(tracks not_allowed)
			(vias allowed)
			(pads allowed)
			(copperpour not_allowed)
			(footprints allowed)
		)
		(placement
			(enabled no)
			(sheetname "")
		)
		(fill
			(thermal_gap 0.5)
			(thermal_bridge_width 0.5)
			(island_removal_mode 0)
		)
		(polygon
			(pts
				(arc
					(start 423.480992 -381.628904)
					(mid 423.495871 -381.592983)
					(end 423.531792 -381.578104)
				)
				(arc
					(start 424.248072 -381.578104)
					(mid 424.283993 -381.592983)
					(end 424.298872 -381.628904)
				)
				(arc
					(start 424.298872 -384.051556)
					(mid 424.283993 -384.087477)
					(end 424.248072 -384.102356)
				)
				(arc
					(start 423.531792 -384.102356)
					(mid 423.495871 -384.087477)
					(end 423.480992 -384.051556)
				)
			)
		)
	)
	(zone
		(layers "F.Cu" "B.Cu" "In1.Cu" "In2.Cu" "In3.Cu" "In4.Cu" "In5.Cu" "In6.Cu"
			"In7.Cu" "In8.Cu" "In9.Cu" "In10.Cu" "In11.Cu" "In12.Cu" "In13.Cu" "In14.Cu"
			"In15.Cu" "In16.Cu"
		)
		(hatch none 0.5)
		(connect_pads
			(clearance 0)
		)
		(min_thickness 0.25)
		(keepout
			(tracks not_allowed)
			(vias allowed)
			(pads allowed)
			(copperpour not_allowed)
			(footprints allowed)
		)
		(placement
			(enabled no)
			(sheetname "")
		)
		(fill
			(thermal_gap 0.5)
			(thermal_bridge_width 0.5)
			(island_removal_mode 0)
		)
		(polygon
			(pts
				(arc
					(start 184.624218 -27.342846)
					(mid 185.081418 -27.800046)
					(end 185.538618 -27.342846)
				)
				(arc
					(start 185.538618 -26.479246)
					(mid 185.081418 -26.022046)
					(end 184.624218 -26.479246)
				)
			)
		)
	)
	(zone
		(layers "F.Cu" "B.Cu" "In1.Cu" "In2.Cu" "In3.Cu" "In4.Cu" "In5.Cu" "In6.Cu"
			"In7.Cu" "In8.Cu" "In9.Cu" "In10.Cu" "In11.Cu" "In12.Cu" "In13.Cu" "In14.Cu"
			"In15.Cu" "In16.Cu"
		)
		(hatch none 0.5)
		(connect_pads
			(clearance 0)
		)
		(min_thickness 0.25)
		(keepout
			(tracks not_allowed)
			(vias allowed)
			(pads allowed)
			(copperpour not_allowed)
			(footprints allowed)
		)
		(placement
			(enabled no)
			(sheetname "")
		)
		(fill
			(thermal_gap 0.5)
			(thermal_bridge_width 0.5)
			(island_removal_mode 0)
		)
		(polygon
			(pts
				(arc
					(start 289.659822 -348.20479)
					(mid 289.278822 -348.58579)
					(end 289.659822 -348.96679)
				)
				(arc
					(start 290.523422 -348.96679)
					(mid 290.904422 -348.58579)
					(end 290.523422 -348.20479)
				)
			)
		)
	)
	(zone
		(layers "F.Cu" "B.Cu" "In1.Cu" "In2.Cu" "In3.Cu" "In4.Cu" "In5.Cu" "In6.Cu"
			"In7.Cu" "In8.Cu" "In9.Cu" "In10.Cu" "In11.Cu" "In12.Cu" "In13.Cu" "In14.Cu"
			"In15.Cu" "In16.Cu"
		)
		(hatch none 0.5)
		(connect_pads
			(clearance 0)
		)
		(min_thickness 0.25)
		(keepout
			(tracks not_allowed)
			(vias allowed)
			(pads allowed)
			(copperpour not_allowed)
			(footprints allowed)
		)
		(placement
			(enabled no)
			(sheetname "")
		)
		(fill
			(thermal_gap 0.5)
			(thermal_bridge_width 0.5)
			(island_removal_mode 0)
		)
		(polygon
			(pts
				(arc
					(start 107.607354 -77.64018)
					(mid 107.150154 -78.09738)
					(end 107.607354 -78.55458)
				)
				(arc
					(start 108.470954 -78.55458)
					(mid 108.928154 -78.09738)
					(end 108.470954 -77.64018)
				)
			)
		)
	)
	(zone
		(layers "F.Cu" "B.Cu" "In1.Cu" "In2.Cu" "In3.Cu" "In4.Cu" "In5.Cu" "In6.Cu"
			"In7.Cu" "In8.Cu" "In9.Cu" "In10.Cu" "In11.Cu" "In12.Cu" "In13.Cu" "In14.Cu"
			"In15.Cu" "In16.Cu"
		)
		(hatch none 0.5)
		(connect_pads
			(clearance 0)
		)
		(min_thickness 0.25)
		(keepout
			(tracks not_allowed)
			(vias allowed)
			(pads allowed)
			(copperpour not_allowed)
			(footprints allowed)
		)
		(placement
			(enabled no)
			(sheetname "")
		)
		(fill
			(thermal_gap 0.5)
			(thermal_bridge_width 0.5)
			(island_removal_mode 0)
		)
		(polygon
			(pts
				(arc
					(start 402.27758 -348.20479)
					(mid 401.89658 -348.58579)
					(end 402.27758 -348.96679)
				)
				(arc
					(start 403.14118 -348.96679)
					(mid 403.52218 -348.58579)
					(end 403.14118 -348.20479)
				)
			)
		)
	)
	(zone
		(layers "F.Cu" "B.Cu" "In1.Cu" "In2.Cu" "In3.Cu" "In4.Cu" "In5.Cu" "In6.Cu"
			"In7.Cu" "In8.Cu" "In9.Cu" "In10.Cu" "In11.Cu" "In12.Cu" "In13.Cu" "In14.Cu"
			"In15.Cu" "In16.Cu"
		)
		(hatch none 0.5)
		(connect_pads
			(clearance 0)
		)
		(min_thickness 0.25)
		(keepout
			(tracks not_allowed)
			(vias allowed)
			(pads allowed)
			(copperpour not_allowed)
			(footprints allowed)
		)
		(placement
			(enabled no)
			(sheetname "")
		)
		(fill
			(thermal_gap 0.5)
			(thermal_bridge_width 0.5)
			(island_removal_mode 0)
		)
		(polygon
			(pts
				(arc
					(start 76.917042 -351.230438)
					(mid 76.536042 -351.611438)
					(end 76.917042 -351.992438)
				)
				(arc
					(start 77.780642 -351.992438)
					(mid 78.161642 -351.611438)
					(end 77.780642 -351.230438)
				)
			)
		)
	)
	(zone
		(layers "F.Cu" "B.Cu" "In1.Cu" "In2.Cu" "In3.Cu" "In4.Cu" "In5.Cu" "In6.Cu"
			"In7.Cu" "In8.Cu" "In9.Cu" "In10.Cu" "In11.Cu" "In12.Cu" "In13.Cu" "In14.Cu"
			"In15.Cu" "In16.Cu"
		)
		(hatch none 0.5)
		(connect_pads
			(clearance 0)
		)
		(min_thickness 0.25)
		(keepout
			(tracks not_allowed)
			(vias allowed)
			(pads allowed)
			(copperpour not_allowed)
			(footprints allowed)
		)
		(placement
			(enabled no)
			(sheetname "")
		)
		(fill
			(thermal_gap 0.5)
			(thermal_bridge_width 0.5)
			(island_removal_mode 0)
		)
		(polygon
			(pts
				(arc
					(start 267.897102 -342.058498)
					(mid 267.516102 -342.439498)
					(end 267.897102 -342.820498)
				)
				(arc
					(start 268.760702 -342.820498)
					(mid 269.141702 -342.439498)
					(end 268.760702 -342.058498)
				)
			)
		)
	)
	(zone
		(layers "F.Cu" "B.Cu" "In1.Cu" "In2.Cu" "In3.Cu" "In4.Cu" "In5.Cu" "In6.Cu"
			"In7.Cu" "In8.Cu" "In9.Cu" "In10.Cu" "In11.Cu" "In12.Cu" "In13.Cu" "In14.Cu"
			"In15.Cu" "In16.Cu"
		)
		(hatch none 0.5)
		(connect_pads
			(clearance 0)
		)
		(min_thickness 0.25)
		(keepout
			(tracks not_allowed)
			(vias allowed)
			(pads allowed)
			(copperpour not_allowed)
			(footprints allowed)
		)
		(placement
			(enabled no)
			(sheetname "")
		)
		(fill
			(thermal_gap 0.5)
			(thermal_bridge_width 0.5)
			(island_removal_mode 0)
		)
		(polygon
			(pts
				(arc
					(start 168.800018 -104.71277)
					(mid 168.342818 -104.25557)
					(end 167.885618 -104.71277)
				)
				(arc
					(start 167.885618 -105.57637)
					(mid 168.342818 -106.03357)
					(end 168.800018 -105.57637)
				)
			)
		)
	)
	(zone
		(layers "F.Cu" "B.Cu" "In1.Cu" "In2.Cu" "In3.Cu" "In4.Cu" "In5.Cu" "In6.Cu"
			"In7.Cu" "In8.Cu" "In9.Cu" "In10.Cu" "In11.Cu" "In12.Cu" "In13.Cu" "In14.Cu"
			"In15.Cu" "In16.Cu"
		)
		(hatch none 0.5)
		(connect_pads
			(clearance 0)
		)
		(min_thickness 0.25)
		(keepout
			(tracks not_allowed)
			(vias allowed)
			(pads allowed)
			(copperpour not_allowed)
			(footprints allowed)
		)
		(placement
			(enabled no)
			(sheetname "")
		)
		(fill
			(thermal_gap 0.5)
			(thermal_bridge_width 0.5)
			(island_removal_mode 0)
		)
		(polygon
			(pts
				(arc
					(start 395.95933 -160.1851)
					(mid 393.82573 -160.1851)
					(end 395.95933 -160.1851)
				)
			)
		)
	)
	(zone
		(layers "F.Cu" "B.Cu" "In1.Cu" "In2.Cu" "In3.Cu" "In4.Cu" "In5.Cu" "In6.Cu"
			"In7.Cu" "In8.Cu" "In9.Cu" "In10.Cu" "In11.Cu" "In12.Cu" "In13.Cu" "In14.Cu"
			"In15.Cu" "In16.Cu"
		)
		(hatch none 0.5)
		(connect_pads
			(clearance 0)
		)
		(min_thickness 0.25)
		(keepout
			(tracks not_allowed)
			(vias allowed)
			(pads allowed)
			(copperpour not_allowed)
			(footprints allowed)
		)
		(placement
			(enabled no)
			(sheetname "")
		)
		(fill
			(thermal_gap 0.5)
			(thermal_bridge_width 0.5)
			(island_removal_mode 0)
		)
		(polygon
			(pts
				(arc
					(start 168.800018 -111.912908)
					(mid 168.342818 -111.455708)
					(end 167.885618 -111.912908)
				)
				(arc
					(start 167.885618 -112.776508)
					(mid 168.342818 -113.233708)
					(end 168.800018 -112.776508)
				)
			)
		)
	)
	(zone
		(layers "F.Cu" "B.Cu" "In1.Cu" "In2.Cu" "In3.Cu" "In4.Cu" "In5.Cu" "In6.Cu"
			"In7.Cu" "In8.Cu" "In9.Cu" "In10.Cu" "In11.Cu" "In12.Cu" "In13.Cu" "In14.Cu"
			"In15.Cu" "In16.Cu"
		)
		(hatch none 0.5)
		(connect_pads
			(clearance 0)
		)
		(min_thickness 0.25)
		(keepout
			(tracks not_allowed)
			(vias allowed)
			(pads allowed)
			(copperpour not_allowed)
			(footprints allowed)
		)
		(placement
			(enabled no)
			(sheetname "")
		)
		(fill
			(thermal_gap 0.5)
			(thermal_bridge_width 0.5)
			(island_removal_mode 0)
		)
		(polygon
			(pts
				(arc
					(start 421.280844 -371.028722)
					(mid 421.295723 -370.992801)
					(end 421.331644 -370.977922)
				)
				(arc
					(start 422.047924 -370.977922)
					(mid 422.083845 -370.992801)
					(end 422.098724 -371.028722)
				)
				(arc
					(start 422.098724 -373.451374)
					(mid 422.083845 -373.487295)
					(end 422.047924 -373.502174)
				)
				(arc
					(start 421.331644 -373.502174)
					(mid 421.295723 -373.487295)
					(end 421.280844 -373.451374)
				)
			)
		)
	)
	(zone
		(layers "F.Cu" "B.Cu" "In1.Cu" "In2.Cu" "In3.Cu" "In4.Cu" "In5.Cu" "In6.Cu"
			"In7.Cu" "In8.Cu" "In9.Cu" "In10.Cu" "In11.Cu" "In12.Cu" "In13.Cu" "In14.Cu"
			"In15.Cu" "In16.Cu"
		)
		(hatch none 0.5)
		(connect_pads
			(clearance 0)
		)
		(min_thickness 0.25)
		(keepout
			(tracks not_allowed)
			(vias allowed)
			(pads allowed)
			(copperpour not_allowed)
			(footprints allowed)
		)
		(placement
			(enabled no)
			(sheetname "")
		)
		(fill
			(thermal_gap 0.5)
			(thermal_bridge_width 0.5)
			(island_removal_mode 0)
		)
		(polygon
			(pts
				(arc
					(start 344.280998 -395.92885)
					(mid 344.295877 -395.892929)
					(end 344.331798 -395.87805)
				)
				(arc
					(start 345.048078 -395.87805)
					(mid 345.083999 -395.892929)
					(end 345.098878 -395.92885)
				)
				(arc
					(start 345.098878 -398.351502)
					(mid 345.083999 -398.387423)
					(end 345.048078 -398.402302)
				)
				(arc
					(start 344.331798 -398.402302)
					(mid 344.295877 -398.387423)
					(end 344.280998 -398.351502)
				)
			)
		)
	)
	(zone
		(layers "F.Cu" "B.Cu" "In1.Cu" "In2.Cu" "In3.Cu" "In4.Cu" "In5.Cu" "In6.Cu"
			"In7.Cu" "In8.Cu" "In9.Cu" "In10.Cu" "In11.Cu" "In12.Cu" "In13.Cu" "In14.Cu"
			"In15.Cu" "In16.Cu"
		)
		(hatch none 0.5)
		(connect_pads
			(clearance 0)
		)
		(min_thickness 0.25)
		(keepout
			(tracks not_allowed)
			(vias allowed)
			(pads allowed)
			(copperpour not_allowed)
			(footprints allowed)
		)
		(placement
			(enabled no)
			(sheetname "")
		)
		(fill
			(thermal_gap 0.5)
			(thermal_bridge_width 0.5)
			(island_removal_mode 0)
		)
		(polygon
			(pts
				(arc
					(start 318.720724 -351.230438)
					(mid 318.339724 -351.611438)
					(end 318.720724 -351.992438)
				)
				(arc
					(start 319.584324 -351.992438)
					(mid 319.965324 -351.611438)
					(end 319.584324 -351.230438)
				)
			)
		)
	)
	(zone
		(layers "F.Cu" "B.Cu" "In1.Cu" "In2.Cu" "In3.Cu" "In4.Cu" "In5.Cu" "In6.Cu"
			"In7.Cu" "In8.Cu" "In9.Cu" "In10.Cu" "In11.Cu" "In12.Cu" "In13.Cu" "In14.Cu"
			"In15.Cu" "In16.Cu"
		)
		(hatch none 0.5)
		(connect_pads
			(clearance 0)
		)
		(min_thickness 0.25)
		(keepout
			(tracks not_allowed)
			(vias allowed)
			(pads allowed)
			(copperpour not_allowed)
			(footprints allowed)
		)
		(placement
			(enabled no)
			(sheetname "")
		)
		(fill
			(thermal_gap 0.5)
			(thermal_bridge_width 0.5)
			(island_removal_mode 0)
		)
		(polygon
			(pts
				(arc
					(start 54.55412 -110.11281)
					(mid 54.09692 -109.65561)
					(end 53.63972 -110.11281)
				)
				(arc
					(start 53.63972 -110.97641)
					(mid 54.09692 -111.43361)
					(end 54.55412 -110.97641)
				)
			)
		)
	)
	(zone
		(layers "F.Cu" "B.Cu" "In1.Cu" "In2.Cu" "In3.Cu" "In4.Cu" "In5.Cu" "In6.Cu"
			"In7.Cu" "In8.Cu" "In9.Cu" "In10.Cu" "In11.Cu" "In12.Cu" "In13.Cu" "In14.Cu"
			"In15.Cu" "In16.Cu"
		)
		(hatch none 0.5)
		(connect_pads
			(clearance 0)
		)
		(min_thickness 0.25)
		(keepout
			(tracks not_allowed)
			(vias allowed)
			(pads allowed)
			(copperpour not_allowed)
			(footprints allowed)
		)
		(placement
			(enabled no)
			(sheetname "")
		)
		(fill
			(thermal_gap 0.5)
			(thermal_bridge_width 0.5)
			(island_removal_mode 0)
		)
		(polygon
			(pts
				(arc
					(start 37.310568 -103.777796)
					(mid 37.767768 -104.234996)
					(end 38.224968 -103.777796)
				)
				(arc
					(start 38.224968 -102.914196)
					(mid 37.767768 -102.456996)
					(end 37.310568 -102.914196)
				)
			)
		)
	)
	(zone
		(layers "F.Cu" "B.Cu" "In1.Cu" "In2.Cu" "In3.Cu" "In4.Cu" "In5.Cu" "In6.Cu"
			"In7.Cu" "In8.Cu" "In9.Cu" "In10.Cu" "In11.Cu" "In12.Cu" "In13.Cu" "In14.Cu"
			"In15.Cu" "In16.Cu"
		)
		(hatch none 0.5)
		(connect_pads
			(clearance 0)
		)
		(min_thickness 0.25)
		(keepout
			(tracks not_allowed)
			(vias allowed)
			(pads allowed)
			(copperpour not_allowed)
			(footprints allowed)
		)
		(placement
			(enabled no)
			(sheetname "")
		)
		(fill
			(thermal_gap 0.5)
			(thermal_bridge_width 0.5)
			(island_removal_mode 0)
		)
		(polygon
			(pts
				(arc
					(start 266.868402 -131.297934)
					(mid 267.325602 -131.755134)
					(end 267.782802 -131.297934)
				)
				(arc
					(start 267.782802 -130.434334)
					(mid 267.325602 -129.977134)
					(end 266.868402 -130.434334)
				)
			)
		)
	)
	(zone
		(layers "F.Cu" "B.Cu" "In1.Cu" "In2.Cu" "In3.Cu" "In4.Cu" "In5.Cu" "In6.Cu"
			"In7.Cu" "In8.Cu" "In9.Cu" "In10.Cu" "In11.Cu" "In12.Cu" "In13.Cu" "In14.Cu"
			"In15.Cu" "In16.Cu"
		)
		(hatch none 0.5)
		(connect_pads
			(clearance 0)
		)
		(min_thickness 0.25)
		(keepout
			(tracks not_allowed)
			(vias allowed)
			(pads allowed)
			(copperpour not_allowed)
			(footprints allowed)
		)
		(placement
			(enabled no)
			(sheetname "")
		)
		(fill
			(thermal_gap 0.5)
			(thermal_bridge_width 0.5)
			(island_removal_mode 0)
		)
		(polygon
			(pts
				(arc
					(start 159.501078 -403.728682)
					(mid 159.515957 -403.692761)
					(end 159.551878 -403.677882)
				)
				(arc
					(start 160.268158 -403.677882)
					(mid 160.304079 -403.692761)
					(end 160.318958 -403.728682)
				)
				(arc
					(start 160.318958 -406.151334)
					(mid 160.304079 -406.187255)
					(end 160.268158 -406.202134)
				)
				(arc
					(start 159.551878 -406.202134)
					(mid 159.515957 -406.187255)
					(end 159.501078 -406.151334)
				)
			)
		)
	)
	(zone
		(layers "F.Cu" "B.Cu" "In1.Cu" "In2.Cu" "In3.Cu" "In4.Cu" "In5.Cu" "In6.Cu"
			"In7.Cu" "In8.Cu" "In9.Cu" "In10.Cu" "In11.Cu" "In12.Cu" "In13.Cu" "In14.Cu"
			"In15.Cu" "In16.Cu"
		)
		(hatch none 0.5)
		(connect_pads
			(clearance 0)
		)
		(min_thickness 0.25)
		(keepout
			(tracks not_allowed)
			(vias allowed)
			(pads allowed)
			(copperpour not_allowed)
			(footprints allowed)
		)
		(placement
			(enabled no)
			(sheetname "")
		)
		(fill
			(thermal_gap 0.5)
			(thermal_bridge_width 0.5)
			(island_removal_mode 0)
		)
		(polygon
			(pts
				(arc
					(start 34.101024 -371.028722)
					(mid 34.115903 -370.992801)
					(end 34.151824 -370.977922)
				)
				(arc
					(start 34.868104 -370.977922)
					(mid 34.904025 -370.992801)
					(end 34.918904 -371.028722)
				)
				(arc
					(start 34.918904 -373.451374)
					(mid 34.904025 -373.487295)
					(end 34.868104 -373.502174)
				)
				(arc
					(start 34.151824 -373.502174)
					(mid 34.115903 -373.487295)
					(end 34.101024 -373.451374)
				)
			)
		)
	)
	(zone
		(layers "F.Cu" "B.Cu" "In1.Cu" "In2.Cu" "In3.Cu" "In4.Cu" "In5.Cu" "In6.Cu"
			"In7.Cu" "In8.Cu" "In9.Cu" "In10.Cu" "In11.Cu" "In12.Cu" "In13.Cu" "In14.Cu"
			"In15.Cu" "In16.Cu"
		)
		(hatch none 0.5)
		(connect_pads
			(clearance 0)
		)
		(min_thickness 0.25)
		(keepout
			(tracks not_allowed)
			(vias allowed)
			(pads allowed)
			(copperpour not_allowed)
			(footprints allowed)
		)
		(placement
			(enabled no)
			(sheetname "")
		)
		(fill
			(thermal_gap 0.5)
			(thermal_bridge_width 0.5)
			(island_removal_mode 0)
		)
		(polygon
			(pts
				(arc
					(start 180.845968 -152.487376)
					(mid 181.303168 -152.944576)
					(end 181.760368 -152.487376)
				)
				(arc
					(start 181.760368 -151.623776)
					(mid 181.303168 -151.166576)
					(end 180.845968 -151.623776)
				)
			)
		)
	)
	(zone
		(layers "F.Cu" "B.Cu" "In1.Cu" "In2.Cu" "In3.Cu" "In4.Cu" "In5.Cu" "In6.Cu"
			"In7.Cu" "In8.Cu" "In9.Cu" "In10.Cu" "In11.Cu" "In12.Cu" "In13.Cu" "In14.Cu"
			"In15.Cu" "In16.Cu"
		)
		(hatch none 0.5)
		(connect_pads
			(clearance 0)
		)
		(min_thickness 0.25)
		(keepout
			(tracks not_allowed)
			(vias allowed)
			(pads allowed)
			(copperpour not_allowed)
			(footprints allowed)
		)
		(placement
			(enabled no)
			(sheetname "")
		)
		(fill
			(thermal_gap 0.5)
			(thermal_bridge_width 0.5)
			(island_removal_mode 0)
		)
		(polygon
			(pts
				(arc
					(start 186.948064 -29.114242)
					(mid 187.405264 -29.571442)
					(end 187.862464 -29.114242)
				)
				(arc
					(start 187.862464 -28.250642)
					(mid 187.405264 -27.793442)
					(end 186.948064 -28.250642)
				)
			)
		)
	)
	(zone
		(layers "F.Cu" "B.Cu" "In1.Cu" "In2.Cu" "In3.Cu" "In4.Cu" "In5.Cu" "In6.Cu"
			"In7.Cu" "In8.Cu" "In9.Cu" "In10.Cu" "In11.Cu" "In12.Cu" "In13.Cu" "In14.Cu"
			"In15.Cu" "In16.Cu"
		)
		(hatch none 0.5)
		(connect_pads
			(clearance 0)
		)
		(min_thickness 0.25)
		(keepout
			(tracks not_allowed)
			(vias allowed)
			(pads allowed)
			(copperpour not_allowed)
			(footprints allowed)
		)
		(placement
			(enabled no)
			(sheetname "")
		)
		(fill
			(thermal_gap 0.5)
			(thermal_bridge_width 0.5)
			(island_removal_mode 0)
		)
		(polygon
			(pts
				(arc
					(start 73.808082 -342.058498)
					(mid 73.427082 -342.439498)
					(end 73.808082 -342.820498)
				)
				(arc
					(start 74.671682 -342.820498)
					(mid 75.052682 -342.439498)
					(end 74.671682 -342.058498)
				)
			)
		)
	)
	(zone
		(layers "F.Cu" "B.Cu" "In1.Cu" "In2.Cu" "In3.Cu" "In4.Cu" "In5.Cu" "In6.Cu"
			"In7.Cu" "In8.Cu" "In9.Cu" "In10.Cu" "In11.Cu" "In12.Cu" "In13.Cu" "In14.Cu"
			"In15.Cu" "In16.Cu"
		)
		(hatch none 0.5)
		(connect_pads
			(clearance 0)
		)
		(min_thickness 0.25)
		(keepout
			(tracks not_allowed)
			(vias allowed)
			(pads allowed)
			(copperpour not_allowed)
			(footprints allowed)
		)
		(placement
			(enabled no)
			(sheetname "")
		)
		(fill
			(thermal_gap 0.5)
			(thermal_bridge_width 0.5)
			(island_removal_mode 0)
		)
		(polygon
			(pts
				(arc
					(start 385.624578 -297.65498)
					(mid 385.954778 -297.32478)
					(end 385.624578 -296.99458)
				)
				(arc
					(start 384.674618 -296.99458)
					(mid 384.344418 -297.32478)
					(end 384.674618 -297.65498)
				)
			)
		)
	)
	(zone
		(layers "F.Cu" "B.Cu" "In1.Cu" "In2.Cu" "In3.Cu" "In4.Cu" "In5.Cu" "In6.Cu"
			"In7.Cu" "In8.Cu" "In9.Cu" "In10.Cu" "In11.Cu" "In12.Cu" "In13.Cu" "In14.Cu"
			"In15.Cu" "In16.Cu"
		)
		(hatch none 0.5)
		(connect_pads
			(clearance 0)
		)
		(min_thickness 0.25)
		(keepout
			(tracks not_allowed)
			(vias allowed)
			(pads allowed)
			(copperpour not_allowed)
			(footprints allowed)
		)
		(placement
			(enabled no)
			(sheetname "")
		)
		(fill
			(thermal_gap 0.5)
			(thermal_bridge_width 0.5)
			(island_removal_mode 0)
		)
		(polygon
			(pts
				(arc
					(start 82.500978 -397.028924)
					(mid 82.515857 -396.993003)
					(end 82.551778 -396.978124)
				)
				(arc
					(start 83.268058 -396.978124)
					(mid 83.303979 -396.993003)
					(end 83.318858 -397.028924)
				)
				(arc
					(start 83.318858 -399.451576)
					(mid 83.303979 -399.487497)
					(end 83.268058 -399.502376)
				)
				(arc
					(start 82.551778 -399.502376)
					(mid 82.515857 -399.487497)
					(end 82.500978 -399.451576)
				)
			)
		)
	)
	(zone
		(layers "F.Cu" "B.Cu" "In1.Cu" "In2.Cu" "In3.Cu" "In4.Cu" "In5.Cu" "In6.Cu"
			"In7.Cu" "In8.Cu" "In9.Cu" "In10.Cu" "In11.Cu" "In12.Cu" "In13.Cu" "In14.Cu"
			"In15.Cu" "In16.Cu"
		)
		(hatch none 0.5)
		(connect_pads
			(clearance 0)
		)
		(min_thickness 0.25)
		(keepout
			(tracks not_allowed)
			(vias allowed)
			(pads allowed)
			(copperpour not_allowed)
			(footprints allowed)
		)
		(placement
			(enabled no)
			(sheetname "")
		)
		(fill
			(thermal_gap 0.5)
			(thermal_bridge_width 0.5)
			(island_removal_mode 0)
		)
		(polygon
			(pts
				(arc
					(start 251.048012 -29.114242)
					(mid 251.505212 -29.571442)
					(end 251.962412 -29.114242)
				)
				(arc
					(start 251.962412 -28.250642)
					(mid 251.505212 -27.793442)
					(end 251.048012 -28.250642)
				)
			)
		)
	)
	(zone
		(layers "F.Cu" "B.Cu" "In1.Cu" "In2.Cu" "In3.Cu" "In4.Cu" "In5.Cu" "In6.Cu"
			"In7.Cu" "In8.Cu" "In9.Cu" "In10.Cu" "In11.Cu" "In12.Cu" "In13.Cu" "In14.Cu"
			"In15.Cu" "In16.Cu"
		)
		(hatch none 0.5)
		(connect_pads
			(clearance 0)
		)
		(min_thickness 0.25)
		(keepout
			(tracks not_allowed)
			(vias allowed)
			(pads allowed)
			(copperpour not_allowed)
			(footprints allowed)
		)
		(placement
			(enabled no)
			(sheetname "")
		)
		(fill
			(thermal_gap 0.5)
			(thermal_bridge_width 0.5)
			(island_removal_mode 0)
		)
		(polygon
			(pts
				(arc
					(start 174.621952 -354.351082)
					(mid 174.240952 -354.732082)
					(end 174.621952 -355.113082)
				)
				(arc
					(start 175.485552 -355.113082)
					(mid 175.866552 -354.732082)
					(end 175.485552 -354.351082)
				)
			)
		)
	)
	(zone
		(layers "F.Cu" "B.Cu" "In1.Cu" "In2.Cu" "In3.Cu" "In4.Cu" "In5.Cu" "In6.Cu"
			"In7.Cu" "In8.Cu" "In9.Cu" "In10.Cu" "In11.Cu" "In12.Cu" "In13.Cu" "In14.Cu"
			"In15.Cu" "In16.Cu"
		)
		(hatch none 0.5)
		(connect_pads
			(clearance 0)
		)
		(min_thickness 0.25)
		(keepout
			(tracks not_allowed)
			(vias allowed)
			(pads allowed)
			(copperpour not_allowed)
			(footprints allowed)
		)
		(placement
			(enabled no)
			(sheetname "")
		)
		(fill
			(thermal_gap 0.5)
			(thermal_bridge_width 0.5)
			(island_removal_mode 0)
		)
		(polygon
			(pts
				(arc
					(start 463.319876 -308.692296)
					(mid 462.557876 -308.692296)
					(end 463.319876 -308.692296)
				)
			)
		)
	)
	(zone
		(layers "F.Cu" "B.Cu" "In1.Cu" "In2.Cu" "In3.Cu" "In4.Cu" "In5.Cu" "In6.Cu"
			"In7.Cu" "In8.Cu" "In9.Cu" "In10.Cu" "In11.Cu" "In12.Cu" "In13.Cu" "In14.Cu"
			"In15.Cu" "In16.Cu"
		)
		(hatch none 0.5)
		(connect_pads
			(clearance 0)
		)
		(min_thickness 0.25)
		(keepout
			(tracks not_allowed)
			(vias allowed)
			(pads allowed)
			(copperpour not_allowed)
			(footprints allowed)
		)
		(placement
			(enabled no)
			(sheetname "")
		)
		(fill
			(thermal_gap 0.5)
			(thermal_bridge_width 0.5)
			(island_removal_mode 0)
		)
		(polygon
			(pts
				(arc
					(start 83.71713 -156.085794)
					(mid 84.17433 -156.542994)
					(end 84.63153 -156.085794)
				)
				(arc
					(start 84.63153 -155.222194)
					(mid 84.17433 -154.764994)
					(end 83.71713 -155.222194)
				)
			)
		)
	)
	(zone
		(layers "F.Cu" "B.Cu" "In1.Cu" "In2.Cu" "In3.Cu" "In4.Cu" "In5.Cu" "In6.Cu"
			"In7.Cu" "In8.Cu" "In9.Cu" "In10.Cu" "In11.Cu" "In12.Cu" "In13.Cu" "In14.Cu"
			"In15.Cu" "In16.Cu"
		)
		(hatch none 0.5)
		(connect_pads
			(clearance 0)
		)
		(min_thickness 0.25)
		(keepout
			(tracks not_allowed)
			(vias allowed)
			(pads allowed)
			(copperpour not_allowed)
			(footprints allowed)
		)
		(placement
			(enabled no)
			(sheetname "")
		)
		(fill
			(thermal_gap 0.5)
			(thermal_bridge_width 0.5)
			(island_removal_mode 0)
		)
		(polygon
			(pts
				(arc
					(start 393.187682 -137.633456)
					(mid 392.730482 -137.176256)
					(end 392.273282 -137.633456)
				)
				(arc
					(start 392.273282 -138.497056)
					(mid 392.730482 -138.954256)
					(end 393.187682 -138.497056)
				)
			)
		)
	)
	(zone
		(layers "F.Cu" "B.Cu" "In1.Cu" "In2.Cu" "In3.Cu" "In4.Cu" "In5.Cu" "In6.Cu"
			"In7.Cu" "In8.Cu" "In9.Cu" "In10.Cu" "In11.Cu" "In12.Cu" "In13.Cu" "In14.Cu"
			"In15.Cu" "In16.Cu"
		)
		(hatch none 0.5)
		(connect_pads
			(clearance 0)
		)
		(min_thickness 0.25)
		(keepout
			(tracks not_allowed)
			(vias allowed)
			(pads allowed)
			(copperpour not_allowed)
			(footprints allowed)
		)
		(placement
			(enabled no)
			(sheetname "")
		)
		(fill
			(thermal_gap 0.5)
			(thermal_bridge_width 0.5)
			(island_removal_mode 0)
		)
		(polygon
			(pts
				(arc
					(start 54.55412 -119.222774)
					(mid 54.09692 -118.765574)
					(end 53.63972 -119.222774)
				)
				(arc
					(start 53.63972 -120.086374)
					(mid 54.09692 -120.543574)
					(end 54.55412 -120.086374)
				)
			)
		)
	)
	(zone
		(layers "F.Cu" "B.Cu" "In1.Cu" "In2.Cu" "In3.Cu" "In4.Cu" "In5.Cu" "In6.Cu"
			"In7.Cu" "In8.Cu" "In9.Cu" "In10.Cu" "In11.Cu" "In12.Cu" "In13.Cu" "In14.Cu"
			"In15.Cu" "In16.Cu"
		)
		(hatch none 0.5)
		(connect_pads
			(clearance 0)
		)
		(min_thickness 0.25)
		(keepout
			(tracks not_allowed)
			(vias allowed)
			(pads allowed)
			(copperpour not_allowed)
			(footprints allowed)
		)
		(placement
			(enabled no)
			(sheetname "")
		)
		(fill
			(thermal_gap 0.5)
			(thermal_bridge_width 0.5)
			(island_removal_mode 0)
		)
		(polygon
			(pts
				(arc
					(start 137.590276 -34.520886)
					(mid 138.047476 -34.978086)
					(end 138.504676 -34.520886)
				)
				(arc
					(start 138.504676 -33.657286)
					(mid 138.047476 -33.200086)
					(end 137.590276 -33.657286)
				)
			)
		)
	)
	(zone
		(layers "F.Cu" "B.Cu" "In1.Cu" "In2.Cu" "In3.Cu" "In4.Cu" "In5.Cu" "In6.Cu"
			"In7.Cu" "In8.Cu" "In9.Cu" "In10.Cu" "In11.Cu" "In12.Cu" "In13.Cu" "In14.Cu"
			"In15.Cu" "In16.Cu"
		)
		(hatch none 0.5)
		(connect_pads
			(clearance 0)
		)
		(min_thickness 0.25)
		(keepout
			(tracks not_allowed)
			(vias allowed)
			(pads allowed)
			(copperpour not_allowed)
			(footprints allowed)
		)
		(placement
			(enabled no)
			(sheetname "")
		)
		(fill
			(thermal_gap 0.5)
			(thermal_bridge_width 0.5)
			(island_removal_mode 0)
		)
		(polygon
			(pts
				(arc
					(start 38.501066 -371.028722)
					(mid 38.515945 -370.992801)
					(end 38.551866 -370.977922)
				)
				(arc
					(start 39.268146 -370.977922)
					(mid 39.304067 -370.992801)
					(end 39.318946 -371.028722)
				)
				(arc
					(start 39.318946 -373.451374)
					(mid 39.304067 -373.487295)
					(end 39.268146 -373.502174)
				)
				(arc
					(start 38.551866 -373.502174)
					(mid 38.515945 -373.487295)
					(end 38.501066 -373.451374)
				)
			)
		)
	)
	(zone
		(layers "F.Cu" "B.Cu" "In1.Cu" "In2.Cu" "In3.Cu" "In4.Cu" "In5.Cu" "In6.Cu"
			"In7.Cu" "In8.Cu" "In9.Cu" "In10.Cu" "In11.Cu" "In12.Cu" "In13.Cu" "In14.Cu"
			"In15.Cu" "In16.Cu"
		)
		(hatch none 0.5)
		(connect_pads
			(clearance 0)
		)
		(min_thickness 0.25)
		(keepout
			(tracks not_allowed)
			(vias allowed)
			(pads allowed)
			(copperpour not_allowed)
			(footprints allowed)
		)
		(placement
			(enabled no)
			(sheetname "")
		)
		(fill
			(thermal_gap 0.5)
			(thermal_bridge_width 0.5)
			(island_removal_mode 0)
		)
		(polygon
			(pts
				(arc
					(start 22.441408 -357.37673)
					(mid 22.060408 -357.75773)
					(end 22.441408 -358.13873)
				)
				(arc
					(start 23.305008 -358.13873)
					(mid 23.686008 -357.75773)
					(end 23.305008 -357.37673)
				)
			)
		)
	)
	(zone
		(layers "F.Cu" "B.Cu" "In1.Cu" "In2.Cu" "In3.Cu" "In4.Cu" "In5.Cu" "In6.Cu"
			"In7.Cu" "In8.Cu" "In9.Cu" "In10.Cu" "In11.Cu" "In12.Cu" "In13.Cu" "In14.Cu"
			"In15.Cu" "In16.Cu"
		)
		(hatch none 0.5)
		(connect_pads
			(clearance 0)
		)
		(min_thickness 0.25)
		(keepout
			(tracks not_allowed)
			(vias allowed)
			(pads allowed)
			(copperpour not_allowed)
			(footprints allowed)
		)
		(placement
			(enabled no)
			(sheetname "")
		)
		(fill
			(thermal_gap 0.5)
			(thermal_bridge_width 0.5)
			(island_removal_mode 0)
		)
		(polygon
			(pts
				(arc
					(start 400.99996 -121.022872)
					(mid 400.54276 -120.565672)
					(end 400.08556 -121.022872)
				)
				(arc
					(start 400.08556 -121.886472)
					(mid 400.54276 -122.343672)
					(end 400.99996 -121.886472)
				)
			)
		)
	)
	(zone
		(layers "F.Cu" "B.Cu" "In1.Cu" "In2.Cu" "In3.Cu" "In4.Cu" "In5.Cu" "In6.Cu"
			"In7.Cu" "In8.Cu" "In9.Cu" "In10.Cu" "In11.Cu" "In12.Cu" "In13.Cu" "In14.Cu"
			"In15.Cu" "In16.Cu"
		)
		(hatch none 0.5)
		(connect_pads
			(clearance 0)
		)
		(min_thickness 0.25)
		(keepout
			(tracks not_allowed)
			(vias allowed)
			(pads allowed)
			(copperpour not_allowed)
			(footprints allowed)
		)
		(placement
			(enabled no)
			(sheetname "")
		)
		(fill
			(thermal_gap 0.5)
			(thermal_bridge_width 0.5)
			(island_removal_mode 0)
		)
		(polygon
			(pts
				(arc
					(start 339.88121 -403.728682)
					(mid 339.896089 -403.692761)
					(end 339.93201 -403.677882)
				)
				(arc
					(start 340.64829 -403.677882)
					(mid 340.684211 -403.692761)
					(end 340.69909 -403.728682)
				)
				(arc
					(start 340.69909 -406.151334)
					(mid 340.684211 -406.187255)
					(end 340.64829 -406.202134)
				)
				(arc
					(start 339.93201 -406.202134)
					(mid 339.896089 -406.187255)
					(end 339.88121 -406.151334)
				)
			)
		)
	)
	(zone
		(layers "F.Cu" "B.Cu" "In1.Cu" "In2.Cu" "In3.Cu" "In4.Cu" "In5.Cu" "In6.Cu"
			"In7.Cu" "In8.Cu" "In9.Cu" "In10.Cu" "In11.Cu" "In12.Cu" "In13.Cu" "In14.Cu"
			"In15.Cu" "In16.Cu"
		)
		(hatch none 0.5)
		(connect_pads
			(clearance 0)
		)
		(min_thickness 0.25)
		(keepout
			(tracks not_allowed)
			(vias allowed)
			(pads allowed)
			(copperpour not_allowed)
			(footprints allowed)
		)
		(placement
			(enabled no)
			(sheetname "")
		)
		(fill
			(thermal_gap 0.5)
			(thermal_bridge_width 0.5)
			(island_removal_mode 0)
		)
		(polygon
			(pts
				(arc
					(start 343.592404 -351.230438)
					(mid 343.211404 -351.611438)
					(end 343.592404 -351.992438)
				)
				(arc
					(start 344.456004 -351.992438)
					(mid 344.837004 -351.611438)
					(end 344.456004 -351.230438)
				)
			)
		)
	)
	(zone
		(layers "F.Cu" "B.Cu" "In1.Cu" "In2.Cu" "In3.Cu" "In4.Cu" "In5.Cu" "In6.Cu"
			"In7.Cu" "In8.Cu" "In9.Cu" "In10.Cu" "In11.Cu" "In12.Cu" "In13.Cu" "In14.Cu"
			"In15.Cu" "In16.Cu"
		)
		(hatch none 0.5)
		(connect_pads
			(clearance 0)
		)
		(min_thickness 0.25)
		(keepout
			(tracks not_allowed)
			(vias allowed)
			(pads allowed)
			(copperpour not_allowed)
			(footprints allowed)
		)
		(placement
			(enabled no)
			(sheetname "")
		)
		(fill
			(thermal_gap 0.5)
			(thermal_bridge_width 0.5)
			(island_removal_mode 0)
		)
		(polygon
			(pts
				(arc
					(start 328.047604 -345.084146)
					(mid 327.666604 -345.465146)
					(end 328.047604 -345.846146)
				)
				(arc
					(start 328.911204 -345.846146)
					(mid 329.292204 -345.465146)
					(end 328.911204 -345.084146)
				)
			)
		)
	)
	(zone
		(layers "F.Cu" "B.Cu" "In1.Cu" "In2.Cu" "In3.Cu" "In4.Cu" "In5.Cu" "In6.Cu"
			"In7.Cu" "In8.Cu" "In9.Cu" "In10.Cu" "In11.Cu" "In12.Cu" "In13.Cu" "In14.Cu"
			"In15.Cu" "In16.Cu"
		)
		(hatch none 0.5)
		(connect_pads
			(clearance 0)
		)
		(min_thickness 0.25)
		(keepout
			(tracks not_allowed)
			(vias allowed)
			(pads allowed)
			(copperpour not_allowed)
			(footprints allowed)
		)
		(placement
			(enabled no)
			(sheetname "")
		)
		(fill
			(thermal_gap 0.5)
			(thermal_bridge_width 0.5)
			(island_removal_mode 0)
		)
		(polygon
			(pts
				(arc
					(start 347.55709 -85.281008)
					(mid 347.09989 -84.823808)
					(end 346.64269 -85.281008)
				)
				(arc
					(start 346.64269 -86.144608)
					(mid 347.09989 -86.601808)
					(end 347.55709 -86.144608)
				)
			)
		)
	)
	(zone
		(layers "F.Cu" "B.Cu" "In1.Cu" "In2.Cu" "In3.Cu" "In4.Cu" "In5.Cu" "In6.Cu"
			"In7.Cu" "In8.Cu" "In9.Cu" "In10.Cu" "In11.Cu" "In12.Cu" "In13.Cu" "In14.Cu"
			"In15.Cu" "In16.Cu"
		)
		(hatch none 0.5)
		(connect_pads
			(clearance 0)
		)
		(min_thickness 0.25)
		(keepout
			(tracks not_allowed)
			(vias allowed)
			(pads allowed)
			(copperpour not_allowed)
			(footprints allowed)
		)
		(placement
			(enabled no)
			(sheetname "")
		)
		(fill
			(thermal_gap 0.5)
			(thermal_bridge_width 0.5)
			(island_removal_mode 0)
		)
		(polygon
			(pts
				(arc
					(start 445.147954 -29.114242)
					(mid 445.605154 -29.571442)
					(end 446.062354 -29.114242)
				)
				(arc
					(start 446.062354 -28.250642)
					(mid 445.605154 -27.793442)
					(end 445.147954 -28.250642)
				)
			)
		)
	)
	(zone
		(layers "F.Cu" "B.Cu" "In1.Cu" "In2.Cu" "In3.Cu" "In4.Cu" "In5.Cu" "In6.Cu"
			"In7.Cu" "In8.Cu" "In9.Cu" "In10.Cu" "In11.Cu" "In12.Cu" "In13.Cu" "In14.Cu"
			"In15.Cu" "In16.Cu"
		)
		(hatch none 0.5)
		(connect_pads
			(clearance 0)
		)
		(min_thickness 0.25)
		(keepout
			(tracks not_allowed)
			(vias allowed)
			(pads allowed)
			(copperpour not_allowed)
			(footprints allowed)
		)
		(placement
			(enabled no)
			(sheetname "")
		)
		(fill
			(thermal_gap 0.5)
			(thermal_bridge_width 0.5)
			(island_removal_mode 0)
		)
		(polygon
			(pts
				(arc
					(start 86.607396 -29.12237)
					(mid 87.064596 -29.57957)
					(end 87.521796 -29.12237)
				)
				(arc
					(start 87.521796 -28.25877)
					(mid 87.064596 -27.80157)
					(end 86.607396 -28.25877)
				)
			)
		)
	)
	(zone
		(layers "F.Cu" "B.Cu" "In1.Cu" "In2.Cu" "In3.Cu" "In4.Cu" "In5.Cu" "In6.Cu"
			"In7.Cu" "In8.Cu" "In9.Cu" "In10.Cu" "In11.Cu" "In12.Cu" "In13.Cu" "In14.Cu"
			"In15.Cu" "In16.Cu"
		)
		(hatch none 0.5)
		(connect_pads
			(clearance 0)
		)
		(min_thickness 0.25)
		(keepout
			(tracks not_allowed)
			(vias allowed)
			(pads allowed)
			(copperpour not_allowed)
			(footprints allowed)
		)
		(placement
			(enabled no)
			(sheetname "")
		)
		(fill
			(thermal_gap 0.5)
			(thermal_bridge_width 0.5)
			(island_removal_mode 0)
		)
		(polygon
			(pts
				(arc
					(start 377.280932 -400.92884)
					(mid 377.295811 -400.892919)
					(end 377.331732 -400.87804)
				)
				(arc
					(start 378.048012 -400.87804)
					(mid 378.083933 -400.892919)
					(end 378.098812 -400.92884)
				)
				(arc
					(start 378.098812 -403.351492)
					(mid 378.083933 -403.387413)
					(end 378.048012 -403.402292)
				)
				(arc
					(start 377.331732 -403.402292)
					(mid 377.295811 -403.387413)
					(end 377.280932 -403.351492)
				)
			)
		)
	)
	(zone
		(layers "F.Cu" "B.Cu" "In1.Cu" "In2.Cu" "In3.Cu" "In4.Cu" "In5.Cu" "In6.Cu"
			"In7.Cu" "In8.Cu" "In9.Cu" "In10.Cu" "In11.Cu" "In12.Cu" "In13.Cu" "In14.Cu"
			"In15.Cu" "In16.Cu"
		)
		(hatch none 0.5)
		(connect_pads
			(clearance 0)
		)
		(min_thickness 0.25)
		(keepout
			(tracks not_allowed)
			(vias allowed)
			(pads allowed)
			(copperpour not_allowed)
			(footprints allowed)
		)
		(placement
			(enabled no)
			(sheetname "")
		)
		(fill
			(thermal_gap 0.5)
			(thermal_bridge_width 0.5)
			(island_removal_mode 0)
		)
		(polygon
			(pts
				(arc
					(start 153.410666 -133.104382)
					(mid 153.867866 -133.561582)
					(end 154.325066 -133.104382)
				)
				(arc
					(start 154.325066 -132.240782)
					(mid 153.867866 -131.783582)
					(end 153.410666 -132.240782)
				)
			)
		)
	)
	(zone
		(layers "F.Cu" "B.Cu" "In1.Cu" "In2.Cu" "In3.Cu" "In4.Cu" "In5.Cu" "In6.Cu"
			"In7.Cu" "In8.Cu" "In9.Cu" "In10.Cu" "In11.Cu" "In12.Cu" "In13.Cu" "In14.Cu"
			"In15.Cu" "In16.Cu"
		)
		(hatch none 0.5)
		(connect_pads
			(clearance 0)
		)
		(min_thickness 0.25)
		(keepout
			(tracks not_allowed)
			(vias allowed)
			(pads allowed)
			(copperpour not_allowed)
			(footprints allowed)
		)
		(placement
			(enabled no)
			(sheetname "")
		)
		(fill
			(thermal_gap 0.5)
			(thermal_bridge_width 0.5)
			(island_removal_mode 0)
		)
		(polygon
			(pts
				(arc
					(start 336.864198 -77.663548)
					(mid 336.406998 -78.120748)
					(end 336.864198 -78.577948)
				)
				(arc
					(start 337.727798 -78.577948)
					(mid 338.184998 -78.120748)
					(end 337.727798 -77.663548)
				)
			)
		)
	)
	(zone
		(layers "F.Cu" "B.Cu" "In1.Cu" "In2.Cu" "In3.Cu" "In4.Cu" "In5.Cu" "In6.Cu"
			"In7.Cu" "In8.Cu" "In9.Cu" "In10.Cu" "In11.Cu" "In12.Cu" "In13.Cu" "In14.Cu"
			"In15.Cu" "In16.Cu"
		)
		(hatch none 0.5)
		(connect_pads
			(clearance 0)
		)
		(min_thickness 0.25)
		(keepout
			(tracks not_allowed)
			(vias allowed)
			(pads allowed)
			(copperpour not_allowed)
			(footprints allowed)
		)
		(placement
			(enabled no)
			(sheetname "")
		)
		(fill
			(thermal_gap 0.5)
			(thermal_bridge_width 0.5)
			(island_removal_mode 0)
		)
		(polygon
			(pts
				(arc
					(start 35.27806 -101.984302)
					(mid 35.73526 -102.441502)
					(end 36.19246 -101.984302)
				)
				(arc
					(start 36.19246 -101.120702)
					(mid 35.73526 -100.663502)
					(end 35.27806 -101.120702)
				)
			)
		)
	)
	(zone
		(layers "F.Cu" "B.Cu" "In1.Cu" "In2.Cu" "In3.Cu" "In4.Cu" "In5.Cu" "In6.Cu"
			"In7.Cu" "In8.Cu" "In9.Cu" "In10.Cu" "In11.Cu" "In12.Cu" "In13.Cu" "In14.Cu"
			"In15.Cu" "In16.Cu"
		)
		(hatch none 0.5)
		(connect_pads
			(clearance 0)
		)
		(min_thickness 0.25)
		(keepout
			(tracks not_allowed)
			(vias allowed)
			(pads allowed)
			(copperpour not_allowed)
			(footprints allowed)
		)
		(placement
			(enabled no)
			(sheetname "")
		)
		(fill
			(thermal_gap 0.5)
			(thermal_bridge_width 0.5)
			(island_removal_mode 0)
		)
		(polygon
			(pts
				(arc
					(start 122.101102 -374.928638)
					(mid 122.115981 -374.892717)
					(end 122.151902 -374.877838)
				)
				(arc
					(start 122.868182 -374.877838)
					(mid 122.904103 -374.892717)
					(end 122.918982 -374.928638)
				)
				(arc
					(start 122.918982 -377.35129)
					(mid 122.904103 -377.387211)
					(end 122.868182 -377.40209)
				)
				(arc
					(start 122.151902 -377.40209)
					(mid 122.115981 -377.387211)
					(end 122.101102 -377.35129)
				)
			)
		)
	)
	(zone
		(layers "F.Cu" "B.Cu" "In1.Cu" "In2.Cu" "In3.Cu" "In4.Cu" "In5.Cu" "In6.Cu"
			"In7.Cu" "In8.Cu" "In9.Cu" "In10.Cu" "In11.Cu" "In12.Cu" "In13.Cu" "In14.Cu"
			"In15.Cu" "In16.Cu"
		)
		(hatch none 0.5)
		(connect_pads
			(clearance 0)
		)
		(min_thickness 0.25)
		(keepout
			(tracks not_allowed)
			(vias allowed)
			(pads allowed)
			(copperpour not_allowed)
			(footprints allowed)
		)
		(placement
			(enabled no)
			(sheetname "")
		)
		(fill
			(thermal_gap 0.5)
			(thermal_bridge_width 0.5)
			(island_removal_mode 0)
		)
		(polygon
			(pts
				(arc
					(start 67.590162 -354.351082)
					(mid 67.209162 -354.732082)
					(end 67.590162 -355.113082)
				)
				(arc
					(start 68.453762 -355.113082)
					(mid 68.834762 -354.732082)
					(end 68.453762 -354.351082)
				)
			)
		)
	)
	(zone
		(layers "F.Cu" "B.Cu" "In1.Cu" "In2.Cu" "In3.Cu" "In4.Cu" "In5.Cu" "In6.Cu"
			"In7.Cu" "In8.Cu" "In9.Cu" "In10.Cu" "In11.Cu" "In12.Cu" "In13.Cu" "In14.Cu"
			"In15.Cu" "In16.Cu"
		)
		(hatch none 0.5)
		(connect_pads
			(clearance 0)
		)
		(min_thickness 0.25)
		(keepout
			(tracks not_allowed)
			(vias allowed)
			(pads allowed)
			(copperpour not_allowed)
			(footprints allowed)
		)
		(placement
			(enabled no)
			(sheetname "")
		)
		(fill
			(thermal_gap 0.5)
			(thermal_bridge_width 0.5)
			(island_removal_mode 0)
		)
		(polygon
			(pts
				(arc
					(start 423.480992 -407.628852)
					(mid 423.495871 -407.592931)
					(end 423.531792 -407.578052)
				)
				(arc
					(start 424.248072 -407.578052)
					(mid 424.283993 -407.592931)
					(end 424.298872 -407.628852)
				)
				(arc
					(start 424.298872 -410.051504)
					(mid 424.283993 -410.087425)
					(end 424.248072 -410.102304)
				)
				(arc
					(start 423.531792 -410.102304)
					(mid 423.495871 -410.087425)
					(end 423.480992 -410.051504)
				)
			)
		)
	)
	(zone
		(layers "F.Cu" "B.Cu" "In1.Cu" "In2.Cu" "In3.Cu" "In4.Cu" "In5.Cu" "In6.Cu"
			"In7.Cu" "In8.Cu" "In9.Cu" "In10.Cu" "In11.Cu" "In12.Cu" "In13.Cu" "In14.Cu"
			"In15.Cu" "In16.Cu"
		)
		(hatch none 0.5)
		(connect_pads
			(clearance 0)
		)
		(min_thickness 0.25)
		(keepout
			(tracks not_allowed)
			(vias allowed)
			(pads allowed)
			(copperpour not_allowed)
			(footprints allowed)
		)
		(placement
			(enabled no)
			(sheetname "")
		)
		(fill
			(thermal_gap 0.5)
			(thermal_bridge_width 0.5)
			(island_removal_mode 0)
		)
		(polygon
			(pts
				(arc
					(start 38.501066 -374.928638)
					(mid 38.515945 -374.892717)
					(end 38.551866 -374.877838)
				)
				(arc
					(start 39.268146 -374.877838)
					(mid 39.304067 -374.892717)
					(end 39.318946 -374.928638)
				)
				(arc
					(start 39.318946 -377.35129)
					(mid 39.304067 -377.387211)
					(end 39.268146 -377.40209)
				)
				(arc
					(start 38.551866 -377.40209)
					(mid 38.515945 -377.387211)
					(end 38.501066 -377.35129)
				)
			)
		)
	)
	(zone
		(layers "F.Cu" "B.Cu" "In1.Cu" "In2.Cu" "In3.Cu" "In4.Cu" "In5.Cu" "In6.Cu"
			"In7.Cu" "In8.Cu" "In9.Cu" "In10.Cu" "In11.Cu" "In12.Cu" "In13.Cu" "In14.Cu"
			"In15.Cu" "In16.Cu"
		)
		(hatch none 0.5)
		(connect_pads
			(clearance 0)
		)
		(min_thickness 0.25)
		(keepout
			(tracks not_allowed)
			(vias allowed)
			(pads allowed)
			(copperpour not_allowed)
			(footprints allowed)
		)
		(placement
			(enabled no)
			(sheetname "")
		)
		(fill
			(thermal_gap 0.5)
			(thermal_bridge_width 0.5)
			(island_removal_mode 0)
		)
		(polygon
			(pts
				(arc
					(start 37.310568 -100.177854)
					(mid 37.767768 -100.635054)
					(end 38.224968 -100.177854)
				)
				(arc
					(start 38.224968 -99.314254)
					(mid 37.767768 -98.857054)
					(end 37.310568 -99.314254)
				)
			)
		)
	)
	(zone
		(layers "F.Cu" "B.Cu" "In1.Cu" "In2.Cu" "In3.Cu" "In4.Cu" "In5.Cu" "In6.Cu"
			"In7.Cu" "In8.Cu" "In9.Cu" "In10.Cu" "In11.Cu" "In12.Cu" "In13.Cu" "In14.Cu"
			"In15.Cu" "In16.Cu"
		)
		(hatch none 0.5)
		(connect_pads
			(clearance 0)
		)
		(min_thickness 0.25)
		(keepout
			(tracks not_allowed)
			(vias allowed)
			(pads allowed)
			(copperpour not_allowed)
			(footprints allowed)
		)
		(placement
			(enabled no)
			(sheetname "")
		)
		(fill
			(thermal_gap 0.5)
			(thermal_bridge_width 0.5)
			(island_removal_mode 0)
		)
		(polygon
			(pts
				(arc
					(start 427.881034 -373.828818)
					(mid 427.895913 -373.792897)
					(end 427.931834 -373.778018)
				)
				(arc
					(start 428.648114 -373.778018)
					(mid 428.684035 -373.792897)
					(end 428.698914 -373.828818)
				)
				(arc
					(start 428.698914 -376.25147)
					(mid 428.684035 -376.287391)
					(end 428.648114 -376.30227)
				)
				(arc
					(start 427.931834 -376.30227)
					(mid 427.895913 -376.287391)
					(end 427.881034 -376.25147)
				)
			)
		)
	)
	(zone
		(layers "F.Cu" "B.Cu" "In1.Cu" "In2.Cu" "In3.Cu" "In4.Cu" "In5.Cu" "In6.Cu"
			"In7.Cu" "In8.Cu" "In9.Cu" "In10.Cu" "In11.Cu" "In12.Cu" "In13.Cu" "In14.Cu"
			"In15.Cu" "In16.Cu"
		)
		(hatch none 0.5)
		(connect_pads
			(clearance 0)
		)
		(min_thickness 0.25)
		(keepout
			(tracks not_allowed)
			(vias allowed)
			(pads allowed)
			(copperpour not_allowed)
			(footprints allowed)
		)
		(placement
			(enabled no)
			(sheetname "")
		)
		(fill
			(thermal_gap 0.5)
			(thermal_bridge_width 0.5)
			(island_removal_mode 0)
		)
		(polygon
			(pts
				(arc
					(start 344.280998 -407.628852)
					(mid 344.295877 -407.592931)
					(end 344.331798 -407.578052)
				)
				(arc
					(start 345.048078 -407.578052)
					(mid 345.083999 -407.592931)
					(end 345.098878 -407.628852)
				)
				(arc
					(start 345.098878 -410.051504)
					(mid 345.083999 -410.087425)
					(end 345.048078 -410.102304)
				)
				(arc
					(start 344.331798 -410.102304)
					(mid 344.295877 -410.087425)
					(end 344.280998 -410.051504)
				)
			)
		)
	)
	(zone
		(layers "F.Cu" "B.Cu" "In1.Cu" "In2.Cu" "In3.Cu" "In4.Cu" "In5.Cu" "In6.Cu"
			"In7.Cu" "In8.Cu" "In9.Cu" "In10.Cu" "In11.Cu" "In12.Cu" "In13.Cu" "In14.Cu"
			"In15.Cu" "In16.Cu"
		)
		(hatch none 0.5)
		(connect_pads
			(clearance 0)
		)
		(min_thickness 0.25)
		(keepout
			(tracks not_allowed)
			(vias allowed)
			(pads allowed)
			(copperpour not_allowed)
			(footprints allowed)
		)
		(placement
			(enabled no)
			(sheetname "")
		)
		(fill
			(thermal_gap 0.5)
			(thermal_bridge_width 0.5)
			(island_removal_mode 0)
		)
		(polygon
			(pts
				(arc
					(start 412.404052 -342.058498)
					(mid 412.023052 -342.439498)
					(end 412.404052 -342.820498)
				)
				(arc
					(start 413.267652 -342.820498)
					(mid 413.648652 -342.439498)
					(end 413.267652 -342.058498)
				)
			)
		)
	)
	(zone
		(layers "F.Cu" "B.Cu" "In1.Cu" "In2.Cu" "In3.Cu" "In4.Cu" "In5.Cu" "In6.Cu"
			"In7.Cu" "In8.Cu" "In9.Cu" "In10.Cu" "In11.Cu" "In12.Cu" "In13.Cu" "In14.Cu"
			"In15.Cu" "In16.Cu"
		)
		(hatch none 0.5)
		(connect_pads
			(clearance 0)
		)
		(min_thickness 0.25)
		(keepout
			(tracks not_allowed)
			(vias allowed)
			(pads allowed)
			(copperpour not_allowed)
			(footprints allowed)
		)
		(placement
			(enabled no)
			(sheetname "")
		)
		(fill
			(thermal_gap 0.5)
			(thermal_bridge_width 0.5)
			(island_removal_mode 0)
		)
		(polygon
			(pts
				(arc
					(start 386.081016 -404.828756)
					(mid 386.095895 -404.792835)
					(end 386.131816 -404.777956)
				)
				(arc
					(start 386.848096 -404.777956)
					(mid 386.884017 -404.792835)
					(end 386.898896 -404.828756)
				)
				(arc
					(start 386.898896 -407.251408)
					(mid 386.884017 -407.287329)
					(end 386.848096 -407.302208)
				)
				(arc
					(start 386.131816 -407.302208)
					(mid 386.095895 -407.287329)
					(end 386.081016 -407.251408)
				)
			)
		)
	)
	(zone
		(layers "F.Cu" "B.Cu" "In1.Cu" "In2.Cu" "In3.Cu" "In4.Cu" "In5.Cu" "In6.Cu"
			"In7.Cu" "In8.Cu" "In9.Cu" "In10.Cu" "In11.Cu" "In12.Cu" "In13.Cu" "In14.Cu"
			"In15.Cu" "In16.Cu"
		)
		(hatch none 0.5)
		(connect_pads
			(clearance 0)
		)
		(min_thickness 0.25)
		(keepout
			(tracks not_allowed)
			(vias allowed)
			(pads allowed)
			(copperpour not_allowed)
			(footprints allowed)
		)
		(placement
			(enabled no)
			(sheetname "")
		)
		(fill
			(thermal_gap 0.5)
			(thermal_bridge_width 0.5)
			(island_removal_mode 0)
		)
		(polygon
			(pts
				(arc
					(start 324.938644 -348.20479)
					(mid 324.557644 -348.58579)
					(end 324.938644 -348.96679)
				)
				(arc
					(start 325.802244 -348.96679)
					(mid 326.183244 -348.58579)
					(end 325.802244 -348.20479)
				)
			)
		)
	)
	(zone
		(layers "F.Cu" "B.Cu" "In1.Cu" "In2.Cu" "In3.Cu" "In4.Cu" "In5.Cu" "In6.Cu"
			"In7.Cu" "In8.Cu" "In9.Cu" "In10.Cu" "In11.Cu" "In12.Cu" "In13.Cu" "In14.Cu"
			"In15.Cu" "In16.Cu"
		)
		(hatch none 0.5)
		(connect_pads
			(clearance 0)
		)
		(min_thickness 0.25)
		(keepout
			(tracks not_allowed)
			(vias allowed)
			(pads allowed)
			(copperpour not_allowed)
			(footprints allowed)
		)
		(placement
			(enabled no)
			(sheetname "")
		)
		(fill
			(thermal_gap 0.5)
			(thermal_bridge_width 0.5)
			(island_removal_mode 0)
		)
		(polygon
			(pts
				(arc
					(start 447.790062 -34.520886)
					(mid 448.247262 -34.978086)
					(end 448.704462 -34.520886)
				)
				(arc
					(start 448.704462 -33.657286)
					(mid 448.247262 -33.200086)
					(end 447.790062 -33.657286)
				)
			)
		)
	)
	(zone
		(layers "F.Cu" "B.Cu" "In1.Cu" "In2.Cu" "In3.Cu" "In4.Cu" "In5.Cu" "In6.Cu"
			"In7.Cu" "In8.Cu" "In9.Cu" "In10.Cu" "In11.Cu" "In12.Cu" "In13.Cu" "In14.Cu"
			"In15.Cu" "In16.Cu"
		)
		(hatch none 0.5)
		(connect_pads
			(clearance 0)
		)
		(min_thickness 0.25)
		(keepout
			(tracks not_allowed)
			(vias allowed)
			(pads allowed)
			(copperpour not_allowed)
			(footprints allowed)
		)
		(placement
			(enabled no)
			(sheetname "")
		)
		(fill
			(thermal_gap 0.5)
			(thermal_bridge_width 0.5)
			(island_removal_mode 0)
		)
		(polygon
			(pts
				(arc
					(start 377.280932 -374.928638)
					(mid 377.295811 -374.892717)
					(end 377.331732 -374.877838)
				)
				(arc
					(start 378.048012 -374.877838)
					(mid 378.083933 -374.892717)
					(end 378.098812 -374.928638)
				)
				(arc
					(start 378.098812 -377.35129)
					(mid 378.083933 -377.387211)
					(end 378.048012 -377.40209)
				)
				(arc
					(start 377.331732 -377.40209)
					(mid 377.295811 -377.387211)
					(end 377.280932 -377.35129)
				)
			)
		)
	)
	(zone
		(layers "F.Cu" "B.Cu" "In1.Cu" "In2.Cu" "In3.Cu" "In4.Cu" "In5.Cu" "In6.Cu"
			"In7.Cu" "In8.Cu" "In9.Cu" "In10.Cu" "In11.Cu" "In12.Cu" "In13.Cu" "In14.Cu"
			"In15.Cu" "In16.Cu"
		)
		(hatch none 0.5)
		(connect_pads
			(clearance 0)
		)
		(min_thickness 0.25)
		(keepout
			(tracks not_allowed)
			(vias allowed)
			(pads allowed)
			(copperpour not_allowed)
			(footprints allowed)
		)
		(placement
			(enabled no)
			(sheetname "")
		)
		(fill
			(thermal_gap 0.5)
			(thermal_bridge_width 0.5)
			(island_removal_mode 0)
		)
		(polygon
			(pts
				(arc
					(start 165.295072 -357.37673)
					(mid 164.914072 -357.75773)
					(end 165.295072 -358.13873)
				)
				(arc
					(start 166.158672 -358.13873)
					(mid 166.539672 -357.75773)
					(end 166.158672 -357.37673)
				)
			)
		)
	)
	(zone
		(layers "F.Cu" "B.Cu" "In1.Cu" "In2.Cu" "In3.Cu" "In4.Cu" "In5.Cu" "In6.Cu"
			"In7.Cu" "In8.Cu" "In9.Cu" "In10.Cu" "In11.Cu" "In12.Cu" "In13.Cu" "In14.Cu"
			"In15.Cu" "In16.Cu"
		)
		(hatch none 0.5)
		(connect_pads
			(clearance 0)
		)
		(min_thickness 0.25)
		(keepout
			(tracks not_allowed)
			(vias allowed)
			(pads allowed)
			(copperpour not_allowed)
			(footprints allowed)
		)
		(placement
			(enabled no)
			(sheetname "")
		)
		(fill
			(thermal_gap 0.5)
			(thermal_bridge_width 0.5)
			(island_removal_mode 0)
		)
		(polygon
			(pts
				(arc
					(start 210.624166 -27.342846)
					(mid 211.081366 -27.800046)
					(end 211.538566 -27.342846)
				)
				(arc
					(start 211.538566 -26.479246)
					(mid 211.081366 -26.022046)
					(end 210.624166 -26.479246)
				)
			)
		)
	)
	(zone
		(layers "F.Cu" "B.Cu" "In1.Cu" "In2.Cu" "In3.Cu" "In4.Cu" "In5.Cu" "In6.Cu"
			"In7.Cu" "In8.Cu" "In9.Cu" "In10.Cu" "In11.Cu" "In12.Cu" "In13.Cu" "In14.Cu"
			"In15.Cu" "In16.Cu"
		)
		(hatch none 0.5)
		(connect_pads
			(clearance 0)
		)
		(min_thickness 0.25)
		(keepout
			(tracks not_allowed)
			(vias allowed)
			(pads allowed)
			(copperpour not_allowed)
			(footprints allowed)
		)
		(placement
			(enabled no)
			(sheetname "")
		)
		(fill
			(thermal_gap 0.5)
			(thermal_bridge_width 0.5)
			(island_removal_mode 0)
		)
		(polygon
			(pts
				(arc
					(start 269.52448 -299.555154)
					(mid 269.85468 -299.224954)
					(end 269.52448 -298.894754)
				)
				(arc
					(start 268.57452 -298.894754)
					(mid 268.24432 -299.224954)
					(end 268.57452 -299.555154)
				)
			)
		)
	)
	(zone
		(layers "F.Cu" "B.Cu" "In1.Cu" "In2.Cu" "In3.Cu" "In4.Cu" "In5.Cu" "In6.Cu"
			"In7.Cu" "In8.Cu" "In9.Cu" "In10.Cu" "In11.Cu" "In12.Cu" "In13.Cu" "In14.Cu"
			"In15.Cu" "In16.Cu"
		)
		(hatch none 0.5)
		(connect_pads
			(clearance 0)
		)
		(min_thickness 0.25)
		(keepout
			(tracks not_allowed)
			(vias allowed)
			(pads allowed)
			(copperpour not_allowed)
			(footprints allowed)
		)
		(placement
			(enabled no)
			(sheetname "")
		)
		(fill
			(thermal_gap 0.5)
			(thermal_bridge_width 0.5)
			(island_removal_mode 0)
		)
		(polygon
			(pts
				(arc
					(start 75.901042 -395.92885)
					(mid 75.915921 -395.892929)
					(end 75.951842 -395.87805)
				)
				(arc
					(start 76.668122 -395.87805)
					(mid 76.704043 -395.892929)
					(end 76.718922 -395.92885)
				)
				(arc
					(start 76.718922 -398.351502)
					(mid 76.704043 -398.387423)
					(end 76.668122 -398.402302)
				)
				(arc
					(start 75.951842 -398.402302)
					(mid 75.915921 -398.387423)
					(end 75.901042 -398.351502)
				)
			)
		)
	)
	(zone
		(layers "F.Cu" "B.Cu" "In1.Cu" "In2.Cu" "In3.Cu" "In4.Cu" "In5.Cu" "In6.Cu"
			"In7.Cu" "In8.Cu" "In9.Cu" "In10.Cu" "In11.Cu" "In12.Cu" "In13.Cu" "In14.Cu"
			"In15.Cu" "In16.Cu"
		)
		(hatch none 0.5)
		(connect_pads
			(clearance 0)
		)
		(min_thickness 0.25)
		(keepout
			(tracks not_allowed)
			(vias allowed)
			(pads allowed)
			(copperpour not_allowed)
			(footprints allowed)
		)
		(placement
			(enabled no)
			(sheetname "")
		)
		(fill
			(thermal_gap 0.5)
			(thermal_bridge_width 0.5)
			(island_removal_mode 0)
		)
		(polygon
			(pts
				(arc
					(start 29.700982 -371.028722)
					(mid 29.715861 -370.992801)
					(end 29.751782 -370.977922)
				)
				(arc
					(start 30.468062 -370.977922)
					(mid 30.503983 -370.992801)
					(end 30.518862 -371.028722)
				)
				(arc
					(start 30.518862 -373.451374)
					(mid 30.503983 -373.487295)
					(end 30.468062 -373.502174)
				)
				(arc
					(start 29.751782 -373.502174)
					(mid 29.715861 -373.487295)
					(end 29.700982 -373.451374)
				)
			)
		)
	)
	(zone
		(layers "F.Cu" "B.Cu" "In1.Cu" "In2.Cu" "In3.Cu" "In4.Cu" "In5.Cu" "In6.Cu"
			"In7.Cu" "In8.Cu" "In9.Cu" "In10.Cu" "In11.Cu" "In12.Cu" "In13.Cu" "In14.Cu"
			"In15.Cu" "In16.Cu"
		)
		(hatch none 0.5)
		(connect_pads
			(clearance 0)
		)
		(min_thickness 0.25)
		(keepout
			(tracks not_allowed)
			(vias allowed)
			(pads allowed)
			(copperpour not_allowed)
			(footprints allowed)
		)
		(placement
			(enabled no)
			(sheetname "")
		)
		(fill
			(thermal_gap 0.5)
			(thermal_bridge_width 0.5)
			(island_removal_mode 0)
		)
		(polygon
			(pts
				(arc
					(start 383.62382 -348.20479)
					(mid 383.24282 -348.58579)
					(end 383.62382 -348.96679)
				)
				(arc
					(start 384.48742 -348.96679)
					(mid 384.86842 -348.58579)
					(end 384.48742 -348.20479)
				)
			)
		)
	)
	(zone
		(layers "F.Cu" "B.Cu" "In1.Cu" "In2.Cu" "In3.Cu" "In4.Cu" "In5.Cu" "In6.Cu"
			"In7.Cu" "In8.Cu" "In9.Cu" "In10.Cu" "In11.Cu" "In12.Cu" "In13.Cu" "In14.Cu"
			"In15.Cu" "In16.Cu"
		)
		(hatch none 0.5)
		(connect_pads
			(clearance 0)
		)
		(min_thickness 0.25)
		(keepout
			(tracks not_allowed)
			(vias allowed)
			(pads allowed)
			(copperpour not_allowed)
			(footprints allowed)
		)
		(placement
			(enabled no)
			(sheetname "")
		)
		(fill
			(thermal_gap 0.5)
			(thermal_bridge_width 0.5)
			(island_removal_mode 0)
		)
		(polygon
			(pts
				(arc
					(start 232.698798 -307.484272)
					(mid 231.936798 -307.484272)
					(end 232.698798 -307.484272)
				)
			)
		)
	)
	(zone
		(layers "F.Cu" "B.Cu" "In1.Cu" "In2.Cu" "In3.Cu" "In4.Cu" "In5.Cu" "In6.Cu"
			"In7.Cu" "In8.Cu" "In9.Cu" "In10.Cu" "In11.Cu" "In12.Cu" "In13.Cu" "In14.Cu"
			"In15.Cu" "In16.Cu"
		)
		(hatch none 0.5)
		(connect_pads
			(clearance 0)
		)
		(min_thickness 0.25)
		(keepout
			(tracks not_allowed)
			(vias allowed)
			(pads allowed)
			(copperpour not_allowed)
			(footprints allowed)
		)
		(placement
			(enabled no)
			(sheetname "")
		)
		(fill
			(thermal_gap 0.5)
			(thermal_bridge_width 0.5)
			(island_removal_mode 0)
		)
		(polygon
			(pts
				(arc
					(start 8.607552 -32.722312)
					(mid 9.064752 -33.179512)
					(end 9.521952 -32.722312)
				)
				(arc
					(start 9.521952 -31.858712)
					(mid 9.064752 -31.401512)
					(end 8.607552 -31.858712)
				)
			)
		)
	)
	(zone
		(layers "F.Cu" "B.Cu" "In1.Cu" "In2.Cu" "In3.Cu" "In4.Cu" "In5.Cu" "In6.Cu"
			"In7.Cu" "In8.Cu" "In9.Cu" "In10.Cu" "In11.Cu" "In12.Cu" "In13.Cu" "In14.Cu"
			"In15.Cu" "In16.Cu"
		)
		(hatch none 0.5)
		(connect_pads
			(clearance 0)
		)
		(min_thickness 0.25)
		(keepout
			(tracks not_allowed)
			(vias allowed)
			(pads allowed)
			(copperpour not_allowed)
			(footprints allowed)
		)
		(placement
			(enabled no)
			(sheetname "")
		)
		(fill
			(thermal_gap 0.5)
			(thermal_bridge_width 0.5)
			(island_removal_mode 0)
		)
		(polygon
			(pts
				(arc
					(start 346.481146 -371.028722)
					(mid 346.496025 -370.992801)
					(end 346.531946 -370.977922)
				)
				(arc
					(start 347.248226 -370.977922)
					(mid 347.284147 -370.992801)
					(end 347.299026 -371.028722)
				)
				(arc
					(start 347.299026 -373.451374)
					(mid 347.284147 -373.487295)
					(end 347.248226 -373.502174)
				)
				(arc
					(start 346.531946 -373.502174)
					(mid 346.496025 -373.487295)
					(end 346.481146 -373.451374)
				)
			)
		)
	)
	(zone
		(layers "F.Cu" "B.Cu" "In1.Cu" "In2.Cu" "In3.Cu" "In4.Cu" "In5.Cu" "In6.Cu"
			"In7.Cu" "In8.Cu" "In9.Cu" "In10.Cu" "In11.Cu" "In12.Cu" "In13.Cu" "In14.Cu"
			"In15.Cu" "In16.Cu"
		)
		(hatch none 0.5)
		(connect_pads
			(clearance 0)
		)
		(min_thickness 0.25)
		(keepout
			(tracks not_allowed)
			(vias allowed)
			(pads allowed)
			(copperpour not_allowed)
			(footprints allowed)
		)
		(placement
			(enabled no)
			(sheetname "")
		)
		(fill
			(thermal_gap 0.5)
			(thermal_bridge_width 0.5)
			(island_removal_mode 0)
		)
		(polygon
			(pts
				(arc
					(start 331.689964 -34.520886)
					(mid 332.147164 -34.978086)
					(end 332.604364 -34.520886)
				)
				(arc
					(start 332.604364 -33.657286)
					(mid 332.147164 -33.200086)
					(end 331.689964 -33.657286)
				)
			)
		)
	)
	(zone
		(layers "F.Cu" "B.Cu" "In1.Cu" "In2.Cu" "In3.Cu" "In4.Cu" "In5.Cu" "In6.Cu"
			"In7.Cu" "In8.Cu" "In9.Cu" "In10.Cu" "In11.Cu" "In12.Cu" "In13.Cu" "In14.Cu"
			"In15.Cu" "In16.Cu"
		)
		(hatch none 0.5)
		(connect_pads
			(clearance 0)
		)
		(min_thickness 0.25)
		(keepout
			(tracks not_allowed)
			(vias allowed)
			(pads allowed)
			(copperpour not_allowed)
			(footprints allowed)
		)
		(placement
			(enabled no)
			(sheetname "")
		)
		(fill
			(thermal_gap 0.5)
			(thermal_bridge_width 0.5)
			(island_removal_mode 0)
		)
		(polygon
			(pts
				(arc
					(start 289.659822 -342.058498)
					(mid 289.278822 -342.439498)
					(end 289.659822 -342.820498)
				)
				(arc
					(start 290.523422 -342.820498)
					(mid 290.904422 -342.439498)
					(end 290.523422 -342.058498)
				)
			)
		)
	)
	(zone
		(layers "F.Cu" "B.Cu" "In1.Cu" "In2.Cu" "In3.Cu" "In4.Cu" "In5.Cu" "In6.Cu"
			"In7.Cu" "In8.Cu" "In9.Cu" "In10.Cu" "In11.Cu" "In12.Cu" "In13.Cu" "In14.Cu"
			"In15.Cu" "In16.Cu"
		)
		(hatch none 0.5)
		(connect_pads
			(clearance 0)
		)
		(min_thickness 0.25)
		(keepout
			(tracks not_allowed)
			(vias allowed)
			(pads allowed)
			(copperpour not_allowed)
			(footprints allowed)
		)
		(placement
			(enabled no)
			(sheetname "")
		)
		(fill
			(thermal_gap 0.5)
			(thermal_bridge_width 0.5)
			(island_removal_mode 0)
		)
		(polygon
			(pts
				(arc
					(start 382.9685 -123.68784)
					(mid 383.4257 -124.14504)
					(end 383.8829 -123.68784)
				)
				(arc
					(start 383.8829 -122.82424)
					(mid 383.4257 -122.36704)
					(end 382.9685 -122.82424)
				)
			)
		)
	)
	(zone
		(layers "F.Cu" "B.Cu" "In1.Cu" "In2.Cu" "In3.Cu" "In4.Cu" "In5.Cu" "In6.Cu"
			"In7.Cu" "In8.Cu" "In9.Cu" "In10.Cu" "In11.Cu" "In12.Cu" "In13.Cu" "In14.Cu"
			"In15.Cu" "In16.Cu"
		)
		(hatch none 0.5)
		(connect_pads
			(clearance 0)
		)
		(min_thickness 0.25)
		(keepout
			(tracks not_allowed)
			(vias allowed)
			(pads allowed)
			(copperpour not_allowed)
			(footprints allowed)
		)
		(placement
			(enabled no)
			(sheetname "")
		)
		(fill
			(thermal_gap 0.5)
			(thermal_bridge_width 0.5)
			(island_removal_mode 0)
		)
		(polygon
			(pts
				(arc
					(start 64.481202 -345.084146)
					(mid 64.100202 -345.465146)
					(end 64.481202 -345.846146)
				)
				(arc
					(start 65.344802 -345.846146)
					(mid 65.725802 -345.465146)
					(end 65.344802 -345.084146)
				)
			)
		)
	)
	(zone
		(layers "F.Cu" "B.Cu" "In1.Cu" "In2.Cu" "In3.Cu" "In4.Cu" "In5.Cu" "In6.Cu"
			"In7.Cu" "In8.Cu" "In9.Cu" "In10.Cu" "In11.Cu" "In12.Cu" "In13.Cu" "In14.Cu"
			"In15.Cu" "In16.Cu"
		)
		(hatch none 0.5)
		(connect_pads
			(clearance 0)
		)
		(min_thickness 0.25)
		(keepout
			(tracks not_allowed)
			(vias allowed)
			(pads allowed)
			(copperpour not_allowed)
			(footprints allowed)
		)
		(placement
			(enabled no)
			(sheetname "")
		)
		(fill
			(thermal_gap 0.5)
			(thermal_bridge_width 0.5)
			(island_removal_mode 0)
		)
		(polygon
			(pts
				(arc
					(start 161.700972 -404.828756)
					(mid 161.715851 -404.792835)
					(end 161.751772 -404.777956)
				)
				(arc
					(start 162.468052 -404.777956)
					(mid 162.503973 -404.792835)
					(end 162.518852 -404.828756)
				)
				(arc
					(start 162.518852 -407.251408)
					(mid 162.503973 -407.287329)
					(end 162.468052 -407.302208)
				)
				(arc
					(start 161.751772 -407.302208)
					(mid 161.715851 -407.287329)
					(end 161.700972 -407.251408)
				)
			)
		)
	)
	(zone
		(layers "F.Cu" "B.Cu" "In1.Cu" "In2.Cu" "In3.Cu" "In4.Cu" "In5.Cu" "In6.Cu"
			"In7.Cu" "In8.Cu" "In9.Cu" "In10.Cu" "In11.Cu" "In12.Cu" "In13.Cu" "In14.Cu"
			"In15.Cu" "In16.Cu"
		)
		(hatch none 0.5)
		(connect_pads
			(clearance 0)
		)
		(min_thickness 0.25)
		(keepout
			(tracks not_allowed)
			(vias allowed)
			(pads allowed)
			(copperpour not_allowed)
			(footprints allowed)
		)
		(placement
			(enabled no)
			(sheetname "")
		)
		(fill
			(thermal_gap 0.5)
			(thermal_bridge_width 0.5)
			(island_removal_mode 0)
		)
		(polygon
			(pts
				(arc
					(start 392.9507 -357.37673)
					(mid 392.5697 -357.75773)
					(end 392.9507 -358.13873)
				)
				(arc
					(start 393.8143 -358.13873)
					(mid 394.1953 -357.75773)
					(end 393.8143 -357.37673)
				)
			)
		)
	)
	(zone
		(layers "F.Cu" "B.Cu" "In1.Cu" "In2.Cu" "In3.Cu" "In4.Cu" "In5.Cu" "In6.Cu"
			"In7.Cu" "In8.Cu" "In9.Cu" "In10.Cu" "In11.Cu" "In12.Cu" "In13.Cu" "In14.Cu"
			"In15.Cu" "In16.Cu"
		)
		(hatch none 0.5)
		(connect_pads
			(clearance 0)
		)
		(min_thickness 0.25)
		(keepout
			(tracks not_allowed)
			(vias allowed)
			(pads allowed)
			(copperpour not_allowed)
			(footprints allowed)
		)
		(placement
			(enabled no)
			(sheetname "")
		)
		(fill
			(thermal_gap 0.5)
			(thermal_bridge_width 0.5)
			(island_removal_mode 0)
		)
		(polygon
			(pts
				(arc
					(start 73.808082 -357.37673)
					(mid 73.427082 -357.75773)
					(end 73.808082 -358.13873)
				)
				(arc
					(start 74.671682 -358.13873)
					(mid 75.052682 -357.75773)
					(end 74.671682 -357.37673)
				)
			)
		)
	)
	(zone
		(layers "F.Cu" "B.Cu" "In1.Cu" "In2.Cu" "In3.Cu" "In4.Cu" "In5.Cu" "In6.Cu"
			"In7.Cu" "In8.Cu" "In9.Cu" "In10.Cu" "In11.Cu" "In12.Cu" "In13.Cu" "In14.Cu"
			"In15.Cu" "In16.Cu"
		)
		(hatch none 0.5)
		(connect_pads
			(clearance 0)
		)
		(min_thickness 0.25)
		(keepout
			(tracks not_allowed)
			(vias allowed)
			(pads allowed)
			(copperpour not_allowed)
			(footprints allowed)
		)
		(placement
			(enabled no)
			(sheetname "")
		)
		(fill
			(thermal_gap 0.5)
			(thermal_bridge_width 0.5)
			(island_removal_mode 0)
		)
		(polygon
			(pts
				(arc
					(start 170.501056 -400.92884)
					(mid 170.515935 -400.892919)
					(end 170.551856 -400.87804)
				)
				(arc
					(start 171.268136 -400.87804)
					(mid 171.304057 -400.892919)
					(end 171.318936 -400.92884)
				)
				(arc
					(start 171.318936 -403.351492)
					(mid 171.304057 -403.387413)
					(end 171.268136 -403.402292)
				)
				(arc
					(start 170.551856 -403.402292)
					(mid 170.515935 -403.387413)
					(end 170.501056 -403.351492)
				)
			)
		)
	)
	(zone
		(layers "F.Cu" "B.Cu" "In1.Cu" "In2.Cu" "In3.Cu" "In4.Cu" "In5.Cu" "In6.Cu"
			"In7.Cu" "In8.Cu" "In9.Cu" "In10.Cu" "In11.Cu" "In12.Cu" "In13.Cu" "In14.Cu"
			"In15.Cu" "In16.Cu"
		)
		(hatch none 0.5)
		(connect_pads
			(clearance 0)
		)
		(min_thickness 0.25)
		(keepout
			(tracks not_allowed)
			(vias allowed)
			(pads allowed)
			(copperpour not_allowed)
			(footprints allowed)
		)
		(placement
			(enabled no)
			(sheetname "")
		)
		(fill
			(thermal_gap 0.5)
			(thermal_bridge_width 0.5)
			(island_removal_mode 0)
		)
		(polygon
			(pts
				(arc
					(start 133.624828 -351.230438)
					(mid 133.243828 -351.611438)
					(end 133.624828 -351.992438)
				)
				(arc
					(start 134.488428 -351.992438)
					(mid 134.869428 -351.611438)
					(end 134.488428 -351.230438)
				)
			)
		)
	)
	(zone
		(layers "F.Cu" "B.Cu" "In1.Cu" "In2.Cu" "In3.Cu" "In4.Cu" "In5.Cu" "In6.Cu"
			"In7.Cu" "In8.Cu" "In9.Cu" "In10.Cu" "In11.Cu" "In12.Cu" "In13.Cu" "In14.Cu"
			"In15.Cu" "In16.Cu"
		)
		(hatch none 0.5)
		(connect_pads
			(clearance 0)
		)
		(min_thickness 0.25)
		(keepout
			(tracks not_allowed)
			(vias allowed)
			(pads allowed)
			(copperpour not_allowed)
			(footprints allowed)
		)
		(placement
			(enabled no)
			(sheetname "")
		)
		(fill
			(thermal_gap 0.5)
			(thermal_bridge_width 0.5)
			(island_removal_mode 0)
		)
		(polygon
			(pts
				(arc
					(start 331.689964 -30.92069)
					(mid 332.147164 -31.37789)
					(end 332.604364 -30.92069)
				)
				(arc
					(start 332.604364 -30.05709)
					(mid 332.147164 -29.59989)
					(end 331.689964 -30.05709)
				)
			)
		)
	)
	(zone
		(layers "F.Cu" "B.Cu" "In1.Cu" "In2.Cu" "In3.Cu" "In4.Cu" "In5.Cu" "In6.Cu"
			"In7.Cu" "In8.Cu" "In9.Cu" "In10.Cu" "In11.Cu" "In12.Cu" "In13.Cu" "In14.Cu"
			"In15.Cu" "In16.Cu"
		)
		(hatch none 0.5)
		(connect_pads
			(clearance 0)
		)
		(min_thickness 0.25)
		(keepout
			(tracks not_allowed)
			(vias allowed)
			(pads allowed)
			(copperpour not_allowed)
			(footprints allowed)
		)
		(placement
			(enabled no)
			(sheetname "")
		)
		(fill
			(thermal_gap 0.5)
			(thermal_bridge_width 0.5)
			(island_removal_mode 0)
		)
		(polygon
			(pts
				(arc
					(start 126.501144 -408.728672)
					(mid 126.516023 -408.692751)
					(end 126.551944 -408.677872)
				)
				(arc
					(start 127.268224 -408.677872)
					(mid 127.304145 -408.692751)
					(end 127.319024 -408.728672)
				)
				(arc
					(start 127.319024 -411.151324)
					(mid 127.304145 -411.187245)
					(end 127.268224 -411.202124)
				)
				(arc
					(start 126.551944 -411.202124)
					(mid 126.516023 -411.187245)
					(end 126.501144 -411.151324)
				)
			)
		)
	)
	(zone
		(layers "F.Cu" "B.Cu" "In1.Cu" "In2.Cu" "In3.Cu" "In4.Cu" "In5.Cu" "In6.Cu"
			"In7.Cu" "In8.Cu" "In9.Cu" "In10.Cu" "In11.Cu" "In12.Cu" "In13.Cu" "In14.Cu"
			"In15.Cu" "In16.Cu"
		)
		(hatch none 0.5)
		(connect_pads
			(clearance 0)
		)
		(min_thickness 0.25)
		(keepout
			(tracks not_allowed)
			(vias allowed)
			(pads allowed)
			(copperpour not_allowed)
			(footprints allowed)
		)
		(placement
			(enabled no)
			(sheetname "")
		)
		(fill
			(thermal_gap 0.5)
			(thermal_bridge_width 0.5)
			(island_removal_mode 0)
		)
		(polygon
			(pts
				(arc
					(start 404.034498 17.603724)
					(mid 404.415498 17.222724)
					(end 404.796498 17.603724)
				)
				(arc
					(start 404.796498 18.467324)
					(mid 404.415498 18.848324)
					(end 404.034498 18.467324)
				)
			)
		)
	)
	(zone
		(layers "F.Cu" "B.Cu" "In1.Cu" "In2.Cu" "In3.Cu" "In4.Cu" "In5.Cu" "In6.Cu"
			"In7.Cu" "In8.Cu" "In9.Cu" "In10.Cu" "In11.Cu" "In12.Cu" "In13.Cu" "In14.Cu"
			"In15.Cu" "In16.Cu"
		)
		(hatch none 0.5)
		(connect_pads
			(clearance 0)
		)
		(min_thickness 0.25)
		(keepout
			(tracks not_allowed)
			(vias allowed)
			(pads allowed)
			(copperpour not_allowed)
			(footprints allowed)
		)
		(placement
			(enabled no)
			(sheetname "")
		)
		(fill
			(thermal_gap 0.5)
			(thermal_bridge_width 0.5)
			(island_removal_mode 0)
		)
		(polygon
			(pts
				(arc
					(start 189.590172 -30.92069)
					(mid 190.047372 -31.37789)
					(end 190.504572 -30.92069)
				)
				(arc
					(start 190.504572 -30.05709)
					(mid 190.047372 -29.59989)
					(end 189.590172 -30.05709)
				)
			)
		)
	)
	(zone
		(layers "F.Cu" "B.Cu" "In1.Cu" "In2.Cu" "In3.Cu" "In4.Cu" "In5.Cu" "In6.Cu"
			"In7.Cu" "In8.Cu" "In9.Cu" "In10.Cu" "In11.Cu" "In12.Cu" "In13.Cu" "In14.Cu"
			"In15.Cu" "In16.Cu"
		)
		(hatch none 0.5)
		(connect_pads
			(clearance 0)
		)
		(min_thickness 0.25)
		(keepout
			(tracks not_allowed)
			(vias allowed)
			(pads allowed)
			(copperpour not_allowed)
			(footprints allowed)
		)
		(placement
			(enabled no)
			(sheetname "")
		)
		(fill
			(thermal_gap 0.5)
			(thermal_bridge_width 0.5)
			(island_removal_mode 0)
		)
		(polygon
			(pts
				(arc
					(start 388.28091 -407.628852)
					(mid 388.295789 -407.592931)
					(end 388.33171 -407.578052)
				)
				(arc
					(start 389.04799 -407.578052)
					(mid 389.083911 -407.592931)
					(end 389.09879 -407.628852)
				)
				(arc
					(start 389.09879 -410.051504)
					(mid 389.083911 -410.087425)
					(end 389.04799 -410.102304)
				)
				(arc
					(start 388.33171 -410.102304)
					(mid 388.295789 -410.087425)
					(end 388.28091 -410.051504)
				)
			)
		)
	)
	(zone
		(layers "F.Cu" "B.Cu" "In1.Cu" "In2.Cu" "In3.Cu" "In4.Cu" "In5.Cu" "In6.Cu"
			"In7.Cu" "In8.Cu" "In9.Cu" "In10.Cu" "In11.Cu" "In12.Cu" "In13.Cu" "In14.Cu"
			"In15.Cu" "In16.Cu"
		)
		(hatch none 0.5)
		(connect_pads
			(clearance 0)
		)
		(min_thickness 0.25)
		(keepout
			(tracks not_allowed)
			(vias allowed)
			(pads allowed)
			(copperpour not_allowed)
			(footprints allowed)
		)
		(placement
			(enabled no)
			(sheetname "")
		)
		(fill
			(thermal_gap 0.5)
			(thermal_bridge_width 0.5)
			(island_removal_mode 0)
		)
		(polygon
			(pts
				(arc
					(start 427.881034 -377.728734)
					(mid 427.895913 -377.692813)
					(end 427.931834 -377.677934)
				)
				(arc
					(start 428.648114 -377.677934)
					(mid 428.684035 -377.692813)
					(end 428.698914 -377.728734)
				)
				(arc
					(start 428.698914 -380.151386)
					(mid 428.684035 -380.187307)
					(end 428.648114 -380.202186)
				)
				(arc
					(start 427.931834 -380.202186)
					(mid 427.895913 -380.187307)
					(end 427.881034 -380.151386)
				)
			)
		)
	)
	(zone
		(layers "F.Cu" "B.Cu" "In1.Cu" "In2.Cu" "In3.Cu" "In4.Cu" "In5.Cu" "In6.Cu"
			"In7.Cu" "In8.Cu" "In9.Cu" "In10.Cu" "In11.Cu" "In12.Cu" "In13.Cu" "In14.Cu"
			"In15.Cu" "In16.Cu"
		)
		(hatch none 0.5)
		(connect_pads
			(clearance 0)
		)
		(min_thickness 0.25)
		(keepout
			(tracks not_allowed)
			(vias allowed)
			(pads allowed)
			(copperpour not_allowed)
			(footprints allowed)
		)
		(placement
			(enabled no)
			(sheetname "")
		)
		(fill
			(thermal_gap 0.5)
			(thermal_bridge_width 0.5)
			(island_removal_mode 0)
		)
		(polygon
			(pts
				(arc
					(start 170.501056 -374.928638)
					(mid 170.515935 -374.892717)
					(end 170.551856 -374.877838)
				)
				(arc
					(start 171.268136 -374.877838)
					(mid 171.304057 -374.892717)
					(end 171.318936 -374.928638)
				)
				(arc
					(start 171.318936 -377.35129)
					(mid 171.304057 -377.387211)
					(end 171.268136 -377.40209)
				)
				(arc
					(start 170.551856 -377.40209)
					(mid 170.515935 -377.387211)
					(end 170.501056 -377.35129)
				)
			)
		)
	)
	(zone
		(layers "F.Cu" "B.Cu" "In1.Cu" "In2.Cu" "In3.Cu" "In4.Cu" "In5.Cu" "In6.Cu"
			"In7.Cu" "In8.Cu" "In9.Cu" "In10.Cu" "In11.Cu" "In12.Cu" "In13.Cu" "In14.Cu"
			"In15.Cu" "In16.Cu"
		)
		(hatch none 0.5)
		(connect_pads
			(clearance 0)
		)
		(min_thickness 0.25)
		(keepout
			(tracks not_allowed)
			(vias allowed)
			(pads allowed)
			(copperpour not_allowed)
			(footprints allowed)
		)
		(placement
			(enabled no)
			(sheetname "")
		)
		(fill
			(thermal_gap 0.5)
			(thermal_bridge_width 0.5)
			(island_removal_mode 0)
		)
		(polygon
			(pts
				(arc
					(start 128.195324 -196.07403)
					(mid 128.219279 -196.076307)
					(end 128.24333 -196.077078)
				)
				(arc
					(start 128.24333 -196.077078)
					(mid 128.62433 -195.696078)
					(end 128.24333 -195.315078)
				)
				(xy 128.22936 -195.315332)
				(arc
					(start 127.39116 -195.315332)
					(mid 126.999242 -195.714166)
					(end 127.427228 -196.07403)
				)
			)
		)
	)
	(zone
		(layers "F.Cu" "B.Cu" "In1.Cu" "In2.Cu" "In3.Cu" "In4.Cu" "In5.Cu" "In6.Cu"
			"In7.Cu" "In8.Cu" "In9.Cu" "In10.Cu" "In11.Cu" "In12.Cu" "In13.Cu" "In14.Cu"
			"In15.Cu" "In16.Cu"
		)
		(hatch none 0.5)
		(connect_pads
			(clearance 0)
		)
		(min_thickness 0.25)
		(keepout
			(tracks not_allowed)
			(vias allowed)
			(pads allowed)
			(copperpour not_allowed)
			(footprints allowed)
		)
		(placement
			(enabled no)
			(sheetname "")
		)
		(fill
			(thermal_gap 0.5)
			(thermal_bridge_width 0.5)
			(island_removal_mode 0)
		)
		(polygon
			(pts
				(arc
					(start 187.057792 -348.20479)
					(mid 186.676792 -348.58579)
					(end 187.057792 -348.96679)
				)
				(arc
					(start 187.921392 -348.96679)
					(mid 188.302392 -348.58579)
					(end 187.921392 -348.20479)
				)
			)
		)
	)
	(zone
		(layers "F.Cu" "B.Cu" "In1.Cu" "In2.Cu" "In3.Cu" "In4.Cu" "In5.Cu" "In6.Cu"
			"In7.Cu" "In8.Cu" "In9.Cu" "In10.Cu" "In11.Cu" "In12.Cu" "In13.Cu" "In14.Cu"
			"In15.Cu" "In16.Cu"
		)
		(hatch none 0.5)
		(connect_pads
			(clearance 0)
		)
		(min_thickness 0.25)
		(keepout
			(tracks not_allowed)
			(vias allowed)
			(pads allowed)
			(copperpour not_allowed)
			(footprints allowed)
		)
		(placement
			(enabled no)
			(sheetname "")
		)
		(fill
			(thermal_gap 0.5)
			(thermal_bridge_width 0.5)
			(island_removal_mode 0)
		)
		(polygon
			(pts
				(arc
					(start 27.501088 -395.92885)
					(mid 27.515967 -395.892929)
					(end 27.551888 -395.87805)
				)
				(arc
					(start 28.268168 -395.87805)
					(mid 28.304089 -395.892929)
					(end 28.318968 -395.92885)
				)
				(arc
					(start 28.318968 -398.351502)
					(mid 28.304089 -398.387423)
					(end 28.268168 -398.402302)
				)
				(arc
					(start 27.551888 -398.402302)
					(mid 27.515967 -398.387423)
					(end 27.501088 -398.351502)
				)
			)
		)
	)
	(zone
		(layers "F.Cu" "B.Cu" "In1.Cu" "In2.Cu" "In3.Cu" "In4.Cu" "In5.Cu" "In6.Cu"
			"In7.Cu" "In8.Cu" "In9.Cu" "In10.Cu" "In11.Cu" "In12.Cu" "In13.Cu" "In14.Cu"
			"In15.Cu" "In16.Cu"
		)
		(hatch none 0.5)
		(connect_pads
			(clearance 0)
		)
		(min_thickness 0.25)
		(keepout
			(tracks not_allowed)
			(vias allowed)
			(pads allowed)
			(copperpour not_allowed)
			(footprints allowed)
		)
		(placement
			(enabled no)
			(sheetname "")
		)
		(fill
			(thermal_gap 0.5)
			(thermal_bridge_width 0.5)
			(island_removal_mode 0)
		)
		(polygon
			(pts
				(arc
					(start 128.701038 -377.728734)
					(mid 128.715917 -377.692813)
					(end 128.751838 -377.677934)
				)
				(arc
					(start 129.468118 -377.677934)
					(mid 129.504039 -377.692813)
					(end 129.518918 -377.728734)
				)
				(arc
					(start 129.518918 -380.151386)
					(mid 129.504039 -380.187307)
					(end 129.468118 -380.202186)
				)
				(arc
					(start 128.751838 -380.202186)
					(mid 128.715917 -380.187307)
					(end 128.701038 -380.151386)
				)
			)
		)
	)
	(zone
		(layers "F.Cu" "B.Cu" "In1.Cu" "In2.Cu" "In3.Cu" "In4.Cu" "In5.Cu" "In6.Cu"
			"In7.Cu" "In8.Cu" "In9.Cu" "In10.Cu" "In11.Cu" "In12.Cu" "In13.Cu" "In14.Cu"
			"In15.Cu" "In16.Cu"
		)
		(hatch none 0.5)
		(connect_pads
			(clearance 0)
		)
		(min_thickness 0.25)
		(keepout
			(tracks not_allowed)
			(vias allowed)
			(pads allowed)
			(copperpour not_allowed)
			(footprints allowed)
		)
		(placement
			(enabled no)
			(sheetname "")
		)
		(fill
			(thermal_gap 0.5)
			(thermal_bridge_width 0.5)
			(island_removal_mode 0)
		)
		(polygon
			(pts
				(arc
					(start 6.753352 -30.922468)
					(mid 7.210552 -31.379668)
					(end 7.667752 -30.922468)
				)
				(arc
					(start 7.667752 -30.058868)
					(mid 7.210552 -29.601668)
					(end 6.753352 -30.058868)
				)
			)
		)
	)
	(zone
		(layers "F.Cu" "B.Cu" "In1.Cu" "In2.Cu" "In3.Cu" "In4.Cu" "In5.Cu" "In6.Cu"
			"In7.Cu" "In8.Cu" "In9.Cu" "In10.Cu" "In11.Cu" "In12.Cu" "In13.Cu" "In14.Cu"
			"In15.Cu" "In16.Cu"
		)
		(hatch none 0.5)
		(connect_pads
			(clearance 0)
		)
		(min_thickness 0.25)
		(keepout
			(tracks not_allowed)
			(vias allowed)
			(pads allowed)
			(copperpour not_allowed)
			(footprints allowed)
		)
		(placement
			(enabled no)
			(sheetname "")
		)
		(fill
			(thermal_gap 0.5)
			(thermal_bridge_width 0.5)
			(island_removal_mode 0)
		)
		(polygon
			(pts
				(arc
					(start 429.375062 -119.559324)
					(mid 429.832262 -120.016524)
					(end 430.289462 -119.559324)
				)
				(arc
					(start 430.289462 -118.695724)
					(mid 429.832262 -118.238524)
					(end 429.375062 -118.695724)
				)
			)
		)
	)
	(zone
		(layers "F.Cu" "B.Cu" "In1.Cu" "In2.Cu" "In3.Cu" "In4.Cu" "In5.Cu" "In6.Cu"
			"In7.Cu" "In8.Cu" "In9.Cu" "In10.Cu" "In11.Cu" "In12.Cu" "In13.Cu" "In14.Cu"
			"In15.Cu" "In16.Cu"
		)
		(hatch none 0.5)
		(connect_pads
			(clearance 0)
		)
		(min_thickness 0.25)
		(keepout
			(tracks not_allowed)
			(vias allowed)
			(pads allowed)
			(copperpour not_allowed)
			(footprints allowed)
		)
		(placement
			(enabled no)
			(sheetname "")
		)
		(fill
			(thermal_gap 0.5)
			(thermal_bridge_width 0.5)
			(island_removal_mode 0)
		)
		(polygon
			(pts
				(arc
					(start 315.917072 -148.88591)
					(mid 316.374272 -149.34311)
					(end 316.831472 -148.88591)
				)
				(arc
					(start 316.831472 -148.02231)
					(mid 316.374272 -147.56511)
					(end 315.917072 -148.02231)
				)
			)
		)
	)
	(zone
		(layers "F.Cu" "B.Cu" "In1.Cu" "In2.Cu" "In3.Cu" "In4.Cu" "In5.Cu" "In6.Cu"
			"In7.Cu" "In8.Cu" "In9.Cu" "In10.Cu" "In11.Cu" "In12.Cu" "In13.Cu" "In14.Cu"
			"In15.Cu" "In16.Cu"
		)
		(hatch none 0.5)
		(connect_pads
			(clearance 0)
		)
		(min_thickness 0.25)
		(keepout
			(tracks not_allowed)
			(vias allowed)
			(pads allowed)
			(copperpour not_allowed)
			(footprints allowed)
		)
		(placement
			(enabled no)
			(sheetname "")
		)
		(fill
			(thermal_gap 0.5)
			(thermal_bridge_width 0.5)
			(island_removal_mode 0)
		)
		(polygon
			(pts
				(arc
					(start 86.243922 -348.20479)
					(mid 85.862922 -348.58579)
					(end 86.243922 -348.96679)
				)
				(arc
					(start 87.107522 -348.96679)
					(mid 87.488522 -348.58579)
					(end 87.107522 -348.20479)
				)
			)
		)
	)
	(zone
		(layers "F.Cu" "B.Cu" "In1.Cu" "In2.Cu" "In3.Cu" "In4.Cu" "In5.Cu" "In6.Cu"
			"In7.Cu" "In8.Cu" "In9.Cu" "In10.Cu" "In11.Cu" "In12.Cu" "In13.Cu" "In14.Cu"
			"In15.Cu" "In16.Cu"
		)
		(hatch none 0.5)
		(connect_pads
			(clearance 0)
		)
		(min_thickness 0.25)
		(keepout
			(tracks not_allowed)
			(vias allowed)
			(pads allowed)
			(copperpour not_allowed)
			(footprints allowed)
		)
		(placement
			(enabled no)
			(sheetname "")
		)
		(fill
			(thermal_gap 0.5)
			(thermal_bridge_width 0.5)
			(island_removal_mode 0)
		)
		(polygon
			(pts
				(arc
					(start 161.700972 -374.928638)
					(mid 161.715851 -374.892717)
					(end 161.751772 -374.877838)
				)
				(arc
					(start 162.468052 -374.877838)
					(mid 162.503973 -374.892717)
					(end 162.518852 -374.928638)
				)
				(arc
					(start 162.518852 -377.35129)
					(mid 162.503973 -377.387211)
					(end 162.468052 -377.40209)
				)
				(arc
					(start 161.751772 -377.40209)
					(mid 161.715851 -377.387211)
					(end 161.700972 -377.35129)
				)
			)
		)
	)
	(zone
		(layers "F.Cu" "B.Cu" "In1.Cu" "In2.Cu" "In3.Cu" "In4.Cu" "In5.Cu" "In6.Cu"
			"In7.Cu" "In8.Cu" "In9.Cu" "In10.Cu" "In11.Cu" "In12.Cu" "In13.Cu" "In14.Cu"
			"In15.Cu" "In16.Cu"
		)
		(hatch none 0.5)
		(connect_pads
			(clearance 0)
		)
		(min_thickness 0.25)
		(keepout
			(tracks not_allowed)
			(vias allowed)
			(pads allowed)
			(copperpour not_allowed)
			(footprints allowed)
		)
		(placement
			(enabled no)
			(sheetname "")
		)
		(fill
			(thermal_gap 0.5)
			(thermal_bridge_width 0.5)
			(island_removal_mode 0)
		)
		(polygon
			(pts
				(arc
					(start 427.948852 -342.058498)
					(mid 427.567852 -342.439498)
					(end 427.948852 -342.820498)
				)
				(arc
					(start 428.812452 -342.820498)
					(mid 429.193452 -342.439498)
					(end 428.812452 -342.058498)
				)
			)
		)
	)
	(zone
		(layers "F.Cu" "B.Cu" "In1.Cu" "In2.Cu" "In3.Cu" "In4.Cu" "In5.Cu" "In6.Cu"
			"In7.Cu" "In8.Cu" "In9.Cu" "In10.Cu" "In11.Cu" "In12.Cu" "In13.Cu" "In14.Cu"
			"In15.Cu" "In16.Cu"
		)
		(hatch none 0.5)
		(connect_pads
			(clearance 0)
		)
		(min_thickness 0.25)
		(keepout
			(tracks not_allowed)
			(vias allowed)
			(pads allowed)
			(copperpour not_allowed)
			(footprints allowed)
		)
		(placement
			(enabled no)
			(sheetname "")
		)
		(fill
			(thermal_gap 0.5)
			(thermal_bridge_width 0.5)
			(island_removal_mode 0)
		)
		(polygon
			(pts
				(arc
					(start 168.800018 -132.232908)
					(mid 168.342818 -131.775708)
					(end 167.885618 -132.232908)
				)
				(arc
					(start 167.885618 -133.096508)
					(mid 168.342818 -133.553708)
					(end 168.800018 -133.096508)
				)
			)
		)
	)
	(zone
		(layers "F.Cu" "B.Cu" "In1.Cu" "In2.Cu" "In3.Cu" "In4.Cu" "In5.Cu" "In6.Cu"
			"In7.Cu" "In8.Cu" "In9.Cu" "In10.Cu" "In11.Cu" "In12.Cu" "In13.Cu" "In14.Cu"
			"In15.Cu" "In16.Cu"
		)
		(hatch none 0.5)
		(connect_pads
			(clearance 0)
		)
		(min_thickness 0.25)
		(keepout
			(tracks not_allowed)
			(vias allowed)
			(pads allowed)
			(copperpour not_allowed)
			(footprints allowed)
		)
		(placement
			(enabled no)
			(sheetname "")
		)
		(fill
			(thermal_gap 0.5)
			(thermal_bridge_width 0.5)
			(island_removal_mode 0)
		)
		(polygon
			(pts
				(arc
					(start 67.590162 -351.230438)
					(mid 67.209162 -351.611438)
					(end 67.590162 -351.992438)
				)
				(arc
					(start 68.453762 -351.992438)
					(mid 68.834762 -351.611438)
					(end 68.453762 -351.230438)
				)
			)
		)
	)
	(zone
		(layers "F.Cu" "B.Cu" "In1.Cu" "In2.Cu" "In3.Cu" "In4.Cu" "In5.Cu" "In6.Cu"
			"In7.Cu" "In8.Cu" "In9.Cu" "In10.Cu" "In11.Cu" "In12.Cu" "In13.Cu" "In14.Cu"
			"In15.Cu" "In16.Cu"
		)
		(hatch none 0.5)
		(connect_pads
			(clearance 0)
		)
		(min_thickness 0.25)
		(keepout
			(tracks not_allowed)
			(vias allowed)
			(pads allowed)
			(copperpour not_allowed)
			(footprints allowed)
		)
		(placement
			(enabled no)
			(sheetname "")
		)
		(fill
			(thermal_gap 0.5)
			(thermal_bridge_width 0.5)
			(island_removal_mode 0)
		)
		(polygon
			(pts
				(arc
					(start 402.85416 -122.822716)
					(mid 402.39696 -122.365516)
					(end 401.93976 -122.822716)
				)
				(arc
					(start 401.93976 -123.686316)
					(mid 402.39696 -124.143516)
					(end 402.85416 -123.686316)
				)
			)
		)
	)
	(zone
		(layers "F.Cu" "B.Cu" "In1.Cu" "In2.Cu" "In3.Cu" "In4.Cu" "In5.Cu" "In6.Cu"
			"In7.Cu" "In8.Cu" "In9.Cu" "In10.Cu" "In11.Cu" "In12.Cu" "In13.Cu" "In14.Cu"
			"In15.Cu" "In16.Cu"
		)
		(hatch none 0.5)
		(connect_pads
			(clearance 0)
		)
		(min_thickness 0.25)
		(keepout
			(tracks not_allowed)
			(vias allowed)
			(pads allowed)
			(copperpour not_allowed)
			(footprints allowed)
		)
		(placement
			(enabled no)
			(sheetname "")
		)
		(fill
			(thermal_gap 0.5)
			(thermal_bridge_width 0.5)
			(island_removal_mode 0)
		)
		(polygon
			(pts
				(arc
					(start 37.986208 -357.37673)
					(mid 37.605208 -357.75773)
					(end 37.986208 -358.13873)
				)
				(arc
					(start 38.849808 -358.13873)
					(mid 39.230808 -357.75773)
					(end 38.849808 -357.37673)
				)
			)
		)
	)
	(zone
		(layers "F.Cu" "B.Cu" "In1.Cu" "In2.Cu" "In3.Cu" "In4.Cu" "In5.Cu" "In6.Cu"
			"In7.Cu" "In8.Cu" "In9.Cu" "In10.Cu" "In11.Cu" "In12.Cu" "In13.Cu" "In14.Cu"
			"In15.Cu" "In16.Cu"
		)
		(hatch none 0.5)
		(connect_pads
			(clearance 0)
		)
		(min_thickness 0.25)
		(keepout
			(tracks not_allowed)
			(vias allowed)
			(pads allowed)
			(copperpour not_allowed)
			(footprints allowed)
		)
		(placement
			(enabled no)
			(sheetname "")
		)
		(fill
			(thermal_gap 0.5)
			(thermal_bridge_width 0.5)
			(island_removal_mode 0)
		)
		(polygon
			(pts
				(arc
					(start 89.100914 -381.628904)
					(mid 89.115793 -381.592983)
					(end 89.151714 -381.578104)
				)
				(arc
					(start 89.867994 -381.578104)
					(mid 89.903915 -381.592983)
					(end 89.918794 -381.628904)
				)
				(arc
					(start 89.918794 -384.051556)
					(mid 89.903915 -384.087477)
					(end 89.867994 -384.102356)
				)
				(arc
					(start 89.151714 -384.102356)
					(mid 89.115793 -384.087477)
					(end 89.100914 -384.051556)
				)
			)
		)
	)
	(zone
		(layers "F.Cu" "B.Cu" "In1.Cu" "In2.Cu" "In3.Cu" "In4.Cu" "In5.Cu" "In6.Cu"
			"In7.Cu" "In8.Cu" "In9.Cu" "In10.Cu" "In11.Cu" "In12.Cu" "In13.Cu" "In14.Cu"
			"In15.Cu" "In16.Cu"
		)
		(hatch none 0.5)
		(connect_pads
			(clearance 0)
		)
		(min_thickness 0.25)
		(keepout
			(tracks not_allowed)
			(vias allowed)
			(pads allowed)
			(copperpour not_allowed)
			(footprints allowed)
		)
		(placement
			(enabled no)
			(sheetname "")
		)
		(fill
			(thermal_gap 0.5)
			(thermal_bridge_width 0.5)
			(island_removal_mode 0)
		)
		(polygon
			(pts
				(arc
					(start 337.374484 -357.37673)
					(mid 336.993484 -357.75773)
					(end 337.374484 -358.13873)
				)
				(arc
					(start 338.238084 -358.13873)
					(mid 338.619084 -357.75773)
					(end 338.238084 -357.37673)
				)
			)
		)
	)
	(zone
		(layers "F.Cu" "B.Cu" "In1.Cu" "In2.Cu" "In3.Cu" "In4.Cu" "In5.Cu" "In6.Cu"
			"In7.Cu" "In8.Cu" "In9.Cu" "In10.Cu" "In11.Cu" "In12.Cu" "In13.Cu" "In14.Cu"
			"In15.Cu" "In16.Cu"
		)
		(hatch none 0.5)
		(connect_pads
			(clearance 0)
		)
		(min_thickness 0.25)
		(keepout
			(tracks not_allowed)
			(vias allowed)
			(pads allowed)
			(copperpour not_allowed)
			(footprints allowed)
		)
		(placement
			(enabled no)
			(sheetname "")
		)
		(fill
			(thermal_gap 0.5)
			(thermal_bridge_width 0.5)
			(island_removal_mode 0)
		)
		(polygon
			(pts
				(arc
					(start 305.690016 -30.92069)
					(mid 306.147216 -31.37789)
					(end 306.604416 -30.92069)
				)
				(arc
					(start 306.604416 -30.05709)
					(mid 306.147216 -29.59989)
					(end 305.690016 -30.05709)
				)
			)
		)
	)
	(zone
		(layers "F.Cu" "B.Cu" "In1.Cu" "In2.Cu" "In3.Cu" "In4.Cu" "In5.Cu" "In6.Cu"
			"In7.Cu" "In8.Cu" "In9.Cu" "In10.Cu" "In11.Cu" "In12.Cu" "In13.Cu" "In14.Cu"
			"In15.Cu" "In16.Cu"
		)
		(hatch none 0.5)
		(connect_pads
			(clearance 0)
		)
		(min_thickness 0.25)
		(keepout
			(tracks not_allowed)
			(vias allowed)
			(pads allowed)
			(copperpour not_allowed)
			(footprints allowed)
		)
		(placement
			(enabled no)
			(sheetname "")
		)
		(fill
			(thermal_gap 0.5)
			(thermal_bridge_width 0.5)
			(island_removal_mode 0)
		)
		(polygon
			(pts
				(arc
					(start 47.30115 -397.028924)
					(mid 47.316029 -396.993003)
					(end 47.35195 -396.978124)
				)
				(arc
					(start 48.06823 -396.978124)
					(mid 48.104151 -396.993003)
					(end 48.11903 -397.028924)
				)
				(arc
					(start 48.11903 -399.451576)
					(mid 48.104151 -399.487497)
					(end 48.06823 -399.502376)
				)
				(arc
					(start 47.35195 -399.502376)
					(mid 47.316029 -399.487497)
					(end 47.30115 -399.451576)
				)
			)
		)
	)
	(zone
		(layers "F.Cu" "B.Cu" "In1.Cu" "In2.Cu" "In3.Cu" "In4.Cu" "In5.Cu" "In6.Cu"
			"In7.Cu" "In8.Cu" "In9.Cu" "In10.Cu" "In11.Cu" "In12.Cu" "In13.Cu" "In14.Cu"
			"In15.Cu" "In16.Cu"
		)
		(hatch none 0.5)
		(connect_pads
			(clearance 0)
		)
		(min_thickness 0.25)
		(keepout
			(tracks not_allowed)
			(vias allowed)
			(pads allowed)
			(copperpour not_allowed)
			(footprints allowed)
		)
		(placement
			(enabled no)
			(sheetname "")
		)
		(fill
			(thermal_gap 0.5)
			(thermal_bridge_width 0.5)
			(island_removal_mode 0)
		)
		(polygon
			(pts
				(arc
					(start 42.074846 -288.154618)
					(mid 42.405046 -287.824418)
					(end 42.074846 -287.494218)
				)
				(arc
					(start 41.124886 -287.494218)
					(mid 40.794686 -287.824418)
					(end 41.124886 -288.154618)
				)
			)
		)
	)
	(zone
		(layers "F.Cu" "B.Cu" "In1.Cu" "In2.Cu" "In3.Cu" "In4.Cu" "In5.Cu" "In6.Cu"
			"In7.Cu" "In8.Cu" "In9.Cu" "In10.Cu" "In11.Cu" "In12.Cu" "In13.Cu" "In14.Cu"
			"In15.Cu" "In16.Cu"
		)
		(hatch none 0.5)
		(connect_pads
			(clearance 0)
		)
		(min_thickness 0.25)
		(keepout
			(tracks not_allowed)
			(vias allowed)
			(pads allowed)
			(copperpour not_allowed)
			(footprints allowed)
		)
		(placement
			(enabled no)
			(sheetname "")
		)
		(fill
			(thermal_gap 0.5)
			(thermal_bridge_width 0.5)
			(island_removal_mode 0)
		)
		(polygon
			(pts
				(arc
					(start 415.513012 -348.20479)
					(mid 415.132012 -348.58579)
					(end 415.513012 -348.96679)
				)
				(arc
					(start 416.376612 -348.96679)
					(mid 416.757612 -348.58579)
					(end 416.376612 -348.20479)
				)
			)
		)
	)
	(zone
		(layers "F.Cu" "B.Cu" "In1.Cu" "In2.Cu" "In3.Cu" "In4.Cu" "In5.Cu" "In6.Cu"
			"In7.Cu" "In8.Cu" "In9.Cu" "In10.Cu" "In11.Cu" "In12.Cu" "In13.Cu" "In14.Cu"
			"In15.Cu" "In16.Cu"
		)
		(hatch none 0.5)
		(connect_pads
			(clearance 0)
		)
		(min_thickness 0.25)
		(keepout
			(tracks not_allowed)
			(vias allowed)
			(pads allowed)
			(copperpour not_allowed)
			(footprints allowed)
		)
		(placement
			(enabled no)
			(sheetname "")
		)
		(fill
			(thermal_gap 0.5)
			(thermal_bridge_width 0.5)
			(island_removal_mode 0)
		)
		(polygon
			(pts
				(arc
					(start 174.901098 -382.728724)
					(mid 174.915977 -382.692803)
					(end 174.951898 -382.677924)
				)
				(arc
					(start 175.668178 -382.677924)
					(mid 175.704099 -382.692803)
					(end 175.718978 -382.728724)
				)
				(arc
					(start 175.718978 -385.151376)
					(mid 175.704099 -385.187297)
					(end 175.668178 -385.202176)
				)
				(arc
					(start 174.951898 -385.202176)
					(mid 174.915977 -385.187297)
					(end 174.901098 -385.151376)
				)
			)
		)
	)
	(zone
		(layers "F.Cu" "B.Cu" "In1.Cu" "In2.Cu" "In3.Cu" "In4.Cu" "In5.Cu" "In6.Cu"
			"In7.Cu" "In8.Cu" "In9.Cu" "In10.Cu" "In11.Cu" "In12.Cu" "In13.Cu" "In14.Cu"
			"In15.Cu" "In16.Cu"
		)
		(hatch none 0.5)
		(connect_pads
			(clearance 0)
		)
		(min_thickness 0.25)
		(keepout
			(tracks not_allowed)
			(vias allowed)
			(pads allowed)
			(copperpour not_allowed)
			(footprints allowed)
		)
		(placement
			(enabled no)
			(sheetname "")
		)
		(fill
			(thermal_gap 0.5)
			(thermal_bridge_width 0.5)
			(island_removal_mode 0)
		)
		(polygon
			(pts
				(arc
					(start 199.817228 -148.88591)
					(mid 200.274428 -149.34311)
					(end 200.731628 -148.88591)
				)
				(arc
					(start 200.731628 -148.02231)
					(mid 200.274428 -147.56511)
					(end 199.817228 -148.02231)
				)
			)
		)
	)
	(zone
		(layers "F.Cu" "B.Cu" "In1.Cu" "In2.Cu" "In3.Cu" "In4.Cu" "In5.Cu" "In6.Cu"
			"In7.Cu" "In8.Cu" "In9.Cu" "In10.Cu" "In11.Cu" "In12.Cu" "In13.Cu" "In14.Cu"
			"In15.Cu" "In16.Cu"
		)
		(hatch none 0.5)
		(connect_pads
			(clearance 0)
		)
		(min_thickness 0.25)
		(keepout
			(tracks not_allowed)
			(vias allowed)
			(pads allowed)
			(copperpour not_allowed)
			(footprints allowed)
		)
		(placement
			(enabled no)
			(sheetname "")
		)
		(fill
			(thermal_gap 0.5)
			(thermal_bridge_width 0.5)
			(island_removal_mode 0)
		)
		(polygon
			(pts
				(arc
					(start 377.4059 -357.37673)
					(mid 377.0249 -357.75773)
					(end 377.4059 -358.13873)
				)
				(arc
					(start 378.2695 -358.13873)
					(mid 378.6505 -357.75773)
					(end 378.2695 -357.37673)
				)
			)
		)
	)
	(zone
		(layers "F.Cu" "B.Cu" "In1.Cu" "In2.Cu" "In3.Cu" "In4.Cu" "In5.Cu" "In6.Cu"
			"In7.Cu" "In8.Cu" "In9.Cu" "In10.Cu" "In11.Cu" "In12.Cu" "In13.Cu" "In14.Cu"
			"In15.Cu" "In16.Cu"
		)
		(hatch none 0.5)
		(connect_pads
			(clearance 0)
		)
		(min_thickness 0.25)
		(keepout
			(tracks not_allowed)
			(vias allowed)
			(pads allowed)
			(copperpour not_allowed)
			(footprints allowed)
		)
		(placement
			(enabled no)
			(sheetname "")
		)
		(fill
			(thermal_gap 0.5)
			(thermal_bridge_width 0.5)
			(island_removal_mode 0)
		)
		(polygon
			(pts
				(arc
					(start 52.69992 -101.112828)
					(mid 52.24272 -100.655628)
					(end 51.78552 -101.112828)
				)
				(arc
					(start 51.78552 -101.976428)
					(mid 52.24272 -102.433628)
					(end 52.69992 -101.976428)
				)
			)
		)
	)
	(zone
		(layers "F.Cu" "B.Cu" "In1.Cu" "In2.Cu" "In3.Cu" "In4.Cu" "In5.Cu" "In6.Cu"
			"In7.Cu" "In8.Cu" "In9.Cu" "In10.Cu" "In11.Cu" "In12.Cu" "In13.Cu" "In14.Cu"
			"In15.Cu" "In16.Cu"
		)
		(hatch none 0.5)
		(connect_pads
			(clearance 0)
		)
		(min_thickness 0.25)
		(keepout
			(tracks not_allowed)
			(vias allowed)
			(pads allowed)
			(copperpour not_allowed)
			(footprints allowed)
		)
		(placement
			(enabled no)
			(sheetname "")
		)
		(fill
			(thermal_gap 0.5)
			(thermal_bridge_width 0.5)
			(island_removal_mode 0)
		)
		(polygon
			(pts
				(arc
					(start 75.901042 -377.728734)
					(mid 75.915921 -377.692813)
					(end 75.951842 -377.677934)
				)
				(arc
					(start 76.668122 -377.677934)
					(mid 76.704043 -377.692813)
					(end 76.718922 -377.728734)
				)
				(arc
					(start 76.718922 -380.151386)
					(mid 76.704043 -380.187307)
					(end 76.668122 -380.202186)
				)
				(arc
					(start 75.951842 -380.202186)
					(mid 75.915921 -380.187307)
					(end 75.901042 -380.151386)
				)
			)
		)
	)
	(zone
		(layers "F.Cu" "B.Cu" "In1.Cu" "In2.Cu" "In3.Cu" "In4.Cu" "In5.Cu" "In6.Cu"
			"In7.Cu" "In8.Cu" "In9.Cu" "In10.Cu" "In11.Cu" "In12.Cu" "In13.Cu" "In14.Cu"
			"In15.Cu" "In16.Cu"
		)
		(hatch none 0.5)
		(connect_pads
			(clearance 0)
		)
		(min_thickness 0.25)
		(keepout
			(tracks not_allowed)
			(vias allowed)
			(pads allowed)
			(copperpour not_allowed)
			(footprints allowed)
		)
		(placement
			(enabled no)
			(sheetname "")
		)
		(fill
			(thermal_gap 0.5)
			(thermal_bridge_width 0.5)
			(island_removal_mode 0)
		)
		(polygon
			(pts
				(arc
					(start 331.081126 -377.728734)
					(mid 331.096005 -377.692813)
					(end 331.131926 -377.677934)
				)
				(arc
					(start 331.848206 -377.677934)
					(mid 331.884127 -377.692813)
					(end 331.899006 -377.728734)
				)
				(arc
					(start 331.899006 -380.151386)
					(mid 331.884127 -380.187307)
					(end 331.848206 -380.202186)
				)
				(arc
					(start 331.131926 -380.202186)
					(mid 331.096005 -380.187307)
					(end 331.081126 -380.151386)
				)
			)
		)
	)
	(zone
		(layers "F.Cu" "B.Cu" "In1.Cu" "In2.Cu" "In3.Cu" "In4.Cu" "In5.Cu" "In6.Cu"
			"In7.Cu" "In8.Cu" "In9.Cu" "In10.Cu" "In11.Cu" "In12.Cu" "In13.Cu" "In14.Cu"
			"In15.Cu" "In16.Cu"
		)
		(hatch none 0.5)
		(connect_pads
			(clearance 0)
		)
		(min_thickness 0.25)
		(keepout
			(tracks not_allowed)
			(vias allowed)
			(pads allowed)
			(copperpour not_allowed)
			(footprints allowed)
		)
		(placement
			(enabled no)
			(sheetname "")
		)
		(fill
			(thermal_gap 0.5)
			(thermal_bridge_width 0.5)
			(island_removal_mode 0)
		)
		(polygon
			(pts
				(arc
					(start 84.700872 -407.628852)
					(mid 84.715751 -407.592931)
					(end 84.751672 -407.578052)
				)
				(arc
					(start 85.467952 -407.578052)
					(mid 85.503873 -407.592931)
					(end 85.518752 -407.628852)
				)
				(arc
					(start 85.518752 -410.051504)
					(mid 85.503873 -410.087425)
					(end 85.467952 -410.102304)
				)
				(arc
					(start 84.751672 -410.102304)
					(mid 84.715751 -410.087425)
					(end 84.700872 -410.051504)
				)
			)
		)
	)
	(zone
		(layers "F.Cu" "B.Cu" "In1.Cu" "In2.Cu" "In3.Cu" "In4.Cu" "In5.Cu" "In6.Cu"
			"In7.Cu" "In8.Cu" "In9.Cu" "In10.Cu" "In11.Cu" "In12.Cu" "In13.Cu" "In14.Cu"
			"In15.Cu" "In16.Cu"
		)
		(hatch none 0.5)
		(connect_pads
			(clearance 0)
		)
		(min_thickness 0.25)
		(keepout
			(tracks not_allowed)
			(vias allowed)
			(pads allowed)
			(copperpour not_allowed)
			(footprints allowed)
		)
		(placement
			(enabled no)
			(sheetname "")
		)
		(fill
			(thermal_gap 0.5)
			(thermal_bridge_width 0.5)
			(island_removal_mode 0)
		)
		(polygon
			(pts
				(arc
					(start 430.080928 -408.728672)
					(mid 430.095807 -408.692751)
					(end 430.131728 -408.677872)
				)
				(arc
					(start 430.848008 -408.677872)
					(mid 430.883929 -408.692751)
					(end 430.898808 -408.728672)
				)
				(arc
					(start 430.898808 -411.151324)
					(mid 430.883929 -411.187245)
					(end 430.848008 -411.202124)
				)
				(arc
					(start 430.131728 -411.202124)
					(mid 430.095807 -411.187245)
					(end 430.080928 -411.151324)
				)
			)
		)
	)
	(zone
		(layers "F.Cu" "B.Cu" "In1.Cu" "In2.Cu" "In3.Cu" "In4.Cu" "In5.Cu" "In6.Cu"
			"In7.Cu" "In8.Cu" "In9.Cu" "In10.Cu" "In11.Cu" "In12.Cu" "In13.Cu" "In14.Cu"
			"In15.Cu" "In16.Cu"
		)
		(hatch none 0.5)
		(connect_pads
			(clearance 0)
		)
		(min_thickness 0.25)
		(keepout
			(tracks not_allowed)
			(vias allowed)
			(pads allowed)
			(copperpour not_allowed)
			(footprints allowed)
		)
		(placement
			(enabled no)
			(sheetname "")
		)
		(fill
			(thermal_gap 0.5)
			(thermal_bridge_width 0.5)
			(island_removal_mode 0)
		)
		(polygon
			(pts
				(arc
					(start 197.17512 -150.67915)
					(mid 197.63232 -151.13635)
					(end 198.08952 -150.67915)
				)
				(arc
					(start 198.08952 -149.81555)
					(mid 197.63232 -149.35835)
					(end 197.17512 -149.81555)
				)
			)
		)
	)
	(zone
		(layers "F.Cu" "B.Cu" "In1.Cu" "In2.Cu" "In3.Cu" "In4.Cu" "In5.Cu" "In6.Cu"
			"In7.Cu" "In8.Cu" "In9.Cu" "In10.Cu" "In11.Cu" "In12.Cu" "In13.Cu" "In14.Cu"
			"In15.Cu" "In16.Cu"
		)
		(hatch none 0.5)
		(connect_pads
			(clearance 0)
		)
		(min_thickness 0.25)
		(keepout
			(tracks not_allowed)
			(vias allowed)
			(pads allowed)
			(copperpour not_allowed)
			(footprints allowed)
		)
		(placement
			(enabled no)
			(sheetname "")
		)
		(fill
			(thermal_gap 0.5)
			(thermal_bridge_width 0.5)
			(island_removal_mode 0)
		)
		(polygon
			(pts
				(arc
					(start 386.73278 -342.058498)
					(mid 386.35178 -342.439498)
					(end 386.73278 -342.820498)
				)
				(arc
					(start 387.59638 -342.820498)
					(mid 387.97738 -342.439498)
					(end 387.59638 -342.058498)
				)
			)
		)
	)
	(zone
		(layers "F.Cu" "B.Cu" "In1.Cu" "In2.Cu" "In3.Cu" "In4.Cu" "In5.Cu" "In6.Cu"
			"In7.Cu" "In8.Cu" "In9.Cu" "In10.Cu" "In11.Cu" "In12.Cu" "In13.Cu" "In14.Cu"
			"In15.Cu" "In16.Cu"
		)
		(hatch none 0.5)
		(connect_pads
			(clearance 0)
		)
		(min_thickness 0.25)
		(keepout
			(tracks not_allowed)
			(vias allowed)
			(pads allowed)
			(copperpour not_allowed)
			(footprints allowed)
		)
		(placement
			(enabled no)
			(sheetname "")
		)
		(fill
			(thermal_gap 0.5)
			(thermal_bridge_width 0.5)
			(island_removal_mode 0)
		)
		(polygon
			(pts
				(arc
					(start 174.621952 -345.084146)
					(mid 174.240952 -345.465146)
					(end 174.621952 -345.846146)
				)
				(arc
					(start 175.485552 -345.846146)
					(mid 175.866552 -345.465146)
					(end 175.485552 -345.084146)
				)
			)
		)
	)
	(zone
		(layers "F.Cu" "B.Cu" "In1.Cu" "In2.Cu" "In3.Cu" "In4.Cu" "In5.Cu" "In6.Cu"
			"In7.Cu" "In8.Cu" "In9.Cu" "In10.Cu" "In11.Cu" "In12.Cu" "In13.Cu" "In14.Cu"
			"In15.Cu" "In16.Cu"
		)
		(hatch none 0.5)
		(connect_pads
			(clearance 0)
		)
		(min_thickness 0.25)
		(keepout
			(tracks not_allowed)
			(vias allowed)
			(pads allowed)
			(copperpour not_allowed)
			(footprints allowed)
		)
		(placement
			(enabled no)
			(sheetname "")
		)
		(fill
			(thermal_gap 0.5)
			(thermal_bridge_width 0.5)
			(island_removal_mode 0)
		)
		(polygon
			(pts
				(arc
					(start 82.500978 -382.728724)
					(mid 82.515857 -382.692803)
					(end 82.551778 -382.677924)
				)
				(arc
					(start 83.268058 -382.677924)
					(mid 83.303979 -382.692803)
					(end 83.318858 -382.728724)
				)
				(arc
					(start 83.318858 -385.151376)
					(mid 83.303979 -385.187297)
					(end 83.268058 -385.202176)
				)
				(arc
					(start 82.551778 -385.202176)
					(mid 82.515857 -385.187297)
					(end 82.500978 -385.151376)
				)
			)
		)
	)
	(zone
		(layers "F.Cu" "B.Cu" "In1.Cu" "In2.Cu" "In3.Cu" "In4.Cu" "In5.Cu" "In6.Cu"
			"In7.Cu" "In8.Cu" "In9.Cu" "In10.Cu" "In11.Cu" "In12.Cu" "In13.Cu" "In14.Cu"
			"In15.Cu" "In16.Cu"
		)
		(hatch none 0.5)
		(connect_pads
			(clearance 0)
		)
		(min_thickness 0.25)
		(keepout
			(tracks not_allowed)
			(vias allowed)
			(pads allowed)
			(copperpour not_allowed)
			(footprints allowed)
		)
		(placement
			(enabled no)
			(sheetname "")
		)
		(fill
			(thermal_gap 0.5)
			(thermal_bridge_width 0.5)
			(island_removal_mode 0)
		)
		(polygon
			(pts
				(arc
					(start 189.590172 -34.520886)
					(mid 190.047372 -34.978086)
					(end 190.504572 -34.520886)
				)
				(arc
					(start 190.504572 -33.657286)
					(mid 190.047372 -33.200086)
					(end 189.590172 -33.657286)
				)
			)
		)
	)
	(zone
		(layers "F.Cu" "B.Cu" "In1.Cu" "In2.Cu" "In3.Cu" "In4.Cu" "In5.Cu" "In6.Cu"
			"In7.Cu" "In8.Cu" "In9.Cu" "In10.Cu" "In11.Cu" "In12.Cu" "In13.Cu" "In14.Cu"
			"In15.Cu" "In16.Cu"
		)
		(hatch none 0.5)
		(connect_pads
			(clearance 0)
		)
		(min_thickness 0.25)
		(keepout
			(tracks not_allowed)
			(vias allowed)
			(pads allowed)
			(copperpour not_allowed)
			(footprints allowed)
		)
		(placement
			(enabled no)
			(sheetname "")
		)
		(fill
			(thermal_gap 0.5)
			(thermal_bridge_width 0.5)
			(island_removal_mode 0)
		)
		(polygon
			(pts
				(arc
					(start 150.768558 -112.784382)
					(mid 151.225758 -113.241582)
					(end 151.682958 -112.784382)
				)
				(arc
					(start 151.682958 -111.920782)
					(mid 151.225758 -111.463582)
					(end 150.768558 -111.920782)
				)
			)
		)
	)
	(zone
		(layers "F.Cu" "B.Cu" "In1.Cu" "In2.Cu" "In3.Cu" "In4.Cu" "In5.Cu" "In6.Cu"
			"In7.Cu" "In8.Cu" "In9.Cu" "In10.Cu" "In11.Cu" "In12.Cu" "In13.Cu" "In14.Cu"
			"In15.Cu" "In16.Cu"
		)
		(hatch none 0.5)
		(connect_pads
			(clearance 0)
		)
		(min_thickness 0.25)
		(keepout
			(tracks not_allowed)
			(vias allowed)
			(pads allowed)
			(copperpour not_allowed)
			(footprints allowed)
		)
		(placement
			(enabled no)
			(sheetname "")
		)
		(fill
			(thermal_gap 0.5)
			(thermal_bridge_width 0.5)
			(island_removal_mode 0)
		)
		(polygon
			(pts
				(arc
					(start 47.30115 -371.028722)
					(mid 47.316029 -370.992801)
					(end 47.35195 -370.977922)
				)
				(arc
					(start 48.06823 -370.977922)
					(mid 48.104151 -370.992801)
					(end 48.11903 -371.028722)
				)
				(arc
					(start 48.11903 -373.451374)
					(mid 48.104151 -373.487295)
					(end 48.06823 -373.502174)
				)
				(arc
					(start 47.35195 -373.502174)
					(mid 47.316029 -373.487295)
					(end 47.30115 -373.451374)
				)
			)
		)
	)
	(zone
		(layers "F.Cu" "B.Cu" "In1.Cu" "In2.Cu" "In3.Cu" "In4.Cu" "In5.Cu" "In6.Cu"
			"In7.Cu" "In8.Cu" "In9.Cu" "In10.Cu" "In11.Cu" "In12.Cu" "In13.Cu" "In14.Cu"
			"In15.Cu" "In16.Cu"
		)
		(hatch none 0.5)
		(connect_pads
			(clearance 0)
		)
		(min_thickness 0.25)
		(keepout
			(tracks not_allowed)
			(vias allowed)
			(pads allowed)
			(copperpour not_allowed)
			(footprints allowed)
		)
		(placement
			(enabled no)
			(sheetname "")
		)
		(fill
			(thermal_gap 0.5)
			(thermal_bridge_width 0.5)
			(island_removal_mode 0)
		)
		(polygon
			(pts
				(arc
					(start 402.27758 -342.058498)
					(mid 401.89658 -342.439498)
					(end 402.27758 -342.820498)
				)
				(arc
					(start 403.14118 -342.820498)
					(mid 403.52218 -342.439498)
					(end 403.14118 -342.058498)
				)
			)
		)
	)
	(zone
		(layers "F.Cu" "B.Cu" "In1.Cu" "In2.Cu" "In3.Cu" "In4.Cu" "In5.Cu" "In6.Cu"
			"In7.Cu" "In8.Cu" "In9.Cu" "In10.Cu" "In11.Cu" "In12.Cu" "In13.Cu" "In14.Cu"
			"In15.Cu" "In16.Cu"
		)
		(hatch none 0.5)
		(connect_pads
			(clearance 0)
		)
		(min_thickness 0.25)
		(keepout
			(tracks not_allowed)
			(vias allowed)
			(pads allowed)
			(copperpour not_allowed)
			(footprints allowed)
		)
		(placement
			(enabled no)
			(sheetname "")
		)
		(fill
			(thermal_gap 0.5)
			(thermal_bridge_width 0.5)
			(island_removal_mode 0)
		)
		(polygon
			(pts
				(arc
					(start 31.768288 -342.058498)
					(mid 31.387288 -342.439498)
					(end 31.768288 -342.820498)
				)
				(arc
					(start 32.631888 -342.820498)
					(mid 33.012888 -342.439498)
					(end 32.631888 -342.058498)
				)
			)
		)
	)
	(zone
		(layers "F.Cu" "B.Cu" "In1.Cu" "In2.Cu" "In3.Cu" "In4.Cu" "In5.Cu" "In6.Cu"
			"In7.Cu" "In8.Cu" "In9.Cu" "In10.Cu" "In11.Cu" "In12.Cu" "In13.Cu" "In14.Cu"
			"In15.Cu" "In16.Cu"
		)
		(hatch none 0.5)
		(connect_pads
			(clearance 0)
		)
		(min_thickness 0.25)
		(keepout
			(tracks not_allowed)
			(vias allowed)
			(pads allowed)
			(copperpour not_allowed)
			(footprints allowed)
		)
		(placement
			(enabled no)
			(sheetname "")
		)
		(fill
			(thermal_gap 0.5)
			(thermal_bridge_width 0.5)
			(island_removal_mode 0)
		)
		(polygon
			(pts
				(arc
					(start 377.280932 -404.828756)
					(mid 377.295811 -404.792835)
					(end 377.331732 -404.777956)
				)
				(arc
					(start 378.048012 -404.777956)
					(mid 378.083933 -404.792835)
					(end 378.098812 -404.828756)
				)
				(arc
					(start 378.098812 -407.251408)
					(mid 378.083933 -407.287329)
					(end 378.048012 -407.302208)
				)
				(arc
					(start 377.331732 -407.302208)
					(mid 377.295811 -407.287329)
					(end 377.280932 -407.251408)
				)
			)
		)
	)
	(zone
		(layers "F.Cu" "B.Cu" "In1.Cu" "In2.Cu" "In3.Cu" "In4.Cu" "In5.Cu" "In6.Cu"
			"In7.Cu" "In8.Cu" "In9.Cu" "In10.Cu" "In11.Cu" "In12.Cu" "In13.Cu" "In14.Cu"
			"In15.Cu" "In16.Cu"
		)
		(hatch none 0.5)
		(connect_pads
			(clearance 0)
		)
		(min_thickness 0.25)
		(keepout
			(tracks not_allowed)
			(vias allowed)
			(pads allowed)
			(copperpour not_allowed)
			(footprints allowed)
		)
		(placement
			(enabled no)
			(sheetname "")
		)
		(fill
			(thermal_gap 0.5)
			(thermal_bridge_width 0.5)
			(island_removal_mode 0)
		)
		(polygon
			(pts
				(arc
					(start 18.401538 -306.28209)
					(mid 17.639538 -306.28209)
					(end 18.401538 -306.28209)
				)
			)
		)
	)
	(zone
		(layers "F.Cu" "B.Cu" "In1.Cu" "In2.Cu" "In3.Cu" "In4.Cu" "In5.Cu" "In6.Cu"
			"In7.Cu" "In8.Cu" "In9.Cu" "In10.Cu" "In11.Cu" "In12.Cu" "In13.Cu" "In14.Cu"
			"In15.Cu" "In16.Cu"
		)
		(hatch none 0.5)
		(connect_pads
			(clearance 0)
		)
		(min_thickness 0.25)
		(keepout
			(tracks not_allowed)
			(vias allowed)
			(pads allowed)
			(copperpour not_allowed)
			(footprints allowed)
		)
		(placement
			(enabled no)
			(sheetname "")
		)
		(fill
			(thermal_gap 0.5)
			(thermal_bridge_width 0.5)
			(island_removal_mode 0)
		)
		(polygon
			(pts
				(arc
					(start 388.28091 -403.728682)
					(mid 388.295789 -403.692761)
					(end 388.33171 -403.677882)
				)
				(arc
					(start 389.04799 -403.677882)
					(mid 389.083911 -403.692761)
					(end 389.09879 -403.728682)
				)
				(arc
					(start 389.09879 -406.151334)
					(mid 389.083911 -406.187255)
					(end 389.04799 -406.202134)
				)
				(arc
					(start 388.33171 -406.202134)
					(mid 388.295789 -406.187255)
					(end 388.28091 -406.151334)
				)
			)
		)
	)
	(zone
		(layers "F.Cu" "B.Cu" "In1.Cu" "In2.Cu" "In3.Cu" "In4.Cu" "In5.Cu" "In6.Cu"
			"In7.Cu" "In8.Cu" "In9.Cu" "In10.Cu" "In11.Cu" "In12.Cu" "In13.Cu" "In14.Cu"
			"In15.Cu" "In16.Cu"
		)
		(hatch none 0.5)
		(connect_pads
			(clearance 0)
		)
		(min_thickness 0.25)
		(keepout
			(tracks not_allowed)
			(vias allowed)
			(pads allowed)
			(copperpour not_allowed)
			(footprints allowed)
		)
		(placement
			(enabled no)
			(sheetname "")
		)
		(fill
			(thermal_gap 0.5)
			(thermal_bridge_width 0.5)
			(island_removal_mode 0)
		)
		(polygon
			(pts
				(arc
					(start 61.372242 -345.084146)
					(mid 60.991242 -345.465146)
					(end 61.372242 -345.846146)
				)
				(arc
					(start 62.235842 -345.846146)
					(mid 62.616842 -345.465146)
					(end 62.235842 -345.084146)
				)
			)
		)
	)
	(zone
		(layers "F.Cu" "B.Cu" "In1.Cu" "In2.Cu" "In3.Cu" "In4.Cu" "In5.Cu" "In6.Cu"
			"In7.Cu" "In8.Cu" "In9.Cu" "In10.Cu" "In11.Cu" "In12.Cu" "In13.Cu" "In14.Cu"
			"In15.Cu" "In16.Cu"
		)
		(hatch none 0.5)
		(connect_pads
			(clearance 0)
		)
		(min_thickness 0.25)
		(keepout
			(tracks not_allowed)
			(vias allowed)
			(pads allowed)
			(copperpour not_allowed)
			(footprints allowed)
		)
		(placement
			(enabled no)
			(sheetname "")
		)
		(fill
			(thermal_gap 0.5)
			(thermal_bridge_width 0.5)
			(island_removal_mode 0)
		)
		(polygon
			(pts
				(arc
					(start 27.501088 -399.828766)
					(mid 27.515967 -399.792845)
					(end 27.551888 -399.777966)
				)
				(arc
					(start 28.268168 -399.777966)
					(mid 28.304089 -399.792845)
					(end 28.318968 -399.828766)
				)
				(arc
					(start 28.318968 -402.251418)
					(mid 28.304089 -402.287339)
					(end 28.268168 -402.302218)
				)
				(arc
					(start 27.551888 -402.302218)
					(mid 27.515967 -402.287339)
					(end 27.501088 -402.251418)
				)
			)
		)
	)
	(zone
		(layers "F.Cu" "B.Cu" "In1.Cu" "In2.Cu" "In3.Cu" "In4.Cu" "In5.Cu" "In6.Cu"
			"In7.Cu" "In8.Cu" "In9.Cu" "In10.Cu" "In11.Cu" "In12.Cu" "In13.Cu" "In14.Cu"
			"In15.Cu" "In16.Cu"
		)
		(hatch none 0.5)
		(connect_pads
			(clearance 0)
		)
		(min_thickness 0.25)
		(keepout
			(tracks not_allowed)
			(vias allowed)
			(pads allowed)
			(copperpour not_allowed)
			(footprints allowed)
		)
		(placement
			(enabled no)
			(sheetname "")
		)
		(fill
			(thermal_gap 0.5)
			(thermal_bridge_width 0.5)
			(island_removal_mode 0)
		)
		(polygon
			(pts
				(arc
					(start 427.881034 -399.828766)
					(mid 427.895913 -399.792845)
					(end 427.931834 -399.777966)
				)
				(arc
					(start 428.648114 -399.777966)
					(mid 428.684035 -399.792845)
					(end 428.698914 -399.828766)
				)
				(arc
					(start 428.698914 -402.251418)
					(mid 428.684035 -402.287339)
					(end 428.648114 -402.302218)
				)
				(arc
					(start 427.931834 -402.302218)
					(mid 427.895913 -402.287339)
					(end 427.881034 -402.251418)
				)
			)
		)
	)
	(zone
		(layers "F.Cu" "B.Cu" "In1.Cu" "In2.Cu" "In3.Cu" "In4.Cu" "In5.Cu" "In6.Cu"
			"In7.Cu" "In8.Cu" "In9.Cu" "In10.Cu" "In11.Cu" "In12.Cu" "In13.Cu" "In14.Cu"
			"In15.Cu" "In16.Cu"
		)
		(hatch none 0.5)
		(connect_pads
			(clearance 0)
		)
		(min_thickness 0.25)
		(keepout
			(tracks not_allowed)
			(vias allowed)
			(pads allowed)
			(copperpour not_allowed)
			(footprints allowed)
		)
		(placement
			(enabled no)
			(sheetname "")
		)
		(fill
			(thermal_gap 0.5)
			(thermal_bridge_width 0.5)
			(island_removal_mode 0)
		)
		(polygon
			(pts
				(arc
					(start 463.65795 -13.599922)
					(mid 461.600042 -11.542014)
					(end 459.54188 -13.599922)
				)
				(arc
					(start 459.54188 -15.200122)
					(mid 461.600042 -17.258284)
					(end 463.65795 -15.200122)
				)
			)
		)
	)
	(zone
		(layers "F.Cu" "B.Cu" "In1.Cu" "In2.Cu" "In3.Cu" "In4.Cu" "In5.Cu" "In6.Cu"
			"In7.Cu" "In8.Cu" "In9.Cu" "In10.Cu" "In11.Cu" "In12.Cu" "In13.Cu" "In14.Cu"
			"In15.Cu" "In16.Cu"
		)
		(hatch none 0.5)
		(connect_pads
			(clearance 0)
		)
		(min_thickness 0.25)
		(keepout
			(tracks not_allowed)
			(vias allowed)
			(pads allowed)
			(copperpour not_allowed)
			(footprints allowed)
		)
		(placement
			(enabled no)
			(sheetname "")
		)
		(fill
			(thermal_gap 0.5)
			(thermal_bridge_width 0.5)
			(island_removal_mode 0)
		)
		(polygon
			(pts
				(arc
					(start 64.74587 -132.577332)
					(mid 65.20307 -133.034532)
					(end 65.66027 -132.577332)
				)
				(arc
					(start 65.66027 -131.713732)
					(mid 65.20307 -131.256532)
					(end 64.74587 -131.713732)
				)
			)
		)
	)
	(zone
		(layers "F.Cu" "B.Cu" "In1.Cu" "In2.Cu" "In3.Cu" "In4.Cu" "In5.Cu" "In6.Cu"
			"In7.Cu" "In8.Cu" "In9.Cu" "In10.Cu" "In11.Cu" "In12.Cu" "In13.Cu" "In14.Cu"
			"In15.Cu" "In16.Cu"
		)
		(hatch none 0.5)
		(connect_pads
			(clearance 0)
		)
		(min_thickness 0.25)
		(keepout
			(tracks not_allowed)
			(vias allowed)
			(pads allowed)
			(copperpour not_allowed)
			(footprints allowed)
		)
		(placement
			(enabled no)
			(sheetname "")
		)
		(fill
			(thermal_gap 0.5)
			(thermal_bridge_width 0.5)
			(island_removal_mode 0)
		)
		(polygon
			(pts
				(arc
					(start 130.03022 -36.60013)
					(mid 128.09982 -36.60013)
					(end 130.03022 -36.60013)
				)
			)
		)
	)
	(zone
		(layers "F.Cu" "B.Cu" "In1.Cu" "In2.Cu" "In3.Cu" "In4.Cu" "In5.Cu" "In6.Cu"
			"In7.Cu" "In8.Cu" "In9.Cu" "In10.Cu" "In11.Cu" "In12.Cu" "In13.Cu" "In14.Cu"
			"In15.Cu" "In16.Cu"
		)
		(hatch none 0.5)
		(connect_pads
			(clearance 0)
		)
		(min_thickness 0.25)
		(keepout
			(tracks not_allowed)
			(vias allowed)
			(pads allowed)
			(copperpour not_allowed)
			(footprints allowed)
		)
		(placement
			(enabled no)
			(sheetname "")
		)
		(fill
			(thermal_gap 0.5)
			(thermal_bridge_width 0.5)
			(island_removal_mode 0)
		)
		(polygon
			(pts
				(arc
					(start 76.917042 -348.20479)
					(mid 76.536042 -348.58579)
					(end 76.917042 -348.96679)
				)
				(arc
					(start 77.780642 -348.96679)
					(mid 78.161642 -348.58579)
					(end 77.780642 -348.20479)
				)
			)
		)
	)
	(zone
		(layers "F.Cu" "B.Cu" "In1.Cu" "In2.Cu" "In3.Cu" "In4.Cu" "In5.Cu" "In6.Cu"
			"In7.Cu" "In8.Cu" "In9.Cu" "In10.Cu" "In11.Cu" "In12.Cu" "In13.Cu" "In14.Cu"
			"In15.Cu" "In16.Cu"
		)
		(hatch none 0.5)
		(connect_pads
			(clearance 0)
		)
		(min_thickness 0.25)
		(keepout
			(tracks not_allowed)
			(vias allowed)
			(pads allowed)
			(copperpour not_allowed)
			(footprints allowed)
		)
		(placement
			(enabled no)
			(sheetname "")
		)
		(fill
			(thermal_gap 0.5)
			(thermal_bridge_width 0.5)
			(island_removal_mode 0)
		)
		(polygon
			(pts
				(arc
					(start 298.986702 -345.084146)
					(mid 298.605702 -345.465146)
					(end 298.986702 -345.846146)
				)
				(arc
					(start 299.850302 -345.846146)
					(mid 300.231302 -345.465146)
					(end 299.850302 -345.084146)
				)
			)
		)
	)
	(zone
		(layers "F.Cu" "B.Cu" "In1.Cu" "In2.Cu" "In3.Cu" "In4.Cu" "In5.Cu" "In6.Cu"
			"In7.Cu" "In8.Cu" "In9.Cu" "In10.Cu" "In11.Cu" "In12.Cu" "In13.Cu" "In14.Cu"
			"In15.Cu" "In16.Cu"
		)
		(hatch none 0.5)
		(connect_pads
			(clearance 0)
		)
		(min_thickness 0.25)
		(keepout
			(tracks not_allowed)
			(vias allowed)
			(pads allowed)
			(copperpour not_allowed)
			(footprints allowed)
		)
		(placement
			(enabled no)
			(sheetname "")
		)
		(fill
			(thermal_gap 0.5)
			(thermal_bridge_width 0.5)
			(island_removal_mode 0)
		)
		(polygon
			(pts
				(arc
					(start 170.654218 -119.222774)
					(mid 170.197018 -118.765574)
					(end 169.739818 -119.222774)
				)
				(arc
					(start 169.739818 -120.086374)
					(mid 170.197018 -120.543574)
					(end 170.654218 -120.086374)
				)
			)
		)
	)
	(zone
		(layers "F.Cu" "B.Cu" "In1.Cu" "In2.Cu" "In3.Cu" "In4.Cu" "In5.Cu" "In6.Cu"
			"In7.Cu" "In8.Cu" "In9.Cu" "In10.Cu" "In11.Cu" "In12.Cu" "In13.Cu" "In14.Cu"
			"In15.Cu" "In16.Cu"
		)
		(hatch none 0.5)
		(connect_pads
			(clearance 0)
		)
		(min_thickness 0.25)
		(keepout
			(tracks not_allowed)
			(vias allowed)
			(pads allowed)
			(copperpour not_allowed)
			(footprints allowed)
		)
		(placement
			(enabled no)
			(sheetname "")
		)
		(fill
			(thermal_gap 0.5)
			(thermal_bridge_width 0.5)
			(island_removal_mode 0)
		)
		(polygon
			(pts
				(arc
					(start 412.404052 -357.37673)
					(mid 412.023052 -357.75773)
					(end 412.404052 -358.13873)
				)
				(arc
					(start 413.267652 -358.13873)
					(mid 413.648652 -357.75773)
					(end 413.267652 -357.37673)
				)
			)
		)
	)
	(zone
		(layers "F.Cu" "B.Cu" "In1.Cu" "In2.Cu" "In3.Cu" "In4.Cu" "In5.Cu" "In6.Cu"
			"In7.Cu" "In8.Cu" "In9.Cu" "In10.Cu" "In11.Cu" "In12.Cu" "In13.Cu" "In14.Cu"
			"In15.Cu" "In16.Cu"
		)
		(hatch none 0.5)
		(connect_pads
			(clearance 0)
		)
		(min_thickness 0.25)
		(keepout
			(tracks not_allowed)
			(vias allowed)
			(pads allowed)
			(copperpour not_allowed)
			(footprints allowed)
		)
		(placement
			(enabled no)
			(sheetname "")
		)
		(fill
			(thermal_gap 0.5)
			(thermal_bridge_width 0.5)
			(island_removal_mode 0)
		)
		(polygon
			(pts
				(arc
					(start 141.54658 -174.805086)
					(mid 142.00378 -175.262286)
					(end 142.46098 -174.805086)
				)
				(arc
					(start 142.46098 -173.941486)
					(mid 142.00378 -173.484286)
					(end 141.54658 -173.941486)
				)
			)
		)
	)
	(zone
		(layers "F.Cu" "B.Cu" "In1.Cu" "In2.Cu" "In3.Cu" "In4.Cu" "In5.Cu" "In6.Cu"
			"In7.Cu" "In8.Cu" "In9.Cu" "In10.Cu" "In11.Cu" "In12.Cu" "In13.Cu" "In14.Cu"
			"In15.Cu" "In16.Cu"
		)
		(hatch none 0.5)
		(connect_pads
			(clearance 0)
		)
		(min_thickness 0.25)
		(keepout
			(tracks not_allowed)
			(vias allowed)
			(pads allowed)
			(copperpour not_allowed)
			(footprints allowed)
		)
		(placement
			(enabled no)
			(sheetname "")
		)
		(fill
			(thermal_gap 0.5)
			(thermal_bridge_width 0.5)
			(island_removal_mode 0)
		)
		(polygon
			(pts
				(arc
					(start 296.945812 -156.087318)
					(mid 297.403012 -156.544518)
					(end 297.860212 -156.087318)
				)
				(arc
					(start 297.860212 -155.223718)
					(mid 297.403012 -154.766518)
					(end 296.945812 -155.223718)
				)
			)
		)
	)
	(zone
		(layers "F.Cu" "B.Cu" "In1.Cu" "In2.Cu" "In3.Cu" "In4.Cu" "In5.Cu" "In6.Cu"
			"In7.Cu" "In8.Cu" "In9.Cu" "In10.Cu" "In11.Cu" "In12.Cu" "In13.Cu" "In14.Cu"
			"In15.Cu" "In16.Cu"
		)
		(hatch none 0.5)
		(connect_pads
			(clearance 0)
		)
		(min_thickness 0.25)
		(keepout
			(tracks not_allowed)
			(vias allowed)
			(pads allowed)
			(copperpour not_allowed)
			(footprints allowed)
		)
		(placement
			(enabled no)
			(sheetname "")
		)
		(fill
			(thermal_gap 0.5)
			(thermal_bridge_width 0.5)
			(island_removal_mode 0)
		)
		(polygon
			(pts
				(arc
					(start 47.30115 -374.928892)
					(mid 47.316029 -374.892971)
					(end 47.35195 -374.878092)
				)
				(arc
					(start 48.06823 -374.878092)
					(mid 48.104151 -374.892971)
					(end 48.11903 -374.928892)
				)
				(arc
					(start 48.11903 -377.351544)
					(mid 48.104151 -377.387465)
					(end 48.06823 -377.402344)
				)
				(arc
					(start 47.35195 -377.402344)
					(mid 47.316029 -377.387465)
					(end 47.30115 -377.351544)
				)
			)
		)
	)
	(zone
		(layers "F.Cu" "B.Cu" "In1.Cu" "In2.Cu" "In3.Cu" "In4.Cu" "In5.Cu" "In6.Cu"
			"In7.Cu" "In8.Cu" "In9.Cu" "In10.Cu" "In11.Cu" "In12.Cu" "In13.Cu" "In14.Cu"
			"In15.Cu" "In16.Cu"
		)
		(hatch none 0.5)
		(connect_pads
			(clearance 0)
		)
		(min_thickness 0.25)
		(keepout
			(tracks not_allowed)
			(vias allowed)
			(pads allowed)
			(copperpour not_allowed)
			(footprints allowed)
		)
		(placement
			(enabled no)
			(sheetname "")
		)
		(fill
			(thermal_gap 0.5)
			(thermal_bridge_width 0.5)
			(island_removal_mode 0)
		)
		(polygon
			(pts
				(arc
					(start 296.945812 -124.967238)
					(mid 297.403012 -125.424438)
					(end 297.860212 -124.967238)
				)
				(arc
					(start 297.860212 -124.103638)
					(mid 297.403012 -123.646438)
					(end 296.945812 -124.103638)
				)
			)
		)
	)
	(zone
		(layers "F.Cu" "B.Cu" "In1.Cu" "In2.Cu" "In3.Cu" "In4.Cu" "In5.Cu" "In6.Cu"
			"In7.Cu" "In8.Cu" "In9.Cu" "In10.Cu" "In11.Cu" "In12.Cu" "In13.Cu" "In14.Cu"
			"In15.Cu" "In16.Cu"
		)
		(hatch none 0.5)
		(connect_pads
			(clearance 0)
		)
		(min_thickness 0.25)
		(keepout
			(tracks not_allowed)
			(vias allowed)
			(pads allowed)
			(copperpour not_allowed)
			(footprints allowed)
		)
		(placement
			(enabled no)
			(sheetname "")
		)
		(fill
			(thermal_gap 0.5)
			(thermal_bridge_width 0.5)
			(island_removal_mode 0)
		)
		(polygon
			(pts
				(arc
					(start 408.907488 -29.12237)
					(mid 409.364688 -29.57957)
					(end 409.821888 -29.12237)
				)
				(arc
					(start 409.821888 -28.25877)
					(mid 409.364688 -27.80157)
					(end 408.907488 -28.25877)
				)
			)
		)
	)
	(zone
		(layers "F.Cu" "B.Cu" "In1.Cu" "In2.Cu" "In3.Cu" "In4.Cu" "In5.Cu" "In6.Cu"
			"In7.Cu" "In8.Cu" "In9.Cu" "In10.Cu" "In11.Cu" "In12.Cu" "In13.Cu" "In14.Cu"
			"In15.Cu" "In16.Cu"
		)
		(hatch none 0.5)
		(connect_pads
			(clearance 0)
		)
		(min_thickness 0.25)
		(keepout
			(tracks not_allowed)
			(vias allowed)
			(pads allowed)
			(copperpour not_allowed)
			(footprints allowed)
		)
		(placement
			(enabled no)
			(sheetname "")
		)
		(fill
			(thermal_gap 0.5)
			(thermal_bridge_width 0.5)
			(island_removal_mode 0)
		)
		(polygon
			(pts
				(arc
					(start 381.05334 -30.922468)
					(mid 381.51054 -31.379668)
					(end 381.96774 -30.922468)
				)
				(arc
					(start 381.96774 -30.058868)
					(mid 381.51054 -29.601668)
					(end 381.05334 -30.058868)
				)
			)
		)
	)
	(zone
		(layers "F.Cu" "B.Cu" "In1.Cu" "In2.Cu" "In3.Cu" "In4.Cu" "In5.Cu" "In6.Cu"
			"In7.Cu" "In8.Cu" "In9.Cu" "In10.Cu" "In11.Cu" "In12.Cu" "In13.Cu" "In14.Cu"
			"In15.Cu" "In16.Cu"
		)
		(hatch none 0.5)
		(connect_pads
			(clearance 0)
		)
		(min_thickness 0.25)
		(keepout
			(tracks not_allowed)
			(vias allowed)
			(pads allowed)
			(copperpour not_allowed)
			(footprints allowed)
		)
		(placement
			(enabled no)
			(sheetname "")
		)
		(fill
			(thermal_gap 0.5)
			(thermal_bridge_width 0.5)
			(island_removal_mode 0)
		)
		(polygon
			(pts
				(arc
					(start 215.59012 -30.92069)
					(mid 216.04732 -31.37789)
					(end 216.50452 -30.92069)
				)
				(arc
					(start 216.50452 -30.05709)
					(mid 216.04732 -29.59989)
					(end 215.59012 -30.05709)
				)
			)
		)
	)
	(zone
		(layers "F.Cu" "B.Cu" "In1.Cu" "In2.Cu" "In3.Cu" "In4.Cu" "In5.Cu" "In6.Cu"
			"In7.Cu" "In8.Cu" "In9.Cu" "In10.Cu" "In11.Cu" "In12.Cu" "In13.Cu" "In14.Cu"
			"In15.Cu" "In16.Cu"
		)
		(hatch none 0.5)
		(connect_pads
			(clearance 0)
		)
		(min_thickness 0.25)
		(keepout
			(tracks not_allowed)
			(vias allowed)
			(pads allowed)
			(copperpour not_allowed)
			(footprints allowed)
		)
		(placement
			(enabled no)
			(sheetname "")
		)
		(fill
			(thermal_gap 0.5)
			(thermal_bridge_width 0.5)
			(island_removal_mode 0)
		)
		(polygon
			(pts
				(arc
					(start 159.501078 -377.728734)
					(mid 159.515957 -377.692813)
					(end 159.551878 -377.677934)
				)
				(arc
					(start 160.268158 -377.677934)
					(mid 160.304079 -377.692813)
					(end 160.318958 -377.728734)
				)
				(arc
					(start 160.318958 -380.151386)
					(mid 160.304079 -380.187307)
					(end 160.268158 -380.202186)
				)
				(arc
					(start 159.551878 -380.202186)
					(mid 159.515957 -380.187307)
					(end 159.501078 -380.151386)
				)
			)
		)
	)
	(zone
		(layers "F.Cu" "B.Cu" "In1.Cu" "In2.Cu" "In3.Cu" "In4.Cu" "In5.Cu" "In6.Cu"
			"In7.Cu" "In8.Cu" "In9.Cu" "In10.Cu" "In11.Cu" "In12.Cu" "In13.Cu" "In14.Cu"
			"In15.Cu" "In16.Cu"
		)
		(hatch none 0.5)
		(connect_pads
			(clearance 0)
		)
		(min_thickness 0.25)
		(keepout
			(tracks not_allowed)
			(vias allowed)
			(pads allowed)
			(copperpour not_allowed)
			(footprints allowed)
		)
		(placement
			(enabled no)
			(sheetname "")
		)
		(fill
			(thermal_gap 0.5)
			(thermal_bridge_width 0.5)
			(island_removal_mode 0)
		)
		(polygon
			(pts
				(arc
					(start 37.310568 -133.104382)
					(mid 37.767768 -133.561582)
					(end 38.224968 -133.104382)
				)
				(arc
					(start 38.224968 -132.240782)
					(mid 37.767768 -131.783582)
					(end 37.310568 -132.240782)
				)
			)
		)
	)
	(zone
		(layers "F.Cu" "B.Cu" "In1.Cu" "In2.Cu" "In3.Cu" "In4.Cu" "In5.Cu" "In6.Cu"
			"In7.Cu" "In8.Cu" "In9.Cu" "In10.Cu" "In11.Cu" "In12.Cu" "In13.Cu" "In14.Cu"
			"In15.Cu" "In16.Cu"
		)
		(hatch none 0.5)
		(connect_pads
			(clearance 0)
		)
		(min_thickness 0.25)
		(keepout
			(tracks not_allowed)
			(vias allowed)
			(pads allowed)
			(copperpour not_allowed)
			(footprints allowed)
		)
		(placement
			(enabled no)
			(sheetname "")
		)
		(fill
			(thermal_gap 0.5)
			(thermal_bridge_width 0.5)
			(island_removal_mode 0)
		)
		(polygon
			(pts
				(arc
					(start 159.077152 -354.351082)
					(mid 158.696152 -354.732082)
					(end 159.077152 -355.113082)
				)
				(arc
					(start 159.940752 -355.113082)
					(mid 160.321752 -354.732082)
					(end 159.940752 -354.351082)
				)
			)
		)
	)
	(zone
		(layers "F.Cu" "B.Cu" "In1.Cu" "In2.Cu" "In3.Cu" "In4.Cu" "In5.Cu" "In6.Cu"
			"In7.Cu" "In8.Cu" "In9.Cu" "In10.Cu" "In11.Cu" "In12.Cu" "In13.Cu" "In14.Cu"
			"In15.Cu" "In16.Cu"
		)
		(hatch none 0.5)
		(connect_pads
			(clearance 0)
		)
		(min_thickness 0.25)
		(keepout
			(tracks not_allowed)
			(vias allowed)
			(pads allowed)
			(copperpour not_allowed)
			(footprints allowed)
		)
		(placement
			(enabled no)
			(sheetname "")
		)
		(fill
			(thermal_gap 0.5)
			(thermal_bridge_width 0.5)
			(island_removal_mode 0)
		)
		(polygon
			(pts
				(arc
					(start 29.700982 -374.928638)
					(mid 29.715861 -374.892717)
					(end 29.751782 -374.877838)
				)
				(arc
					(start 30.468062 -374.877838)
					(mid 30.503983 -374.892717)
					(end 30.518862 -374.928638)
				)
				(arc
					(start 30.518862 -377.35129)
					(mid 30.503983 -377.387211)
					(end 30.468062 -377.40209)
				)
				(arc
					(start 29.751782 -377.40209)
					(mid 29.715861 -377.387211)
					(end 29.700982 -377.35129)
				)
			)
		)
	)
	(zone
		(layers "F.Cu" "B.Cu" "In1.Cu" "In2.Cu" "In3.Cu" "In4.Cu" "In5.Cu" "In6.Cu"
			"In7.Cu" "In8.Cu" "In9.Cu" "In10.Cu" "In11.Cu" "In12.Cu" "In13.Cu" "In14.Cu"
			"In15.Cu" "In16.Cu"
		)
		(hatch none 0.5)
		(connect_pads
			(clearance 0)
		)
		(min_thickness 0.25)
		(keepout
			(tracks not_allowed)
			(vias allowed)
			(pads allowed)
			(copperpour not_allowed)
			(footprints allowed)
		)
		(placement
			(enabled no)
			(sheetname "")
		)
		(fill
			(thermal_gap 0.5)
			(thermal_bridge_width 0.5)
			(island_removal_mode 0)
		)
		(polygon
			(pts
				(arc
					(start 150.768558 -109.18444)
					(mid 151.225758 -109.64164)
					(end 151.682958 -109.18444)
				)
				(arc
					(start 151.682958 -108.32084)
					(mid 151.225758 -107.86364)
					(end 150.768558 -108.32084)
				)
			)
		)
	)
	(zone
		(layers "F.Cu" "B.Cu" "In1.Cu" "In2.Cu" "In3.Cu" "In4.Cu" "In5.Cu" "In6.Cu"
			"In7.Cu" "In8.Cu" "In9.Cu" "In10.Cu" "In11.Cu" "In12.Cu" "In13.Cu" "In14.Cu"
			"In15.Cu" "In16.Cu"
		)
		(hatch none 0.5)
		(connect_pads
			(clearance 0)
		)
		(min_thickness 0.25)
		(keepout
			(tracks not_allowed)
			(vias allowed)
			(pads allowed)
			(copperpour not_allowed)
			(footprints allowed)
		)
		(placement
			(enabled no)
			(sheetname "")
		)
		(fill
			(thermal_gap 0.5)
			(thermal_bridge_width 0.5)
			(island_removal_mode 0)
		)
		(polygon
			(pts
				(arc
					(start 54.55412 -102.912672)
					(mid 54.09692 -102.455472)
					(end 53.63972 -102.912672)
				)
				(arc
					(start 53.63972 -103.776272)
					(mid 54.09692 -104.233472)
					(end 54.55412 -103.776272)
				)
			)
		)
	)
	(zone
		(layers "F.Cu" "B.Cu" "In1.Cu" "In2.Cu" "In3.Cu" "In4.Cu" "In5.Cu" "In6.Cu"
			"In7.Cu" "In8.Cu" "In9.Cu" "In10.Cu" "In11.Cu" "In12.Cu" "In13.Cu" "In14.Cu"
			"In15.Cu" "In16.Cu"
		)
		(hatch none 0.5)
		(connect_pads
			(clearance 0)
		)
		(min_thickness 0.25)
		(keepout
			(tracks not_allowed)
			(vias allowed)
			(pads allowed)
			(copperpour not_allowed)
			(footprints allowed)
		)
		(placement
			(enabled no)
			(sheetname "")
		)
		(fill
			(thermal_gap 0.5)
			(thermal_bridge_width 0.5)
			(island_removal_mode 0)
		)
		(polygon
			(pts
				(arc
					(start 414.90011 -154.28722)
					(mid 415.35731 -154.74442)
					(end 415.81451 -154.28722)
				)
				(arc
					(start 415.81451 -153.42362)
					(mid 415.35731 -152.96642)
					(end 414.90011 -153.42362)
				)
			)
		)
	)
	(zone
		(layers "F.Cu" "B.Cu" "In1.Cu" "In2.Cu" "In3.Cu" "In4.Cu" "In5.Cu" "In6.Cu"
			"In7.Cu" "In8.Cu" "In9.Cu" "In10.Cu" "In11.Cu" "In12.Cu" "In13.Cu" "In14.Cu"
			"In15.Cu" "In16.Cu"
		)
		(hatch none 0.5)
		(connect_pads
			(clearance 0)
		)
		(min_thickness 0.25)
		(keepout
			(tracks not_allowed)
			(vias allowed)
			(pads allowed)
			(copperpour not_allowed)
			(footprints allowed)
		)
		(placement
			(enabled no)
			(sheetname "")
		)
		(fill
			(thermal_gap 0.5)
			(thermal_bridge_width 0.5)
			(island_removal_mode 0)
		)
		(polygon
			(pts
				(arc
					(start 168.404032 -345.084146)
					(mid 168.023032 -345.465146)
					(end 168.404032 -345.846146)
				)
				(arc
					(start 169.267632 -345.846146)
					(mid 169.648632 -345.465146)
					(end 169.267632 -345.084146)
				)
			)
		)
	)
	(zone
		(layers "F.Cu" "B.Cu" "In1.Cu" "In2.Cu" "In3.Cu" "In4.Cu" "In5.Cu" "In6.Cu"
			"In7.Cu" "In8.Cu" "In9.Cu" "In10.Cu" "In11.Cu" "In12.Cu" "In13.Cu" "In14.Cu"
			"In15.Cu" "In16.Cu"
		)
		(hatch none 0.5)
		(connect_pads
			(clearance 0)
		)
		(min_thickness 0.25)
		(keepout
			(tracks not_allowed)
			(vias allowed)
			(pads allowed)
			(copperpour not_allowed)
			(footprints allowed)
		)
		(placement
			(enabled no)
			(sheetname "")
		)
		(fill
			(thermal_gap 0.5)
			(thermal_bridge_width 0.5)
			(island_removal_mode 0)
		)
		(polygon
			(pts
				(arc
					(start 281.609292 -95.214948)
					(mid 279.475692 -95.214948)
					(end 281.609292 -95.214948)
				)
			)
		)
	)
	(zone
		(layers "F.Cu" "B.Cu" "In1.Cu" "In2.Cu" "In3.Cu" "In4.Cu" "In5.Cu" "In6.Cu"
			"In7.Cu" "In8.Cu" "In9.Cu" "In10.Cu" "In11.Cu" "In12.Cu" "In13.Cu" "In14.Cu"
			"In15.Cu" "In16.Cu"
		)
		(hatch none 0.5)
		(connect_pads
			(clearance 0)
		)
		(min_thickness 0.25)
		(keepout
			(tracks not_allowed)
			(vias allowed)
			(pads allowed)
			(copperpour not_allowed)
			(footprints allowed)
		)
		(placement
			(enabled no)
			(sheetname "")
		)
		(fill
			(thermal_gap 0.5)
			(thermal_bridge_width 0.5)
			(island_removal_mode 0)
		)
		(polygon
			(pts
				(arc
					(start 273.798792 -81.976468)
					(mid 274.255992 -82.433668)
					(end 274.713192 -81.976468)
				)
				(arc
					(start 274.713192 -81.112868)
					(mid 274.255992 -80.655668)
					(end 273.798792 -81.112868)
				)
			)
		)
	)
	(zone
		(layers "F.Cu" "B.Cu" "In1.Cu" "In2.Cu" "In3.Cu" "In4.Cu" "In5.Cu" "In6.Cu"
			"In7.Cu" "In8.Cu" "In9.Cu" "In10.Cu" "In11.Cu" "In12.Cu" "In13.Cu" "In14.Cu"
			"In15.Cu" "In16.Cu"
		)
		(hatch none 0.5)
		(connect_pads
			(clearance 0)
		)
		(min_thickness 0.25)
		(keepout
			(tracks not_allowed)
			(vias allowed)
			(pads allowed)
			(copperpour not_allowed)
			(footprints allowed)
		)
		(placement
			(enabled no)
			(sheetname "")
		)
		(fill
			(thermal_gap 0.5)
			(thermal_bridge_width 0.5)
			(island_removal_mode 0)
		)
		(polygon
			(pts
				(arc
					(start 31.768288 -348.20479)
					(mid 31.387288 -348.58579)
					(end 31.768288 -348.96679)
				)
				(arc
					(start 32.631888 -348.96679)
					(mid 33.012888 -348.58579)
					(end 32.631888 -348.20479)
				)
			)
		)
	)
	(zone
		(layers "F.Cu" "B.Cu" "In1.Cu" "In2.Cu" "In3.Cu" "In4.Cu" "In5.Cu" "In6.Cu"
			"In7.Cu" "In8.Cu" "In9.Cu" "In10.Cu" "In11.Cu" "In12.Cu" "In13.Cu" "In14.Cu"
			"In15.Cu" "In16.Cu"
		)
		(hatch none 0.5)
		(connect_pads
			(clearance 0)
		)
		(min_thickness 0.25)
		(keepout
			(tracks not_allowed)
			(vias allowed)
			(pads allowed)
			(copperpour not_allowed)
			(footprints allowed)
		)
		(placement
			(enabled no)
			(sheetname "")
		)
		(fill
			(thermal_gap 0.5)
			(thermal_bridge_width 0.5)
			(island_removal_mode 0)
		)
		(polygon
			(pts
				(arc
					(start 115.501166 -403.728682)
					(mid 115.516045 -403.692761)
					(end 115.551966 -403.677882)
				)
				(arc
					(start 116.268246 -403.677882)
					(mid 116.304167 -403.692761)
					(end 116.319046 -403.728682)
				)
				(arc
					(start 116.319046 -406.151334)
					(mid 116.304167 -406.187255)
					(end 116.268246 -406.202134)
				)
				(arc
					(start 115.551966 -406.202134)
					(mid 115.516045 -406.187255)
					(end 115.501166 -406.151334)
				)
			)
		)
	)
	(zone
		(layers "F.Cu" "B.Cu" "In1.Cu" "In2.Cu" "In3.Cu" "In4.Cu" "In5.Cu" "In6.Cu"
			"In7.Cu" "In8.Cu" "In9.Cu" "In10.Cu" "In11.Cu" "In12.Cu" "In13.Cu" "In14.Cu"
			"In15.Cu" "In16.Cu"
		)
		(hatch none 0.5)
		(connect_pads
			(clearance 0)
		)
		(min_thickness 0.25)
		(keepout
			(tracks not_allowed)
			(vias allowed)
			(pads allowed)
			(copperpour not_allowed)
			(footprints allowed)
		)
		(placement
			(enabled no)
			(sheetname "")
		)
		(fill
			(thermal_gap 0.5)
			(thermal_bridge_width 0.5)
			(island_removal_mode 0)
		)
		(polygon
			(pts
				(arc
					(start 246.430038 -170.041062)
					(mid 246.887238 -169.583862)
					(end 246.430038 -169.126662)
				)
				(arc
					(start 245.566438 -169.126662)
					(mid 245.109238 -169.583862)
					(end 245.566438 -170.041062)
				)
			)
		)
	)
	(zone
		(layers "F.Cu" "B.Cu" "In1.Cu" "In2.Cu" "In3.Cu" "In4.Cu" "In5.Cu" "In6.Cu"
			"In7.Cu" "In8.Cu" "In9.Cu" "In10.Cu" "In11.Cu" "In12.Cu" "In13.Cu" "In14.Cu"
			"In15.Cu" "In16.Cu"
		)
		(hatch none 0.5)
		(connect_pads
			(clearance 0)
		)
		(min_thickness 0.25)
		(keepout
			(tracks not_allowed)
			(vias allowed)
			(pads allowed)
			(copperpour not_allowed)
			(footprints allowed)
		)
		(placement
			(enabled no)
			(sheetname "")
		)
		(fill
			(thermal_gap 0.5)
			(thermal_bridge_width 0.5)
			(island_removal_mode 0)
		)
		(polygon
			(pts
				(arc
					(start 142.951708 -354.351082)
					(mid 142.570708 -354.732082)
					(end 142.951708 -355.113082)
				)
				(arc
					(start 143.815308 -355.113082)
					(mid 144.196308 -354.732082)
					(end 143.815308 -354.351082)
				)
			)
		)
	)
	(zone
		(layers "F.Cu" "B.Cu" "In1.Cu" "In2.Cu" "In3.Cu" "In4.Cu" "In5.Cu" "In6.Cu"
			"In7.Cu" "In8.Cu" "In9.Cu" "In10.Cu" "In11.Cu" "In12.Cu" "In13.Cu" "In14.Cu"
			"In15.Cu" "In16.Cu"
		)
		(hatch none 0.5)
		(connect_pads
			(clearance 0)
		)
		(min_thickness 0.25)
		(keepout
			(tracks not_allowed)
			(vias allowed)
			(pads allowed)
			(copperpour not_allowed)
			(footprints allowed)
		)
		(placement
			(enabled no)
			(sheetname "")
		)
		(fill
			(thermal_gap 0.5)
			(thermal_bridge_width 0.5)
			(island_removal_mode 0)
		)
		(polygon
			(pts
				(arc
					(start 170.654218 -134.032752)
					(mid 170.197018 -133.575552)
					(end 169.739818 -134.032752)
				)
				(arc
					(start 169.739818 -134.896352)
					(mid 170.197018 -135.353552)
					(end 170.654218 -134.896352)
				)
			)
		)
	)
	(zone
		(layers "F.Cu" "B.Cu" "In1.Cu" "In2.Cu" "In3.Cu" "In4.Cu" "In5.Cu" "In6.Cu"
			"In7.Cu" "In8.Cu" "In9.Cu" "In10.Cu" "In11.Cu" "In12.Cu" "In13.Cu" "In14.Cu"
			"In15.Cu" "In16.Cu"
		)
		(hatch none 0.5)
		(connect_pads
			(clearance 0)
		)
		(min_thickness 0.25)
		(keepout
			(tracks not_allowed)
			(vias allowed)
			(pads allowed)
			(copperpour not_allowed)
			(footprints allowed)
		)
		(placement
			(enabled no)
			(sheetname "")
		)
		(fill
			(thermal_gap 0.5)
			(thermal_bridge_width 0.5)
			(island_removal_mode 0)
		)
		(polygon
			(pts
				(arc
					(start 187.057792 -357.352854)
					(mid 186.676792 -357.733854)
					(end 187.057792 -358.114854)
				)
				(arc
					(start 187.921392 -358.114854)
					(mid 188.302392 -357.733854)
					(end 187.921392 -357.352854)
				)
			)
		)
	)
	(zone
		(layers "F.Cu" "B.Cu" "In1.Cu" "In2.Cu" "In3.Cu" "In4.Cu" "In5.Cu" "In6.Cu"
			"In7.Cu" "In8.Cu" "In9.Cu" "In10.Cu" "In11.Cu" "In12.Cu" "In13.Cu" "In14.Cu"
			"In15.Cu" "In16.Cu"
		)
		(hatch none 0.5)
		(connect_pads
			(clearance 0)
		)
		(min_thickness 0.25)
		(keepout
			(tracks not_allowed)
			(vias allowed)
			(pads allowed)
			(copperpour not_allowed)
			(footprints allowed)
		)
		(placement
			(enabled no)
			(sheetname "")
		)
		(fill
			(thermal_gap 0.5)
			(thermal_bridge_width 0.5)
			(island_removal_mode 0)
		)
		(polygon
			(pts
				(arc
					(start 47.313088 -342.058498)
					(mid 46.932088 -342.439498)
					(end 47.313088 -342.820498)
				)
				(arc
					(start 48.176688 -342.820498)
					(mid 48.557688 -342.439498)
					(end 48.176688 -342.058498)
				)
			)
		)
	)
	(zone
		(layers "F.Cu" "B.Cu" "In1.Cu" "In2.Cu" "In3.Cu" "In4.Cu" "In5.Cu" "In6.Cu"
			"In7.Cu" "In8.Cu" "In9.Cu" "In10.Cu" "In11.Cu" "In12.Cu" "In13.Cu" "In14.Cu"
			"In15.Cu" "In16.Cu"
		)
		(hatch none 0.5)
		(connect_pads
			(clearance 0)
		)
		(min_thickness 0.25)
		(keepout
			(tracks not_allowed)
			(vias allowed)
			(pads allowed)
			(copperpour not_allowed)
			(footprints allowed)
		)
		(placement
			(enabled no)
			(sheetname "")
		)
		(fill
			(thermal_gap 0.5)
			(thermal_bridge_width 0.5)
			(island_removal_mode 0)
		)
		(polygon
			(pts
				(arc
					(start 98.270314 -329.553062)
					(mid 97.813114 -329.095862)
					(end 97.355914 -329.553062)
				)
				(arc
					(start 97.355914 -330.416662)
					(mid 97.813114 -330.873862)
					(end 98.270314 -330.416662)
				)
			)
		)
	)
	(zone
		(layers "F.Cu" "B.Cu" "In1.Cu" "In2.Cu" "In3.Cu" "In4.Cu" "In5.Cu" "In6.Cu"
			"In7.Cu" "In8.Cu" "In9.Cu" "In10.Cu" "In11.Cu" "In12.Cu" "In13.Cu" "In14.Cu"
			"In15.Cu" "In16.Cu"
		)
		(hatch none 0.5)
		(connect_pads
			(clearance 0)
		)
		(min_thickness 0.25)
		(keepout
			(tracks not_allowed)
			(vias allowed)
			(pads allowed)
			(copperpour not_allowed)
			(footprints allowed)
		)
		(placement
			(enabled no)
			(sheetname "")
		)
		(fill
			(thermal_gap 0.5)
			(thermal_bridge_width 0.5)
			(island_removal_mode 0)
		)
		(polygon
			(pts
				(arc
					(start 133.624828 -342.058498)
					(mid 133.243828 -342.439498)
					(end 133.624828 -342.820498)
				)
				(arc
					(start 134.488428 -342.820498)
					(mid 134.869428 -342.439498)
					(end 134.488428 -342.058498)
				)
			)
		)
	)
	(zone
		(layers "F.Cu" "B.Cu" "In1.Cu" "In2.Cu" "In3.Cu" "In4.Cu" "In5.Cu" "In6.Cu"
			"In7.Cu" "In8.Cu" "In9.Cu" "In10.Cu" "In11.Cu" "In12.Cu" "In13.Cu" "In14.Cu"
			"In15.Cu" "In16.Cu"
		)
		(hatch none 0.5)
		(connect_pads
			(clearance 0)
		)
		(min_thickness 0.25)
		(keepout
			(tracks not_allowed)
			(vias allowed)
			(pads allowed)
			(copperpour not_allowed)
			(footprints allowed)
		)
		(placement
			(enabled no)
			(sheetname "")
		)
		(fill
			(thermal_gap 0.5)
			(thermal_bridge_width 0.5)
			(island_removal_mode 0)
		)
		(polygon
			(pts
				(arc
					(start 80.301084 -403.728682)
					(mid 80.315963 -403.692761)
					(end 80.351884 -403.677882)
				)
				(arc
					(start 81.068164 -403.677882)
					(mid 81.104085 -403.692761)
					(end 81.118964 -403.728682)
				)
				(arc
					(start 81.118964 -406.151334)
					(mid 81.104085 -406.187255)
					(end 81.068164 -406.202134)
				)
				(arc
					(start 80.351884 -406.202134)
					(mid 80.315963 -406.187255)
					(end 80.301084 -406.151334)
				)
			)
		)
	)
	(zone
		(layers "F.Cu" "B.Cu" "In1.Cu" "In2.Cu" "In3.Cu" "In4.Cu" "In5.Cu" "In6.Cu"
			"In7.Cu" "In8.Cu" "In9.Cu" "In10.Cu" "In11.Cu" "In12.Cu" "In13.Cu" "In14.Cu"
			"In15.Cu" "In16.Cu"
		)
		(hatch none 0.5)
		(connect_pads
			(clearance 0)
		)
		(min_thickness 0.25)
		(keepout
			(tracks not_allowed)
			(vias allowed)
			(pads allowed)
			(copperpour not_allowed)
			(footprints allowed)
		)
		(placement
			(enabled no)
			(sheetname "")
		)
		(fill
			(thermal_gap 0.5)
			(thermal_bridge_width 0.5)
			(island_removal_mode 0)
		)
		(polygon
			(pts
				(arc
					(start 136.733788 -354.351082)
					(mid 136.352788 -354.732082)
					(end 136.733788 -355.113082)
				)
				(arc
					(start 137.597388 -355.113082)
					(mid 137.978388 -354.732082)
					(end 137.597388 -354.351082)
				)
			)
		)
	)
	(zone
		(layers "F.Cu" "B.Cu" "In1.Cu" "In2.Cu" "In3.Cu" "In4.Cu" "In5.Cu" "In6.Cu"
			"In7.Cu" "In8.Cu" "In9.Cu" "In10.Cu" "In11.Cu" "In12.Cu" "In13.Cu" "In14.Cu"
			"In15.Cu" "In16.Cu"
		)
		(hatch none 0.5)
		(connect_pads
			(clearance 0)
		)
		(min_thickness 0.25)
		(keepout
			(tracks not_allowed)
			(vias allowed)
			(pads allowed)
			(copperpour not_allowed)
			(footprints allowed)
		)
		(placement
			(enabled no)
			(sheetname "")
		)
		(fill
			(thermal_gap 0.5)
			(thermal_bridge_width 0.5)
			(island_removal_mode 0)
		)
		(polygon
			(pts
				(arc
					(start 54.891178 -363.334808)
					(mid 55.348378 -363.792008)
					(end 55.805578 -363.334808)
				)
				(arc
					(start 55.805578 -362.471208)
					(mid 55.348378 -362.014008)
					(end 54.891178 -362.471208)
				)
			)
		)
	)
	(zone
		(layers "F.Cu" "B.Cu" "In1.Cu" "In2.Cu" "In3.Cu" "In4.Cu" "In5.Cu" "In6.Cu"
			"In7.Cu" "In8.Cu" "In9.Cu" "In10.Cu" "In11.Cu" "In12.Cu" "In13.Cu" "In14.Cu"
			"In15.Cu" "In16.Cu"
		)
		(hatch none 0.5)
		(connect_pads
			(clearance 0)
		)
		(min_thickness 0.25)
		(keepout
			(tracks not_allowed)
			(vias allowed)
			(pads allowed)
			(copperpour not_allowed)
			(footprints allowed)
		)
		(placement
			(enabled no)
			(sheetname "")
		)
		(fill
			(thermal_gap 0.5)
			(thermal_bridge_width 0.5)
			(island_removal_mode 0)
		)
		(polygon
			(pts
				(arc
					(start 289.280854 -378.828554)
					(mid 289.295733 -378.792633)
					(end 289.331654 -378.777754)
				)
				(arc
					(start 290.047934 -378.777754)
					(mid 290.083855 -378.792633)
					(end 290.098734 -378.828554)
				)
				(arc
					(start 290.098734 -381.251206)
					(mid 290.083855 -381.287127)
					(end 290.047934 -381.302006)
				)
				(arc
					(start 289.331654 -381.302006)
					(mid 289.295733 -381.287127)
					(end 289.280854 -381.251206)
				)
			)
		)
	)
	(zone
		(layers "F.Cu" "B.Cu" "In1.Cu" "In2.Cu" "In3.Cu" "In4.Cu" "In5.Cu" "In6.Cu"
			"In7.Cu" "In8.Cu" "In9.Cu" "In10.Cu" "In11.Cu" "In12.Cu" "In13.Cu" "In14.Cu"
			"In15.Cu" "In16.Cu"
		)
		(hatch none 0.5)
		(connect_pads
			(clearance 0)
		)
		(min_thickness 0.25)
		(keepout
			(tracks not_allowed)
			(vias allowed)
			(pads allowed)
			(copperpour not_allowed)
			(footprints allowed)
		)
		(placement
			(enabled no)
			(sheetname "")
		)
		(fill
			(thermal_gap 0.5)
			(thermal_bridge_width 0.5)
			(island_removal_mode 0)
		)
		(polygon
			(pts
				(arc
					(start 187.057792 -345.084146)
					(mid 186.676792 -345.465146)
					(end 187.057792 -345.846146)
				)
				(arc
					(start 187.921392 -345.846146)
					(mid 188.302392 -345.465146)
					(end 187.921392 -345.084146)
				)
			)
		)
	)
	(zone
		(layers "F.Cu" "B.Cu" "In1.Cu" "In2.Cu" "In3.Cu" "In4.Cu" "In5.Cu" "In6.Cu"
			"In7.Cu" "In8.Cu" "In9.Cu" "In10.Cu" "In11.Cu" "In12.Cu" "In13.Cu" "In14.Cu"
			"In15.Cu" "In16.Cu"
		)
		(hatch none 0.5)
		(connect_pads
			(clearance 0)
		)
		(min_thickness 0.25)
		(keepout
			(tracks not_allowed)
			(vias allowed)
			(pads allowed)
			(copperpour not_allowed)
			(footprints allowed)
		)
		(placement
			(enabled no)
			(sheetname "")
		)
		(fill
			(thermal_gap 0.5)
			(thermal_bridge_width 0.5)
			(island_removal_mode 0)
		)
		(polygon
			(pts
				(arc
					(start 298.986702 -351.230438)
					(mid 298.605702 -351.611438)
					(end 298.986702 -351.992438)
				)
				(arc
					(start 299.850302 -351.992438)
					(mid 300.231302 -351.611438)
					(end 299.850302 -351.230438)
				)
			)
		)
	)
	(zone
		(layers "F.Cu" "B.Cu" "In1.Cu" "In2.Cu" "In3.Cu" "In4.Cu" "In5.Cu" "In6.Cu"
			"In7.Cu" "In8.Cu" "In9.Cu" "In10.Cu" "In11.Cu" "In12.Cu" "In13.Cu" "In14.Cu"
			"In15.Cu" "In16.Cu"
		)
		(hatch none 0.5)
		(connect_pads
			(clearance 0)
		)
		(min_thickness 0.25)
		(keepout
			(tracks not_allowed)
			(vias allowed)
			(pads allowed)
			(copperpour not_allowed)
			(footprints allowed)
		)
		(placement
			(enabled no)
			(sheetname "")
		)
		(fill
			(thermal_gap 0.5)
			(thermal_bridge_width 0.5)
			(island_removal_mode 0)
		)
		(polygon
			(pts
				(arc
					(start 379.48108 -399.828766)
					(mid 379.495959 -399.792845)
					(end 379.53188 -399.777966)
				)
				(arc
					(start 380.24816 -399.777966)
					(mid 380.284081 -399.792845)
					(end 380.29896 -399.828766)
				)
				(arc
					(start 380.29896 -402.251418)
					(mid 380.284081 -402.287339)
					(end 380.24816 -402.302218)
				)
				(arc
					(start 379.53188 -402.302218)
					(mid 379.495959 -402.287339)
					(end 379.48108 -402.251418)
				)
			)
		)
	)
	(zone
		(layers "F.Cu" "B.Cu" "In1.Cu" "In2.Cu" "In3.Cu" "In4.Cu" "In5.Cu" "In6.Cu"
			"In7.Cu" "In8.Cu" "In9.Cu" "In10.Cu" "In11.Cu" "In12.Cu" "In13.Cu" "In14.Cu"
			"In15.Cu" "In16.Cu"
		)
		(hatch none 0.5)
		(connect_pads
			(clearance 0)
		)
		(min_thickness 0.25)
		(keepout
			(tracks not_allowed)
			(vias allowed)
			(pads allowed)
			(copperpour not_allowed)
			(footprints allowed)
		)
		(placement
			(enabled no)
			(sheetname "")
		)
		(fill
			(thermal_gap 0.5)
			(thermal_bridge_width 0.5)
			(island_removal_mode 0)
		)
		(polygon
			(pts
				(arc
					(start 70.699122 -348.20479)
					(mid 70.318122 -348.58579)
					(end 70.699122 -348.96679)
				)
				(arc
					(start 71.562722 -348.96679)
					(mid 71.943722 -348.58579)
					(end 71.562722 -348.20479)
				)
			)
		)
	)
	(zone
		(layers "F.Cu" "B.Cu" "In1.Cu" "In2.Cu" "In3.Cu" "In4.Cu" "In5.Cu" "In6.Cu"
			"In7.Cu" "In8.Cu" "In9.Cu" "In10.Cu" "In11.Cu" "In12.Cu" "In13.Cu" "In14.Cu"
			"In15.Cu" "In16.Cu"
		)
		(hatch none 0.5)
		(connect_pads
			(clearance 0)
		)
		(min_thickness 0.25)
		(keepout
			(tracks not_allowed)
			(vias allowed)
			(pads allowed)
			(copperpour not_allowed)
			(footprints allowed)
		)
		(placement
			(enabled no)
			(sheetname "")
		)
		(fill
			(thermal_gap 0.5)
			(thermal_bridge_width 0.5)
			(island_removal_mode 0)
		)
		(polygon
			(pts
				(arc
					(start 52.69992 -104.71277)
					(mid 52.24272 -104.25557)
					(end 51.78552 -104.71277)
				)
				(arc
					(start 51.78552 -105.57637)
					(mid 52.24272 -106.03357)
					(end 52.69992 -105.57637)
				)
			)
		)
	)
	(zone
		(layers "F.Cu" "B.Cu" "In1.Cu" "In2.Cu" "In3.Cu" "In4.Cu" "In5.Cu" "In6.Cu"
			"In7.Cu" "In8.Cu" "In9.Cu" "In10.Cu" "In11.Cu" "In12.Cu" "In13.Cu" "In14.Cu"
			"In15.Cu" "In16.Cu"
		)
		(hatch none 0.5)
		(connect_pads
			(clearance 0)
		)
		(min_thickness 0.25)
		(keepout
			(tracks not_allowed)
			(vias allowed)
			(pads allowed)
			(copperpour not_allowed)
			(footprints allowed)
		)
		(placement
			(enabled no)
			(sheetname "")
		)
		(fill
			(thermal_gap 0.5)
			(thermal_bridge_width 0.5)
			(island_removal_mode 0)
		)
		(polygon
			(pts
				(arc
					(start 385.610608 -107.377738)
					(mid 386.067808 -107.834938)
					(end 386.525008 -107.377738)
				)
				(arc
					(start 386.525008 -106.514138)
					(mid 386.067808 -106.056938)
					(end 385.610608 -106.514138)
				)
			)
		)
	)
	(zone
		(layers "F.Cu" "B.Cu" "In1.Cu" "In2.Cu" "In3.Cu" "In4.Cu" "In5.Cu" "In6.Cu"
			"In7.Cu" "In8.Cu" "In9.Cu" "In10.Cu" "In11.Cu" "In12.Cu" "In13.Cu" "In14.Cu"
			"In15.Cu" "In16.Cu"
		)
		(hatch none 0.5)
		(connect_pads
			(clearance 0)
		)
		(min_thickness 0.25)
		(keepout
			(tracks not_allowed)
			(vias allowed)
			(pads allowed)
			(copperpour not_allowed)
			(footprints allowed)
		)
		(placement
			(enabled no)
			(sheetname "")
		)
		(fill
			(thermal_gap 0.5)
			(thermal_bridge_width 0.5)
			(island_removal_mode 0)
		)
		(polygon
			(pts
				(arc
					(start 318.807338 -29.12237)
					(mid 319.264538 -29.57957)
					(end 319.721738 -29.12237)
				)
				(arc
					(start 319.721738 -28.25877)
					(mid 319.264538 -27.80157)
					(end 318.807338 -28.25877)
				)
			)
		)
	)
	(zone
		(layers "F.Cu" "B.Cu" "In1.Cu" "In2.Cu" "In3.Cu" "In4.Cu" "In5.Cu" "In6.Cu"
			"In7.Cu" "In8.Cu" "In9.Cu" "In10.Cu" "In11.Cu" "In12.Cu" "In13.Cu" "In14.Cu"
			"In15.Cu" "In16.Cu"
		)
		(hatch none 0.5)
		(connect_pads
			(clearance 0)
		)
		(min_thickness 0.25)
		(keepout
			(tracks not_allowed)
			(vias allowed)
			(pads allowed)
			(copperpour not_allowed)
			(footprints allowed)
		)
		(placement
			(enabled no)
			(sheetname "")
		)
		(fill
			(thermal_gap 0.5)
			(thermal_bridge_width 0.5)
			(island_removal_mode 0)
		)
		(polygon
			(pts
				(arc
					(start 369.790218 -30.92069)
					(mid 370.247418 -31.37789)
					(end 370.704618 -30.92069)
				)
				(arc
					(start 370.704618 -30.05709)
					(mid 370.247418 -29.59989)
					(end 369.790218 -30.05709)
				)
			)
		)
	)
	(zone
		(layers "F.Cu" "B.Cu" "In1.Cu" "In2.Cu" "In3.Cu" "In4.Cu" "In5.Cu" "In6.Cu"
			"In7.Cu" "In8.Cu" "In9.Cu" "In10.Cu" "In11.Cu" "In12.Cu" "In13.Cu" "In14.Cu"
			"In15.Cu" "In16.Cu"
		)
		(hatch none 0.5)
		(connect_pads
			(clearance 0)
		)
		(min_thickness 0.25)
		(keepout
			(tracks not_allowed)
			(vias allowed)
			(pads allowed)
			(copperpour not_allowed)
			(footprints allowed)
		)
		(placement
			(enabled no)
			(sheetname "")
		)
		(fill
			(thermal_gap 0.5)
			(thermal_bridge_width 0.5)
			(island_removal_mode 0)
		)
		(polygon
			(pts
				(arc
					(start 337.374484 -345.084146)
					(mid 336.993484 -345.465146)
					(end 337.374484 -345.846146)
				)
				(arc
					(start 338.238084 -345.846146)
					(mid 338.619084 -345.465146)
					(end 338.238084 -345.084146)
				)
			)
		)
	)
	(zone
		(layers "F.Cu" "B.Cu" "In1.Cu" "In2.Cu" "In3.Cu" "In4.Cu" "In5.Cu" "In6.Cu"
			"In7.Cu" "In8.Cu" "In9.Cu" "In10.Cu" "In11.Cu" "In12.Cu" "In13.Cu" "In14.Cu"
			"In15.Cu" "In16.Cu"
		)
		(hatch none 0.5)
		(connect_pads
			(clearance 0)
		)
		(min_thickness 0.25)
		(keepout
			(tracks not_allowed)
			(vias allowed)
			(pads allowed)
			(copperpour not_allowed)
			(footprints allowed)
		)
		(placement
			(enabled no)
			(sheetname "")
		)
		(fill
			(thermal_gap 0.5)
			(thermal_bridge_width 0.5)
			(island_removal_mode 0)
		)
		(polygon
			(pts
				(arc
					(start 413.04591 -132.577332)
					(mid 413.50311 -133.034532)
					(end 413.96031 -132.577332)
				)
				(arc
					(start 413.96031 -131.713732)
					(mid 413.50311 -131.256532)
					(end 413.04591 -131.713732)
				)
			)
		)
	)
	(zone
		(layers "F.Cu" "B.Cu" "In1.Cu" "In2.Cu" "In3.Cu" "In4.Cu" "In5.Cu" "In6.Cu"
			"In7.Cu" "In8.Cu" "In9.Cu" "In10.Cu" "In11.Cu" "In12.Cu" "In13.Cu" "In14.Cu"
			"In15.Cu" "In16.Cu"
		)
		(hatch none 0.5)
		(connect_pads
			(clearance 0)
		)
		(min_thickness 0.25)
		(keepout
			(tracks not_allowed)
			(vias allowed)
			(pads allowed)
			(copperpour not_allowed)
			(footprints allowed)
		)
		(placement
			(enabled no)
			(sheetname "")
		)
		(fill
			(thermal_gap 0.5)
			(thermal_bridge_width 0.5)
			(island_removal_mode 0)
		)
		(polygon
			(pts
				(arc
					(start 295.881044 -369.928902)
					(mid 295.895923 -369.892981)
					(end 295.931844 -369.878102)
				)
				(arc
					(start 296.648124 -369.878102)
					(mid 296.684045 -369.892981)
					(end 296.698924 -369.928902)
				)
				(arc
					(start 296.698924 -372.351554)
					(mid 296.684045 -372.387475)
					(end 296.648124 -372.402354)
				)
				(arc
					(start 295.931844 -372.402354)
					(mid 295.895923 -372.387475)
					(end 295.881044 -372.351554)
				)
			)
		)
	)
	(zone
		(layers "F.Cu" "B.Cu" "In1.Cu" "In2.Cu" "In3.Cu" "In4.Cu" "In5.Cu" "In6.Cu"
			"In7.Cu" "In8.Cu" "In9.Cu" "In10.Cu" "In11.Cu" "In12.Cu" "In13.Cu" "In14.Cu"
			"In15.Cu" "In16.Cu"
		)
		(hatch none 0.5)
		(connect_pads
			(clearance 0)
		)
		(min_thickness 0.25)
		(keepout
			(tracks not_allowed)
			(vias allowed)
			(pads allowed)
			(copperpour not_allowed)
			(footprints allowed)
		)
		(placement
			(enabled no)
			(sheetname "")
		)
		(fill
			(thermal_gap 0.5)
			(thermal_bridge_width 0.5)
			(island_removal_mode 0)
		)
		(polygon
			(pts
				(arc
					(start 376.78487 21.000212)
					(mid 376.40387 21.381212)
					(end 376.02287 21.000212)
				)
				(arc
					(start 376.02287 20.136612)
					(mid 376.40387 19.755612)
					(end 376.78487 20.136612)
				)
			)
		)
	)
	(zone
		(layers "F.Cu" "B.Cu" "In1.Cu" "In2.Cu" "In3.Cu" "In4.Cu" "In5.Cu" "In6.Cu"
			"In7.Cu" "In8.Cu" "In9.Cu" "In10.Cu" "In11.Cu" "In12.Cu" "In13.Cu" "In14.Cu"
			"In15.Cu" "In16.Cu"
		)
		(hatch none 0.5)
		(connect_pads
			(clearance 0)
		)
		(min_thickness 0.25)
		(keepout
			(tracks not_allowed)
			(vias allowed)
			(pads allowed)
			(copperpour not_allowed)
			(footprints allowed)
		)
		(placement
			(enabled no)
			(sheetname "")
		)
		(fill
			(thermal_gap 0.5)
			(thermal_bridge_width 0.5)
			(island_removal_mode 0)
		)
		(polygon
			(pts
				(arc
					(start 134.948168 -32.714184)
					(mid 135.405368 -33.171384)
					(end 135.862568 -32.714184)
				)
				(arc
					(start 135.862568 -31.850584)
					(mid 135.405368 -31.393384)
					(end 134.948168 -31.850584)
				)
			)
		)
	)
	(zone
		(layers "F.Cu" "B.Cu" "In1.Cu" "In2.Cu" "In3.Cu" "In4.Cu" "In5.Cu" "In6.Cu"
			"In7.Cu" "In8.Cu" "In9.Cu" "In10.Cu" "In11.Cu" "In12.Cu" "In13.Cu" "In14.Cu"
			"In15.Cu" "In16.Cu"
		)
		(hatch none 0.5)
		(connect_pads
			(clearance 0)
		)
		(min_thickness 0.25)
		(keepout
			(tracks not_allowed)
			(vias allowed)
			(pads allowed)
			(copperpour not_allowed)
			(footprints allowed)
		)
		(placement
			(enabled no)
			(sheetname "")
		)
		(fill
			(thermal_gap 0.5)
			(thermal_bridge_width 0.5)
			(island_removal_mode 0)
		)
		(polygon
			(pts
				(arc
					(start 40.70096 -395.92885)
					(mid 40.715839 -395.892929)
					(end 40.75176 -395.87805)
				)
				(arc
					(start 41.46804 -395.87805)
					(mid 41.503961 -395.892929)
					(end 41.51884 -395.92885)
				)
				(arc
					(start 41.51884 -398.351502)
					(mid 41.503961 -398.387423)
					(end 41.46804 -398.402302)
				)
				(arc
					(start 40.75176 -398.402302)
					(mid 40.715839 -398.387423)
					(end 40.70096 -398.351502)
				)
			)
		)
	)
	(zone
		(layers "F.Cu" "B.Cu" "In1.Cu" "In2.Cu" "In3.Cu" "In4.Cu" "In5.Cu" "In6.Cu"
			"In7.Cu" "In8.Cu" "In9.Cu" "In10.Cu" "In11.Cu" "In12.Cu" "In13.Cu" "In14.Cu"
			"In15.Cu" "In16.Cu"
		)
		(hatch none 0.5)
		(connect_pads
			(clearance 0)
		)
		(min_thickness 0.25)
		(keepout
			(tracks not_allowed)
			(vias allowed)
			(pads allowed)
			(copperpour not_allowed)
			(footprints allowed)
		)
		(placement
			(enabled no)
			(sheetname "")
		)
		(fill
			(thermal_gap 0.5)
			(thermal_bridge_width 0.5)
			(island_removal_mode 0)
		)
		(polygon
			(pts
				(arc
					(start 380.51486 -351.230438)
					(mid 380.13386 -351.611438)
					(end 380.51486 -351.992438)
				)
				(arc
					(start 381.37846 -351.992438)
					(mid 381.75946 -351.611438)
					(end 381.37846 -351.230438)
				)
			)
		)
	)
	(zone
		(layers "F.Cu" "B.Cu" "In1.Cu" "In2.Cu" "In3.Cu" "In4.Cu" "In5.Cu" "In6.Cu"
			"In7.Cu" "In8.Cu" "In9.Cu" "In10.Cu" "In11.Cu" "In12.Cu" "In13.Cu" "In14.Cu"
			"In15.Cu" "In16.Cu"
		)
		(hatch none 0.5)
		(connect_pads
			(clearance 0)
		)
		(min_thickness 0.25)
		(keepout
			(tracks not_allowed)
			(vias allowed)
			(pads allowed)
			(copperpour not_allowed)
			(footprints allowed)
		)
		(placement
			(enabled no)
			(sheetname "")
		)
		(fill
			(thermal_gap 0.5)
			(thermal_bridge_width 0.5)
			(island_removal_mode 0)
		)
		(polygon
			(pts
				(arc
					(start 21.490178 -30.92069)
					(mid 21.947378 -31.37789)
					(end 22.404578 -30.92069)
				)
				(arc
					(start 22.404578 -30.05709)
					(mid 21.947378 -29.59989)
					(end 21.490178 -30.05709)
				)
			)
		)
	)
	(zone
		(layers "F.Cu" "B.Cu" "In1.Cu" "In2.Cu" "In3.Cu" "In4.Cu" "In5.Cu" "In6.Cu"
			"In7.Cu" "In8.Cu" "In9.Cu" "In10.Cu" "In11.Cu" "In12.Cu" "In13.Cu" "In14.Cu"
			"In15.Cu" "In16.Cu"
		)
		(hatch none 0.5)
		(connect_pads
			(clearance 0)
		)
		(min_thickness 0.25)
		(keepout
			(tracks not_allowed)
			(vias allowed)
			(pads allowed)
			(copperpour not_allowed)
			(footprints allowed)
		)
		(placement
			(enabled no)
			(sheetname "")
		)
		(fill
			(thermal_gap 0.5)
			(thermal_bridge_width 0.5)
			(island_removal_mode 0)
		)
		(polygon
			(pts
				(arc
					(start 458.028294 11.147552)
					(mid 457.647294 11.528552)
					(end 457.266294 11.147552)
				)
				(arc
					(start 457.266294 10.283952)
					(mid 457.647294 9.902952)
					(end 458.028294 10.283952)
				)
			)
		)
	)
	(zone
		(layers "F.Cu" "B.Cu" "In1.Cu" "In2.Cu" "In3.Cu" "In4.Cu" "In5.Cu" "In6.Cu"
			"In7.Cu" "In8.Cu" "In9.Cu" "In10.Cu" "In11.Cu" "In12.Cu" "In13.Cu" "In14.Cu"
			"In15.Cu" "In16.Cu"
		)
		(hatch none 0.5)
		(connect_pads
			(clearance 0)
		)
		(min_thickness 0.25)
		(keepout
			(tracks not_allowed)
			(vias allowed)
			(pads allowed)
			(copperpour not_allowed)
			(footprints allowed)
		)
		(placement
			(enabled no)
			(sheetname "")
		)
		(fill
			(thermal_gap 0.5)
			(thermal_bridge_width 0.5)
			(island_removal_mode 0)
		)
		(polygon
			(pts
				(arc
					(start 402.85416 -102.912672)
					(mid 402.39696 -102.455472)
					(end 401.93976 -102.912672)
				)
				(arc
					(start 401.93976 -103.776272)
					(mid 402.39696 -104.233472)
					(end 402.85416 -103.776272)
				)
			)
		)
	)
	(zone
		(layers "F.Cu" "B.Cu" "In1.Cu" "In2.Cu" "In3.Cu" "In4.Cu" "In5.Cu" "In6.Cu"
			"In7.Cu" "In8.Cu" "In9.Cu" "In10.Cu" "In11.Cu" "In12.Cu" "In13.Cu" "In14.Cu"
			"In15.Cu" "In16.Cu"
		)
		(hatch none 0.5)
		(connect_pads
			(clearance 0)
		)
		(min_thickness 0.25)
		(keepout
			(tracks not_allowed)
			(vias allowed)
			(pads allowed)
			(copperpour not_allowed)
			(footprints allowed)
		)
		(placement
			(enabled no)
			(sheetname "")
		)
		(fill
			(thermal_gap 0.5)
			(thermal_bridge_width 0.5)
			(island_removal_mode 0)
		)
		(polygon
			(pts
				(arc
					(start 40.70096 -373.828818)
					(mid 40.715839 -373.792897)
					(end 40.75176 -373.778018)
				)
				(arc
					(start 41.46804 -373.778018)
					(mid 41.503961 -373.792897)
					(end 41.51884 -373.828818)
				)
				(arc
					(start 41.51884 -376.25147)
					(mid 41.503961 -376.287391)
					(end 41.46804 -376.30227)
				)
				(arc
					(start 40.75176 -376.30227)
					(mid 40.715839 -376.287391)
					(end 40.70096 -376.25147)
				)
			)
		)
	)
	(zone
		(layers "F.Cu" "B.Cu" "In1.Cu" "In2.Cu" "In3.Cu" "In4.Cu" "In5.Cu" "In6.Cu"
			"In7.Cu" "In8.Cu" "In9.Cu" "In10.Cu" "In11.Cu" "In12.Cu" "In13.Cu" "In14.Cu"
			"In15.Cu" "In16.Cu"
		)
		(hatch none 0.5)
		(connect_pads
			(clearance 0)
		)
		(min_thickness 0.25)
		(keepout
			(tracks not_allowed)
			(vias allowed)
			(pads allowed)
			(copperpour not_allowed)
			(footprints allowed)
		)
		(placement
			(enabled no)
			(sheetname "")
		)
		(fill
			(thermal_gap 0.5)
			(thermal_bridge_width 0.5)
			(island_removal_mode 0)
		)
		(polygon
			(pts
				(arc
					(start 127.406908 -354.351082)
					(mid 127.025908 -354.732082)
					(end 127.406908 -355.113082)
				)
				(arc
					(start 128.270508 -355.113082)
					(mid 128.651508 -354.732082)
					(end 128.270508 -354.351082)
				)
			)
		)
	)
	(zone
		(layers "F.Cu" "B.Cu" "In1.Cu" "In2.Cu" "In3.Cu" "In4.Cu" "In5.Cu" "In6.Cu"
			"In7.Cu" "In8.Cu" "In9.Cu" "In10.Cu" "In11.Cu" "In12.Cu" "In13.Cu" "In14.Cu"
			"In15.Cu" "In16.Cu"
		)
		(hatch none 0.5)
		(connect_pads
			(clearance 0)
		)
		(min_thickness 0.25)
		(keepout
			(tracks not_allowed)
			(vias allowed)
			(pads allowed)
			(copperpour not_allowed)
			(footprints allowed)
		)
		(placement
			(enabled no)
			(sheetname "")
		)
		(fill
			(thermal_gap 0.5)
			(thermal_bridge_width 0.5)
			(island_removal_mode 0)
		)
		(polygon
			(pts
				(arc
					(start 382.9685 -134.897876)
					(mid 383.4257 -135.355076)
					(end 383.8829 -134.897876)
				)
				(arc
					(start 383.8829 -134.034276)
					(mid 383.4257 -133.577076)
					(end 382.9685 -134.034276)
				)
			)
		)
	)
	(zone
		(layers "F.Cu" "B.Cu" "In1.Cu" "In2.Cu" "In3.Cu" "In4.Cu" "In5.Cu" "In6.Cu"
			"In7.Cu" "In8.Cu" "In9.Cu" "In10.Cu" "In11.Cu" "In12.Cu" "In13.Cu" "In14.Cu"
			"In15.Cu" "In16.Cu"
		)
		(hatch none 0.5)
		(connect_pads
			(clearance 0)
		)
		(min_thickness 0.25)
		(keepout
			(tracks not_allowed)
			(vias allowed)
			(pads allowed)
			(copperpour not_allowed)
			(footprints allowed)
		)
		(placement
			(enabled no)
			(sheetname "")
		)
		(fill
			(thermal_gap 0.5)
			(thermal_bridge_width 0.5)
			(island_removal_mode 0)
		)
		(polygon
			(pts
				(arc
					(start 180.839872 -345.084146)
					(mid 180.458872 -345.465146)
					(end 180.839872 -345.846146)
				)
				(arc
					(start 181.703472 -345.846146)
					(mid 182.084472 -345.465146)
					(end 181.703472 -345.084146)
				)
			)
		)
	)
	(zone
		(layers "F.Cu" "B.Cu" "In1.Cu" "In2.Cu" "In3.Cu" "In4.Cu" "In5.Cu" "In6.Cu"
			"In7.Cu" "In8.Cu" "In9.Cu" "In10.Cu" "In11.Cu" "In12.Cu" "In13.Cu" "In14.Cu"
			"In15.Cu" "In16.Cu"
		)
		(hatch none 0.5)
		(connect_pads
			(clearance 0)
		)
		(min_thickness 0.25)
		(keepout
			(tracks not_allowed)
			(vias allowed)
			(pads allowed)
			(copperpour not_allowed)
			(footprints allowed)
		)
		(placement
			(enabled no)
			(sheetname "")
		)
		(fill
			(thermal_gap 0.5)
			(thermal_bridge_width 0.5)
			(island_removal_mode 0)
		)
		(polygon
			(pts
				(arc
					(start 340.483444 -342.058498)
					(mid 340.102444 -342.439498)
					(end 340.483444 -342.820498)
				)
				(arc
					(start 341.347044 -342.820498)
					(mid 341.728044 -342.439498)
					(end 341.347044 -342.058498)
				)
			)
		)
	)
	(zone
		(layers "F.Cu" "B.Cu" "In1.Cu" "In2.Cu" "In3.Cu" "In4.Cu" "In5.Cu" "In6.Cu"
			"In7.Cu" "In8.Cu" "In9.Cu" "In10.Cu" "In11.Cu" "In12.Cu" "In13.Cu" "In14.Cu"
			"In15.Cu" "In16.Cu"
		)
		(hatch none 0.5)
		(connect_pads
			(clearance 0)
		)
		(min_thickness 0.25)
		(keepout
			(tracks not_allowed)
			(vias allowed)
			(pads allowed)
			(copperpour not_allowed)
			(footprints allowed)
		)
		(placement
			(enabled no)
			(sheetname "")
		)
		(fill
			(thermal_gap 0.5)
			(thermal_bridge_width 0.5)
			(island_removal_mode 0)
		)
		(polygon
			(pts
				(arc
					(start 52.69992 -124.622814)
					(mid 52.24272 -124.165614)
					(end 51.78552 -124.622814)
				)
				(arc
					(start 51.78552 -125.486414)
					(mid 52.24272 -125.943614)
					(end 52.69992 -125.486414)
				)
			)
		)
	)
	(zone
		(layers "F.Cu" "B.Cu" "In1.Cu" "In2.Cu" "In3.Cu" "In4.Cu" "In5.Cu" "In6.Cu"
			"In7.Cu" "In8.Cu" "In9.Cu" "In10.Cu" "In11.Cu" "In12.Cu" "In13.Cu" "In14.Cu"
			"In15.Cu" "In16.Cu"
		)
		(hatch none 0.5)
		(connect_pads
			(clearance 0)
		)
		(min_thickness 0.25)
		(keepout
			(tracks not_allowed)
			(vias allowed)
			(pads allowed)
			(copperpour not_allowed)
			(footprints allowed)
		)
		(placement
			(enabled no)
			(sheetname "")
		)
		(fill
			(thermal_gap 0.5)
			(thermal_bridge_width 0.5)
			(island_removal_mode 0)
		)
		(polygon
			(pts
				(arc
					(start 302.48098 -408.728672)
					(mid 302.495859 -408.692751)
					(end 302.53178 -408.677872)
				)
				(arc
					(start 303.24806 -408.677872)
					(mid 303.283981 -408.692751)
					(end 303.29886 -408.728672)
				)
				(arc
					(start 303.29886 -411.151324)
					(mid 303.283981 -411.187245)
					(end 303.24806 -411.202124)
				)
				(arc
					(start 302.53178 -411.202124)
					(mid 302.495859 -411.187245)
					(end 302.48098 -411.151324)
				)
			)
		)
	)
	(zone
		(layers "F.Cu" "B.Cu" "In1.Cu" "In2.Cu" "In3.Cu" "In4.Cu" "In5.Cu" "In6.Cu"
			"In7.Cu" "In8.Cu" "In9.Cu" "In10.Cu" "In11.Cu" "In12.Cu" "In13.Cu" "In14.Cu"
			"In15.Cu" "In16.Cu"
		)
		(hatch none 0.5)
		(connect_pads
			(clearance 0)
		)
		(min_thickness 0.25)
		(keepout
			(tracks not_allowed)
			(vias allowed)
			(pads allowed)
			(copperpour not_allowed)
			(footprints allowed)
		)
		(placement
			(enabled no)
			(sheetname "")
		)
		(fill
			(thermal_gap 0.5)
			(thermal_bridge_width 0.5)
			(island_removal_mode 0)
		)
		(polygon
			(pts
				(arc
					(start 73.700894 -371.028722)
					(mid 73.715773 -370.992801)
					(end 73.751694 -370.977922)
				)
				(arc
					(start 74.467974 -370.977922)
					(mid 74.503895 -370.992801)
					(end 74.518774 -371.028722)
				)
				(arc
					(start 74.518774 -373.451374)
					(mid 74.503895 -373.487295)
					(end 74.467974 -373.502174)
				)
				(arc
					(start 73.751694 -373.502174)
					(mid 73.715773 -373.487295)
					(end 73.700894 -373.451374)
				)
			)
		)
	)
	(zone
		(layers "F.Cu" "B.Cu" "In1.Cu" "In2.Cu" "In3.Cu" "In4.Cu" "In5.Cu" "In6.Cu"
			"In7.Cu" "In8.Cu" "In9.Cu" "In10.Cu" "In11.Cu" "In12.Cu" "In13.Cu" "In14.Cu"
			"In15.Cu" "In16.Cu"
		)
		(hatch none 0.5)
		(connect_pads
			(clearance 0)
		)
		(min_thickness 0.25)
		(keepout
			(tracks not_allowed)
			(vias allowed)
			(pads allowed)
			(copperpour not_allowed)
			(footprints allowed)
		)
		(placement
			(enabled no)
			(sheetname "")
		)
		(fill
			(thermal_gap 0.5)
			(thermal_bridge_width 0.5)
			(island_removal_mode 0)
		)
		(polygon
			(pts
				(arc
					(start 126.501144 -374.928638)
					(mid 126.516023 -374.892717)
					(end 126.551944 -374.877838)
				)
				(arc
					(start 127.268224 -374.877838)
					(mid 127.304145 -374.892717)
					(end 127.319024 -374.928638)
				)
				(arc
					(start 127.319024 -377.35129)
					(mid 127.304145 -377.387211)
					(end 127.268224 -377.40209)
				)
				(arc
					(start 126.551944 -377.40209)
					(mid 126.516023 -377.387211)
					(end 126.501144 -377.35129)
				)
			)
		)
	)
	(zone
		(layers "F.Cu" "B.Cu" "In1.Cu" "In2.Cu" "In3.Cu" "In4.Cu" "In5.Cu" "In6.Cu"
			"In7.Cu" "In8.Cu" "In9.Cu" "In10.Cu" "In11.Cu" "In12.Cu" "In13.Cu" "In14.Cu"
			"In15.Cu" "In16.Cu"
		)
		(hatch none 0.5)
		(connect_pads
			(clearance 0)
		)
		(min_thickness 0.25)
		(keepout
			(tracks not_allowed)
			(vias allowed)
			(pads allowed)
			(copperpour not_allowed)
			(footprints allowed)
		)
		(placement
			(enabled no)
			(sheetname "")
		)
		(fill
			(thermal_gap 0.5)
			(thermal_bridge_width 0.5)
			(island_removal_mode 0)
		)
		(polygon
			(pts
				(arc
					(start 380.51486 -354.351082)
					(mid 380.13386 -354.732082)
					(end 380.51486 -355.113082)
				)
				(arc
					(start 381.37846 -355.113082)
					(mid 381.75946 -354.732082)
					(end 381.37846 -354.351082)
				)
			)
		)
	)
	(zone
		(layers "F.Cu" "B.Cu" "In1.Cu" "In2.Cu" "In3.Cu" "In4.Cu" "In5.Cu" "In6.Cu"
			"In7.Cu" "In8.Cu" "In9.Cu" "In10.Cu" "In11.Cu" "In12.Cu" "In13.Cu" "In14.Cu"
			"In15.Cu" "In16.Cu"
		)
		(hatch none 0.5)
		(connect_pads
			(clearance 0)
		)
		(min_thickness 0.25)
		(keepout
			(tracks not_allowed)
			(vias allowed)
			(pads allowed)
			(copperpour not_allowed)
			(footprints allowed)
		)
		(placement
			(enabled no)
			(sheetname "")
		)
		(fill
			(thermal_gap 0.5)
			(thermal_bridge_width 0.5)
			(island_removal_mode 0)
		)
		(polygon
			(pts
				(arc
					(start 393.148058 -29.114242)
					(mid 393.605258 -29.571442)
					(end 394.062458 -29.114242)
				)
				(arc
					(start 394.062458 -28.250642)
					(mid 393.605258 -27.793442)
					(end 393.148058 -28.250642)
				)
			)
		)
	)
	(zone
		(layers "F.Cu" "B.Cu" "In1.Cu" "In2.Cu" "In3.Cu" "In4.Cu" "In5.Cu" "In6.Cu"
			"In7.Cu" "In8.Cu" "In9.Cu" "In10.Cu" "In11.Cu" "In12.Cu" "In13.Cu" "In14.Cu"
			"In15.Cu" "In16.Cu"
		)
		(hatch none 0.5)
		(connect_pads
			(clearance 0)
		)
		(min_thickness 0.25)
		(keepout
			(tracks not_allowed)
			(vias allowed)
			(pads allowed)
			(copperpour not_allowed)
			(footprints allowed)
		)
		(placement
			(enabled no)
			(sheetname "")
		)
		(fill
			(thermal_gap 0.5)
			(thermal_bridge_width 0.5)
			(island_removal_mode 0)
		)
		(polygon
			(pts
				(arc
					(start 73.700894 -408.728672)
					(mid 73.715773 -408.692751)
					(end 73.751694 -408.677872)
				)
				(arc
					(start 74.467974 -408.677872)
					(mid 74.503895 -408.692751)
					(end 74.518774 -408.728672)
				)
				(arc
					(start 74.518774 -411.151324)
					(mid 74.503895 -411.187245)
					(end 74.467974 -411.202124)
				)
				(arc
					(start 73.751694 -411.202124)
					(mid 73.715773 -411.187245)
					(end 73.700894 -411.151324)
				)
			)
		)
	)
	(zone
		(layers "F.Cu" "B.Cu" "In1.Cu" "In2.Cu" "In3.Cu" "In4.Cu" "In5.Cu" "In6.Cu"
			"In7.Cu" "In8.Cu" "In9.Cu" "In10.Cu" "In11.Cu" "In12.Cu" "In13.Cu" "In14.Cu"
			"In15.Cu" "In16.Cu"
		)
		(hatch none 0.5)
		(connect_pads
			(clearance 0)
		)
		(min_thickness 0.25)
		(keepout
			(tracks not_allowed)
			(vias allowed)
			(pads allowed)
			(copperpour not_allowed)
			(footprints allowed)
		)
		(placement
			(enabled no)
			(sheetname "")
		)
		(fill
			(thermal_gap 0.5)
			(thermal_bridge_width 0.5)
			(island_removal_mode 0)
		)
		(polygon
			(pts
				(arc
					(start 32.7533 -34.52241)
					(mid 33.2105 -34.97961)
					(end 33.6677 -34.52241)
				)
				(arc
					(start 33.6677 -33.65881)
					(mid 33.2105 -33.20161)
					(end 32.7533 -33.65881)
				)
			)
		)
	)
	(zone
		(layers "F.Cu" "B.Cu" "In1.Cu" "In2.Cu" "In3.Cu" "In4.Cu" "In5.Cu" "In6.Cu"
			"In7.Cu" "In8.Cu" "In9.Cu" "In10.Cu" "In11.Cu" "In12.Cu" "In13.Cu" "In14.Cu"
			"In15.Cu" "In16.Cu"
		)
		(hatch none 0.5)
		(connect_pads
			(clearance 0)
		)
		(min_thickness 0.25)
		(keepout
			(tracks not_allowed)
			(vias allowed)
			(pads allowed)
			(copperpour not_allowed)
			(footprints allowed)
		)
		(placement
			(enabled no)
			(sheetname "")
		)
		(fill
			(thermal_gap 0.5)
			(thermal_bridge_width 0.5)
			(island_removal_mode 0)
		)
		(polygon
			(pts
				(arc
					(start 344.280998 -381.628904)
					(mid 344.295877 -381.592983)
					(end 344.331798 -381.578104)
				)
				(arc
					(start 345.048078 -381.578104)
					(mid 345.083999 -381.592983)
					(end 345.098878 -381.628904)
				)
				(arc
					(start 345.098878 -384.051556)
					(mid 345.083999 -384.087477)
					(end 345.048078 -384.102356)
				)
				(arc
					(start 344.331798 -384.102356)
					(mid 344.295877 -384.087477)
					(end 344.280998 -384.051556)
				)
			)
		)
	)
	(zone
		(layers "F.Cu" "B.Cu" "In1.Cu" "In2.Cu" "In3.Cu" "In4.Cu" "In5.Cu" "In6.Cu"
			"In7.Cu" "In8.Cu" "In9.Cu" "In10.Cu" "In11.Cu" "In12.Cu" "In13.Cu" "In14.Cu"
			"In15.Cu" "In16.Cu"
		)
		(hatch none 0.5)
		(connect_pads
			(clearance 0)
		)
		(min_thickness 0.25)
		(keepout
			(tracks not_allowed)
			(vias allowed)
			(pads allowed)
			(copperpour not_allowed)
			(footprints allowed)
		)
		(placement
			(enabled no)
			(sheetname "")
		)
		(fill
			(thermal_gap 0.5)
			(thermal_bridge_width 0.5)
			(island_removal_mode 0)
		)
		(polygon
			(pts
				(arc
					(start 380.51486 -345.084146)
					(mid 380.13386 -345.465146)
					(end 380.51486 -345.846146)
				)
				(arc
					(start 381.37846 -345.846146)
					(mid 381.75946 -345.465146)
					(end 381.37846 -345.084146)
				)
			)
		)
	)
	(zone
		(layers "F.Cu" "B.Cu" "In1.Cu" "In2.Cu" "In3.Cu" "In4.Cu" "In5.Cu" "In6.Cu"
			"In7.Cu" "In8.Cu" "In9.Cu" "In10.Cu" "In11.Cu" "In12.Cu" "In13.Cu" "In14.Cu"
			"In15.Cu" "In16.Cu"
		)
		(hatch none 0.5)
		(connect_pads
			(clearance 0)
		)
		(min_thickness 0.25)
		(keepout
			(tracks not_allowed)
			(vias allowed)
			(pads allowed)
			(copperpour not_allowed)
			(footprints allowed)
		)
		(placement
			(enabled no)
			(sheetname "")
		)
		(fill
			(thermal_gap 0.5)
			(thermal_bridge_width 0.5)
			(island_removal_mode 0)
		)
		(polygon
			(pts
				(arc
					(start 386.73278 -354.351082)
					(mid 386.35178 -354.732082)
					(end 386.73278 -355.113082)
				)
				(arc
					(start 387.59638 -355.113082)
					(mid 387.97738 -354.732082)
					(end 387.59638 -354.351082)
				)
			)
		)
	)
	(zone
		(layers "F.Cu" "B.Cu" "In1.Cu" "In2.Cu" "In3.Cu" "In4.Cu" "In5.Cu" "In6.Cu"
			"In7.Cu" "In8.Cu" "In9.Cu" "In10.Cu" "In11.Cu" "In12.Cu" "In13.Cu" "In14.Cu"
			"In15.Cu" "In16.Cu"
		)
		(hatch none 0.5)
		(connect_pads
			(clearance 0)
		)
		(min_thickness 0.25)
		(keepout
			(tracks not_allowed)
			(vias allowed)
			(pads allowed)
			(copperpour not_allowed)
			(footprints allowed)
		)
		(placement
			(enabled no)
			(sheetname "")
		)
		(fill
			(thermal_gap 0.5)
			(thermal_bridge_width 0.5)
			(island_removal_mode 0)
		)
		(polygon
			(pts
				(arc
					(start 66.60007 -143.48714)
					(mid 67.05727 -143.94434)
					(end 67.51447 -143.48714)
				)
				(arc
					(start 67.51447 -142.62354)
					(mid 67.05727 -142.16634)
					(end 66.60007 -142.62354)
				)
			)
		)
	)
	(zone
		(layers "F.Cu" "B.Cu" "In1.Cu" "In2.Cu" "In3.Cu" "In4.Cu" "In5.Cu" "In6.Cu"
			"In7.Cu" "In8.Cu" "In9.Cu" "In10.Cu" "In11.Cu" "In12.Cu" "In13.Cu" "In14.Cu"
			"In15.Cu" "In16.Cu"
		)
		(hatch none 0.5)
		(connect_pads
			(clearance 0)
		)
		(min_thickness 0.25)
		(keepout
			(tracks not_allowed)
			(vias allowed)
			(pads allowed)
			(copperpour not_allowed)
			(footprints allowed)
		)
		(placement
			(enabled no)
			(sheetname "")
		)
		(fill
			(thermal_gap 0.5)
			(thermal_bridge_width 0.5)
			(island_removal_mode 0)
		)
		(polygon
			(pts
				(arc
					(start 286.754062 -134.032752)
					(mid 286.296862 -133.575552)
					(end 285.839662 -134.032752)
				)
				(arc
					(start 285.839662 -134.896352)
					(mid 286.296862 -135.353552)
					(end 286.754062 -134.896352)
				)
			)
		)
	)
	(zone
		(layers "F.Cu" "B.Cu" "In1.Cu" "In2.Cu" "In3.Cu" "In4.Cu" "In5.Cu" "In6.Cu"
			"In7.Cu" "In8.Cu" "In9.Cu" "In10.Cu" "In11.Cu" "In12.Cu" "In13.Cu" "In14.Cu"
			"In15.Cu" "In16.Cu"
		)
		(hatch none 0.5)
		(connect_pads
			(clearance 0)
		)
		(min_thickness 0.25)
		(keepout
			(tracks not_allowed)
			(vias allowed)
			(pads allowed)
			(copperpour not_allowed)
			(footprints allowed)
		)
		(placement
			(enabled no)
			(sheetname "")
		)
		(fill
			(thermal_gap 0.5)
			(thermal_bridge_width 0.5)
			(island_removal_mode 0)
		)
		(polygon
			(pts
				(arc
					(start 298.800012 -150.687278)
					(mid 299.257212 -151.144478)
					(end 299.714412 -150.687278)
				)
				(arc
					(start 299.714412 -149.823678)
					(mid 299.257212 -149.366478)
					(end 298.800012 -149.823678)
				)
			)
		)
	)
	(zone
		(layers "F.Cu" "B.Cu" "In1.Cu" "In2.Cu" "In3.Cu" "In4.Cu" "In5.Cu" "In6.Cu"
			"In7.Cu" "In8.Cu" "In9.Cu" "In10.Cu" "In11.Cu" "In12.Cu" "In13.Cu" "In14.Cu"
			"In15.Cu" "In16.Cu"
		)
		(hatch none 0.5)
		(connect_pads
			(clearance 0)
		)
		(min_thickness 0.25)
		(keepout
			(tracks not_allowed)
			(vias allowed)
			(pads allowed)
			(copperpour not_allowed)
			(footprints allowed)
		)
		(placement
			(enabled no)
			(sheetname "")
		)
		(fill
			(thermal_gap 0.5)
			(thermal_bridge_width 0.5)
			(island_removal_mode 0)
		)
		(polygon
			(pts
				(arc
					(start 271.006062 -342.058498)
					(mid 270.625062 -342.439498)
					(end 271.006062 -342.820498)
				)
				(arc
					(start 271.869662 -342.820498)
					(mid 272.250662 -342.439498)
					(end 271.869662 -342.058498)
				)
			)
		)
	)
	(zone
		(layers "F.Cu" "B.Cu" "In1.Cu" "In2.Cu" "In3.Cu" "In4.Cu" "In5.Cu" "In6.Cu"
			"In7.Cu" "In8.Cu" "In9.Cu" "In10.Cu" "In11.Cu" "In12.Cu" "In13.Cu" "In14.Cu"
			"In15.Cu" "In16.Cu"
		)
		(hatch none 0.5)
		(connect_pads
			(clearance 0)
		)
		(min_thickness 0.25)
		(keepout
			(tracks not_allowed)
			(vias allowed)
			(pads allowed)
			(copperpour not_allowed)
			(footprints allowed)
		)
		(placement
			(enabled no)
			(sheetname "")
		)
		(fill
			(thermal_gap 0.5)
			(thermal_bridge_width 0.5)
			(island_removal_mode 0)
		)
		(polygon
			(pts
				(arc
					(start 413.04591 -152.487376)
					(mid 413.50311 -152.944576)
					(end 413.96031 -152.487376)
				)
				(arc
					(start 413.96031 -151.623776)
					(mid 413.50311 -151.166576)
					(end 413.04591 -151.623776)
				)
			)
		)
	)
	(zone
		(layers "F.Cu" "B.Cu" "In1.Cu" "In2.Cu" "In3.Cu" "In4.Cu" "In5.Cu" "In6.Cu"
			"In7.Cu" "In8.Cu" "In9.Cu" "In10.Cu" "In11.Cu" "In12.Cu" "In13.Cu" "In14.Cu"
			"In15.Cu" "In16.Cu"
		)
		(hatch none 0.5)
		(connect_pads
			(clearance 0)
		)
		(min_thickness 0.25)
		(keepout
			(tracks not_allowed)
			(vias allowed)
			(pads allowed)
			(copperpour not_allowed)
			(footprints allowed)
		)
		(placement
			(enabled no)
			(sheetname "")
		)
		(fill
			(thermal_gap 0.5)
			(thermal_bridge_width 0.5)
			(island_removal_mode 0)
		)
		(polygon
			(pts
				(arc
					(start 425.680886 -371.028722)
					(mid 425.695765 -370.992801)
					(end 425.731686 -370.977922)
				)
				(arc
					(start 426.447966 -370.977922)
					(mid 426.483887 -370.992801)
					(end 426.498766 -371.028722)
				)
				(arc
					(start 426.498766 -373.451374)
					(mid 426.483887 -373.487295)
					(end 426.447966 -373.502174)
				)
				(arc
					(start 425.731686 -373.502174)
					(mid 425.695765 -373.487295)
					(end 425.680886 -373.451374)
				)
			)
		)
	)
	(zone
		(layers "F.Cu" "B.Cu" "In1.Cu" "In2.Cu" "In3.Cu" "In4.Cu" "In5.Cu" "In6.Cu"
			"In7.Cu" "In8.Cu" "In9.Cu" "In10.Cu" "In11.Cu" "In12.Cu" "In13.Cu" "In14.Cu"
			"In15.Cu" "In16.Cu"
		)
		(hatch none 0.5)
		(connect_pads
			(clearance 0)
		)
		(min_thickness 0.25)
		(keepout
			(tracks not_allowed)
			(vias allowed)
			(pads allowed)
			(copperpour not_allowed)
			(footprints allowed)
		)
		(placement
			(enabled no)
			(sheetname "")
		)
		(fill
			(thermal_gap 0.5)
			(thermal_bridge_width 0.5)
			(island_removal_mode 0)
		)
		(polygon
			(pts
				(arc
					(start 434.166772 -357.37673)
					(mid 433.785772 -357.75773)
					(end 434.166772 -358.13873)
				)
				(arc
					(start 435.030372 -358.13873)
					(mid 435.411372 -357.75773)
					(end 435.030372 -357.37673)
				)
			)
		)
	)
	(zone
		(layers "F.Cu" "B.Cu" "In1.Cu" "In2.Cu" "In3.Cu" "In4.Cu" "In5.Cu" "In6.Cu"
			"In7.Cu" "In8.Cu" "In9.Cu" "In10.Cu" "In11.Cu" "In12.Cu" "In13.Cu" "In14.Cu"
			"In15.Cu" "In16.Cu"
		)
		(hatch none 0.5)
		(connect_pads
			(clearance 0)
		)
		(min_thickness 0.25)
		(keepout
			(tracks not_allowed)
			(vias allowed)
			(pads allowed)
			(copperpour not_allowed)
			(footprints allowed)
		)
		(placement
			(enabled no)
			(sheetname "")
		)
		(fill
			(thermal_gap 0.5)
			(thermal_bridge_width 0.5)
			(island_removal_mode 0)
		)
		(polygon
			(pts
				(arc
					(start 34.877248 -354.351082)
					(mid 34.496248 -354.732082)
					(end 34.877248 -355.113082)
				)
				(arc
					(start 35.740848 -355.113082)
					(mid 36.121848 -354.732082)
					(end 35.740848 -354.351082)
				)
			)
		)
	)
	(zone
		(layers "F.Cu" "B.Cu" "In1.Cu" "In2.Cu" "In3.Cu" "In4.Cu" "In5.Cu" "In6.Cu"
			"In7.Cu" "In8.Cu" "In9.Cu" "In10.Cu" "In11.Cu" "In12.Cu" "In13.Cu" "In14.Cu"
			"In15.Cu" "In16.Cu"
		)
		(hatch none 0.5)
		(connect_pads
			(clearance 0)
		)
		(min_thickness 0.25)
		(keepout
			(tracks not_allowed)
			(vias allowed)
			(pads allowed)
			(copperpour not_allowed)
			(footprints allowed)
		)
		(placement
			(enabled no)
			(sheetname "")
		)
		(fill
			(thermal_gap 0.5)
			(thermal_bridge_width 0.5)
			(island_removal_mode 0)
		)
		(polygon
			(pts
				(arc
					(start 111.862108 -345.084146)
					(mid 111.481108 -345.465146)
					(end 111.862108 -345.846146)
				)
				(arc
					(start 112.725708 -345.846146)
					(mid 113.106708 -345.465146)
					(end 112.725708 -345.084146)
				)
			)
		)
	)
	(zone
		(layers "F.Cu" "B.Cu" "In1.Cu" "In2.Cu" "In3.Cu" "In4.Cu" "In5.Cu" "In6.Cu"
			"In7.Cu" "In8.Cu" "In9.Cu" "In10.Cu" "In11.Cu" "In12.Cu" "In13.Cu" "In14.Cu"
			"In15.Cu" "In16.Cu"
		)
		(hatch none 0.5)
		(connect_pads
			(clearance 0)
		)
		(min_thickness 0.25)
		(keepout
			(tracks not_allowed)
			(vias allowed)
			(pads allowed)
			(copperpour not_allowed)
			(footprints allowed)
		)
		(placement
			(enabled no)
			(sheetname "")
		)
		(fill
			(thermal_gap 0.5)
			(thermal_bridge_width 0.5)
			(island_removal_mode 0)
		)
		(polygon
			(pts
				(arc
					(start 421.280844 -397.028924)
					(mid 421.295723 -396.993003)
					(end 421.331644 -396.978124)
				)
				(arc
					(start 422.047924 -396.978124)
					(mid 422.083845 -396.993003)
					(end 422.098724 -397.028924)
				)
				(arc
					(start 422.098724 -399.451576)
					(mid 422.083845 -399.487497)
					(end 422.047924 -399.502376)
				)
				(arc
					(start 421.331644 -399.502376)
					(mid 421.295723 -399.487497)
					(end 421.280844 -399.451576)
				)
			)
		)
	)
	(zone
		(layers "F.Cu" "B.Cu" "In1.Cu" "In2.Cu" "In3.Cu" "In4.Cu" "In5.Cu" "In6.Cu"
			"In7.Cu" "In8.Cu" "In9.Cu" "In10.Cu" "In11.Cu" "In12.Cu" "In13.Cu" "In14.Cu"
			"In15.Cu" "In16.Cu"
		)
		(hatch none 0.5)
		(connect_pads
			(clearance 0)
		)
		(min_thickness 0.25)
		(keepout
			(tracks not_allowed)
			(vias allowed)
			(pads allowed)
			(copperpour not_allowed)
			(footprints allowed)
		)
		(placement
			(enabled no)
			(sheetname "")
		)
		(fill
			(thermal_gap 0.5)
			(thermal_bridge_width 0.5)
			(island_removal_mode 0)
		)
		(polygon
			(pts
				(arc
					(start 429.375062 -134.369302)
					(mid 429.832262 -134.826502)
					(end 430.289462 -134.369302)
				)
				(arc
					(start 430.289462 -133.505702)
					(mid 429.832262 -133.048502)
					(end 429.375062 -133.505702)
				)
			)
		)
	)
	(zone
		(layers "F.Cu" "B.Cu" "In1.Cu" "In2.Cu" "In3.Cu" "In4.Cu" "In5.Cu" "In6.Cu"
			"In7.Cu" "In8.Cu" "In9.Cu" "In10.Cu" "In11.Cu" "In12.Cu" "In13.Cu" "In14.Cu"
			"In15.Cu" "In16.Cu"
		)
		(hatch none 0.5)
		(connect_pads
			(clearance 0)
		)
		(min_thickness 0.25)
		(keepout
			(tracks not_allowed)
			(vias allowed)
			(pads allowed)
			(copperpour not_allowed)
			(footprints allowed)
		)
		(placement
			(enabled no)
			(sheetname "")
		)
		(fill
			(thermal_gap 0.5)
			(thermal_bridge_width 0.5)
			(island_removal_mode 0)
		)
		(polygon
			(pts
				(arc
					(start 115.87099 -330.66863)
					(mid 115.41379 -330.21143)
					(end 114.95659 -330.66863)
				)
				(arc
					(start 114.95659 -331.53223)
					(mid 115.41379 -331.98943)
					(end 115.87099 -331.53223)
				)
			)
		)
	)
	(zone
		(layers "F.Cu" "B.Cu" "In1.Cu" "In2.Cu" "In3.Cu" "In4.Cu" "In5.Cu" "In6.Cu"
			"In7.Cu" "In8.Cu" "In9.Cu" "In10.Cu" "In11.Cu" "In12.Cu" "In13.Cu" "In14.Cu"
			"In15.Cu" "In16.Cu"
		)
		(hatch none 0.5)
		(connect_pads
			(clearance 0)
		)
		(min_thickness 0.25)
		(keepout
			(tracks not_allowed)
			(vias allowed)
			(pads allowed)
			(copperpour not_allowed)
			(footprints allowed)
		)
		(placement
			(enabled no)
			(sheetname "")
		)
		(fill
			(thermal_gap 0.5)
			(thermal_bridge_width 0.5)
			(island_removal_mode 0)
		)
		(polygon
			(pts
				(arc
					(start 89.352882 -345.084146)
					(mid 88.971882 -345.465146)
					(end 89.352882 -345.846146)
				)
				(arc
					(start 90.216482 -345.846146)
					(mid 90.597482 -345.465146)
					(end 90.216482 -345.084146)
				)
			)
		)
	)
	(zone
		(layers "F.Cu" "B.Cu" "In1.Cu" "In2.Cu" "In3.Cu" "In4.Cu" "In5.Cu" "In6.Cu"
			"In7.Cu" "In8.Cu" "In9.Cu" "In10.Cu" "In11.Cu" "In12.Cu" "In13.Cu" "In14.Cu"
			"In15.Cu" "In16.Cu"
		)
		(hatch none 0.5)
		(connect_pads
			(clearance 0)
		)
		(min_thickness 0.25)
		(keepout
			(tracks not_allowed)
			(vias allowed)
			(pads allowed)
			(copperpour not_allowed)
			(footprints allowed)
		)
		(placement
			(enabled no)
			(sheetname "")
		)
		(fill
			(thermal_gap 0.5)
			(thermal_bridge_width 0.5)
			(island_removal_mode 0)
		)
		(polygon
			(pts
				(arc
					(start 334.864202 -78.425548)
					(mid 334.407002 -78.882748)
					(end 334.864202 -79.339948)
				)
				(arc
					(start 335.727802 -79.339948)
					(mid 336.185002 -78.882748)
					(end 335.727802 -78.425548)
				)
			)
		)
	)
	(zone
		(layers "F.Cu" "B.Cu" "In1.Cu" "In2.Cu" "In3.Cu" "In4.Cu" "In5.Cu" "In6.Cu"
			"In7.Cu" "In8.Cu" "In9.Cu" "In10.Cu" "In11.Cu" "In12.Cu" "In13.Cu" "In14.Cu"
			"In15.Cu" "In16.Cu"
		)
		(hatch none 0.5)
		(connect_pads
			(clearance 0)
		)
		(min_thickness 0.25)
		(keepout
			(tracks not_allowed)
			(vias allowed)
			(pads allowed)
			(copperpour not_allowed)
			(footprints allowed)
		)
		(placement
			(enabled no)
			(sheetname "")
		)
		(fill
			(thermal_gap 0.5)
			(thermal_bridge_width 0.5)
			(island_removal_mode 0)
		)
		(polygon
			(pts
				(arc
					(start 31.90113 -377.728734)
					(mid 31.916009 -377.692813)
					(end 31.95193 -377.677934)
				)
				(arc
					(start 32.66821 -377.677934)
					(mid 32.704131 -377.692813)
					(end 32.71901 -377.728734)
				)
				(arc
					(start 32.71901 -380.151386)
					(mid 32.704131 -380.187307)
					(end 32.66821 -380.202186)
				)
				(arc
					(start 31.95193 -380.202186)
					(mid 31.916009 -380.187307)
					(end 31.90113 -380.151386)
				)
			)
		)
	)
	(zone
		(layers "F.Cu" "B.Cu" "In1.Cu" "In2.Cu" "In3.Cu" "In4.Cu" "In5.Cu" "In6.Cu"
			"In7.Cu" "In8.Cu" "In9.Cu" "In10.Cu" "In11.Cu" "In12.Cu" "In13.Cu" "In14.Cu"
			"In15.Cu" "In16.Cu"
		)
		(hatch none 0.5)
		(connect_pads
			(clearance 0)
		)
		(min_thickness 0.25)
		(keepout
			(tracks not_allowed)
			(vias allowed)
			(pads allowed)
			(copperpour not_allowed)
			(footprints allowed)
		)
		(placement
			(enabled no)
			(sheetname "")
		)
		(fill
			(thermal_gap 0.5)
			(thermal_bridge_width 0.5)
			(island_removal_mode 0)
		)
		(polygon
			(pts
				(arc
					(start 130.901186 -404.828756)
					(mid 130.916065 -404.792835)
					(end 130.951986 -404.777956)
				)
				(arc
					(start 131.668266 -404.777956)
					(mid 131.704187 -404.792835)
					(end 131.719066 -404.828756)
				)
				(arc
					(start 131.719066 -407.251408)
					(mid 131.704187 -407.287329)
					(end 131.668266 -407.302208)
				)
				(arc
					(start 130.951986 -407.302208)
					(mid 130.916065 -407.287329)
					(end 130.901186 -407.251408)
				)
			)
		)
	)
	(zone
		(layers "F.Cu" "B.Cu" "In1.Cu" "In2.Cu" "In3.Cu" "In4.Cu" "In5.Cu" "In6.Cu"
			"In7.Cu" "In8.Cu" "In9.Cu" "In10.Cu" "In11.Cu" "In12.Cu" "In13.Cu" "In14.Cu"
			"In15.Cu" "In16.Cu"
		)
		(hatch none 0.5)
		(connect_pads
			(clearance 0)
		)
		(min_thickness 0.25)
		(keepout
			(tracks not_allowed)
			(vias allowed)
			(pads allowed)
			(copperpour not_allowed)
			(footprints allowed)
		)
		(placement
			(enabled no)
			(sheetname "")
		)
		(fill
			(thermal_gap 0.5)
			(thermal_bridge_width 0.5)
			(island_removal_mode 0)
		)
		(polygon
			(pts
				(arc
					(start 381.680974 -404.828756)
					(mid 381.695853 -404.792835)
					(end 381.731774 -404.777956)
				)
				(arc
					(start 382.448054 -404.777956)
					(mid 382.483975 -404.792835)
					(end 382.498854 -404.828756)
				)
				(arc
					(start 382.498854 -407.251408)
					(mid 382.483975 -407.287329)
					(end 382.448054 -407.302208)
				)
				(arc
					(start 381.731774 -407.302208)
					(mid 381.695853 -407.287329)
					(end 381.680974 -407.251408)
				)
			)
		)
	)
	(zone
		(layers "F.Cu" "B.Cu" "In1.Cu" "In2.Cu" "In3.Cu" "In4.Cu" "In5.Cu" "In6.Cu"
			"In7.Cu" "In8.Cu" "In9.Cu" "In10.Cu" "In11.Cu" "In12.Cu" "In13.Cu" "In14.Cu"
			"In15.Cu" "In16.Cu"
		)
		(hatch none 0.5)
		(connect_pads
			(clearance 0)
		)
		(min_thickness 0.25)
		(keepout
			(tracks not_allowed)
			(vias allowed)
			(pads allowed)
			(copperpour not_allowed)
			(footprints allowed)
		)
		(placement
			(enabled no)
			(sheetname "")
		)
		(fill
			(thermal_gap 0.5)
			(thermal_bridge_width 0.5)
			(island_removal_mode 0)
		)
		(polygon
			(pts
				(arc
					(start 295.881044 -381.628904)
					(mid 295.895923 -381.592983)
					(end 295.931844 -381.578104)
				)
				(arc
					(start 296.648124 -381.578104)
					(mid 296.684045 -381.592983)
					(end 296.698924 -381.628904)
				)
				(arc
					(start 296.698924 -384.051556)
					(mid 296.684045 -384.087477)
					(end 296.648124 -384.102356)
				)
				(arc
					(start 295.931844 -384.102356)
					(mid 295.895923 -384.087477)
					(end 295.881044 -384.051556)
				)
			)
		)
	)
	(zone
		(layers "F.Cu" "B.Cu" "In1.Cu" "In2.Cu" "In3.Cu" "In4.Cu" "In5.Cu" "In6.Cu"
			"In7.Cu" "In8.Cu" "In9.Cu" "In10.Cu" "In11.Cu" "In12.Cu" "In13.Cu" "In14.Cu"
			"In15.Cu" "In16.Cu"
		)
		(hatch none 0.5)
		(connect_pads
			(clearance 0)
		)
		(min_thickness 0.25)
		(keepout
			(tracks not_allowed)
			(vias allowed)
			(pads allowed)
			(copperpour not_allowed)
			(footprints allowed)
		)
		(placement
			(enabled no)
			(sheetname "")
		)
		(fill
			(thermal_gap 0.5)
			(thermal_bridge_width 0.5)
			(island_removal_mode 0)
		)
		(polygon
			(pts
				(arc
					(start 34.877248 -348.20479)
					(mid 34.496248 -348.58579)
					(end 34.877248 -348.96679)
				)
				(arc
					(start 35.740848 -348.96679)
					(mid 36.121848 -348.58579)
					(end 35.740848 -348.20479)
				)
			)
		)
	)
	(zone
		(layers "F.Cu" "B.Cu" "In1.Cu" "In2.Cu" "In3.Cu" "In4.Cu" "In5.Cu" "In6.Cu"
			"In7.Cu" "In8.Cu" "In9.Cu" "In10.Cu" "In11.Cu" "In12.Cu" "In13.Cu" "In14.Cu"
			"In15.Cu" "In16.Cu"
		)
		(hatch none 0.5)
		(connect_pads
			(clearance 0)
		)
		(min_thickness 0.25)
		(keepout
			(tracks not_allowed)
			(vias allowed)
			(pads allowed)
			(copperpour not_allowed)
			(footprints allowed)
		)
		(placement
			(enabled no)
			(sheetname "")
		)
		(fill
			(thermal_gap 0.5)
			(thermal_bridge_width 0.5)
			(island_removal_mode 0)
		)
		(polygon
			(pts
				(arc
					(start 38.501066 -400.92884)
					(mid 38.515945 -400.892919)
					(end 38.551866 -400.87804)
				)
				(arc
					(start 39.268146 -400.87804)
					(mid 39.304067 -400.892919)
					(end 39.318946 -400.92884)
				)
				(arc
					(start 39.318946 -403.351492)
					(mid 39.304067 -403.387413)
					(end 39.268146 -403.402292)
				)
				(arc
					(start 38.551866 -403.402292)
					(mid 38.515945 -403.387413)
					(end 38.501066 -403.351492)
				)
			)
		)
	)
	(zone
		(layers "F.Cu" "B.Cu" "In1.Cu" "In2.Cu" "In3.Cu" "In4.Cu" "In5.Cu" "In6.Cu"
			"In7.Cu" "In8.Cu" "In9.Cu" "In10.Cu" "In11.Cu" "In12.Cu" "In13.Cu" "In14.Cu"
			"In15.Cu" "In16.Cu"
		)
		(hatch none 0.5)
		(connect_pads
			(clearance 0)
		)
		(min_thickness 0.25)
		(keepout
			(tracks not_allowed)
			(vias allowed)
			(pads allowed)
			(copperpour not_allowed)
			(footprints allowed)
		)
		(placement
			(enabled no)
			(sheetname "")
		)
		(fill
			(thermal_gap 0.5)
			(thermal_bridge_width 0.5)
			(island_removal_mode 0)
		)
		(polygon
			(pts
				(arc
					(start 44.204128 -348.20479)
					(mid 43.823128 -348.58579)
					(end 44.204128 -348.96679)
				)
				(arc
					(start 45.067728 -348.96679)
					(mid 45.448728 -348.58579)
					(end 45.067728 -348.20479)
				)
			)
		)
	)
	(zone
		(layers "F.Cu" "B.Cu" "In1.Cu" "In2.Cu" "In3.Cu" "In4.Cu" "In5.Cu" "In6.Cu"
			"In7.Cu" "In8.Cu" "In9.Cu" "In10.Cu" "In11.Cu" "In12.Cu" "In13.Cu" "In14.Cu"
			"In15.Cu" "In16.Cu"
		)
		(hatch none 0.5)
		(connect_pads
			(clearance 0)
		)
		(min_thickness 0.25)
		(keepout
			(tracks not_allowed)
			(vias allowed)
			(pads allowed)
			(copperpour not_allowed)
			(footprints allowed)
		)
		(placement
			(enabled no)
			(sheetname "")
		)
		(fill
			(thermal_gap 0.5)
			(thermal_bridge_width 0.5)
			(island_removal_mode 0)
		)
		(polygon
			(pts
				(arc
					(start 163.90112 -377.728734)
					(mid 163.915999 -377.692813)
					(end 163.95192 -377.677934)
				)
				(arc
					(start 164.6682 -377.677934)
					(mid 164.704121 -377.692813)
					(end 164.719 -377.728734)
				)
				(arc
					(start 164.719 -380.151386)
					(mid 164.704121 -380.187307)
					(end 164.6682 -380.202186)
				)
				(arc
					(start 163.95192 -380.202186)
					(mid 163.915999 -380.187307)
					(end 163.90112 -380.151386)
				)
			)
		)
	)
	(zone
		(layers "F.Cu" "B.Cu" "In1.Cu" "In2.Cu" "In3.Cu" "In4.Cu" "In5.Cu" "In6.Cu"
			"In7.Cu" "In8.Cu" "In9.Cu" "In10.Cu" "In11.Cu" "In12.Cu" "In13.Cu" "In14.Cu"
			"In15.Cu" "In16.Cu"
		)
		(hatch none 0.5)
		(connect_pads
			(clearance 0)
		)
		(min_thickness 0.25)
		(keepout
			(tracks not_allowed)
			(vias allowed)
			(pads allowed)
			(copperpour not_allowed)
			(footprints allowed)
		)
		(placement
			(enabled no)
			(sheetname "")
		)
		(fill
			(thermal_gap 0.5)
			(thermal_bridge_width 0.5)
			(island_removal_mode 0)
		)
		(polygon
			(pts
				(arc
					(start 235.3183 -336.402426)
					(mid 234.8611 -335.945226)
					(end 234.4039 -336.402426)
				)
				(arc
					(start 234.4039 -337.266026)
					(mid 234.8611 -337.723226)
					(end 235.3183 -337.266026)
				)
			)
		)
	)
	(zone
		(layers "F.Cu" "B.Cu" "In1.Cu" "In2.Cu" "In3.Cu" "In4.Cu" "In5.Cu" "In6.Cu"
			"In7.Cu" "In8.Cu" "In9.Cu" "In10.Cu" "In11.Cu" "In12.Cu" "In13.Cu" "In14.Cu"
			"In15.Cu" "In16.Cu"
		)
		(hatch none 0.5)
		(connect_pads
			(clearance 0)
		)
		(min_thickness 0.25)
		(keepout
			(tracks not_allowed)
			(vias allowed)
			(pads allowed)
			(copperpour not_allowed)
			(footprints allowed)
		)
		(placement
			(enabled no)
			(sheetname "")
		)
		(fill
			(thermal_gap 0.5)
			(thermal_bridge_width 0.5)
			(island_removal_mode 0)
		)
		(polygon
			(pts
				(arc
					(start 36.301172 -373.828818)
					(mid 36.316051 -373.792897)
					(end 36.351972 -373.778018)
				)
				(arc
					(start 37.068252 -373.778018)
					(mid 37.104173 -373.792897)
					(end 37.119052 -373.828818)
				)
				(arc
					(start 37.119052 -376.25147)
					(mid 37.104173 -376.287391)
					(end 37.068252 -376.30227)
				)
				(arc
					(start 36.351972 -376.30227)
					(mid 36.316051 -376.287391)
					(end 36.301172 -376.25147)
				)
			)
		)
	)
	(zone
		(layers "F.Cu" "B.Cu" "In1.Cu" "In2.Cu" "In3.Cu" "In4.Cu" "In5.Cu" "In6.Cu"
			"In7.Cu" "In8.Cu" "In9.Cu" "In10.Cu" "In11.Cu" "In12.Cu" "In13.Cu" "In14.Cu"
			"In15.Cu" "In16.Cu"
		)
		(hatch none 0.5)
		(connect_pads
			(clearance 0)
		)
		(min_thickness 0.25)
		(keepout
			(tracks not_allowed)
			(vias allowed)
			(pads allowed)
			(copperpour not_allowed)
			(footprints allowed)
		)
		(placement
			(enabled no)
			(sheetname "")
		)
		(fill
			(thermal_gap 0.5)
			(thermal_bridge_width 0.5)
			(island_removal_mode 0)
		)
		(polygon
			(pts
				(arc
					(start 385.610608 -103.777796)
					(mid 386.067808 -104.234996)
					(end 386.525008 -103.777796)
				)
				(arc
					(start 386.525008 -102.914196)
					(mid 386.067808 -102.456996)
					(end 385.610608 -102.914196)
				)
			)
		)
	)
	(zone
		(layers "F.Cu" "B.Cu" "In1.Cu" "In2.Cu" "In3.Cu" "In4.Cu" "In5.Cu" "In6.Cu"
			"In7.Cu" "In8.Cu" "In9.Cu" "In10.Cu" "In11.Cu" "In12.Cu" "In13.Cu" "In14.Cu"
			"In15.Cu" "In16.Cu"
		)
		(hatch none 0.5)
		(connect_pads
			(clearance 0)
		)
		(min_thickness 0.25)
		(keepout
			(tracks not_allowed)
			(vias allowed)
			(pads allowed)
			(copperpour not_allowed)
			(footprints allowed)
		)
		(placement
			(enabled no)
			(sheetname "")
		)
		(fill
			(thermal_gap 0.5)
			(thermal_bridge_width 0.5)
			(island_removal_mode 0)
		)
		(polygon
			(pts
				(arc
					(start 399.16862 -354.351082)
					(mid 398.78762 -354.732082)
					(end 399.16862 -355.113082)
				)
				(arc
					(start 400.03222 -355.113082)
					(mid 400.41322 -354.732082)
					(end 400.03222 -354.351082)
				)
			)
		)
	)
	(zone
		(layers "F.Cu" "B.Cu" "In1.Cu" "In2.Cu" "In3.Cu" "In4.Cu" "In5.Cu" "In6.Cu"
			"In7.Cu" "In8.Cu" "In9.Cu" "In10.Cu" "In11.Cu" "In12.Cu" "In13.Cu" "In14.Cu"
			"In15.Cu" "In16.Cu"
		)
		(hatch none 0.5)
		(connect_pads
			(clearance 0)
		)
		(min_thickness 0.25)
		(keepout
			(tracks not_allowed)
			(vias allowed)
			(pads allowed)
			(copperpour not_allowed)
			(footprints allowed)
		)
		(placement
			(enabled no)
			(sheetname "")
		)
		(fill
			(thermal_gap 0.5)
			(thermal_bridge_width 0.5)
			(island_removal_mode 0)
		)
		(polygon
			(pts
				(arc
					(start 295.881044 -407.628852)
					(mid 295.895923 -407.592931)
					(end 295.931844 -407.578052)
				)
				(arc
					(start 296.648124 -407.578052)
					(mid 296.684045 -407.592931)
					(end 296.698924 -407.628852)
				)
				(arc
					(start 296.698924 -410.051504)
					(mid 296.684045 -410.087425)
					(end 296.648124 -410.102304)
				)
				(arc
					(start 295.931844 -410.102304)
					(mid 295.895923 -410.087425)
					(end 295.881044 -410.051504)
				)
			)
		)
	)
	(zone
		(layers "F.Cu" "B.Cu" "In1.Cu" "In2.Cu" "In3.Cu" "In4.Cu" "In5.Cu" "In6.Cu"
			"In7.Cu" "In8.Cu" "In9.Cu" "In10.Cu" "In11.Cu" "In12.Cu" "In13.Cu" "In14.Cu"
			"In15.Cu" "In16.Cu"
		)
		(hatch none 0.5)
		(connect_pads
			(clearance 0)
		)
		(min_thickness 0.25)
		(keepout
			(tracks not_allowed)
			(vias allowed)
			(pads allowed)
			(copperpour not_allowed)
			(footprints allowed)
		)
		(placement
			(enabled no)
			(sheetname "")
		)
		(fill
			(thermal_gap 0.5)
			(thermal_bridge_width 0.5)
			(island_removal_mode 0)
		)
		(polygon
			(pts
				(arc
					(start 333.28102 -382.728724)
					(mid 333.295899 -382.692803)
					(end 333.33182 -382.677924)
				)
				(arc
					(start 334.0481 -382.677924)
					(mid 334.084021 -382.692803)
					(end 334.0989 -382.728724)
				)
				(arc
					(start 334.0989 -385.151376)
					(mid 334.084021 -385.187297)
					(end 334.0481 -385.202176)
				)
				(arc
					(start 333.33182 -385.202176)
					(mid 333.295899 -385.187297)
					(end 333.28102 -385.151376)
				)
			)
		)
	)
	(zone
		(layers "F.Cu" "B.Cu" "In1.Cu" "In2.Cu" "In3.Cu" "In4.Cu" "In5.Cu" "In6.Cu"
			"In7.Cu" "In8.Cu" "In9.Cu" "In10.Cu" "In11.Cu" "In12.Cu" "In13.Cu" "In14.Cu"
			"In15.Cu" "In16.Cu"
		)
		(hatch none 0.5)
		(connect_pads
			(clearance 0)
		)
		(min_thickness 0.25)
		(keepout
			(tracks not_allowed)
			(vias allowed)
			(pads allowed)
			(copperpour not_allowed)
			(footprints allowed)
		)
		(placement
			(enabled no)
			(sheetname "")
		)
		(fill
			(thermal_gap 0.5)
			(thermal_bridge_width 0.5)
			(island_removal_mode 0)
		)
		(polygon
			(pts
				(arc
					(start 277.04796 -32.714184)
					(mid 277.50516 -33.171384)
					(end 277.96236 -32.714184)
				)
				(arc
					(start 277.96236 -31.850584)
					(mid 277.50516 -31.393384)
					(end 277.04796 -31.850584)
				)
			)
		)
	)
	(zone
		(layers "F.Cu" "B.Cu" "In1.Cu" "In2.Cu" "In3.Cu" "In4.Cu" "In5.Cu" "In6.Cu"
			"In7.Cu" "In8.Cu" "In9.Cu" "In10.Cu" "In11.Cu" "In12.Cu" "In13.Cu" "In14.Cu"
			"In15.Cu" "In16.Cu"
		)
		(hatch none 0.5)
		(connect_pads
			(clearance 0)
		)
		(min_thickness 0.25)
		(keepout
			(tracks not_allowed)
			(vias allowed)
			(pads allowed)
			(copperpour not_allowed)
			(footprints allowed)
		)
		(placement
			(enabled no)
			(sheetname "")
		)
		(fill
			(thermal_gap 0.5)
			(thermal_bridge_width 0.5)
			(island_removal_mode 0)
		)
		(polygon
			(pts
				(arc
					(start 29.700982 -408.728672)
					(mid 29.715861 -408.692751)
					(end 29.751782 -408.677872)
				)
				(arc
					(start 30.468062 -408.677872)
					(mid 30.503983 -408.692751)
					(end 30.518862 -408.728672)
				)
				(arc
					(start 30.518862 -411.151324)
					(mid 30.503983 -411.187245)
					(end 30.468062 -411.202124)
				)
				(arc
					(start 29.751782 -411.202124)
					(mid 29.715861 -411.187245)
					(end 29.700982 -411.151324)
				)
			)
		)
	)
	(zone
		(layers "F.Cu" "B.Cu" "In1.Cu" "In2.Cu" "In3.Cu" "In4.Cu" "In5.Cu" "In6.Cu"
			"In7.Cu" "In8.Cu" "In9.Cu" "In10.Cu" "In11.Cu" "In12.Cu" "In13.Cu" "In14.Cu"
			"In15.Cu" "In16.Cu"
		)
		(hatch none 0.5)
		(connect_pads
			(clearance 0)
		)
		(min_thickness 0.25)
		(keepout
			(tracks not_allowed)
			(vias allowed)
			(pads allowed)
			(copperpour not_allowed)
			(footprints allowed)
		)
		(placement
			(enabled no)
			(sheetname "")
		)
		(fill
			(thermal_gap 0.5)
			(thermal_bridge_width 0.5)
			(island_removal_mode 0)
		)
		(polygon
			(pts
				(arc
					(start 153.856182 -238.591852)
					(mid 153.398982 -239.049052)
					(end 153.856182 -239.506252)
				)
				(arc
					(start 154.719782 -239.506252)
					(mid 155.176982 -239.049052)
					(end 154.719782 -238.591852)
				)
			)
		)
	)
	(zone
		(layers "F.Cu" "B.Cu" "In1.Cu" "In2.Cu" "In3.Cu" "In4.Cu" "In5.Cu" "In6.Cu"
			"In7.Cu" "In8.Cu" "In9.Cu" "In10.Cu" "In11.Cu" "In12.Cu" "In13.Cu" "In14.Cu"
			"In15.Cu" "In16.Cu"
		)
		(hatch none 0.5)
		(connect_pads
			(clearance 0)
		)
		(min_thickness 0.25)
		(keepout
			(tracks not_allowed)
			(vias allowed)
			(pads allowed)
			(copperpour not_allowed)
			(footprints allowed)
		)
		(placement
			(enabled no)
			(sheetname "")
		)
		(fill
			(thermal_gap 0.5)
			(thermal_bridge_width 0.5)
			(island_removal_mode 0)
		)
		(polygon
			(pts
				(arc
					(start 400.99996 -124.622814)
					(mid 400.54276 -124.165614)
					(end 400.08556 -124.622814)
				)
				(arc
					(start 400.08556 -125.486414)
					(mid 400.54276 -125.943614)
					(end 400.99996 -125.486414)
				)
			)
		)
	)
	(zone
		(layers "F.Cu" "B.Cu" "In1.Cu" "In2.Cu" "In3.Cu" "In4.Cu" "In5.Cu" "In6.Cu"
			"In7.Cu" "In8.Cu" "In9.Cu" "In10.Cu" "In11.Cu" "In12.Cu" "In13.Cu" "In14.Cu"
			"In15.Cu" "In16.Cu"
		)
		(hatch none 0.5)
		(connect_pads
			(clearance 0)
		)
		(min_thickness 0.25)
		(keepout
			(tracks not_allowed)
			(vias allowed)
			(pads allowed)
			(copperpour not_allowed)
			(footprints allowed)
		)
		(placement
			(enabled no)
			(sheetname "")
		)
		(fill
			(thermal_gap 0.5)
			(thermal_bridge_width 0.5)
			(island_removal_mode 0)
		)
		(polygon
			(pts
				(arc
					(start 256.460498 10.192004)
					(mid 256.841498 9.811004)
					(end 257.222498 10.192004)
				)
				(arc
					(start 257.222498 11.055604)
					(mid 256.841498 11.436604)
					(end 256.460498 11.055604)
				)
			)
		)
	)
	(zone
		(layers "F.Cu" "B.Cu" "In1.Cu" "In2.Cu" "In3.Cu" "In4.Cu" "In5.Cu" "In6.Cu"
			"In7.Cu" "In8.Cu" "In9.Cu" "In10.Cu" "In11.Cu" "In12.Cu" "In13.Cu" "In14.Cu"
			"In15.Cu" "In16.Cu"
		)
		(hatch none 0.5)
		(connect_pads
			(clearance 0)
		)
		(min_thickness 0.25)
		(keepout
			(tracks not_allowed)
			(vias allowed)
			(pads allowed)
			(copperpour not_allowed)
			(footprints allowed)
		)
		(placement
			(enabled no)
			(sheetname "")
		)
		(fill
			(thermal_gap 0.5)
			(thermal_bridge_width 0.5)
			(island_removal_mode 0)
		)
		(polygon
			(pts
				(arc
					(start 163.759388 -160.1851)
					(mid 161.625788 -160.1851)
					(end 163.759388 -160.1851)
				)
			)
		)
	)
	(zone
		(layers "F.Cu" "B.Cu" "In1.Cu" "In2.Cu" "In3.Cu" "In4.Cu" "In5.Cu" "In6.Cu"
			"In7.Cu" "In8.Cu" "In9.Cu" "In10.Cu" "In11.Cu" "In12.Cu" "In13.Cu" "In14.Cu"
			"In15.Cu" "In16.Cu"
		)
		(hatch none 0.5)
		(connect_pads
			(clearance 0)
		)
		(min_thickness 0.25)
		(keepout
			(tracks not_allowed)
			(vias allowed)
			(pads allowed)
			(copperpour not_allowed)
			(footprints allowed)
		)
		(placement
			(enabled no)
			(sheetname "")
		)
		(fill
			(thermal_gap 0.5)
			(thermal_bridge_width 0.5)
			(island_removal_mode 0)
		)
		(polygon
			(pts
				(arc
					(start 374.29694 -351.230438)
					(mid 373.91594 -351.611438)
					(end 374.29694 -351.992438)
				)
				(arc
					(start 375.16054 -351.992438)
					(mid 375.54154 -351.611438)
					(end 375.16054 -351.230438)
				)
			)
		)
	)
	(zone
		(layers "F.Cu" "B.Cu" "In1.Cu" "In2.Cu" "In3.Cu" "In4.Cu" "In5.Cu" "In6.Cu"
			"In7.Cu" "In8.Cu" "In9.Cu" "In10.Cu" "In11.Cu" "In12.Cu" "In13.Cu" "In14.Cu"
			"In15.Cu" "In16.Cu"
		)
		(hatch none 0.5)
		(connect_pads
			(clearance 0)
		)
		(min_thickness 0.25)
		(keepout
			(tracks not_allowed)
			(vias allowed)
			(pads allowed)
			(copperpour not_allowed)
			(footprints allowed)
		)
		(placement
			(enabled no)
			(sheetname "")
		)
		(fill
			(thermal_gap 0.5)
			(thermal_bridge_width 0.5)
			(island_removal_mode 0)
		)
		(polygon
			(pts
				(arc
					(start 183.948832 -348.20479)
					(mid 183.567832 -348.58579)
					(end 183.948832 -348.96679)
				)
				(arc
					(start 184.812432 -348.96679)
					(mid 185.193432 -348.58579)
					(end 184.812432 -348.20479)
				)
			)
		)
	)
	(zone
		(layers "F.Cu" "B.Cu" "In1.Cu" "In2.Cu" "In3.Cu" "In4.Cu" "In5.Cu" "In6.Cu"
			"In7.Cu" "In8.Cu" "In9.Cu" "In10.Cu" "In11.Cu" "In12.Cu" "In13.Cu" "In14.Cu"
			"In15.Cu" "In16.Cu"
		)
		(hatch none 0.5)
		(connect_pads
			(clearance 0)
		)
		(min_thickness 0.25)
		(keepout
			(tracks not_allowed)
			(vias allowed)
			(pads allowed)
			(copperpour not_allowed)
			(footprints allowed)
		)
		(placement
			(enabled no)
			(sheetname "")
		)
		(fill
			(thermal_gap 0.5)
			(thermal_bridge_width 0.5)
			(island_removal_mode 0)
		)
		(polygon
			(pts
				(arc
					(start 339.88121 -369.928902)
					(mid 339.896089 -369.892981)
					(end 339.93201 -369.878102)
				)
				(arc
					(start 340.64829 -369.878102)
					(mid 340.684211 -369.892981)
					(end 340.69909 -369.928902)
				)
				(arc
					(start 340.69909 -372.351554)
					(mid 340.684211 -372.387475)
					(end 340.64829 -372.402354)
				)
				(arc
					(start 339.93201 -372.402354)
					(mid 339.896089 -372.387475)
					(end 339.88121 -372.351554)
				)
			)
		)
	)
	(zone
		(layers "F.Cu" "B.Cu" "In1.Cu" "In2.Cu" "In3.Cu" "In4.Cu" "In5.Cu" "In6.Cu"
			"In7.Cu" "In8.Cu" "In9.Cu" "In10.Cu" "In11.Cu" "In12.Cu" "In13.Cu" "In14.Cu"
			"In15.Cu" "In16.Cu"
		)
		(hatch none 0.5)
		(connect_pads
			(clearance 0)
		)
		(min_thickness 0.25)
		(keepout
			(tracks not_allowed)
			(vias allowed)
			(pads allowed)
			(copperpour not_allowed)
			(footprints allowed)
		)
		(placement
			(enabled no)
			(sheetname "")
		)
		(fill
			(thermal_gap 0.5)
			(thermal_bridge_width 0.5)
			(island_removal_mode 0)
		)
		(polygon
			(pts
				(arc
					(start 110.470696 -94.515686)
					(mid 110.927896 -94.058486)
					(end 110.470696 -93.601286)
				)
				(arc
					(start 109.607096 -93.601286)
					(mid 109.149896 -94.058486)
					(end 109.607096 -94.515686)
				)
			)
		)
	)
	(zone
		(layers "F.Cu" "B.Cu" "In1.Cu" "In2.Cu" "In3.Cu" "In4.Cu" "In5.Cu" "In6.Cu"
			"In7.Cu" "In8.Cu" "In9.Cu" "In10.Cu" "In11.Cu" "In12.Cu" "In13.Cu" "In14.Cu"
			"In15.Cu" "In16.Cu"
		)
		(hatch none 0.5)
		(connect_pads
			(clearance 0)
		)
		(min_thickness 0.25)
		(keepout
			(tracks not_allowed)
			(vias allowed)
			(pads allowed)
			(copperpour not_allowed)
			(footprints allowed)
		)
		(placement
			(enabled no)
			(sheetname "")
		)
		(fill
			(thermal_gap 0.5)
			(thermal_bridge_width 0.5)
			(island_removal_mode 0)
		)
		(polygon
			(pts
				(arc
					(start 429.375062 -154.279346)
					(mid 429.832262 -154.736546)
					(end 430.289462 -154.279346)
				)
				(arc
					(start 430.289462 -153.415746)
					(mid 429.832262 -152.958546)
					(end 429.375062 -153.415746)
				)
			)
		)
	)
	(zone
		(layers "F.Cu" "B.Cu" "In1.Cu" "In2.Cu" "In3.Cu" "In4.Cu" "In5.Cu" "In6.Cu"
			"In7.Cu" "In8.Cu" "In9.Cu" "In10.Cu" "In11.Cu" "In12.Cu" "In13.Cu" "In14.Cu"
			"In15.Cu" "In16.Cu"
		)
		(hatch none 0.5)
		(connect_pads
			(clearance 0)
		)
		(min_thickness 0.25)
		(keepout
			(tracks not_allowed)
			(vias allowed)
			(pads allowed)
			(copperpour not_allowed)
			(footprints allowed)
		)
		(placement
			(enabled no)
			(sheetname "")
		)
		(fill
			(thermal_gap 0.5)
			(thermal_bridge_width 0.5)
			(island_removal_mode 0)
		)
		(polygon
			(pts
				(arc
					(start 296.945812 -152.487376)
					(mid 297.403012 -152.944576)
					(end 297.860212 -152.487376)
				)
				(arc
					(start 297.860212 -151.623776)
					(mid 297.403012 -151.166576)
					(end 296.945812 -151.623776)
				)
			)
		)
	)
	(zone
		(layers "F.Cu" "B.Cu" "In1.Cu" "In2.Cu" "In3.Cu" "In4.Cu" "In5.Cu" "In6.Cu"
			"In7.Cu" "In8.Cu" "In9.Cu" "In10.Cu" "In11.Cu" "In12.Cu" "In13.Cu" "In14.Cu"
			"In15.Cu" "In16.Cu"
		)
		(hatch none 0.5)
		(connect_pads
			(clearance 0)
		)
		(min_thickness 0.25)
		(keepout
			(tracks not_allowed)
			(vias allowed)
			(pads allowed)
			(copperpour not_allowed)
			(footprints allowed)
		)
		(placement
			(enabled no)
			(sheetname "")
		)
		(fill
			(thermal_gap 0.5)
			(thermal_bridge_width 0.5)
			(island_removal_mode 0)
		)
		(polygon
			(pts
				(arc
					(start 45.101002 -373.828818)
					(mid 45.115881 -373.792897)
					(end 45.151802 -373.778018)
				)
				(arc
					(start 45.868082 -373.778018)
					(mid 45.904003 -373.792897)
					(end 45.918882 -373.828818)
				)
				(arc
					(start 45.918882 -376.25147)
					(mid 45.904003 -376.287391)
					(end 45.868082 -376.30227)
				)
				(arc
					(start 45.151802 -376.30227)
					(mid 45.115881 -376.287391)
					(end 45.101002 -376.25147)
				)
			)
		)
	)
	(zone
		(layers "F.Cu" "B.Cu" "In1.Cu" "In2.Cu" "In3.Cu" "In4.Cu" "In5.Cu" "In6.Cu"
			"In7.Cu" "In8.Cu" "In9.Cu" "In10.Cu" "In11.Cu" "In12.Cu" "In13.Cu" "In14.Cu"
			"In15.Cu" "In16.Cu"
		)
		(hatch none 0.5)
		(connect_pads
			(clearance 0)
		)
		(min_thickness 0.25)
		(keepout
			(tracks not_allowed)
			(vias allowed)
			(pads allowed)
			(copperpour not_allowed)
			(footprints allowed)
		)
		(placement
			(enabled no)
			(sheetname "")
		)
		(fill
			(thermal_gap 0.5)
			(thermal_bridge_width 0.5)
			(island_removal_mode 0)
		)
		(polygon
			(pts
				(arc
					(start 289.280854 -400.92884)
					(mid 289.295733 -400.892919)
					(end 289.331654 -400.87804)
				)
				(arc
					(start 290.047934 -400.87804)
					(mid 290.083855 -400.892919)
					(end 290.098734 -400.92884)
				)
				(arc
					(start 290.098734 -403.351492)
					(mid 290.083855 -403.387413)
					(end 290.047934 -403.402292)
				)
				(arc
					(start 289.331654 -403.402292)
					(mid 289.295733 -403.387413)
					(end 289.280854 -403.351492)
				)
			)
		)
	)
	(zone
		(layers "F.Cu" "B.Cu" "In1.Cu" "In2.Cu" "In3.Cu" "In4.Cu" "In5.Cu" "In6.Cu"
			"In7.Cu" "In8.Cu" "In9.Cu" "In10.Cu" "In11.Cu" "In12.Cu" "In13.Cu" "In14.Cu"
			"In15.Cu" "In16.Cu"
		)
		(hatch none 0.5)
		(connect_pads
			(clearance 0)
		)
		(min_thickness 0.25)
		(keepout
			(tracks not_allowed)
			(vias allowed)
			(pads allowed)
			(copperpour not_allowed)
			(footprints allowed)
		)
		(placement
			(enabled no)
			(sheetname "")
		)
		(fill
			(thermal_gap 0.5)
			(thermal_bridge_width 0.5)
			(island_removal_mode 0)
		)
		(polygon
			(pts
				(arc
					(start 392.9507 -351.230438)
					(mid 392.5697 -351.611438)
					(end 392.9507 -351.992438)
				)
				(arc
					(start 393.8143 -351.992438)
					(mid 394.1953 -351.611438)
					(end 393.8143 -351.230438)
				)
			)
		)
	)
	(zone
		(layers "F.Cu" "B.Cu" "In1.Cu" "In2.Cu" "In3.Cu" "In4.Cu" "In5.Cu" "In6.Cu"
			"In7.Cu" "In8.Cu" "In9.Cu" "In10.Cu" "In11.Cu" "In12.Cu" "In13.Cu" "In14.Cu"
			"In15.Cu" "In16.Cu"
		)
		(hatch none 0.5)
		(connect_pads
			(clearance 0)
		)
		(min_thickness 0.25)
		(keepout
			(tracks not_allowed)
			(vias allowed)
			(pads allowed)
			(copperpour not_allowed)
			(footprints allowed)
		)
		(placement
			(enabled no)
			(sheetname "")
		)
		(fill
			(thermal_gap 0.5)
			(thermal_bridge_width 0.5)
			(island_removal_mode 0)
		)
		(polygon
			(pts
				(arc
					(start 130.901186 -400.92884)
					(mid 130.916065 -400.892919)
					(end 130.951986 -400.87804)
				)
				(arc
					(start 131.668266 -400.87804)
					(mid 131.704187 -400.892919)
					(end 131.719066 -400.92884)
				)
				(arc
					(start 131.719066 -403.351492)
					(mid 131.704187 -403.387413)
					(end 131.668266 -403.402292)
				)
				(arc
					(start 130.951986 -403.402292)
					(mid 130.916065 -403.387413)
					(end 130.901186 -403.351492)
				)
			)
		)
	)
	(zone
		(layers "F.Cu" "B.Cu" "In1.Cu" "In2.Cu" "In3.Cu" "In4.Cu" "In5.Cu" "In6.Cu"
			"In7.Cu" "In8.Cu" "In9.Cu" "In10.Cu" "In11.Cu" "In12.Cu" "In13.Cu" "In14.Cu"
			"In15.Cu" "In16.Cu"
		)
		(hatch none 0.5)
		(connect_pads
			(clearance 0)
		)
		(min_thickness 0.25)
		(keepout
			(tracks not_allowed)
			(vias allowed)
			(pads allowed)
			(copperpour not_allowed)
			(footprints allowed)
		)
		(placement
			(enabled no)
			(sheetname "")
		)
		(fill
			(thermal_gap 0.5)
			(thermal_bridge_width 0.5)
			(island_removal_mode 0)
		)
		(polygon
			(pts
				(arc
					(start 274.115022 -357.37673)
					(mid 273.734022 -357.75773)
					(end 274.115022 -358.13873)
				)
				(arc
					(start 274.978622 -358.13873)
					(mid 275.359622 -357.75773)
					(end 274.978622 -357.37673)
				)
			)
		)
	)
	(zone
		(layers "F.Cu" "B.Cu" "In1.Cu" "In2.Cu" "In3.Cu" "In4.Cu" "In5.Cu" "In6.Cu"
			"In7.Cu" "In8.Cu" "In9.Cu" "In10.Cu" "In11.Cu" "In12.Cu" "In13.Cu" "In14.Cu"
			"In15.Cu" "In16.Cu"
		)
		(hatch none 0.5)
		(connect_pads
			(clearance 0)
		)
		(min_thickness 0.25)
		(keepout
			(tracks not_allowed)
			(vias allowed)
			(pads allowed)
			(copperpour not_allowed)
			(footprints allowed)
		)
		(placement
			(enabled no)
			(sheetname "")
		)
		(fill
			(thermal_gap 0.5)
			(thermal_bridge_width 0.5)
			(island_removal_mode 0)
		)
		(polygon
			(pts
				(arc
					(start 187.057792 -354.327206)
					(mid 186.676792 -354.708206)
					(end 187.057792 -355.089206)
				)
				(arc
					(start 187.921392 -355.089206)
					(mid 188.302392 -354.708206)
					(end 187.921392 -354.327206)
				)
			)
		)
	)
	(zone
		(layers "F.Cu" "B.Cu" "In1.Cu" "In2.Cu" "In3.Cu" "In4.Cu" "In5.Cu" "In6.Cu"
			"In7.Cu" "In8.Cu" "In9.Cu" "In10.Cu" "In11.Cu" "In12.Cu" "In13.Cu" "In14.Cu"
			"In15.Cu" "In16.Cu"
		)
		(hatch none 0.5)
		(connect_pads
			(clearance 0)
		)
		(min_thickness 0.25)
		(keepout
			(tracks not_allowed)
			(vias allowed)
			(pads allowed)
			(copperpour not_allowed)
			(footprints allowed)
		)
		(placement
			(enabled no)
			(sheetname "")
		)
		(fill
			(thermal_gap 0.5)
			(thermal_bridge_width 0.5)
			(island_removal_mode 0)
		)
		(polygon
			(pts
				(arc
					(start 383.62382 -345.084146)
					(mid 383.24282 -345.465146)
					(end 383.62382 -345.846146)
				)
				(arc
					(start 384.48742 -345.846146)
					(mid 384.86842 -345.465146)
					(end 384.48742 -345.084146)
				)
			)
		)
	)
	(zone
		(layers "F.Cu" "B.Cu" "In1.Cu" "In2.Cu" "In3.Cu" "In4.Cu" "In5.Cu" "In6.Cu"
			"In7.Cu" "In8.Cu" "In9.Cu" "In10.Cu" "In11.Cu" "In12.Cu" "In13.Cu" "In14.Cu"
			"In15.Cu" "In16.Cu"
		)
		(hatch none 0.5)
		(connect_pads
			(clearance 0)
		)
		(min_thickness 0.25)
		(keepout
			(tracks not_allowed)
			(vias allowed)
			(pads allowed)
			(copperpour not_allowed)
			(footprints allowed)
		)
		(placement
			(enabled no)
			(sheetname "")
		)
		(fill
			(thermal_gap 0.5)
			(thermal_bridge_width 0.5)
			(island_removal_mode 0)
		)
		(polygon
			(pts
				(arc
					(start 156.030168 -36.60013)
					(mid 154.099768 -36.60013)
					(end 156.030168 -36.60013)
				)
			)
		)
	)
	(zone
		(layers "F.Cu" "B.Cu" "In1.Cu" "In2.Cu" "In3.Cu" "In4.Cu" "In5.Cu" "In6.Cu"
			"In7.Cu" "In8.Cu" "In9.Cu" "In10.Cu" "In11.Cu" "In12.Cu" "In13.Cu" "In14.Cu"
			"In15.Cu" "In16.Cu"
		)
		(hatch none 0.5)
		(connect_pads
			(clearance 0)
		)
		(min_thickness 0.25)
		(keepout
			(tracks not_allowed)
			(vias allowed)
			(pads allowed)
			(copperpour not_allowed)
			(footprints allowed)
		)
		(placement
			(enabled no)
			(sheetname "")
		)
		(fill
			(thermal_gap 0.5)
			(thermal_bridge_width 0.5)
			(island_removal_mode 0)
		)
		(polygon
			(pts
				(arc
					(start 382.9685 -105.584498)
					(mid 383.4257 -106.041698)
					(end 383.8829 -105.584498)
				)
				(arc
					(start 383.8829 -104.720898)
					(mid 383.4257 -104.263698)
					(end 382.9685 -104.720898)
				)
			)
		)
	)
	(zone
		(layers "F.Cu" "B.Cu" "In1.Cu" "In2.Cu" "In3.Cu" "In4.Cu" "In5.Cu" "In6.Cu"
			"In7.Cu" "In8.Cu" "In9.Cu" "In10.Cu" "In11.Cu" "In12.Cu" "In13.Cu" "In14.Cu"
			"In15.Cu" "In16.Cu"
		)
		(hatch none 0.5)
		(connect_pads
			(clearance 0)
		)
		(min_thickness 0.25)
		(keepout
			(tracks not_allowed)
			(vias allowed)
			(pads allowed)
			(copperpour not_allowed)
			(footprints allowed)
		)
		(placement
			(enabled no)
			(sheetname "")
		)
		(fill
			(thermal_gap 0.5)
			(thermal_bridge_width 0.5)
			(island_removal_mode 0)
		)
		(polygon
			(pts
				(arc
					(start 197.17512 -154.279346)
					(mid 197.63232 -154.736546)
					(end 198.08952 -154.279346)
				)
				(arc
					(start 198.08952 -153.415746)
					(mid 197.63232 -152.958546)
					(end 197.17512 -153.415746)
				)
			)
		)
	)
	(zone
		(layers "F.Cu" "B.Cu" "In1.Cu" "In2.Cu" "In3.Cu" "In4.Cu" "In5.Cu" "In6.Cu"
			"In7.Cu" "In8.Cu" "In9.Cu" "In10.Cu" "In11.Cu" "In12.Cu" "In13.Cu" "In14.Cu"
			"In15.Cu" "In16.Cu"
		)
		(hatch none 0.5)
		(connect_pads
			(clearance 0)
		)
		(min_thickness 0.25)
		(keepout
			(tracks not_allowed)
			(vias allowed)
			(pads allowed)
			(copperpour not_allowed)
			(footprints allowed)
		)
		(placement
			(enabled no)
			(sheetname "")
		)
		(fill
			(thermal_gap 0.5)
			(thermal_bridge_width 0.5)
			(island_removal_mode 0)
		)
		(polygon
			(pts
				(arc
					(start 374.29694 -354.351082)
					(mid 373.91594 -354.732082)
					(end 374.29694 -355.113082)
				)
				(arc
					(start 375.16054 -355.113082)
					(mid 375.54154 -354.732082)
					(end 375.16054 -354.351082)
				)
			)
		)
	)
	(zone
		(layers "F.Cu" "B.Cu" "In1.Cu" "In2.Cu" "In3.Cu" "In4.Cu" "In5.Cu" "In6.Cu"
			"In7.Cu" "In8.Cu" "In9.Cu" "In10.Cu" "In11.Cu" "In12.Cu" "In13.Cu" "In14.Cu"
			"In15.Cu" "In16.Cu"
		)
		(hatch none 0.5)
		(connect_pads
			(clearance 0)
		)
		(min_thickness 0.25)
		(keepout
			(tracks not_allowed)
			(vias allowed)
			(pads allowed)
			(copperpour not_allowed)
			(footprints allowed)
		)
		(placement
			(enabled no)
			(sheetname "")
		)
		(fill
			(thermal_gap 0.5)
			(thermal_bridge_width 0.5)
			(island_removal_mode 0)
		)
		(polygon
			(pts
				(arc
					(start 117.5385 -82.49539)
					(mid 117.0813 -82.03819)
					(end 116.6241 -82.49539)
				)
				(arc
					(start 116.6241 -83.35899)
					(mid 117.0813 -83.81619)
					(end 117.5385 -83.35899)
				)
			)
		)
	)
	(zone
		(layers "F.Cu" "B.Cu" "In1.Cu" "In2.Cu" "In3.Cu" "In4.Cu" "In5.Cu" "In6.Cu"
			"In7.Cu" "In8.Cu" "In9.Cu" "In10.Cu" "In11.Cu" "In12.Cu" "In13.Cu" "In14.Cu"
			"In15.Cu" "In16.Cu"
		)
		(hatch none 0.5)
		(connect_pads
			(clearance 0)
		)
		(min_thickness 0.25)
		(keepout
			(tracks not_allowed)
			(vias allowed)
			(pads allowed)
			(copperpour not_allowed)
			(footprints allowed)
		)
		(placement
			(enabled no)
			(sheetname "")
		)
		(fill
			(thermal_gap 0.5)
			(thermal_bridge_width 0.5)
			(island_removal_mode 0)
		)
		(polygon
			(pts
				(arc
					(start 421.730932 -357.37673)
					(mid 421.349932 -357.75773)
					(end 421.730932 -358.13873)
				)
				(arc
					(start 422.594532 -358.13873)
					(mid 422.975532 -357.75773)
					(end 422.594532 -357.37673)
				)
			)
		)
	)
	(zone
		(layers "F.Cu" "B.Cu" "In1.Cu" "In2.Cu" "In3.Cu" "In4.Cu" "In5.Cu" "In6.Cu"
			"In7.Cu" "In8.Cu" "In9.Cu" "In10.Cu" "In11.Cu" "In12.Cu" "In13.Cu" "In14.Cu"
			"In15.Cu" "In16.Cu"
		)
		(hatch none 0.5)
		(connect_pads
			(clearance 0)
		)
		(min_thickness 0.25)
		(keepout
			(tracks not_allowed)
			(vias allowed)
			(pads allowed)
			(copperpour not_allowed)
			(footprints allowed)
		)
		(placement
			(enabled no)
			(sheetname "")
		)
		(fill
			(thermal_gap 0.5)
			(thermal_bridge_width 0.5)
			(island_removal_mode 0)
		)
		(polygon
			(pts
				(arc
					(start 316.953138 -34.52241)
					(mid 317.410338 -34.97961)
					(end 317.867538 -34.52241)
				)
				(arc
					(start 317.867538 -33.65881)
					(mid 317.410338 -33.20161)
					(end 316.953138 -33.65881)
				)
			)
		)
	)
	(zone
		(layers "F.Cu" "B.Cu" "In1.Cu" "In2.Cu" "In3.Cu" "In4.Cu" "In5.Cu" "In6.Cu"
			"In7.Cu" "In8.Cu" "In9.Cu" "In10.Cu" "In11.Cu" "In12.Cu" "In13.Cu" "In14.Cu"
			"In15.Cu" "In16.Cu"
		)
		(hatch none 0.5)
		(connect_pads
			(clearance 0)
		)
		(min_thickness 0.25)
		(keepout
			(tracks not_allowed)
			(vias allowed)
			(pads allowed)
			(copperpour not_allowed)
			(footprints allowed)
		)
		(placement
			(enabled no)
			(sheetname "")
		)
		(fill
			(thermal_gap 0.5)
			(thermal_bridge_width 0.5)
			(island_removal_mode 0)
		)
		(polygon
			(pts
				(arc
					(start 78.100936 -378.828554)
					(mid 78.115815 -378.792633)
					(end 78.151736 -378.777754)
				)
				(arc
					(start 78.868016 -378.777754)
					(mid 78.903937 -378.792633)
					(end 78.918816 -378.828554)
				)
				(arc
					(start 78.918816 -381.251206)
					(mid 78.903937 -381.287127)
					(end 78.868016 -381.302006)
				)
				(arc
					(start 78.151736 -381.302006)
					(mid 78.115815 -381.287127)
					(end 78.100936 -381.251206)
				)
			)
		)
	)
	(zone
		(layers "F.Cu" "B.Cu" "In1.Cu" "In2.Cu" "In3.Cu" "In4.Cu" "In5.Cu" "In6.Cu"
			"In7.Cu" "In8.Cu" "In9.Cu" "In10.Cu" "In11.Cu" "In12.Cu" "In13.Cu" "In14.Cu"
			"In15.Cu" "In16.Cu"
		)
		(hatch none 0.5)
		(connect_pads
			(clearance 0)
		)
		(min_thickness 0.25)
		(keepout
			(tracks not_allowed)
			(vias allowed)
			(pads allowed)
			(copperpour not_allowed)
			(footprints allowed)
		)
		(placement
			(enabled no)
			(sheetname "")
		)
		(fill
			(thermal_gap 0.5)
			(thermal_bridge_width 0.5)
			(island_removal_mode 0)
		)
		(polygon
			(pts
				(arc
					(start 168.404032 -348.20479)
					(mid 168.023032 -348.58579)
					(end 168.404032 -348.96679)
				)
				(arc
					(start 169.267632 -348.96679)
					(mid 169.648632 -348.58579)
					(end 169.267632 -348.20479)
				)
			)
		)
	)
	(zone
		(layers "F.Cu" "B.Cu" "In1.Cu" "In2.Cu" "In3.Cu" "In4.Cu" "In5.Cu" "In6.Cu"
			"In7.Cu" "In8.Cu" "In9.Cu" "In10.Cu" "In11.Cu" "In12.Cu" "In13.Cu" "In14.Cu"
			"In15.Cu" "In16.Cu"
		)
		(hatch none 0.5)
		(connect_pads
			(clearance 0)
		)
		(min_thickness 0.25)
		(keepout
			(tracks not_allowed)
			(vias allowed)
			(pads allowed)
			(copperpour not_allowed)
			(footprints allowed)
		)
		(placement
			(enabled no)
			(sheetname "")
		)
		(fill
			(thermal_gap 0.5)
			(thermal_bridge_width 0.5)
			(island_removal_mode 0)
		)
		(polygon
			(pts
				(arc
					(start 81.075022 -119.55907)
					(mid 81.532222 -120.01627)
					(end 81.989422 -119.55907)
				)
				(arc
					(start 81.989422 -118.69547)
					(mid 81.532222 -118.23827)
					(end 81.075022 -118.69547)
				)
			)
		)
	)
	(zone
		(layers "F.Cu" "B.Cu" "In1.Cu" "In2.Cu" "In3.Cu" "In4.Cu" "In5.Cu" "In6.Cu"
			"In7.Cu" "In8.Cu" "In9.Cu" "In10.Cu" "In11.Cu" "In12.Cu" "In13.Cu" "In14.Cu"
			"In15.Cu" "In16.Cu"
		)
		(hatch none 0.5)
		(connect_pads
			(clearance 0)
		)
		(min_thickness 0.25)
		(keepout
			(tracks not_allowed)
			(vias allowed)
			(pads allowed)
			(copperpour not_allowed)
			(footprints allowed)
		)
		(placement
			(enabled no)
			(sheetname "")
		)
		(fill
			(thermal_gap 0.5)
			(thermal_bridge_width 0.5)
			(island_removal_mode 0)
		)
		(polygon
			(pts
				(arc
					(start 402.27758 -357.37673)
					(mid 401.89658 -357.75773)
					(end 402.27758 -358.13873)
				)
				(arc
					(start 403.14118 -358.13873)
					(mid 403.52218 -357.75773)
					(end 403.14118 -357.37673)
				)
			)
		)
	)
	(zone
		(layers "F.Cu" "B.Cu" "In1.Cu" "In2.Cu" "In3.Cu" "In4.Cu" "In5.Cu" "In6.Cu"
			"In7.Cu" "In8.Cu" "In9.Cu" "In10.Cu" "In11.Cu" "In12.Cu" "In13.Cu" "In14.Cu"
			"In15.Cu" "In16.Cu"
		)
		(hatch none 0.5)
		(connect_pads
			(clearance 0)
		)
		(min_thickness 0.25)
		(keepout
			(tracks not_allowed)
			(vias allowed)
			(pads allowed)
			(copperpour not_allowed)
			(footprints allowed)
		)
		(placement
			(enabled no)
			(sheetname "")
		)
		(fill
			(thermal_gap 0.5)
			(thermal_bridge_width 0.5)
			(island_removal_mode 0)
		)
		(polygon
			(pts
				(arc
					(start 331.156564 -357.37673)
					(mid 330.775564 -357.75773)
					(end 331.156564 -358.13873)
				)
				(arc
					(start 332.020164 -358.13873)
					(mid 332.401164 -357.75773)
					(end 332.020164 -357.37673)
				)
			)
		)
	)
	(zone
		(layers "F.Cu" "B.Cu" "In1.Cu" "In2.Cu" "In3.Cu" "In4.Cu" "In5.Cu" "In6.Cu"
			"In7.Cu" "In8.Cu" "In9.Cu" "In10.Cu" "In11.Cu" "In12.Cu" "In13.Cu" "In14.Cu"
			"In15.Cu" "In16.Cu"
		)
		(hatch none 0.5)
		(connect_pads
			(clearance 0)
		)
		(min_thickness 0.25)
		(keepout
			(tracks not_allowed)
			(vias allowed)
			(pads allowed)
			(copperpour not_allowed)
			(footprints allowed)
		)
		(placement
			(enabled no)
			(sheetname "")
		)
		(fill
			(thermal_gap 0.5)
			(thermal_bridge_width 0.5)
			(island_removal_mode 0)
		)
		(polygon
			(pts
				(arc
					(start 382.9685 -109.18444)
					(mid 383.4257 -109.64164)
					(end 383.8829 -109.18444)
				)
				(arc
					(start 383.8829 -108.32084)
					(mid 383.4257 -107.86364)
					(end 382.9685 -108.32084)
				)
			)
		)
	)
	(zone
		(layers "F.Cu" "B.Cu" "In1.Cu" "In2.Cu" "In3.Cu" "In4.Cu" "In5.Cu" "In6.Cu"
			"In7.Cu" "In8.Cu" "In9.Cu" "In10.Cu" "In11.Cu" "In12.Cu" "In13.Cu" "In14.Cu"
			"In15.Cu" "In16.Cu"
		)
		(hatch none 0.5)
		(connect_pads
			(clearance 0)
		)
		(min_thickness 0.25)
		(keepout
			(tracks not_allowed)
			(vias allowed)
			(pads allowed)
			(copperpour not_allowed)
			(footprints allowed)
		)
		(placement
			(enabled no)
			(sheetname "")
		)
		(fill
			(thermal_gap 0.5)
			(thermal_bridge_width 0.5)
			(island_removal_mode 0)
		)
		(polygon
			(pts
				(arc
					(start 187.057792 -342.058498)
					(mid 186.676792 -342.439498)
					(end 187.057792 -342.820498)
				)
				(arc
					(start 187.921392 -342.820498)
					(mid 188.302392 -342.439498)
					(end 187.921392 -342.058498)
				)
			)
		)
	)
	(zone
		(layers "F.Cu" "B.Cu" "In1.Cu" "In2.Cu" "In3.Cu" "In4.Cu" "In5.Cu" "In6.Cu"
			"In7.Cu" "In8.Cu" "In9.Cu" "In10.Cu" "In11.Cu" "In12.Cu" "In13.Cu" "In14.Cu"
			"In15.Cu" "In16.Cu"
		)
		(hatch none 0.5)
		(connect_pads
			(clearance 0)
		)
		(min_thickness 0.25)
		(keepout
			(tracks not_allowed)
			(vias allowed)
			(pads allowed)
			(copperpour not_allowed)
			(footprints allowed)
		)
		(placement
			(enabled no)
			(sheetname "")
		)
		(fill
			(thermal_gap 0.5)
			(thermal_bridge_width 0.5)
			(island_removal_mode 0)
		)
		(polygon
			(pts
				(arc
					(start 382.90754 -32.722312)
					(mid 383.36474 -33.179512)
					(end 383.82194 -32.722312)
				)
				(arc
					(start 383.82194 -31.858712)
					(mid 383.36474 -31.401512)
					(end 382.90754 -31.858712)
				)
			)
		)
	)
	(zone
		(layers "F.Cu" "B.Cu" "In1.Cu" "In2.Cu" "In3.Cu" "In4.Cu" "In5.Cu" "In6.Cu"
			"In7.Cu" "In8.Cu" "In9.Cu" "In10.Cu" "In11.Cu" "In12.Cu" "In13.Cu" "In14.Cu"
			"In15.Cu" "In16.Cu"
		)
		(hatch none 0.5)
		(connect_pads
			(clearance 0)
		)
		(min_thickness 0.25)
		(keepout
			(tracks not_allowed)
			(vias allowed)
			(pads allowed)
			(copperpour not_allowed)
			(footprints allowed)
		)
		(placement
			(enabled no)
			(sheetname "")
		)
		(fill
			(thermal_gap 0.5)
			(thermal_bridge_width 0.5)
			(island_removal_mode 0)
		)
		(polygon
			(pts
				(arc
					(start 413.04591 -136.177274)
					(mid 413.50311 -136.634474)
					(end 413.96031 -136.177274)
				)
				(arc
					(start 413.96031 -135.313674)
					(mid 413.50311 -134.856474)
					(end 413.04591 -135.313674)
				)
			)
		)
	)
	(zone
		(layers "F.Cu" "B.Cu" "In1.Cu" "In2.Cu" "In3.Cu" "In4.Cu" "In5.Cu" "In6.Cu"
			"In7.Cu" "In8.Cu" "In9.Cu" "In10.Cu" "In11.Cu" "In12.Cu" "In13.Cu" "In14.Cu"
			"In15.Cu" "In16.Cu"
		)
		(hatch none 0.5)
		(connect_pads
			(clearance 0)
		)
		(min_thickness 0.25)
		(keepout
			(tracks not_allowed)
			(vias allowed)
			(pads allowed)
			(copperpour not_allowed)
			(footprints allowed)
		)
		(placement
			(enabled no)
			(sheetname "")
		)
		(fill
			(thermal_gap 0.5)
			(thermal_bridge_width 0.5)
			(island_removal_mode 0)
		)
		(polygon
			(pts
				(arc
					(start 419.08095 -381.628904)
					(mid 419.095829 -381.592983)
					(end 419.13175 -381.578104)
				)
				(arc
					(start 419.84803 -381.578104)
					(mid 419.883951 -381.592983)
					(end 419.89883 -381.628904)
				)
				(arc
					(start 419.89883 -384.051556)
					(mid 419.883951 -384.087477)
					(end 419.84803 -384.102356)
				)
				(arc
					(start 419.13175 -384.102356)
					(mid 419.095829 -384.087477)
					(end 419.08095 -384.051556)
				)
			)
		)
	)
	(zone
		(layers "F.Cu" "B.Cu" "In1.Cu" "In2.Cu" "In3.Cu" "In4.Cu" "In5.Cu" "In6.Cu"
			"In7.Cu" "In8.Cu" "In9.Cu" "In10.Cu" "In11.Cu" "In12.Cu" "In13.Cu" "In14.Cu"
			"In15.Cu" "In16.Cu"
		)
		(hatch none 0.5)
		(connect_pads
			(clearance 0)
		)
		(min_thickness 0.25)
		(keepout
			(tracks not_allowed)
			(vias allowed)
			(pads allowed)
			(copperpour not_allowed)
			(footprints allowed)
		)
		(placement
			(enabled no)
			(sheetname "")
		)
		(fill
			(thermal_gap 0.5)
			(thermal_bridge_width 0.5)
			(island_removal_mode 0)
		)
		(polygon
			(pts
				(arc
					(start 333.28102 -378.828554)
					(mid 333.295899 -378.792633)
					(end 333.33182 -378.777754)
				)
				(arc
					(start 334.0481 -378.777754)
					(mid 334.084021 -378.792633)
					(end 334.0989 -378.828554)
				)
				(arc
					(start 334.0989 -381.251206)
					(mid 334.084021 -381.287127)
					(end 334.0481 -381.302006)
				)
				(arc
					(start 333.33182 -381.302006)
					(mid 333.295899 -381.287127)
					(end 333.28102 -381.251206)
				)
			)
		)
	)
	(zone
		(layers "F.Cu" "B.Cu" "In1.Cu" "In2.Cu" "In3.Cu" "In4.Cu" "In5.Cu" "In6.Cu"
			"In7.Cu" "In8.Cu" "In9.Cu" "In10.Cu" "In11.Cu" "In12.Cu" "In13.Cu" "In14.Cu"
			"In15.Cu" "In16.Cu"
		)
		(hatch none 0.5)
		(connect_pads
			(clearance 0)
		)
		(min_thickness 0.25)
		(keepout
			(tracks not_allowed)
			(vias allowed)
			(pads allowed)
			(copperpour not_allowed)
			(footprints allowed)
		)
		(placement
			(enabled no)
			(sheetname "")
		)
		(fill
			(thermal_gap 0.5)
			(thermal_bridge_width 0.5)
			(island_removal_mode 0)
		)
		(polygon
			(pts
				(arc
					(start 430.080928 -378.828554)
					(mid 430.095807 -378.792633)
					(end 430.131728 -378.777754)
				)
				(arc
					(start 430.848008 -378.777754)
					(mid 430.883929 -378.792633)
					(end 430.898808 -378.828554)
				)
				(arc
					(start 430.898808 -381.251206)
					(mid 430.883929 -381.287127)
					(end 430.848008 -381.302006)
				)
				(arc
					(start 430.131728 -381.302006)
					(mid 430.095807 -381.287127)
					(end 430.080928 -381.251206)
				)
			)
		)
	)
	(zone
		(layers "F.Cu" "B.Cu" "In1.Cu" "In2.Cu" "In3.Cu" "In4.Cu" "In5.Cu" "In6.Cu"
			"In7.Cu" "In8.Cu" "In9.Cu" "In10.Cu" "In11.Cu" "In12.Cu" "In13.Cu" "In14.Cu"
			"In15.Cu" "In16.Cu"
		)
		(hatch none 0.5)
		(connect_pads
			(clearance 0)
		)
		(min_thickness 0.25)
		(keepout
			(tracks not_allowed)
			(vias allowed)
			(pads allowed)
			(copperpour not_allowed)
			(footprints allowed)
		)
		(placement
			(enabled no)
			(sheetname "")
		)
		(fill
			(thermal_gap 0.5)
			(thermal_bridge_width 0.5)
			(island_removal_mode 0)
		)
		(polygon
			(pts
				(arc
					(start 174.901098 -404.828756)
					(mid 174.915977 -404.792835)
					(end 174.951898 -404.777956)
				)
				(arc
					(start 175.668178 -404.777956)
					(mid 175.704099 -404.792835)
					(end 175.718978 -404.828756)
				)
				(arc
					(start 175.718978 -407.251408)
					(mid 175.704099 -407.287329)
					(end 175.668178 -407.302208)
				)
				(arc
					(start 174.951898 -407.302208)
					(mid 174.915977 -407.287329)
					(end 174.901098 -407.251408)
				)
			)
		)
	)
	(zone
		(layers "F.Cu" "B.Cu" "In1.Cu" "In2.Cu" "In3.Cu" "In4.Cu" "In5.Cu" "In6.Cu"
			"In7.Cu" "In8.Cu" "In9.Cu" "In10.Cu" "In11.Cu" "In12.Cu" "In13.Cu" "In14.Cu"
			"In15.Cu" "In16.Cu"
		)
		(hatch none 0.5)
		(connect_pads
			(clearance 0)
		)
		(min_thickness 0.25)
		(keepout
			(tracks not_allowed)
			(vias allowed)
			(pads allowed)
			(copperpour not_allowed)
			(footprints allowed)
		)
		(placement
			(enabled no)
			(sheetname "")
		)
		(fill
			(thermal_gap 0.5)
			(thermal_bridge_width 0.5)
			(island_removal_mode 0)
		)
		(polygon
			(pts
				(arc
					(start 331.081126 -403.728682)
					(mid 331.096005 -403.692761)
					(end 331.131926 -403.677882)
				)
				(arc
					(start 331.848206 -403.677882)
					(mid 331.884127 -403.692761)
					(end 331.899006 -403.728682)
				)
				(arc
					(start 331.899006 -406.151334)
					(mid 331.884127 -406.187255)
					(end 331.848206 -406.202134)
				)
				(arc
					(start 331.131926 -406.202134)
					(mid 331.096005 -406.187255)
					(end 331.081126 -406.151334)
				)
			)
		)
	)
	(zone
		(layers "F.Cu" "B.Cu" "In1.Cu" "In2.Cu" "In3.Cu" "In4.Cu" "In5.Cu" "In6.Cu"
			"In7.Cu" "In8.Cu" "In9.Cu" "In10.Cu" "In11.Cu" "In12.Cu" "In13.Cu" "In14.Cu"
			"In15.Cu" "In16.Cu"
		)
		(hatch none 0.5)
		(connect_pads
			(clearance 0)
		)
		(min_thickness 0.25)
		(keepout
			(tracks not_allowed)
			(vias allowed)
			(pads allowed)
			(copperpour not_allowed)
			(footprints allowed)
		)
		(placement
			(enabled no)
			(sheetname "")
		)
		(fill
			(thermal_gap 0.5)
			(thermal_bridge_width 0.5)
			(island_removal_mode 0)
		)
		(polygon
			(pts
				(arc
					(start 287.08096 -377.728734)
					(mid 287.095839 -377.692813)
					(end 287.13176 -377.677934)
				)
				(arc
					(start 287.84804 -377.677934)
					(mid 287.883961 -377.692813)
					(end 287.89884 -377.728734)
				)
				(arc
					(start 287.89884 -380.151386)
					(mid 287.883961 -380.187307)
					(end 287.84804 -380.202186)
				)
				(arc
					(start 287.13176 -380.202186)
					(mid 287.095839 -380.187307)
					(end 287.08096 -380.151386)
				)
			)
		)
	)
	(zone
		(layers "F.Cu" "B.Cu" "In1.Cu" "In2.Cu" "In3.Cu" "In4.Cu" "In5.Cu" "In6.Cu"
			"In7.Cu" "In8.Cu" "In9.Cu" "In10.Cu" "In11.Cu" "In12.Cu" "In13.Cu" "In14.Cu"
			"In15.Cu" "In16.Cu"
		)
		(hatch none 0.5)
		(connect_pads
			(clearance 0)
		)
		(min_thickness 0.25)
		(keepout
			(tracks not_allowed)
			(vias allowed)
			(pads allowed)
			(copperpour not_allowed)
			(footprints allowed)
		)
		(placement
			(enabled no)
			(sheetname "")
		)
		(fill
			(thermal_gap 0.5)
			(thermal_bridge_width 0.5)
			(island_removal_mode 0)
		)
		(polygon
			(pts
				(arc
					(start 64.74587 -136.177274)
					(mid 65.20307 -136.634474)
					(end 65.66027 -136.177274)
				)
				(arc
					(start 65.66027 -135.313674)
					(mid 65.20307 -134.856474)
					(end 64.74587 -135.313674)
				)
			)
		)
	)
	(zone
		(layers "F.Cu" "B.Cu" "In1.Cu" "In2.Cu" "In3.Cu" "In4.Cu" "In5.Cu" "In6.Cu"
			"In7.Cu" "In8.Cu" "In9.Cu" "In10.Cu" "In11.Cu" "In12.Cu" "In13.Cu" "In14.Cu"
			"In15.Cu" "In16.Cu"
		)
		(hatch none 0.5)
		(connect_pads
			(clearance 0)
		)
		(min_thickness 0.25)
		(keepout
			(tracks not_allowed)
			(vias allowed)
			(pads allowed)
			(copperpour not_allowed)
			(footprints allowed)
		)
		(placement
			(enabled no)
			(sheetname "")
		)
		(fill
			(thermal_gap 0.5)
			(thermal_bridge_width 0.5)
			(island_removal_mode 0)
		)
		(polygon
			(pts
				(arc
					(start 31.90113 -369.928902)
					(mid 31.916009 -369.892981)
					(end 31.95193 -369.878102)
				)
				(arc
					(start 32.66821 -369.878102)
					(mid 32.704131 -369.892981)
					(end 32.71901 -369.928902)
				)
				(arc
					(start 32.71901 -372.351554)
					(mid 32.704131 -372.387475)
					(end 32.66821 -372.402354)
				)
				(arc
					(start 31.95193 -372.402354)
					(mid 31.916009 -372.387475)
					(end 31.90113 -372.351554)
				)
			)
		)
	)
	(zone
		(layers "F.Cu" "B.Cu" "In1.Cu" "In2.Cu" "In3.Cu" "In4.Cu" "In5.Cu" "In6.Cu"
			"In7.Cu" "In8.Cu" "In9.Cu" "In10.Cu" "In11.Cu" "In12.Cu" "In13.Cu" "In14.Cu"
			"In15.Cu" "In16.Cu"
		)
		(hatch none 0.5)
		(connect_pads
			(clearance 0)
		)
		(min_thickness 0.25)
		(keepout
			(tracks not_allowed)
			(vias allowed)
			(pads allowed)
			(copperpour not_allowed)
			(footprints allowed)
		)
		(placement
			(enabled no)
			(sheetname "")
		)
		(fill
			(thermal_gap 0.5)
			(thermal_bridge_width 0.5)
			(island_removal_mode 0)
		)
		(polygon
			(pts
				(arc
					(start 304.224436 -160.1851)
					(mid 302.090328 -160.1851)
					(end 304.224436 -160.1851)
				)
			)
		)
	)
	(zone
		(layers "F.Cu" "B.Cu" "In1.Cu" "In2.Cu" "In3.Cu" "In4.Cu" "In5.Cu" "In6.Cu"
			"In7.Cu" "In8.Cu" "In9.Cu" "In10.Cu" "In11.Cu" "In12.Cu" "In13.Cu" "In14.Cu"
			"In15.Cu" "In16.Cu"
		)
		(hatch none 0.5)
		(connect_pads
			(clearance 0)
		)
		(min_thickness 0.25)
		(keepout
			(tracks not_allowed)
			(vias allowed)
			(pads allowed)
			(copperpour not_allowed)
			(footprints allowed)
		)
		(placement
			(enabled no)
			(sheetname "")
		)
		(fill
			(thermal_gap 0.5)
			(thermal_bridge_width 0.5)
			(island_removal_mode 0)
		)
		(polygon
			(pts
				(arc
					(start 408.907488 -32.722312)
					(mid 409.364688 -33.179512)
					(end 409.821888 -32.722312)
				)
				(arc
					(start 409.821888 -31.858712)
					(mid 409.364688 -31.401512)
					(end 408.907488 -31.858712)
				)
			)
		)
	)
	(zone
		(layers "F.Cu" "B.Cu" "In1.Cu" "In2.Cu" "In3.Cu" "In4.Cu" "In5.Cu" "In6.Cu"
			"In7.Cu" "In8.Cu" "In9.Cu" "In10.Cu" "In11.Cu" "In12.Cu" "In13.Cu" "In14.Cu"
			"In15.Cu" "In16.Cu"
		)
		(hatch none 0.5)
		(connect_pads
			(clearance 0)
		)
		(min_thickness 0.25)
		(keepout
			(tracks not_allowed)
			(vias allowed)
			(pads allowed)
			(copperpour not_allowed)
			(footprints allowed)
		)
		(placement
			(enabled no)
			(sheetname "")
		)
		(fill
			(thermal_gap 0.5)
			(thermal_bridge_width 0.5)
			(island_removal_mode 0)
		)
		(polygon
			(pts
				(arc
					(start 44.204128 -357.37673)
					(mid 43.823128 -357.75773)
					(end 44.204128 -358.13873)
				)
				(arc
					(start 45.067728 -358.13873)
					(mid 45.448728 -357.75773)
					(end 45.067728 -357.37673)
				)
			)
		)
	)
	(zone
		(layers "F.Cu" "B.Cu" "In1.Cu" "In2.Cu" "In3.Cu" "In4.Cu" "In5.Cu" "In6.Cu"
			"In7.Cu" "In8.Cu" "In9.Cu" "In10.Cu" "In11.Cu" "In12.Cu" "In13.Cu" "In14.Cu"
			"In15.Cu" "In16.Cu"
		)
		(hatch none 0.5)
		(connect_pads
			(clearance 0)
		)
		(min_thickness 0.25)
		(keepout
			(tracks not_allowed)
			(vias allowed)
			(pads allowed)
			(copperpour not_allowed)
			(footprints allowed)
		)
		(placement
			(enabled no)
			(sheetname "")
		)
		(fill
			(thermal_gap 0.5)
			(thermal_bridge_width 0.5)
			(island_removal_mode 0)
		)
		(polygon
			(pts
				(arc
					(start 298.080938 -374.928638)
					(mid 298.095817 -374.892717)
					(end 298.131738 -374.877838)
				)
				(arc
					(start 298.848018 -374.877838)
					(mid 298.883939 -374.892717)
					(end 298.898818 -374.928638)
				)
				(arc
					(start 298.898818 -377.35129)
					(mid 298.883939 -377.387211)
					(end 298.848018 -377.40209)
				)
				(arc
					(start 298.131738 -377.40209)
					(mid 298.095817 -377.387211)
					(end 298.080938 -377.35129)
				)
			)
		)
	)
	(zone
		(layers "F.Cu" "B.Cu" "In1.Cu" "In2.Cu" "In3.Cu" "In4.Cu" "In5.Cu" "In6.Cu"
			"In7.Cu" "In8.Cu" "In9.Cu" "In10.Cu" "In11.Cu" "In12.Cu" "In13.Cu" "In14.Cu"
			"In15.Cu" "In16.Cu"
		)
		(hatch none 0.5)
		(connect_pads
			(clearance 0)
		)
		(min_thickness 0.25)
		(keepout
			(tracks not_allowed)
			(vias allowed)
			(pads allowed)
			(copperpour not_allowed)
			(footprints allowed)
		)
		(placement
			(enabled no)
			(sheetname "")
		)
		(fill
			(thermal_gap 0.5)
			(thermal_bridge_width 0.5)
			(island_removal_mode 0)
		)
		(polygon
			(pts
				(arc
					(start 339.88121 -399.828766)
					(mid 339.896089 -399.792845)
					(end 339.93201 -399.777966)
				)
				(arc
					(start 340.64829 -399.777966)
					(mid 340.684211 -399.792845)
					(end 340.69909 -399.828766)
				)
				(arc
					(start 340.69909 -402.251418)
					(mid 340.684211 -402.287339)
					(end 340.64829 -402.302218)
				)
				(arc
					(start 339.93201 -402.302218)
					(mid 339.896089 -402.287339)
					(end 339.88121 -402.251418)
				)
			)
		)
	)
	(zone
		(layers "F.Cu" "B.Cu" "In1.Cu" "In2.Cu" "In3.Cu" "In4.Cu" "In5.Cu" "In6.Cu"
			"In7.Cu" "In8.Cu" "In9.Cu" "In10.Cu" "In11.Cu" "In12.Cu" "In13.Cu" "In14.Cu"
			"In15.Cu" "In16.Cu"
		)
		(hatch none 0.5)
		(connect_pads
			(clearance 0)
		)
		(min_thickness 0.25)
		(keepout
			(tracks not_allowed)
			(vias allowed)
			(pads allowed)
			(copperpour not_allowed)
			(footprints allowed)
		)
		(placement
			(enabled no)
			(sheetname "")
		)
		(fill
			(thermal_gap 0.5)
			(thermal_bridge_width 0.5)
			(island_removal_mode 0)
		)
		(polygon
			(pts
				(arc
					(start 40.70096 -403.728682)
					(mid 40.715839 -403.692761)
					(end 40.75176 -403.677882)
				)
				(arc
					(start 41.46804 -403.677882)
					(mid 41.503961 -403.692761)
					(end 41.51884 -403.728682)
				)
				(arc
					(start 41.51884 -406.151334)
					(mid 41.503961 -406.187255)
					(end 41.46804 -406.202134)
				)
				(arc
					(start 40.75176 -406.202134)
					(mid 40.715839 -406.187255)
					(end 40.70096 -406.151334)
				)
			)
		)
	)
	(zone
		(layers "F.Cu" "B.Cu" "In1.Cu" "In2.Cu" "In3.Cu" "In4.Cu" "In5.Cu" "In6.Cu"
			"In7.Cu" "In8.Cu" "In9.Cu" "In10.Cu" "In11.Cu" "In12.Cu" "In13.Cu" "In14.Cu"
			"In15.Cu" "In16.Cu"
		)
		(hatch none 0.5)
		(connect_pads
			(clearance 0)
		)
		(min_thickness 0.25)
		(keepout
			(tracks not_allowed)
			(vias allowed)
			(pads allowed)
			(copperpour not_allowed)
			(footprints allowed)
		)
		(placement
			(enabled no)
			(sheetname "")
		)
		(fill
			(thermal_gap 0.5)
			(thermal_bridge_width 0.5)
			(island_removal_mode 0)
		)
		(polygon
			(pts
				(arc
					(start 287.08096 -381.628904)
					(mid 287.095839 -381.592983)
					(end 287.13176 -381.578104)
				)
				(arc
					(start 287.84804 -381.578104)
					(mid 287.883961 -381.592983)
					(end 287.89884 -381.628904)
				)
				(arc
					(start 287.89884 -384.051556)
					(mid 287.883961 -384.087477)
					(end 287.84804 -384.102356)
				)
				(arc
					(start 287.13176 -384.102356)
					(mid 287.095839 -384.087477)
					(end 287.08096 -384.051556)
				)
			)
		)
	)
	(zone
		(layers "F.Cu" "B.Cu" "In1.Cu" "In2.Cu" "In3.Cu" "In4.Cu" "In5.Cu" "In6.Cu"
			"In7.Cu" "In8.Cu" "In9.Cu" "In10.Cu" "In11.Cu" "In12.Cu" "In13.Cu" "In14.Cu"
			"In15.Cu" "In16.Cu"
		)
		(hatch none 0.5)
		(connect_pads
			(clearance 0)
		)
		(min_thickness 0.25)
		(keepout
			(tracks not_allowed)
			(vias allowed)
			(pads allowed)
			(copperpour not_allowed)
			(footprints allowed)
		)
		(placement
			(enabled no)
			(sheetname "")
		)
		(fill
			(thermal_gap 0.5)
			(thermal_bridge_width 0.5)
			(island_removal_mode 0)
		)
		(polygon
			(pts
				(arc
					(start 82.500978 -374.928638)
					(mid 82.515857 -374.892717)
					(end 82.551778 -374.877838)
				)
				(arc
					(start 83.268058 -374.877838)
					(mid 83.303979 -374.892717)
					(end 83.318858 -374.928638)
				)
				(arc
					(start 83.318858 -377.35129)
					(mid 83.303979 -377.387211)
					(end 83.268058 -377.40209)
				)
				(arc
					(start 82.551778 -377.40209)
					(mid 82.515857 -377.387211)
					(end 82.500978 -377.35129)
				)
			)
		)
	)
	(zone
		(layers "F.Cu" "B.Cu" "In1.Cu" "In2.Cu" "In3.Cu" "In4.Cu" "In5.Cu" "In6.Cu"
			"In7.Cu" "In8.Cu" "In9.Cu" "In10.Cu" "In11.Cu" "In12.Cu" "In13.Cu" "In14.Cu"
			"In15.Cu" "In16.Cu"
		)
		(hatch none 0.5)
		(connect_pads
			(clearance 0)
		)
		(min_thickness 0.25)
		(keepout
			(tracks not_allowed)
			(vias allowed)
			(pads allowed)
			(copperpour not_allowed)
			(footprints allowed)
		)
		(placement
			(enabled no)
			(sheetname "")
		)
		(fill
			(thermal_gap 0.5)
			(thermal_bridge_width 0.5)
			(island_removal_mode 0)
		)
		(polygon
			(pts
				(arc
					(start 177.730912 -348.20479)
					(mid 177.349912 -348.58579)
					(end 177.730912 -348.96679)
				)
				(arc
					(start 178.594512 -348.96679)
					(mid 178.975512 -348.58579)
					(end 178.594512 -348.20479)
				)
			)
		)
	)
	(zone
		(layers "F.Cu" "B.Cu" "In1.Cu" "In2.Cu" "In3.Cu" "In4.Cu" "In5.Cu" "In6.Cu"
			"In7.Cu" "In8.Cu" "In9.Cu" "In10.Cu" "In11.Cu" "In12.Cu" "In13.Cu" "In14.Cu"
			"In15.Cu" "In16.Cu"
		)
		(hatch none 0.5)
		(connect_pads
			(clearance 0)
		)
		(min_thickness 0.25)
		(keepout
			(tracks not_allowed)
			(vias allowed)
			(pads allowed)
			(copperpour not_allowed)
			(footprints allowed)
		)
		(placement
			(enabled no)
			(sheetname "")
		)
		(fill
			(thermal_gap 0.5)
			(thermal_bridge_width 0.5)
			(island_removal_mode 0)
		)
		(polygon
			(pts
				(arc
					(start 22.441408 -342.058498)
					(mid 22.060408 -342.439498)
					(end 22.441408 -342.820498)
				)
				(arc
					(start 23.305008 -342.820498)
					(mid 23.686008 -342.439498)
					(end 23.305008 -342.058498)
				)
			)
		)
	)
	(zone
		(layers "F.Cu" "B.Cu" "In1.Cu" "In2.Cu" "In3.Cu" "In4.Cu" "In5.Cu" "In6.Cu"
			"In7.Cu" "In8.Cu" "In9.Cu" "In10.Cu" "In11.Cu" "In12.Cu" "In13.Cu" "In14.Cu"
			"In15.Cu" "In16.Cu"
		)
		(hatch none 0.5)
		(connect_pads
			(clearance 0)
		)
		(min_thickness 0.25)
		(keepout
			(tracks not_allowed)
			(vias allowed)
			(pads allowed)
			(copperpour not_allowed)
			(footprints allowed)
		)
		(placement
			(enabled no)
			(sheetname "")
		)
		(fill
			(thermal_gap 0.5)
			(thermal_bridge_width 0.5)
			(island_removal_mode 0)
		)
		(polygon
			(pts
				(arc
					(start 432.280822 -395.92885)
					(mid 432.295701 -395.892929)
					(end 432.331622 -395.87805)
				)
				(arc
					(start 433.047902 -395.87805)
					(mid 433.083823 -395.892929)
					(end 433.098702 -395.92885)
				)
				(arc
					(start 433.098702 -398.351502)
					(mid 433.083823 -398.387423)
					(end 433.047902 -398.402302)
				)
				(arc
					(start 432.331622 -398.402302)
					(mid 432.295701 -398.387423)
					(end 432.280822 -398.351502)
				)
			)
		)
	)
	(zone
		(layers "F.Cu" "B.Cu" "In1.Cu" "In2.Cu" "In3.Cu" "In4.Cu" "In5.Cu" "In6.Cu"
			"In7.Cu" "In8.Cu" "In9.Cu" "In10.Cu" "In11.Cu" "In12.Cu" "In13.Cu" "In14.Cu"
			"In15.Cu" "In16.Cu"
		)
		(hatch none 0.5)
		(connect_pads
			(clearance 0)
		)
		(min_thickness 0.25)
		(keepout
			(tracks not_allowed)
			(vias allowed)
			(pads allowed)
			(copperpour not_allowed)
			(footprints allowed)
		)
		(placement
			(enabled no)
			(sheetname "")
		)
		(fill
			(thermal_gap 0.5)
			(thermal_bridge_width 0.5)
			(island_removal_mode 0)
		)
		(polygon
			(pts
				(arc
					(start 284.899862 -101.112828)
					(mid 284.442662 -100.655628)
					(end 283.985462 -101.112828)
				)
				(arc
					(start 283.985462 -101.976428)
					(mid 284.442662 -102.433628)
					(end 284.899862 -101.976428)
				)
			)
		)
	)
	(zone
		(layers "F.Cu" "B.Cu" "In1.Cu" "In2.Cu" "In3.Cu" "In4.Cu" "In5.Cu" "In6.Cu"
			"In7.Cu" "In8.Cu" "In9.Cu" "In10.Cu" "In11.Cu" "In12.Cu" "In13.Cu" "In14.Cu"
			"In15.Cu" "In16.Cu"
		)
		(hatch none 0.5)
		(connect_pads
			(clearance 0)
		)
		(min_thickness 0.25)
		(keepout
			(tracks not_allowed)
			(vias allowed)
			(pads allowed)
			(copperpour not_allowed)
			(footprints allowed)
		)
		(placement
			(enabled no)
			(sheetname "")
		)
		(fill
			(thermal_gap 0.5)
			(thermal_bridge_width 0.5)
			(island_removal_mode 0)
		)
		(polygon
			(pts
				(arc
					(start 212.948012 -32.714184)
					(mid 213.405212 -33.171384)
					(end 213.862412 -32.714184)
				)
				(arc
					(start 213.862412 -31.850584)
					(mid 213.405212 -31.393384)
					(end 212.948012 -31.850584)
				)
			)
		)
	)
	(zone
		(layers "F.Cu" "B.Cu" "In1.Cu" "In2.Cu" "In3.Cu" "In4.Cu" "In5.Cu" "In6.Cu"
			"In7.Cu" "In8.Cu" "In9.Cu" "In10.Cu" "In11.Cu" "In12.Cu" "In13.Cu" "In14.Cu"
			"In15.Cu" "In16.Cu"
		)
		(hatch none 0.5)
		(connect_pads
			(clearance 0)
		)
		(min_thickness 0.25)
		(keepout
			(tracks not_allowed)
			(vias allowed)
			(pads allowed)
			(copperpour not_allowed)
			(footprints allowed)
		)
		(placement
			(enabled no)
			(sheetname "")
		)
		(fill
			(thermal_gap 0.5)
			(thermal_bridge_width 0.5)
			(island_removal_mode 0)
		)
		(polygon
			(pts
				(arc
					(start 86.243922 -342.058498)
					(mid 85.862922 -342.439498)
					(end 86.243922 -342.820498)
				)
				(arc
					(start 87.107522 -342.820498)
					(mid 87.488522 -342.439498)
					(end 87.107522 -342.058498)
				)
			)
		)
	)
	(zone
		(layers "F.Cu" "B.Cu" "In1.Cu" "In2.Cu" "In3.Cu" "In4.Cu" "In5.Cu" "In6.Cu"
			"In7.Cu" "In8.Cu" "In9.Cu" "In10.Cu" "In11.Cu" "In12.Cu" "In13.Cu" "In14.Cu"
			"In15.Cu" "In16.Cu"
		)
		(hatch none 0.5)
		(connect_pads
			(clearance 0)
		)
		(min_thickness 0.25)
		(keepout
			(tracks not_allowed)
			(vias allowed)
			(pads allowed)
			(copperpour not_allowed)
			(footprints allowed)
		)
		(placement
			(enabled no)
			(sheetname "")
		)
		(fill
			(thermal_gap 0.5)
			(thermal_bridge_width 0.5)
			(island_removal_mode 0)
		)
		(polygon
			(pts
				(arc
					(start 300.280832 -369.928902)
					(mid 300.295711 -369.892981)
					(end 300.331632 -369.878102)
				)
				(arc
					(start 301.047912 -369.878102)
					(mid 301.083833 -369.892981)
					(end 301.098712 -369.928902)
				)
				(arc
					(start 301.098712 -372.351554)
					(mid 301.083833 -372.387475)
					(end 301.047912 -372.402354)
				)
				(arc
					(start 300.331632 -372.402354)
					(mid 300.295711 -372.387475)
					(end 300.280832 -372.351554)
				)
			)
		)
	)
	(zone
		(layers "F.Cu" "B.Cu" "In1.Cu" "In2.Cu" "In3.Cu" "In4.Cu" "In5.Cu" "In6.Cu"
			"In7.Cu" "In8.Cu" "In9.Cu" "In10.Cu" "In11.Cu" "In12.Cu" "In13.Cu" "In14.Cu"
			"In15.Cu" "In16.Cu"
		)
		(hatch none 0.5)
		(connect_pads
			(clearance 0)
		)
		(min_thickness 0.25)
		(keepout
			(tracks not_allowed)
			(vias allowed)
			(pads allowed)
			(copperpour not_allowed)
			(footprints allowed)
		)
		(placement
			(enabled no)
			(sheetname "")
		)
		(fill
			(thermal_gap 0.5)
			(thermal_bridge_width 0.5)
			(island_removal_mode 0)
		)
		(polygon
			(pts
				(arc
					(start 344.280998 -399.828766)
					(mid 344.295877 -399.792845)
					(end 344.331798 -399.777966)
				)
				(arc
					(start 345.048078 -399.777966)
					(mid 345.083999 -399.792845)
					(end 345.098878 -399.828766)
				)
				(arc
					(start 345.098878 -402.251418)
					(mid 345.083999 -402.287339)
					(end 345.048078 -402.302218)
				)
				(arc
					(start 344.331798 -402.302218)
					(mid 344.295877 -402.287339)
					(end 344.280998 -402.251418)
				)
			)
		)
	)
	(zone
		(layers "F.Cu" "B.Cu" "In1.Cu" "In2.Cu" "In3.Cu" "In4.Cu" "In5.Cu" "In6.Cu"
			"In7.Cu" "In8.Cu" "In9.Cu" "In10.Cu" "In11.Cu" "In12.Cu" "In13.Cu" "In14.Cu"
			"In15.Cu" "In16.Cu"
		)
		(hatch none 0.5)
		(connect_pads
			(clearance 0)
		)
		(min_thickness 0.25)
		(keepout
			(tracks not_allowed)
			(vias allowed)
			(pads allowed)
			(copperpour not_allowed)
			(footprints allowed)
		)
		(placement
			(enabled no)
			(sheetname "")
		)
		(fill
			(thermal_gap 0.5)
			(thermal_bridge_width 0.5)
			(island_removal_mode 0)
		)
		(polygon
			(pts
				(arc
					(start 315.611764 -357.37673)
					(mid 315.230764 -357.75773)
					(end 315.611764 -358.13873)
				)
				(arc
					(start 316.475364 -358.13873)
					(mid 316.856364 -357.75773)
					(end 316.475364 -357.37673)
				)
			)
		)
	)
	(zone
		(layers "F.Cu" "B.Cu" "In1.Cu" "In2.Cu" "In3.Cu" "In4.Cu" "In5.Cu" "In6.Cu"
			"In7.Cu" "In8.Cu" "In9.Cu" "In10.Cu" "In11.Cu" "In12.Cu" "In13.Cu" "In14.Cu"
			"In15.Cu" "In16.Cu"
		)
		(hatch none 0.5)
		(connect_pads
			(clearance 0)
		)
		(min_thickness 0.25)
		(keepout
			(tracks not_allowed)
			(vias allowed)
			(pads allowed)
			(copperpour not_allowed)
			(footprints allowed)
		)
		(placement
			(enabled no)
			(sheetname "")
		)
		(fill
			(thermal_gap 0.5)
			(thermal_bridge_width 0.5)
			(island_removal_mode 0)
		)
		(polygon
			(pts
				(arc
					(start 383.62382 -342.058498)
					(mid 383.24282 -342.439498)
					(end 383.62382 -342.820498)
				)
				(arc
					(start 384.48742 -342.820498)
					(mid 384.86842 -342.439498)
					(end 384.48742 -342.058498)
				)
			)
		)
	)
	(zone
		(layers "F.Cu" "B.Cu" "In1.Cu" "In2.Cu" "In3.Cu" "In4.Cu" "In5.Cu" "In6.Cu"
			"In7.Cu" "In8.Cu" "In9.Cu" "In10.Cu" "In11.Cu" "In12.Cu" "In13.Cu" "In14.Cu"
			"In15.Cu" "In16.Cu"
		)
		(hatch none 0.5)
		(connect_pads
			(clearance 0)
		)
		(min_thickness 0.25)
		(keepout
			(tracks not_allowed)
			(vias allowed)
			(pads allowed)
			(copperpour not_allowed)
			(footprints allowed)
		)
		(placement
			(enabled no)
			(sheetname "")
		)
		(fill
			(thermal_gap 0.5)
			(thermal_bridge_width 0.5)
			(island_removal_mode 0)
		)
		(polygon
			(pts
				(arc
					(start 340.483444 -357.37673)
					(mid 340.102444 -357.75773)
					(end 340.483444 -358.13873)
				)
				(arc
					(start 341.347044 -358.13873)
					(mid 341.728044 -357.75773)
					(end 341.347044 -357.37673)
				)
			)
		)
	)
	(zone
		(layers "F.Cu" "B.Cu" "In1.Cu" "In2.Cu" "In3.Cu" "In4.Cu" "In5.Cu" "In6.Cu"
			"In7.Cu" "In8.Cu" "In9.Cu" "In10.Cu" "In11.Cu" "In12.Cu" "In13.Cu" "In14.Cu"
			"In15.Cu" "In16.Cu"
		)
		(hatch none 0.5)
		(connect_pads
			(clearance 0)
		)
		(min_thickness 0.25)
		(keepout
			(tracks not_allowed)
			(vias allowed)
			(pads allowed)
			(copperpour not_allowed)
			(footprints allowed)
		)
		(placement
			(enabled no)
			(sheetname "")
		)
		(fill
			(thermal_gap 0.5)
			(thermal_bridge_width 0.5)
			(island_removal_mode 0)
		)
		(polygon
			(pts
				(arc
					(start 386.081016 -371.028722)
					(mid 386.095895 -370.992801)
					(end 386.131816 -370.977922)
				)
				(arc
					(start 386.848096 -370.977922)
					(mid 386.884017 -370.992801)
					(end 386.898896 -371.028722)
				)
				(arc
					(start 386.898896 -373.451374)
					(mid 386.884017 -373.487295)
					(end 386.848096 -373.502174)
				)
				(arc
					(start 386.131816 -373.502174)
					(mid 386.095895 -373.487295)
					(end 386.081016 -373.451374)
				)
			)
		)
	)
	(zone
		(layers "F.Cu" "B.Cu" "In1.Cu" "In2.Cu" "In3.Cu" "In4.Cu" "In5.Cu" "In6.Cu"
			"In7.Cu" "In8.Cu" "In9.Cu" "In10.Cu" "In11.Cu" "In12.Cu" "In13.Cu" "In14.Cu"
			"In15.Cu" "In16.Cu"
		)
		(hatch none 0.5)
		(connect_pads
			(clearance 0)
		)
		(min_thickness 0.25)
		(keepout
			(tracks not_allowed)
			(vias allowed)
			(pads allowed)
			(copperpour not_allowed)
			(footprints allowed)
		)
		(placement
			(enabled no)
			(sheetname "")
		)
		(fill
			(thermal_gap 0.5)
			(thermal_bridge_width 0.5)
			(island_removal_mode 0)
		)
		(polygon
			(pts
				(arc
					(start 274.115022 -348.20479)
					(mid 273.734022 -348.58579)
					(end 274.115022 -348.96679)
				)
				(arc
					(start 274.978622 -348.96679)
					(mid 275.359622 -348.58579)
					(end 274.978622 -348.20479)
				)
			)
		)
	)
	(zone
		(layers "F.Cu" "B.Cu" "In1.Cu" "In2.Cu" "In3.Cu" "In4.Cu" "In5.Cu" "In6.Cu"
			"In7.Cu" "In8.Cu" "In9.Cu" "In10.Cu" "In11.Cu" "In12.Cu" "In13.Cu" "In14.Cu"
			"In15.Cu" "In16.Cu"
		)
		(hatch none 0.5)
		(connect_pads
			(clearance 0)
		)
		(min_thickness 0.25)
		(keepout
			(tracks not_allowed)
			(vias allowed)
			(pads allowed)
			(copperpour not_allowed)
			(footprints allowed)
		)
		(placement
			(enabled no)
			(sheetname "")
		)
		(fill
			(thermal_gap 0.5)
			(thermal_bridge_width 0.5)
			(island_removal_mode 0)
		)
		(polygon
			(pts
				(arc
					(start 355.053392 -30.922468)
					(mid 355.510592 -31.379668)
					(end 355.967792 -30.922468)
				)
				(arc
					(start 355.967792 -30.058868)
					(mid 355.510592 -29.601668)
					(end 355.053392 -30.058868)
				)
			)
		)
	)
	(zone
		(layers "F.Cu" "B.Cu" "In1.Cu" "In2.Cu" "In3.Cu" "In4.Cu" "In5.Cu" "In6.Cu"
			"In7.Cu" "In8.Cu" "In9.Cu" "In10.Cu" "In11.Cu" "In12.Cu" "In13.Cu" "In14.Cu"
			"In15.Cu" "In16.Cu"
		)
		(hatch none 0.5)
		(connect_pads
			(clearance 0)
		)
		(min_thickness 0.25)
		(keepout
			(tracks not_allowed)
			(vias allowed)
			(pads allowed)
			(copperpour not_allowed)
			(footprints allowed)
		)
		(placement
			(enabled no)
			(sheetname "")
		)
		(fill
			(thermal_gap 0.5)
			(thermal_bridge_width 0.5)
			(island_removal_mode 0)
		)
		(polygon
			(pts
				(arc
					(start 41.095168 -345.084146)
					(mid 40.714168 -345.465146)
					(end 41.095168 -345.846146)
				)
				(arc
					(start 41.958768 -345.846146)
					(mid 42.339768 -345.465146)
					(end 41.958768 -345.084146)
				)
			)
		)
	)
	(zone
		(layers "F.Cu" "B.Cu" "In1.Cu" "In2.Cu" "In3.Cu" "In4.Cu" "In5.Cu" "In6.Cu"
			"In7.Cu" "In8.Cu" "In9.Cu" "In10.Cu" "In11.Cu" "In12.Cu" "In13.Cu" "In14.Cu"
			"In15.Cu" "In16.Cu"
		)
		(hatch none 0.5)
		(connect_pads
			(clearance 0)
		)
		(min_thickness 0.25)
		(keepout
			(tracks not_allowed)
			(vias allowed)
			(pads allowed)
			(copperpour not_allowed)
			(footprints allowed)
		)
		(placement
			(enabled no)
			(sheetname "")
		)
		(fill
			(thermal_gap 0.5)
			(thermal_bridge_width 0.5)
			(island_removal_mode 0)
		)
		(polygon
			(pts
				(arc
					(start 67.590162 -342.058498)
					(mid 67.209162 -342.439498)
					(end 67.590162 -342.820498)
				)
				(arc
					(start 68.453762 -342.820498)
					(mid 68.834762 -342.439498)
					(end 68.453762 -342.058498)
				)
			)
		)
	)
	(zone
		(layers "F.Cu" "B.Cu" "In1.Cu" "In2.Cu" "In3.Cu" "In4.Cu" "In5.Cu" "In6.Cu"
			"In7.Cu" "In8.Cu" "In9.Cu" "In10.Cu" "In11.Cu" "In12.Cu" "In13.Cu" "In14.Cu"
			"In15.Cu" "In16.Cu"
		)
		(hatch none 0.5)
		(connect_pads
			(clearance 0)
		)
		(min_thickness 0.25)
		(keepout
			(tracks not_allowed)
			(vias allowed)
			(pads allowed)
			(copperpour not_allowed)
			(footprints allowed)
		)
		(placement
			(enabled no)
			(sheetname "")
		)
		(fill
			(thermal_gap 0.5)
			(thermal_bridge_width 0.5)
			(island_removal_mode 0)
		)
		(polygon
			(pts
				(arc
					(start 415.513012 -354.351082)
					(mid 415.132012 -354.732082)
					(end 415.513012 -355.113082)
				)
				(arc
					(start 416.376612 -355.113082)
					(mid 416.757612 -354.732082)
					(end 416.376612 -354.351082)
				)
			)
		)
	)
	(zone
		(layers "F.Cu" "B.Cu" "In1.Cu" "In2.Cu" "In3.Cu" "In4.Cu" "In5.Cu" "In6.Cu"
			"In7.Cu" "In8.Cu" "In9.Cu" "In10.Cu" "In11.Cu" "In12.Cu" "In13.Cu" "In14.Cu"
			"In15.Cu" "In16.Cu"
		)
		(hatch none 0.5)
		(connect_pads
			(clearance 0)
		)
		(min_thickness 0.25)
		(keepout
			(tracks not_allowed)
			(vias allowed)
			(pads allowed)
			(copperpour not_allowed)
			(footprints allowed)
		)
		(placement
			(enabled no)
			(sheetname "")
		)
		(fill
			(thermal_gap 0.5)
			(thermal_bridge_width 0.5)
			(island_removal_mode 0)
		)
		(polygon
			(pts
				(arc
					(start 119.901208 -407.628852)
					(mid 119.916087 -407.592931)
					(end 119.952008 -407.578052)
				)
				(arc
					(start 120.668288 -407.578052)
					(mid 120.704209 -407.592931)
					(end 120.719088 -407.628852)
				)
				(arc
					(start 120.719088 -410.051504)
					(mid 120.704209 -410.087425)
					(end 120.668288 -410.102304)
				)
				(arc
					(start 119.952008 -410.102304)
					(mid 119.916087 -410.087425)
					(end 119.901208 -410.051504)
				)
			)
		)
	)
	(zone
		(layers "F.Cu" "B.Cu" "In1.Cu" "In2.Cu" "In3.Cu" "In4.Cu" "In5.Cu" "In6.Cu"
			"In7.Cu" "In8.Cu" "In9.Cu" "In10.Cu" "In11.Cu" "In12.Cu" "In13.Cu" "In14.Cu"
			"In15.Cu" "In16.Cu"
		)
		(hatch none 0.5)
		(connect_pads
			(clearance 0)
		)
		(min_thickness 0.25)
		(keepout
			(tracks not_allowed)
			(vias allowed)
			(pads allowed)
			(copperpour not_allowed)
			(footprints allowed)
		)
		(placement
			(enabled no)
			(sheetname "")
		)
		(fill
			(thermal_gap 0.5)
			(thermal_bridge_width 0.5)
			(island_removal_mode 0)
		)
		(polygon
			(pts
				(arc
					(start 296.945812 -148.887434)
					(mid 297.403012 -149.344634)
					(end 297.860212 -148.887434)
				)
				(arc
					(start 297.860212 -148.023834)
					(mid 297.403012 -147.566634)
					(end 296.945812 -148.023834)
				)
			)
		)
	)
	(zone
		(layers "F.Cu" "B.Cu" "In1.Cu" "In2.Cu" "In3.Cu" "In4.Cu" "In5.Cu" "In6.Cu"
			"In7.Cu" "In8.Cu" "In9.Cu" "In10.Cu" "In11.Cu" "In12.Cu" "In13.Cu" "In14.Cu"
			"In15.Cu" "In16.Cu"
		)
		(hatch none 0.5)
		(connect_pads
			(clearance 0)
		)
		(min_thickness 0.25)
		(keepout
			(tracks not_allowed)
			(vias allowed)
			(pads allowed)
			(copperpour not_allowed)
			(footprints allowed)
		)
		(placement
			(enabled no)
			(sheetname "")
		)
		(fill
			(thermal_gap 0.5)
			(thermal_bridge_width 0.5)
			(island_removal_mode 0)
		)
		(polygon
			(pts
				(arc
					(start 337.681062 -400.92884)
					(mid 337.695941 -400.892919)
					(end 337.731862 -400.87804)
				)
				(arc
					(start 338.448142 -400.87804)
					(mid 338.484063 -400.892919)
					(end 338.498942 -400.92884)
				)
				(arc
					(start 338.498942 -403.351492)
					(mid 338.484063 -403.387413)
					(end 338.448142 -403.402292)
				)
				(arc
					(start 337.731862 -403.402292)
					(mid 337.695941 -403.387413)
					(end 337.681062 -403.351492)
				)
			)
		)
	)
	(zone
		(layers "F.Cu" "B.Cu" "In1.Cu" "In2.Cu" "In3.Cu" "In4.Cu" "In5.Cu" "In6.Cu"
			"In7.Cu" "In8.Cu" "In9.Cu" "In10.Cu" "In11.Cu" "In12.Cu" "In13.Cu" "In14.Cu"
			"In15.Cu" "In16.Cu"
		)
		(hatch none 0.5)
		(connect_pads
			(clearance 0)
		)
		(min_thickness 0.25)
		(keepout
			(tracks not_allowed)
			(vias allowed)
			(pads allowed)
			(copperpour not_allowed)
			(footprints allowed)
		)
		(placement
			(enabled no)
			(sheetname "")
		)
		(fill
			(thermal_gap 0.5)
			(thermal_bridge_width 0.5)
			(island_removal_mode 0)
		)
		(polygon
			(pts
				(arc
					(start 377.280932 -378.828554)
					(mid 377.295811 -378.792633)
					(end 377.331732 -378.777754)
				)
				(arc
					(start 378.048012 -378.777754)
					(mid 378.083933 -378.792633)
					(end 378.098812 -378.828554)
				)
				(arc
					(start 378.098812 -381.251206)
					(mid 378.083933 -381.287127)
					(end 378.048012 -381.302006)
				)
				(arc
					(start 377.331732 -381.302006)
					(mid 377.295811 -381.287127)
					(end 377.280932 -381.251206)
				)
			)
		)
	)
	(zone
		(layers "F.Cu" "B.Cu" "In1.Cu" "In2.Cu" "In3.Cu" "In4.Cu" "In5.Cu" "In6.Cu"
			"In7.Cu" "In8.Cu" "In9.Cu" "In10.Cu" "In11.Cu" "In12.Cu" "In13.Cu" "In14.Cu"
			"In15.Cu" "In16.Cu"
		)
		(hatch none 0.5)
		(connect_pads
			(clearance 0)
		)
		(min_thickness 0.25)
		(keepout
			(tracks not_allowed)
			(vias allowed)
			(pads allowed)
			(copperpour not_allowed)
			(footprints allowed)
		)
		(placement
			(enabled no)
			(sheetname "")
		)
		(fill
			(thermal_gap 0.5)
			(thermal_bridge_width 0.5)
			(island_removal_mode 0)
		)
		(polygon
			(pts
				(arc
					(start 200.853294 -34.52241)
					(mid 201.310494 -34.97961)
					(end 201.767694 -34.52241)
				)
				(arc
					(start 201.767694 -33.65881)
					(mid 201.310494 -33.20161)
					(end 200.853294 -33.65881)
				)
			)
		)
	)
	(zone
		(layers "F.Cu" "B.Cu" "In1.Cu" "In2.Cu" "In3.Cu" "In4.Cu" "In5.Cu" "In6.Cu"
			"In7.Cu" "In8.Cu" "In9.Cu" "In10.Cu" "In11.Cu" "In12.Cu" "In13.Cu" "In14.Cu"
			"In15.Cu" "In16.Cu"
		)
		(hatch none 0.5)
		(connect_pads
			(clearance 0)
		)
		(min_thickness 0.25)
		(keepout
			(tracks not_allowed)
			(vias allowed)
			(pads allowed)
			(copperpour not_allowed)
			(footprints allowed)
		)
		(placement
			(enabled no)
			(sheetname "")
		)
		(fill
			(thermal_gap 0.5)
			(thermal_bridge_width 0.5)
			(island_removal_mode 0)
		)
		(polygon
			(pts
				(arc
					(start 339.391498 17.603724)
					(mid 339.772498 17.222724)
					(end 340.153498 17.603724)
				)
				(arc
					(start 340.153498 18.467324)
					(mid 339.772498 18.848324)
					(end 339.391498 18.467324)
				)
			)
		)
	)
	(zone
		(layers "F.Cu" "B.Cu" "In1.Cu" "In2.Cu" "In3.Cu" "In4.Cu" "In5.Cu" "In6.Cu"
			"In7.Cu" "In8.Cu" "In9.Cu" "In10.Cu" "In11.Cu" "In12.Cu" "In13.Cu" "In14.Cu"
			"In15.Cu" "In16.Cu"
		)
		(hatch none 0.5)
		(connect_pads
			(clearance 0)
		)
		(min_thickness 0.25)
		(keepout
			(tracks not_allowed)
			(vias allowed)
			(pads allowed)
			(copperpour not_allowed)
			(footprints allowed)
		)
		(placement
			(enabled no)
			(sheetname "")
		)
		(fill
			(thermal_gap 0.5)
			(thermal_bridge_width 0.5)
			(island_removal_mode 0)
		)
		(polygon
			(pts
				(arc
					(start 39.224966 -288.154618)
					(mid 39.555166 -287.824418)
					(end 39.224966 -287.494218)
				)
				(arc
					(start 38.275006 -287.494218)
					(mid 37.944806 -287.824418)
					(end 38.275006 -288.154618)
				)
			)
		)
	)
	(zone
		(layers "F.Cu" "B.Cu" "In1.Cu" "In2.Cu" "In3.Cu" "In4.Cu" "In5.Cu" "In6.Cu"
			"In7.Cu" "In8.Cu" "In9.Cu" "In10.Cu" "In11.Cu" "In12.Cu" "In13.Cu" "In14.Cu"
			"In15.Cu" "In16.Cu"
		)
		(hatch none 0.5)
		(connect_pads
			(clearance 0)
		)
		(min_thickness 0.25)
		(keepout
			(tracks not_allowed)
			(vias allowed)
			(pads allowed)
			(copperpour not_allowed)
			(footprints allowed)
		)
		(placement
			(enabled no)
			(sheetname "")
		)
		(fill
			(thermal_gap 0.5)
			(thermal_bridge_width 0.5)
			(island_removal_mode 0)
		)
		(polygon
			(pts
				(arc
					(start 342.081104 -404.828756)
					(mid 342.095983 -404.792835)
					(end 342.131904 -404.777956)
				)
				(arc
					(start 342.848184 -404.777956)
					(mid 342.884105 -404.792835)
					(end 342.898984 -404.828756)
				)
				(arc
					(start 342.898984 -407.251408)
					(mid 342.884105 -407.287329)
					(end 342.848184 -407.302208)
				)
				(arc
					(start 342.131904 -407.302208)
					(mid 342.095983 -407.287329)
					(end 342.081104 -407.251408)
				)
			)
		)
	)
	(zone
		(layers "F.Cu" "B.Cu" "In1.Cu" "In2.Cu" "In3.Cu" "In4.Cu" "In5.Cu" "In6.Cu"
			"In7.Cu" "In8.Cu" "In9.Cu" "In10.Cu" "In11.Cu" "In12.Cu" "In13.Cu" "In14.Cu"
			"In15.Cu" "In16.Cu"
		)
		(hatch none 0.5)
		(connect_pads
			(clearance 0)
		)
		(min_thickness 0.25)
		(keepout
			(tracks not_allowed)
			(vias allowed)
			(pads allowed)
			(copperpour not_allowed)
			(footprints allowed)
		)
		(placement
			(enabled no)
			(sheetname "")
		)
		(fill
			(thermal_gap 0.5)
			(thermal_bridge_width 0.5)
			(island_removal_mode 0)
		)
		(polygon
			(pts
				(arc
					(start 286.550862 -351.230438)
					(mid 286.169862 -351.611438)
					(end 286.550862 -351.992438)
				)
				(arc
					(start 287.414462 -351.992438)
					(mid 287.795462 -351.611438)
					(end 287.414462 -351.230438)
				)
			)
		)
	)
	(zone
		(layers "F.Cu" "B.Cu" "In1.Cu" "In2.Cu" "In3.Cu" "In4.Cu" "In5.Cu" "In6.Cu"
			"In7.Cu" "In8.Cu" "In9.Cu" "In10.Cu" "In11.Cu" "In12.Cu" "In13.Cu" "In14.Cu"
			"In15.Cu" "In16.Cu"
		)
		(hatch none 0.5)
		(connect_pads
			(clearance 0)
		)
		(min_thickness 0.25)
		(keepout
			(tracks not_allowed)
			(vias allowed)
			(pads allowed)
			(copperpour not_allowed)
			(footprints allowed)
		)
		(placement
			(enabled no)
			(sheetname "")
		)
		(fill
			(thermal_gap 0.5)
			(thermal_bridge_width 0.5)
			(island_removal_mode 0)
		)
		(polygon
			(pts
				(arc
					(start 318.720724 -345.084146)
					(mid 318.339724 -345.465146)
					(end 318.720724 -345.846146)
				)
				(arc
					(start 319.584324 -345.846146)
					(mid 319.965324 -345.465146)
					(end 319.584324 -345.084146)
				)
			)
		)
	)
	(zone
		(layers "F.Cu" "B.Cu" "In1.Cu" "In2.Cu" "In3.Cu" "In4.Cu" "In5.Cu" "In6.Cu"
			"In7.Cu" "In8.Cu" "In9.Cu" "In10.Cu" "In11.Cu" "In12.Cu" "In13.Cu" "In14.Cu"
			"In15.Cu" "In16.Cu"
		)
		(hatch none 0.5)
		(connect_pads
			(clearance 0)
		)
		(min_thickness 0.25)
		(keepout
			(tracks not_allowed)
			(vias allowed)
			(pads allowed)
			(copperpour not_allowed)
			(footprints allowed)
		)
		(placement
			(enabled no)
			(sheetname "")
		)
		(fill
			(thermal_gap 0.5)
			(thermal_bridge_width 0.5)
			(island_removal_mode 0)
		)
		(polygon
			(pts
				(arc
					(start 425.680886 -408.728672)
					(mid 425.695765 -408.692751)
					(end 425.731686 -408.677872)
				)
				(arc
					(start 426.447966 -408.677872)
					(mid 426.483887 -408.692751)
					(end 426.498766 -408.728672)
				)
				(arc
					(start 426.498766 -411.151324)
					(mid 426.483887 -411.187245)
					(end 426.447966 -411.202124)
				)
				(arc
					(start 425.731686 -411.202124)
					(mid 425.695765 -411.187245)
					(end 425.680886 -411.151324)
				)
			)
		)
	)
	(zone
		(layers "F.Cu" "B.Cu" "In1.Cu" "In2.Cu" "In3.Cu" "In4.Cu" "In5.Cu" "In6.Cu"
			"In7.Cu" "In8.Cu" "In9.Cu" "In10.Cu" "In11.Cu" "In12.Cu" "In13.Cu" "In14.Cu"
			"In15.Cu" "In16.Cu"
		)
		(hatch none 0.5)
		(connect_pads
			(clearance 0)
		)
		(min_thickness 0.25)
		(keepout
			(tracks not_allowed)
			(vias allowed)
			(pads allowed)
			(copperpour not_allowed)
			(footprints allowed)
		)
		(placement
			(enabled no)
			(sheetname "")
		)
		(fill
			(thermal_gap 0.5)
			(thermal_bridge_width 0.5)
			(island_removal_mode 0)
		)
		(polygon
			(pts
				(arc
					(start 386.73278 -345.084146)
					(mid 386.35178 -345.465146)
					(end 386.73278 -345.846146)
				)
				(arc
					(start 387.59638 -345.846146)
					(mid 387.97738 -345.465146)
					(end 387.59638 -345.084146)
				)
			)
		)
	)
	(zone
		(layers "F.Cu" "B.Cu" "In1.Cu" "In2.Cu" "In3.Cu" "In4.Cu" "In5.Cu" "In6.Cu"
			"In7.Cu" "In8.Cu" "In9.Cu" "In10.Cu" "In11.Cu" "In12.Cu" "In13.Cu" "In14.Cu"
			"In15.Cu" "In16.Cu"
		)
		(hatch none 0.5)
		(connect_pads
			(clearance 0)
		)
		(min_thickness 0.25)
		(keepout
			(tracks not_allowed)
			(vias allowed)
			(pads allowed)
			(copperpour not_allowed)
			(footprints allowed)
		)
		(placement
			(enabled no)
			(sheetname "")
		)
		(fill
			(thermal_gap 0.5)
			(thermal_bridge_width 0.5)
			(island_removal_mode 0)
		)
		(polygon
			(pts
				(arc
					(start 37.310568 -136.704324)
					(mid 37.767768 -137.161524)
					(end 38.224968 -136.704324)
				)
				(arc
					(start 38.224968 -135.840724)
					(mid 37.767768 -135.383524)
					(end 37.310568 -135.840724)
				)
			)
		)
	)
	(zone
		(layers "F.Cu" "B.Cu" "In1.Cu" "In2.Cu" "In3.Cu" "In4.Cu" "In5.Cu" "In6.Cu"
			"In7.Cu" "In8.Cu" "In9.Cu" "In10.Cu" "In11.Cu" "In12.Cu" "In13.Cu" "In14.Cu"
			"In15.Cu" "In16.Cu"
		)
		(hatch none 0.5)
		(connect_pads
			(clearance 0)
		)
		(min_thickness 0.25)
		(keepout
			(tracks not_allowed)
			(vias allowed)
			(pads allowed)
			(copperpour not_allowed)
			(footprints allowed)
		)
		(placement
			(enabled no)
			(sheetname "")
		)
		(fill
			(thermal_gap 0.5)
			(thermal_bridge_width 0.5)
			(island_removal_mode 0)
		)
		(polygon
			(pts
				(arc
					(start 413.04591 -145.287238)
					(mid 413.50311 -145.744438)
					(end 413.96031 -145.287238)
				)
				(arc
					(start 413.96031 -144.423638)
					(mid 413.50311 -143.966438)
					(end 413.04591 -144.423638)
				)
			)
		)
	)
	(zone
		(layers "F.Cu" "B.Cu" "In1.Cu" "In2.Cu" "In3.Cu" "In4.Cu" "In5.Cu" "In6.Cu"
			"In7.Cu" "In8.Cu" "In9.Cu" "In10.Cu" "In11.Cu" "In12.Cu" "In13.Cu" "In14.Cu"
			"In15.Cu" "In16.Cu"
		)
		(hatch none 0.5)
		(connect_pads
			(clearance 0)
		)
		(min_thickness 0.25)
		(keepout
			(tracks not_allowed)
			(vias allowed)
			(pads allowed)
			(copperpour not_allowed)
			(footprints allowed)
		)
		(placement
			(enabled no)
			(sheetname "")
		)
		(fill
			(thermal_gap 0.5)
			(thermal_bridge_width 0.5)
			(island_removal_mode 0)
		)
		(polygon
			(pts
				(arc
					(start 182.700168 -150.687278)
					(mid 183.157368 -151.144478)
					(end 183.614568 -150.687278)
				)
				(arc
					(start 183.614568 -149.823678)
					(mid 183.157368 -149.366478)
					(end 182.700168 -149.823678)
				)
			)
		)
	)
	(zone
		(layers "F.Cu" "B.Cu" "In1.Cu" "In2.Cu" "In3.Cu" "In4.Cu" "In5.Cu" "In6.Cu"
			"In7.Cu" "In8.Cu" "In9.Cu" "In10.Cu" "In11.Cu" "In12.Cu" "In13.Cu" "In14.Cu"
			"In15.Cu" "In16.Cu"
		)
		(hatch none 0.5)
		(connect_pads
			(clearance 0)
		)
		(min_thickness 0.25)
		(keepout
			(tracks not_allowed)
			(vias allowed)
			(pads allowed)
			(copperpour not_allowed)
			(footprints allowed)
		)
		(placement
			(enabled no)
			(sheetname "")
		)
		(fill
			(thermal_gap 0.5)
			(thermal_bridge_width 0.5)
			(island_removal_mode 0)
		)
		(polygon
			(pts
				(arc
					(start 356.907592 -29.12237)
					(mid 357.364792 -29.57957)
					(end 357.821992 -29.12237)
				)
				(arc
					(start 357.821992 -28.25877)
					(mid 357.364792 -27.80157)
					(end 356.907592 -28.25877)
				)
			)
		)
	)
	(zone
		(layers "F.Cu" "B.Cu" "In1.Cu" "In2.Cu" "In3.Cu" "In4.Cu" "In5.Cu" "In6.Cu"
			"In7.Cu" "In8.Cu" "In9.Cu" "In10.Cu" "In11.Cu" "In12.Cu" "In13.Cu" "In14.Cu"
			"In15.Cu" "In16.Cu"
		)
		(hatch none 0.5)
		(connect_pads
			(clearance 0)
		)
		(min_thickness 0.25)
		(keepout
			(tracks not_allowed)
			(vias allowed)
			(pads allowed)
			(copperpour not_allowed)
			(footprints allowed)
		)
		(placement
			(enabled no)
			(sheetname "")
		)
		(fill
			(thermal_gap 0.5)
			(thermal_bridge_width 0.5)
			(island_removal_mode 0)
		)
		(polygon
			(pts
				(arc
					(start 80.301084 -381.628904)
					(mid 80.315963 -381.592983)
					(end 80.351884 -381.578104)
				)
				(arc
					(start 81.068164 -381.578104)
					(mid 81.104085 -381.592983)
					(end 81.118964 -381.628904)
				)
				(arc
					(start 81.118964 -384.051556)
					(mid 81.104085 -384.087477)
					(end 81.068164 -384.102356)
				)
				(arc
					(start 80.351884 -384.102356)
					(mid 80.315963 -384.087477)
					(end 80.301084 -384.051556)
				)
			)
		)
	)
	(zone
		(layers "F.Cu" "B.Cu" "In1.Cu" "In2.Cu" "In3.Cu" "In4.Cu" "In5.Cu" "In6.Cu"
			"In7.Cu" "In8.Cu" "In9.Cu" "In10.Cu" "In11.Cu" "In12.Cu" "In13.Cu" "In14.Cu"
			"In15.Cu" "In16.Cu"
		)
		(hatch none 0.5)
		(connect_pads
			(clearance 0)
		)
		(min_thickness 0.25)
		(keepout
			(tracks not_allowed)
			(vias allowed)
			(pads allowed)
			(copperpour not_allowed)
			(footprints allowed)
		)
		(placement
			(enabled no)
			(sheetname "")
		)
		(fill
			(thermal_gap 0.5)
			(thermal_bridge_width 0.5)
			(island_removal_mode 0)
		)
		(polygon
			(pts
				(arc
					(start 197.17512 -134.369302)
					(mid 197.63232 -134.826502)
					(end 198.08952 -134.369302)
				)
				(arc
					(start 198.08952 -133.505702)
					(mid 197.63232 -133.048502)
					(end 197.17512 -133.505702)
				)
			)
		)
	)
	(zone
		(layers "F.Cu" "B.Cu" "In1.Cu" "In2.Cu" "In3.Cu" "In4.Cu" "In5.Cu" "In6.Cu"
			"In7.Cu" "In8.Cu" "In9.Cu" "In10.Cu" "In11.Cu" "In12.Cu" "In13.Cu" "In14.Cu"
			"In15.Cu" "In16.Cu"
		)
		(hatch none 0.5)
		(connect_pads
			(clearance 0)
		)
		(min_thickness 0.25)
		(keepout
			(tracks not_allowed)
			(vias allowed)
			(pads allowed)
			(copperpour not_allowed)
			(footprints allowed)
		)
		(placement
			(enabled no)
			(sheetname "")
		)
		(fill
			(thermal_gap 0.5)
			(thermal_bridge_width 0.5)
			(island_removal_mode 0)
		)
		(polygon
			(pts
				(arc
					(start 163.90112 -373.828818)
					(mid 163.915999 -373.792897)
					(end 163.95192 -373.778018)
				)
				(arc
					(start 164.6682 -373.778018)
					(mid 164.704121 -373.792897)
					(end 164.719 -373.828818)
				)
				(arc
					(start 164.719 -376.25147)
					(mid 164.704121 -376.287391)
					(end 164.6682 -376.30227)
				)
				(arc
					(start 163.95192 -376.30227)
					(mid 163.915999 -376.287391)
					(end 163.90112 -376.25147)
				)
			)
		)
	)
	(zone
		(layers "F.Cu" "B.Cu" "In1.Cu" "In2.Cu" "In3.Cu" "In4.Cu" "In5.Cu" "In6.Cu"
			"In7.Cu" "In8.Cu" "In9.Cu" "In10.Cu" "In11.Cu" "In12.Cu" "In13.Cu" "In14.Cu"
			"In15.Cu" "In16.Cu"
		)
		(hatch none 0.5)
		(connect_pads
			(clearance 0)
		)
		(min_thickness 0.25)
		(keepout
			(tracks not_allowed)
			(vias allowed)
			(pads allowed)
			(copperpour not_allowed)
			(footprints allowed)
		)
		(placement
			(enabled no)
			(sheetname "")
		)
		(fill
			(thermal_gap 0.5)
			(thermal_bridge_width 0.5)
			(island_removal_mode 0)
		)
		(polygon
			(pts
				(arc
					(start 267.478002 -101.984302)
					(mid 267.935202 -102.441502)
					(end 268.392402 -101.984302)
				)
				(arc
					(start 268.392402 -101.120702)
					(mid 267.935202 -100.663502)
					(end 267.478002 -101.120702)
				)
			)
		)
	)
	(zone
		(layers "F.Cu" "B.Cu" "In1.Cu" "In2.Cu" "In3.Cu" "In4.Cu" "In5.Cu" "In6.Cu"
			"In7.Cu" "In8.Cu" "In9.Cu" "In10.Cu" "In11.Cu" "In12.Cu" "In13.Cu" "In14.Cu"
			"In15.Cu" "In16.Cu"
		)
		(hatch none 0.5)
		(connect_pads
			(clearance 0)
		)
		(min_thickness 0.25)
		(keepout
			(tracks not_allowed)
			(vias allowed)
			(pads allowed)
			(copperpour not_allowed)
			(footprints allowed)
		)
		(placement
			(enabled no)
			(sheetname "")
		)
		(fill
			(thermal_gap 0.5)
			(thermal_bridge_width 0.5)
			(island_removal_mode 0)
		)
		(polygon
			(pts
				(arc
					(start 150.768558 -123.68784)
					(mid 151.225758 -124.14504)
					(end 151.682958 -123.68784)
				)
				(arc
					(start 151.682958 -122.82424)
					(mid 151.225758 -122.36704)
					(end 150.768558 -122.82424)
				)
			)
		)
	)
	(zone
		(layers "F.Cu" "B.Cu" "In1.Cu" "In2.Cu" "In3.Cu" "In4.Cu" "In5.Cu" "In6.Cu"
			"In7.Cu" "In8.Cu" "In9.Cu" "In10.Cu" "In11.Cu" "In12.Cu" "In13.Cu" "In14.Cu"
			"In15.Cu" "In16.Cu"
		)
		(hatch none 0.5)
		(connect_pads
			(clearance 0)
		)
		(min_thickness 0.25)
		(keepout
			(tracks not_allowed)
			(vias allowed)
			(pads allowed)
			(copperpour not_allowed)
			(footprints allowed)
		)
		(placement
			(enabled no)
			(sheetname "")
		)
		(fill
			(thermal_gap 0.5)
			(thermal_bridge_width 0.5)
			(island_removal_mode 0)
		)
		(polygon
			(pts
				(arc
					(start 36.301172 -403.728682)
					(mid 36.316051 -403.692761)
					(end 36.351972 -403.677882)
				)
				(arc
					(start 37.068252 -403.677882)
					(mid 37.104173 -403.692761)
					(end 37.119052 -403.728682)
				)
				(arc
					(start 37.119052 -406.151334)
					(mid 37.104173 -406.187255)
					(end 37.068252 -406.202134)
				)
				(arc
					(start 36.351972 -406.202134)
					(mid 36.316051 -406.187255)
					(end 36.301172 -406.151334)
				)
			)
		)
	)
	(zone
		(layers "F.Cu" "B.Cu" "In1.Cu" "In2.Cu" "In3.Cu" "In4.Cu" "In5.Cu" "In6.Cu"
			"In7.Cu" "In8.Cu" "In9.Cu" "In10.Cu" "In11.Cu" "In12.Cu" "In13.Cu" "In14.Cu"
			"In15.Cu" "In16.Cu"
		)
		(hatch none 0.5)
		(connect_pads
			(clearance 0)
		)
		(min_thickness 0.25)
		(keepout
			(tracks not_allowed)
			(vias allowed)
			(pads allowed)
			(copperpour not_allowed)
			(footprints allowed)
		)
		(placement
			(enabled no)
			(sheetname "")
		)
		(fill
			(thermal_gap 0.5)
			(thermal_bridge_width 0.5)
			(island_removal_mode 0)
		)
		(polygon
			(pts
				(arc
					(start 419.08095 -373.828818)
					(mid 419.095829 -373.792897)
					(end 419.13175 -373.778018)
				)
				(arc
					(start 419.84803 -373.778018)
					(mid 419.883951 -373.792897)
					(end 419.89883 -373.828818)
				)
				(arc
					(start 419.89883 -376.25147)
					(mid 419.883951 -376.287391)
					(end 419.84803 -376.30227)
				)
				(arc
					(start 419.13175 -376.30227)
					(mid 419.095829 -376.287391)
					(end 419.08095 -376.25147)
				)
			)
		)
	)
	(zone
		(layers "F.Cu" "B.Cu" "In1.Cu" "In2.Cu" "In3.Cu" "In4.Cu" "In5.Cu" "In6.Cu"
			"In7.Cu" "In8.Cu" "In9.Cu" "In10.Cu" "In11.Cu" "In12.Cu" "In13.Cu" "In14.Cu"
			"In15.Cu" "In16.Cu"
		)
		(hatch none 0.5)
		(connect_pads
			(clearance 0)
		)
		(min_thickness 0.25)
		(keepout
			(tracks not_allowed)
			(vias allowed)
			(pads allowed)
			(copperpour not_allowed)
			(footprints allowed)
		)
		(placement
			(enabled no)
			(sheetname "")
		)
		(fill
			(thermal_gap 0.5)
			(thermal_bridge_width 0.5)
			(island_removal_mode 0)
		)
		(polygon
			(pts
				(arc
					(start 414.230312 -36.60013)
					(mid 412.299912 -36.60013)
					(end 414.230312 -36.60013)
				)
			)
		)
	)
	(zone
		(layers "F.Cu" "B.Cu" "In1.Cu" "In2.Cu" "In3.Cu" "In4.Cu" "In5.Cu" "In6.Cu"
			"In7.Cu" "In8.Cu" "In9.Cu" "In10.Cu" "In11.Cu" "In12.Cu" "In13.Cu" "In14.Cu"
			"In15.Cu" "In16.Cu"
		)
		(hatch none 0.5)
		(connect_pads
			(clearance 0)
		)
		(min_thickness 0.25)
		(keepout
			(tracks not_allowed)
			(vias allowed)
			(pads allowed)
			(copperpour not_allowed)
			(footprints allowed)
		)
		(placement
			(enabled no)
			(sheetname "")
		)
		(fill
			(thermal_gap 0.5)
			(thermal_bridge_width 0.5)
			(island_removal_mode 0)
		)
		(polygon
			(pts
				(arc
					(start 150.768558 -131.297934)
					(mid 151.225758 -131.755134)
					(end 151.682958 -131.297934)
				)
				(arc
					(start 151.682958 -130.434334)
					(mid 151.225758 -129.977134)
					(end 150.768558 -130.434334)
				)
			)
		)
	)
	(zone
		(layers "F.Cu" "B.Cu" "In1.Cu" "In2.Cu" "In3.Cu" "In4.Cu" "In5.Cu" "In6.Cu"
			"In7.Cu" "In8.Cu" "In9.Cu" "In10.Cu" "In11.Cu" "In12.Cu" "In13.Cu" "In14.Cu"
			"In15.Cu" "In16.Cu"
		)
		(hatch none 0.5)
		(connect_pads
			(clearance 0)
		)
		(min_thickness 0.25)
		(keepout
			(tracks not_allowed)
			(vias allowed)
			(pads allowed)
			(copperpour not_allowed)
			(footprints allowed)
		)
		(placement
			(enabled no)
			(sheetname "")
		)
		(fill
			(thermal_gap 0.5)
			(thermal_bridge_width 0.5)
			(island_removal_mode 0)
		)
		(polygon
			(pts
				(arc
					(start 295.877742 -351.230438)
					(mid 295.496742 -351.611438)
					(end 295.877742 -351.992438)
				)
				(arc
					(start 296.741342 -351.992438)
					(mid 297.122342 -351.611438)
					(end 296.741342 -351.230438)
				)
			)
		)
	)
	(zone
		(layers "F.Cu" "B.Cu" "In1.Cu" "In2.Cu" "In3.Cu" "In4.Cu" "In5.Cu" "In6.Cu"
			"In7.Cu" "In8.Cu" "In9.Cu" "In10.Cu" "In11.Cu" "In12.Cu" "In13.Cu" "In14.Cu"
			"In15.Cu" "In16.Cu"
		)
		(hatch none 0.5)
		(connect_pads
			(clearance 0)
		)
		(min_thickness 0.25)
		(keepout
			(tracks not_allowed)
			(vias allowed)
			(pads allowed)
			(copperpour not_allowed)
			(footprints allowed)
		)
		(placement
			(enabled no)
			(sheetname "")
		)
		(fill
			(thermal_gap 0.5)
			(thermal_bridge_width 0.5)
			(island_removal_mode 0)
		)
		(polygon
			(pts
				(arc
					(start 34.877248 -345.084146)
					(mid 34.496248 -345.465146)
					(end 34.877248 -345.846146)
				)
				(arc
					(start 35.740848 -345.846146)
					(mid 36.121848 -345.465146)
					(end 35.740848 -345.084146)
				)
			)
		)
	)
	(zone
		(layers "F.Cu" "B.Cu" "In1.Cu" "In2.Cu" "In3.Cu" "In4.Cu" "In5.Cu" "In6.Cu"
			"In7.Cu" "In8.Cu" "In9.Cu" "In10.Cu" "In11.Cu" "In12.Cu" "In13.Cu" "In14.Cu"
			"In15.Cu" "In16.Cu"
		)
		(hatch none 0.5)
		(connect_pads
			(clearance 0)
		)
		(min_thickness 0.25)
		(keepout
			(tracks not_allowed)
			(vias allowed)
			(pads allowed)
			(copperpour not_allowed)
			(footprints allowed)
		)
		(placement
			(enabled no)
			(sheetname "")
		)
		(fill
			(thermal_gap 0.5)
			(thermal_bridge_width 0.5)
			(island_removal_mode 0)
		)
		(polygon
			(pts
				(arc
					(start 141.54658 -178.869086)
					(mid 142.00378 -179.326286)
					(end 142.46098 -178.869086)
				)
				(arc
					(start 142.46098 -178.005486)
					(mid 142.00378 -177.548286)
					(end 141.54658 -178.005486)
				)
			)
		)
	)
	(zone
		(layers "F.Cu" "B.Cu" "In1.Cu" "In2.Cu" "In3.Cu" "In4.Cu" "In5.Cu" "In6.Cu"
			"In7.Cu" "In8.Cu" "In9.Cu" "In10.Cu" "In11.Cu" "In12.Cu" "In13.Cu" "In14.Cu"
			"In15.Cu" "In16.Cu"
		)
		(hatch none 0.5)
		(connect_pads
			(clearance 0)
		)
		(min_thickness 0.25)
		(keepout
			(tracks not_allowed)
			(vias allowed)
			(pads allowed)
			(copperpour not_allowed)
			(footprints allowed)
		)
		(placement
			(enabled no)
			(sheetname "")
		)
		(fill
			(thermal_gap 0.5)
			(thermal_bridge_width 0.5)
			(island_removal_mode 0)
		)
		(polygon
			(pts
				(arc
					(start 37.324538 -299.555154)
					(mid 37.654738 -299.224954)
					(end 37.324538 -298.894754)
				)
				(arc
					(start 36.374578 -298.894754)
					(mid 36.044378 -299.224954)
					(end 36.374578 -299.555154)
				)
			)
		)
	)
	(zone
		(layers "F.Cu" "B.Cu" "In1.Cu" "In2.Cu" "In3.Cu" "In4.Cu" "In5.Cu" "In6.Cu"
			"In7.Cu" "In8.Cu" "In9.Cu" "In10.Cu" "In11.Cu" "In12.Cu" "In13.Cu" "In14.Cu"
			"In15.Cu" "In16.Cu"
		)
		(hatch none 0.5)
		(connect_pads
			(clearance 0)
		)
		(min_thickness 0.25)
		(keepout
			(tracks not_allowed)
			(vias allowed)
			(pads allowed)
			(copperpour not_allowed)
			(footprints allowed)
		)
		(placement
			(enabled no)
			(sheetname "")
		)
		(fill
			(thermal_gap 0.5)
			(thermal_bridge_width 0.5)
			(island_removal_mode 0)
		)
		(polygon
			(pts
				(arc
					(start 298.080938 -378.828554)
					(mid 298.095817 -378.792633)
					(end 298.131738 -378.777754)
				)
				(arc
					(start 298.848018 -378.777754)
					(mid 298.883939 -378.792633)
					(end 298.898818 -378.828554)
				)
				(arc
					(start 298.898818 -381.251206)
					(mid 298.883939 -381.287127)
					(end 298.848018 -381.302006)
				)
				(arc
					(start 298.131738 -381.302006)
					(mid 298.095817 -381.287127)
					(end 298.080938 -381.251206)
				)
			)
		)
	)
	(zone
		(layers "F.Cu" "B.Cu" "In1.Cu" "In2.Cu" "In3.Cu" "In4.Cu" "In5.Cu" "In6.Cu"
			"In7.Cu" "In8.Cu" "In9.Cu" "In10.Cu" "In11.Cu" "In12.Cu" "In13.Cu" "In14.Cu"
			"In15.Cu" "In16.Cu"
		)
		(hatch none 0.5)
		(connect_pads
			(clearance 0)
		)
		(min_thickness 0.25)
		(keepout
			(tracks not_allowed)
			(vias allowed)
			(pads allowed)
			(copperpour not_allowed)
			(footprints allowed)
		)
		(placement
			(enabled no)
			(sheetname "")
		)
		(fill
			(thermal_gap 0.5)
			(thermal_bridge_width 0.5)
			(island_removal_mode 0)
		)
		(polygon
			(pts
				(arc
					(start 165.295072 -345.084146)
					(mid 164.914072 -345.465146)
					(end 165.295072 -345.846146)
				)
				(arc
					(start 166.158672 -345.846146)
					(mid 166.539672 -345.465146)
					(end 166.158672 -345.084146)
				)
			)
		)
	)
	(zone
		(layers "F.Cu" "B.Cu" "In1.Cu" "In2.Cu" "In3.Cu" "In4.Cu" "In5.Cu" "In6.Cu"
			"In7.Cu" "In8.Cu" "In9.Cu" "In10.Cu" "In11.Cu" "In12.Cu" "In13.Cu" "In14.Cu"
			"In15.Cu" "In16.Cu"
		)
		(hatch none 0.5)
		(connect_pads
			(clearance 0)
		)
		(min_thickness 0.25)
		(keepout
			(tracks not_allowed)
			(vias allowed)
			(pads allowed)
			(copperpour not_allowed)
			(footprints allowed)
		)
		(placement
			(enabled no)
			(sheetname "")
		)
		(fill
			(thermal_gap 0.5)
			(thermal_bridge_width 0.5)
			(island_removal_mode 0)
		)
		(polygon
			(pts
				(arc
					(start 339.727032 -95.301054)
					(mid 340.184232 -94.843854)
					(end 339.727032 -94.386654)
				)
				(arc
					(start 338.863432 -94.386654)
					(mid 338.406232 -94.843854)
					(end 338.863432 -95.301054)
				)
			)
		)
	)
	(zone
		(layers "F.Cu" "B.Cu" "In1.Cu" "In2.Cu" "In3.Cu" "In4.Cu" "In5.Cu" "In6.Cu"
			"In7.Cu" "In8.Cu" "In9.Cu" "In10.Cu" "In11.Cu" "In12.Cu" "In13.Cu" "In14.Cu"
			"In15.Cu" "In16.Cu"
		)
		(hatch none 0.5)
		(connect_pads
			(clearance 0)
		)
		(min_thickness 0.25)
		(keepout
			(tracks not_allowed)
			(vias allowed)
			(pads allowed)
			(copperpour not_allowed)
			(footprints allowed)
		)
		(placement
			(enabled no)
			(sheetname "")
		)
		(fill
			(thermal_gap 0.5)
			(thermal_bridge_width 0.5)
			(island_removal_mode 0)
		)
		(polygon
			(pts
				(arc
					(start 197.17512 -143.479266)
					(mid 197.63232 -143.936466)
					(end 198.08952 -143.479266)
				)
				(arc
					(start 198.08952 -142.615666)
					(mid 197.63232 -142.158466)
					(end 197.17512 -142.615666)
				)
			)
		)
	)
	(zone
		(layers "F.Cu" "B.Cu" "In1.Cu" "In2.Cu" "In3.Cu" "In4.Cu" "In5.Cu" "In6.Cu"
			"In7.Cu" "In8.Cu" "In9.Cu" "In10.Cu" "In11.Cu" "In12.Cu" "In13.Cu" "In14.Cu"
			"In15.Cu" "In16.Cu"
		)
		(hatch none 0.5)
		(connect_pads
			(clearance 0)
		)
		(min_thickness 0.25)
		(keepout
			(tracks not_allowed)
			(vias allowed)
			(pads allowed)
			(copperpour not_allowed)
			(footprints allowed)
		)
		(placement
			(enabled no)
			(sheetname "")
		)
		(fill
			(thermal_gap 0.5)
			(thermal_bridge_width 0.5)
			(island_removal_mode 0)
		)
		(polygon
			(pts
				(arc
					(start 274.240498 17.603724)
					(mid 274.621498 17.222724)
					(end 275.002498 17.603724)
				)
				(arc
					(start 275.002498 18.467324)
					(mid 274.621498 18.848324)
					(end 274.240498 18.467324)
				)
			)
		)
	)
	(zone
		(layers "F.Cu" "B.Cu" "In1.Cu" "In2.Cu" "In3.Cu" "In4.Cu" "In5.Cu" "In6.Cu"
			"In7.Cu" "In8.Cu" "In9.Cu" "In10.Cu" "In11.Cu" "In12.Cu" "In13.Cu" "In14.Cu"
			"In15.Cu" "In16.Cu"
		)
		(hatch none 0.5)
		(connect_pads
			(clearance 0)
		)
		(min_thickness 0.25)
		(keepout
			(tracks not_allowed)
			(vias allowed)
			(pads allowed)
			(copperpour not_allowed)
			(footprints allowed)
		)
		(placement
			(enabled no)
			(sheetname "")
		)
		(fill
			(thermal_gap 0.5)
			(thermal_bridge_width 0.5)
			(island_removal_mode 0)
		)
		(polygon
			(pts
				(arc
					(start 166.101014 -404.828756)
					(mid 166.115893 -404.792835)
					(end 166.151814 -404.777956)
				)
				(arc
					(start 166.868094 -404.777956)
					(mid 166.904015 -404.792835)
					(end 166.918894 -404.828756)
				)
				(arc
					(start 166.918894 -407.251408)
					(mid 166.904015 -407.287329)
					(end 166.868094 -407.302208)
				)
				(arc
					(start 166.151814 -407.302208)
					(mid 166.115893 -407.287329)
					(end 166.101014 -407.251408)
				)
			)
		)
	)
	(zone
		(layers "F.Cu" "B.Cu" "In1.Cu" "In2.Cu" "In3.Cu" "In4.Cu" "In5.Cu" "In6.Cu"
			"In7.Cu" "In8.Cu" "In9.Cu" "In10.Cu" "In11.Cu" "In12.Cu" "In13.Cu" "In14.Cu"
			"In15.Cu" "In16.Cu"
		)
		(hatch none 0.5)
		(connect_pads
			(clearance 0)
		)
		(min_thickness 0.25)
		(keepout
			(tracks not_allowed)
			(vias allowed)
			(pads allowed)
			(copperpour not_allowed)
			(footprints allowed)
		)
		(placement
			(enabled no)
			(sheetname "")
		)
		(fill
			(thermal_gap 0.5)
			(thermal_bridge_width 0.5)
			(island_removal_mode 0)
		)
		(polygon
			(pts
				(arc
					(start 159.501078 -407.628852)
					(mid 159.515957 -407.592931)
					(end 159.551878 -407.578052)
				)
				(arc
					(start 160.268158 -407.578052)
					(mid 160.304079 -407.592931)
					(end 160.318958 -407.628852)
				)
				(arc
					(start 160.318958 -410.051504)
					(mid 160.304079 -410.087425)
					(end 160.268158 -410.102304)
				)
				(arc
					(start 159.551878 -410.102304)
					(mid 159.515957 -410.087425)
					(end 159.501078 -410.051504)
				)
			)
		)
	)
	(zone
		(layers "F.Cu" "B.Cu" "In1.Cu" "In2.Cu" "In3.Cu" "In4.Cu" "In5.Cu" "In6.Cu"
			"In7.Cu" "In8.Cu" "In9.Cu" "In10.Cu" "In11.Cu" "In12.Cu" "In13.Cu" "In14.Cu"
			"In15.Cu" "In16.Cu"
		)
		(hatch none 0.5)
		(connect_pads
			(clearance 0)
		)
		(min_thickness 0.25)
		(keepout
			(tracks not_allowed)
			(vias allowed)
			(pads allowed)
			(copperpour not_allowed)
			(footprints allowed)
		)
		(placement
			(enabled no)
			(sheetname "")
		)
		(fill
			(thermal_gap 0.5)
			(thermal_bridge_width 0.5)
			(island_removal_mode 0)
		)
		(polygon
			(pts
				(arc
					(start 54.55412 -99.31273)
					(mid 54.09692 -98.85553)
					(end 53.63972 -99.31273)
				)
				(arc
					(start 53.63972 -100.17633)
					(mid 54.09692 -100.63353)
					(end 54.55412 -100.17633)
				)
			)
		)
	)
	(zone
		(layers "F.Cu" "B.Cu" "In1.Cu" "In2.Cu" "In3.Cu" "In4.Cu" "In5.Cu" "In6.Cu"
			"In7.Cu" "In8.Cu" "In9.Cu" "In10.Cu" "In11.Cu" "In12.Cu" "In13.Cu" "In14.Cu"
			"In15.Cu" "In16.Cu"
		)
		(hatch none 0.5)
		(connect_pads
			(clearance 0)
		)
		(min_thickness 0.25)
		(keepout
			(tracks not_allowed)
			(vias allowed)
			(pads allowed)
			(copperpour not_allowed)
			(footprints allowed)
		)
		(placement
			(enabled no)
			(sheetname "")
		)
		(fill
			(thermal_gap 0.5)
			(thermal_bridge_width 0.5)
			(island_removal_mode 0)
		)
		(polygon
			(pts
				(arc
					(start 284.899862 -135.83285)
					(mid 284.442662 -135.37565)
					(end 283.985462 -135.83285)
				)
				(arc
					(start 283.985462 -136.69645)
					(mid 284.442662 -137.15365)
					(end 284.899862 -136.69645)
				)
			)
		)
	)
	(zone
		(layers "F.Cu" "B.Cu" "In1.Cu" "In2.Cu" "In3.Cu" "In4.Cu" "In5.Cu" "In6.Cu"
			"In7.Cu" "In8.Cu" "In9.Cu" "In10.Cu" "In11.Cu" "In12.Cu" "In13.Cu" "In14.Cu"
			"In15.Cu" "In16.Cu"
		)
		(hatch none 0.5)
		(connect_pads
			(clearance 0)
		)
		(min_thickness 0.25)
		(keepout
			(tracks not_allowed)
			(vias allowed)
			(pads allowed)
			(copperpour not_allowed)
			(footprints allowed)
		)
		(placement
			(enabled no)
			(sheetname "")
		)
		(fill
			(thermal_gap 0.5)
			(thermal_bridge_width 0.5)
			(island_removal_mode 0)
		)
		(polygon
			(pts
				(arc
					(start 381.680974 -371.028722)
					(mid 381.695853 -370.992801)
					(end 381.731774 -370.977922)
				)
				(arc
					(start 382.448054 -370.977922)
					(mid 382.483975 -370.992801)
					(end 382.498854 -371.028722)
				)
				(arc
					(start 382.498854 -373.451374)
					(mid 382.483975 -373.487295)
					(end 382.448054 -373.502174)
				)
				(arc
					(start 381.731774 -373.502174)
					(mid 381.695853 -373.487295)
					(end 381.680974 -373.451374)
				)
			)
		)
	)
	(zone
		(layers "F.Cu" "B.Cu" "In1.Cu" "In2.Cu" "In3.Cu" "In4.Cu" "In5.Cu" "In6.Cu"
			"In7.Cu" "In8.Cu" "In9.Cu" "In10.Cu" "In11.Cu" "In12.Cu" "In13.Cu" "In14.Cu"
			"In15.Cu" "In16.Cu"
		)
		(hatch none 0.5)
		(connect_pads
			(clearance 0)
		)
		(min_thickness 0.25)
		(keepout
			(tracks not_allowed)
			(vias allowed)
			(pads allowed)
			(copperpour not_allowed)
			(footprints allowed)
		)
		(placement
			(enabled no)
			(sheetname "")
		)
		(fill
			(thermal_gap 0.5)
			(thermal_bridge_width 0.5)
			(island_removal_mode 0)
		)
		(polygon
			(pts
				(arc
					(start 18.84807 -29.114242)
					(mid 19.30527 -29.571442)
					(end 19.76247 -29.114242)
				)
				(arc
					(start 19.76247 -28.250642)
					(mid 19.30527 -27.793442)
					(end 18.84807 -28.250642)
				)
			)
		)
	)
	(zone
		(layers "F.Cu" "B.Cu" "In1.Cu" "In2.Cu" "In3.Cu" "In4.Cu" "In5.Cu" "In6.Cu"
			"In7.Cu" "In8.Cu" "In9.Cu" "In10.Cu" "In11.Cu" "In12.Cu" "In13.Cu" "In14.Cu"
			"In15.Cu" "In16.Cu"
		)
		(hatch none 0.5)
		(connect_pads
			(clearance 0)
		)
		(min_thickness 0.25)
		(keepout
			(tracks not_allowed)
			(vias allowed)
			(pads allowed)
			(copperpour not_allowed)
			(footprints allowed)
		)
		(placement
			(enabled no)
			(sheetname "")
		)
		(fill
			(thermal_gap 0.5)
			(thermal_bridge_width 0.5)
			(island_removal_mode 0)
		)
		(polygon
			(pts
				(arc
					(start 161.700972 -378.828554)
					(mid 161.715851 -378.792633)
					(end 161.751772 -378.777754)
				)
				(arc
					(start 162.468052 -378.777754)
					(mid 162.503973 -378.792633)
					(end 162.518852 -378.828554)
				)
				(arc
					(start 162.518852 -381.251206)
					(mid 162.503973 -381.287127)
					(end 162.468052 -381.302006)
				)
				(arc
					(start 161.751772 -381.302006)
					(mid 161.715851 -381.287127)
					(end 161.700972 -381.251206)
				)
			)
		)
	)
	(zone
		(layers "F.Cu" "B.Cu" "In1.Cu" "In2.Cu" "In3.Cu" "In4.Cu" "In5.Cu" "In6.Cu"
			"In7.Cu" "In8.Cu" "In9.Cu" "In10.Cu" "In11.Cu" "In12.Cu" "In13.Cu" "In14.Cu"
			"In15.Cu" "In16.Cu"
		)
		(hatch none 0.5)
		(connect_pads
			(clearance 0)
		)
		(min_thickness 0.25)
		(keepout
			(tracks not_allowed)
			(vias allowed)
			(pads allowed)
			(copperpour not_allowed)
			(footprints allowed)
		)
		(placement
			(enabled no)
			(sheetname "")
		)
		(fill
			(thermal_gap 0.5)
			(thermal_bridge_width 0.5)
			(island_removal_mode 0)
		)
		(polygon
			(pts
				(arc
					(start 174.901098 -374.928638)
					(mid 174.915977 -374.892717)
					(end 174.951898 -374.877838)
				)
				(arc
					(start 175.668178 -374.877838)
					(mid 175.704099 -374.892717)
					(end 175.718978 -374.928638)
				)
				(arc
					(start 175.718978 -377.35129)
					(mid 175.704099 -377.387211)
					(end 175.668178 -377.40209)
				)
				(arc
					(start 174.951898 -377.40209)
					(mid 174.915977 -377.387211)
					(end 174.901098 -377.35129)
				)
			)
		)
	)
	(zone
		(layers "F.Cu" "B.Cu" "In1.Cu" "In2.Cu" "In3.Cu" "In4.Cu" "In5.Cu" "In6.Cu"
			"In7.Cu" "In8.Cu" "In9.Cu" "In10.Cu" "In11.Cu" "In12.Cu" "In13.Cu" "In14.Cu"
			"In15.Cu" "In16.Cu"
		)
		(hatch none 0.5)
		(connect_pads
			(clearance 0)
		)
		(min_thickness 0.25)
		(keepout
			(tracks not_allowed)
			(vias allowed)
			(pads allowed)
			(copperpour not_allowed)
			(footprints allowed)
		)
		(placement
			(enabled no)
			(sheetname "")
		)
		(fill
			(thermal_gap 0.5)
			(thermal_bridge_width 0.5)
			(island_removal_mode 0)
		)
		(polygon
			(pts
				(arc
					(start 166.101014 -374.928638)
					(mid 166.115893 -374.892717)
					(end 166.151814 -374.877838)
				)
				(arc
					(start 166.868094 -374.877838)
					(mid 166.904015 -374.892717)
					(end 166.918894 -374.928638)
				)
				(arc
					(start 166.918894 -377.35129)
					(mid 166.904015 -377.387211)
					(end 166.868094 -377.40209)
				)
				(arc
					(start 166.151814 -377.40209)
					(mid 166.115893 -377.387211)
					(end 166.101014 -377.35129)
				)
			)
		)
	)
	(zone
		(layers "F.Cu" "B.Cu" "In1.Cu" "In2.Cu" "In3.Cu" "In4.Cu" "In5.Cu" "In6.Cu"
			"In7.Cu" "In8.Cu" "In9.Cu" "In10.Cu" "In11.Cu" "In12.Cu" "In13.Cu" "In14.Cu"
			"In15.Cu" "In16.Cu"
		)
		(hatch none 0.5)
		(connect_pads
			(clearance 0)
		)
		(min_thickness 0.25)
		(keepout
			(tracks not_allowed)
			(vias allowed)
			(pads allowed)
			(copperpour not_allowed)
			(footprints allowed)
		)
		(placement
			(enabled no)
			(sheetname "")
		)
		(fill
			(thermal_gap 0.5)
			(thermal_bridge_width 0.5)
			(island_removal_mode 0)
		)
		(polygon
			(pts
				(arc
					(start 240.807494 -29.12237)
					(mid 241.264694 -29.57957)
					(end 241.721894 -29.12237)
				)
				(arc
					(start 241.721894 -28.25877)
					(mid 241.264694 -27.80157)
					(end 240.807494 -28.25877)
				)
			)
		)
	)
	(zone
		(layers "F.Cu" "B.Cu" "In1.Cu" "In2.Cu" "In3.Cu" "In4.Cu" "In5.Cu" "In6.Cu"
			"In7.Cu" "In8.Cu" "In9.Cu" "In10.Cu" "In11.Cu" "In12.Cu" "In13.Cu" "In14.Cu"
			"In15.Cu" "In16.Cu"
		)
		(hatch none 0.5)
		(connect_pads
			(clearance 0)
		)
		(min_thickness 0.25)
		(keepout
			(tracks not_allowed)
			(vias allowed)
			(pads allowed)
			(copperpour not_allowed)
			(footprints allowed)
		)
		(placement
			(enabled no)
			(sheetname "")
		)
		(fill
			(thermal_gap 0.5)
			(thermal_bridge_width 0.5)
			(island_removal_mode 0)
		)
		(polygon
			(pts
				(arc
					(start 127.406908 -348.20479)
					(mid 127.025908 -348.58579)
					(end 127.406908 -348.96679)
				)
				(arc
					(start 128.270508 -348.96679)
					(mid 128.651508 -348.58579)
					(end 128.270508 -348.20479)
				)
			)
		)
	)
	(zone
		(layers "F.Cu" "B.Cu" "In1.Cu" "In2.Cu" "In3.Cu" "In4.Cu" "In5.Cu" "In6.Cu"
			"In7.Cu" "In8.Cu" "In9.Cu" "In10.Cu" "In11.Cu" "In12.Cu" "In13.Cu" "In14.Cu"
			"In15.Cu" "In16.Cu"
		)
		(hatch none 0.5)
		(connect_pads
			(clearance 0)
		)
		(min_thickness 0.25)
		(keepout
			(tracks not_allowed)
			(vias allowed)
			(pads allowed)
			(copperpour not_allowed)
			(footprints allowed)
		)
		(placement
			(enabled no)
			(sheetname "")
		)
		(fill
			(thermal_gap 0.5)
			(thermal_bridge_width 0.5)
			(island_removal_mode 0)
		)
		(polygon
			(pts
				(arc
					(start 380.51486 -357.37673)
					(mid 380.13386 -357.75773)
					(end 380.51486 -358.13873)
				)
				(arc
					(start 381.37846 -358.13873)
					(mid 381.75946 -357.75773)
					(end 381.37846 -357.37673)
				)
			)
		)
	)
	(zone
		(layers "F.Cu" "B.Cu" "In1.Cu" "In2.Cu" "In3.Cu" "In4.Cu" "In5.Cu" "In6.Cu"
			"In7.Cu" "In8.Cu" "In9.Cu" "In10.Cu" "In11.Cu" "In12.Cu" "In13.Cu" "In14.Cu"
			"In15.Cu" "In16.Cu"
		)
		(hatch none 0.5)
		(connect_pads
			(clearance 0)
		)
		(min_thickness 0.25)
		(keepout
			(tracks not_allowed)
			(vias allowed)
			(pads allowed)
			(copperpour not_allowed)
			(footprints allowed)
		)
		(placement
			(enabled no)
			(sheetname "")
		)
		(fill
			(thermal_gap 0.5)
			(thermal_bridge_width 0.5)
			(island_removal_mode 0)
		)
		(polygon
			(pts
				(arc
					(start 321.829684 -351.230438)
					(mid 321.448684 -351.611438)
					(end 321.829684 -351.992438)
				)
				(arc
					(start 322.693284 -351.992438)
					(mid 323.074284 -351.611438)
					(end 322.693284 -351.230438)
				)
			)
		)
	)
	(zone
		(layers "F.Cu" "B.Cu" "In1.Cu" "In2.Cu" "In3.Cu" "In4.Cu" "In5.Cu" "In6.Cu"
			"In7.Cu" "In8.Cu" "In9.Cu" "In10.Cu" "In11.Cu" "In12.Cu" "In13.Cu" "In14.Cu"
			"In15.Cu" "In16.Cu"
		)
		(hatch none 0.5)
		(connect_pads
			(clearance 0)
		)
		(min_thickness 0.25)
		(keepout
			(tracks not_allowed)
			(vias allowed)
			(pads allowed)
			(copperpour not_allowed)
			(footprints allowed)
		)
		(placement
			(enabled no)
			(sheetname "")
		)
		(fill
			(thermal_gap 0.5)
			(thermal_bridge_width 0.5)
			(island_removal_mode 0)
		)
		(polygon
			(pts
				(arc
					(start 160.073086 -138.496548)
					(mid 160.530286 -138.953748)
					(end 160.987486 -138.496548)
				)
				(arc
					(start 160.987486 -137.632948)
					(mid 160.530286 -137.175748)
					(end 160.073086 -137.632948)
				)
			)
		)
	)
	(zone
		(layers "F.Cu" "B.Cu" "In1.Cu" "In2.Cu" "In3.Cu" "In4.Cu" "In5.Cu" "In6.Cu"
			"In7.Cu" "In8.Cu" "In9.Cu" "In10.Cu" "In11.Cu" "In12.Cu" "In13.Cu" "In14.Cu"
			"In15.Cu" "In16.Cu"
		)
		(hatch none 0.5)
		(connect_pads
			(clearance 0)
		)
		(min_thickness 0.25)
		(keepout
			(tracks not_allowed)
			(vias allowed)
			(pads allowed)
			(copperpour not_allowed)
			(footprints allowed)
		)
		(placement
			(enabled no)
			(sheetname "")
		)
		(fill
			(thermal_gap 0.5)
			(thermal_bridge_width 0.5)
			(island_removal_mode 0)
		)
		(polygon
			(pts
				(arc
					(start 264.953242 -34.52241)
					(mid 265.410442 -34.97961)
					(end 265.867642 -34.52241)
				)
				(arc
					(start 265.867642 -33.65881)
					(mid 265.410442 -33.20161)
					(end 264.953242 -33.65881)
				)
			)
		)
	)
	(zone
		(layers "F.Cu" "B.Cu" "In1.Cu" "In2.Cu" "In3.Cu" "In4.Cu" "In5.Cu" "In6.Cu"
			"In7.Cu" "In8.Cu" "In9.Cu" "In10.Cu" "In11.Cu" "In12.Cu" "In13.Cu" "In14.Cu"
			"In15.Cu" "In16.Cu"
		)
		(hatch none 0.5)
		(connect_pads
			(clearance 0)
		)
		(min_thickness 0.25)
		(keepout
			(tracks not_allowed)
			(vias allowed)
			(pads allowed)
			(copperpour not_allowed)
			(footprints allowed)
		)
		(placement
			(enabled no)
			(sheetname "")
		)
		(fill
			(thermal_gap 0.5)
			(thermal_bridge_width 0.5)
			(island_removal_mode 0)
		)
		(polygon
			(pts
				(arc
					(start 311.63387 18.460212)
					(mid 311.25287 18.841212)
					(end 310.87187 18.460212)
				)
				(arc
					(start 310.87187 17.596612)
					(mid 311.25287 17.215612)
					(end 311.63387 17.596612)
				)
			)
		)
	)
	(zone
		(layers "F.Cu" "B.Cu" "In1.Cu" "In2.Cu" "In3.Cu" "In4.Cu" "In5.Cu" "In6.Cu"
			"In7.Cu" "In8.Cu" "In9.Cu" "In10.Cu" "In11.Cu" "In12.Cu" "In13.Cu" "In14.Cu"
			"In15.Cu" "In16.Cu"
		)
		(hatch none 0.5)
		(connect_pads
			(clearance 0)
		)
		(min_thickness 0.25)
		(keepout
			(tracks not_allowed)
			(vias allowed)
			(pads allowed)
			(copperpour not_allowed)
			(footprints allowed)
		)
		(placement
			(enabled no)
			(sheetname "")
		)
		(fill
			(thermal_gap 0.5)
			(thermal_bridge_width 0.5)
			(island_removal_mode 0)
		)
		(polygon
			(pts
				(arc
					(start 302.48098 -374.928638)
					(mid 302.495859 -374.892717)
					(end 302.53178 -374.877838)
				)
				(arc
					(start 303.24806 -374.877838)
					(mid 303.283981 -374.892717)
					(end 303.29886 -374.928638)
				)
				(arc
					(start 303.29886 -377.35129)
					(mid 303.283981 -377.387211)
					(end 303.24806 -377.40209)
				)
				(arc
					(start 302.53178 -377.40209)
					(mid 302.495859 -377.387211)
					(end 302.48098 -377.35129)
				)
			)
		)
	)
	(zone
		(layers "F.Cu" "B.Cu" "In1.Cu" "In2.Cu" "In3.Cu" "In4.Cu" "In5.Cu" "In6.Cu"
			"In7.Cu" "In8.Cu" "In9.Cu" "In10.Cu" "In11.Cu" "In12.Cu" "In13.Cu" "In14.Cu"
			"In15.Cu" "In16.Cu"
		)
		(hatch none 0.5)
		(connect_pads
			(clearance 0)
		)
		(min_thickness 0.25)
		(keepout
			(tracks not_allowed)
			(vias allowed)
			(pads allowed)
			(copperpour not_allowed)
			(footprints allowed)
		)
		(placement
			(enabled no)
			(sheetname "")
		)
		(fill
			(thermal_gap 0.5)
			(thermal_bridge_width 0.5)
			(island_removal_mode 0)
		)
		(polygon
			(pts
				(arc
					(start 449.342002 -235.083096)
					(mid 449.799202 -234.625896)
					(end 449.342002 -234.168696)
				)
				(arc
					(start 448.478402 -234.168696)
					(mid 448.021202 -234.625896)
					(end 448.478402 -235.083096)
				)
			)
		)
	)
	(zone
		(layers "F.Cu" "B.Cu" "In1.Cu" "In2.Cu" "In3.Cu" "In4.Cu" "In5.Cu" "In6.Cu"
			"In7.Cu" "In8.Cu" "In9.Cu" "In10.Cu" "In11.Cu" "In12.Cu" "In13.Cu" "In14.Cu"
			"In15.Cu" "In16.Cu"
		)
		(hatch none 0.5)
		(connect_pads
			(clearance 0)
		)
		(min_thickness 0.25)
		(keepout
			(tracks not_allowed)
			(vias allowed)
			(pads allowed)
			(copperpour not_allowed)
			(footprints allowed)
		)
		(placement
			(enabled no)
			(sheetname "")
		)
		(fill
			(thermal_gap 0.5)
			(thermal_bridge_width 0.5)
			(island_removal_mode 0)
		)
		(polygon
			(pts
				(arc
					(start 432.280822 -373.828818)
					(mid 432.295701 -373.792897)
					(end 432.331622 -373.778018)
				)
				(arc
					(start 433.047902 -373.778018)
					(mid 433.083823 -373.792897)
					(end 433.098702 -373.828818)
				)
				(arc
					(start 433.098702 -376.25147)
					(mid 433.083823 -376.287391)
					(end 433.047902 -376.30227)
				)
				(arc
					(start 432.331622 -376.30227)
					(mid 432.295701 -376.287391)
					(end 432.280822 -376.25147)
				)
			)
		)
	)
	(zone
		(layers "F.Cu" "B.Cu" "In1.Cu" "In2.Cu" "In3.Cu" "In4.Cu" "In5.Cu" "In6.Cu"
			"In7.Cu" "In8.Cu" "In9.Cu" "In10.Cu" "In11.Cu" "In12.Cu" "In13.Cu" "In14.Cu"
			"In15.Cu" "In16.Cu"
		)
		(hatch none 0.5)
		(connect_pads
			(clearance 0)
		)
		(min_thickness 0.25)
		(keepout
			(tracks not_allowed)
			(vias allowed)
			(pads allowed)
			(copperpour not_allowed)
			(footprints allowed)
		)
		(placement
			(enabled no)
			(sheetname "")
		)
		(fill
			(thermal_gap 0.5)
			(thermal_bridge_width 0.5)
			(island_removal_mode 0)
		)
		(polygon
			(pts
				(arc
					(start 177.730912 -342.058498)
					(mid 177.349912 -342.439498)
					(end 177.730912 -342.820498)
				)
				(arc
					(start 178.594512 -342.820498)
					(mid 178.975512 -342.439498)
					(end 178.594512 -342.058498)
				)
			)
		)
	)
	(zone
		(layers "F.Cu" "B.Cu" "In1.Cu" "In2.Cu" "In3.Cu" "In4.Cu" "In5.Cu" "In6.Cu"
			"In7.Cu" "In8.Cu" "In9.Cu" "In10.Cu" "In11.Cu" "In12.Cu" "In13.Cu" "In14.Cu"
			"In15.Cu" "In16.Cu"
		)
		(hatch none 0.5)
		(connect_pads
			(clearance 0)
		)
		(min_thickness 0.25)
		(keepout
			(tracks not_allowed)
			(vias allowed)
			(pads allowed)
			(copperpour not_allowed)
			(footprints allowed)
		)
		(placement
			(enabled no)
			(sheetname "")
		)
		(fill
			(thermal_gap 0.5)
			(thermal_bridge_width 0.5)
			(island_removal_mode 0)
		)
		(polygon
			(pts
				(arc
					(start 66.60007 -147.087336)
					(mid 67.05727 -147.544536)
					(end 67.51447 -147.087336)
				)
				(arc
					(start 67.51447 -146.223736)
					(mid 67.05727 -145.766536)
					(end 66.60007 -146.223736)
				)
			)
		)
	)
	(zone
		(layers "F.Cu" "B.Cu" "In1.Cu" "In2.Cu" "In3.Cu" "In4.Cu" "In5.Cu" "In6.Cu"
			"In7.Cu" "In8.Cu" "In9.Cu" "In10.Cu" "In11.Cu" "In12.Cu" "In13.Cu" "In14.Cu"
			"In15.Cu" "In16.Cu"
		)
		(hatch none 0.5)
		(connect_pads
			(clearance 0)
		)
		(min_thickness 0.25)
		(keepout
			(tracks not_allowed)
			(vias allowed)
			(pads allowed)
			(copperpour not_allowed)
			(footprints allowed)
		)
		(placement
			(enabled no)
			(sheetname "")
		)
		(fill
			(thermal_gap 0.5)
			(thermal_bridge_width 0.5)
			(island_removal_mode 0)
		)
		(polygon
			(pts
				(arc
					(start 142.18158 -176.837086)
					(mid 142.63878 -177.294286)
					(end 143.09598 -176.837086)
				)
				(arc
					(start 143.09598 -175.973486)
					(mid 142.63878 -175.516286)
					(end 142.18158 -175.973486)
				)
			)
		)
	)
	(zone
		(layers "F.Cu" "B.Cu" "In1.Cu" "In2.Cu" "In3.Cu" "In4.Cu" "In5.Cu" "In6.Cu"
			"In7.Cu" "In8.Cu" "In9.Cu" "In10.Cu" "In11.Cu" "In12.Cu" "In13.Cu" "In14.Cu"
			"In15.Cu" "In16.Cu"
		)
		(hatch none 0.5)
		(connect_pads
			(clearance 0)
		)
		(min_thickness 0.25)
		(keepout
			(tracks not_allowed)
			(vias allowed)
			(pads allowed)
			(copperpour not_allowed)
			(footprints allowed)
		)
		(placement
			(enabled no)
			(sheetname "")
		)
		(fill
			(thermal_gap 0.5)
			(thermal_bridge_width 0.5)
			(island_removal_mode 0)
		)
		(polygon
			(pts
				(arc
					(start 170.501056 -371.028722)
					(mid 170.515935 -370.992801)
					(end 170.551856 -370.977922)
				)
				(arc
					(start 171.268136 -370.977922)
					(mid 171.304057 -370.992801)
					(end 171.318936 -371.028722)
				)
				(arc
					(start 171.318936 -373.451374)
					(mid 171.304057 -373.487295)
					(end 171.268136 -373.502174)
				)
				(arc
					(start 170.551856 -373.502174)
					(mid 170.515935 -373.487295)
					(end 170.501056 -373.451374)
				)
			)
		)
	)
	(zone
		(layers "F.Cu" "B.Cu" "In1.Cu" "In2.Cu" "In3.Cu" "In4.Cu" "In5.Cu" "In6.Cu"
			"In7.Cu" "In8.Cu" "In9.Cu" "In10.Cu" "In11.Cu" "In12.Cu" "In13.Cu" "In14.Cu"
			"In15.Cu" "In16.Cu"
		)
		(hatch none 0.5)
		(connect_pads
			(clearance 0)
		)
		(min_thickness 0.25)
		(keepout
			(tracks not_allowed)
			(vias allowed)
			(pads allowed)
			(copperpour not_allowed)
			(footprints allowed)
		)
		(placement
			(enabled no)
			(sheetname "")
		)
		(fill
			(thermal_gap 0.5)
			(thermal_bridge_width 0.5)
			(island_removal_mode 0)
		)
		(polygon
			(pts
				(arc
					(start 52.69992 -135.83285)
					(mid 52.24272 -135.37565)
					(end 51.78552 -135.83285)
				)
				(arc
					(start 51.78552 -136.69645)
					(mid 52.24272 -137.15365)
					(end 52.69992 -136.69645)
				)
			)
		)
	)
	(zone
		(layers "F.Cu" "B.Cu" "In1.Cu" "In2.Cu" "In3.Cu" "In4.Cu" "In5.Cu" "In6.Cu"
			"In7.Cu" "In8.Cu" "In9.Cu" "In10.Cu" "In11.Cu" "In12.Cu" "In13.Cu" "In14.Cu"
			"In15.Cu" "In16.Cu"
		)
		(hatch none 0.5)
		(connect_pads
			(clearance 0)
		)
		(min_thickness 0.25)
		(keepout
			(tracks not_allowed)
			(vias allowed)
			(pads allowed)
			(copperpour not_allowed)
			(footprints allowed)
		)
		(placement
			(enabled no)
			(sheetname "")
		)
		(fill
			(thermal_gap 0.5)
			(thermal_bridge_width 0.5)
			(island_removal_mode 0)
		)
		(polygon
			(pts
				(arc
					(start 300.280832 -373.828818)
					(mid 300.295711 -373.792897)
					(end 300.331632 -373.778018)
				)
				(arc
					(start 301.047912 -373.778018)
					(mid 301.083833 -373.792897)
					(end 301.098712 -373.828818)
				)
				(arc
					(start 301.098712 -376.25147)
					(mid 301.083833 -376.287391)
					(end 301.047912 -376.30227)
				)
				(arc
					(start 300.331632 -376.30227)
					(mid 300.295711 -376.287391)
					(end 300.280832 -376.25147)
				)
			)
		)
	)
	(zone
		(layers "F.Cu" "B.Cu" "In1.Cu" "In2.Cu" "In3.Cu" "In4.Cu" "In5.Cu" "In6.Cu"
			"In7.Cu" "In8.Cu" "In9.Cu" "In10.Cu" "In11.Cu" "In12.Cu" "In13.Cu" "In14.Cu"
			"In15.Cu" "In16.Cu"
		)
		(hatch none 0.5)
		(connect_pads
			(clearance 0)
		)
		(min_thickness 0.25)
		(keepout
			(tracks not_allowed)
			(vias allowed)
			(pads allowed)
			(copperpour not_allowed)
			(footprints allowed)
		)
		(placement
			(enabled no)
			(sheetname "")
		)
		(fill
			(thermal_gap 0.5)
			(thermal_bridge_width 0.5)
			(island_removal_mode 0)
		)
		(polygon
			(pts
				(arc
					(start 379.48108 -381.628904)
					(mid 379.495959 -381.592983)
					(end 379.53188 -381.578104)
				)
				(arc
					(start 380.24816 -381.578104)
					(mid 380.284081 -381.592983)
					(end 380.29896 -381.628904)
				)
				(arc
					(start 380.29896 -384.051556)
					(mid 380.284081 -384.087477)
					(end 380.24816 -384.102356)
				)
				(arc
					(start 379.53188 -384.102356)
					(mid 379.495959 -384.087477)
					(end 379.48108 -384.051556)
				)
			)
		)
	)
	(zone
		(layers "F.Cu" "B.Cu" "In1.Cu" "In2.Cu" "In3.Cu" "In4.Cu" "In5.Cu" "In6.Cu"
			"In7.Cu" "In8.Cu" "In9.Cu" "In10.Cu" "In11.Cu" "In12.Cu" "In13.Cu" "In14.Cu"
			"In15.Cu" "In16.Cu"
		)
		(hatch none 0.5)
		(connect_pads
			(clearance 0)
		)
		(min_thickness 0.25)
		(keepout
			(tracks not_allowed)
			(vias allowed)
			(pads allowed)
			(copperpour not_allowed)
			(footprints allowed)
		)
		(placement
			(enabled no)
			(sheetname "")
		)
		(fill
			(thermal_gap 0.5)
			(thermal_bridge_width 0.5)
			(island_removal_mode 0)
		)
		(polygon
			(pts
				(arc
					(start 430.080928 -397.028924)
					(mid 430.095807 -396.993003)
					(end 430.131728 -396.978124)
				)
				(arc
					(start 430.848008 -396.978124)
					(mid 430.883929 -396.993003)
					(end 430.898808 -397.028924)
				)
				(arc
					(start 430.898808 -399.451576)
					(mid 430.883929 -399.487497)
					(end 430.848008 -399.502376)
				)
				(arc
					(start 430.131728 -399.502376)
					(mid 430.095807 -399.487497)
					(end 430.080928 -399.451576)
				)
			)
		)
	)
	(zone
		(layers "F.Cu" "B.Cu" "In1.Cu" "In2.Cu" "In3.Cu" "In4.Cu" "In5.Cu" "In6.Cu"
			"In7.Cu" "In8.Cu" "In9.Cu" "In10.Cu" "In11.Cu" "In12.Cu" "In13.Cu" "In14.Cu"
			"In15.Cu" "In16.Cu"
		)
		(hatch none 0.5)
		(connect_pads
			(clearance 0)
		)
		(min_thickness 0.25)
		(keepout
			(tracks not_allowed)
			(vias allowed)
			(pads allowed)
			(copperpour not_allowed)
			(footprints allowed)
		)
		(placement
			(enabled no)
			(sheetname "")
		)
		(fill
			(thermal_gap 0.5)
			(thermal_bridge_width 0.5)
			(island_removal_mode 0)
		)
		(polygon
			(pts
				(arc
					(start 172.70095 -395.92885)
					(mid 172.715829 -395.892929)
					(end 172.75175 -395.87805)
				)
				(arc
					(start 173.46803 -395.87805)
					(mid 173.503951 -395.892929)
					(end 173.51883 -395.92885)
				)
				(arc
					(start 173.51883 -398.351502)
					(mid 173.503951 -398.387423)
					(end 173.46803 -398.402302)
				)
				(arc
					(start 172.75175 -398.402302)
					(mid 172.715829 -398.387423)
					(end 172.70095 -398.351502)
				)
			)
		)
	)
	(zone
		(layers "F.Cu" "B.Cu" "In1.Cu" "In2.Cu" "In3.Cu" "In4.Cu" "In5.Cu" "In6.Cu"
			"In7.Cu" "In8.Cu" "In9.Cu" "In10.Cu" "In11.Cu" "In12.Cu" "In13.Cu" "In14.Cu"
			"In15.Cu" "In16.Cu"
		)
		(hatch none 0.5)
		(connect_pads
			(clearance 0)
		)
		(min_thickness 0.25)
		(keepout
			(tracks not_allowed)
			(vias allowed)
			(pads allowed)
			(copperpour not_allowed)
			(footprints allowed)
		)
		(placement
			(enabled no)
			(sheetname "")
		)
		(fill
			(thermal_gap 0.5)
			(thermal_bridge_width 0.5)
			(island_removal_mode 0)
		)
		(polygon
			(pts
				(arc
					(start 102.808786 -342.207088)
					(mid 102.351586 -342.664288)
					(end 102.808786 -343.121488)
				)
				(arc
					(start 103.672386 -343.121488)
					(mid 104.129586 -342.664288)
					(end 103.672386 -342.207088)
				)
			)
		)
	)
	(zone
		(layers "F.Cu" "B.Cu" "In1.Cu" "In2.Cu" "In3.Cu" "In4.Cu" "In5.Cu" "In6.Cu"
			"In7.Cu" "In8.Cu" "In9.Cu" "In10.Cu" "In11.Cu" "In12.Cu" "In13.Cu" "In14.Cu"
			"In15.Cu" "In16.Cu"
		)
		(hatch none 0.5)
		(connect_pads
			(clearance 0)
		)
		(min_thickness 0.25)
		(keepout
			(tracks not_allowed)
			(vias allowed)
			(pads allowed)
			(copperpour not_allowed)
			(footprints allowed)
		)
		(placement
			(enabled no)
			(sheetname "")
		)
		(fill
			(thermal_gap 0.5)
			(thermal_bridge_width 0.5)
			(island_removal_mode 0)
		)
		(polygon
			(pts
				(arc
					(start 415.513012 -342.058498)
					(mid 415.132012 -342.439498)
					(end 415.513012 -342.820498)
				)
				(arc
					(start 416.376612 -342.820498)
					(mid 416.757612 -342.439498)
					(end 416.376612 -342.058498)
				)
			)
		)
	)
	(zone
		(layers "F.Cu" "B.Cu" "In1.Cu" "In2.Cu" "In3.Cu" "In4.Cu" "In5.Cu" "In6.Cu"
			"In7.Cu" "In8.Cu" "In9.Cu" "In10.Cu" "In11.Cu" "In12.Cu" "In13.Cu" "In14.Cu"
			"In15.Cu" "In16.Cu"
		)
		(hatch none 0.5)
		(connect_pads
			(clearance 0)
		)
		(min_thickness 0.25)
		(keepout
			(tracks not_allowed)
			(vias allowed)
			(pads allowed)
			(copperpour not_allowed)
			(footprints allowed)
		)
		(placement
			(enabled no)
			(sheetname "")
		)
		(fill
			(thermal_gap 0.5)
			(thermal_bridge_width 0.5)
			(island_removal_mode 0)
		)
		(polygon
			(pts
				(arc
					(start 71.501 -369.928902)
					(mid 71.515879 -369.892981)
					(end 71.5518 -369.878102)
				)
				(arc
					(start 72.26808 -369.878102)
					(mid 72.304001 -369.892981)
					(end 72.31888 -369.928902)
				)
				(arc
					(start 72.31888 -372.351554)
					(mid 72.304001 -372.387475)
					(end 72.26808 -372.402354)
				)
				(arc
					(start 71.5518 -372.402354)
					(mid 71.515879 -372.387475)
					(end 71.501 -372.351554)
				)
			)
		)
	)
	(zone
		(layers "F.Cu" "B.Cu" "In1.Cu" "In2.Cu" "In3.Cu" "In4.Cu" "In5.Cu" "In6.Cu"
			"In7.Cu" "In8.Cu" "In9.Cu" "In10.Cu" "In11.Cu" "In12.Cu" "In13.Cu" "In14.Cu"
			"In15.Cu" "In16.Cu"
		)
		(hatch none 0.5)
		(connect_pads
			(clearance 0)
		)
		(min_thickness 0.25)
		(keepout
			(tracks not_allowed)
			(vias allowed)
			(pads allowed)
			(copperpour not_allowed)
			(footprints allowed)
		)
		(placement
			(enabled no)
			(sheetname "")
		)
		(fill
			(thermal_gap 0.5)
			(thermal_bridge_width 0.5)
			(island_removal_mode 0)
		)
		(polygon
			(pts
				(arc
					(start 440.23026 -36.60013)
					(mid 438.29986 -36.60013)
					(end 440.23026 -36.60013)
				)
			)
		)
	)
	(zone
		(layers "F.Cu" "B.Cu" "In1.Cu" "In2.Cu" "In3.Cu" "In4.Cu" "In5.Cu" "In6.Cu"
			"In7.Cu" "In8.Cu" "In9.Cu" "In10.Cu" "In11.Cu" "In12.Cu" "In13.Cu" "In14.Cu"
			"In15.Cu" "In16.Cu"
		)
		(hatch none 0.5)
		(connect_pads
			(clearance 0)
		)
		(min_thickness 0.25)
		(keepout
			(tracks not_allowed)
			(vias allowed)
			(pads allowed)
			(copperpour not_allowed)
			(footprints allowed)
		)
		(placement
			(enabled no)
			(sheetname "")
		)
		(fill
			(thermal_gap 0.5)
			(thermal_bridge_width 0.5)
			(island_removal_mode 0)
		)
		(polygon
			(pts
				(arc
					(start 238.953294 -34.52241)
					(mid 239.410494 -34.97961)
					(end 239.867694 -34.52241)
				)
				(arc
					(start 239.867694 -33.65881)
					(mid 239.410494 -33.20161)
					(end 238.953294 -33.65881)
				)
			)
		)
	)
	(zone
		(layers "F.Cu" "B.Cu" "In1.Cu" "In2.Cu" "In3.Cu" "In4.Cu" "In5.Cu" "In6.Cu"
			"In7.Cu" "In8.Cu" "In9.Cu" "In10.Cu" "In11.Cu" "In12.Cu" "In13.Cu" "In14.Cu"
			"In15.Cu" "In16.Cu"
		)
		(hatch none 0.5)
		(connect_pads
			(clearance 0)
		)
		(min_thickness 0.25)
		(keepout
			(tracks not_allowed)
			(vias allowed)
			(pads allowed)
			(copperpour not_allowed)
			(footprints allowed)
		)
		(placement
			(enabled no)
			(sheetname "")
		)
		(fill
			(thermal_gap 0.5)
			(thermal_bridge_width 0.5)
			(island_removal_mode 0)
		)
		(polygon
			(pts
				(arc
					(start 124.30125 -407.628852)
					(mid 124.316129 -407.592931)
					(end 124.35205 -407.578052)
				)
				(arc
					(start 125.06833 -407.578052)
					(mid 125.104251 -407.592931)
					(end 125.11913 -407.628852)
				)
				(arc
					(start 125.11913 -410.051504)
					(mid 125.104251 -410.087425)
					(end 125.06833 -410.102304)
				)
				(arc
					(start 124.35205 -410.102304)
					(mid 124.316129 -410.087425)
					(end 124.30125 -410.051504)
				)
			)
		)
	)
	(zone
		(layers "F.Cu" "B.Cu" "In1.Cu" "In2.Cu" "In3.Cu" "In4.Cu" "In5.Cu" "In6.Cu"
			"In7.Cu" "In8.Cu" "In9.Cu" "In10.Cu" "In11.Cu" "In12.Cu" "In13.Cu" "In14.Cu"
			"In15.Cu" "In16.Cu"
		)
		(hatch none 0.5)
		(connect_pads
			(clearance 0)
		)
		(min_thickness 0.25)
		(keepout
			(tracks not_allowed)
			(vias allowed)
			(pads allowed)
			(copperpour not_allowed)
			(footprints allowed)
		)
		(placement
			(enabled no)
			(sheetname "")
		)
		(fill
			(thermal_gap 0.5)
			(thermal_bridge_width 0.5)
			(island_removal_mode 0)
		)
		(polygon
			(pts
				(arc
					(start 66.60007 -119.567198)
					(mid 67.05727 -120.024398)
					(end 67.51447 -119.567198)
				)
				(arc
					(start 67.51447 -118.703598)
					(mid 67.05727 -118.246398)
					(end 66.60007 -118.703598)
				)
			)
		)
	)
	(zone
		(layers "F.Cu" "B.Cu" "In1.Cu" "In2.Cu" "In3.Cu" "In4.Cu" "In5.Cu" "In6.Cu"
			"In7.Cu" "In8.Cu" "In9.Cu" "In10.Cu" "In11.Cu" "In12.Cu" "In13.Cu" "In14.Cu"
			"In15.Cu" "In16.Cu"
		)
		(hatch none 0.5)
		(connect_pads
			(clearance 0)
		)
		(min_thickness 0.25)
		(keepout
			(tracks not_allowed)
			(vias allowed)
			(pads allowed)
			(copperpour not_allowed)
			(footprints allowed)
		)
		(placement
			(enabled no)
			(sheetname "")
		)
		(fill
			(thermal_gap 0.5)
			(thermal_bridge_width 0.5)
			(island_removal_mode 0)
		)
		(polygon
			(pts
				(arc
					(start 86.243922 -345.084146)
					(mid 85.862922 -345.465146)
					(end 86.243922 -345.846146)
				)
				(arc
					(start 87.107522 -345.846146)
					(mid 87.488522 -345.465146)
					(end 87.107522 -345.084146)
				)
			)
		)
	)
	(zone
		(layers "F.Cu" "B.Cu" "In1.Cu" "In2.Cu" "In3.Cu" "In4.Cu" "In5.Cu" "In6.Cu"
			"In7.Cu" "In8.Cu" "In9.Cu" "In10.Cu" "In11.Cu" "In12.Cu" "In13.Cu" "In14.Cu"
			"In15.Cu" "In16.Cu"
		)
		(hatch none 0.5)
		(connect_pads
			(clearance 0)
		)
		(min_thickness 0.25)
		(keepout
			(tracks not_allowed)
			(vias allowed)
			(pads allowed)
			(copperpour not_allowed)
			(footprints allowed)
		)
		(placement
			(enabled no)
			(sheetname "")
		)
		(fill
			(thermal_gap 0.5)
			(thermal_bridge_width 0.5)
			(island_removal_mode 0)
		)
		(polygon
			(pts
				(arc
					(start 130.901186 -382.728724)
					(mid 130.916065 -382.692803)
					(end 130.951986 -382.677924)
				)
				(arc
					(start 131.668266 -382.677924)
					(mid 131.704187 -382.692803)
					(end 131.719066 -382.728724)
				)
				(arc
					(start 131.719066 -385.151376)
					(mid 131.704187 -385.187297)
					(end 131.668266 -385.202176)
				)
				(arc
					(start 130.951986 -385.202176)
					(mid 130.916065 -385.187297)
					(end 130.901186 -385.151376)
				)
			)
		)
	)
	(zone
		(layers "F.Cu" "B.Cu" "In1.Cu" "In2.Cu" "In3.Cu" "In4.Cu" "In5.Cu" "In6.Cu"
			"In7.Cu" "In8.Cu" "In9.Cu" "In10.Cu" "In11.Cu" "In12.Cu" "In13.Cu" "In14.Cu"
			"In15.Cu" "In16.Cu"
		)
		(hatch none 0.5)
		(connect_pads
			(clearance 0)
		)
		(min_thickness 0.25)
		(keepout
			(tracks not_allowed)
			(vias allowed)
			(pads allowed)
			(copperpour not_allowed)
			(footprints allowed)
		)
		(placement
			(enabled no)
			(sheetname "")
		)
		(fill
			(thermal_gap 0.5)
			(thermal_bridge_width 0.5)
			(island_removal_mode 0)
		)
		(polygon
			(pts
				(arc
					(start 80.301084 -369.928902)
					(mid 80.315963 -369.892981)
					(end 80.351884 -369.878102)
				)
				(arc
					(start 81.068164 -369.878102)
					(mid 81.104085 -369.892981)
					(end 81.118964 -369.928902)
				)
				(arc
					(start 81.118964 -372.351554)
					(mid 81.104085 -372.387475)
					(end 81.068164 -372.402354)
				)
				(arc
					(start 80.351884 -372.402354)
					(mid 80.315963 -372.387475)
					(end 80.301084 -372.351554)
				)
			)
		)
	)
	(zone
		(layers "F.Cu" "B.Cu" "In1.Cu" "In2.Cu" "In3.Cu" "In4.Cu" "In5.Cu" "In6.Cu"
			"In7.Cu" "In8.Cu" "In9.Cu" "In10.Cu" "In11.Cu" "In12.Cu" "In13.Cu" "In14.Cu"
			"In15.Cu" "In16.Cu"
		)
		(hatch none 0.5)
		(connect_pads
			(clearance 0)
		)
		(min_thickness 0.25)
		(keepout
			(tracks not_allowed)
			(vias allowed)
			(pads allowed)
			(copperpour not_allowed)
			(footprints allowed)
		)
		(placement
			(enabled no)
			(sheetname "")
		)
		(fill
			(thermal_gap 0.5)
			(thermal_bridge_width 0.5)
			(island_removal_mode 0)
		)
		(polygon
			(pts
				(arc
					(start 256.460498 7.652004)
					(mid 256.841498 7.271004)
					(end 257.222498 7.652004)
				)
				(arc
					(start 257.222498 8.515604)
					(mid 256.841498 8.896604)
					(end 256.460498 8.515604)
				)
			)
		)
	)
	(zone
		(layers "F.Cu" "B.Cu" "In1.Cu" "In2.Cu" "In3.Cu" "In4.Cu" "In5.Cu" "In6.Cu"
			"In7.Cu" "In8.Cu" "In9.Cu" "In10.Cu" "In11.Cu" "In12.Cu" "In13.Cu" "In14.Cu"
			"In15.Cu" "In16.Cu"
		)
		(hatch none 0.5)
		(connect_pads
			(clearance 0)
		)
		(min_thickness 0.25)
		(keepout
			(tracks not_allowed)
			(vias allowed)
			(pads allowed)
			(copperpour not_allowed)
			(footprints allowed)
		)
		(placement
			(enabled no)
			(sheetname "")
		)
		(fill
			(thermal_gap 0.5)
			(thermal_bridge_width 0.5)
			(island_removal_mode 0)
		)
		(polygon
			(pts
				(arc
					(start 86.607396 -32.722312)
					(mid 87.064596 -33.179512)
					(end 87.521796 -32.722312)
				)
				(arc
					(start 87.521796 -31.858712)
					(mid 87.064596 -31.401512)
					(end 86.607396 -31.858712)
				)
			)
		)
	)
	(zone
		(layers "F.Cu" "B.Cu" "In1.Cu" "In2.Cu" "In3.Cu" "In4.Cu" "In5.Cu" "In6.Cu"
			"In7.Cu" "In8.Cu" "In9.Cu" "In10.Cu" "In11.Cu" "In12.Cu" "In13.Cu" "In14.Cu"
			"In15.Cu" "In16.Cu"
		)
		(hatch none 0.5)
		(connect_pads
			(clearance 0)
		)
		(min_thickness 0.25)
		(keepout
			(tracks not_allowed)
			(vias allowed)
			(pads allowed)
			(copperpour not_allowed)
			(footprints allowed)
		)
		(placement
			(enabled no)
			(sheetname "")
		)
		(fill
			(thermal_gap 0.5)
			(thermal_bridge_width 0.5)
			(island_removal_mode 0)
		)
		(polygon
			(pts
				(arc
					(start 431.057812 -357.37673)
					(mid 430.676812 -357.75773)
					(end 431.057812 -358.13873)
				)
				(arc
					(start 431.921412 -358.13873)
					(mid 432.302412 -357.75773)
					(end 431.921412 -357.37673)
				)
			)
		)
	)
	(zone
		(layers "F.Cu" "B.Cu" "In1.Cu" "In2.Cu" "In3.Cu" "In4.Cu" "In5.Cu" "In6.Cu"
			"In7.Cu" "In8.Cu" "In9.Cu" "In10.Cu" "In11.Cu" "In12.Cu" "In13.Cu" "In14.Cu"
			"In15.Cu" "In16.Cu"
		)
		(hatch none 0.5)
		(connect_pads
			(clearance 0)
		)
		(min_thickness 0.25)
		(keepout
			(tracks not_allowed)
			(vias allowed)
			(pads allowed)
			(copperpour not_allowed)
			(footprints allowed)
		)
		(placement
			(enabled no)
			(sheetname "")
		)
		(fill
			(thermal_gap 0.5)
			(thermal_bridge_width 0.5)
			(island_removal_mode 0)
		)
		(polygon
			(pts
				(arc
					(start 118.3005 -88.495378)
					(mid 117.8433 -88.038178)
					(end 117.3861 -88.495378)
				)
				(arc
					(start 117.3861 -89.358978)
					(mid 117.8433 -89.816178)
					(end 118.3005 -89.358978)
				)
			)
		)
	)
	(zone
		(layers "F.Cu" "B.Cu" "In1.Cu" "In2.Cu" "In3.Cu" "In4.Cu" "In5.Cu" "In6.Cu"
			"In7.Cu" "In8.Cu" "In9.Cu" "In10.Cu" "In11.Cu" "In12.Cu" "In13.Cu" "In14.Cu"
			"In15.Cu" "In16.Cu"
		)
		(hatch none 0.5)
		(connect_pads
			(clearance 0)
		)
		(min_thickness 0.25)
		(keepout
			(tracks not_allowed)
			(vias allowed)
			(pads allowed)
			(copperpour not_allowed)
			(footprints allowed)
		)
		(placement
			(enabled no)
			(sheetname "")
		)
		(fill
			(thermal_gap 0.5)
			(thermal_bridge_width 0.5)
			(island_removal_mode 0)
		)
		(polygon
			(pts
				(xy 326.524874 -394.325348)
				(arc
					(start 326.524874 -417.533836)
					(mid 326.502556 -417.587718)
					(end 326.448674 -417.610036)
				)
				(arc
					(start 313.151012 -417.610036)
					(mid 313.09713 -417.587718)
					(end 313.074812 -417.533836)
				)
				(arc
					(start 313.074812 -394.356082)
					(mid 313.09713 -394.3022)
					(end 313.151012 -394.279882)
				)
				(xy 326.479408 -394.279882)
			)
		)
	)
	(zone
		(layers "F.Cu" "B.Cu" "In1.Cu" "In2.Cu" "In3.Cu" "In4.Cu" "In5.Cu" "In6.Cu"
			"In7.Cu" "In8.Cu" "In9.Cu" "In10.Cu" "In11.Cu" "In12.Cu" "In13.Cu" "In14.Cu"
			"In15.Cu" "In16.Cu"
		)
		(hatch none 0.5)
		(connect_pads
			(clearance 0)
		)
		(min_thickness 0.25)
		(keepout
			(tracks not_allowed)
			(vias allowed)
			(pads allowed)
			(copperpour not_allowed)
			(footprints allowed)
		)
		(placement
			(enabled no)
			(sheetname "")
		)
		(fill
			(thermal_gap 0.5)
			(thermal_bridge_width 0.5)
			(island_removal_mode 0)
		)
		(polygon
			(pts
				(arc
					(start 356.907592 -32.722312)
					(mid 357.364792 -33.179512)
					(end 357.821992 -32.722312)
				)
				(arc
					(start 357.821992 -31.858712)
					(mid 357.364792 -31.401512)
					(end 356.907592 -31.858712)
				)
			)
		)
	)
	(zone
		(layers "F.Cu" "B.Cu" "In1.Cu" "In2.Cu" "In3.Cu" "In4.Cu" "In5.Cu" "In6.Cu"
			"In7.Cu" "In8.Cu" "In9.Cu" "In10.Cu" "In11.Cu" "In12.Cu" "In13.Cu" "In14.Cu"
			"In15.Cu" "In16.Cu"
		)
		(hatch none 0.5)
		(connect_pads
			(clearance 0)
		)
		(min_thickness 0.25)
		(keepout
			(tracks not_allowed)
			(vias allowed)
			(pads allowed)
			(copperpour not_allowed)
			(footprints allowed)
		)
		(placement
			(enabled no)
			(sheetname "")
		)
		(fill
			(thermal_gap 0.5)
			(thermal_bridge_width 0.5)
			(island_removal_mode 0)
		)
		(polygon
			(pts
				(arc
					(start 402.27758 -351.230438)
					(mid 401.89658 -351.611438)
					(end 402.27758 -351.992438)
				)
				(arc
					(start 403.14118 -351.992438)
					(mid 403.52218 -351.611438)
					(end 403.14118 -351.230438)
				)
			)
		)
	)
	(zone
		(layers "F.Cu" "B.Cu" "In1.Cu" "In2.Cu" "In3.Cu" "In4.Cu" "In5.Cu" "In6.Cu"
			"In7.Cu" "In8.Cu" "In9.Cu" "In10.Cu" "In11.Cu" "In12.Cu" "In13.Cu" "In14.Cu"
			"In15.Cu" "In16.Cu"
		)
		(hatch none 0.5)
		(connect_pads
			(clearance 0)
		)
		(min_thickness 0.25)
		(keepout
			(tracks not_allowed)
			(vias allowed)
			(pads allowed)
			(copperpour not_allowed)
			(footprints allowed)
		)
		(placement
			(enabled no)
			(sheetname "")
		)
		(fill
			(thermal_gap 0.5)
			(thermal_bridge_width 0.5)
			(island_removal_mode 0)
		)
		(polygon
			(pts
				(arc
					(start 22.441408 -345.084146)
					(mid 22.060408 -345.465146)
					(end 22.441408 -345.846146)
				)
				(arc
					(start 23.305008 -345.846146)
					(mid 23.686008 -345.465146)
					(end 23.305008 -345.084146)
				)
			)
		)
	)
	(zone
		(layers "F.Cu" "B.Cu" "In1.Cu" "In2.Cu" "In3.Cu" "In4.Cu" "In5.Cu" "In6.Cu"
			"In7.Cu" "In8.Cu" "In9.Cu" "In10.Cu" "In11.Cu" "In12.Cu" "In13.Cu" "In14.Cu"
			"In15.Cu" "In16.Cu"
		)
		(hatch none 0.5)
		(connect_pads
			(clearance 0)
		)
		(min_thickness 0.25)
		(keepout
			(tracks not_allowed)
			(vias allowed)
			(pads allowed)
			(copperpour not_allowed)
			(footprints allowed)
		)
		(placement
			(enabled no)
			(sheetname "")
		)
		(fill
			(thermal_gap 0.5)
			(thermal_bridge_width 0.5)
			(island_removal_mode 0)
		)
		(polygon
			(pts
				(arc
					(start 344.280998 -369.928902)
					(mid 344.295877 -369.892981)
					(end 344.331798 -369.878102)
				)
				(arc
					(start 345.048078 -369.878102)
					(mid 345.083999 -369.892981)
					(end 345.098878 -369.928902)
				)
				(arc
					(start 345.098878 -372.351554)
					(mid 345.083999 -372.387475)
					(end 345.048078 -372.402354)
				)
				(arc
					(start 344.331798 -372.402354)
					(mid 344.295877 -372.387475)
					(end 344.280998 -372.351554)
				)
			)
		)
	)
	(zone
		(layers "F.Cu" "B.Cu" "In1.Cu" "In2.Cu" "In3.Cu" "In4.Cu" "In5.Cu" "In6.Cu"
			"In7.Cu" "In8.Cu" "In9.Cu" "In10.Cu" "In11.Cu" "In12.Cu" "In13.Cu" "In14.Cu"
			"In15.Cu" "In16.Cu"
		)
		(hatch none 0.5)
		(connect_pads
			(clearance 0)
		)
		(min_thickness 0.25)
		(keepout
			(tracks not_allowed)
			(vias allowed)
			(pads allowed)
			(copperpour not_allowed)
			(footprints allowed)
		)
		(placement
			(enabled no)
			(sheetname "")
		)
		(fill
			(thermal_gap 0.5)
			(thermal_bridge_width 0.5)
			(island_removal_mode 0)
		)
		(polygon
			(pts
				(arc
					(start 271.006062 -345.084146)
					(mid 270.625062 -345.465146)
					(end 271.006062 -345.846146)
				)
				(arc
					(start 271.869662 -345.846146)
					(mid 272.250662 -345.465146)
					(end 271.869662 -345.084146)
				)
			)
		)
	)
	(zone
		(layers "F.Cu" "B.Cu" "In1.Cu" "In2.Cu" "In3.Cu" "In4.Cu" "In5.Cu" "In6.Cu"
			"In7.Cu" "In8.Cu" "In9.Cu" "In10.Cu" "In11.Cu" "In12.Cu" "In13.Cu" "In14.Cu"
			"In15.Cu" "In16.Cu"
		)
		(hatch none 0.5)
		(connect_pads
			(clearance 0)
		)
		(min_thickness 0.25)
		(keepout
			(tracks not_allowed)
			(vias allowed)
			(pads allowed)
			(copperpour not_allowed)
			(footprints allowed)
		)
		(placement
			(enabled no)
			(sheetname "")
		)
		(fill
			(thermal_gap 0.5)
			(thermal_bridge_width 0.5)
			(island_removal_mode 0)
		)
		(polygon
			(pts
				(arc
					(start 283.441902 -342.058498)
					(mid 283.060902 -342.439498)
					(end 283.441902 -342.820498)
				)
				(arc
					(start 284.305502 -342.820498)
					(mid 284.686502 -342.439498)
					(end 284.305502 -342.058498)
				)
			)
		)
	)
	(zone
		(layers "F.Cu" "B.Cu" "In1.Cu" "In2.Cu" "In3.Cu" "In4.Cu" "In5.Cu" "In6.Cu"
			"In7.Cu" "In8.Cu" "In9.Cu" "In10.Cu" "In11.Cu" "In12.Cu" "In13.Cu" "In14.Cu"
			"In15.Cu" "In16.Cu"
		)
		(hatch none 0.5)
		(connect_pads
			(clearance 0)
		)
		(min_thickness 0.25)
		(keepout
			(tracks not_allowed)
			(vias allowed)
			(pads allowed)
			(copperpour not_allowed)
			(footprints allowed)
		)
		(placement
			(enabled no)
			(sheetname "")
		)
		(fill
			(thermal_gap 0.5)
			(thermal_bridge_width 0.5)
			(island_removal_mode 0)
		)
		(polygon
			(pts
				(arc
					(start 289.659822 -357.37673)
					(mid 289.278822 -357.75773)
					(end 289.659822 -358.13873)
				)
				(arc
					(start 290.523422 -358.13873)
					(mid 290.904422 -357.75773)
					(end 290.523422 -357.37673)
				)
			)
		)
	)
	(zone
		(layers "F.Cu" "B.Cu" "In1.Cu" "In2.Cu" "In3.Cu" "In4.Cu" "In5.Cu" "In6.Cu"
			"In7.Cu" "In8.Cu" "In9.Cu" "In10.Cu" "In11.Cu" "In12.Cu" "In13.Cu" "In14.Cu"
			"In15.Cu" "In16.Cu"
		)
		(hatch none 0.5)
		(connect_pads
			(clearance 0)
		)
		(min_thickness 0.25)
		(keepout
			(tracks not_allowed)
			(vias allowed)
			(pads allowed)
			(copperpour not_allowed)
			(footprints allowed)
		)
		(placement
			(enabled no)
			(sheetname "")
		)
		(fill
			(thermal_gap 0.5)
			(thermal_bridge_width 0.5)
			(island_removal_mode 0)
		)
		(polygon
			(pts
				(arc
					(start 28.659328 -342.058498)
					(mid 28.278328 -342.439498)
					(end 28.659328 -342.820498)
				)
				(arc
					(start 29.522928 -342.820498)
					(mid 29.903928 -342.439498)
					(end 29.522928 -342.058498)
				)
			)
		)
	)
	(zone
		(layers "F.Cu" "B.Cu" "In1.Cu" "In2.Cu" "In3.Cu" "In4.Cu" "In5.Cu" "In6.Cu"
			"In7.Cu" "In8.Cu" "In9.Cu" "In10.Cu" "In11.Cu" "In12.Cu" "In13.Cu" "In14.Cu"
			"In15.Cu" "In16.Cu"
		)
		(hatch none 0.5)
		(connect_pads
			(clearance 0)
		)
		(min_thickness 0.25)
		(keepout
			(tracks not_allowed)
			(vias allowed)
			(pads allowed)
			(copperpour not_allowed)
			(footprints allowed)
		)
		(placement
			(enabled no)
			(sheetname "")
		)
		(fill
			(thermal_gap 0.5)
			(thermal_bridge_width 0.5)
			(island_removal_mode 0)
		)
		(polygon
			(pts
				(arc
					(start 31.90113 -407.628852)
					(mid 31.916009 -407.592931)
					(end 31.95193 -407.578052)
				)
				(arc
					(start 32.66821 -407.578052)
					(mid 32.704131 -407.592931)
					(end 32.71901 -407.628852)
				)
				(arc
					(start 32.71901 -410.051504)
					(mid 32.704131 -410.087425)
					(end 32.66821 -410.102304)
				)
				(arc
					(start 31.95193 -410.102304)
					(mid 31.916009 -410.087425)
					(end 31.90113 -410.051504)
				)
			)
		)
	)
	(zone
		(layers "F.Cu" "B.Cu" "In1.Cu" "In2.Cu" "In3.Cu" "In4.Cu" "In5.Cu" "In6.Cu"
			"In7.Cu" "In8.Cu" "In9.Cu" "In10.Cu" "In11.Cu" "In12.Cu" "In13.Cu" "In14.Cu"
			"In15.Cu" "In16.Cu"
		)
		(hatch none 0.5)
		(connect_pads
			(clearance 0)
		)
		(min_thickness 0.25)
		(keepout
			(tracks not_allowed)
			(vias allowed)
			(pads allowed)
			(copperpour not_allowed)
			(footprints allowed)
		)
		(placement
			(enabled no)
			(sheetname "")
		)
		(fill
			(thermal_gap 0.5)
			(thermal_bridge_width 0.5)
			(island_removal_mode 0)
		)
		(polygon
			(pts
				(arc
					(start 434.48097 -408.728672)
					(mid 434.495849 -408.692751)
					(end 434.53177 -408.677872)
				)
				(arc
					(start 435.24805 -408.677872)
					(mid 435.283971 -408.692751)
					(end 435.29885 -408.728672)
				)
				(arc
					(start 435.29885 -411.151324)
					(mid 435.283971 -411.187245)
					(end 435.24805 -411.202124)
				)
				(arc
					(start 434.53177 -411.202124)
					(mid 434.495849 -411.187245)
					(end 434.48097 -411.151324)
				)
			)
		)
	)
	(zone
		(layers "F.Cu" "B.Cu" "In1.Cu" "In2.Cu" "In3.Cu" "In4.Cu" "In5.Cu" "In6.Cu"
			"In7.Cu" "In8.Cu" "In9.Cu" "In10.Cu" "In11.Cu" "In12.Cu" "In13.Cu" "In14.Cu"
			"In15.Cu" "In16.Cu"
		)
		(hatch none 0.5)
		(connect_pads
			(clearance 0)
		)
		(min_thickness 0.25)
		(keepout
			(tracks not_allowed)
			(vias allowed)
			(pads allowed)
			(copperpour not_allowed)
			(footprints allowed)
		)
		(placement
			(enabled no)
			(sheetname "")
		)
		(fill
			(thermal_gap 0.5)
			(thermal_bridge_width 0.5)
			(island_removal_mode 0)
		)
		(polygon
			(pts
				(arc
					(start 289.280854 -408.728672)
					(mid 289.295733 -408.692751)
					(end 289.331654 -408.677872)
				)
				(arc
					(start 290.047934 -408.677872)
					(mid 290.083855 -408.692751)
					(end 290.098734 -408.728672)
				)
				(arc
					(start 290.098734 -411.151324)
					(mid 290.083855 -411.187245)
					(end 290.047934 -411.202124)
				)
				(arc
					(start 289.331654 -411.202124)
					(mid 289.295733 -411.187245)
					(end 289.280854 -411.151324)
				)
			)
		)
	)
	(zone
		(layers "F.Cu" "B.Cu" "In1.Cu" "In2.Cu" "In3.Cu" "In4.Cu" "In5.Cu" "In6.Cu"
			"In7.Cu" "In8.Cu" "In9.Cu" "In10.Cu" "In11.Cu" "In12.Cu" "In13.Cu" "In14.Cu"
			"In15.Cu" "In16.Cu"
		)
		(hatch none 0.5)
		(connect_pads
			(clearance 0)
		)
		(min_thickness 0.25)
		(keepout
			(tracks not_allowed)
			(vias allowed)
			(pads allowed)
			(copperpour not_allowed)
			(footprints allowed)
		)
		(placement
			(enabled no)
			(sheetname "")
		)
		(fill
			(thermal_gap 0.5)
			(thermal_bridge_width 0.5)
			(island_removal_mode 0)
		)
		(polygon
			(pts
				(arc
					(start 427.948852 -357.37673)
					(mid 427.567852 -357.75773)
					(end 427.948852 -358.13873)
				)
				(arc
					(start 428.812452 -358.13873)
					(mid 429.193452 -357.75773)
					(end 428.812452 -357.37673)
				)
			)
		)
	)
	(zone
		(layers "F.Cu" "B.Cu" "In1.Cu" "In2.Cu" "In3.Cu" "In4.Cu" "In5.Cu" "In6.Cu"
			"In7.Cu" "In8.Cu" "In9.Cu" "In10.Cu" "In11.Cu" "In12.Cu" "In13.Cu" "In14.Cu"
			"In15.Cu" "In16.Cu"
		)
		(hatch none 0.5)
		(connect_pads
			(clearance 0)
		)
		(min_thickness 0.25)
		(keepout
			(tracks not_allowed)
			(vias allowed)
			(pads allowed)
			(copperpour not_allowed)
			(footprints allowed)
		)
		(placement
			(enabled no)
			(sheetname "")
		)
		(fill
			(thermal_gap 0.5)
			(thermal_bridge_width 0.5)
			(island_removal_mode 0)
		)
		(polygon
			(pts
				(arc
					(start 50.422048 -342.058498)
					(mid 50.041048 -342.439498)
					(end 50.422048 -342.820498)
				)
				(arc
					(start 51.285648 -342.820498)
					(mid 51.666648 -342.439498)
					(end 51.285648 -342.058498)
				)
			)
		)
	)
	(zone
		(layers "F.Cu" "B.Cu" "In1.Cu" "In2.Cu" "In3.Cu" "In4.Cu" "In5.Cu" "In6.Cu"
			"In7.Cu" "In8.Cu" "In9.Cu" "In10.Cu" "In11.Cu" "In12.Cu" "In13.Cu" "In14.Cu"
			"In15.Cu" "In16.Cu"
		)
		(hatch none 0.5)
		(connect_pads
			(clearance 0)
		)
		(min_thickness 0.25)
		(keepout
			(tracks not_allowed)
			(vias allowed)
			(pads allowed)
			(copperpour not_allowed)
			(footprints allowed)
		)
		(placement
			(enabled no)
			(sheetname "")
		)
		(fill
			(thermal_gap 0.5)
			(thermal_bridge_width 0.5)
			(island_removal_mode 0)
		)
		(polygon
			(pts
				(arc
					(start 153.410666 -110.977934)
					(mid 153.867866 -111.435134)
					(end 154.325066 -110.977934)
				)
				(arc
					(start 154.325066 -110.114334)
					(mid 153.867866 -109.657134)
					(end 153.410666 -110.114334)
				)
			)
		)
	)
	(zone
		(layers "F.Cu" "B.Cu" "In1.Cu" "In2.Cu" "In3.Cu" "In4.Cu" "In5.Cu" "In6.Cu"
			"In7.Cu" "In8.Cu" "In9.Cu" "In10.Cu" "In11.Cu" "In12.Cu" "In13.Cu" "In14.Cu"
			"In15.Cu" "In16.Cu"
		)
		(hatch none 0.5)
		(connect_pads
			(clearance 0)
		)
		(min_thickness 0.25)
		(keepout
			(tracks not_allowed)
			(vias allowed)
			(pads allowed)
			(copperpour not_allowed)
			(footprints allowed)
		)
		(placement
			(enabled no)
			(sheetname "")
		)
		(fill
			(thermal_gap 0.5)
			(thermal_bridge_width 0.5)
			(island_removal_mode 0)
		)
		(polygon
			(pts
				(arc
					(start 73.808082 -351.230438)
					(mid 73.427082 -351.611438)
					(end 73.808082 -351.992438)
				)
				(arc
					(start 74.671682 -351.992438)
					(mid 75.052682 -351.611438)
					(end 74.671682 -351.230438)
				)
			)
		)
	)
	(zone
		(layers "F.Cu" "B.Cu" "In1.Cu" "In2.Cu" "In3.Cu" "In4.Cu" "In5.Cu" "In6.Cu"
			"In7.Cu" "In8.Cu" "In9.Cu" "In10.Cu" "In11.Cu" "In12.Cu" "In13.Cu" "In14.Cu"
			"In15.Cu" "In16.Cu"
		)
		(hatch none 0.5)
		(connect_pads
			(clearance 0)
		)
		(min_thickness 0.25)
		(keepout
			(tracks not_allowed)
			(vias allowed)
			(pads allowed)
			(copperpour not_allowed)
			(footprints allowed)
		)
		(placement
			(enabled no)
			(sheetname "")
		)
		(fill
			(thermal_gap 0.5)
			(thermal_bridge_width 0.5)
			(island_removal_mode 0)
		)
		(polygon
			(pts
				(arc
					(start 180.845968 -148.887434)
					(mid 181.303168 -149.344634)
					(end 181.760368 -148.887434)
				)
				(arc
					(start 181.760368 -148.023834)
					(mid 181.303168 -147.566634)
					(end 180.845968 -148.023834)
				)
			)
		)
	)
	(zone
		(layers "F.Cu" "B.Cu" "In1.Cu" "In2.Cu" "In3.Cu" "In4.Cu" "In5.Cu" "In6.Cu"
			"In7.Cu" "In8.Cu" "In9.Cu" "In10.Cu" "In11.Cu" "In12.Cu" "In13.Cu" "In14.Cu"
			"In15.Cu" "In16.Cu"
		)
		(hatch none 0.5)
		(connect_pads
			(clearance 0)
		)
		(min_thickness 0.25)
		(keepout
			(tracks not_allowed)
			(vias allowed)
			(pads allowed)
			(copperpour not_allowed)
			(footprints allowed)
		)
		(placement
			(enabled no)
			(sheetname "")
		)
		(fill
			(thermal_gap 0.5)
			(thermal_bridge_width 0.5)
			(island_removal_mode 0)
		)
		(polygon
			(pts
				(arc
					(start 117.70106 -374.928638)
					(mid 117.715939 -374.892717)
					(end 117.75186 -374.877838)
				)
				(arc
					(start 118.46814 -374.877838)
					(mid 118.504061 -374.892717)
					(end 118.51894 -374.928638)
				)
				(arc
					(start 118.51894 -377.35129)
					(mid 118.504061 -377.387211)
					(end 118.46814 -377.40209)
				)
				(arc
					(start 117.75186 -377.40209)
					(mid 117.715939 -377.387211)
					(end 117.70106 -377.35129)
				)
			)
		)
	)
	(zone
		(layers "F.Cu" "B.Cu" "In1.Cu" "In2.Cu" "In3.Cu" "In4.Cu" "In5.Cu" "In6.Cu"
			"In7.Cu" "In8.Cu" "In9.Cu" "In10.Cu" "In11.Cu" "In12.Cu" "In13.Cu" "In14.Cu"
			"In15.Cu" "In16.Cu"
		)
		(hatch none 0.5)
		(connect_pads
			(clearance 0)
		)
		(min_thickness 0.25)
		(keepout
			(tracks not_allowed)
			(vias allowed)
			(pads allowed)
			(copperpour not_allowed)
			(footprints allowed)
		)
		(placement
			(enabled no)
			(sheetname "")
		)
		(fill
			(thermal_gap 0.5)
			(thermal_bridge_width 0.5)
			(island_removal_mode 0)
		)
		(polygon
			(pts
				(arc
					(start 168.800018 -124.622814)
					(mid 168.342818 -124.165614)
					(end 167.885618 -124.622814)
				)
				(arc
					(start 167.885618 -125.486414)
					(mid 168.342818 -125.943614)
					(end 168.800018 -125.486414)
				)
			)
		)
	)
	(zone
		(layers "F.Cu" "B.Cu" "In1.Cu" "In2.Cu" "In3.Cu" "In4.Cu" "In5.Cu" "In6.Cu"
			"In7.Cu" "In8.Cu" "In9.Cu" "In10.Cu" "In11.Cu" "In12.Cu" "In13.Cu" "In14.Cu"
			"In15.Cu" "In16.Cu"
		)
		(hatch none 0.5)
		(connect_pads
			(clearance 0)
		)
		(min_thickness 0.25)
		(keepout
			(tracks not_allowed)
			(vias allowed)
			(pads allowed)
			(copperpour not_allowed)
			(footprints allowed)
		)
		(placement
			(enabled no)
			(sheetname "")
		)
		(fill
			(thermal_gap 0.5)
			(thermal_bridge_width 0.5)
			(island_removal_mode 0)
		)
		(polygon
			(pts
				(arc
					(start 289.280854 -397.028924)
					(mid 289.295733 -396.993003)
					(end 289.331654 -396.978124)
				)
				(arc
					(start 290.047934 -396.978124)
					(mid 290.083855 -396.993003)
					(end 290.098734 -397.028924)
				)
				(arc
					(start 290.098734 -399.451576)
					(mid 290.083855 -399.487497)
					(end 290.047934 -399.502376)
				)
				(arc
					(start 289.331654 -399.502376)
					(mid 289.295733 -399.487497)
					(end 289.280854 -399.451576)
				)
			)
		)
	)
	(zone
		(layers "F.Cu" "B.Cu" "In1.Cu" "In2.Cu" "In3.Cu" "In4.Cu" "In5.Cu" "In6.Cu"
			"In7.Cu" "In8.Cu" "In9.Cu" "In10.Cu" "In11.Cu" "In12.Cu" "In13.Cu" "In14.Cu"
			"In15.Cu" "In16.Cu"
		)
		(hatch none 0.5)
		(connect_pads
			(clearance 0)
		)
		(min_thickness 0.25)
		(keepout
			(tracks not_allowed)
			(vias allowed)
			(pads allowed)
			(copperpour not_allowed)
			(footprints allowed)
		)
		(placement
			(enabled no)
			(sheetname "")
		)
		(fill
			(thermal_gap 0.5)
			(thermal_bridge_width 0.5)
			(island_removal_mode 0)
		)
		(polygon
			(pts
				(arc
					(start 122.85345 -34.52241)
					(mid 123.31065 -34.97961)
					(end 123.76785 -34.52241)
				)
				(arc
					(start 123.76785 -33.65881)
					(mid 123.31065 -33.20161)
					(end 122.85345 -33.65881)
				)
			)
		)
	)
	(zone
		(layers "F.Cu" "B.Cu" "In1.Cu" "In2.Cu" "In3.Cu" "In4.Cu" "In5.Cu" "In6.Cu"
			"In7.Cu" "In8.Cu" "In9.Cu" "In10.Cu" "In11.Cu" "In12.Cu" "In13.Cu" "In14.Cu"
			"In15.Cu" "In16.Cu"
		)
		(hatch none 0.5)
		(connect_pads
			(clearance 0)
		)
		(min_thickness 0.25)
		(keepout
			(tracks not_allowed)
			(vias allowed)
			(pads allowed)
			(copperpour not_allowed)
			(footprints allowed)
		)
		(placement
			(enabled no)
			(sheetname "")
		)
		(fill
			(thermal_gap 0.5)
			(thermal_bridge_width 0.5)
			(island_removal_mode 0)
		)
		(polygon
			(pts
				(arc
					(start 86.243922 -354.351082)
					(mid 85.862922 -354.732082)
					(end 86.243922 -355.113082)
				)
				(arc
					(start 87.107522 -355.113082)
					(mid 87.488522 -354.732082)
					(end 87.107522 -354.351082)
				)
			)
		)
	)
	(zone
		(layers "F.Cu" "B.Cu" "In1.Cu" "In2.Cu" "In3.Cu" "In4.Cu" "In5.Cu" "In6.Cu"
			"In7.Cu" "In8.Cu" "In9.Cu" "In10.Cu" "In11.Cu" "In12.Cu" "In13.Cu" "In14.Cu"
			"In15.Cu" "In16.Cu"
		)
		(hatch none 0.5)
		(connect_pads
			(clearance 0)
		)
		(min_thickness 0.25)
		(keepout
			(tracks not_allowed)
			(vias allowed)
			(pads allowed)
			(copperpour not_allowed)
			(footprints allowed)
		)
		(placement
			(enabled no)
			(sheetname "")
		)
		(fill
			(thermal_gap 0.5)
			(thermal_bridge_width 0.5)
			(island_removal_mode 0)
		)
		(polygon
			(pts
				(arc
					(start 289.280854 -404.828756)
					(mid 289.295733 -404.792835)
					(end 289.331654 -404.777956)
				)
				(arc
					(start 290.047934 -404.777956)
					(mid 290.083855 -404.792835)
					(end 290.098734 -404.828756)
				)
				(arc
					(start 290.098734 -407.251408)
					(mid 290.083855 -407.287329)
					(end 290.047934 -407.302208)
				)
				(arc
					(start 289.331654 -407.302208)
					(mid 289.295733 -407.287329)
					(end 289.280854 -407.251408)
				)
			)
		)
	)
	(zone
		(layers "F.Cu" "B.Cu" "In1.Cu" "In2.Cu" "In3.Cu" "In4.Cu" "In5.Cu" "In6.Cu"
			"In7.Cu" "In8.Cu" "In9.Cu" "In10.Cu" "In11.Cu" "In12.Cu" "In13.Cu" "In14.Cu"
			"In15.Cu" "In16.Cu"
		)
		(hatch none 0.5)
		(connect_pads
			(clearance 0)
		)
		(min_thickness 0.25)
		(keepout
			(tracks not_allowed)
			(vias allowed)
			(pads allowed)
			(copperpour not_allowed)
			(footprints allowed)
		)
		(placement
			(enabled no)
			(sheetname "")
		)
		(fill
			(thermal_gap 0.5)
			(thermal_bridge_width 0.5)
			(island_removal_mode 0)
		)
		(polygon
			(pts
				(arc
					(start 440.384692 -351.230438)
					(mid 440.003692 -351.611438)
					(end 440.384692 -351.992438)
				)
				(arc
					(start 441.248292 -351.992438)
					(mid 441.629292 -351.611438)
					(end 441.248292 -351.230438)
				)
			)
		)
	)
	(zone
		(layers "F.Cu" "B.Cu" "In1.Cu" "In2.Cu" "In3.Cu" "In4.Cu" "In5.Cu" "In6.Cu"
			"In7.Cu" "In8.Cu" "In9.Cu" "In10.Cu" "In11.Cu" "In12.Cu" "In13.Cu" "In14.Cu"
			"In15.Cu" "In16.Cu"
		)
		(hatch none 0.5)
		(connect_pads
			(clearance 0)
		)
		(min_thickness 0.25)
		(keepout
			(tracks not_allowed)
			(vias allowed)
			(pads allowed)
			(copperpour not_allowed)
			(footprints allowed)
		)
		(placement
			(enabled no)
			(sheetname "")
		)
		(fill
			(thermal_gap 0.5)
			(thermal_bridge_width 0.5)
			(island_removal_mode 0)
		)
		(polygon
			(pts
				(arc
					(start 287.08096 -373.828818)
					(mid 287.095839 -373.792897)
					(end 287.13176 -373.778018)
				)
				(arc
					(start 287.84804 -373.778018)
					(mid 287.883961 -373.792897)
					(end 287.89884 -373.828818)
				)
				(arc
					(start 287.89884 -376.25147)
					(mid 287.883961 -376.287391)
					(end 287.84804 -376.30227)
				)
				(arc
					(start 287.13176 -376.30227)
					(mid 287.095839 -376.287391)
					(end 287.08096 -376.25147)
				)
			)
		)
	)
	(zone
		(layers "F.Cu" "B.Cu" "In1.Cu" "In2.Cu" "In3.Cu" "In4.Cu" "In5.Cu" "In6.Cu"
			"In7.Cu" "In8.Cu" "In9.Cu" "In10.Cu" "In11.Cu" "In12.Cu" "In13.Cu" "In14.Cu"
			"In15.Cu" "In16.Cu"
		)
		(hatch none 0.5)
		(connect_pads
			(clearance 0)
		)
		(min_thickness 0.25)
		(keepout
			(tracks not_allowed)
			(vias allowed)
			(pads allowed)
			(copperpour not_allowed)
			(footprints allowed)
		)
		(placement
			(enabled no)
			(sheetname "")
		)
		(fill
			(thermal_gap 0.5)
			(thermal_bridge_width 0.5)
			(island_removal_mode 0)
		)
		(polygon
			(pts
				(arc
					(start 386.73278 -357.37673)
					(mid 386.35178 -357.75773)
					(end 386.73278 -358.13873)
				)
				(arc
					(start 387.59638 -358.13873)
					(mid 387.97738 -357.75773)
					(end 387.59638 -357.37673)
				)
			)
		)
	)
	(zone
		(layers "F.Cu" "B.Cu" "In1.Cu" "In2.Cu" "In3.Cu" "In4.Cu" "In5.Cu" "In6.Cu"
			"In7.Cu" "In8.Cu" "In9.Cu" "In10.Cu" "In11.Cu" "In12.Cu" "In13.Cu" "In14.Cu"
			"In15.Cu" "In16.Cu"
		)
		(hatch none 0.5)
		(connect_pads
			(clearance 0)
		)
		(min_thickness 0.25)
		(keepout
			(tracks not_allowed)
			(vias allowed)
			(pads allowed)
			(copperpour not_allowed)
			(footprints allowed)
		)
		(placement
			(enabled no)
			(sheetname "")
		)
		(fill
			(thermal_gap 0.5)
			(thermal_bridge_width 0.5)
			(island_removal_mode 0)
		)
		(polygon
			(pts
				(arc
					(start 165.295072 -351.230438)
					(mid 164.914072 -351.611438)
					(end 165.295072 -351.992438)
				)
				(arc
					(start 166.158672 -351.992438)
					(mid 166.539672 -351.611438)
					(end 166.158672 -351.230438)
				)
			)
		)
	)
	(zone
		(layers "F.Cu" "B.Cu" "In1.Cu" "In2.Cu" "In3.Cu" "In4.Cu" "In5.Cu" "In6.Cu"
			"In7.Cu" "In8.Cu" "In9.Cu" "In10.Cu" "In11.Cu" "In12.Cu" "In13.Cu" "In14.Cu"
			"In15.Cu" "In16.Cu"
		)
		(hatch none 0.5)
		(connect_pads
			(clearance 0)
		)
		(min_thickness 0.25)
		(keepout
			(tracks not_allowed)
			(vias allowed)
			(pads allowed)
			(copperpour not_allowed)
			(footprints allowed)
		)
		(placement
			(enabled no)
			(sheetname "")
		)
		(fill
			(thermal_gap 0.5)
			(thermal_bridge_width 0.5)
			(island_removal_mode 0)
		)
		(polygon
			(pts
				(arc
					(start 381.05334 -34.52241)
					(mid 381.51054 -34.97961)
					(end 381.96774 -34.52241)
				)
				(arc
					(start 381.96774 -33.65881)
					(mid 381.51054 -33.20161)
					(end 381.05334 -33.65881)
				)
			)
		)
	)
	(zone
		(layers "F.Cu" "B.Cu" "In1.Cu" "In2.Cu" "In3.Cu" "In4.Cu" "In5.Cu" "In6.Cu"
			"In7.Cu" "In8.Cu" "In9.Cu" "In10.Cu" "In11.Cu" "In12.Cu" "In13.Cu" "In14.Cu"
			"In15.Cu" "In16.Cu"
		)
		(hatch none 0.5)
		(connect_pads
			(clearance 0)
		)
		(min_thickness 0.25)
		(keepout
			(tracks not_allowed)
			(vias allowed)
			(pads allowed)
			(copperpour not_allowed)
			(footprints allowed)
		)
		(placement
			(enabled no)
			(sheetname "")
		)
		(fill
			(thermal_gap 0.5)
			(thermal_bridge_width 0.5)
			(island_removal_mode 0)
		)
		(polygon
			(pts
				(arc
					(start 168.301162 -381.628904)
					(mid 168.316041 -381.592983)
					(end 168.351962 -381.578104)
				)
				(arc
					(start 169.068242 -381.578104)
					(mid 169.104163 -381.592983)
					(end 169.119042 -381.628904)
				)
				(arc
					(start 169.119042 -384.051556)
					(mid 169.104163 -384.087477)
					(end 169.068242 -384.102356)
				)
				(arc
					(start 168.351962 -384.102356)
					(mid 168.316041 -384.087477)
					(end 168.301162 -384.051556)
				)
			)
		)
	)
	(zone
		(layers "F.Cu" "B.Cu" "In1.Cu" "In2.Cu" "In3.Cu" "In4.Cu" "In5.Cu" "In6.Cu"
			"In7.Cu" "In8.Cu" "In9.Cu" "In10.Cu" "In11.Cu" "In12.Cu" "In13.Cu" "In14.Cu"
			"In15.Cu" "In16.Cu"
		)
		(hatch none 0.5)
		(connect_pads
			(clearance 0)
		)
		(min_thickness 0.25)
		(keepout
			(tracks not_allowed)
			(vias allowed)
			(pads allowed)
			(copperpour not_allowed)
			(footprints allowed)
		)
		(placement
			(enabled no)
			(sheetname "")
		)
		(fill
			(thermal_gap 0.5)
			(thermal_bridge_width 0.5)
			(island_removal_mode 0)
		)
		(polygon
			(pts
				(arc
					(start 128.701038 -407.628852)
					(mid 128.715917 -407.592931)
					(end 128.751838 -407.578052)
				)
				(arc
					(start 129.468118 -407.578052)
					(mid 129.504039 -407.592931)
					(end 129.518918 -407.628852)
				)
				(arc
					(start 129.518918 -410.051504)
					(mid 129.504039 -410.087425)
					(end 129.468118 -410.102304)
				)
				(arc
					(start 128.751838 -410.102304)
					(mid 128.715917 -410.087425)
					(end 128.701038 -410.051504)
				)
			)
		)
	)
	(zone
		(layers "F.Cu" "B.Cu" "In1.Cu" "In2.Cu" "In3.Cu" "In4.Cu" "In5.Cu" "In6.Cu"
			"In7.Cu" "In8.Cu" "In9.Cu" "In10.Cu" "In11.Cu" "In12.Cu" "In13.Cu" "In14.Cu"
			"In15.Cu" "In16.Cu"
		)
		(hatch none 0.5)
		(connect_pads
			(clearance 0)
		)
		(min_thickness 0.25)
		(keepout
			(tracks not_allowed)
			(vias allowed)
			(pads allowed)
			(copperpour not_allowed)
			(footprints allowed)
		)
		(placement
			(enabled no)
			(sheetname "")
		)
		(fill
			(thermal_gap 0.5)
			(thermal_bridge_width 0.5)
			(island_removal_mode 0)
		)
		(polygon
			(pts
				(arc
					(start 441.42787 21.000212)
					(mid 441.04687 21.381212)
					(end 440.66587 21.000212)
				)
				(arc
					(start 440.66587 20.136612)
					(mid 441.04687 19.755612)
					(end 441.42787 20.136612)
				)
			)
		)
	)
	(zone
		(layers "F.Cu" "B.Cu" "In1.Cu" "In2.Cu" "In3.Cu" "In4.Cu" "In5.Cu" "In6.Cu"
			"In7.Cu" "In8.Cu" "In9.Cu" "In10.Cu" "In11.Cu" "In12.Cu" "In13.Cu" "In14.Cu"
			"In15.Cu" "In16.Cu"
		)
		(hatch none 0.5)
		(connect_pads
			(clearance 0)
		)
		(min_thickness 0.25)
		(keepout
			(tracks not_allowed)
			(vias allowed)
			(pads allowed)
			(copperpour not_allowed)
			(footprints allowed)
		)
		(placement
			(enabled no)
			(sheetname "")
		)
		(fill
			(thermal_gap 0.5)
			(thermal_bridge_width 0.5)
			(island_removal_mode 0)
		)
		(polygon
			(pts
				(arc
					(start 162.186112 -357.37673)
					(mid 161.805112 -357.75773)
					(end 162.186112 -358.13873)
				)
				(arc
					(start 163.049712 -358.13873)
					(mid 163.430712 -357.75773)
					(end 163.049712 -357.37673)
				)
			)
		)
	)
	(zone
		(layers "F.Cu" "B.Cu" "In1.Cu" "In2.Cu" "In3.Cu" "In4.Cu" "In5.Cu" "In6.Cu"
			"In7.Cu" "In8.Cu" "In9.Cu" "In10.Cu" "In11.Cu" "In12.Cu" "In13.Cu" "In14.Cu"
			"In15.Cu" "In16.Cu"
		)
		(hatch none 0.5)
		(connect_pads
			(clearance 0)
		)
		(min_thickness 0.25)
		(keepout
			(tracks not_allowed)
			(vias allowed)
			(pads allowed)
			(copperpour not_allowed)
			(footprints allowed)
		)
		(placement
			(enabled no)
			(sheetname "")
		)
		(fill
			(thermal_gap 0.5)
			(thermal_bridge_width 0.5)
			(island_removal_mode 0)
		)
		(polygon
			(pts
				(arc
					(start 274.240498 20.143724)
					(mid 274.621498 19.762724)
					(end 275.002498 20.143724)
				)
				(arc
					(start 275.002498 21.007324)
					(mid 274.621498 21.388324)
					(end 274.240498 21.007324)
				)
			)
		)
	)
	(zone
		(layers "F.Cu" "B.Cu" "In1.Cu" "In2.Cu" "In3.Cu" "In4.Cu" "In5.Cu" "In6.Cu"
			"In7.Cu" "In8.Cu" "In9.Cu" "In10.Cu" "In11.Cu" "In12.Cu" "In13.Cu" "In14.Cu"
			"In15.Cu" "In16.Cu"
		)
		(hatch none 0.5)
		(connect_pads
			(clearance 0)
		)
		(min_thickness 0.25)
		(keepout
			(tracks not_allowed)
			(vias allowed)
			(pads allowed)
			(copperpour not_allowed)
			(footprints allowed)
		)
		(placement
			(enabled no)
			(sheetname "")
		)
		(fill
			(thermal_gap 0.5)
			(thermal_bridge_width 0.5)
			(island_removal_mode 0)
		)
		(polygon
			(pts
				(arc
					(start 409.295092 -345.084146)
					(mid 408.914092 -345.465146)
					(end 409.295092 -345.846146)
				)
				(arc
					(start 410.158692 -345.846146)
					(mid 410.539692 -345.465146)
					(end 410.158692 -345.084146)
				)
			)
		)
	)
	(zone
		(layers "F.Cu" "B.Cu" "In1.Cu" "In2.Cu" "In3.Cu" "In4.Cu" "In5.Cu" "In6.Cu"
			"In7.Cu" "In8.Cu" "In9.Cu" "In10.Cu" "In11.Cu" "In12.Cu" "In13.Cu" "In14.Cu"
			"In15.Cu" "In16.Cu"
		)
		(hatch none 0.5)
		(connect_pads
			(clearance 0)
		)
		(min_thickness 0.25)
		(keepout
			(tracks not_allowed)
			(vias allowed)
			(pads allowed)
			(copperpour not_allowed)
			(footprints allowed)
		)
		(placement
			(enabled no)
			(sheetname "")
		)
		(fill
			(thermal_gap 0.5)
			(thermal_bridge_width 0.5)
			(island_removal_mode 0)
		)
		(polygon
			(pts
				(arc
					(start 115.501166 -395.92885)
					(mid 115.516045 -395.892929)
					(end 115.551966 -395.87805)
				)
				(arc
					(start 116.268246 -395.87805)
					(mid 116.304167 -395.892929)
					(end 116.319046 -395.92885)
				)
				(arc
					(start 116.319046 -398.351502)
					(mid 116.304167 -398.387423)
					(end 116.268246 -398.402302)
				)
				(arc
					(start 115.551966 -398.402302)
					(mid 115.516045 -398.387423)
					(end 115.501166 -398.351502)
				)
			)
		)
	)
	(zone
		(layers "F.Cu" "B.Cu" "In1.Cu" "In2.Cu" "In3.Cu" "In4.Cu" "In5.Cu" "In6.Cu"
			"In7.Cu" "In8.Cu" "In9.Cu" "In10.Cu" "In11.Cu" "In12.Cu" "In13.Cu" "In14.Cu"
			"In15.Cu" "In16.Cu"
		)
		(hatch none 0.5)
		(connect_pads
			(clearance 0)
		)
		(min_thickness 0.25)
		(keepout
			(tracks not_allowed)
			(vias allowed)
			(pads allowed)
			(copperpour not_allowed)
			(footprints allowed)
		)
		(placement
			(enabled no)
			(sheetname "")
		)
		(fill
			(thermal_gap 0.5)
			(thermal_bridge_width 0.5)
			(island_removal_mode 0)
		)
		(polygon
			(pts
				(arc
					(start 381.680974 -378.828554)
					(mid 381.695853 -378.792633)
					(end 381.731774 -378.777754)
				)
				(arc
					(start 382.448054 -378.777754)
					(mid 382.483975 -378.792633)
					(end 382.498854 -378.828554)
				)
				(arc
					(start 382.498854 -381.251206)
					(mid 382.483975 -381.287127)
					(end 382.448054 -381.302006)
				)
				(arc
					(start 381.731774 -381.302006)
					(mid 381.695853 -381.287127)
					(end 381.680974 -381.251206)
				)
			)
		)
	)
	(zone
		(layers "F.Cu" "B.Cu" "In1.Cu" "In2.Cu" "In3.Cu" "In4.Cu" "In5.Cu" "In6.Cu"
			"In7.Cu" "In8.Cu" "In9.Cu" "In10.Cu" "In11.Cu" "In12.Cu" "In13.Cu" "In14.Cu"
			"In15.Cu" "In16.Cu"
		)
		(hatch none 0.5)
		(connect_pads
			(clearance 0)
		)
		(min_thickness 0.25)
		(keepout
			(tracks not_allowed)
			(vias allowed)
			(pads allowed)
			(copperpour not_allowed)
			(footprints allowed)
		)
		(placement
			(enabled no)
			(sheetname "")
		)
		(fill
			(thermal_gap 0.5)
			(thermal_bridge_width 0.5)
			(island_removal_mode 0)
		)
		(polygon
			(pts
				(arc
					(start 34.66846 -123.68784)
					(mid 35.12566 -124.14504)
					(end 35.58286 -123.68784)
				)
				(arc
					(start 35.58286 -122.82424)
					(mid 35.12566 -122.36704)
					(end 34.66846 -122.82424)
				)
			)
		)
	)
	(zone
		(layers "F.Cu" "B.Cu" "In1.Cu" "In2.Cu" "In3.Cu" "In4.Cu" "In5.Cu" "In6.Cu"
			"In7.Cu" "In8.Cu" "In9.Cu" "In10.Cu" "In11.Cu" "In12.Cu" "In13.Cu" "In14.Cu"
			"In15.Cu" "In16.Cu"
		)
		(hatch none 0.5)
		(connect_pads
			(clearance 0)
		)
		(min_thickness 0.25)
		(keepout
			(tracks not_allowed)
			(vias allowed)
			(pads allowed)
			(copperpour not_allowed)
			(footprints allowed)
		)
		(placement
			(enabled no)
			(sheetname "")
		)
		(fill
			(thermal_gap 0.5)
			(thermal_bridge_width 0.5)
			(island_removal_mode 0)
		)
		(polygon
			(pts
				(arc
					(start 128.701038 -399.828766)
					(mid 128.715917 -399.792845)
					(end 128.751838 -399.777966)
				)
				(arc
					(start 129.468118 -399.777966)
					(mid 129.504039 -399.792845)
					(end 129.518918 -399.828766)
				)
				(arc
					(start 129.518918 -402.251418)
					(mid 129.504039 -402.287339)
					(end 129.468118 -402.302218)
				)
				(arc
					(start 128.751838 -402.302218)
					(mid 128.715917 -402.287339)
					(end 128.701038 -402.251418)
				)
			)
		)
	)
	(zone
		(layers "F.Cu" "B.Cu" "In1.Cu" "In2.Cu" "In3.Cu" "In4.Cu" "In5.Cu" "In6.Cu"
			"In7.Cu" "In8.Cu" "In9.Cu" "In10.Cu" "In11.Cu" "In12.Cu" "In13.Cu" "In14.Cu"
			"In15.Cu" "In16.Cu"
		)
		(hatch none 0.5)
		(connect_pads
			(clearance 0)
		)
		(min_thickness 0.25)
		(keepout
			(tracks not_allowed)
			(vias allowed)
			(pads allowed)
			(copperpour not_allowed)
			(footprints allowed)
		)
		(placement
			(enabled no)
			(sheetname "")
		)
		(fill
			(thermal_gap 0.5)
			(thermal_bridge_width 0.5)
			(island_removal_mode 0)
		)
		(polygon
			(pts
				(arc
					(start 423.480992 -377.728734)
					(mid 423.495871 -377.692813)
					(end 423.531792 -377.677934)
				)
				(arc
					(start 424.248072 -377.677934)
					(mid 424.283993 -377.692813)
					(end 424.298872 -377.728734)
				)
				(arc
					(start 424.298872 -380.151386)
					(mid 424.283993 -380.187307)
					(end 424.248072 -380.202186)
				)
				(arc
					(start 423.531792 -380.202186)
					(mid 423.495871 -380.187307)
					(end 423.480992 -380.151386)
				)
			)
		)
	)
	(zone
		(layers "F.Cu" "B.Cu" "In1.Cu" "In2.Cu" "In3.Cu" "In4.Cu" "In5.Cu" "In6.Cu"
			"In7.Cu" "In8.Cu" "In9.Cu" "In10.Cu" "In11.Cu" "In12.Cu" "In13.Cu" "In14.Cu"
			"In15.Cu" "In16.Cu"
		)
		(hatch none 0.5)
		(connect_pads
			(clearance 0)
		)
		(min_thickness 0.25)
		(keepout
			(tracks not_allowed)
			(vias allowed)
			(pads allowed)
			(copperpour not_allowed)
			(footprints allowed)
		)
		(placement
			(enabled no)
			(sheetname "")
		)
		(fill
			(thermal_gap 0.5)
			(thermal_bridge_width 0.5)
			(island_removal_mode 0)
		)
		(polygon
			(pts
				(arc
					(start 168.800018 -101.112828)
					(mid 168.342818 -100.655628)
					(end 167.885618 -101.112828)
				)
				(arc
					(start 167.885618 -101.976428)
					(mid 168.342818 -102.433628)
					(end 168.800018 -101.976428)
				)
			)
		)
	)
	(zone
		(layers "F.Cu" "B.Cu" "In1.Cu" "In2.Cu" "In3.Cu" "In4.Cu" "In5.Cu" "In6.Cu"
			"In7.Cu" "In8.Cu" "In9.Cu" "In10.Cu" "In11.Cu" "In12.Cu" "In13.Cu" "In14.Cu"
			"In15.Cu" "In16.Cu"
		)
		(hatch none 0.5)
		(connect_pads
			(clearance 0)
		)
		(min_thickness 0.25)
		(keepout
			(tracks not_allowed)
			(vias allowed)
			(pads allowed)
			(copperpour not_allowed)
			(footprints allowed)
		)
		(placement
			(enabled no)
			(sheetname "")
		)
		(fill
			(thermal_gap 0.5)
			(thermal_bridge_width 0.5)
			(island_removal_mode 0)
		)
		(polygon
			(pts
				(arc
					(start 291.481002 -407.628852)
					(mid 291.495881 -407.592931)
					(end 291.531802 -407.578052)
				)
				(arc
					(start 292.248082 -407.578052)
					(mid 292.284003 -407.592931)
					(end 292.298882 -407.628852)
				)
				(arc
					(start 292.298882 -410.051504)
					(mid 292.284003 -410.087425)
					(end 292.248082 -410.102304)
				)
				(arc
					(start 291.531802 -410.102304)
					(mid 291.495881 -410.087425)
					(end 291.481002 -410.051504)
				)
			)
		)
	)
	(zone
		(layers "F.Cu" "B.Cu" "In1.Cu" "In2.Cu" "In3.Cu" "In4.Cu" "In5.Cu" "In6.Cu"
			"In7.Cu" "In8.Cu" "In9.Cu" "In10.Cu" "In11.Cu" "In12.Cu" "In13.Cu" "In14.Cu"
			"In15.Cu" "In16.Cu"
		)
		(hatch none 0.5)
		(connect_pads
			(clearance 0)
		)
		(min_thickness 0.25)
		(keepout
			(tracks not_allowed)
			(vias allowed)
			(pads allowed)
			(copperpour not_allowed)
			(footprints allowed)
		)
		(placement
			(enabled no)
			(sheetname "")
		)
		(fill
			(thermal_gap 0.5)
			(thermal_bridge_width 0.5)
			(island_removal_mode 0)
		)
		(polygon
			(pts
				(arc
					(start 380.51486 -342.058498)
					(mid 380.13386 -342.439498)
					(end 380.51486 -342.820498)
				)
				(arc
					(start 381.37846 -342.820498)
					(mid 381.75946 -342.439498)
					(end 381.37846 -342.058498)
				)
			)
		)
	)
	(zone
		(layers "F.Cu" "B.Cu" "In1.Cu" "In2.Cu" "In3.Cu" "In4.Cu" "In5.Cu" "In6.Cu"
			"In7.Cu" "In8.Cu" "In9.Cu" "In10.Cu" "In11.Cu" "In12.Cu" "In13.Cu" "In14.Cu"
			"In15.Cu" "In16.Cu"
		)
		(hatch none 0.5)
		(connect_pads
			(clearance 0)
		)
		(min_thickness 0.25)
		(keepout
			(tracks not_allowed)
			(vias allowed)
			(pads allowed)
			(copperpour not_allowed)
			(footprints allowed)
		)
		(placement
			(enabled no)
			(sheetname "")
		)
		(fill
			(thermal_gap 0.5)
			(thermal_bridge_width 0.5)
			(island_removal_mode 0)
		)
		(polygon
			(pts
				(arc
					(start 171.512992 -348.20479)
					(mid 171.131992 -348.58579)
					(end 171.512992 -348.96679)
				)
				(arc
					(start 172.376592 -348.96679)
					(mid 172.757592 -348.58579)
					(end 172.376592 -348.20479)
				)
			)
		)
	)
	(zone
		(layers "F.Cu" "B.Cu" "In1.Cu" "In2.Cu" "In3.Cu" "In4.Cu" "In5.Cu" "In6.Cu"
			"In7.Cu" "In8.Cu" "In9.Cu" "In10.Cu" "In11.Cu" "In12.Cu" "In13.Cu" "In14.Cu"
			"In15.Cu" "In16.Cu"
		)
		(hatch none 0.5)
		(connect_pads
			(clearance 0)
		)
		(min_thickness 0.25)
		(keepout
			(tracks not_allowed)
			(vias allowed)
			(pads allowed)
			(copperpour not_allowed)
			(footprints allowed)
		)
		(placement
			(enabled no)
			(sheetname "")
		)
		(fill
			(thermal_gap 0.5)
			(thermal_bridge_width 0.5)
			(island_removal_mode 0)
		)
		(polygon
			(pts
				(arc
					(start 375.081038 -395.92885)
					(mid 375.095917 -395.892929)
					(end 375.131838 -395.87805)
				)
				(arc
					(start 375.848118 -395.87805)
					(mid 375.884039 -395.892929)
					(end 375.898918 -395.92885)
				)
				(arc
					(start 375.898918 -398.351502)
					(mid 375.884039 -398.387423)
					(end 375.848118 -398.402302)
				)
				(arc
					(start 375.131838 -398.402302)
					(mid 375.095917 -398.387423)
					(end 375.081038 -398.351502)
				)
			)
		)
	)
	(zone
		(layers "F.Cu" "B.Cu" "In1.Cu" "In2.Cu" "In3.Cu" "In4.Cu" "In5.Cu" "In6.Cu"
			"In7.Cu" "In8.Cu" "In9.Cu" "In10.Cu" "In11.Cu" "In12.Cu" "In13.Cu" "In14.Cu"
			"In15.Cu" "In16.Cu"
		)
		(hatch none 0.5)
		(connect_pads
			(clearance 0)
		)
		(min_thickness 0.25)
		(keepout
			(tracks not_allowed)
			(vias allowed)
			(pads allowed)
			(copperpour not_allowed)
			(footprints allowed)
		)
		(placement
			(enabled no)
			(sheetname "")
		)
		(fill
			(thermal_gap 0.5)
			(thermal_bridge_width 0.5)
			(island_removal_mode 0)
		)
		(polygon
			(pts
				(arc
					(start 328.047604 -348.20479)
					(mid 327.666604 -348.58579)
					(end 328.047604 -348.96679)
				)
				(arc
					(start 328.911204 -348.96679)
					(mid 329.292204 -348.58579)
					(end 328.911204 -348.20479)
				)
			)
		)
	)
	(zone
		(layers "F.Cu" "B.Cu" "In1.Cu" "In2.Cu" "In3.Cu" "In4.Cu" "In5.Cu" "In6.Cu"
			"In7.Cu" "In8.Cu" "In9.Cu" "In10.Cu" "In11.Cu" "In12.Cu" "In13.Cu" "In14.Cu"
			"In15.Cu" "In16.Cu"
		)
		(hatch none 0.5)
		(connect_pads
			(clearance 0)
		)
		(min_thickness 0.25)
		(keepout
			(tracks not_allowed)
			(vias allowed)
			(pads allowed)
			(copperpour not_allowed)
			(footprints allowed)
		)
		(placement
			(enabled no)
			(sheetname "")
		)
		(fill
			(thermal_gap 0.5)
			(thermal_bridge_width 0.5)
			(island_removal_mode 0)
		)
		(polygon
			(pts
				(arc
					(start 315.917072 -121.365772)
					(mid 316.374272 -121.822972)
					(end 316.831472 -121.365772)
				)
				(arc
					(start 316.831472 -120.502172)
					(mid 316.374272 -120.044972)
					(end 315.917072 -120.502172)
				)
			)
		)
	)
	(zone
		(layers "F.Cu" "B.Cu" "In1.Cu" "In2.Cu" "In3.Cu" "In4.Cu" "In5.Cu" "In6.Cu"
			"In7.Cu" "In8.Cu" "In9.Cu" "In10.Cu" "In11.Cu" "In12.Cu" "In13.Cu" "In14.Cu"
			"In15.Cu" "In16.Cu"
		)
		(hatch none 0.5)
		(connect_pads
			(clearance 0)
		)
		(min_thickness 0.25)
		(keepout
			(tracks not_allowed)
			(vias allowed)
			(pads allowed)
			(copperpour not_allowed)
			(footprints allowed)
		)
		(placement
			(enabled no)
			(sheetname "")
		)
		(fill
			(thermal_gap 0.5)
			(thermal_bridge_width 0.5)
			(island_removal_mode 0)
		)
		(polygon
			(pts
				(arc
					(start 115.501166 -373.828818)
					(mid 115.516045 -373.792897)
					(end 115.551966 -373.778018)
				)
				(arc
					(start 116.268246 -373.778018)
					(mid 116.304167 -373.792897)
					(end 116.319046 -373.828818)
				)
				(arc
					(start 116.319046 -376.25147)
					(mid 116.304167 -376.287391)
					(end 116.268246 -376.30227)
				)
				(arc
					(start 115.551966 -376.30227)
					(mid 115.516045 -376.287391)
					(end 115.501166 -376.25147)
				)
			)
		)
	)
	(zone
		(layers "F.Cu" "B.Cu" "In1.Cu" "In2.Cu" "In3.Cu" "In4.Cu" "In5.Cu" "In6.Cu"
			"In7.Cu" "In8.Cu" "In9.Cu" "In10.Cu" "In11.Cu" "In12.Cu" "In13.Cu" "In14.Cu"
			"In15.Cu" "In16.Cu"
		)
		(hatch none 0.5)
		(connect_pads
			(clearance 0)
		)
		(min_thickness 0.25)
		(keepout
			(tracks not_allowed)
			(vias allowed)
			(pads allowed)
			(copperpour not_allowed)
			(footprints allowed)
		)
		(placement
			(enabled no)
			(sheetname "")
		)
		(fill
			(thermal_gap 0.5)
			(thermal_bridge_width 0.5)
			(island_removal_mode 0)
		)
		(polygon
			(pts
				(arc
					(start 414.90011 -147.087336)
					(mid 415.35731 -147.544536)
					(end 415.81451 -147.087336)
				)
				(arc
					(start 415.81451 -146.223736)
					(mid 415.35731 -145.766536)
					(end 414.90011 -146.223736)
				)
			)
		)
	)
	(zone
		(layers "F.Cu" "B.Cu" "In1.Cu" "In2.Cu" "In3.Cu" "In4.Cu" "In5.Cu" "In6.Cu"
			"In7.Cu" "In8.Cu" "In9.Cu" "In10.Cu" "In11.Cu" "In12.Cu" "In13.Cu" "In14.Cu"
			"In15.Cu" "In16.Cu"
		)
		(hatch none 0.5)
		(connect_pads
			(clearance 0)
		)
		(min_thickness 0.25)
		(keepout
			(tracks not_allowed)
			(vias allowed)
			(pads allowed)
			(copperpour not_allowed)
			(footprints allowed)
		)
		(placement
			(enabled no)
			(sheetname "")
		)
		(fill
			(thermal_gap 0.5)
			(thermal_bridge_width 0.5)
			(island_removal_mode 0)
		)
		(polygon
			(pts
				(arc
					(start 432.01717 -156.085794)
					(mid 432.47437 -156.542994)
					(end 432.93157 -156.085794)
				)
				(arc
					(start 432.93157 -155.222194)
					(mid 432.47437 -154.764994)
					(end 432.01717 -155.222194)
				)
			)
		)
	)
	(zone
		(layers "F.Cu" "B.Cu" "In1.Cu" "In2.Cu" "In3.Cu" "In4.Cu" "In5.Cu" "In6.Cu"
			"In7.Cu" "In8.Cu" "In9.Cu" "In10.Cu" "In11.Cu" "In12.Cu" "In13.Cu" "In14.Cu"
			"In15.Cu" "In16.Cu"
		)
		(hatch none 0.5)
		(connect_pads
			(clearance 0)
		)
		(min_thickness 0.25)
		(keepout
			(tracks not_allowed)
			(vias allowed)
			(pads allowed)
			(copperpour not_allowed)
			(footprints allowed)
		)
		(placement
			(enabled no)
			(sheetname "")
		)
		(fill
			(thermal_gap 0.5)
			(thermal_bridge_width 0.5)
			(island_removal_mode 0)
		)
		(polygon
			(pts
				(arc
					(start 115.501166 -369.928902)
					(mid 115.516045 -369.892981)
					(end 115.551966 -369.878102)
				)
				(arc
					(start 116.268246 -369.878102)
					(mid 116.304167 -369.892981)
					(end 116.319046 -369.928902)
				)
				(arc
					(start 116.319046 -372.351554)
					(mid 116.304167 -372.387475)
					(end 116.268246 -372.402354)
				)
				(arc
					(start 115.551966 -372.402354)
					(mid 115.516045 -372.387475)
					(end 115.501166 -372.351554)
				)
			)
		)
	)
	(zone
		(layers "F.Cu" "B.Cu" "In1.Cu" "In2.Cu" "In3.Cu" "In4.Cu" "In5.Cu" "In6.Cu"
			"In7.Cu" "In8.Cu" "In9.Cu" "In10.Cu" "In11.Cu" "In12.Cu" "In13.Cu" "In14.Cu"
			"In15.Cu" "In16.Cu"
		)
		(hatch none 0.5)
		(connect_pads
			(clearance 0)
		)
		(min_thickness 0.25)
		(keepout
			(tracks not_allowed)
			(vias allowed)
			(pads allowed)
			(copperpour not_allowed)
			(footprints allowed)
		)
		(placement
			(enabled no)
			(sheetname "")
		)
		(fill
			(thermal_gap 0.5)
			(thermal_bridge_width 0.5)
			(island_removal_mode 0)
		)
		(polygon
			(pts
				(arc
					(start 170.654218 -130.43281)
					(mid 170.197018 -129.97561)
					(end 169.739818 -130.43281)
				)
				(arc
					(start 169.739818 -131.29641)
					(mid 170.197018 -131.75361)
					(end 170.654218 -131.29641)
				)
			)
		)
	)
	(zone
		(layers "F.Cu" "B.Cu" "In1.Cu" "In2.Cu" "In3.Cu" "In4.Cu" "In5.Cu" "In6.Cu"
			"In7.Cu" "In8.Cu" "In9.Cu" "In10.Cu" "In11.Cu" "In12.Cu" "In13.Cu" "In14.Cu"
			"In15.Cu" "In16.Cu"
		)
		(hatch none 0.5)
		(connect_pads
			(clearance 0)
		)
		(min_thickness 0.25)
		(keepout
			(tracks not_allowed)
			(vias allowed)
			(pads allowed)
			(copperpour not_allowed)
			(footprints allowed)
		)
		(placement
			(enabled no)
			(sheetname "")
		)
		(fill
			(thermal_gap 0.5)
			(thermal_bridge_width 0.5)
			(island_removal_mode 0)
		)
		(polygon
			(pts
				(arc
					(start 153.410666 -125.494542)
					(mid 153.867866 -125.951742)
					(end 154.325066 -125.494542)
				)
				(arc
					(start 154.325066 -124.630942)
					(mid 153.867866 -124.173742)
					(end 153.410666 -124.630942)
				)
			)
		)
	)
	(zone
		(layers "F.Cu" "B.Cu" "In1.Cu" "In2.Cu" "In3.Cu" "In4.Cu" "In5.Cu" "In6.Cu"
			"In7.Cu" "In8.Cu" "In9.Cu" "In10.Cu" "In11.Cu" "In12.Cu" "In13.Cu" "In14.Cu"
			"In15.Cu" "In16.Cu"
		)
		(hatch none 0.5)
		(connect_pads
			(clearance 0)
		)
		(min_thickness 0.25)
		(keepout
			(tracks not_allowed)
			(vias allowed)
			(pads allowed)
			(copperpour not_allowed)
			(footprints allowed)
		)
		(placement
			(enabled no)
			(sheetname "")
		)
		(fill
			(thermal_gap 0.5)
			(thermal_bridge_width 0.5)
			(island_removal_mode 0)
		)
		(polygon
			(pts
				(arc
					(start 44.204128 -354.351082)
					(mid 43.823128 -354.732082)
					(end 44.204128 -355.113082)
				)
				(arc
					(start 45.067728 -355.113082)
					(mid 45.448728 -354.732082)
					(end 45.067728 -354.351082)
				)
			)
		)
	)
	(zone
		(layers "F.Cu" "B.Cu" "In1.Cu" "In2.Cu" "In3.Cu" "In4.Cu" "In5.Cu" "In6.Cu"
			"In7.Cu" "In8.Cu" "In9.Cu" "In10.Cu" "In11.Cu" "In12.Cu" "In13.Cu" "In14.Cu"
			"In15.Cu" "In16.Cu"
		)
		(name "Package Keepin")
		(hatch none 0.5)
		(connect_pads
			(clearance 0)
		)
		(min_thickness 0.25)
		(keepout
			(tracks allowed)
			(vias allowed)
			(pads allowed)
			(copperpour allowed)
			(footprints allowed)
		)
		(placement
			(enabled no)
			(sheetname "")
		)
		(fill
			(thermal_gap 0.5)
			(thermal_bridge_width 0.5)
			(island_removal_mode 0)
		)
		(polygon
			(pts
				(arc
					(start 465.600034 -417.573968)
					(mid 466.295824 -417.285762)
					(end 466.58403 -416.589972)
				)
				(arc
					(start 466.58403 -246.488204)
					(mid 466.509045 -246.111699)
					(end 466.29574 -245.792498)
				)
				(arc
					(start 463.667602 -243.16436)
					(mid 463.013616 -242.185835)
					(end 462.783936 -241.031522)
				)
				(arc
					(start 462.783936 -87.588344)
					(mid 463.013647 -86.434157)
					(end 463.667602 -85.45576)
				)
				(arc
					(start 466.295994 -82.827368)
					(mid 466.509189 -82.50816)
					(end 466.58403 -82.131662)
				)
				(arc
					(start 466.58403 -1.999996)
					(mid 466.295824 -1.304206)
					(end 465.600034 -1.016)
				)
				(arc
					(start 446.265046 -1.016)
					(mid 445.569256 -1.304206)
					(end 445.28105 -1.999996)
				)
				(arc
					(start 445.28105 -11.850116)
					(mid 444.690578 -13.275642)
					(end 443.265052 -13.866114)
				)
				(arc
					(start 435.265068 -13.866114)
					(mid 433.839542 -13.275642)
					(end 433.24907 -11.850116)
				)
				(arc
					(start 433.24907 -1.999996)
					(mid 432.960864 -1.304206)
					(end 432.265074 -1.016)
				)
				(arc
					(start 420.265098 -1.016)
					(mid 419.569308 -1.304206)
					(end 419.281102 -1.999996)
				)
				(arc
					(start 419.281102 -11.850116)
					(mid 418.69063 -13.275642)
					(end 417.265104 -13.866114)
				)
				(arc
					(start 409.26512 -13.866114)
					(mid 407.839594 -13.275642)
					(end 407.249122 -11.850116)
				)
				(arc
					(start 407.249122 -1.999996)
					(mid 406.960916 -1.304206)
					(end 406.265126 -1.016)
				)
				(arc
					(start 394.264896 -1.016)
					(mid 393.569106 -1.304206)
					(end 393.2809 -1.999996)
				)
				(arc
					(start 393.2809 -11.850116)
					(mid 392.690428 -13.275642)
					(end 391.264902 -13.866114)
				)
				(arc
					(start 383.264918 -13.866114)
					(mid 381.839392 -13.275642)
					(end 381.24892 -11.850116)
				)
				(arc
					(start 381.24892 -1.999996)
					(mid 380.960714 -1.304206)
					(end 380.264924 -1.016)
				)
				(arc
					(start 368.264948 -1.016)
					(mid 367.569158 -1.304206)
					(end 367.280952 -1.999996)
				)
				(arc
					(start 367.280952 -11.850116)
					(mid 366.69048 -13.275642)
					(end 365.264954 -13.866114)
				)
				(arc
					(start 357.26497 -13.866114)
					(mid 355.839444 -13.275642)
					(end 355.248972 -11.850116)
				)
				(arc
					(start 355.248972 -1.999996)
					(mid 354.960766 -1.304206)
					(end 354.264976 -1.016)
				)
				(arc
					(start 330.164948 -1.016)
					(mid 329.469158 -1.304206)
					(end 329.180952 -1.999996)
				)
				(arc
					(start 329.180952 -11.850116)
					(mid 328.59048 -13.275642)
					(end 327.164954 -13.866114)
				)
				(arc
					(start 319.16497 -13.866114)
					(mid 317.739444 -13.275642)
					(end 317.148972 -11.850116)
				)
				(arc
					(start 317.148972 -1.999996)
					(mid 316.860766 -1.304206)
					(end 316.164976 -1.016)
				)
				(arc
					(start 304.165 -1.016)
					(mid 303.46921 -1.304206)
					(end 303.181004 -1.999996)
				)
				(arc
					(start 303.181004 -11.850116)
					(mid 302.590532 -13.275642)
					(end 301.165006 -13.866114)
				)
				(arc
					(start 293.165022 -13.866114)
					(mid 291.739496 -13.275642)
					(end 291.149024 -11.850116)
				)
				(arc
					(start 291.149024 -1.999996)
					(mid 290.860818 -1.304206)
					(end 290.165028 -1.016)
				)
				(arc
					(start 278.165052 -1.016)
					(mid 277.469262 -1.304206)
					(end 277.181056 -1.999996)
				)
				(arc
					(start 277.181056 -11.850116)
					(mid 276.590584 -13.275642)
					(end 275.165058 -13.866114)
				)
				(arc
					(start 267.165074 -13.866114)
					(mid 265.739548 -13.275642)
					(end 265.149076 -11.850116)
				)
				(arc
					(start 265.149076 -1.999996)
					(mid 264.86087 -1.304206)
					(end 264.16508 -1.016)
				)
				(arc
					(start 252.165104 -1.016)
					(mid 251.469314 -1.304206)
					(end 251.181108 -1.999996)
				)
				(arc
					(start 251.181108 -11.850116)
					(mid 250.590636 -13.275642)
					(end 249.16511 -13.866114)
				)
				(arc
					(start 241.164872 -13.866114)
					(mid 239.73951 -13.275552)
					(end 239.148874 -11.850116)
				)
				(arc
					(start 239.148874 -1.999996)
					(mid 238.860668 -1.304206)
					(end 238.164878 -1.016)
				)
				(arc
					(start 214.065104 -1.016)
					(mid 213.369314 -1.304206)
					(end 213.081108 -1.999996)
				)
				(arc
					(start 213.081108 -11.850116)
					(mid 212.490636 -13.275642)
					(end 211.06511 -13.866114)
				)
				(arc
					(start 203.064872 -13.866114)
					(mid 201.63951 -13.275552)
					(end 201.048874 -11.850116)
				)
				(arc
					(start 201.048874 -1.999996)
					(mid 200.760668 -1.304206)
					(end 200.064878 -1.016)
				)
				(arc
					(start 188.064902 -1.016)
					(mid 187.369112 -1.304206)
					(end 187.080906 -1.999996)
				)
				(arc
					(start 187.080906 -11.850116)
					(mid 186.490434 -13.275642)
					(end 185.064908 -13.866114)
				)
				(arc
					(start 177.064924 -13.866114)
					(mid 175.639398 -13.275642)
					(end 175.048926 -11.850116)
				)
				(arc
					(start 175.048926 -1.999996)
					(mid 174.76072 -1.304206)
					(end 174.06493 -1.016)
				)
				(arc
					(start 162.064954 -1.016)
					(mid 161.369164 -1.304206)
					(end 161.080958 -1.999996)
				)
				(arc
					(start 161.080958 -11.850116)
					(mid 160.490486 -13.275642)
					(end 159.06496 -13.866114)
				)
				(arc
					(start 151.064976 -13.866114)
					(mid 149.63945 -13.275642)
					(end 149.048978 -11.850116)
				)
				(arc
					(start 149.048978 -1.999996)
					(mid 148.760772 -1.304206)
					(end 148.064982 -1.016)
				)
				(arc
					(start 136.065006 -1.016)
					(mid 135.369216 -1.304206)
					(end 135.08101 -1.999996)
				)
				(arc
					(start 135.08101 -11.850116)
					(mid 134.490538 -13.275642)
					(end 133.065012 -13.866114)
				)
				(arc
					(start 125.065028 -13.866114)
					(mid 123.639502 -13.275642)
					(end 123.04903 -11.850116)
				)
				(arc
					(start 123.04903 -1.999996)
					(mid 122.760824 -1.304206)
					(end 122.065034 -1.016)
				)
				(arc
					(start 97.965006 -1.016)
					(mid 97.269216 -1.304206)
					(end 96.98101 -1.999996)
				)
				(arc
					(start 96.98101 -11.850116)
					(mid 96.390538 -13.275642)
					(end 94.965012 -13.866114)
				)
				(arc
					(start 86.965028 -13.866114)
					(mid 85.539502 -13.275642)
					(end 84.94903 -11.850116)
				)
				(arc
					(start 84.94903 -1.999996)
					(mid 84.660824 -1.304206)
					(end 83.965034 -1.016)
				)
				(arc
					(start 71.965058 -1.016)
					(mid 71.269268 -1.304206)
					(end 70.981062 -1.999996)
				)
				(arc
					(start 70.981062 -11.850116)
					(mid 70.39059 -13.275642)
					(end 68.965064 -13.866114)
				)
				(arc
					(start 60.96508 -13.866114)
					(mid 59.539554 -13.275642)
					(end 58.949082 -11.850116)
				)
				(arc
					(start 58.949082 -1.999996)
					(mid 58.660876 -1.304206)
					(end 57.965086 -1.016)
				)
				(arc
					(start 45.96511 -1.016)
					(mid 45.26932 -1.304206)
					(end 44.981114 -1.999996)
				)
				(arc
					(start 44.981114 -11.850116)
					(mid 44.390642 -13.275642)
					(end 42.965116 -13.866114)
				)
				(arc
					(start 34.964878 -13.866114)
					(mid 33.539352 -13.275642)
					(end 32.94888 -11.850116)
				)
				(arc
					(start 32.94888 -1.999996)
					(mid 32.660674 -1.304206)
					(end 31.964884 -1.016)
				)
				(arc
					(start 19.964908 -1.016)
					(mid 19.269118 -1.304206)
					(end 18.980912 -1.999996)
				)
				(arc
					(start 18.980912 -11.850116)
					(mid 18.39044 -13.275642)
					(end 16.964914 -13.866114)
				)
				(arc
					(start 8.96493 -13.866114)
					(mid 7.539404 -13.275642)
					(end 6.948932 -11.850116)
				)
				(arc
					(start 6.948932 -1.999996)
					(mid 6.660726 -1.304206)
					(end 5.964936 -1.016)
				)
				(xy 4.721098 -1.016) (xy 4.036314 -0.331216) (xy 4.036314 1.62306) (xy 4.461256 2.048002) (xy 8.625332 2.048002)
				(xy 9.553956 1.119378) (xy 9.553956 -9.333484) (xy 11.222736 -11.002264) (xy 14.623034 -11.002264)
				(xy 15.787878 -9.83742) (xy 15.787878 0.26924) (xy 17.236186 1.717548) (xy 34.64687 1.717548) (xy 35.937698 0.42672)
				(xy 35.937698 -9.396476) (xy 37.291518 -10.750296) (xy 41.164002 -10.750296) (xy 41.85666 -10.057638)
				(xy 41.85666 0.268986) (xy 43.52544 1.937766) (xy 60.432696 1.937766) (xy 62.038484 0.331978) (xy 62.038484 -9.806178)
				(xy 62.982856 -10.75055) (xy 66.666364 -10.75055) (xy 67.862958 -9.553956) (xy 67.862958 0.26924)
				(xy 69.625972 2.032254) (xy 86.627462 2.032254) (xy 87.949786 0.70993) (xy 87.949786 -9.742678)
				(xy 88.831674 -10.624566) (xy 92.955872 -10.624566) (xy 93.96349 -9.616948) (xy 93.96349 0.363728)
				(xy 95.60052 2.000758) (xy 124.786644 2.000758) (xy 126.045976 0.741426) (xy 126.045976 -10.026396)
				(xy 126.864364 -10.844784) (xy 130.95732 -10.844784) (xy 132.18541 -9.616694) (xy 132.18541 0.74168)
				(xy 133.129782 1.686052) (xy 151.13889 1.686052) (xy 151.894794 0.930148) (xy 151.894794 -9.55421)
				(xy 153.342848 -11.002264) (xy 156.333952 -11.002264) (xy 158.159958 -9.176258) (xy 158.159958 0.23749)
				(xy 159.797242 1.874774) (xy 176.704244 1.874774) (xy 178.026568 0.55245) (xy 178.026568 -9.679686)
				(xy 179.065682 -10.7188) (xy 182.528972 -10.7188) (xy 184.166002 -9.08177) (xy 184.166002 0.520954)
				(xy 185.519822 1.874774) (xy 202.615546 1.874774) (xy 204.126846 0.363474) (xy 204.126846 -9.49071)
				(xy 205.48092 -10.844784) (xy 208.692242 -10.844784) (xy 210.109054 -9.427972) (xy 210.109054 0.55245)
				(xy 211.840826 2.284222) (xy 240.52276 2.284222) (xy 242.254532 0.55245) (xy 242.254532 -10.12063)
				(xy 242.884198 -10.750296) (xy 246.819674 -10.750296) (xy 248.173494 -9.396476) (xy 248.173494 0.520954)
				(xy 249.338338 1.685798) (xy 266.655042 1.685798) (xy 268.008608 0.332232) (xy 268.008608 -9.67994)
				(xy 269.015972 -10.687304) (xy 272.983198 -10.687304) (xy 274.08505 -9.585452) (xy 274.08505 0.583692)
				(xy 275.15566 1.654302) (xy 293.133272 1.654302) (xy 294.046148 0.741426) (xy 294.046148 -9.144762)
				(xy 295.809162 -10.907776) (xy 298.516802 -10.907776) (xy 300.154086 -9.270492) (xy 300.154086 0.237236)
				(xy 301.50816 1.59131) (xy 319.29705 1.59131) (xy 319.989454 0.898906) (xy 319.989454 -9.553956)
				(xy 321.185794 -10.750296) (xy 324.617588 -10.750296) (xy 324.68058 -10.813288) (xy 324.68058 -10.7188)
				(xy 326.097392 -9.301988) (xy 326.097392 0.112014) (xy 327.734422 1.749044) (xy 356.8573 1.749044)
				(xy 358.08539 0.520954) (xy 358.08539 -9.743186) (xy 359.155746 -10.813542) (xy 363.091222 -10.813542)
				(xy 364.130336 -9.774428) (xy 364.130336 0.395224) (xy 365.767366 2.032254) (xy 383.178558 2.032254)
				(xy 384.343402 0.86741) (xy 384.343402 -9.774428) (xy 385.19354 -10.624566) (xy 389.380984 -10.624566)
				(xy 390.042146 -9.963404) (xy 390.042146 -0.077216) (xy 392.057128 1.937766) (xy 408.901138 1.937766)
				(xy 410.00299 0.835914) (xy 410.00299 -9.490964) (xy 411.136338 -10.624312) (xy 415.41827 -10.624312)
				(xy 416.299904 -9.742678) (xy 416.299904 0.23749) (xy 418.031676 1.969262) (xy 434.84419 1.969262)
				(xy 436.19801 0.615442) (xy 436.19801 -9.585706) (xy 437.331358 -10.719054) (xy 440.85764 -10.719054)
				(xy 442.337444 -9.23925) (xy 442.337444 0.678434) (xy 443.691264 2.032254) (xy 466.391244 2.032254)
				(xy 467.272878 2.913888) (xy 467.272878 24.889968) (xy 465.85632 26.306526) (xy 159.902398 26.306526)
				(xy 158.368492 24.77262) (xy 158.368492 7.960614) (xy 156.816298 6.40842) (xy 152.776174 6.40842)
				(xy 16.826738 6.40842) (xy 15.69339 7.541768) (xy 15.69339 24.732234) (xy 14.245082 26.180542) (xy 1.336548 26.180542)
				(xy -0.048768 24.795226) (xy -0.048768 3.197098) (xy 1.336548 1.811782) (xy 3.477768 1.811782) (xy 3.871214 1.418336)
				(xy 3.871214 -0.65405) (xy 3.509264 -1.016)
				(arc
					(start 1.999996 -1.016)
					(mid 1.304206 -1.304206)
					(end 1.016 -1.999996)
				)
				(arc
					(start 1.016 -82.131662)
					(mid 1.0908 -82.508177)
					(end 1.304036 -82.827368)
				)
				(arc
					(start 3.932428 -85.45576)
					(mid 4.58639 -86.434154)
					(end 4.816094 -87.588344)
				)
				(arc
					(start 4.816094 -241.031522)
					(mid 4.586378 -242.18582)
					(end 3.932428 -243.16436)
				)
				(arc
					(start 1.30429 -245.792498)
					(mid 1.090929 -246.111676)
					(end 1.016 -246.488204)
				)
				(arc
					(start 1.016 -416.589972)
					(mid 1.304206 -417.285762)
					(end 1.999996 -417.573968)
				)
				(xy 6.815074 -417.573968) (xy 7.32663 -418.085524) (xy 7.32663 -420.046404) (xy 6.720586 -420.652448)
				(xy 1.557274 -420.652448) (xy -0.017272 -422.226994) (xy -0.017272 -461.038956) (xy 1.368298 -462.424526)
				(xy 466.220556 -462.424526) (xy 467.478872 -461.16621) (xy 467.478872 -422.125648) (xy 465.93506 -420.581836)
				(xy 447.201544 -420.581836) (xy 446.052702 -421.730678) (xy 446.052702 -429.680624) (xy 444.604394 -431.128932)
				(xy 370.647468 -431.128932) (xy 369.23091 -429.712374) (xy 369.23091 -421.841168) (xy 367.71961 -420.329868)
				(xy 359.565194 -420.329868) (xy 357.990902 -421.90416) (xy 357.990902 -429.712374) (xy 356.511352 -431.191924)
				(xy 282.774898 -431.191924) (xy 281.358086 -429.775112) (xy 281.358086 -422.030144) (xy 279.909778 -420.581836)
				(xy 276.572472 -420.581836) (xy 274.746212 -422.408096) (xy 274.746212 -431.349658) (xy 273.613118 -432.482752)
				(xy 201.450956 -432.482752) (xy 200.443338 -431.475134) (xy 200.443338 -422.155874) (xy 198.743316 -420.455852)
				(xy 187.345828 -420.455852) (xy 186.149488 -421.652192) (xy 186.149488 -429.71212) (xy 184.512204 -431.349404)
				(xy 111.153702 -431.349404) (xy 109.89437 -430.090072) (xy 109.89437 -422.281858) (xy 108.194348 -420.581836)
				(xy 99.441508 -420.581836) (xy 98.056192 -421.967152) (xy 98.056192 -429.901096) (xy 96.670876 -431.286412)
				(xy 23.375366 -431.286412) (xy 21.832824 -429.74387) (xy 21.832824 -422.313354) (xy 20.195794 -420.676324)
				(xy 8.090154 -420.676324) (xy 7.507478 -420.093648) (xy 7.507478 -418.038534) (xy 7.972044 -417.573968)
				(arc
					(start 200.481184 -417.573968)
					(mid 200.880036 -417.489508)
					(end 201.210418 -417.250626)
				)
				(arc
					(start 201.210418 -417.250626)
					(mid 202.222794 -416.518846)
					(end 203.444856 -416.260026)
				)
				(arc
					(start 271.794986 -416.260026)
					(mid 273.017058 -416.518822)
					(end 274.029424 -417.250626)
				)
				(arc
					(start 274.029424 -417.250626)
					(mid 274.359806 -417.489507)
					(end 274.758658 -417.573968)
				)
			)
		)
	)
	(zone
		(layers "F.Cu" "B.Cu" "In1.Cu" "In2.Cu" "In3.Cu" "In4.Cu" "In5.Cu" "In6.Cu"
			"In7.Cu" "In8.Cu" "In9.Cu" "In10.Cu" "In11.Cu" "In12.Cu" "In13.Cu" "In14.Cu"
			"In15.Cu" "In16.Cu"
		)
		(hatch none 0.5)
		(connect_pads
			(clearance 0)
		)
		(min_thickness 0.25)
		(keepout
			(tracks not_allowed)
			(vias allowed)
			(pads allowed)
			(copperpour not_allowed)
			(footprints allowed)
		)
		(placement
			(enabled no)
			(sheetname "")
		)
		(fill
			(thermal_gap 0.5)
			(thermal_bridge_width 0.5)
			(island_removal_mode 0)
		)
		(polygon
			(pts
				(arc
					(start 34.66846 -109.18444)
					(mid 35.12566 -109.64164)
					(end 35.58286 -109.18444)
				)
				(arc
					(start 35.58286 -108.32084)
					(mid 35.12566 -107.86364)
					(end 34.66846 -108.32084)
				)
			)
		)
	)
	(zone
		(layers "F.Cu" "B.Cu" "In1.Cu" "In2.Cu" "In3.Cu" "In4.Cu" "In5.Cu" "In6.Cu"
			"In7.Cu" "In8.Cu" "In9.Cu" "In10.Cu" "In11.Cu" "In12.Cu" "In13.Cu" "In14.Cu"
			"In15.Cu" "In16.Cu"
		)
		(hatch none 0.5)
		(connect_pads
			(clearance 0)
		)
		(min_thickness 0.25)
		(keepout
			(tracks not_allowed)
			(vias allowed)
			(pads allowed)
			(copperpour not_allowed)
			(footprints allowed)
		)
		(placement
			(enabled no)
			(sheetname "")
		)
		(fill
			(thermal_gap 0.5)
			(thermal_bridge_width 0.5)
			(island_removal_mode 0)
		)
		(polygon
			(pts
				(arc
					(start 375.081038 -407.628852)
					(mid 375.095917 -407.592931)
					(end 375.131838 -407.578052)
				)
				(arc
					(start 375.848118 -407.578052)
					(mid 375.884039 -407.592931)
					(end 375.898918 -407.628852)
				)
				(arc
					(start 375.898918 -410.051504)
					(mid 375.884039 -410.087425)
					(end 375.848118 -410.102304)
				)
				(arc
					(start 375.131838 -410.102304)
					(mid 375.095917 -410.087425)
					(end 375.081038 -410.051504)
				)
			)
		)
	)
	(zone
		(layers "F.Cu" "B.Cu" "In1.Cu" "In2.Cu" "In3.Cu" "In4.Cu" "In5.Cu" "In6.Cu"
			"In7.Cu" "In8.Cu" "In9.Cu" "In10.Cu" "In11.Cu" "In12.Cu" "In13.Cu" "In14.Cu"
			"In15.Cu" "In16.Cu"
		)
		(hatch none 0.5)
		(connect_pads
			(clearance 0)
		)
		(min_thickness 0.25)
		(keepout
			(tracks not_allowed)
			(vias allowed)
			(pads allowed)
			(copperpour not_allowed)
			(footprints allowed)
		)
		(placement
			(enabled no)
			(sheetname "")
		)
		(fill
			(thermal_gap 0.5)
			(thermal_bridge_width 0.5)
			(island_removal_mode 0)
		)
		(polygon
			(pts
				(arc
					(start 399.16862 -351.230438)
					(mid 398.78762 -351.611438)
					(end 399.16862 -351.992438)
				)
				(arc
					(start 400.03222 -351.992438)
					(mid 400.41322 -351.611438)
					(end 400.03222 -351.230438)
				)
			)
		)
	)
	(zone
		(layers "F.Cu" "B.Cu" "In1.Cu" "In2.Cu" "In3.Cu" "In4.Cu" "In5.Cu" "In6.Cu"
			"In7.Cu" "In8.Cu" "In9.Cu" "In10.Cu" "In11.Cu" "In12.Cu" "In13.Cu" "In14.Cu"
			"In15.Cu" "In16.Cu"
		)
		(hatch none 0.5)
		(connect_pads
			(clearance 0)
		)
		(min_thickness 0.25)
		(keepout
			(tracks not_allowed)
			(vias allowed)
			(pads allowed)
			(copperpour not_allowed)
			(footprints allowed)
		)
		(placement
			(enabled no)
			(sheetname "")
		)
		(fill
			(thermal_gap 0.5)
			(thermal_bridge_width 0.5)
			(island_removal_mode 0)
		)
		(polygon
			(pts
				(arc
					(start 401.494498 10.258044)
					(mid 401.875498 9.877044)
					(end 402.256498 10.258044)
				)
				(arc
					(start 402.256498 11.121644)
					(mid 401.875498 11.502644)
					(end 401.494498 11.121644)
				)
			)
		)
	)
	(zone
		(layers "F.Cu" "B.Cu" "In1.Cu" "In2.Cu" "In3.Cu" "In4.Cu" "In5.Cu" "In6.Cu"
			"In7.Cu" "In8.Cu" "In9.Cu" "In10.Cu" "In11.Cu" "In12.Cu" "In13.Cu" "In14.Cu"
			"In15.Cu" "In16.Cu"
		)
		(hatch none 0.5)
		(connect_pads
			(clearance 0)
		)
		(min_thickness 0.25)
		(keepout
			(tracks not_allowed)
			(vias allowed)
			(pads allowed)
			(copperpour not_allowed)
			(footprints allowed)
		)
		(placement
			(enabled no)
			(sheetname "")
		)
		(fill
			(thermal_gap 0.5)
			(thermal_bridge_width 0.5)
			(island_removal_mode 0)
		)
		(polygon
			(pts
				(arc
					(start 298.080938 -400.92884)
					(mid 298.095817 -400.892919)
					(end 298.131738 -400.87804)
				)
				(arc
					(start 298.848018 -400.87804)
					(mid 298.883939 -400.892919)
					(end 298.898818 -400.92884)
				)
				(arc
					(start 298.898818 -403.351492)
					(mid 298.883939 -403.387413)
					(end 298.848018 -403.402292)
				)
				(arc
					(start 298.131738 -403.402292)
					(mid 298.095817 -403.387413)
					(end 298.080938 -403.351492)
				)
			)
		)
	)
	(zone
		(layers "F.Cu" "B.Cu" "In1.Cu" "In2.Cu" "In3.Cu" "In4.Cu" "In5.Cu" "In6.Cu"
			"In7.Cu" "In8.Cu" "In9.Cu" "In10.Cu" "In11.Cu" "In12.Cu" "In13.Cu" "In14.Cu"
			"In15.Cu" "In16.Cu"
		)
		(hatch none 0.5)
		(connect_pads
			(clearance 0)
		)
		(min_thickness 0.25)
		(keepout
			(tracks not_allowed)
			(vias allowed)
			(pads allowed)
			(copperpour not_allowed)
			(footprints allowed)
		)
		(placement
			(enabled no)
			(sheetname "")
		)
		(fill
			(thermal_gap 0.5)
			(thermal_bridge_width 0.5)
			(island_removal_mode 0)
		)
		(polygon
			(pts
				(arc
					(start 385.624578 -299.555154)
					(mid 385.954778 -299.224954)
					(end 385.624578 -298.894754)
				)
				(arc
					(start 384.674618 -298.894754)
					(mid 384.344418 -299.224954)
					(end 384.674618 -299.555154)
				)
			)
		)
	)
	(zone
		(layers "F.Cu" "B.Cu" "In1.Cu" "In2.Cu" "In3.Cu" "In4.Cu" "In5.Cu" "In6.Cu"
			"In7.Cu" "In8.Cu" "In9.Cu" "In10.Cu" "In11.Cu" "In12.Cu" "In13.Cu" "In14.Cu"
			"In15.Cu" "In16.Cu"
		)
		(hatch none 0.5)
		(connect_pads
			(clearance 0)
		)
		(min_thickness 0.25)
		(keepout
			(tracks not_allowed)
			(vias allowed)
			(pads allowed)
			(copperpour not_allowed)
			(footprints allowed)
		)
		(placement
			(enabled no)
			(sheetname "")
		)
		(fill
			(thermal_gap 0.5)
			(thermal_bridge_width 0.5)
			(island_removal_mode 0)
		)
		(polygon
			(pts
				(arc
					(start 266.868402 -109.18444)
					(mid 267.325602 -109.64164)
					(end 267.782802 -109.18444)
				)
				(arc
					(start 267.782802 -108.32084)
					(mid 267.325602 -107.86364)
					(end 266.868402 -108.32084)
				)
			)
		)
	)
	(zone
		(layers "F.Cu" "B.Cu" "In1.Cu" "In2.Cu" "In3.Cu" "In4.Cu" "In5.Cu" "In6.Cu"
			"In7.Cu" "In8.Cu" "In9.Cu" "In10.Cu" "In11.Cu" "In12.Cu" "In13.Cu" "In14.Cu"
			"In15.Cu" "In16.Cu"
		)
		(hatch none 0.5)
		(connect_pads
			(clearance 0)
		)
		(min_thickness 0.25)
		(keepout
			(tracks not_allowed)
			(vias allowed)
			(pads allowed)
			(copperpour not_allowed)
			(footprints allowed)
		)
		(placement
			(enabled no)
			(sheetname "")
		)
		(fill
			(thermal_gap 0.5)
			(thermal_bridge_width 0.5)
			(island_removal_mode 0)
		)
		(polygon
			(pts
				(arc
					(start 300.280832 -377.728734)
					(mid 300.295711 -377.692813)
					(end 300.331632 -377.677934)
				)
				(arc
					(start 301.047912 -377.677934)
					(mid 301.083833 -377.692813)
					(end 301.098712 -377.728734)
				)
				(arc
					(start 301.098712 -380.151386)
					(mid 301.083833 -380.187307)
					(end 301.047912 -380.202186)
				)
				(arc
					(start 300.331632 -380.202186)
					(mid 300.295711 -380.187307)
					(end 300.280832 -380.151386)
				)
			)
		)
	)
	(zone
		(layers "F.Cu" "B.Cu" "In1.Cu" "In2.Cu" "In3.Cu" "In4.Cu" "In5.Cu" "In6.Cu"
			"In7.Cu" "In8.Cu" "In9.Cu" "In10.Cu" "In11.Cu" "In12.Cu" "In13.Cu" "In14.Cu"
			"In15.Cu" "In16.Cu"
		)
		(hatch none 0.5)
		(connect_pads
			(clearance 0)
		)
		(min_thickness 0.25)
		(keepout
			(tracks not_allowed)
			(vias allowed)
			(pads allowed)
			(copperpour not_allowed)
			(footprints allowed)
		)
		(placement
			(enabled no)
			(sheetname "")
		)
		(fill
			(thermal_gap 0.5)
			(thermal_bridge_width 0.5)
			(island_removal_mode 0)
		)
		(polygon
			(pts
				(arc
					(start 375.081038 -381.628904)
					(mid 375.095917 -381.592983)
					(end 375.131838 -381.578104)
				)
				(arc
					(start 375.848118 -381.578104)
					(mid 375.884039 -381.592983)
					(end 375.898918 -381.628904)
				)
				(arc
					(start 375.898918 -384.051556)
					(mid 375.884039 -384.087477)
					(end 375.848118 -384.102356)
				)
				(arc
					(start 375.131838 -384.102356)
					(mid 375.095917 -384.087477)
					(end 375.081038 -384.051556)
				)
			)
		)
	)
	(zone
		(layers "F.Cu" "B.Cu" "In1.Cu" "In2.Cu" "In3.Cu" "In4.Cu" "In5.Cu" "In6.Cu"
			"In7.Cu" "In8.Cu" "In9.Cu" "In10.Cu" "In11.Cu" "In12.Cu" "In13.Cu" "In14.Cu"
			"In15.Cu" "In16.Cu"
		)
		(hatch none 0.5)
		(connect_pads
			(clearance 0)
		)
		(min_thickness 0.25)
		(keepout
			(tracks not_allowed)
			(vias allowed)
			(pads allowed)
			(copperpour not_allowed)
			(footprints allowed)
		)
		(placement
			(enabled no)
			(sheetname "")
		)
		(fill
			(thermal_gap 0.5)
			(thermal_bridge_width 0.5)
			(island_removal_mode 0)
		)
		(polygon
			(pts
				(arc
					(start 415.513012 -345.084146)
					(mid 415.132012 -345.465146)
					(end 415.513012 -345.846146)
				)
				(arc
					(start 416.376612 -345.846146)
					(mid 416.757612 -345.465146)
					(end 416.376612 -345.084146)
				)
			)
		)
	)
	(zone
		(layers "F.Cu" "B.Cu" "In1.Cu" "In2.Cu" "In3.Cu" "In4.Cu" "In5.Cu" "In6.Cu"
			"In7.Cu" "In8.Cu" "In9.Cu" "In10.Cu" "In11.Cu" "In12.Cu" "In13.Cu" "In14.Cu"
			"In15.Cu" "In16.Cu"
		)
		(hatch none 0.5)
		(connect_pads
			(clearance 0)
		)
		(min_thickness 0.25)
		(keepout
			(tracks not_allowed)
			(vias allowed)
			(pads allowed)
			(copperpour not_allowed)
			(footprints allowed)
		)
		(placement
			(enabled no)
			(sheetname "")
		)
		(fill
			(thermal_gap 0.5)
			(thermal_bridge_width 0.5)
			(island_removal_mode 0)
		)
		(polygon
			(pts
				(arc
					(start 89.352882 -357.37673)
					(mid 88.971882 -357.75773)
					(end 89.352882 -358.13873)
				)
				(arc
					(start 90.216482 -358.13873)
					(mid 90.597482 -357.75773)
					(end 90.216482 -357.37673)
				)
			)
		)
	)
	(zone
		(layers "F.Cu" "B.Cu" "In1.Cu" "In2.Cu" "In3.Cu" "In4.Cu" "In5.Cu" "In6.Cu"
			"In7.Cu" "In8.Cu" "In9.Cu" "In10.Cu" "In11.Cu" "In12.Cu" "In13.Cu" "In14.Cu"
			"In15.Cu" "In16.Cu"
		)
		(hatch none 0.5)
		(connect_pads
			(clearance 0)
		)
		(min_thickness 0.25)
		(keepout
			(tracks not_allowed)
			(vias allowed)
			(pads allowed)
			(copperpour not_allowed)
			(footprints allowed)
		)
		(placement
			(enabled no)
			(sheetname "")
		)
		(fill
			(thermal_gap 0.5)
			(thermal_bridge_width 0.5)
			(island_removal_mode 0)
		)
		(polygon
			(pts
				(arc
					(start 293.680896 -397.028924)
					(mid 293.695775 -396.993003)
					(end 293.731696 -396.978124)
				)
				(arc
					(start 294.447976 -396.978124)
					(mid 294.483897 -396.993003)
					(end 294.498776 -397.028924)
				)
				(arc
					(start 294.498776 -399.451576)
					(mid 294.483897 -399.487497)
					(end 294.447976 -399.502376)
				)
				(arc
					(start 293.731696 -399.502376)
					(mid 293.695775 -399.487497)
					(end 293.680896 -399.451576)
				)
			)
		)
	)
	(zone
		(layers "F.Cu" "B.Cu" "In1.Cu" "In2.Cu" "In3.Cu" "In4.Cu" "In5.Cu" "In6.Cu"
			"In7.Cu" "In8.Cu" "In9.Cu" "In10.Cu" "In11.Cu" "In12.Cu" "In13.Cu" "In14.Cu"
			"In15.Cu" "In16.Cu"
		)
		(hatch none 0.5)
		(connect_pads
			(clearance 0)
		)
		(min_thickness 0.25)
		(keepout
			(tracks not_allowed)
			(vias allowed)
			(pads allowed)
			(copperpour not_allowed)
			(footprints allowed)
		)
		(placement
			(enabled no)
			(sheetname "")
		)
		(fill
			(thermal_gap 0.5)
			(thermal_bridge_width 0.5)
			(island_removal_mode 0)
		)
		(polygon
			(pts
				(arc
					(start 118.080028 -345.084146)
					(mid 117.699028 -345.465146)
					(end 118.080028 -345.846146)
				)
				(arc
					(start 118.943628 -345.846146)
					(mid 119.324628 -345.465146)
					(end 118.943628 -345.084146)
				)
			)
		)
	)
	(zone
		(layers "F.Cu" "B.Cu" "In1.Cu" "In2.Cu" "In3.Cu" "In4.Cu" "In5.Cu" "In6.Cu"
			"In7.Cu" "In8.Cu" "In9.Cu" "In10.Cu" "In11.Cu" "In12.Cu" "In13.Cu" "In14.Cu"
			"In15.Cu" "In16.Cu"
		)
		(hatch none 0.5)
		(connect_pads
			(clearance 0)
		)
		(min_thickness 0.25)
		(keepout
			(tracks not_allowed)
			(vias allowed)
			(pads allowed)
			(copperpour not_allowed)
			(footprints allowed)
		)
		(placement
			(enabled no)
			(sheetname "")
		)
		(fill
			(thermal_gap 0.5)
			(thermal_bridge_width 0.5)
			(island_removal_mode 0)
		)
		(polygon
			(pts
				(arc
					(start 425.680886 -400.92884)
					(mid 425.695765 -400.892919)
					(end 425.731686 -400.87804)
				)
				(arc
					(start 426.447966 -400.87804)
					(mid 426.483887 -400.892919)
					(end 426.498766 -400.92884)
				)
				(arc
					(start 426.498766 -403.351492)
					(mid 426.483887 -403.387413)
					(end 426.447966 -403.402292)
				)
				(arc
					(start 425.731686 -403.402292)
					(mid 425.695765 -403.387413)
					(end 425.680886 -403.351492)
				)
			)
		)
	)
	(zone
		(layers "F.Cu" "B.Cu" "In1.Cu" "In2.Cu" "In3.Cu" "In4.Cu" "In5.Cu" "In6.Cu"
			"In7.Cu" "In8.Cu" "In9.Cu" "In10.Cu" "In11.Cu" "In12.Cu" "In13.Cu" "In14.Cu"
			"In15.Cu" "In16.Cu"
		)
		(hatch none 0.5)
		(connect_pads
			(clearance 0)
		)
		(min_thickness 0.25)
		(keepout
			(tracks not_allowed)
			(vias allowed)
			(pads allowed)
			(copperpour not_allowed)
			(footprints allowed)
		)
		(placement
			(enabled no)
			(sheetname "")
		)
		(fill
			(thermal_gap 0.5)
			(thermal_bridge_width 0.5)
			(island_removal_mode 0)
		)
		(polygon
			(pts
				(arc
					(start 414.90011 -119.567198)
					(mid 415.35731 -120.024398)
					(end 415.81451 -119.567198)
				)
				(arc
					(start 415.81451 -118.703598)
					(mid 415.35731 -118.246398)
					(end 414.90011 -118.703598)
				)
			)
		)
	)
	(zone
		(layers "F.Cu" "B.Cu" "In1.Cu" "In2.Cu" "In3.Cu" "In4.Cu" "In5.Cu" "In6.Cu"
			"In7.Cu" "In8.Cu" "In9.Cu" "In10.Cu" "In11.Cu" "In12.Cu" "In13.Cu" "In14.Cu"
			"In15.Cu" "In16.Cu"
		)
		(hatch none 0.5)
		(connect_pads
			(clearance 0)
		)
		(min_thickness 0.25)
		(keepout
			(tracks not_allowed)
			(vias allowed)
			(pads allowed)
			(copperpour not_allowed)
			(footprints allowed)
		)
		(placement
			(enabled no)
			(sheetname "")
		)
		(fill
			(thermal_gap 0.5)
			(thermal_bridge_width 0.5)
			(island_removal_mode 0)
		)
		(polygon
			(pts
				(arc
					(start 133.624828 -345.084146)
					(mid 133.243828 -345.465146)
					(end 133.624828 -345.846146)
				)
				(arc
					(start 134.488428 -345.846146)
					(mid 134.869428 -345.465146)
					(end 134.488428 -345.084146)
				)
			)
		)
	)
	(zone
		(layers "F.Cu" "B.Cu" "In1.Cu" "In2.Cu" "In3.Cu" "In4.Cu" "In5.Cu" "In6.Cu"
			"In7.Cu" "In8.Cu" "In9.Cu" "In10.Cu" "In11.Cu" "In12.Cu" "In13.Cu" "In14.Cu"
			"In15.Cu" "In16.Cu"
		)
		(hatch none 0.5)
		(connect_pads
			(clearance 0)
		)
		(min_thickness 0.25)
		(keepout
			(tracks not_allowed)
			(vias allowed)
			(pads allowed)
			(copperpour not_allowed)
			(footprints allowed)
		)
		(placement
			(enabled no)
			(sheetname "")
		)
		(fill
			(thermal_gap 0.5)
			(thermal_bridge_width 0.5)
			(island_removal_mode 0)
		)
		(polygon
			(pts
				(arc
					(start 156.275024 -299.555154)
					(mid 156.605224 -299.224954)
					(end 156.275024 -298.894754)
				)
				(arc
					(start 155.325064 -298.894754)
					(mid 154.994864 -299.224954)
					(end 155.325064 -299.555154)
				)
			)
		)
	)
	(zone
		(layers "F.Cu" "B.Cu" "In1.Cu" "In2.Cu" "In3.Cu" "In4.Cu" "In5.Cu" "In6.Cu"
			"In7.Cu" "In8.Cu" "In9.Cu" "In10.Cu" "In11.Cu" "In12.Cu" "In13.Cu" "In14.Cu"
			"In15.Cu" "In16.Cu"
		)
		(hatch none 0.5)
		(connect_pads
			(clearance 0)
		)
		(min_thickness 0.25)
		(keepout
			(tracks not_allowed)
			(vias allowed)
			(pads allowed)
			(copperpour not_allowed)
			(footprints allowed)
		)
		(placement
			(enabled no)
			(sheetname "")
		)
		(fill
			(thermal_gap 0.5)
			(thermal_bridge_width 0.5)
			(island_removal_mode 0)
		)
		(polygon
			(pts
				(arc
					(start 180.839872 -351.230438)
					(mid 180.458872 -351.611438)
					(end 180.839872 -351.992438)
				)
				(arc
					(start 181.703472 -351.992438)
					(mid 182.084472 -351.611438)
					(end 181.703472 -351.230438)
				)
			)
		)
	)
	(zone
		(layers "F.Cu" "B.Cu" "In1.Cu" "In2.Cu" "In3.Cu" "In4.Cu" "In5.Cu" "In6.Cu"
			"In7.Cu" "In8.Cu" "In9.Cu" "In10.Cu" "In11.Cu" "In12.Cu" "In13.Cu" "In14.Cu"
			"In15.Cu" "In16.Cu"
		)
		(hatch none 0.5)
		(connect_pads
			(clearance 0)
		)
		(min_thickness 0.25)
		(keepout
			(tracks not_allowed)
			(vias allowed)
			(pads allowed)
			(copperpour not_allowed)
			(footprints allowed)
		)
		(placement
			(enabled no)
			(sheetname "")
		)
		(fill
			(thermal_gap 0.5)
			(thermal_bridge_width 0.5)
			(island_removal_mode 0)
		)
		(polygon
			(pts
				(arc
					(start 34.877248 -357.37673)
					(mid 34.496248 -357.75773)
					(end 34.877248 -358.13873)
				)
				(arc
					(start 35.740848 -358.13873)
					(mid 36.121848 -357.75773)
					(end 35.740848 -357.37673)
				)
			)
		)
	)
	(zone
		(layers "F.Cu" "B.Cu" "In1.Cu" "In2.Cu" "In3.Cu" "In4.Cu" "In5.Cu" "In6.Cu"
			"In7.Cu" "In8.Cu" "In9.Cu" "In10.Cu" "In11.Cu" "In12.Cu" "In13.Cu" "In14.Cu"
			"In15.Cu" "In16.Cu"
		)
		(hatch none 0.5)
		(connect_pads
			(clearance 0)
		)
		(min_thickness 0.25)
		(keepout
			(tracks not_allowed)
			(vias allowed)
			(pads allowed)
			(copperpour not_allowed)
			(footprints allowed)
		)
		(placement
			(enabled no)
			(sheetname "")
		)
		(fill
			(thermal_gap 0.5)
			(thermal_bridge_width 0.5)
			(island_removal_mode 0)
		)
		(polygon
			(pts
				(arc
					(start 430.080928 -382.728724)
					(mid 430.095807 -382.692803)
					(end 430.131728 -382.677924)
				)
				(arc
					(start 430.848008 -382.677924)
					(mid 430.883929 -382.692803)
					(end 430.898808 -382.728724)
				)
				(arc
					(start 430.898808 -385.151376)
					(mid 430.883929 -385.187297)
					(end 430.848008 -385.202176)
				)
				(arc
					(start 430.131728 -385.202176)
					(mid 430.095807 -385.187297)
					(end 430.080928 -385.151376)
				)
			)
		)
	)
	(zone
		(layers "F.Cu" "B.Cu" "In1.Cu" "In2.Cu" "In3.Cu" "In4.Cu" "In5.Cu" "In6.Cu"
			"In7.Cu" "In8.Cu" "In9.Cu" "In10.Cu" "In11.Cu" "In12.Cu" "In13.Cu" "In14.Cu"
			"In15.Cu" "In16.Cu"
		)
		(hatch none 0.5)
		(connect_pads
			(clearance 0)
		)
		(min_thickness 0.25)
		(keepout
			(tracks not_allowed)
			(vias allowed)
			(pads allowed)
			(copperpour not_allowed)
			(footprints allowed)
		)
		(placement
			(enabled no)
			(sheetname "")
		)
		(fill
			(thermal_gap 0.5)
			(thermal_bridge_width 0.5)
			(island_removal_mode 0)
		)
		(polygon
			(pts
				(arc
					(start 180.845968 -145.287238)
					(mid 181.303168 -145.744438)
					(end 181.760368 -145.287238)
				)
				(arc
					(start 181.760368 -144.423638)
					(mid 181.303168 -143.966438)
					(end 180.845968 -144.423638)
				)
			)
		)
	)
	(zone
		(layers "F.Cu" "B.Cu" "In1.Cu" "In2.Cu" "In3.Cu" "In4.Cu" "In5.Cu" "In6.Cu"
			"In7.Cu" "In8.Cu" "In9.Cu" "In10.Cu" "In11.Cu" "In12.Cu" "In13.Cu" "In14.Cu"
			"In15.Cu" "In16.Cu"
		)
		(hatch none 0.5)
		(connect_pads
			(clearance 0)
		)
		(min_thickness 0.25)
		(keepout
			(tracks not_allowed)
			(vias allowed)
			(pads allowed)
			(copperpour not_allowed)
			(footprints allowed)
		)
		(placement
			(enabled no)
			(sheetname "")
		)
		(fill
			(thermal_gap 0.5)
			(thermal_bridge_width 0.5)
			(island_removal_mode 0)
		)
		(polygon
			(pts
				(arc
					(start 424.839892 -357.37673)
					(mid 424.458892 -357.75773)
					(end 424.839892 -358.13873)
				)
				(arc
					(start 425.703492 -358.13873)
					(mid 426.084492 -357.75773)
					(end 425.703492 -357.37673)
				)
			)
		)
	)
	(zone
		(layers "F.Cu" "B.Cu" "In1.Cu" "In2.Cu" "In3.Cu" "In4.Cu" "In5.Cu" "In6.Cu"
			"In7.Cu" "In8.Cu" "In9.Cu" "In10.Cu" "In11.Cu" "In12.Cu" "In13.Cu" "In14.Cu"
			"In15.Cu" "In16.Cu"
		)
		(hatch none 0.5)
		(connect_pads
			(clearance 0)
		)
		(min_thickness 0.25)
		(keepout
			(tracks not_allowed)
			(vias allowed)
			(pads allowed)
			(copperpour not_allowed)
			(footprints allowed)
		)
		(placement
			(enabled no)
			(sheetname "")
		)
		(fill
			(thermal_gap 0.5)
			(thermal_bridge_width 0.5)
			(island_removal_mode 0)
		)
		(polygon
			(pts
				(arc
					(start 355.053392 -34.52241)
					(mid 355.510592 -34.97961)
					(end 355.967792 -34.52241)
				)
				(arc
					(start 355.967792 -33.65881)
					(mid 355.510592 -33.20161)
					(end 355.053392 -33.65881)
				)
			)
		)
	)
	(zone
		(layers "F.Cu" "B.Cu" "In1.Cu" "In2.Cu" "In3.Cu" "In4.Cu" "In5.Cu" "In6.Cu"
			"In7.Cu" "In8.Cu" "In9.Cu" "In10.Cu" "In11.Cu" "In12.Cu" "In13.Cu" "In14.Cu"
			"In15.Cu" "In16.Cu"
		)
		(hatch none 0.5)
		(connect_pads
			(clearance 0)
		)
		(min_thickness 0.25)
		(keepout
			(tracks not_allowed)
			(vias allowed)
			(pads allowed)
			(copperpour not_allowed)
			(footprints allowed)
		)
		(placement
			(enabled no)
			(sheetname "")
		)
		(fill
			(thermal_gap 0.5)
			(thermal_bridge_width 0.5)
			(island_removal_mode 0)
		)
		(polygon
			(pts
				(arc
					(start 133.624828 -348.20479)
					(mid 133.243828 -348.58579)
					(end 133.624828 -348.96679)
				)
				(arc
					(start 134.488428 -348.96679)
					(mid 134.869428 -348.58579)
					(end 134.488428 -348.20479)
				)
			)
		)
	)
	(zone
		(layers "F.Cu" "B.Cu" "In1.Cu" "In2.Cu" "In3.Cu" "In4.Cu" "In5.Cu" "In6.Cu"
			"In7.Cu" "In8.Cu" "In9.Cu" "In10.Cu" "In11.Cu" "In12.Cu" "In13.Cu" "In14.Cu"
			"In15.Cu" "In16.Cu"
		)
		(hatch none 0.5)
		(connect_pads
			(clearance 0)
		)
		(min_thickness 0.25)
		(keepout
			(tracks not_allowed)
			(vias allowed)
			(pads allowed)
			(copperpour not_allowed)
			(footprints allowed)
		)
		(placement
			(enabled no)
			(sheetname "")
		)
		(fill
			(thermal_gap 0.5)
			(thermal_bridge_width 0.5)
			(island_removal_mode 0)
		)
		(polygon
			(pts
				(arc
					(start 382.9685 -120.087898)
					(mid 383.4257 -120.545098)
					(end 383.8829 -120.087898)
				)
				(arc
					(start 383.8829 -119.224298)
					(mid 383.4257 -118.767098)
					(end 382.9685 -119.224298)
				)
			)
		)
	)
	(zone
		(layers "F.Cu" "B.Cu" "In1.Cu" "In2.Cu" "In3.Cu" "In4.Cu" "In5.Cu" "In6.Cu"
			"In7.Cu" "In8.Cu" "In9.Cu" "In10.Cu" "In11.Cu" "In12.Cu" "In13.Cu" "In14.Cu"
			"In15.Cu" "In16.Cu"
		)
		(hatch none 0.5)
		(connect_pads
			(clearance 0)
		)
		(min_thickness 0.25)
		(keepout
			(tracks not_allowed)
			(vias allowed)
			(pads allowed)
			(copperpour not_allowed)
			(footprints allowed)
		)
		(placement
			(enabled no)
			(sheetname "")
		)
		(fill
			(thermal_gap 0.5)
			(thermal_bridge_width 0.5)
			(island_removal_mode 0)
		)
		(polygon
			(pts
				(arc
					(start 31.768288 -354.351082)
					(mid 31.387288 -354.732082)
					(end 31.768288 -355.113082)
				)
				(arc
					(start 32.631888 -355.113082)
					(mid 33.012888 -354.732082)
					(end 32.631888 -354.351082)
				)
			)
		)
	)
	(zone
		(layers "F.Cu" "B.Cu" "In1.Cu" "In2.Cu" "In3.Cu" "In4.Cu" "In5.Cu" "In6.Cu"
			"In7.Cu" "In8.Cu" "In9.Cu" "In10.Cu" "In11.Cu" "In12.Cu" "In13.Cu" "In14.Cu"
			"In15.Cu" "In16.Cu"
		)
		(hatch none 0.5)
		(connect_pads
			(clearance 0)
		)
		(min_thickness 0.25)
		(keepout
			(tracks not_allowed)
			(vias allowed)
			(pads allowed)
			(copperpour not_allowed)
			(footprints allowed)
		)
		(placement
			(enabled no)
			(sheetname "")
		)
		(fill
			(thermal_gap 0.5)
			(thermal_bridge_width 0.5)
			(island_removal_mode 0)
		)
		(polygon
			(pts
				(arc
					(start 418.621972 -345.084146)
					(mid 418.240972 -345.465146)
					(end 418.621972 -345.846146)
				)
				(arc
					(start 419.485572 -345.846146)
					(mid 419.866572 -345.465146)
					(end 419.485572 -345.084146)
				)
			)
		)
	)
	(zone
		(layers "F.Cu" "B.Cu" "In1.Cu" "In2.Cu" "In3.Cu" "In4.Cu" "In5.Cu" "In6.Cu"
			"In7.Cu" "In8.Cu" "In9.Cu" "In10.Cu" "In11.Cu" "In12.Cu" "In13.Cu" "In14.Cu"
			"In15.Cu" "In16.Cu"
		)
		(hatch none 0.5)
		(connect_pads
			(clearance 0)
		)
		(min_thickness 0.25)
		(keepout
			(tracks not_allowed)
			(vias allowed)
			(pads allowed)
			(copperpour not_allowed)
			(footprints allowed)
		)
		(placement
			(enabled no)
			(sheetname "")
		)
		(fill
			(thermal_gap 0.5)
			(thermal_bridge_width 0.5)
			(island_removal_mode 0)
		)
		(polygon
			(pts
				(arc
					(start 153.410666 -121.894346)
					(mid 153.867866 -122.351546)
					(end 154.325066 -121.894346)
				)
				(arc
					(start 154.325066 -121.030746)
					(mid 153.867866 -120.573546)
					(end 153.410666 -121.030746)
				)
			)
		)
	)
	(zone
		(layers "F.Cu" "B.Cu" "In1.Cu" "In2.Cu" "In3.Cu" "In4.Cu" "In5.Cu" "In6.Cu"
			"In7.Cu" "In8.Cu" "In9.Cu" "In10.Cu" "In11.Cu" "In12.Cu" "In13.Cu" "In14.Cu"
			"In15.Cu" "In16.Cu"
		)
		(hatch none 0.5)
		(connect_pads
			(clearance 0)
		)
		(min_thickness 0.25)
		(keepout
			(tracks not_allowed)
			(vias allowed)
			(pads allowed)
			(copperpour not_allowed)
			(footprints allowed)
		)
		(placement
			(enabled no)
			(sheetname "")
		)
		(fill
			(thermal_gap 0.5)
			(thermal_bridge_width 0.5)
			(island_removal_mode 0)
		)
		(polygon
			(pts
				(arc
					(start 266.868402 -112.784382)
					(mid 267.325602 -113.241582)
					(end 267.782802 -112.784382)
				)
				(arc
					(start 267.782802 -111.920782)
					(mid 267.325602 -111.463582)
					(end 266.868402 -111.920782)
				)
			)
		)
	)
	(zone
		(layers "F.Cu" "B.Cu" "In1.Cu" "In2.Cu" "In3.Cu" "In4.Cu" "In5.Cu" "In6.Cu"
			"In7.Cu" "In8.Cu" "In9.Cu" "In10.Cu" "In11.Cu" "In12.Cu" "In13.Cu" "In14.Cu"
			"In15.Cu" "In16.Cu"
		)
		(hatch none 0.5)
		(connect_pads
			(clearance 0)
		)
		(min_thickness 0.25)
		(keepout
			(tracks not_allowed)
			(vias allowed)
			(pads allowed)
			(copperpour not_allowed)
			(footprints allowed)
		)
		(placement
			(enabled no)
			(sheetname "")
		)
		(fill
			(thermal_gap 0.5)
			(thermal_bridge_width 0.5)
			(island_removal_mode 0)
		)
		(polygon
			(pts
				(arc
					(start 124.30125 -373.828818)
					(mid 124.316129 -373.792897)
					(end 124.35205 -373.778018)
				)
				(arc
					(start 125.06833 -373.778018)
					(mid 125.104251 -373.792897)
					(end 125.11913 -373.828818)
				)
				(arc
					(start 125.11913 -376.25147)
					(mid 125.104251 -376.287391)
					(end 125.06833 -376.30227)
				)
				(arc
					(start 124.35205 -376.30227)
					(mid 124.316129 -376.287391)
					(end 124.30125 -376.25147)
				)
			)
		)
	)
	(zone
		(layers "F.Cu" "B.Cu" "In1.Cu" "In2.Cu" "In3.Cu" "In4.Cu" "In5.Cu" "In6.Cu"
			"In7.Cu" "In8.Cu" "In9.Cu" "In10.Cu" "In11.Cu" "In12.Cu" "In13.Cu" "In14.Cu"
			"In15.Cu" "In16.Cu"
		)
		(hatch none 0.5)
		(connect_pads
			(clearance 0)
		)
		(min_thickness 0.25)
		(keepout
			(tracks not_allowed)
			(vias allowed)
			(pads allowed)
			(copperpour not_allowed)
			(footprints allowed)
		)
		(placement
			(enabled no)
			(sheetname "")
		)
		(fill
			(thermal_gap 0.5)
			(thermal_bridge_width 0.5)
			(island_removal_mode 0)
		)
		(polygon
			(pts
				(arc
					(start 29.700982 -404.828756)
					(mid 29.715861 -404.792835)
					(end 29.751782 -404.777956)
				)
				(arc
					(start 30.468062 -404.777956)
					(mid 30.503983 -404.792835)
					(end 30.518862 -404.828756)
				)
				(arc
					(start 30.518862 -407.251408)
					(mid 30.503983 -407.287329)
					(end 30.468062 -407.302208)
				)
				(arc
					(start 29.751782 -407.302208)
					(mid 29.715861 -407.287329)
					(end 29.700982 -407.251408)
				)
			)
		)
	)
	(zone
		(layers "F.Cu" "B.Cu" "In1.Cu" "In2.Cu" "In3.Cu" "In4.Cu" "In5.Cu" "In6.Cu"
			"In7.Cu" "In8.Cu" "In9.Cu" "In10.Cu" "In11.Cu" "In12.Cu" "In13.Cu" "In14.Cu"
			"In15.Cu" "In16.Cu"
		)
		(hatch none 0.5)
		(connect_pads
			(clearance 0)
		)
		(min_thickness 0.25)
		(keepout
			(tracks not_allowed)
			(vias allowed)
			(pads allowed)
			(copperpour not_allowed)
			(footprints allowed)
		)
		(placement
			(enabled no)
			(sheetname "")
		)
		(fill
			(thermal_gap 0.5)
			(thermal_bridge_width 0.5)
			(island_removal_mode 0)
		)
		(polygon
			(pts
				(arc
					(start 160.948116 -32.714184)
					(mid 161.405316 -33.171384)
					(end 161.862516 -32.714184)
				)
				(arc
					(start 161.862516 -31.850584)
					(mid 161.405316 -31.393384)
					(end 160.948116 -31.850584)
				)
			)
		)
	)
	(zone
		(layers "F.Cu" "B.Cu" "In1.Cu" "In2.Cu" "In3.Cu" "In4.Cu" "In5.Cu" "In6.Cu"
			"In7.Cu" "In8.Cu" "In9.Cu" "In10.Cu" "In11.Cu" "In12.Cu" "In13.Cu" "In14.Cu"
			"In15.Cu" "In16.Cu"
		)
		(hatch none 0.5)
		(connect_pads
			(clearance 0)
		)
		(min_thickness 0.25)
		(keepout
			(tracks not_allowed)
			(vias allowed)
			(pads allowed)
			(copperpour not_allowed)
			(footprints allowed)
		)
		(placement
			(enabled no)
			(sheetname "")
		)
		(fill
			(thermal_gap 0.5)
			(thermal_bridge_width 0.5)
			(island_removal_mode 0)
		)
		(polygon
			(pts
				(arc
					(start 425.680886 -397.028924)
					(mid 425.695765 -396.993003)
					(end 425.731686 -396.978124)
				)
				(arc
					(start 426.447966 -396.978124)
					(mid 426.483887 -396.993003)
					(end 426.498766 -397.028924)
				)
				(arc
					(start 426.498766 -399.451576)
					(mid 426.483887 -399.487497)
					(end 426.447966 -399.502376)
				)
				(arc
					(start 425.731686 -399.502376)
					(mid 425.695765 -399.487497)
					(end 425.680886 -399.451576)
				)
			)
		)
	)
	(zone
		(layers "F.Cu" "B.Cu" "In1.Cu" "In2.Cu" "In3.Cu" "In4.Cu" "In5.Cu" "In6.Cu"
			"In7.Cu" "In8.Cu" "In9.Cu" "In10.Cu" "In11.Cu" "In12.Cu" "In13.Cu" "In14.Cu"
			"In15.Cu" "In16.Cu"
		)
		(hatch none 0.5)
		(connect_pads
			(clearance 0)
		)
		(min_thickness 0.25)
		(keepout
			(tracks not_allowed)
			(vias allowed)
			(pads allowed)
			(copperpour not_allowed)
			(footprints allowed)
		)
		(placement
			(enabled no)
			(sheetname "")
		)
		(fill
			(thermal_gap 0.5)
			(thermal_bridge_width 0.5)
			(island_removal_mode 0)
		)
		(polygon
			(pts
				(arc
					(start 83.71713 -136.17575)
					(mid 84.17433 -136.63295)
					(end 84.63153 -136.17575)
				)
				(arc
					(start 84.63153 -135.31215)
					(mid 84.17433 -134.85495)
					(end 83.71713 -135.31215)
				)
			)
		)
	)
	(zone
		(layers "F.Cu" "B.Cu" "In1.Cu" "In2.Cu" "In3.Cu" "In4.Cu" "In5.Cu" "In6.Cu"
			"In7.Cu" "In8.Cu" "In9.Cu" "In10.Cu" "In11.Cu" "In12.Cu" "In13.Cu" "In14.Cu"
			"In15.Cu" "In16.Cu"
		)
		(hatch none 0.5)
		(connect_pads
			(clearance 0)
		)
		(min_thickness 0.25)
		(keepout
			(tracks not_allowed)
			(vias allowed)
			(pads allowed)
			(copperpour not_allowed)
			(footprints allowed)
		)
		(placement
			(enabled no)
			(sheetname "")
		)
		(fill
			(thermal_gap 0.5)
			(thermal_bridge_width 0.5)
			(island_removal_mode 0)
		)
		(polygon
			(pts
				(arc
					(start 122.101102 -404.828756)
					(mid 122.115981 -404.792835)
					(end 122.151902 -404.777956)
				)
				(arc
					(start 122.868182 -404.777956)
					(mid 122.904103 -404.792835)
					(end 122.918982 -404.828756)
				)
				(arc
					(start 122.918982 -407.251408)
					(mid 122.904103 -407.287329)
					(end 122.868182 -407.302208)
				)
				(arc
					(start 122.151902 -407.302208)
					(mid 122.115981 -407.287329)
					(end 122.101102 -407.251408)
				)
			)
		)
	)
	(zone
		(layers "F.Cu" "B.Cu" "In1.Cu" "In2.Cu" "In3.Cu" "In4.Cu" "In5.Cu" "In6.Cu"
			"In7.Cu" "In8.Cu" "In9.Cu" "In10.Cu" "In11.Cu" "In12.Cu" "In13.Cu" "In14.Cu"
			"In15.Cu" "In16.Cu"
		)
		(hatch none 0.5)
		(connect_pads
			(clearance 0)
		)
		(min_thickness 0.25)
		(keepout
			(tracks not_allowed)
			(vias allowed)
			(pads allowed)
			(copperpour not_allowed)
			(footprints allowed)
		)
		(placement
			(enabled no)
			(sheetname "")
		)
		(fill
			(thermal_gap 0.5)
			(thermal_bridge_width 0.5)
			(island_removal_mode 0)
		)
		(polygon
			(pts
				(arc
					(start 114.971068 -342.058498)
					(mid 114.590068 -342.439498)
					(end 114.971068 -342.820498)
				)
				(arc
					(start 115.834668 -342.820498)
					(mid 116.215668 -342.439498)
					(end 115.834668 -342.058498)
				)
			)
		)
	)
	(zone
		(layers "F.Cu" "B.Cu" "In1.Cu" "In2.Cu" "In3.Cu" "In4.Cu" "In5.Cu" "In6.Cu"
			"In7.Cu" "In8.Cu" "In9.Cu" "In10.Cu" "In11.Cu" "In12.Cu" "In13.Cu" "In14.Cu"
			"In15.Cu" "In16.Cu"
		)
		(hatch none 0.5)
		(connect_pads
			(clearance 0)
		)
		(min_thickness 0.25)
		(keepout
			(tracks not_allowed)
			(vias allowed)
			(pads allowed)
			(copperpour not_allowed)
			(footprints allowed)
		)
		(placement
			(enabled no)
			(sheetname "")
		)
		(fill
			(thermal_gap 0.5)
			(thermal_bridge_width 0.5)
			(island_removal_mode 0)
		)
		(polygon
			(pts
				(arc
					(start 86.243922 -357.37673)
					(mid 85.862922 -357.75773)
					(end 86.243922 -358.13873)
				)
				(arc
					(start 87.107522 -358.13873)
					(mid 87.488522 -357.75773)
					(end 87.107522 -357.37673)
				)
			)
		)
	)
	(zone
		(layers "F.Cu" "B.Cu" "In1.Cu" "In2.Cu" "In3.Cu" "In4.Cu" "In5.Cu" "In6.Cu"
			"In7.Cu" "In8.Cu" "In9.Cu" "In10.Cu" "In11.Cu" "In12.Cu" "In13.Cu" "In14.Cu"
			"In15.Cu" "In16.Cu"
		)
		(hatch none 0.5)
		(connect_pads
			(clearance 0)
		)
		(min_thickness 0.25)
		(keepout
			(tracks not_allowed)
			(vias allowed)
			(pads allowed)
			(copperpour not_allowed)
			(footprints allowed)
		)
		(placement
			(enabled no)
			(sheetname "")
		)
		(fill
			(thermal_gap 0.5)
			(thermal_bridge_width 0.5)
			(island_removal_mode 0)
		)
		(polygon
			(pts
				(arc
					(start 64.74587 -156.087318)
					(mid 65.20307 -156.544518)
					(end 65.66027 -156.087318)
				)
				(arc
					(start 65.66027 -155.223718)
					(mid 65.20307 -154.766518)
					(end 64.74587 -155.223718)
				)
			)
		)
	)
	(zone
		(layers "F.Cu" "B.Cu" "In1.Cu" "In2.Cu" "In3.Cu" "In4.Cu" "In5.Cu" "In6.Cu"
			"In7.Cu" "In8.Cu" "In9.Cu" "In10.Cu" "In11.Cu" "In12.Cu" "In13.Cu" "In14.Cu"
			"In15.Cu" "In16.Cu"
		)
		(hatch none 0.5)
		(connect_pads
			(clearance 0)
		)
		(min_thickness 0.25)
		(keepout
			(tracks not_allowed)
			(vias allowed)
			(pads allowed)
			(copperpour not_allowed)
			(footprints allowed)
		)
		(placement
			(enabled no)
			(sheetname "")
		)
		(fill
			(thermal_gap 0.5)
			(thermal_bridge_width 0.5)
			(island_removal_mode 0)
		)
		(polygon
			(pts
				(arc
					(start 40.70096 -369.928902)
					(mid 40.715839 -369.892981)
					(end 40.75176 -369.878102)
				)
				(arc
					(start 41.46804 -369.878102)
					(mid 41.503961 -369.892981)
					(end 41.51884 -369.928902)
				)
				(arc
					(start 41.51884 -372.351554)
					(mid 41.503961 -372.387475)
					(end 41.46804 -372.402354)
				)
				(arc
					(start 40.75176 -372.402354)
					(mid 40.715839 -372.387475)
					(end 40.70096 -372.351554)
				)
			)
		)
	)
	(zone
		(layers "F.Cu" "B.Cu" "In1.Cu" "In2.Cu" "In3.Cu" "In4.Cu" "In5.Cu" "In6.Cu"
			"In7.Cu" "In8.Cu" "In9.Cu" "In10.Cu" "In11.Cu" "In12.Cu" "In13.Cu" "In14.Cu"
			"In15.Cu" "In16.Cu"
		)
		(hatch none 0.5)
		(connect_pads
			(clearance 0)
		)
		(min_thickness 0.25)
		(keepout
			(tracks not_allowed)
			(vias allowed)
			(pads allowed)
			(copperpour not_allowed)
			(footprints allowed)
		)
		(placement
			(enabled no)
			(sheetname "")
		)
		(fill
			(thermal_gap 0.5)
			(thermal_bridge_width 0.5)
			(island_removal_mode 0)
		)
		(polygon
			(pts
				(arc
					(start 36.301172 -399.828766)
					(mid 36.316051 -399.792845)
					(end 36.351972 -399.777966)
				)
				(arc
					(start 37.068252 -399.777966)
					(mid 37.104173 -399.792845)
					(end 37.119052 -399.828766)
				)
				(arc
					(start 37.119052 -402.251418)
					(mid 37.104173 -402.287339)
					(end 37.068252 -402.302218)
				)
				(arc
					(start 36.351972 -402.302218)
					(mid 36.316051 -402.287339)
					(end 36.301172 -402.251418)
				)
			)
		)
	)
	(zone
		(layers "F.Cu" "B.Cu" "In1.Cu" "In2.Cu" "In3.Cu" "In4.Cu" "In5.Cu" "In6.Cu"
			"In7.Cu" "In8.Cu" "In9.Cu" "In10.Cu" "In11.Cu" "In12.Cu" "In13.Cu" "In14.Cu"
			"In15.Cu" "In16.Cu"
		)
		(hatch none 0.5)
		(connect_pads
			(clearance 0)
		)
		(min_thickness 0.25)
		(keepout
			(tracks not_allowed)
			(vias allowed)
			(pads allowed)
			(copperpour not_allowed)
			(footprints allowed)
		)
		(placement
			(enabled no)
			(sheetname "")
		)
		(fill
			(thermal_gap 0.5)
			(thermal_bridge_width 0.5)
			(island_removal_mode 0)
		)
		(polygon
			(pts
				(arc
					(start 432.280822 -407.628852)
					(mid 432.295701 -407.592931)
					(end 432.331622 -407.578052)
				)
				(arc
					(start 433.047902 -407.578052)
					(mid 433.083823 -407.592931)
					(end 433.098702 -407.628852)
				)
				(arc
					(start 433.098702 -410.051504)
					(mid 433.083823 -410.087425)
					(end 433.047902 -410.102304)
				)
				(arc
					(start 432.331622 -410.102304)
					(mid 432.295701 -410.087425)
					(end 432.280822 -410.051504)
				)
			)
		)
	)
	(zone
		(layers "F.Cu" "B.Cu" "In1.Cu" "In2.Cu" "In3.Cu" "In4.Cu" "In5.Cu" "In6.Cu"
			"In7.Cu" "In8.Cu" "In9.Cu" "In10.Cu" "In11.Cu" "In12.Cu" "In13.Cu" "In14.Cu"
			"In15.Cu" "In16.Cu"
		)
		(hatch none 0.5)
		(connect_pads
			(clearance 0)
		)
		(min_thickness 0.25)
		(keepout
			(tracks allowed)
			(vias allowed)
			(pads allowed)
			(copperpour allowed)
			(footprints not_allowed)
		)
		(placement
			(enabled no)
			(sheetname "")
		)
		(fill
			(thermal_gap 0.5)
			(thermal_bridge_width 0.5)
			(island_removal_mode 0)
		)
		(polygon
			(pts
				(arc
					(start 6.800088 -400.66595)
					(mid 9.365996 -398.100042)
					(end 6.800088 -395.53388)
				)
				(arc
					(start 5.199888 -395.53388)
					(mid 2.633726 -398.100042)
					(end 5.199888 -400.66595)
				)
			)
		)
	)
	(zone
		(layers "F.Cu" "B.Cu" "In1.Cu" "In2.Cu" "In3.Cu" "In4.Cu" "In5.Cu" "In6.Cu"
			"In7.Cu" "In8.Cu" "In9.Cu" "In10.Cu" "In11.Cu" "In12.Cu" "In13.Cu" "In14.Cu"
			"In15.Cu" "In16.Cu"
		)
		(hatch none 0.5)
		(connect_pads
			(clearance 0)
		)
		(min_thickness 0.25)
		(keepout
			(tracks not_allowed)
			(vias allowed)
			(pads allowed)
			(copperpour not_allowed)
			(footprints allowed)
		)
		(placement
			(enabled no)
			(sheetname "")
		)
		(fill
			(thermal_gap 0.5)
			(thermal_bridge_width 0.5)
			(island_removal_mode 0)
		)
		(polygon
			(pts
				(arc
					(start 199.817228 -124.965714)
					(mid 200.274428 -125.422914)
					(end 200.731628 -124.965714)
				)
				(arc
					(start 200.731628 -124.102114)
					(mid 200.274428 -123.644914)
					(end 199.817228 -124.102114)
				)
			)
		)
	)
	(zone
		(layers "F.Cu" "B.Cu" "In1.Cu" "In2.Cu" "In3.Cu" "In4.Cu" "In5.Cu" "In6.Cu"
			"In7.Cu" "In8.Cu" "In9.Cu" "In10.Cu" "In11.Cu" "In12.Cu" "In13.Cu" "In14.Cu"
			"In15.Cu" "In16.Cu"
		)
		(hatch none 0.5)
		(connect_pads
			(clearance 0)
		)
		(min_thickness 0.25)
		(keepout
			(tracks not_allowed)
			(vias allowed)
			(pads allowed)
			(copperpour not_allowed)
			(footprints allowed)
		)
		(placement
			(enabled no)
			(sheetname "")
		)
		(fill
			(thermal_gap 0.5)
			(thermal_bridge_width 0.5)
			(island_removal_mode 0)
		)
		(polygon
			(pts
				(arc
					(start 22.441408 -351.230438)
					(mid 22.060408 -351.611438)
					(end 22.441408 -351.992438)
				)
				(arc
					(start 23.305008 -351.992438)
					(mid 23.686008 -351.611438)
					(end 23.305008 -351.230438)
				)
			)
		)
	)
	(zone
		(layers "F.Cu" "B.Cu" "In1.Cu" "In2.Cu" "In3.Cu" "In4.Cu" "In5.Cu" "In6.Cu"
			"In7.Cu" "In8.Cu" "In9.Cu" "In10.Cu" "In11.Cu" "In12.Cu" "In13.Cu" "In14.Cu"
			"In15.Cu" "In16.Cu"
		)
		(hatch none 0.5)
		(connect_pads
			(clearance 0)
		)
		(min_thickness 0.25)
		(keepout
			(tracks not_allowed)
			(vias allowed)
			(pads allowed)
			(copperpour not_allowed)
			(footprints allowed)
		)
		(placement
			(enabled no)
			(sheetname "")
		)
		(fill
			(thermal_gap 0.5)
			(thermal_bridge_width 0.5)
			(island_removal_mode 0)
		)
		(polygon
			(pts
				(arc
					(start 377.280932 -397.028924)
					(mid 377.295811 -396.993003)
					(end 377.331732 -396.978124)
				)
				(arc
					(start 378.048012 -396.978124)
					(mid 378.083933 -396.993003)
					(end 378.098812 -397.028924)
				)
				(arc
					(start 378.098812 -399.451576)
					(mid 378.083933 -399.487497)
					(end 378.048012 -399.502376)
				)
				(arc
					(start 377.331732 -399.502376)
					(mid 377.295811 -399.487497)
					(end 377.280932 -399.451576)
				)
			)
		)
	)
	(zone
		(layers "F.Cu" "B.Cu" "In1.Cu" "In2.Cu" "In3.Cu" "In4.Cu" "In5.Cu" "In6.Cu"
			"In7.Cu" "In8.Cu" "In9.Cu" "In10.Cu" "In11.Cu" "In12.Cu" "In13.Cu" "In14.Cu"
			"In15.Cu" "In16.Cu"
		)
		(hatch none 0.5)
		(connect_pads
			(clearance 0)
		)
		(min_thickness 0.25)
		(keepout
			(tracks not_allowed)
			(vias allowed)
			(pads allowed)
			(copperpour not_allowed)
			(footprints allowed)
		)
		(placement
			(enabled no)
			(sheetname "")
		)
		(fill
			(thermal_gap 0.5)
			(thermal_bridge_width 0.5)
			(island_removal_mode 0)
		)
		(polygon
			(pts
				(arc
					(start 34.101024 -400.92884)
					(mid 34.115903 -400.892919)
					(end 34.151824 -400.87804)
				)
				(arc
					(start 34.868104 -400.87804)
					(mid 34.904025 -400.892919)
					(end 34.918904 -400.92884)
				)
				(arc
					(start 34.918904 -403.351492)
					(mid 34.904025 -403.387413)
					(end 34.868104 -403.402292)
				)
				(arc
					(start 34.151824 -403.402292)
					(mid 34.115903 -403.387413)
					(end 34.101024 -403.351492)
				)
			)
		)
	)
	(zone
		(layers "F.Cu" "B.Cu" "In1.Cu" "In2.Cu" "In3.Cu" "In4.Cu" "In5.Cu" "In6.Cu"
			"In7.Cu" "In8.Cu" "In9.Cu" "In10.Cu" "In11.Cu" "In12.Cu" "In13.Cu" "In14.Cu"
			"In15.Cu" "In16.Cu"
		)
		(hatch none 0.5)
		(connect_pads
			(clearance 0)
		)
		(min_thickness 0.25)
		(keepout
			(tracks not_allowed)
			(vias allowed)
			(pads allowed)
			(copperpour not_allowed)
			(footprints allowed)
		)
		(placement
			(enabled no)
			(sheetname "")
		)
		(fill
			(thermal_gap 0.5)
			(thermal_bridge_width 0.5)
			(island_removal_mode 0)
		)
		(polygon
			(pts
				(arc
					(start 66.60007 -134.377176)
					(mid 67.05727 -134.834376)
					(end 67.51447 -134.377176)
				)
				(arc
					(start 67.51447 -133.513576)
					(mid 67.05727 -133.056376)
					(end 66.60007 -133.513576)
				)
			)
		)
	)
	(zone
		(layers "F.Cu" "B.Cu" "In1.Cu" "In2.Cu" "In3.Cu" "In4.Cu" "In5.Cu" "In6.Cu"
			"In7.Cu" "In8.Cu" "In9.Cu" "In10.Cu" "In11.Cu" "In12.Cu" "In13.Cu" "In14.Cu"
			"In15.Cu" "In16.Cu"
		)
		(hatch none 0.5)
		(connect_pads
			(clearance 0)
		)
		(min_thickness 0.25)
		(keepout
			(tracks not_allowed)
			(vias allowed)
			(pads allowed)
			(copperpour not_allowed)
			(footprints allowed)
		)
		(placement
			(enabled no)
			(sheetname "")
		)
		(fill
			(thermal_gap 0.5)
			(thermal_bridge_width 0.5)
			(island_removal_mode 0)
		)
		(polygon
			(pts
				(arc
					(start 52.69992 -132.232908)
					(mid 52.24272 -131.775708)
					(end 51.78552 -132.232908)
				)
				(arc
					(start 51.78552 -133.096508)
					(mid 52.24272 -133.553708)
					(end 52.69992 -133.096508)
				)
			)
		)
	)
	(zone
		(layers "F.Cu" "B.Cu" "In1.Cu" "In2.Cu" "In3.Cu" "In4.Cu" "In5.Cu" "In6.Cu"
			"In7.Cu" "In8.Cu" "In9.Cu" "In10.Cu" "In11.Cu" "In12.Cu" "In13.Cu" "In14.Cu"
			"In15.Cu" "In16.Cu"
		)
		(hatch none 0.5)
		(connect_pads
			(clearance 0)
		)
		(min_thickness 0.25)
		(keepout
			(tracks not_allowed)
			(vias allowed)
			(pads allowed)
			(copperpour not_allowed)
			(footprints allowed)
		)
		(placement
			(enabled no)
			(sheetname "")
		)
		(fill
			(thermal_gap 0.5)
			(thermal_bridge_width 0.5)
			(island_removal_mode 0)
		)
		(polygon
			(pts
				(arc
					(start 171.512992 -345.084146)
					(mid 171.131992 -345.465146)
					(end 171.512992 -345.846146)
				)
				(arc
					(start 172.376592 -345.846146)
					(mid 172.757592 -345.465146)
					(end 172.376592 -345.084146)
				)
			)
		)
	)
	(zone
		(layers "F.Cu" "B.Cu" "In1.Cu" "In2.Cu" "In3.Cu" "In4.Cu" "In5.Cu" "In6.Cu"
			"In7.Cu" "In8.Cu" "In9.Cu" "In10.Cu" "In11.Cu" "In12.Cu" "In13.Cu" "In14.Cu"
			"In15.Cu" "In16.Cu"
		)
		(hatch none 0.5)
		(connect_pads
			(clearance 0)
		)
		(min_thickness 0.25)
		(keepout
			(tracks not_allowed)
			(vias allowed)
			(pads allowed)
			(copperpour not_allowed)
			(footprints allowed)
		)
		(placement
			(enabled no)
			(sheetname "")
		)
		(fill
			(thermal_gap 0.5)
			(thermal_bridge_width 0.5)
			(island_removal_mode 0)
		)
		(polygon
			(pts
				(arc
					(start 390.481058 -371.028722)
					(mid 390.495937 -370.992801)
					(end 390.531858 -370.977922)
				)
				(arc
					(start 391.248138 -370.977922)
					(mid 391.284059 -370.992801)
					(end 391.298938 -371.028722)
				)
				(arc
					(start 391.298938 -373.451374)
					(mid 391.284059 -373.487295)
					(end 391.248138 -373.502174)
				)
				(arc
					(start 390.531858 -373.502174)
					(mid 390.495937 -373.487295)
					(end 390.481058 -373.451374)
				)
			)
		)
	)
	(zone
		(layers "F.Cu" "B.Cu" "In1.Cu" "In2.Cu" "In3.Cu" "In4.Cu" "In5.Cu" "In6.Cu"
			"In7.Cu" "In8.Cu" "In9.Cu" "In10.Cu" "In11.Cu" "In12.Cu" "In13.Cu" "In14.Cu"
			"In15.Cu" "In16.Cu"
		)
		(hatch none 0.5)
		(connect_pads
			(clearance 0)
		)
		(min_thickness 0.25)
		(keepout
			(tracks not_allowed)
			(vias allowed)
			(pads allowed)
			(copperpour not_allowed)
			(footprints allowed)
		)
		(placement
			(enabled no)
			(sheetname "")
		)
		(fill
			(thermal_gap 0.5)
			(thermal_bridge_width 0.5)
			(island_removal_mode 0)
		)
		(polygon
			(pts
				(arc
					(start 81.075022 -143.479266)
					(mid 81.532222 -143.936466)
					(end 81.989422 -143.479266)
				)
				(arc
					(start 81.989422 -142.615666)
					(mid 81.532222 -142.158466)
					(end 81.075022 -142.615666)
				)
			)
		)
	)
	(zone
		(layers "F.Cu" "B.Cu" "In1.Cu" "In2.Cu" "In3.Cu" "In4.Cu" "In5.Cu" "In6.Cu"
			"In7.Cu" "In8.Cu" "In9.Cu" "In10.Cu" "In11.Cu" "In12.Cu" "In13.Cu" "In14.Cu"
			"In15.Cu" "In16.Cu"
		)
		(hatch none 0.5)
		(connect_pads
			(clearance 0)
		)
		(min_thickness 0.25)
		(keepout
			(tracks not_allowed)
			(vias allowed)
			(pads allowed)
			(copperpour not_allowed)
			(footprints allowed)
		)
		(placement
			(enabled no)
			(sheetname "")
		)
		(fill
			(thermal_gap 0.5)
			(thermal_bridge_width 0.5)
			(island_removal_mode 0)
		)
		(polygon
			(pts
				(arc
					(start 170.501056 -382.728724)
					(mid 170.515935 -382.692803)
					(end 170.551856 -382.677924)
				)
				(arc
					(start 171.268136 -382.677924)
					(mid 171.304057 -382.692803)
					(end 171.318936 -382.728724)
				)
				(arc
					(start 171.318936 -385.151376)
					(mid 171.304057 -385.187297)
					(end 171.268136 -385.202176)
				)
				(arc
					(start 170.551856 -385.202176)
					(mid 170.515935 -385.187297)
					(end 170.501056 -385.151376)
				)
			)
		)
	)
	(zone
		(layers "F.Cu" "B.Cu" "In1.Cu" "In2.Cu" "In3.Cu" "In4.Cu" "In5.Cu" "In6.Cu"
			"In7.Cu" "In8.Cu" "In9.Cu" "In10.Cu" "In11.Cu" "In12.Cu" "In13.Cu" "In14.Cu"
			"In15.Cu" "In16.Cu"
		)
		(hatch none 0.5)
		(connect_pads
			(clearance 0)
		)
		(min_thickness 0.25)
		(keepout
			(tracks not_allowed)
			(vias allowed)
			(pads allowed)
			(copperpour not_allowed)
			(footprints allowed)
		)
		(placement
			(enabled no)
			(sheetname "")
		)
		(fill
			(thermal_gap 0.5)
			(thermal_bridge_width 0.5)
			(island_removal_mode 0)
		)
		(polygon
			(pts
				(arc
					(start 333.28102 -408.728672)
					(mid 333.295899 -408.692751)
					(end 333.33182 -408.677872)
				)
				(arc
					(start 334.0481 -408.677872)
					(mid 334.084021 -408.692751)
					(end 334.0989 -408.728672)
				)
				(arc
					(start 334.0989 -411.151324)
					(mid 334.084021 -411.187245)
					(end 334.0481 -411.202124)
				)
				(arc
					(start 333.33182 -411.202124)
					(mid 333.295899 -411.187245)
					(end 333.28102 -411.151324)
				)
			)
		)
	)
	(zone
		(layers "F.Cu" "B.Cu" "In1.Cu" "In2.Cu" "In3.Cu" "In4.Cu" "In5.Cu" "In6.Cu"
			"In7.Cu" "In8.Cu" "In9.Cu" "In10.Cu" "In11.Cu" "In12.Cu" "In13.Cu" "In14.Cu"
			"In15.Cu" "In16.Cu"
		)
		(hatch none 0.5)
		(connect_pads
			(clearance 0)
		)
		(min_thickness 0.25)
		(keepout
			(tracks not_allowed)
			(vias allowed)
			(pads allowed)
			(copperpour not_allowed)
			(footprints allowed)
		)
		(placement
			(enabled no)
			(sheetname "")
		)
		(fill
			(thermal_gap 0.5)
			(thermal_bridge_width 0.5)
			(island_removal_mode 0)
		)
		(polygon
			(pts
				(arc
					(start 73.700894 -382.728724)
					(mid 73.715773 -382.692803)
					(end 73.751694 -382.677924)
				)
				(arc
					(start 74.467974 -382.677924)
					(mid 74.503895 -382.692803)
					(end 74.518774 -382.728724)
				)
				(arc
					(start 74.518774 -385.151376)
					(mid 74.503895 -385.187297)
					(end 74.467974 -385.202176)
				)
				(arc
					(start 73.751694 -385.202176)
					(mid 73.715773 -385.187297)
					(end 73.700894 -385.151376)
				)
			)
		)
	)
	(zone
		(layers "F.Cu" "B.Cu" "In1.Cu" "In2.Cu" "In3.Cu" "In4.Cu" "In5.Cu" "In6.Cu"
			"In7.Cu" "In8.Cu" "In9.Cu" "In10.Cu" "In11.Cu" "In12.Cu" "In13.Cu" "In14.Cu"
			"In15.Cu" "In16.Cu"
		)
		(hatch none 0.5)
		(connect_pads
			(clearance 0)
		)
		(min_thickness 0.25)
		(keepout
			(tracks not_allowed)
			(vias allowed)
			(pads allowed)
			(copperpour not_allowed)
			(footprints allowed)
		)
		(placement
			(enabled no)
			(sheetname "")
		)
		(fill
			(thermal_gap 0.5)
			(thermal_bridge_width 0.5)
			(island_removal_mode 0)
		)
		(polygon
			(pts
				(arc
					(start 463.319876 -307.607716)
					(mid 462.557876 -307.607716)
					(end 463.319876 -307.607716)
				)
			)
		)
	)
	(zone
		(layers "F.Cu" "B.Cu" "In1.Cu" "In2.Cu" "In3.Cu" "In4.Cu" "In5.Cu" "In6.Cu"
			"In7.Cu" "In8.Cu" "In9.Cu" "In10.Cu" "In11.Cu" "In12.Cu" "In13.Cu" "In14.Cu"
			"In15.Cu" "In16.Cu"
		)
		(hatch none 0.5)
		(connect_pads
			(clearance 0)
		)
		(min_thickness 0.25)
		(keepout
			(tracks not_allowed)
			(vias allowed)
			(pads allowed)
			(copperpour not_allowed)
			(footprints allowed)
		)
		(placement
			(enabled no)
			(sheetname "")
		)
		(fill
			(thermal_gap 0.5)
			(thermal_bridge_width 0.5)
			(island_removal_mode 0)
		)
		(polygon
			(pts
				(arc
					(start 54.729126 -370.447062)
					(mid 54.348126 -370.066062)
					(end 53.967126 -370.447062)
				)
				(arc
					(start 53.967126 -371.310662)
					(mid 54.348126 -371.691662)
					(end 54.729126 -371.310662)
				)
			)
		)
	)
	(zone
		(layers "F.Cu" "B.Cu" "In1.Cu" "In2.Cu" "In3.Cu" "In4.Cu" "In5.Cu" "In6.Cu"
			"In7.Cu" "In8.Cu" "In9.Cu" "In10.Cu" "In11.Cu" "In12.Cu" "In13.Cu" "In14.Cu"
			"In15.Cu" "In16.Cu"
		)
		(hatch none 0.5)
		(connect_pads
			(clearance 0)
		)
		(min_thickness 0.25)
		(keepout
			(tracks not_allowed)
			(vias allowed)
			(pads allowed)
			(copperpour not_allowed)
			(footprints allowed)
		)
		(placement
			(enabled no)
			(sheetname "")
		)
		(fill
			(thermal_gap 0.5)
			(thermal_bridge_width 0.5)
			(island_removal_mode 0)
		)
		(polygon
			(pts
				(arc
					(start 25.550368 -357.37673)
					(mid 25.169368 -357.75773)
					(end 25.550368 -358.13873)
				)
				(arc
					(start 26.413968 -358.13873)
					(mid 26.794968 -357.75773)
					(end 26.413968 -357.37673)
				)
			)
		)
	)
	(zone
		(layers "F.Cu" "B.Cu" "In1.Cu" "In2.Cu" "In3.Cu" "In4.Cu" "In5.Cu" "In6.Cu"
			"In7.Cu" "In8.Cu" "In9.Cu" "In10.Cu" "In11.Cu" "In12.Cu" "In13.Cu" "In14.Cu"
			"In15.Cu" "In16.Cu"
		)
		(hatch none 0.5)
		(connect_pads
			(clearance 0)
		)
		(min_thickness 0.25)
		(keepout
			(tracks not_allowed)
			(vias allowed)
			(pads allowed)
			(copperpour not_allowed)
			(footprints allowed)
		)
		(placement
			(enabled no)
			(sheetname "")
		)
		(fill
			(thermal_gap 0.5)
			(thermal_bridge_width 0.5)
			(island_removal_mode 0)
		)
		(polygon
			(pts
				(arc
					(start 377.280932 -371.028722)
					(mid 377.295811 -370.992801)
					(end 377.331732 -370.977922)
				)
				(arc
					(start 378.048012 -370.977922)
					(mid 378.083933 -370.992801)
					(end 378.098812 -371.028722)
				)
				(arc
					(start 378.098812 -373.451374)
					(mid 378.083933 -373.487295)
					(end 378.048012 -373.502174)
				)
				(arc
					(start 377.331732 -373.502174)
					(mid 377.295811 -373.487295)
					(end 377.280932 -373.451374)
				)
			)
		)
	)
	(zone
		(layers "F.Cu" "B.Cu" "In1.Cu" "In2.Cu" "In3.Cu" "In4.Cu" "In5.Cu" "In6.Cu"
			"In7.Cu" "In8.Cu" "In9.Cu" "In10.Cu" "In11.Cu" "In12.Cu" "In13.Cu" "In14.Cu"
			"In15.Cu" "In16.Cu"
		)
		(hatch none 0.5)
		(connect_pads
			(clearance 0)
		)
		(min_thickness 0.25)
		(keepout
			(tracks not_allowed)
			(vias allowed)
			(pads allowed)
			(copperpour not_allowed)
			(footprints allowed)
		)
		(placement
			(enabled no)
			(sheetname "")
		)
		(fill
			(thermal_gap 0.5)
			(thermal_bridge_width 0.5)
			(island_removal_mode 0)
		)
		(polygon
			(pts
				(arc
					(start 433.053236 -30.922468)
					(mid 433.510436 -31.379668)
					(end 433.967636 -30.922468)
				)
				(arc
					(start 433.967636 -30.058868)
					(mid 433.510436 -29.601668)
					(end 433.053236 -30.058868)
				)
			)
		)
	)
	(zone
		(layers "F.Cu" "B.Cu" "In1.Cu" "In2.Cu" "In3.Cu" "In4.Cu" "In5.Cu" "In6.Cu"
			"In7.Cu" "In8.Cu" "In9.Cu" "In10.Cu" "In11.Cu" "In12.Cu" "In13.Cu" "In14.Cu"
			"In15.Cu" "In16.Cu"
		)
		(hatch none 0.5)
		(connect_pads
			(clearance 0)
		)
		(min_thickness 0.25)
		(keepout
			(tracks not_allowed)
			(vias allowed)
			(pads allowed)
			(copperpour not_allowed)
			(footprints allowed)
		)
		(placement
			(enabled no)
			(sheetname "")
		)
		(fill
			(thermal_gap 0.5)
			(thermal_bridge_width 0.5)
			(island_removal_mode 0)
		)
		(polygon
			(pts
				(arc
					(start 286.754062 -110.11281)
					(mid 286.296862 -109.65561)
					(end 285.839662 -110.11281)
				)
				(arc
					(start 285.839662 -110.97641)
					(mid 286.296862 -111.43361)
					(end 286.754062 -110.97641)
				)
			)
		)
	)
	(zone
		(layers "F.Cu" "B.Cu" "In1.Cu" "In2.Cu" "In3.Cu" "In4.Cu" "In5.Cu" "In6.Cu"
			"In7.Cu" "In8.Cu" "In9.Cu" "In10.Cu" "In11.Cu" "In12.Cu" "In13.Cu" "In14.Cu"
			"In15.Cu" "In16.Cu"
		)
		(hatch none 0.5)
		(connect_pads
			(clearance 0)
		)
		(min_thickness 0.25)
		(keepout
			(tracks not_allowed)
			(vias allowed)
			(pads allowed)
			(copperpour not_allowed)
			(footprints allowed)
		)
		(placement
			(enabled no)
			(sheetname "")
		)
		(fill
			(thermal_gap 0.5)
			(thermal_bridge_width 0.5)
			(island_removal_mode 0)
		)
		(polygon
			(pts
				(arc
					(start 440.384692 -348.20479)
					(mid 440.003692 -348.58579)
					(end 440.384692 -348.96679)
				)
				(arc
					(start 441.248292 -348.96679)
					(mid 441.629292 -348.58579)
					(end 441.248292 -348.20479)
				)
			)
		)
	)
	(zone
		(layers "F.Cu" "B.Cu" "In1.Cu" "In2.Cu" "In3.Cu" "In4.Cu" "In5.Cu" "In6.Cu"
			"In7.Cu" "In8.Cu" "In9.Cu" "In10.Cu" "In11.Cu" "In12.Cu" "In13.Cu" "In14.Cu"
			"In15.Cu" "In16.Cu"
		)
		(hatch none 0.5)
		(connect_pads
			(clearance 0)
		)
		(min_thickness 0.25)
		(keepout
			(tracks not_allowed)
			(vias allowed)
			(pads allowed)
			(copperpour not_allowed)
			(footprints allowed)
		)
		(placement
			(enabled no)
			(sheetname "")
		)
		(fill
			(thermal_gap 0.5)
			(thermal_bridge_width 0.5)
			(island_removal_mode 0)
		)
		(polygon
			(pts
				(arc
					(start 277.223982 -348.20479)
					(mid 276.842982 -348.58579)
					(end 277.223982 -348.96679)
				)
				(arc
					(start 278.087582 -348.96679)
					(mid 278.468582 -348.58579)
					(end 278.087582 -348.20479)
				)
			)
		)
	)
	(zone
		(layers "F.Cu" "B.Cu" "In1.Cu" "In2.Cu" "In3.Cu" "In4.Cu" "In5.Cu" "In6.Cu"
			"In7.Cu" "In8.Cu" "In9.Cu" "In10.Cu" "In11.Cu" "In12.Cu" "In13.Cu" "In14.Cu"
			"In15.Cu" "In16.Cu"
		)
		(hatch none 0.5)
		(connect_pads
			(clearance 0)
		)
		(min_thickness 0.25)
		(keepout
			(tracks not_allowed)
			(vias allowed)
			(pads allowed)
			(copperpour not_allowed)
			(footprints allowed)
		)
		(placement
			(enabled no)
			(sheetname "")
		)
		(fill
			(thermal_gap 0.5)
			(thermal_bridge_width 0.5)
			(island_removal_mode 0)
		)
		(polygon
			(pts
				(arc
					(start 80.301084 -395.92885)
					(mid 80.315963 -395.892929)
					(end 80.351884 -395.87805)
				)
				(arc
					(start 81.068164 -395.87805)
					(mid 81.104085 -395.892929)
					(end 81.118964 -395.92885)
				)
				(arc
					(start 81.118964 -398.351502)
					(mid 81.104085 -398.387423)
					(end 81.068164 -398.402302)
				)
				(arc
					(start 80.351884 -398.402302)
					(mid 80.315963 -398.387423)
					(end 80.301084 -398.351502)
				)
			)
		)
	)
	(zone
		(layers "F.Cu" "B.Cu" "In1.Cu" "In2.Cu" "In3.Cu" "In4.Cu" "In5.Cu" "In6.Cu"
			"In7.Cu" "In8.Cu" "In9.Cu" "In10.Cu" "In11.Cu" "In12.Cu" "In13.Cu" "In14.Cu"
			"In15.Cu" "In16.Cu"
		)
		(hatch none 0.5)
		(connect_pads
			(clearance 0)
		)
		(min_thickness 0.25)
		(keepout
			(tracks not_allowed)
			(vias allowed)
			(pads allowed)
			(copperpour not_allowed)
			(footprints allowed)
		)
		(placement
			(enabled no)
			(sheetname "")
		)
		(fill
			(thermal_gap 0.5)
			(thermal_bridge_width 0.5)
			(island_removal_mode 0)
		)
		(polygon
			(pts
				(arc
					(start 296.945812 -121.367296)
					(mid 297.403012 -121.824496)
					(end 297.860212 -121.367296)
				)
				(arc
					(start 297.860212 -120.503696)
					(mid 297.403012 -120.046496)
					(end 296.945812 -120.503696)
				)
			)
		)
	)
	(zone
		(layers "F.Cu" "B.Cu" "In1.Cu" "In2.Cu" "In3.Cu" "In4.Cu" "In5.Cu" "In6.Cu"
			"In7.Cu" "In8.Cu" "In9.Cu" "In10.Cu" "In11.Cu" "In12.Cu" "In13.Cu" "In14.Cu"
			"In15.Cu" "In16.Cu"
		)
		(hatch none 0.5)
		(connect_pads
			(clearance 0)
		)
		(min_thickness 0.25)
		(keepout
			(tracks not_allowed)
			(vias allowed)
			(pads allowed)
			(copperpour not_allowed)
			(footprints allowed)
		)
		(placement
			(enabled no)
			(sheetname "")
		)
		(fill
			(thermal_gap 0.5)
			(thermal_bridge_width 0.5)
			(island_removal_mode 0)
		)
		(polygon
			(pts
				(arc
					(start 424.839892 -348.20479)
					(mid 424.458892 -348.58579)
					(end 424.839892 -348.96679)
				)
				(arc
					(start 425.703492 -348.96679)
					(mid 426.084492 -348.58579)
					(end 425.703492 -348.20479)
				)
			)
		)
	)
	(zone
		(layers "F.Cu" "B.Cu" "In1.Cu" "In2.Cu" "In3.Cu" "In4.Cu" "In5.Cu" "In6.Cu"
			"In7.Cu" "In8.Cu" "In9.Cu" "In10.Cu" "In11.Cu" "In12.Cu" "In13.Cu" "In14.Cu"
			"In15.Cu" "In16.Cu"
		)
		(hatch none 0.5)
		(connect_pads
			(clearance 0)
		)
		(min_thickness 0.25)
		(keepout
			(tracks not_allowed)
			(vias allowed)
			(pads allowed)
			(copperpour not_allowed)
			(footprints allowed)
		)
		(placement
			(enabled no)
			(sheetname "")
		)
		(fill
			(thermal_gap 0.5)
			(thermal_bridge_width 0.5)
			(island_removal_mode 0)
		)
		(polygon
			(pts
				(arc
					(start 383.881122 -407.628852)
					(mid 383.896001 -407.592931)
					(end 383.931922 -407.578052)
				)
				(arc
					(start 384.648202 -407.578052)
					(mid 384.684123 -407.592931)
					(end 384.699002 -407.628852)
				)
				(arc
					(start 384.699002 -410.051504)
					(mid 384.684123 -410.087425)
					(end 384.648202 -410.102304)
				)
				(arc
					(start 383.931922 -410.102304)
					(mid 383.896001 -410.087425)
					(end 383.881122 -410.051504)
				)
			)
		)
	)
	(zone
		(layers "F.Cu" "B.Cu" "In1.Cu" "In2.Cu" "In3.Cu" "In4.Cu" "In5.Cu" "In6.Cu"
			"In7.Cu" "In8.Cu" "In9.Cu" "In10.Cu" "In11.Cu" "In12.Cu" "In13.Cu" "In14.Cu"
			"In15.Cu" "In16.Cu"
		)
		(hatch none 0.5)
		(connect_pads
			(clearance 0)
		)
		(min_thickness 0.25)
		(keepout
			(tracks not_allowed)
			(vias allowed)
			(pads allowed)
			(copperpour not_allowed)
			(footprints allowed)
		)
		(placement
			(enabled no)
			(sheetname "")
		)
		(fill
			(thermal_gap 0.5)
			(thermal_bridge_width 0.5)
			(island_removal_mode 0)
		)
		(polygon
			(pts
				(arc
					(start 253.69012 -30.92069)
					(mid 254.14732 -31.37789)
					(end 254.60452 -30.92069)
				)
				(arc
					(start 254.60452 -30.05709)
					(mid 254.14732 -29.59989)
					(end 253.69012 -30.05709)
				)
			)
		)
	)
	(zone
		(layers "F.Cu" "B.Cu" "In1.Cu" "In2.Cu" "In3.Cu" "In4.Cu" "In5.Cu" "In6.Cu"
			"In7.Cu" "In8.Cu" "In9.Cu" "In10.Cu" "In11.Cu" "In12.Cu" "In13.Cu" "In14.Cu"
			"In15.Cu" "In16.Cu"
		)
		(hatch none 0.5)
		(connect_pads
			(clearance 0)
		)
		(min_thickness 0.25)
		(keepout
			(tracks not_allowed)
			(vias allowed)
			(pads allowed)
			(copperpour not_allowed)
			(footprints allowed)
		)
		(placement
			(enabled no)
			(sheetname "")
		)
		(fill
			(thermal_gap 0.5)
			(thermal_bridge_width 0.5)
			(island_removal_mode 0)
		)
		(polygon
			(pts
				(arc
					(start 377.4059 -351.230438)
					(mid 377.0249 -351.611438)
					(end 377.4059 -351.992438)
				)
				(arc
					(start 378.2695 -351.992438)
					(mid 378.6505 -351.611438)
					(end 378.2695 -351.230438)
				)
			)
		)
	)
	(zone
		(layers "F.Cu" "B.Cu" "In1.Cu" "In2.Cu" "In3.Cu" "In4.Cu" "In5.Cu" "In6.Cu"
			"In7.Cu" "In8.Cu" "In9.Cu" "In10.Cu" "In11.Cu" "In12.Cu" "In13.Cu" "In14.Cu"
			"In15.Cu" "In16.Cu"
		)
		(hatch none 0.5)
		(connect_pads
			(clearance 0)
		)
		(min_thickness 0.25)
		(keepout
			(tracks not_allowed)
			(vias allowed)
			(pads allowed)
			(copperpour not_allowed)
			(footprints allowed)
		)
		(placement
			(enabled no)
			(sheetname "")
		)
		(fill
			(thermal_gap 0.5)
			(thermal_bridge_width 0.5)
			(island_removal_mode 0)
		)
		(polygon
			(pts
				(arc
					(start 292.768782 -354.351082)
					(mid 292.387782 -354.732082)
					(end 292.768782 -355.113082)
				)
				(arc
					(start 293.632382 -355.113082)
					(mid 294.013382 -354.732082)
					(end 293.632382 -354.351082)
				)
			)
		)
	)
	(zone
		(layers "F.Cu" "B.Cu" "In1.Cu" "In2.Cu" "In3.Cu" "In4.Cu" "In5.Cu" "In6.Cu"
			"In7.Cu" "In8.Cu" "In9.Cu" "In10.Cu" "In11.Cu" "In12.Cu" "In13.Cu" "In14.Cu"
			"In15.Cu" "In16.Cu"
		)
		(hatch none 0.5)
		(connect_pads
			(clearance 0)
		)
		(min_thickness 0.25)
		(keepout
			(tracks not_allowed)
			(vias allowed)
			(pads allowed)
			(copperpour not_allowed)
			(footprints allowed)
		)
		(placement
			(enabled no)
			(sheetname "")
		)
		(fill
			(thermal_gap 0.5)
			(thermal_bridge_width 0.5)
			(island_removal_mode 0)
		)
		(polygon
			(pts
				(arc
					(start 399.16862 -342.058498)
					(mid 398.78762 -342.439498)
					(end 399.16862 -342.820498)
				)
				(arc
					(start 400.03222 -342.820498)
					(mid 400.41322 -342.439498)
					(end 400.03222 -342.058498)
				)
			)
		)
	)
	(zone
		(layers "F.Cu" "B.Cu" "In1.Cu" "In2.Cu" "In3.Cu" "In4.Cu" "In5.Cu" "In6.Cu"
			"In7.Cu" "In8.Cu" "In9.Cu" "In10.Cu" "In11.Cu" "In12.Cu" "In13.Cu" "In14.Cu"
			"In15.Cu" "In16.Cu"
		)
		(hatch none 0.5)
		(connect_pads
			(clearance 0)
		)
		(min_thickness 0.25)
		(keepout
			(tracks not_allowed)
			(vias allowed)
			(pads allowed)
			(copperpour not_allowed)
			(footprints allowed)
		)
		(placement
			(enabled no)
			(sheetname "")
		)
		(fill
			(thermal_gap 0.5)
			(thermal_bridge_width 0.5)
			(island_removal_mode 0)
		)
		(polygon
			(pts
				(arc
					(start 73.490074 -34.520886)
					(mid 73.947274 -34.978086)
					(end 74.404474 -34.520886)
				)
				(arc
					(start 74.404474 -33.657286)
					(mid 73.947274 -33.200086)
					(end 73.490074 -33.657286)
				)
			)
		)
	)
	(zone
		(layers "F.Cu" "B.Cu" "In1.Cu" "In2.Cu" "In3.Cu" "In4.Cu" "In5.Cu" "In6.Cu"
			"In7.Cu" "In8.Cu" "In9.Cu" "In10.Cu" "In11.Cu" "In12.Cu" "In13.Cu" "In14.Cu"
			"In15.Cu" "In16.Cu"
		)
		(hatch none 0.5)
		(connect_pads
			(clearance 0)
		)
		(min_thickness 0.25)
		(keepout
			(tracks not_allowed)
			(vias allowed)
			(pads allowed)
			(copperpour not_allowed)
			(footprints allowed)
		)
		(placement
			(enabled no)
			(sheetname "")
		)
		(fill
			(thermal_gap 0.5)
			(thermal_bridge_width 0.5)
			(island_removal_mode 0)
		)
		(polygon
			(pts
				(arc
					(start 383.881122 -373.828818)
					(mid 383.896001 -373.792897)
					(end 383.931922 -373.778018)
				)
				(arc
					(start 384.648202 -373.778018)
					(mid 384.684123 -373.792897)
					(end 384.699002 -373.828818)
				)
				(arc
					(start 384.699002 -376.25147)
					(mid 384.684123 -376.287391)
					(end 384.648202 -376.30227)
				)
				(arc
					(start 383.931922 -376.30227)
					(mid 383.896001 -376.287391)
					(end 383.881122 -376.25147)
				)
			)
		)
	)
	(zone
		(layers "F.Cu" "B.Cu" "In1.Cu" "In2.Cu" "In3.Cu" "In4.Cu" "In5.Cu" "In6.Cu"
			"In7.Cu" "In8.Cu" "In9.Cu" "In10.Cu" "In11.Cu" "In12.Cu" "In13.Cu" "In14.Cu"
			"In15.Cu" "In16.Cu"
		)
		(hatch none 0.5)
		(connect_pads
			(clearance 0)
		)
		(min_thickness 0.25)
		(keepout
			(tracks not_allowed)
			(vias allowed)
			(pads allowed)
			(copperpour not_allowed)
			(footprints allowed)
		)
		(placement
			(enabled no)
			(sheetname "")
		)
		(fill
			(thermal_gap 0.5)
			(thermal_bridge_width 0.5)
			(island_removal_mode 0)
		)
		(polygon
			(pts
				(arc
					(start 266.868402 -134.897876)
					(mid 267.325602 -135.355076)
					(end 267.782802 -134.897876)
				)
				(arc
					(start 267.782802 -134.034276)
					(mid 267.325602 -133.577076)
					(end 266.868402 -134.034276)
				)
			)
		)
	)
	(zone
		(layers "F.Cu" "B.Cu" "In1.Cu" "In2.Cu" "In3.Cu" "In4.Cu" "In5.Cu" "In6.Cu"
			"In7.Cu" "In8.Cu" "In9.Cu" "In10.Cu" "In11.Cu" "In12.Cu" "In13.Cu" "In14.Cu"
			"In15.Cu" "In16.Cu"
		)
		(hatch none 0.5)
		(connect_pads
			(clearance 0)
		)
		(min_thickness 0.25)
		(keepout
			(tracks not_allowed)
			(vias allowed)
			(pads allowed)
			(copperpour not_allowed)
			(footprints allowed)
		)
		(placement
			(enabled no)
			(sheetname "")
		)
		(fill
			(thermal_gap 0.5)
			(thermal_bridge_width 0.5)
			(island_removal_mode 0)
		)
		(polygon
			(pts
				(arc
					(start 385.765294 8.574532)
					(mid 385.384294 8.955532)
					(end 385.003294 8.574532)
				)
				(arc
					(start 385.003294 7.710932)
					(mid 385.384294 7.329932)
					(end 385.765294 7.710932)
				)
			)
		)
	)
	(zone
		(layers "F.Cu" "B.Cu" "In1.Cu" "In2.Cu" "In3.Cu" "In4.Cu" "In5.Cu" "In6.Cu"
			"In7.Cu" "In8.Cu" "In9.Cu" "In10.Cu" "In11.Cu" "In12.Cu" "In13.Cu" "In14.Cu"
			"In15.Cu" "In16.Cu"
		)
		(hatch none 0.5)
		(connect_pads
			(clearance 0)
		)
		(min_thickness 0.25)
		(keepout
			(tracks not_allowed)
			(vias allowed)
			(pads allowed)
			(copperpour not_allowed)
			(footprints allowed)
		)
		(placement
			(enabled no)
			(sheetname "")
		)
		(fill
			(thermal_gap 0.5)
			(thermal_bridge_width 0.5)
			(island_removal_mode 0)
		)
		(polygon
			(pts
				(arc
					(start 280.332942 -345.084146)
					(mid 279.951942 -345.465146)
					(end 280.332942 -345.846146)
				)
				(arc
					(start 281.196542 -345.846146)
					(mid 281.577542 -345.465146)
					(end 281.196542 -345.084146)
				)
			)
		)
	)
	(zone
		(layers "F.Cu" "B.Cu" "In1.Cu" "In2.Cu" "In3.Cu" "In4.Cu" "In5.Cu" "In6.Cu"
			"In7.Cu" "In8.Cu" "In9.Cu" "In10.Cu" "In11.Cu" "In12.Cu" "In13.Cu" "In14.Cu"
			"In15.Cu" "In16.Cu"
		)
		(hatch none 0.5)
		(connect_pads
			(clearance 0)
		)
		(min_thickness 0.25)
		(keepout
			(tracks not_allowed)
			(vias allowed)
			(pads allowed)
			(copperpour not_allowed)
			(footprints allowed)
		)
		(placement
			(enabled no)
			(sheetname "")
		)
		(fill
			(thermal_gap 0.5)
			(thermal_bridge_width 0.5)
			(island_removal_mode 0)
		)
		(polygon
			(pts
				(arc
					(start 379.48108 -403.728682)
					(mid 379.495959 -403.692761)
					(end 379.53188 -403.677882)
				)
				(arc
					(start 380.24816 -403.677882)
					(mid 380.284081 -403.692761)
					(end 380.29896 -403.728682)
				)
				(arc
					(start 380.29896 -406.151334)
					(mid 380.284081 -406.187255)
					(end 380.24816 -406.202134)
				)
				(arc
					(start 379.53188 -406.202134)
					(mid 379.495959 -406.187255)
					(end 379.48108 -406.151334)
				)
			)
		)
	)
	(zone
		(layers "F.Cu" "B.Cu" "In1.Cu" "In2.Cu" "In3.Cu" "In4.Cu" "In5.Cu" "In6.Cu"
			"In7.Cu" "In8.Cu" "In9.Cu" "In10.Cu" "In11.Cu" "In12.Cu" "In13.Cu" "In14.Cu"
			"In15.Cu" "In16.Cu"
		)
		(hatch none 0.5)
		(connect_pads
			(clearance 0)
		)
		(min_thickness 0.25)
		(keepout
			(tracks not_allowed)
			(vias allowed)
			(pads allowed)
			(copperpour not_allowed)
			(footprints allowed)
		)
		(placement
			(enabled no)
			(sheetname "")
		)
		(fill
			(thermal_gap 0.5)
			(thermal_bridge_width 0.5)
			(island_removal_mode 0)
		)
		(polygon
			(pts
				(arc
					(start 197.17512 -147.079208)
					(mid 197.63232 -147.536408)
					(end 198.08952 -147.079208)
				)
				(arc
					(start 198.08952 -146.215608)
					(mid 197.63232 -145.758408)
					(end 197.17512 -146.215608)
				)
			)
		)
	)
	(zone
		(layers "F.Cu" "B.Cu" "In1.Cu" "In2.Cu" "In3.Cu" "In4.Cu" "In5.Cu" "In6.Cu"
			"In7.Cu" "In8.Cu" "In9.Cu" "In10.Cu" "In11.Cu" "In12.Cu" "In13.Cu" "In14.Cu"
			"In15.Cu" "In16.Cu"
		)
		(hatch none 0.5)
		(connect_pads
			(clearance 0)
		)
		(min_thickness 0.25)
		(keepout
			(tracks not_allowed)
			(vias allowed)
			(pads allowed)
			(copperpour not_allowed)
			(footprints allowed)
		)
		(placement
			(enabled no)
			(sheetname "")
		)
		(fill
			(thermal_gap 0.5)
			(thermal_bridge_width 0.5)
			(island_removal_mode 0)
		)
		(polygon
			(pts
				(arc
					(start 137.590276 -30.92069)
					(mid 138.047476 -31.37789)
					(end 138.504676 -30.92069)
				)
				(arc
					(start 138.504676 -30.05709)
					(mid 138.047476 -29.59989)
					(end 137.590276 -30.05709)
				)
			)
		)
	)
	(zone
		(layers "F.Cu" "B.Cu" "In1.Cu" "In2.Cu" "In3.Cu" "In4.Cu" "In5.Cu" "In6.Cu"
			"In7.Cu" "In8.Cu" "In9.Cu" "In10.Cu" "In11.Cu" "In12.Cu" "In13.Cu" "In14.Cu"
			"In15.Cu" "In16.Cu"
		)
		(hatch none 0.5)
		(connect_pads
			(clearance 0)
		)
		(min_thickness 0.25)
		(keepout
			(tracks not_allowed)
			(vias allowed)
			(pads allowed)
			(copperpour not_allowed)
			(footprints allowed)
		)
		(placement
			(enabled no)
			(sheetname "")
		)
		(fill
			(thermal_gap 0.5)
			(thermal_bridge_width 0.5)
			(island_removal_mode 0)
		)
		(polygon
			(pts
				(arc
					(start 390.481058 -400.92884)
					(mid 390.495937 -400.892919)
					(end 390.531858 -400.87804)
				)
				(arc
					(start 391.248138 -400.87804)
					(mid 391.284059 -400.892919)
					(end 391.298938 -400.92884)
				)
				(arc
					(start 391.298938 -403.351492)
					(mid 391.284059 -403.387413)
					(end 391.248138 -403.402292)
				)
				(arc
					(start 390.531858 -403.402292)
					(mid 390.495937 -403.387413)
					(end 390.481058 -403.351492)
				)
			)
		)
	)
	(zone
		(layers "F.Cu" "B.Cu" "In1.Cu" "In2.Cu" "In3.Cu" "In4.Cu" "In5.Cu" "In6.Cu"
			"In7.Cu" "In8.Cu" "In9.Cu" "In10.Cu" "In11.Cu" "In12.Cu" "In13.Cu" "In14.Cu"
			"In15.Cu" "In16.Cu"
		)
		(hatch none 0.5)
		(connect_pads
			(clearance 0)
		)
		(min_thickness 0.25)
		(keepout
			(tracks not_allowed)
			(vias allowed)
			(pads allowed)
			(copperpour not_allowed)
			(footprints allowed)
		)
		(placement
			(enabled no)
			(sheetname "")
		)
		(fill
			(thermal_gap 0.5)
			(thermal_bridge_width 0.5)
			(island_removal_mode 0)
		)
		(polygon
			(pts
				(arc
					(start 316.953138 -30.922468)
					(mid 317.410338 -31.379668)
					(end 317.867538 -30.922468)
				)
				(arc
					(start 317.867538 -30.058868)
					(mid 317.410338 -29.601668)
					(end 316.953138 -30.058868)
				)
			)
		)
	)
	(zone
		(layers "F.Cu" "B.Cu" "In1.Cu" "In2.Cu" "In3.Cu" "In4.Cu" "In5.Cu" "In6.Cu"
			"In7.Cu" "In8.Cu" "In9.Cu" "In10.Cu" "In11.Cu" "In12.Cu" "In13.Cu" "In14.Cu"
			"In15.Cu" "In16.Cu"
		)
		(hatch none 0.5)
		(connect_pads
			(clearance 0)
		)
		(min_thickness 0.25)
		(keepout
			(tracks not_allowed)
			(vias allowed)
			(pads allowed)
			(copperpour not_allowed)
			(footprints allowed)
		)
		(placement
			(enabled no)
			(sheetname "")
		)
		(fill
			(thermal_gap 0.5)
			(thermal_bridge_width 0.5)
			(island_removal_mode 0)
		)
		(polygon
			(pts
				(arc
					(start 38.501066 -404.828756)
					(mid 38.515945 -404.792835)
					(end 38.551866 -404.777956)
				)
				(arc
					(start 39.268146 -404.777956)
					(mid 39.304067 -404.792835)
					(end 39.318946 -404.828756)
				)
				(arc
					(start 39.318946 -407.251408)
					(mid 39.304067 -407.287329)
					(end 39.268146 -407.302208)
				)
				(arc
					(start 38.551866 -407.302208)
					(mid 38.515945 -407.287329)
					(end 38.501066 -407.251408)
				)
			)
		)
	)
	(zone
		(layers "F.Cu" "B.Cu" "In1.Cu" "In2.Cu" "In3.Cu" "In4.Cu" "In5.Cu" "In6.Cu"
			"In7.Cu" "In8.Cu" "In9.Cu" "In10.Cu" "In11.Cu" "In12.Cu" "In13.Cu" "In14.Cu"
			"In15.Cu" "In16.Cu"
		)
		(hatch none 0.5)
		(connect_pads
			(clearance 0)
		)
		(min_thickness 0.25)
		(keepout
			(tracks not_allowed)
			(vias allowed)
			(pads allowed)
			(copperpour not_allowed)
			(footprints allowed)
		)
		(placement
			(enabled no)
			(sheetname "")
		)
		(fill
			(thermal_gap 0.5)
			(thermal_bridge_width 0.5)
			(island_removal_mode 0)
		)
		(polygon
			(pts
				(arc
					(start 168.800018 -135.83285)
					(mid 168.342818 -135.37565)
					(end 167.885618 -135.83285)
				)
				(arc
					(start 167.885618 -136.69645)
					(mid 168.342818 -137.15365)
					(end 168.800018 -136.69645)
				)
			)
		)
	)
	(zone
		(layers "F.Cu" "B.Cu" "In1.Cu" "In2.Cu" "In3.Cu" "In4.Cu" "In5.Cu" "In6.Cu"
			"In7.Cu" "In8.Cu" "In9.Cu" "In10.Cu" "In11.Cu" "In12.Cu" "In13.Cu" "In14.Cu"
			"In15.Cu" "In16.Cu"
		)
		(hatch none 0.5)
		(connect_pads
			(clearance 0)
		)
		(min_thickness 0.25)
		(keepout
			(tracks not_allowed)
			(vias allowed)
			(pads allowed)
			(copperpour not_allowed)
			(footprints allowed)
		)
		(placement
			(enabled no)
			(sheetname "")
		)
		(fill
			(thermal_gap 0.5)
			(thermal_bridge_width 0.5)
			(island_removal_mode 0)
		)
		(polygon
			(pts
				(arc
					(start 163.90112 -369.928902)
					(mid 163.915999 -369.892981)
					(end 163.95192 -369.878102)
				)
				(arc
					(start 164.6682 -369.878102)
					(mid 164.704121 -369.892981)
					(end 164.719 -369.928902)
				)
				(arc
					(start 164.719 -372.351554)
					(mid 164.704121 -372.387475)
					(end 164.6682 -372.402354)
				)
				(arc
					(start 163.95192 -372.402354)
					(mid 163.915999 -372.387475)
					(end 163.90112 -372.351554)
				)
			)
		)
	)
	(zone
		(layers "F.Cu" "B.Cu" "In1.Cu" "In2.Cu" "In3.Cu" "In4.Cu" "In5.Cu" "In6.Cu"
			"In7.Cu" "In8.Cu" "In9.Cu" "In10.Cu" "In11.Cu" "In12.Cu" "In13.Cu" "In14.Cu"
			"In15.Cu" "In16.Cu"
		)
		(hatch none 0.5)
		(connect_pads
			(clearance 0)
		)
		(min_thickness 0.25)
		(keepout
			(tracks not_allowed)
			(vias allowed)
			(pads allowed)
			(copperpour not_allowed)
			(footprints allowed)
		)
		(placement
			(enabled no)
			(sheetname "")
		)
		(fill
			(thermal_gap 0.5)
			(thermal_bridge_width 0.5)
			(island_removal_mode 0)
		)
		(polygon
			(pts
				(arc
					(start 136.733788 -348.20479)
					(mid 136.352788 -348.58579)
					(end 136.733788 -348.96679)
				)
				(arc
					(start 137.597388 -348.96679)
					(mid 137.978388 -348.58579)
					(end 137.597388 -348.20479)
				)
			)
		)
	)
	(zone
		(layers "F.Cu" "B.Cu" "In1.Cu" "In2.Cu" "In3.Cu" "In4.Cu" "In5.Cu" "In6.Cu"
			"In7.Cu" "In8.Cu" "In9.Cu" "In10.Cu" "In11.Cu" "In12.Cu" "In13.Cu" "In14.Cu"
			"In15.Cu" "In16.Cu"
		)
		(hatch none 0.5)
		(connect_pads
			(clearance 0)
		)
		(min_thickness 0.25)
		(keepout
			(tracks not_allowed)
			(vias allowed)
			(pads allowed)
			(copperpour not_allowed)
			(footprints allowed)
		)
		(placement
			(enabled no)
			(sheetname "")
		)
		(fill
			(thermal_gap 0.5)
			(thermal_bridge_width 0.5)
			(island_removal_mode 0)
		)
		(polygon
			(pts
				(arc
					(start 374.29694 -357.37673)
					(mid 373.91594 -357.75773)
					(end 374.29694 -358.13873)
				)
				(arc
					(start 375.16054 -358.13873)
					(mid 375.54154 -357.75773)
					(end 375.16054 -357.37673)
				)
			)
		)
	)
	(zone
		(layers "F.Cu" "B.Cu" "In1.Cu" "In2.Cu" "In3.Cu" "In4.Cu" "In5.Cu" "In6.Cu"
			"In7.Cu" "In8.Cu" "In9.Cu" "In10.Cu" "In11.Cu" "In12.Cu" "In13.Cu" "In14.Cu"
			"In15.Cu" "In16.Cu"
		)
		(hatch none 0.5)
		(connect_pads
			(clearance 0)
		)
		(min_thickness 0.25)
		(keepout
			(tracks not_allowed)
			(vias allowed)
			(pads allowed)
			(copperpour not_allowed)
			(footprints allowed)
		)
		(placement
			(enabled no)
			(sheetname "")
		)
		(fill
			(thermal_gap 0.5)
			(thermal_bridge_width 0.5)
			(island_removal_mode 0)
		)
		(polygon
			(pts
				(arc
					(start 383.881122 -377.728734)
					(mid 383.896001 -377.692813)
					(end 383.931922 -377.677934)
				)
				(arc
					(start 384.648202 -377.677934)
					(mid 384.684123 -377.692813)
					(end 384.699002 -377.728734)
				)
				(arc
					(start 384.699002 -380.151386)
					(mid 384.684123 -380.187307)
					(end 384.648202 -380.202186)
				)
				(arc
					(start 383.931922 -380.202186)
					(mid 383.896001 -380.187307)
					(end 383.881122 -380.151386)
				)
			)
		)
	)
	(zone
		(layers "F.Cu" "B.Cu" "In1.Cu" "In2.Cu" "In3.Cu" "In4.Cu" "In5.Cu" "In6.Cu"
			"In7.Cu" "In8.Cu" "In9.Cu" "In10.Cu" "In11.Cu" "In12.Cu" "In13.Cu" "In14.Cu"
			"In15.Cu" "In16.Cu"
		)
		(hatch none 0.5)
		(connect_pads
			(clearance 0)
		)
		(min_thickness 0.25)
		(keepout
			(tracks not_allowed)
			(vias allowed)
			(pads allowed)
			(copperpour not_allowed)
			(footprints allowed)
		)
		(placement
			(enabled no)
			(sheetname "")
		)
		(fill
			(thermal_gap 0.5)
			(thermal_bridge_width 0.5)
			(island_removal_mode 0)
		)
		(polygon
			(pts
				(arc
					(start 262.608314 -74.801222)
					(mid 262.151114 -75.258422)
					(end 262.608314 -75.715622)
				)
				(arc
					(start 263.471914 -75.715622)
					(mid 263.929114 -75.258422)
					(end 263.471914 -74.801222)
				)
			)
		)
	)
	(zone
		(layers "F.Cu" "B.Cu" "In1.Cu" "In2.Cu" "In3.Cu" "In4.Cu" "In5.Cu" "In6.Cu"
			"In7.Cu" "In8.Cu" "In9.Cu" "In10.Cu" "In11.Cu" "In12.Cu" "In13.Cu" "In14.Cu"
			"In15.Cu" "In16.Cu"
		)
		(hatch none 0.5)
		(connect_pads
			(clearance 0)
		)
		(min_thickness 0.25)
		(keepout
			(tracks not_allowed)
			(vias allowed)
			(pads allowed)
			(copperpour not_allowed)
			(footprints allowed)
		)
		(placement
			(enabled no)
			(sheetname "")
		)
		(fill
			(thermal_gap 0.5)
			(thermal_bridge_width 0.5)
			(island_removal_mode 0)
		)
		(polygon
			(pts
				(arc
					(start 441.42787 18.460212)
					(mid 441.04687 18.841212)
					(end 440.66587 18.460212)
				)
				(arc
					(start 440.66587 17.596612)
					(mid 441.04687 17.215612)
					(end 441.42787 17.596612)
				)
			)
		)
	)
	(zone
		(layers "F.Cu" "B.Cu" "In1.Cu" "In2.Cu" "In3.Cu" "In4.Cu" "In5.Cu" "In6.Cu"
			"In7.Cu" "In8.Cu" "In9.Cu" "In10.Cu" "In11.Cu" "In12.Cu" "In13.Cu" "In14.Cu"
			"In15.Cu" "In16.Cu"
		)
		(hatch none 0.5)
		(connect_pads
			(clearance 0)
		)
		(min_thickness 0.25)
		(keepout
			(tracks not_allowed)
			(vias allowed)
			(pads allowed)
			(copperpour not_allowed)
			(footprints allowed)
		)
		(placement
			(enabled no)
			(sheetname "")
		)
		(fill
			(thermal_gap 0.5)
			(thermal_bridge_width 0.5)
			(island_removal_mode 0)
		)
		(polygon
			(pts
				(arc
					(start 287.08096 -369.928902)
					(mid 287.095839 -369.892981)
					(end 287.13176 -369.878102)
				)
				(arc
					(start 287.84804 -369.878102)
					(mid 287.883961 -369.892981)
					(end 287.89884 -369.928902)
				)
				(arc
					(start 287.89884 -372.351554)
					(mid 287.883961 -372.387475)
					(end 287.84804 -372.402354)
				)
				(arc
					(start 287.13176 -372.402354)
					(mid 287.095839 -372.387475)
					(end 287.08096 -372.351554)
				)
			)
		)
	)
	(zone
		(layers "F.Cu" "B.Cu" "In1.Cu" "In2.Cu" "In3.Cu" "In4.Cu" "In5.Cu" "In6.Cu"
			"In7.Cu" "In8.Cu" "In9.Cu" "In10.Cu" "In11.Cu" "In12.Cu" "In13.Cu" "In14.Cu"
			"In15.Cu" "In16.Cu"
		)
		(hatch none 0.5)
		(connect_pads
			(clearance 0)
		)
		(min_thickness 0.25)
		(keepout
			(tracks not_allowed)
			(vias allowed)
			(pads allowed)
			(copperpour not_allowed)
			(footprints allowed)
		)
		(placement
			(enabled no)
			(sheetname "")
		)
		(fill
			(thermal_gap 0.5)
			(thermal_bridge_width 0.5)
			(island_removal_mode 0)
		)
		(polygon
			(pts
				(arc
					(start 427.881034 -407.628852)
					(mid 427.895913 -407.592931)
					(end 427.931834 -407.578052)
				)
				(arc
					(start 428.648114 -407.578052)
					(mid 428.684035 -407.592931)
					(end 428.698914 -407.628852)
				)
				(arc
					(start 428.698914 -410.051504)
					(mid 428.684035 -410.087425)
					(end 428.648114 -410.102304)
				)
				(arc
					(start 427.931834 -410.102304)
					(mid 427.895913 -410.087425)
					(end 427.881034 -410.051504)
				)
			)
		)
	)
	(zone
		(layers "F.Cu" "B.Cu" "In1.Cu" "In2.Cu" "In3.Cu" "In4.Cu" "In5.Cu" "In6.Cu"
			"In7.Cu" "In8.Cu" "In9.Cu" "In10.Cu" "In11.Cu" "In12.Cu" "In13.Cu" "In14.Cu"
			"In15.Cu" "In16.Cu"
		)
		(hatch none 0.5)
		(connect_pads
			(clearance 0)
		)
		(min_thickness 0.25)
		(keepout
			(tracks not_allowed)
			(vias allowed)
			(pads allowed)
			(copperpour not_allowed)
			(footprints allowed)
		)
		(placement
			(enabled no)
			(sheetname "")
		)
		(fill
			(thermal_gap 0.5)
			(thermal_bridge_width 0.5)
			(island_removal_mode 0)
		)
		(polygon
			(pts
				(arc
					(start 286.550862 -342.058498)
					(mid 286.169862 -342.439498)
					(end 286.550862 -342.820498)
				)
				(arc
					(start 287.414462 -342.820498)
					(mid 287.795462 -342.439498)
					(end 287.414462 -342.058498)
				)
			)
		)
	)
	(zone
		(layers "F.Cu" "B.Cu" "In1.Cu" "In2.Cu" "In3.Cu" "In4.Cu" "In5.Cu" "In6.Cu"
			"In7.Cu" "In8.Cu" "In9.Cu" "In10.Cu" "In11.Cu" "In12.Cu" "In13.Cu" "In14.Cu"
			"In15.Cu" "In16.Cu"
		)
		(hatch none 0.5)
		(connect_pads
			(clearance 0)
		)
		(min_thickness 0.25)
		(keepout
			(tracks not_allowed)
			(vias allowed)
			(pads allowed)
			(copperpour not_allowed)
			(footprints allowed)
		)
		(placement
			(enabled no)
			(sheetname "")
		)
		(fill
			(thermal_gap 0.5)
			(thermal_bridge_width 0.5)
			(island_removal_mode 0)
		)
		(polygon
			(pts
				(arc
					(start 415.513012 -351.230438)
					(mid 415.132012 -351.611438)
					(end 415.513012 -351.992438)
				)
				(arc
					(start 416.376612 -351.992438)
					(mid 416.757612 -351.611438)
					(end 416.376612 -351.230438)
				)
			)
		)
	)
	(zone
		(layers "F.Cu" "B.Cu" "In1.Cu" "In2.Cu" "In3.Cu" "In4.Cu" "In5.Cu" "In6.Cu"
			"In7.Cu" "In8.Cu" "In9.Cu" "In10.Cu" "In11.Cu" "In12.Cu" "In13.Cu" "In14.Cu"
			"In15.Cu" "In16.Cu"
		)
		(hatch none 0.5)
		(connect_pads
			(clearance 0)
		)
		(min_thickness 0.25)
		(keepout
			(tracks not_allowed)
			(vias allowed)
			(pads allowed)
			(copperpour not_allowed)
			(footprints allowed)
		)
		(placement
			(enabled no)
			(sheetname "")
		)
		(fill
			(thermal_gap 0.5)
			(thermal_bridge_width 0.5)
			(island_removal_mode 0)
		)
		(polygon
			(pts
				(arc
					(start 27.501088 -403.728682)
					(mid 27.515967 -403.692761)
					(end 27.551888 -403.677882)
				)
				(arc
					(start 28.268168 -403.677882)
					(mid 28.304089 -403.692761)
					(end 28.318968 -403.728682)
				)
				(arc
					(start 28.318968 -406.151334)
					(mid 28.304089 -406.187255)
					(end 28.268168 -406.202134)
				)
				(arc
					(start 27.551888 -406.202134)
					(mid 27.515967 -406.187255)
					(end 27.501088 -406.151334)
				)
			)
		)
	)
	(zone
		(layers "F.Cu" "B.Cu" "In1.Cu" "In2.Cu" "In3.Cu" "In4.Cu" "In5.Cu" "In6.Cu"
			"In7.Cu" "In8.Cu" "In9.Cu" "In10.Cu" "In11.Cu" "In12.Cu" "In13.Cu" "In14.Cu"
			"In15.Cu" "In16.Cu"
		)
		(hatch none 0.5)
		(connect_pads
			(clearance 0)
		)
		(min_thickness 0.25)
		(keepout
			(tracks not_allowed)
			(vias allowed)
			(pads allowed)
			(copperpour not_allowed)
			(footprints allowed)
		)
		(placement
			(enabled no)
			(sheetname "")
		)
		(fill
			(thermal_gap 0.5)
			(thermal_bridge_width 0.5)
			(island_removal_mode 0)
		)
		(polygon
			(pts
				(arc
					(start 118.080028 -354.351082)
					(mid 117.699028 -354.732082)
					(end 118.080028 -355.113082)
				)
				(arc
					(start 118.943628 -355.113082)
					(mid 119.324628 -354.732082)
					(end 118.943628 -354.351082)
				)
			)
		)
	)
	(zone
		(layers "F.Cu" "B.Cu" "In1.Cu" "In2.Cu" "In3.Cu" "In4.Cu" "In5.Cu" "In6.Cu"
			"In7.Cu" "In8.Cu" "In9.Cu" "In10.Cu" "In11.Cu" "In12.Cu" "In13.Cu" "In14.Cu"
			"In15.Cu" "In16.Cu"
		)
		(hatch none 0.5)
		(connect_pads
			(clearance 0)
		)
		(min_thickness 0.25)
		(keepout
			(tracks not_allowed)
			(vias allowed)
			(pads allowed)
			(copperpour not_allowed)
			(footprints allowed)
		)
		(placement
			(enabled no)
			(sheetname "")
		)
		(fill
			(thermal_gap 0.5)
			(thermal_bridge_width 0.5)
			(island_removal_mode 0)
		)
		(polygon
			(pts
				(arc
					(start 335.481168 -395.92885)
					(mid 335.496047 -395.892929)
					(end 335.531968 -395.87805)
				)
				(arc
					(start 336.248248 -395.87805)
					(mid 336.284169 -395.892929)
					(end 336.299048 -395.92885)
				)
				(arc
					(start 336.299048 -398.351502)
					(mid 336.284169 -398.387423)
					(end 336.248248 -398.402302)
				)
				(arc
					(start 335.531968 -398.402302)
					(mid 335.496047 -398.387423)
					(end 335.481168 -398.351502)
				)
			)
		)
	)
	(zone
		(layers "F.Cu" "B.Cu" "In1.Cu" "In2.Cu" "In3.Cu" "In4.Cu" "In5.Cu" "In6.Cu"
			"In7.Cu" "In8.Cu" "In9.Cu" "In10.Cu" "In11.Cu" "In12.Cu" "In13.Cu" "In14.Cu"
			"In15.Cu" "In16.Cu"
		)
		(hatch none 0.5)
		(connect_pads
			(clearance 0)
		)
		(min_thickness 0.25)
		(keepout
			(tracks not_allowed)
			(vias allowed)
			(pads allowed)
			(copperpour not_allowed)
			(footprints allowed)
		)
		(placement
			(enabled no)
			(sheetname "")
		)
		(fill
			(thermal_gap 0.5)
			(thermal_bridge_width 0.5)
			(island_removal_mode 0)
		)
		(polygon
			(pts
				(arc
					(start 303.047908 -29.114242)
					(mid 303.505108 -29.571442)
					(end 303.962308 -29.114242)
				)
				(arc
					(start 303.962308 -28.250642)
					(mid 303.505108 -27.793442)
					(end 303.047908 -28.250642)
				)
			)
		)
	)
	(zone
		(layers "F.Cu" "B.Cu" "In1.Cu" "In2.Cu" "In3.Cu" "In4.Cu" "In5.Cu" "In6.Cu"
			"In7.Cu" "In8.Cu" "In9.Cu" "In10.Cu" "In11.Cu" "In12.Cu" "In13.Cu" "In14.Cu"
			"In15.Cu" "In16.Cu"
		)
		(hatch none 0.5)
		(connect_pads
			(clearance 0)
		)
		(min_thickness 0.25)
		(keepout
			(tracks not_allowed)
			(vias allowed)
			(pads allowed)
			(copperpour not_allowed)
			(footprints allowed)
		)
		(placement
			(enabled no)
			(sheetname "")
		)
		(fill
			(thermal_gap 0.5)
			(thermal_bridge_width 0.5)
			(island_removal_mode 0)
		)
		(polygon
			(pts
				(arc
					(start 193.275712 -342.058498)
					(mid 192.894712 -342.439498)
					(end 193.275712 -342.820498)
				)
				(arc
					(start 194.139312 -342.820498)
					(mid 194.520312 -342.439498)
					(end 194.139312 -342.058498)
				)
			)
		)
	)
	(zone
		(layers "F.Cu" "B.Cu" "In1.Cu" "In2.Cu" "In3.Cu" "In4.Cu" "In5.Cu" "In6.Cu"
			"In7.Cu" "In8.Cu" "In9.Cu" "In10.Cu" "In11.Cu" "In12.Cu" "In13.Cu" "In14.Cu"
			"In15.Cu" "In16.Cu"
		)
		(hatch none 0.5)
		(connect_pads
			(clearance 0)
		)
		(min_thickness 0.25)
		(keepout
			(tracks not_allowed)
			(vias allowed)
			(pads allowed)
			(copperpour not_allowed)
			(footprints allowed)
		)
		(placement
			(enabled no)
			(sheetname "")
		)
		(fill
			(thermal_gap 0.5)
			(thermal_bridge_width 0.5)
			(island_removal_mode 0)
		)
		(polygon
			(pts
				(arc
					(start 434.166772 -345.084146)
					(mid 433.785772 -345.465146)
					(end 434.166772 -345.846146)
				)
				(arc
					(start 435.030372 -345.846146)
					(mid 435.411372 -345.465146)
					(end 435.030372 -345.084146)
				)
			)
		)
	)
	(zone
		(layers "F.Cu" "B.Cu" "In1.Cu" "In2.Cu" "In3.Cu" "In4.Cu" "In5.Cu" "In6.Cu"
			"In7.Cu" "In8.Cu" "In9.Cu" "In10.Cu" "In11.Cu" "In12.Cu" "In13.Cu" "In14.Cu"
			"In15.Cu" "In16.Cu"
		)
		(hatch none 0.5)
		(connect_pads
			(clearance 0)
		)
		(min_thickness 0.25)
		(keepout
			(tracks not_allowed)
			(vias allowed)
			(pads allowed)
			(copperpour not_allowed)
			(footprints allowed)
		)
		(placement
			(enabled no)
			(sheetname "")
		)
		(fill
			(thermal_gap 0.5)
			(thermal_bridge_width 0.5)
			(island_removal_mode 0)
		)
		(polygon
			(pts
				(arc
					(start 163.590224 -34.520886)
					(mid 164.047424 -34.978086)
					(end 164.504624 -34.520886)
				)
				(arc
					(start 164.504624 -33.657286)
					(mid 164.047424 -33.200086)
					(end 163.590224 -33.657286)
				)
			)
		)
	)
	(zone
		(layers "F.Cu" "B.Cu" "In1.Cu" "In2.Cu" "In3.Cu" "In4.Cu" "In5.Cu" "In6.Cu"
			"In7.Cu" "In8.Cu" "In9.Cu" "In10.Cu" "In11.Cu" "In12.Cu" "In13.Cu" "In14.Cu"
			"In15.Cu" "In16.Cu"
		)
		(hatch none 0.5)
		(connect_pads
			(clearance 0)
		)
		(min_thickness 0.25)
		(keepout
			(tracks not_allowed)
			(vias allowed)
			(pads allowed)
			(copperpour not_allowed)
			(footprints allowed)
		)
		(placement
			(enabled no)
			(sheetname "")
		)
		(fill
			(thermal_gap 0.5)
			(thermal_bridge_width 0.5)
			(island_removal_mode 0)
		)
		(polygon
			(pts
				(arc
					(start 58.102246 -367.653062)
					(mid 57.721246 -367.272062)
					(end 57.340246 -367.653062)
				)
				(arc
					(start 57.340246 -368.516662)
					(mid 57.721246 -368.897662)
					(end 58.102246 -368.516662)
				)
			)
		)
	)
	(zone
		(layers "F.Cu" "B.Cu" "In1.Cu" "In2.Cu" "In3.Cu" "In4.Cu" "In5.Cu" "In6.Cu"
			"In7.Cu" "In8.Cu" "In9.Cu" "In10.Cu" "In11.Cu" "In12.Cu" "In13.Cu" "In14.Cu"
			"In15.Cu" "In16.Cu"
		)
		(hatch none 0.5)
		(connect_pads
			(clearance 0)
		)
		(min_thickness 0.25)
		(keepout
			(tracks not_allowed)
			(vias allowed)
			(pads allowed)
			(copperpour not_allowed)
			(footprints allowed)
		)
		(placement
			(enabled no)
			(sheetname "")
		)
		(fill
			(thermal_gap 0.5)
			(thermal_bridge_width 0.5)
			(island_removal_mode 0)
		)
		(polygon
			(pts
				(arc
					(start 31.90113 -381.628904)
					(mid 31.916009 -381.592983)
					(end 31.95193 -381.578104)
				)
				(arc
					(start 32.66821 -381.578104)
					(mid 32.704131 -381.592983)
					(end 32.71901 -381.628904)
				)
				(arc
					(start 32.71901 -384.051556)
					(mid 32.704131 -384.087477)
					(end 32.66821 -384.102356)
				)
				(arc
					(start 31.95193 -384.102356)
					(mid 31.916009 -384.087477)
					(end 31.90113 -384.051556)
				)
			)
		)
	)
	(zone
		(layers "F.Cu" "B.Cu" "In1.Cu" "In2.Cu" "In3.Cu" "In4.Cu" "In5.Cu" "In6.Cu"
			"In7.Cu" "In8.Cu" "In9.Cu" "In10.Cu" "In11.Cu" "In12.Cu" "In13.Cu" "In14.Cu"
			"In15.Cu" "In16.Cu"
		)
		(hatch none 0.5)
		(connect_pads
			(clearance 0)
		)
		(min_thickness 0.25)
		(keepout
			(tracks not_allowed)
			(vias allowed)
			(pads allowed)
			(copperpour not_allowed)
			(footprints allowed)
		)
		(placement
			(enabled no)
			(sheetname "")
		)
		(fill
			(thermal_gap 0.5)
			(thermal_bridge_width 0.5)
			(island_removal_mode 0)
		)
		(polygon
			(pts
				(arc
					(start 298.986702 -348.20479)
					(mid 298.605702 -348.58579)
					(end 298.986702 -348.96679)
				)
				(arc
					(start 299.850302 -348.96679)
					(mid 300.231302 -348.58579)
					(end 299.850302 -348.20479)
				)
			)
		)
	)
	(zone
		(layers "F.Cu" "B.Cu" "In1.Cu" "In2.Cu" "In3.Cu" "In4.Cu" "In5.Cu" "In6.Cu"
			"In7.Cu" "In8.Cu" "In9.Cu" "In10.Cu" "In11.Cu" "In12.Cu" "In13.Cu" "In14.Cu"
			"In15.Cu" "In16.Cu"
		)
		(hatch none 0.5)
		(connect_pads
			(clearance 0)
		)
		(min_thickness 0.25)
		(keepout
			(tracks not_allowed)
			(vias allowed)
			(pads allowed)
			(copperpour not_allowed)
			(footprints allowed)
		)
		(placement
			(enabled no)
			(sheetname "")
		)
		(fill
			(thermal_gap 0.5)
			(thermal_bridge_width 0.5)
			(island_removal_mode 0)
		)
		(polygon
			(pts
				(arc
					(start 329.231498 10.225024)
					(mid 329.612498 9.844024)
					(end 329.993498 10.225024)
				)
				(arc
					(start 329.993498 11.088624)
					(mid 329.612498 11.469624)
					(end 329.231498 11.088624)
				)
			)
		)
	)
	(zone
		(layers "F.Cu" "B.Cu" "In1.Cu" "In2.Cu" "In3.Cu" "In4.Cu" "In5.Cu" "In6.Cu"
			"In7.Cu" "In8.Cu" "In9.Cu" "In10.Cu" "In11.Cu" "In12.Cu" "In13.Cu" "In14.Cu"
			"In15.Cu" "In16.Cu"
		)
		(hatch none 0.5)
		(connect_pads
			(clearance 0)
		)
		(min_thickness 0.25)
		(keepout
			(tracks not_allowed)
			(vias allowed)
			(pads allowed)
			(copperpour not_allowed)
			(footprints allowed)
		)
		(placement
			(enabled no)
			(sheetname "")
		)
		(fill
			(thermal_gap 0.5)
			(thermal_bridge_width 0.5)
			(island_removal_mode 0)
		)
		(polygon
			(pts
				(arc
					(start 248.948956 -307.484272)
					(mid 248.186956 -307.484272)
					(end 248.948956 -307.484272)
				)
			)
		)
	)
	(zone
		(layers "F.Cu" "B.Cu" "In1.Cu" "In2.Cu" "In3.Cu" "In4.Cu" "In5.Cu" "In6.Cu"
			"In7.Cu" "In8.Cu" "In9.Cu" "In10.Cu" "In11.Cu" "In12.Cu" "In13.Cu" "In14.Cu"
			"In15.Cu" "In16.Cu"
		)
		(hatch none 0.5)
		(connect_pads
			(clearance 0)
		)
		(min_thickness 0.25)
		(keepout
			(tracks not_allowed)
			(vias allowed)
			(pads allowed)
			(copperpour not_allowed)
			(footprints allowed)
		)
		(placement
			(enabled no)
			(sheetname "")
		)
		(fill
			(thermal_gap 0.5)
			(thermal_bridge_width 0.5)
			(island_removal_mode 0)
		)
		(polygon
			(pts
				(arc
					(start 385.610608 -133.104382)
					(mid 386.067808 -133.561582)
					(end 386.525008 -133.104382)
				)
				(arc
					(start 386.525008 -132.240782)
					(mid 386.067808 -131.783582)
					(end 385.610608 -132.240782)
				)
			)
		)
	)
	(zone
		(layers "F.Cu" "B.Cu" "In1.Cu" "In2.Cu" "In3.Cu" "In4.Cu" "In5.Cu" "In6.Cu"
			"In7.Cu" "In8.Cu" "In9.Cu" "In10.Cu" "In11.Cu" "In12.Cu" "In13.Cu" "In14.Cu"
			"In15.Cu" "In16.Cu"
		)
		(hatch none 0.5)
		(connect_pads
			(clearance 0)
		)
		(min_thickness 0.25)
		(keepout
			(tracks not_allowed)
			(vias allowed)
			(pads allowed)
			(copperpour not_allowed)
			(footprints allowed)
		)
		(placement
			(enabled no)
			(sheetname "")
		)
		(fill
			(thermal_gap 0.5)
			(thermal_bridge_width 0.5)
			(island_removal_mode 0)
		)
		(polygon
			(pts
				(arc
					(start 71.501 -399.828766)
					(mid 71.515879 -399.792845)
					(end 71.5518 -399.777966)
				)
				(arc
					(start 72.26808 -399.777966)
					(mid 72.304001 -399.792845)
					(end 72.31888 -399.828766)
				)
				(arc
					(start 72.31888 -402.251418)
					(mid 72.304001 -402.287339)
					(end 72.26808 -402.302218)
				)
				(arc
					(start 71.5518 -402.302218)
					(mid 71.515879 -402.287339)
					(end 71.501 -402.251418)
				)
			)
		)
	)
	(zone
		(layers "F.Cu" "B.Cu" "In1.Cu" "In2.Cu" "In3.Cu" "In4.Cu" "In5.Cu" "In6.Cu"
			"In7.Cu" "In8.Cu" "In9.Cu" "In10.Cu" "In11.Cu" "In12.Cu" "In13.Cu" "In14.Cu"
			"In15.Cu" "In16.Cu"
		)
		(hatch none 0.5)
		(connect_pads
			(clearance 0)
		)
		(min_thickness 0.25)
		(keepout
			(tracks not_allowed)
			(vias allowed)
			(pads allowed)
			(copperpour not_allowed)
			(footprints allowed)
		)
		(placement
			(enabled no)
			(sheetname "")
		)
		(fill
			(thermal_gap 0.5)
			(thermal_bridge_width 0.5)
			(island_removal_mode 0)
		)
		(polygon
			(pts
				(arc
					(start 168.301162 -399.828766)
					(mid 168.316041 -399.792845)
					(end 168.351962 -399.777966)
				)
				(arc
					(start 169.068242 -399.777966)
					(mid 169.104163 -399.792845)
					(end 169.119042 -399.828766)
				)
				(arc
					(start 169.119042 -402.251418)
					(mid 169.104163 -402.287339)
					(end 169.068242 -402.302218)
				)
				(arc
					(start 168.351962 -402.302218)
					(mid 168.316041 -402.287339)
					(end 168.301162 -402.251418)
				)
			)
		)
	)
	(zone
		(layers "F.Cu" "B.Cu" "In1.Cu" "In2.Cu" "In3.Cu" "In4.Cu" "In5.Cu" "In6.Cu"
			"In7.Cu" "In8.Cu" "In9.Cu" "In10.Cu" "In11.Cu" "In12.Cu" "In13.Cu" "In14.Cu"
			"In15.Cu" "In16.Cu"
		)
		(hatch none 0.5)
		(connect_pads
			(clearance 0)
		)
		(min_thickness 0.25)
		(keepout
			(tracks not_allowed)
			(vias allowed)
			(pads allowed)
			(copperpour not_allowed)
			(footprints allowed)
		)
		(placement
			(enabled no)
			(sheetname "")
		)
		(fill
			(thermal_gap 0.5)
			(thermal_bridge_width 0.5)
			(island_removal_mode 0)
		)
		(polygon
			(pts
				(arc
					(start 89.352882 -351.230438)
					(mid 88.971882 -351.611438)
					(end 89.352882 -351.992438)
				)
				(arc
					(start 90.216482 -351.992438)
					(mid 90.597482 -351.611438)
					(end 90.216482 -351.230438)
				)
			)
		)
	)
	(zone
		(layers "F.Cu" "B.Cu" "In1.Cu" "In2.Cu" "In3.Cu" "In4.Cu" "In5.Cu" "In6.Cu"
			"In7.Cu" "In8.Cu" "In9.Cu" "In10.Cu" "In11.Cu" "In12.Cu" "In13.Cu" "In14.Cu"
			"In15.Cu" "In16.Cu"
		)
		(hatch none 0.5)
		(connect_pads
			(clearance 0)
		)
		(min_thickness 0.25)
		(keepout
			(tracks not_allowed)
			(vias allowed)
			(pads allowed)
			(copperpour not_allowed)
			(footprints allowed)
		)
		(placement
			(enabled no)
			(sheetname "")
		)
		(fill
			(thermal_gap 0.5)
			(thermal_bridge_width 0.5)
			(island_removal_mode 0)
		)
		(polygon
			(pts
				(arc
					(start 295.877742 -345.084146)
					(mid 295.496742 -345.465146)
					(end 295.877742 -345.846146)
				)
				(arc
					(start 296.741342 -345.846146)
					(mid 297.122342 -345.465146)
					(end 296.741342 -345.084146)
				)
			)
		)
	)
	(zone
		(layers "F.Cu" "B.Cu" "In1.Cu" "In2.Cu" "In3.Cu" "In4.Cu" "In5.Cu" "In6.Cu"
			"In7.Cu" "In8.Cu" "In9.Cu" "In10.Cu" "In11.Cu" "In12.Cu" "In13.Cu" "In14.Cu"
			"In15.Cu" "In16.Cu"
		)
		(hatch none 0.5)
		(connect_pads
			(clearance 0)
		)
		(min_thickness 0.25)
		(keepout
			(tracks not_allowed)
			(vias allowed)
			(pads allowed)
			(copperpour not_allowed)
			(footprints allowed)
		)
		(placement
			(enabled no)
			(sheetname "")
		)
		(fill
			(thermal_gap 0.5)
			(thermal_bridge_width 0.5)
			(island_removal_mode 0)
		)
		(polygon
			(pts
				(arc
					(start 122.101102 -408.728672)
					(mid 122.115981 -408.692751)
					(end 122.151902 -408.677872)
				)
				(arc
					(start 122.868182 -408.677872)
					(mid 122.904103 -408.692751)
					(end 122.918982 -408.728672)
				)
				(arc
					(start 122.918982 -411.151324)
					(mid 122.904103 -411.187245)
					(end 122.868182 -411.202124)
				)
				(arc
					(start 122.151902 -411.202124)
					(mid 122.115981 -411.187245)
					(end 122.101102 -411.151324)
				)
			)
		)
	)
	(zone
		(layers "F.Cu" "B.Cu" "In1.Cu" "In2.Cu" "In3.Cu" "In4.Cu" "In5.Cu" "In6.Cu"
			"In7.Cu" "In8.Cu" "In9.Cu" "In10.Cu" "In11.Cu" "In12.Cu" "In13.Cu" "In14.Cu"
			"In15.Cu" "In16.Cu"
		)
		(hatch none 0.5)
		(connect_pads
			(clearance 0)
		)
		(min_thickness 0.25)
		(keepout
			(tracks not_allowed)
			(vias allowed)
			(pads allowed)
			(copperpour not_allowed)
			(footprints allowed)
		)
		(placement
			(enabled no)
			(sheetname "")
		)
		(fill
			(thermal_gap 0.5)
			(thermal_bridge_width 0.5)
			(island_removal_mode 0)
		)
		(polygon
			(pts
				(arc
					(start 89.352882 -354.351082)
					(mid 88.971882 -354.732082)
					(end 89.352882 -355.113082)
				)
				(arc
					(start 90.216482 -355.113082)
					(mid 90.597482 -354.732082)
					(end 90.216482 -354.351082)
				)
			)
		)
	)
	(zone
		(layers "F.Cu" "B.Cu" "In1.Cu" "In2.Cu" "In3.Cu" "In4.Cu" "In5.Cu" "In6.Cu"
			"In7.Cu" "In8.Cu" "In9.Cu" "In10.Cu" "In11.Cu" "In12.Cu" "In13.Cu" "In14.Cu"
			"In15.Cu" "In16.Cu"
		)
		(hatch none 0.5)
		(connect_pads
			(clearance 0)
		)
		(min_thickness 0.25)
		(keepout
			(tracks not_allowed)
			(vias allowed)
			(pads allowed)
			(copperpour not_allowed)
			(footprints allowed)
		)
		(placement
			(enabled no)
			(sheetname "")
		)
		(fill
			(thermal_gap 0.5)
			(thermal_bridge_width 0.5)
			(island_removal_mode 0)
		)
		(polygon
			(pts
				(arc
					(start 81.075022 -150.67915)
					(mid 81.532222 -151.13635)
					(end 81.989422 -150.67915)
				)
				(arc
					(start 81.989422 -149.81555)
					(mid 81.532222 -149.35835)
					(end 81.075022 -149.81555)
				)
			)
		)
	)
	(zone
		(layers "F.Cu" "B.Cu" "In1.Cu" "In2.Cu" "In3.Cu" "In4.Cu" "In5.Cu" "In6.Cu"
			"In7.Cu" "In8.Cu" "In9.Cu" "In10.Cu" "In11.Cu" "In12.Cu" "In13.Cu" "In14.Cu"
			"In15.Cu" "In16.Cu"
		)
		(hatch none 0.5)
		(connect_pads
			(clearance 0)
		)
		(min_thickness 0.25)
		(keepout
			(tracks not_allowed)
			(vias allowed)
			(pads allowed)
			(copperpour not_allowed)
			(footprints allowed)
		)
		(placement
			(enabled no)
			(sheetname "")
		)
		(fill
			(thermal_gap 0.5)
			(thermal_bridge_width 0.5)
			(island_removal_mode 0)
		)
		(polygon
			(pts
				(arc
					(start 27.501088 -373.828818)
					(mid 27.515967 -373.792897)
					(end 27.551888 -373.778018)
				)
				(arc
					(start 28.268168 -373.778018)
					(mid 28.304089 -373.792897)
					(end 28.318968 -373.828818)
				)
				(arc
					(start 28.318968 -376.25147)
					(mid 28.304089 -376.287391)
					(end 28.268168 -376.30227)
				)
				(arc
					(start 27.551888 -376.30227)
					(mid 27.515967 -376.287391)
					(end 27.501088 -376.25147)
				)
			)
		)
	)
	(zone
		(layers "F.Cu" "B.Cu" "In1.Cu" "In2.Cu" "In3.Cu" "In4.Cu" "In5.Cu" "In6.Cu"
			"In7.Cu" "In8.Cu" "In9.Cu" "In10.Cu" "In11.Cu" "In12.Cu" "In13.Cu" "In14.Cu"
			"In15.Cu" "In16.Cu"
		)
		(hatch none 0.5)
		(connect_pads
			(clearance 0)
		)
		(min_thickness 0.25)
		(keepout
			(tracks not_allowed)
			(vias allowed)
			(pads allowed)
			(copperpour not_allowed)
			(footprints allowed)
		)
		(placement
			(enabled no)
			(sheetname "")
		)
		(fill
			(thermal_gap 0.5)
			(thermal_bridge_width 0.5)
			(island_removal_mode 0)
		)
		(polygon
			(pts
				(arc
					(start 73.808082 -348.20479)
					(mid 73.427082 -348.58579)
					(end 73.808082 -348.96679)
				)
				(arc
					(start 74.671682 -348.96679)
					(mid 75.052682 -348.58579)
					(end 74.671682 -348.20479)
				)
			)
		)
	)
	(zone
		(layers "F.Cu" "B.Cu" "In1.Cu" "In2.Cu" "In3.Cu" "In4.Cu" "In5.Cu" "In6.Cu"
			"In7.Cu" "In8.Cu" "In9.Cu" "In10.Cu" "In11.Cu" "In12.Cu" "In13.Cu" "In14.Cu"
			"In15.Cu" "In16.Cu"
		)
		(hatch none 0.5)
		(connect_pads
			(clearance 0)
		)
		(min_thickness 0.25)
		(keepout
			(tracks not_allowed)
			(vias allowed)
			(pads allowed)
			(copperpour not_allowed)
			(footprints allowed)
		)
		(placement
			(enabled no)
			(sheetname "")
		)
		(fill
			(thermal_gap 0.5)
			(thermal_bridge_width 0.5)
			(island_removal_mode 0)
		)
		(polygon
			(pts
				(arc
					(start 342.081104 -371.028722)
					(mid 342.095983 -370.992801)
					(end 342.131904 -370.977922)
				)
				(arc
					(start 342.848184 -370.977922)
					(mid 342.884105 -370.992801)
					(end 342.898984 -371.028722)
				)
				(arc
					(start 342.898984 -373.451374)
					(mid 342.884105 -373.487295)
					(end 342.848184 -373.502174)
				)
				(arc
					(start 342.131904 -373.502174)
					(mid 342.095983 -373.487295)
					(end 342.081104 -373.451374)
				)
			)
		)
	)
	(zone
		(layers "F.Cu" "B.Cu" "In1.Cu" "In2.Cu" "In3.Cu" "In4.Cu" "In5.Cu" "In6.Cu"
			"In7.Cu" "In8.Cu" "In9.Cu" "In10.Cu" "In11.Cu" "In12.Cu" "In13.Cu" "In14.Cu"
			"In15.Cu" "In16.Cu"
		)
		(hatch none 0.5)
		(connect_pads
			(clearance 0)
		)
		(min_thickness 0.25)
		(keepout
			(tracks not_allowed)
			(vias allowed)
			(pads allowed)
			(copperpour not_allowed)
			(footprints allowed)
		)
		(placement
			(enabled no)
			(sheetname "")
		)
		(fill
			(thermal_gap 0.5)
			(thermal_bridge_width 0.5)
			(island_removal_mode 0)
		)
		(polygon
			(pts
				(arc
					(start 293.680896 -371.028722)
					(mid 293.695775 -370.992801)
					(end 293.731696 -370.977922)
				)
				(arc
					(start 294.447976 -370.977922)
					(mid 294.483897 -370.992801)
					(end 294.498776 -371.028722)
				)
				(arc
					(start 294.498776 -373.451374)
					(mid 294.483897 -373.487295)
					(end 294.447976 -373.502174)
				)
				(arc
					(start 293.731696 -373.502174)
					(mid 293.695775 -373.487295)
					(end 293.680896 -373.451374)
				)
			)
		)
	)
	(zone
		(layers "F.Cu" "B.Cu" "In1.Cu" "In2.Cu" "In3.Cu" "In4.Cu" "In5.Cu" "In6.Cu"
			"In7.Cu" "In8.Cu" "In9.Cu" "In10.Cu" "In11.Cu" "In12.Cu" "In13.Cu" "In14.Cu"
			"In15.Cu" "In16.Cu"
		)
		(hatch none 0.5)
		(connect_pads
			(clearance 0)
		)
		(min_thickness 0.25)
		(keepout
			(tracks not_allowed)
			(vias allowed)
			(pads allowed)
			(copperpour not_allowed)
			(footprints allowed)
		)
		(placement
			(enabled no)
			(sheetname "")
		)
		(fill
			(thermal_gap 0.5)
			(thermal_bridge_width 0.5)
			(island_removal_mode 0)
		)
		(polygon
			(pts
				(arc
					(start 170.501056 -408.728672)
					(mid 170.515935 -408.692751)
					(end 170.551856 -408.677872)
				)
				(arc
					(start 171.268136 -408.677872)
					(mid 171.304057 -408.692751)
					(end 171.318936 -408.728672)
				)
				(arc
					(start 171.318936 -411.151324)
					(mid 171.304057 -411.187245)
					(end 171.268136 -411.202124)
				)
				(arc
					(start 170.551856 -411.202124)
					(mid 170.515935 -411.187245)
					(end 170.501056 -411.151324)
				)
			)
		)
	)
	(zone
		(layers "F.Cu" "B.Cu" "In1.Cu" "In2.Cu" "In3.Cu" "In4.Cu" "In5.Cu" "In6.Cu"
			"In7.Cu" "In8.Cu" "In9.Cu" "In10.Cu" "In11.Cu" "In12.Cu" "In13.Cu" "In14.Cu"
			"In15.Cu" "In16.Cu"
		)
		(hatch none 0.5)
		(connect_pads
			(clearance 0)
		)
		(min_thickness 0.25)
		(keepout
			(tracks not_allowed)
			(vias allowed)
			(pads allowed)
			(copperpour not_allowed)
			(footprints allowed)
		)
		(placement
			(enabled no)
			(sheetname "")
		)
		(fill
			(thermal_gap 0.5)
			(thermal_bridge_width 0.5)
			(island_removal_mode 0)
		)
		(polygon
			(pts
				(arc
					(start 166.101014 -400.92884)
					(mid 166.115893 -400.892919)
					(end 166.151814 -400.87804)
				)
				(arc
					(start 166.868094 -400.87804)
					(mid 166.904015 -400.892919)
					(end 166.918894 -400.92884)
				)
				(arc
					(start 166.918894 -403.351492)
					(mid 166.904015 -403.387413)
					(end 166.868094 -403.402292)
				)
				(arc
					(start 166.151814 -403.402292)
					(mid 166.115893 -403.387413)
					(end 166.101014 -403.351492)
				)
			)
		)
	)
	(zone
		(layers "F.Cu" "B.Cu" "In1.Cu" "In2.Cu" "In3.Cu" "In4.Cu" "In5.Cu" "In6.Cu"
			"In7.Cu" "In8.Cu" "In9.Cu" "In10.Cu" "In11.Cu" "In12.Cu" "In13.Cu" "In14.Cu"
			"In15.Cu" "In16.Cu"
		)
		(hatch none 0.5)
		(connect_pads
			(clearance 0)
		)
		(min_thickness 0.25)
		(keepout
			(tracks not_allowed)
			(vias allowed)
			(pads allowed)
			(copperpour not_allowed)
			(footprints allowed)
		)
		(placement
			(enabled no)
			(sheetname "")
		)
		(fill
			(thermal_gap 0.5)
			(thermal_bridge_width 0.5)
			(island_removal_mode 0)
		)
		(polygon
			(pts
				(arc
					(start 29.700982 -400.92884)
					(mid 29.715861 -400.892919)
					(end 29.751782 -400.87804)
				)
				(arc
					(start 30.468062 -400.87804)
					(mid 30.503983 -400.892919)
					(end 30.518862 -400.92884)
				)
				(arc
					(start 30.518862 -403.351492)
					(mid 30.503983 -403.387413)
					(end 30.468062 -403.402292)
				)
				(arc
					(start 29.751782 -403.402292)
					(mid 29.715861 -403.387413)
					(end 29.700982 -403.351492)
				)
			)
		)
	)
	(zone
		(layers "F.Cu" "B.Cu" "In1.Cu" "In2.Cu" "In3.Cu" "In4.Cu" "In5.Cu" "In6.Cu"
			"In7.Cu" "In8.Cu" "In9.Cu" "In10.Cu" "In11.Cu" "In12.Cu" "In13.Cu" "In14.Cu"
			"In15.Cu" "In16.Cu"
		)
		(hatch none 0.5)
		(connect_pads
			(clearance 0)
		)
		(min_thickness 0.25)
		(keepout
			(tracks not_allowed)
			(vias allowed)
			(pads allowed)
			(copperpour not_allowed)
			(footprints allowed)
		)
		(placement
			(enabled no)
			(sheetname "")
		)
		(fill
			(thermal_gap 0.5)
			(thermal_bridge_width 0.5)
			(island_removal_mode 0)
		)
		(polygon
			(pts
				(arc
					(start 283.441902 -357.37673)
					(mid 283.060902 -357.75773)
					(end 283.441902 -358.13873)
				)
				(arc
					(start 284.305502 -358.13873)
					(mid 284.686502 -357.75773)
					(end 284.305502 -357.37673)
				)
			)
		)
	)
	(zone
		(layers "F.Cu" "B.Cu" "In1.Cu" "In2.Cu" "In3.Cu" "In4.Cu" "In5.Cu" "In6.Cu"
			"In7.Cu" "In8.Cu" "In9.Cu" "In10.Cu" "In11.Cu" "In12.Cu" "In13.Cu" "In14.Cu"
			"In15.Cu" "In16.Cu"
		)
		(hatch none 0.5)
		(connect_pads
			(clearance 0)
		)
		(min_thickness 0.25)
		(keepout
			(tracks not_allowed)
			(vias allowed)
			(pads allowed)
			(copperpour not_allowed)
			(footprints allowed)
		)
		(placement
			(enabled no)
			(sheetname "")
		)
		(fill
			(thermal_gap 0.5)
			(thermal_bridge_width 0.5)
			(island_removal_mode 0)
		)
		(polygon
			(pts
				(arc
					(start 78.100936 -404.828756)
					(mid 78.115815 -404.792835)
					(end 78.151736 -404.777956)
				)
				(arc
					(start 78.868016 -404.777956)
					(mid 78.903937 -404.792835)
					(end 78.918816 -404.828756)
				)
				(arc
					(start 78.918816 -407.251408)
					(mid 78.903937 -407.287329)
					(end 78.868016 -407.302208)
				)
				(arc
					(start 78.151736 -407.302208)
					(mid 78.115815 -407.287329)
					(end 78.100936 -407.251408)
				)
			)
		)
	)
	(zone
		(layers "F.Cu" "B.Cu" "In1.Cu" "In2.Cu" "In3.Cu" "In4.Cu" "In5.Cu" "In6.Cu"
			"In7.Cu" "In8.Cu" "In9.Cu" "In10.Cu" "In11.Cu" "In12.Cu" "In13.Cu" "In14.Cu"
			"In15.Cu" "In16.Cu"
		)
		(hatch none 0.5)
		(connect_pads
			(clearance 0)
		)
		(min_thickness 0.25)
		(keepout
			(tracks not_allowed)
			(vias allowed)
			(pads allowed)
			(copperpour not_allowed)
			(footprints allowed)
		)
		(placement
			(enabled no)
			(sheetname "")
		)
		(fill
			(thermal_gap 0.5)
			(thermal_bridge_width 0.5)
			(island_removal_mode 0)
		)
		(polygon
			(pts
				(arc
					(start 329.231498 7.685024)
					(mid 329.612498 7.304024)
					(end 329.993498 7.685024)
				)
				(arc
					(start 329.993498 8.548624)
					(mid 329.612498 8.929624)
					(end 329.231498 8.548624)
				)
			)
		)
	)
	(zone
		(layers "F.Cu" "B.Cu" "In1.Cu" "In2.Cu" "In3.Cu" "In4.Cu" "In5.Cu" "In6.Cu"
			"In7.Cu" "In8.Cu" "In9.Cu" "In10.Cu" "In11.Cu" "In12.Cu" "In13.Cu" "In14.Cu"
			"In15.Cu" "In16.Cu"
		)
		(hatch none 0.5)
		(connect_pads
			(clearance 0)
		)
		(min_thickness 0.25)
		(keepout
			(tracks not_allowed)
			(vias allowed)
			(pads allowed)
			(copperpour not_allowed)
			(footprints allowed)
		)
		(placement
			(enabled no)
			(sheetname "")
		)
		(fill
			(thermal_gap 0.5)
			(thermal_bridge_width 0.5)
			(island_removal_mode 0)
		)
		(polygon
			(pts
				(arc
					(start 272.374868 -299.555154)
					(mid 272.705068 -299.224954)
					(end 272.374868 -298.894754)
				)
				(arc
					(start 271.424908 -298.894754)
					(mid 271.094708 -299.224954)
					(end 271.424908 -299.555154)
				)
			)
		)
	)
	(zone
		(layers "F.Cu" "B.Cu" "In1.Cu" "In2.Cu" "In3.Cu" "In4.Cu" "In5.Cu" "In6.Cu"
			"In7.Cu" "In8.Cu" "In9.Cu" "In10.Cu" "In11.Cu" "In12.Cu" "In13.Cu" "In14.Cu"
			"In15.Cu" "In16.Cu"
		)
		(hatch none 0.5)
		(connect_pads
			(clearance 0)
		)
		(min_thickness 0.25)
		(keepout
			(tracks not_allowed)
			(vias allowed)
			(pads allowed)
			(copperpour not_allowed)
			(footprints allowed)
		)
		(placement
			(enabled no)
			(sheetname "")
		)
		(fill
			(thermal_gap 0.5)
			(thermal_bridge_width 0.5)
			(island_removal_mode 0)
		)
		(polygon
			(pts
				(arc
					(start 340.483444 -351.230438)
					(mid 340.102444 -351.611438)
					(end 340.483444 -351.992438)
				)
				(arc
					(start 341.347044 -351.992438)
					(mid 341.728044 -351.611438)
					(end 341.347044 -351.230438)
				)
			)
		)
	)
	(zone
		(layers "F.Cu" "B.Cu" "In1.Cu" "In2.Cu" "In3.Cu" "In4.Cu" "In5.Cu" "In6.Cu"
			"In7.Cu" "In8.Cu" "In9.Cu" "In10.Cu" "In11.Cu" "In12.Cu" "In13.Cu" "In14.Cu"
			"In15.Cu" "In16.Cu"
		)
		(hatch none 0.5)
		(connect_pads
			(clearance 0)
		)
		(min_thickness 0.25)
		(keepout
			(tracks not_allowed)
			(vias allowed)
			(pads allowed)
			(copperpour not_allowed)
			(footprints allowed)
		)
		(placement
			(enabled no)
			(sheetname "")
		)
		(fill
			(thermal_gap 0.5)
			(thermal_bridge_width 0.5)
			(island_removal_mode 0)
		)
		(polygon
			(pts
				(arc
					(start 199.817228 -145.285714)
					(mid 200.274428 -145.742914)
					(end 200.731628 -145.285714)
				)
				(arc
					(start 200.731628 -144.422114)
					(mid 200.274428 -143.964914)
					(end 199.817228 -144.422114)
				)
			)
		)
	)
	(zone
		(layers "F.Cu" "B.Cu" "In1.Cu" "In2.Cu" "In3.Cu" "In4.Cu" "In5.Cu" "In6.Cu"
			"In7.Cu" "In8.Cu" "In9.Cu" "In10.Cu" "In11.Cu" "In12.Cu" "In13.Cu" "In14.Cu"
			"In15.Cu" "In16.Cu"
		)
		(hatch none 0.5)
		(connect_pads
			(clearance 0)
		)
		(min_thickness 0.25)
		(keepout
			(tracks not_allowed)
			(vias allowed)
			(pads allowed)
			(copperpour not_allowed)
			(footprints allowed)
		)
		(placement
			(enabled no)
			(sheetname "")
		)
		(fill
			(thermal_gap 0.5)
			(thermal_bridge_width 0.5)
			(island_removal_mode 0)
		)
		(polygon
			(pts
				(arc
					(start 395.790166 -34.520886)
					(mid 396.247366 -34.978086)
					(end 396.704566 -34.520886)
				)
				(arc
					(start 396.704566 -33.657286)
					(mid 396.247366 -33.200086)
					(end 395.790166 -33.657286)
				)
			)
		)
	)
	(zone
		(layers "F.Cu" "B.Cu" "In1.Cu" "In2.Cu" "In3.Cu" "In4.Cu" "In5.Cu" "In6.Cu"
			"In7.Cu" "In8.Cu" "In9.Cu" "In10.Cu" "In11.Cu" "In12.Cu" "In13.Cu" "In14.Cu"
			"In15.Cu" "In16.Cu"
		)
		(hatch none 0.5)
		(connect_pads
			(clearance 0)
		)
		(min_thickness 0.25)
		(keepout
			(tracks not_allowed)
			(vias allowed)
			(pads allowed)
			(copperpour not_allowed)
			(footprints allowed)
		)
		(placement
			(enabled no)
			(sheetname "")
		)
		(fill
			(thermal_gap 0.5)
			(thermal_bridge_width 0.5)
			(island_removal_mode 0)
		)
		(polygon
			(pts
				(arc
					(start 75.901042 -407.628852)
					(mid 75.915921 -407.592931)
					(end 75.951842 -407.578052)
				)
				(arc
					(start 76.668122 -407.578052)
					(mid 76.704043 -407.592931)
					(end 76.718922 -407.628852)
				)
				(arc
					(start 76.718922 -410.051504)
					(mid 76.704043 -410.087425)
					(end 76.668122 -410.102304)
				)
				(arc
					(start 75.951842 -410.102304)
					(mid 75.915921 -410.087425)
					(end 75.901042 -410.051504)
				)
			)
		)
	)
	(zone
		(layers "F.Cu" "B.Cu" "In1.Cu" "In2.Cu" "In3.Cu" "In4.Cu" "In5.Cu" "In6.Cu"
			"In7.Cu" "In8.Cu" "In9.Cu" "In10.Cu" "In11.Cu" "In12.Cu" "In13.Cu" "In14.Cu"
			"In15.Cu" "In16.Cu"
		)
		(hatch none 0.5)
		(connect_pads
			(clearance 0)
		)
		(min_thickness 0.25)
		(keepout
			(tracks not_allowed)
			(vias allowed)
			(pads allowed)
			(copperpour not_allowed)
			(footprints allowed)
		)
		(placement
			(enabled no)
			(sheetname "")
		)
		(fill
			(thermal_gap 0.5)
			(thermal_bridge_width 0.5)
			(island_removal_mode 0)
		)
		(polygon
			(pts
				(arc
					(start 413.04591 -124.967238)
					(mid 413.50311 -125.424438)
					(end 413.96031 -124.967238)
				)
				(arc
					(start 413.96031 -124.103638)
					(mid 413.50311 -123.646438)
					(end 413.04591 -124.103638)
				)
			)
		)
	)
	(zone
		(layers "F.Cu" "B.Cu" "In1.Cu" "In2.Cu" "In3.Cu" "In4.Cu" "In5.Cu" "In6.Cu"
			"In7.Cu" "In8.Cu" "In9.Cu" "In10.Cu" "In11.Cu" "In12.Cu" "In13.Cu" "In14.Cu"
			"In15.Cu" "In16.Cu"
		)
		(hatch none 0.5)
		(connect_pads
			(clearance 0)
		)
		(min_thickness 0.25)
		(keepout
			(tracks not_allowed)
			(vias allowed)
			(pads allowed)
			(copperpour not_allowed)
			(footprints allowed)
		)
		(placement
			(enabled no)
			(sheetname "")
		)
		(fill
			(thermal_gap 0.5)
			(thermal_bridge_width 0.5)
			(island_removal_mode 0)
		)
		(polygon
			(pts
				(arc
					(start 328.047604 -357.37673)
					(mid 327.666604 -357.75773)
					(end 328.047604 -358.13873)
				)
				(arc
					(start 328.911204 -358.13873)
					(mid 329.292204 -357.75773)
					(end 328.911204 -357.37673)
				)
			)
		)
	)
	(zone
		(layers "F.Cu" "B.Cu" "In1.Cu" "In2.Cu" "In3.Cu" "In4.Cu" "In5.Cu" "In6.Cu"
			"In7.Cu" "In8.Cu" "In9.Cu" "In10.Cu" "In11.Cu" "In12.Cu" "In13.Cu" "In14.Cu"
			"In15.Cu" "In16.Cu"
		)
		(hatch none 0.5)
		(connect_pads
			(clearance 0)
		)
		(min_thickness 0.25)
		(keepout
			(tracks not_allowed)
			(vias allowed)
			(pads allowed)
			(copperpour not_allowed)
			(footprints allowed)
		)
		(placement
			(enabled no)
			(sheetname "")
		)
		(fill
			(thermal_gap 0.5)
			(thermal_bridge_width 0.5)
			(island_removal_mode 0)
		)
		(polygon
			(pts
				(arc
					(start 70.699122 -342.058498)
					(mid 70.318122 -342.439498)
					(end 70.699122 -342.820498)
				)
				(arc
					(start 71.562722 -342.820498)
					(mid 71.943722 -342.439498)
					(end 71.562722 -342.058498)
				)
			)
		)
	)
	(zone
		(layers "F.Cu" "B.Cu" "In1.Cu" "In2.Cu" "In3.Cu" "In4.Cu" "In5.Cu" "In6.Cu"
			"In7.Cu" "In8.Cu" "In9.Cu" "In10.Cu" "In11.Cu" "In12.Cu" "In13.Cu" "In14.Cu"
			"In15.Cu" "In16.Cu"
		)
		(hatch none 0.5)
		(connect_pads
			(clearance 0)
		)
		(min_thickness 0.25)
		(keepout
			(tracks not_allowed)
			(vias allowed)
			(pads allowed)
			(copperpour not_allowed)
			(footprints allowed)
		)
		(placement
			(enabled no)
			(sheetname "")
		)
		(fill
			(thermal_gap 0.5)
			(thermal_bridge_width 0.5)
			(island_removal_mode 0)
		)
		(polygon
			(pts
				(arc
					(start 74.475594 -117.758718)
					(mid 74.932794 -118.215918)
					(end 75.389994 -117.758718)
				)
				(arc
					(start 75.389994 -116.895118)
					(mid 74.932794 -116.437918)
					(end 74.475594 -116.895118)
				)
			)
		)
	)
	(zone
		(layers "F.Cu" "B.Cu" "In1.Cu" "In2.Cu" "In3.Cu" "In4.Cu" "In5.Cu" "In6.Cu"
			"In7.Cu" "In8.Cu" "In9.Cu" "In10.Cu" "In11.Cu" "In12.Cu" "In13.Cu" "In14.Cu"
			"In15.Cu" "In16.Cu"
		)
		(hatch none 0.5)
		(connect_pads
			(clearance 0)
		)
		(min_thickness 0.25)
		(keepout
			(tracks not_allowed)
			(vias allowed)
			(pads allowed)
			(copperpour not_allowed)
			(footprints allowed)
		)
		(placement
			(enabled no)
			(sheetname "")
		)
		(fill
			(thermal_gap 0.5)
			(thermal_bridge_width 0.5)
			(island_removal_mode 0)
		)
		(polygon
			(pts
				(arc
					(start 335.481168 -403.728682)
					(mid 335.496047 -403.692761)
					(end 335.531968 -403.677882)
				)
				(arc
					(start 336.248248 -403.677882)
					(mid 336.284169 -403.692761)
					(end 336.299048 -403.728682)
				)
				(arc
					(start 336.299048 -406.151334)
					(mid 336.284169 -406.187255)
					(end 336.248248 -406.202134)
				)
				(arc
					(start 335.531968 -406.202134)
					(mid 335.496047 -406.187255)
					(end 335.481168 -406.151334)
				)
			)
		)
	)
	(zone
		(layers "F.Cu" "B.Cu" "In1.Cu" "In2.Cu" "In3.Cu" "In4.Cu" "In5.Cu" "In6.Cu"
			"In7.Cu" "In8.Cu" "In9.Cu" "In10.Cu" "In11.Cu" "In12.Cu" "In13.Cu" "In14.Cu"
			"In15.Cu" "In16.Cu"
		)
		(hatch none 0.5)
		(connect_pads
			(clearance 0)
		)
		(min_thickness 0.25)
		(keepout
			(tracks not_allowed)
			(vias allowed)
			(pads allowed)
			(copperpour not_allowed)
			(footprints allowed)
		)
		(placement
			(enabled no)
			(sheetname "")
		)
		(fill
			(thermal_gap 0.5)
			(thermal_bridge_width 0.5)
			(island_removal_mode 0)
		)
		(polygon
			(pts
				(arc
					(start 318.720724 -357.37673)
					(mid 318.339724 -357.75773)
					(end 318.720724 -358.13873)
				)
				(arc
					(start 319.584324 -358.13873)
					(mid 319.965324 -357.75773)
					(end 319.584324 -357.37673)
				)
			)
		)
	)
	(zone
		(layers "F.Cu" "B.Cu" "In1.Cu" "In2.Cu" "In3.Cu" "In4.Cu" "In5.Cu" "In6.Cu"
			"In7.Cu" "In8.Cu" "In9.Cu" "In10.Cu" "In11.Cu" "In12.Cu" "In13.Cu" "In14.Cu"
			"In15.Cu" "In16.Cu"
		)
		(hatch none 0.5)
		(connect_pads
			(clearance 0)
		)
		(min_thickness 0.25)
		(keepout
			(tracks not_allowed)
			(vias allowed)
			(pads allowed)
			(copperpour not_allowed)
			(footprints allowed)
		)
		(placement
			(enabled no)
			(sheetname "")
		)
		(fill
			(thermal_gap 0.5)
			(thermal_bridge_width 0.5)
			(island_removal_mode 0)
		)
		(polygon
			(pts
				(arc
					(start 339.88121 -407.628852)
					(mid 339.896089 -407.592931)
					(end 339.93201 -407.578052)
				)
				(arc
					(start 340.64829 -407.578052)
					(mid 340.684211 -407.592931)
					(end 340.69909 -407.628852)
				)
				(arc
					(start 340.69909 -410.051504)
					(mid 340.684211 -410.087425)
					(end 340.64829 -410.102304)
				)
				(arc
					(start 339.93201 -410.102304)
					(mid 339.896089 -410.087425)
					(end 339.88121 -410.051504)
				)
			)
		)
	)
	(zone
		(layers "F.Cu" "B.Cu" "In1.Cu" "In2.Cu" "In3.Cu" "In4.Cu" "In5.Cu" "In6.Cu"
			"In7.Cu" "In8.Cu" "In9.Cu" "In10.Cu" "In11.Cu" "In12.Cu" "In13.Cu" "In14.Cu"
			"In15.Cu" "In16.Cu"
		)
		(hatch none 0.5)
		(connect_pads
			(clearance 0)
		)
		(min_thickness 0.25)
		(keepout
			(tracks not_allowed)
			(vias allowed)
			(pads allowed)
			(copperpour not_allowed)
			(footprints allowed)
		)
		(placement
			(enabled no)
			(sheetname "")
		)
		(fill
			(thermal_gap 0.5)
			(thermal_bridge_width 0.5)
			(island_removal_mode 0)
		)
		(polygon
			(pts
				(arc
					(start 286.550862 -345.084146)
					(mid 286.169862 -345.465146)
					(end 286.550862 -345.846146)
				)
				(arc
					(start 287.414462 -345.846146)
					(mid 287.795462 -345.465146)
					(end 287.414462 -345.084146)
				)
			)
		)
	)
	(zone
		(layers "F.Cu" "B.Cu" "In1.Cu" "In2.Cu" "In3.Cu" "In4.Cu" "In5.Cu" "In6.Cu"
			"In7.Cu" "In8.Cu" "In9.Cu" "In10.Cu" "In11.Cu" "In12.Cu" "In13.Cu" "In14.Cu"
			"In15.Cu" "In16.Cu"
		)
		(hatch none 0.5)
		(connect_pads
			(clearance 0)
		)
		(min_thickness 0.25)
		(keepout
			(tracks not_allowed)
			(vias allowed)
			(pads allowed)
			(copperpour not_allowed)
			(footprints allowed)
		)
		(placement
			(enabled no)
			(sheetname "")
		)
		(fill
			(thermal_gap 0.5)
			(thermal_bridge_width 0.5)
			(island_removal_mode 0)
		)
		(polygon
			(pts
				(arc
					(start 346.481146 -374.928638)
					(mid 346.496025 -374.892717)
					(end 346.531946 -374.877838)
				)
				(arc
					(start 347.248226 -374.877838)
					(mid 347.284147 -374.892717)
					(end 347.299026 -374.928638)
				)
				(arc
					(start 347.299026 -377.35129)
					(mid 347.284147 -377.387211)
					(end 347.248226 -377.40209)
				)
				(arc
					(start 346.531946 -377.40209)
					(mid 346.496025 -377.387211)
					(end 346.481146 -377.35129)
				)
			)
		)
	)
	(zone
		(layers "F.Cu" "B.Cu" "In1.Cu" "In2.Cu" "In3.Cu" "In4.Cu" "In5.Cu" "In6.Cu"
			"In7.Cu" "In8.Cu" "In9.Cu" "In10.Cu" "In11.Cu" "In12.Cu" "In13.Cu" "In14.Cu"
			"In15.Cu" "In16.Cu"
		)
		(hatch none 0.5)
		(connect_pads
			(clearance 0)
		)
		(min_thickness 0.25)
		(keepout
			(tracks not_allowed)
			(vias allowed)
			(pads allowed)
			(copperpour not_allowed)
			(footprints allowed)
		)
		(placement
			(enabled no)
			(sheetname "")
		)
		(fill
			(thermal_gap 0.5)
			(thermal_bridge_width 0.5)
			(island_removal_mode 0)
		)
		(polygon
			(pts
				(arc
					(start 42.901108 -374.928638)
					(mid 42.915987 -374.892717)
					(end 42.951908 -374.877838)
				)
				(arc
					(start 43.668188 -374.877838)
					(mid 43.704109 -374.892717)
					(end 43.718988 -374.928638)
				)
				(arc
					(start 43.718988 -377.35129)
					(mid 43.704109 -377.387211)
					(end 43.668188 -377.40209)
				)
				(arc
					(start 42.951908 -377.40209)
					(mid 42.915987 -377.387211)
					(end 42.901108 -377.35129)
				)
			)
		)
	)
	(zone
		(layers "F.Cu" "B.Cu" "In1.Cu" "In2.Cu" "In3.Cu" "In4.Cu" "In5.Cu" "In6.Cu"
			"In7.Cu" "In8.Cu" "In9.Cu" "In10.Cu" "In11.Cu" "In12.Cu" "In13.Cu" "In14.Cu"
			"In15.Cu" "In16.Cu"
		)
		(hatch none 0.5)
		(connect_pads
			(clearance 0)
		)
		(min_thickness 0.25)
		(keepout
			(tracks not_allowed)
			(vias allowed)
			(pads allowed)
			(copperpour not_allowed)
			(footprints allowed)
		)
		(placement
			(enabled no)
			(sheetname "")
		)
		(fill
			(thermal_gap 0.5)
			(thermal_bridge_width 0.5)
			(island_removal_mode 0)
		)
		(polygon
			(pts
				(arc
					(start 92.461842 -354.351082)
					(mid 92.080842 -354.732082)
					(end 92.461842 -355.113082)
				)
				(arc
					(start 93.325442 -355.113082)
					(mid 93.706442 -354.732082)
					(end 93.325442 -354.351082)
				)
			)
		)
	)
	(zone
		(layers "F.Cu" "B.Cu" "In1.Cu" "In2.Cu" "In3.Cu" "In4.Cu" "In5.Cu" "In6.Cu"
			"In7.Cu" "In8.Cu" "In9.Cu" "In10.Cu" "In11.Cu" "In12.Cu" "In13.Cu" "In14.Cu"
			"In15.Cu" "In16.Cu"
		)
		(hatch none 0.5)
		(connect_pads
			(clearance 0)
		)
		(min_thickness 0.25)
		(keepout
			(tracks not_allowed)
			(vias allowed)
			(pads allowed)
			(copperpour not_allowed)
			(footprints allowed)
		)
		(placement
			(enabled no)
			(sheetname "")
		)
		(fill
			(thermal_gap 0.5)
			(thermal_bridge_width 0.5)
			(island_removal_mode 0)
		)
		(polygon
			(pts
				(arc
					(start 329.047856 -32.714184)
					(mid 329.505056 -33.171384)
					(end 329.962256 -32.714184)
				)
				(arc
					(start 329.962256 -31.850584)
					(mid 329.505056 -31.393384)
					(end 329.047856 -31.850584)
				)
			)
		)
	)
	(zone
		(layers "F.Cu" "B.Cu" "In1.Cu" "In2.Cu" "In3.Cu" "In4.Cu" "In5.Cu" "In6.Cu"
			"In7.Cu" "In8.Cu" "In9.Cu" "In10.Cu" "In11.Cu" "In12.Cu" "In13.Cu" "In14.Cu"
			"In15.Cu" "In16.Cu"
		)
		(hatch none 0.5)
		(connect_pads
			(clearance 0)
		)
		(min_thickness 0.25)
		(keepout
			(tracks not_allowed)
			(vias allowed)
			(pads allowed)
			(copperpour not_allowed)
			(footprints allowed)
		)
		(placement
			(enabled no)
			(sheetname "")
		)
		(fill
			(thermal_gap 0.5)
			(thermal_bridge_width 0.5)
			(island_removal_mode 0)
		)
		(polygon
			(pts
				(arc
					(start 22.441408 -354.351082)
					(mid 22.060408 -354.732082)
					(end 22.441408 -355.113082)
				)
				(arc
					(start 23.305008 -355.113082)
					(mid 23.686008 -354.732082)
					(end 23.305008 -354.351082)
				)
			)
		)
	)
	(zone
		(layers "F.Cu" "B.Cu" "In1.Cu" "In2.Cu" "In3.Cu" "In4.Cu" "In5.Cu" "In6.Cu"
			"In7.Cu" "In8.Cu" "In9.Cu" "In10.Cu" "In11.Cu" "In12.Cu" "In13.Cu" "In14.Cu"
			"In15.Cu" "In16.Cu"
		)
		(hatch none 0.5)
		(connect_pads
			(clearance 0)
		)
		(min_thickness 0.25)
		(keepout
			(tracks not_allowed)
			(vias allowed)
			(pads allowed)
			(copperpour not_allowed)
			(footprints allowed)
		)
		(placement
			(enabled no)
			(sheetname "")
		)
		(fill
			(thermal_gap 0.5)
			(thermal_bridge_width 0.5)
			(island_removal_mode 0)
		)
		(polygon
			(pts
				(arc
					(start 172.70095 -407.628852)
					(mid 172.715829 -407.592931)
					(end 172.75175 -407.578052)
				)
				(arc
					(start 173.46803 -407.578052)
					(mid 173.503951 -407.592931)
					(end 173.51883 -407.628852)
				)
				(arc
					(start 173.51883 -410.051504)
					(mid 173.503951 -410.087425)
					(end 173.46803 -410.102304)
				)
				(arc
					(start 172.75175 -410.102304)
					(mid 172.715829 -410.087425)
					(end 172.70095 -410.051504)
				)
			)
		)
	)
	(zone
		(layers "F.Cu" "B.Cu" "In1.Cu" "In2.Cu" "In3.Cu" "In4.Cu" "In5.Cu" "In6.Cu"
			"In7.Cu" "In8.Cu" "In9.Cu" "In10.Cu" "In11.Cu" "In12.Cu" "In13.Cu" "In14.Cu"
			"In15.Cu" "In16.Cu"
		)
		(hatch none 0.5)
		(connect_pads
			(clearance 0)
		)
		(min_thickness 0.25)
		(keepout
			(tracks not_allowed)
			(vias allowed)
			(pads allowed)
			(copperpour not_allowed)
			(footprints allowed)
		)
		(placement
			(enabled no)
			(sheetname "")
		)
		(fill
			(thermal_gap 0.5)
			(thermal_bridge_width 0.5)
			(island_removal_mode 0)
		)
		(polygon
			(pts
				(arc
					(start 331.081126 -399.828766)
					(mid 331.096005 -399.792845)
					(end 331.131926 -399.777966)
				)
				(arc
					(start 331.848206 -399.777966)
					(mid 331.884127 -399.792845)
					(end 331.899006 -399.828766)
				)
				(arc
					(start 331.899006 -402.251418)
					(mid 331.884127 -402.287339)
					(end 331.848206 -402.302218)
				)
				(arc
					(start 331.131926 -402.302218)
					(mid 331.096005 -402.287339)
					(end 331.081126 -402.251418)
				)
			)
		)
	)
	(zone
		(layers "F.Cu" "B.Cu" "In1.Cu" "In2.Cu" "In3.Cu" "In4.Cu" "In5.Cu" "In6.Cu"
			"In7.Cu" "In8.Cu" "In9.Cu" "In10.Cu" "In11.Cu" "In12.Cu" "In13.Cu" "In14.Cu"
			"In15.Cu" "In16.Cu"
		)
		(hatch none 0.5)
		(connect_pads
			(clearance 0)
		)
		(min_thickness 0.25)
		(keepout
			(tracks not_allowed)
			(vias allowed)
			(pads allowed)
			(copperpour not_allowed)
			(footprints allowed)
		)
		(placement
			(enabled no)
			(sheetname "")
		)
		(fill
			(thermal_gap 0.5)
			(thermal_bridge_width 0.5)
			(island_removal_mode 0)
		)
		(polygon
			(pts
				(arc
					(start 379.48108 -369.928902)
					(mid 379.495959 -369.892981)
					(end 379.53188 -369.878102)
				)
				(arc
					(start 380.24816 -369.878102)
					(mid 380.284081 -369.892981)
					(end 380.29896 -369.928902)
				)
				(arc
					(start 380.29896 -372.351554)
					(mid 380.284081 -372.387475)
					(end 380.24816 -372.402354)
				)
				(arc
					(start 379.53188 -372.402354)
					(mid 379.495959 -372.387475)
					(end 379.48108 -372.351554)
				)
			)
		)
	)
	(zone
		(layers "F.Cu" "B.Cu" "In1.Cu" "In2.Cu" "In3.Cu" "In4.Cu" "In5.Cu" "In6.Cu"
			"In7.Cu" "In8.Cu" "In9.Cu" "In10.Cu" "In11.Cu" "In12.Cu" "In13.Cu" "In14.Cu"
			"In15.Cu" "In16.Cu"
		)
		(hatch none 0.5)
		(connect_pads
			(clearance 0)
		)
		(min_thickness 0.25)
		(keepout
			(tracks not_allowed)
			(vias allowed)
			(pads allowed)
			(copperpour not_allowed)
			(footprints allowed)
		)
		(placement
			(enabled no)
			(sheetname "")
		)
		(fill
			(thermal_gap 0.5)
			(thermal_bridge_width 0.5)
			(island_removal_mode 0)
		)
		(polygon
			(pts
				(arc
					(start 161.700972 -382.728724)
					(mid 161.715851 -382.692803)
					(end 161.751772 -382.677924)
				)
				(arc
					(start 162.468052 -382.677924)
					(mid 162.503973 -382.692803)
					(end 162.518852 -382.728724)
				)
				(arc
					(start 162.518852 -385.151376)
					(mid 162.503973 -385.187297)
					(end 162.468052 -385.202176)
				)
				(arc
					(start 161.751772 -385.202176)
					(mid 161.715851 -385.187297)
					(end 161.700972 -385.151376)
				)
			)
		)
	)
	(zone
		(layers "F.Cu" "B.Cu" "In1.Cu" "In2.Cu" "In3.Cu" "In4.Cu" "In5.Cu" "In6.Cu"
			"In7.Cu" "In8.Cu" "In9.Cu" "In10.Cu" "In11.Cu" "In12.Cu" "In13.Cu" "In14.Cu"
			"In15.Cu" "In16.Cu"
		)
		(hatch none 0.5)
		(connect_pads
			(clearance 0)
		)
		(min_thickness 0.25)
		(keepout
			(tracks not_allowed)
			(vias allowed)
			(pads allowed)
			(copperpour not_allowed)
			(footprints allowed)
		)
		(placement
			(enabled no)
			(sheetname "")
		)
		(fill
			(thermal_gap 0.5)
			(thermal_bridge_width 0.5)
			(island_removal_mode 0)
		)
		(polygon
			(pts
				(arc
					(start 40.70096 -399.828766)
					(mid 40.715839 -399.792845)
					(end 40.75176 -399.777966)
				)
				(arc
					(start 41.46804 -399.777966)
					(mid 41.503961 -399.792845)
					(end 41.51884 -399.828766)
				)
				(arc
					(start 41.51884 -402.251418)
					(mid 41.503961 -402.287339)
					(end 41.46804 -402.302218)
				)
				(arc
					(start 40.75176 -402.302218)
					(mid 40.715839 -402.287339)
					(end 40.70096 -402.251418)
				)
			)
		)
	)
	(zone
		(layers "F.Cu" "B.Cu" "In1.Cu" "In2.Cu" "In3.Cu" "In4.Cu" "In5.Cu" "In6.Cu"
			"In7.Cu" "In8.Cu" "In9.Cu" "In10.Cu" "In11.Cu" "In12.Cu" "In13.Cu" "In14.Cu"
			"In15.Cu" "In16.Cu"
		)
		(hatch none 0.5)
		(connect_pads
			(clearance 0)
		)
		(min_thickness 0.25)
		(keepout
			(tracks not_allowed)
			(vias allowed)
			(pads allowed)
			(copperpour not_allowed)
			(footprints allowed)
		)
		(placement
			(enabled no)
			(sheetname "")
		)
		(fill
			(thermal_gap 0.5)
			(thermal_bridge_width 0.5)
			(island_removal_mode 0)
		)
		(polygon
			(pts
				(arc
					(start 292.768782 -348.20479)
					(mid 292.387782 -348.58579)
					(end 292.768782 -348.96679)
				)
				(arc
					(start 293.632382 -348.96679)
					(mid 294.013382 -348.58579)
					(end 293.632382 -348.20479)
				)
			)
		)
	)
	(zone
		(layers "F.Cu" "B.Cu" "In1.Cu" "In2.Cu" "In3.Cu" "In4.Cu" "In5.Cu" "In6.Cu"
			"In7.Cu" "In8.Cu" "In9.Cu" "In10.Cu" "In11.Cu" "In12.Cu" "In13.Cu" "In14.Cu"
			"In15.Cu" "In16.Cu"
		)
		(hatch none 0.5)
		(connect_pads
			(clearance 0)
		)
		(min_thickness 0.25)
		(keepout
			(tracks not_allowed)
			(vias allowed)
			(pads allowed)
			(copperpour not_allowed)
			(footprints allowed)
		)
		(placement
			(enabled no)
			(sheetname "")
		)
		(fill
			(thermal_gap 0.5)
			(thermal_bridge_width 0.5)
			(island_removal_mode 0)
		)
		(polygon
			(pts
				(arc
					(start 42.901108 -397.028924)
					(mid 42.915987 -396.993003)
					(end 42.951908 -396.978124)
				)
				(arc
					(start 43.668188 -396.978124)
					(mid 43.704109 -396.993003)
					(end 43.718988 -397.028924)
				)
				(arc
					(start 43.718988 -399.451576)
					(mid 43.704109 -399.487497)
					(end 43.668188 -399.502376)
				)
				(arc
					(start 42.951908 -399.502376)
					(mid 42.915987 -399.487497)
					(end 42.901108 -399.451576)
				)
			)
		)
	)
	(zone
		(layers "F.Cu" "B.Cu" "In1.Cu" "In2.Cu" "In3.Cu" "In4.Cu" "In5.Cu" "In6.Cu"
			"In7.Cu" "In8.Cu" "In9.Cu" "In10.Cu" "In11.Cu" "In12.Cu" "In13.Cu" "In14.Cu"
			"In15.Cu" "In16.Cu"
		)
		(hatch none 0.5)
		(connect_pads
			(clearance 0)
		)
		(min_thickness 0.25)
		(keepout
			(tracks not_allowed)
			(vias allowed)
			(pads allowed)
			(copperpour not_allowed)
			(footprints allowed)
		)
		(placement
			(enabled no)
			(sheetname "")
		)
		(fill
			(thermal_gap 0.5)
			(thermal_bridge_width 0.5)
			(island_removal_mode 0)
		)
		(polygon
			(pts
				(arc
					(start 267.897102 -345.084146)
					(mid 267.516102 -345.465146)
					(end 267.897102 -345.846146)
				)
				(arc
					(start 268.760702 -345.846146)
					(mid 269.141702 -345.465146)
					(end 268.760702 -345.084146)
				)
			)
		)
	)
	(zone
		(layers "F.Cu" "B.Cu" "In1.Cu" "In2.Cu" "In3.Cu" "In4.Cu" "In5.Cu" "In6.Cu"
			"In7.Cu" "In8.Cu" "In9.Cu" "In10.Cu" "In11.Cu" "In12.Cu" "In13.Cu" "In14.Cu"
			"In15.Cu" "In16.Cu"
		)
		(hatch none 0.5)
		(connect_pads
			(clearance 0)
		)
		(min_thickness 0.25)
		(keepout
			(tracks not_allowed)
			(vias allowed)
			(pads allowed)
			(copperpour not_allowed)
			(footprints allowed)
		)
		(placement
			(enabled no)
			(sheetname "")
		)
		(fill
			(thermal_gap 0.5)
			(thermal_bridge_width 0.5)
			(island_removal_mode 0)
		)
		(polygon
			(pts
				(arc
					(start 434.166772 -348.20479)
					(mid 433.785772 -348.58579)
					(end 434.166772 -348.96679)
				)
				(arc
					(start 435.030372 -348.96679)
					(mid 435.411372 -348.58579)
					(end 435.030372 -348.20479)
				)
			)
		)
	)
	(zone
		(layers "F.Cu" "B.Cu" "In1.Cu" "In2.Cu" "In3.Cu" "In4.Cu" "In5.Cu" "In6.Cu"
			"In7.Cu" "In8.Cu" "In9.Cu" "In10.Cu" "In11.Cu" "In12.Cu" "In13.Cu" "In14.Cu"
			"In15.Cu" "In16.Cu"
		)
		(hatch none 0.5)
		(connect_pads
			(clearance 0)
		)
		(min_thickness 0.25)
		(keepout
			(tracks not_allowed)
			(vias allowed)
			(pads allowed)
			(copperpour not_allowed)
			(footprints allowed)
		)
		(placement
			(enabled no)
			(sheetname "")
		)
		(fill
			(thermal_gap 0.5)
			(thermal_bridge_width 0.5)
			(island_removal_mode 0)
		)
		(polygon
			(pts
				(arc
					(start 127.406908 -351.230438)
					(mid 127.025908 -351.611438)
					(end 127.406908 -351.992438)
				)
				(arc
					(start 128.270508 -351.992438)
					(mid 128.651508 -351.611438)
					(end 128.270508 -351.230438)
				)
			)
		)
	)
	(zone
		(layers "F.Cu" "B.Cu" "In1.Cu" "In2.Cu" "In3.Cu" "In4.Cu" "In5.Cu" "In6.Cu"
			"In7.Cu" "In8.Cu" "In9.Cu" "In10.Cu" "In11.Cu" "In12.Cu" "In13.Cu" "In14.Cu"
			"In15.Cu" "In16.Cu"
		)
		(hatch none 0.5)
		(connect_pads
			(clearance 0)
		)
		(min_thickness 0.25)
		(keepout
			(tracks not_allowed)
			(vias allowed)
			(pads allowed)
			(copperpour not_allowed)
			(footprints allowed)
		)
		(placement
			(enabled no)
			(sheetname "")
		)
		(fill
			(thermal_gap 0.5)
			(thermal_bridge_width 0.5)
			(island_removal_mode 0)
		)
		(polygon
			(pts
				(arc
					(start 315.917072 -136.17575)
					(mid 316.374272 -136.63295)
					(end 316.831472 -136.17575)
				)
				(arc
					(start 316.831472 -135.31215)
					(mid 316.374272 -134.85495)
					(end 315.917072 -135.31215)
				)
			)
		)
	)
	(zone
		(layers "F.Cu" "B.Cu" "In1.Cu" "In2.Cu" "In3.Cu" "In4.Cu" "In5.Cu" "In6.Cu"
			"In7.Cu" "In8.Cu" "In9.Cu" "In10.Cu" "In11.Cu" "In12.Cu" "In13.Cu" "In14.Cu"
			"In15.Cu" "In16.Cu"
		)
		(hatch none 0.5)
		(connect_pads
			(clearance 0)
		)
		(min_thickness 0.25)
		(keepout
			(tracks not_allowed)
			(vias allowed)
			(pads allowed)
			(copperpour not_allowed)
			(footprints allowed)
		)
		(placement
			(enabled no)
			(sheetname "")
		)
		(fill
			(thermal_gap 0.5)
			(thermal_bridge_width 0.5)
			(island_removal_mode 0)
		)
		(polygon
			(pts
				(xy 313.074812 -417.378642) (xy 326.524874 -417.378642) (xy 326.524874 -394.325348) (xy 326.479408 -394.279882)
				(xy 313.074812 -394.279882)
			)
		)
	)
	(zone
		(layers "F.Cu" "B.Cu" "In1.Cu" "In2.Cu" "In3.Cu" "In4.Cu" "In5.Cu" "In6.Cu"
			"In7.Cu" "In8.Cu" "In9.Cu" "In10.Cu" "In11.Cu" "In12.Cu" "In13.Cu" "In14.Cu"
			"In15.Cu" "In16.Cu"
		)
		(hatch none 0.5)
		(connect_pads
			(clearance 0)
		)
		(min_thickness 0.25)
		(keepout
			(tracks not_allowed)
			(vias allowed)
			(pads allowed)
			(copperpour not_allowed)
			(footprints allowed)
		)
		(placement
			(enabled no)
			(sheetname "")
		)
		(fill
			(thermal_gap 0.5)
			(thermal_bridge_width 0.5)
			(island_removal_mode 0)
		)
		(polygon
			(pts
				(arc
					(start 334.265524 -345.084146)
					(mid 333.884524 -345.465146)
					(end 334.265524 -345.846146)
				)
				(arc
					(start 335.129124 -345.846146)
					(mid 335.510124 -345.465146)
					(end 335.129124 -345.084146)
				)
			)
		)
	)
	(zone
		(layers "F.Cu" "B.Cu" "In1.Cu" "In2.Cu" "In3.Cu" "In4.Cu" "In5.Cu" "In6.Cu"
			"In7.Cu" "In8.Cu" "In9.Cu" "In10.Cu" "In11.Cu" "In12.Cu" "In13.Cu" "In14.Cu"
			"In15.Cu" "In16.Cu"
		)
		(hatch none 0.5)
		(connect_pads
			(clearance 0)
		)
		(min_thickness 0.25)
		(keepout
			(tracks not_allowed)
			(vias allowed)
			(pads allowed)
			(copperpour not_allowed)
			(footprints allowed)
		)
		(placement
			(enabled no)
			(sheetname "")
		)
		(fill
			(thermal_gap 0.5)
			(thermal_bridge_width 0.5)
			(island_removal_mode 0)
		)
		(polygon
			(pts
				(arc
					(start 180.845968 -132.577332)
					(mid 181.303168 -133.034532)
					(end 181.760368 -132.577332)
				)
				(arc
					(start 181.760368 -131.713732)
					(mid 181.303168 -131.256532)
					(end 180.845968 -131.713732)
				)
			)
		)
	)
	(zone
		(layers "F.Cu" "B.Cu" "In1.Cu" "In2.Cu" "In3.Cu" "In4.Cu" "In5.Cu" "In6.Cu"
			"In7.Cu" "In8.Cu" "In9.Cu" "In10.Cu" "In11.Cu" "In12.Cu" "In13.Cu" "In14.Cu"
			"In15.Cu" "In16.Cu"
		)
		(hatch none 0.5)
		(connect_pads
			(clearance 0)
		)
		(min_thickness 0.25)
		(keepout
			(tracks not_allowed)
			(vias allowed)
			(pads allowed)
			(copperpour not_allowed)
			(footprints allowed)
		)
		(placement
			(enabled no)
			(sheetname "")
		)
		(fill
			(thermal_gap 0.5)
			(thermal_bridge_width 0.5)
			(island_removal_mode 0)
		)
		(polygon
			(pts
				(arc
					(start 386.081016 -408.728672)
					(mid 386.095895 -408.692751)
					(end 386.131816 -408.677872)
				)
				(arc
					(start 386.848096 -408.677872)
					(mid 386.884017 -408.692751)
					(end 386.898896 -408.728672)
				)
				(arc
					(start 386.898896 -411.151324)
					(mid 386.884017 -411.187245)
					(end 386.848096 -411.202124)
				)
				(arc
					(start 386.131816 -411.202124)
					(mid 386.095895 -411.187245)
					(end 386.081016 -411.151324)
				)
			)
		)
	)
	(zone
		(layers "F.Cu" "B.Cu" "In1.Cu" "In2.Cu" "In3.Cu" "In4.Cu" "In5.Cu" "In6.Cu"
			"In7.Cu" "In8.Cu" "In9.Cu" "In10.Cu" "In11.Cu" "In12.Cu" "In13.Cu" "In14.Cu"
			"In15.Cu" "In16.Cu"
		)
		(hatch none 0.5)
		(connect_pads
			(clearance 0)
		)
		(min_thickness 0.25)
		(keepout
			(tracks not_allowed)
			(vias allowed)
			(pads allowed)
			(copperpour not_allowed)
			(footprints allowed)
		)
		(placement
			(enabled no)
			(sheetname "")
		)
		(fill
			(thermal_gap 0.5)
			(thermal_bridge_width 0.5)
			(island_removal_mode 0)
		)
		(polygon
			(pts
				(arc
					(start 389.84174 -345.084146)
					(mid 389.46074 -345.465146)
					(end 389.84174 -345.846146)
				)
				(arc
					(start 390.70534 -345.846146)
					(mid 391.08634 -345.465146)
					(end 390.70534 -345.084146)
				)
			)
		)
	)
	(zone
		(layers "F.Cu" "B.Cu" "In1.Cu" "In2.Cu" "In3.Cu" "In4.Cu" "In5.Cu" "In6.Cu"
			"In7.Cu" "In8.Cu" "In9.Cu" "In10.Cu" "In11.Cu" "In12.Cu" "In13.Cu" "In14.Cu"
			"In15.Cu" "In16.Cu"
		)
		(hatch none 0.5)
		(connect_pads
			(clearance 0)
		)
		(min_thickness 0.25)
		(keepout
			(tracks not_allowed)
			(vias allowed)
			(pads allowed)
			(copperpour not_allowed)
			(footprints allowed)
		)
		(placement
			(enabled no)
			(sheetname "")
		)
		(fill
			(thermal_gap 0.5)
			(thermal_bridge_width 0.5)
			(island_removal_mode 0)
		)
		(polygon
			(pts
				(arc
					(start 337.374484 -354.351082)
					(mid 336.993484 -354.732082)
					(end 337.374484 -355.113082)
				)
				(arc
					(start 338.238084 -355.113082)
					(mid 338.619084 -354.732082)
					(end 338.238084 -354.351082)
				)
			)
		)
	)
	(zone
		(layers "F.Cu" "B.Cu" "In1.Cu" "In2.Cu" "In3.Cu" "In4.Cu" "In5.Cu" "In6.Cu"
			"In7.Cu" "In8.Cu" "In9.Cu" "In10.Cu" "In11.Cu" "In12.Cu" "In13.Cu" "In14.Cu"
			"In15.Cu" "In16.Cu"
		)
		(hatch none 0.5)
		(connect_pads
			(clearance 0)
		)
		(min_thickness 0.25)
		(keepout
			(tracks not_allowed)
			(vias allowed)
			(pads allowed)
			(copperpour not_allowed)
			(footprints allowed)
		)
		(placement
			(enabled no)
			(sheetname "")
		)
		(fill
			(thermal_gap 0.5)
			(thermal_bridge_width 0.5)
			(island_removal_mode 0)
		)
		(polygon
			(pts
				(arc
					(start 81.075022 -154.279346)
					(mid 81.532222 -154.736546)
					(end 81.989422 -154.279346)
				)
				(arc
					(start 81.989422 -153.415746)
					(mid 81.532222 -152.958546)
					(end 81.075022 -153.415746)
				)
			)
		)
	)
	(zone
		(layers "F.Cu" "In5.Cu" "In7.Cu" "In9.Cu")
		(hatch none 0.5)
		(connect_pads
			(clearance 0)
		)
		(min_thickness 0.25)
		(keepout
			(tracks not_allowed)
			(vias allowed)
			(pads allowed)
			(copperpour not_allowed)
			(footprints allowed)
		)
		(placement
			(enabled no)
			(sheetname "")
		)
		(fill yes
			(thermal_gap 0.5)
			(thermal_bridge_width 0.5)
			(island_removal_mode 0)
		)
		(polygon
			(pts
				(arc
					(start 340.124288 20.143724)
					(mid 339.420708 20.143724)
					(end 340.124288 20.143724)
				)
			)
		)
	)
	(zone
		(layers "F.Cu" "In5.Cu" "In7.Cu" "In9.Cu")
		(hatch none 0.5)
		(connect_pads
			(clearance 0)
		)
		(min_thickness 0.25)
		(keepout
			(tracks not_allowed)
			(vias allowed)
			(pads allowed)
			(copperpour not_allowed)
			(footprints allowed)
		)
		(placement
			(enabled no)
			(sheetname "")
		)
		(fill yes
			(thermal_gap 0.5)
			(thermal_bridge_width 0.5)
			(island_removal_mode 0)
		)
		(polygon
			(pts
				(arc
					(start 385.736084 11.114532)
					(mid 385.032504 11.114532)
					(end 385.736084 11.114532)
				)
			)
		)
	)
	(zone
		(layers "F.Cu" "In5.Cu" "In7.Cu" "In9.Cu")
		(hatch none 0.5)
		(connect_pads
			(clearance 0)
		)
		(min_thickness 0.25)
		(keepout
			(tracks not_allowed)
			(vias allowed)
			(pads allowed)
			(copperpour not_allowed)
			(footprints allowed)
		)
		(placement
			(enabled no)
			(sheetname "")
		)
		(fill yes
			(thermal_gap 0.5)
			(thermal_bridge_width 0.5)
			(island_removal_mode 0)
		)
		(polygon
			(pts
				(arc
					(start 329.964288 10.225024)
					(mid 329.260708 10.225024)
					(end 329.964288 10.225024)
				)
			)
		)
	)
	(zone
		(layers "F.Cu" "In5.Cu" "In7.Cu" "In9.Cu")
		(hatch none 0.5)
		(connect_pads
			(clearance 0)
		)
		(min_thickness 0.25)
		(keepout
			(tracks not_allowed)
			(vias allowed)
			(pads allowed)
			(copperpour not_allowed)
			(footprints allowed)
		)
		(placement
			(enabled no)
			(sheetname "")
		)
		(fill yes
			(thermal_gap 0.5)
			(thermal_bridge_width 0.5)
			(island_removal_mode 0)
		)
		(polygon
			(pts
				(arc
					(start 329.964288 11.088624)
					(mid 329.260708 11.088624)
					(end 329.964288 11.088624)
				)
			)
		)
	)
	(zone
		(layers "F.Cu" "In5.Cu" "In7.Cu" "In9.Cu")
		(hatch none 0.5)
		(connect_pads
			(clearance 0)
		)
		(min_thickness 0.25)
		(keepout
			(tracks not_allowed)
			(vias allowed)
			(pads allowed)
			(copperpour not_allowed)
			(footprints allowed)
		)
		(placement
			(enabled no)
			(sheetname "")
		)
		(fill yes
			(thermal_gap 0.5)
			(thermal_bridge_width 0.5)
			(island_removal_mode 0)
		)
		(polygon
			(pts
				(arc
					(start 340.124288 21.007324)
					(mid 339.420708 21.007324)
					(end 340.124288 21.007324)
				)
			)
		)
	)
	(zone
		(layers "F.Cu" "In5.Cu" "In7.Cu" "In9.Cu")
		(hatch none 0.5)
		(connect_pads
			(clearance 0)
		)
		(min_thickness 0.25)
		(keepout
			(tracks not_allowed)
			(vias allowed)
			(pads allowed)
			(copperpour not_allowed)
			(footprints allowed)
		)
		(placement
			(enabled no)
			(sheetname "")
		)
		(fill yes
			(thermal_gap 0.5)
			(thermal_bridge_width 0.5)
			(island_removal_mode 0)
		)
		(polygon
			(pts
				(arc
					(start 385.736084 10.250932)
					(mid 385.032504 10.250932)
					(end 385.736084 10.250932)
				)
			)
		)
	)
	(zone
		(layers "F.Cu" "In5.Cu" "In7.Cu" "In9.Cu")
		(hatch none 0.5)
		(connect_pads
			(clearance 0)
		)
		(min_thickness 0.25)
		(keepout
			(tracks not_allowed)
			(vias allowed)
			(pads allowed)
			(copperpour not_allowed)
			(footprints allowed)
		)
		(placement
			(enabled no)
			(sheetname "")
		)
		(fill yes
			(thermal_gap 0.5)
			(thermal_bridge_width 0.5)
			(island_removal_mode 0)
		)
		(polygon
			(pts
				(arc
					(start 376.75566 21.000212)
					(mid 376.05208 21.000212)
					(end 376.75566 21.000212)
				)
			)
		)
	)
	(zone
		(layers "F.Cu" "In5.Cu" "In7.Cu" "In9.Cu")
		(hatch none 0.5)
		(connect_pads
			(clearance 0)
		)
		(min_thickness 0.25)
		(keepout
			(tracks not_allowed)
			(vias allowed)
			(pads allowed)
			(copperpour not_allowed)
			(footprints allowed)
		)
		(placement
			(enabled no)
			(sheetname "")
		)
		(fill yes
			(thermal_gap 0.5)
			(thermal_bridge_width 0.5)
			(island_removal_mode 0)
		)
		(polygon
			(pts
				(arc
					(start 376.75566 20.136612)
					(mid 376.05208 20.136612)
					(end 376.75566 20.136612)
				)
			)
		)
	)
	(zone
		(layers "F.Cu" "In5.Cu" "In7.Cu" "In9.Cu" "In11.Cu")
		(hatch none 0.5)
		(connect_pads
			(clearance 0)
		)
		(min_thickness 0.25)
		(keepout
			(tracks not_allowed)
			(vias allowed)
			(pads allowed)
			(copperpour not_allowed)
			(footprints allowed)
		)
		(placement
			(enabled no)
			(sheetname "")
		)
		(fill yes
			(thermal_gap 0.5)
			(thermal_bridge_width 0.5)
			(island_removal_mode 0)
		)
		(polygon
			(pts
				(arc
					(start 404.767288 20.143724)
					(mid 404.063708 20.143724)
					(end 404.767288 20.143724)
				)
			)
		)
	)
	(zone
		(layers "F.Cu" "In5.Cu" "In7.Cu" "In9.Cu" "In11.Cu")
		(hatch none 0.5)
		(connect_pads
			(clearance 0)
		)
		(min_thickness 0.25)
		(keepout
			(tracks not_allowed)
			(vias allowed)
			(pads allowed)
			(copperpour not_allowed)
			(footprints allowed)
		)
		(placement
			(enabled no)
			(sheetname "")
		)
		(fill yes
			(thermal_gap 0.5)
			(thermal_bridge_width 0.5)
			(island_removal_mode 0)
		)
		(polygon
			(pts
				(arc
					(start 441.39866 20.136612)
					(mid 440.69508 20.136612)
					(end 441.39866 20.136612)
				)
			)
		)
	)
	(zone
		(layers "F.Cu" "In5.Cu" "In7.Cu" "In9.Cu" "In11.Cu")
		(hatch none 0.5)
		(connect_pads
			(clearance 0)
		)
		(min_thickness 0.25)
		(keepout
			(tracks not_allowed)
			(vias allowed)
			(pads allowed)
			(copperpour not_allowed)
			(footprints allowed)
		)
		(placement
			(enabled no)
			(sheetname "")
		)
		(fill yes
			(thermal_gap 0.5)
			(thermal_bridge_width 0.5)
			(island_removal_mode 0)
		)
		(polygon
			(pts
				(arc
					(start 404.767288 21.007324)
					(mid 404.063708 21.007324)
					(end 404.767288 21.007324)
				)
			)
		)
	)
	(zone
		(layers "F.Cu" "In5.Cu" "In7.Cu" "In9.Cu" "In11.Cu")
		(hatch none 0.5)
		(connect_pads
			(clearance 0)
		)
		(min_thickness 0.25)
		(keepout
			(tracks not_allowed)
			(vias allowed)
			(pads allowed)
			(copperpour not_allowed)
			(footprints allowed)
		)
		(placement
			(enabled no)
			(sheetname "")
		)
		(fill yes
			(thermal_gap 0.5)
			(thermal_bridge_width 0.5)
			(island_removal_mode 0)
		)
		(polygon
			(pts
				(arc
					(start 402.227288 11.121644)
					(mid 401.523708 11.121644)
					(end 402.227288 11.121644)
				)
			)
		)
	)
	(zone
		(layers "F.Cu" "In5.Cu" "In7.Cu" "In9.Cu" "In11.Cu")
		(hatch none 0.5)
		(connect_pads
			(clearance 0)
		)
		(min_thickness 0.25)
		(keepout
			(tracks not_allowed)
			(vias allowed)
			(pads allowed)
			(copperpour not_allowed)
			(footprints allowed)
		)
		(placement
			(enabled no)
			(sheetname "")
		)
		(fill yes
			(thermal_gap 0.5)
			(thermal_bridge_width 0.5)
			(island_removal_mode 0)
		)
		(polygon
			(pts
				(arc
					(start 402.227288 10.258044)
					(mid 401.523708 10.258044)
					(end 402.227288 10.258044)
				)
			)
		)
	)
	(zone
		(layers "F.Cu" "In5.Cu" "In7.Cu" "In9.Cu" "In11.Cu")
		(hatch none 0.5)
		(connect_pads
			(clearance 0)
		)
		(min_thickness 0.25)
		(keepout
			(tracks not_allowed)
			(vias allowed)
			(pads allowed)
			(copperpour not_allowed)
			(footprints allowed)
		)
		(placement
			(enabled no)
			(sheetname "")
		)
		(fill yes
			(thermal_gap 0.5)
			(thermal_bridge_width 0.5)
			(island_removal_mode 0)
		)
		(polygon
			(pts
				(arc
					(start 441.39866 21.000212)
					(mid 440.69508 21.000212)
					(end 441.39866 21.000212)
				)
			)
		)
	)
	(zone
		(layers "F.Cu" "In5.Cu" "In7.Cu" "In9.Cu" "In11.Cu")
		(hatch none 0.5)
		(connect_pads
			(clearance 0)
		)
		(min_thickness 0.25)
		(keepout
			(tracks not_allowed)
			(vias allowed)
			(pads allowed)
			(copperpour not_allowed)
			(footprints allowed)
		)
		(placement
			(enabled no)
			(sheetname "")
		)
		(fill yes
			(thermal_gap 0.5)
			(thermal_bridge_width 0.5)
			(island_removal_mode 0)
		)
		(polygon
			(pts
				(arc
					(start 457.999084 11.147552)
					(mid 457.295504 11.147552)
					(end 457.999084 11.147552)
				)
			)
		)
	)
	(zone
		(layers "F.Cu" "In5.Cu" "In7.Cu" "In9.Cu" "In11.Cu")
		(hatch none 0.5)
		(connect_pads
			(clearance 0)
		)
		(min_thickness 0.25)
		(keepout
			(tracks not_allowed)
			(vias allowed)
			(pads allowed)
			(copperpour not_allowed)
			(footprints allowed)
		)
		(placement
			(enabled no)
			(sheetname "")
		)
		(fill yes
			(thermal_gap 0.5)
			(thermal_bridge_width 0.5)
			(island_removal_mode 0)
		)
		(polygon
			(pts
				(arc
					(start 457.999084 10.283952)
					(mid 457.295504 10.283952)
					(end 457.999084 10.283952)
				)
			)
		)
	)
	(zone
		(layers "F.Cu" "In5.Cu" "In7.Cu" "In9.Cu" "In11.Cu" "In13.Cu")
		(hatch none 0.5)
		(connect_pads
			(clearance 0)
		)
		(min_thickness 0.25)
		(keepout
			(tracks not_allowed)
			(vias allowed)
			(pads allowed)
			(copperpour not_allowed)
			(footprints allowed)
		)
		(placement
			(enabled no)
			(sheetname "")
		)
		(fill yes
			(thermal_gap 0.5)
			(thermal_bridge_width 0.5)
			(island_removal_mode 0)
		)
		(polygon
			(pts
				(arc
					(start 257.193288 11.055604)
					(mid 256.489708 11.055604)
					(end 257.193288 11.055604)
				)
			)
		)
	)
	(zone
		(layers "F.Cu" "In5.Cu" "In7.Cu" "In9.Cu" "In11.Cu" "In13.Cu")
		(hatch none 0.5)
		(connect_pads
			(clearance 0)
		)
		(min_thickness 0.25)
		(keepout
			(tracks not_allowed)
			(vias allowed)
			(pads allowed)
			(copperpour not_allowed)
			(footprints allowed)
		)
		(placement
			(enabled no)
			(sheetname "")
		)
		(fill yes
			(thermal_gap 0.5)
			(thermal_bridge_width 0.5)
			(island_removal_mode 0)
		)
		(polygon
			(pts
				(arc
					(start 311.60466 21.000212)
					(mid 310.90108 21.000212)
					(end 311.60466 21.000212)
				)
			)
		)
	)
	(zone
		(layers "F.Cu" "In5.Cu" "In7.Cu" "In9.Cu" "In11.Cu" "In13.Cu")
		(hatch none 0.5)
		(connect_pads
			(clearance 0)
		)
		(min_thickness 0.25)
		(keepout
			(tracks not_allowed)
			(vias allowed)
			(pads allowed)
			(copperpour not_allowed)
			(footprints allowed)
		)
		(placement
			(enabled no)
			(sheetname "")
		)
		(fill yes
			(thermal_gap 0.5)
			(thermal_bridge_width 0.5)
			(island_removal_mode 0)
		)
		(polygon
			(pts
				(arc
					(start 274.973288 20.143724)
					(mid 274.269708 20.143724)
					(end 274.973288 20.143724)
				)
			)
		)
	)
	(zone
		(layers "F.Cu" "In5.Cu" "In7.Cu" "In9.Cu" "In11.Cu" "In13.Cu")
		(hatch none 0.5)
		(connect_pads
			(clearance 0)
		)
		(min_thickness 0.25)
		(keepout
			(tracks not_allowed)
			(vias allowed)
			(pads allowed)
			(copperpour not_allowed)
			(footprints allowed)
		)
		(placement
			(enabled no)
			(sheetname "")
		)
		(fill yes
			(thermal_gap 0.5)
			(thermal_bridge_width 0.5)
			(island_removal_mode 0)
		)
		(polygon
			(pts
				(arc
					(start 312.965084 11.081512)
					(mid 312.261504 11.081512)
					(end 312.965084 11.081512)
				)
			)
		)
	)
	(zone
		(layers "F.Cu" "In5.Cu" "In7.Cu" "In9.Cu" "In11.Cu" "In13.Cu")
		(hatch none 0.5)
		(connect_pads
			(clearance 0)
		)
		(min_thickness 0.25)
		(keepout
			(tracks not_allowed)
			(vias allowed)
			(pads allowed)
			(copperpour not_allowed)
			(footprints allowed)
		)
		(placement
			(enabled no)
			(sheetname "")
		)
		(fill yes
			(thermal_gap 0.5)
			(thermal_bridge_width 0.5)
			(island_removal_mode 0)
		)
		(polygon
			(pts
				(arc
					(start 311.60466 20.136612)
					(mid 310.90108 20.136612)
					(end 311.60466 20.136612)
				)
			)
		)
	)
	(zone
		(layers "F.Cu" "In5.Cu" "In7.Cu" "In9.Cu" "In11.Cu" "In13.Cu")
		(hatch none 0.5)
		(connect_pads
			(clearance 0)
		)
		(min_thickness 0.25)
		(keepout
			(tracks not_allowed)
			(vias allowed)
			(pads allowed)
			(copperpour not_allowed)
			(footprints allowed)
		)
		(placement
			(enabled no)
			(sheetname "")
		)
		(fill yes
			(thermal_gap 0.5)
			(thermal_bridge_width 0.5)
			(island_removal_mode 0)
		)
		(polygon
			(pts
				(arc
					(start 257.193288 10.192004)
					(mid 256.489708 10.192004)
					(end 257.193288 10.192004)
				)
			)
		)
	)
	(zone
		(layers "F.Cu" "In5.Cu" "In7.Cu" "In9.Cu" "In11.Cu" "In13.Cu")
		(hatch none 0.5)
		(connect_pads
			(clearance 0)
		)
		(min_thickness 0.25)
		(keepout
			(tracks not_allowed)
			(vias allowed)
			(pads allowed)
			(copperpour not_allowed)
			(footprints allowed)
		)
		(placement
			(enabled no)
			(sheetname "")
		)
		(fill yes
			(thermal_gap 0.5)
			(thermal_bridge_width 0.5)
			(island_removal_mode 0)
		)
		(polygon
			(pts
				(arc
					(start 312.965084 10.217912)
					(mid 312.261504 10.217912)
					(end 312.965084 10.217912)
				)
			)
		)
	)
	(zone
		(layers "F.Cu" "In5.Cu" "In7.Cu" "In9.Cu" "In11.Cu" "In13.Cu")
		(hatch none 0.5)
		(connect_pads
			(clearance 0)
		)
		(min_thickness 0.25)
		(keepout
			(tracks not_allowed)
			(vias allowed)
			(pads allowed)
			(copperpour not_allowed)
			(footprints allowed)
		)
		(placement
			(enabled no)
			(sheetname "")
		)
		(fill yes
			(thermal_gap 0.5)
			(thermal_bridge_width 0.5)
			(island_removal_mode 0)
		)
		(polygon
			(pts
				(arc
					(start 274.973288 21.007324)
					(mid 274.269708 21.007324)
					(end 274.973288 21.007324)
				)
			)
		)
	)
	(zone
		(layer "B.Cu")
		(hatch none 0.5)
		(connect_pads
			(clearance 0)
		)
		(min_thickness 0.25)
		(keepout
			(tracks not_allowed)
			(vias allowed)
			(pads allowed)
			(copperpour not_allowed)
			(footprints allowed)
		)
		(placement
			(enabled no)
			(sheetname "")
		)
		(fill
			(thermal_gap 0.5)
			(thermal_bridge_width 0.5)
			(island_removal_mode 0)
		)
		(polygon
			(pts
				(arc
					(start 106.810048 -407.599896)
					(mid 104.010206 -404.800054)
					(end 101.21011 -407.599896)
				)
				(arc
					(start 101.21011 -407.599896)
					(mid 104.010206 -410.399992)
					(end 106.810048 -407.599896)
				)
			)
		)
	)
	(zone
		(layer "B.Cu")
		(hatch none 0.5)
		(connect_pads
			(clearance 0)
		)
		(min_thickness 0.25)
		(keepout
			(tracks not_allowed)
			(vias allowed)
			(pads allowed)
			(copperpour not_allowed)
			(footprints allowed)
		)
		(placement
			(enabled no)
			(sheetname "")
		)
		(fill
			(thermal_gap 0.5)
			(thermal_bridge_width 0.5)
			(island_removal_mode 0)
		)
		(polygon
			(pts
				(arc
					(start 32.6898 -405.589994)
					(mid 31.93034 -405.589994)
					(end 32.6898 -405.589994)
				)
			)
		)
	)
	(zone
		(layer "B.Cu")
		(hatch none 0.5)
		(connect_pads
			(clearance 0)
		)
		(min_thickness 0.25)
		(keepout
			(tracks allowed)
			(vias allowed)
			(pads allowed)
			(copperpour allowed)
			(footprints not_allowed)
		)
		(placement
			(enabled no)
			(sheetname "")
		)
		(fill
			(thermal_gap 0.5)
			(thermal_bridge_width 0.5)
			(island_removal_mode 0)
		)
		(polygon
			(pts
				(arc
					(start 83.319874 -20.72005)
					(mid 85.320124 -22.7203)
					(end 87.32012 -20.72005)
				)
				(arc
					(start 87.32012 -20.72005)
					(mid 85.320124 -18.720054)
					(end 83.319874 -20.72005)
				)
			)
		)
	)
	(zone
		(layer "B.Cu")
		(hatch none 0.5)
		(connect_pads
			(clearance 0)
		)
		(min_thickness 0.25)
		(keepout
			(tracks not_allowed)
			(vias allowed)
			(pads allowed)
			(copperpour not_allowed)
			(footprints allowed)
		)
		(placement
			(enabled no)
			(sheetname "")
		)
		(fill
			(thermal_gap 0.5)
			(thermal_bridge_width 0.5)
			(island_removal_mode 0)
		)
		(polygon
			(pts
				(arc
					(start 131.689856 -402.790152)
					(mid 130.930396 -402.790152)
					(end 131.689856 -402.790152)
				)
			)
		)
	)
	(zone
		(layer "B.Cu")
		(hatch none 0.5)
		(connect_pads
			(clearance 0)
		)
		(min_thickness 0.25)
		(keepout
			(tracks not_allowed)
			(vias allowed)
			(pads allowed)
			(copperpour not_allowed)
			(footprints allowed)
		)
		(placement
			(enabled no)
			(sheetname "")
		)
		(fill
			(thermal_gap 0.5)
			(thermal_bridge_width 0.5)
			(island_removal_mode 0)
		)
		(polygon
			(pts
				(arc
					(start 98.620072 -15.649956)
					(mid 96.620076 -13.64996)
					(end 94.62008 -15.649956)
				)
				(arc
					(start 94.62008 -15.649956)
					(mid 96.620076 -17.649952)
					(end 98.620072 -15.649956)
				)
			)
		)
	)
	(zone
		(layer "B.Cu")
		(hatch none 0.5)
		(connect_pads
			(clearance 0)
		)
		(min_thickness 0.25)
		(keepout
			(tracks not_allowed)
			(vias allowed)
			(pads allowed)
			(copperpour not_allowed)
			(footprints allowed)
		)
		(placement
			(enabled no)
			(sheetname "")
		)
		(fill
			(thermal_gap 0.5)
			(thermal_bridge_width 0.5)
			(island_removal_mode 0)
		)
		(polygon
			(pts
				(arc
					(start 384.669792 -400.390106)
					(mid 383.910332 -400.390106)
					(end 384.669792 -400.390106)
				)
			)
		)
	)
	(zone
		(layer "B.Cu")
		(hatch none 0.5)
		(connect_pads
			(clearance 0)
		)
		(min_thickness 0.25)
		(keepout
			(tracks not_allowed)
			(vias allowed)
			(pads allowed)
			(copperpour not_allowed)
			(footprints allowed)
		)
		(placement
			(enabled no)
			(sheetname "")
		)
		(fill
			(thermal_gap 0.5)
			(thermal_bridge_width 0.5)
			(island_removal_mode 0)
		)
		(polygon
			(pts
				(arc
					(start 48.08982 -371.590062)
					(mid 47.33036 -371.590062)
					(end 48.08982 -371.590062)
				)
			)
		)
	)
	(zone
		(layer "B.Cu")
		(hatch none 0.5)
		(connect_pads
			(clearance 0)
		)
		(min_thickness 0.25)
		(keepout
			(tracks not_allowed)
			(vias allowed)
			(pads allowed)
			(copperpour not_allowed)
			(footprints allowed)
		)
		(placement
			(enabled no)
			(sheetname "")
		)
		(fill
			(thermal_gap 0.5)
			(thermal_bridge_width 0.5)
			(island_removal_mode 0)
		)
		(polygon
			(pts
				(arc
					(start 314.976256 -306.349908)
					(mid 314.323476 -306.349908)
					(end 314.976256 -306.349908)
				)
			)
		)
	)
	(zone
		(layer "B.Cu")
		(hatch none 0.5)
		(connect_pads
			(clearance 0)
		)
		(min_thickness 0.25)
		(keepout
			(tracks not_allowed)
			(vias allowed)
			(pads allowed)
			(copperpour not_allowed)
			(footprints allowed)
		)
		(placement
			(enabled no)
			(sheetname "")
		)
		(fill
			(thermal_gap 0.5)
			(thermal_bridge_width 0.5)
			(island_removal_mode 0)
		)
		(polygon
			(pts
				(arc
					(start 380.1999 -270.89989)
					(mid 377.949968 -268.649958)
					(end 375.700036 -270.89989)
				)
				(arc
					(start 375.700036 -270.89989)
					(mid 377.949968 -273.149822)
					(end 380.1999 -270.89989)
				)
			)
		)
	)
	(zone
		(layer "B.Cu")
		(hatch none 0.5)
		(connect_pads
			(clearance 0)
		)
		(min_thickness 0.25)
		(keepout
			(tracks not_allowed)
			(vias allowed)
			(pads allowed)
			(copperpour not_allowed)
			(footprints allowed)
		)
		(placement
			(enabled no)
			(sheetname "")
		)
		(fill
			(thermal_gap 0.5)
			(thermal_bridge_width 0.5)
			(island_removal_mode 0)
		)
		(polygon
			(pts
				(arc
					(start 394.919962 -15.649956)
					(mid 392.919966 -13.64996)
					(end 390.91997 -15.649956)
				)
				(arc
					(start 390.91997 -15.649956)
					(mid 392.919966 -17.649952)
					(end 394.919962 -15.649956)
				)
			)
		)
	)
	(zone
		(layer "B.Cu")
		(hatch none 0.5)
		(connect_pads
			(clearance 0)
		)
		(min_thickness 0.25)
		(keepout
			(tracks allowed)
			(vias allowed)
			(pads allowed)
			(copperpour allowed)
			(footprints allowed)
		)
		(placement
			(enabled no)
			(sheetname "")
		)
		(fill
			(thermal_gap 0.5)
			(thermal_bridge_width 0.5)
			(island_removal_mode 0)
		)
		(polygon
			(pts
				(xy 345.959938 -312.599578) (xy 347.610938 -312.599578) (xy 347.610938 -314.758578) (xy 345.959938 -314.758578)
			)
		)
	)
	(zone
		(layer "B.Cu")
		(hatch none 0.5)
		(connect_pads
			(clearance 0)
		)
		(min_thickness 0.25)
		(keepout
			(tracks not_allowed)
			(vias allowed)
			(pads allowed)
			(copperpour not_allowed)
			(footprints allowed)
		)
		(placement
			(enabled no)
			(sheetname "")
		)
		(fill
			(thermal_gap 0.5)
			(thermal_bridge_width 0.5)
			(island_removal_mode 0)
		)
		(polygon
			(pts
				(arc
					(start 125.08992 -400.390106)
					(mid 124.33046 -400.390106)
					(end 125.08992 -400.390106)
				)
			)
		)
	)
	(zone
		(layer "B.Cu")
		(hatch none 0.5)
		(connect_pads
			(clearance 0)
		)
		(min_thickness 0.25)
		(keepout
			(tracks not_allowed)
			(vias allowed)
			(pads allowed)
			(copperpour not_allowed)
			(footprints allowed)
		)
		(placement
			(enabled no)
			(sheetname "")
		)
		(fill
			(thermal_gap 0.5)
			(thermal_bridge_width 0.5)
			(island_removal_mode 0)
		)
		(polygon
			(pts
				(arc
					(start 396.87627 -317.749936)
					(mid 396.22349 -317.749936)
					(end 396.87627 -317.749936)
				)
			)
		)
	)
	(zone
		(layer "B.Cu")
		(hatch none 0.5)
		(connect_pads
			(clearance 0)
		)
		(min_thickness 0.25)
		(keepout
			(tracks not_allowed)
			(vias allowed)
			(pads allowed)
			(copperpour not_allowed)
			(footprints allowed)
		)
		(placement
			(enabled no)
			(sheetname "")
		)
		(fill
			(thermal_gap 0.5)
			(thermal_bridge_width 0.5)
			(island_removal_mode 0)
		)
		(polygon
			(pts
				(arc
					(start 166.576248 -318.699896)
					(mid 165.923468 -318.699896)
					(end 166.576248 -318.699896)
				)
			)
		)
	)
	(zone
		(layer "B.Cu")
		(hatch none 0.5)
		(connect_pads
			(clearance 0)
		)
		(min_thickness 0.25)
		(keepout
			(tracks not_allowed)
			(vias allowed)
			(pads allowed)
			(copperpour not_allowed)
			(footprints allowed)
		)
		(placement
			(enabled no)
			(sheetname "")
		)
		(fill
			(thermal_gap 0.5)
			(thermal_bridge_width 0.5)
			(island_removal_mode 0)
		)
		(polygon
			(pts
				(arc
					(start 82.776314 -306.349908)
					(mid 82.123534 -306.349908)
					(end 82.776314 -306.349908)
				)
			)
		)
	)
	(zone
		(layer "B.Cu")
		(hatch none 0.5)
		(connect_pads
			(clearance 0)
		)
		(min_thickness 0.25)
		(keepout
			(tracks not_allowed)
			(vias allowed)
			(pads allowed)
			(copperpour not_allowed)
			(footprints allowed)
		)
		(placement
			(enabled no)
			(sheetname "")
		)
		(fill
			(thermal_gap 0.5)
			(thermal_bridge_width 0.5)
			(island_removal_mode 0)
		)
		(polygon
			(pts
				(arc
					(start 380.26975 -400.390106)
					(mid 379.51029 -400.390106)
					(end 380.26975 -400.390106)
				)
			)
		)
	)
	(zone
		(layer "B.Cu")
		(hatch none 0.5)
		(connect_pads
			(clearance 0)
		)
		(min_thickness 0.25)
		(keepout
			(tracks not_allowed)
			(vias allowed)
			(pads allowed)
			(copperpour not_allowed)
			(footprints allowed)
		)
		(placement
			(enabled no)
			(sheetname "")
		)
		(fill
			(thermal_gap 0.5)
			(thermal_bridge_width 0.5)
			(island_removal_mode 0)
		)
		(polygon
			(pts
				(arc
					(start 136.720072 -15.649956)
					(mid 134.720076 -13.64996)
					(end 132.72008 -15.649956)
				)
				(arc
					(start 132.72008 -15.649956)
					(mid 134.720076 -17.649952)
					(end 136.720072 -15.649956)
				)
			)
		)
	)
	(zone
		(layer "B.Cu")
		(hatch none 0.5)
		(connect_pads
			(clearance 0)
		)
		(min_thickness 0.25)
		(keepout
			(tracks allowed)
			(vias allowed)
			(pads allowed)
			(copperpour allowed)
			(footprints not_allowed)
		)
		(placement
			(enabled no)
			(sheetname "")
		)
		(fill
			(thermal_gap 0.5)
			(thermal_bridge_width 0.5)
			(island_removal_mode 0)
		)
		(polygon
			(pts
				(arc
					(start 460.099918 -313.85002)
					(mid 464.09991 -317.850012)
					(end 468.099902 -313.85002)
				)
				(arc
					(start 468.099902 -313.85002)
					(mid 464.09991 -309.850028)
					(end 460.099918 -313.85002)
				)
			)
		)
	)
	(zone
		(layer "B.Cu")
		(hatch none 0.5)
		(connect_pads
			(clearance 0)
		)
		(min_thickness 0.25)
		(keepout
			(tracks allowed)
			(vias allowed)
			(pads allowed)
			(copperpour allowed)
			(footprints not_allowed)
		)
		(placement
			(enabled no)
			(sheetname "")
		)
		(fill
			(thermal_gap 0.5)
			(thermal_bridge_width 0.5)
			(island_removal_mode 0)
		)
		(polygon
			(pts
				(arc
					(start 273.200114 -393.100052)
					(mid 268.200124 -388.100062)
					(end 263.19988 -393.100052)
				)
				(arc
					(start 263.19988 -393.100052)
					(mid 268.200124 -398.100296)
					(end 273.200114 -393.100052)
				)
			)
		)
	)
	(zone
		(layer "B.Cu")
		(hatch none 0.5)
		(connect_pads
			(clearance 0)
		)
		(min_thickness 0.25)
		(keepout
			(tracks not_allowed)
			(vias allowed)
			(pads allowed)
			(copperpour not_allowed)
			(footprints allowed)
		)
		(placement
			(enabled no)
			(sheetname "")
		)
		(fill
			(thermal_gap 0.5)
			(thermal_bridge_width 0.5)
			(island_removal_mode 0)
		)
		(polygon
			(pts
				(arc
					(start 116.289836 -370.489988)
					(mid 115.530376 -370.489988)
					(end 116.289836 -370.489988)
				)
			)
		)
	)
	(zone
		(layer "B.Cu")
		(hatch none 0.5)
		(connect_pads
			(clearance 0)
		)
		(min_thickness 0.25)
		(keepout
			(tracks allowed)
			(vias allowed)
			(pads allowed)
			(copperpour allowed)
			(footprints allowed)
		)
		(placement
			(enabled no)
			(sheetname "")
		)
		(fill
			(thermal_gap 0.5)
			(thermal_bridge_width 0.5)
			(island_removal_mode 0)
		)
		(polygon
			(pts
				(xy 104.981248 -353.61118) (xy 108.058458 -353.61118) (xy 108.215938 -353.4537) (xy 108.215938 -350.795844)
				(xy 108.128562 -350.708468) (xy 105.007664 -350.708468) (xy 104.941878 -350.774254) (xy 104.941878 -353.57181)
			)
		)
	)
	(zone
		(layer "B.Cu")
		(hatch none 0.5)
		(connect_pads
			(clearance 0)
		)
		(min_thickness 0.25)
		(keepout
			(tracks not_allowed)
			(vias allowed)
			(pads allowed)
			(copperpour not_allowed)
			(footprints allowed)
		)
		(placement
			(enabled no)
			(sheetname "")
		)
		(fill
			(thermal_gap 0.5)
			(thermal_bridge_width 0.5)
			(island_removal_mode 0)
		)
		(polygon
			(pts
				(arc
					(start 303.26965 -405.390096)
					(mid 302.51019 -405.390096)
					(end 303.26965 -405.390096)
				)
			)
		)
	)
	(zone
		(layer "B.Cu")
		(hatch none 0.5)
		(connect_pads
			(clearance 0)
		)
		(min_thickness 0.25)
		(keepout
			(tracks not_allowed)
			(vias allowed)
			(pads allowed)
			(copperpour not_allowed)
			(footprints allowed)
		)
		(placement
			(enabled no)
			(sheetname "")
		)
		(fill
			(thermal_gap 0.5)
			(thermal_bridge_width 0.5)
			(island_removal_mode 0)
		)
		(polygon
			(pts
				(arc
					(start 30.489652 -380.69012)
					(mid 29.730192 -380.69012)
					(end 30.489652 -380.69012)
				)
			)
		)
	)
	(zone
		(layer "B.Cu")
		(hatch none 0.5)
		(connect_pads
			(clearance 0)
		)
		(min_thickness 0.25)
		(keepout
			(tracks not_allowed)
			(vias allowed)
			(pads allowed)
			(copperpour not_allowed)
			(footprints allowed)
		)
		(placement
			(enabled no)
			(sheetname "")
		)
		(fill
			(thermal_gap 0.5)
			(thermal_bridge_width 0.5)
			(island_removal_mode 0)
		)
		(polygon
			(pts
				(arc
					(start 107.214924 -17.999964)
					(mid 110.01502 -20.80006)
					(end 112.815116 -17.999964)
				)
				(arc
					(start 112.815116 -17.999964)
					(mid 110.01502 -15.199868)
					(end 107.214924 -17.999964)
				)
			)
		)
	)
	(zone
		(layer "B.Cu")
		(hatch none 0.5)
		(connect_pads
			(clearance 0)
		)
		(min_thickness 0.25)
		(keepout
			(tracks not_allowed)
			(vias allowed)
			(pads allowed)
			(copperpour not_allowed)
			(footprints allowed)
		)
		(placement
			(enabled no)
			(sheetname "")
		)
		(fill
			(thermal_gap 0.5)
			(thermal_bridge_width 0.5)
			(island_removal_mode 0)
		)
		(polygon
			(pts
				(arc
					(start 116.289836 -401.690078)
					(mid 115.530376 -401.690078)
					(end 116.289836 -401.690078)
				)
			)
		)
	)
	(zone
		(layer "B.Cu")
		(hatch none 0.5)
		(connect_pads
			(clearance 0)
		)
		(min_thickness 0.25)
		(keepout
			(tracks not_allowed)
			(vias allowed)
			(pads allowed)
			(copperpour not_allowed)
			(footprints allowed)
		)
		(placement
			(enabled no)
			(sheetname "")
		)
		(fill
			(thermal_gap 0.5)
			(thermal_bridge_width 0.5)
			(island_removal_mode 0)
		)
		(polygon
			(pts
				(arc
					(start 163.726368 -316.799722)
					(mid 163.073588 -316.799722)
					(end 163.726368 -316.799722)
				)
			)
		)
	)
	(zone
		(layer "B.Cu")
		(hatch none 0.5)
		(connect_pads
			(clearance 0)
		)
		(min_thickness 0.25)
		(keepout
			(tracks not_allowed)
			(vias allowed)
			(pads allowed)
			(copperpour not_allowed)
			(footprints allowed)
		)
		(placement
			(enabled no)
			(sheetname "")
		)
		(fill
			(thermal_gap 0.5)
			(thermal_bridge_width 0.5)
			(island_removal_mode 0)
		)
		(polygon
			(pts
				(arc
					(start 463.199988 -13.599922)
					(mid 461.600042 -11.999976)
					(end 460.000096 -13.599922)
				)
				(arc
					(start 460.000096 -15.200122)
					(mid 461.600042 -16.800068)
					(end 463.199988 -15.200122)
				)
			)
		)
	)
	(zone
		(layer "B.Cu")
		(hatch none 0.5)
		(connect_pads
			(clearance 0)
		)
		(min_thickness 0.25)
		(keepout
			(tracks not_allowed)
			(vias allowed)
			(pads allowed)
			(copperpour not_allowed)
			(footprints allowed)
		)
		(placement
			(enabled no)
			(sheetname "")
		)
		(fill
			(thermal_gap 0.5)
			(thermal_bridge_width 0.5)
			(island_removal_mode 0)
		)
		(polygon
			(pts
				(arc
					(start 16.800068 -84.70011)
					(mid 18.800064 -86.700106)
					(end 20.80006 -84.70011)
				)
				(arc
					(start 20.80006 -84.70011)
					(mid 18.800064 -82.700114)
					(end 16.800068 -84.70011)
				)
			)
		)
	)
	(zone
		(layer "B.Cu")
		(hatch none 0.5)
		(connect_pads
			(clearance 0)
		)
		(min_thickness 0.25)
		(keepout
			(tracks not_allowed)
			(vias allowed)
			(pads allowed)
			(copperpour not_allowed)
			(footprints allowed)
		)
		(placement
			(enabled no)
			(sheetname "")
		)
		(fill
			(thermal_gap 0.5)
			(thermal_bridge_width 0.5)
			(island_removal_mode 0)
		)
		(polygon
			(pts
				(arc
					(start 303.26965 -380.69012)
					(mid 302.51019 -380.69012)
					(end 303.26965 -380.69012)
				)
			)
		)
	)
	(zone
		(layer "B.Cu")
		(hatch none 0.5)
		(connect_pads
			(clearance 0)
		)
		(min_thickness 0.25)
		(keepout
			(tracks not_allowed)
			(vias allowed)
			(pads allowed)
			(copperpour not_allowed)
			(footprints allowed)
		)
		(placement
			(enabled no)
			(sheetname "")
		)
		(fill
			(thermal_gap 0.5)
			(thermal_bridge_width 0.5)
			(island_removal_mode 0)
		)
		(polygon
			(pts
				(arc
					(start 433.449984 -320.900044)
					(mid 437.950102 -325.400162)
					(end 442.449966 -320.900044)
				)
				(arc
					(start 442.449966 -320.900044)
					(mid 437.950102 -316.40018)
					(end 433.449984 -320.900044)
				)
			)
		)
	)
	(zone
		(layer "B.Cu")
		(hatch none 0.5)
		(connect_pads
			(clearance 0)
		)
		(min_thickness 0.25)
		(keepout
			(tracks not_allowed)
			(vias allowed)
			(pads allowed)
			(copperpour not_allowed)
			(footprints allowed)
		)
		(placement
			(enabled no)
			(sheetname "")
		)
		(fill
			(thermal_gap 0.5)
			(thermal_bridge_width 0.5)
			(island_removal_mode 0)
		)
		(polygon
			(pts
				(arc
					(start 125.42012 -20.72005)
					(mid 123.420124 -18.720054)
					(end 121.419874 -20.72005)
				)
				(arc
					(start 121.419874 -20.72005)
					(mid 123.420124 -22.7203)
					(end 125.42012 -20.72005)
				)
			)
		)
	)
	(zone
		(layer "B.Cu")
		(hatch none 0.5)
		(connect_pads
			(clearance 0)
		)
		(min_thickness 0.25)
		(keepout
			(tracks not_allowed)
			(vias allowed)
			(pads allowed)
			(copperpour not_allowed)
			(footprints allowed)
		)
		(placement
			(enabled no)
			(sheetname "")
		)
		(fill
			(thermal_gap 0.5)
			(thermal_bridge_width 0.5)
			(island_removal_mode 0)
		)
		(polygon
			(pts
				(arc
					(start 54.699916 -368.516662)
					(mid 53.996336 -368.516662)
					(end 54.699916 -368.516662)
				)
			)
		)
	)
	(zone
		(layer "B.Cu")
		(hatch none 0.5)
		(connect_pads
			(clearance 0)
		)
		(min_thickness 0.25)
		(keepout
			(tracks allowed)
			(vias allowed)
			(pads allowed)
			(copperpour allowed)
			(footprints not_allowed)
		)
		(placement
			(enabled no)
			(sheetname "")
		)
		(fill
			(thermal_gap 0.5)
			(thermal_bridge_width 0.5)
			(island_removal_mode 0)
		)
		(polygon
			(pts
				(arc
					(start 99.009962 -407.599896)
					(mid 104.009952 -412.599886)
					(end 109.009942 -407.599896)
				)
				(arc
					(start 109.009942 -407.599896)
					(mid 104.009952 -402.599906)
					(end 99.009962 -407.599896)
				)
			)
		)
	)
	(zone
		(layer "B.Cu")
		(hatch none 0.5)
		(connect_pads
			(clearance 0)
		)
		(min_thickness 0.25)
		(keepout
			(tracks allowed)
			(vias allowed)
			(pads allowed)
			(copperpour allowed)
			(footprints not_allowed)
		)
		(placement
			(enabled no)
			(sheetname "")
		)
		(fill
			(thermal_gap 0.5)
			(thermal_bridge_width 0.5)
			(island_removal_mode 0)
		)
		(polygon
			(pts
				(arc
					(start 173.420024 -20.72005)
					(mid 175.42002 -22.720046)
					(end 177.420016 -20.72005)
				)
				(arc
					(start 177.420016 -20.72005)
					(mid 175.42002 -18.720054)
					(end 173.420024 -20.72005)
				)
			)
		)
	)
	(zone
		(layer "B.Cu")
		(hatch none 0.5)
		(connect_pads
			(clearance 0)
		)
		(min_thickness 0.25)
		(keepout
			(tracks not_allowed)
			(vias allowed)
			(pads allowed)
			(copperpour not_allowed)
			(footprints allowed)
		)
		(placement
			(enabled no)
			(sheetname "")
		)
		(fill
			(thermal_gap 0.5)
			(thermal_bridge_width 0.5)
			(island_removal_mode 0)
		)
		(polygon
			(pts
				(arc
					(start 307.376322 -318.699896)
					(mid 306.723542 -318.699896)
					(end 307.376322 -318.699896)
				)
			)
		)
	)
	(zone
		(layer "B.Cu")
		(hatch none 0.5)
		(connect_pads
			(clearance 0)
		)
		(min_thickness 0.25)
		(keepout
			(tracks not_allowed)
			(vias allowed)
			(pads allowed)
			(copperpour not_allowed)
			(footprints allowed)
		)
		(placement
			(enabled no)
			(sheetname "")
		)
		(fill
			(thermal_gap 0.5)
			(thermal_bridge_width 0.5)
			(island_removal_mode 0)
		)
		(polygon
			(pts
				(arc
					(start 347.09989 -194.360038)
					(mid 349.899986 -197.160134)
					(end 352.700082 -194.360038)
				)
				(arc
					(start 352.700082 -194.360038)
					(mid 349.899986 -191.559942)
					(end 347.09989 -194.360038)
				)
			)
		)
	)
	(zone
		(layer "B.Cu")
		(hatch none 0.5)
		(connect_pads
			(clearance 0)
		)
		(min_thickness 0.25)
		(keepout
			(tracks not_allowed)
			(vias allowed)
			(pads allowed)
			(copperpour not_allowed)
			(footprints allowed)
		)
		(placement
			(enabled no)
			(sheetname "")
		)
		(fill
			(thermal_gap 0.5)
			(thermal_bridge_width 0.5)
			(island_removal_mode 0)
		)
		(polygon
			(pts
				(arc
					(start 34.889694 -379.390148)
					(mid 34.130234 -379.390148)
					(end 34.889694 -379.390148)
				)
			)
		)
	)
	(zone
		(layer "B.Cu")
		(hatch none 0.5)
		(connect_pads
			(clearance 0)
		)
		(min_thickness 0.25)
		(keepout
			(tracks not_allowed)
			(vias allowed)
			(pads allowed)
			(copperpour not_allowed)
			(footprints allowed)
		)
		(placement
			(enabled no)
			(sheetname "")
		)
		(fill
			(thermal_gap 0.5)
			(thermal_bridge_width 0.5)
			(island_removal_mode 0)
		)
		(polygon
			(pts
				(arc
					(start 460.04988 -398.100042)
					(mid 461.600042 -399.650204)
					(end 463.14995 -398.100042)
				)
				(arc
					(start 463.14995 -398.100042)
					(mid 461.600042 -396.550134)
					(end 460.04988 -398.100042)
				)
			)
		)
	)
	(zone
		(layer "B.Cu")
		(hatch none 0.5)
		(connect_pads
			(clearance 0)
		)
		(min_thickness 0.25)
		(keepout
			(tracks allowed)
			(vias allowed)
			(pads allowed)
			(copperpour allowed)
			(footprints allowed)
		)
		(placement
			(enabled no)
			(sheetname "")
		)
		(fill
			(thermal_gap 0.5)
			(thermal_bridge_width 0.5)
			(island_removal_mode 0)
		)
		(polygon
			(pts
				(xy 104.551734 -376.039126) (xy 104.551734 -374.855486) (xy 106.297984 -374.855486) (xy 106.297984 -376.039126)
			)
		)
	)
	(zone
		(layer "B.Cu")
		(hatch none 0.5)
		(connect_pads
			(clearance 0)
		)
		(min_thickness 0.25)
		(keepout
			(tracks not_allowed)
			(vias allowed)
			(pads allowed)
			(copperpour not_allowed)
			(footprints allowed)
		)
		(placement
			(enabled no)
			(sheetname "")
		)
		(fill
			(thermal_gap 0.5)
			(thermal_bridge_width 0.5)
			(island_removal_mode 0)
		)
		(polygon
			(pts
				(arc
					(start 307.376322 -317.749936)
					(mid 306.723542 -317.749936)
					(end 307.376322 -317.749936)
				)
			)
		)
	)
	(zone
		(layer "B.Cu")
		(hatch none 0.5)
		(connect_pads
			(clearance 0)
		)
		(min_thickness 0.25)
		(keepout
			(tracks not_allowed)
			(vias allowed)
			(pads allowed)
			(copperpour not_allowed)
			(footprints allowed)
		)
		(placement
			(enabled no)
			(sheetname "")
		)
		(fill
			(thermal_gap 0.5)
			(thermal_bridge_width 0.5)
			(island_removal_mode 0)
		)
		(polygon
			(pts
				(arc
					(start 420.626286 -315.849762)
					(mid 419.973506 -315.849762)
					(end 420.626286 -315.849762)
				)
			)
		)
	)
	(zone
		(layer "B.Cu")
		(hatch none 0.5)
		(connect_pads
			(clearance 0)
		)
		(min_thickness 0.25)
		(keepout
			(tracks not_allowed)
			(vias allowed)
			(pads allowed)
			(copperpour not_allowed)
			(footprints allowed)
		)
		(placement
			(enabled no)
			(sheetname "")
		)
		(fill
			(thermal_gap 0.5)
			(thermal_bridge_width 0.5)
			(island_removal_mode 0)
		)
		(polygon
			(pts
				(arc
					(start 132.999988 -276.010116)
					(mid 136.250172 -279.2603)
					(end 139.500102 -276.010116)
				)
				(arc
					(start 139.500102 -276.010116)
					(mid 136.250172 -272.760186)
					(end 132.999988 -276.010116)
				)
			)
		)
	)
	(zone
		(layer "B.Cu")
		(hatch none 0.5)
		(connect_pads
			(clearance 0)
		)
		(min_thickness 0.25)
		(keepout
			(tracks not_allowed)
			(vias allowed)
			(pads allowed)
			(copperpour not_allowed)
			(footprints allowed)
		)
		(placement
			(enabled no)
			(sheetname "")
		)
		(fill
			(thermal_gap 0.5)
			(thermal_bridge_width 0.5)
			(island_removal_mode 0)
		)
		(polygon
			(pts
				(arc
					(start 31.900114 -320.900044)
					(mid 29.650182 -318.650112)
					(end 27.399996 -320.900044)
				)
				(arc
					(start 27.399996 -320.900044)
					(mid 29.650182 -323.15023)
					(end 31.900114 -320.900044)
				)
			)
		)
	)
	(zone
		(layer "B.Cu")
		(hatch none 0.5)
		(connect_pads
			(clearance 0)
		)
		(min_thickness 0.25)
		(keepout
			(tracks not_allowed)
			(vias allowed)
			(pads allowed)
			(copperpour not_allowed)
			(footprints allowed)
		)
		(placement
			(enabled no)
			(sheetname "")
		)
		(fill
			(thermal_gap 0.5)
			(thermal_bridge_width 0.5)
			(island_removal_mode 0)
		)
		(polygon
			(pts
				(arc
					(start 380.26975 -371.790214)
					(mid 379.51029 -371.790214)
					(end 380.26975 -371.790214)
				)
			)
		)
	)
	(zone
		(layer "B.Cu")
		(hatch none 0.5)
		(connect_pads
			(clearance 0)
		)
		(min_thickness 0.25)
		(keepout
			(tracks not_allowed)
			(vias allowed)
			(pads allowed)
			(copperpour not_allowed)
			(footprints allowed)
		)
		(placement
			(enabled no)
			(sheetname "")
		)
		(fill
			(thermal_gap 0.5)
			(thermal_bridge_width 0.5)
			(island_removal_mode 0)
		)
		(polygon
			(pts
				(arc
					(start 394.02639 -316.799722)
					(mid 393.37361 -316.799722)
					(end 394.02639 -316.799722)
				)
			)
		)
	)
	(zone
		(layer "B.Cu")
		(hatch none 0.5)
		(connect_pads
			(clearance 0)
		)
		(min_thickness 0.25)
		(keepout
			(tracks allowed)
			(vias allowed)
			(pads allowed)
			(copperpour allowed)
			(footprints not_allowed)
		)
		(placement
			(enabled no)
			(sheetname "")
		)
		(fill
			(thermal_gap 0.5)
			(thermal_bridge_width 0.5)
			(island_removal_mode 0)
		)
		(polygon
			(pts
				(arc
					(start 354.899976 -194.360038)
					(mid 349.899986 -189.360048)
					(end 344.899996 -194.360038)
				)
				(arc
					(start 344.899996 -194.360038)
					(mid 349.899986 -199.360028)
					(end 354.899976 -194.360038)
				)
			)
		)
	)
	(zone
		(layer "B.Cu")
		(hatch none 0.5)
		(connect_pads
			(clearance 0)
		)
		(min_thickness 0.25)
		(keepout
			(tracks allowed)
			(vias allowed)
			(pads allowed)
			(copperpour allowed)
			(footprints not_allowed)
		)
		(placement
			(enabled no)
			(sheetname "")
		)
		(fill
			(thermal_gap 0.5)
			(thermal_bridge_width 0.5)
			(island_removal_mode 0)
		)
		(polygon
			(pts
				(arc
					(start 344.899996 -194.360038)
					(mid 349.899986 -199.360028)
					(end 354.899976 -194.360038)
				)
				(arc
					(start 354.899976 -194.360038)
					(mid 349.899986 -189.360048)
					(end 344.899996 -194.360038)
				)
			)
		)
	)
	(zone
		(layer "B.Cu")
		(hatch none 0.5)
		(connect_pads
			(clearance 0)
		)
		(min_thickness 0.25)
		(keepout
			(tracks allowed)
			(vias allowed)
			(pads allowed)
			(copperpour allowed)
			(footprints not_allowed)
		)
		(placement
			(enabled no)
			(sheetname "")
		)
		(fill
			(thermal_gap 0.5)
			(thermal_bridge_width 0.5)
			(island_removal_mode 0)
		)
		(polygon
			(pts
				(arc
					(start 358.590088 -407.599896)
					(mid 363.590078 -412.599886)
					(end 368.590068 -407.599896)
				)
				(arc
					(start 368.590068 -407.599896)
					(mid 363.590078 -402.599906)
					(end 358.590088 -407.599896)
				)
			)
		)
	)
	(zone
		(layer "B.Cu")
		(hatch none 0.5)
		(connect_pads
			(clearance 0)
		)
		(min_thickness 0.25)
		(keepout
			(tracks not_allowed)
			(vias allowed)
			(pads allowed)
			(copperpour not_allowed)
			(footprints allowed)
		)
		(placement
			(enabled no)
			(sheetname "")
		)
		(fill
			(thermal_gap 0.5)
			(thermal_bridge_width 0.5)
			(island_removal_mode 0)
		)
		(polygon
			(pts
				(arc
					(start 460.84998 -313.85002)
					(mid 464.100164 -317.100204)
					(end 467.350094 -313.85002)
				)
				(arc
					(start 467.350094 -313.85002)
					(mid 464.100164 -310.60009)
					(end 460.84998 -313.85002)
				)
			)
		)
	)
	(zone
		(layer "B.Cu")
		(hatch none 0.5)
		(connect_pads
			(clearance 0)
		)
		(min_thickness 0.25)
		(keepout
			(tracks not_allowed)
			(vias allowed)
			(pads allowed)
			(copperpour not_allowed)
			(footprints allowed)
		)
		(placement
			(enabled no)
			(sheetname "")
		)
		(fill
			(thermal_gap 0.5)
			(thermal_bridge_width 0.5)
			(island_removal_mode 0)
		)
		(polygon
			(pts
				(arc
					(start 116.289836 -400.390106)
					(mid 115.530376 -400.390106)
					(end 116.289836 -400.390106)
				)
			)
		)
	)
	(zone
		(layer "B.Cu")
		(hatch none 0.5)
		(connect_pads
			(clearance 0)
		)
		(min_thickness 0.25)
		(keepout
			(tracks not_allowed)
			(vias allowed)
			(pads allowed)
			(copperpour not_allowed)
			(footprints allowed)
		)
		(placement
			(enabled no)
			(sheetname "")
		)
		(fill
			(thermal_gap 0.5)
			(thermal_bridge_width 0.5)
			(island_removal_mode 0)
		)
		(polygon
			(pts
				(arc
					(start 20.80006 -194.360038)
					(mid 15.80007 -189.360048)
					(end 10.80008 -194.360038)
				)
				(arc
					(start 10.80008 -194.360038)
					(mid 15.80007 -199.360028)
					(end 20.80006 -194.360038)
				)
			)
		)
	)
	(zone
		(layer "B.Cu")
		(hatch none 0.5)
		(connect_pads
			(clearance 0)
		)
		(min_thickness 0.25)
		(keepout
			(tracks not_allowed)
			(vias allowed)
			(pads allowed)
			(copperpour not_allowed)
			(footprints allowed)
		)
		(placement
			(enabled no)
			(sheetname "")
		)
		(fill
			(thermal_gap 0.5)
			(thermal_bridge_width 0.5)
			(island_removal_mode 0)
		)
		(polygon
			(pts
				(arc
					(start 380.1999 -320.900044)
					(mid 377.949968 -318.650112)
					(end 375.700036 -320.900044)
				)
				(arc
					(start 375.700036 -320.900044)
					(mid 377.949968 -323.149976)
					(end 380.1999 -320.900044)
				)
			)
		)
	)
	(zone
		(layer "B.Cu")
		(hatch none 0.5)
		(connect_pads
			(clearance 0)
		)
		(min_thickness 0.25)
		(keepout
			(tracks not_allowed)
			(vias allowed)
			(pads allowed)
			(copperpour not_allowed)
			(footprints allowed)
		)
		(placement
			(enabled no)
			(sheetname "")
		)
		(fill
			(thermal_gap 0.5)
			(thermal_bridge_width 0.5)
			(island_removal_mode 0)
		)
		(polygon
			(pts
				(arc
					(start 378.069602 -402.790152)
					(mid 377.310142 -402.790152)
					(end 378.069602 -402.790152)
				)
			)
		)
	)
	(zone
		(layer "B.Cu")
		(hatch none 0.5)
		(connect_pads
			(clearance 0)
		)
		(min_thickness 0.25)
		(keepout
			(tracks not_allowed)
			(vias allowed)
			(pads allowed)
			(copperpour not_allowed)
			(footprints allowed)
		)
		(placement
			(enabled no)
			(sheetname "")
		)
		(fill
			(thermal_gap 0.5)
			(thermal_bridge_width 0.5)
			(island_removal_mode 0)
		)
		(polygon
			(pts
				(arc
					(start 311.176162 -317.749936)
					(mid 310.523382 -317.749936)
					(end 311.176162 -317.749936)
				)
			)
		)
	)
	(zone
		(layer "B.Cu")
		(hatch none 0.5)
		(connect_pads
			(clearance 0)
		)
		(min_thickness 0.25)
		(keepout
			(tracks not_allowed)
			(vias allowed)
			(pads allowed)
			(copperpour not_allowed)
			(footprints allowed)
		)
		(placement
			(enabled no)
			(sheetname "")
		)
		(fill
			(thermal_gap 0.5)
			(thermal_bridge_width 0.5)
			(island_removal_mode 0)
		)
		(polygon
			(pts
				(arc
					(start 310.226202 -315.849762)
					(mid 309.573422 -315.849762)
					(end 310.226202 -315.849762)
				)
			)
		)
	)
	(zone
		(layer "B.Cu")
		(hatch none 0.5)
		(connect_pads
			(clearance 0)
		)
		(min_thickness 0.25)
		(keepout
			(tracks not_allowed)
			(vias allowed)
			(pads allowed)
			(copperpour not_allowed)
			(footprints allowed)
		)
		(placement
			(enabled no)
			(sheetname "")
		)
		(fill
			(thermal_gap 0.5)
			(thermal_bridge_width 0.5)
			(island_removal_mode 0)
		)
		(polygon
			(pts
				(arc
					(start 141.249908 -270.89989)
					(mid 145.750026 -275.400008)
					(end 150.24989 -270.89989)
				)
				(arc
					(start 150.24989 -270.89989)
					(mid 145.750026 -266.400026)
					(end 141.249908 -270.89989)
				)
			)
		)
	)
	(zone
		(layer "B.Cu")
		(hatch none 0.5)
		(connect_pads
			(clearance 0)
		)
		(min_thickness 0.25)
		(keepout
			(tracks allowed)
			(vias allowed)
			(pads allowed)
			(copperpour allowed)
			(footprints not_allowed)
		)
		(placement
			(enabled no)
			(sheetname "")
		)
		(fill
			(thermal_gap 0.5)
			(thermal_bridge_width 0.5)
			(island_removal_mode 0)
		)
		(polygon
			(pts
				(arc
					(start 460.180944 -314.65012)
					(mid 462.73922 -317.611267)
					(end 466.600032 -316.972442)
				)
				(xy 466.600032 -328.972418) (xy 448.449954 -328.972418) (xy 448.449954 -312.482992) (xy 448.520058 -312.464196)
				(xy 448.520058 -314.65012)
			)
		)
	)
	(zone
		(layer "B.Cu")
		(hatch none 0.5)
		(connect_pads
			(clearance 0)
		)
		(min_thickness 0.25)
		(keepout
			(tracks not_allowed)
			(vias allowed)
			(pads allowed)
			(copperpour not_allowed)
			(footprints allowed)
		)
		(placement
			(enabled no)
			(sheetname "")
		)
		(fill
			(thermal_gap 0.5)
			(thermal_bridge_width 0.5)
			(island_removal_mode 0)
		)
		(polygon
			(pts
				(arc
					(start 386.869686 -371.590062)
					(mid 386.110226 -371.590062)
					(end 386.869686 -371.590062)
				)
			)
		)
	)
	(zone
		(layer "B.Cu")
		(hatch none 0.5)
		(connect_pads
			(clearance 0)
		)
		(min_thickness 0.25)
		(keepout
			(tracks not_allowed)
			(vias allowed)
			(pads allowed)
			(copperpour not_allowed)
			(footprints allowed)
		)
		(placement
			(enabled no)
			(sheetname "")
		)
		(fill
			(thermal_gap 0.5)
			(thermal_bridge_width 0.5)
			(island_removal_mode 0)
		)
		(polygon
			(pts
				(arc
					(start 182.72633 -316.799722)
					(mid 182.07355 -316.799722)
					(end 182.72633 -316.799722)
				)
			)
		)
	)
	(zone
		(layer "B.Cu")
		(hatch none 0.5)
		(connect_pads
			(clearance 0)
		)
		(min_thickness 0.25)
		(keepout
			(tracks allowed)
			(vias allowed)
			(pads allowed)
			(copperpour allowed)
			(footprints allowed)
		)
		(placement
			(enabled no)
			(sheetname "")
		)
		(fill
			(thermal_gap 0.5)
			(thermal_bridge_width 0.5)
			(island_removal_mode 0)
		)
		(polygon
			(pts
				(xy 44.352464 -398.58442) (xy 45.093128 -398.58442) (xy 45.729144 -397.948404) (xy 45.729144 -396.133574)
				(xy 45.040804 -395.445234) (xy 44.216828 -395.445234) (xy 44.133516 -395.528546) (xy 44.133516 -398.365472)
			)
		)
	)
	(zone
		(layer "B.Cu")
		(hatch none 0.5)
		(connect_pads
			(clearance 0)
		)
		(min_thickness 0.25)
		(keepout
			(tracks allowed)
			(vias allowed)
			(pads allowed)
			(copperpour allowed)
			(footprints not_allowed)
		)
		(placement
			(enabled no)
			(sheetname "")
		)
		(fill
			(thermal_gap 0.5)
			(thermal_bridge_width 0.5)
			(island_removal_mode 0)
		)
		(polygon
			(pts
				(arc
					(start 184.719976 -15.649956)
					(mid 186.719972 -17.649952)
					(end 188.719968 -15.649956)
				)
				(arc
					(start 188.719968 -15.649956)
					(mid 186.719972 -13.64996)
					(end 184.719976 -15.649956)
				)
			)
		)
	)
	(zone
		(layer "B.Cu")
		(hatch none 0.5)
		(connect_pads
			(clearance 0)
		)
		(min_thickness 0.25)
		(keepout
			(tracks not_allowed)
			(vias allowed)
			(pads allowed)
			(copperpour not_allowed)
			(footprints allowed)
		)
		(placement
			(enabled no)
			(sheetname "")
		)
		(fill
			(thermal_gap 0.5)
			(thermal_bridge_width 0.5)
			(island_removal_mode 0)
		)
		(polygon
			(pts
				(arc
					(start 23.800054 -84.70011)
					(mid 18.800064 -79.70012)
					(end 13.800074 -84.70011)
				)
				(arc
					(start 13.800074 -84.70011)
					(mid 18.800064 -89.7001)
					(end 23.800054 -84.70011)
				)
			)
		)
	)
	(zone
		(layer "B.Cu")
		(hatch none 0.5)
		(connect_pads
			(clearance 0)
		)
		(min_thickness 0.25)
		(keepout
			(tracks not_allowed)
			(vias allowed)
			(pads allowed)
			(copperpour not_allowed)
			(footprints allowed)
		)
		(placement
			(enabled no)
			(sheetname "")
		)
		(fill
			(thermal_gap 0.5)
			(thermal_bridge_width 0.5)
			(island_removal_mode 0)
		)
		(polygon
			(pts
				(arc
					(start 131.689856 -372.890034)
					(mid 130.930396 -372.890034)
					(end 131.689856 -372.890034)
				)
			)
		)
	)
	(zone
		(layer "B.Cu")
		(hatch none 0.5)
		(connect_pads
			(clearance 0)
		)
		(min_thickness 0.25)
		(keepout
			(tracks not_allowed)
			(vias allowed)
			(pads allowed)
			(copperpour not_allowed)
			(footprints allowed)
		)
		(placement
			(enabled no)
			(sheetname "")
		)
		(fill
			(thermal_gap 0.5)
			(thermal_bridge_width 0.5)
			(island_removal_mode 0)
		)
		(polygon
			(pts
				(arc
					(start 317.349886 -270.89989)
					(mid 321.850004 -275.400008)
					(end 326.350122 -270.89989)
				)
				(arc
					(start 326.350122 -270.89989)
					(mid 321.850004 -266.399772)
					(end 317.349886 -270.89989)
				)
			)
		)
	)
	(zone
		(layer "B.Cu")
		(hatch none 0.5)
		(connect_pads
			(clearance 0)
		)
		(min_thickness 0.25)
		(keepout
			(tracks not_allowed)
			(vias allowed)
			(pads allowed)
			(copperpour not_allowed)
			(footprints allowed)
		)
		(placement
			(enabled no)
			(sheetname "")
		)
		(fill
			(thermal_gap 0.5)
			(thermal_bridge_width 0.5)
			(island_removal_mode 0)
		)
		(polygon
			(pts
				(arc
					(start 365.19993 -276.010116)
					(mid 368.450114 -279.2603)
					(end 371.700044 -276.010116)
				)
				(arc
					(start 371.700044 -276.010116)
					(mid 368.450114 -272.760186)
					(end 365.19993 -276.010116)
				)
			)
		)
	)
	(zone
		(layer "B.Cu")
		(hatch none 0.5)
		(connect_pads
			(clearance 0)
		)
		(min_thickness 0.25)
		(keepout
			(tracks not_allowed)
			(vias allowed)
			(pads allowed)
			(copperpour not_allowed)
			(footprints allowed)
		)
		(placement
			(enabled no)
			(sheetname "")
		)
		(fill
			(thermal_gap 0.5)
			(thermal_bridge_width 0.5)
			(island_removal_mode 0)
		)
		(polygon
			(pts
				(arc
					(start 184.62625 -316.799722)
					(mid 183.97347 -316.799722)
					(end 184.62625 -316.799722)
				)
			)
		)
	)
	(zone
		(layer "B.Cu")
		(hatch none 0.5)
		(connect_pads
			(clearance 0)
		)
		(min_thickness 0.25)
		(keepout
			(tracks allowed)
			(vias allowed)
			(pads allowed)
			(copperpour allowed)
			(footprints not_allowed)
		)
		(placement
			(enabled no)
			(sheetname "")
		)
		(fill
			(thermal_gap 0.5)
			(thermal_bridge_width 0.5)
			(island_removal_mode 0)
		)
		(polygon
			(pts
				(arc
					(start 163.064952 -5.999988)
					(mid 168.064942 -10.999978)
					(end 173.064932 -5.999988)
				)
				(arc
					(start 173.064932 -5.999988)
					(mid 168.064942 -0.999998)
					(end 163.064952 -5.999988)
				)
			)
		)
	)
	(zone
		(layer "B.Cu")
		(hatch none 0.5)
		(connect_pads
			(clearance 0)
		)
		(min_thickness 0.25)
		(keepout
			(tracks allowed)
			(vias allowed)
			(pads allowed)
			(copperpour allowed)
			(footprints not_allowed)
		)
		(placement
			(enabled no)
			(sheetname "")
		)
		(fill
			(thermal_gap 0.5)
			(thermal_bridge_width 0.5)
			(island_removal_mode 0)
		)
		(polygon
			(pts
				(arc
					(start 135.24992 -326.900032)
					(mid 136.567974 -330.082096)
					(end 139.750038 -331.399896)
				)
				(arc
					(start 211.749894 -331.399896)
					(mid 214.931943 -330.082006)
					(end 216.250012 -326.900032)
				)
				(arc
					(start 216.250012 -264.899902)
					(mid 214.931853 -261.718092)
					(end 211.749894 -260.400038)
				)
				(arc
					(start 139.750038 -260.400038)
					(mid 136.568064 -261.718002)
					(end 135.24992 -264.899902)
				)
			)
		)
	)
	(zone
		(layer "B.Cu")
		(hatch none 0.5)
		(connect_pads
			(clearance 0)
		)
		(min_thickness 0.25)
		(keepout
			(tracks allowed)
			(vias allowed)
			(pads allowed)
			(copperpour allowed)
			(footprints not_allowed)
		)
		(placement
			(enabled no)
			(sheetname "")
		)
		(fill
			(thermal_gap 0.5)
			(thermal_bridge_width 0.5)
			(island_removal_mode 0)
		)
		(polygon
			(pts
				(arc
					(start 237.519972 -20.72005)
					(mid 239.519968 -22.720046)
					(end 241.519964 -20.72005)
				)
				(arc
					(start 241.519964 -20.72005)
					(mid 239.519968 -18.720054)
					(end 237.519972 -20.72005)
				)
			)
		)
	)
	(zone
		(layer "B.Cu")
		(hatch none 0.5)
		(connect_pads
			(clearance 0)
		)
		(min_thickness 0.25)
		(keepout
			(tracks not_allowed)
			(vias allowed)
			(pads allowed)
			(copperpour not_allowed)
			(footprints allowed)
		)
		(placement
			(enabled no)
			(sheetname "")
		)
		(fill
			(thermal_gap 0.5)
			(thermal_bridge_width 0.5)
			(island_removal_mode 0)
		)
		(polygon
			(pts
				(arc
					(start 311.176162 -318.699896)
					(mid 310.523382 -318.699896)
					(end 311.176162 -318.699896)
				)
			)
		)
	)
	(zone
		(layer "B.Cu")
		(hatch none 0.5)
		(connect_pads
			(clearance 0)
		)
		(min_thickness 0.25)
		(keepout
			(tracks not_allowed)
			(vias allowed)
			(pads allowed)
			(copperpour not_allowed)
			(footprints allowed)
		)
		(placement
			(enabled no)
			(sheetname "")
		)
		(fill
			(thermal_gap 0.5)
			(thermal_bridge_width 0.5)
			(island_removal_mode 0)
		)
		(polygon
			(pts
				(arc
					(start 43.689778 -380.69012)
					(mid 42.930318 -380.69012)
					(end 43.689778 -380.69012)
				)
			)
		)
	)
	(zone
		(layer "B.Cu")
		(hatch none 0.5)
		(connect_pads
			(clearance 0)
		)
		(min_thickness 0.25)
		(keepout
			(tracks not_allowed)
			(vias allowed)
			(pads allowed)
			(copperpour not_allowed)
			(footprints allowed)
		)
		(placement
			(enabled no)
			(sheetname "")
		)
		(fill
			(thermal_gap 0.5)
			(thermal_bridge_width 0.5)
			(island_removal_mode 0)
		)
		(polygon
			(pts
				(arc
					(start 189.376304 -318.699896)
					(mid 188.723524 -318.699896)
					(end 189.376304 -318.699896)
				)
			)
		)
	)
	(zone
		(layer "B.Cu")
		(hatch none 0.5)
		(connect_pads
			(clearance 0)
		)
		(min_thickness 0.25)
		(keepout
			(tracks not_allowed)
			(vias allowed)
			(pads allowed)
			(copperpour not_allowed)
			(footprints allowed)
		)
		(placement
			(enabled no)
			(sheetname "")
		)
		(fill
			(thermal_gap 0.5)
			(thermal_bridge_width 0.5)
			(island_removal_mode 0)
		)
		(polygon
			(pts
				(arc
					(start 61.319918 -20.72005)
					(mid 59.319922 -18.720054)
					(end 57.319926 -20.72005)
				)
				(arc
					(start 57.319926 -20.72005)
					(mid 59.319922 -22.720046)
					(end 61.319918 -20.72005)
				)
			)
		)
	)
	(zone
		(layer "B.Cu")
		(hatch none 0.5)
		(connect_pads
			(clearance 0)
		)
		(min_thickness 0.25)
		(keepout
			(tracks allowed)
			(vias allowed)
			(pads allowed)
			(copperpour allowed)
			(footprints not_allowed)
		)
		(placement
			(enabled no)
			(sheetname "")
		)
		(fill
			(thermal_gap 0.5)
			(thermal_bridge_width 0.5)
			(island_removal_mode 0)
		)
		(polygon
			(pts
				(arc
					(start 122.700034 -194.360038)
					(mid 117.700044 -189.360048)
					(end 112.700054 -194.360038)
				)
				(arc
					(start 112.700054 -194.360038)
					(mid 117.700044 -199.360028)
					(end 122.700034 -194.360038)
				)
			)
		)
	)
	(zone
		(layer "B.Cu")
		(hatch none 0.5)
		(connect_pads
			(clearance 0)
		)
		(min_thickness 0.25)
		(keepout
			(tracks allowed)
			(vias allowed)
			(pads allowed)
			(copperpour allowed)
			(footprints not_allowed)
		)
		(placement
			(enabled no)
			(sheetname "")
		)
		(fill
			(thermal_gap 0.5)
			(thermal_bridge_width 0.5)
			(island_removal_mode 0)
		)
		(polygon
			(pts
				(arc
					(start 263.899904 -378.70003)
					(mid 271.900142 -386.700268)
					(end 279.900126 -378.70003)
				)
				(arc
					(start 279.900126 -378.70003)
					(mid 271.900142 -370.700046)
					(end 263.899904 -378.70003)
				)
			)
		)
	)
	(zone
		(layer "B.Cu")
		(hatch none 0.5)
		(connect_pads
			(clearance 0)
		)
		(min_thickness 0.25)
		(keepout
			(tracks not_allowed)
			(vias allowed)
			(pads allowed)
			(copperpour not_allowed)
			(footprints allowed)
		)
		(placement
			(enabled no)
			(sheetname "")
		)
		(fill
			(thermal_gap 0.5)
			(thermal_bridge_width 0.5)
			(island_removal_mode 0)
		)
		(polygon
			(pts
				(arc
					(start 164.676328 -317.749936)
					(mid 164.023548 -317.749936)
					(end 164.676328 -317.749936)
				)
			)
		)
	)
	(zone
		(layer "B.Cu")
		(hatch none 0.5)
		(connect_pads
			(clearance 0)
		)
		(min_thickness 0.25)
		(keepout
			(tracks not_allowed)
			(vias allowed)
			(pads allowed)
			(copperpour not_allowed)
			(footprints allowed)
		)
		(placement
			(enabled no)
			(sheetname "")
		)
		(fill
			(thermal_gap 0.5)
			(thermal_bridge_width 0.5)
			(island_removal_mode 0)
		)
		(polygon
			(pts
				(arc
					(start 347.89999 -72.69988)
					(mid 349.899986 -74.699876)
					(end 351.899982 -72.69988)
				)
				(arc
					(start 351.899982 -72.69988)
					(mid 349.899986 -70.699884)
					(end 347.89999 -72.69988)
				)
			)
		)
	)
	(zone
		(layer "B.Cu")
		(hatch none 0.5)
		(connect_pads
			(clearance 0)
		)
		(min_thickness 0.25)
		(keepout
			(tracks not_allowed)
			(vias allowed)
			(pads allowed)
			(copperpour not_allowed)
			(footprints allowed)
		)
		(placement
			(enabled no)
			(sheetname "")
		)
		(fill
			(thermal_gap 0.5)
			(thermal_bridge_width 0.5)
			(island_removal_mode 0)
		)
		(polygon
			(pts
				(arc
					(start 298.869608 -405.390096)
					(mid 298.110148 -405.390096)
					(end 298.869608 -405.390096)
				)
			)
		)
	)
	(zone
		(layer "B.Cu")
		(hatch none 0.5)
		(connect_pads
			(clearance 0)
		)
		(min_thickness 0.25)
		(keepout
			(tracks not_allowed)
			(vias allowed)
			(pads allowed)
			(copperpour not_allowed)
			(footprints allowed)
		)
		(placement
			(enabled no)
			(sheetname "")
		)
		(fill
			(thermal_gap 0.5)
			(thermal_bridge_width 0.5)
			(island_removal_mode 0)
		)
		(polygon
			(pts
				(arc
					(start 122.700034 -194.360038)
					(mid 117.700044 -189.360048)
					(end 112.700054 -194.360038)
				)
				(arc
					(start 112.700054 -194.360038)
					(mid 117.700044 -199.360028)
					(end 122.700034 -194.360038)
				)
			)
		)
	)
	(zone
		(layer "B.Cu")
		(hatch none 0.5)
		(connect_pads
			(clearance 0)
		)
		(min_thickness 0.25)
		(keepout
			(tracks not_allowed)
			(vias allowed)
			(pads allowed)
			(copperpour not_allowed)
			(footprints allowed)
		)
		(placement
			(enabled no)
			(sheetname "")
		)
		(fill
			(thermal_gap 0.5)
			(thermal_bridge_width 0.5)
			(island_removal_mode 0)
		)
		(polygon
			(pts
				(arc
					(start 15.999968 -84.70011)
					(mid 18.800064 -87.500206)
					(end 21.599906 -84.70011)
				)
				(arc
					(start 21.599906 -84.70011)
					(mid 18.800064 -81.900268)
					(end 15.999968 -84.70011)
				)
			)
		)
	)
	(zone
		(layer "B.Cu")
		(hatch none 0.5)
		(connect_pads
			(clearance 0)
		)
		(min_thickness 0.25)
		(keepout
			(tracks not_allowed)
			(vias allowed)
			(pads allowed)
			(copperpour not_allowed)
			(footprints allowed)
		)
		(placement
			(enabled no)
			(sheetname "")
		)
		(fill
			(thermal_gap 0.5)
			(thermal_bridge_width 0.5)
			(island_removal_mode 0)
		)
		(polygon
			(pts
				(arc
					(start 196.600064 -393.100052)
					(mid 199.40016 -395.900148)
					(end 202.200002 -393.100052)
				)
				(arc
					(start 202.200002 -393.100052)
					(mid 199.40016 -390.30021)
					(end 196.600064 -393.100052)
				)
			)
		)
	)
	(zone
		(layer "B.Cu")
		(hatch none 0.5)
		(connect_pads
			(clearance 0)
		)
		(min_thickness 0.25)
		(keepout
			(tracks not_allowed)
			(vias allowed)
			(pads allowed)
			(copperpour not_allowed)
			(footprints allowed)
		)
		(placement
			(enabled no)
			(sheetname "")
		)
		(fill
			(thermal_gap 0.5)
			(thermal_bridge_width 0.5)
			(island_removal_mode 0)
		)
		(polygon
			(pts
				(arc
					(start 314.976256 -308.249828)
					(mid 314.323476 -308.249828)
					(end 314.976256 -308.249828)
				)
			)
		)
	)
	(zone
		(layer "B.Cu")
		(hatch none 0.5)
		(connect_pads
			(clearance 0)
		)
		(min_thickness 0.25)
		(keepout
			(tracks allowed)
			(vias allowed)
			(pads allowed)
			(copperpour allowed)
			(footprints not_allowed)
		)
		(placement
			(enabled no)
			(sheetname "")
		)
		(fill
			(thermal_gap 0.5)
			(thermal_bridge_width 0.5)
			(island_removal_mode 0)
		)
		(polygon
			(pts
				(xy 268.100048 -416.275774) (xy 268.100048 -410.969968) (xy 199.749918 -410.969968) (xy 199.749918 -417.58997)
				(arc
					(start 200.481184 -417.58997)
					(mid 200.886546 -417.504238)
					(end 201.222356 -417.261548)
				)
				(arc
					(start 201.222356 -417.261548)
					(mid 202.229499 -416.533318)
					(end 203.445364 -416.275774)
				)
			)
		)
	)
	(zone
		(layer "B.Cu")
		(hatch none 0.5)
		(connect_pads
			(clearance 0)
		)
		(min_thickness 0.25)
		(keepout
			(tracks not_allowed)
			(vias allowed)
			(pads allowed)
			(copperpour not_allowed)
			(footprints allowed)
		)
		(placement
			(enabled no)
			(sheetname "")
		)
		(fill
			(thermal_gap 0.5)
			(thermal_bridge_width 0.5)
			(island_removal_mode 0)
		)
		(polygon
			(pts
				(arc
					(start 80.87614 -307.299868)
					(mid 80.22336 -307.299868)
					(end 80.87614 -307.299868)
				)
			)
		)
	)
	(zone
		(layer "B.Cu")
		(hatch none 0.5)
		(connect_pads
			(clearance 0)
		)
		(min_thickness 0.25)
		(keepout
			(tracks not_allowed)
			(vias allowed)
			(pads allowed)
			(copperpour not_allowed)
			(footprints allowed)
		)
		(placement
			(enabled no)
			(sheetname "")
		)
		(fill
			(thermal_gap 0.5)
			(thermal_bridge_width 0.5)
			(island_removal_mode 0)
		)
		(polygon
			(pts
				(arc
					(start 391.269728 -402.790152)
					(mid 390.510268 -402.790152)
					(end 391.269728 -402.790152)
				)
			)
		)
	)
	(zone
		(layer "B.Cu")
		(hatch none 0.5)
		(connect_pads
			(clearance 0)
		)
		(min_thickness 0.25)
		(keepout
			(tracks not_allowed)
			(vias allowed)
			(pads allowed)
			(copperpour not_allowed)
			(footprints allowed)
		)
		(placement
			(enabled no)
			(sheetname "")
		)
		(fill
			(thermal_gap 0.5)
			(thermal_bridge_width 0.5)
			(island_removal_mode 0)
		)
		(polygon
			(pts
				(arc
					(start 354.899976 -72.69988)
					(mid 349.899986 -67.69989)
					(end 344.899996 -72.69988)
				)
				(arc
					(start 344.899996 -72.69988)
					(mid 349.899986 -77.69987)
					(end 354.899976 -72.69988)
				)
			)
		)
	)
	(zone
		(layer "B.Cu")
		(hatch none 0.5)
		(connect_pads
			(clearance 0)
		)
		(min_thickness 0.25)
		(keepout
			(tracks not_allowed)
			(vias allowed)
			(pads allowed)
			(copperpour not_allowed)
			(footprints allowed)
		)
		(placement
			(enabled no)
			(sheetname "")
		)
		(fill
			(thermal_gap 0.5)
			(thermal_bridge_width 0.5)
			(island_removal_mode 0)
		)
		(polygon
			(pts
				(arc
					(start 41.48963 -379.590046)
					(mid 40.73017 -379.590046)
					(end 41.48963 -379.590046)
				)
			)
		)
	)
	(zone
		(layer "B.Cu")
		(hatch none 0.5)
		(connect_pads
			(clearance 0)
		)
		(min_thickness 0.25)
		(keepout
			(tracks not_allowed)
			(vias allowed)
			(pads allowed)
			(copperpour not_allowed)
			(footprints allowed)
		)
		(placement
			(enabled no)
			(sheetname "")
		)
		(fill
			(thermal_gap 0.5)
			(thermal_bridge_width 0.5)
			(island_removal_mode 0)
		)
		(polygon
			(pts
				(arc
					(start 187.476384 -318.699896)
					(mid 186.823604 -318.699896)
					(end 187.476384 -318.699896)
				)
			)
		)
	)
	(zone
		(layer "B.Cu")
		(hatch none 0.5)
		(connect_pads
			(clearance 0)
		)
		(min_thickness 0.25)
		(keepout
			(tracks not_allowed)
			(vias allowed)
			(pads allowed)
			(copperpour not_allowed)
			(footprints allowed)
		)
		(placement
			(enabled no)
			(sheetname "")
		)
		(fill
			(thermal_gap 0.5)
			(thermal_bridge_width 0.5)
			(island_removal_mode 0)
		)
		(polygon
			(pts
				(arc
					(start 236.054646 -87.386414)
					(mid 235.351066 -87.386414)
					(end 236.054646 -87.386414)
				)
			)
		)
	)
	(zone
		(layer "B.Cu")
		(hatch none 0.5)
		(connect_pads
			(clearance 0)
		)
		(min_thickness 0.25)
		(keepout
			(tracks allowed)
			(vias allowed)
			(pads allowed)
			(copperpour allowed)
			(footprints not_allowed)
		)
		(placement
			(enabled no)
			(sheetname "")
		)
		(fill
			(thermal_gap 0.5)
			(thermal_bridge_width 0.5)
			(island_removal_mode 0)
		)
		(polygon
			(pts
				(arc
					(start 10.80008 -84.70011)
					(mid 18.800064 -92.700094)
					(end 26.800048 -84.70011)
				)
				(arc
					(start 26.800048 -72.69988)
					(mid 18.800064 -64.699896)
					(end 10.80008 -72.69988)
				)
			)
		)
	)
	(zone
		(layer "B.Cu")
		(hatch none 0.5)
		(connect_pads
			(clearance 0)
		)
		(min_thickness 0.25)
		(keepout
			(tracks allowed)
			(vias allowed)
			(pads allowed)
			(copperpour allowed)
			(footprints allowed)
		)
		(placement
			(enabled no)
			(sheetname "")
		)
		(fill
			(thermal_gap 0.5)
			(thermal_bridge_width 0.5)
			(island_removal_mode 0)
		)
		(polygon
			(pts
				(xy 97.296478 -353.15017) (xy 97.296478 -351.385124) (xy 99.158552 -351.385124) (xy 99.158552 -353.15017)
			)
		)
	)
	(zone
		(layer "B.Cu")
		(hatch none 0.5)
		(connect_pads
			(clearance 0)
		)
		(min_thickness 0.25)
		(keepout
			(tracks not_allowed)
			(vias allowed)
			(pads allowed)
			(copperpour not_allowed)
			(footprints allowed)
		)
		(placement
			(enabled no)
			(sheetname "")
		)
		(fill
			(thermal_gap 0.5)
			(thermal_bridge_width 0.5)
			(island_removal_mode 0)
		)
		(polygon
			(pts
				(xy 54.790086 -396.54988) (xy 54.790086 -417.58997) (xy 64.790066 -417.58997) (xy 64.790066 -396.54988)
			)
		)
	)
	(zone
		(layer "B.Cu")
		(hatch none 0.5)
		(connect_pads
			(clearance 0)
		)
		(min_thickness 0.25)
		(keepout
			(tracks allowed)
			(vias allowed)
			(pads allowed)
			(copperpour allowed)
			(footprints not_allowed)
		)
		(placement
			(enabled no)
			(sheetname "")
		)
		(fill
			(thermal_gap 0.5)
			(thermal_bridge_width 0.5)
			(island_removal_mode 0)
		)
		(polygon
			(pts
				(xy 39.150036 -280.399998) (xy 39.150036 -311.399936) (xy 80.149954 -311.399936) (xy 80.149954 -280.399998)
			)
		)
	)
	(zone
		(layer "B.Cu")
		(hatch none 0.5)
		(connect_pads
			(clearance 0)
		)
		(min_thickness 0.25)
		(keepout
			(tracks allowed)
			(vias allowed)
			(pads allowed)
			(copperpour allowed)
			(footprints not_allowed)
		)
		(placement
			(enabled no)
			(sheetname "")
		)
		(fill
			(thermal_gap 0.5)
			(thermal_bridge_width 0.5)
			(island_removal_mode 0)
		)
		(polygon
			(pts
				(xy 100.149914 -328.972418) (xy 135.24992 -328.972418)
				(arc
					(start 135.24992 -279.882854)
					(mid 133.087682 -278.459495)
					(end 132.249926 -276.010116)
				)
				(arc
					(start 132.249926 -276.010116)
					(mid 133.087648 -273.56063)
					(end 135.24992 -272.137124)
				)
				(xy 135.24992 -266.897612) (xy 100.149914 -266.897612)
				(arc
					(start 100.149914 -285.947104)
					(mid 102.312199 -287.3706)
					(end 103.149908 -289.820096)
				)
				(arc
					(start 103.149908 -289.820096)
					(mid 102.312186 -292.269582)
					(end 100.149914 -293.693088)
				)
			)
		)
	)
	(zone
		(layer "B.Cu")
		(hatch none 0.5)
		(connect_pads
			(clearance 0)
		)
		(min_thickness 0.25)
		(keepout
			(tracks not_allowed)
			(vias allowed)
			(pads allowed)
			(copperpour not_allowed)
			(footprints allowed)
		)
		(placement
			(enabled no)
			(sheetname "")
		)
		(fill
			(thermal_gap 0.5)
			(thermal_bridge_width 0.5)
			(island_removal_mode 0)
		)
		(polygon
			(pts
				(arc
					(start 188.426344 -315.849762)
					(mid 187.773564 -315.849762)
					(end 188.426344 -315.849762)
				)
			)
		)
	)
	(zone
		(layer "B.Cu")
		(hatch none 0.5)
		(connect_pads
			(clearance 0)
		)
		(min_thickness 0.25)
		(keepout
			(tracks not_allowed)
			(vias allowed)
			(pads allowed)
			(copperpour not_allowed)
			(footprints allowed)
		)
		(placement
			(enabled no)
			(sheetname "")
		)
		(fill
			(thermal_gap 0.5)
			(thermal_bridge_width 0.5)
			(island_removal_mode 0)
		)
		(polygon
			(pts
				(arc
					(start 116.289836 -371.790214)
					(mid 115.530376 -371.790214)
					(end 116.289836 -371.790214)
				)
			)
		)
	)
	(zone
		(layer "B.Cu")
		(hatch none 0.5)
		(connect_pads
			(clearance 0)
		)
		(min_thickness 0.25)
		(keepout
			(tracks allowed)
			(vias allowed)
			(pads allowed)
			(copperpour allowed)
			(footprints not_allowed)
		)
		(placement
			(enabled no)
			(sheetname "")
		)
		(fill
			(thermal_gap 0.5)
			(thermal_bridge_width 0.5)
			(island_removal_mode 0)
		)
		(polygon
			(pts
				(xy 138.530076 -137.379964) (xy 158.530036 -137.379964) (xy 158.530036 -117.380004) (xy 138.530076 -117.380004)
			)
		)
	)
	(zone
		(layer "B.Cu")
		(hatch none 0.5)
		(connect_pads
			(clearance 0)
		)
		(min_thickness 0.25)
		(keepout
			(tracks not_allowed)
			(vias allowed)
			(pads allowed)
			(copperpour not_allowed)
			(footprints allowed)
		)
		(placement
			(enabled no)
			(sheetname "")
		)
		(fill
			(thermal_gap 0.5)
			(thermal_bridge_width 0.5)
			(island_removal_mode 0)
		)
		(polygon
			(pts
				(arc
					(start 312.126122 -309.199788)
					(mid 311.473342 -309.199788)
					(end 312.126122 -309.199788)
				)
			)
		)
	)
	(zone
		(layer "B.Cu")
		(hatch none 0.5)
		(connect_pads
			(clearance 0)
		)
		(min_thickness 0.25)
		(keepout
			(tracks not_allowed)
			(vias allowed)
			(pads allowed)
			(copperpour not_allowed)
			(footprints allowed)
		)
		(placement
			(enabled no)
			(sheetname "")
		)
		(fill
			(thermal_gap 0.5)
			(thermal_bridge_width 0.5)
			(island_removal_mode 0)
		)
		(polygon
			(pts
				(arc
					(start 373.450104 -320.900044)
					(mid 377.950222 -325.400162)
					(end 382.450086 -320.900044)
				)
				(arc
					(start 382.450086 -320.900044)
					(mid 377.950222 -316.40018)
					(end 373.450104 -320.900044)
				)
			)
		)
	)
	(zone
		(layer "B.Cu")
		(hatch none 0.5)
		(connect_pads
			(clearance 0)
		)
		(min_thickness 0.25)
		(keepout
			(tracks not_allowed)
			(vias allowed)
			(pads allowed)
			(copperpour not_allowed)
			(footprints allowed)
		)
		(placement
			(enabled no)
			(sheetname "")
		)
		(fill
			(thermal_gap 0.5)
			(thermal_bridge_width 0.5)
			(island_removal_mode 0)
		)
		(polygon
			(pts
				(arc
					(start 9.320022 -20.72005)
					(mid 7.320026 -18.720054)
					(end 5.32003 -20.72005)
				)
				(arc
					(start 5.32003 -20.72005)
					(mid 7.320026 -22.720046)
					(end 9.320022 -20.72005)
				)
			)
		)
	)
	(zone
		(layer "B.Cu")
		(hatch none 0.5)
		(connect_pads
			(clearance 0)
		)
		(min_thickness 0.25)
		(keepout
			(tracks allowed)
			(vias allowed)
			(pads allowed)
			(copperpour allowed)
			(footprints allowed)
		)
		(placement
			(enabled no)
			(sheetname "")
		)
		(fill
			(thermal_gap 0.5)
			(thermal_bridge_width 0.5)
			(island_removal_mode 0)
		)
		(polygon
			(pts
				(xy 11.938 -265.684) (xy 11.938 -263.525) (xy 13.716 -263.525) (xy 13.716 -265.684)
			)
		)
	)
	(zone
		(layer "B.Cu")
		(hatch none 0.5)
		(connect_pads
			(clearance 0)
		)
		(min_thickness 0.25)
		(keepout
			(tracks allowed)
			(vias allowed)
			(pads allowed)
			(copperpour allowed)
			(footprints allowed)
		)
		(placement
			(enabled no)
			(sheetname "")
		)
		(fill
			(thermal_gap 0.5)
			(thermal_bridge_width 0.5)
			(island_removal_mode 0)
		)
		(polygon
			(pts
				(xy 70.74789 -298.891706) (xy 71.269098 -298.891706) (xy 71.442834 -298.71797) (xy 71.442834 -292.71849)
				(xy 71.29526 -292.570916) (xy 70.761098 -292.570916) (xy 70.640702 -292.691312) (xy 70.640702 -298.784518)
			)
		)
	)
	(zone
		(layer "B.Cu")
		(hatch none 0.5)
		(connect_pads
			(clearance 0)
		)
		(min_thickness 0.25)
		(keepout
			(tracks not_allowed)
			(vias allowed)
			(pads allowed)
			(copperpour not_allowed)
			(footprints allowed)
		)
		(placement
			(enabled no)
			(sheetname "")
		)
		(fill
			(thermal_gap 0.5)
			(thermal_bridge_width 0.5)
			(island_removal_mode 0)
		)
		(polygon
			(pts
				(arc
					(start 173.064932 -5.999988)
					(mid 168.064942 -0.999998)
					(end 163.064952 -5.999988)
				)
				(arc
					(start 163.064952 -5.999988)
					(mid 168.064942 -10.999978)
					(end 173.064932 -5.999988)
				)
			)
		)
	)
	(zone
		(layer "B.Cu")
		(hatch none 0.5)
		(connect_pads
			(clearance 0)
		)
		(min_thickness 0.25)
		(keepout
			(tracks allowed)
			(vias allowed)
			(pads allowed)
			(copperpour allowed)
			(footprints allowed)
		)
		(placement
			(enabled no)
			(sheetname "")
		)
		(fill
			(thermal_gap 0.5)
			(thermal_bridge_width 0.5)
			(island_removal_mode 0)
		)
		(polygon
			(pts
				(xy 105.822242 -356.628192) (xy 105.822242 -353.977194) (xy 105.734866 -353.889818) (xy 102.613968 -353.889818)
				(xy 102.60203 -353.87788) (xy 102.11816 -353.87788) (xy 101.419406 -354.576634) (xy 101.419406 -357.237792)
				(xy 101.672136 -357.490522) (xy 105.61193 -357.490522) (xy 105.822242 -357.28021)
			)
		)
	)
	(zone
		(layer "B.Cu")
		(hatch none 0.5)
		(connect_pads
			(clearance 0)
		)
		(min_thickness 0.25)
		(keepout
			(tracks allowed)
			(vias allowed)
			(pads allowed)
			(copperpour allowed)
			(footprints not_allowed)
		)
		(placement
			(enabled no)
			(sheetname "")
		)
		(fill
			(thermal_gap 0.5)
			(thermal_bridge_width 0.5)
			(island_removal_mode 0)
		)
		(polygon
			(pts
				(xy 97.144078 -150.230078) (xy 97.144078 -168.230042) (xy 116.753894 -168.230042) (xy 116.753894 -150.230078)
			)
		)
	)
	(zone
		(layer "B.Cu")
		(hatch none 0.5)
		(connect_pads
			(clearance 0)
		)
		(min_thickness 0.25)
		(keepout
			(tracks not_allowed)
			(vias allowed)
			(pads allowed)
			(copperpour not_allowed)
			(footprints allowed)
		)
		(placement
			(enabled no)
			(sheetname "")
		)
		(fill
			(thermal_gap 0.5)
			(thermal_bridge_width 0.5)
			(island_removal_mode 0)
		)
		(polygon
			(pts
				(arc
					(start 420.626286 -316.799722)
					(mid 419.973506 -316.799722)
					(end 420.626286 -316.799722)
				)
			)
		)
	)
	(zone
		(layer "B.Cu")
		(hatch none 0.5)
		(connect_pads
			(clearance 0)
		)
		(min_thickness 0.25)
		(keepout
			(tracks allowed)
			(vias allowed)
			(pads allowed)
			(copperpour allowed)
			(footprints allowed)
		)
		(placement
			(enabled no)
			(sheetname "")
		)
		(fill
			(thermal_gap 0.5)
			(thermal_bridge_width 0.5)
			(island_removal_mode 0)
		)
		(polygon
			(pts
				(xy 104.14 -318.516) (xy 104.14 -316.865) (xy 106.299 -316.865) (xy 106.299 -318.516)
			)
		)
	)
	(zone
		(layer "B.Cu")
		(hatch none 0.5)
		(connect_pads
			(clearance 0)
		)
		(min_thickness 0.25)
		(keepout
			(tracks not_allowed)
			(vias allowed)
			(pads allowed)
			(copperpour not_allowed)
			(footprints allowed)
		)
		(placement
			(enabled no)
			(sheetname "")
		)
		(fill
			(thermal_gap 0.5)
			(thermal_bridge_width 0.5)
			(island_removal_mode 0)
		)
		(polygon
			(pts
				(arc
					(start 125.08992 -370.489988)
					(mid 124.33046 -370.489988)
					(end 125.08992 -370.489988)
				)
			)
		)
	)
	(zone
		(layer "B.Cu")
		(hatch none 0.5)
		(connect_pads
			(clearance 0)
		)
		(min_thickness 0.25)
		(keepout
			(tracks allowed)
			(vias allowed)
			(pads allowed)
			(copperpour allowed)
			(footprints allowed)
		)
		(placement
			(enabled no)
			(sheetname "")
		)
		(fill
			(thermal_gap 0.5)
			(thermal_bridge_width 0.5)
			(island_removal_mode 0)
		)
		(polygon
			(pts
				(xy 232.213404 -86.14664) (xy 232.213404 -84.914486) (xy 234.124754 -84.914486) (xy 234.124754 -86.14664)
			)
		)
	)
	(zone
		(layer "B.Cu")
		(hatch none 0.5)
		(connect_pads
			(clearance 0)
		)
		(min_thickness 0.25)
		(keepout
			(tracks not_allowed)
			(vias allowed)
			(pads allowed)
			(copperpour not_allowed)
			(footprints allowed)
		)
		(placement
			(enabled no)
			(sheetname "")
		)
		(fill
			(thermal_gap 0.5)
			(thermal_bridge_width 0.5)
			(island_removal_mode 0)
		)
		(polygon
			(pts
				(arc
					(start 39.289736 -379.390148)
					(mid 38.530276 -379.390148)
					(end 39.289736 -379.390148)
				)
			)
		)
	)
	(zone
		(layer "B.Cu")
		(hatch none 0.5)
		(connect_pads
			(clearance 0)
		)
		(min_thickness 0.25)
		(keepout
			(tracks not_allowed)
			(vias allowed)
			(pads allowed)
			(copperpour not_allowed)
			(footprints allowed)
		)
		(placement
			(enabled no)
			(sheetname "")
		)
		(fill
			(thermal_gap 0.5)
			(thermal_bridge_width 0.5)
			(island_removal_mode 0)
		)
		(polygon
			(pts
				(arc
					(start 292.269672 -378.290074)
					(mid 291.510212 -378.290074)
					(end 292.269672 -378.290074)
				)
			)
		)
	)
	(zone
		(layer "B.Cu")
		(hatch none 0.5)
		(connect_pads
			(clearance 0)
		)
		(min_thickness 0.25)
		(keepout
			(tracks allowed)
			(vias allowed)
			(pads allowed)
			(copperpour allowed)
			(footprints allowed)
		)
		(placement
			(enabled no)
			(sheetname "")
		)
		(fill
			(thermal_gap 0.5)
			(thermal_bridge_width 0.5)
			(island_removal_mode 0)
		)
		(polygon
			(pts
				(xy 104.729026 -359.5497) (xy 104.729026 -358.011476) (xy 106.752898 -358.011476) (xy 106.752898 -359.5497)
			)
		)
	)
	(zone
		(layer "B.Cu")
		(hatch none 0.5)
		(connect_pads
			(clearance 0)
		)
		(min_thickness 0.25)
		(keepout
			(tracks not_allowed)
			(vias allowed)
			(pads allowed)
			(copperpour not_allowed)
			(footprints allowed)
		)
		(placement
			(enabled no)
			(sheetname "")
		)
		(fill
			(thermal_gap 0.5)
			(thermal_bridge_width 0.5)
			(island_removal_mode 0)
		)
		(polygon
			(pts
				(arc
					(start 396.87627 -318.699896)
					(mid 396.22349 -318.699896)
					(end 396.87627 -318.699896)
				)
			)
		)
	)
	(zone
		(layer "B.Cu")
		(hatch none 0.5)
		(connect_pads
			(clearance 0)
		)
		(min_thickness 0.25)
		(keepout
			(tracks not_allowed)
			(vias allowed)
			(pads allowed)
			(copperpour not_allowed)
			(footprints allowed)
		)
		(placement
			(enabled no)
			(sheetname "")
		)
		(fill
			(thermal_gap 0.5)
			(thermal_bridge_width 0.5)
			(island_removal_mode 0)
		)
		(polygon
			(pts
				(arc
					(start 301.069502 -405.589994)
					(mid 300.310042 -405.589994)
					(end 301.069502 -405.589994)
				)
			)
		)
	)
	(zone
		(layer "B.Cu")
		(hatch none 0.5)
		(connect_pads
			(clearance 0)
		)
		(min_thickness 0.25)
		(keepout
			(tracks not_allowed)
			(vias allowed)
			(pads allowed)
			(copperpour not_allowed)
			(footprints allowed)
		)
		(placement
			(enabled no)
			(sheetname "")
		)
		(fill
			(thermal_gap 0.5)
			(thermal_bridge_width 0.5)
			(island_removal_mode 0)
		)
		(polygon
			(pts
				(arc
					(start 391.269728 -372.890034)
					(mid 390.510268 -372.890034)
					(end 391.269728 -372.890034)
				)
			)
		)
	)
	(zone
		(layer "B.Cu")
		(hatch none 0.5)
		(connect_pads
			(clearance 0)
		)
		(min_thickness 0.25)
		(keepout
			(tracks not_allowed)
			(vias allowed)
			(pads allowed)
			(copperpour not_allowed)
			(footprints allowed)
		)
		(placement
			(enabled no)
			(sheetname "")
		)
		(fill
			(thermal_gap 0.5)
			(thermal_bridge_width 0.5)
			(island_removal_mode 0)
		)
		(polygon
			(pts
				(arc
					(start 79.92618 -307.299868)
					(mid 79.2734 -307.299868)
					(end 79.92618 -307.299868)
				)
			)
		)
	)
	(zone
		(layer "B.Cu")
		(hatch none 0.5)
		(connect_pads
			(clearance 0)
		)
		(min_thickness 0.25)
		(keepout
			(tracks not_allowed)
			(vias allowed)
			(pads allowed)
			(copperpour not_allowed)
			(footprints allowed)
		)
		(placement
			(enabled no)
			(sheetname "")
		)
		(fill
			(thermal_gap 0.5)
			(thermal_bridge_width 0.5)
			(island_removal_mode 0)
		)
		(polygon
			(pts
				(arc
					(start 75.17638 -318.699896)
					(mid 74.5236 -318.699896)
					(end 75.17638 -318.699896)
				)
			)
		)
	)
	(zone
		(layer "B.Cu")
		(hatch none 0.5)
		(connect_pads
			(clearance 0)
		)
		(min_thickness 0.25)
		(keepout
			(tracks not_allowed)
			(vias allowed)
			(pads allowed)
			(copperpour not_allowed)
			(footprints allowed)
		)
		(placement
			(enabled no)
			(sheetname "")
		)
		(fill
			(thermal_gap 0.5)
			(thermal_bridge_width 0.5)
			(island_removal_mode 0)
		)
		(polygon
			(pts
				(arc
					(start 81.826354 -308.249828)
					(mid 81.173574 -308.249828)
					(end 81.826354 -308.249828)
				)
			)
		)
	)
	(zone
		(layer "B.Cu")
		(hatch none 0.5)
		(connect_pads
			(clearance 0)
		)
		(min_thickness 0.25)
		(keepout
			(tracks not_allowed)
			(vias allowed)
			(pads allowed)
			(copperpour not_allowed)
			(footprints allowed)
		)
		(placement
			(enabled no)
			(sheetname "")
		)
		(fill
			(thermal_gap 0.5)
			(thermal_bridge_width 0.5)
			(island_removal_mode 0)
		)
		(polygon
			(pts
				(arc
					(start 395.92631 -315.849762)
					(mid 395.27353 -315.849762)
					(end 395.92631 -315.849762)
				)
			)
		)
	)
	(zone
		(layer "B.Cu")
		(hatch none 0.5)
		(connect_pads
			(clearance 0)
		)
		(min_thickness 0.25)
		(keepout
			(tracks allowed)
			(vias allowed)
			(pads allowed)
			(copperpour allowed)
			(footprints not_allowed)
		)
		(placement
			(enabled no)
			(sheetname "")
		)
		(fill
			(thermal_gap 0.5)
			(thermal_bridge_width 0.5)
			(island_removal_mode 0)
		)
		(polygon
			(pts
				(arc
					(start 158.720028 -15.649956)
					(mid 160.720024 -17.649952)
					(end 162.72002 -15.649956)
				)
				(arc
					(start 162.72002 -15.649956)
					(mid 160.720024 -13.64996)
					(end 158.720028 -15.649956)
				)
			)
		)
	)
	(zone
		(layer "B.Cu")
		(hatch none 0.5)
		(connect_pads
			(clearance 0)
		)
		(min_thickness 0.25)
		(keepout
			(tracks not_allowed)
			(vias allowed)
			(pads allowed)
			(copperpour not_allowed)
			(footprints allowed)
		)
		(placement
			(enabled no)
			(sheetname "")
		)
		(fill
			(thermal_gap 0.5)
			(thermal_bridge_width 0.5)
			(island_removal_mode 0)
		)
		(polygon
			(pts
				(arc
					(start 34.889694 -380.69012)
					(mid 34.130234 -380.69012)
					(end 34.889694 -380.69012)
				)
			)
		)
	)
	(zone
		(layer "B.Cu")
		(hatch none 0.5)
		(connect_pads
			(clearance 0)
		)
		(min_thickness 0.25)
		(keepout
			(tracks not_allowed)
			(vias allowed)
			(pads allowed)
			(copperpour not_allowed)
			(footprints allowed)
		)
		(placement
			(enabled no)
			(sheetname "")
		)
		(fill
			(thermal_gap 0.5)
			(thermal_bridge_width 0.5)
			(island_removal_mode 0)
		)
		(polygon
			(pts
				(arc
					(start 313.076082 -309.199788)
					(mid 312.423302 -309.199788)
					(end 313.076082 -309.199788)
				)
			)
		)
	)
	(zone
		(layer "B.Cu")
		(hatch none 0.5)
		(connect_pads
			(clearance 0)
		)
		(min_thickness 0.25)
		(keepout
			(tracks not_allowed)
			(vias allowed)
			(pads allowed)
			(copperpour not_allowed)
			(footprints allowed)
		)
		(placement
			(enabled no)
			(sheetname "")
		)
		(fill
			(thermal_gap 0.5)
			(thermal_bridge_width 0.5)
			(island_removal_mode 0)
		)
		(polygon
			(pts
				(arc
					(start 37.089842 -404.290022)
					(mid 36.330382 -404.290022)
					(end 37.089842 -404.290022)
				)
			)
		)
	)
	(zone
		(layer "B.Cu")
		(hatch none 0.5)
		(connect_pads
			(clearance 0)
		)
		(min_thickness 0.25)
		(keepout
			(tracks allowed)
			(vias allowed)
			(pads allowed)
			(copperpour allowed)
			(footprints not_allowed)
		)
		(placement
			(enabled no)
			(sheetname "")
		)
		(fill
			(thermal_gap 0.5)
			(thermal_bridge_width 0.5)
			(island_removal_mode 0)
		)
		(polygon
			(pts
				(arc
					(start 300.820074 -15.649956)
					(mid 302.82007 -17.649952)
					(end 304.820066 -15.649956)
				)
				(arc
					(start 304.820066 -15.649956)
					(mid 302.82007 -13.64996)
					(end 300.820074 -15.649956)
				)
			)
		)
	)
	(zone
		(layer "B.Cu")
		(hatch none 0.5)
		(connect_pads
			(clearance 0)
		)
		(min_thickness 0.25)
		(keepout
			(tracks allowed)
			(vias allowed)
			(pads allowed)
			(copperpour allowed)
			(footprints allowed)
		)
		(placement
			(enabled no)
			(sheetname "")
		)
		(fill
			(thermal_gap 0.5)
			(thermal_bridge_width 0.5)
			(island_removal_mode 0)
		)
		(polygon
			(pts
				(xy 129.110994 -321.945) (xy 129.110994 -320.294) (xy 131.269994 -320.294) (xy 131.269994 -321.945)
			)
		)
	)
	(zone
		(layer "B.Cu")
		(hatch none 0.5)
		(connect_pads
			(clearance 0)
		)
		(min_thickness 0.25)
		(keepout
			(tracks not_allowed)
			(vias allowed)
			(pads allowed)
			(copperpour not_allowed)
			(footprints allowed)
		)
		(placement
			(enabled no)
			(sheetname "")
		)
		(fill
			(thermal_gap 0.5)
			(thermal_bridge_width 0.5)
			(island_removal_mode 0)
		)
		(polygon
			(pts
				(arc
					(start 380.26975 -401.690078)
					(mid 379.51029 -401.690078)
					(end 380.26975 -401.690078)
				)
			)
		)
	)
	(zone
		(layer "B.Cu")
		(hatch none 0.5)
		(connect_pads
			(clearance 0)
		)
		(min_thickness 0.25)
		(keepout
			(tracks not_allowed)
			(vias allowed)
			(pads allowed)
			(copperpour not_allowed)
			(footprints allowed)
		)
		(placement
			(enabled no)
			(sheetname "")
		)
		(fill
			(thermal_gap 0.5)
			(thermal_bridge_width 0.5)
			(island_removal_mode 0)
		)
		(polygon
			(pts
				(arc
					(start 416.826192 -316.799722)
					(mid 416.173412 -316.799722)
					(end 416.826192 -316.799722)
				)
			)
		)
	)
	(zone
		(layer "B.Cu")
		(hatch none 0.5)
		(connect_pads
			(clearance 0)
		)
		(min_thickness 0.25)
		(keepout
			(tracks not_allowed)
			(vias allowed)
			(pads allowed)
			(copperpour not_allowed)
			(footprints allowed)
		)
		(placement
			(enabled no)
			(sheetname "")
		)
		(fill
			(thermal_gap 0.5)
			(thermal_bridge_width 0.5)
			(island_removal_mode 0)
		)
		(polygon
			(pts
				(arc
					(start 127.289814 -402.790152)
					(mid 126.530354 -402.790152)
					(end 127.289814 -402.790152)
				)
			)
		)
	)
	(zone
		(layer "B.Cu")
		(hatch none 0.5)
		(connect_pads
			(clearance 0)
		)
		(min_thickness 0.25)
		(keepout
			(tracks not_allowed)
			(vias allowed)
			(pads allowed)
			(copperpour not_allowed)
			(footprints allowed)
		)
		(placement
			(enabled no)
			(sheetname "")
		)
		(fill
			(thermal_gap 0.5)
			(thermal_bridge_width 0.5)
			(island_removal_mode 0)
		)
		(polygon
			(pts
				(arc
					(start 446.920112 -15.649956)
					(mid 444.920116 -13.64996)
					(end 442.92012 -15.649956)
				)
				(arc
					(start 442.92012 -15.649956)
					(mid 444.920116 -17.649952)
					(end 446.920112 -15.649956)
				)
			)
		)
	)
	(zone
		(layer "B.Cu")
		(hatch none 0.5)
		(connect_pads
			(clearance 0)
		)
		(min_thickness 0.25)
		(keepout
			(tracks not_allowed)
			(vias allowed)
			(pads allowed)
			(copperpour not_allowed)
			(footprints allowed)
		)
		(placement
			(enabled no)
			(sheetname "")
		)
		(fill
			(thermal_gap 0.5)
			(thermal_bridge_width 0.5)
			(island_removal_mode 0)
		)
		(polygon
			(pts
				(arc
					(start 160.876234 -317.749936)
					(mid 160.223454 -317.749936)
					(end 160.876234 -317.749936)
				)
			)
		)
	)
	(zone
		(layer "B.Cu")
		(hatch none 0.5)
		(connect_pads
			(clearance 0)
		)
		(min_thickness 0.25)
		(keepout
			(tracks allowed)
			(vias allowed)
			(pads allowed)
			(copperpour allowed)
			(footprints allowed)
		)
		(placement
			(enabled no)
			(sheetname "")
		)
		(fill
			(thermal_gap 0.5)
			(thermal_bridge_width 0.5)
			(island_removal_mode 0)
		)
		(polygon
			(pts
				(xy 105.448608 -329.067414) (xy 106.603038 -329.067414) (xy 106.662982 -329.00747) (xy 106.662982 -327.680828)
				(xy 106.512868 -327.530714) (xy 105.440988 -327.530714) (xy 105.111296 -327.860406) (xy 105.111296 -328.730102)
			)
		)
	)
	(zone
		(layer "B.Cu")
		(hatch none 0.5)
		(connect_pads
			(clearance 0)
		)
		(min_thickness 0.25)
		(keepout
			(tracks not_allowed)
			(vias allowed)
			(pads allowed)
			(copperpour not_allowed)
			(footprints allowed)
		)
		(placement
			(enabled no)
			(sheetname "")
		)
		(fill
			(thermal_gap 0.5)
			(thermal_bridge_width 0.5)
			(island_removal_mode 0)
		)
		(polygon
			(pts
				(arc
					(start 122.889772 -402.790152)
					(mid 122.130312 -402.790152)
					(end 122.889772 -402.790152)
				)
			)
		)
	)
	(zone
		(layer "B.Cu")
		(hatch none 0.5)
		(connect_pads
			(clearance 0)
		)
		(min_thickness 0.25)
		(keepout
			(tracks not_allowed)
			(vias allowed)
			(pads allowed)
			(copperpour not_allowed)
			(footprints allowed)
		)
		(placement
			(enabled no)
			(sheetname "")
		)
		(fill
			(thermal_gap 0.5)
			(thermal_bridge_width 0.5)
			(island_removal_mode 0)
		)
		(polygon
			(pts
				(arc
					(start 145.749772 -265.869674)
					(mid 150.77948 -270.899382)
					(end 145.749772 -275.92909)
				)
				(arc
					(start 145.749772 -275.446744)
					(mid 150.296626 -270.89989)
					(end 145.749772 -266.353036)
				)
			)
		)
	)
	(zone
		(layer "B.Cu")
		(hatch none 0.5)
		(connect_pads
			(clearance 0)
		)
		(min_thickness 0.25)
		(keepout
			(tracks allowed)
			(vias allowed)
			(pads allowed)
			(copperpour allowed)
			(footprints allowed)
		)
		(placement
			(enabled no)
			(sheetname "")
		)
		(fill
			(thermal_gap 0.5)
			(thermal_bridge_width 0.5)
			(island_removal_mode 0)
		)
		(polygon
			(pts
				(xy 448.08775 -235.405422) (xy 448.08775 -234.018074) (xy 449.824602 -234.018074) (xy 449.824602 -235.405422)
			)
		)
	)
	(zone
		(layer "B.Cu")
		(hatch none 0.5)
		(connect_pads
			(clearance 0)
		)
		(min_thickness 0.25)
		(keepout
			(tracks not_allowed)
			(vias allowed)
			(pads allowed)
			(copperpour not_allowed)
			(footprints allowed)
		)
		(placement
			(enabled no)
			(sheetname "")
		)
		(fill
			(thermal_gap 0.5)
			(thermal_bridge_width 0.5)
			(island_removal_mode 0)
		)
		(polygon
			(pts
				(arc
					(start 298.869608 -406.690068)
					(mid 298.110148 -406.690068)
					(end 298.869608 -406.690068)
				)
			)
		)
	)
	(zone
		(layer "B.Cu")
		(hatch none 0.5)
		(connect_pads
			(clearance 0)
		)
		(min_thickness 0.25)
		(keepout
			(tracks not_allowed)
			(vias allowed)
			(pads allowed)
			(copperpour not_allowed)
			(footprints allowed)
		)
		(placement
			(enabled no)
			(sheetname "")
		)
		(fill
			(thermal_gap 0.5)
			(thermal_bridge_width 0.5)
			(island_removal_mode 0)
		)
		(polygon
			(pts
				(arc
					(start 39.289736 -406.690068)
					(mid 38.530276 -406.690068)
					(end 39.289736 -406.690068)
				)
			)
		)
	)
	(zone
		(layer "B.Cu")
		(hatch none 0.5)
		(connect_pads
			(clearance 0)
		)
		(min_thickness 0.25)
		(keepout
			(tracks not_allowed)
			(vias allowed)
			(pads allowed)
			(copperpour not_allowed)
			(footprints allowed)
		)
		(placement
			(enabled no)
			(sheetname "")
		)
		(fill
			(thermal_gap 0.5)
			(thermal_bridge_width 0.5)
			(island_removal_mode 0)
		)
		(polygon
			(pts
				(arc
					(start 453.799956 -84.70011)
					(mid 448.799966 -79.70012)
					(end 443.799976 -84.70011)
				)
				(arc
					(start 443.799976 -84.70011)
					(mid 448.799966 -89.7001)
					(end 453.799956 -84.70011)
				)
			)
		)
	)
	(zone
		(layer "B.Cu")
		(hatch none 0.5)
		(connect_pads
			(clearance 0)
		)
		(min_thickness 0.25)
		(keepout
			(tracks allowed)
			(vias allowed)
			(pads allowed)
			(copperpour allowed)
			(footprints allowed)
		)
		(placement
			(enabled no)
			(sheetname "")
		)
		(fill
			(thermal_gap 0.5)
			(thermal_bridge_width 0.5)
			(island_removal_mode 0)
		)
		(polygon
			(pts
				(xy 338.508848 -316.891924) (xy 338.508848 -318.542924) (xy 336.349848 -318.542924) (xy 336.349848 -316.891924)
			)
		)
	)
	(zone
		(layer "B.Cu")
		(hatch none 0.5)
		(connect_pads
			(clearance 0)
		)
		(min_thickness 0.25)
		(keepout
			(tracks not_allowed)
			(vias allowed)
			(pads allowed)
			(copperpour not_allowed)
			(footprints allowed)
		)
		(placement
			(enabled no)
			(sheetname "")
		)
		(fill
			(thermal_gap 0.5)
			(thermal_bridge_width 0.5)
			(island_removal_mode 0)
		)
		(polygon
			(pts
				(arc
					(start 79.92618 -309.199788)
					(mid 79.2734 -309.199788)
					(end 79.92618 -309.199788)
				)
			)
		)
	)
	(zone
		(layer "B.Cu")
		(hatch none 0.5)
		(connect_pads
			(clearance 0)
		)
		(min_thickness 0.25)
		(keepout
			(tracks not_allowed)
			(vias allowed)
			(pads allowed)
			(copperpour not_allowed)
			(footprints allowed)
		)
		(placement
			(enabled no)
			(sheetname "")
		)
		(fill
			(thermal_gap 0.5)
			(thermal_bridge_width 0.5)
			(island_removal_mode 0)
		)
		(polygon
			(pts
				(arc
					(start 278.820118 -15.649956)
					(mid 276.820122 -13.64996)
					(end 274.820126 -15.649956)
				)
				(arc
					(start 274.820126 -15.649956)
					(mid 276.820122 -17.649952)
					(end 278.820118 -15.649956)
				)
			)
		)
	)
	(zone
		(layer "B.Cu")
		(hatch none 0.5)
		(connect_pads
			(clearance 0)
		)
		(min_thickness 0.25)
		(keepout
			(tracks not_allowed)
			(vias allowed)
			(pads allowed)
			(copperpour not_allowed)
			(footprints allowed)
		)
		(placement
			(enabled no)
			(sheetname "")
		)
		(fill
			(thermal_gap 0.5)
			(thermal_bridge_width 0.5)
			(island_removal_mode 0)
		)
		(polygon
			(pts
				(arc
					(start 214.719916 -15.649956)
					(mid 212.71992 -13.64996)
					(end 210.719924 -15.649956)
				)
				(arc
					(start 210.719924 -15.649956)
					(mid 212.71992 -17.649952)
					(end 214.719916 -15.649956)
				)
			)
		)
	)
	(zone
		(layer "B.Cu")
		(hatch none 0.5)
		(connect_pads
			(clearance 0)
		)
		(min_thickness 0.25)
		(keepout
			(tracks allowed)
			(vias allowed)
			(pads allowed)
			(copperpour allowed)
			(footprints not_allowed)
		)
		(placement
			(enabled no)
			(sheetname "")
		)
		(fill
			(thermal_gap 0.5)
			(thermal_bridge_width 0.5)
			(island_removal_mode 0)
		)
		(polygon
			(pts
				(arc
					(start 353.62007 -20.72005)
					(mid 355.620066 -22.720046)
					(end 357.620062 -20.72005)
				)
				(arc
					(start 357.620062 -20.72005)
					(mid 355.620066 -18.720054)
					(end 353.62007 -20.72005)
				)
			)
		)
	)
	(zone
		(layer "B.Cu")
		(hatch none 0.5)
		(connect_pads
			(clearance 0)
		)
		(min_thickness 0.25)
		(keepout
			(tracks not_allowed)
			(vias allowed)
			(pads allowed)
			(copperpour not_allowed)
			(footprints allowed)
		)
		(placement
			(enabled no)
			(sheetname "")
		)
		(fill
			(thermal_gap 0.5)
			(thermal_bridge_width 0.5)
			(island_removal_mode 0)
		)
		(polygon
			(pts
				(arc
					(start 330.820014 -15.649956)
					(mid 328.820018 -13.64996)
					(end 326.820022 -15.649956)
				)
				(arc
					(start 326.820022 -15.649956)
					(mid 328.820018 -17.649952)
					(end 330.820014 -15.649956)
				)
			)
		)
	)
	(zone
		(layer "B.Cu")
		(hatch none 0.5)
		(connect_pads
			(clearance 0)
		)
		(min_thickness 0.25)
		(keepout
			(tracks not_allowed)
			(vias allowed)
			(pads allowed)
			(copperpour not_allowed)
			(footprints allowed)
		)
		(placement
			(enabled no)
			(sheetname "")
		)
		(fill
			(thermal_gap 0.5)
			(thermal_bridge_width 0.5)
			(island_removal_mode 0)
		)
		(polygon
			(pts
				(arc
					(start 35.31997 -20.72005)
					(mid 33.319974 -18.720054)
					(end 31.319978 -20.72005)
				)
				(arc
					(start 31.319978 -20.72005)
					(mid 33.319974 -22.720046)
					(end 35.31997 -20.72005)
				)
			)
		)
	)
	(zone
		(layer "B.Cu")
		(hatch none 0.5)
		(connect_pads
			(clearance 0)
		)
		(min_thickness 0.25)
		(keepout
			(tracks allowed)
			(vias allowed)
			(pads allowed)
			(copperpour allowed)
			(footprints allowed)
		)
		(placement
			(enabled no)
			(sheetname "")
		)
		(fill
			(thermal_gap 0.5)
			(thermal_bridge_width 0.5)
			(island_removal_mode 0)
		)
		(polygon
			(pts
				(xy 342.530938 -312.599578) (xy 344.181938 -312.599578) (xy 344.181938 -314.758578) (xy 342.530938 -314.758578)
			)
		)
	)
	(zone
		(layer "B.Cu")
		(hatch none 0.5)
		(connect_pads
			(clearance 0)
		)
		(min_thickness 0.25)
		(keepout
			(tracks not_allowed)
			(vias allowed)
			(pads allowed)
			(copperpour not_allowed)
			(footprints allowed)
		)
		(placement
			(enabled no)
			(sheetname "")
		)
		(fill
			(thermal_gap 0.5)
			(thermal_bridge_width 0.5)
			(island_removal_mode 0)
		)
		(polygon
			(pts
				(arc
					(start 290.069524 -379.390148)
					(mid 289.310064 -379.390148)
					(end 290.069524 -379.390148)
				)
			)
		)
	)
	(zone
		(layer "B.Cu")
		(hatch none 0.5)
		(connect_pads
			(clearance 0)
		)
		(min_thickness 0.25)
		(keepout
			(tracks allowed)
			(vias allowed)
			(pads allowed)
			(copperpour allowed)
			(footprints not_allowed)
		)
		(placement
			(enabled no)
			(sheetname "")
		)
		(fill
			(thermal_gap 0.5)
			(thermal_bridge_width 0.5)
			(island_removal_mode 0)
		)
		(polygon
			(pts
				(xy 216.250012 -328.972418) (xy 251.350018 -328.972418)
				(arc
					(start 251.350018 -301.242984)
					(mid 249.187733 -299.819488)
					(end 248.350024 -297.369992)
				)
				(arc
					(start 248.350024 -297.369992)
					(mid 249.187746 -294.920506)
					(end 251.350018 -293.497)
				)
				(xy 251.350018 -266.897612) (xy 216.250012 -266.897612)
				(arc
					(start 216.250012 -307.249068)
					(mid 217.300238 -307.192095)
					(end 218.329002 -307.410866)
				)
				(xy 218.329002 -300.569884) (xy 246.149114 -300.569884) (xy 246.149114 -316.570106) (xy 218.329002 -316.570106)
				(arc
					(start 218.329002 -314.949332)
					(mid 217.30022 -315.167941)
					(end 216.250012 -315.110876)
				)
			)
		)
	)
	(zone
		(layer "B.Cu")
		(hatch none 0.5)
		(connect_pads
			(clearance 0)
		)
		(min_thickness 0.25)
		(keepout
			(tracks allowed)
			(vias allowed)
			(pads allowed)
			(copperpour allowed)
			(footprints allowed)
		)
		(placement
			(enabled no)
			(sheetname "")
		)
		(fill
			(thermal_gap 0.5)
			(thermal_bridge_width 0.5)
			(island_removal_mode 0)
		)
		(polygon
			(pts
				(xy 137.402062 -230.152702) (xy 138.17727 -230.152702) (xy 138.526266 -229.803706) (xy 138.526266 -228.175566)
				(xy 138.487658 -228.136958) (xy 137.099548 -228.136958) (xy 137.022078 -228.214428) (xy 137.022078 -229.772718)
			)
		)
	)
	(zone
		(layer "B.Cu")
		(hatch none 0.5)
		(connect_pads
			(clearance 0)
		)
		(min_thickness 0.25)
		(keepout
			(tracks allowed)
			(vias allowed)
			(pads allowed)
			(copperpour allowed)
			(footprints not_allowed)
		)
		(placement
			(enabled no)
			(sheetname "")
		)
		(fill
			(thermal_gap 0.5)
			(thermal_bridge_width 0.5)
			(island_removal_mode 0)
		)
		(polygon
			(pts
				(arc
					(start 315.52007 -20.72005)
					(mid 317.520066 -22.720046)
					(end 319.520062 -20.72005)
				)
				(arc
					(start 319.520062 -20.72005)
					(mid 317.520066 -18.720054)
					(end 315.52007 -20.72005)
				)
			)
		)
	)
	(zone
		(layer "B.Cu")
		(hatch none 0.5)
		(connect_pads
			(clearance 0)
		)
		(min_thickness 0.25)
		(keepout
			(tracks allowed)
			(vias allowed)
			(pads allowed)
			(copperpour allowed)
			(footprints allowed)
		)
		(placement
			(enabled no)
			(sheetname "")
		)
		(fill
			(thermal_gap 0.5)
			(thermal_bridge_width 0.5)
			(island_removal_mode 0)
		)
		(polygon
			(pts
				(xy 227.556314 -80.082644) (xy 227.556314 -77.870558) (xy 229.399846 -77.870558) (xy 229.399846 -80.082644)
			)
		)
	)
	(zone
		(layer "B.Cu")
		(hatch none 0.5)
		(connect_pads
			(clearance 0)
		)
		(min_thickness 0.25)
		(keepout
			(tracks not_allowed)
			(vias allowed)
			(pads allowed)
			(copperpour not_allowed)
			(footprints allowed)
		)
		(placement
			(enabled no)
			(sheetname "")
		)
		(fill
			(thermal_gap 0.5)
			(thermal_bridge_width 0.5)
			(island_removal_mode 0)
		)
		(polygon
			(pts
				(arc
					(start 382.469644 -402.790152)
					(mid 381.710184 -402.790152)
					(end 382.469644 -402.790152)
				)
			)
		)
	)
	(zone
		(layer "B.Cu")
		(hatch none 0.5)
		(connect_pads
			(clearance 0)
		)
		(min_thickness 0.25)
		(keepout
			(tracks allowed)
			(vias allowed)
			(pads allowed)
			(copperpour allowed)
			(footprints not_allowed)
		)
		(placement
			(enabled no)
			(sheetname "")
		)
		(fill
			(thermal_gap 0.5)
			(thermal_bridge_width 0.5)
			(island_removal_mode 0)
		)
		(polygon
			(pts
				(xy 397.949928 -190.069978) (xy 417.949888 -190.069978) (xy 417.949888 -170.070018) (xy 397.949928 -170.070018)
			)
		)
	)
	(zone
		(layer "B.Cu")
		(hatch none 0.5)
		(connect_pads
			(clearance 0)
		)
		(min_thickness 0.25)
		(keepout
			(tracks not_allowed)
			(vias allowed)
			(pads allowed)
			(copperpour not_allowed)
			(footprints allowed)
		)
		(placement
			(enabled no)
			(sheetname "")
		)
		(fill
			(thermal_gap 0.5)
			(thermal_bridge_width 0.5)
			(island_removal_mode 0)
		)
		(polygon
			(pts
				(arc
					(start 266.899898 -378.70003)
					(mid 271.899888 -383.70002)
					(end 276.899878 -378.70003)
				)
				(arc
					(start 276.899878 -378.70003)
					(mid 271.899888 -373.70004)
					(end 266.899898 -378.70003)
				)
			)
		)
	)
	(zone
		(layer "B.Cu")
		(hatch none 0.5)
		(connect_pads
			(clearance 0)
		)
		(min_thickness 0.25)
		(keepout
			(tracks not_allowed)
			(vias allowed)
			(pads allowed)
			(copperpour not_allowed)
			(footprints allowed)
		)
		(placement
			(enabled no)
			(sheetname "")
		)
		(fill
			(thermal_gap 0.5)
			(thermal_bridge_width 0.5)
			(island_removal_mode 0)
		)
		(polygon
			(pts
				(arc
					(start 287.86963 -404.290022)
					(mid 287.11017 -404.290022)
					(end 287.86963 -404.290022)
				)
			)
		)
	)
	(zone
		(layer "B.Cu")
		(hatch none 0.5)
		(connect_pads
			(clearance 0)
		)
		(min_thickness 0.25)
		(keepout
			(tracks not_allowed)
			(vias allowed)
			(pads allowed)
			(copperpour not_allowed)
			(footprints allowed)
		)
		(placement
			(enabled no)
			(sheetname "")
		)
		(fill
			(thermal_gap 0.5)
			(thermal_bridge_width 0.5)
			(island_removal_mode 0)
		)
		(polygon
			(pts
				(arc
					(start 419.676326 -318.699896)
					(mid 419.023546 -318.699896)
					(end 419.676326 -318.699896)
				)
			)
		)
	)
	(zone
		(layer "B.Cu")
		(hatch none 0.5)
		(connect_pads
			(clearance 0)
		)
		(min_thickness 0.25)
		(keepout
			(tracks not_allowed)
			(vias allowed)
			(pads allowed)
			(copperpour not_allowed)
			(footprints allowed)
		)
		(placement
			(enabled no)
			(sheetname "")
		)
		(fill
			(thermal_gap 0.5)
			(thermal_bridge_width 0.5)
			(island_removal_mode 0)
		)
		(polygon
			(pts
				(arc
					(start 298.869608 -379.390148)
					(mid 298.110148 -379.390148)
					(end 298.869608 -379.390148)
				)
			)
		)
	)
	(zone
		(layer "B.Cu")
		(hatch none 0.5)
		(connect_pads
			(clearance 0)
		)
		(min_thickness 0.25)
		(keepout
			(tracks allowed)
			(vias allowed)
			(pads allowed)
			(copperpour allowed)
			(footprints not_allowed)
		)
		(placement
			(enabled no)
			(sheetname "")
		)
		(fill
			(thermal_gap 0.5)
			(thermal_bridge_width 0.5)
			(island_removal_mode 0)
		)
		(polygon
			(pts
				(arc
					(start 112.700054 -194.360038)
					(mid 117.700044 -199.360028)
					(end 122.700034 -194.360038)
				)
				(arc
					(start 122.700034 -194.360038)
					(mid 117.700044 -189.360048)
					(end 112.700054 -194.360038)
				)
			)
		)
	)
	(zone
		(layer "B.Cu")
		(hatch none 0.5)
		(connect_pads
			(clearance 0)
		)
		(min_thickness 0.25)
		(keepout
			(tracks allowed)
			(vias allowed)
			(pads allowed)
			(copperpour allowed)
			(footprints not_allowed)
		)
		(placement
			(enabled no)
			(sheetname "")
		)
		(fill
			(thermal_gap 0.5)
			(thermal_bridge_width 0.5)
			(island_removal_mode 0)
		)
		(polygon
			(pts
				(arc
					(start 26.800048 -72.69988)
					(mid 18.800064 -64.699896)
					(end 10.80008 -72.69988)
				)
				(arc
					(start 10.80008 -84.70011)
					(mid 18.800064 -92.700094)
					(end 26.800048 -84.70011)
				)
			)
		)
	)
	(zone
		(layer "B.Cu")
		(hatch none 0.5)
		(connect_pads
			(clearance 0)
		)
		(min_thickness 0.25)
		(keepout
			(tracks not_allowed)
			(vias allowed)
			(pads allowed)
			(copperpour not_allowed)
			(footprints allowed)
		)
		(placement
			(enabled no)
			(sheetname "")
		)
		(fill
			(thermal_gap 0.5)
			(thermal_bridge_width 0.5)
			(island_removal_mode 0)
		)
		(polygon
			(pts
				(arc
					(start 122.889772 -401.49018)
					(mid 122.130312 -401.49018)
					(end 122.889772 -401.49018)
				)
			)
		)
	)
	(zone
		(layer "B.Cu")
		(hatch none 0.5)
		(connect_pads
			(clearance 0)
		)
		(min_thickness 0.25)
		(keepout
			(tracks not_allowed)
			(vias allowed)
			(pads allowed)
			(copperpour not_allowed)
			(footprints allowed)
		)
		(placement
			(enabled no)
			(sheetname "")
		)
		(fill
			(thermal_gap 0.5)
			(thermal_bridge_width 0.5)
			(island_removal_mode 0)
		)
		(polygon
			(pts
				(arc
					(start 306.426108 -316.799722)
					(mid 305.773328 -316.799722)
					(end 306.426108 -316.799722)
				)
			)
		)
	)
	(zone
		(layer "B.Cu")
		(hatch none 0.5)
		(connect_pads
			(clearance 0)
		)
		(min_thickness 0.25)
		(keepout
			(tracks not_allowed)
			(vias allowed)
			(pads allowed)
			(copperpour not_allowed)
			(footprints allowed)
		)
		(placement
			(enabled no)
			(sheetname "")
		)
		(fill
			(thermal_gap 0.5)
			(thermal_bridge_width 0.5)
			(island_removal_mode 0)
		)
		(polygon
			(pts
				(arc
					(start 361.590082 -407.599896)
					(mid 363.590078 -409.599892)
					(end 365.590074 -407.599896)
				)
				(arc
					(start 365.590074 -407.599896)
					(mid 363.590078 -405.5999)
					(end 361.590082 -407.599896)
				)
			)
		)
	)
	(zone
		(layer "B.Cu")
		(hatch none 0.5)
		(connect_pads
			(clearance 0)
		)
		(min_thickness 0.25)
		(keepout
			(tracks allowed)
			(vias allowed)
			(pads allowed)
			(copperpour allowed)
			(footprints allowed)
		)
		(placement
			(enabled no)
			(sheetname "")
		)
		(fill
			(thermal_gap 0.5)
			(thermal_bridge_width 0.5)
			(island_removal_mode 0)
		)
		(polygon
			(pts
				(xy 98.321114 -354.280216) (xy 101.398324 -354.280216) (xy 101.555804 -354.122736) (xy 101.555804 -351.46488)
				(xy 101.468428 -351.377504) (xy 98.34753 -351.377504) (xy 98.281744 -351.44329) (xy 98.281744 -354.240846)
			)
		)
	)
	(zone
		(layer "B.Cu")
		(hatch none 0.5)
		(connect_pads
			(clearance 0)
		)
		(min_thickness 0.25)
		(keepout
			(tracks allowed)
			(vias allowed)
			(pads allowed)
			(copperpour allowed)
			(footprints allowed)
		)
		(placement
			(enabled no)
			(sheetname "")
		)
		(fill
			(thermal_gap 0.5)
			(thermal_bridge_width 0.5)
			(island_removal_mode 0)
		)
		(polygon
			(pts
				(xy 229.6668 -222.9358) (xy 230.8098 -222.9358) (xy 231.2416 -222.504) (xy 231.2416 -222.3516) (xy 231.394 -222.1992)
				(xy 231.902 -222.1992) (xy 232.156 -221.9452) (xy 232.156 -221.6404) (xy 232.4354 -221.361) (xy 232.8164 -221.361)
				(xy 232.9434 -221.234) (xy 232.9434 -220.7768) (xy 233.1466 -220.5736) (xy 233.7816 -220.5736) (xy 234.9754 -219.3798)
				(xy 235.4072 -219.3798) (xy 235.6866 -219.6592) (xy 235.6866 -224.1804) (xy 235.5342 -224.3328)
				(xy 232.8926 -224.3328) (xy 232.5624 -224.0026) (xy 232.5624 -222.5548) (xy 231.8258 -222.5548)
				(xy 231.6226 -222.758) (xy 231.6226 -222.9866) (xy 231.3686 -223.2406) (xy 229.7176 -223.2406) (xy 229.6668 -223.1898)
			)
		)
	)
	(zone
		(layer "B.Cu")
		(hatch none 0.5)
		(connect_pads
			(clearance 0)
		)
		(min_thickness 0.25)
		(keepout
			(tracks not_allowed)
			(vias allowed)
			(pads allowed)
			(copperpour not_allowed)
			(footprints allowed)
		)
		(placement
			(enabled no)
			(sheetname "")
		)
		(fill
			(thermal_gap 0.5)
			(thermal_bridge_width 0.5)
			(island_removal_mode 0)
		)
		(polygon
			(pts
				(arc
					(start 460.000096 -398.100042)
					(mid 461.600042 -399.699988)
					(end 463.199988 -398.100042)
				)
				(arc
					(start 463.199988 -398.100042)
					(mid 461.600042 -396.500096)
					(end 460.000096 -398.100042)
				)
			)
		)
	)
	(zone
		(layer "B.Cu")
		(hatch none 0.5)
		(connect_pads
			(clearance 0)
		)
		(min_thickness 0.25)
		(keepout
			(tracks allowed)
			(vias allowed)
			(pads allowed)
			(copperpour allowed)
			(footprints allowed)
		)
		(placement
			(enabled no)
			(sheetname "")
		)
		(fill
			(thermal_gap 0.5)
			(thermal_bridge_width 0.5)
			(island_removal_mode 0)
		)
		(polygon
			(pts
				(xy 419.931342 -301.7774) (xy 421.633142 -301.7774) (xy 421.836342 -301.9806) (xy 421.836342 -302.2346)
				(xy 421.328342 -302.7426) (xy 419.753542 -302.7426) (xy 419.550342 -302.9458) (xy 419.550342 -307.0352)
				(xy 419.093142 -307.4924) (xy 408.298142 -307.4924) (xy 407.713942 -308.0766) (xy 407.713942 -320.4464)
				(xy 407.180542 -320.4464) (xy 407.053542 -320.3194) (xy 407.053542 -307.8988) (xy 407.917142 -307.0352)
				(xy 419.016942 -307.0352) (xy 419.118542 -306.9336) (xy 419.118542 -302.5902)
			)
		)
	)
	(zone
		(layer "B.Cu")
		(hatch none 0.5)
		(connect_pads
			(clearance 0)
		)
		(min_thickness 0.25)
		(keepout
			(tracks not_allowed)
			(vias allowed)
			(pads allowed)
			(copperpour not_allowed)
			(footprints allowed)
		)
		(placement
			(enabled no)
			(sheetname "")
		)
		(fill
			(thermal_gap 0.5)
			(thermal_bridge_width 0.5)
			(island_removal_mode 0)
		)
		(polygon
			(pts
				(arc
					(start 293.520114 -20.72005)
					(mid 291.520118 -18.720054)
					(end 289.520122 -20.72005)
				)
				(arc
					(start 289.520122 -20.72005)
					(mid 291.520118 -22.720046)
					(end 293.520114 -20.72005)
				)
			)
		)
	)
	(zone
		(layer "B.Cu")
		(hatch none 0.5)
		(connect_pads
			(clearance 0)
		)
		(min_thickness 0.25)
		(keepout
			(tracks allowed)
			(vias allowed)
			(pads allowed)
			(copperpour allowed)
			(footprints not_allowed)
		)
		(placement
			(enabled no)
			(sheetname "")
		)
		(fill
			(thermal_gap 0.5)
			(thermal_bridge_width 0.5)
			(island_removal_mode 0)
		)
		(polygon
			(pts
				(arc
					(start 255.849882 -260.400038)
					(mid 252.667998 -261.718018)
					(end 251.350018 -264.899902)
				)
				(arc
					(start 251.350018 -326.900032)
					(mid 252.667998 -330.081916)
					(end 255.849882 -331.399896)
				)
				(arc
					(start 327.849992 -331.399896)
					(mid 331.032041 -330.082006)
					(end 332.35011 -326.900032)
				)
				(arc
					(start 332.35011 -264.899902)
					(mid 331.031951 -261.718092)
					(end 327.849992 -260.400038)
				)
			)
		)
	)
	(zone
		(layer "B.Cu")
		(hatch none 0.5)
		(connect_pads
			(clearance 0)
		)
		(min_thickness 0.25)
		(keepout
			(tracks not_allowed)
			(vias allowed)
			(pads allowed)
			(copperpour not_allowed)
			(footprints allowed)
		)
		(placement
			(enabled no)
			(sheetname "")
		)
		(fill
			(thermal_gap 0.5)
			(thermal_bridge_width 0.5)
			(island_removal_mode 0)
		)
		(polygon
			(pts
				(arc
					(start 32.6898 -379.590046)
					(mid 31.93034 -379.590046)
					(end 32.6898 -379.590046)
				)
			)
		)
	)
	(zone
		(layer "B.Cu")
		(hatch none 0.5)
		(connect_pads
			(clearance 0)
		)
		(min_thickness 0.25)
		(keepout
			(tracks allowed)
			(vias allowed)
			(pads allowed)
			(copperpour allowed)
			(footprints allowed)
		)
		(placement
			(enabled no)
			(sheetname "")
		)
		(fill
			(thermal_gap 0.5)
			(thermal_bridge_width 0.5)
			(island_removal_mode 0)
		)
		(polygon
			(pts
				(xy 54.327044 -366.380014) (xy 54.327044 -365.293402) (xy 56.325516 -365.293402) (xy 56.325516 -366.380014)
			)
		)
	)
	(zone
		(layer "B.Cu")
		(hatch none 0.5)
		(connect_pads
			(clearance 0)
		)
		(min_thickness 0.25)
		(keepout
			(tracks not_allowed)
			(vias allowed)
			(pads allowed)
			(copperpour not_allowed)
			(footprints allowed)
		)
		(placement
			(enabled no)
			(sheetname "")
		)
		(fill
			(thermal_gap 0.5)
			(thermal_bridge_width 0.5)
			(island_removal_mode 0)
		)
		(polygon
			(pts
				(arc
					(start 185.576464 -318.699896)
					(mid 184.923684 -318.699896)
					(end 185.576464 -318.699896)
				)
			)
		)
	)
	(zone
		(layer "B.Cu")
		(hatch none 0.5)
		(connect_pads
			(clearance 0)
		)
		(min_thickness 0.25)
		(keepout
			(tracks not_allowed)
			(vias allowed)
			(pads allowed)
			(copperpour not_allowed)
			(footprints allowed)
		)
		(placement
			(enabled no)
			(sheetname "")
		)
		(fill
			(thermal_gap 0.5)
			(thermal_bridge_width 0.5)
			(island_removal_mode 0)
		)
		(polygon
			(pts
				(arc
					(start 37.089842 -378.290074)
					(mid 36.330382 -378.290074)
					(end 37.089842 -378.290074)
				)
			)
		)
	)
	(zone
		(layer "B.Cu")
		(hatch none 0.5)
		(connect_pads
			(clearance 0)
		)
		(min_thickness 0.25)
		(keepout
			(tracks not_allowed)
			(vias allowed)
			(pads allowed)
			(copperpour not_allowed)
			(footprints allowed)
		)
		(placement
			(enabled no)
			(sheetname "")
		)
		(fill
			(thermal_gap 0.5)
			(thermal_bridge_width 0.5)
			(island_removal_mode 0)
		)
		(polygon
			(pts
				(arc
					(start 266.199874 -393.100052)
					(mid 268.200124 -395.100302)
					(end 270.20012 -393.100052)
				)
				(arc
					(start 270.20012 -393.100052)
					(mid 268.200124 -391.100056)
					(end 266.199874 -393.100052)
				)
			)
		)
	)
	(zone
		(layer "B.Cu")
		(hatch none 0.5)
		(connect_pads
			(clearance 0)
		)
		(min_thickness 0.25)
		(keepout
			(tracks not_allowed)
			(vias allowed)
			(pads allowed)
			(copperpour not_allowed)
			(footprints allowed)
		)
		(placement
			(enabled no)
			(sheetname "")
		)
		(fill
			(thermal_gap 0.5)
			(thermal_bridge_width 0.5)
			(island_removal_mode 0)
		)
		(polygon
			(pts
				(arc
					(start 81.826354 -306.349908)
					(mid 81.173574 -306.349908)
					(end 81.826354 -306.349908)
				)
			)
		)
	)
	(zone
		(layer "B.Cu")
		(hatch none 0.5)
		(connect_pads
			(clearance 0)
		)
		(min_thickness 0.25)
		(keepout
			(tracks allowed)
			(vias allowed)
			(pads allowed)
			(copperpour allowed)
			(footprints allowed)
		)
		(placement
			(enabled no)
			(sheetname "")
		)
		(fill
			(thermal_gap 0.5)
			(thermal_bridge_width 0.5)
			(island_removal_mode 0)
		)
		(polygon
			(pts
				(xy 101.000052 -334.481932) (xy 103.133144 -334.481932) (xy 104.094788 -333.520288) (xy 104.094788 -330.058014)
				(xy 103.622856 -329.586082) (xy 100.930202 -329.586082) (xy 100.89515 -329.621134) (xy 100.89515 -334.37703)
			)
		)
	)
	(zone
		(layer "B.Cu")
		(hatch none 0.5)
		(connect_pads
			(clearance 0)
		)
		(min_thickness 0.25)
		(keepout
			(tracks not_allowed)
			(vias allowed)
			(pads allowed)
			(copperpour not_allowed)
			(footprints allowed)
		)
		(placement
			(enabled no)
			(sheetname "")
		)
		(fill
			(thermal_gap 0.5)
			(thermal_bridge_width 0.5)
			(island_removal_mode 0)
		)
		(polygon
			(pts
				(arc
					(start 391.269728 -371.590062)
					(mid 390.510268 -371.590062)
					(end 391.269728 -371.590062)
				)
			)
		)
	)
	(zone
		(layer "B.Cu")
		(hatch none 0.5)
		(connect_pads
			(clearance 0)
		)
		(min_thickness 0.25)
		(keepout
			(tracks not_allowed)
			(vias allowed)
			(pads allowed)
			(copperpour not_allowed)
			(footprints allowed)
		)
		(placement
			(enabled no)
			(sheetname "")
		)
		(fill
			(thermal_gap 0.5)
			(thermal_bridge_width 0.5)
			(island_removal_mode 0)
		)
		(polygon
			(pts
				(arc
					(start 389.06958 -400.390106)
					(mid 388.31012 -400.390106)
					(end 389.06958 -400.390106)
				)
			)
		)
	)
	(zone
		(layer "B.Cu")
		(hatch none 0.5)
		(connect_pads
			(clearance 0)
		)
		(min_thickness 0.25)
		(keepout
			(tracks not_allowed)
			(vias allowed)
			(pads allowed)
			(copperpour not_allowed)
			(footprints allowed)
		)
		(placement
			(enabled no)
			(sheetname "")
		)
		(fill
			(thermal_gap 0.5)
			(thermal_bridge_width 0.5)
			(island_removal_mode 0)
		)
		(polygon
			(pts
				(arc
					(start 45.889672 -371.790214)
					(mid 45.130212 -371.790214)
					(end 45.889672 -371.790214)
				)
			)
		)
	)
	(zone
		(layer "B.Cu")
		(hatch none 0.5)
		(connect_pads
			(clearance 0)
		)
		(min_thickness 0.25)
		(keepout
			(tracks allowed)
			(vias allowed)
			(pads allowed)
			(copperpour allowed)
			(footprints not_allowed)
		)
		(placement
			(enabled no)
			(sheetname "")
		)
		(fill
			(thermal_gap 0.5)
			(thermal_bridge_width 0.5)
			(island_removal_mode 0)
		)
		(polygon
			(pts
				(xy 80.149954 -280.399998) (xy 39.150036 -280.399998) (xy 39.150036 -311.399936) (xy 80.149954 -311.399936)
			)
		)
	)
	(zone
		(layer "B.Cu")
		(hatch none 0.5)
		(connect_pads
			(clearance 0)
		)
		(min_thickness 0.25)
		(keepout
			(tracks allowed)
			(vias allowed)
			(pads allowed)
			(copperpour allowed)
			(footprints not_allowed)
		)
		(placement
			(enabled no)
			(sheetname "")
		)
		(fill
			(thermal_gap 0.5)
			(thermal_bridge_width 0.5)
			(island_removal_mode 0)
		)
		(polygon
			(pts
				(xy 428.449994 -280.399998) (xy 387.450076 -280.399998) (xy 387.450076 -311.399936) (xy 428.449994 -311.399936)
			)
		)
	)
	(zone
		(layer "B.Cu")
		(hatch none 0.5)
		(connect_pads
			(clearance 0)
		)
		(min_thickness 0.25)
		(keepout
			(tracks allowed)
			(vias allowed)
			(pads allowed)
			(copperpour allowed)
			(footprints allowed)
		)
		(placement
			(enabled no)
			(sheetname "")
		)
		(fill
			(thermal_gap 0.5)
			(thermal_bridge_width 0.5)
			(island_removal_mode 0)
		)
		(polygon
			(pts
				(xy 104.492806 -335.735676) (xy 106.661204 -335.735676) (xy 107.010708 -335.386172) (xy 107.010708 -334.004666)
				(xy 106.82732 -333.821278) (xy 104.964992 -333.821278) (xy 104.457754 -334.328516) (xy 104.457754 -335.700624)
			)
		)
	)
	(zone
		(layer "B.Cu")
		(hatch none 0.5)
		(connect_pads
			(clearance 0)
		)
		(min_thickness 0.25)
		(keepout
			(tracks not_allowed)
			(vias allowed)
			(pads allowed)
			(copperpour not_allowed)
			(footprints allowed)
		)
		(placement
			(enabled no)
			(sheetname "")
		)
		(fill
			(thermal_gap 0.5)
			(thermal_bridge_width 0.5)
			(island_removal_mode 0)
		)
		(polygon
			(pts
				(arc
					(start 31.900114 -270.89989)
					(mid 29.650182 -268.649958)
					(end 27.399996 -270.89989)
				)
				(arc
					(start 27.399996 -270.89989)
					(mid 29.650182 -273.150076)
					(end 31.900114 -270.89989)
				)
			)
		)
	)
	(zone
		(layer "B.Cu")
		(hatch none 0.5)
		(connect_pads
			(clearance 0)
		)
		(min_thickness 0.25)
		(keepout
			(tracks allowed)
			(vias allowed)
			(pads allowed)
			(copperpour allowed)
			(footprints allowed)
		)
		(placement
			(enabled no)
			(sheetname "")
		)
		(fill
			(thermal_gap 0.5)
			(thermal_bridge_width 0.5)
			(island_removal_mode 0)
		)
		(polygon
			(pts
				(xy 237.786418 -267.970762) (xy 237.786418 -265.811762) (xy 239.437418 -265.811762) (xy 239.437418 -267.970762)
			)
		)
	)
	(zone
		(layer "B.Cu")
		(hatch none 0.5)
		(connect_pads
			(clearance 0)
		)
		(min_thickness 0.25)
		(keepout
			(tracks not_allowed)
			(vias allowed)
			(pads allowed)
			(copperpour not_allowed)
			(footprints allowed)
		)
		(placement
			(enabled no)
			(sheetname "")
		)
		(fill
			(thermal_gap 0.5)
			(thermal_bridge_width 0.5)
			(island_removal_mode 0)
		)
		(polygon
			(pts
				(arc
					(start 415.876232 -318.699896)
					(mid 415.223452 -318.699896)
					(end 415.876232 -318.699896)
				)
			)
		)
	)
	(zone
		(layer "B.Cu")
		(hatch none 0.5)
		(connect_pads
			(clearance 0)
		)
		(min_thickness 0.25)
		(keepout
			(tracks allowed)
			(vias allowed)
			(pads allowed)
			(copperpour allowed)
			(footprints allowed)
		)
		(placement
			(enabled no)
			(sheetname "")
		)
		(fill
			(thermal_gap 0.5)
			(thermal_bridge_width 0.5)
			(island_removal_mode 0)
		)
		(polygon
			(pts
				(xy 110.330742 -312.599578) (xy 111.981742 -312.599578) (xy 111.981742 -314.758578) (xy 110.330742 -314.758578)
			)
		)
	)
	(zone
		(layer "B.Cu")
		(hatch none 0.5)
		(connect_pads
			(clearance 0)
		)
		(min_thickness 0.25)
		(keepout
			(tracks allowed)
			(vias allowed)
			(pads allowed)
			(copperpour allowed)
			(footprints not_allowed)
		)
		(placement
			(enabled no)
			(sheetname "")
		)
		(fill
			(thermal_gap 0.5)
			(thermal_bridge_width 0.5)
			(island_removal_mode 0)
		)
		(polygon
			(pts
				(arc
					(start 5.32003 -20.72005)
					(mid 7.320026 -22.720046)
					(end 9.320022 -20.72005)
				)
				(arc
					(start 9.320022 -20.72005)
					(mid 7.320026 -18.720054)
					(end 5.32003 -20.72005)
				)
			)
		)
	)
	(zone
		(layer "B.Cu")
		(hatch none 0.5)
		(connect_pads
			(clearance 0)
		)
		(min_thickness 0.25)
		(keepout
			(tracks allowed)
			(vias allowed)
			(pads allowed)
			(copperpour allowed)
			(footprints not_allowed)
		)
		(placement
			(enabled no)
			(sheetname "")
		)
		(fill
			(thermal_gap 0.5)
			(thermal_bridge_width 0.5)
			(island_removal_mode 0)
		)
		(polygon
			(pts
				(arc
					(start 139.800076 -407.960068)
					(mid 147.80006 -415.960052)
					(end 155.800044 -407.960068)
				)
				(arc
					(start 155.800044 -407.960068)
					(mid 147.80006 -399.960084)
					(end 139.800076 -407.960068)
				)
			)
		)
	)
	(zone
		(layer "B.Cu")
		(hatch none 0.5)
		(connect_pads
			(clearance 0)
		)
		(min_thickness 0.25)
		(keepout
			(tracks allowed)
			(vias allowed)
			(pads allowed)
			(copperpour allowed)
			(footprints allowed)
		)
		(placement
			(enabled no)
			(sheetname "")
		)
		(fill
			(thermal_gap 0.5)
			(thermal_bridge_width 0.5)
			(island_removal_mode 0)
		)
		(polygon
			(pts
				(xy 217.98026 -267.970762) (xy 217.98026 -265.811762) (xy 219.75826 -265.811762) (xy 219.75826 -267.970762)
			)
		)
	)
	(zone
		(layer "B.Cu")
		(hatch none 0.5)
		(connect_pads
			(clearance 0)
		)
		(min_thickness 0.25)
		(keepout
			(tracks not_allowed)
			(vias allowed)
			(pads allowed)
			(copperpour not_allowed)
			(footprints allowed)
		)
		(placement
			(enabled no)
			(sheetname "")
		)
		(fill
			(thermal_gap 0.5)
			(thermal_bridge_width 0.5)
			(island_removal_mode 0)
		)
		(polygon
			(pts
				(arc
					(start 147.999958 -320.900044)
					(mid 145.750026 -318.650112)
					(end 143.500094 -320.900044)
				)
				(arc
					(start 143.500094 -320.900044)
					(mid 145.750026 -323.149976)
					(end 147.999958 -320.900044)
				)
			)
		)
	)
	(zone
		(layer "B.Cu")
		(hatch none 0.5)
		(connect_pads
			(clearance 0)
		)
		(min_thickness 0.25)
		(keepout
			(tracks not_allowed)
			(vias allowed)
			(pads allowed)
			(copperpour not_allowed)
			(footprints allowed)
		)
		(placement
			(enabled no)
			(sheetname "")
		)
		(fill
			(thermal_gap 0.5)
			(thermal_bridge_width 0.5)
			(island_removal_mode 0)
		)
		(polygon
			(pts
				(arc
					(start 118.48973 -372.890034)
					(mid 117.73027 -372.890034)
					(end 118.48973 -372.890034)
				)
			)
		)
	)
	(zone
		(layer "B.Cu")
		(hatch none 0.5)
		(connect_pads
			(clearance 0)
		)
		(min_thickness 0.25)
		(keepout
			(tracks not_allowed)
			(vias allowed)
			(pads allowed)
			(copperpour not_allowed)
			(footprints allowed)
		)
		(placement
			(enabled no)
			(sheetname "")
		)
		(fill
			(thermal_gap 0.5)
			(thermal_bridge_width 0.5)
			(island_removal_mode 0)
		)
		(polygon
			(pts
				(arc
					(start 310.226202 -316.799722)
					(mid 309.573422 -316.799722)
					(end 310.226202 -316.799722)
				)
			)
		)
	)
	(zone
		(layer "B.Cu")
		(hatch none 0.5)
		(connect_pads
			(clearance 0)
		)
		(min_thickness 0.25)
		(keepout
			(tracks allowed)
			(vias allowed)
			(pads allowed)
			(copperpour allowed)
			(footprints not_allowed)
		)
		(placement
			(enabled no)
			(sheetname "")
		)
		(fill
			(thermal_gap 0.5)
			(thermal_bridge_width 0.5)
			(island_removal_mode 0)
		)
		(polygon
			(pts
				(arc
					(start 203.700126 -378.70003)
					(mid 195.700142 -370.700046)
					(end 187.699904 -378.70003)
				)
				(arc
					(start 187.699904 -378.70003)
					(mid 195.700142 -386.700268)
					(end 203.700126 -378.70003)
				)
			)
		)
	)
	(zone
		(layer "B.Cu")
		(hatch none 0.5)
		(connect_pads
			(clearance 0)
		)
		(min_thickness 0.25)
		(keepout
			(tracks not_allowed)
			(vias allowed)
			(pads allowed)
			(copperpour not_allowed)
			(footprints allowed)
		)
		(placement
			(enabled no)
			(sheetname "")
		)
		(fill
			(thermal_gap 0.5)
			(thermal_bridge_width 0.5)
			(island_removal_mode 0)
		)
		(polygon
			(pts
				(arc
					(start 118.48973 -402.790152)
					(mid 117.73027 -402.790152)
					(end 118.48973 -402.790152)
				)
			)
		)
	)
	(zone
		(layer "B.Cu")
		(hatch none 0.5)
		(connect_pads
			(clearance 0)
		)
		(min_thickness 0.25)
		(keepout
			(tracks allowed)
			(vias allowed)
			(pads allowed)
			(copperpour allowed)
			(footprints not_allowed)
		)
		(placement
			(enabled no)
			(sheetname "")
		)
		(fill
			(thermal_gap 0.5)
			(thermal_bridge_width 0.5)
			(island_removal_mode 0)
		)
		(polygon
			(pts
				(arc
					(start 248.819924 -15.649956)
					(mid 250.81992 -17.649952)
					(end 252.819916 -15.649956)
				)
				(arc
					(start 252.819916 -15.649956)
					(mid 250.81992 -13.64996)
					(end 248.819924 -15.649956)
				)
			)
		)
	)
	(zone
		(layer "B.Cu")
		(hatch none 0.5)
		(connect_pads
			(clearance 0)
		)
		(min_thickness 0.25)
		(keepout
			(tracks not_allowed)
			(vias allowed)
			(pads allowed)
			(copperpour not_allowed)
			(footprints allowed)
		)
		(placement
			(enabled no)
			(sheetname "")
		)
		(fill
			(thermal_gap 0.5)
			(thermal_bridge_width 0.5)
			(island_removal_mode 0)
		)
		(polygon
			(pts
				(arc
					(start 303.26965 -379.390148)
					(mid 302.51019 -379.390148)
					(end 303.26965 -379.390148)
				)
			)
		)
	)
	(zone
		(layer "B.Cu")
		(hatch none 0.5)
		(connect_pads
			(clearance 0)
		)
		(min_thickness 0.25)
		(keepout
			(tracks not_allowed)
			(vias allowed)
			(pads allowed)
			(copperpour not_allowed)
			(footprints allowed)
		)
		(placement
			(enabled no)
			(sheetname "")
		)
		(fill
			(thermal_gap 0.5)
			(thermal_bridge_width 0.5)
			(island_removal_mode 0)
		)
		(polygon
			(pts
				(arc
					(start 184.62625 -315.849762)
					(mid 183.97347 -315.849762)
					(end 184.62625 -315.849762)
				)
			)
		)
	)
	(zone
		(layer "B.Cu")
		(hatch none 0.5)
		(connect_pads
			(clearance 0)
		)
		(min_thickness 0.25)
		(keepout
			(tracks not_allowed)
			(vias allowed)
			(pads allowed)
			(copperpour not_allowed)
			(footprints allowed)
		)
		(placement
			(enabled no)
			(sheetname "")
		)
		(fill
			(thermal_gap 0.5)
			(thermal_bridge_width 0.5)
			(island_removal_mode 0)
		)
		(polygon
			(pts
				(arc
					(start 368.920014 -15.649956)
					(mid 366.920018 -13.64996)
					(end 364.920022 -15.649956)
				)
				(arc
					(start 364.920022 -15.649956)
					(mid 366.920018 -17.649952)
					(end 368.920014 -15.649956)
				)
			)
		)
	)
	(zone
		(layer "B.Cu")
		(hatch none 0.5)
		(connect_pads
			(clearance 0)
		)
		(min_thickness 0.25)
		(keepout
			(tracks not_allowed)
			(vias allowed)
			(pads allowed)
			(copperpour not_allowed)
			(footprints allowed)
		)
		(placement
			(enabled no)
			(sheetname "")
		)
		(fill
			(thermal_gap 0.5)
			(thermal_bridge_width 0.5)
			(island_removal_mode 0)
		)
		(polygon
			(pts
				(arc
					(start 306.426108 -315.849762)
					(mid 305.773328 -315.849762)
					(end 306.426108 -315.849762)
				)
			)
		)
	)
	(zone
		(layer "B.Cu")
		(hatch none 0.5)
		(connect_pads
			(clearance 0)
		)
		(min_thickness 0.25)
		(keepout
			(tracks not_allowed)
			(vias allowed)
			(pads allowed)
			(copperpour not_allowed)
			(footprints allowed)
		)
		(placement
			(enabled no)
			(sheetname "")
		)
		(fill
			(thermal_gap 0.5)
			(thermal_bridge_width 0.5)
			(island_removal_mode 0)
		)
		(polygon
			(pts
				(arc
					(start 395.92631 -316.799722)
					(mid 395.27353 -316.799722)
					(end 395.92631 -316.799722)
				)
			)
		)
	)
	(zone
		(layer "B.Cu")
		(hatch none 0.5)
		(connect_pads
			(clearance 0)
		)
		(min_thickness 0.25)
		(keepout
			(tracks allowed)
			(vias allowed)
			(pads allowed)
			(copperpour allowed)
			(footprints not_allowed)
		)
		(placement
			(enabled no)
			(sheetname "")
		)
		(fill
			(thermal_gap 0.5)
			(thermal_bridge_width 0.5)
			(island_removal_mode 0)
		)
		(polygon
			(pts
				(arc
					(start 267.299948 -98.700082)
					(mid 259.299964 -90.700098)
					(end 251.29998 -98.700082)
				)
				(arc
					(start 251.29998 -98.700082)
					(mid 259.299964 -106.700066)
					(end 267.299948 -98.700082)
				)
			)
		)
	)
	(zone
		(layer "B.Cu")
		(hatch none 0.5)
		(connect_pads
			(clearance 0)
		)
		(min_thickness 0.25)
		(keepout
			(tracks allowed)
			(vias allowed)
			(pads allowed)
			(copperpour allowed)
			(footprints not_allowed)
		)
		(placement
			(enabled no)
			(sheetname "")
		)
		(fill
			(thermal_gap 0.5)
			(thermal_bridge_width 0.5)
			(island_removal_mode 0)
		)
		(polygon
			(pts
				(arc
					(start 187.699904 -378.70003)
					(mid 195.700142 -386.700268)
					(end 203.700126 -378.70003)
				)
				(arc
					(start 203.700126 -378.70003)
					(mid 195.700142 -370.700046)
					(end 187.699904 -378.70003)
				)
			)
		)
	)
	(zone
		(layer "B.Cu")
		(hatch none 0.5)
		(connect_pads
			(clearance 0)
		)
		(min_thickness 0.25)
		(keepout
			(tracks allowed)
			(vias allowed)
			(pads allowed)
			(copperpour allowed)
			(footprints allowed)
		)
		(placement
			(enabled no)
			(sheetname "")
		)
		(fill
			(thermal_gap 0.5)
			(thermal_bridge_width 0.5)
			(island_removal_mode 0)
		)
		(polygon
			(pts
				(xy 120.162828 -312.599578) (xy 121.813828 -312.599578) (xy 121.813828 -314.758578) (xy 120.162828 -314.758578)
			)
		)
	)
	(zone
		(layer "B.Cu")
		(hatch none 0.5)
		(connect_pads
			(clearance 0)
		)
		(min_thickness 0.25)
		(keepout
			(tracks allowed)
			(vias allowed)
			(pads allowed)
			(copperpour allowed)
			(footprints not_allowed)
		)
		(placement
			(enabled no)
			(sheetname "")
		)
		(fill
			(thermal_gap 0.5)
			(thermal_bridge_width 0.5)
			(island_removal_mode 0)
		)
		(polygon
			(pts
				(arc
					(start 125.42012 -20.72005)
					(mid 123.420124 -18.720054)
					(end 121.419874 -20.72005)
				)
				(arc
					(start 121.419874 -20.72005)
					(mid 123.420124 -22.7203)
					(end 125.42012 -20.72005)
				)
			)
		)
	)
	(zone
		(layer "B.Cu")
		(hatch none 0.5)
		(connect_pads
			(clearance 0)
		)
		(min_thickness 0.25)
		(keepout
			(tracks not_allowed)
			(vias allowed)
			(pads allowed)
			(copperpour not_allowed)
			(footprints allowed)
		)
		(placement
			(enabled no)
			(sheetname "")
		)
		(fill
			(thermal_gap 0.5)
			(thermal_bridge_width 0.5)
			(island_removal_mode 0)
		)
		(polygon
			(pts
				(arc
					(start 3.999992 -407.599896)
					(mid 5.999988 -409.599892)
					(end 7.999984 -407.599896)
				)
				(arc
					(start 7.999984 -407.599896)
					(mid 5.999988 -405.5999)
					(end 3.999992 -407.599896)
				)
			)
		)
	)
	(zone
		(layer "B.Cu")
		(hatch none 0.5)
		(connect_pads
			(clearance 0)
		)
		(min_thickness 0.25)
		(keepout
			(tracks not_allowed)
			(vias allowed)
			(pads allowed)
			(copperpour not_allowed)
			(footprints allowed)
		)
		(placement
			(enabled no)
			(sheetname "")
		)
		(fill
			(thermal_gap 0.5)
			(thermal_bridge_width 0.5)
			(island_removal_mode 0)
		)
		(polygon
			(pts
				(arc
					(start 115.700048 -194.360038)
					(mid 117.700044 -196.360034)
					(end 119.70004 -194.360038)
				)
				(arc
					(start 119.70004 -194.360038)
					(mid 117.700044 -192.360042)
					(end 115.700048 -194.360038)
				)
			)
		)
	)
	(zone
		(layer "B.Cu")
		(hatch none 0.5)
		(connect_pads
			(clearance 0)
		)
		(min_thickness 0.25)
		(keepout
			(tracks allowed)
			(vias allowed)
			(pads allowed)
			(copperpour allowed)
			(footprints not_allowed)
		)
		(placement
			(enabled no)
			(sheetname "")
		)
		(fill
			(thermal_gap 0.5)
			(thermal_bridge_width 0.5)
			(island_removal_mode 0)
		)
		(polygon
			(pts
				(arc
					(start 109.70006 -72.69988)
					(mid 117.700044 -80.699864)
					(end 125.700028 -72.69988)
				)
				(arc
					(start 125.700028 -60.699904)
					(mid 117.700044 -52.69992)
					(end 109.70006 -60.699904)
				)
			)
		)
	)
	(zone
		(layer "B.Cu")
		(hatch none 0.5)
		(connect_pads
			(clearance 0)
		)
		(min_thickness 0.25)
		(keepout
			(tracks allowed)
			(vias allowed)
			(pads allowed)
			(copperpour allowed)
			(footprints allowed)
		)
		(placement
			(enabled no)
			(sheetname "")
		)
		(fill
			(thermal_gap 0.5)
			(thermal_bridge_width 0.5)
			(island_removal_mode 0)
		)
		(polygon
			(pts
				(xy 101.447092 -386.207) (xy 101.447092 -384.247136) (xy 100.2538 -384.247136) (xy 100.2538 -386.207)
			)
		)
	)
	(zone
		(layer "B.Cu")
		(hatch none 0.5)
		(connect_pads
			(clearance 0)
		)
		(min_thickness 0.25)
		(keepout
			(tracks not_allowed)
			(vias allowed)
			(pads allowed)
			(copperpour not_allowed)
			(footprints allowed)
		)
		(placement
			(enabled no)
			(sheetname "")
		)
		(fill
			(thermal_gap 0.5)
			(thermal_bridge_width 0.5)
			(island_removal_mode 0)
		)
		(polygon
			(pts
				(arc
					(start 125.08992 -401.690078)
					(mid 124.33046 -401.690078)
					(end 125.08992 -401.690078)
				)
			)
		)
	)
	(zone
		(layer "B.Cu")
		(hatch none 0.5)
		(connect_pads
			(clearance 0)
		)
		(min_thickness 0.25)
		(keepout
			(tracks allowed)
			(vias allowed)
			(pads allowed)
			(copperpour allowed)
			(footprints not_allowed)
		)
		(placement
			(enabled no)
			(sheetname "")
		)
		(fill
			(thermal_gap 0.5)
			(thermal_bridge_width 0.5)
			(island_removal_mode 0)
		)
		(polygon
			(pts
				(xy 192.969896 -137.379964) (xy 212.97011 -137.379964) (xy 212.97011 -117.380004) (xy 192.969896 -117.380004)
			)
		)
	)
	(zone
		(layer "B.Cu")
		(hatch none 0.5)
		(connect_pads
			(clearance 0)
		)
		(min_thickness 0.25)
		(keepout
			(tracks not_allowed)
			(vias allowed)
			(pads allowed)
			(copperpour not_allowed)
			(footprints allowed)
		)
		(placement
			(enabled no)
			(sheetname "")
		)
		(fill
			(thermal_gap 0.5)
			(thermal_bridge_width 0.5)
			(island_removal_mode 0)
		)
		(polygon
			(pts
				(arc
					(start 397.465042 -5.999988)
					(mid 400.265138 -8.800084)
					(end 403.06498 -5.999988)
				)
				(arc
					(start 403.06498 -5.999988)
					(mid 400.265138 -3.200146)
					(end 397.465042 -5.999988)
				)
			)
		)
	)
	(zone
		(layer "B.Cu")
		(hatch none 0.5)
		(connect_pads
			(clearance 0)
		)
		(min_thickness 0.25)
		(keepout
			(tracks allowed)
			(vias allowed)
			(pads allowed)
			(copperpour allowed)
			(footprints not_allowed)
		)
		(placement
			(enabled no)
			(sheetname "")
		)
		(fill
			(thermal_gap 0.5)
			(thermal_bridge_width 0.5)
			(island_removal_mode 0)
		)
		(polygon
			(pts
				(arc
					(start 221.114874 -5.999988)
					(mid 226.115118 -11.000232)
					(end 231.115108 -5.999988)
				)
				(arc
					(start 231.115108 -5.999988)
					(mid 226.115118 -0.999998)
					(end 221.114874 -5.999988)
				)
			)
		)
	)
	(zone
		(layer "B.Cu")
		(hatch none 0.5)
		(connect_pads
			(clearance 0)
		)
		(min_thickness 0.25)
		(keepout
			(tracks allowed)
			(vias allowed)
			(pads allowed)
			(copperpour allowed)
			(footprints not_allowed)
		)
		(placement
			(enabled no)
			(sheetname "")
		)
		(fill
			(thermal_gap 0.5)
			(thermal_bridge_width 0.5)
			(island_removal_mode 0)
		)
		(polygon
			(pts
				(xy 370.730018 -137.379964) (xy 390.729978 -137.379964) (xy 390.729978 -117.380004) (xy 370.730018 -117.380004)
			)
		)
	)
	(zone
		(layer "B.Cu")
		(hatch none 0.5)
		(connect_pads
			(clearance 0)
		)
		(min_thickness 0.25)
		(keepout
			(tracks not_allowed)
			(vias allowed)
			(pads allowed)
			(copperpour not_allowed)
			(footprints allowed)
		)
		(placement
			(enabled no)
			(sheetname "")
		)
		(fill
			(thermal_gap 0.5)
			(thermal_bridge_width 0.5)
			(island_removal_mode 0)
		)
		(polygon
			(pts
				(arc
					(start 392.126216 -315.849762)
					(mid 391.473436 -315.849762)
					(end 392.126216 -315.849762)
				)
			)
		)
	)
	(zone
		(layer "B.Cu")
		(hatch none 0.5)
		(connect_pads
			(clearance 0)
		)
		(min_thickness 0.25)
		(keepout
			(tracks not_allowed)
			(vias allowed)
			(pads allowed)
			(copperpour not_allowed)
			(footprints allowed)
		)
		(placement
			(enabled no)
			(sheetname "")
		)
		(fill
			(thermal_gap 0.5)
			(thermal_bridge_width 0.5)
			(island_removal_mode 0)
		)
		(polygon
			(pts
				(arc
					(start 446.000124 -84.70011)
					(mid 448.80022 -87.500206)
					(end 451.600062 -84.70011)
				)
				(arc
					(start 451.600062 -84.70011)
					(mid 448.80022 -81.900268)
					(end 446.000124 -84.70011)
				)
			)
		)
	)
	(zone
		(layer "B.Cu")
		(hatch none 0.5)
		(connect_pads
			(clearance 0)
		)
		(min_thickness 0.25)
		(keepout
			(tracks not_allowed)
			(vias allowed)
			(pads allowed)
			(copperpour not_allowed)
			(footprints allowed)
		)
		(placement
			(enabled no)
			(sheetname "")
		)
		(fill
			(thermal_gap 0.5)
			(thermal_bridge_width 0.5)
			(island_removal_mode 0)
		)
		(polygon
			(pts
				(arc
					(start 43.689778 -379.390148)
					(mid 42.930318 -379.390148)
					(end 43.689778 -379.390148)
				)
			)
		)
	)
	(zone
		(layer "B.Cu")
		(hatch none 0.5)
		(connect_pads
			(clearance 0)
		)
		(min_thickness 0.25)
		(keepout
			(tracks not_allowed)
			(vias allowed)
			(pads allowed)
			(copperpour not_allowed)
			(footprints allowed)
		)
		(placement
			(enabled no)
			(sheetname "")
		)
		(fill
			(thermal_gap 0.5)
			(thermal_bridge_width 0.5)
			(island_removal_mode 0)
		)
		(polygon
			(pts
				(arc
					(start 301.069502 -379.590046)
					(mid 300.310042 -379.590046)
					(end 301.069502 -379.590046)
				)
			)
		)
	)
	(zone
		(layer "B.Cu")
		(hatch none 0.5)
		(connect_pads
			(clearance 0)
		)
		(min_thickness 0.25)
		(keepout
			(tracks allowed)
			(vias allowed)
			(pads allowed)
			(copperpour allowed)
			(footprints not_allowed)
		)
		(placement
			(enabled no)
			(sheetname "")
		)
		(fill
			(thermal_gap 0.5)
			(thermal_bridge_width 0.5)
			(island_removal_mode 0)
		)
		(polygon
			(pts
				(xy 312.349896 -280.399998) (xy 271.349978 -280.399998) (xy 271.349978 -311.399936) (xy 312.349896 -311.399936)
			)
		)
	)
	(zone
		(layer "B.Cu")
		(hatch none 0.5)
		(connect_pads
			(clearance 0)
		)
		(min_thickness 0.25)
		(keepout
			(tracks allowed)
			(vias allowed)
			(pads allowed)
			(copperpour allowed)
			(footprints not_allowed)
		)
		(placement
			(enabled no)
			(sheetname "")
		)
		(fill
			(thermal_gap 0.5)
			(thermal_bridge_width 0.5)
			(island_removal_mode 0)
		)
		(polygon
			(pts
				(arc
					(start 443.449964 -308.61)
					(mid 447.449956 -312.609992)
					(end 451.449948 -308.61)
				)
				(arc
					(start 451.449948 -308.61)
					(mid 447.449956 -304.610008)
					(end 443.449964 -308.61)
				)
			)
		)
	)
	(zone
		(layer "B.Cu")
		(hatch none 0.5)
		(connect_pads
			(clearance 0)
		)
		(min_thickness 0.25)
		(keepout
			(tracks allowed)
			(vias allowed)
			(pads allowed)
			(copperpour allowed)
			(footprints not_allowed)
		)
		(placement
			(enabled no)
			(sheetname "")
		)
		(fill
			(thermal_gap 0.5)
			(thermal_bridge_width 0.5)
			(island_removal_mode 0)
		)
		(polygon
			(pts
				(xy 165.749986 -84.68995) (xy 185.749946 -84.68995) (xy 185.749946 -64.68999) (xy 165.749986 -64.68999)
			)
		)
	)
	(zone
		(layer "B.Cu")
		(hatch none 0.5)
		(connect_pads
			(clearance 0)
		)
		(min_thickness 0.25)
		(keepout
			(tracks not_allowed)
			(vias allowed)
			(pads allowed)
			(copperpour not_allowed)
			(footprints allowed)
		)
		(placement
			(enabled no)
			(sheetname "")
		)
		(fill
			(thermal_gap 0.5)
			(thermal_bridge_width 0.5)
			(island_removal_mode 0)
		)
		(polygon
			(pts
				(arc
					(start 6.800088 -399.699988)
					(mid 8.400034 -398.100042)
					(end 6.800088 -396.500096)
				)
				(arc
					(start 5.199888 -396.500096)
					(mid 3.599942 -398.100042)
					(end 5.199888 -399.699988)
				)
			)
		)
	)
	(zone
		(layer "B.Cu")
		(hatch none 0.5)
		(connect_pads
			(clearance 0)
		)
		(min_thickness 0.25)
		(keepout
			(tracks not_allowed)
			(vias allowed)
			(pads allowed)
			(copperpour not_allowed)
			(footprints allowed)
		)
		(placement
			(enabled no)
			(sheetname "")
		)
		(fill
			(thermal_gap 0.5)
			(thermal_bridge_width 0.5)
			(island_removal_mode 0)
		)
		(polygon
			(pts
				(arc
					(start 312.126122 -305.399948)
					(mid 311.473342 -305.399948)
					(end 312.126122 -305.399948)
				)
			)
		)
	)
	(zone
		(layer "B.Cu")
		(hatch none 0.5)
		(connect_pads
			(clearance 0)
		)
		(min_thickness 0.25)
		(keepout
			(tracks allowed)
			(vias allowed)
			(pads allowed)
			(copperpour allowed)
			(footprints not_allowed)
		)
		(placement
			(enabled no)
			(sheetname "")
		)
		(fill
			(thermal_gap 0.5)
			(thermal_bridge_width 0.5)
			(island_removal_mode 0)
		)
		(polygon
			(pts
				(xy 309.069994 -137.379964) (xy 329.069954 -137.379964) (xy 329.069954 -117.380004) (xy 309.069994 -117.380004)
			)
		)
	)
	(zone
		(layer "B.Cu")
		(hatch none 0.5)
		(connect_pads
			(clearance 0)
		)
		(min_thickness 0.25)
		(keepout
			(tracks not_allowed)
			(vias allowed)
			(pads allowed)
			(copperpour not_allowed)
			(footprints allowed)
		)
		(placement
			(enabled no)
			(sheetname "")
		)
		(fill
			(thermal_gap 0.5)
			(thermal_bridge_width 0.5)
			(island_removal_mode 0)
		)
		(polygon
			(pts
				(arc
					(start 78.97622 -318.699896)
					(mid 78.32344 -318.699896)
					(end 78.97622 -318.699896)
				)
			)
		)
	)
	(zone
		(layer "B.Cu")
		(hatch none 0.5)
		(connect_pads
			(clearance 0)
		)
		(min_thickness 0.25)
		(keepout
			(tracks not_allowed)
			(vias allowed)
			(pads allowed)
			(copperpour not_allowed)
			(footprints allowed)
		)
		(placement
			(enabled no)
			(sheetname "")
		)
		(fill
			(thermal_gap 0.5)
			(thermal_bridge_width 0.5)
			(island_removal_mode 0)
		)
		(polygon
			(pts
				(arc
					(start 127.289814 -401.49018)
					(mid 126.530354 -401.49018)
					(end 127.289814 -401.49018)
				)
			)
		)
	)
	(zone
		(layer "B.Cu")
		(hatch none 0.5)
		(connect_pads
			(clearance 0)
		)
		(min_thickness 0.25)
		(keepout
			(tracks not_allowed)
			(vias allowed)
			(pads allowed)
			(copperpour not_allowed)
			(footprints allowed)
		)
		(placement
			(enabled no)
			(sheetname "")
		)
		(fill
			(thermal_gap 0.5)
			(thermal_bridge_width 0.5)
			(island_removal_mode 0)
		)
		(polygon
			(pts
				(arc
					(start 384.669792 -370.489988)
					(mid 383.910332 -370.489988)
					(end 384.669792 -370.489988)
				)
			)
		)
	)
	(zone
		(layer "B.Cu")
		(hatch none 0.5)
		(connect_pads
			(clearance 0)
		)
		(min_thickness 0.25)
		(keepout
			(tracks not_allowed)
			(vias allowed)
			(pads allowed)
			(copperpour not_allowed)
			(footprints allowed)
		)
		(placement
			(enabled no)
			(sheetname "")
		)
		(fill
			(thermal_gap 0.5)
			(thermal_bridge_width 0.5)
			(island_removal_mode 0)
		)
		(polygon
			(pts
				(arc
					(start 252.819916 -15.649956)
					(mid 250.81992 -13.64996)
					(end 248.819924 -15.649956)
				)
				(arc
					(start 248.819924 -15.649956)
					(mid 250.81992 -17.649952)
					(end 252.819916 -15.649956)
				)
			)
		)
	)
	(zone
		(layer "B.Cu")
		(hatch none 0.5)
		(connect_pads
			(clearance 0)
		)
		(min_thickness 0.25)
		(keepout
			(tracks not_allowed)
			(vias allowed)
			(pads allowed)
			(copperpour not_allowed)
			(footprints allowed)
		)
		(placement
			(enabled no)
			(sheetname "")
		)
		(fill
			(thermal_gap 0.5)
			(thermal_bridge_width 0.5)
			(island_removal_mode 0)
		)
		(polygon
			(pts
				(arc
					(start 187.476384 -317.749936)
					(mid 186.823604 -317.749936)
					(end 187.476384 -317.749936)
				)
			)
		)
	)
	(zone
		(layer "B.Cu")
		(hatch none 0.5)
		(connect_pads
			(clearance 0)
		)
		(min_thickness 0.25)
		(keepout
			(tracks allowed)
			(vias allowed)
			(pads allowed)
			(copperpour allowed)
			(footprints allowed)
		)
		(placement
			(enabled no)
			(sheetname "")
		)
		(fill
			(thermal_gap 0.5)
			(thermal_bridge_width 0.5)
			(island_removal_mode 0)
		)
		(polygon
			(pts
				(xy 253.655322 -230.80726) (xy 254.277622 -230.80726) (xy 254.359918 -230.724964) (xy 254.359918 -229.090728)
				(xy 254.284734 -229.015544) (xy 253.63297 -229.015544) (xy 253.535434 -229.11308) (xy 253.535434 -230.687372)
			)
		)
	)
	(zone
		(layer "B.Cu")
		(hatch none 0.5)
		(connect_pads
			(clearance 0)
		)
		(min_thickness 0.25)
		(keepout
			(tracks allowed)
			(vias allowed)
			(pads allowed)
			(copperpour allowed)
			(footprints allowed)
		)
		(placement
			(enabled no)
			(sheetname "")
		)
		(fill
			(thermal_gap 0.5)
			(thermal_bridge_width 0.5)
			(island_removal_mode 0)
		)
		(polygon
			(pts
				(xy 54.695598 -363.82833) (xy 54.695598 -361.936284) (xy 56.005476 -361.936284) (xy 56.005476 -363.82833)
			)
		)
	)
	(zone
		(layer "B.Cu")
		(hatch none 0.5)
		(connect_pads
			(clearance 0)
		)
		(min_thickness 0.25)
		(keepout
			(tracks not_allowed)
			(vias allowed)
			(pads allowed)
			(copperpour not_allowed)
			(footprints allowed)
		)
		(placement
			(enabled no)
			(sheetname "")
		)
		(fill
			(thermal_gap 0.5)
			(thermal_bridge_width 0.5)
			(island_removal_mode 0)
		)
		(polygon
			(pts
				(arc
					(start 314.976256 -310.149748)
					(mid 314.323476 -310.149748)
					(end 314.976256 -310.149748)
				)
			)
		)
	)
	(zone
		(layer "B.Cu")
		(hatch none 0.5)
		(connect_pads
			(clearance 0)
		)
		(min_thickness 0.25)
		(keepout
			(tracks not_allowed)
			(vias allowed)
			(pads allowed)
			(copperpour not_allowed)
			(footprints allowed)
		)
		(placement
			(enabled no)
			(sheetname "")
		)
		(fill
			(thermal_gap 0.5)
			(thermal_bridge_width 0.5)
			(island_removal_mode 0)
		)
		(polygon
			(pts
				(arc
					(start 294.469566 -405.390096)
					(mid 293.710106 -405.390096)
					(end 294.469566 -405.390096)
				)
			)
		)
	)
	(zone
		(layer "B.Cu")
		(hatch none 0.5)
		(connect_pads
			(clearance 0)
		)
		(min_thickness 0.25)
		(keepout
			(tracks not_allowed)
			(vias allowed)
			(pads allowed)
			(copperpour not_allowed)
			(footprints allowed)
		)
		(placement
			(enabled no)
			(sheetname "")
		)
		(fill
			(thermal_gap 0.5)
			(thermal_bridge_width 0.5)
			(island_removal_mode 0)
		)
		(polygon
			(pts
				(arc
					(start 46.619922 -15.649956)
					(mid 44.619926 -13.64996)
					(end 42.61993 -15.649956)
				)
				(arc
					(start 42.61993 -15.649956)
					(mid 44.619926 -17.649952)
					(end 46.619922 -15.649956)
				)
			)
		)
	)
	(zone
		(layer "B.Cu")
		(hatch none 0.5)
		(connect_pads
			(clearance 0)
		)
		(min_thickness 0.25)
		(keepout
			(tracks allowed)
			(vias allowed)
			(pads allowed)
			(copperpour allowed)
			(footprints allowed)
		)
		(placement
			(enabled no)
			(sheetname "")
		)
		(fill
			(thermal_gap 0.5)
			(thermal_bridge_width 0.5)
			(island_removal_mode 0)
		)
		(polygon
			(pts
				(xy 226.99726 -267.970762) (xy 226.99726 -265.811762) (xy 228.77526 -265.811762) (xy 228.77526 -267.970762)
			)
		)
	)
	(zone
		(layer "B.Cu")
		(hatch none 0.5)
		(connect_pads
			(clearance 0)
		)
		(min_thickness 0.25)
		(keepout
			(tracks allowed)
			(vias allowed)
			(pads allowed)
			(copperpour allowed)
			(footprints not_allowed)
		)
		(placement
			(enabled no)
			(sheetname "")
		)
		(fill
			(thermal_gap 0.5)
			(thermal_bridge_width 0.5)
			(island_removal_mode 0)
		)
		(polygon
			(pts
				(xy 185.749946 -170.070018) (xy 165.749986 -170.070018) (xy 165.749986 -190.069978) (xy 185.749946 -190.069978)
			)
		)
	)
	(zone
		(layer "B.Cu")
		(hatch none 0.5)
		(connect_pads
			(clearance 0)
		)
		(min_thickness 0.25)
		(keepout
			(tracks not_allowed)
			(vias allowed)
			(pads allowed)
			(copperpour not_allowed)
			(footprints allowed)
		)
		(placement
			(enabled no)
			(sheetname "")
		)
		(fill
			(thermal_gap 0.5)
			(thermal_bridge_width 0.5)
			(island_removal_mode 0)
		)
		(polygon
			(pts
				(arc
					(start 34.889694 -405.390096)
					(mid 34.130234 -405.390096)
					(end 34.889694 -405.390096)
				)
			)
		)
	)
	(zone
		(layer "B.Cu")
		(hatch none 0.5)
		(connect_pads
			(clearance 0)
		)
		(min_thickness 0.25)
		(keepout
			(tracks not_allowed)
			(vias allowed)
			(pads allowed)
			(copperpour not_allowed)
			(footprints allowed)
		)
		(placement
			(enabled no)
			(sheetname "")
		)
		(fill
			(thermal_gap 0.5)
			(thermal_bridge_width 0.5)
			(island_removal_mode 0)
		)
		(polygon
			(pts
				(arc
					(start 82.776314 -304.449734)
					(mid 82.123534 -304.449734)
					(end 82.776314 -304.449734)
				)
			)
		)
	)
	(zone
		(layer "B.Cu")
		(hatch none 0.5)
		(connect_pads
			(clearance 0)
		)
		(min_thickness 0.25)
		(keepout
			(tracks allowed)
			(vias allowed)
			(pads allowed)
			(copperpour allowed)
			(footprints not_allowed)
		)
		(placement
			(enabled no)
			(sheetname "")
		)
		(fill
			(thermal_gap 0.5)
			(thermal_bridge_width 0.5)
			(island_removal_mode 0)
		)
		(polygon
			(pts
				(xy 254.62992 -137.379964) (xy 274.62988 -137.379964) (xy 274.62988 -117.380004) (xy 254.62992 -117.380004)
			)
		)
	)
	(zone
		(layer "B.Cu")
		(hatch none 0.5)
		(connect_pads
			(clearance 0)
		)
		(min_thickness 0.25)
		(keepout
			(tracks not_allowed)
			(vias allowed)
			(pads allowed)
			(copperpour not_allowed)
			(footprints allowed)
		)
		(placement
			(enabled no)
			(sheetname "")
		)
		(fill
			(thermal_gap 0.5)
			(thermal_bridge_width 0.5)
			(island_removal_mode 0)
		)
		(polygon
			(pts
				(arc
					(start 115.01501 -17.999964)
					(mid 110.01502 -12.999974)
					(end 105.01503 -17.999964)
				)
				(arc
					(start 105.01503 -17.999964)
					(mid 110.01502 -22.999954)
					(end 115.01501 -17.999964)
				)
			)
		)
	)
	(zone
		(layer "B.Cu")
		(hatch none 0.5)
		(connect_pads
			(clearance 0)
		)
		(min_thickness 0.25)
		(keepout
			(tracks allowed)
			(vias allowed)
			(pads allowed)
			(copperpour allowed)
			(footprints not_allowed)
		)
		(placement
			(enabled no)
			(sheetname "")
		)
		(fill
			(thermal_gap 0.5)
			(thermal_bridge_width 0.5)
			(island_removal_mode 0)
		)
		(polygon
			(pts
				(arc
					(start 311.799986 -407.960068)
					(mid 319.79997 -415.960052)
					(end 327.799954 -407.960068)
				)
				(arc
					(start 327.799954 -407.960068)
					(mid 319.79997 -399.960084)
					(end 311.799986 -407.960068)
				)
			)
		)
	)
	(zone
		(layer "B.Cu")
		(hatch none 0.5)
		(connect_pads
			(clearance 0)
		)
		(min_thickness 0.25)
		(keepout
			(tracks not_allowed)
			(vias allowed)
			(pads allowed)
			(copperpour not_allowed)
			(footprints allowed)
		)
		(placement
			(enabled no)
			(sheetname "")
		)
		(fill
			(thermal_gap 0.5)
			(thermal_bridge_width 0.5)
			(island_removal_mode 0)
		)
		(polygon
			(pts
				(arc
					(start 12.999974 -194.360038)
					(mid 15.80007 -197.160134)
					(end 18.599912 -194.360038)
				)
				(arc
					(start 18.599912 -194.360038)
					(mid 15.80007 -191.560196)
					(end 12.999974 -194.360038)
				)
			)
		)
	)
	(zone
		(layer "B.Cu")
		(hatch none 0.5)
		(connect_pads
			(clearance 0)
		)
		(min_thickness 0.25)
		(keepout
			(tracks not_allowed)
			(vias allowed)
			(pads allowed)
			(copperpour not_allowed)
			(footprints allowed)
		)
		(placement
			(enabled no)
			(sheetname "")
		)
		(fill
			(thermal_gap 0.5)
			(thermal_bridge_width 0.5)
			(island_removal_mode 0)
		)
		(polygon
			(pts
				(arc
					(start 314.026296 -316.799722)
					(mid 313.373516 -316.799722)
					(end 314.026296 -316.799722)
				)
			)
		)
	)
	(zone
		(layer "B.Cu")
		(hatch none 0.5)
		(connect_pads
			(clearance 0)
		)
		(min_thickness 0.25)
		(keepout
			(tracks not_allowed)
			(vias allowed)
			(pads allowed)
			(copperpour not_allowed)
			(footprints allowed)
		)
		(placement
			(enabled no)
			(sheetname "")
		)
		(fill
			(thermal_gap 0.5)
			(thermal_bridge_width 0.5)
			(island_removal_mode 0)
		)
		(polygon
			(pts
				(arc
					(start 48.08982 -372.890034)
					(mid 47.33036 -372.890034)
					(end 48.08982 -372.890034)
				)
			)
		)
	)
	(zone
		(layer "B.Cu")
		(hatch none 0.5)
		(connect_pads
			(clearance 0)
		)
		(min_thickness 0.25)
		(keepout
			(tracks not_allowed)
			(vias allowed)
			(pads allowed)
			(copperpour not_allowed)
			(footprints allowed)
		)
		(placement
			(enabled no)
			(sheetname "")
		)
		(fill
			(thermal_gap 0.5)
			(thermal_bridge_width 0.5)
			(island_removal_mode 0)
		)
		(polygon
			(pts
				(arc
					(start 421.576246 -318.699896)
					(mid 420.923466 -318.699896)
					(end 421.576246 -318.699896)
				)
			)
		)
	)
	(zone
		(layer "B.Cu")
		(hatch none 0.5)
		(connect_pads
			(clearance 0)
		)
		(min_thickness 0.25)
		(keepout
			(tracks allowed)
			(vias allowed)
			(pads allowed)
			(copperpour allowed)
			(footprints not_allowed)
		)
		(placement
			(enabled no)
			(sheetname "")
		)
		(fill
			(thermal_gap 0.5)
			(thermal_bridge_width 0.5)
			(island_removal_mode 0)
		)
		(polygon
			(pts
				(arc
					(start 219.758006 -347.400118)
					(mid 215.758014 -343.400126)
					(end 211.758022 -347.400118)
				)
				(arc
					(start 211.758022 -347.400118)
					(mid 215.758014 -351.40011)
					(end 219.758006 -347.400118)
				)
			)
		)
	)
	(zone
		(layer "B.Cu")
		(hatch none 0.5)
		(connect_pads
			(clearance 0)
		)
		(min_thickness 0.25)
		(keepout
			(tracks not_allowed)
			(vias allowed)
			(pads allowed)
			(copperpour not_allowed)
			(footprints allowed)
		)
		(placement
			(enabled no)
			(sheetname "")
		)
		(fill
			(thermal_gap 0.5)
			(thermal_bridge_width 0.5)
			(island_removal_mode 0)
		)
		(polygon
			(pts
				(arc
					(start 28.289758 -405.589994)
					(mid 27.530298 -405.589994)
					(end 28.289758 -405.589994)
				)
			)
		)
	)
	(zone
		(layer "B.Cu")
		(hatch none 0.5)
		(connect_pads
			(clearance 0)
		)
		(min_thickness 0.25)
		(keepout
			(tracks not_allowed)
			(vias allowed)
			(pads allowed)
			(copperpour not_allowed)
			(footprints allowed)
		)
		(placement
			(enabled no)
			(sheetname "")
		)
		(fill
			(thermal_gap 0.5)
			(thermal_bridge_width 0.5)
			(island_removal_mode 0)
		)
		(polygon
			(pts
				(arc
					(start 28.289758 -404.290022)
					(mid 27.530298 -404.290022)
					(end 28.289758 -404.290022)
				)
			)
		)
	)
	(zone
		(layer "B.Cu")
		(hatch none 0.5)
		(connect_pads
			(clearance 0)
		)
		(min_thickness 0.25)
		(keepout
			(tracks allowed)
			(vias allowed)
			(pads allowed)
			(copperpour allowed)
			(footprints not_allowed)
		)
		(placement
			(enabled no)
			(sheetname "")
		)
		(fill
			(thermal_gap 0.5)
			(thermal_bridge_width 0.5)
			(island_removal_mode 0)
		)
		(polygon
			(pts
				(arc
					(start 337.214972 -17.999964)
					(mid 342.214962 -22.999954)
					(end 347.214952 -17.999964)
				)
				(arc
					(start 347.214952 -17.999964)
					(mid 342.214962 -12.999974)
					(end 337.214972 -17.999964)
				)
			)
		)
	)
	(zone
		(layer "B.Cu")
		(hatch none 0.5)
		(connect_pads
			(clearance 0)
		)
		(min_thickness 0.25)
		(keepout
			(tracks allowed)
			(vias allowed)
			(pads allowed)
			(copperpour allowed)
			(footprints not_allowed)
		)
		(placement
			(enabled no)
			(sheetname "")
		)
		(fill
			(thermal_gap 0.5)
			(thermal_bridge_width 0.5)
			(island_removal_mode 0)
		)
		(polygon
			(pts
				(arc
					(start 367.450116 -326.900032)
					(mid 368.768096 -330.081916)
					(end 371.94998 -331.399896)
				)
				(arc
					(start 443.95009 -331.399896)
					(mid 447.131974 -330.081916)
					(end 448.449954 -326.900032)
				)
				(arc
					(start 448.449954 -264.899902)
					(mid 447.131974 -261.718018)
					(end 443.95009 -260.400038)
				)
				(arc
					(start 371.94998 -260.400038)
					(mid 368.768096 -261.718018)
					(end 367.450116 -264.899902)
				)
			)
		)
	)
	(zone
		(layer "B.Cu")
		(hatch none 0.5)
		(connect_pads
			(clearance 0)
		)
		(min_thickness 0.25)
		(keepout
			(tracks not_allowed)
			(vias allowed)
			(pads allowed)
			(copperpour not_allowed)
			(footprints allowed)
		)
		(placement
			(enabled no)
			(sheetname "")
		)
		(fill
			(thermal_gap 0.5)
			(thermal_bridge_width 0.5)
			(island_removal_mode 0)
		)
		(polygon
			(pts
				(arc
					(start 99.009962 -407.599896)
					(mid 104.009952 -412.599886)
					(end 109.009942 -407.599896)
				)
				(arc
					(start 109.009942 -407.599896)
					(mid 104.009952 -402.599906)
					(end 99.009962 -407.599896)
				)
			)
		)
	)
	(zone
		(layer "B.Cu")
		(hatch none 0.5)
		(connect_pads
			(clearance 0)
		)
		(min_thickness 0.25)
		(keepout
			(tracks allowed)
			(vias allowed)
			(pads allowed)
			(copperpour allowed)
			(footprints not_allowed)
		)
		(placement
			(enabled no)
			(sheetname "")
		)
		(fill
			(thermal_gap 0.5)
			(thermal_bridge_width 0.5)
			(island_removal_mode 0)
		)
		(polygon
			(pts
				(arc
					(start 105.01503 -17.999964)
					(mid 110.01502 -22.999954)
					(end 115.01501 -17.999964)
				)
				(arc
					(start 115.01501 -17.999964)
					(mid 110.01502 -12.999974)
					(end 105.01503 -17.999964)
				)
			)
		)
	)
	(zone
		(layer "B.Cu")
		(hatch none 0.5)
		(connect_pads
			(clearance 0)
		)
		(min_thickness 0.25)
		(keepout
			(tracks not_allowed)
			(vias allowed)
			(pads allowed)
			(copperpour not_allowed)
			(footprints allowed)
		)
		(placement
			(enabled no)
			(sheetname "")
		)
		(fill
			(thermal_gap 0.5)
			(thermal_bridge_width 0.5)
			(island_removal_mode 0)
		)
		(polygon
			(pts
				(arc
					(start 25.150064 -270.89989)
					(mid 29.650182 -275.400008)
					(end 34.150046 -270.89989)
				)
				(arc
					(start 34.150046 -270.89989)
					(mid 29.650182 -266.400026)
					(end 25.150064 -270.89989)
				)
			)
		)
	)
	(zone
		(layer "B.Cu")
		(hatch none 0.5)
		(connect_pads
			(clearance 0)
		)
		(min_thickness 0.25)
		(keepout
			(tracks not_allowed)
			(vias allowed)
			(pads allowed)
			(copperpour not_allowed)
			(footprints allowed)
		)
		(placement
			(enabled no)
			(sheetname "")
		)
		(fill
			(thermal_gap 0.5)
			(thermal_bridge_width 0.5)
			(island_removal_mode 0)
		)
		(polygon
			(pts
				(arc
					(start 16.89989 -301.410116)
					(mid 20.150074 -304.6603)
					(end 23.400004 -301.410116)
				)
				(arc
					(start 23.400004 -301.410116)
					(mid 20.150074 -298.160186)
					(end 16.89989 -301.410116)
				)
			)
		)
	)
	(zone
		(layer "B.Cu")
		(hatch none 0.5)
		(connect_pads
			(clearance 0)
		)
		(min_thickness 0.25)
		(keepout
			(tracks not_allowed)
			(vias allowed)
			(pads allowed)
			(copperpour not_allowed)
			(footprints allowed)
		)
		(placement
			(enabled no)
			(sheetname "")
		)
		(fill
			(thermal_gap 0.5)
			(thermal_bridge_width 0.5)
			(island_removal_mode 0)
		)
		(polygon
			(pts
				(arc
					(start 397.82623 -315.849762)
					(mid 397.17345 -315.849762)
					(end 397.82623 -315.849762)
				)
			)
		)
	)
	(zone
		(layer "B.Cu")
		(hatch none 0.5)
		(connect_pads
			(clearance 0)
		)
		(min_thickness 0.25)
		(keepout
			(tracks not_allowed)
			(vias allowed)
			(pads allowed)
			(copperpour not_allowed)
			(footprints allowed)
		)
		(placement
			(enabled no)
			(sheetname "")
		)
		(fill
			(thermal_gap 0.5)
			(thermal_bridge_width 0.5)
			(island_removal_mode 0)
		)
		(polygon
			(pts
				(arc
					(start 106.009948 -407.599896)
					(mid 104.009952 -405.5999)
					(end 102.009956 -407.599896)
				)
				(arc
					(start 102.009956 -407.599896)
					(mid 104.009952 -409.599892)
					(end 106.009948 -407.599896)
				)
			)
		)
	)
	(zone
		(layer "B.Cu")
		(hatch none 0.5)
		(connect_pads
			(clearance 0)
		)
		(min_thickness 0.25)
		(keepout
			(tracks not_allowed)
			(vias allowed)
			(pads allowed)
			(copperpour not_allowed)
			(footprints allowed)
		)
		(placement
			(enabled no)
			(sheetname "")
		)
		(fill
			(thermal_gap 0.5)
			(thermal_bridge_width 0.5)
			(island_removal_mode 0)
		)
		(polygon
			(pts
				(arc
					(start 380.26975 -370.489988)
					(mid 379.51029 -370.489988)
					(end 380.26975 -370.489988)
				)
			)
		)
	)
	(zone
		(layer "B.Cu")
		(hatch none 0.5)
		(connect_pads
			(clearance 0)
		)
		(min_thickness 0.25)
		(keepout
			(tracks allowed)
			(vias allowed)
			(pads allowed)
			(copperpour allowed)
			(footprints not_allowed)
		)
		(placement
			(enabled no)
			(sheetname "")
		)
		(fill
			(thermal_gap 0.5)
			(thermal_bridge_width 0.5)
			(island_removal_mode 0)
		)
		(polygon
			(pts
				(arc
					(start 390.91997 -15.649956)
					(mid 392.919966 -17.649952)
					(end 394.919962 -15.649956)
				)
				(arc
					(start 394.919962 -15.649956)
					(mid 392.919966 -13.64996)
					(end 390.91997 -15.649956)
				)
			)
		)
	)
	(zone
		(layer "B.Cu")
		(hatch none 0.5)
		(connect_pads
			(clearance 0)
		)
		(min_thickness 0.25)
		(keepout
			(tracks not_allowed)
			(vias allowed)
			(pads allowed)
			(copperpour not_allowed)
			(footprints allowed)
		)
		(placement
			(enabled no)
			(sheetname "")
		)
		(fill
			(thermal_gap 0.5)
			(thermal_bridge_width 0.5)
			(island_removal_mode 0)
		)
		(polygon
			(pts
				(arc
					(start 81.826354 -304.449734)
					(mid 81.173574 -304.449734)
					(end 81.826354 -304.449734)
				)
			)
		)
	)
	(zone
		(layer "B.Cu")
		(hatch none 0.5)
		(connect_pads
			(clearance 0)
		)
		(min_thickness 0.25)
		(keepout
			(tracks allowed)
			(vias allowed)
			(pads allowed)
			(copperpour allowed)
			(footprints allowed)
		)
		(placement
			(enabled no)
			(sheetname "")
		)
		(fill
			(thermal_gap 0.5)
			(thermal_bridge_width 0.5)
			(island_removal_mode 0)
		)
		(polygon
			(pts
				(arc
					(start 99.164902 -329.358244)
					(mid 99.179781 -329.322323)
					(end 99.215702 -329.307444)
				)
				(arc
					(start 100.244402 -329.307444)
					(mid 100.280323 -329.322323)
					(end 100.295202 -329.358244)
				)
				(arc
					(start 100.295202 -330.674472)
					(mid 100.280323 -330.710393)
					(end 100.244402 -330.725272)
				)
				(arc
					(start 99.215702 -330.725272)
					(mid 99.179781 -330.710393)
					(end 99.164902 -330.674472)
				)
			)
		)
	)
	(zone
		(layer "B.Cu")
		(hatch none 0.5)
		(connect_pads
			(clearance 0)
		)
		(min_thickness 0.25)
		(keepout
			(tracks not_allowed)
			(vias allowed)
			(pads allowed)
			(copperpour not_allowed)
			(footprints allowed)
		)
		(placement
			(enabled no)
			(sheetname "")
		)
		(fill
			(thermal_gap 0.5)
			(thermal_bridge_width 0.5)
			(island_removal_mode 0)
		)
		(polygon
			(pts
				(arc
					(start 239.365028 -84.305648)
					(mid 238.661448 -84.305648)
					(end 239.365028 -84.305648)
				)
			)
		)
	)
	(zone
		(layer "B.Cu")
		(hatch none 0.5)
		(connect_pads
			(clearance 0)
		)
		(min_thickness 0.25)
		(keepout
			(tracks not_allowed)
			(vias allowed)
			(pads allowed)
			(copperpour not_allowed)
			(footprints allowed)
		)
		(placement
			(enabled no)
			(sheetname "")
		)
		(fill
			(thermal_gap 0.5)
			(thermal_bridge_width 0.5)
			(island_removal_mode 0)
		)
		(polygon
			(pts
				(arc
					(start 30.964886 -17.999964)
					(mid 25.964896 -12.999974)
					(end 20.964906 -17.999964)
				)
				(arc
					(start 20.964906 -17.999964)
					(mid 25.964896 -22.999954)
					(end 30.964886 -17.999964)
				)
			)
		)
	)
	(zone
		(layer "B.Cu")
		(hatch none 0.5)
		(connect_pads
			(clearance 0)
		)
		(min_thickness 0.25)
		(keepout
			(tracks not_allowed)
			(vias allowed)
			(pads allowed)
			(copperpour not_allowed)
			(footprints allowed)
		)
		(placement
			(enabled no)
			(sheetname "")
		)
		(fill
			(thermal_gap 0.5)
			(thermal_bridge_width 0.5)
			(island_removal_mode 0)
		)
		(polygon
			(pts
				(arc
					(start 264.100056 -320.900044)
					(mid 261.850124 -318.650112)
					(end 259.599938 -320.900044)
				)
				(arc
					(start 259.599938 -320.900044)
					(mid 261.850124 -323.15023)
					(end 264.100056 -320.900044)
				)
			)
		)
	)
	(zone
		(layer "B.Cu")
		(hatch none 0.5)
		(connect_pads
			(clearance 0)
		)
		(min_thickness 0.25)
		(keepout
			(tracks allowed)
			(vias allowed)
			(pads allowed)
			(copperpour allowed)
			(footprints not_allowed)
		)
		(placement
			(enabled no)
			(sheetname "")
		)
		(fill
			(thermal_gap 0.5)
			(thermal_bridge_width 0.5)
			(island_removal_mode 0)
		)
		(polygon
			(pts
				(arc
					(start 199.419972 -20.72005)
					(mid 201.419968 -22.720046)
					(end 203.419964 -20.72005)
				)
				(arc
					(start 203.419964 -20.72005)
					(mid 201.419968 -18.720054)
					(end 199.419972 -20.72005)
				)
			)
		)
	)
	(zone
		(layer "B.Cu")
		(hatch none 0.5)
		(connect_pads
			(clearance 0)
		)
		(min_thickness 0.25)
		(keepout
			(tracks not_allowed)
			(vias allowed)
			(pads allowed)
			(copperpour not_allowed)
			(footprints allowed)
		)
		(placement
			(enabled no)
			(sheetname "")
		)
		(fill
			(thermal_gap 0.5)
			(thermal_bridge_width 0.5)
			(island_removal_mode 0)
		)
		(polygon
			(pts
				(arc
					(start 231.115108 -5.999988)
					(mid 226.115118 -0.999998)
					(end 221.114874 -5.999988)
				)
				(arc
					(start 221.114874 -5.999988)
					(mid 226.115118 -11.000232)
					(end 231.115108 -5.999988)
				)
			)
		)
	)
	(zone
		(layer "B.Cu")
		(hatch none 0.5)
		(connect_pads
			(clearance 0)
		)
		(min_thickness 0.25)
		(keepout
			(tracks not_allowed)
			(vias allowed)
			(pads allowed)
			(copperpour not_allowed)
			(footprints allowed)
		)
		(placement
			(enabled no)
			(sheetname "")
		)
		(fill
			(thermal_gap 0.5)
			(thermal_bridge_width 0.5)
			(island_removal_mode 0)
		)
		(polygon
			(pts
				(arc
					(start 129.489708 -371.790214)
					(mid 128.730248 -371.790214)
					(end 129.489708 -371.790214)
				)
			)
		)
	)
	(zone
		(layer "B.Cu")
		(hatch none 0.5)
		(connect_pads
			(clearance 0)
		)
		(min_thickness 0.25)
		(keepout
			(tracks not_allowed)
			(vias allowed)
			(pads allowed)
			(copperpour not_allowed)
			(footprints allowed)
		)
		(placement
			(enabled no)
			(sheetname "")
		)
		(fill
			(thermal_gap 0.5)
			(thermal_bridge_width 0.5)
			(island_removal_mode 0)
		)
		(polygon
			(pts
				(arc
					(start 177.420016 -20.72005)
					(mid 175.42002 -18.720054)
					(end 173.420024 -20.72005)
				)
				(arc
					(start 173.420024 -20.72005)
					(mid 175.42002 -22.720046)
					(end 177.420016 -20.72005)
				)
			)
		)
	)
	(zone
		(layer "B.Cu")
		(hatch none 0.5)
		(connect_pads
			(clearance 0)
		)
		(min_thickness 0.25)
		(keepout
			(tracks not_allowed)
			(vias allowed)
			(pads allowed)
			(copperpour not_allowed)
			(footprints allowed)
		)
		(placement
			(enabled no)
			(sheetname "")
		)
		(fill
			(thermal_gap 0.5)
			(thermal_bridge_width 0.5)
			(island_removal_mode 0)
		)
		(polygon
			(pts
				(arc
					(start 375.869708 -370.489988)
					(mid 375.110248 -370.489988)
					(end 375.869708 -370.489988)
				)
			)
		)
	)
	(zone
		(layer "B.Cu")
		(hatch none 0.5)
		(connect_pads
			(clearance 0)
		)
		(min_thickness 0.25)
		(keepout
			(tracks not_allowed)
			(vias allowed)
			(pads allowed)
			(copperpour not_allowed)
			(footprints allowed)
		)
		(placement
			(enabled no)
			(sheetname "")
		)
		(fill
			(thermal_gap 0.5)
			(thermal_bridge_width 0.5)
			(island_removal_mode 0)
		)
		(polygon
			(pts
				(arc
					(start 160.876234 -318.699896)
					(mid 160.223454 -318.699896)
					(end 160.876234 -318.699896)
				)
			)
		)
	)
	(zone
		(layer "B.Cu")
		(hatch none 0.5)
		(connect_pads
			(clearance 0)
		)
		(min_thickness 0.25)
		(keepout
			(tracks allowed)
			(vias allowed)
			(pads allowed)
			(copperpour allowed)
			(footprints not_allowed)
		)
		(placement
			(enabled no)
			(sheetname "")
		)
		(fill
			(thermal_gap 0.5)
			(thermal_bridge_width 0.5)
			(island_removal_mode 0)
		)
		(polygon
			(pts
				(arc
					(start 289.520122 -20.72005)
					(mid 291.520118 -22.720046)
					(end 293.520114 -20.72005)
				)
				(arc
					(start 293.520114 -20.72005)
					(mid 291.520118 -18.720054)
					(end 289.520122 -20.72005)
				)
			)
		)
	)
	(zone
		(layer "B.Cu")
		(hatch none 0.5)
		(connect_pads
			(clearance 0)
		)
		(min_thickness 0.25)
		(keepout
			(tracks not_allowed)
			(vias allowed)
			(pads allowed)
			(copperpour not_allowed)
			(footprints allowed)
		)
		(placement
			(enabled no)
			(sheetname "")
		)
		(fill
			(thermal_gap 0.5)
			(thermal_bridge_width 0.5)
			(island_removal_mode 0)
		)
		(polygon
			(pts
				(arc
					(start 120.689878 -400.390106)
					(mid 119.930418 -400.390106)
					(end 120.689878 -400.390106)
				)
			)
		)
	)
	(zone
		(layer "B.Cu")
		(hatch none 0.5)
		(connect_pads
			(clearance 0)
		)
		(min_thickness 0.25)
		(keepout
			(tracks allowed)
			(vias allowed)
			(pads allowed)
			(copperpour allowed)
			(footprints not_allowed)
		)
		(placement
			(enabled no)
			(sheetname "")
		)
		(fill
			(thermal_gap 0.5)
			(thermal_bridge_width 0.5)
			(island_removal_mode 0)
		)
		(polygon
			(pts
				(arc
					(start 16.150082 -301.410116)
					(mid 20.150074 -305.410108)
					(end 24.150066 -301.410116)
				)
				(arc
					(start 24.150066 -301.410116)
					(mid 20.150074 -297.410124)
					(end 16.150082 -301.410116)
				)
			)
		)
	)
	(zone
		(layer "B.Cu")
		(hatch none 0.5)
		(connect_pads
			(clearance 0)
		)
		(min_thickness 0.25)
		(keepout
			(tracks not_allowed)
			(vias allowed)
			(pads allowed)
			(copperpour not_allowed)
			(footprints allowed)
		)
		(placement
			(enabled no)
			(sheetname "")
		)
		(fill
			(thermal_gap 0.5)
			(thermal_bridge_width 0.5)
			(island_removal_mode 0)
		)
		(polygon
			(pts
				(arc
					(start 82.776314 -308.249828)
					(mid 82.123534 -308.249828)
					(end 82.776314 -308.249828)
				)
			)
		)
	)
	(zone
		(layer "B.Cu")
		(hatch none 0.5)
		(connect_pads
			(clearance 0)
		)
		(min_thickness 0.25)
		(keepout
			(tracks not_allowed)
			(vias allowed)
			(pads allowed)
			(copperpour not_allowed)
			(footprints allowed)
		)
		(placement
			(enabled no)
			(sheetname "")
		)
		(fill
			(thermal_gap 0.5)
			(thermal_bridge_width 0.5)
			(island_removal_mode 0)
		)
		(polygon
			(pts
				(arc
					(start 416.826192 -315.849762)
					(mid 416.173412 -315.849762)
					(end 416.826192 -315.849762)
				)
			)
		)
	)
	(zone
		(layer "B.Cu")
		(hatch none 0.5)
		(connect_pads
			(clearance 0)
		)
		(min_thickness 0.25)
		(keepout
			(tracks allowed)
			(vias allowed)
			(pads allowed)
			(copperpour allowed)
			(footprints allowed)
		)
		(placement
			(enabled no)
			(sheetname "")
		)
		(fill
			(thermal_gap 0.5)
			(thermal_bridge_width 0.5)
			(island_removal_mode 0)
		)
		(polygon
			(pts
				(arc
					(start 369.421664 -228.721158)
					(mid 369.436543 -228.685237)
					(end 369.472464 -228.670358)
				)
				(arc
					(start 370.409978 -228.670358)
					(mid 370.445899 -228.685237)
					(end 370.460778 -228.721158)
				)
				(arc
					(start 370.460778 -230.042466)
					(mid 370.445899 -230.078387)
					(end 370.409978 -230.093266)
				)
				(arc
					(start 369.472464 -230.093266)
					(mid 369.436543 -230.078387)
					(end 369.421664 -230.042466)
				)
			)
		)
	)
	(zone
		(layer "B.Cu")
		(hatch none 0.5)
		(connect_pads
			(clearance 0)
		)
		(min_thickness 0.25)
		(keepout
			(tracks not_allowed)
			(vias allowed)
			(pads allowed)
			(copperpour not_allowed)
			(footprints allowed)
		)
		(placement
			(enabled no)
			(sheetname "")
		)
		(fill
			(thermal_gap 0.5)
			(thermal_bridge_width 0.5)
			(island_removal_mode 0)
		)
		(polygon
			(pts
				(arc
					(start 95.899986 -289.820096)
					(mid 99.15017 -293.07028)
					(end 102.4001 -289.820096)
				)
				(arc
					(start 102.4001 -289.820096)
					(mid 99.15017 -286.570166)
					(end 95.899986 -289.820096)
				)
			)
		)
	)
	(zone
		(layer "B.Cu")
		(hatch none 0.5)
		(connect_pads
			(clearance 0)
		)
		(min_thickness 0.25)
		(keepout
			(tracks not_allowed)
			(vias allowed)
			(pads allowed)
			(copperpour not_allowed)
			(footprints allowed)
		)
		(placement
			(enabled no)
			(sheetname "")
		)
		(fill
			(thermal_gap 0.5)
			(thermal_bridge_width 0.5)
			(island_removal_mode 0)
		)
		(polygon
			(pts
				(arc
					(start 41.48963 -405.589994)
					(mid 40.73017 -405.589994)
					(end 41.48963 -405.589994)
				)
			)
		)
	)
	(zone
		(layer "B.Cu")
		(hatch none 0.5)
		(connect_pads
			(clearance 0)
		)
		(min_thickness 0.25)
		(keepout
			(tracks not_allowed)
			(vias allowed)
			(pads allowed)
			(copperpour not_allowed)
			(footprints allowed)
		)
		(placement
			(enabled no)
			(sheetname "")
		)
		(fill
			(thermal_gap 0.5)
			(thermal_bridge_width 0.5)
			(island_removal_mode 0)
		)
		(polygon
			(pts
				(arc
					(start 464.09991 -398.100042)
					(mid 461.600042 -395.600174)
					(end 459.09992 -398.100042)
				)
				(arc
					(start 459.09992 -398.100042)
					(mid 461.600042 -400.600164)
					(end 464.09991 -398.100042)
				)
			)
		)
	)
	(zone
		(layer "B.Cu")
		(hatch none 0.5)
		(connect_pads
			(clearance 0)
		)
		(min_thickness 0.25)
		(keepout
			(tracks not_allowed)
			(vias allowed)
			(pads allowed)
			(copperpour not_allowed)
			(footprints allowed)
		)
		(placement
			(enabled no)
			(sheetname "")
		)
		(fill
			(thermal_gap 0.5)
			(thermal_bridge_width 0.5)
			(island_removal_mode 0)
		)
		(polygon
			(pts
				(arc
					(start 80.87614 -309.199788)
					(mid 80.22336 -309.199788)
					(end 80.87614 -309.199788)
				)
			)
		)
	)
	(zone
		(layer "B.Cu")
		(hatch none 0.5)
		(connect_pads
			(clearance 0)
		)
		(min_thickness 0.25)
		(keepout
			(tracks not_allowed)
			(vias allowed)
			(pads allowed)
			(copperpour not_allowed)
			(footprints allowed)
		)
		(placement
			(enabled no)
			(sheetname "")
		)
		(fill
			(thermal_gap 0.5)
			(thermal_bridge_width 0.5)
			(island_removal_mode 0)
		)
		(polygon
			(pts
				(arc
					(start 118.48973 -371.590062)
					(mid 117.73027 -371.590062)
					(end 118.48973 -371.590062)
				)
			)
		)
	)
	(zone
		(layer "B.Cu")
		(hatch none 0.5)
		(connect_pads
			(clearance 0)
		)
		(min_thickness 0.25)
		(keepout
			(tracks allowed)
			(vias allowed)
			(pads allowed)
			(copperpour allowed)
			(footprints allowed)
		)
		(placement
			(enabled no)
			(sheetname "")
		)
		(fill
			(thermal_gap 0.5)
			(thermal_bridge_width 0.5)
			(island_removal_mode 0)
		)
		(polygon
			(pts
				(xy 448.601338 -268.094206) (xy 448.601338 -265.935206) (xy 450.379338 -265.935206) (xy 450.379338 -268.094206)
			)
		)
	)
	(zone
		(layer "B.Cu")
		(hatch none 0.5)
		(connect_pads
			(clearance 0)
		)
		(min_thickness 0.25)
		(keepout
			(tracks allowed)
			(vias allowed)
			(pads allowed)
			(copperpour allowed)
			(footprints allowed)
		)
		(placement
			(enabled no)
			(sheetname "")
		)
		(fill
			(thermal_gap 0.5)
			(thermal_bridge_width 0.5)
			(island_removal_mode 0)
		)
		(polygon
			(pts
				(xy 338.508848 -320.320924) (xy 338.508848 -321.971924) (xy 336.349848 -321.971924) (xy 336.349848 -320.320924)
			)
		)
	)
	(zone
		(layer "B.Cu")
		(hatch none 0.5)
		(connect_pads
			(clearance 0)
		)
		(min_thickness 0.25)
		(keepout
			(tracks allowed)
			(vias allowed)
			(pads allowed)
			(copperpour allowed)
			(footprints not_allowed)
		)
		(placement
			(enabled no)
			(sheetname "")
		)
		(fill
			(thermal_gap 0.5)
			(thermal_bridge_width 0.5)
			(island_removal_mode 0)
		)
		(polygon
			(pts
				(arc
					(start 200.300082 -98.700082)
					(mid 208.300066 -106.700066)
					(end 216.30005 -98.700082)
				)
				(arc
					(start 216.30005 -98.700082)
					(mid 208.300066 -90.700098)
					(end 200.300082 -98.700082)
				)
			)
		)
	)
	(zone
		(layer "B.Cu")
		(hatch none 0.5)
		(connect_pads
			(clearance 0)
		)
		(min_thickness 0.25)
		(keepout
			(tracks not_allowed)
			(vias allowed)
			(pads allowed)
			(copperpour not_allowed)
			(footprints allowed)
		)
		(placement
			(enabled no)
			(sheetname "")
		)
		(fill
			(thermal_gap 0.5)
			(thermal_bridge_width 0.5)
			(island_removal_mode 0)
		)
		(polygon
			(pts
				(arc
					(start 417.776406 -318.699896)
					(mid 417.123626 -318.699896)
					(end 417.776406 -318.699896)
				)
			)
		)
	)
	(zone
		(layer "B.Cu")
		(hatch none 0.5)
		(connect_pads
			(clearance 0)
		)
		(min_thickness 0.25)
		(keepout
			(tracks not_allowed)
			(vias allowed)
			(pads allowed)
			(copperpour not_allowed)
			(footprints allowed)
		)
		(placement
			(enabled no)
			(sheetname "")
		)
		(fill
			(thermal_gap 0.5)
			(thermal_bridge_width 0.5)
			(island_removal_mode 0)
		)
		(polygon
			(pts
				(arc
					(start 37.089842 -405.589994)
					(mid 36.330382 -405.589994)
					(end 37.089842 -405.589994)
				)
			)
		)
	)
	(zone
		(layer "B.Cu")
		(hatch none 0.5)
		(connect_pads
			(clearance 0)
		)
		(min_thickness 0.25)
		(keepout
			(tracks allowed)
			(vias allowed)
			(pads allowed)
			(copperpour allowed)
			(footprints not_allowed)
		)
		(placement
			(enabled no)
			(sheetname "")
		)
		(fill
			(thermal_gap 0.5)
			(thermal_bridge_width 0.5)
			(island_removal_mode 0)
		)
		(polygon
			(pts
				(arc
					(start 456.79995 -72.69988)
					(mid 448.799966 -64.699896)
					(end 440.799982 -72.69988)
				)
				(arc
					(start 440.799982 -84.70011)
					(mid 448.799966 -92.700094)
					(end 456.79995 -84.70011)
				)
			)
		)
	)
	(zone
		(layer "B.Cu")
		(hatch none 0.5)
		(connect_pads
			(clearance 0)
		)
		(min_thickness 0.25)
		(keepout
			(tracks allowed)
			(vias allowed)
			(pads allowed)
			(copperpour allowed)
			(footprints allowed)
		)
		(placement
			(enabled no)
			(sheetname "")
		)
		(fill
			(thermal_gap 0.5)
			(thermal_bridge_width 0.5)
			(island_removal_mode 0)
		)
		(polygon
			(pts
				(xy 333.756 -222.9612) (xy 336.1436 -222.9612) (xy 336.3468 -223.1644) (xy 336.3468 -224.5106) (xy 335.9404 -224.5106)
				(xy 335.5594 -224.1296) (xy 333.883 -224.1296) (xy 333.756 -224.0026)
			)
		)
	)
	(zone
		(layer "B.Cu")
		(hatch none 0.5)
		(connect_pads
			(clearance 0)
		)
		(min_thickness 0.25)
		(keepout
			(tracks not_allowed)
			(vias allowed)
			(pads allowed)
			(copperpour not_allowed)
			(footprints allowed)
		)
		(placement
			(enabled no)
			(sheetname "")
		)
		(fill
			(thermal_gap 0.5)
			(thermal_bridge_width 0.5)
			(island_removal_mode 0)
		)
		(polygon
			(pts
				(arc
					(start 129.489708 -401.690078)
					(mid 128.730248 -401.690078)
					(end 129.489708 -401.690078)
				)
			)
		)
	)
	(zone
		(layer "B.Cu")
		(hatch none 0.5)
		(connect_pads
			(clearance 0)
		)
		(min_thickness 0.25)
		(keepout
			(tracks allowed)
			(vias allowed)
			(pads allowed)
			(copperpour allowed)
			(footprints not_allowed)
		)
		(placement
			(enabled no)
			(sheetname "")
		)
		(fill
			(thermal_gap 0.5)
			(thermal_bridge_width 0.5)
			(island_removal_mode 0)
		)
		(polygon
			(pts
				(arc
					(start 132.249926 -276.010116)
					(mid 136.249918 -280.010108)
					(end 140.24991 -276.010116)
				)
				(arc
					(start 140.24991 -276.010116)
					(mid 136.249918 -272.010124)
					(end 132.249926 -276.010116)
				)
			)
		)
	)
	(zone
		(layer "B.Cu")
		(hatch none 0.5)
		(connect_pads
			(clearance 0)
		)
		(min_thickness 0.25)
		(keepout
			(tracks allowed)
			(vias allowed)
			(pads allowed)
			(copperpour allowed)
			(footprints not_allowed)
		)
		(placement
			(enabled no)
			(sheetname "")
		)
		(fill
			(thermal_gap 0.5)
			(thermal_bridge_width 0.5)
			(island_removal_mode 0)
		)
		(polygon
			(pts
				(arc
					(start 251.29998 -98.700082)
					(mid 259.299964 -106.700066)
					(end 267.299948 -98.700082)
				)
				(arc
					(start 267.299948 -98.700082)
					(mid 259.299964 -90.700098)
					(end 251.29998 -98.700082)
				)
			)
		)
	)
	(zone
		(layer "B.Cu")
		(hatch none 0.5)
		(connect_pads
			(clearance 0)
		)
		(min_thickness 0.25)
		(keepout
			(tracks allowed)
			(vias allowed)
			(pads allowed)
			(copperpour allowed)
			(footprints allowed)
		)
		(placement
			(enabled no)
			(sheetname "")
		)
		(fill
			(thermal_gap 0.5)
			(thermal_bridge_width 0.5)
			(island_removal_mode 0)
		)
		(polygon
			(pts
				(xy 102.27564 -349.686118) (xy 105.35285 -349.686118) (xy 105.51033 -349.528638) (xy 105.51033 -346.870782)
				(xy 105.422954 -346.783406) (xy 102.302056 -346.783406) (xy 102.23627 -346.849192) (xy 102.23627 -349.646748)
			)
		)
	)
	(zone
		(layer "B.Cu")
		(hatch none 0.5)
		(connect_pads
			(clearance 0)
		)
		(min_thickness 0.25)
		(keepout
			(tracks not_allowed)
			(vias allowed)
			(pads allowed)
			(copperpour not_allowed)
			(footprints allowed)
		)
		(placement
			(enabled no)
			(sheetname "")
		)
		(fill
			(thermal_gap 0.5)
			(thermal_bridge_width 0.5)
			(island_removal_mode 0)
		)
		(polygon
			(pts
				(arc
					(start 120.689878 -370.489988)
					(mid 119.930418 -370.489988)
					(end 120.689878 -370.489988)
				)
			)
		)
	)
	(zone
		(layer "B.Cu")
		(hatch none 0.5)
		(connect_pads
			(clearance 0)
		)
		(min_thickness 0.25)
		(keepout
			(tracks not_allowed)
			(vias allowed)
			(pads allowed)
			(copperpour not_allowed)
			(footprints allowed)
		)
		(placement
			(enabled no)
			(sheetname "")
		)
		(fill
			(thermal_gap 0.5)
			(thermal_bridge_width 0.5)
			(island_removal_mode 0)
		)
		(polygon
			(pts
				(arc
					(start 233.493818 -82.503264)
					(mid 232.790238 -82.503264)
					(end 233.493818 -82.503264)
				)
			)
		)
	)
	(zone
		(layer "B.Cu")
		(hatch none 0.5)
		(connect_pads
			(clearance 0)
		)
		(min_thickness 0.25)
		(keepout
			(tracks allowed)
			(vias allowed)
			(pads allowed)
			(copperpour allowed)
			(footprints allowed)
		)
		(placement
			(enabled no)
			(sheetname "")
		)
		(fill
			(thermal_gap 0.5)
			(thermal_bridge_width 0.5)
			(island_removal_mode 0)
		)
		(polygon
			(pts
				(xy 223.7486 -216.9668) (xy 223.7486 -214.503) (xy 224.8408 -213.4108) (xy 225.3742 -213.4108) (xy 225.806 -213.8426)
				(xy 225.806 -214.376) (xy 226.0092 -214.5792) (xy 226.0092 -214.8078) (xy 226.2124 -215.011) (xy 227.0252 -215.011)
				(xy 227.3046 -215.2904) (xy 227.3046 -216.3572) (xy 226.695 -216.9668)
			)
		)
	)
	(zone
		(layer "B.Cu")
		(hatch none 0.5)
		(connect_pads
			(clearance 0)
		)
		(min_thickness 0.25)
		(keepout
			(tracks not_allowed)
			(vias allowed)
			(pads allowed)
			(copperpour not_allowed)
			(footprints allowed)
		)
		(placement
			(enabled no)
			(sheetname "")
		)
		(fill
			(thermal_gap 0.5)
			(thermal_bridge_width 0.5)
			(island_removal_mode 0)
		)
		(polygon
			(pts
				(arc
					(start 389.06958 -401.690078)
					(mid 388.31012 -401.690078)
					(end 389.06958 -401.690078)
				)
			)
		)
	)
	(zone
		(layer "B.Cu")
		(hatch none 0.5)
		(connect_pads
			(clearance 0)
		)
		(min_thickness 0.25)
		(keepout
			(tracks allowed)
			(vias allowed)
			(pads allowed)
			(copperpour allowed)
			(footprints allowed)
		)
		(placement
			(enabled no)
			(sheetname "")
		)
		(fill
			(thermal_gap 0.5)
			(thermal_bridge_width 0.5)
			(island_removal_mode 0)
		)
		(polygon
			(pts
				(xy 340.0552 -213.3092) (xy 339.725 -213.3092) (xy 339.09 -212.6742) (xy 339.09 -210.3628) (xy 339.344 -210.1088)
				(xy 339.8012 -210.1088) (xy 339.852 -210.1596) (xy 339.852 -212.6488) (xy 340.1822 -212.979) (xy 340.1822 -213.1822)
			)
		)
	)
	(zone
		(layer "B.Cu")
		(hatch none 0.5)
		(connect_pads
			(clearance 0)
		)
		(min_thickness 0.25)
		(keepout
			(tracks allowed)
			(vias allowed)
			(pads allowed)
			(copperpour allowed)
			(footprints allowed)
		)
		(placement
			(enabled no)
			(sheetname "")
		)
		(fill
			(thermal_gap 0.5)
			(thermal_bridge_width 0.5)
			(island_removal_mode 0)
		)
		(polygon
			(pts
				(xy 237.491524 -80.703674) (xy 237.491524 -78.8797) (xy 239.024414 -78.8797) (xy 239.024414 -80.703674)
			)
		)
	)
	(zone
		(layer "B.Cu")
		(hatch none 0.5)
		(connect_pads
			(clearance 0)
		)
		(min_thickness 0.25)
		(keepout
			(tracks not_allowed)
			(vias allowed)
			(pads allowed)
			(copperpour not_allowed)
			(footprints allowed)
		)
		(placement
			(enabled no)
			(sheetname "")
		)
		(fill
			(thermal_gap 0.5)
			(thermal_bridge_width 0.5)
			(island_removal_mode 0)
		)
		(polygon
			(pts
				(arc
					(start 312.126122 -315.849762)
					(mid 311.473342 -315.849762)
					(end 312.126122 -315.849762)
				)
			)
		)
	)
	(zone
		(layer "B.Cu")
		(hatch none 0.5)
		(connect_pads
			(clearance 0)
		)
		(min_thickness 0.25)
		(keepout
			(tracks not_allowed)
			(vias allowed)
			(pads allowed)
			(copperpour not_allowed)
			(footprints allowed)
		)
		(placement
			(enabled no)
			(sheetname "")
		)
		(fill
			(thermal_gap 0.5)
			(thermal_bridge_width 0.5)
			(island_removal_mode 0)
		)
		(polygon
			(pts
				(arc
					(start 79.92618 -316.799722)
					(mid 79.2734 -316.799722)
					(end 79.92618 -316.799722)
				)
			)
		)
	)
	(zone
		(layer "B.Cu")
		(hatch none 0.5)
		(connect_pads
			(clearance 0)
		)
		(min_thickness 0.25)
		(keepout
			(tracks allowed)
			(vias allowed)
			(pads allowed)
			(copperpour allowed)
			(footprints allowed)
		)
		(placement
			(enabled no)
			(sheetname "")
		)
		(fill
			(thermal_gap 0.5)
			(thermal_bridge_width 0.5)
			(island_removal_mode 0)
		)
		(polygon
			(pts
				(xy 108.598716 -353.036378) (xy 108.598716 -351.51441) (xy 110.493302 -351.51441) (xy 110.493302 -353.036378)
			)
		)
	)
	(zone
		(layer "B.Cu")
		(hatch none 0.5)
		(connect_pads
			(clearance 0)
		)
		(min_thickness 0.25)
		(keepout
			(tracks not_allowed)
			(vias allowed)
			(pads allowed)
			(copperpour not_allowed)
			(footprints allowed)
		)
		(placement
			(enabled no)
			(sheetname "")
		)
		(fill
			(thermal_gap 0.5)
			(thermal_bridge_width 0.5)
			(island_removal_mode 0)
		)
		(polygon
			(pts
				(arc
					(start 405.264874 -5.999988)
					(mid 400.264884 -0.999998)
					(end 395.264894 -5.999988)
				)
				(arc
					(start 395.264894 -5.999988)
					(mid 400.264884 -10.999978)
					(end 405.264874 -5.999988)
				)
			)
		)
	)
	(zone
		(layer "B.Cu")
		(hatch none 0.5)
		(connect_pads
			(clearance 0)
		)
		(min_thickness 0.25)
		(keepout
			(tracks not_allowed)
			(vias allowed)
			(pads allowed)
			(copperpour not_allowed)
			(footprints allowed)
		)
		(placement
			(enabled no)
			(sheetname "")
		)
		(fill
			(thermal_gap 0.5)
			(thermal_bridge_width 0.5)
			(island_removal_mode 0)
		)
		(polygon
			(pts
				(arc
					(start 28.289758 -378.290074)
					(mid 27.530298 -378.290074)
					(end 28.289758 -378.290074)
				)
			)
		)
	)
	(zone
		(layer "B.Cu")
		(hatch none 0.5)
		(connect_pads
			(clearance 0)
		)
		(min_thickness 0.25)
		(keepout
			(tracks allowed)
			(vias allowed)
			(pads allowed)
			(copperpour allowed)
			(footprints not_allowed)
		)
		(placement
			(enabled no)
			(sheetname "")
		)
		(fill
			(thermal_gap 0.5)
			(thermal_bridge_width 0.5)
			(island_removal_mode 0)
		)
		(polygon
			(pts
				(arc
					(start 1.100074 -399.09496)
					(mid 2.263379 -401.422384)
					(end 4.43865 -402.850096)
				)
				(arc
					(start 4.43865 -402.850096)
					(mid 2.263472 -404.277724)
					(end 1.100074 -406.604978)
				)
				(xy 0.999998 -406.604978) (xy 0.999998 -399.09496)
			)
		)
	)
	(zone
		(layer "B.Cu")
		(hatch none 0.5)
		(connect_pads
			(clearance 0)
		)
		(min_thickness 0.25)
		(keepout
			(tracks allowed)
			(vias allowed)
			(pads allowed)
			(copperpour allowed)
			(footprints allowed)
		)
		(placement
			(enabled no)
			(sheetname "")
		)
		(fill
			(thermal_gap 0.5)
			(thermal_bridge_width 0.5)
			(island_removal_mode 0)
		)
		(polygon
			(pts
				(xy 346.2782 -214.1474) (xy 346.2782 -213.8934) (xy 346.7862 -213.3854) (xy 346.7862 -210.7946)
				(xy 347.0402 -210.5406) (xy 348.5896 -210.5406) (xy 348.7674 -210.7184) (xy 348.7674 -212.852) (xy 348.996 -213.0806)
				(xy 348.996 -213.3346) (xy 348.1832 -214.1474)
			)
		)
	)
	(zone
		(layer "B.Cu")
		(hatch none 0.5)
		(connect_pads
			(clearance 0)
		)
		(min_thickness 0.25)
		(keepout
			(tracks allowed)
			(vias allowed)
			(pads allowed)
			(copperpour allowed)
			(footprints not_allowed)
		)
		(placement
			(enabled no)
			(sheetname "")
		)
		(fill
			(thermal_gap 0.5)
			(thermal_bridge_width 0.5)
			(island_removal_mode 0)
		)
		(polygon
			(pts
				(arc
					(start 1.999996 -0.999998)
					(mid 1.292891 -1.292891)
					(end 0.999998 -1.999996)
				)
				(xy 0.999998 -50.120042) (xy 466.600032 -50.120042)
				(arc
					(start 466.600032 -1.999996)
					(mid 466.307139 -1.292891)
					(end 465.600034 -0.999998)
				)
				(arc
					(start 446.265046 -0.999998)
					(mid 445.557941 -1.292891)
					(end 445.265048 -1.999996)
				)
				(arc
					(start 445.265048 -11.850116)
					(mid 444.679263 -13.264327)
					(end 443.265052 -13.850112)
				)
				(arc
					(start 435.265068 -13.850112)
					(mid 433.850857 -13.264327)
					(end 433.265072 -11.850116)
				)
				(arc
					(start 433.265072 -1.999996)
					(mid 432.972179 -1.292891)
					(end 432.265074 -0.999998)
				)
				(arc
					(start 420.265098 -0.999998)
					(mid 419.557993 -1.292891)
					(end 419.2651 -1.999996)
				)
				(arc
					(start 419.2651 -11.850116)
					(mid 418.679315 -13.264327)
					(end 417.265104 -13.850112)
				)
				(arc
					(start 409.26512 -13.850112)
					(mid 407.850909 -13.264327)
					(end 407.265124 -11.850116)
				)
				(arc
					(start 407.265124 -1.999996)
					(mid 406.972231 -1.292891)
					(end 406.265126 -0.999998)
				)
				(arc
					(start 394.264896 -0.999998)
					(mid 393.557791 -1.292891)
					(end 393.264898 -1.999996)
				)
				(arc
					(start 393.264898 -11.850116)
					(mid 392.679113 -13.264327)
					(end 391.264902 -13.850112)
				)
				(arc
					(start 383.264918 -13.850112)
					(mid 381.850707 -13.264327)
					(end 381.264922 -11.850116)
				)
				(arc
					(start 381.264922 -1.999996)
					(mid 380.972029 -1.292891)
					(end 380.264924 -0.999998)
				)
				(arc
					(start 368.264948 -0.999998)
					(mid 367.557843 -1.292891)
					(end 367.26495 -1.999996)
				)
				(arc
					(start 367.26495 -11.850116)
					(mid 366.679165 -13.264327)
					(end 365.264954 -13.850112)
				)
				(arc
					(start 357.26497 -13.850112)
					(mid 355.850759 -13.264327)
					(end 355.264974 -11.850116)
				)
				(arc
					(start 355.264974 -1.999996)
					(mid 354.972081 -1.292891)
					(end 354.264976 -0.999998)
				)
				(arc
					(start 330.164948 -0.999998)
					(mid 329.457843 -1.292891)
					(end 329.16495 -1.999996)
				)
				(arc
					(start 329.16495 -11.850116)
					(mid 328.579165 -13.264327)
					(end 327.164954 -13.850112)
				)
				(arc
					(start 319.16497 -13.850112)
					(mid 317.750759 -13.264327)
					(end 317.164974 -11.850116)
				)
				(arc
					(start 317.164974 -1.999996)
					(mid 316.872081 -1.292891)
					(end 316.164976 -0.999998)
				)
				(arc
					(start 304.165 -0.999998)
					(mid 303.457895 -1.292891)
					(end 303.165002 -1.999996)
				)
				(arc
					(start 303.165002 -11.850116)
					(mid 302.579217 -13.264327)
					(end 301.165006 -13.850112)
				)
				(arc
					(start 293.165022 -13.850112)
					(mid 291.750811 -13.264327)
					(end 291.165026 -11.850116)
				)
				(arc
					(start 291.165026 -1.999996)
					(mid 290.872133 -1.292891)
					(end 290.165028 -0.999998)
				)
				(arc
					(start 278.165052 -0.999998)
					(mid 277.457947 -1.292891)
					(end 277.165054 -1.999996)
				)
				(arc
					(start 277.165054 -11.850116)
					(mid 276.579269 -13.264327)
					(end 275.165058 -13.850112)
				)
				(arc
					(start 267.165074 -13.850112)
					(mid 265.750863 -13.264327)
					(end 265.165078 -11.850116)
				)
				(arc
					(start 265.165078 -1.999996)
					(mid 264.872185 -1.292891)
					(end 264.16508 -0.999998)
				)
				(arc
					(start 252.165104 -0.999998)
					(mid 251.457999 -1.292891)
					(end 251.165106 -1.999996)
				)
				(arc
					(start 251.165106 -11.850116)
					(mid 250.579321 -13.264327)
					(end 249.16511 -13.850112)
				)
				(arc
					(start 241.165126 -13.850112)
					(mid 239.750915 -13.264327)
					(end 239.164876 -11.850116)
				)
				(arc
					(start 239.164876 -1.999996)
					(mid 238.871983 -1.292891)
					(end 238.164878 -0.999998)
				)
				(arc
					(start 214.065104 -0.999998)
					(mid 213.357999 -1.292891)
					(end 213.065106 -1.999996)
				)
				(arc
					(start 213.065106 -11.850116)
					(mid 212.479321 -13.264327)
					(end 211.06511 -13.850112)
				)
				(arc
					(start 203.065126 -13.850112)
					(mid 201.650915 -13.264327)
					(end 201.064876 -11.850116)
				)
				(arc
					(start 201.064876 -1.999996)
					(mid 200.771983 -1.292891)
					(end 200.064878 -0.999998)
				)
				(arc
					(start 188.064902 -0.999998)
					(mid 187.357797 -1.292891)
					(end 187.064904 -1.999996)
				)
				(arc
					(start 187.064904 -11.850116)
					(mid 186.479119 -13.264327)
					(end 185.064908 -13.850112)
				)
				(arc
					(start 177.064924 -13.850112)
					(mid 175.650713 -13.264327)
					(end 175.064928 -11.850116)
				)
				(arc
					(start 175.064928 -1.999996)
					(mid 174.772035 -1.292891)
					(end 174.06493 -0.999998)
				)
				(arc
					(start 162.064954 -0.999998)
					(mid 161.357849 -1.292891)
					(end 161.064956 -1.999996)
				)
				(arc
					(start 161.064956 -11.850116)
					(mid 160.479171 -13.264327)
					(end 159.06496 -13.850112)
				)
				(arc
					(start 151.064976 -13.850112)
					(mid 149.650765 -13.264327)
					(end 149.06498 -11.850116)
				)
				(arc
					(start 149.06498 -1.999996)
					(mid 148.772087 -1.292891)
					(end 148.064982 -0.999998)
				)
				(arc
					(start 136.065006 -0.999998)
					(mid 135.357901 -1.292891)
					(end 135.065008 -1.999996)
				)
				(arc
					(start 135.065008 -11.850116)
					(mid 134.479223 -13.264327)
					(end 133.065012 -13.850112)
				)
				(arc
					(start 125.065028 -13.850112)
					(mid 123.650817 -13.264327)
					(end 123.065032 -11.850116)
				)
				(arc
					(start 123.065032 -1.999996)
					(mid 122.772139 -1.292891)
					(end 122.065034 -0.999998)
				)
				(arc
					(start 97.965006 -0.999998)
					(mid 97.257901 -1.292891)
					(end 96.965008 -1.999996)
				)
				(arc
					(start 96.965008 -11.850116)
					(mid 96.379223 -13.264327)
					(end 94.965012 -13.850112)
				)
				(arc
					(start 86.965028 -13.850112)
					(mid 85.550817 -13.264327)
					(end 84.965032 -11.850116)
				)
				(arc
					(start 84.965032 -1.999996)
					(mid 84.672139 -1.292891)
					(end 83.965034 -0.999998)
				)
				(arc
					(start 71.965058 -0.999998)
					(mid 71.257953 -1.292891)
					(end 70.96506 -1.999996)
				)
				(arc
					(start 70.96506 -11.850116)
					(mid 70.379275 -13.264327)
					(end 68.965064 -13.850112)
				)
				(arc
					(start 60.96508 -13.850112)
					(mid 59.550869 -13.264327)
					(end 58.965084 -11.850116)
				)
				(arc
					(start 58.965084 -1.999996)
					(mid 58.672191 -1.292891)
					(end 57.965086 -0.999998)
				)
				(arc
					(start 45.96511 -0.999998)
					(mid 45.258005 -1.292891)
					(end 44.965112 -1.999996)
				)
				(arc
					(start 44.965112 -11.850116)
					(mid 44.379327 -13.264327)
					(end 42.965116 -13.850112)
				)
				(arc
					(start 34.964878 -13.850112)
					(mid 33.550667 -13.264327)
					(end 32.964882 -11.850116)
				)
				(arc
					(start 32.964882 -1.999996)
					(mid 32.671989 -1.292891)
					(end 31.964884 -0.999998)
				)
				(arc
					(start 19.964908 -0.999998)
					(mid 19.257803 -1.292891)
					(end 18.96491 -1.999996)
				)
				(arc
					(start 18.96491 -11.850116)
					(mid 18.379125 -13.264327)
					(end 16.964914 -13.850112)
				)
				(arc
					(start 8.96493 -13.850112)
					(mid 7.550719 -13.264327)
					(end 6.964934 -11.850116)
				)
				(arc
					(start 6.964934 -1.999996)
					(mid 6.672041 -1.292891)
					(end 5.964936 -0.999998)
				)
			)
		)
	)
	(zone
		(layer "B.Cu")
		(hatch none 0.5)
		(connect_pads
			(clearance 0)
		)
		(min_thickness 0.25)
		(keepout
			(tracks not_allowed)
			(vias allowed)
			(pads allowed)
			(copperpour not_allowed)
			(footprints allowed)
		)
		(placement
			(enabled no)
			(sheetname "")
		)
		(fill
			(thermal_gap 0.5)
			(thermal_bridge_width 0.5)
			(island_removal_mode 0)
		)
		(polygon
			(pts
				(arc
					(start 393.076176 -318.699896)
					(mid 392.423396 -318.699896)
					(end 393.076176 -318.699896)
				)
			)
		)
	)
	(zone
		(layer "B.Cu")
		(hatch none 0.5)
		(connect_pads
			(clearance 0)
		)
		(min_thickness 0.25)
		(keepout
			(tracks not_allowed)
			(vias allowed)
			(pads allowed)
			(copperpour not_allowed)
			(footprints allowed)
		)
		(placement
			(enabled no)
			(sheetname "")
		)
		(fill
			(thermal_gap 0.5)
			(thermal_bridge_width 0.5)
			(island_removal_mode 0)
		)
		(polygon
			(pts
				(arc
					(start 312.126122 -307.299868)
					(mid 311.473342 -307.299868)
					(end 312.126122 -307.299868)
				)
			)
		)
	)
	(zone
		(layer "B.Cu")
		(hatch none 0.5)
		(connect_pads
			(clearance 0)
		)
		(min_thickness 0.25)
		(keepout
			(tracks not_allowed)
			(vias allowed)
			(pads allowed)
			(copperpour not_allowed)
			(footprints allowed)
		)
		(placement
			(enabled no)
			(sheetname "")
		)
		(fill
			(thermal_gap 0.5)
			(thermal_bridge_width 0.5)
			(island_removal_mode 0)
		)
		(polygon
			(pts
				(arc
					(start 409.619958 -20.72005)
					(mid 407.619962 -18.720054)
					(end 405.619966 -20.72005)
				)
				(arc
					(start 405.619966 -20.72005)
					(mid 407.619962 -22.720046)
					(end 409.619958 -20.72005)
				)
			)
		)
	)
	(zone
		(layer "B.Cu")
		(hatch none 0.5)
		(connect_pads
			(clearance 0)
		)
		(min_thickness 0.25)
		(keepout
			(tracks allowed)
			(vias allowed)
			(pads allowed)
			(copperpour allowed)
			(footprints not_allowed)
		)
		(placement
			(enabled no)
			(sheetname "")
		)
		(fill
			(thermal_gap 0.5)
			(thermal_bridge_width 0.5)
			(island_removal_mode 0)
		)
		(polygon
			(pts
				(arc
					(start 446.79997 -194.360038)
					(mid 451.79996 -199.360028)
					(end 456.79995 -194.360038)
				)
				(arc
					(start 456.79995 -194.360038)
					(mid 451.79996 -189.360048)
					(end 446.79997 -194.360038)
				)
			)
		)
	)
	(zone
		(layer "B.Cu")
		(hatch none 0.5)
		(connect_pads
			(clearance 0)
		)
		(min_thickness 0.25)
		(keepout
			(tracks not_allowed)
			(vias allowed)
			(pads allowed)
			(copperpour not_allowed)
			(footprints allowed)
		)
		(placement
			(enabled no)
			(sheetname "")
		)
		(fill
			(thermal_gap 0.5)
			(thermal_bridge_width 0.5)
			(island_removal_mode 0)
		)
		(polygon
			(pts
				(arc
					(start 41.48963 -404.290022)
					(mid 40.73017 -404.290022)
					(end 41.48963 -404.290022)
				)
			)
		)
	)
	(zone
		(layer "B.Cu")
		(hatch none 0.5)
		(connect_pads
			(clearance 0)
		)
		(min_thickness 0.25)
		(keepout
			(tracks not_allowed)
			(vias allowed)
			(pads allowed)
			(copperpour not_allowed)
			(footprints allowed)
		)
		(placement
			(enabled no)
			(sheetname "")
		)
		(fill
			(thermal_gap 0.5)
			(thermal_bridge_width 0.5)
			(island_removal_mode 0)
		)
		(polygon
			(pts
				(arc
					(start 314.026296 -308.249828)
					(mid 313.373516 -308.249828)
					(end 314.026296 -308.249828)
				)
			)
		)
	)
	(zone
		(layer "B.Cu")
		(hatch none 0.5)
		(connect_pads
			(clearance 0)
		)
		(min_thickness 0.25)
		(keepout
			(tracks not_allowed)
			(vias allowed)
			(pads allowed)
			(copperpour not_allowed)
			(footprints allowed)
		)
		(placement
			(enabled no)
			(sheetname "")
		)
		(fill
			(thermal_gap 0.5)
			(thermal_bridge_width 0.5)
			(island_removal_mode 0)
		)
		(polygon
			(pts
				(arc
					(start 25.150064 -320.900044)
					(mid 29.650182 -325.400162)
					(end 34.150046 -320.900044)
				)
				(arc
					(start 34.150046 -320.900044)
					(mid 29.650182 -316.40018)
					(end 25.150064 -320.900044)
				)
			)
		)
	)
	(zone
		(layer "B.Cu")
		(hatch none 0.5)
		(connect_pads
			(clearance 0)
		)
		(min_thickness 0.25)
		(keepout
			(tracks allowed)
			(vias allowed)
			(pads allowed)
			(copperpour allowed)
			(footprints allowed)
		)
		(placement
			(enabled no)
			(sheetname "")
		)
		(fill
			(thermal_gap 0.5)
			(thermal_bridge_width 0.5)
			(island_removal_mode 0)
		)
		(polygon
			(pts
				(xy 123.591828 -312.599578) (xy 125.242828 -312.599578) (xy 125.242828 -314.758578) (xy 123.591828 -314.758578)
			)
		)
	)
	(zone
		(layer "B.Cu")
		(hatch none 0.5)
		(connect_pads
			(clearance 0)
		)
		(min_thickness 0.25)
		(keepout
			(tracks not_allowed)
			(vias allowed)
			(pads allowed)
			(copperpour not_allowed)
			(footprints allowed)
		)
		(placement
			(enabled no)
			(sheetname "")
		)
		(fill
			(thermal_gap 0.5)
			(thermal_bridge_width 0.5)
			(island_removal_mode 0)
		)
		(polygon
			(pts
				(arc
					(start 159.926274 -316.799722)
					(mid 159.273494 -316.799722)
					(end 159.926274 -316.799722)
				)
			)
		)
	)
	(zone
		(layer "B.Cu")
		(hatch none 0.5)
		(connect_pads
			(clearance 0)
		)
		(min_thickness 0.25)
		(keepout
			(tracks allowed)
			(vias allowed)
			(pads allowed)
			(copperpour allowed)
			(footprints allowed)
		)
		(placement
			(enabled no)
			(sheetname "")
		)
		(fill
			(thermal_gap 0.5)
			(thermal_bridge_width 0.5)
			(island_removal_mode 0)
		)
		(polygon
			(pts
				(xy 2.921 -265.684) (xy 2.921 -263.525) (xy 4.699 -263.525) (xy 4.699 -265.684)
			)
		)
	)
	(zone
		(layer "B.Cu")
		(hatch none 0.5)
		(connect_pads
			(clearance 0)
		)
		(min_thickness 0.25)
		(keepout
			(tracks not_allowed)
			(vias allowed)
			(pads allowed)
			(copperpour not_allowed)
			(footprints allowed)
		)
		(placement
			(enabled no)
			(sheetname "")
		)
		(fill
			(thermal_gap 0.5)
			(thermal_bridge_width 0.5)
			(island_removal_mode 0)
		)
		(polygon
			(pts
				(arc
					(start 23.165054 -17.999964)
					(mid 25.96515 -20.80006)
					(end 28.764992 -17.999964)
				)
				(arc
					(start 28.764992 -17.999964)
					(mid 25.96515 -15.200122)
					(end 23.165054 -17.999964)
				)
			)
		)
	)
	(zone
		(layer "B.Cu")
		(hatch none 0.5)
		(connect_pads
			(clearance 0)
		)
		(min_thickness 0.25)
		(keepout
			(tracks not_allowed)
			(vias allowed)
			(pads allowed)
			(copperpour not_allowed)
			(footprints allowed)
		)
		(placement
			(enabled no)
			(sheetname "")
		)
		(fill
			(thermal_gap 0.5)
			(thermal_bridge_width 0.5)
			(island_removal_mode 0)
		)
		(polygon
			(pts
				(arc
					(start 312.126122 -316.799722)
					(mid 311.473342 -316.799722)
					(end 312.126122 -316.799722)
				)
			)
		)
	)
	(zone
		(layer "B.Cu")
		(hatch none 0.5)
		(connect_pads
			(clearance 0)
		)
		(min_thickness 0.25)
		(keepout
			(tracks not_allowed)
			(vias allowed)
			(pads allowed)
			(copperpour not_allowed)
			(footprints allowed)
		)
		(placement
			(enabled no)
			(sheetname "")
		)
		(fill
			(thermal_gap 0.5)
			(thermal_bridge_width 0.5)
			(island_removal_mode 0)
		)
		(polygon
			(pts
				(arc
					(start 108.015024 -17.999964)
					(mid 110.01502 -19.99996)
					(end 112.015016 -17.999964)
				)
				(arc
					(start 112.015016 -17.999964)
					(mid 110.01502 -15.999968)
					(end 108.015024 -17.999964)
				)
			)
		)
	)
	(zone
		(layer "B.Cu")
		(hatch none 0.5)
		(connect_pads
			(clearance 0)
		)
		(min_thickness 0.25)
		(keepout
			(tracks allowed)
			(vias allowed)
			(pads allowed)
			(copperpour allowed)
			(footprints not_allowed)
		)
		(placement
			(enabled no)
			(sheetname "")
		)
		(fill
			(thermal_gap 0.5)
			(thermal_bridge_width 0.5)
			(island_removal_mode 0)
		)
		(polygon
			(pts
				(arc
					(start 379.620018 -20.72005)
					(mid 381.620014 -22.720046)
					(end 383.62001 -20.72005)
				)
				(arc
					(start 383.62001 -20.72005)
					(mid 381.620014 -18.720054)
					(end 379.620018 -20.72005)
				)
			)
		)
	)
	(zone
		(layer "B.Cu")
		(hatch none 0.5)
		(connect_pads
			(clearance 0)
		)
		(min_thickness 0.25)
		(keepout
			(tracks allowed)
			(vias allowed)
			(pads allowed)
			(copperpour allowed)
			(footprints not_allowed)
		)
		(placement
			(enabled no)
			(sheetname "")
		)
		(fill
			(thermal_gap 0.5)
			(thermal_bridge_width 0.5)
			(island_removal_mode 0)
		)
		(polygon
			(pts
				(arc
					(start 364.450122 -276.010116)
					(mid 368.450114 -280.010108)
					(end 372.450106 -276.010116)
				)
				(arc
					(start 372.450106 -276.010116)
					(mid 368.450114 -272.010124)
					(end 364.450122 -276.010116)
				)
			)
		)
	)
	(zone
		(layer "B.Cu")
		(hatch none 0.5)
		(connect_pads
			(clearance 0)
		)
		(min_thickness 0.25)
		(keepout
			(tracks allowed)
			(vias allowed)
			(pads allowed)
			(copperpour allowed)
			(footprints not_allowed)
		)
		(placement
			(enabled no)
			(sheetname "")
		)
		(fill
			(thermal_gap 0.5)
			(thermal_bridge_width 0.5)
			(island_removal_mode 0)
		)
		(polygon
			(pts
				(arc
					(start 460.520034 -312.06567)
					(mid 463.240224 -309.943569)
					(end 466.600032 -310.727598)
				)
				(xy 466.600032 -266.897612) (xy 448.449954 -266.897612) (xy 448.449954 -304.737008) (xy 448.520058 -304.755804)
				(xy 448.520058 -302.64989) (xy 460.520034 -302.64989)
			)
		)
	)
	(zone
		(layer "B.Cu")
		(hatch none 0.5)
		(connect_pads
			(clearance 0)
		)
		(min_thickness 0.25)
		(keepout
			(tracks not_allowed)
			(vias allowed)
			(pads allowed)
			(copperpour not_allowed)
			(footprints allowed)
		)
		(placement
			(enabled no)
			(sheetname "")
		)
		(fill
			(thermal_gap 0.5)
			(thermal_bridge_width 0.5)
			(island_removal_mode 0)
		)
		(polygon
			(pts
				(arc
					(start 314.976256 -316.799722)
					(mid 314.323476 -316.799722)
					(end 314.976256 -316.799722)
				)
			)
		)
	)
	(zone
		(layer "B.Cu")
		(hatch none 0.5)
		(connect_pads
			(clearance 0)
		)
		(min_thickness 0.25)
		(keepout
			(tracks allowed)
			(vias allowed)
			(pads allowed)
			(copperpour allowed)
			(footprints not_allowed)
		)
		(placement
			(enabled no)
			(sheetname "")
		)
		(fill
			(thermal_gap 0.5)
			(thermal_bridge_width 0.5)
			(island_removal_mode 0)
		)
		(polygon
			(pts
				(arc
					(start 450.93255 -5.999988)
					(mid 455.93254 -10.999978)
					(end 460.93253 -5.999988)
				)
				(arc
					(start 460.93253 -5.999988)
					(mid 455.93254 -0.999998)
					(end 450.93255 -5.999988)
				)
			)
		)
	)
	(zone
		(layer "B.Cu")
		(hatch none 0.5)
		(connect_pads
			(clearance 0)
		)
		(min_thickness 0.25)
		(keepout
			(tracks not_allowed)
			(vias allowed)
			(pads allowed)
			(copperpour not_allowed)
			(footprints allowed)
		)
		(placement
			(enabled no)
			(sheetname "")
		)
		(fill
			(thermal_gap 0.5)
			(thermal_bridge_width 0.5)
			(island_removal_mode 0)
		)
		(polygon
			(pts
				(arc
					(start 309.276242 -318.699896)
					(mid 308.623462 -318.699896)
					(end 309.276242 -318.699896)
				)
			)
		)
	)
	(zone
		(layer "B.Cu")
		(hatch none 0.5)
		(connect_pads
			(clearance 0)
		)
		(min_thickness 0.25)
		(keepout
			(tracks not_allowed)
			(vias allowed)
			(pads allowed)
			(copperpour not_allowed)
			(footprints allowed)
		)
		(placement
			(enabled no)
			(sheetname "")
		)
		(fill
			(thermal_gap 0.5)
			(thermal_bridge_width 0.5)
			(island_removal_mode 0)
		)
		(polygon
			(pts
				(arc
					(start 418.726366 -315.849762)
					(mid 418.073586 -315.849762)
					(end 418.726366 -315.849762)
				)
			)
		)
	)
	(zone
		(layer "B.Cu")
		(hatch none 0.5)
		(connect_pads
			(clearance 0)
		)
		(min_thickness 0.25)
		(keepout
			(tracks allowed)
			(vias allowed)
			(pads allowed)
			(copperpour allowed)
			(footprints allowed)
		)
		(placement
			(enabled no)
			(sheetname "")
		)
		(fill
			(thermal_gap 0.5)
			(thermal_bridge_width 0.5)
			(island_removal_mode 0)
		)
		(polygon
			(pts
				(arc
					(start 101.440234 -328.924412)
					(mid 101.455113 -328.888491)
					(end 101.491034 -328.873612)
				)
				(arc
					(start 102.630732 -328.873612)
					(mid 102.666653 -328.888491)
					(end 102.681532 -328.924412)
				)
				(arc
					(start 102.681532 -329.85202)
					(mid 102.666653 -329.887941)
					(end 102.630732 -329.90282)
				)
				(arc
					(start 101.491034 -329.90282)
					(mid 101.455113 -329.887941)
					(end 101.440234 -329.85202)
				)
			)
		)
	)
	(zone
		(layer "B.Cu")
		(hatch none 0.5)
		(connect_pads
			(clearance 0)
		)
		(min_thickness 0.25)
		(keepout
			(tracks not_allowed)
			(vias allowed)
			(pads allowed)
			(copperpour not_allowed)
			(footprints allowed)
		)
		(placement
			(enabled no)
			(sheetname "")
		)
		(fill
			(thermal_gap 0.5)
			(thermal_bridge_width 0.5)
			(island_removal_mode 0)
		)
		(polygon
			(pts
				(arc
					(start 81.826354 -310.149748)
					(mid 81.173574 -310.149748)
					(end 81.826354 -310.149748)
				)
			)
		)
	)
	(zone
		(layer "B.Cu")
		(hatch none 0.5)
		(connect_pads
			(clearance 0)
		)
		(min_thickness 0.25)
		(keepout
			(tracks allowed)
			(vias allowed)
			(pads allowed)
			(copperpour allowed)
			(footprints allowed)
		)
		(placement
			(enabled no)
			(sheetname "")
		)
		(fill
			(thermal_gap 0.5)
			(thermal_bridge_width 0.5)
			(island_removal_mode 0)
		)
		(polygon
			(pts
				(xy 101.838252 -359.148888) (xy 101.838252 -357.133144) (xy 103.490014 -357.133144) (xy 103.490014 -359.148888)
			)
		)
	)
	(zone
		(layer "B.Cu")
		(hatch none 0.5)
		(connect_pads
			(clearance 0)
		)
		(min_thickness 0.25)
		(keepout
			(tracks allowed)
			(vias allowed)
			(pads allowed)
			(copperpour allowed)
			(footprints allowed)
		)
		(placement
			(enabled no)
			(sheetname "")
		)
		(fill
			(thermal_gap 0.5)
			(thermal_bridge_width 0.5)
			(island_removal_mode 0)
		)
		(polygon
			(pts
				(xy 452.157338 -268.094206) (xy 452.157338 -265.935206) (xy 453.808338 -265.935206) (xy 453.808338 -268.094206)
			)
		)
	)
	(zone
		(layer "B.Cu")
		(hatch none 0.5)
		(connect_pads
			(clearance 0)
		)
		(min_thickness 0.25)
		(keepout
			(tracks not_allowed)
			(vias allowed)
			(pads allowed)
			(copperpour not_allowed)
			(footprints allowed)
		)
		(placement
			(enabled no)
			(sheetname "")
		)
		(fill
			(thermal_gap 0.5)
			(thermal_bridge_width 0.5)
			(island_removal_mode 0)
		)
		(polygon
			(pts
				(arc
					(start 265.400028 -393.100052)
					(mid 268.200124 -395.900148)
					(end 270.999966 -393.100052)
				)
				(arc
					(start 270.999966 -393.100052)
					(mid 268.200124 -390.30021)
					(end 265.400028 -393.100052)
				)
			)
		)
	)
	(zone
		(layer "B.Cu")
		(hatch none 0.5)
		(connect_pads
			(clearance 0)
		)
		(min_thickness 0.25)
		(keepout
			(tracks not_allowed)
			(vias allowed)
			(pads allowed)
			(copperpour not_allowed)
			(footprints allowed)
		)
		(placement
			(enabled no)
			(sheetname "")
		)
		(fill
			(thermal_gap 0.5)
			(thermal_bridge_width 0.5)
			(island_removal_mode 0)
		)
		(polygon
			(pts
				(arc
					(start 54.699916 -371.310662)
					(mid 53.996336 -371.310662)
					(end 54.699916 -371.310662)
				)
			)
		)
	)
	(zone
		(layer "B.Cu")
		(hatch none 0.5)
		(connect_pads
			(clearance 0)
		)
		(min_thickness 0.25)
		(keepout
			(tracks allowed)
			(vias allowed)
			(pads allowed)
			(copperpour allowed)
			(footprints not_allowed)
		)
		(placement
			(enabled no)
			(sheetname "")
		)
		(fill
			(thermal_gap 0.5)
			(thermal_bridge_width 0.5)
			(island_removal_mode 0)
		)
		(polygon
			(pts
				(arc
					(start 357.89997 -60.699904)
					(mid 349.899986 -52.69992)
					(end 341.900002 -60.699904)
				)
				(arc
					(start 341.900002 -72.69988)
					(mid 349.899986 -80.699864)
					(end 357.89997 -72.69988)
				)
			)
		)
	)
	(zone
		(layer "B.Cu")
		(hatch none 0.5)
		(connect_pads
			(clearance 0)
		)
		(min_thickness 0.25)
		(keepout
			(tracks not_allowed)
			(vias allowed)
			(pads allowed)
			(copperpour not_allowed)
			(footprints allowed)
		)
		(placement
			(enabled no)
			(sheetname "")
		)
		(fill
			(thermal_gap 0.5)
			(thermal_bridge_width 0.5)
			(island_removal_mode 0)
		)
		(polygon
			(pts
				(arc
					(start 30.489652 -406.690068)
					(mid 29.730192 -406.690068)
					(end 30.489652 -406.690068)
				)
			)
		)
	)
	(zone
		(layer "B.Cu")
		(hatch none 0.5)
		(connect_pads
			(clearance 0)
		)
		(min_thickness 0.25)
		(keepout
			(tracks allowed)
			(vias allowed)
			(pads allowed)
			(copperpour allowed)
			(footprints allowed)
		)
		(placement
			(enabled no)
			(sheetname "")
		)
		(fill
			(thermal_gap 0.5)
			(thermal_bridge_width 0.5)
			(island_removal_mode 0)
		)
		(polygon
			(pts
				(xy 113.759742 -312.599578) (xy 115.410742 -312.599578) (xy 115.410742 -314.758578) (xy 113.759742 -314.758578)
			)
		)
	)
	(zone
		(layer "B.Cu")
		(hatch none 0.5)
		(connect_pads
			(clearance 0)
		)
		(min_thickness 0.25)
		(keepout
			(tracks allowed)
			(vias allowed)
			(pads allowed)
			(copperpour allowed)
			(footprints not_allowed)
		)
		(placement
			(enabled no)
			(sheetname "")
		)
		(fill
			(thermal_gap 0.5)
			(thermal_bridge_width 0.5)
			(island_removal_mode 0)
		)
		(polygon
			(pts
				(xy 397.949928 -84.68995) (xy 417.949888 -84.68995) (xy 417.949888 -64.68999) (xy 397.949928 -64.68999)
			)
		)
	)
	(zone
		(layer "B.Cu")
		(hatch none 0.5)
		(connect_pads
			(clearance 0)
		)
		(min_thickness 0.25)
		(keepout
			(tracks allowed)
			(vias allowed)
			(pads allowed)
			(copperpour allowed)
			(footprints not_allowed)
		)
		(placement
			(enabled no)
			(sheetname "")
		)
		(fill
			(thermal_gap 0.5)
			(thermal_bridge_width 0.5)
			(island_removal_mode 0)
		)
		(polygon
			(pts
				(arc
					(start 194.399916 -393.100052)
					(mid 199.399906 -398.100042)
					(end 204.399896 -393.100052)
				)
				(arc
					(start 204.399896 -393.100052)
					(mid 199.399906 -388.100062)
					(end 194.399916 -393.100052)
				)
			)
		)
	)
	(zone
		(layer "B.Cu")
		(hatch none 0.5)
		(connect_pads
			(clearance 0)
		)
		(min_thickness 0.25)
		(keepout
			(tracks not_allowed)
			(vias allowed)
			(pads allowed)
			(copperpour not_allowed)
			(footprints allowed)
		)
		(placement
			(enabled no)
			(sheetname "")
		)
		(fill
			(thermal_gap 0.5)
			(thermal_bridge_width 0.5)
			(island_removal_mode 0)
		)
		(polygon
			(pts
				(arc
					(start 213.739984 -311.179972)
					(mid 216.990168 -314.430156)
					(end 220.240098 -311.179972)
				)
				(arc
					(start 220.240098 -311.179972)
					(mid 216.990168 -307.930042)
					(end 213.739984 -311.179972)
				)
			)
		)
	)
	(zone
		(layer "B.Cu")
		(hatch none 0.5)
		(connect_pads
			(clearance 0)
		)
		(min_thickness 0.25)
		(keepout
			(tracks not_allowed)
			(vias allowed)
			(pads allowed)
			(copperpour not_allowed)
			(footprints allowed)
		)
		(placement
			(enabled no)
			(sheetname "")
		)
		(fill
			(thermal_gap 0.5)
			(thermal_bridge_width 0.5)
			(island_removal_mode 0)
		)
		(polygon
			(pts
				(arc
					(start 211.758022 -347.400118)
					(mid 215.758014 -351.40011)
					(end 219.758006 -347.400118)
				)
				(arc
					(start 219.758006 -347.400118)
					(mid 215.758014 -343.400126)
					(end 211.758022 -347.400118)
				)
			)
		)
	)
	(zone
		(layer "B.Cu")
		(hatch none 0.5)
		(connect_pads
			(clearance 0)
		)
		(min_thickness 0.25)
		(keepout
			(tracks not_allowed)
			(vias allowed)
			(pads allowed)
			(copperpour not_allowed)
			(footprints allowed)
		)
		(placement
			(enabled no)
			(sheetname "")
		)
		(fill
			(thermal_gap 0.5)
			(thermal_bridge_width 0.5)
			(island_removal_mode 0)
		)
		(polygon
			(pts
				(arc
					(start 87.32012 -20.72005)
					(mid 85.320124 -18.720054)
					(end 83.319874 -20.72005)
				)
				(arc
					(start 83.319874 -20.72005)
					(mid 85.320124 -22.7203)
					(end 87.32012 -20.72005)
				)
			)
		)
	)
	(zone
		(layer "B.Cu")
		(hatch none 0.5)
		(connect_pads
			(clearance 0)
		)
		(min_thickness 0.25)
		(keepout
			(tracks not_allowed)
			(vias allowed)
			(pads allowed)
			(copperpour not_allowed)
			(footprints allowed)
		)
		(placement
			(enabled no)
			(sheetname "")
		)
		(fill
			(thermal_gap 0.5)
			(thermal_bridge_width 0.5)
			(island_removal_mode 0)
		)
		(polygon
			(pts
				(arc
					(start 241.519964 -20.72005)
					(mid 239.519968 -18.720054)
					(end 237.519972 -20.72005)
				)
				(arc
					(start 237.519972 -20.72005)
					(mid 239.519968 -22.720046)
					(end 241.519964 -20.72005)
				)
			)
		)
	)
	(zone
		(layer "B.Cu")
		(hatch none 0.5)
		(connect_pads
			(clearance 0)
		)
		(min_thickness 0.25)
		(keepout
			(tracks allowed)
			(vias allowed)
			(pads allowed)
			(copperpour allowed)
			(footprints not_allowed)
		)
		(placement
			(enabled no)
			(sheetname "")
		)
		(fill
			(thermal_gap 0.5)
			(thermal_bridge_width 0.5)
			(island_removal_mode 0)
		)
		(polygon
			(pts
				(arc
					(start 279.900126 -378.70003)
					(mid 271.900142 -370.700046)
					(end 263.899904 -378.70003)
				)
				(arc
					(start 263.899904 -378.70003)
					(mid 271.900142 -386.700268)
					(end 279.900126 -378.70003)
				)
			)
		)
	)
	(zone
		(layer "B.Cu")
		(hatch none 0.5)
		(connect_pads
			(clearance 0)
		)
		(min_thickness 0.25)
		(keepout
			(tracks not_allowed)
			(vias allowed)
			(pads allowed)
			(copperpour not_allowed)
			(footprints allowed)
		)
		(placement
			(enabled no)
			(sheetname "")
		)
		(fill
			(thermal_gap 0.5)
			(thermal_bridge_width 0.5)
			(island_removal_mode 0)
		)
		(polygon
			(pts
				(arc
					(start 420.91991 -15.649956)
					(mid 418.919914 -13.64996)
					(end 416.919918 -15.649956)
				)
				(arc
					(start 416.919918 -15.649956)
					(mid 418.919914 -17.649952)
					(end 420.91991 -15.649956)
				)
			)
		)
	)
	(zone
		(layer "B.Cu")
		(hatch none 0.5)
		(connect_pads
			(clearance 0)
		)
		(min_thickness 0.25)
		(keepout
			(tracks not_allowed)
			(vias allowed)
			(pads allowed)
			(copperpour not_allowed)
			(footprints allowed)
		)
		(placement
			(enabled no)
			(sheetname "")
		)
		(fill
			(thermal_gap 0.5)
			(thermal_bridge_width 0.5)
			(island_removal_mode 0)
		)
		(polygon
			(pts
				(arc
					(start 382.469644 -371.590062)
					(mid 381.710184 -371.590062)
					(end 382.469644 -371.590062)
				)
			)
		)
	)
	(zone
		(layer "B.Cu")
		(hatch none 0.5)
		(connect_pads
			(clearance 0)
		)
		(min_thickness 0.25)
		(keepout
			(tracks not_allowed)
			(vias allowed)
			(pads allowed)
			(copperpour not_allowed)
			(footprints allowed)
		)
		(placement
			(enabled no)
			(sheetname "")
		)
		(fill
			(thermal_gap 0.5)
			(thermal_bridge_width 0.5)
			(island_removal_mode 0)
		)
		(polygon
			(pts
				(arc
					(start 433.449984 -270.89989)
					(mid 437.950102 -275.400008)
					(end 442.449966 -270.89989)
				)
				(arc
					(start 442.449966 -270.89989)
					(mid 437.950102 -266.400026)
					(end 433.449984 -270.89989)
				)
			)
		)
	)
	(zone
		(layer "B.Cu")
		(hatch none 0.5)
		(connect_pads
			(clearance 0)
		)
		(min_thickness 0.25)
		(keepout
			(tracks not_allowed)
			(vias allowed)
			(pads allowed)
			(copperpour not_allowed)
			(footprints allowed)
		)
		(placement
			(enabled no)
			(sheetname "")
		)
		(fill
			(thermal_gap 0.5)
			(thermal_bridge_width 0.5)
			(island_removal_mode 0)
		)
		(polygon
			(pts
				(arc
					(start 122.889772 -372.890034)
					(mid 122.130312 -372.890034)
					(end 122.889772 -372.890034)
				)
			)
		)
	)
	(zone
		(layer "B.Cu")
		(hatch none 0.5)
		(connect_pads
			(clearance 0)
		)
		(min_thickness 0.25)
		(keepout
			(tracks allowed)
			(vias allowed)
			(pads allowed)
			(copperpour allowed)
			(footprints not_allowed)
		)
		(placement
			(enabled no)
			(sheetname "")
		)
		(fill
			(thermal_gap 0.5)
			(thermal_bridge_width 0.5)
			(island_removal_mode 0)
		)
		(polygon
			(pts
				(arc
					(start 326.820022 -15.649956)
					(mid 328.820018 -17.649952)
					(end 330.820014 -15.649956)
				)
				(arc
					(start 330.820014 -15.649956)
					(mid 328.820018 -13.64996)
					(end 326.820022 -15.649956)
				)
			)
		)
	)
	(zone
		(layer "B.Cu")
		(hatch none 0.5)
		(connect_pads
			(clearance 0)
		)
		(min_thickness 0.25)
		(keepout
			(tracks not_allowed)
			(vias allowed)
			(pads allowed)
			(copperpour not_allowed)
			(footprints allowed)
		)
		(placement
			(enabled no)
			(sheetname "")
		)
		(fill
			(thermal_gap 0.5)
			(thermal_bridge_width 0.5)
			(island_removal_mode 0)
		)
		(polygon
			(pts
				(arc
					(start 30.489652 -379.390148)
					(mid 29.730192 -379.390148)
					(end 30.489652 -379.390148)
				)
			)
		)
	)
	(zone
		(layer "B.Cu")
		(hatch none 0.5)
		(connect_pads
			(clearance 0)
		)
		(min_thickness 0.25)
		(keepout
			(tracks allowed)
			(vias allowed)
			(pads allowed)
			(copperpour allowed)
			(footprints allowed)
		)
		(placement
			(enabled no)
			(sheetname "")
		)
		(fill
			(thermal_gap 0.5)
			(thermal_bridge_width 0.5)
			(island_removal_mode 0)
		)
		(polygon
			(pts
				(xy 131.48183 -176.629568) (xy 132.550916 -176.629568) (xy 132.679694 -176.50079) (xy 132.679694 -175.831246)
				(xy 132.409184 -175.560736) (xy 131.559046 -175.560736) (xy 131.443222 -175.67656) (xy 131.443222 -176.59096)
			)
		)
	)
	(zone
		(layer "B.Cu")
		(hatch none 0.5)
		(connect_pads
			(clearance 0)
		)
		(min_thickness 0.25)
		(keepout
			(tracks not_allowed)
			(vias allowed)
			(pads allowed)
			(copperpour not_allowed)
			(footprints allowed)
		)
		(placement
			(enabled no)
			(sheetname "")
		)
		(fill
			(thermal_gap 0.5)
			(thermal_bridge_width 0.5)
			(island_removal_mode 0)
		)
		(polygon
			(pts
				(arc
					(start 314.976256 -304.449734)
					(mid 314.323476 -304.449734)
					(end 314.976256 -304.449734)
				)
			)
		)
	)
	(zone
		(layer "B.Cu")
		(hatch none 0.5)
		(connect_pads
			(clearance 0)
		)
		(min_thickness 0.25)
		(keepout
			(tracks allowed)
			(vias allowed)
			(pads allowed)
			(copperpour allowed)
			(footprints not_allowed)
		)
		(placement
			(enabled no)
			(sheetname "")
		)
		(fill
			(thermal_gap 0.5)
			(thermal_bridge_width 0.5)
			(island_removal_mode 0)
		)
		(polygon
			(pts
				(arc
					(start 405.619966 -20.72005)
					(mid 407.619962 -22.720046)
					(end 409.619958 -20.72005)
				)
				(arc
					(start 409.619958 -20.72005)
					(mid 407.619962 -18.720054)
					(end 405.619966 -20.72005)
				)
			)
		)
	)
	(zone
		(layer "B.Cu")
		(hatch none 0.5)
		(connect_pads
			(clearance 0)
		)
		(min_thickness 0.25)
		(keepout
			(tracks not_allowed)
			(vias allowed)
			(pads allowed)
			(copperpour not_allowed)
			(footprints allowed)
		)
		(placement
			(enabled no)
			(sheetname "")
		)
		(fill
			(thermal_gap 0.5)
			(thermal_bridge_width 0.5)
			(island_removal_mode 0)
		)
		(polygon
			(pts
				(xy 412.809944 -396.54988) (xy 412.809944 -417.58997) (xy 402.809964 -417.58997) (xy 402.809964 -396.54988)
			)
		)
	)
	(zone
		(layer "B.Cu")
		(hatch none 0.5)
		(connect_pads
			(clearance 0)
		)
		(min_thickness 0.25)
		(keepout
			(tracks not_allowed)
			(vias allowed)
			(pads allowed)
			(copperpour not_allowed)
			(footprints allowed)
		)
		(placement
			(enabled no)
			(sheetname "")
		)
		(fill
			(thermal_gap 0.5)
			(thermal_bridge_width 0.5)
			(island_removal_mode 0)
		)
		(polygon
			(pts
				(arc
					(start 28.289758 -379.590046)
					(mid 27.530298 -379.590046)
					(end 28.289758 -379.590046)
				)
			)
		)
	)
	(zone
		(layer "B.Cu")
		(hatch none 0.5)
		(connect_pads
			(clearance 0)
		)
		(min_thickness 0.25)
		(keepout
			(tracks not_allowed)
			(vias allowed)
			(pads allowed)
			(copperpour not_allowed)
			(footprints allowed)
		)
		(placement
			(enabled no)
			(sheetname "")
		)
		(fill
			(thermal_gap 0.5)
			(thermal_bridge_width 0.5)
			(island_removal_mode 0)
		)
		(polygon
			(pts
				(arc
					(start 201.250042 -320.900044)
					(mid 205.75016 -325.400162)
					(end 210.250024 -320.900044)
				)
				(arc
					(start 210.250024 -320.900044)
					(mid 205.75016 -316.40018)
					(end 201.250042 -320.900044)
				)
			)
		)
	)
	(zone
		(layer "B.Cu")
		(hatch none 0.5)
		(connect_pads
			(clearance 0)
		)
		(min_thickness 0.25)
		(keepout
			(tracks not_allowed)
			(vias allowed)
			(pads allowed)
			(copperpour not_allowed)
			(footprints allowed)
		)
		(placement
			(enabled no)
			(sheetname "")
		)
		(fill
			(thermal_gap 0.5)
			(thermal_bridge_width 0.5)
			(island_removal_mode 0)
		)
		(polygon
			(pts
				(arc
					(start 188.719968 -15.649956)
					(mid 186.719972 -13.64996)
					(end 184.719976 -15.649956)
				)
				(arc
					(start 184.719976 -15.649956)
					(mid 186.719972 -17.649952)
					(end 188.719968 -15.649956)
				)
			)
		)
	)
	(zone
		(layer "B.Cu")
		(hatch none 0.5)
		(connect_pads
			(clearance 0)
		)
		(min_thickness 0.25)
		(keepout
			(tracks not_allowed)
			(vias allowed)
			(pads allowed)
			(copperpour not_allowed)
			(footprints allowed)
		)
		(placement
			(enabled no)
			(sheetname "")
		)
		(fill
			(thermal_gap 0.5)
			(thermal_bridge_width 0.5)
			(island_removal_mode 0)
		)
		(polygon
			(pts
				(arc
					(start 453.132444 -5.999988)
					(mid 455.93254 -8.800084)
					(end 458.732382 -5.999988)
				)
				(arc
					(start 458.732382 -5.999988)
					(mid 455.93254 -3.200146)
					(end 453.132444 -5.999988)
				)
			)
		)
	)
	(zone
		(layer "B.Cu")
		(hatch none 0.5)
		(connect_pads
			(clearance 0)
		)
		(min_thickness 0.25)
		(keepout
			(tracks allowed)
			(vias allowed)
			(pads allowed)
			(copperpour allowed)
			(footprints allowed)
		)
		(placement
			(enabled no)
			(sheetname "")
		)
		(fill
			(thermal_gap 0.5)
			(thermal_bridge_width 0.5)
			(island_removal_mode 0)
		)
		(polygon
			(pts
				(xy 45.122338 -398.161256) (xy 45.805344 -398.161256) (xy 45.878496 -398.088104) (xy 45.878496 -396.221458)
				(xy 45.753274 -396.096236) (xy 45.085508 -396.096236) (xy 44.981368 -396.200376) (xy 44.981368 -398.020286)
			)
		)
	)
	(zone
		(layer "B.Cu")
		(hatch none 0.5)
		(connect_pads
			(clearance 0)
		)
		(min_thickness 0.25)
		(keepout
			(tracks not_allowed)
			(vias allowed)
			(pads allowed)
			(copperpour not_allowed)
			(footprints allowed)
		)
		(placement
			(enabled no)
			(sheetname "")
		)
		(fill
			(thermal_gap 0.5)
			(thermal_bridge_width 0.5)
			(island_removal_mode 0)
		)
		(polygon
			(pts
				(arc
					(start 165.626288 -315.849762)
					(mid 164.973508 -315.849762)
					(end 165.626288 -315.849762)
				)
			)
		)
	)
	(zone
		(layer "B.Cu")
		(hatch none 0.5)
		(connect_pads
			(clearance 0)
		)
		(min_thickness 0.25)
		(keepout
			(tracks not_allowed)
			(vias allowed)
			(pads allowed)
			(copperpour not_allowed)
			(footprints allowed)
		)
		(placement
			(enabled no)
			(sheetname "")
		)
		(fill
			(thermal_gap 0.5)
			(thermal_bridge_width 0.5)
			(island_removal_mode 0)
		)
		(polygon
			(pts
				(arc
					(start 289.16503 -5.999988)
					(mid 284.16504 -0.999998)
					(end 279.16505 -5.999988)
				)
				(arc
					(start 279.16505 -5.999988)
					(mid 284.16504 -10.999978)
					(end 289.16503 -5.999988)
				)
			)
		)
	)
	(zone
		(layer "B.Cu")
		(hatch none 0.5)
		(connect_pads
			(clearance 0)
		)
		(min_thickness 0.25)
		(keepout
			(tracks not_allowed)
			(vias allowed)
			(pads allowed)
			(copperpour not_allowed)
			(footprints allowed)
		)
		(placement
			(enabled no)
			(sheetname "")
		)
		(fill
			(thermal_gap 0.5)
			(thermal_bridge_width 0.5)
			(island_removal_mode 0)
		)
		(polygon
			(pts
				(arc
					(start 30.489652 -405.390096)
					(mid 29.730192 -405.390096)
					(end 30.489652 -405.390096)
				)
			)
		)
	)
	(zone
		(layer "B.Cu")
		(hatch none 0.5)
		(connect_pads
			(clearance 0)
		)
		(min_thickness 0.25)
		(keepout
			(tracks not_allowed)
			(vias allowed)
			(pads allowed)
			(copperpour not_allowed)
			(footprints allowed)
		)
		(placement
			(enabled no)
			(sheetname "")
		)
		(fill
			(thermal_gap 0.5)
			(thermal_bridge_width 0.5)
			(island_removal_mode 0)
		)
		(polygon
			(pts
				(arc
					(start 13.800074 -194.360038)
					(mid 15.80007 -196.360034)
					(end 17.800066 -194.360038)
				)
				(arc
					(start 17.800066 -194.360038)
					(mid 15.80007 -192.360042)
					(end 13.800074 -194.360038)
				)
			)
		)
	)
	(zone
		(layer "B.Cu")
		(hatch none 0.5)
		(connect_pads
			(clearance 0)
		)
		(min_thickness 0.25)
		(keepout
			(tracks allowed)
			(vias allowed)
			(pads allowed)
			(copperpour allowed)
			(footprints allowed)
		)
		(placement
			(enabled no)
			(sheetname "")
		)
		(fill
			(thermal_gap 0.5)
			(thermal_bridge_width 0.5)
			(island_removal_mode 0)
		)
		(polygon
			(pts
				(xy 330.327 -83.82) (xy 330.327 -82.804) (xy 331.089 -82.804) (xy 331.089 -83.82)
			)
		)
	)
	(zone
		(layer "B.Cu")
		(hatch none 0.5)
		(connect_pads
			(clearance 0)
		)
		(min_thickness 0.25)
		(keepout
			(tracks not_allowed)
			(vias allowed)
			(pads allowed)
			(copperpour not_allowed)
			(footprints allowed)
		)
		(placement
			(enabled no)
			(sheetname "")
		)
		(fill
			(thermal_gap 0.5)
			(thermal_bridge_width 0.5)
			(island_removal_mode 0)
		)
		(polygon
			(pts
				(arc
					(start 233.004106 -87.4141)
					(mid 232.300526 -87.4141)
					(end 233.004106 -87.4141)
				)
			)
		)
	)
	(zone
		(layer "B.Cu")
		(hatch none 0.5)
		(connect_pads
			(clearance 0)
		)
		(min_thickness 0.25)
		(keepout
			(tracks not_allowed)
			(vias allowed)
			(pads allowed)
			(copperpour not_allowed)
			(footprints allowed)
		)
		(placement
			(enabled no)
			(sheetname "")
		)
		(fill
			(thermal_gap 0.5)
			(thermal_bridge_width 0.5)
			(island_removal_mode 0)
		)
		(polygon
			(pts
				(arc
					(start 129.489708 -370.489988)
					(mid 128.730248 -370.489988)
					(end 129.489708 -370.489988)
				)
			)
		)
	)
	(zone
		(layer "B.Cu")
		(hatch none 0.5)
		(connect_pads
			(clearance 0)
		)
		(min_thickness 0.25)
		(keepout
			(tracks not_allowed)
			(vias allowed)
			(pads allowed)
			(copperpour not_allowed)
			(footprints allowed)
		)
		(placement
			(enabled no)
			(sheetname "")
		)
		(fill
			(thermal_gap 0.5)
			(thermal_bridge_width 0.5)
			(island_removal_mode 0)
		)
		(polygon
			(pts
				(arc
					(start 161.826448 -315.849762)
					(mid 161.173668 -315.849762)
					(end 161.826448 -315.849762)
				)
			)
		)
	)
	(zone
		(layer "B.Cu")
		(hatch none 0.5)
		(connect_pads
			(clearance 0)
		)
		(min_thickness 0.25)
		(keepout
			(tracks not_allowed)
			(vias allowed)
			(pads allowed)
			(copperpour not_allowed)
			(footprints allowed)
		)
		(placement
			(enabled no)
			(sheetname "")
		)
		(fill
			(thermal_gap 0.5)
			(thermal_bridge_width 0.5)
			(island_removal_mode 0)
		)
		(polygon
			(pts
				(arc
					(start 324.099936 -270.89989)
					(mid 321.850004 -268.649958)
					(end 319.600072 -270.89989)
				)
				(arc
					(start 319.600072 -270.89989)
					(mid 321.850004 -273.149822)
					(end 324.099936 -270.89989)
				)
			)
		)
	)
	(zone
		(layer "B.Cu")
		(hatch none 0.5)
		(connect_pads
			(clearance 0)
		)
		(min_thickness 0.25)
		(keepout
			(tracks allowed)
			(vias allowed)
			(pads allowed)
			(copperpour allowed)
			(footprints not_allowed)
		)
		(placement
			(enabled no)
			(sheetname "")
		)
		(fill
			(thermal_gap 0.5)
			(thermal_bridge_width 0.5)
			(island_removal_mode 0)
		)
		(polygon
			(pts
				(arc
					(start 216.30005 -98.700082)
					(mid 208.300066 -90.700098)
					(end 200.300082 -98.700082)
				)
				(arc
					(start 200.300082 -98.700082)
					(mid 208.300066 -106.700066)
					(end 216.30005 -98.700082)
				)
			)
		)
	)
	(zone
		(layer "B.Cu")
		(hatch none 0.5)
		(connect_pads
			(clearance 0)
		)
		(min_thickness 0.25)
		(keepout
			(tracks not_allowed)
			(vias allowed)
			(pads allowed)
			(copperpour not_allowed)
			(footprints allowed)
		)
		(placement
			(enabled no)
			(sheetname "")
		)
		(fill
			(thermal_gap 0.5)
			(thermal_bridge_width 0.5)
			(island_removal_mode 0)
		)
		(polygon
			(pts
				(arc
					(start 39.289736 -405.390096)
					(mid 38.530276 -405.390096)
					(end 39.289736 -405.390096)
				)
			)
		)
	)
	(zone
		(layer "B.Cu")
		(hatch none 0.5)
		(connect_pads
			(clearance 0)
		)
		(min_thickness 0.25)
		(keepout
			(tracks not_allowed)
			(vias allowed)
			(pads allowed)
			(copperpour not_allowed)
			(footprints allowed)
		)
		(placement
			(enabled no)
			(sheetname "")
		)
		(fill
			(thermal_gap 0.5)
			(thermal_bridge_width 0.5)
			(island_removal_mode 0)
		)
		(polygon
			(pts
				(arc
					(start 421.576246 -317.749936)
					(mid 420.923466 -317.749936)
					(end 421.576246 -317.749936)
				)
			)
		)
	)
	(zone
		(layer "B.Cu")
		(hatch none 0.5)
		(connect_pads
			(clearance 0)
		)
		(min_thickness 0.25)
		(keepout
			(tracks not_allowed)
			(vias allowed)
			(pads allowed)
			(copperpour not_allowed)
			(footprints allowed)
		)
		(placement
			(enabled no)
			(sheetname "")
		)
		(fill
			(thermal_gap 0.5)
			(thermal_bridge_width 0.5)
			(island_removal_mode 0)
		)
		(polygon
			(pts
				(arc
					(start 347.09989 -72.69988)
					(mid 349.899986 -75.499976)
					(end 352.700082 -72.69988)
				)
				(arc
					(start 352.700082 -72.69988)
					(mid 349.899986 -69.899784)
					(end 347.09989 -72.69988)
				)
			)
		)
	)
	(zone
		(layer "B.Cu")
		(hatch none 0.5)
		(connect_pads
			(clearance 0)
		)
		(min_thickness 0.25)
		(keepout
			(tracks allowed)
			(vias allowed)
			(pads allowed)
			(copperpour allowed)
			(footprints allowed)
		)
		(placement
			(enabled no)
			(sheetname "")
		)
		(fill
			(thermal_gap 0.5)
			(thermal_bridge_width 0.5)
			(island_removal_mode 0)
		)
		(polygon
			(pts
				(xy 104.74579 -333.10957) (xy 107.722416 -333.10957) (xy 107.866688 -332.965298) (xy 107.866688 -330.050394)
				(xy 107.763818 -329.947524) (xy 104.735376 -329.947524) (xy 104.735376 -333.099156)
			)
		)
	)
	(zone
		(layer "B.Cu")
		(hatch none 0.5)
		(connect_pads
			(clearance 0)
		)
		(min_thickness 0.25)
		(keepout
			(tracks allowed)
			(vias allowed)
			(pads allowed)
			(copperpour allowed)
			(footprints allowed)
		)
		(placement
			(enabled no)
			(sheetname "")
		)
		(fill
			(thermal_gap 0.5)
			(thermal_bridge_width 0.5)
			(island_removal_mode 0)
		)
		(polygon
			(pts
				(xy 71.631302 -301.7774) (xy 73.333102 -301.7774) (xy 73.536302 -301.9806) (xy 73.536302 -302.2346)
				(xy 73.028302 -302.7426) (xy 71.453502 -302.7426) (xy 71.250302 -302.9458) (xy 71.250302 -307.0352)
				(xy 70.793102 -307.4924) (xy 59.998102 -307.4924) (xy 59.413902 -308.0766) (xy 59.413902 -320.4464)
				(xy 58.880502 -320.4464) (xy 58.753502 -320.3194) (xy 58.753502 -307.8988) (xy 59.617102 -307.0352)
				(xy 70.716902 -307.0352) (xy 70.818502 -306.9336) (xy 70.818502 -302.5902)
			)
		)
	)
	(zone
		(layer "B.Cu")
		(hatch none 0.5)
		(connect_pads
			(clearance 0)
		)
		(min_thickness 0.25)
		(keepout
			(tracks not_allowed)
			(vias allowed)
			(pads allowed)
			(copperpour not_allowed)
			(footprints allowed)
		)
		(placement
			(enabled no)
			(sheetname "")
		)
		(fill
			(thermal_gap 0.5)
			(thermal_bridge_width 0.5)
			(island_removal_mode 0)
		)
		(polygon
			(pts
				(arc
					(start 389.06958 -370.489988)
					(mid 388.31012 -370.489988)
					(end 389.06958 -370.489988)
				)
			)
		)
	)
	(zone
		(layer "B.Cu")
		(hatch none 0.5)
		(connect_pads
			(clearance 0)
		)
		(min_thickness 0.25)
		(keepout
			(tracks allowed)
			(vias allowed)
			(pads allowed)
			(copperpour allowed)
			(footprints allowed)
		)
		(placement
			(enabled no)
			(sheetname "")
		)
		(fill
			(thermal_gap 0.5)
			(thermal_bridge_width 0.5)
			(island_removal_mode 0)
		)
		(polygon
			(pts
				(xy 221.53626 -267.970762) (xy 221.53626 -265.811762) (xy 223.18726 -265.811762) (xy 223.18726 -267.970762)
			)
		)
	)
	(zone
		(layer "B.Cu")
		(hatch none 0.5)
		(connect_pads
			(clearance 0)
		)
		(min_thickness 0.25)
		(keepout
			(tracks allowed)
			(vias allowed)
			(pads allowed)
			(copperpour allowed)
			(footprints not_allowed)
		)
		(placement
			(enabled no)
			(sheetname "")
		)
		(fill
			(thermal_gap 0.5)
			(thermal_bridge_width 0.5)
			(island_removal_mode 0)
		)
		(polygon
			(pts
				(xy 49.649888 -84.68995) (xy 69.650102 -84.68995) (xy 69.650102 -64.68999) (xy 49.649888 -64.68999)
			)
		)
	)
	(zone
		(layer "B.Cu")
		(hatch none 0.5)
		(connect_pads
			(clearance 0)
		)
		(min_thickness 0.25)
		(keepout
			(tracks not_allowed)
			(vias allowed)
			(pads allowed)
			(copperpour not_allowed)
			(footprints allowed)
		)
		(placement
			(enabled no)
			(sheetname "")
		)
		(fill
			(thermal_gap 0.5)
			(thermal_bridge_width 0.5)
			(island_removal_mode 0)
		)
		(polygon
			(pts
				(arc
					(start 162.72002 -15.649956)
					(mid 160.720024 -13.64996)
					(end 158.720028 -15.649956)
				)
				(arc
					(start 158.720028 -15.649956)
					(mid 160.720024 -17.649952)
					(end 162.72002 -15.649956)
				)
			)
		)
	)
	(zone
		(layer "B.Cu")
		(hatch none 0.5)
		(connect_pads
			(clearance 0)
		)
		(min_thickness 0.25)
		(keepout
			(tracks allowed)
			(vias allowed)
			(pads allowed)
			(copperpour allowed)
			(footprints not_allowed)
		)
		(placement
			(enabled no)
			(sheetname "")
		)
		(fill
			(thermal_gap 0.5)
			(thermal_bridge_width 0.5)
			(island_removal_mode 0)
		)
		(polygon
			(pts
				(arc
					(start 20.964906 -17.999964)
					(mid 25.964896 -22.999954)
					(end 30.964886 -17.999964)
				)
				(arc
					(start 30.964886 -17.999964)
					(mid 25.964896 -12.999974)
					(end 20.964906 -17.999964)
				)
			)
		)
	)
	(zone
		(layer "B.Cu")
		(hatch none 0.5)
		(connect_pads
			(clearance 0)
		)
		(min_thickness 0.25)
		(keepout
			(tracks not_allowed)
			(vias allowed)
			(pads allowed)
			(copperpour not_allowed)
			(footprints allowed)
		)
		(placement
			(enabled no)
			(sheetname "")
		)
		(fill
			(thermal_gap 0.5)
			(thermal_bridge_width 0.5)
			(island_removal_mode 0)
		)
		(polygon
			(pts
				(arc
					(start 141.249908 -320.900044)
					(mid 145.750026 -325.400162)
					(end 150.24989 -320.900044)
				)
				(arc
					(start 150.24989 -320.900044)
					(mid 145.750026 -316.40018)
					(end 141.249908 -320.900044)
				)
			)
		)
	)
	(zone
		(layer "B.Cu")
		(hatch none 0.5)
		(connect_pads
			(clearance 0)
		)
		(min_thickness 0.25)
		(keepout
			(tracks allowed)
			(vias allowed)
			(pads allowed)
			(copperpour allowed)
			(footprints allowed)
		)
		(placement
			(enabled no)
			(sheetname "")
		)
		(fill
			(thermal_gap 0.5)
			(thermal_bridge_width 0.5)
			(island_removal_mode 0)
		)
		(polygon
			(pts
				(xy 187.7314 -301.7774) (xy 189.4332 -301.7774) (xy 189.6364 -301.9806) (xy 189.6364 -302.2346)
				(xy 189.1284 -302.7426) (xy 187.5536 -302.7426) (xy 187.3504 -302.9458) (xy 187.3504 -307.0352)
				(xy 186.8932 -307.4924) (xy 176.0982 -307.4924) (xy 175.514 -308.0766) (xy 175.514 -320.4464) (xy 174.9806 -320.4464)
				(xy 174.8536 -320.3194) (xy 174.8536 -307.8988) (xy 175.7172 -307.0352) (xy 186.817 -307.0352) (xy 186.9186 -306.9336)
				(xy 186.9186 -302.5902)
			)
		)
	)
	(zone
		(layer "B.Cu")
		(hatch none 0.5)
		(connect_pads
			(clearance 0)
		)
		(min_thickness 0.25)
		(keepout
			(tracks allowed)
			(vias allowed)
			(pads allowed)
			(copperpour allowed)
			(footprints not_allowed)
		)
		(placement
			(enabled no)
			(sheetname "")
		)
		(fill
			(thermal_gap 0.5)
			(thermal_bridge_width 0.5)
			(island_removal_mode 0)
		)
		(polygon
			(pts
				(xy 22.429978 -137.379964) (xy 42.429938 -137.379964) (xy 42.429938 -117.380004) (xy 22.429978 -117.380004)
			)
		)
	)
	(zone
		(layer "B.Cu")
		(hatch none 0.5)
		(connect_pads
			(clearance 0)
		)
		(min_thickness 0.25)
		(keepout
			(tracks allowed)
			(vias allowed)
			(pads allowed)
			(copperpour allowed)
			(footprints not_allowed)
		)
		(placement
			(enabled no)
			(sheetname "")
		)
		(fill
			(thermal_gap 0.5)
			(thermal_bridge_width 0.5)
			(island_removal_mode 0)
		)
		(polygon
			(pts
				(arc
					(start 395.264894 -5.999988)
					(mid 400.264884 -10.999978)
					(end 405.264874 -5.999988)
				)
				(arc
					(start 405.264874 -5.999988)
					(mid 400.264884 -0.999998)
					(end 395.264894 -5.999988)
				)
			)
		)
	)
	(zone
		(layer "B.Cu")
		(hatch none 0.5)
		(connect_pads
			(clearance 0)
		)
		(min_thickness 0.25)
		(keepout
			(tracks not_allowed)
			(vias allowed)
			(pads allowed)
			(copperpour not_allowed)
			(footprints allowed)
		)
		(placement
			(enabled no)
			(sheetname "")
		)
		(fill
			(thermal_gap 0.5)
			(thermal_bridge_width 0.5)
			(island_removal_mode 0)
		)
		(polygon
			(pts
				(arc
					(start 231.799892 -194.360038)
					(mid 233.799888 -196.360034)
					(end 235.799884 -194.360038)
				)
				(arc
					(start 235.799884 -194.360038)
					(mid 233.799888 -192.360042)
					(end 231.799892 -194.360038)
				)
			)
		)
	)
	(zone
		(layer "B.Cu")
		(hatch none 0.5)
		(connect_pads
			(clearance 0)
		)
		(min_thickness 0.25)
		(keepout
			(tracks not_allowed)
			(vias allowed)
			(pads allowed)
			(copperpour not_allowed)
			(footprints allowed)
		)
		(placement
			(enabled no)
			(sheetname "")
		)
		(fill
			(thermal_gap 0.5)
			(thermal_bridge_width 0.5)
			(island_removal_mode 0)
		)
		(polygon
			(pts
				(arc
					(start 386.869686 -402.790152)
					(mid 386.110226 -402.790152)
					(end 386.869686 -402.790152)
				)
			)
		)
	)
	(zone
		(layer "B.Cu")
		(hatch none 0.5)
		(connect_pads
			(clearance 0)
		)
		(min_thickness 0.25)
		(keepout
			(tracks not_allowed)
			(vias allowed)
			(pads allowed)
			(copperpour not_allowed)
			(footprints allowed)
		)
		(placement
			(enabled no)
			(sheetname "")
		)
		(fill
			(thermal_gap 0.5)
			(thermal_bridge_width 0.5)
			(island_removal_mode 0)
		)
		(polygon
			(pts
				(arc
					(start 162.776408 -318.699896)
					(mid 162.123628 -318.699896)
					(end 162.776408 -318.699896)
				)
			)
		)
	)
	(zone
		(layer "B.Cu")
		(hatch none 0.5)
		(connect_pads
			(clearance 0)
		)
		(min_thickness 0.25)
		(keepout
			(tracks not_allowed)
			(vias allowed)
			(pads allowed)
			(copperpour not_allowed)
			(footprints allowed)
		)
		(placement
			(enabled no)
			(sheetname "")
		)
		(fill
			(thermal_gap 0.5)
			(thermal_bridge_width 0.5)
			(island_removal_mode 0)
		)
		(polygon
			(pts
				(arc
					(start 314.026296 -304.449734)
					(mid 313.373516 -304.449734)
					(end 314.026296 -304.449734)
				)
			)
		)
	)
	(zone
		(layer "B.Cu")
		(hatch none 0.5)
		(connect_pads
			(clearance 0)
		)
		(min_thickness 0.25)
		(keepout
			(tracks not_allowed)
			(vias allowed)
			(pads allowed)
			(copperpour not_allowed)
			(footprints allowed)
		)
		(placement
			(enabled no)
			(sheetname "")
		)
		(fill
			(thermal_gap 0.5)
			(thermal_bridge_width 0.5)
			(island_removal_mode 0)
		)
		(polygon
			(pts
				(arc
					(start 347.214952 -17.999964)
					(mid 342.214962 -12.999974)
					(end 337.214972 -17.999964)
				)
				(arc
					(start 337.214972 -17.999964)
					(mid 342.214962 -22.999954)
					(end 347.214952 -17.999964)
				)
			)
		)
	)
	(zone
		(layer "B.Cu")
		(hatch none 0.5)
		(connect_pads
			(clearance 0)
		)
		(min_thickness 0.25)
		(keepout
			(tracks allowed)
			(vias allowed)
			(pads allowed)
			(copperpour allowed)
			(footprints allowed)
		)
		(placement
			(enabled no)
			(sheetname "")
		)
		(fill
			(thermal_gap 0.5)
			(thermal_bridge_width 0.5)
			(island_removal_mode 0)
		)
		(polygon
			(pts
				(xy 352.363024 -312.599578) (xy 354.014024 -312.599578) (xy 354.014024 -314.758578) (xy 352.363024 -314.758578)
			)
		)
	)
	(zone
		(layer "B.Cu")
		(hatch none 0.5)
		(connect_pads
			(clearance 0)
		)
		(min_thickness 0.25)
		(keepout
			(tracks not_allowed)
			(vias allowed)
			(pads allowed)
			(copperpour not_allowed)
			(footprints allowed)
		)
		(placement
			(enabled no)
			(sheetname "")
		)
		(fill
			(thermal_gap 0.5)
			(thermal_bridge_width 0.5)
			(island_removal_mode 0)
		)
		(polygon
			(pts
				(arc
					(start 260.999986 -98.700082)
					(mid 259.299964 -97.00006)
					(end 257.599942 -98.700082)
				)
				(arc
					(start 257.599942 -98.700082)
					(mid 259.299964 -100.400104)
					(end 260.999986 -98.700082)
				)
			)
		)
	)
	(zone
		(layer "B.Cu")
		(hatch none 0.5)
		(connect_pads
			(clearance 0)
		)
		(min_thickness 0.25)
		(keepout
			(tracks not_allowed)
			(vias allowed)
			(pads allowed)
			(copperpour not_allowed)
			(footprints allowed)
		)
		(placement
			(enabled no)
			(sheetname "")
		)
		(fill
			(thermal_gap 0.5)
			(thermal_bridge_width 0.5)
			(island_removal_mode 0)
		)
		(polygon
			(pts
				(arc
					(start 384.669792 -371.790214)
					(mid 383.910332 -371.790214)
					(end 384.669792 -371.790214)
				)
			)
		)
	)
	(zone
		(layer "B.Cu")
		(hatch none 0.5)
		(connect_pads
			(clearance 0)
		)
		(min_thickness 0.25)
		(keepout
			(tracks not_allowed)
			(vias allowed)
			(pads allowed)
			(copperpour not_allowed)
			(footprints allowed)
		)
		(placement
			(enabled no)
			(sheetname "")
		)
		(fill
			(thermal_gap 0.5)
			(thermal_bridge_width 0.5)
			(island_removal_mode 0)
		)
		(polygon
			(pts
				(arc
					(start 79.92618 -305.399948)
					(mid 79.2734 -305.399948)
					(end 79.92618 -305.399948)
				)
			)
		)
	)
	(zone
		(layer "B.Cu")
		(hatch none 0.5)
		(connect_pads
			(clearance 0)
		)
		(min_thickness 0.25)
		(keepout
			(tracks not_allowed)
			(vias allowed)
			(pads allowed)
			(copperpour not_allowed)
			(footprints allowed)
		)
		(placement
			(enabled no)
			(sheetname "")
		)
		(fill
			(thermal_gap 0.5)
			(thermal_bridge_width 0.5)
			(island_removal_mode 0)
		)
		(polygon
			(pts
				(arc
					(start 287.86963 -405.589994)
					(mid 287.11017 -405.589994)
					(end 287.86963 -405.589994)
				)
			)
		)
	)
	(zone
		(layer "B.Cu")
		(hatch none 0.5)
		(connect_pads
			(clearance 0)
		)
		(min_thickness 0.25)
		(keepout
			(tracks not_allowed)
			(vias allowed)
			(pads allowed)
			(copperpour not_allowed)
			(footprints allowed)
		)
		(placement
			(enabled no)
			(sheetname "")
		)
		(fill
			(thermal_gap 0.5)
			(thermal_bridge_width 0.5)
			(island_removal_mode 0)
		)
		(polygon
			(pts
				(arc
					(start 347.89999 -194.360038)
					(mid 349.899986 -196.360034)
					(end 351.899982 -194.360038)
				)
				(arc
					(start 351.899982 -194.360038)
					(mid 349.899986 -192.360042)
					(end 347.89999 -194.360038)
				)
			)
		)
	)
	(zone
		(layer "B.Cu")
		(hatch none 0.5)
		(connect_pads
			(clearance 0)
		)
		(min_thickness 0.25)
		(keepout
			(tracks not_allowed)
			(vias allowed)
			(pads allowed)
			(copperpour not_allowed)
			(footprints allowed)
		)
		(placement
			(enabled no)
			(sheetname "")
		)
		(fill
			(thermal_gap 0.5)
			(thermal_bridge_width 0.5)
			(island_removal_mode 0)
		)
		(polygon
			(pts
				(arc
					(start 20.619974 -15.649956)
					(mid 18.619978 -13.64996)
					(end 16.619982 -15.649956)
				)
				(arc
					(start 16.619982 -15.649956)
					(mid 18.619978 -17.649952)
					(end 20.619974 -15.649956)
				)
			)
		)
	)
	(zone
		(layer "B.Cu")
		(hatch none 0.5)
		(connect_pads
			(clearance 0)
		)
		(min_thickness 0.25)
		(keepout
			(tracks allowed)
			(vias allowed)
			(pads allowed)
			(copperpour allowed)
			(footprints allowed)
		)
		(placement
			(enabled no)
			(sheetname "")
		)
		(fill
			(thermal_gap 0.5)
			(thermal_bridge_width 0.5)
			(island_removal_mode 0)
		)
		(polygon
			(pts
				(xy 454.316338 -268.094206) (xy 454.316338 -265.935206) (xy 455.967338 -265.935206) (xy 455.967338 -268.094206)
			)
		)
	)
	(zone
		(layer "B.Cu")
		(hatch none 0.5)
		(connect_pads
			(clearance 0)
		)
		(min_thickness 0.25)
		(keepout
			(tracks allowed)
			(vias allowed)
			(pads allowed)
			(copperpour allowed)
			(footprints allowed)
		)
		(placement
			(enabled no)
			(sheetname "")
		)
		(fill
			(thermal_gap 0.5)
			(thermal_bridge_width 0.5)
			(island_removal_mode 0)
		)
		(polygon
			(pts
				(xy 457.618338 -268.094206) (xy 457.618338 -265.935206) (xy 459.396338 -265.935206) (xy 459.396338 -268.094206)
			)
		)
	)
	(zone
		(layer "B.Cu")
		(hatch none 0.5)
		(connect_pads
			(clearance 0)
		)
		(min_thickness 0.25)
		(keepout
			(tracks not_allowed)
			(vias allowed)
			(pads allowed)
			(copperpour not_allowed)
			(footprints allowed)
		)
		(placement
			(enabled no)
			(sheetname "")
		)
		(fill
			(thermal_gap 0.5)
			(thermal_bridge_width 0.5)
			(island_removal_mode 0)
		)
		(polygon
			(pts
				(arc
					(start 368.590068 -407.599896)
					(mid 363.590078 -402.599906)
					(end 358.590088 -407.599896)
				)
				(arc
					(start 358.590088 -407.599896)
					(mid 363.590078 -412.599886)
					(end 368.590068 -407.599896)
				)
			)
		)
	)
	(zone
		(layer "B.Cu")
		(hatch none 0.5)
		(connect_pads
			(clearance 0)
		)
		(min_thickness 0.25)
		(keepout
			(tracks not_allowed)
			(vias allowed)
			(pads allowed)
			(copperpour not_allowed)
			(footprints allowed)
		)
		(placement
			(enabled no)
			(sheetname "")
		)
		(fill
			(thermal_gap 0.5)
			(thermal_bridge_width 0.5)
			(island_removal_mode 0)
		)
		(polygon
			(pts
				(arc
					(start 460.04988 -15.200122)
					(mid 461.600042 -16.750284)
					(end 463.14995 -15.200122)
				)
				(arc
					(start 463.14995 -13.599922)
					(mid 461.600042 -12.050014)
					(end 460.04988 -13.599922)
				)
			)
		)
	)
	(zone
		(layer "B.Cu")
		(hatch none 0.5)
		(connect_pads
			(clearance 0)
		)
		(min_thickness 0.25)
		(keepout
			(tracks allowed)
			(vias allowed)
			(pads allowed)
			(copperpour allowed)
			(footprints allowed)
		)
		(placement
			(enabled no)
			(sheetname "")
		)
		(fill
			(thermal_gap 0.5)
			(thermal_bridge_width 0.5)
			(island_removal_mode 0)
		)
		(polygon
			(pts
				(xy 105.977944 -381.268732) (xy 105.977944 -379.532134) (xy 104.71658 -379.532134) (xy 104.71658 -381.268732)
			)
		)
	)
	(zone
		(layer "B.Cu")
		(hatch none 0.5)
		(connect_pads
			(clearance 0)
		)
		(min_thickness 0.25)
		(keepout
			(tracks not_allowed)
			(vias allowed)
			(pads allowed)
			(copperpour not_allowed)
			(footprints allowed)
		)
		(placement
			(enabled no)
			(sheetname "")
		)
		(fill
			(thermal_gap 0.5)
			(thermal_bridge_width 0.5)
			(island_removal_mode 0)
		)
		(polygon
			(pts
				(arc
					(start 394.97635 -318.699896)
					(mid 394.32357 -318.699896)
					(end 394.97635 -318.699896)
				)
			)
		)
	)
	(zone
		(layer "B.Cu")
		(hatch none 0.5)
		(connect_pads
			(clearance 0)
		)
		(min_thickness 0.25)
		(keepout
			(tracks not_allowed)
			(vias allowed)
			(pads allowed)
			(copperpour not_allowed)
			(footprints allowed)
		)
		(placement
			(enabled no)
			(sheetname "")
		)
		(fill
			(thermal_gap 0.5)
			(thermal_bridge_width 0.5)
			(island_removal_mode 0)
		)
		(polygon
			(pts
				(arc
					(start 301.069502 -378.290074)
					(mid 300.310042 -378.290074)
					(end 301.069502 -378.290074)
				)
			)
		)
	)
	(zone
		(layer "B.Cu")
		(hatch none 0.5)
		(connect_pads
			(clearance 0)
		)
		(min_thickness 0.25)
		(keepout
			(tracks allowed)
			(vias allowed)
			(pads allowed)
			(copperpour allowed)
			(footprints not_allowed)
		)
		(placement
			(enabled no)
			(sheetname "")
		)
		(fill
			(thermal_gap 0.5)
			(thermal_bridge_width 0.5)
			(island_removal_mode 0)
		)
		(polygon
			(pts
				(arc
					(start 263.19988 -393.100052)
					(mid 268.200124 -398.100296)
					(end 273.200114 -393.100052)
				)
				(arc
					(start 273.200114 -393.100052)
					(mid 268.200124 -388.100062)
					(end 263.19988 -393.100052)
				)
			)
		)
	)
	(zone
		(layer "B.Cu")
		(hatch none 0.5)
		(connect_pads
			(clearance 0)
		)
		(min_thickness 0.25)
		(keepout
			(tracks not_allowed)
			(vias allowed)
			(pads allowed)
			(copperpour not_allowed)
			(footprints allowed)
		)
		(placement
			(enabled no)
			(sheetname "")
		)
		(fill
			(thermal_gap 0.5)
			(thermal_bridge_width 0.5)
			(island_removal_mode 0)
		)
		(polygon
			(pts
				(arc
					(start 391.269728 -401.49018)
					(mid 390.510268 -401.49018)
					(end 391.269728 -401.49018)
				)
			)
		)
	)
	(zone
		(layer "B.Cu")
		(hatch none 0.5)
		(connect_pads
			(clearance 0)
		)
		(min_thickness 0.25)
		(keepout
			(tracks not_allowed)
			(vias allowed)
			(pads allowed)
			(copperpour not_allowed)
			(footprints allowed)
		)
		(placement
			(enabled no)
			(sheetname "")
		)
		(fill
			(thermal_gap 0.5)
			(thermal_bridge_width 0.5)
			(island_removal_mode 0)
		)
		(polygon
			(pts
				(xy 324.79996 -396.54988) (xy 314.79998 -396.54988) (xy 314.79998 -417.58997) (xy 324.79996 -417.58997)
			)
		)
	)
	(zone
		(layer "B.Cu")
		(hatch none 0.5)
		(connect_pads
			(clearance 0)
		)
		(min_thickness 0.25)
		(keepout
			(tracks allowed)
			(vias allowed)
			(pads allowed)
			(copperpour allowed)
			(footprints not_allowed)
		)
		(placement
			(enabled no)
			(sheetname "")
		)
		(fill
			(thermal_gap 0.5)
			(thermal_bridge_width 0.5)
			(island_removal_mode 0)
		)
		(polygon
			(pts
				(xy 158.530036 -117.380004) (xy 138.530076 -117.380004) (xy 138.530076 -137.379964) (xy 158.530036 -137.379964)
			)
		)
	)
	(zone
		(layer "B.Cu")
		(hatch none 0.5)
		(connect_pads
			(clearance 0)
		)
		(min_thickness 0.25)
		(keepout
			(tracks not_allowed)
			(vias allowed)
			(pads allowed)
			(copperpour not_allowed)
			(footprints allowed)
		)
		(placement
			(enabled no)
			(sheetname "")
		)
		(fill
			(thermal_gap 0.5)
			(thermal_bridge_width 0.5)
			(island_removal_mode 0)
		)
		(polygon
			(pts
				(xy 402.809964 -396.54988) (xy 412.809944 -396.54988) (xy 412.809944 -417.365434) (xy 402.809964 -417.365434)
			)
		)
	)
	(zone
		(layer "B.Cu")
		(hatch none 0.5)
		(connect_pads
			(clearance 0)
		)
		(min_thickness 0.25)
		(keepout
			(tracks not_allowed)
			(vias allowed)
			(pads allowed)
			(copperpour not_allowed)
			(footprints allowed)
		)
		(placement
			(enabled no)
			(sheetname "")
		)
		(fill
			(thermal_gap 0.5)
			(thermal_bridge_width 0.5)
			(island_removal_mode 0)
		)
		(polygon
			(pts
				(arc
					(start 301.069502 -404.290022)
					(mid 300.310042 -404.290022)
					(end 301.069502 -404.290022)
				)
			)
		)
	)
	(zone
		(layer "B.Cu")
		(hatch none 0.5)
		(connect_pads
			(clearance 0)
		)
		(min_thickness 0.25)
		(keepout
			(tracks allowed)
			(vias allowed)
			(pads allowed)
			(copperpour allowed)
			(footprints not_allowed)
		)
		(placement
			(enabled no)
			(sheetname "")
		)
		(fill
			(thermal_gap 0.5)
			(thermal_bridge_width 0.5)
			(island_removal_mode 0)
		)
		(polygon
			(pts
				(arc
					(start 228.799898 -194.360038)
					(mid 233.799888 -199.360028)
					(end 238.799878 -194.360038)
				)
				(arc
					(start 238.799878 -194.360038)
					(mid 233.799888 -189.360048)
					(end 228.799898 -194.360038)
				)
			)
		)
	)
	(zone
		(layer "B.Cu")
		(hatch none 0.5)
		(connect_pads
			(clearance 0)
		)
		(min_thickness 0.25)
		(keepout
			(tracks not_allowed)
			(vias allowed)
			(pads allowed)
			(copperpour not_allowed)
			(footprints allowed)
		)
		(placement
			(enabled no)
			(sheetname "")
		)
		(fill
			(thermal_gap 0.5)
			(thermal_bridge_width 0.5)
			(island_removal_mode 0)
		)
		(polygon
			(pts
				(arc
					(start 444.200026 -308.61)
					(mid 447.449956 -311.85993)
					(end 450.699886 -308.61)
				)
				(arc
					(start 450.699886 -308.61)
					(mid 447.449956 -305.36007)
					(end 444.200026 -308.61)
				)
			)
		)
	)
	(zone
		(layer "B.Cu")
		(hatch none 0.5)
		(connect_pads
			(clearance 0)
		)
		(min_thickness 0.25)
		(keepout
			(tracks not_allowed)
			(vias allowed)
			(pads allowed)
			(copperpour not_allowed)
			(footprints allowed)
		)
		(placement
			(enabled no)
			(sheetname "")
		)
		(fill
			(thermal_gap 0.5)
			(thermal_bridge_width 0.5)
			(island_removal_mode 0)
		)
		(polygon
			(pts
				(arc
					(start 314.026296 -306.349908)
					(mid 313.373516 -306.349908)
					(end 314.026296 -306.349908)
				)
			)
		)
	)
	(zone
		(layer "B.Cu")
		(hatch none 0.5)
		(connect_pads
			(clearance 0)
		)
		(min_thickness 0.25)
		(keepout
			(tracks not_allowed)
			(vias allowed)
			(pads allowed)
			(copperpour not_allowed)
			(footprints allowed)
		)
		(placement
			(enabled no)
			(sheetname "")
		)
		(fill
			(thermal_gap 0.5)
			(thermal_bridge_width 0.5)
			(island_removal_mode 0)
		)
		(polygon
			(pts
				(arc
					(start 440.200034 -320.900044)
					(mid 437.950102 -318.650112)
					(end 435.699916 -320.900044)
				)
				(arc
					(start 435.699916 -320.900044)
					(mid 437.950102 -323.15023)
					(end 440.200034 -320.900044)
				)
			)
		)
	)
	(zone
		(layer "B.Cu")
		(hatch none 0.5)
		(connect_pads
			(clearance 0)
		)
		(min_thickness 0.25)
		(keepout
			(tracks not_allowed)
			(vias allowed)
			(pads allowed)
			(copperpour not_allowed)
			(footprints allowed)
		)
		(placement
			(enabled no)
			(sheetname "")
		)
		(fill
			(thermal_gap 0.5)
			(thermal_bridge_width 0.5)
			(island_removal_mode 0)
		)
		(polygon
			(pts
				(arc
					(start 162.776408 -317.749936)
					(mid 162.123628 -317.749936)
					(end 162.776408 -317.749936)
				)
			)
		)
	)
	(zone
		(layer "B.Cu")
		(hatch none 0.5)
		(connect_pads
			(clearance 0)
		)
		(min_thickness 0.25)
		(keepout
			(tracks not_allowed)
			(vias allowed)
			(pads allowed)
			(copperpour not_allowed)
			(footprints allowed)
		)
		(placement
			(enabled no)
			(sheetname "")
		)
		(fill
			(thermal_gap 0.5)
			(thermal_bridge_width 0.5)
			(island_removal_mode 0)
		)
		(polygon
			(pts
				(arc
					(start 383.62001 -20.72005)
					(mid 381.620014 -18.720054)
					(end 379.620018 -20.72005)
				)
				(arc
					(start 379.620018 -20.72005)
					(mid 381.620014 -22.720046)
					(end 383.62001 -20.72005)
				)
			)
		)
	)
	(zone
		(layer "B.Cu")
		(hatch none 0.5)
		(connect_pads
			(clearance 0)
		)
		(min_thickness 0.25)
		(keepout
			(tracks allowed)
			(vias allowed)
			(pads allowed)
			(copperpour allowed)
			(footprints not_allowed)
		)
		(placement
			(enabled no)
			(sheetname "")
		)
		(fill
			(thermal_gap 0.5)
			(thermal_bridge_width 0.5)
			(island_removal_mode 0)
		)
		(polygon
			(pts
				(arc
					(start 212.989922 -311.179972)
					(mid 216.989914 -315.179964)
					(end 220.989906 -311.179972)
				)
				(arc
					(start 220.989906 -311.179972)
					(mid 216.989914 -307.17998)
					(end 212.989922 -311.179972)
				)
			)
		)
	)
	(zone
		(layer "B.Cu")
		(hatch none 0.5)
		(connect_pads
			(clearance 0)
		)
		(min_thickness 0.25)
		(keepout
			(tracks allowed)
			(vias allowed)
			(pads allowed)
			(copperpour allowed)
			(footprints not_allowed)
		)
		(placement
			(enabled no)
			(sheetname "")
		)
		(fill
			(thermal_gap 0.5)
			(thermal_bridge_width 0.5)
			(island_removal_mode 0)
		)
		(polygon
			(pts
				(arc
					(start 147.420076 -20.72005)
					(mid 149.420072 -22.720046)
					(end 151.420068 -20.72005)
				)
				(arc
					(start 151.420068 -20.72005)
					(mid 149.420072 -18.720054)
					(end 147.420076 -20.72005)
				)
			)
		)
	)
	(zone
		(layer "B.Cu")
		(hatch none 0.5)
		(connect_pads
			(clearance 0)
		)
		(min_thickness 0.25)
		(keepout
			(tracks allowed)
			(vias allowed)
			(pads allowed)
			(copperpour allowed)
			(footprints not_allowed)
		)
		(placement
			(enabled no)
			(sheetname "")
		)
		(fill
			(thermal_gap 0.5)
			(thermal_bridge_width 0.5)
			(island_removal_mode 0)
		)
		(polygon
			(pts
				(arc
					(start 279.16505 -5.999988)
					(mid 284.16504 -10.999978)
					(end 289.16503 -5.999988)
				)
				(arc
					(start 289.16503 -5.999988)
					(mid 284.16504 -0.999998)
					(end 279.16505 -5.999988)
				)
			)
		)
	)
	(zone
		(layer "B.Cu")
		(hatch none 0.5)
		(connect_pads
			(clearance 0)
		)
		(min_thickness 0.25)
		(keepout
			(tracks not_allowed)
			(vias allowed)
			(pads allowed)
			(copperpour not_allowed)
			(footprints allowed)
		)
		(placement
			(enabled no)
			(sheetname "")
		)
		(fill
			(thermal_gap 0.5)
			(thermal_bridge_width 0.5)
			(island_removal_mode 0)
		)
		(polygon
			(pts
				(arc
					(start 82.776314 -316.799722)
					(mid 82.123534 -316.799722)
					(end 82.776314 -316.799722)
				)
			)
		)
	)
	(zone
		(layer "B.Cu")
		(hatch none 0.5)
		(connect_pads
			(clearance 0)
		)
		(min_thickness 0.25)
		(keepout
			(tracks not_allowed)
			(vias allowed)
			(pads allowed)
			(copperpour not_allowed)
			(footprints allowed)
		)
		(placement
			(enabled no)
			(sheetname "")
		)
		(fill
			(thermal_gap 0.5)
			(thermal_bridge_width 0.5)
			(island_removal_mode 0)
		)
		(polygon
			(pts
				(arc
					(start 3.199892 -407.599896)
					(mid 5.999988 -410.399992)
					(end 8.800084 -407.599896)
				)
				(arc
					(start 8.800084 -407.599896)
					(mid 5.999988 -404.7998)
					(end 3.199892 -407.599896)
				)
			)
		)
	)
	(zone
		(layer "B.Cu")
		(hatch none 0.5)
		(connect_pads
			(clearance 0)
		)
		(min_thickness 0.25)
		(keepout
			(tracks allowed)
			(vias allowed)
			(pads allowed)
			(copperpour allowed)
			(footprints not_allowed)
		)
		(placement
			(enabled no)
			(sheetname "")
		)
		(fill
			(thermal_gap 0.5)
			(thermal_bridge_width 0.5)
			(island_removal_mode 0)
		)
		(polygon
			(pts
				(xy 460.520034 -302.64989) (xy 448.520058 -302.64989) (xy 448.520058 -314.65012) (xy 460.520034 -314.65012)
			)
		)
	)
	(zone
		(layer "B.Cu")
		(hatch none 0.5)
		(connect_pads
			(clearance 0)
		)
		(min_thickness 0.25)
		(keepout
			(tracks allowed)
			(vias allowed)
			(pads allowed)
			(copperpour allowed)
			(footprints not_allowed)
		)
		(placement
			(enabled no)
			(sheetname "")
		)
		(fill
			(thermal_gap 0.5)
			(thermal_bridge_width 0.5)
			(island_removal_mode 0)
		)
		(polygon
			(pts
				(arc
					(start 95.149924 -289.820096)
					(mid 99.149916 -293.820088)
					(end 103.149908 -289.820096)
				)
				(arc
					(start 103.149908 -289.820096)
					(mid 99.149916 -285.820104)
					(end 95.149924 -289.820096)
				)
			)
		)
	)
	(zone
		(layer "B.Cu")
		(hatch none 0.5)
		(connect_pads
			(clearance 0)
		)
		(min_thickness 0.25)
		(keepout
			(tracks not_allowed)
			(vias allowed)
			(pads allowed)
			(copperpour not_allowed)
			(footprints allowed)
		)
		(placement
			(enabled no)
			(sheetname "")
		)
		(fill
			(thermal_gap 0.5)
			(thermal_bridge_width 0.5)
			(island_removal_mode 0)
		)
		(polygon
			(pts
				(arc
					(start 264.100056 -270.89989)
					(mid 261.850124 -268.649958)
					(end 259.599938 -270.89989)
				)
				(arc
					(start 259.599938 -270.89989)
					(mid 261.850124 -273.150076)
					(end 264.100056 -270.89989)
				)
			)
		)
	)
	(zone
		(layer "B.Cu")
		(hatch none 0.5)
		(connect_pads
			(clearance 0)
		)
		(min_thickness 0.25)
		(keepout
			(tracks not_allowed)
			(vias allowed)
			(pads allowed)
			(copperpour not_allowed)
			(footprints allowed)
		)
		(placement
			(enabled no)
			(sheetname "")
		)
		(fill
			(thermal_gap 0.5)
			(thermal_bridge_width 0.5)
			(island_removal_mode 0)
		)
		(polygon
			(pts
				(arc
					(start 394.02639 -315.849762)
					(mid 393.37361 -315.849762)
					(end 394.02639 -315.849762)
				)
			)
		)
	)
	(zone
		(layer "B.Cu")
		(hatch none 0.5)
		(connect_pads
			(clearance 0)
		)
		(min_thickness 0.25)
		(keepout
			(tracks not_allowed)
			(vias allowed)
			(pads allowed)
			(copperpour not_allowed)
			(footprints allowed)
		)
		(placement
			(enabled no)
			(sheetname "")
		)
		(fill
			(thermal_gap 0.5)
			(thermal_bridge_width 0.5)
			(island_removal_mode 0)
		)
		(polygon
			(pts
				(arc
					(start 414.926272 -315.849762)
					(mid 414.273492 -315.849762)
					(end 414.926272 -315.849762)
				)
			)
		)
	)
	(zone
		(layer "B.Cu")
		(hatch none 0.5)
		(connect_pads
			(clearance 0)
		)
		(min_thickness 0.25)
		(keepout
			(tracks not_allowed)
			(vias allowed)
			(pads allowed)
			(copperpour not_allowed)
			(footprints allowed)
		)
		(placement
			(enabled no)
			(sheetname "")
		)
		(fill
			(thermal_gap 0.5)
			(thermal_bridge_width 0.5)
			(island_removal_mode 0)
		)
		(polygon
			(pts
				(arc
					(start 378.069602 -371.590062)
					(mid 377.310142 -371.590062)
					(end 378.069602 -371.590062)
				)
			)
		)
	)
	(zone
		(layer "B.Cu")
		(hatch none 0.5)
		(connect_pads
			(clearance 0)
		)
		(min_thickness 0.25)
		(keepout
			(tracks allowed)
			(vias allowed)
			(pads allowed)
			(copperpour allowed)
			(footprints allowed)
		)
		(placement
			(enabled no)
			(sheetname "")
		)
		(fill
			(thermal_gap 0.5)
			(thermal_bridge_width 0.5)
			(island_removal_mode 0)
		)
		(polygon
			(pts
				(xy 239.945418 -267.970762) (xy 239.945418 -265.811762) (xy 241.596418 -265.811762) (xy 241.596418 -267.970762)
			)
		)
	)
	(zone
		(layer "B.Cu")
		(hatch none 0.5)
		(connect_pads
			(clearance 0)
		)
		(min_thickness 0.25)
		(keepout
			(tracks not_allowed)
			(vias allowed)
			(pads allowed)
			(copperpour not_allowed)
			(footprints allowed)
		)
		(placement
			(enabled no)
			(sheetname "")
		)
		(fill
			(thermal_gap 0.5)
			(thermal_bridge_width 0.5)
			(island_removal_mode 0)
		)
		(polygon
			(pts
				(arc
					(start 313.076082 -305.399948)
					(mid 312.423302 -305.399948)
					(end 313.076082 -305.399948)
				)
			)
		)
	)
	(zone
		(layer "B.Cu")
		(hatch none 0.5)
		(connect_pads
			(clearance 0)
		)
		(min_thickness 0.25)
		(keepout
			(tracks allowed)
			(vias allowed)
			(pads allowed)
			(copperpour allowed)
			(footprints not_allowed)
		)
		(placement
			(enabled no)
			(sheetname "")
		)
		(fill
			(thermal_gap 0.5)
			(thermal_bridge_width 0.5)
			(island_removal_mode 0)
		)
		(polygon
			(pts
				(arc
					(start 466.499956 -406.604978)
					(mid 465.336454 -404.277689)
					(end 463.161126 -402.850096)
				)
				(arc
					(start 463.161126 -402.850096)
					(mid 465.336474 -401.422385)
					(end 466.499956 -399.09496)
				)
				(xy 466.600032 -399.09496) (xy 466.600032 -406.604978)
			)
		)
	)
	(zone
		(layer "B.Cu")
		(hatch none 0.5)
		(connect_pads
			(clearance 0)
		)
		(min_thickness 0.25)
		(keepout
			(tracks allowed)
			(vias allowed)
			(pads allowed)
			(copperpour allowed)
			(footprints not_allowed)
		)
		(placement
			(enabled no)
			(sheetname "")
		)
		(fill
			(thermal_gap 0.5)
			(thermal_bridge_width 0.5)
			(island_removal_mode 0)
		)
		(polygon
			(pts
				(xy 301.850044 -170.070018) (xy 281.850084 -170.070018) (xy 281.850084 -190.069978) (xy 301.850044 -190.069978)
			)
		)
	)
	(zone
		(layer "B.Cu")
		(hatch none 0.5)
		(connect_pads
			(clearance 0)
		)
		(min_thickness 0.25)
		(keepout
			(tracks allowed)
			(vias allowed)
			(pads allowed)
			(copperpour allowed)
			(footprints not_allowed)
		)
		(placement
			(enabled no)
			(sheetname "")
		)
		(fill
			(thermal_gap 0.5)
			(thermal_bridge_width 0.5)
			(island_removal_mode 0)
		)
		(polygon
			(pts
				(arc
					(start -0.500126 -311.410096)
					(mid 3.50012 -315.410342)
					(end 7.500112 -311.410096)
				)
				(arc
					(start 7.500112 -311.410096)
					(mid 3.50012 -307.410104)
					(end -0.500126 -311.410096)
				)
			)
		)
	)
	(zone
		(layer "B.Cu")
		(hatch none 0.5)
		(connect_pads
			(clearance 0)
		)
		(min_thickness 0.25)
		(keepout
			(tracks not_allowed)
			(vias allowed)
			(pads allowed)
			(copperpour not_allowed)
			(footprints allowed)
		)
		(placement
			(enabled no)
			(sheetname "")
		)
		(fill
			(thermal_gap 0.5)
			(thermal_bridge_width 0.5)
			(island_removal_mode 0)
		)
		(polygon
			(pts
				(arc
					(start 186.526424 -315.849762)
					(mid 185.873644 -315.849762)
					(end 186.526424 -315.849762)
				)
			)
		)
	)
	(zone
		(layer "B.Cu")
		(hatch none 0.5)
		(connect_pads
			(clearance 0)
		)
		(min_thickness 0.25)
		(keepout
			(tracks not_allowed)
			(vias allowed)
			(pads allowed)
			(copperpour not_allowed)
			(footprints allowed)
		)
		(placement
			(enabled no)
			(sheetname "")
		)
		(fill
			(thermal_gap 0.5)
			(thermal_bridge_width 0.5)
			(island_removal_mode 0)
		)
		(polygon
			(pts
				(arc
					(start 257.350006 -270.89989)
					(mid 261.850124 -275.400008)
					(end 266.349988 -270.89989)
				)
				(arc
					(start 266.349988 -270.89989)
					(mid 261.850124 -266.400026)
					(end 257.350006 -270.89989)
				)
			)
		)
		(polygon
			(pts
				(arc
					(start 264.199878 -270.89989)
					(mid 261.850124 -268.550136)
					(end 259.500116 -270.89989)
				)
				(arc
					(start 259.500116 -270.89989)
					(mid 261.850124 -273.249898)
					(end 264.199878 -270.89989)
				)
			)
		)
	)
	(zone
		(layer "B.Cu")
		(hatch none 0.5)
		(connect_pads
			(clearance 0)
		)
		(min_thickness 0.25)
		(keepout
			(tracks not_allowed)
			(vias allowed)
			(pads allowed)
			(copperpour not_allowed)
			(footprints allowed)
		)
		(placement
			(enabled no)
			(sheetname "")
		)
		(fill
			(thermal_gap 0.5)
			(thermal_bridge_width 0.5)
			(island_removal_mode 0)
		)
		(polygon
			(pts
				(arc
					(start 296.669714 -378.290074)
					(mid 295.910254 -378.290074)
					(end 296.669714 -378.290074)
				)
			)
		)
	)
	(zone
		(layer "B.Cu")
		(hatch none 0.5)
		(connect_pads
			(clearance 0)
		)
		(min_thickness 0.25)
		(keepout
			(tracks allowed)
			(vias allowed)
			(pads allowed)
			(copperpour allowed)
			(footprints not_allowed)
		)
		(placement
			(enabled no)
			(sheetname "")
		)
		(fill
			(thermal_gap 0.5)
			(thermal_bridge_width 0.5)
			(island_removal_mode 0)
		)
		(polygon
			(pts
				(xy 76.870052 -137.379964) (xy 96.870012 -137.379964) (xy 96.870012 -117.380004) (xy 76.870052 -117.380004)
			)
		)
	)
	(zone
		(layer "B.Cu")
		(hatch none 0.5)
		(connect_pads
			(clearance 0)
		)
		(min_thickness 0.25)
		(keepout
			(tracks not_allowed)
			(vias allowed)
			(pads allowed)
			(copperpour not_allowed)
			(footprints allowed)
		)
		(placement
			(enabled no)
			(sheetname "")
		)
		(fill
			(thermal_gap 0.5)
			(thermal_bridge_width 0.5)
			(island_removal_mode 0)
		)
		(polygon
			(pts
				(arc
					(start 80.87614 -317.749936)
					(mid 80.22336 -317.749936)
					(end 80.87614 -317.749936)
				)
			)
		)
	)
	(zone
		(layer "B.Cu")
		(hatch none 0.5)
		(connect_pads
			(clearance 0)
		)
		(min_thickness 0.25)
		(keepout
			(tracks allowed)
			(vias allowed)
			(pads allowed)
			(copperpour allowed)
			(footprints not_allowed)
		)
		(placement
			(enabled no)
			(sheetname "")
		)
		(fill
			(thermal_gap 0.5)
			(thermal_bridge_width 0.5)
			(island_removal_mode 0)
		)
		(polygon
			(pts
				(arc
					(start 31.319978 -20.72005)
					(mid 33.319974 -22.720046)
					(end 35.31997 -20.72005)
				)
				(arc
					(start 35.31997 -20.72005)
					(mid 33.319974 -18.720054)
					(end 31.319978 -20.72005)
				)
			)
		)
	)
	(zone
		(layer "B.Cu")
		(hatch none 0.5)
		(connect_pads
			(clearance 0)
		)
		(min_thickness 0.25)
		(keepout
			(tracks not_allowed)
			(vias allowed)
			(pads allowed)
			(copperpour not_allowed)
			(footprints allowed)
		)
		(placement
			(enabled no)
			(sheetname "")
		)
		(fill
			(thermal_gap 0.5)
			(thermal_bridge_width 0.5)
			(island_removal_mode 0)
		)
		(polygon
			(pts
				(arc
					(start 290.069524 -405.390096)
					(mid 289.310064 -405.390096)
					(end 290.069524 -405.390096)
				)
			)
		)
	)
	(zone
		(layer "B.Cu")
		(hatch none 0.5)
		(connect_pads
			(clearance 0)
		)
		(min_thickness 0.25)
		(keepout
			(tracks not_allowed)
			(vias allowed)
			(pads allowed)
			(copperpour not_allowed)
			(footprints allowed)
		)
		(placement
			(enabled no)
			(sheetname "")
		)
		(fill
			(thermal_gap 0.5)
			(thermal_bridge_width 0.5)
			(island_removal_mode 0)
		)
		(polygon
			(pts
				(arc
					(start 308.326282 -316.799722)
					(mid 307.673502 -316.799722)
					(end 308.326282 -316.799722)
				)
			)
		)
	)
	(zone
		(layer "B.Cu")
		(hatch none 0.5)
		(connect_pads
			(clearance 0)
		)
		(min_thickness 0.25)
		(keepout
			(tracks not_allowed)
			(vias allowed)
			(pads allowed)
			(copperpour not_allowed)
			(footprints allowed)
		)
		(placement
			(enabled no)
			(sheetname "")
		)
		(fill
			(thermal_gap 0.5)
			(thermal_bridge_width 0.5)
			(island_removal_mode 0)
		)
		(polygon
			(pts
				(arc
					(start 37.089842 -379.590046)
					(mid 36.330382 -379.590046)
					(end 37.089842 -379.590046)
				)
			)
		)
	)
	(zone
		(layer "B.Cu")
		(hatch none 0.5)
		(connect_pads
			(clearance 0)
		)
		(min_thickness 0.25)
		(keepout
			(tracks allowed)
			(vias allowed)
			(pads allowed)
			(copperpour allowed)
			(footprints allowed)
		)
		(placement
			(enabled no)
			(sheetname "")
		)
		(fill
			(thermal_gap 0.5)
			(thermal_bridge_width 0.5)
			(island_removal_mode 0)
		)
		(polygon
			(pts
				(xy 104.14 -321.945) (xy 104.14 -320.294) (xy 106.299 -320.294) (xy 106.299 -321.945)
			)
		)
	)
	(zone
		(layer "B.Cu")
		(hatch none 0.5)
		(connect_pads
			(clearance 0)
		)
		(min_thickness 0.25)
		(keepout
			(tracks allowed)
			(vias allowed)
			(pads allowed)
			(copperpour allowed)
			(footprints allowed)
		)
		(placement
			(enabled no)
			(sheetname "")
		)
		(fill
			(thermal_gap 0.5)
			(thermal_bridge_width 0.5)
			(island_removal_mode 0)
		)
		(polygon
			(pts
				(xy 6.477 -265.684) (xy 6.477 -263.525) (xy 8.128 -263.525) (xy 8.128 -265.684)
			)
		)
	)
	(zone
		(layer "B.Cu")
		(hatch none 0.5)
		(connect_pads
			(clearance 0)
		)
		(min_thickness 0.25)
		(keepout
			(tracks not_allowed)
			(vias allowed)
			(pads allowed)
			(copperpour not_allowed)
			(footprints allowed)
		)
		(placement
			(enabled no)
			(sheetname "")
		)
		(fill
			(thermal_gap 0.5)
			(thermal_bridge_width 0.5)
			(island_removal_mode 0)
		)
		(polygon
			(pts
				(arc
					(start 74.226166 -315.849762)
					(mid 73.573386 -315.849762)
					(end 74.226166 -315.849762)
				)
			)
		)
	)
	(zone
		(layer "B.Cu")
		(hatch none 0.5)
		(connect_pads
			(clearance 0)
		)
		(min_thickness 0.25)
		(keepout
			(tracks not_allowed)
			(vias allowed)
			(pads allowed)
			(copperpour not_allowed)
			(footprints allowed)
		)
		(placement
			(enabled no)
			(sheetname "")
		)
		(fill
			(thermal_gap 0.5)
			(thermal_bridge_width 0.5)
			(island_removal_mode 0)
		)
		(polygon
			(pts
				(arc
					(start 125.08992 -371.790214)
					(mid 124.33046 -371.790214)
					(end 125.08992 -371.790214)
				)
			)
		)
	)
	(zone
		(layer "B.Cu")
		(hatch none 0.5)
		(connect_pads
			(clearance 0)
		)
		(min_thickness 0.25)
		(keepout
			(tracks allowed)
			(vias allowed)
			(pads allowed)
			(copperpour allowed)
			(footprints not_allowed)
		)
		(placement
			(enabled no)
			(sheetname "")
		)
		(fill
			(thermal_gap 0.5)
			(thermal_bridge_width 0.5)
			(island_removal_mode 0)
		)
		(polygon
			(pts
				(arc
					(start 442.92012 -15.649956)
					(mid 444.920116 -17.649952)
					(end 446.920112 -15.649956)
				)
				(arc
					(start 446.920112 -15.649956)
					(mid 444.920116 -13.64996)
					(end 442.92012 -15.649956)
				)
			)
		)
	)
	(zone
		(layer "B.Cu")
		(hatch none 0.5)
		(connect_pads
			(clearance 0)
		)
		(min_thickness 0.25)
		(keepout
			(tracks allowed)
			(vias allowed)
			(pads allowed)
			(copperpour allowed)
			(footprints not_allowed)
		)
		(placement
			(enabled no)
			(sheetname "")
		)
		(fill
			(thermal_gap 0.5)
			(thermal_bridge_width 0.5)
			(island_removal_mode 0)
		)
		(polygon
			(pts
				(xy 155.24988 -280.399998) (xy 155.24988 -311.399936) (xy 196.250052 -311.399936) (xy 196.250052 -280.399998)
			)
		)
	)
	(zone
		(layer "B.Cu")
		(hatch none 0.5)
		(connect_pads
			(clearance 0)
		)
		(min_thickness 0.25)
		(keepout
			(tracks not_allowed)
			(vias allowed)
			(pads allowed)
			(copperpour not_allowed)
			(footprints allowed)
		)
		(placement
			(enabled no)
			(sheetname "")
		)
		(fill
			(thermal_gap 0.5)
			(thermal_bridge_width 0.5)
			(island_removal_mode 0)
		)
		(polygon
			(pts
				(arc
					(start 415.876232 -317.749936)
					(mid 415.223452 -317.749936)
					(end 415.876232 -317.749936)
				)
			)
		)
	)
	(zone
		(layer "B.Cu")
		(hatch none 0.5)
		(connect_pads
			(clearance 0)
		)
		(min_thickness 0.25)
		(keepout
			(tracks not_allowed)
			(vias allowed)
			(pads allowed)
			(copperpour not_allowed)
			(footprints allowed)
		)
		(placement
			(enabled no)
			(sheetname "")
		)
		(fill
			(thermal_gap 0.5)
			(thermal_bridge_width 0.5)
			(island_removal_mode 0)
		)
		(polygon
			(pts
				(arc
					(start 287.86963 -378.290074)
					(mid 287.11017 -378.290074)
					(end 287.86963 -378.290074)
				)
			)
		)
	)
	(zone
		(layer "B.Cu")
		(hatch none 0.5)
		(connect_pads
			(clearance 0)
		)
		(min_thickness 0.25)
		(keepout
			(tracks not_allowed)
			(vias allowed)
			(pads allowed)
			(copperpour not_allowed)
			(footprints allowed)
		)
		(placement
			(enabled no)
			(sheetname "")
		)
		(fill
			(thermal_gap 0.5)
			(thermal_bridge_width 0.5)
			(island_removal_mode 0)
		)
		(polygon
			(pts
				(arc
					(start 75.17638 -317.749936)
					(mid 74.5236 -317.749936)
					(end 75.17638 -317.749936)
				)
			)
		)
	)
	(zone
		(layer "B.Cu")
		(hatch none 0.5)
		(connect_pads
			(clearance 0)
		)
		(min_thickness 0.25)
		(keepout
			(tracks allowed)
			(vias allowed)
			(pads allowed)
			(copperpour allowed)
			(footprints not_allowed)
		)
		(placement
			(enabled no)
			(sheetname "")
		)
		(fill
			(thermal_gap 0.5)
			(thermal_bridge_width 0.5)
			(island_removal_mode 0)
		)
		(polygon
			(pts
				(arc
					(start 238.799878 -194.360038)
					(mid 233.799888 -189.360048)
					(end 228.799898 -194.360038)
				)
				(arc
					(start 228.799898 -194.360038)
					(mid 233.799888 -199.360028)
					(end 238.799878 -194.360038)
				)
			)
		)
	)
	(zone
		(layer "B.Cu")
		(hatch none 0.5)
		(connect_pads
			(clearance 0)
		)
		(min_thickness 0.25)
		(keepout
			(tracks not_allowed)
			(vias allowed)
			(pads allowed)
			(copperpour not_allowed)
			(footprints allowed)
		)
		(placement
			(enabled no)
			(sheetname "")
		)
		(fill
			(thermal_gap 0.5)
			(thermal_bridge_width 0.5)
			(island_removal_mode 0)
		)
		(polygon
			(pts
				(arc
					(start 296.669714 -404.290022)
					(mid 295.910254 -404.290022)
					(end 296.669714 -404.290022)
				)
			)
		)
	)
	(zone
		(layer "B.Cu")
		(hatch none 0.5)
		(connect_pads
			(clearance 0)
		)
		(min_thickness 0.25)
		(keepout
			(tracks allowed)
			(vias allowed)
			(pads allowed)
			(copperpour allowed)
			(footprints allowed)
		)
		(placement
			(enabled no)
			(sheetname "")
		)
		(fill
			(thermal_gap 0.5)
			(thermal_bridge_width 0.5)
			(island_removal_mode 0)
		)
		(polygon
			(pts
				(xy 88.777826 -397.94307) (xy 89.77376 -397.94307) (xy 89.909396 -397.807434) (xy 89.909396 -396.112492)
				(xy 89.805256 -396.008352) (xy 88.78824 -396.008352) (xy 88.464898 -396.331694) (xy 88.464898 -397.630142)
			)
		)
	)
	(zone
		(layer "B.Cu")
		(hatch none 0.5)
		(connect_pads
			(clearance 0)
		)
		(min_thickness 0.25)
		(keepout
			(tracks not_allowed)
			(vias allowed)
			(pads allowed)
			(copperpour not_allowed)
			(footprints allowed)
		)
		(placement
			(enabled no)
			(sheetname "")
		)
		(fill
			(thermal_gap 0.5)
			(thermal_bridge_width 0.5)
			(island_removal_mode 0)
		)
		(polygon
			(pts
				(arc
					(start 81.826354 -316.799722)
					(mid 81.173574 -316.799722)
					(end 81.826354 -316.799722)
				)
			)
		)
	)
	(zone
		(layer "B.Cu")
		(hatch none 0.5)
		(connect_pads
			(clearance 0)
		)
		(min_thickness 0.25)
		(keepout
			(tracks not_allowed)
			(vias allowed)
			(pads allowed)
			(copperpour not_allowed)
			(footprints allowed)
		)
		(placement
			(enabled no)
			(sheetname "")
		)
		(fill
			(thermal_gap 0.5)
			(thermal_bridge_width 0.5)
			(island_removal_mode 0)
		)
		(polygon
			(pts
				(arc
					(start 317.349886 -320.900044)
					(mid 321.850004 -325.400162)
					(end 326.350122 -320.900044)
				)
				(arc
					(start 326.350122 -320.900044)
					(mid 321.850004 -316.399926)
					(end 317.349886 -320.900044)
				)
			)
		)
	)
	(zone
		(layer "B.Cu")
		(hatch none 0.5)
		(connect_pads
			(clearance 0)
		)
		(min_thickness 0.25)
		(keepout
			(tracks not_allowed)
			(vias allowed)
			(pads allowed)
			(copperpour not_allowed)
			(footprints allowed)
		)
		(placement
			(enabled no)
			(sheetname "")
		)
		(fill
			(thermal_gap 0.5)
			(thermal_bridge_width 0.5)
			(island_removal_mode 0)
		)
		(polygon
			(pts
				(arc
					(start 239.365028 -85.169248)
					(mid 238.661448 -85.169248)
					(end 239.365028 -85.169248)
				)
			)
		)
	)
	(zone
		(layer "B.Cu")
		(hatch none 0.5)
		(connect_pads
			(clearance 0)
		)
		(min_thickness 0.25)
		(keepout
			(tracks not_allowed)
			(vias allowed)
			(pads allowed)
			(copperpour not_allowed)
			(footprints allowed)
		)
		(placement
			(enabled no)
			(sheetname "")
		)
		(fill
			(thermal_gap 0.5)
			(thermal_bridge_width 0.5)
			(island_removal_mode 0)
		)
		(polygon
			(pts
				(arc
					(start 398.77619 -317.749936)
					(mid 398.12341 -317.749936)
					(end 398.77619 -317.749936)
				)
			)
		)
	)
	(zone
		(layer "B.Cu")
		(hatch none 0.5)
		(connect_pads
			(clearance 0)
		)
		(min_thickness 0.25)
		(keepout
			(tracks allowed)
			(vias allowed)
			(pads allowed)
			(copperpour allowed)
			(footprints not_allowed)
		)
		(placement
			(enabled no)
			(sheetname "")
		)
		(fill
			(thermal_gap 0.5)
			(thermal_bridge_width 0.5)
			(island_removal_mode 0)
		)
		(polygon
			(pts
				(arc
					(start 364.920022 -15.649956)
					(mid 366.920018 -17.649952)
					(end 368.920014 -15.649956)
				)
				(arc
					(start 368.920014 -15.649956)
					(mid 366.920018 -13.64996)
					(end 364.920022 -15.649956)
				)
			)
		)
	)
	(zone
		(layer "B.Cu")
		(hatch none 0.5)
		(connect_pads
			(clearance 0)
		)
		(min_thickness 0.25)
		(keepout
			(tracks allowed)
			(vias allowed)
			(pads allowed)
			(copperpour allowed)
			(footprints not_allowed)
		)
		(placement
			(enabled no)
			(sheetname "")
		)
		(fill
			(thermal_gap 0.5)
			(thermal_bridge_width 0.5)
			(island_removal_mode 0)
		)
		(polygon
			(pts
				(xy 387.450076 -311.399936) (xy 428.449994 -311.399936) (xy 428.449994 -280.399998) (xy 387.450076 -280.399998)
			)
		)
	)
	(zone
		(layer "B.Cu")
		(hatch none 0.5)
		(connect_pads
			(clearance 0)
		)
		(min_thickness 0.25)
		(keepout
			(tracks not_allowed)
			(vias allowed)
			(pads allowed)
			(copperpour not_allowed)
			(footprints allowed)
		)
		(placement
			(enabled no)
			(sheetname "")
		)
		(fill
			(thermal_gap 0.5)
			(thermal_bridge_width 0.5)
			(island_removal_mode 0)
		)
		(polygon
			(pts
				(arc
					(start 39.289736 -380.69012)
					(mid 38.530276 -380.69012)
					(end 39.289736 -380.69012)
				)
			)
		)
	)
	(zone
		(layer "B.Cu")
		(hatch none 0.5)
		(connect_pads
			(clearance 0)
		)
		(min_thickness 0.25)
		(keepout
			(tracks not_allowed)
			(vias allowed)
			(pads allowed)
			(copperpour not_allowed)
			(footprints allowed)
		)
		(placement
			(enabled no)
			(sheetname "")
		)
		(fill
			(thermal_gap 0.5)
			(thermal_bridge_width 0.5)
			(island_removal_mode 0)
		)
		(polygon
			(pts
				(arc
					(start 313.076082 -307.299868)
					(mid 312.423302 -307.299868)
					(end 313.076082 -307.299868)
				)
			)
		)
	)
	(zone
		(layer "B.Cu")
		(hatch none 0.5)
		(connect_pads
			(clearance 0)
		)
		(min_thickness 0.25)
		(keepout
			(tracks not_allowed)
			(vias allowed)
			(pads allowed)
			(copperpour not_allowed)
			(footprints allowed)
		)
		(placement
			(enabled no)
			(sheetname "")
		)
		(fill
			(thermal_gap 0.5)
			(thermal_bridge_width 0.5)
			(island_removal_mode 0)
		)
		(polygon
			(pts
				(arc
					(start 418.726366 -316.799722)
					(mid 418.073586 -316.799722)
					(end 418.726366 -316.799722)
				)
			)
		)
	)
	(zone
		(layer "B.Cu")
		(hatch none 0.5)
		(connect_pads
			(clearance 0)
		)
		(min_thickness 0.25)
		(keepout
			(tracks allowed)
			(vias allowed)
			(pads allowed)
			(copperpour allowed)
			(footprints not_allowed)
		)
		(placement
			(enabled no)
			(sheetname "")
		)
		(fill
			(thermal_gap 0.5)
			(thermal_bridge_width 0.5)
			(island_removal_mode 0)
		)
		(polygon
			(pts
				(xy 425.170092 -137.379964) (xy 445.170052 -137.379964) (xy 445.170052 -117.380004) (xy 425.170092 -117.380004)
			)
		)
	)
	(zone
		(layer "B.Cu")
		(hatch none 0.5)
		(connect_pads
			(clearance 0)
		)
		(min_thickness 0.25)
		(keepout
			(tracks allowed)
			(vias allowed)
			(pads allowed)
			(copperpour allowed)
			(footprints allowed)
		)
		(placement
			(enabled no)
			(sheetname "")
		)
		(fill
			(thermal_gap 0.5)
			(thermal_bridge_width 0.5)
			(island_removal_mode 0)
		)
		(polygon
			(pts
				(xy 445.103758 -209.85353) (xy 445.103758 -207.922876) (xy 446.413636 -207.922876) (xy 446.413636 -209.85353)
			)
		)
	)
	(zone
		(layer "B.Cu")
		(hatch none 0.5)
		(connect_pads
			(clearance 0)
		)
		(min_thickness 0.25)
		(keepout
			(tracks allowed)
			(vias allowed)
			(pads allowed)
			(copperpour allowed)
			(footprints not_allowed)
		)
		(placement
			(enabled no)
			(sheetname "")
		)
		(fill
			(thermal_gap 0.5)
			(thermal_bridge_width 0.5)
			(island_removal_mode 0)
		)
		(polygon
			(pts
				(xy 42.429938 -117.380004) (xy 22.429978 -117.380004) (xy 22.429978 -137.379964) (xy 42.429938 -137.379964)
			)
		)
	)
	(zone
		(layer "B.Cu")
		(hatch none 0.5)
		(connect_pads
			(clearance 0)
		)
		(min_thickness 0.25)
		(keepout
			(tracks not_allowed)
			(vias allowed)
			(pads allowed)
			(copperpour not_allowed)
			(footprints allowed)
		)
		(placement
			(enabled no)
			(sheetname "")
		)
		(fill
			(thermal_gap 0.5)
			(thermal_bridge_width 0.5)
			(island_removal_mode 0)
		)
		(polygon
			(pts
				(arc
					(start 201.250042 -270.89989)
					(mid 205.75016 -275.400008)
					(end 210.250024 -270.89989)
				)
				(arc
					(start 210.250024 -270.89989)
					(mid 205.75016 -266.400026)
					(end 201.250042 -270.89989)
				)
			)
		)
	)
	(zone
		(layer "B.Cu")
		(hatch none 0.5)
		(connect_pads
			(clearance 0)
		)
		(min_thickness 0.25)
		(keepout
			(tracks not_allowed)
			(vias allowed)
			(pads allowed)
			(copperpour not_allowed)
			(footprints allowed)
		)
		(placement
			(enabled no)
			(sheetname "")
		)
		(fill
			(thermal_gap 0.5)
			(thermal_bridge_width 0.5)
			(island_removal_mode 0)
		)
		(polygon
			(pts
				(arc
					(start 151.420068 -20.72005)
					(mid 149.420072 -18.720054)
					(end 147.420076 -20.72005)
				)
				(arc
					(start 147.420076 -20.72005)
					(mid 149.420072 -22.720046)
					(end 151.420068 -20.72005)
				)
			)
		)
	)
	(zone
		(layer "B.Cu")
		(hatch none 0.5)
		(connect_pads
			(clearance 0)
		)
		(min_thickness 0.25)
		(keepout
			(tracks allowed)
			(vias allowed)
			(pads allowed)
			(copperpour allowed)
			(footprints allowed)
		)
		(placement
			(enabled no)
			(sheetname "")
		)
		(fill
			(thermal_gap 0.5)
			(thermal_bridge_width 0.5)
			(island_removal_mode 0)
		)
		(polygon
			(pts
				(xy 8.636 -265.684) (xy 8.636 -263.525) (xy 10.287 -263.525) (xy 10.287 -265.684)
			)
		)
	)
	(zone
		(layer "B.Cu")
		(hatch none 0.5)
		(connect_pads
			(clearance 0)
		)
		(min_thickness 0.25)
		(keepout
			(tracks allowed)
			(vias allowed)
			(pads allowed)
			(copperpour allowed)
			(footprints not_allowed)
		)
		(placement
			(enabled no)
			(sheetname "")
		)
		(fill
			(thermal_gap 0.5)
			(thermal_bridge_width 0.5)
			(island_removal_mode 0)
		)
		(polygon
			(pts
				(xy 96.870012 -117.380004) (xy 76.870052 -117.380004) (xy 76.870052 -137.379964) (xy 96.870012 -137.379964)
			)
		)
	)
	(zone
		(layer "B.Cu")
		(hatch none 0.5)
		(connect_pads
			(clearance 0)
		)
		(min_thickness 0.25)
		(keepout
			(tracks allowed)
			(vias allowed)
			(pads allowed)
			(copperpour allowed)
			(footprints not_allowed)
		)
		(placement
			(enabled no)
			(sheetname "")
		)
		(fill
			(thermal_gap 0.5)
			(thermal_bridge_width 0.5)
			(island_removal_mode 0)
		)
		(polygon
			(pts
				(arc
					(start 327.35012 -289.820096)
					(mid 331.350112 -293.820088)
					(end 335.350104 -289.820096)
				)
				(arc
					(start 335.350104 -289.820096)
					(mid 331.350112 -285.820104)
					(end 327.35012 -289.820096)
				)
			)
		)
	)
	(zone
		(layer "B.Cu")
		(hatch none 0.5)
		(connect_pads
			(clearance 0)
		)
		(min_thickness 0.25)
		(keepout
			(tracks not_allowed)
			(vias allowed)
			(pads allowed)
			(copperpour not_allowed)
			(footprints allowed)
		)
		(placement
			(enabled no)
			(sheetname "")
		)
		(fill
			(thermal_gap 0.5)
			(thermal_bridge_width 0.5)
			(island_removal_mode 0)
		)
		(polygon
			(pts
				(arc
					(start 78.02626 -316.799722)
					(mid 77.37348 -316.799722)
					(end 78.02626 -316.799722)
				)
			)
		)
	)
	(zone
		(layer "B.Cu")
		(hatch none 0.5)
		(connect_pads
			(clearance 0)
		)
		(min_thickness 0.25)
		(keepout
			(tracks not_allowed)
			(vias allowed)
			(pads allowed)
			(copperpour not_allowed)
			(footprints allowed)
		)
		(placement
			(enabled no)
			(sheetname "")
		)
		(fill
			(thermal_gap 0.5)
			(thermal_bridge_width 0.5)
			(island_removal_mode 0)
		)
		(polygon
			(pts
				(arc
					(start 41.48963 -378.290074)
					(mid 40.73017 -378.290074)
					(end 41.48963 -378.290074)
				)
			)
		)
	)
	(zone
		(layer "B.Cu")
		(hatch none 0.5)
		(connect_pads
			(clearance 0)
		)
		(min_thickness 0.25)
		(keepout
			(tracks not_allowed)
			(vias allowed)
			(pads allowed)
			(copperpour not_allowed)
			(footprints allowed)
		)
		(placement
			(enabled no)
			(sheetname "")
		)
		(fill
			(thermal_gap 0.5)
			(thermal_bridge_width 0.5)
			(island_removal_mode 0)
		)
		(polygon
			(pts
				(arc
					(start 281.364944 -5.999988)
					(mid 284.16504 -8.800084)
					(end 286.964882 -5.999988)
				)
				(arc
					(start 286.964882 -5.999988)
					(mid 284.16504 -3.200146)
					(end 281.364944 -5.999988)
				)
			)
		)
	)
	(zone
		(layer "B.Cu")
		(hatch none 0.5)
		(connect_pads
			(clearance 0)
		)
		(min_thickness 0.25)
		(keepout
			(tracks not_allowed)
			(vias allowed)
			(pads allowed)
			(copperpour not_allowed)
			(footprints allowed)
		)
		(placement
			(enabled no)
			(sheetname "")
		)
		(fill
			(thermal_gap 0.5)
			(thermal_bridge_width 0.5)
			(island_removal_mode 0)
		)
		(polygon
			(pts
				(arc
					(start 85.149944 -270.89989)
					(mid 89.650062 -275.400008)
					(end 94.149926 -270.89989)
				)
				(arc
					(start 94.149926 -270.89989)
					(mid 89.650062 -266.400026)
					(end 85.149944 -270.89989)
				)
			)
		)
	)
	(zone
		(layer "B.Cu")
		(hatch none 0.5)
		(connect_pads
			(clearance 0)
		)
		(min_thickness 0.25)
		(keepout
			(tracks not_allowed)
			(vias allowed)
			(pads allowed)
			(copperpour not_allowed)
			(footprints allowed)
		)
		(placement
			(enabled no)
			(sheetname "")
		)
		(fill
			(thermal_gap 0.5)
			(thermal_bridge_width 0.5)
			(island_removal_mode 0)
		)
		(polygon
			(pts
				(arc
					(start 249.102372 -297.372024)
					(mid 252.352302 -300.621954)
					(end 255.602232 -297.372024)
				)
				(arc
					(start 255.602232 -297.372024)
					(mid 252.352302 -294.122094)
					(end 249.102372 -297.372024)
				)
			)
		)
	)
	(zone
		(layer "B.Cu")
		(hatch none 0.5)
		(connect_pads
			(clearance 0)
		)
		(min_thickness 0.25)
		(keepout
			(tracks not_allowed)
			(vias allowed)
			(pads allowed)
			(copperpour not_allowed)
			(footprints allowed)
		)
		(placement
			(enabled no)
			(sheetname "")
		)
		(fill
			(thermal_gap 0.5)
			(thermal_bridge_width 0.5)
			(island_removal_mode 0)
		)
		(polygon
			(pts
				(arc
					(start 292.269672 -405.589994)
					(mid 291.510212 -405.589994)
					(end 292.269672 -405.589994)
				)
			)
		)
	)
	(zone
		(layer "B.Cu")
		(hatch none 0.5)
		(connect_pads
			(clearance 0)
		)
		(min_thickness 0.25)
		(keepout
			(tracks not_allowed)
			(vias allowed)
			(pads allowed)
			(copperpour not_allowed)
			(footprints allowed)
		)
		(placement
			(enabled no)
			(sheetname "")
		)
		(fill
			(thermal_gap 0.5)
			(thermal_bridge_width 0.5)
			(island_removal_mode 0)
		)
		(polygon
			(pts
				(arc
					(start 204.399896 -393.100052)
					(mid 199.399906 -388.100062)
					(end 194.399916 -393.100052)
				)
				(arc
					(start 194.399916 -393.100052)
					(mid 199.399906 -398.100042)
					(end 204.399896 -393.100052)
				)
			)
		)
	)
	(zone
		(layer "B.Cu")
		(hatch none 0.5)
		(connect_pads
			(clearance 0)
		)
		(min_thickness 0.25)
		(keepout
			(tracks not_allowed)
			(vias allowed)
			(pads allowed)
			(copperpour not_allowed)
			(footprints allowed)
		)
		(placement
			(enabled no)
			(sheetname "")
		)
		(fill
			(thermal_gap 0.5)
			(thermal_bridge_width 0.5)
			(island_removal_mode 0)
		)
		(polygon
			(pts
				(arc
					(start 254.299974 -98.700082)
					(mid 259.299964 -103.700072)
					(end 264.299954 -98.700082)
				)
				(arc
					(start 264.299954 -98.700082)
					(mid 259.299964 -93.700092)
					(end 254.299974 -98.700082)
				)
			)
		)
		(polygon
			(pts
				(arc
					(start 260.999986 -98.700082)
					(mid 259.299964 -97.00006)
					(end 257.599942 -98.700082)
				)
				(arc
					(start 257.599942 -98.700082)
					(mid 259.299964 -100.400104)
					(end 260.999986 -98.700082)
				)
			)
		)
	)
	(zone
		(layer "B.Cu")
		(hatch none 0.5)
		(connect_pads
			(clearance 0)
		)
		(min_thickness 0.25)
		(keepout
			(tracks not_allowed)
			(vias allowed)
			(pads allowed)
			(copperpour not_allowed)
			(footprints allowed)
		)
		(placement
			(enabled no)
			(sheetname "")
		)
		(fill
			(thermal_gap 0.5)
			(thermal_bridge_width 0.5)
			(island_removal_mode 0)
		)
		(polygon
			(pts
				(arc
					(start 76.12634 -315.849762)
					(mid 75.47356 -315.849762)
					(end 76.12634 -315.849762)
				)
			)
		)
	)
	(zone
		(layer "B.Cu")
		(hatch none 0.5)
		(connect_pads
			(clearance 0)
		)
		(min_thickness 0.25)
		(keepout
			(tracks not_allowed)
			(vias allowed)
			(pads allowed)
			(copperpour not_allowed)
			(footprints allowed)
		)
		(placement
			(enabled no)
			(sheetname "")
		)
		(fill
			(thermal_gap 0.5)
			(thermal_bridge_width 0.5)
			(island_removal_mode 0)
		)
		(polygon
			(pts
				(arc
					(start 328.099928 -289.820096)
					(mid 331.350112 -293.07028)
					(end 334.600042 -289.820096)
				)
				(arc
					(start 334.600042 -289.820096)
					(mid 331.350112 -286.570166)
					(end 328.099928 -289.820096)
				)
			)
		)
	)
	(zone
		(layer "B.Cu")
		(hatch none 0.5)
		(connect_pads
			(clearance 0)
		)
		(min_thickness 0.25)
		(keepout
			(tracks allowed)
			(vias allowed)
			(pads allowed)
			(copperpour allowed)
			(footprints not_allowed)
		)
		(placement
			(enabled no)
			(sheetname "")
		)
		(fill
			(thermal_gap 0.5)
			(thermal_bridge_width 0.5)
			(island_removal_mode 0)
		)
		(polygon
			(pts
				(arc
					(start 399.800064 -407.960068)
					(mid 407.800048 -415.960052)
					(end 415.800032 -407.960068)
				)
				(arc
					(start 415.800032 -407.960068)
					(mid 407.800048 -399.960084)
					(end 399.800064 -407.960068)
				)
			)
		)
	)
	(zone
		(layer "B.Cu")
		(hatch none 0.5)
		(connect_pads
			(clearance 0)
		)
		(min_thickness 0.25)
		(keepout
			(tracks not_allowed)
			(vias allowed)
			(pads allowed)
			(copperpour not_allowed)
			(footprints allowed)
		)
		(placement
			(enabled no)
			(sheetname "")
		)
		(fill
			(thermal_gap 0.5)
			(thermal_bridge_width 0.5)
			(island_removal_mode 0)
		)
		(polygon
			(pts
				(arc
					(start 78.02626 -315.849762)
					(mid 77.37348 -315.849762)
					(end 78.02626 -315.849762)
				)
			)
		)
	)
	(zone
		(layer "B.Cu")
		(hatch none 0.5)
		(connect_pads
			(clearance 0)
		)
		(min_thickness 0.25)
		(keepout
			(tracks allowed)
			(vias allowed)
			(pads allowed)
			(copperpour allowed)
			(footprints not_allowed)
		)
		(placement
			(enabled no)
			(sheetname "")
		)
		(fill
			(thermal_gap 0.5)
			(thermal_bridge_width 0.5)
			(island_removal_mode 0)
		)
		(polygon
			(pts
				(arc
					(start 68.619878 -15.649956)
					(mid 70.620128 -17.650206)
					(end 72.620124 -15.649956)
				)
				(arc
					(start 72.620124 -15.649956)
					(mid 70.620128 -13.64996)
					(end 68.619878 -15.649956)
				)
			)
		)
	)
	(zone
		(layer "B.Cu")
		(hatch none 0.5)
		(connect_pads
			(clearance 0)
		)
		(min_thickness 0.25)
		(keepout
			(tracks not_allowed)
			(vias allowed)
			(pads allowed)
			(copperpour not_allowed)
			(footprints allowed)
		)
		(placement
			(enabled no)
			(sheetname "")
		)
		(fill
			(thermal_gap 0.5)
			(thermal_bridge_width 0.5)
			(island_removal_mode 0)
		)
		(polygon
			(pts
				(arc
					(start 213.300056 -98.700082)
					(mid 208.300066 -93.700092)
					(end 203.300076 -98.700082)
				)
				(arc
					(start 203.300076 -98.700082)
					(mid 208.300066 -103.700072)
					(end 213.300056 -98.700082)
				)
			)
		)
	)
	(zone
		(layer "B.Cu")
		(hatch none 0.5)
		(connect_pads
			(clearance 0)
		)
		(min_thickness 0.25)
		(keepout
			(tracks not_allowed)
			(vias allowed)
			(pads allowed)
			(copperpour not_allowed)
			(footprints allowed)
		)
		(placement
			(enabled no)
			(sheetname "")
		)
		(fill
			(thermal_gap 0.5)
			(thermal_bridge_width 0.5)
			(island_removal_mode 0)
		)
		(polygon
			(pts
				(arc
					(start 458.799946 -407.599896)
					(mid 461.600042 -410.399992)
					(end 464.399884 -407.599896)
				)
				(arc
					(start 464.399884 -407.599896)
					(mid 461.600042 -404.800054)
					(end 458.799946 -407.599896)
				)
			)
		)
	)
	(zone
		(layer "B.Cu")
		(hatch none 0.5)
		(connect_pads
			(clearance 0)
		)
		(min_thickness 0.25)
		(keepout
			(tracks not_allowed)
			(vias allowed)
			(pads allowed)
			(copperpour not_allowed)
			(footprints allowed)
		)
		(placement
			(enabled no)
			(sheetname "")
		)
		(fill
			(thermal_gap 0.5)
			(thermal_bridge_width 0.5)
			(island_removal_mode 0)
		)
		(polygon
			(pts
				(arc
					(start 114.899948 -194.360038)
					(mid 117.700044 -197.160134)
					(end 120.499886 -194.360038)
				)
				(arc
					(start 120.499886 -194.360038)
					(mid 117.700044 -191.560196)
					(end 114.899948 -194.360038)
				)
			)
		)
	)
	(zone
		(layer "B.Cu")
		(hatch none 0.5)
		(connect_pads
			(clearance 0)
		)
		(min_thickness 0.25)
		(keepout
			(tracks not_allowed)
			(vias allowed)
			(pads allowed)
			(copperpour not_allowed)
			(footprints allowed)
		)
		(placement
			(enabled no)
			(sheetname "")
		)
		(fill
			(thermal_gap 0.5)
			(thermal_bridge_width 0.5)
			(island_removal_mode 0)
		)
		(polygon
			(pts
				(arc
					(start 54.699916 -367.653062)
					(mid 53.996336 -367.653062)
					(end 54.699916 -367.653062)
				)
			)
		)
	)
	(zone
		(layer "B.Cu")
		(hatch none 0.5)
		(connect_pads
			(clearance 0)
		)
		(min_thickness 0.25)
		(keepout
			(tracks not_allowed)
			(vias allowed)
			(pads allowed)
			(copperpour not_allowed)
			(footprints allowed)
		)
		(placement
			(enabled no)
			(sheetname "")
		)
		(fill
			(thermal_gap 0.5)
			(thermal_bridge_width 0.5)
			(island_removal_mode 0)
		)
		(polygon
			(pts
				(arc
					(start 309.276242 -317.749936)
					(mid 308.623462 -317.749936)
					(end 309.276242 -317.749936)
				)
			)
		)
	)
	(zone
		(layer "B.Cu")
		(hatch none 0.5)
		(connect_pads
			(clearance 0)
		)
		(min_thickness 0.25)
		(keepout
			(tracks not_allowed)
			(vias allowed)
			(pads allowed)
			(copperpour not_allowed)
			(footprints allowed)
		)
		(placement
			(enabled no)
			(sheetname "")
		)
		(fill
			(thermal_gap 0.5)
			(thermal_bridge_width 0.5)
			(island_removal_mode 0)
		)
		(polygon
			(pts
				(arc
					(start 131.689856 -401.49018)
					(mid 130.930396 -401.49018)
					(end 131.689856 -401.49018)
				)
			)
		)
	)
	(zone
		(layer "B.Cu")
		(hatch none 0.5)
		(connect_pads
			(clearance 0)
		)
		(min_thickness 0.25)
		(keepout
			(tracks allowed)
			(vias allowed)
			(pads allowed)
			(copperpour allowed)
			(footprints not_allowed)
		)
		(placement
			(enabled no)
			(sheetname "")
		)
		(fill
			(thermal_gap 0.5)
			(thermal_bridge_width 0.5)
			(island_removal_mode 0)
		)
		(polygon
			(pts
				(arc
					(start 431.619914 -20.72005)
					(mid 433.61991 -22.720046)
					(end 435.619906 -20.72005)
				)
				(arc
					(start 435.619906 -20.72005)
					(mid 433.61991 -18.720054)
					(end 431.619914 -20.72005)
				)
			)
		)
	)
	(zone
		(layer "B.Cu")
		(hatch none 0.5)
		(connect_pads
			(clearance 0)
		)
		(min_thickness 0.25)
		(keepout
			(tracks not_allowed)
			(vias allowed)
			(pads allowed)
			(copperpour not_allowed)
			(footprints allowed)
		)
		(placement
			(enabled no)
			(sheetname "")
		)
		(fill
			(thermal_gap 0.5)
			(thermal_bridge_width 0.5)
			(island_removal_mode 0)
		)
		(polygon
			(pts
				(arc
					(start 32.6898 -404.290022)
					(mid 31.93034 -404.290022)
					(end 32.6898 -404.290022)
				)
			)
		)
	)
	(zone
		(layer "B.Cu")
		(hatch none 0.5)
		(connect_pads
			(clearance 0)
		)
		(min_thickness 0.25)
		(keepout
			(tracks allowed)
			(vias allowed)
			(pads allowed)
			(copperpour allowed)
			(footprints allowed)
		)
		(placement
			(enabled no)
			(sheetname "")
		)
		(fill
			(thermal_gap 0.5)
			(thermal_bridge_width 0.5)
			(island_removal_mode 0)
		)
		(polygon
			(pts
				(xy 223.69526 -267.970762) (xy 223.69526 -265.811762) (xy 225.34626 -265.811762) (xy 225.34626 -267.970762)
			)
		)
	)
	(zone
		(layer "B.Cu")
		(hatch none 0.5)
		(connect_pads
			(clearance 0)
		)
		(min_thickness 0.25)
		(keepout
			(tracks allowed)
			(vias allowed)
			(pads allowed)
			(copperpour allowed)
			(footprints not_allowed)
		)
		(placement
			(enabled no)
			(sheetname "")
		)
		(fill
			(thermal_gap 0.5)
			(thermal_bridge_width 0.5)
			(island_removal_mode 0)
		)
		(polygon
			(pts
				(arc
					(start 210.719924 -15.649956)
					(mid 212.71992 -17.649952)
					(end 214.719916 -15.649956)
				)
				(arc
					(start 214.719916 -15.649956)
					(mid 212.71992 -13.64996)
					(end 210.719924 -15.649956)
				)
			)
		)
	)
	(zone
		(layer "B.Cu")
		(hatch none 0.5)
		(connect_pads
			(clearance 0)
		)
		(min_thickness 0.25)
		(keepout
			(tracks allowed)
			(vias allowed)
			(pads allowed)
			(copperpour allowed)
			(footprints allowed)
		)
		(placement
			(enabled no)
			(sheetname "")
		)
		(fill
			(thermal_gap 0.5)
			(thermal_bridge_width 0.5)
			(island_removal_mode 0)
		)
		(polygon
			(pts
				(xy 363.479842 -316.891924) (xy 363.479842 -318.542924) (xy 361.320842 -318.542924) (xy 361.320842 -316.891924)
			)
		)
	)
	(zone
		(layer "B.Cu")
		(hatch none 0.5)
		(connect_pads
			(clearance 0)
		)
		(min_thickness 0.25)
		(keepout
			(tracks not_allowed)
			(vias allowed)
			(pads allowed)
			(copperpour not_allowed)
			(footprints allowed)
		)
		(placement
			(enabled no)
			(sheetname "")
		)
		(fill
			(thermal_gap 0.5)
			(thermal_bridge_width 0.5)
			(island_removal_mode 0)
		)
		(polygon
			(pts
				(arc
					(start 165.626288 -316.799722)
					(mid 164.973508 -316.799722)
					(end 165.626288 -316.799722)
				)
			)
		)
	)
	(zone
		(layer "B.Cu")
		(hatch none 0.5)
		(connect_pads
			(clearance 0)
		)
		(min_thickness 0.25)
		(keepout
			(tracks allowed)
			(vias allowed)
			(pads allowed)
			(copperpour allowed)
			(footprints not_allowed)
		)
		(placement
			(enabled no)
			(sheetname "")
		)
		(fill
			(thermal_gap 0.5)
			(thermal_bridge_width 0.5)
			(island_removal_mode 0)
		)
		(polygon
			(pts
				(xy 281.850084 -190.069978) (xy 301.850044 -190.069978) (xy 301.850044 -170.070018) (xy 281.850084 -170.070018)
			)
		)
	)
	(zone
		(layer "B.Cu")
		(hatch none 0.5)
		(connect_pads
			(clearance 0)
		)
		(min_thickness 0.25)
		(keepout
			(tracks not_allowed)
			(vias allowed)
			(pads allowed)
			(copperpour not_allowed)
			(footprints allowed)
		)
		(placement
			(enabled no)
			(sheetname "")
		)
		(fill
			(thermal_gap 0.5)
			(thermal_bridge_width 0.5)
			(island_removal_mode 0)
		)
		(polygon
			(pts
				(arc
					(start 375.869708 -400.390106)
					(mid 375.110248 -400.390106)
					(end 375.869708 -400.390106)
				)
			)
		)
	)
	(zone
		(layer "B.Cu")
		(hatch none 0.5)
		(connect_pads
			(clearance 0)
		)
		(min_thickness 0.25)
		(keepout
			(tracks not_allowed)
			(vias allowed)
			(pads allowed)
			(copperpour not_allowed)
			(footprints allowed)
		)
		(placement
			(enabled no)
			(sheetname "")
		)
		(fill
			(thermal_gap 0.5)
			(thermal_bridge_width 0.5)
			(island_removal_mode 0)
		)
		(polygon
			(pts
				(arc
					(start 267.519912 -20.72005)
					(mid 265.519916 -18.720054)
					(end 263.51992 -20.72005)
				)
				(arc
					(start 263.51992 -20.72005)
					(mid 265.519916 -22.720046)
					(end 267.519912 -20.72005)
				)
			)
		)
	)
	(zone
		(layer "B.Cu")
		(hatch none 0.5)
		(connect_pads
			(clearance 0)
		)
		(min_thickness 0.25)
		(keepout
			(tracks not_allowed)
			(vias allowed)
			(pads allowed)
			(copperpour not_allowed)
			(footprints allowed)
		)
		(placement
			(enabled no)
			(sheetname "")
		)
		(fill
			(thermal_gap 0.5)
			(thermal_bridge_width 0.5)
			(island_removal_mode 0)
		)
		(polygon
			(pts
				(arc
					(start 360.789982 -407.599896)
					(mid 363.590078 -410.399992)
					(end 366.38992 -407.599896)
				)
				(arc
					(start 366.38992 -407.599896)
					(mid 363.590078 -404.800054)
					(end 360.789982 -407.599896)
				)
			)
		)
	)
	(zone
		(layer "B.Cu")
		(hatch none 0.5)
		(connect_pads
			(clearance 0)
		)
		(min_thickness 0.25)
		(keepout
			(tracks not_allowed)
			(vias allowed)
			(pads allowed)
			(copperpour not_allowed)
			(footprints allowed)
		)
		(placement
			(enabled no)
			(sheetname "")
		)
		(fill
			(thermal_gap 0.5)
			(thermal_bridge_width 0.5)
			(island_removal_mode 0)
		)
		(polygon
			(pts
				(arc
					(start 357.620062 -20.72005)
					(mid 355.620066 -18.720054)
					(end 353.62007 -20.72005)
				)
				(arc
					(start 353.62007 -20.72005)
					(mid 355.620066 -22.720046)
					(end 357.620062 -20.72005)
				)
			)
		)
	)
	(zone
		(layer "B.Cu")
		(hatch none 0.5)
		(connect_pads
			(clearance 0)
		)
		(min_thickness 0.25)
		(keepout
			(tracks not_allowed)
			(vias allowed)
			(pads allowed)
			(copperpour not_allowed)
			(footprints allowed)
		)
		(placement
			(enabled no)
			(sheetname "")
		)
		(fill
			(thermal_gap 0.5)
			(thermal_bridge_width 0.5)
			(island_removal_mode 0)
		)
		(polygon
			(pts
				(arc
					(start 384.669792 -401.690078)
					(mid 383.910332 -401.690078)
					(end 384.669792 -401.690078)
				)
			)
		)
	)
	(zone
		(layer "B.Cu")
		(hatch none 0.5)
		(connect_pads
			(clearance 0)
		)
		(min_thickness 0.25)
		(keepout
			(tracks not_allowed)
			(vias allowed)
			(pads allowed)
			(copperpour not_allowed)
			(footprints allowed)
		)
		(placement
			(enabled no)
			(sheetname "")
		)
		(fill
			(thermal_gap 0.5)
			(thermal_bridge_width 0.5)
			(island_removal_mode 0)
		)
		(polygon
			(pts
				(arc
					(start 287.86963 -379.590046)
					(mid 287.11017 -379.590046)
					(end 287.86963 -379.590046)
				)
			)
		)
	)
	(zone
		(layer "B.Cu")
		(hatch none 0.5)
		(connect_pads
			(clearance 0)
		)
		(min_thickness 0.25)
		(keepout
			(tracks not_allowed)
			(vias allowed)
			(pads allowed)
			(copperpour not_allowed)
			(footprints allowed)
		)
		(placement
			(enabled no)
			(sheetname "")
		)
		(fill
			(thermal_gap 0.5)
			(thermal_bridge_width 0.5)
			(island_removal_mode 0)
		)
		(polygon
			(pts
				(arc
					(start 314.026296 -310.149748)
					(mid 313.373516 -310.149748)
					(end 314.026296 -310.149748)
				)
			)
		)
	)
	(zone
		(layer "B.Cu")
		(hatch none 0.5)
		(connect_pads
			(clearance 0)
		)
		(min_thickness 0.25)
		(keepout
			(tracks not_allowed)
			(vias allowed)
			(pads allowed)
			(copperpour not_allowed)
			(footprints allowed)
		)
		(placement
			(enabled no)
			(sheetname "")
		)
		(fill
			(thermal_gap 0.5)
			(thermal_bridge_width 0.5)
			(island_removal_mode 0)
		)
		(polygon
			(pts
				(arc
					(start 80.87614 -305.399948)
					(mid 80.22336 -305.399948)
					(end 80.87614 -305.399948)
				)
			)
		)
	)
	(zone
		(layer "B.Cu")
		(hatch none 0.5)
		(connect_pads
			(clearance 0)
		)
		(min_thickness 0.25)
		(keepout
			(tracks not_allowed)
			(vias allowed)
			(pads allowed)
			(copperpour not_allowed)
			(footprints allowed)
		)
		(placement
			(enabled no)
			(sheetname "")
		)
		(fill
			(thermal_gap 0.5)
			(thermal_bridge_width 0.5)
			(island_removal_mode 0)
		)
		(polygon
			(pts
				(arc
					(start 165.2651 -5.999988)
					(mid 168.065196 -8.800084)
					(end 170.865038 -5.999988)
				)
				(arc
					(start 170.865038 -5.999988)
					(mid 168.065196 -3.200146)
					(end 165.2651 -5.999988)
				)
			)
		)
	)
	(zone
		(layer "B.Cu")
		(hatch none 0.5)
		(connect_pads
			(clearance 0)
		)
		(min_thickness 0.25)
		(keepout
			(tracks not_allowed)
			(vias allowed)
			(pads allowed)
			(copperpour not_allowed)
			(footprints allowed)
		)
		(placement
			(enabled no)
			(sheetname "")
		)
		(fill
			(thermal_gap 0.5)
			(thermal_bridge_width 0.5)
			(island_removal_mode 0)
		)
		(polygon
			(pts
				(arc
					(start 440.200034 -270.89989)
					(mid 437.950102 -268.649958)
					(end 435.699916 -270.89989)
				)
				(arc
					(start 435.699916 -270.89989)
					(mid 437.950102 -273.150076)
					(end 440.200034 -270.89989)
				)
			)
		)
	)
	(zone
		(layer "B.Cu")
		(hatch none 0.5)
		(connect_pads
			(clearance 0)
		)
		(min_thickness 0.25)
		(keepout
			(tracks not_allowed)
			(vias allowed)
			(pads allowed)
			(copperpour not_allowed)
			(footprints allowed)
		)
		(placement
			(enabled no)
			(sheetname "")
		)
		(fill
			(thermal_gap 0.5)
			(thermal_bridge_width 0.5)
			(island_removal_mode 0)
		)
		(polygon
			(pts
				(arc
					(start 254.299974 -98.700082)
					(mid 259.299964 -103.700072)
					(end 264.299954 -98.700082)
				)
				(arc
					(start 264.299954 -98.700082)
					(mid 259.299964 -93.700092)
					(end 254.299974 -98.700082)
				)
			)
		)
	)
	(zone
		(layer "B.Cu")
		(hatch none 0.5)
		(connect_pads
			(clearance 0)
		)
		(min_thickness 0.25)
		(keepout
			(tracks allowed)
			(vias allowed)
			(pads allowed)
			(copperpour allowed)
			(footprints allowed)
		)
		(placement
			(enabled no)
			(sheetname "")
		)
		(fill
			(thermal_gap 0.5)
			(thermal_bridge_width 0.5)
			(island_removal_mode 0)
		)
		(polygon
			(pts
				(xy 303.831244 -301.7774) (xy 305.533044 -301.7774) (xy 305.736244 -301.9806) (xy 305.736244 -302.2346)
				(xy 305.228244 -302.7426) (xy 303.653444 -302.7426) (xy 303.450244 -302.9458) (xy 303.450244 -307.0352)
				(xy 302.993044 -307.4924) (xy 292.198044 -307.4924) (xy 291.613844 -308.0766) (xy 291.613844 -320.4464)
				(xy 291.080444 -320.4464) (xy 290.953444 -320.3194) (xy 290.953444 -307.8988) (xy 291.817044 -307.0352)
				(xy 302.916844 -307.0352) (xy 303.018444 -306.9336) (xy 303.018444 -302.5902)
			)
		)
	)
	(zone
		(layer "B.Cu")
		(hatch none 0.5)
		(connect_pads
			(clearance 0)
		)
		(min_thickness 0.25)
		(keepout
			(tracks allowed)
			(vias allowed)
			(pads allowed)
			(copperpour allowed)
			(footprints allowed)
		)
		(placement
			(enabled no)
			(sheetname "")
		)
		(fill
			(thermal_gap 0.5)
			(thermal_bridge_width 0.5)
			(island_removal_mode 0)
		)
		(polygon
			(pts
				(xy 72.698864 -298.570904) (xy 73.166732 -298.570904) (xy 73.220072 -298.517564) (xy 73.220072 -293.213028)
				(xy 73.166478 -293.159434) (xy 72.56526 -293.159434) (xy 72.56526 -298.4373)
			)
		)
	)
	(zone
		(layer "B.Cu")
		(hatch none 0.5)
		(connect_pads
			(clearance 0)
		)
		(min_thickness 0.25)
		(keepout
			(tracks not_allowed)
			(vias allowed)
			(pads allowed)
			(copperpour not_allowed)
			(footprints allowed)
		)
		(placement
			(enabled no)
			(sheetname "")
		)
		(fill
			(thermal_gap 0.5)
			(thermal_bridge_width 0.5)
			(island_removal_mode 0)
		)
		(polygon
			(pts
				(arc
					(start 292.269672 -404.290022)
					(mid 291.510212 -404.290022)
					(end 292.269672 -404.290022)
				)
			)
		)
	)
	(zone
		(layer "B.Cu")
		(hatch none 0.5)
		(connect_pads
			(clearance 0)
		)
		(min_thickness 0.25)
		(keepout
			(tracks allowed)
			(vias allowed)
			(pads allowed)
			(copperpour allowed)
			(footprints allowed)
		)
		(placement
			(enabled no)
			(sheetname "")
		)
		(fill
			(thermal_gap 0.5)
			(thermal_bridge_width 0.5)
			(island_removal_mode 0)
		)
		(polygon
			(pts
				(xy 104.36606 -329.498706) (xy 106.656632 -329.498706) (xy 106.752898 -329.40244) (xy 106.752898 -328.633328)
				(xy 106.228134 -328.108564) (xy 104.777032 -328.108564) (xy 104.278938 -328.606658) (xy 104.278938 -329.411584)
			)
		)
	)
	(zone
		(layer "B.Cu")
		(hatch none 0.5)
		(connect_pads
			(clearance 0)
		)
		(min_thickness 0.25)
		(keepout
			(tracks not_allowed)
			(vias allowed)
			(pads allowed)
			(copperpour not_allowed)
			(footprints allowed)
		)
		(placement
			(enabled no)
			(sheetname "")
		)
		(fill
			(thermal_gap 0.5)
			(thermal_bridge_width 0.5)
			(island_removal_mode 0)
		)
		(polygon
			(pts
				(arc
					(start 435.619906 -20.72005)
					(mid 433.61991 -18.720054)
					(end 431.619914 -20.72005)
				)
				(arc
					(start 431.619914 -20.72005)
					(mid 433.61991 -22.720046)
					(end 435.619906 -20.72005)
				)
			)
		)
	)
	(zone
		(layer "B.Cu")
		(hatch none 0.5)
		(connect_pads
			(clearance 0)
		)
		(min_thickness 0.25)
		(keepout
			(tracks allowed)
			(vias allowed)
			(pads allowed)
			(copperpour allowed)
			(footprints not_allowed)
		)
		(placement
			(enabled no)
			(sheetname "")
		)
		(fill
			(thermal_gap 0.5)
			(thermal_bridge_width 0.5)
			(island_removal_mode 0)
		)
		(polygon
			(pts
				(arc
					(start 94.62008 -15.649956)
					(mid 96.620076 -17.649952)
					(end 98.620072 -15.649956)
				)
				(arc
					(start 98.620072 -15.649956)
					(mid 96.620076 -13.64996)
					(end 94.62008 -15.649956)
				)
			)
		)
	)
	(zone
		(layer "B.Cu")
		(hatch none 0.5)
		(connect_pads
			(clearance 0)
		)
		(min_thickness 0.25)
		(keepout
			(tracks allowed)
			(vias allowed)
			(pads allowed)
			(copperpour allowed)
			(footprints allowed)
		)
		(placement
			(enabled no)
			(sheetname "")
		)
		(fill
			(thermal_gap 0.5)
			(thermal_bridge_width 0.5)
			(island_removal_mode 0)
		)
		(polygon
			(pts
				(xy 363.479842 -320.320924) (xy 363.479842 -321.971924) (xy 361.320842 -321.971924) (xy 361.320842 -320.320924)
			)
		)
	)
	(zone
		(layer "B.Cu")
		(hatch none 0.5)
		(connect_pads
			(clearance 0)
		)
		(min_thickness 0.25)
		(keepout
			(tracks not_allowed)
			(vias allowed)
			(pads allowed)
			(copperpour not_allowed)
			(footprints allowed)
		)
		(placement
			(enabled no)
			(sheetname "")
		)
		(fill
			(thermal_gap 0.5)
			(thermal_bridge_width 0.5)
			(island_removal_mode 0)
		)
		(polygon
			(pts
				(arc
					(start 313.076082 -317.749936)
					(mid 312.423302 -317.749936)
					(end 313.076082 -317.749936)
				)
			)
		)
	)
	(zone
		(layer "B.Cu")
		(hatch none 0.5)
		(connect_pads
			(clearance 0)
		)
		(min_thickness 0.25)
		(keepout
			(tracks not_allowed)
			(vias allowed)
			(pads allowed)
			(copperpour not_allowed)
			(footprints allowed)
		)
		(placement
			(enabled no)
			(sheetname "")
		)
		(fill
			(thermal_gap 0.5)
			(thermal_bridge_width 0.5)
			(island_removal_mode 0)
		)
		(polygon
			(pts
				(arc
					(start 166.576248 -317.749936)
					(mid 165.923468 -317.749936)
					(end 166.576248 -317.749936)
				)
			)
		)
	)
	(zone
		(layer "B.Cu")
		(hatch none 0.5)
		(connect_pads
			(clearance 0)
		)
		(min_thickness 0.25)
		(keepout
			(tracks not_allowed)
			(vias allowed)
			(pads allowed)
			(copperpour not_allowed)
			(footprints allowed)
		)
		(placement
			(enabled no)
			(sheetname "")
		)
		(fill
			(thermal_gap 0.5)
			(thermal_bridge_width 0.5)
			(island_removal_mode 0)
		)
		(polygon
			(pts
				(arc
					(start 182.72633 -315.849762)
					(mid 182.07355 -315.849762)
					(end 182.72633 -315.849762)
				)
			)
		)
	)
	(zone
		(layer "B.Cu")
		(hatch none 0.5)
		(connect_pads
			(clearance 0)
		)
		(min_thickness 0.25)
		(keepout
			(tracks not_allowed)
			(vias allowed)
			(pads allowed)
			(copperpour not_allowed)
			(footprints allowed)
		)
		(placement
			(enabled no)
			(sheetname "")
		)
		(fill
			(thermal_gap 0.5)
			(thermal_bridge_width 0.5)
			(island_removal_mode 0)
		)
		(polygon
			(pts
				(arc
					(start 375.869708 -371.790214)
					(mid 375.110248 -371.790214)
					(end 375.869708 -371.790214)
				)
			)
		)
	)
	(zone
		(layer "B.Cu")
		(hatch none 0.5)
		(connect_pads
			(clearance 0)
		)
		(min_thickness 0.25)
		(keepout
			(tracks allowed)
			(vias allowed)
			(pads allowed)
			(copperpour allowed)
			(footprints not_allowed)
		)
		(placement
			(enabled no)
			(sheetname "")
		)
		(fill
			(thermal_gap 0.5)
			(thermal_bridge_width 0.5)
			(island_removal_mode 0)
		)
		(polygon
			(pts
				(arc
					(start 364.450122 -276.010116)
					(mid 365.287844 -273.56063)
					(end 367.450116 -272.137124)
				)
				(xy 367.450116 -266.897612) (xy 332.35011 -266.897612)
				(arc
					(start 332.35011 -285.947104)
					(mid 334.512395 -287.3706)
					(end 335.350104 -289.820096)
				)
				(arc
					(start 335.350104 -289.820096)
					(mid 334.512382 -292.269582)
					(end 332.35011 -293.693088)
				)
				(xy 332.35011 -328.972418) (xy 367.450116 -328.972418)
				(arc
					(start 367.450116 -279.882854)
					(mid 365.287878 -278.459495)
					(end 364.450122 -276.010116)
				)
			)
		)
	)
	(zone
		(layer "B.Cu")
		(hatch none 0.5)
		(connect_pads
			(clearance 0)
		)
		(min_thickness 0.25)
		(keepout
			(tracks allowed)
			(vias allowed)
			(pads allowed)
			(copperpour allowed)
			(footprints not_allowed)
		)
		(placement
			(enabled no)
			(sheetname "")
		)
		(fill
			(thermal_gap 0.5)
			(thermal_bridge_width 0.5)
			(island_removal_mode 0)
		)
		(polygon
			(pts
				(arc
					(start 42.61993 -15.649956)
					(mid 44.619926 -17.649952)
					(end 46.619922 -15.649956)
				)
				(arc
					(start 46.619922 -15.649956)
					(mid 44.619926 -13.64996)
					(end 42.61993 -15.649956)
				)
			)
		)
	)
	(zone
		(layer "B.Cu")
		(hatch none 0.5)
		(connect_pads
			(clearance 0)
		)
		(min_thickness 0.25)
		(keepout
			(tracks not_allowed)
			(vias allowed)
			(pads allowed)
			(copperpour not_allowed)
			(footprints allowed)
		)
		(placement
			(enabled no)
			(sheetname "")
		)
		(fill
			(thermal_gap 0.5)
			(thermal_bridge_width 0.5)
			(island_removal_mode 0)
		)
		(polygon
			(pts
				(arc
					(start 210.000088 -98.700082)
					(mid 208.300066 -97.00006)
					(end 206.600044 -98.700082)
				)
				(arc
					(start 206.600044 -98.700082)
					(mid 208.300066 -100.400104)
					(end 210.000088 -98.700082)
				)
			)
		)
	)
	(zone
		(layer "B.Cu")
		(hatch none 0.5)
		(connect_pads
			(clearance 0)
		)
		(min_thickness 0.25)
		(keepout
			(tracks allowed)
			(vias allowed)
			(pads allowed)
			(copperpour allowed)
			(footprints not_allowed)
		)
		(placement
			(enabled no)
			(sheetname "")
		)
		(fill
			(thermal_gap 0.5)
			(thermal_bridge_width 0.5)
			(island_removal_mode 0)
		)
		(polygon
			(pts
				(xy 246.149114 -316.570106) (xy 246.149114 -300.569884) (xy 218.329002 -300.569884) (xy 218.329002 -316.570106)
			)
		)
	)
	(zone
		(layer "B.Cu")
		(hatch none 0.5)
		(connect_pads
			(clearance 0)
		)
		(min_thickness 0.25)
		(keepout
			(tracks not_allowed)
			(vias allowed)
			(pads allowed)
			(copperpour not_allowed)
			(footprints allowed)
		)
		(placement
			(enabled no)
			(sheetname "")
		)
		(fill
			(thermal_gap 0.5)
			(thermal_bridge_width 0.5)
			(island_removal_mode 0)
		)
		(polygon
			(pts
				(arc
					(start 340.214966 -17.999964)
					(mid 342.214962 -19.99996)
					(end 344.214958 -17.999964)
				)
				(arc
					(start 344.214958 -17.999964)
					(mid 342.214962 -15.999968)
					(end 340.214966 -17.999964)
				)
			)
		)
	)
	(zone
		(layer "B.Cu")
		(hatch none 0.5)
		(connect_pads
			(clearance 0)
		)
		(min_thickness 0.25)
		(keepout
			(tracks not_allowed)
			(vias allowed)
			(pads allowed)
			(copperpour not_allowed)
			(footprints allowed)
		)
		(placement
			(enabled no)
			(sheetname "")
		)
		(fill
			(thermal_gap 0.5)
			(thermal_bridge_width 0.5)
			(island_removal_mode 0)
		)
		(polygon
			(pts
				(arc
					(start 147.999958 -270.89989)
					(mid 145.750026 -268.649958)
					(end 143.500094 -270.89989)
				)
				(arc
					(start 143.500094 -270.89989)
					(mid 145.750026 -273.149822)
					(end 147.999958 -270.89989)
				)
			)
		)
	)
	(zone
		(layer "B.Cu")
		(hatch none 0.5)
		(connect_pads
			(clearance 0)
		)
		(min_thickness 0.25)
		(keepout
			(tracks not_allowed)
			(vias allowed)
			(pads allowed)
			(copperpour not_allowed)
			(footprints allowed)
		)
		(placement
			(enabled no)
			(sheetname "")
		)
		(fill
			(thermal_gap 0.5)
			(thermal_bridge_width 0.5)
			(island_removal_mode 0)
		)
		(polygon
			(pts
				(arc
					(start 339.41512 -17.999964)
					(mid 342.215216 -20.80006)
					(end 345.015058 -17.999964)
				)
				(arc
					(start 345.015058 -17.999964)
					(mid 342.215216 -15.200122)
					(end 339.41512 -17.999964)
				)
			)
		)
	)
	(zone
		(layer "B.Cu")
		(hatch none 0.5)
		(connect_pads
			(clearance 0)
		)
		(min_thickness 0.25)
		(keepout
			(tracks not_allowed)
			(vias allowed)
			(pads allowed)
			(copperpour not_allowed)
			(footprints allowed)
		)
		(placement
			(enabled no)
			(sheetname "")
		)
		(fill
			(thermal_gap 0.5)
			(thermal_bridge_width 0.5)
			(island_removal_mode 0)
		)
		(polygon
			(pts
				(arc
					(start 231.000046 -194.360038)
					(mid 233.800142 -197.160134)
					(end 236.599984 -194.360038)
				)
				(arc
					(start 236.599984 -194.360038)
					(mid 233.800142 -191.560196)
					(end 231.000046 -194.360038)
				)
			)
		)
	)
	(zone
		(layer "B.Cu")
		(hatch none 0.5)
		(connect_pads
			(clearance 0)
		)
		(min_thickness 0.25)
		(keepout
			(tracks allowed)
			(vias allowed)
			(pads allowed)
			(copperpour allowed)
			(footprints not_allowed)
		)
		(placement
			(enabled no)
			(sheetname "")
		)
		(fill
			(thermal_gap 0.5)
			(thermal_bridge_width 0.5)
			(island_removal_mode 0)
		)
		(polygon
			(pts
				(arc
					(start 132.72008 -15.649956)
					(mid 134.720076 -17.649952)
					(end 136.720072 -15.649956)
				)
				(arc
					(start 136.720072 -15.649956)
					(mid 134.720076 -13.64996)
					(end 132.72008 -15.649956)
				)
			)
		)
	)
	(zone
		(layer "B.Cu")
		(hatch none 0.5)
		(connect_pads
			(clearance 0)
		)
		(min_thickness 0.25)
		(keepout
			(tracks not_allowed)
			(vias allowed)
			(pads allowed)
			(copperpour not_allowed)
			(footprints allowed)
		)
		(placement
			(enabled no)
			(sheetname "")
		)
		(fill
			(thermal_gap 0.5)
			(thermal_bridge_width 0.5)
			(island_removal_mode 0)
		)
		(polygon
			(pts
				(arc
					(start 74.226166 -316.799722)
					(mid 73.573386 -316.799722)
					(end 74.226166 -316.799722)
				)
			)
		)
	)
	(zone
		(layer "B.Cu")
		(hatch none 0.5)
		(connect_pads
			(clearance 0)
		)
		(min_thickness 0.25)
		(keepout
			(tracks not_allowed)
			(vias allowed)
			(pads allowed)
			(copperpour not_allowed)
			(footprints allowed)
		)
		(placement
			(enabled no)
			(sheetname "")
		)
		(fill
			(thermal_gap 0.5)
			(thermal_bridge_width 0.5)
			(island_removal_mode 0)
		)
		(polygon
			(pts
				(arc
					(start 118.48973 -401.49018)
					(mid 117.73027 -401.49018)
					(end 118.48973 -401.49018)
				)
			)
		)
	)
	(zone
		(layer "B.Cu")
		(hatch none 0.5)
		(connect_pads
			(clearance 0)
		)
		(min_thickness 0.25)
		(keepout
			(tracks not_allowed)
			(vias allowed)
			(pads allowed)
			(copperpour not_allowed)
			(footprints allowed)
		)
		(placement
			(enabled no)
			(sheetname "")
		)
		(fill
			(thermal_gap 0.5)
			(thermal_bridge_width 0.5)
			(island_removal_mode 0)
		)
		(polygon
			(pts
				(arc
					(start 197.39991 -393.100052)
					(mid 199.399906 -395.100048)
					(end 201.399902 -393.100052)
				)
				(arc
					(start 201.399902 -393.100052)
					(mid 199.399906 -391.100056)
					(end 197.39991 -393.100052)
				)
			)
		)
	)
	(zone
		(layer "B.Cu")
		(hatch none 0.5)
		(connect_pads
			(clearance 0)
		)
		(min_thickness 0.25)
		(keepout
			(tracks not_allowed)
			(vias allowed)
			(pads allowed)
			(copperpour not_allowed)
			(footprints allowed)
		)
		(placement
			(enabled no)
			(sheetname "")
		)
		(fill
			(thermal_gap 0.5)
			(thermal_bridge_width 0.5)
			(island_removal_mode 0)
		)
		(polygon
			(pts
				(arc
					(start 6.800088 -399.64995)
					(mid 8.349996 -398.100042)
					(end 6.800088 -396.54988)
				)
				(arc
					(start 5.199888 -396.54988)
					(mid 3.649726 -398.100042)
					(end 5.199888 -399.64995)
				)
			)
		)
	)
	(zone
		(layer "B.Cu")
		(hatch none 0.5)
		(connect_pads
			(clearance 0)
		)
		(min_thickness 0.25)
		(keepout
			(tracks not_allowed)
			(vias allowed)
			(pads allowed)
			(copperpour not_allowed)
			(footprints allowed)
		)
		(placement
			(enabled no)
			(sheetname "")
		)
		(fill
			(thermal_gap 0.5)
			(thermal_bridge_width 0.5)
			(island_removal_mode 0)
		)
		(polygon
			(pts
				(arc
					(start 378.069602 -372.890034)
					(mid 377.310142 -372.890034)
					(end 378.069602 -372.890034)
				)
			)
		)
	)
	(zone
		(layer "B.Cu")
		(hatch none 0.5)
		(connect_pads
			(clearance 0)
		)
		(min_thickness 0.25)
		(keepout
			(tracks not_allowed)
			(vias allowed)
			(pads allowed)
			(copperpour not_allowed)
			(footprints allowed)
		)
		(placement
			(enabled no)
			(sheetname "")
		)
		(fill
			(thermal_gap 0.5)
			(thermal_bridge_width 0.5)
			(island_removal_mode 0)
		)
		(polygon
			(pts
				(arc
					(start 79.92618 -315.849762)
					(mid 79.2734 -315.849762)
					(end 79.92618 -315.849762)
				)
			)
		)
	)
	(zone
		(layer "B.Cu")
		(hatch none 0.5)
		(connect_pads
			(clearance 0)
		)
		(min_thickness 0.25)
		(keepout
			(tracks allowed)
			(vias allowed)
			(pads allowed)
			(copperpour allowed)
			(footprints allowed)
		)
		(placement
			(enabled no)
			(sheetname "")
		)
		(fill
			(thermal_gap 0.5)
			(thermal_bridge_width 0.5)
			(island_removal_mode 0)
		)
		(polygon
			(pts
				(xy 355.792024 -312.599578) (xy 357.443024 -312.599578) (xy 357.443024 -314.758578) (xy 355.792024 -314.758578)
			)
		)
	)
	(zone
		(layer "B.Cu")
		(hatch none 0.5)
		(connect_pads
			(clearance 0)
		)
		(min_thickness 0.25)
		(keepout
			(tracks not_allowed)
			(vias allowed)
			(pads allowed)
			(copperpour not_allowed)
			(footprints allowed)
		)
		(placement
			(enabled no)
			(sheetname "")
		)
		(fill
			(thermal_gap 0.5)
			(thermal_bridge_width 0.5)
			(island_removal_mode 0)
		)
		(polygon
			(pts
				(arc
					(start 294.469566 -380.69012)
					(mid 293.710106 -380.69012)
					(end 294.469566 -380.69012)
				)
			)
		)
	)
	(zone
		(layer "B.Cu")
		(hatch none 0.5)
		(connect_pads
			(clearance 0)
		)
		(min_thickness 0.25)
		(keepout
			(tracks not_allowed)
			(vias allowed)
			(pads allowed)
			(copperpour not_allowed)
			(footprints allowed)
		)
		(placement
			(enabled no)
			(sheetname "")
		)
		(fill
			(thermal_gap 0.5)
			(thermal_bridge_width 0.5)
			(island_removal_mode 0)
		)
		(polygon
			(pts
				(arc
					(start 290.069524 -380.69012)
					(mid 289.310064 -380.69012)
					(end 290.069524 -380.69012)
				)
			)
		)
	)
	(zone
		(layer "B.Cu")
		(hatch none 0.5)
		(connect_pads
			(clearance 0)
		)
		(min_thickness 0.25)
		(keepout
			(tracks not_allowed)
			(vias allowed)
			(pads allowed)
			(copperpour not_allowed)
			(footprints allowed)
		)
		(placement
			(enabled no)
			(sheetname "")
		)
		(fill
			(thermal_gap 0.5)
			(thermal_bridge_width 0.5)
			(island_removal_mode 0)
		)
		(polygon
			(pts
				(arc
					(start 91.899994 -320.900044)
					(mid 89.650062 -318.650112)
					(end 87.399876 -320.900044)
				)
				(arc
					(start 87.399876 -320.900044)
					(mid 89.650062 -323.15023)
					(end 91.899994 -320.900044)
				)
			)
		)
	)
	(zone
		(layer "B.Cu")
		(hatch none 0.5)
		(connect_pads
			(clearance 0)
		)
		(min_thickness 0.25)
		(keepout
			(tracks not_allowed)
			(vias allowed)
			(pads allowed)
			(copperpour not_allowed)
			(footprints allowed)
		)
		(placement
			(enabled no)
			(sheetname "")
		)
		(fill
			(thermal_gap 0.5)
			(thermal_bridge_width 0.5)
			(island_removal_mode 0)
		)
		(polygon
			(pts
				(arc
					(start 414.926272 -316.799722)
					(mid 414.273492 -316.799722)
					(end 414.926272 -316.799722)
				)
			)
		)
	)
	(zone
		(layer "B.Cu")
		(hatch none 0.5)
		(connect_pads
			(clearance 0)
		)
		(min_thickness 0.25)
		(keepout
			(tracks not_allowed)
			(vias allowed)
			(pads allowed)
			(copperpour not_allowed)
			(footprints allowed)
		)
		(placement
			(enabled no)
			(sheetname "")
		)
		(fill
			(thermal_gap 0.5)
			(thermal_bridge_width 0.5)
			(island_removal_mode 0)
		)
		(polygon
			(pts
				(arc
					(start 249.100086 -297.369992)
					(mid 252.350016 -300.619922)
					(end 255.599946 -297.369992)
				)
				(arc
					(start 255.599946 -297.369992)
					(mid 252.350016 -294.120062)
					(end 249.100086 -297.369992)
				)
			)
		)
	)
	(zone
		(layer "B.Cu")
		(hatch none 0.5)
		(connect_pads
			(clearance 0)
		)
		(min_thickness 0.25)
		(keepout
			(tracks not_allowed)
			(vias allowed)
			(pads allowed)
			(copperpour not_allowed)
			(footprints allowed)
		)
		(placement
			(enabled no)
			(sheetname "")
		)
		(fill
			(thermal_gap 0.5)
			(thermal_bridge_width 0.5)
			(island_removal_mode 0)
		)
		(polygon
			(pts
				(arc
					(start 319.520062 -20.72005)
					(mid 317.520066 -18.720054)
					(end 315.52007 -20.72005)
				)
				(arc
					(start 315.52007 -20.72005)
					(mid 317.520066 -22.720046)
					(end 319.520062 -20.72005)
				)
			)
		)
	)
	(zone
		(layer "B.Cu")
		(hatch none 0.5)
		(connect_pads
			(clearance 0)
		)
		(min_thickness 0.25)
		(keepout
			(tracks not_allowed)
			(vias allowed)
			(pads allowed)
			(copperpour not_allowed)
			(footprints allowed)
		)
		(placement
			(enabled no)
			(sheetname "")
		)
		(fill
			(thermal_gap 0.5)
			(thermal_bridge_width 0.5)
			(island_removal_mode 0)
		)
		(polygon
			(pts
				(arc
					(start 129.489708 -400.390106)
					(mid 128.730248 -400.390106)
					(end 129.489708 -400.390106)
				)
			)
		)
	)
	(zone
		(layer "B.Cu")
		(hatch none 0.5)
		(connect_pads
			(clearance 0)
		)
		(min_thickness 0.25)
		(keepout
			(tracks not_allowed)
			(vias allowed)
			(pads allowed)
			(copperpour not_allowed)
			(footprints allowed)
		)
		(placement
			(enabled no)
			(sheetname "")
		)
		(fill
			(thermal_gap 0.5)
			(thermal_bridge_width 0.5)
			(island_removal_mode 0)
		)
		(polygon
			(pts
				(arc
					(start 417.776406 -317.749936)
					(mid 417.123626 -317.749936)
					(end 417.776406 -317.749936)
				)
			)
		)
	)
	(zone
		(layer "B.Cu")
		(hatch none 0.5)
		(connect_pads
			(clearance 0)
		)
		(min_thickness 0.25)
		(keepout
			(tracks not_allowed)
			(vias allowed)
			(pads allowed)
			(copperpour not_allowed)
			(footprints allowed)
		)
		(placement
			(enabled no)
			(sheetname "")
		)
		(fill
			(thermal_gap 0.5)
			(thermal_bridge_width 0.5)
			(island_removal_mode 0)
		)
		(polygon
			(pts
				(arc
					(start 386.869686 -372.890034)
					(mid 386.110226 -372.890034)
					(end 386.869686 -372.890034)
				)
			)
		)
	)
	(zone
		(layer "B.Cu")
		(hatch none 0.5)
		(connect_pads
			(clearance 0)
		)
		(min_thickness 0.25)
		(keepout
			(tracks not_allowed)
			(vias allowed)
			(pads allowed)
			(copperpour not_allowed)
			(footprints allowed)
		)
		(placement
			(enabled no)
			(sheetname "")
		)
		(fill
			(thermal_gap 0.5)
			(thermal_bridge_width 0.5)
			(island_removal_mode 0)
		)
		(polygon
			(pts
				(arc
					(start 43.689778 -405.390096)
					(mid 42.930318 -405.390096)
					(end 43.689778 -405.390096)
				)
			)
		)
	)
	(zone
		(layer "B.Cu")
		(hatch none 0.5)
		(connect_pads
			(clearance 0)
		)
		(min_thickness 0.25)
		(keepout
			(tracks not_allowed)
			(vias allowed)
			(pads allowed)
			(copperpour not_allowed)
			(footprints allowed)
		)
		(placement
			(enabled no)
			(sheetname "")
		)
		(fill
			(thermal_gap 0.5)
			(thermal_bridge_width 0.5)
			(island_removal_mode 0)
		)
		(polygon
			(pts
				(arc
					(start 120.689878 -401.690078)
					(mid 119.930418 -401.690078)
					(end 120.689878 -401.690078)
				)
			)
		)
	)
	(zone
		(layer "B.Cu")
		(hatch none 0.5)
		(connect_pads
			(clearance 0)
		)
		(min_thickness 0.25)
		(keepout
			(tracks allowed)
			(vias allowed)
			(pads allowed)
			(copperpour allowed)
			(footprints not_allowed)
		)
		(placement
			(enabled no)
			(sheetname "")
		)
		(fill
			(thermal_gap 0.5)
			(thermal_bridge_width 0.5)
			(island_removal_mode 0)
		)
		(polygon
			(pts
				(xy 196.250052 -280.399998) (xy 155.24988 -280.399998) (xy 155.24988 -311.399936) (xy 196.250052 -311.399936)
			)
		)
	)
	(zone
		(layer "B.Cu")
		(hatch none 0.5)
		(connect_pads
			(clearance 0)
		)
		(min_thickness 0.25)
		(keepout
			(tracks not_allowed)
			(vias allowed)
			(pads allowed)
			(copperpour not_allowed)
			(footprints allowed)
		)
		(placement
			(enabled no)
			(sheetname "")
		)
		(fill
			(thermal_gap 0.5)
			(thermal_bridge_width 0.5)
			(island_removal_mode 0)
		)
		(polygon
			(pts
				(arc
					(start 190.699898 -378.70003)
					(mid 195.699888 -383.70002)
					(end 200.699878 -378.70003)
				)
				(arc
					(start 200.699878 -378.70003)
					(mid 195.699888 -373.70004)
					(end 190.699898 -378.70003)
				)
			)
		)
	)
	(zone
		(layer "B.Cu")
		(hatch none 0.5)
		(connect_pads
			(clearance 0)
		)
		(min_thickness 0.25)
		(keepout
			(tracks not_allowed)
			(vias allowed)
			(pads allowed)
			(copperpour not_allowed)
			(footprints allowed)
		)
		(placement
			(enabled no)
			(sheetname "")
		)
		(fill
			(thermal_gap 0.5)
			(thermal_bridge_width 0.5)
			(island_removal_mode 0)
		)
		(polygon
			(pts
				(arc
					(start 32.6898 -378.290074)
					(mid 31.93034 -378.290074)
					(end 32.6898 -378.290074)
				)
			)
		)
	)
	(zone
		(layer "B.Cu")
		(hatch none 0.5)
		(connect_pads
			(clearance 0)
		)
		(min_thickness 0.25)
		(keepout
			(tracks not_allowed)
			(vias allowed)
			(pads allowed)
			(copperpour not_allowed)
			(footprints allowed)
		)
		(placement
			(enabled no)
			(sheetname "")
		)
		(fill
			(thermal_gap 0.5)
			(thermal_bridge_width 0.5)
			(island_removal_mode 0)
		)
		(polygon
			(pts
				(arc
					(start 290.069524 -406.690068)
					(mid 289.310064 -406.690068)
					(end 290.069524 -406.690068)
				)
			)
		)
	)
	(zone
		(layer "B.Cu")
		(hatch none 0.5)
		(connect_pads
			(clearance 0)
		)
		(min_thickness 0.25)
		(keepout
			(tracks allowed)
			(vias allowed)
			(pads allowed)
			(copperpour allowed)
			(footprints allowed)
		)
		(placement
			(enabled no)
			(sheetname "")
		)
		(fill
			(thermal_gap 0.5)
			(thermal_bridge_width 0.5)
			(island_removal_mode 0)
		)
		(polygon
			(pts
				(xy 104.648762 -385.954778) (xy 104.648762 -384.645154) (xy 106.395266 -384.645154) (xy 106.395266 -385.954778)
			)
		)
	)
	(zone
		(layer "B.Cu")
		(hatch none 0.5)
		(connect_pads
			(clearance 0)
		)
		(min_thickness 0.25)
		(keepout
			(tracks allowed)
			(vias allowed)
			(pads allowed)
			(copperpour allowed)
			(footprints not_allowed)
		)
		(placement
			(enabled no)
			(sheetname "")
		)
		(fill
			(thermal_gap 0.5)
			(thermal_bridge_width 0.5)
			(island_removal_mode 0)
		)
		(polygon
			(pts
				(xy 69.650102 -170.070018) (xy 49.649888 -170.070018) (xy 49.649888 -190.069978) (xy 69.650102 -190.069978)
			)
		)
	)
	(zone
		(layer "B.Cu")
		(hatch none 0.5)
		(connect_pads
			(clearance 0)
		)
		(min_thickness 0.25)
		(keepout
			(tracks allowed)
			(vias allowed)
			(pads allowed)
			(copperpour allowed)
			(footprints not_allowed)
		)
		(placement
			(enabled no)
			(sheetname "")
		)
		(fill
			(thermal_gap 0.5)
			(thermal_bridge_width 0.5)
			(island_removal_mode 0)
		)
		(polygon
			(pts
				(arc
					(start 456.600052 -14.400022)
					(mid 461.600042 -19.400012)
					(end 466.600032 -14.400022)
				)
				(arc
					(start 466.600032 -14.400022)
					(mid 461.600042 -9.400032)
					(end 456.600052 -14.400022)
				)
			)
		)
	)
	(zone
		(layer "B.Cu")
		(hatch none 0.5)
		(connect_pads
			(clearance 0)
		)
		(min_thickness 0.25)
		(keepout
			(tracks not_allowed)
			(vias allowed)
			(pads allowed)
			(copperpour not_allowed)
			(footprints allowed)
		)
		(placement
			(enabled no)
			(sheetname "")
		)
		(fill
			(thermal_gap 0.5)
			(thermal_bridge_width 0.5)
			(island_removal_mode 0)
		)
		(polygon
			(pts
				(arc
					(start 185.576464 -317.749936)
					(mid 184.923684 -317.749936)
					(end 185.576464 -317.749936)
				)
			)
		)
	)
	(zone
		(layer "B.Cu")
		(hatch none 0.5)
		(connect_pads
			(clearance 0)
		)
		(min_thickness 0.25)
		(keepout
			(tracks allowed)
			(vias allowed)
			(pads allowed)
			(copperpour allowed)
			(footprints allowed)
		)
		(placement
			(enabled no)
			(sheetname "")
		)
		(fill
			(thermal_gap 0.5)
			(thermal_bridge_width 0.5)
			(island_removal_mode 0)
		)
		(polygon
			(pts
				(xy 229.555294 -77.336904) (xy 229.555294 -76.036678) (xy 231.515158 -76.036678) (xy 231.515158 -77.336904)
			)
		)
	)
	(zone
		(layer "B.Cu")
		(hatch none 0.5)
		(connect_pads
			(clearance 0)
		)
		(min_thickness 0.25)
		(keepout
			(tracks not_allowed)
			(vias allowed)
			(pads allowed)
			(copperpour not_allowed)
			(footprints allowed)
		)
		(placement
			(enabled no)
			(sheetname "")
		)
		(fill
			(thermal_gap 0.5)
			(thermal_bridge_width 0.5)
			(island_removal_mode 0)
		)
		(polygon
			(pts
				(arc
					(start 393.076176 -317.749936)
					(mid 392.423396 -317.749936)
					(end 393.076176 -317.749936)
				)
			)
		)
	)
	(zone
		(layer "B.Cu")
		(hatch none 0.5)
		(connect_pads
			(clearance 0)
		)
		(min_thickness 0.25)
		(keepout
			(tracks not_allowed)
			(vias allowed)
			(pads allowed)
			(copperpour not_allowed)
			(footprints allowed)
		)
		(placement
			(enabled no)
			(sheetname "")
		)
		(fill
			(thermal_gap 0.5)
			(thermal_bridge_width 0.5)
			(island_removal_mode 0)
		)
		(polygon
			(pts
				(arc
					(start 354.899976 -194.360038)
					(mid 349.899986 -189.360048)
					(end 344.899996 -194.360038)
				)
				(arc
					(start 344.899996 -194.360038)
					(mid 349.899986 -199.360028)
					(end 354.899976 -194.360038)
				)
			)
		)
	)
	(zone
		(layer "B.Cu")
		(hatch none 0.5)
		(connect_pads
			(clearance 0)
		)
		(min_thickness 0.25)
		(keepout
			(tracks not_allowed)
			(vias allowed)
			(pads allowed)
			(copperpour not_allowed)
			(footprints allowed)
		)
		(placement
			(enabled no)
			(sheetname "")
		)
		(fill
			(thermal_gap 0.5)
			(thermal_bridge_width 0.5)
			(island_removal_mode 0)
		)
		(polygon
			(pts
				(arc
					(start 446.79997 -84.70011)
					(mid 448.799966 -86.700106)
					(end 450.799962 -84.70011)
				)
				(arc
					(start 450.799962 -84.70011)
					(mid 448.799966 -82.700114)
					(end 446.79997 -84.70011)
				)
			)
		)
	)
	(zone
		(layer "B.Cu")
		(hatch none 0.5)
		(connect_pads
			(clearance 0)
		)
		(min_thickness 0.25)
		(keepout
			(tracks allowed)
			(vias allowed)
			(pads allowed)
			(copperpour allowed)
			(footprints not_allowed)
		)
		(placement
			(enabled no)
			(sheetname "")
		)
		(fill
			(thermal_gap 0.5)
			(thermal_bridge_width 0.5)
			(island_removal_mode 0)
		)
		(polygon
			(pts
				(xy 0.999998 -328.972418) (xy 19.150076 -328.972418)
				(arc
					(start 19.150076 -305.282854)
					(mid 16.987838 -303.859495)
					(end 16.150082 -301.410116)
				)
				(arc
					(start 16.150082 -301.410116)
					(mid 16.987804 -298.96063)
					(end 19.150076 -297.537124)
				)
				(xy 19.150076 -266.897612) (xy 0.999998 -266.897612)
				(arc
					(start 0.999998 -308.28742)
					(mid 2.22299 -307.619351)
					(end 3.600958 -307.411374)
				)
				(xy 3.600958 -300.070012) (xy 15.600934 -300.070012) (xy 15.600934 -312.069988)
				(arc
					(start 7.445248 -312.069988)
					(mid 4.9277 -315.146606)
					(end 0.999998 -314.532518)
				)
			)
		)
	)
	(zone
		(layer "B.Cu")
		(hatch none 0.5)
		(connect_pads
			(clearance 0)
		)
		(min_thickness 0.25)
		(keepout
			(tracks not_allowed)
			(vias allowed)
			(pads allowed)
			(copperpour not_allowed)
			(footprints allowed)
		)
		(placement
			(enabled no)
			(sheetname "")
		)
		(fill
			(thermal_gap 0.5)
			(thermal_bridge_width 0.5)
			(island_removal_mode 0)
		)
		(polygon
			(pts
				(arc
					(start 208.000092 -320.900044)
					(mid 205.75016 -318.650112)
					(end 203.499974 -320.900044)
				)
				(arc
					(start 203.499974 -320.900044)
					(mid 205.75016 -323.15023)
					(end 208.000092 -320.900044)
				)
			)
		)
	)
	(zone
		(layer "B.Cu")
		(hatch none 0.5)
		(connect_pads
			(clearance 0)
		)
		(min_thickness 0.25)
		(keepout
			(tracks not_allowed)
			(vias allowed)
			(pads allowed)
			(copperpour not_allowed)
			(footprints allowed)
		)
		(placement
			(enabled no)
			(sheetname "")
		)
		(fill
			(thermal_gap 0.5)
			(thermal_bridge_width 0.5)
			(island_removal_mode 0)
		)
		(polygon
			(pts
				(arc
					(start 324.099936 -320.900044)
					(mid 321.850004 -318.650112)
					(end 319.600072 -320.900044)
				)
				(arc
					(start 319.600072 -320.900044)
					(mid 321.850004 -323.149976)
					(end 324.099936 -320.900044)
				)
			)
		)
	)
	(zone
		(layer "B.Cu")
		(hatch none 0.5)
		(connect_pads
			(clearance 0)
		)
		(min_thickness 0.25)
		(keepout
			(tracks not_allowed)
			(vias allowed)
			(pads allowed)
			(copperpour not_allowed)
			(footprints allowed)
		)
		(placement
			(enabled no)
			(sheetname "")
		)
		(fill
			(thermal_gap 0.5)
			(thermal_bridge_width 0.5)
			(island_removal_mode 0)
		)
		(polygon
			(pts
				(arc
					(start 76.12634 -316.799722)
					(mid 75.47356 -316.799722)
					(end 76.12634 -316.799722)
				)
			)
		)
	)
	(zone
		(layer "B.Cu")
		(hatch none 0.5)
		(connect_pads
			(clearance 0)
		)
		(min_thickness 0.25)
		(keepout
			(tracks allowed)
			(vias allowed)
			(pads allowed)
			(copperpour allowed)
			(footprints not_allowed)
		)
		(placement
			(enabled no)
			(sheetname "")
		)
		(fill
			(thermal_gap 0.5)
			(thermal_bridge_width 0.5)
			(island_removal_mode 0)
		)
		(polygon
			(pts
				(xy 274.62988 -117.380004) (xy 254.62992 -117.380004) (xy 254.62992 -137.379964) (xy 274.62988 -137.379964)
			)
		)
	)
	(zone
		(layer "B.Cu")
		(hatch none 0.5)
		(connect_pads
			(clearance 0)
		)
		(min_thickness 0.25)
		(keepout
			(tracks allowed)
			(vias allowed)
			(pads allowed)
			(copperpour allowed)
			(footprints allowed)
		)
		(placement
			(enabled no)
			(sheetname "")
		)
		(fill
			(thermal_gap 0.5)
			(thermal_bridge_width 0.5)
			(island_removal_mode 0)
		)
		(polygon
			(pts
				(xy 383.111248 -231.441244) (xy 383.111248 -230.28656) (xy 385.231132 -230.28656) (xy 385.231132 -231.441244)
			)
		)
	)
	(zone
		(layer "B.Cu")
		(hatch none 0.5)
		(connect_pads
			(clearance 0)
		)
		(min_thickness 0.25)
		(keepout
			(tracks not_allowed)
			(vias allowed)
			(pads allowed)
			(copperpour not_allowed)
			(footprints allowed)
		)
		(placement
			(enabled no)
			(sheetname "")
		)
		(fill
			(thermal_gap 0.5)
			(thermal_bridge_width 0.5)
			(island_removal_mode 0)
		)
		(polygon
			(pts
				(arc
					(start 392.126216 -316.799722)
					(mid 391.473436 -316.799722)
					(end 392.126216 -316.799722)
				)
			)
		)
	)
	(zone
		(layer "B.Cu")
		(hatch none 0.5)
		(connect_pads
			(clearance 0)
		)
		(min_thickness 0.25)
		(keepout
			(tracks allowed)
			(vias allowed)
			(pads allowed)
			(copperpour allowed)
			(footprints allowed)
		)
		(placement
			(enabled no)
			(sheetname "")
		)
		(fill
			(thermal_gap 0.5)
			(thermal_bridge_width 0.5)
			(island_removal_mode 0)
		)
		(polygon
			(pts
				(xy 108.45292 -333.065628) (xy 111.53013 -333.065628) (xy 111.68761 -332.908148) (xy 111.68761 -330.250292)
				(xy 111.600234 -330.162916) (xy 108.479336 -330.162916) (xy 108.41355 -330.228702) (xy 108.41355 -333.026258)
			)
		)
	)
	(zone
		(layer "B.Cu")
		(hatch none 0.5)
		(connect_pads
			(clearance 0)
		)
		(min_thickness 0.25)
		(keepout
			(tracks allowed)
			(vias allowed)
			(pads allowed)
			(copperpour allowed)
			(footprints allowed)
		)
		(placement
			(enabled no)
			(sheetname "")
		)
		(fill
			(thermal_gap 0.5)
			(thermal_bridge_width 0.5)
			(island_removal_mode 0)
		)
		(polygon
			(pts
				(xy 236.72038 -218.39428) (xy 237.383574 -218.39428) (xy 237.901988 -217.875866) (xy 237.901988 -217.494612)
				(xy 237.749588 -217.342212) (xy 237.132114 -217.342212) (xy 236.47654 -217.997786) (xy 236.47654 -218.15044)
			)
		)
	)
	(zone
		(layer "B.Cu")
		(hatch none 0.5)
		(connect_pads
			(clearance 0)
		)
		(min_thickness 0.25)
		(keepout
			(tracks allowed)
			(vias allowed)
			(pads allowed)
			(copperpour allowed)
			(footprints allowed)
		)
		(placement
			(enabled no)
			(sheetname "")
		)
		(fill
			(thermal_gap 0.5)
			(thermal_bridge_width 0.5)
			(island_removal_mode 0)
		)
		(polygon
			(pts
				(xy 129.110994 -318.516) (xy 129.110994 -316.865) (xy 131.269994 -316.865) (xy 131.269994 -318.516)
			)
		)
	)
	(zone
		(layer "B.Cu")
		(hatch none 0.5)
		(connect_pads
			(clearance 0)
		)
		(min_thickness 0.25)
		(keepout
			(tracks not_allowed)
			(vias allowed)
			(pads allowed)
			(copperpour not_allowed)
			(footprints allowed)
		)
		(placement
			(enabled no)
			(sheetname "")
		)
		(fill
			(thermal_gap 0.5)
			(thermal_bridge_width 0.5)
			(island_removal_mode 0)
		)
		(polygon
			(pts
				(arc
					(start 235.191046 -87.386414)
					(mid 234.487466 -87.386414)
					(end 235.191046 -87.386414)
				)
			)
		)
	)
	(zone
		(layer "B.Cu")
		(hatch none 0.5)
		(connect_pads
			(clearance 0)
		)
		(min_thickness 0.25)
		(keepout
			(tracks not_allowed)
			(vias allowed)
			(pads allowed)
			(copperpour not_allowed)
			(footprints allowed)
		)
		(placement
			(enabled no)
			(sheetname "")
		)
		(fill
			(thermal_gap 0.5)
			(thermal_bridge_width 0.5)
			(island_removal_mode 0)
		)
		(polygon
			(pts
				(arc
					(start 292.269672 -379.590046)
					(mid 291.510212 -379.590046)
					(end 292.269672 -379.590046)
				)
			)
		)
	)
	(zone
		(layer "B.Cu")
		(hatch none 0.5)
		(connect_pads
			(clearance 0)
		)
		(min_thickness 0.25)
		(keepout
			(tracks not_allowed)
			(vias allowed)
			(pads allowed)
			(copperpour not_allowed)
			(footprints allowed)
		)
		(placement
			(enabled no)
			(sheetname "")
		)
		(fill
			(thermal_gap 0.5)
			(thermal_bridge_width 0.5)
			(island_removal_mode 0)
		)
		(polygon
			(pts
				(arc
					(start 85.149944 -320.900044)
					(mid 89.650062 -325.400162)
					(end 94.149926 -320.900044)
				)
				(arc
					(start 94.149926 -320.900044)
					(mid 89.650062 -316.40018)
					(end 85.149944 -320.900044)
				)
			)
		)
	)
	(zone
		(layer "B.Cu")
		(hatch none 0.5)
		(connect_pads
			(clearance 0)
		)
		(min_thickness 0.25)
		(keepout
			(tracks not_allowed)
			(vias allowed)
			(pads allowed)
			(copperpour not_allowed)
			(footprints allowed)
		)
		(placement
			(enabled no)
			(sheetname "")
		)
		(fill
			(thermal_gap 0.5)
			(thermal_bridge_width 0.5)
			(island_removal_mode 0)
		)
		(polygon
			(pts
				(arc
					(start 183.67629 -318.699896)
					(mid 183.02351 -318.699896)
					(end 183.67629 -318.699896)
				)
			)
		)
	)
	(zone
		(layer "B.Cu")
		(hatch none 0.5)
		(connect_pads
			(clearance 0)
		)
		(min_thickness 0.25)
		(keepout
			(tracks allowed)
			(vias allowed)
			(pads allowed)
			(copperpour allowed)
			(footprints not_allowed)
		)
		(placement
			(enabled no)
			(sheetname "")
		)
		(fill
			(thermal_gap 0.5)
			(thermal_bridge_width 0.5)
			(island_removal_mode 0)
		)
		(polygon
			(pts
				(xy 281.850084 -84.68995) (xy 301.850044 -84.68995) (xy 301.850044 -64.68999) (xy 281.850084 -64.68999)
			)
		)
	)
	(zone
		(layer "B.Cu")
		(hatch none 0.5)
		(connect_pads
			(clearance 0)
		)
		(min_thickness 0.25)
		(keepout
			(tracks allowed)
			(vias allowed)
			(pads allowed)
			(copperpour allowed)
			(footprints allowed)
		)
		(placement
			(enabled no)
			(sheetname "")
		)
		(fill
			(thermal_gap 0.5)
			(thermal_bridge_width 0.5)
			(island_removal_mode 0)
		)
		(polygon
			(pts
				(xy 223.8756 -224.917) (xy 224.4598 -224.917) (xy 224.8916 -224.4852) (xy 224.8916 -222.5548) (xy 224.8408 -222.504)
				(xy 224.3582 -222.504) (xy 223.8756 -222.9866)
			)
		)
	)
	(zone
		(layer "B.Cu")
		(hatch none 0.5)
		(connect_pads
			(clearance 0)
		)
		(min_thickness 0.25)
		(keepout
			(tracks not_allowed)
			(vias allowed)
			(pads allowed)
			(copperpour not_allowed)
			(footprints allowed)
		)
		(placement
			(enabled no)
			(sheetname "")
		)
		(fill
			(thermal_gap 0.5)
			(thermal_bridge_width 0.5)
			(island_removal_mode 0)
		)
		(polygon
			(pts
				(arc
					(start 82.776314 -310.149748)
					(mid 82.123534 -310.149748)
					(end 82.776314 -310.149748)
				)
			)
		)
	)
	(zone
		(layer "B.Cu")
		(hatch none 0.5)
		(connect_pads
			(clearance 0)
		)
		(min_thickness 0.25)
		(keepout
			(tracks allowed)
			(vias allowed)
			(pads allowed)
			(copperpour allowed)
			(footprints not_allowed)
		)
		(placement
			(enabled no)
			(sheetname "")
		)
		(fill
			(thermal_gap 0.5)
			(thermal_bridge_width 0.5)
			(island_removal_mode 0)
		)
		(polygon
			(pts
				(arc
					(start 448.449954 -264.899902)
					(mid 447.131974 -261.718018)
					(end 443.95009 -260.400038)
				)
				(arc
					(start 371.94998 -260.400038)
					(mid 368.768096 -261.718018)
					(end 367.450116 -264.899902)
				)
				(xy 367.450116 -266.897612) (xy 332.35011 -266.897612)
				(arc
					(start 332.35011 -264.899902)
					(mid 331.031951 -261.718092)
					(end 327.849992 -260.400038)
				)
				(arc
					(start 255.849882 -260.400038)
					(mid 252.667998 -261.718018)
					(end 251.350018 -264.899902)
				)
				(xy 251.350018 -266.897612) (xy 216.250012 -266.897612)
				(arc
					(start 216.250012 -264.899902)
					(mid 214.931853 -261.718092)
					(end 211.749894 -260.400038)
				)
				(arc
					(start 139.750038 -260.400038)
					(mid 136.568064 -261.718002)
					(end 135.24992 -264.899902)
				)
				(xy 135.24992 -266.897612) (xy 100.149914 -266.897612)
				(arc
					(start 100.149914 -264.899902)
					(mid 98.831934 -261.718018)
					(end 95.65005 -260.400038)
				)
				(arc
					(start 23.64994 -260.400038)
					(mid 20.468056 -261.718018)
					(end 19.150076 -264.899902)
				)
				(xy 19.150076 -266.897612) (xy 0.999998 -266.897612)
				(arc
					(start 0.999998 -246.488458)
					(mid 1.076118 -246.105775)
					(end 1.29286 -245.781322)
				)
				(arc
					(start 3.921252 -243.15293)
					(mid 4.57168 -242.179635)
					(end 4.800092 -241.031522)
				)
				(arc
					(start 4.800092 -87.588344)
					(mid 4.571648 -86.44035)
					(end 3.921252 -85.46719)
				)
				(arc
					(start 1.29286 -82.838798)
					(mid 1.076078 -82.514361)
					(end 0.999998 -82.131662)
				)
				(xy 0.999998 -50.120042) (xy 466.600032 -50.120042)
				(arc
					(start 466.600032 -82.131662)
					(mid 466.523912 -82.514345)
					(end 466.30717 -82.838798)
				)
				(arc
					(start 463.678778 -85.46719)
					(mid 463.028428 -86.440369)
					(end 462.799938 -87.588344)
				)
				(arc
					(start 462.799938 -241.031522)
					(mid 463.028401 -242.179614)
					(end 463.678778 -243.15293)
				)
				(arc
					(start 466.30717 -245.781322)
					(mid 466.523952 -246.105759)
					(end 466.600032 -246.488458)
				)
				(xy 466.600032 -266.897612) (xy 448.449954 -266.897612)
			)
		)
	)
	(zone
		(layer "B.Cu")
		(hatch none 0.5)
		(connect_pads
			(clearance 0)
		)
		(min_thickness 0.25)
		(keepout
			(tracks not_allowed)
			(vias allowed)
			(pads allowed)
			(copperpour not_allowed)
			(footprints allowed)
		)
		(placement
			(enabled no)
			(sheetname "")
		)
		(fill
			(thermal_gap 0.5)
			(thermal_bridge_width 0.5)
			(island_removal_mode 0)
		)
		(polygon
			(pts
				(arc
					(start 186.526424 -316.799722)
					(mid 185.873644 -316.799722)
					(end 186.526424 -316.799722)
				)
			)
		)
	)
	(zone
		(layer "B.Cu")
		(hatch none 0.5)
		(connect_pads
			(clearance 0)
		)
		(min_thickness 0.25)
		(keepout
			(tracks not_allowed)
			(vias allowed)
			(pads allowed)
			(copperpour not_allowed)
			(footprints allowed)
		)
		(placement
			(enabled no)
			(sheetname "")
		)
		(fill
			(thermal_gap 0.5)
			(thermal_bridge_width 0.5)
			(island_removal_mode 0)
		)
		(polygon
			(pts
				(arc
					(start 375.869708 -401.690078)
					(mid 375.110248 -401.690078)
					(end 375.869708 -401.690078)
				)
			)
		)
	)
	(zone
		(layer "B.Cu")
		(hatch none 0.5)
		(connect_pads
			(clearance 0)
		)
		(min_thickness 0.25)
		(keepout
			(tracks allowed)
			(vias allowed)
			(pads allowed)
			(copperpour allowed)
			(footprints not_allowed)
		)
		(placement
			(enabled no)
			(sheetname "")
		)
		(fill
			(thermal_gap 0.5)
			(thermal_bridge_width 0.5)
			(island_removal_mode 0)
		)
		(polygon
			(pts
				(arc
					(start 23.64994 -260.400038)
					(mid 20.468056 -261.718018)
					(end 19.150076 -264.899902)
				)
				(arc
					(start 19.150076 -326.900032)
					(mid 20.468056 -330.081916)
					(end 23.64994 -331.399896)
				)
				(arc
					(start 95.65005 -331.399896)
					(mid 98.831934 -330.081916)
					(end 100.149914 -326.900032)
				)
				(arc
					(start 100.149914 -264.899902)
					(mid 98.831934 -261.718018)
					(end 95.65005 -260.400038)
				)
			)
		)
	)
	(zone
		(layer "B.Cu")
		(hatch none 0.5)
		(connect_pads
			(clearance 0)
		)
		(min_thickness 0.25)
		(keepout
			(tracks allowed)
			(vias allowed)
			(pads allowed)
			(copperpour allowed)
			(footprints not_allowed)
		)
		(placement
			(enabled no)
			(sheetname "")
		)
		(fill
			(thermal_gap 0.5)
			(thermal_bridge_width 0.5)
			(island_removal_mode 0)
		)
		(polygon
			(pts
				(arc
					(start 416.919918 -15.649956)
					(mid 418.919914 -17.649952)
					(end 420.91991 -15.649956)
				)
				(arc
					(start 420.91991 -15.649956)
					(mid 418.919914 -13.64996)
					(end 416.919918 -15.649956)
				)
			)
		)
	)
	(zone
		(layer "B.Cu")
		(hatch none 0.5)
		(connect_pads
			(clearance 0)
		)
		(min_thickness 0.25)
		(keepout
			(tracks not_allowed)
			(vias allowed)
			(pads allowed)
			(copperpour not_allowed)
			(footprints allowed)
		)
		(placement
			(enabled no)
			(sheetname "")
		)
		(fill
			(thermal_gap 0.5)
			(thermal_bridge_width 0.5)
			(island_removal_mode 0)
		)
		(polygon
			(pts
				(arc
					(start 159.926274 -315.849762)
					(mid 159.273494 -315.849762)
					(end 159.926274 -315.849762)
				)
			)
		)
	)
	(zone
		(layer "B.Cu")
		(hatch none 0.5)
		(connect_pads
			(clearance 0)
		)
		(min_thickness 0.25)
		(keepout
			(tracks allowed)
			(vias allowed)
			(pads allowed)
			(copperpour allowed)
			(footprints not_allowed)
		)
		(placement
			(enabled no)
			(sheetname "")
		)
		(fill
			(thermal_gap 0.5)
			(thermal_bridge_width 0.5)
			(island_removal_mode 0)
		)
		(polygon
			(pts
				(xy 165.749986 -190.069978) (xy 185.749946 -190.069978) (xy 185.749946 -170.070018) (xy 165.749986 -170.070018)
			)
		)
	)
	(zone
		(layer "B.Cu")
		(hatch none 0.5)
		(connect_pads
			(clearance 0)
		)
		(min_thickness 0.25)
		(keepout
			(tracks allowed)
			(vias allowed)
			(pads allowed)
			(copperpour allowed)
			(footprints allowed)
		)
		(placement
			(enabled no)
			(sheetname "")
		)
		(fill
			(thermal_gap 0.5)
			(thermal_bridge_width 0.5)
			(island_removal_mode 0)
		)
		(polygon
			(pts
				(xy 100.007166 -332.272894) (xy 101.334062 -332.272894) (xy 101.37902 -332.227936) (xy 101.37902 -331.894434)
				(xy 101.214174 -331.729588) (xy 100.052124 -331.729588) (xy 99.924616 -331.857096) (xy 99.924616 -332.190344)
			)
		)
	)
	(zone
		(layer "B.Cu")
		(hatch none 0.5)
		(connect_pads
			(clearance 0)
		)
		(min_thickness 0.25)
		(keepout
			(tracks allowed)
			(vias allowed)
			(pads allowed)
			(copperpour allowed)
			(footprints not_allowed)
		)
		(placement
			(enabled no)
			(sheetname "")
		)
		(fill
			(thermal_gap 0.5)
			(thermal_bridge_width 0.5)
			(island_removal_mode 0)
		)
		(polygon
			(pts
				(arc
					(start 51.799998 -407.960068)
					(mid 59.799982 -415.960052)
					(end 67.799966 -407.960068)
				)
				(arc
					(start 67.799966 -407.960068)
					(mid 59.799982 -399.960084)
					(end 51.799998 -407.960068)
				)
			)
		)
	)
	(zone
		(layer "B.Cu")
		(hatch none 0.5)
		(connect_pads
			(clearance 0)
		)
		(min_thickness 0.25)
		(keepout
			(tracks allowed)
			(vias allowed)
			(pads allowed)
			(copperpour allowed)
			(footprints allowed)
		)
		(placement
			(enabled no)
			(sheetname "")
		)
		(fill
			(thermal_gap 0.5)
			(thermal_bridge_width 0.5)
			(island_removal_mode 0)
		)
		(polygon
			(pts
				(xy 243.247418 -267.970762) (xy 243.247418 -265.811762) (xy 245.025418 -265.811762) (xy 245.025418 -267.970762)
			)
		)
	)
	(zone
		(layer "B.Cu")
		(hatch none 0.5)
		(connect_pads
			(clearance 0)
		)
		(min_thickness 0.25)
		(keepout
			(tracks not_allowed)
			(vias allowed)
			(pads allowed)
			(copperpour not_allowed)
			(footprints allowed)
		)
		(placement
			(enabled no)
			(sheetname "")
		)
		(fill
			(thermal_gap 0.5)
			(thermal_bridge_width 0.5)
			(island_removal_mode 0)
		)
		(polygon
			(pts
				(arc
					(start 303.26965 -406.690068)
					(mid 302.51019 -406.690068)
					(end 303.26965 -406.690068)
				)
			)
		)
	)
	(zone
		(layer "B.Cu")
		(hatch none 0.5)
		(connect_pads
			(clearance 0)
		)
		(min_thickness 0.25)
		(keepout
			(tracks allowed)
			(vias allowed)
			(pads allowed)
			(copperpour allowed)
			(footprints not_allowed)
		)
		(placement
			(enabled no)
			(sheetname "")
		)
		(fill
			(thermal_gap 0.5)
			(thermal_bridge_width 0.5)
			(island_removal_mode 0)
		)
		(polygon
			(pts
				(xy 15.600934 -300.070012) (xy 3.600958 -300.070012) (xy 3.600958 -312.069988) (xy 15.600934 -312.069988)
			)
		)
	)
	(zone
		(layer "B.Cu")
		(hatch none 0.5)
		(connect_pads
			(clearance 0)
		)
		(min_thickness 0.25)
		(keepout
			(tracks not_allowed)
			(vias allowed)
			(pads allowed)
			(copperpour not_allowed)
			(footprints allowed)
		)
		(placement
			(enabled no)
			(sheetname "")
		)
		(fill
			(thermal_gap 0.5)
			(thermal_bridge_width 0.5)
			(island_removal_mode 0)
		)
		(polygon
			(pts
				(arc
					(start 203.419964 -20.72005)
					(mid 201.419968 -18.720054)
					(end 199.419972 -20.72005)
				)
				(arc
					(start 199.419972 -20.72005)
					(mid 201.419968 -22.720046)
					(end 203.419964 -20.72005)
				)
			)
		)
	)
	(zone
		(layer "B.Cu")
		(hatch none 0.5)
		(connect_pads
			(clearance 0)
		)
		(min_thickness 0.25)
		(keepout
			(tracks allowed)
			(vias allowed)
			(pads allowed)
			(copperpour allowed)
			(footprints allowed)
		)
		(placement
			(enabled no)
			(sheetname "")
		)
		(fill
			(thermal_gap 0.5)
			(thermal_bridge_width 0.5)
			(island_removal_mode 0)
		)
		(polygon
			(pts
				(xy 226.217734 -60.678568) (xy 226.217734 -58.689494) (xy 227.70211 -58.689494) (xy 227.70211 -60.678568)
			)
		)
	)
	(zone
		(layer "B.Cu")
		(hatch none 0.5)
		(connect_pads
			(clearance 0)
		)
		(min_thickness 0.25)
		(keepout
			(tracks not_allowed)
			(vias allowed)
			(pads allowed)
			(copperpour not_allowed)
			(footprints allowed)
		)
		(placement
			(enabled no)
			(sheetname "")
		)
		(fill
			(thermal_gap 0.5)
			(thermal_bridge_width 0.5)
			(island_removal_mode 0)
		)
		(polygon
			(pts
				(arc
					(start 23.9649 -17.999964)
					(mid 25.964896 -19.99996)
					(end 27.964892 -17.999964)
				)
				(arc
					(start 27.964892 -17.999964)
					(mid 25.964896 -15.999968)
					(end 23.9649 -17.999964)
				)
			)
		)
	)
	(zone
		(layer "B.Cu")
		(hatch none 0.5)
		(connect_pads
			(clearance 0)
		)
		(min_thickness 0.25)
		(keepout
			(tracks not_allowed)
			(vias allowed)
			(pads allowed)
			(copperpour not_allowed)
			(footprints allowed)
		)
		(placement
			(enabled no)
			(sheetname "")
		)
		(fill
			(thermal_gap 0.5)
			(thermal_bridge_width 0.5)
			(island_removal_mode 0)
		)
		(polygon
			(pts
				(arc
					(start 77.0763 -317.749936)
					(mid 76.42352 -317.749936)
					(end 77.0763 -317.749936)
				)
			)
		)
	)
	(zone
		(layer "B.Cu")
		(hatch none 0.5)
		(connect_pads
			(clearance 0)
		)
		(min_thickness 0.25)
		(keepout
			(tracks allowed)
			(vias allowed)
			(pads allowed)
			(copperpour allowed)
			(footprints not_allowed)
		)
		(placement
			(enabled no)
			(sheetname "")
		)
		(fill
			(thermal_gap 0.5)
			(thermal_bridge_width 0.5)
			(island_removal_mode 0)
		)
		(polygon
			(pts
				(arc
					(start 16.619982 -15.649956)
					(mid 18.619978 -17.649952)
					(end 20.619974 -15.649956)
				)
				(arc
					(start 20.619974 -15.649956)
					(mid 18.619978 -13.64996)
					(end 16.619982 -15.649956)
				)
			)
		)
	)
	(zone
		(layer "B.Cu")
		(hatch none 0.5)
		(connect_pads
			(clearance 0)
		)
		(min_thickness 0.25)
		(keepout
			(tracks allowed)
			(vias allowed)
			(pads allowed)
			(copperpour allowed)
			(footprints not_allowed)
		)
		(placement
			(enabled no)
			(sheetname "")
		)
		(fill
			(thermal_gap 0.5)
			(thermal_bridge_width 0.5)
			(island_removal_mode 0)
		)
		(polygon
			(pts
				(arc
					(start 57.319926 -20.72005)
					(mid 59.319922 -22.720046)
					(end 61.319918 -20.72005)
				)
				(arc
					(start 61.319918 -20.72005)
					(mid 59.319922 -18.720054)
					(end 57.319926 -20.72005)
				)
			)
		)
	)
	(zone
		(layer "B.Cu")
		(hatch none 0.5)
		(connect_pads
			(clearance 0)
		)
		(min_thickness 0.25)
		(keepout
			(tracks allowed)
			(vias allowed)
			(pads allowed)
			(copperpour allowed)
			(footprints allowed)
		)
		(placement
			(enabled no)
			(sheetname "")
		)
		(fill
			(thermal_gap 0.5)
			(thermal_bridge_width 0.5)
			(island_removal_mode 0)
		)
		(polygon
			(pts
				(xy 234.230418 -267.970762) (xy 234.230418 -265.811762) (xy 236.008418 -265.811762) (xy 236.008418 -267.970762)
			)
		)
	)
	(zone
		(layer "B.Cu")
		(hatch none 0.5)
		(connect_pads
			(clearance 0)
		)
		(min_thickness 0.25)
		(keepout
			(tracks not_allowed)
			(vias allowed)
			(pads allowed)
			(copperpour not_allowed)
			(footprints allowed)
		)
		(placement
			(enabled no)
			(sheetname "")
		)
		(fill
			(thermal_gap 0.5)
			(thermal_bridge_width 0.5)
			(island_removal_mode 0)
		)
		(polygon
			(pts
				(arc
					(start 183.67629 -317.749936)
					(mid 183.02351 -317.749936)
					(end 183.67629 -317.749936)
				)
			)
		)
	)
	(zone
		(layer "B.Cu")
		(hatch none 0.5)
		(connect_pads
			(clearance 0)
		)
		(min_thickness 0.25)
		(keepout
			(tracks allowed)
			(vias allowed)
			(pads allowed)
			(copperpour allowed)
			(footprints allowed)
		)
		(placement
			(enabled no)
			(sheetname "")
		)
		(fill
			(thermal_gap 0.5)
			(thermal_bridge_width 0.5)
			(island_removal_mode 0)
		)
		(polygon
			(pts
				(xy 21.400262 -230.58628) (xy 22.169628 -230.58628) (xy 22.347428 -230.40848) (xy 22.347428 -228.226874)
				(xy 21.544026 -228.226874) (xy 21.36648 -228.40442) (xy 21.36648 -230.552498)
			)
		)
	)
	(zone
		(layer "B.Cu")
		(hatch none 0.5)
		(connect_pads
			(clearance 0)
		)
		(min_thickness 0.25)
		(keepout
			(tracks not_allowed)
			(vias allowed)
			(pads allowed)
			(copperpour not_allowed)
			(footprints allowed)
		)
		(placement
			(enabled no)
			(sheetname "")
		)
		(fill
			(thermal_gap 0.5)
			(thermal_bridge_width 0.5)
			(island_removal_mode 0)
		)
		(polygon
			(pts
				(arc
					(start 394.97635 -317.749936)
					(mid 394.32357 -317.749936)
					(end 394.97635 -317.749936)
				)
			)
		)
	)
	(zone
		(layer "B.Cu")
		(hatch none 0.5)
		(connect_pads
			(clearance 0)
		)
		(min_thickness 0.25)
		(keepout
			(tracks not_allowed)
			(vias allowed)
			(pads allowed)
			(copperpour not_allowed)
			(footprints allowed)
		)
		(placement
			(enabled no)
			(sheetname "")
		)
		(fill
			(thermal_gap 0.5)
			(thermal_bridge_width 0.5)
			(island_removal_mode 0)
		)
		(polygon
			(pts
				(arc
					(start 122.889772 -371.590062)
					(mid 122.130312 -371.590062)
					(end 122.889772 -371.590062)
				)
			)
		)
	)
	(zone
		(layer "B.Cu")
		(hatch none 0.5)
		(connect_pads
			(clearance 0)
		)
		(min_thickness 0.25)
		(keepout
			(tracks not_allowed)
			(vias allowed)
			(pads allowed)
			(copperpour not_allowed)
			(footprints allowed)
		)
		(placement
			(enabled no)
			(sheetname "")
		)
		(fill
			(thermal_gap 0.5)
			(thermal_bridge_width 0.5)
			(island_removal_mode 0)
		)
		(polygon
			(pts
				(arc
					(start 164.676328 -318.699896)
					(mid 164.023548 -318.699896)
					(end 164.676328 -318.699896)
				)
			)
		)
	)
	(zone
		(layer "B.Cu")
		(hatch none 0.5)
		(connect_pads
			(clearance 0)
		)
		(min_thickness 0.25)
		(keepout
			(tracks not_allowed)
			(vias allowed)
			(pads allowed)
			(copperpour not_allowed)
			(footprints allowed)
		)
		(placement
			(enabled no)
			(sheetname "")
		)
		(fill
			(thermal_gap 0.5)
			(thermal_bridge_width 0.5)
			(island_removal_mode 0)
		)
		(polygon
			(pts
				(arc
					(start 78.97622 -317.749936)
					(mid 78.32344 -317.749936)
					(end 78.97622 -317.749936)
				)
			)
		)
	)
	(zone
		(layer "B.Cu")
		(hatch none 0.5)
		(connect_pads
			(clearance 0)
		)
		(min_thickness 0.25)
		(keepout
			(tracks not_allowed)
			(vias allowed)
			(pads allowed)
			(copperpour not_allowed)
			(footprints allowed)
		)
		(placement
			(enabled no)
			(sheetname "")
		)
		(fill
			(thermal_gap 0.5)
			(thermal_bridge_width 0.5)
			(island_removal_mode 0)
		)
		(polygon
			(pts
				(arc
					(start 208.000092 -270.89989)
					(mid 205.75016 -268.649958)
					(end 203.499974 -270.89989)
				)
				(arc
					(start 203.499974 -270.89989)
					(mid 205.75016 -273.150076)
					(end 208.000092 -270.89989)
				)
			)
		)
	)
	(zone
		(layer "B.Cu")
		(hatch none 0.5)
		(connect_pads
			(clearance 0)
		)
		(min_thickness 0.25)
		(keepout
			(tracks not_allowed)
			(vias allowed)
			(pads allowed)
			(copperpour not_allowed)
			(footprints allowed)
		)
		(placement
			(enabled no)
			(sheetname "")
		)
		(fill
			(thermal_gap 0.5)
			(thermal_bridge_width 0.5)
			(island_removal_mode 0)
		)
		(polygon
			(pts
				(arc
					(start 80.87614 -318.699896)
					(mid 80.22336 -318.699896)
					(end 80.87614 -318.699896)
				)
			)
		)
	)
	(zone
		(layer "B.Cu")
		(hatch none 0.5)
		(connect_pads
			(clearance 0)
		)
		(min_thickness 0.25)
		(keepout
			(tracks not_allowed)
			(vias allowed)
			(pads allowed)
			(copperpour not_allowed)
			(footprints allowed)
		)
		(placement
			(enabled no)
			(sheetname "")
		)
		(fill
			(thermal_gap 0.5)
			(thermal_bridge_width 0.5)
			(island_removal_mode 0)
		)
		(polygon
			(pts
				(arc
					(start 238.799878 -194.360038)
					(mid 233.799888 -189.360048)
					(end 228.799898 -194.360038)
				)
				(arc
					(start 228.799898 -194.360038)
					(mid 233.799888 -199.360028)
					(end 238.799878 -194.360038)
				)
			)
		)
	)
	(zone
		(layer "B.Cu")
		(hatch none 0.5)
		(connect_pads
			(clearance 0)
		)
		(min_thickness 0.25)
		(keepout
			(tracks allowed)
			(vias allowed)
			(pads allowed)
			(copperpour allowed)
			(footprints not_allowed)
		)
		(placement
			(enabled no)
			(sheetname "")
		)
		(fill
			(thermal_gap 0.5)
			(thermal_bridge_width 0.5)
			(island_removal_mode 0)
		)
		(polygon
			(pts
				(xy 49.649888 -190.069978) (xy 69.650102 -190.069978) (xy 69.650102 -170.070018) (xy 49.649888 -170.070018)
			)
		)
	)
	(zone
		(layer "B.Cu")
		(hatch none 0.5)
		(connect_pads
			(clearance 0)
		)
		(min_thickness 0.25)
		(keepout
			(tracks not_allowed)
			(vias allowed)
			(pads allowed)
			(copperpour not_allowed)
			(footprints allowed)
		)
		(placement
			(enabled no)
			(sheetname "")
		)
		(fill
			(thermal_gap 0.5)
			(thermal_bridge_width 0.5)
			(island_removal_mode 0)
		)
		(polygon
			(pts
				(arc
					(start 419.676326 -317.749936)
					(mid 419.023546 -317.749936)
					(end 419.676326 -317.749936)
				)
			)
		)
	)
	(zone
		(layer "B.Cu")
		(hatch none 0.5)
		(connect_pads
			(clearance 0)
		)
		(min_thickness 0.25)
		(keepout
			(tracks not_allowed)
			(vias allowed)
			(pads allowed)
			(copperpour not_allowed)
			(footprints allowed)
		)
		(placement
			(enabled no)
			(sheetname "")
		)
		(fill
			(thermal_gap 0.5)
			(thermal_bridge_width 0.5)
			(island_removal_mode 0)
		)
		(polygon
			(pts
				(arc
					(start 43.689778 -406.690068)
					(mid 42.930318 -406.690068)
					(end 43.689778 -406.690068)
				)
			)
		)
	)
	(zone
		(layer "B.Cu")
		(hatch none 0.5)
		(connect_pads
			(clearance 0)
		)
		(min_thickness 0.25)
		(keepout
			(tracks not_allowed)
			(vias allowed)
			(pads allowed)
			(copperpour not_allowed)
			(footprints allowed)
		)
		(placement
			(enabled no)
			(sheetname "")
		)
		(fill
			(thermal_gap 0.5)
			(thermal_bridge_width 0.5)
			(island_removal_mode 0)
		)
		(polygon
			(pts
				(arc
					(start 397.82623 -316.799722)
					(mid 397.17345 -316.799722)
					(end 397.82623 -316.799722)
				)
			)
		)
	)
	(zone
		(layer "B.Cu")
		(hatch none 0.5)
		(connect_pads
			(clearance 0)
		)
		(min_thickness 0.25)
		(keepout
			(tracks not_allowed)
			(vias allowed)
			(pads allowed)
			(copperpour not_allowed)
			(footprints allowed)
		)
		(placement
			(enabled no)
			(sheetname "")
		)
		(fill
			(thermal_gap 0.5)
			(thermal_bridge_width 0.5)
			(island_removal_mode 0)
		)
		(polygon
			(pts
				(arc
					(start 223.315022 -5.999988)
					(mid 226.115118 -8.800084)
					(end 228.91496 -5.999988)
				)
				(arc
					(start 228.91496 -5.999988)
					(mid 226.115118 -3.200146)
					(end 223.315022 -5.999988)
				)
			)
		)
	)
	(zone
		(layer "B.Cu")
		(hatch none 0.5)
		(connect_pads
			(clearance 0)
		)
		(min_thickness 0.25)
		(keepout
			(tracks not_allowed)
			(vias allowed)
			(pads allowed)
			(copperpour not_allowed)
			(footprints allowed)
		)
		(placement
			(enabled no)
			(sheetname "")
		)
		(fill
			(thermal_gap 0.5)
			(thermal_bridge_width 0.5)
			(island_removal_mode 0)
		)
		(polygon
			(pts
				(arc
					(start 54.699916 -370.447062)
					(mid 53.996336 -370.447062)
					(end 54.699916 -370.447062)
				)
			)
		)
	)
	(zone
		(layer "B.Cu")
		(hatch none 0.5)
		(connect_pads
			(clearance 0)
		)
		(min_thickness 0.25)
		(keepout
			(tracks allowed)
			(vias allowed)
			(pads allowed)
			(copperpour allowed)
			(footprints not_allowed)
		)
		(placement
			(enabled no)
			(sheetname "")
		)
		(fill
			(thermal_gap 0.5)
			(thermal_bridge_width 0.5)
			(island_removal_mode 0)
		)
		(polygon
			(pts
				(arc
					(start 463.161126 -402.850096)
					(mid 461.600163 -393.100538)
					(end 460.038704 -402.850096)
				)
				(arc
					(start 460.038704 -402.850096)
					(mid 457.549935 -404.667956)
					(end 456.600052 -407.599896)
				)
				(arc
					(start 456.600052 -407.599896)
					(mid 461.600042 -412.599886)
					(end 466.600032 -407.599896)
				)
				(arc
					(start 466.600032 -407.599896)
					(mid 465.649985 -404.667939)
					(end 463.161126 -402.850096)
				)
			)
		)
	)
	(zone
		(layer "B.Cu")
		(hatch none 0.5)
		(connect_pads
			(clearance 0)
		)
		(min_thickness 0.25)
		(keepout
			(tracks not_allowed)
			(vias allowed)
			(pads allowed)
			(copperpour not_allowed)
			(footprints allowed)
		)
		(placement
			(enabled no)
			(sheetname "")
		)
		(fill
			(thermal_gap 0.5)
			(thermal_bridge_width 0.5)
			(island_removal_mode 0)
		)
		(polygon
			(pts
				(arc
					(start 34.889694 -406.690068)
					(mid 34.130234 -406.690068)
					(end 34.889694 -406.690068)
				)
			)
		)
	)
	(zone
		(layer "B.Cu")
		(hatch none 0.5)
		(connect_pads
			(clearance 0)
		)
		(min_thickness 0.25)
		(keepout
			(tracks not_allowed)
			(vias allowed)
			(pads allowed)
			(copperpour not_allowed)
			(footprints allowed)
		)
		(placement
			(enabled no)
			(sheetname "")
		)
		(fill
			(thermal_gap 0.5)
			(thermal_bridge_width 0.5)
			(island_removal_mode 0)
		)
		(polygon
			(pts
				(arc
					(start 188.426344 -316.799722)
					(mid 187.773564 -316.799722)
					(end 188.426344 -316.799722)
				)
			)
		)
	)
	(zone
		(layer "B.Cu")
		(hatch none 0.5)
		(connect_pads
			(clearance 0)
		)
		(min_thickness 0.25)
		(keepout
			(tracks allowed)
			(vias allowed)
			(pads allowed)
			(copperpour allowed)
			(footprints not_allowed)
		)
		(placement
			(enabled no)
			(sheetname "")
		)
		(fill
			(thermal_gap 0.5)
			(thermal_bridge_width 0.5)
			(island_removal_mode 0)
		)
		(polygon
			(pts
				(arc
					(start 4.43865 -402.850096)
					(mid 5.999988 -412.600724)
					(end 7.561326 -402.850096)
				)
				(arc
					(start 7.561326 -402.850096)
					(mid 5.999988 -393.099468)
					(end 4.43865 -402.850096)
				)
			)
		)
	)
	(zone
		(layer "B.Cu")
		(hatch none 0.5)
		(connect_pads
			(clearance 0)
		)
		(min_thickness 0.25)
		(keepout
			(tracks not_allowed)
			(vias allowed)
			(pads allowed)
			(copperpour not_allowed)
			(footprints allowed)
		)
		(placement
			(enabled no)
			(sheetname "")
		)
		(fill
			(thermal_gap 0.5)
			(thermal_bridge_width 0.5)
			(island_removal_mode 0)
		)
		(polygon
			(pts
				(arc
					(start 459.600046 -407.599896)
					(mid 461.600042 -409.599892)
					(end 463.600038 -407.599896)
				)
				(arc
					(start 463.600038 -407.599896)
					(mid 461.600042 -405.5999)
					(end 459.600046 -407.599896)
				)
			)
		)
	)
	(zone
		(layer "B.Cu")
		(hatch none 0.5)
		(connect_pads
			(clearance 0)
		)
		(min_thickness 0.25)
		(keepout
			(tracks allowed)
			(vias allowed)
			(pads allowed)
			(copperpour allowed)
			(footprints not_allowed)
		)
		(placement
			(enabled no)
			(sheetname "")
		)
		(fill
			(thermal_gap 0.5)
			(thermal_bridge_width 0.5)
			(island_removal_mode 0)
		)
		(polygon
			(pts
				(arc
					(start 274.820126 -15.649956)
					(mid 276.820122 -17.649952)
					(end 278.820118 -15.649956)
				)
				(arc
					(start 278.820118 -15.649956)
					(mid 276.820122 -13.64996)
					(end 274.820126 -15.649956)
				)
			)
		)
	)
	(zone
		(layer "B.Cu")
		(hatch none 0.5)
		(connect_pads
			(clearance 0)
		)
		(min_thickness 0.25)
		(keepout
			(tracks not_allowed)
			(vias allowed)
			(pads allowed)
			(copperpour not_allowed)
			(footprints allowed)
		)
		(placement
			(enabled no)
			(sheetname "")
		)
		(fill
			(thermal_gap 0.5)
			(thermal_bridge_width 0.5)
			(island_removal_mode 0)
		)
		(polygon
			(pts
				(arc
					(start 72.620124 -15.649956)
					(mid 70.620128 -13.64996)
					(end 68.619878 -15.649956)
				)
				(arc
					(start 68.619878 -15.649956)
					(mid 70.620128 -17.650206)
					(end 72.620124 -15.649956)
				)
			)
		)
	)
	(zone
		(layer "B.Cu")
		(hatch none 0.5)
		(connect_pads
			(clearance 0)
		)
		(min_thickness 0.25)
		(keepout
			(tracks not_allowed)
			(vias allowed)
			(pads allowed)
			(copperpour not_allowed)
			(footprints allowed)
		)
		(placement
			(enabled no)
			(sheetname "")
		)
		(fill
			(thermal_gap 0.5)
			(thermal_bridge_width 0.5)
			(island_removal_mode 0)
		)
		(polygon
			(pts
				(arc
					(start 373.450104 -270.89989)
					(mid 377.950222 -275.400008)
					(end 382.450086 -270.89989)
				)
				(arc
					(start 382.450086 -270.89989)
					(mid 377.950222 -266.400026)
					(end 373.450104 -270.89989)
				)
			)
		)
	)
	(zone
		(layer "B.Cu")
		(hatch none 0.5)
		(connect_pads
			(clearance 0)
		)
		(min_thickness 0.25)
		(keepout
			(tracks not_allowed)
			(vias allowed)
			(pads allowed)
			(copperpour not_allowed)
			(footprints allowed)
		)
		(placement
			(enabled no)
			(sheetname "")
		)
		(fill
			(thermal_gap 0.5)
			(thermal_bridge_width 0.5)
			(island_removal_mode 0)
		)
		(polygon
			(pts
				(arc
					(start 120.689878 -371.790214)
					(mid 119.930418 -371.790214)
					(end 120.689878 -371.790214)
				)
			)
		)
	)
	(zone
		(layer "B.Cu")
		(hatch none 0.5)
		(connect_pads
			(clearance 0)
		)
		(min_thickness 0.25)
		(keepout
			(tracks not_allowed)
			(vias allowed)
			(pads allowed)
			(copperpour not_allowed)
			(footprints allowed)
		)
		(placement
			(enabled no)
			(sheetname "")
		)
		(fill
			(thermal_gap 0.5)
			(thermal_bridge_width 0.5)
			(island_removal_mode 0)
		)
		(polygon
			(pts
				(arc
					(start 273.200114 -393.100052)
					(mid 268.200124 -388.100062)
					(end 263.19988 -393.100052)
				)
				(arc
					(start 263.19988 -393.100052)
					(mid 268.200124 -398.100296)
					(end 273.200114 -393.100052)
				)
			)
		)
	)
	(zone
		(layer "B.Cu")
		(hatch none 0.5)
		(connect_pads
			(clearance 0)
		)
		(min_thickness 0.25)
		(keepout
			(tracks not_allowed)
			(vias allowed)
			(pads allowed)
			(copperpour not_allowed)
			(footprints allowed)
		)
		(placement
			(enabled no)
			(sheetname "")
		)
		(fill
			(thermal_gap 0.5)
			(thermal_bridge_width 0.5)
			(island_removal_mode 0)
		)
		(polygon
			(pts
				(arc
					(start 294.469566 -379.390148)
					(mid 293.710106 -379.390148)
					(end 294.469566 -379.390148)
				)
			)
		)
	)
	(zone
		(layer "B.Cu")
		(hatch none 0.5)
		(connect_pads
			(clearance 0)
		)
		(min_thickness 0.25)
		(keepout
			(tracks allowed)
			(vias allowed)
			(pads allowed)
			(copperpour allowed)
			(footprints allowed)
		)
		(placement
			(enabled no)
			(sheetname "")
		)
		(fill
			(thermal_gap 0.5)
			(thermal_bridge_width 0.5)
			(island_removal_mode 0)
		)
		(polygon
			(pts
				(xy 46.65726 -377.610624) (xy 47.251874 -377.610624) (xy 47.418752 -377.443746) (xy 47.418752 -370.92509)
				(xy 47.168562 -370.6749) (xy 46.678342 -370.6749) (xy 46.615858 -370.737384) (xy 46.615858 -377.569222)
			)
		)
	)
	(zone
		(layer "B.Cu")
		(hatch none 0.5)
		(connect_pads
			(clearance 0)
		)
		(min_thickness 0.25)
		(keepout
			(tracks not_allowed)
			(vias allowed)
			(pads allowed)
			(copperpour not_allowed)
			(footprints allowed)
		)
		(placement
			(enabled no)
			(sheetname "")
		)
		(fill
			(thermal_gap 0.5)
			(thermal_bridge_width 0.5)
			(island_removal_mode 0)
		)
		(polygon
			(pts
				(arc
					(start 460.93253 -5.999988)
					(mid 455.93254 -0.999998)
					(end 450.93255 -5.999988)
				)
				(arc
					(start 450.93255 -5.999988)
					(mid 455.93254 -10.999978)
					(end 460.93253 -5.999988)
				)
			)
		)
	)
	(zone
		(layer "B.Cu")
		(hatch none 0.5)
		(connect_pads
			(clearance 0)
		)
		(min_thickness 0.25)
		(keepout
			(tracks allowed)
			(vias allowed)
			(pads allowed)
			(copperpour allowed)
			(footprints not_allowed)
		)
		(placement
			(enabled no)
			(sheetname "")
		)
		(fill
			(thermal_gap 0.5)
			(thermal_bridge_width 0.5)
			(island_removal_mode 0)
		)
		(polygon
			(pts
				(arc
					(start 456.79995 -194.360038)
					(mid 451.79996 -189.360048)
					(end 446.79997 -194.360038)
				)
				(arc
					(start 446.79997 -194.360038)
					(mid 451.79996 -199.360028)
					(end 456.79995 -194.360038)
				)
			)
		)
	)
	(zone
		(layer "B.Cu")
		(hatch none 0.5)
		(connect_pads
			(clearance 0)
		)
		(min_thickness 0.25)
		(keepout
			(tracks allowed)
			(vias allowed)
			(pads allowed)
			(copperpour allowed)
			(footprints allowed)
		)
		(placement
			(enabled no)
			(sheetname "")
		)
		(fill
			(thermal_gap 0.5)
			(thermal_bridge_width 0.5)
			(island_removal_mode 0)
		)
		(polygon
			(pts
				(xy 339.6742 -225.0694) (xy 343.4588 -225.0694) (xy 343.6112 -225.2218) (xy 343.6112 -226.0092)
				(xy 343.5096 -226.1108) (xy 343.1032 -226.1108) (xy 342.8238 -225.8314) (xy 341.2236 -225.8314)
				(xy 340.9442 -226.1108) (xy 340.9442 -226.695) (xy 340.5632 -227.076) (xy 339.5726 -227.076) (xy 339.5726 -225.171)
			)
		)
	)
	(zone
		(layer "B.Cu")
		(hatch none 0.5)
		(connect_pads
			(clearance 0)
		)
		(min_thickness 0.25)
		(keepout
			(tracks not_allowed)
			(vias allowed)
			(pads allowed)
			(copperpour not_allowed)
			(footprints allowed)
		)
		(placement
			(enabled no)
			(sheetname "")
		)
		(fill
			(thermal_gap 0.5)
			(thermal_bridge_width 0.5)
			(island_removal_mode 0)
		)
		(polygon
			(pts
				(arc
					(start 294.469566 -406.690068)
					(mid 293.710106 -406.690068)
					(end 294.469566 -406.690068)
				)
			)
		)
	)
	(zone
		(layer "B.Cu")
		(hatch none 0.5)
		(connect_pads
			(clearance 0)
		)
		(min_thickness 0.25)
		(keepout
			(tracks not_allowed)
			(vias allowed)
			(pads allowed)
			(copperpour not_allowed)
			(footprints allowed)
		)
		(placement
			(enabled no)
			(sheetname "")
		)
		(fill
			(thermal_gap 0.5)
			(thermal_bridge_width 0.5)
			(island_removal_mode 0)
		)
		(polygon
			(pts
				(arc
					(start 389.06958 -371.790214)
					(mid 388.31012 -371.790214)
					(end 389.06958 -371.790214)
				)
			)
		)
	)
	(zone
		(layer "B.Cu")
		(hatch none 0.5)
		(connect_pads
			(clearance 0)
		)
		(min_thickness 0.25)
		(keepout
			(tracks not_allowed)
			(vias allowed)
			(pads allowed)
			(copperpour not_allowed)
			(footprints allowed)
		)
		(placement
			(enabled no)
			(sheetname "")
		)
		(fill
			(thermal_gap 0.5)
			(thermal_bridge_width 0.5)
			(island_removal_mode 0)
		)
		(polygon
			(pts
				(arc
					(start 257.350006 -270.89989)
					(mid 261.850124 -275.400008)
					(end 266.349988 -270.89989)
				)
				(arc
					(start 266.349988 -270.89989)
					(mid 261.850124 -266.400026)
					(end 257.350006 -270.89989)
				)
			)
		)
	)
	(zone
		(layer "B.Cu")
		(hatch none 0.5)
		(connect_pads
			(clearance 0)
		)
		(min_thickness 0.25)
		(keepout
			(tracks not_allowed)
			(vias allowed)
			(pads allowed)
			(copperpour not_allowed)
			(footprints allowed)
		)
		(placement
			(enabled no)
			(sheetname "")
		)
		(fill
			(thermal_gap 0.5)
			(thermal_bridge_width 0.5)
			(island_removal_mode 0)
		)
		(polygon
			(pts
				(arc
					(start 91.899994 -270.89989)
					(mid 89.650062 -268.649958)
					(end 87.399876 -270.89989)
				)
				(arc
					(start 87.399876 -270.89989)
					(mid 89.650062 -273.150076)
					(end 91.899994 -270.89989)
				)
			)
		)
	)
	(zone
		(layer "B.Cu")
		(hatch none 0.5)
		(connect_pads
			(clearance 0)
		)
		(min_thickness 0.25)
		(keepout
			(tracks not_allowed)
			(vias allowed)
			(pads allowed)
			(copperpour not_allowed)
			(footprints allowed)
		)
		(placement
			(enabled no)
			(sheetname "")
		)
		(fill
			(thermal_gap 0.5)
			(thermal_bridge_width 0.5)
			(island_removal_mode 0)
		)
		(polygon
			(pts
				(arc
					(start 313.076082 -318.699896)
					(mid 312.423302 -318.699896)
					(end 313.076082 -318.699896)
				)
			)
		)
	)
	(zone
		(layer "B.Cu")
		(hatch none 0.5)
		(connect_pads
			(clearance 0)
		)
		(min_thickness 0.25)
		(keepout
			(tracks not_allowed)
			(vias allowed)
			(pads allowed)
			(copperpour not_allowed)
			(footprints allowed)
		)
		(placement
			(enabled no)
			(sheetname "")
		)
		(fill
			(thermal_gap 0.5)
			(thermal_bridge_width 0.5)
			(island_removal_mode 0)
		)
		(polygon
			(pts
				(arc
					(start 10.999978 -407.599896)
					(mid 5.999988 -402.599906)
					(end 0.999998 -407.599896)
				)
				(arc
					(start 0.999998 -407.599896)
					(mid 5.999988 -412.599886)
					(end 10.999978 -407.599896)
				)
			)
		)
	)
	(zone
		(layer "B.Cu")
		(hatch none 0.5)
		(connect_pads
			(clearance 0)
		)
		(min_thickness 0.25)
		(keepout
			(tracks not_allowed)
			(vias allowed)
			(pads allowed)
			(copperpour not_allowed)
			(footprints allowed)
		)
		(placement
			(enabled no)
			(sheetname "")
		)
		(fill
			(thermal_gap 0.5)
			(thermal_bridge_width 0.5)
			(island_removal_mode 0)
		)
		(polygon
			(pts
				(arc
					(start 308.326282 -315.849762)
					(mid 307.673502 -315.849762)
					(end 308.326282 -315.849762)
				)
			)
		)
	)
	(zone
		(layer "B.Cu")
		(hatch none 0.5)
		(connect_pads
			(clearance 0)
		)
		(min_thickness 0.25)
		(keepout
			(tracks not_allowed)
			(vias allowed)
			(pads allowed)
			(copperpour not_allowed)
			(footprints allowed)
		)
		(placement
			(enabled no)
			(sheetname "")
		)
		(fill
			(thermal_gap 0.5)
			(thermal_bridge_width 0.5)
			(island_removal_mode 0)
		)
		(polygon
			(pts
				(arc
					(start 161.826448 -316.799722)
					(mid 161.173668 -316.799722)
					(end 161.826448 -316.799722)
				)
			)
		)
	)
	(zone
		(layer "B.Cu")
		(hatch none 0.5)
		(connect_pads
			(clearance 0)
		)
		(min_thickness 0.25)
		(keepout
			(tracks not_allowed)
			(vias allowed)
			(pads allowed)
			(copperpour not_allowed)
			(footprints allowed)
		)
		(placement
			(enabled no)
			(sheetname "")
		)
		(fill
			(thermal_gap 0.5)
			(thermal_bridge_width 0.5)
			(island_removal_mode 0)
		)
		(polygon
			(pts
				(arc
					(start 398.77619 -318.699896)
					(mid 398.12341 -318.699896)
					(end 398.77619 -318.699896)
				)
			)
		)
	)
	(zone
		(layer "B.Cu")
		(hatch none 0.5)
		(connect_pads
			(clearance 0)
		)
		(min_thickness 0.25)
		(keepout
			(tracks not_allowed)
			(vias allowed)
			(pads allowed)
			(copperpour not_allowed)
			(footprints allowed)
		)
		(placement
			(enabled no)
			(sheetname "")
		)
		(fill
			(thermal_gap 0.5)
			(thermal_bridge_width 0.5)
			(island_removal_mode 0)
		)
		(polygon
			(pts
				(arc
					(start 466.600032 -407.599896)
					(mid 461.600042 -402.599906)
					(end 456.600052 -407.599896)
				)
				(arc
					(start 456.600052 -407.599896)
					(mid 461.600042 -412.599886)
					(end 466.600032 -407.599896)
				)
			)
		)
	)
	(zone
		(layer "B.Cu")
		(hatch none 0.5)
		(connect_pads
			(clearance 0)
		)
		(min_thickness 0.25)
		(keepout
			(tracks not_allowed)
			(vias allowed)
			(pads allowed)
			(copperpour not_allowed)
			(footprints allowed)
		)
		(placement
			(enabled no)
			(sheetname "")
		)
		(fill
			(thermal_gap 0.5)
			(thermal_bridge_width 0.5)
			(island_removal_mode 0)
		)
		(polygon
			(pts
				(arc
					(start 298.869608 -380.69012)
					(mid 298.110148 -380.69012)
					(end 298.869608 -380.69012)
				)
			)
		)
	)
	(zone
		(layer "B.Cu")
		(hatch none 0.5)
		(connect_pads
			(clearance 0)
		)
		(min_thickness 0.25)
		(keepout
			(tracks not_allowed)
			(vias allowed)
			(pads allowed)
			(copperpour not_allowed)
			(footprints allowed)
		)
		(placement
			(enabled no)
			(sheetname "")
		)
		(fill
			(thermal_gap 0.5)
			(thermal_bridge_width 0.5)
			(island_removal_mode 0)
		)
		(polygon
			(pts
				(arc
					(start 382.469644 -401.49018)
					(mid 381.710184 -401.49018)
					(end 382.469644 -401.49018)
				)
			)
		)
	)
	(zone
		(layer "B.Cu")
		(hatch none 0.5)
		(connect_pads
			(clearance 0)
		)
		(min_thickness 0.25)
		(keepout
			(tracks not_allowed)
			(vias allowed)
			(pads allowed)
			(copperpour not_allowed)
			(footprints allowed)
		)
		(placement
			(enabled no)
			(sheetname "")
		)
		(fill
			(thermal_gap 0.5)
			(thermal_bridge_width 0.5)
			(island_removal_mode 0)
		)
		(polygon
			(pts
				(arc
					(start 296.669714 -405.589994)
					(mid 295.910254 -405.589994)
					(end 296.669714 -405.589994)
				)
			)
		)
	)
	(zone
		(layer "B.Cu")
		(hatch none 0.5)
		(connect_pads
			(clearance 0)
		)
		(min_thickness 0.25)
		(keepout
			(tracks not_allowed)
			(vias allowed)
			(pads allowed)
			(copperpour not_allowed)
			(footprints allowed)
		)
		(placement
			(enabled no)
			(sheetname "")
		)
		(fill
			(thermal_gap 0.5)
			(thermal_bridge_width 0.5)
			(island_removal_mode 0)
		)
		(polygon
			(pts
				(arc
					(start 378.069602 -401.49018)
					(mid 377.310142 -401.49018)
					(end 378.069602 -401.49018)
				)
			)
		)
	)
	(zone
		(layer "B.Cu")
		(hatch none 0.5)
		(connect_pads
			(clearance 0)
		)
		(min_thickness 0.25)
		(keepout
			(tracks not_allowed)
			(vias allowed)
			(pads allowed)
			(copperpour not_allowed)
			(footprints allowed)
		)
		(placement
			(enabled no)
			(sheetname "")
		)
		(fill
			(thermal_gap 0.5)
			(thermal_bridge_width 0.5)
			(island_removal_mode 0)
		)
		(polygon
			(pts
				(arc
					(start 127.289814 -371.590062)
					(mid 126.530354 -371.590062)
					(end 127.289814 -371.590062)
				)
			)
		)
	)
	(zone
		(layer "B.Cu")
		(hatch none 0.5)
		(connect_pads
			(clearance 0)
		)
		(min_thickness 0.25)
		(keepout
			(tracks not_allowed)
			(vias allowed)
			(pads allowed)
			(copperpour not_allowed)
			(footprints allowed)
		)
		(placement
			(enabled no)
			(sheetname "")
		)
		(fill
			(thermal_gap 0.5)
			(thermal_bridge_width 0.5)
			(island_removal_mode 0)
		)
		(polygon
			(pts
				(arc
					(start 163.726368 -315.849762)
					(mid 163.073588 -315.849762)
					(end 163.726368 -315.849762)
				)
			)
		)
	)
	(zone
		(layer "B.Cu")
		(hatch none 0.5)
		(connect_pads
			(clearance 0)
		)
		(min_thickness 0.25)
		(keepout
			(tracks not_allowed)
			(vias allowed)
			(pads allowed)
			(copperpour not_allowed)
			(footprints allowed)
		)
		(placement
			(enabled no)
			(sheetname "")
		)
		(fill
			(thermal_gap 0.5)
			(thermal_bridge_width 0.5)
			(island_removal_mode 0)
		)
		(polygon
			(pts
				(arc
					(start 386.869686 -401.49018)
					(mid 386.110226 -401.49018)
					(end 386.869686 -401.49018)
				)
			)
		)
	)
	(zone
		(layer "B.Cu")
		(hatch none 0.5)
		(connect_pads
			(clearance 0)
		)
		(min_thickness 0.25)
		(keepout
			(tracks not_allowed)
			(vias allowed)
			(pads allowed)
			(copperpour not_allowed)
			(footprints allowed)
		)
		(placement
			(enabled no)
			(sheetname "")
		)
		(fill
			(thermal_gap 0.5)
			(thermal_bridge_width 0.5)
			(island_removal_mode 0)
		)
		(polygon
			(pts
				(arc
					(start 257.350006 -320.900044)
					(mid 261.850124 -325.400162)
					(end 266.349988 -320.900044)
				)
				(arc
					(start 266.349988 -320.900044)
					(mid 261.850124 -316.40018)
					(end 257.350006 -320.900044)
				)
			)
		)
	)
	(zone
		(layer "B.Cu")
		(hatch none 0.5)
		(connect_pads
			(clearance 0)
		)
		(min_thickness 0.25)
		(keepout
			(tracks not_allowed)
			(vias allowed)
			(pads allowed)
			(copperpour not_allowed)
			(footprints allowed)
		)
		(placement
			(enabled no)
			(sheetname "")
		)
		(fill
			(thermal_gap 0.5)
			(thermal_bridge_width 0.5)
			(island_removal_mode 0)
		)
		(polygon
			(pts
				(arc
					(start 382.469644 -372.890034)
					(mid 381.710184 -372.890034)
					(end 382.469644 -372.890034)
				)
			)
		)
	)
	(zone
		(layer "B.Cu")
		(hatch none 0.5)
		(connect_pads
			(clearance 0)
		)
		(min_thickness 0.25)
		(keepout
			(tracks not_allowed)
			(vias allowed)
			(pads allowed)
			(copperpour not_allowed)
			(footprints allowed)
		)
		(placement
			(enabled no)
			(sheetname "")
		)
		(fill
			(thermal_gap 0.5)
			(thermal_bridge_width 0.5)
			(island_removal_mode 0)
		)
		(polygon
			(pts
				(arc
					(start 296.669714 -379.590046)
					(mid 295.910254 -379.590046)
					(end 296.669714 -379.590046)
				)
			)
		)
	)
	(zone
		(layer "B.Cu")
		(hatch none 0.5)
		(connect_pads
			(clearance 0)
		)
		(min_thickness 0.25)
		(keepout
			(tracks not_allowed)
			(vias allowed)
			(pads allowed)
			(copperpour not_allowed)
			(footprints allowed)
		)
		(placement
			(enabled no)
			(sheetname "")
		)
		(fill
			(thermal_gap 0.5)
			(thermal_bridge_width 0.5)
			(island_removal_mode 0)
		)
		(polygon
			(pts
				(arc
					(start 77.0763 -318.699896)
					(mid 76.42352 -318.699896)
					(end 77.0763 -318.699896)
				)
			)
		)
	)
	(zone
		(layer "B.Cu")
		(hatch none 0.5)
		(connect_pads
			(clearance 0)
		)
		(min_thickness 0.25)
		(keepout
			(tracks not_allowed)
			(vias allowed)
			(pads allowed)
			(copperpour not_allowed)
			(footprints allowed)
		)
		(placement
			(enabled no)
			(sheetname "")
		)
		(fill
			(thermal_gap 0.5)
			(thermal_bridge_width 0.5)
			(island_removal_mode 0)
		)
		(polygon
			(pts
				(arc
					(start 233.867706 -87.4141)
					(mid 233.164126 -87.4141)
					(end 233.867706 -87.4141)
				)
			)
		)
	)
	(zone
		(layer "B.Cu")
		(hatch none 0.5)
		(connect_pads
			(clearance 0)
		)
		(min_thickness 0.25)
		(keepout
			(tracks not_allowed)
			(vias allowed)
			(pads allowed)
			(copperpour not_allowed)
			(footprints allowed)
		)
		(placement
			(enabled no)
			(sheetname "")
		)
		(fill
			(thermal_gap 0.5)
			(thermal_bridge_width 0.5)
			(island_removal_mode 0)
		)
		(polygon
			(pts
				(arc
					(start 6.800088 -400.699986)
					(mid 9.400032 -398.100042)
					(end 6.800088 -395.500098)
				)
				(arc
					(start 5.199888 -395.500098)
					(mid 2.599944 -398.100042)
					(end 5.199888 -400.699986)
				)
			)
		)
		(polygon
			(pts
				(arc
					(start 5.199888 -396.500096)
					(mid 3.599942 -398.100042)
					(end 5.199888 -399.699988)
				)
				(arc
					(start 6.800088 -399.699988)
					(mid 8.400034 -398.100042)
					(end 6.800088 -396.500096)
				)
			)
		)
	)
	(zone
		(layer "B.Cu")
		(hatch none 0.5)
		(connect_pads
			(clearance 0)
		)
		(min_thickness 0.25)
		(keepout
			(tracks not_allowed)
			(vias allowed)
			(pads allowed)
			(copperpour not_allowed)
			(footprints allowed)
		)
		(placement
			(enabled no)
			(sheetname "")
		)
		(fill
			(thermal_gap 0.5)
			(thermal_bridge_width 0.5)
			(island_removal_mode 0)
		)
		(polygon
			(pts
				(arc
					(start 189.376304 -317.749936)
					(mid 188.723524 -317.749936)
					(end 189.376304 -317.749936)
				)
			)
		)
	)
	(zone
		(layer "B.Cu")
		(hatch none 0.5)
		(connect_pads
			(clearance 0)
		)
		(min_thickness 0.25)
		(keepout
			(tracks allowed)
			(vias allowed)
			(pads allowed)
			(copperpour allowed)
			(footprints not_allowed)
		)
		(placement
			(enabled no)
			(sheetname "")
		)
		(fill
			(thermal_gap 0.5)
			(thermal_bridge_width 0.5)
			(island_removal_mode 0)
		)
		(polygon
			(pts
				(arc
					(start 10.80008 -194.360038)
					(mid 15.80007 -199.360028)
					(end 20.80006 -194.360038)
				)
				(arc
					(start 20.80006 -194.360038)
					(mid 15.80007 -189.360048)
					(end 10.80008 -194.360038)
				)
			)
		)
	)
	(zone
		(layer "B.Cu")
		(hatch none 0.5)
		(connect_pads
			(clearance 0)
		)
		(min_thickness 0.25)
		(keepout
			(tracks allowed)
			(vias allowed)
			(pads allowed)
			(copperpour allowed)
			(footprints not_allowed)
		)
		(placement
			(enabled no)
			(sheetname "")
		)
		(fill
			(thermal_gap 0.5)
			(thermal_bridge_width 0.5)
			(island_removal_mode 0)
		)
		(polygon
			(pts
				(xy 271.349978 -280.399998) (xy 271.349978 -311.399936) (xy 312.349896 -311.399936) (xy 312.349896 -280.399998)
			)
		)
	)
	(zone
		(layer "B.Cu")
		(hatch none 0.5)
		(connect_pads
			(clearance 0)
		)
		(min_thickness 0.25)
		(keepout
			(tracks allowed)
			(vias allowed)
			(pads allowed)
			(copperpour allowed)
			(footprints not_allowed)
		)
		(placement
			(enabled no)
			(sheetname "")
		)
		(fill
			(thermal_gap 0.5)
			(thermal_bridge_width 0.5)
			(island_removal_mode 0)
		)
		(polygon
			(pts
				(arc
					(start 20.80006 -194.360038)
					(mid 15.80007 -189.360048)
					(end 10.80008 -194.360038)
				)
				(arc
					(start 10.80008 -194.360038)
					(mid 15.80007 -199.360028)
					(end 20.80006 -194.360038)
				)
			)
		)
	)
	(zone
		(layer "B.Cu")
		(hatch none 0.5)
		(connect_pads
			(clearance 0)
		)
		(min_thickness 0.25)
		(keepout
			(tracks allowed)
			(vias allowed)
			(pads allowed)
			(copperpour allowed)
			(footprints not_allowed)
		)
		(placement
			(enabled no)
			(sheetname "")
		)
		(fill
			(thermal_gap 0.5)
			(thermal_bridge_width 0.5)
			(island_removal_mode 0)
		)
		(polygon
			(pts
				(arc
					(start 248.350024 -297.369992)
					(mid 252.350016 -301.369984)
					(end 256.350008 -297.369992)
				)
				(arc
					(start 256.350008 -297.369992)
					(mid 252.350016 -293.37)
					(end 248.350024 -297.369992)
				)
			)
		)
	)
	(zone
		(layer "B.Cu")
		(hatch none 0.5)
		(connect_pads
			(clearance 0)
		)
		(min_thickness 0.25)
		(keepout
			(tracks not_allowed)
			(vias allowed)
			(pads allowed)
			(copperpour not_allowed)
			(footprints allowed)
		)
		(placement
			(enabled no)
			(sheetname "")
		)
		(fill
			(thermal_gap 0.5)
			(thermal_bridge_width 0.5)
			(island_removal_mode 0)
		)
		(polygon
			(pts
				(arc
					(start 304.820066 -15.649956)
					(mid 302.82007 -13.64996)
					(end 300.820074 -15.649956)
				)
				(arc
					(start 300.820074 -15.649956)
					(mid 302.82007 -17.649952)
					(end 304.820066 -15.649956)
				)
			)
		)
	)
	(zone
		(layer "B.Cu")
		(hatch none 0.5)
		(connect_pads
			(clearance 0)
		)
		(min_thickness 0.25)
		(keepout
			(tracks not_allowed)
			(vias allowed)
			(pads allowed)
			(copperpour not_allowed)
			(footprints allowed)
		)
		(placement
			(enabled no)
			(sheetname "")
		)
		(fill
			(thermal_gap 0.5)
			(thermal_bridge_width 0.5)
			(island_removal_mode 0)
		)
		(polygon
			(pts
				(arc
					(start 127.289814 -372.890034)
					(mid 126.530354 -372.890034)
					(end 127.289814 -372.890034)
				)
			)
		)
	)
	(zone
		(layer "B.Cu")
		(hatch none 0.5)
		(connect_pads
			(clearance 0)
		)
		(min_thickness 0.25)
		(keepout
			(tracks not_allowed)
			(vias allowed)
			(pads allowed)
			(copperpour not_allowed)
			(footprints allowed)
		)
		(placement
			(enabled no)
			(sheetname "")
		)
		(fill
			(thermal_gap 0.5)
			(thermal_bridge_width 0.5)
			(island_removal_mode 0)
		)
		(polygon
			(pts
				(arc
					(start 45.889672 -370.489988)
					(mid 45.130212 -370.489988)
					(end 45.889672 -370.489988)
				)
			)
		)
	)
	(zone
		(layer "B.Cu")
		(hatch none 0.5)
		(connect_pads
			(clearance 0)
		)
		(min_thickness 0.25)
		(keepout
			(tracks not_allowed)
			(vias allowed)
			(pads allowed)
			(copperpour not_allowed)
			(footprints allowed)
		)
		(placement
			(enabled no)
			(sheetname "")
		)
		(fill
			(thermal_gap 0.5)
			(thermal_bridge_width 0.5)
			(island_removal_mode 0)
		)
		(polygon
			(pts
				(arc
					(start 131.689856 -371.590062)
					(mid 130.930396 -371.590062)
					(end 131.689856 -371.590062)
				)
			)
		)
	)
	(zone
		(layer "B.Cu")
		(hatch none 0.5)
		(connect_pads
			(clearance 0)
		)
		(min_thickness 0.25)
		(keepout
			(tracks not_allowed)
			(vias allowed)
			(pads allowed)
			(copperpour not_allowed)
			(footprints allowed)
		)
		(placement
			(enabled no)
			(sheetname "")
		)
		(fill
			(thermal_gap 0.5)
			(thermal_bridge_width 0.5)
			(island_removal_mode 0)
		)
		(polygon
			(pts
				(arc
					(start 233.493818 -83.366864)
					(mid 232.790238 -83.366864)
					(end 233.493818 -83.366864)
				)
			)
		)
	)
	(zone
		(layer "B.Cu")
		(hatch none 0.5)
		(connect_pads
			(clearance 0)
		)
		(min_thickness 0.25)
		(keepout
			(tracks allowed)
			(vias allowed)
			(pads allowed)
			(copperpour allowed)
			(footprints not_allowed)
		)
		(placement
			(enabled no)
			(sheetname "")
		)
		(fill
			(thermal_gap 0.5)
			(thermal_bridge_width 0.5)
			(island_removal_mode 0)
		)
		(polygon
			(pts
				(arc
					(start 263.51992 -20.72005)
					(mid 265.519916 -22.720046)
					(end 267.519912 -20.72005)
				)
				(arc
					(start 267.519912 -20.72005)
					(mid 265.519916 -18.720054)
					(end 263.51992 -20.72005)
				)
			)
		)
	)
	(zone
		(layers "B.Cu" "In7.Cu" "In9.Cu" "In11.Cu" "In13.Cu" "In15.Cu")
		(hatch none 0.5)
		(connect_pads
			(clearance 0)
		)
		(min_thickness 0.25)
		(keepout
			(tracks not_allowed)
			(vias allowed)
			(pads allowed)
			(copperpour not_allowed)
			(footprints allowed)
		)
		(placement
			(enabled no)
			(sheetname "")
		)
		(fill yes
			(thermal_gap 0.5)
			(thermal_bridge_width 0.5)
			(island_removal_mode 0)
		)
		(polygon
			(pts
				(arc
					(start 430.126394 -283.549852)
					(mid 429.473614 -283.549852)
					(end 430.126394 -283.549852)
				)
			)
		)
	)
	(zone
		(layers "B.Cu" "In7.Cu" "In9.Cu" "In11.Cu" "In13.Cu" "In15.Cu")
		(hatch none 0.5)
		(connect_pads
			(clearance 0)
		)
		(min_thickness 0.25)
		(keepout
			(tracks not_allowed)
			(vias allowed)
			(pads allowed)
			(copperpour not_allowed)
			(footprints allowed)
		)
		(placement
			(enabled no)
			(sheetname "")
		)
		(fill yes
			(thermal_gap 0.5)
			(thermal_bridge_width 0.5)
			(island_removal_mode 0)
		)
		(polygon
			(pts
				(arc
					(start 400.89455 -121.022872)
					(mid 400.19097 -121.022872)
					(end 400.89455 -121.022872)
				)
			)
		)
	)
	(zone
		(layers "B.Cu" "In7.Cu" "In9.Cu" "In11.Cu" "In13.Cu" "In15.Cu")
		(hatch none 0.5)
		(connect_pads
			(clearance 0)
		)
		(min_thickness 0.25)
		(keepout
			(tracks not_allowed)
			(vias allowed)
			(pads allowed)
			(copperpour not_allowed)
			(footprints allowed)
		)
		(placement
			(enabled no)
			(sheetname "")
		)
		(fill yes
			(thermal_gap 0.5)
			(thermal_bridge_width 0.5)
			(island_removal_mode 0)
		)
		(polygon
			(pts
				(arc
					(start 282.676092 -318.699896)
					(mid 282.023312 -318.699896)
					(end 282.676092 -318.699896)
				)
			)
		)
	)
	(zone
		(layers "B.Cu" "In7.Cu" "In9.Cu" "In11.Cu" "In13.Cu" "In15.Cu")
		(hatch none 0.5)
		(connect_pads
			(clearance 0)
		)
		(min_thickness 0.25)
		(keepout
			(tracks not_allowed)
			(vias allowed)
			(pads allowed)
			(copperpour not_allowed)
			(footprints allowed)
		)
		(placement
			(enabled no)
			(sheetname "")
		)
		(fill yes
			(thermal_gap 0.5)
			(thermal_bridge_width 0.5)
			(island_removal_mode 0)
		)
		(polygon
			(pts
				(arc
					(start 402.74875 -134.032752)
					(mid 402.04517 -134.032752)
					(end 402.74875 -134.032752)
				)
			)
		)
	)
	(zone
		(layers "B.Cu" "In7.Cu" "In9.Cu" "In11.Cu" "In13.Cu" "In15.Cu")
		(hatch none 0.5)
		(connect_pads
			(clearance 0)
		)
		(min_thickness 0.25)
		(keepout
			(tracks not_allowed)
			(vias allowed)
			(pads allowed)
			(copperpour not_allowed)
			(footprints allowed)
		)
		(placement
			(enabled no)
			(sheetname "")
		)
		(fill yes
			(thermal_gap 0.5)
			(thermal_bridge_width 0.5)
			(island_removal_mode 0)
		)
		(polygon
			(pts
				(arc
					(start 85.489542 -401.690078)
					(mid 84.730082 -401.690078)
					(end 85.489542 -401.690078)
				)
			)
		)
	)
	(zone
		(layers "B.Cu" "In7.Cu" "In9.Cu" "In11.Cu" "In13.Cu" "In15.Cu")
		(hatch none 0.5)
		(connect_pads
			(clearance 0)
		)
		(min_thickness 0.25)
		(keepout
			(tracks not_allowed)
			(vias allowed)
			(pads allowed)
			(copperpour not_allowed)
			(footprints allowed)
		)
		(placement
			(enabled no)
			(sheetname "")
		)
		(fill yes
			(thermal_gap 0.5)
			(thermal_bridge_width 0.5)
			(island_removal_mode 0)
		)
		(polygon
			(pts
				(arc
					(start 75.176126 -274.049744)
					(mid 74.523346 -274.049744)
					(end 75.176126 -274.049744)
				)
			)
		)
	)
	(zone
		(layers "B.Cu" "In7.Cu" "In9.Cu" "In11.Cu" "In13.Cu" "In15.Cu")
		(hatch none 0.5)
		(connect_pads
			(clearance 0)
		)
		(min_thickness 0.25)
		(keepout
			(tracks not_allowed)
			(vias allowed)
			(pads allowed)
			(copperpour not_allowed)
			(footprints allowed)
		)
		(placement
			(enabled no)
			(sheetname "")
		)
		(fill yes
			(thermal_gap 0.5)
			(thermal_bridge_width 0.5)
			(island_removal_mode 0)
		)
		(polygon
			(pts
				(arc
					(start 303.26965 -409.290012)
					(mid 302.51019 -409.290012)
					(end 303.26965 -409.290012)
				)
			)
		)
	)
	(zone
		(layers "B.Cu" "In7.Cu" "In9.Cu" "In11.Cu" "In13.Cu" "In15.Cu")
		(hatch none 0.5)
		(connect_pads
			(clearance 0)
		)
		(min_thickness 0.25)
		(keepout
			(tracks not_allowed)
			(vias allowed)
			(pads allowed)
			(copperpour not_allowed)
			(footprints allowed)
		)
		(placement
			(enabled no)
			(sheetname "")
		)
		(fill yes
			(thermal_gap 0.5)
			(thermal_bridge_width 0.5)
			(island_removal_mode 0)
		)
		(polygon
			(pts
				(arc
					(start 299.609002 -150.687278)
					(mid 298.905422 -150.687278)
					(end 299.609002 -150.687278)
				)
			)
		)
	)
	(zone
		(layers "B.Cu" "In7.Cu" "In9.Cu" "In11.Cu" "In13.Cu" "In15.Cu")
		(hatch none 0.5)
		(connect_pads
			(clearance 0)
		)
		(min_thickness 0.25)
		(keepout
			(tracks not_allowed)
			(vias allowed)
			(pads allowed)
			(copperpour not_allowed)
			(footprints allowed)
		)
		(placement
			(enabled no)
			(sheetname "")
		)
		(fill yes
			(thermal_gap 0.5)
			(thermal_bridge_width 0.5)
			(island_removal_mode 0)
		)
		(polygon
			(pts
				(arc
					(start 67.40906 -133.513576)
					(mid 66.70548 -133.513576)
					(end 67.40906 -133.513576)
				)
			)
		)
	)
	(zone
		(layers "B.Cu" "In7.Cu" "In9.Cu" "In11.Cu" "In13.Cu" "In15.Cu")
		(hatch none 0.5)
		(connect_pads
			(clearance 0)
		)
		(min_thickness 0.25)
		(keepout
			(tracks not_allowed)
			(vias allowed)
			(pads allowed)
			(copperpour not_allowed)
			(footprints allowed)
		)
		(placement
			(enabled no)
			(sheetname "")
		)
		(fill yes
			(thermal_gap 0.5)
			(thermal_bridge_width 0.5)
			(island_removal_mode 0)
		)
		(polygon
			(pts
				(arc
					(start 422.525952 -275.949918)
					(mid 421.873172 -275.949918)
					(end 422.525952 -275.949918)
				)
			)
		)
	)
	(zone
		(layers "B.Cu" "In7.Cu" "In9.Cu" "In11.Cu" "In13.Cu" "In15.Cu")
		(hatch none 0.5)
		(connect_pads
			(clearance 0)
		)
		(min_thickness 0.25)
		(keepout
			(tracks not_allowed)
			(vias allowed)
			(pads allowed)
			(copperpour not_allowed)
			(footprints allowed)
		)
		(placement
			(enabled no)
			(sheetname "")
		)
		(fill yes
			(thermal_gap 0.5)
			(thermal_bridge_width 0.5)
			(island_removal_mode 0)
		)
		(polygon
			(pts
				(arc
					(start 418.725858 -274.999958)
					(mid 418.073078 -274.999958)
					(end 418.725858 -274.999958)
				)
			)
		)
	)
	(zone
		(layers "B.Cu" "In7.Cu" "In9.Cu" "In11.Cu" "In13.Cu" "In15.Cu")
		(hatch none 0.5)
		(connect_pads
			(clearance 0)
		)
		(min_thickness 0.25)
		(keepout
			(tracks not_allowed)
			(vias allowed)
			(pads allowed)
			(copperpour not_allowed)
			(footprints allowed)
		)
		(placement
			(enabled no)
			(sheetname "")
		)
		(fill yes
			(thermal_gap 0.5)
			(thermal_bridge_width 0.5)
			(island_removal_mode 0)
		)
		(polygon
			(pts
				(arc
					(start 54.44871 -100.17633)
					(mid 53.74513 -100.17633)
					(end 54.44871 -100.17633)
				)
			)
		)
	)
	(zone
		(layers "B.Cu" "In7.Cu" "In9.Cu" "In11.Cu" "In13.Cu" "In15.Cu")
		(hatch none 0.5)
		(connect_pads
			(clearance 0)
		)
		(min_thickness 0.25)
		(keepout
			(tracks not_allowed)
			(vias allowed)
			(pads allowed)
			(copperpour not_allowed)
			(footprints allowed)
		)
		(placement
			(enabled no)
			(sheetname "")
		)
		(fill yes
			(thermal_gap 0.5)
			(thermal_bridge_width 0.5)
			(island_removal_mode 0)
		)
		(polygon
			(pts
				(arc
					(start 430.126394 -274.999704)
					(mid 429.473614 -274.999704)
					(end 430.126394 -274.999704)
				)
			)
		)
	)
	(zone
		(layers "B.Cu" "In7.Cu" "In9.Cu" "In11.Cu" "In13.Cu" "In15.Cu")
		(hatch none 0.5)
		(connect_pads
			(clearance 0)
		)
		(min_thickness 0.25)
		(keepout
			(tracks not_allowed)
			(vias allowed)
			(pads allowed)
			(copperpour not_allowed)
			(footprints allowed)
		)
		(placement
			(enabled no)
			(sheetname "")
		)
		(fill yes
			(thermal_gap 0.5)
			(thermal_bridge_width 0.5)
			(island_removal_mode 0)
		)
		(polygon
			(pts
				(arc
					(start 181.654704 -148.887434)
					(mid 180.951124 -148.887434)
					(end 181.654704 -148.887434)
				)
			)
		)
	)
	(zone
		(layers "B.Cu" "In7.Cu" "In9.Cu" "In11.Cu" "In13.Cu" "In15.Cu")
		(hatch none 0.5)
		(connect_pads
			(clearance 0)
		)
		(min_thickness 0.25)
		(keepout
			(tracks not_allowed)
			(vias allowed)
			(pads allowed)
			(copperpour not_allowed)
			(footprints allowed)
		)
		(placement
			(enabled no)
			(sheetname "")
		)
		(fill yes
			(thermal_gap 0.5)
			(thermal_bridge_width 0.5)
			(island_removal_mode 0)
		)
		(polygon
			(pts
				(arc
					(start 331.869796 -371.790214)
					(mid 331.110336 -371.790214)
					(end 331.869796 -371.790214)
				)
			)
		)
	)
	(zone
		(layers "B.Cu" "In7.Cu" "In9.Cu" "In11.Cu" "In13.Cu" "In15.Cu")
		(hatch none 0.5)
		(connect_pads
			(clearance 0)
		)
		(min_thickness 0.25)
		(keepout
			(tracks not_allowed)
			(vias allowed)
			(pads allowed)
			(copperpour not_allowed)
			(footprints allowed)
		)
		(placement
			(enabled no)
			(sheetname "")
		)
		(fill yes
			(thermal_gap 0.5)
			(thermal_bridge_width 0.5)
			(island_removal_mode 0)
		)
		(polygon
			(pts
				(arc
					(start 71.376286 -318.699896)
					(mid 70.723506 -318.699896)
					(end 71.376286 -318.699896)
				)
			)
		)
	)
	(zone
		(layers "B.Cu" "In7.Cu" "In9.Cu" "In11.Cu" "In13.Cu" "In15.Cu")
		(hatch none 0.5)
		(connect_pads
			(clearance 0)
		)
		(min_thickness 0.25)
		(keepout
			(tracks not_allowed)
			(vias allowed)
			(pads allowed)
			(copperpour not_allowed)
			(footprints allowed)
		)
		(placement
			(enabled no)
			(sheetname "")
		)
		(fill yes
			(thermal_gap 0.5)
			(thermal_bridge_width 0.5)
			(island_removal_mode 0)
		)
		(polygon
			(pts
				(arc
					(start 284.794452 -101.976428)
					(mid 284.090872 -101.976428)
					(end 284.794452 -101.976428)
				)
			)
		)
	)
	(zone
		(layers "B.Cu" "In7.Cu" "In9.Cu" "In11.Cu" "In13.Cu" "In15.Cu")
		(hatch none 0.5)
		(connect_pads
			(clearance 0)
		)
		(min_thickness 0.25)
		(keepout
			(tracks not_allowed)
			(vias allowed)
			(pads allowed)
			(copperpour not_allowed)
			(footprints allowed)
		)
		(placement
			(enabled no)
			(sheetname "")
		)
		(fill yes
			(thermal_gap 0.5)
			(thermal_bridge_width 0.5)
			(island_removal_mode 0)
		)
		(polygon
			(pts
				(arc
					(start 302.62576 -274.999958)
					(mid 301.97298 -274.999958)
					(end 302.62576 -274.999958)
				)
			)
		)
	)
	(zone
		(layers "B.Cu" "In7.Cu" "In9.Cu" "In11.Cu" "In13.Cu" "In15.Cu")
		(hatch none 0.5)
		(connect_pads
			(clearance 0)
		)
		(min_thickness 0.25)
		(keepout
			(tracks not_allowed)
			(vias allowed)
			(pads allowed)
			(copperpour not_allowed)
			(footprints allowed)
		)
		(placement
			(enabled no)
			(sheetname "")
		)
		(fill yes
			(thermal_gap 0.5)
			(thermal_bridge_width 0.5)
			(island_removal_mode 0)
		)
		(polygon
			(pts
				(arc
					(start 334.06969 -372.890034)
					(mid 333.31023 -372.890034)
					(end 334.06969 -372.890034)
				)
			)
		)
	)
	(zone
		(layers "B.Cu" "In7.Cu" "In9.Cu" "In11.Cu" "In13.Cu" "In15.Cu")
		(hatch none 0.5)
		(connect_pads
			(clearance 0)
		)
		(min_thickness 0.25)
		(keepout
			(tracks not_allowed)
			(vias allowed)
			(pads allowed)
			(copperpour not_allowed)
			(footprints allowed)
		)
		(placement
			(enabled no)
			(sheetname "")
		)
		(fill yes
			(thermal_gap 0.5)
			(thermal_bridge_width 0.5)
			(island_removal_mode 0)
		)
		(polygon
			(pts
				(arc
					(start 67.40906 -147.087336)
					(mid 66.70548 -147.087336)
					(end 67.40906 -147.087336)
				)
			)
		)
	)
	(zone
		(layers "B.Cu" "In7.Cu" "In9.Cu" "In11.Cu" "In13.Cu" "In15.Cu")
		(hatch none 0.5)
		(connect_pads
			(clearance 0)
		)
		(min_thickness 0.25)
		(keepout
			(tracks not_allowed)
			(vias allowed)
			(pads allowed)
			(copperpour not_allowed)
			(footprints allowed)
		)
		(placement
			(enabled no)
			(sheetname "")
		)
		(fill yes
			(thermal_gap 0.5)
			(thermal_bridge_width 0.5)
			(island_removal_mode 0)
		)
		(polygon
			(pts
				(arc
					(start 292.175946 -273.09953)
					(mid 291.523166 -273.09953)
					(end 292.175946 -273.09953)
				)
			)
		)
	)
	(zone
		(layers "B.Cu" "In7.Cu" "In9.Cu" "In11.Cu" "In13.Cu" "In15.Cu")
		(hatch none 0.5)
		(connect_pads
			(clearance 0)
		)
		(min_thickness 0.25)
		(keepout
			(tracks not_allowed)
			(vias allowed)
			(pads allowed)
			(copperpour not_allowed)
			(footprints allowed)
		)
		(placement
			(enabled no)
			(sheetname "")
		)
		(fill yes
			(thermal_gap 0.5)
			(thermal_bridge_width 0.5)
			(island_removal_mode 0)
		)
		(polygon
			(pts
				(arc
					(start 131.689856 -397.59001)
					(mid 130.930396 -397.59001)
					(end 131.689856 -397.59001)
				)
			)
		)
	)
	(zone
		(layers "B.Cu" "In7.Cu" "In9.Cu" "In11.Cu" "In13.Cu" "In15.Cu")
		(hatch none 0.5)
		(connect_pads
			(clearance 0)
		)
		(min_thickness 0.25)
		(keepout
			(tracks not_allowed)
			(vias allowed)
			(pads allowed)
			(copperpour not_allowed)
			(footprints allowed)
		)
		(placement
			(enabled no)
			(sheetname "")
		)
		(fill yes
			(thermal_gap 0.5)
			(thermal_bridge_width 0.5)
			(island_removal_mode 0)
		)
		(polygon
			(pts
				(arc
					(start 182.726076 -275.949918)
					(mid 182.073296 -275.949918)
					(end 182.726076 -275.949918)
				)
			)
		)
	)
	(zone
		(layers "B.Cu" "In7.Cu" "In9.Cu" "In11.Cu" "In13.Cu" "In15.Cu")
		(hatch none 0.5)
		(connect_pads
			(clearance 0)
		)
		(min_thickness 0.25)
		(keepout
			(tracks not_allowed)
			(vias allowed)
			(pads allowed)
			(copperpour not_allowed)
			(footprints allowed)
		)
		(placement
			(enabled no)
			(sheetname "")
		)
		(fill yes
			(thermal_gap 0.5)
			(thermal_bridge_width 0.5)
			(island_removal_mode 0)
		)
		(polygon
			(pts
				(arc
					(start 170.548554 -120.086374)
					(mid 169.844974 -120.086374)
					(end 170.548554 -120.086374)
				)
			)
		)
	)
	(zone
		(layers "B.Cu" "In7.Cu" "In9.Cu" "In11.Cu" "In13.Cu" "In15.Cu")
		(hatch none 0.5)
		(connect_pads
			(clearance 0)
		)
		(min_thickness 0.25)
		(keepout
			(tracks not_allowed)
			(vias allowed)
			(pads allowed)
			(copperpour not_allowed)
			(footprints allowed)
		)
		(placement
			(enabled no)
			(sheetname "")
		)
		(fill yes
			(thermal_gap 0.5)
			(thermal_bridge_width 0.5)
			(island_removal_mode 0)
		)
		(polygon
			(pts
				(arc
					(start 286.648652 -134.032752)
					(mid 285.945072 -134.032752)
					(end 286.648652 -134.032752)
				)
			)
		)
	)
	(zone
		(layers "B.Cu" "In7.Cu" "In9.Cu" "In11.Cu" "In13.Cu" "In15.Cu")
		(hatch none 0.5)
		(connect_pads
			(clearance 0)
		)
		(min_thickness 0.25)
		(keepout
			(tracks not_allowed)
			(vias allowed)
			(pads allowed)
			(copperpour not_allowed)
			(footprints allowed)
		)
		(placement
			(enabled no)
			(sheetname "")
		)
		(fill yes
			(thermal_gap 0.5)
			(thermal_bridge_width 0.5)
			(island_removal_mode 0)
		)
		(polygon
			(pts
				(arc
					(start 197.926452 -281.649932)
					(mid 197.273672 -281.649932)
					(end 197.926452 -281.649932)
				)
			)
		)
	)
	(zone
		(layers "B.Cu" "In7.Cu" "In9.Cu" "In11.Cu" "In13.Cu" "In15.Cu")
		(hatch none 0.5)
		(connect_pads
			(clearance 0)
		)
		(min_thickness 0.25)
		(keepout
			(tracks not_allowed)
			(vias allowed)
			(pads allowed)
			(copperpour not_allowed)
			(footprints allowed)
		)
		(placement
			(enabled no)
			(sheetname "")
		)
		(fill yes
			(thermal_gap 0.5)
			(thermal_bridge_width 0.5)
			(island_removal_mode 0)
		)
		(polygon
			(pts
				(arc
					(start 28.289758 -383.490216)
					(mid 27.530298 -383.490216)
					(end 28.289758 -383.490216)
				)
			)
		)
	)
	(zone
		(layers "B.Cu" "In7.Cu" "In9.Cu" "In11.Cu" "In13.Cu" "In15.Cu")
		(hatch none 0.5)
		(connect_pads
			(clearance 0)
		)
		(min_thickness 0.25)
		(keepout
			(tracks not_allowed)
			(vias allowed)
			(pads allowed)
			(copperpour not_allowed)
			(footprints allowed)
		)
		(placement
			(enabled no)
			(sheetname "")
		)
		(fill yes
			(thermal_gap 0.5)
			(thermal_bridge_width 0.5)
			(island_removal_mode 0)
		)
		(polygon
			(pts
				(arc
					(start 81.826354 -281.649932)
					(mid 81.173574 -281.649932)
					(end 81.826354 -281.649932)
				)
			)
		)
	)
	(zone
		(layers "B.Cu" "In7.Cu" "In9.Cu" "In11.Cu" "In13.Cu" "In15.Cu")
		(hatch none 0.5)
		(connect_pads
			(clearance 0)
		)
		(min_thickness 0.25)
		(keepout
			(tracks not_allowed)
			(vias allowed)
			(pads allowed)
			(copperpour not_allowed)
			(footprints allowed)
		)
		(placement
			(enabled no)
			(sheetname "")
		)
		(fill yes
			(thermal_gap 0.5)
			(thermal_bridge_width 0.5)
			(island_removal_mode 0)
		)
		(polygon
			(pts
				(arc
					(start 400.89455 -104.71277)
					(mid 400.19097 -104.71277)
					(end 400.89455 -104.71277)
				)
			)
		)
	)
	(zone
		(layers "B.Cu" "In7.Cu" "In9.Cu" "In11.Cu" "In13.Cu" "In15.Cu")
		(hatch none 0.5)
		(connect_pads
			(clearance 0)
		)
		(min_thickness 0.25)
		(keepout
			(tracks not_allowed)
			(vias allowed)
			(pads allowed)
			(copperpour not_allowed)
			(footprints allowed)
		)
		(placement
			(enabled no)
			(sheetname "")
		)
		(fill yes
			(thermal_gap 0.5)
			(thermal_bridge_width 0.5)
			(island_removal_mode 0)
		)
		(polygon
			(pts
				(arc
					(start 413.8549 -151.623776)
					(mid 413.15132 -151.623776)
					(end 413.8549 -151.623776)
				)
			)
		)
	)
	(zone
		(layers "B.Cu" "In7.Cu" "In9.Cu" "In11.Cu" "In13.Cu" "In15.Cu")
		(hatch none 0.5)
		(connect_pads
			(clearance 0)
		)
		(min_thickness 0.25)
		(keepout
			(tracks not_allowed)
			(vias allowed)
			(pads allowed)
			(copperpour not_allowed)
			(footprints allowed)
		)
		(placement
			(enabled no)
			(sheetname "")
		)
		(fill yes
			(thermal_gap 0.5)
			(thermal_bridge_width 0.5)
			(island_removal_mode 0)
		)
		(polygon
			(pts
				(arc
					(start 120.689878 -375.69013)
					(mid 119.930418 -375.69013)
					(end 120.689878 -375.69013)
				)
			)
		)
	)
	(zone
		(layers "B.Cu" "In7.Cu" "In9.Cu" "In11.Cu" "In13.Cu" "In15.Cu")
		(hatch none 0.5)
		(connect_pads
			(clearance 0)
		)
		(min_thickness 0.25)
		(keepout
			(tracks not_allowed)
			(vias allowed)
			(pads allowed)
			(copperpour not_allowed)
			(footprints allowed)
		)
		(placement
			(enabled no)
			(sheetname "")
		)
		(fill yes
			(thermal_gap 0.5)
			(thermal_bridge_width 0.5)
			(island_removal_mode 0)
		)
		(polygon
			(pts
				(arc
					(start 274.126198 -315.849762)
					(mid 273.473418 -315.849762)
					(end 274.126198 -315.849762)
				)
			)
		)
	)
	(zone
		(layers "B.Cu" "In7.Cu" "In9.Cu" "In11.Cu" "In13.Cu" "In15.Cu")
		(hatch none 0.5)
		(connect_pads
			(clearance 0)
		)
		(min_thickness 0.25)
		(keepout
			(tracks not_allowed)
			(vias allowed)
			(pads allowed)
			(copperpour not_allowed)
			(footprints allowed)
		)
		(placement
			(enabled no)
			(sheetname "")
		)
		(fill yes
			(thermal_gap 0.5)
			(thermal_bridge_width 0.5)
			(island_removal_mode 0)
		)
		(polygon
			(pts
				(arc
					(start 65.55486 -144.423638)
					(mid 64.85128 -144.423638)
					(end 65.55486 -144.423638)
				)
			)
		)
	)
	(zone
		(layers "B.Cu" "In7.Cu" "In9.Cu" "In11.Cu" "In13.Cu" "In15.Cu")
		(hatch none 0.5)
		(connect_pads
			(clearance 0)
		)
		(min_thickness 0.25)
		(keepout
			(tracks not_allowed)
			(vias allowed)
			(pads allowed)
			(copperpour not_allowed)
			(footprints allowed)
		)
		(placement
			(enabled no)
			(sheetname "")
		)
		(fill yes
			(thermal_gap 0.5)
			(thermal_bridge_width 0.5)
			(island_removal_mode 0)
		)
		(polygon
			(pts
				(arc
					(start 430.869598 -379.390148)
					(mid 430.110138 -379.390148)
					(end 430.869598 -379.390148)
				)
			)
		)
	)
	(zone
		(layers "B.Cu" "In7.Cu" "In9.Cu" "In11.Cu" "In13.Cu" "In15.Cu")
		(hatch none 0.5)
		(connect_pads
			(clearance 0)
		)
		(min_thickness 0.25)
		(keepout
			(tracks not_allowed)
			(vias allowed)
			(pads allowed)
			(copperpour not_allowed)
			(footprints allowed)
		)
		(placement
			(enabled no)
			(sheetname "")
		)
		(fill yes
			(thermal_gap 0.5)
			(thermal_bridge_width 0.5)
			(island_removal_mode 0)
		)
		(polygon
			(pts
				(arc
					(start 63.776098 -273.099784)
					(mid 63.123318 -273.099784)
					(end 63.776098 -273.099784)
				)
			)
		)
	)
	(zone
		(layers "B.Cu" "In7.Cu" "In9.Cu" "In11.Cu" "In13.Cu" "In15.Cu")
		(hatch none 0.5)
		(connect_pads
			(clearance 0)
		)
		(min_thickness 0.25)
		(keepout
			(tracks not_allowed)
			(vias allowed)
			(pads allowed)
			(copperpour not_allowed)
			(footprints allowed)
		)
		(placement
			(enabled no)
			(sheetname "")
		)
		(fill yes
			(thermal_gap 0.5)
			(thermal_bridge_width 0.5)
			(island_removal_mode 0)
		)
		(polygon
			(pts
				(arc
					(start 177.976276 -318.699896)
					(mid 177.323496 -318.699896)
					(end 177.976276 -318.699896)
				)
			)
		)
	)
	(zone
		(layers "B.Cu" "In7.Cu" "In9.Cu" "In11.Cu" "In13.Cu" "In15.Cu")
		(hatch none 0.5)
		(connect_pads
			(clearance 0)
		)
		(min_thickness 0.25)
		(keepout
			(tracks not_allowed)
			(vias allowed)
			(pads allowed)
			(copperpour not_allowed)
			(footprints allowed)
		)
		(placement
			(enabled no)
			(sheetname "")
		)
		(fill yes
			(thermal_gap 0.5)
			(thermal_bridge_width 0.5)
			(island_removal_mode 0)
		)
		(polygon
			(pts
				(arc
					(start 286.648652 -134.896352)
					(mid 285.945072 -134.896352)
					(end 286.648652 -134.896352)
				)
			)
		)
	)
	(zone
		(layers "B.Cu" "In7.Cu" "In9.Cu" "In11.Cu" "In13.Cu" "In15.Cu")
		(hatch none 0.5)
		(connect_pads
			(clearance 0)
		)
		(min_thickness 0.25)
		(keepout
			(tracks not_allowed)
			(vias allowed)
			(pads allowed)
			(copperpour not_allowed)
			(footprints allowed)
		)
		(placement
			(enabled no)
			(sheetname "")
		)
		(fill yes
			(thermal_gap 0.5)
			(thermal_bridge_width 0.5)
			(island_removal_mode 0)
		)
		(polygon
			(pts
				(arc
					(start 386.869686 -397.59001)
					(mid 386.110226 -397.59001)
					(end 386.869686 -397.59001)
				)
			)
		)
	)
	(zone
		(layers "B.Cu" "In7.Cu" "In9.Cu" "In11.Cu" "In13.Cu" "In15.Cu")
		(hatch none 0.5)
		(connect_pads
			(clearance 0)
		)
		(min_thickness 0.25)
		(keepout
			(tracks not_allowed)
			(vias allowed)
			(pads allowed)
			(copperpour not_allowed)
			(footprints allowed)
		)
		(placement
			(enabled no)
			(sheetname "")
		)
		(fill yes
			(thermal_gap 0.5)
			(thermal_bridge_width 0.5)
			(island_removal_mode 0)
		)
		(polygon
			(pts
				(arc
					(start 70.426326 -316.799722)
					(mid 69.773546 -316.799722)
					(end 70.426326 -316.799722)
				)
			)
		)
	)
	(zone
		(layers "B.Cu" "In7.Cu" "In9.Cu" "In11.Cu" "In13.Cu" "In15.Cu")
		(hatch none 0.5)
		(connect_pads
			(clearance 0)
		)
		(min_thickness 0.25)
		(keepout
			(tracks not_allowed)
			(vias allowed)
			(pads allowed)
			(copperpour not_allowed)
			(footprints allowed)
		)
		(placement
			(enabled no)
			(sheetname "")
		)
		(fill yes
			(thermal_gap 0.5)
			(thermal_bridge_width 0.5)
			(island_removal_mode 0)
		)
		(polygon
			(pts
				(arc
					(start 120.689878 -396.49019)
					(mid 119.930418 -396.49019)
					(end 120.689878 -396.49019)
				)
			)
		)
	)
	(zone
		(layers "B.Cu" "In7.Cu" "In9.Cu" "In11.Cu" "In13.Cu" "In15.Cu")
		(hatch none 0.5)
		(connect_pads
			(clearance 0)
		)
		(min_thickness 0.25)
		(keepout
			(tracks not_allowed)
			(vias allowed)
			(pads allowed)
			(copperpour not_allowed)
			(footprints allowed)
		)
		(placement
			(enabled no)
			(sheetname "")
		)
		(fill yes
			(thermal_gap 0.5)
			(thermal_bridge_width 0.5)
			(island_removal_mode 0)
		)
		(polygon
			(pts
				(arc
					(start 65.55486 -152.487376)
					(mid 64.85128 -152.487376)
					(end 65.55486 -152.487376)
				)
			)
		)
	)
	(zone
		(layers "B.Cu" "In7.Cu" "In9.Cu" "In11.Cu" "In13.Cu" "In15.Cu")
		(hatch none 0.5)
		(connect_pads
			(clearance 0)
		)
		(min_thickness 0.25)
		(keepout
			(tracks not_allowed)
			(vias allowed)
			(pads allowed)
			(copperpour not_allowed)
			(footprints allowed)
		)
		(placement
			(enabled no)
			(sheetname "")
		)
		(fill yes
			(thermal_gap 0.5)
			(thermal_bridge_width 0.5)
			(island_removal_mode 0)
		)
		(polygon
			(pts
				(arc
					(start 415.7091 -130.777234)
					(mid 415.00552 -130.777234)
					(end 415.7091 -130.777234)
				)
			)
		)
	)
	(zone
		(layers "B.Cu" "In7.Cu" "In9.Cu" "In11.Cu" "In13.Cu" "In15.Cu")
		(hatch none 0.5)
		(connect_pads
			(clearance 0)
		)
		(min_thickness 0.25)
		(keepout
			(tracks not_allowed)
			(vias allowed)
			(pads allowed)
			(copperpour not_allowed)
			(footprints allowed)
		)
		(placement
			(enabled no)
			(sheetname "")
		)
		(fill yes
			(thermal_gap 0.5)
			(thermal_bridge_width 0.5)
			(island_removal_mode 0)
		)
		(polygon
			(pts
				(arc
					(start 435.26964 -406.690068)
					(mid 434.51018 -406.690068)
					(end 435.26964 -406.690068)
				)
			)
		)
	)
	(zone
		(layers "B.Cu" "In7.Cu" "In9.Cu" "In11.Cu" "In13.Cu" "In15.Cu")
		(hatch none 0.5)
		(connect_pads
			(clearance 0)
		)
		(min_thickness 0.25)
		(keepout
			(tracks not_allowed)
			(vias allowed)
			(pads allowed)
			(copperpour not_allowed)
			(footprints allowed)
		)
		(placement
			(enabled no)
			(sheetname "")
		)
		(fill yes
			(thermal_gap 0.5)
			(thermal_bridge_width 0.5)
			(island_removal_mode 0)
		)
		(polygon
			(pts
				(arc
					(start 72.28967 -401.690078)
					(mid 71.53021 -401.690078)
					(end 72.28967 -401.690078)
				)
			)
		)
	)
	(zone
		(layers "B.Cu" "In7.Cu" "In9.Cu" "In11.Cu" "In13.Cu" "In15.Cu")
		(hatch none 0.5)
		(connect_pads
			(clearance 0)
		)
		(min_thickness 0.25)
		(keepout
			(tracks not_allowed)
			(vias allowed)
			(pads allowed)
			(copperpour not_allowed)
			(footprints allowed)
		)
		(placement
			(enabled no)
			(sheetname "")
		)
		(fill yes
			(thermal_gap 0.5)
			(thermal_bridge_width 0.5)
			(island_removal_mode 0)
		)
		(polygon
			(pts
				(arc
					(start 50.47615 -317.749936)
					(mid 49.82337 -317.749936)
					(end 50.47615 -317.749936)
				)
			)
		)
	)
	(zone
		(layers "B.Cu" "In7.Cu" "In9.Cu" "In11.Cu" "In13.Cu" "In15.Cu")
		(hatch none 0.5)
		(connect_pads
			(clearance 0)
		)
		(min_thickness 0.25)
		(keepout
			(tracks not_allowed)
			(vias allowed)
			(pads allowed)
			(copperpour not_allowed)
			(footprints allowed)
		)
		(placement
			(enabled no)
			(sheetname "")
		)
		(fill yes
			(thermal_gap 0.5)
			(thermal_bridge_width 0.5)
			(island_removal_mode 0)
		)
		(polygon
			(pts
				(arc
					(start 171.289726 -379.390148)
					(mid 170.530266 -379.390148)
					(end 171.289726 -379.390148)
				)
			)
		)
	)
	(zone
		(layers "B.Cu" "In7.Cu" "In9.Cu" "In11.Cu" "In13.Cu" "In15.Cu")
		(hatch none 0.5)
		(connect_pads
			(clearance 0)
		)
		(min_thickness 0.25)
		(keepout
			(tracks not_allowed)
			(vias allowed)
			(pads allowed)
			(copperpour not_allowed)
			(footprints allowed)
		)
		(placement
			(enabled no)
			(sheetname "")
		)
		(fill yes
			(thermal_gap 0.5)
			(thermal_bridge_width 0.5)
			(island_removal_mode 0)
		)
		(polygon
			(pts
				(arc
					(start 54.44871 -131.29641)
					(mid 53.74513 -131.29641)
					(end 54.44871 -131.29641)
				)
			)
		)
	)
	(zone
		(layers "B.Cu" "In7.Cu" "In9.Cu" "In11.Cu" "In13.Cu" "In15.Cu")
		(hatch none 0.5)
		(connect_pads
			(clearance 0)
		)
		(min_thickness 0.25)
		(keepout
			(tracks not_allowed)
			(vias allowed)
			(pads allowed)
			(copperpour not_allowed)
			(footprints allowed)
		)
		(placement
			(enabled no)
			(sheetname "")
		)
		(fill yes
			(thermal_gap 0.5)
			(thermal_bridge_width 0.5)
			(island_removal_mode 0)
		)
		(polygon
			(pts
				(arc
					(start 415.7091 -134.377176)
					(mid 415.00552 -134.377176)
					(end 415.7091 -134.377176)
				)
			)
		)
	)
	(zone
		(layers "B.Cu" "In7.Cu" "In9.Cu" "In11.Cu" "In13.Cu" "In15.Cu")
		(hatch none 0.5)
		(connect_pads
			(clearance 0)
		)
		(min_thickness 0.25)
		(keepout
			(tracks not_allowed)
			(vias allowed)
			(pads allowed)
			(copperpour not_allowed)
			(footprints allowed)
		)
		(placement
			(enabled no)
			(sheetname "")
		)
		(fill yes
			(thermal_gap 0.5)
			(thermal_bridge_width 0.5)
			(island_removal_mode 0)
		)
		(polygon
			(pts
				(arc
					(start 52.59451 -121.022872)
					(mid 51.89093 -121.022872)
					(end 52.59451 -121.022872)
				)
			)
		)
	)
	(zone
		(layers "B.Cu" "In7.Cu" "In9.Cu" "In11.Cu" "In13.Cu" "In15.Cu")
		(hatch none 0.5)
		(connect_pads
			(clearance 0)
		)
		(min_thickness 0.25)
		(keepout
			(tracks not_allowed)
			(vias allowed)
			(pads allowed)
			(copperpour not_allowed)
			(footprints allowed)
		)
		(placement
			(enabled no)
			(sheetname "")
		)
		(fill yes
			(thermal_gap 0.5)
			(thermal_bridge_width 0.5)
			(island_removal_mode 0)
		)
		(polygon
			(pts
				(arc
					(start 79.925926 -275.949918)
					(mid 79.273146 -275.949918)
					(end 79.925926 -275.949918)
				)
			)
		)
	)
	(zone
		(layers "B.Cu" "In7.Cu" "In9.Cu" "In11.Cu" "In13.Cu" "In15.Cu")
		(hatch none 0.5)
		(connect_pads
			(clearance 0)
		)
		(min_thickness 0.25)
		(keepout
			(tracks not_allowed)
			(vias allowed)
			(pads allowed)
			(copperpour not_allowed)
			(footprints allowed)
		)
		(placement
			(enabled no)
			(sheetname "")
		)
		(fill yes
			(thermal_gap 0.5)
			(thermal_bridge_width 0.5)
			(island_removal_mode 0)
		)
		(polygon
			(pts
				(arc
					(start 297.754802 -124.967238)
					(mid 297.051222 -124.967238)
					(end 297.754802 -124.967238)
				)
			)
		)
	)
	(zone
		(layers "B.Cu" "In7.Cu" "In9.Cu" "In11.Cu" "In13.Cu" "In15.Cu")
		(hatch none 0.5)
		(connect_pads
			(clearance 0)
		)
		(min_thickness 0.25)
		(keepout
			(tracks not_allowed)
			(vias allowed)
			(pads allowed)
			(copperpour not_allowed)
			(footprints allowed)
		)
		(placement
			(enabled no)
			(sheetname "")
		)
		(fill yes
			(thermal_gap 0.5)
			(thermal_bridge_width 0.5)
			(island_removal_mode 0)
		)
		(polygon
			(pts
				(arc
					(start 415.7091 -133.513576)
					(mid 415.00552 -133.513576)
					(end 415.7091 -133.513576)
				)
			)
		)
	)
	(zone
		(layers "B.Cu" "In7.Cu" "In9.Cu" "In11.Cu" "In13.Cu" "In15.Cu")
		(hatch none 0.5)
		(connect_pads
			(clearance 0)
		)
		(min_thickness 0.25)
		(keepout
			(tracks not_allowed)
			(vias allowed)
			(pads allowed)
			(copperpour not_allowed)
			(footprints allowed)
		)
		(placement
			(enabled no)
			(sheetname "")
		)
		(fill yes
			(thermal_gap 0.5)
			(thermal_bridge_width 0.5)
			(island_removal_mode 0)
		)
		(polygon
			(pts
				(arc
					(start 380.26975 -374.390158)
					(mid 379.51029 -374.390158)
					(end 380.26975 -374.390158)
				)
			)
		)
	)
	(zone
		(layers "B.Cu" "In7.Cu" "In9.Cu" "In11.Cu" "In13.Cu" "In15.Cu")
		(hatch none 0.5)
		(connect_pads
			(clearance 0)
		)
		(min_thickness 0.25)
		(keepout
			(tracks not_allowed)
			(vias allowed)
			(pads allowed)
			(copperpour not_allowed)
			(footprints allowed)
		)
		(placement
			(enabled no)
			(sheetname "")
		)
		(fill yes
			(thermal_gap 0.5)
			(thermal_bridge_width 0.5)
			(island_removal_mode 0)
		)
		(polygon
			(pts
				(arc
					(start 194.126104 -274.999958)
					(mid 193.473324 -274.999958)
					(end 194.126104 -274.999958)
				)
			)
		)
	)
	(zone
		(layers "B.Cu" "In7.Cu" "In9.Cu" "In11.Cu" "In13.Cu" "In15.Cu")
		(hatch none 0.5)
		(connect_pads
			(clearance 0)
		)
		(min_thickness 0.25)
		(keepout
			(tracks not_allowed)
			(vias allowed)
			(pads allowed)
			(copperpour not_allowed)
			(footprints allowed)
		)
		(placement
			(enabled no)
			(sheetname "")
		)
		(fill yes
			(thermal_gap 0.5)
			(thermal_bridge_width 0.5)
			(island_removal_mode 0)
		)
		(polygon
			(pts
				(arc
					(start 276.976078 -317.749936)
					(mid 276.323298 -317.749936)
					(end 276.976078 -317.749936)
				)
			)
		)
	)
	(zone
		(layers "B.Cu" "In7.Cu" "In9.Cu" "In11.Cu" "In13.Cu" "In15.Cu")
		(hatch none 0.5)
		(connect_pads
			(clearance 0)
		)
		(min_thickness 0.25)
		(keepout
			(tracks not_allowed)
			(vias allowed)
			(pads allowed)
			(copperpour not_allowed)
			(footprints allowed)
		)
		(placement
			(enabled no)
			(sheetname "")
		)
		(fill yes
			(thermal_gap 0.5)
			(thermal_bridge_width 0.5)
			(island_removal_mode 0)
		)
		(polygon
			(pts
				(arc
					(start 81.826354 -287.349946)
					(mid 81.173574 -287.349946)
					(end 81.826354 -287.349946)
				)
			)
		)
	)
	(zone
		(layers "B.Cu" "In7.Cu" "In9.Cu" "In11.Cu" "In13.Cu" "In15.Cu")
		(hatch none 0.5)
		(connect_pads
			(clearance 0)
		)
		(min_thickness 0.25)
		(keepout
			(tracks not_allowed)
			(vias allowed)
			(pads allowed)
			(copperpour not_allowed)
			(footprints allowed)
		)
		(placement
			(enabled no)
			(sheetname "")
		)
		(fill yes
			(thermal_gap 0.5)
			(thermal_bridge_width 0.5)
			(island_removal_mode 0)
		)
		(polygon
			(pts
				(arc
					(start 198.876412 -287.349946)
					(mid 198.223632 -287.349946)
					(end 198.876412 -287.349946)
				)
			)
		)
	)
	(zone
		(layers "B.Cu" "In7.Cu" "In9.Cu" "In11.Cu" "In13.Cu" "In15.Cu")
		(hatch none 0.5)
		(connect_pads
			(clearance 0)
		)
		(min_thickness 0.25)
		(keepout
			(tracks not_allowed)
			(vias allowed)
			(pads allowed)
			(copperpour not_allowed)
			(footprints allowed)
		)
		(placement
			(enabled no)
			(sheetname "")
		)
		(fill yes
			(thermal_gap 0.5)
			(thermal_bridge_width 0.5)
			(island_removal_mode 0)
		)
		(polygon
			(pts
				(arc
					(start 54.44871 -134.032752)
					(mid 53.74513 -134.032752)
					(end 54.44871 -134.032752)
				)
			)
		)
	)
	(zone
		(layers "B.Cu" "In7.Cu" "In9.Cu" "In11.Cu" "In13.Cu" "In15.Cu")
		(hatch none 0.5)
		(connect_pads
			(clearance 0)
		)
		(min_thickness 0.25)
		(keepout
			(tracks not_allowed)
			(vias allowed)
			(pads allowed)
			(copperpour not_allowed)
			(footprints allowed)
		)
		(placement
			(enabled no)
			(sheetname "")
		)
		(fill yes
			(thermal_gap 0.5)
			(thermal_bridge_width 0.5)
			(island_removal_mode 0)
		)
		(polygon
			(pts
				(arc
					(start 286.648652 -110.97641)
					(mid 285.945072 -110.97641)
					(end 286.648652 -110.97641)
				)
			)
		)
	)
	(zone
		(layers "B.Cu" "In7.Cu" "In9.Cu" "In11.Cu" "In13.Cu" "In15.Cu")
		(hatch none 0.5)
		(connect_pads
			(clearance 0)
		)
		(min_thickness 0.25)
		(keepout
			(tracks not_allowed)
			(vias allowed)
			(pads allowed)
			(copperpour not_allowed)
			(footprints allowed)
		)
		(placement
			(enabled no)
			(sheetname "")
		)
		(fill yes
			(thermal_gap 0.5)
			(thermal_bridge_width 0.5)
			(island_removal_mode 0)
		)
		(polygon
			(pts
				(arc
					(start 129.489708 -397.790162)
					(mid 128.730248 -397.790162)
					(end 129.489708 -397.790162)
				)
			)
		)
	)
	(zone
		(layers "B.Cu" "In7.Cu" "In9.Cu" "In11.Cu" "In13.Cu" "In15.Cu")
		(hatch none 0.5)
		(connect_pads
			(clearance 0)
		)
		(min_thickness 0.25)
		(keepout
			(tracks not_allowed)
			(vias allowed)
			(pads allowed)
			(copperpour not_allowed)
			(footprints allowed)
		)
		(placement
			(enabled no)
			(sheetname "")
		)
		(fill yes
			(thermal_gap 0.5)
			(thermal_bridge_width 0.5)
			(island_removal_mode 0)
		)
		(polygon
			(pts
				(arc
					(start 382.469644 -397.59001)
					(mid 381.710184 -397.59001)
					(end 382.469644 -397.59001)
				)
			)
		)
	)
	(zone
		(layers "B.Cu" "In7.Cu" "In9.Cu" "In11.Cu" "In13.Cu" "In15.Cu")
		(hatch none 0.5)
		(connect_pads
			(clearance 0)
		)
		(min_thickness 0.25)
		(keepout
			(tracks not_allowed)
			(vias allowed)
			(pads allowed)
			(copperpour not_allowed)
			(footprints allowed)
		)
		(placement
			(enabled no)
			(sheetname "")
		)
		(fill yes
			(thermal_gap 0.5)
			(thermal_bridge_width 0.5)
			(island_removal_mode 0)
		)
		(polygon
			(pts
				(arc
					(start 297.754802 -131.713732)
					(mid 297.051222 -131.713732)
					(end 297.754802 -131.713732)
				)
			)
		)
	)
	(zone
		(layers "B.Cu" "In7.Cu" "In9.Cu" "In11.Cu" "In13.Cu" "In15.Cu")
		(hatch none 0.5)
		(connect_pads
			(clearance 0)
		)
		(min_thickness 0.25)
		(keepout
			(tracks not_allowed)
			(vias allowed)
			(pads allowed)
			(copperpour not_allowed)
			(footprints allowed)
		)
		(placement
			(enabled no)
			(sheetname "")
		)
		(fill yes
			(thermal_gap 0.5)
			(thermal_bridge_width 0.5)
			(island_removal_mode 0)
		)
		(polygon
			(pts
				(arc
					(start 425.37634 -317.749936)
					(mid 424.72356 -317.749936)
					(end 425.37634 -317.749936)
				)
			)
		)
	)
	(zone
		(layers "B.Cu" "In7.Cu" "In9.Cu" "In11.Cu" "In13.Cu" "In15.Cu")
		(hatch none 0.5)
		(connect_pads
			(clearance 0)
		)
		(min_thickness 0.25)
		(keepout
			(tracks not_allowed)
			(vias allowed)
			(pads allowed)
			(copperpour not_allowed)
			(footprints allowed)
		)
		(placement
			(enabled no)
			(sheetname "")
		)
		(fill yes
			(thermal_gap 0.5)
			(thermal_bridge_width 0.5)
			(island_removal_mode 0)
		)
		(polygon
			(pts
				(arc
					(start 174.176436 -318.699896)
					(mid 173.523656 -318.699896)
					(end 174.176436 -318.699896)
				)
			)
		)
	)
	(zone
		(layers "B.Cu" "In7.Cu" "In9.Cu" "In11.Cu" "In13.Cu" "In15.Cu")
		(hatch none 0.5)
		(connect_pads
			(clearance 0)
		)
		(min_thickness 0.25)
		(keepout
			(tracks not_allowed)
			(vias allowed)
			(pads allowed)
			(copperpour not_allowed)
			(footprints allowed)
		)
		(placement
			(enabled no)
			(sheetname "")
		)
		(fill yes
			(thermal_gap 0.5)
			(thermal_bridge_width 0.5)
			(island_removal_mode 0)
		)
		(polygon
			(pts
				(arc
					(start 342.869774 -372.890034)
					(mid 342.110314 -372.890034)
					(end 342.869774 -372.890034)
				)
			)
		)
	)
	(zone
		(layers "B.Cu" "In7.Cu" "In9.Cu" "In11.Cu" "In13.Cu" "In15.Cu")
		(hatch none 0.5)
		(connect_pads
			(clearance 0)
		)
		(min_thickness 0.25)
		(keepout
			(tracks not_allowed)
			(vias allowed)
			(pads allowed)
			(copperpour not_allowed)
			(footprints allowed)
		)
		(placement
			(enabled no)
			(sheetname "")
		)
		(fill yes
			(thermal_gap 0.5)
			(thermal_bridge_width 0.5)
			(island_removal_mode 0)
		)
		(polygon
			(pts
				(arc
					(start 311.175908 -273.099784)
					(mid 310.523128 -273.099784)
					(end 311.175908 -273.099784)
				)
			)
		)
	)
	(zone
		(layers "B.Cu" "In7.Cu" "In9.Cu" "In11.Cu" "In13.Cu" "In15.Cu")
		(hatch none 0.5)
		(connect_pads
			(clearance 0)
		)
		(min_thickness 0.25)
		(keepout
			(tracks not_allowed)
			(vias allowed)
			(pads allowed)
			(copperpour not_allowed)
			(footprints allowed)
		)
		(placement
			(enabled no)
			(sheetname "")
		)
		(fill yes
			(thermal_gap 0.5)
			(thermal_bridge_width 0.5)
			(island_removal_mode 0)
		)
		(polygon
			(pts
				(arc
					(start 120.689878 -374.390158)
					(mid 119.930418 -374.390158)
					(end 120.689878 -374.390158)
				)
			)
		)
	)
	(zone
		(layers "B.Cu" "In7.Cu" "In9.Cu" "In11.Cu" "In13.Cu" "In15.Cu")
		(hatch none 0.5)
		(connect_pads
			(clearance 0)
		)
		(min_thickness 0.25)
		(keepout
			(tracks not_allowed)
			(vias allowed)
			(pads allowed)
			(copperpour not_allowed)
			(footprints allowed)
		)
		(placement
			(enabled no)
			(sheetname "")
		)
		(fill yes
			(thermal_gap 0.5)
			(thermal_bridge_width 0.5)
			(island_removal_mode 0)
		)
		(polygon
			(pts
				(arc
					(start 173.48962 -405.589994)
					(mid 172.73016 -405.589994)
					(end 173.48962 -405.589994)
				)
			)
		)
	)
	(zone
		(layers "B.Cu" "In7.Cu" "In9.Cu" "In11.Cu" "In13.Cu" "In15.Cu")
		(hatch none 0.5)
		(connect_pads
			(clearance 0)
		)
		(min_thickness 0.25)
		(keepout
			(tracks not_allowed)
			(vias allowed)
			(pads allowed)
			(copperpour not_allowed)
			(footprints allowed)
		)
		(placement
			(enabled no)
			(sheetname "")
		)
		(fill yes
			(thermal_gap 0.5)
			(thermal_bridge_width 0.5)
			(island_removal_mode 0)
		)
		(polygon
			(pts
				(arc
					(start 183.508904 -146.223736)
					(mid 182.805324 -146.223736)
					(end 183.508904 -146.223736)
				)
			)
		)
	)
	(zone
		(layers "B.Cu" "In7.Cu" "In9.Cu" "In11.Cu" "In13.Cu" "In15.Cu")
		(hatch none 0.5)
		(connect_pads
			(clearance 0)
		)
		(min_thickness 0.25)
		(keepout
			(tracks not_allowed)
			(vias allowed)
			(pads allowed)
			(copperpour not_allowed)
			(footprints allowed)
		)
		(placement
			(enabled no)
			(sheetname "")
		)
		(fill yes
			(thermal_gap 0.5)
			(thermal_bridge_width 0.5)
			(island_removal_mode 0)
		)
		(polygon
			(pts
				(arc
					(start 183.508904 -129.913634)
					(mid 182.805324 -129.913634)
					(end 183.508904 -129.913634)
				)
			)
		)
	)
	(zone
		(layers "B.Cu" "In7.Cu" "In9.Cu" "In11.Cu" "In13.Cu" "In15.Cu")
		(hatch none 0.5)
		(connect_pads
			(clearance 0)
		)
		(min_thickness 0.25)
		(keepout
			(tracks not_allowed)
			(vias allowed)
			(pads allowed)
			(copperpour not_allowed)
			(footprints allowed)
		)
		(placement
			(enabled no)
			(sheetname "")
		)
		(fill yes
			(thermal_gap 0.5)
			(thermal_bridge_width 0.5)
			(island_removal_mode 0)
		)
		(polygon
			(pts
				(arc
					(start 171.289726 -406.690068)
					(mid 170.530266 -406.690068)
					(end 171.289726 -406.690068)
				)
			)
		)
	)
	(zone
		(layers "B.Cu" "In7.Cu" "In9.Cu" "In11.Cu" "In13.Cu" "In15.Cu")
		(hatch none 0.5)
		(connect_pads
			(clearance 0)
		)
		(min_thickness 0.25)
		(keepout
			(tracks not_allowed)
			(vias allowed)
			(pads allowed)
			(copperpour not_allowed)
			(footprints allowed)
		)
		(placement
			(enabled no)
			(sheetname "")
		)
		(fill yes
			(thermal_gap 0.5)
			(thermal_bridge_width 0.5)
			(island_removal_mode 0)
		)
		(polygon
			(pts
				(arc
					(start 286.648652 -106.512614)
					(mid 285.945072 -106.512614)
					(end 286.648652 -106.512614)
				)
			)
		)
	)
	(zone
		(layers "B.Cu" "In7.Cu" "In9.Cu" "In11.Cu" "In13.Cu" "In15.Cu")
		(hatch none 0.5)
		(connect_pads
			(clearance 0)
		)
		(min_thickness 0.25)
		(keepout
			(tracks not_allowed)
			(vias allowed)
			(pads allowed)
			(copperpour not_allowed)
			(footprints allowed)
		)
		(placement
			(enabled no)
			(sheetname "")
		)
		(fill yes
			(thermal_gap 0.5)
			(thermal_bridge_width 0.5)
			(island_removal_mode 0)
		)
		(polygon
			(pts
				(arc
					(start 413.8549 -156.087318)
					(mid 413.15132 -156.087318)
					(end 413.8549 -156.087318)
				)
			)
		)
	)
	(zone
		(layers "B.Cu" "In7.Cu" "In9.Cu" "In11.Cu" "In13.Cu" "In15.Cu")
		(hatch none 0.5)
		(connect_pads
			(clearance 0)
		)
		(min_thickness 0.25)
		(keepout
			(tracks not_allowed)
			(vias allowed)
			(pads allowed)
			(copperpour not_allowed)
			(footprints allowed)
		)
		(placement
			(enabled no)
			(sheetname "")
		)
		(fill yes
			(thermal_gap 0.5)
			(thermal_bridge_width 0.5)
			(island_removal_mode 0)
		)
		(polygon
			(pts
				(arc
					(start 273.176238 -318.699896)
					(mid 272.523458 -318.699896)
					(end 273.176238 -318.699896)
				)
			)
		)
	)
	(zone
		(layers "B.Cu" "In7.Cu" "In9.Cu" "In11.Cu" "In13.Cu" "In15.Cu")
		(hatch none 0.5)
		(connect_pads
			(clearance 0)
		)
		(min_thickness 0.25)
		(keepout
			(tracks not_allowed)
			(vias allowed)
			(pads allowed)
			(copperpour not_allowed)
			(footprints allowed)
		)
		(placement
			(enabled no)
			(sheetname "")
		)
		(fill yes
			(thermal_gap 0.5)
			(thermal_bridge_width 0.5)
			(island_removal_mode 0)
		)
		(polygon
			(pts
				(arc
					(start 282.676092 -317.749936)
					(mid 282.023312 -317.749936)
					(end 282.676092 -317.749936)
				)
			)
		)
	)
	(zone
		(layers "B.Cu" "In7.Cu" "In9.Cu" "In11.Cu" "In13.Cu" "In15.Cu")
		(hatch none 0.5)
		(connect_pads
			(clearance 0)
		)
		(min_thickness 0.25)
		(keepout
			(tracks not_allowed)
			(vias allowed)
			(pads allowed)
			(copperpour not_allowed)
			(footprints allowed)
		)
		(placement
			(enabled no)
			(sheetname "")
		)
		(fill yes
			(thermal_gap 0.5)
			(thermal_bridge_width 0.5)
			(island_removal_mode 0)
		)
		(polygon
			(pts
				(arc
					(start 198.876412 -281.649932)
					(mid 198.223632 -281.649932)
					(end 198.876412 -281.649932)
				)
			)
		)
	)
	(zone
		(layers "B.Cu" "In7.Cu" "In9.Cu" "In11.Cu" "In13.Cu" "In15.Cu")
		(hatch none 0.5)
		(connect_pads
			(clearance 0)
		)
		(min_thickness 0.25)
		(keepout
			(tracks not_allowed)
			(vias allowed)
			(pads allowed)
			(copperpour not_allowed)
			(footprints allowed)
		)
		(placement
			(enabled no)
			(sheetname "")
		)
		(fill yes
			(thermal_gap 0.5)
			(thermal_bridge_width 0.5)
			(island_removal_mode 0)
		)
		(polygon
			(pts
				(arc
					(start 384.669792 -397.790162)
					(mid 383.910332 -397.790162)
					(end 384.669792 -397.790162)
				)
			)
		)
	)
	(zone
		(layers "B.Cu" "In7.Cu" "In9.Cu" "In11.Cu" "In13.Cu" "In15.Cu")
		(hatch none 0.5)
		(connect_pads
			(clearance 0)
		)
		(min_thickness 0.25)
		(keepout
			(tracks not_allowed)
			(vias allowed)
			(pads allowed)
			(copperpour not_allowed)
			(footprints allowed)
		)
		(placement
			(enabled no)
			(sheetname "")
		)
		(fill yes
			(thermal_gap 0.5)
			(thermal_bridge_width 0.5)
			(island_removal_mode 0)
		)
		(polygon
			(pts
				(arc
					(start 181.654704 -156.087318)
					(mid 180.951124 -156.087318)
					(end 181.654704 -156.087318)
				)
			)
		)
	)
	(zone
		(layers "B.Cu" "In7.Cu" "In9.Cu" "In11.Cu" "In13.Cu" "In15.Cu")
		(hatch none 0.5)
		(connect_pads
			(clearance 0)
		)
		(min_thickness 0.25)
		(keepout
			(tracks not_allowed)
			(vias allowed)
			(pads allowed)
			(copperpour not_allowed)
			(footprints allowed)
		)
		(placement
			(enabled no)
			(sheetname "")
		)
		(fill yes
			(thermal_gap 0.5)
			(thermal_bridge_width 0.5)
			(island_removal_mode 0)
		)
		(polygon
			(pts
				(arc
					(start 402.74875 -131.29641)
					(mid 402.04517 -131.29641)
					(end 402.74875 -131.29641)
				)
			)
		)
	)
	(zone
		(layers "B.Cu" "In7.Cu" "In9.Cu" "In11.Cu" "In13.Cu" "In15.Cu")
		(hatch none 0.5)
		(connect_pads
			(clearance 0)
		)
		(min_thickness 0.25)
		(keepout
			(tracks not_allowed)
			(vias allowed)
			(pads allowed)
			(copperpour not_allowed)
			(footprints allowed)
		)
		(placement
			(enabled no)
			(sheetname "")
		)
		(fill yes
			(thermal_gap 0.5)
			(thermal_bridge_width 0.5)
			(island_removal_mode 0)
		)
		(polygon
			(pts
				(arc
					(start 297.754802 -148.023834)
					(mid 297.051222 -148.023834)
					(end 297.754802 -148.023834)
				)
			)
		)
	)
	(zone
		(layers "B.Cu" "In7.Cu" "In9.Cu" "In11.Cu" "In13.Cu" "In15.Cu")
		(hatch none 0.5)
		(connect_pads
			(clearance 0)
		)
		(min_thickness 0.25)
		(keepout
			(tracks not_allowed)
			(vias allowed)
			(pads allowed)
			(copperpour not_allowed)
			(footprints allowed)
		)
		(placement
			(enabled no)
			(sheetname "")
		)
		(fill yes
			(thermal_gap 0.5)
			(thermal_bridge_width 0.5)
			(island_removal_mode 0)
		)
		(polygon
			(pts
				(arc
					(start 431.076354 -274.999704)
					(mid 430.423574 -274.999704)
					(end 431.076354 -274.999704)
				)
			)
		)
	)
	(zone
		(layers "B.Cu" "In7.Cu" "In9.Cu" "In11.Cu" "In13.Cu" "In15.Cu")
		(hatch none 0.5)
		(connect_pads
			(clearance 0)
		)
		(min_thickness 0.25)
		(keepout
			(tracks not_allowed)
			(vias allowed)
			(pads allowed)
			(copperpour not_allowed)
			(footprints allowed)
		)
		(placement
			(enabled no)
			(sheetname "")
		)
		(fill yes
			(thermal_gap 0.5)
			(thermal_bridge_width 0.5)
			(island_removal_mode 0)
		)
		(polygon
			(pts
				(arc
					(start 45.72635 -316.799722)
					(mid 45.07357 -316.799722)
					(end 45.72635 -316.799722)
				)
			)
		)
	)
	(zone
		(layers "B.Cu" "In7.Cu" "In9.Cu" "In11.Cu" "In13.Cu" "In15.Cu")
		(hatch none 0.5)
		(connect_pads
			(clearance 0)
		)
		(min_thickness 0.25)
		(keepout
			(tracks not_allowed)
			(vias allowed)
			(pads allowed)
			(copperpour not_allowed)
			(footprints allowed)
		)
		(placement
			(enabled no)
			(sheetname "")
		)
		(fill yes
			(thermal_gap 0.5)
			(thermal_bridge_width 0.5)
			(island_removal_mode 0)
		)
		(polygon
			(pts
				(arc
					(start 67.576192 -317.749936)
					(mid 66.923412 -317.749936)
					(end 67.576192 -317.749936)
				)
			)
		)
	)
	(zone
		(layers "B.Cu" "In7.Cu" "In9.Cu" "In11.Cu" "In13.Cu" "In15.Cu")
		(hatch none 0.5)
		(connect_pads
			(clearance 0)
		)
		(min_thickness 0.25)
		(keepout
			(tracks not_allowed)
			(vias allowed)
			(pads allowed)
			(copperpour not_allowed)
			(footprints allowed)
		)
		(placement
			(enabled no)
			(sheetname "")
		)
		(fill yes
			(thermal_gap 0.5)
			(thermal_bridge_width 0.5)
			(island_removal_mode 0)
		)
		(polygon
			(pts
				(arc
					(start 403.526244 -315.849762)
					(mid 402.873464 -315.849762)
					(end 403.526244 -315.849762)
				)
			)
		)
	)
	(zone
		(layers "B.Cu" "In7.Cu" "In9.Cu" "In11.Cu" "In13.Cu" "In15.Cu")
		(hatch none 0.5)
		(connect_pads
			(clearance 0)
		)
		(min_thickness 0.25)
		(keepout
			(tracks not_allowed)
			(vias allowed)
			(pads allowed)
			(copperpour not_allowed)
			(footprints allowed)
		)
		(placement
			(enabled no)
			(sheetname "")
		)
		(fill yes
			(thermal_gap 0.5)
			(thermal_bridge_width 0.5)
			(island_removal_mode 0)
		)
		(polygon
			(pts
				(arc
					(start 28.289758 -408.190192)
					(mid 27.530298 -408.190192)
					(end 28.289758 -408.190192)
				)
			)
		)
	)
	(zone
		(layers "B.Cu" "In7.Cu" "In9.Cu" "In11.Cu" "In13.Cu" "In15.Cu")
		(hatch none 0.5)
		(connect_pads
			(clearance 0)
		)
		(min_thickness 0.25)
		(keepout
			(tracks not_allowed)
			(vias allowed)
			(pads allowed)
			(copperpour not_allowed)
			(footprints allowed)
		)
		(placement
			(enabled no)
			(sheetname "")
		)
		(fill yes
			(thermal_gap 0.5)
			(thermal_bridge_width 0.5)
			(island_removal_mode 0)
		)
		(polygon
			(pts
				(arc
					(start 180.82641 -315.849762)
					(mid 180.17363 -315.849762)
					(end 180.82641 -315.849762)
				)
			)
		)
	)
	(zone
		(layers "B.Cu" "In7.Cu" "In9.Cu" "In11.Cu" "In13.Cu" "In15.Cu")
		(hatch none 0.5)
		(connect_pads
			(clearance 0)
		)
		(min_thickness 0.25)
		(keepout
			(tracks not_allowed)
			(vias allowed)
			(pads allowed)
			(copperpour not_allowed)
			(footprints allowed)
		)
		(placement
			(enabled no)
			(sheetname "")
		)
		(fill yes
			(thermal_gap 0.5)
			(thermal_bridge_width 0.5)
			(island_removal_mode 0)
		)
		(polygon
			(pts
				(arc
					(start 78.026006 -275.949918)
					(mid 77.373226 -275.949918)
					(end 78.026006 -275.949918)
				)
			)
		)
	)
	(zone
		(layers "B.Cu" "In7.Cu" "In9.Cu" "In11.Cu" "In13.Cu" "In15.Cu")
		(hatch none 0.5)
		(connect_pads
			(clearance 0)
		)
		(min_thickness 0.25)
		(keepout
			(tracks not_allowed)
			(vias allowed)
			(pads allowed)
			(copperpour not_allowed)
			(footprints allowed)
		)
		(placement
			(enabled no)
			(sheetname "")
		)
		(fill yes
			(thermal_gap 0.5)
			(thermal_bridge_width 0.5)
			(island_removal_mode 0)
		)
		(polygon
			(pts
				(arc
					(start 184.625996 -274.999704)
					(mid 183.973216 -274.999704)
					(end 184.625996 -274.999704)
				)
			)
		)
	)
	(zone
		(layers "B.Cu" "In7.Cu" "In9.Cu" "In11.Cu" "In13.Cu" "In15.Cu")
		(hatch none 0.5)
		(connect_pads
			(clearance 0)
		)
		(min_thickness 0.25)
		(keepout
			(tracks not_allowed)
			(vias allowed)
			(pads allowed)
			(copperpour not_allowed)
			(footprints allowed)
		)
		(placement
			(enabled no)
			(sheetname "")
		)
		(fill yes
			(thermal_gap 0.5)
			(thermal_bridge_width 0.5)
			(island_removal_mode 0)
		)
		(polygon
			(pts
				(arc
					(start 297.754802 -135.313674)
					(mid 297.051222 -135.313674)
					(end 297.754802 -135.313674)
				)
			)
		)
	)
	(zone
		(layers "B.Cu" "In7.Cu" "In9.Cu" "In11.Cu" "In13.Cu" "In15.Cu")
		(hatch none 0.5)
		(connect_pads
			(clearance 0)
		)
		(min_thickness 0.25)
		(keepout
			(tracks not_allowed)
			(vias allowed)
			(pads allowed)
			(copperpour not_allowed)
			(footprints allowed)
		)
		(placement
			(enabled no)
			(sheetname "")
		)
		(fill yes
			(thermal_gap 0.5)
			(thermal_bridge_width 0.5)
			(island_removal_mode 0)
		)
		(polygon
			(pts
				(arc
					(start 298.82592 -275.949918)
					(mid 298.17314 -275.949918)
					(end 298.82592 -275.949918)
				)
			)
		)
	)
	(zone
		(layers "B.Cu" "In7.Cu" "In9.Cu" "In11.Cu" "In13.Cu" "In15.Cu")
		(hatch none 0.5)
		(connect_pads
			(clearance 0)
		)
		(min_thickness 0.25)
		(keepout
			(tracks not_allowed)
			(vias allowed)
			(pads allowed)
			(copperpour not_allowed)
			(footprints allowed)
		)
		(placement
			(enabled no)
			(sheetname "")
		)
		(fill yes
			(thermal_gap 0.5)
			(thermal_bridge_width 0.5)
			(island_removal_mode 0)
		)
		(polygon
			(pts
				(arc
					(start 177.026316 -315.849762)
					(mid 176.373536 -315.849762)
					(end 177.026316 -315.849762)
				)
			)
		)
	)
	(zone
		(layers "B.Cu" "In7.Cu" "In9.Cu" "In11.Cu" "In13.Cu" "In15.Cu")
		(hatch none 0.5)
		(connect_pads
			(clearance 0)
		)
		(min_thickness 0.25)
		(keepout
			(tracks not_allowed)
			(vias allowed)
			(pads allowed)
			(copperpour not_allowed)
			(footprints allowed)
		)
		(placement
			(enabled no)
			(sheetname "")
		)
		(fill yes
			(thermal_gap 0.5)
			(thermal_bridge_width 0.5)
			(island_removal_mode 0)
		)
		(polygon
			(pts
				(arc
					(start 80.87614 -286.399732)
					(mid 80.22336 -286.399732)
					(end 80.87614 -286.399732)
				)
			)
		)
	)
	(zone
		(layers "B.Cu" "In7.Cu" "In9.Cu" "In11.Cu" "In13.Cu" "In15.Cu")
		(hatch none 0.5)
		(connect_pads
			(clearance 0)
		)
		(min_thickness 0.25)
		(keepout
			(tracks not_allowed)
			(vias allowed)
			(pads allowed)
			(copperpour not_allowed)
			(footprints allowed)
		)
		(placement
			(enabled no)
			(sheetname "")
		)
		(fill yes
			(thermal_gap 0.5)
			(thermal_bridge_width 0.5)
			(island_removal_mode 0)
		)
		(polygon
			(pts
				(arc
					(start 299.609002 -142.62354)
					(mid 298.905422 -142.62354)
					(end 299.609002 -142.62354)
				)
			)
		)
	)
	(zone
		(layers "B.Cu" "In7.Cu" "In9.Cu" "In11.Cu" "In13.Cu" "In15.Cu")
		(hatch none 0.5)
		(connect_pads
			(clearance 0)
		)
		(min_thickness 0.25)
		(keepout
			(tracks not_allowed)
			(vias allowed)
			(pads allowed)
			(copperpour not_allowed)
			(footprints allowed)
		)
		(placement
			(enabled no)
			(sheetname "")
		)
		(fill yes
			(thermal_gap 0.5)
			(thermal_bridge_width 0.5)
			(island_removal_mode 0)
		)
		(polygon
			(pts
				(arc
					(start 37.176202 -310.149748)
					(mid 36.523422 -310.149748)
					(end 37.176202 -310.149748)
				)
			)
		)
	)
	(zone
		(layers "B.Cu" "In7.Cu" "In9.Cu" "In11.Cu" "In13.Cu" "In15.Cu")
		(hatch none 0.5)
		(connect_pads
			(clearance 0)
		)
		(min_thickness 0.25)
		(keepout
			(tracks not_allowed)
			(vias allowed)
			(pads allowed)
			(copperpour not_allowed)
			(footprints allowed)
		)
		(placement
			(enabled no)
			(sheetname "")
		)
		(fill yes
			(thermal_gap 0.5)
			(thermal_bridge_width 0.5)
			(island_removal_mode 0)
		)
		(polygon
			(pts
				(arc
					(start 118.48973 -375.490232)
					(mid 117.73027 -375.490232)
					(end 118.48973 -375.490232)
				)
			)
		)
	)
	(zone
		(layers "B.Cu" "In7.Cu" "In9.Cu" "In11.Cu" "In13.Cu" "In15.Cu")
		(hatch none 0.5)
		(connect_pads
			(clearance 0)
		)
		(min_thickness 0.25)
		(keepout
			(tracks not_allowed)
			(vias allowed)
			(pads allowed)
			(copperpour not_allowed)
			(footprints allowed)
		)
		(placement
			(enabled no)
			(sheetname "")
		)
		(fill yes
			(thermal_gap 0.5)
			(thermal_bridge_width 0.5)
			(island_removal_mode 0)
		)
		(polygon
			(pts
				(arc
					(start 405.426418 -316.799722)
					(mid 404.773638 -316.799722)
					(end 405.426418 -316.799722)
				)
			)
		)
	)
	(zone
		(layers "B.Cu" "In7.Cu" "In9.Cu" "In11.Cu" "In13.Cu" "In15.Cu")
		(hatch none 0.5)
		(connect_pads
			(clearance 0)
		)
		(min_thickness 0.25)
		(keepout
			(tracks not_allowed)
			(vias allowed)
			(pads allowed)
			(copperpour not_allowed)
			(footprints allowed)
		)
		(placement
			(enabled no)
			(sheetname "")
		)
		(fill yes
			(thermal_gap 0.5)
			(thermal_bridge_width 0.5)
			(island_removal_mode 0)
		)
		(polygon
			(pts
				(arc
					(start 426.3263 -316.799722)
					(mid 425.67352 -316.799722)
					(end 426.3263 -316.799722)
				)
			)
		)
	)
	(zone
		(layers "B.Cu" "In7.Cu" "In9.Cu" "In11.Cu" "In13.Cu" "In15.Cu")
		(hatch none 0.5)
		(connect_pads
			(clearance 0)
		)
		(min_thickness 0.25)
		(keepout
			(tracks not_allowed)
			(vias allowed)
			(pads allowed)
			(copperpour not_allowed)
			(footprints allowed)
		)
		(placement
			(enabled no)
			(sheetname "")
		)
		(fill yes
			(thermal_gap 0.5)
			(thermal_bridge_width 0.5)
			(island_removal_mode 0)
		)
		(polygon
			(pts
				(arc
					(start 30.489652 -409.290012)
					(mid 29.730192 -409.290012)
					(end 30.489652 -409.290012)
				)
			)
		)
	)
	(zone
		(layers "B.Cu" "In7.Cu" "In9.Cu" "In11.Cu" "In13.Cu" "In15.Cu")
		(hatch none 0.5)
		(connect_pads
			(clearance 0)
		)
		(min_thickness 0.25)
		(keepout
			(tracks not_allowed)
			(vias allowed)
			(pads allowed)
			(copperpour not_allowed)
			(footprints allowed)
		)
		(placement
			(enabled no)
			(sheetname "")
		)
		(fill yes
			(thermal_gap 0.5)
			(thermal_bridge_width 0.5)
			(island_removal_mode 0)
		)
		(polygon
			(pts
				(arc
					(start 290.069524 -409.290012)
					(mid 289.310064 -409.290012)
					(end 290.069524 -409.290012)
				)
			)
		)
	)
	(zone
		(layers "B.Cu" "In7.Cu" "In9.Cu" "In11.Cu" "In13.Cu" "In15.Cu")
		(hatch none 0.5)
		(connect_pads
			(clearance 0)
		)
		(min_thickness 0.25)
		(keepout
			(tracks not_allowed)
			(vias allowed)
			(pads allowed)
			(copperpour not_allowed)
			(footprints allowed)
		)
		(placement
			(enabled no)
			(sheetname "")
		)
		(fill yes
			(thermal_gap 0.5)
			(thermal_bridge_width 0.5)
			(island_removal_mode 0)
		)
		(polygon
			(pts
				(arc
					(start 34.889694 -384.590036)
					(mid 34.130234 -384.590036)
					(end 34.889694 -384.590036)
				)
			)
		)
	)
	(zone
		(layers "B.Cu" "In7.Cu" "In9.Cu" "In11.Cu" "In13.Cu" "In15.Cu")
		(hatch none 0.5)
		(connect_pads
			(clearance 0)
		)
		(min_thickness 0.25)
		(keepout
			(tracks not_allowed)
			(vias allowed)
			(pads allowed)
			(copperpour not_allowed)
			(footprints allowed)
		)
		(placement
			(enabled no)
			(sheetname "")
		)
		(fill yes
			(thermal_gap 0.5)
			(thermal_bridge_width 0.5)
			(island_removal_mode 0)
		)
		(polygon
			(pts
				(arc
					(start 417.776152 -273.099784)
					(mid 417.123372 -273.099784)
					(end 417.776152 -273.099784)
				)
			)
		)
	)
	(zone
		(layers "B.Cu" "In7.Cu" "In9.Cu" "In11.Cu" "In13.Cu" "In15.Cu")
		(hatch none 0.5)
		(connect_pads
			(clearance 0)
		)
		(min_thickness 0.25)
		(keepout
			(tracks not_allowed)
			(vias allowed)
			(pads allowed)
			(copperpour not_allowed)
			(footprints allowed)
		)
		(placement
			(enabled no)
			(sheetname "")
		)
		(fill yes
			(thermal_gap 0.5)
			(thermal_bridge_width 0.5)
			(island_removal_mode 0)
		)
		(polygon
			(pts
				(arc
					(start 402.74875 -120.086374)
					(mid 402.04517 -120.086374)
					(end 402.74875 -120.086374)
				)
			)
		)
	)
	(zone
		(layers "B.Cu" "In7.Cu" "In9.Cu" "In11.Cu" "In13.Cu" "In15.Cu")
		(hatch none 0.5)
		(connect_pads
			(clearance 0)
		)
		(min_thickness 0.25)
		(keepout
			(tracks not_allowed)
			(vias allowed)
			(pads allowed)
			(copperpour not_allowed)
			(footprints allowed)
		)
		(placement
			(enabled no)
			(sheetname "")
		)
		(fill yes
			(thermal_gap 0.5)
			(thermal_bridge_width 0.5)
			(island_removal_mode 0)
		)
		(polygon
			(pts
				(arc
					(start 312.125868 -275.949918)
					(mid 311.473088 -275.949918)
					(end 312.125868 -275.949918)
				)
			)
		)
	)
	(zone
		(layers "B.Cu" "In7.Cu" "In9.Cu" "In11.Cu" "In13.Cu" "In15.Cu")
		(hatch none 0.5)
		(connect_pads
			(clearance 0)
		)
		(min_thickness 0.25)
		(keepout
			(tracks not_allowed)
			(vias allowed)
			(pads allowed)
			(copperpour not_allowed)
			(footprints allowed)
		)
		(placement
			(enabled no)
			(sheetname "")
		)
		(fill yes
			(thermal_gap 0.5)
			(thermal_bridge_width 0.5)
			(island_removal_mode 0)
		)
		(polygon
			(pts
				(arc
					(start 340.66988 -401.690078)
					(mid 339.91042 -401.690078)
					(end 340.66988 -401.690078)
				)
			)
		)
	)
	(zone
		(layers "B.Cu" "In7.Cu" "In9.Cu" "In11.Cu" "In13.Cu" "In15.Cu")
		(hatch none 0.5)
		(connect_pads
			(clearance 0)
		)
		(min_thickness 0.25)
		(keepout
			(tracks not_allowed)
			(vias allowed)
			(pads allowed)
			(copperpour not_allowed)
			(footprints allowed)
		)
		(placement
			(enabled no)
			(sheetname "")
		)
		(fill yes
			(thermal_gap 0.5)
			(thermal_bridge_width 0.5)
			(island_removal_mode 0)
		)
		(polygon
			(pts
				(arc
					(start 342.869774 -401.49018)
					(mid 342.110314 -401.49018)
					(end 342.869774 -401.49018)
				)
			)
		)
	)
	(zone
		(layers "B.Cu" "In7.Cu" "In9.Cu" "In11.Cu" "In13.Cu" "In15.Cu")
		(hatch none 0.5)
		(connect_pads
			(clearance 0)
		)
		(min_thickness 0.25)
		(keepout
			(tracks not_allowed)
			(vias allowed)
			(pads allowed)
			(copperpour not_allowed)
			(footprints allowed)
		)
		(placement
			(enabled no)
			(sheetname "")
		)
		(fill yes
			(thermal_gap 0.5)
			(thermal_bridge_width 0.5)
			(island_removal_mode 0)
		)
		(polygon
			(pts
				(arc
					(start 391.269728 -398.890236)
					(mid 390.510268 -398.890236)
					(end 391.269728 -398.890236)
				)
			)
		)
	)
	(zone
		(layers "B.Cu" "In7.Cu" "In9.Cu" "In11.Cu" "In13.Cu" "In15.Cu")
		(hatch none 0.5)
		(connect_pads
			(clearance 0)
		)
		(min_thickness 0.25)
		(keepout
			(tracks not_allowed)
			(vias allowed)
			(pads allowed)
			(copperpour not_allowed)
			(footprints allowed)
		)
		(placement
			(enabled no)
			(sheetname "")
		)
		(fill yes
			(thermal_gap 0.5)
			(thermal_bridge_width 0.5)
			(island_removal_mode 0)
		)
		(polygon
			(pts
				(arc
					(start 183.508904 -118.703598)
					(mid 182.805324 -118.703598)
					(end 183.508904 -118.703598)
				)
			)
		)
	)
	(zone
		(layers "B.Cu" "In7.Cu" "In9.Cu" "In11.Cu" "In13.Cu" "In15.Cu")
		(hatch none 0.5)
		(connect_pads
			(clearance 0)
		)
		(min_thickness 0.25)
		(keepout
			(tracks not_allowed)
			(vias allowed)
			(pads allowed)
			(copperpour not_allowed)
			(footprints allowed)
		)
		(placement
			(enabled no)
			(sheetname "")
		)
		(fill yes
			(thermal_gap 0.5)
			(thermal_bridge_width 0.5)
			(island_removal_mode 0)
		)
		(polygon
			(pts
				(arc
					(start 196.026278 -288.299906)
					(mid 195.373498 -288.299906)
					(end 196.026278 -288.299906)
				)
			)
		)
	)
	(zone
		(layers "B.Cu" "In7.Cu" "In9.Cu" "In11.Cu" "In13.Cu" "In15.Cu")
		(hatch none 0.5)
		(connect_pads
			(clearance 0)
		)
		(min_thickness 0.25)
		(keepout
			(tracks not_allowed)
			(vias allowed)
			(pads allowed)
			(copperpour not_allowed)
			(footprints allowed)
		)
		(placement
			(enabled no)
			(sheetname "")
		)
		(fill yes
			(thermal_gap 0.5)
			(thermal_bridge_width 0.5)
			(island_removal_mode 0)
		)
		(polygon
			(pts
				(arc
					(start 67.40906 -153.42362)
					(mid 66.70548 -153.42362)
					(end 67.40906 -153.42362)
				)
			)
		)
	)
	(zone
		(layers "B.Cu" "In7.Cu" "In9.Cu" "In11.Cu" "In13.Cu" "In15.Cu")
		(hatch none 0.5)
		(connect_pads
			(clearance 0)
		)
		(min_thickness 0.25)
		(keepout
			(tracks not_allowed)
			(vias allowed)
			(pads allowed)
			(copperpour not_allowed)
			(footprints allowed)
		)
		(placement
			(enabled no)
			(sheetname "")
		)
		(fill yes
			(thermal_gap 0.5)
			(thermal_bridge_width 0.5)
			(island_removal_mode 0)
		)
		(polygon
			(pts
				(arc
					(start 340.66988 -371.790214)
					(mid 339.91042 -371.790214)
					(end 340.66988 -371.790214)
				)
			)
		)
	)
	(zone
		(layers "B.Cu" "In7.Cu" "In9.Cu" "In11.Cu" "In13.Cu" "In15.Cu")
		(hatch none 0.5)
		(connect_pads
			(clearance 0)
		)
		(min_thickness 0.25)
		(keepout
			(tracks not_allowed)
			(vias allowed)
			(pads allowed)
			(copperpour not_allowed)
			(footprints allowed)
		)
		(placement
			(enabled no)
			(sheetname "")
		)
		(fill yes
			(thermal_gap 0.5)
			(thermal_bridge_width 0.5)
			(island_removal_mode 0)
		)
		(polygon
			(pts
				(arc
					(start 170.548554 -123.686316)
					(mid 169.844974 -123.686316)
					(end 170.548554 -123.686316)
				)
			)
		)
	)
	(zone
		(layers "B.Cu" "In7.Cu" "In9.Cu" "In11.Cu" "In13.Cu" "In15.Cu")
		(hatch none 0.5)
		(connect_pads
			(clearance 0)
		)
		(min_thickness 0.25)
		(keepout
			(tracks not_allowed)
			(vias allowed)
			(pads allowed)
			(copperpour not_allowed)
			(footprints allowed)
		)
		(placement
			(enabled no)
			(sheetname "")
		)
		(fill yes
			(thermal_gap 0.5)
			(thermal_bridge_width 0.5)
			(island_removal_mode 0)
		)
		(polygon
			(pts
				(arc
					(start 77.076046 -274.049744)
					(mid 76.423266 -274.049744)
					(end 77.076046 -274.049744)
				)
			)
		)
	)
	(zone
		(layers "B.Cu" "In7.Cu" "In9.Cu" "In11.Cu" "In13.Cu" "In15.Cu")
		(hatch none 0.5)
		(connect_pads
			(clearance 0)
		)
		(min_thickness 0.25)
		(keepout
			(tracks not_allowed)
			(vias allowed)
			(pads allowed)
			(copperpour not_allowed)
			(footprints allowed)
		)
		(placement
			(enabled no)
			(sheetname "")
		)
		(fill yes
			(thermal_gap 0.5)
			(thermal_bridge_width 0.5)
			(island_removal_mode 0)
		)
		(polygon
			(pts
				(arc
					(start 429.17618 -317.749936)
					(mid 428.5234 -317.749936)
					(end 429.17618 -317.749936)
				)
			)
		)
	)
	(zone
		(layers "B.Cu" "In7.Cu" "In9.Cu" "In11.Cu" "In13.Cu" "In15.Cu")
		(hatch none 0.5)
		(connect_pads
			(clearance 0)
		)
		(min_thickness 0.25)
		(keepout
			(tracks not_allowed)
			(vias allowed)
			(pads allowed)
			(copperpour not_allowed)
			(footprints allowed)
		)
		(placement
			(enabled no)
			(sheetname "")
		)
		(fill yes
			(thermal_gap 0.5)
			(thermal_bridge_width 0.5)
			(island_removal_mode 0)
		)
		(polygon
			(pts
				(arc
					(start 168.694354 -112.776508)
					(mid 167.990774 -112.776508)
					(end 168.694354 -112.776508)
				)
			)
		)
	)
	(zone
		(layers "B.Cu" "In7.Cu" "In9.Cu" "In11.Cu" "In13.Cu" "In15.Cu")
		(hatch none 0.5)
		(connect_pads
			(clearance 0)
		)
		(min_thickness 0.25)
		(keepout
			(tracks not_allowed)
			(vias allowed)
			(pads allowed)
			(copperpour not_allowed)
			(footprints allowed)
		)
		(placement
			(enabled no)
			(sheetname "")
		)
		(fill yes
			(thermal_gap 0.5)
			(thermal_bridge_width 0.5)
			(island_removal_mode 0)
		)
		(polygon
			(pts
				(arc
					(start 38.126162 -316.799722)
					(mid 37.473382 -316.799722)
					(end 38.126162 -316.799722)
				)
			)
		)
	)
	(zone
		(layers "B.Cu" "In7.Cu" "In9.Cu" "In11.Cu" "In13.Cu" "In15.Cu")
		(hatch none 0.5)
		(connect_pads
			(clearance 0)
		)
		(min_thickness 0.25)
		(keepout
			(tracks not_allowed)
			(vias allowed)
			(pads allowed)
			(copperpour not_allowed)
			(footprints allowed)
		)
		(placement
			(enabled no)
			(sheetname "")
		)
		(fill yes
			(thermal_gap 0.5)
			(thermal_bridge_width 0.5)
			(island_removal_mode 0)
		)
		(polygon
			(pts
				(arc
					(start 304.526188 -315.849762)
					(mid 303.873408 -315.849762)
					(end 304.526188 -315.849762)
				)
			)
		)
	)
	(zone
		(layers "B.Cu" "In7.Cu" "In9.Cu" "In11.Cu" "In13.Cu" "In15.Cu")
		(hatch none 0.5)
		(connect_pads
			(clearance 0)
		)
		(min_thickness 0.25)
		(keepout
			(tracks not_allowed)
			(vias allowed)
			(pads allowed)
			(copperpour not_allowed)
			(footprints allowed)
		)
		(placement
			(enabled no)
			(sheetname "")
		)
		(fill yes
			(thermal_gap 0.5)
			(thermal_bridge_width 0.5)
			(island_removal_mode 0)
		)
		(polygon
			(pts
				(arc
					(start 433.069492 -404.290022)
					(mid 432.310032 -404.290022)
					(end 433.069492 -404.290022)
				)
			)
		)
	)
	(zone
		(layers "B.Cu" "In7.Cu" "In9.Cu" "In11.Cu" "In13.Cu" "In15.Cu")
		(hatch none 0.5)
		(connect_pads
			(clearance 0)
		)
		(min_thickness 0.25)
		(keepout
			(tracks not_allowed)
			(vias allowed)
			(pads allowed)
			(copperpour not_allowed)
			(footprints allowed)
		)
		(placement
			(enabled no)
			(sheetname "")
		)
		(fill yes
			(thermal_gap 0.5)
			(thermal_bridge_width 0.5)
			(island_removal_mode 0)
		)
		(polygon
			(pts
				(arc
					(start 39.289736 -409.290012)
					(mid 38.530276 -409.290012)
					(end 39.289736 -409.290012)
				)
			)
		)
	)
	(zone
		(layers "B.Cu" "In7.Cu" "In9.Cu" "In11.Cu" "In13.Cu" "In15.Cu")
		(hatch none 0.5)
		(connect_pads
			(clearance 0)
		)
		(min_thickness 0.25)
		(keepout
			(tracks not_allowed)
			(vias allowed)
			(pads allowed)
			(copperpour not_allowed)
			(footprints allowed)
		)
		(placement
			(enabled no)
			(sheetname "")
		)
		(fill yes
			(thermal_gap 0.5)
			(thermal_bridge_width 0.5)
			(island_removal_mode 0)
		)
		(polygon
			(pts
				(arc
					(start 170.548554 -107.376214)
					(mid 169.844974 -107.376214)
					(end 170.548554 -107.376214)
				)
			)
		)
	)
	(zone
		(layers "B.Cu" "In7.Cu" "In9.Cu" "In11.Cu" "In13.Cu" "In15.Cu")
		(hatch none 0.5)
		(connect_pads
			(clearance 0)
		)
		(min_thickness 0.25)
		(keepout
			(tracks not_allowed)
			(vias allowed)
			(pads allowed)
			(copperpour not_allowed)
			(footprints allowed)
		)
		(placement
			(enabled no)
			(sheetname "")
		)
		(fill yes
			(thermal_gap 0.5)
			(thermal_bridge_width 0.5)
			(island_removal_mode 0)
		)
		(polygon
			(pts
				(arc
					(start 277.926292 -315.849762)
					(mid 277.273512 -315.849762)
					(end 277.926292 -315.849762)
				)
			)
		)
	)
	(zone
		(layers "B.Cu" "In7.Cu" "In9.Cu" "In11.Cu" "In13.Cu" "In15.Cu")
		(hatch none 0.5)
		(connect_pads
			(clearance 0)
		)
		(min_thickness 0.25)
		(keepout
			(tracks not_allowed)
			(vias allowed)
			(pads allowed)
			(copperpour not_allowed)
			(footprints allowed)
		)
		(placement
			(enabled no)
			(sheetname "")
		)
		(fill yes
			(thermal_gap 0.5)
			(thermal_bridge_width 0.5)
			(island_removal_mode 0)
		)
		(polygon
			(pts
				(arc
					(start 175.126396 -316.799722)
					(mid 174.473616 -316.799722)
					(end 175.126396 -316.799722)
				)
			)
		)
	)
	(zone
		(layers "B.Cu" "In7.Cu" "In9.Cu" "In11.Cu" "In13.Cu" "In15.Cu")
		(hatch none 0.5)
		(connect_pads
			(clearance 0)
		)
		(min_thickness 0.25)
		(keepout
			(tracks not_allowed)
			(vias allowed)
			(pads allowed)
			(copperpour not_allowed)
			(footprints allowed)
		)
		(placement
			(enabled no)
			(sheetname "")
		)
		(fill yes
			(thermal_gap 0.5)
			(thermal_bridge_width 0.5)
			(island_removal_mode 0)
		)
		(polygon
			(pts
				(arc
					(start 271.276318 -303.499774)
					(mid 270.623538 -303.499774)
					(end 271.276318 -303.499774)
				)
			)
		)
	)
	(zone
		(layers "B.Cu" "In7.Cu" "In9.Cu" "In11.Cu" "In13.Cu" "In15.Cu")
		(hatch none 0.5)
		(connect_pads
			(clearance 0)
		)
		(min_thickness 0.25)
		(keepout
			(tracks not_allowed)
			(vias allowed)
			(pads allowed)
			(copperpour not_allowed)
			(footprints allowed)
		)
		(placement
			(enabled no)
			(sheetname "")
		)
		(fill yes
			(thermal_gap 0.5)
			(thermal_bridge_width 0.5)
			(island_removal_mode 0)
		)
		(polygon
			(pts
				(arc
					(start 127.289814 -375.490232)
					(mid 126.530354 -375.490232)
					(end 127.289814 -375.490232)
				)
			)
		)
	)
	(zone
		(layers "B.Cu" "In7.Cu" "In9.Cu" "In11.Cu" "In13.Cu" "In15.Cu")
		(hatch none 0.5)
		(connect_pads
			(clearance 0)
		)
		(min_thickness 0.25)
		(keepout
			(tracks not_allowed)
			(vias allowed)
			(pads allowed)
			(copperpour not_allowed)
			(footprints allowed)
		)
		(placement
			(enabled no)
			(sheetname "")
		)
		(fill yes
			(thermal_gap 0.5)
			(thermal_bridge_width 0.5)
			(island_removal_mode 0)
		)
		(polygon
			(pts
				(arc
					(start 162.489642 -406.690068)
					(mid 161.730182 -406.690068)
					(end 162.489642 -406.690068)
				)
			)
		)
	)
	(zone
		(layers "B.Cu" "In7.Cu" "In9.Cu" "In11.Cu" "In13.Cu" "In15.Cu")
		(hatch none 0.5)
		(connect_pads
			(clearance 0)
		)
		(min_thickness 0.25)
		(keepout
			(tracks not_allowed)
			(vias allowed)
			(pads allowed)
			(copperpour not_allowed)
			(footprints allowed)
		)
		(placement
			(enabled no)
			(sheetname "")
		)
		(fill yes
			(thermal_gap 0.5)
			(thermal_bridge_width 0.5)
			(island_removal_mode 0)
		)
		(polygon
			(pts
				(arc
					(start 257.193288 8.515604)
					(mid 256.489708 8.515604)
					(end 257.193288 8.515604)
				)
			)
		)
	)
	(zone
		(layers "B.Cu" "In7.Cu" "In9.Cu" "In11.Cu" "In13.Cu" "In15.Cu")
		(hatch none 0.5)
		(connect_pads
			(clearance 0)
		)
		(min_thickness 0.25)
		(keepout
			(tracks not_allowed)
			(vias allowed)
			(pads allowed)
			(copperpour not_allowed)
			(footprints allowed)
		)
		(placement
			(enabled no)
			(sheetname "")
		)
		(fill yes
			(thermal_gap 0.5)
			(thermal_bridge_width 0.5)
			(island_removal_mode 0)
		)
		(polygon
			(pts
				(arc
					(start 131.689856 -375.490232)
					(mid 130.930396 -375.490232)
					(end 131.689856 -375.490232)
				)
			)
		)
	)
	(zone
		(layers "B.Cu" "In7.Cu" "In9.Cu" "In11.Cu" "In13.Cu" "In15.Cu")
		(hatch none 0.5)
		(connect_pads
			(clearance 0)
		)
		(min_thickness 0.25)
		(keepout
			(tracks not_allowed)
			(vias allowed)
			(pads allowed)
			(copperpour not_allowed)
			(footprints allowed)
		)
		(placement
			(enabled no)
			(sheetname "")
		)
		(fill yes
			(thermal_gap 0.5)
			(thermal_bridge_width 0.5)
			(island_removal_mode 0)
		)
		(polygon
			(pts
				(arc
					(start 80.87614 -288.299906)
					(mid 80.22336 -288.299906)
					(end 80.87614 -288.299906)
				)
			)
		)
	)
	(zone
		(layers "B.Cu" "In7.Cu" "In9.Cu" "In11.Cu" "In13.Cu" "In15.Cu")
		(hatch none 0.5)
		(connect_pads
			(clearance 0)
		)
		(min_thickness 0.25)
		(keepout
			(tracks not_allowed)
			(vias allowed)
			(pads allowed)
			(copperpour not_allowed)
			(footprints allowed)
		)
		(placement
			(enabled no)
			(sheetname "")
		)
		(fill yes
			(thermal_gap 0.5)
			(thermal_bridge_width 0.5)
			(island_removal_mode 0)
		)
		(polygon
			(pts
				(arc
					(start 168.694354 -121.022872)
					(mid 167.990774 -121.022872)
					(end 168.694354 -121.022872)
				)
			)
		)
	)
	(zone
		(layers "B.Cu" "In7.Cu" "In9.Cu" "In11.Cu" "In13.Cu" "In15.Cu")
		(hatch none 0.5)
		(connect_pads
			(clearance 0)
		)
		(min_thickness 0.25)
		(keepout
			(tracks not_allowed)
			(vias allowed)
			(pads allowed)
			(copperpour not_allowed)
			(footprints allowed)
		)
		(placement
			(enabled no)
			(sheetname "")
		)
		(fill yes
			(thermal_gap 0.5)
			(thermal_bridge_width 0.5)
			(island_removal_mode 0)
		)
		(polygon
			(pts
				(arc
					(start 297.754802 -148.887434)
					(mid 297.051222 -148.887434)
					(end 297.754802 -148.887434)
				)
			)
		)
	)
	(zone
		(layers "B.Cu" "In7.Cu" "In9.Cu" "In11.Cu" "In13.Cu" "In15.Cu")
		(hatch none 0.5)
		(connect_pads
			(clearance 0)
		)
		(min_thickness 0.25)
		(keepout
			(tracks not_allowed)
			(vias allowed)
			(pads allowed)
			(copperpour not_allowed)
			(footprints allowed)
		)
		(placement
			(enabled no)
			(sheetname "")
		)
		(fill yes
			(thermal_gap 0.5)
			(thermal_bridge_width 0.5)
			(island_removal_mode 0)
		)
		(polygon
			(pts
				(arc
					(start 168.694354 -132.232908)
					(mid 167.990774 -132.232908)
					(end 168.694354 -132.232908)
				)
			)
		)
	)
	(zone
		(layers "B.Cu" "In7.Cu" "In9.Cu" "In11.Cu" "In13.Cu" "In15.Cu")
		(hatch none 0.5)
		(connect_pads
			(clearance 0)
		)
		(min_thickness 0.25)
		(keepout
			(tracks not_allowed)
			(vias allowed)
			(pads allowed)
			(copperpour not_allowed)
			(footprints allowed)
		)
		(placement
			(enabled no)
			(sheetname "")
		)
		(fill yes
			(thermal_gap 0.5)
			(thermal_bridge_width 0.5)
			(island_removal_mode 0)
		)
		(polygon
			(pts
				(arc
					(start 338.469732 -371.590062)
					(mid 337.710272 -371.590062)
					(end 338.469732 -371.590062)
				)
			)
		)
	)
	(zone
		(layers "B.Cu" "In7.Cu" "In9.Cu" "In11.Cu" "In13.Cu" "In15.Cu")
		(hatch none 0.5)
		(connect_pads
			(clearance 0)
		)
		(min_thickness 0.25)
		(keepout
			(tracks not_allowed)
			(vias allowed)
			(pads allowed)
			(copperpour not_allowed)
			(footprints allowed)
		)
		(placement
			(enabled no)
			(sheetname "")
		)
		(fill yes
			(thermal_gap 0.5)
			(thermal_bridge_width 0.5)
			(island_removal_mode 0)
		)
		(polygon
			(pts
				(arc
					(start 378.069602 -376.790204)
					(mid 377.310142 -376.790204)
					(end 378.069602 -376.790204)
				)
			)
		)
	)
	(zone
		(layers "B.Cu" "In7.Cu" "In9.Cu" "In11.Cu" "In13.Cu" "In15.Cu")
		(hatch none 0.5)
		(connect_pads
			(clearance 0)
		)
		(min_thickness 0.25)
		(keepout
			(tracks not_allowed)
			(vias allowed)
			(pads allowed)
			(copperpour not_allowed)
			(footprints allowed)
		)
		(placement
			(enabled no)
			(sheetname "")
		)
		(fill yes
			(thermal_gap 0.5)
			(thermal_bridge_width 0.5)
			(island_removal_mode 0)
		)
		(polygon
			(pts
				(arc
					(start 194.126104 -275.949918)
					(mid 193.473324 -275.949918)
					(end 194.126104 -275.949918)
				)
			)
		)
	)
	(zone
		(layers "B.Cu" "In7.Cu" "In9.Cu" "In11.Cu" "In13.Cu" "In15.Cu")
		(hatch none 0.5)
		(connect_pads
			(clearance 0)
		)
		(min_thickness 0.25)
		(keepout
			(tracks not_allowed)
			(vias allowed)
			(pads allowed)
			(copperpour not_allowed)
			(footprints allowed)
		)
		(placement
			(enabled no)
			(sheetname "")
		)
		(fill yes
			(thermal_gap 0.5)
			(thermal_bridge_width 0.5)
			(island_removal_mode 0)
		)
		(polygon
			(pts
				(arc
					(start 74.489564 -402.790152)
					(mid 73.730104 -402.790152)
					(end 74.489564 -402.790152)
				)
			)
		)
	)
	(zone
		(layers "B.Cu" "In7.Cu" "In9.Cu" "In11.Cu" "In13.Cu" "In15.Cu")
		(hatch none 0.5)
		(connect_pads
			(clearance 0)
		)
		(min_thickness 0.25)
		(keepout
			(tracks not_allowed)
			(vias allowed)
			(pads allowed)
			(copperpour not_allowed)
			(footprints allowed)
		)
		(placement
			(enabled no)
			(sheetname "")
		)
		(fill yes
			(thermal_gap 0.5)
			(thermal_bridge_width 0.5)
			(island_removal_mode 0)
		)
		(polygon
			(pts
				(arc
					(start 413.8549 -148.887434)
					(mid 413.15132 -148.887434)
					(end 413.8549 -148.887434)
				)
			)
		)
	)
	(zone
		(layers "B.Cu" "In7.Cu" "In9.Cu" "In11.Cu" "In13.Cu" "In15.Cu")
		(hatch none 0.5)
		(connect_pads
			(clearance 0)
		)
		(min_thickness 0.25)
		(keepout
			(tracks not_allowed)
			(vias allowed)
			(pads allowed)
			(copperpour not_allowed)
			(footprints allowed)
		)
		(placement
			(enabled no)
			(sheetname "")
		)
		(fill yes
			(thermal_gap 0.5)
			(thermal_bridge_width 0.5)
			(island_removal_mode 0)
		)
		(polygon
			(pts
				(arc
					(start 72.28967 -371.790214)
					(mid 71.53021 -371.790214)
					(end 72.28967 -371.790214)
				)
			)
		)
	)
	(zone
		(layers "B.Cu" "In7.Cu" "In9.Cu" "In11.Cu" "In13.Cu" "In15.Cu")
		(hatch none 0.5)
		(connect_pads
			(clearance 0)
		)
		(min_thickness 0.25)
		(keepout
			(tracks not_allowed)
			(vias allowed)
			(pads allowed)
			(copperpour not_allowed)
			(footprints allowed)
		)
		(placement
			(enabled no)
			(sheetname "")
		)
		(fill yes
			(thermal_gap 0.5)
			(thermal_bridge_width 0.5)
			(island_removal_mode 0)
		)
		(polygon
			(pts
				(arc
					(start 303.576228 -318.699896)
					(mid 302.923448 -318.699896)
					(end 303.576228 -318.699896)
				)
			)
		)
	)
	(zone
		(layers "B.Cu" "In7.Cu" "In9.Cu" "In11.Cu" "In13.Cu" "In15.Cu")
		(hatch none 0.5)
		(connect_pads
			(clearance 0)
		)
		(min_thickness 0.25)
		(keepout
			(tracks not_allowed)
			(vias allowed)
			(pads allowed)
			(copperpour not_allowed)
			(footprints allowed)
		)
		(placement
			(enabled no)
			(sheetname "")
		)
		(fill yes
			(thermal_gap 0.5)
			(thermal_bridge_width 0.5)
			(island_removal_mode 0)
		)
		(polygon
			(pts
				(arc
					(start 405.426418 -315.849762)
					(mid 404.773638 -315.849762)
					(end 405.426418 -315.849762)
				)
			)
		)
	)
	(zone
		(layers "B.Cu" "In7.Cu" "In9.Cu" "In11.Cu" "In13.Cu" "In15.Cu")
		(hatch none 0.5)
		(connect_pads
			(clearance 0)
		)
		(min_thickness 0.25)
		(keepout
			(tracks not_allowed)
			(vias allowed)
			(pads allowed)
			(copperpour not_allowed)
			(footprints allowed)
		)
		(placement
			(enabled no)
			(sheetname "")
		)
		(fill yes
			(thermal_gap 0.5)
			(thermal_bridge_width 0.5)
			(island_removal_mode 0)
		)
		(polygon
			(pts
				(arc
					(start 305.475894 -274.049744)
					(mid 304.823114 -274.049744)
					(end 305.475894 -274.049744)
				)
			)
		)
	)
	(zone
		(layers "B.Cu" "In7.Cu" "In9.Cu" "In11.Cu" "In13.Cu" "In15.Cu")
		(hatch none 0.5)
		(connect_pads
			(clearance 0)
		)
		(min_thickness 0.25)
		(keepout
			(tracks not_allowed)
			(vias allowed)
			(pads allowed)
			(copperpour not_allowed)
			(footprints allowed)
		)
		(placement
			(enabled no)
			(sheetname "")
		)
		(fill yes
			(thermal_gap 0.5)
			(thermal_bridge_width 0.5)
			(island_removal_mode 0)
		)
		(polygon
			(pts
				(arc
					(start 170.548554 -110.97641)
					(mid 169.844974 -110.97641)
					(end 170.548554 -110.97641)
				)
			)
		)
	)
	(zone
		(layers "B.Cu" "In7.Cu" "In9.Cu" "In11.Cu" "In13.Cu" "In15.Cu")
		(hatch none 0.5)
		(connect_pads
			(clearance 0)
		)
		(min_thickness 0.25)
		(keepout
			(tracks not_allowed)
			(vias allowed)
			(pads allowed)
			(copperpour not_allowed)
			(footprints allowed)
		)
		(placement
			(enabled no)
			(sheetname "")
		)
		(fill yes
			(thermal_gap 0.5)
			(thermal_bridge_width 0.5)
			(island_removal_mode 0)
		)
		(polygon
			(pts
				(arc
					(start 196.026278 -307.299868)
					(mid 195.373498 -307.299868)
					(end 196.026278 -307.299868)
				)
			)
		)
	)
	(zone
		(layers "B.Cu" "In7.Cu" "In9.Cu" "In11.Cu" "In13.Cu" "In15.Cu")
		(hatch none 0.5)
		(connect_pads
			(clearance 0)
		)
		(min_thickness 0.25)
		(keepout
			(tracks not_allowed)
			(vias allowed)
			(pads allowed)
			(copperpour not_allowed)
			(footprints allowed)
		)
		(placement
			(enabled no)
			(sheetname "")
		)
		(fill yes
			(thermal_gap 0.5)
			(thermal_bridge_width 0.5)
			(island_removal_mode 0)
		)
		(polygon
			(pts
				(arc
					(start 28.289758 -382.18999)
					(mid 27.530298 -382.18999)
					(end 28.289758 -382.18999)
				)
			)
		)
	)
	(zone
		(layers "B.Cu" "In7.Cu" "In9.Cu" "In11.Cu" "In13.Cu" "In15.Cu")
		(hatch none 0.5)
		(connect_pads
			(clearance 0)
		)
		(min_thickness 0.25)
		(keepout
			(tracks not_allowed)
			(vias allowed)
			(pads allowed)
			(copperpour not_allowed)
			(footprints allowed)
		)
		(placement
			(enabled no)
			(sheetname "")
		)
		(fill yes
			(thermal_gap 0.5)
			(thermal_bridge_width 0.5)
			(island_removal_mode 0)
		)
		(polygon
			(pts
				(arc
					(start 125.08992 -396.49019)
					(mid 124.33046 -396.49019)
					(end 125.08992 -396.49019)
				)
			)
		)
	)
	(zone
		(layers "B.Cu" "In7.Cu" "In9.Cu" "In11.Cu" "In13.Cu" "In15.Cu")
		(hatch none 0.5)
		(connect_pads
			(clearance 0)
		)
		(min_thickness 0.25)
		(keepout
			(tracks not_allowed)
			(vias allowed)
			(pads allowed)
			(copperpour not_allowed)
			(footprints allowed)
		)
		(placement
			(enabled no)
			(sheetname "")
		)
		(fill yes
			(thermal_gap 0.5)
			(thermal_bridge_width 0.5)
			(island_removal_mode 0)
		)
		(polygon
			(pts
				(arc
					(start 334.06969 -371.590062)
					(mid 333.31023 -371.590062)
					(end 334.06969 -371.590062)
				)
			)
		)
	)
	(zone
		(layers "B.Cu" "In7.Cu" "In9.Cu" "In11.Cu" "In13.Cu" "In15.Cu")
		(hatch none 0.5)
		(connect_pads
			(clearance 0)
		)
		(min_thickness 0.25)
		(keepout
			(tracks not_allowed)
			(vias allowed)
			(pads allowed)
			(copperpour not_allowed)
			(footprints allowed)
		)
		(placement
			(enabled no)
			(sheetname "")
		)
		(fill yes
			(thermal_gap 0.5)
			(thermal_bridge_width 0.5)
			(island_removal_mode 0)
		)
		(polygon
			(pts
				(arc
					(start 54.44871 -120.086374)
					(mid 53.74513 -120.086374)
					(end 54.44871 -120.086374)
				)
			)
		)
	)
	(zone
		(layers "B.Cu" "In7.Cu" "In9.Cu" "In11.Cu" "In13.Cu" "In15.Cu")
		(hatch none 0.5)
		(connect_pads
			(clearance 0)
		)
		(min_thickness 0.25)
		(keepout
			(tracks not_allowed)
			(vias allowed)
			(pads allowed)
			(copperpour not_allowed)
			(footprints allowed)
		)
		(placement
			(enabled no)
			(sheetname "")
		)
		(fill yes
			(thermal_gap 0.5)
			(thermal_bridge_width 0.5)
			(island_removal_mode 0)
		)
		(polygon
			(pts
				(arc
					(start 296.669714 -383.490216)
					(mid 295.910254 -383.490216)
					(end 296.669714 -383.490216)
				)
			)
		)
	)
	(zone
		(layers "B.Cu" "In7.Cu" "In9.Cu" "In11.Cu" "In13.Cu" "In15.Cu")
		(hatch none 0.5)
		(connect_pads
			(clearance 0)
		)
		(min_thickness 0.25)
		(keepout
			(tracks not_allowed)
			(vias allowed)
			(pads allowed)
			(copperpour not_allowed)
			(footprints allowed)
		)
		(placement
			(enabled no)
			(sheetname "")
		)
		(fill yes
			(thermal_gap 0.5)
			(thermal_bridge_width 0.5)
			(island_removal_mode 0)
		)
		(polygon
			(pts
				(arc
					(start 417.776152 -274.049744)
					(mid 417.123372 -274.049744)
					(end 417.776152 -274.049744)
				)
			)
		)
	)
	(zone
		(layers "B.Cu" "In7.Cu" "In9.Cu" "In11.Cu" "In13.Cu" "In15.Cu")
		(hatch none 0.5)
		(connect_pads
			(clearance 0)
		)
		(min_thickness 0.25)
		(keepout
			(tracks not_allowed)
			(vias allowed)
			(pads allowed)
			(copperpour not_allowed)
			(footprints allowed)
		)
		(placement
			(enabled no)
			(sheetname "")
		)
		(fill yes
			(thermal_gap 0.5)
			(thermal_bridge_width 0.5)
			(island_removal_mode 0)
		)
		(polygon
			(pts
				(arc
					(start 400.89455 -136.69645)
					(mid 400.19097 -136.69645)
					(end 400.89455 -136.69645)
				)
			)
		)
	)
	(zone
		(layers "B.Cu" "In7.Cu" "In9.Cu" "In11.Cu" "In13.Cu" "In15.Cu")
		(hatch none 0.5)
		(connect_pads
			(clearance 0)
		)
		(min_thickness 0.25)
		(keepout
			(tracks not_allowed)
			(vias allowed)
			(pads allowed)
			(copperpour not_allowed)
			(footprints allowed)
		)
		(placement
			(enabled no)
			(sheetname "")
		)
		(fill yes
			(thermal_gap 0.5)
			(thermal_bridge_width 0.5)
			(island_removal_mode 0)
		)
		(polygon
			(pts
				(arc
					(start 426.469556 -379.390148)
					(mid 425.710096 -379.390148)
					(end 426.469556 -379.390148)
				)
			)
		)
	)
	(zone
		(layers "B.Cu" "In7.Cu" "In9.Cu" "In11.Cu" "In13.Cu" "In15.Cu")
		(hatch none 0.5)
		(connect_pads
			(clearance 0)
		)
		(min_thickness 0.25)
		(keepout
			(tracks not_allowed)
			(vias allowed)
			(pads allowed)
			(copperpour not_allowed)
			(footprints allowed)
		)
		(placement
			(enabled no)
			(sheetname "")
		)
		(fill yes
			(thermal_gap 0.5)
			(thermal_bridge_width 0.5)
			(island_removal_mode 0)
		)
		(polygon
			(pts
				(arc
					(start 181.654704 -135.313674)
					(mid 180.951124 -135.313674)
					(end 181.654704 -135.313674)
				)
			)
		)
	)
	(zone
		(layers "B.Cu" "In7.Cu" "In9.Cu" "In11.Cu" "In13.Cu" "In15.Cu")
		(hatch none 0.5)
		(connect_pads
			(clearance 0)
		)
		(min_thickness 0.25)
		(keepout
			(tracks not_allowed)
			(vias allowed)
			(pads allowed)
			(copperpour not_allowed)
			(footprints allowed)
		)
		(placement
			(enabled no)
			(sheetname "")
		)
		(fill yes
			(thermal_gap 0.5)
			(thermal_bridge_width 0.5)
			(island_removal_mode 0)
		)
		(polygon
			(pts
				(arc
					(start 52.59451 -125.486414)
					(mid 51.89093 -125.486414)
					(end 52.59451 -125.486414)
				)
			)
		)
	)
	(zone
		(layers "B.Cu" "In7.Cu" "In9.Cu" "In11.Cu" "In13.Cu" "In15.Cu")
		(hatch none 0.5)
		(connect_pads
			(clearance 0)
		)
		(min_thickness 0.25)
		(keepout
			(tracks not_allowed)
			(vias allowed)
			(pads allowed)
			(copperpour not_allowed)
			(footprints allowed)
		)
		(placement
			(enabled no)
			(sheetname "")
		)
		(fill yes
			(thermal_gap 0.5)
			(thermal_bridge_width 0.5)
			(island_removal_mode 0)
		)
		(polygon
			(pts
				(arc
					(start 129.489708 -375.69013)
					(mid 128.730248 -375.69013)
					(end 129.489708 -375.69013)
				)
			)
		)
	)
	(zone
		(layers "B.Cu" "In7.Cu" "In9.Cu" "In11.Cu" "In13.Cu" "In15.Cu")
		(hatch none 0.5)
		(connect_pads
			(clearance 0)
		)
		(min_thickness 0.25)
		(keepout
			(tracks not_allowed)
			(vias allowed)
			(pads allowed)
			(copperpour not_allowed)
			(footprints allowed)
		)
		(placement
			(enabled no)
			(sheetname "")
		)
		(fill yes
			(thermal_gap 0.5)
			(thermal_bridge_width 0.5)
			(island_removal_mode 0)
		)
		(polygon
			(pts
				(arc
					(start 422.069514 -406.690068)
					(mid 421.310054 -406.690068)
					(end 422.069514 -406.690068)
				)
			)
		)
	)
	(zone
		(layers "B.Cu" "In7.Cu" "In9.Cu" "In11.Cu" "In13.Cu" "In15.Cu")
		(hatch none 0.5)
		(connect_pads
			(clearance 0)
		)
		(min_thickness 0.25)
		(keepout
			(tracks not_allowed)
			(vias allowed)
			(pads allowed)
			(copperpour not_allowed)
			(footprints allowed)
		)
		(placement
			(enabled no)
			(sheetname "")
		)
		(fill yes
			(thermal_gap 0.5)
			(thermal_bridge_width 0.5)
			(island_removal_mode 0)
		)
		(polygon
			(pts
				(arc
					(start 378.069602 -375.490232)
					(mid 377.310142 -375.490232)
					(end 378.069602 -375.490232)
				)
			)
		)
	)
	(zone
		(layers "B.Cu" "In7.Cu" "In9.Cu" "In11.Cu" "In13.Cu" "In15.Cu")
		(hatch none 0.5)
		(connect_pads
			(clearance 0)
		)
		(min_thickness 0.25)
		(keepout
			(tracks not_allowed)
			(vias allowed)
			(pads allowed)
			(copperpour not_allowed)
			(footprints allowed)
		)
		(placement
			(enabled no)
			(sheetname "")
		)
		(fill yes
			(thermal_gap 0.5)
			(thermal_bridge_width 0.5)
			(island_removal_mode 0)
		)
		(polygon
			(pts
				(arc
					(start 402.576284 -317.749936)
					(mid 401.923504 -317.749936)
					(end 402.576284 -317.749936)
				)
			)
		)
	)
	(zone
		(layers "B.Cu" "In7.Cu" "In9.Cu" "In11.Cu" "In13.Cu" "In15.Cu")
		(hatch none 0.5)
		(connect_pads
			(clearance 0)
		)
		(min_thickness 0.25)
		(keepout
			(tracks not_allowed)
			(vias allowed)
			(pads allowed)
			(copperpour not_allowed)
			(footprints allowed)
		)
		(placement
			(enabled no)
			(sheetname "")
		)
		(fill yes
			(thermal_gap 0.5)
			(thermal_bridge_width 0.5)
			(island_removal_mode 0)
		)
		(polygon
			(pts
				(arc
					(start 39.076376 -303.499774)
					(mid 38.423596 -303.499774)
					(end 39.076376 -303.499774)
				)
			)
		)
	)
	(zone
		(layers "B.Cu" "In7.Cu" "In9.Cu" "In11.Cu" "In13.Cu" "In15.Cu")
		(hatch none 0.5)
		(connect_pads
			(clearance 0)
		)
		(min_thickness 0.25)
		(keepout
			(tracks not_allowed)
			(vias allowed)
			(pads allowed)
			(copperpour not_allowed)
			(footprints allowed)
		)
		(placement
			(enabled no)
			(sheetname "")
		)
		(fill yes
			(thermal_gap 0.5)
			(thermal_bridge_width 0.5)
			(island_removal_mode 0)
		)
		(polygon
			(pts
				(arc
					(start 43.826176 -316.799722)
					(mid 43.173396 -316.799722)
					(end 43.826176 -316.799722)
				)
			)
		)
	)
	(zone
		(layers "B.Cu" "In7.Cu" "In9.Cu" "In11.Cu" "In13.Cu" "In15.Cu")
		(hatch none 0.5)
		(connect_pads
			(clearance 0)
		)
		(min_thickness 0.25)
		(keepout
			(tracks not_allowed)
			(vias allowed)
			(pads allowed)
			(copperpour not_allowed)
			(footprints allowed)
		)
		(placement
			(enabled no)
			(sheetname "")
		)
		(fill yes
			(thermal_gap 0.5)
			(thermal_bridge_width 0.5)
			(island_removal_mode 0)
		)
		(polygon
			(pts
				(arc
					(start 270.326104 -310.149748)
					(mid 269.673324 -310.149748)
					(end 270.326104 -310.149748)
				)
			)
		)
	)
	(zone
		(layers "B.Cu" "In7.Cu" "In9.Cu" "In11.Cu" "In13.Cu" "In15.Cu")
		(hatch none 0.5)
		(connect_pads
			(clearance 0)
		)
		(min_thickness 0.25)
		(keepout
			(tracks not_allowed)
			(vias allowed)
			(pads allowed)
			(copperpour not_allowed)
			(footprints allowed)
		)
		(placement
			(enabled no)
			(sheetname "")
		)
		(fill yes
			(thermal_gap 0.5)
			(thermal_bridge_width 0.5)
			(island_removal_mode 0)
		)
		(polygon
			(pts
				(arc
					(start 428.669704 -378.290074)
					(mid 427.910244 -378.290074)
					(end 428.669704 -378.290074)
				)
			)
		)
	)
	(zone
		(layers "B.Cu" "In7.Cu" "In9.Cu" "In11.Cu" "In13.Cu" "In15.Cu")
		(hatch none 0.5)
		(connect_pads
			(clearance 0)
		)
		(min_thickness 0.25)
		(keepout
			(tracks not_allowed)
			(vias allowed)
			(pads allowed)
			(copperpour not_allowed)
			(footprints allowed)
		)
		(placement
			(enabled no)
			(sheetname "")
		)
		(fill yes
			(thermal_gap 0.5)
			(thermal_bridge_width 0.5)
			(island_removal_mode 0)
		)
		(polygon
			(pts
				(arc
					(start 183.676036 -273.099784)
					(mid 183.023256 -273.099784)
					(end 183.676036 -273.099784)
				)
			)
		)
	)
	(zone
		(layers "B.Cu" "In7.Cu" "In9.Cu" "In11.Cu" "In13.Cu" "In15.Cu")
		(hatch none 0.5)
		(connect_pads
			(clearance 0)
		)
		(min_thickness 0.25)
		(keepout
			(tracks not_allowed)
			(vias allowed)
			(pads allowed)
			(copperpour not_allowed)
			(footprints allowed)
		)
		(placement
			(enabled no)
			(sheetname "")
		)
		(fill yes
			(thermal_gap 0.5)
			(thermal_bridge_width 0.5)
			(island_removal_mode 0)
		)
		(polygon
			(pts
				(arc
					(start 401.626324 -315.849762)
					(mid 400.973544 -315.849762)
					(end 401.626324 -315.849762)
				)
			)
		)
	)
	(zone
		(layers "B.Cu" "In7.Cu" "In9.Cu" "In11.Cu" "In13.Cu" "In15.Cu")
		(hatch none 0.5)
		(connect_pads
			(clearance 0)
		)
		(min_thickness 0.25)
		(keepout
			(tracks not_allowed)
			(vias allowed)
			(pads allowed)
			(copperpour not_allowed)
			(footprints allowed)
		)
		(placement
			(enabled no)
			(sheetname "")
		)
		(fill yes
			(thermal_gap 0.5)
			(thermal_bridge_width 0.5)
			(island_removal_mode 0)
		)
		(polygon
			(pts
				(arc
					(start 233.819192 -216.304368)
					(mid 233.115612 -216.304368)
					(end 233.819192 -216.304368)
				)
			)
		)
	)
	(zone
		(layers "B.Cu" "In7.Cu" "In9.Cu" "In11.Cu" "In13.Cu" "In15.Cu")
		(hatch none 0.5)
		(connect_pads
			(clearance 0)
		)
		(min_thickness 0.25)
		(keepout
			(tracks not_allowed)
			(vias allowed)
			(pads allowed)
			(copperpour not_allowed)
			(footprints allowed)
		)
		(placement
			(enabled no)
			(sheetname "")
		)
		(fill yes
			(thermal_gap 0.5)
			(thermal_bridge_width 0.5)
			(island_removal_mode 0)
		)
		(polygon
			(pts
				(arc
					(start 297.754802 -145.287238)
					(mid 297.051222 -145.287238)
					(end 297.754802 -145.287238)
				)
			)
		)
	)
	(zone
		(layers "B.Cu" "In7.Cu" "In9.Cu" "In11.Cu" "In13.Cu" "In15.Cu")
		(hatch none 0.5)
		(connect_pads
			(clearance 0)
		)
		(min_thickness 0.25)
		(keepout
			(tracks not_allowed)
			(vias allowed)
			(pads allowed)
			(copperpour not_allowed)
			(footprints allowed)
		)
		(placement
			(enabled no)
			(sheetname "")
		)
		(fill yes
			(thermal_gap 0.5)
			(thermal_bridge_width 0.5)
			(island_removal_mode 0)
		)
		(polygon
			(pts
				(arc
					(start 196.026278 -282.599892)
					(mid 195.373498 -282.599892)
					(end 196.026278 -282.599892)
				)
			)
		)
	)
	(zone
		(layers "B.Cu" "In7.Cu" "In9.Cu" "In11.Cu" "In13.Cu" "In15.Cu")
		(hatch none 0.5)
		(connect_pads
			(clearance 0)
		)
		(min_thickness 0.25)
		(keepout
			(tracks not_allowed)
			(vias allowed)
			(pads allowed)
			(copperpour not_allowed)
			(footprints allowed)
		)
		(placement
			(enabled no)
			(sheetname "")
		)
		(fill yes
			(thermal_gap 0.5)
			(thermal_bridge_width 0.5)
			(island_removal_mode 0)
		)
		(polygon
			(pts
				(arc
					(start 189.37605 -274.049744)
					(mid 188.72327 -274.049744)
					(end 189.37605 -274.049744)
				)
			)
		)
	)
	(zone
		(layers "B.Cu" "In7.Cu" "In9.Cu" "In11.Cu" "In13.Cu" "In15.Cu")
		(hatch none 0.5)
		(connect_pads
			(clearance 0)
		)
		(min_thickness 0.25)
		(keepout
			(tracks not_allowed)
			(vias allowed)
			(pads allowed)
			(copperpour not_allowed)
			(footprints allowed)
		)
		(placement
			(enabled no)
			(sheetname "")
		)
		(fill yes
			(thermal_gap 0.5)
			(thermal_bridge_width 0.5)
			(island_removal_mode 0)
		)
		(polygon
			(pts
				(arc
					(start 85.489542 -370.489988)
					(mid 84.730082 -370.489988)
					(end 85.489542 -370.489988)
				)
			)
		)
	)
	(zone
		(layers "B.Cu" "In7.Cu" "In9.Cu" "In11.Cu" "In13.Cu" "In15.Cu")
		(hatch none 0.5)
		(connect_pads
			(clearance 0)
		)
		(min_thickness 0.25)
		(keepout
			(tracks not_allowed)
			(vias allowed)
			(pads allowed)
			(copperpour not_allowed)
			(footprints allowed)
		)
		(placement
			(enabled no)
			(sheetname "")
		)
		(fill yes
			(thermal_gap 0.5)
			(thermal_bridge_width 0.5)
			(island_removal_mode 0)
		)
		(polygon
			(pts
				(arc
					(start 426.326046 -274.999958)
					(mid 425.673266 -274.999958)
					(end 426.326046 -274.999958)
				)
			)
		)
	)
	(zone
		(layers "B.Cu" "In7.Cu" "In9.Cu" "In11.Cu" "In13.Cu" "In15.Cu")
		(hatch none 0.5)
		(connect_pads
			(clearance 0)
		)
		(min_thickness 0.25)
		(keepout
			(tracks not_allowed)
			(vias allowed)
			(pads allowed)
			(copperpour not_allowed)
			(footprints allowed)
		)
		(placement
			(enabled no)
			(sheetname "")
		)
		(fill yes
			(thermal_gap 0.5)
			(thermal_bridge_width 0.5)
			(island_removal_mode 0)
		)
		(polygon
			(pts
				(arc
					(start 429.17618 -284.499812)
					(mid 428.5234 -284.499812)
					(end 429.17618 -284.499812)
				)
			)
		)
	)
	(zone
		(layers "B.Cu" "In7.Cu" "In9.Cu" "In11.Cu" "In13.Cu" "In15.Cu")
		(hatch none 0.5)
		(connect_pads
			(clearance 0)
		)
		(min_thickness 0.25)
		(keepout
			(tracks not_allowed)
			(vias allowed)
			(pads allowed)
			(copperpour not_allowed)
			(footprints allowed)
		)
		(placement
			(enabled no)
			(sheetname "")
		)
		(fill yes
			(thermal_gap 0.5)
			(thermal_bridge_width 0.5)
			(island_removal_mode 0)
		)
		(polygon
			(pts
				(arc
					(start 296.669714 -409.490164)
					(mid 295.910254 -409.490164)
					(end 296.669714 -409.490164)
				)
			)
		)
	)
	(zone
		(layers "B.Cu" "In7.Cu" "In9.Cu" "In11.Cu" "In13.Cu" "In15.Cu")
		(hatch none 0.5)
		(connect_pads
			(clearance 0)
		)
		(min_thickness 0.25)
		(keepout
			(tracks not_allowed)
			(vias allowed)
			(pads allowed)
			(copperpour not_allowed)
			(footprints allowed)
		)
		(placement
			(enabled no)
			(sheetname "")
		)
		(fill yes
			(thermal_gap 0.5)
			(thermal_bridge_width 0.5)
			(island_removal_mode 0)
		)
		(polygon
			(pts
				(arc
					(start 298.869608 -409.290012)
					(mid 298.110148 -409.290012)
					(end 298.869608 -409.290012)
				)
			)
		)
	)
	(zone
		(layers "B.Cu" "In7.Cu" "In9.Cu" "In11.Cu" "In13.Cu" "In15.Cu")
		(hatch none 0.5)
		(connect_pads
			(clearance 0)
		)
		(min_thickness 0.25)
		(keepout
			(tracks not_allowed)
			(vias allowed)
			(pads allowed)
			(copperpour not_allowed)
			(footprints allowed)
		)
		(placement
			(enabled no)
			(sheetname "")
		)
		(fill yes
			(thermal_gap 0.5)
			(thermal_bridge_width 0.5)
			(island_removal_mode 0)
		)
		(polygon
			(pts
				(arc
					(start 45.72635 -315.849762)
					(mid 45.07357 -315.849762)
					(end 45.72635 -315.849762)
				)
			)
		)
	)
	(zone
		(layers "B.Cu" "In7.Cu" "In9.Cu" "In11.Cu" "In13.Cu" "In15.Cu")
		(hatch none 0.5)
		(connect_pads
			(clearance 0)
		)
		(min_thickness 0.25)
		(keepout
			(tracks not_allowed)
			(vias allowed)
			(pads allowed)
			(copperpour not_allowed)
			(footprints allowed)
		)
		(placement
			(enabled no)
			(sheetname "")
		)
		(fill yes
			(thermal_gap 0.5)
			(thermal_bridge_width 0.5)
			(island_removal_mode 0)
		)
		(polygon
			(pts
				(arc
					(start 72.28967 -370.489988)
					(mid 71.53021 -370.489988)
					(end 72.28967 -370.489988)
				)
			)
		)
	)
	(zone
		(layers "B.Cu" "In7.Cu" "In9.Cu" "In11.Cu" "In13.Cu" "In15.Cu")
		(hatch none 0.5)
		(connect_pads
			(clearance 0)
		)
		(min_thickness 0.25)
		(keepout
			(tracks not_allowed)
			(vias allowed)
			(pads allowed)
			(copperpour not_allowed)
			(footprints allowed)
		)
		(placement
			(enabled no)
			(sheetname "")
		)
		(fill yes
			(thermal_gap 0.5)
			(thermal_bridge_width 0.5)
			(island_removal_mode 0)
		)
		(polygon
			(pts
				(arc
					(start 47.62627 -315.849762)
					(mid 46.97349 -315.849762)
					(end 47.62627 -315.849762)
				)
			)
		)
	)
	(zone
		(layers "B.Cu" "In7.Cu" "In9.Cu" "In11.Cu" "In13.Cu" "In15.Cu")
		(hatch none 0.5)
		(connect_pads
			(clearance 0)
		)
		(min_thickness 0.25)
		(keepout
			(tracks not_allowed)
			(vias allowed)
			(pads allowed)
			(copperpour not_allowed)
			(footprints allowed)
		)
		(placement
			(enabled no)
			(sheetname "")
		)
		(fill yes
			(thermal_gap 0.5)
			(thermal_bridge_width 0.5)
			(island_removal_mode 0)
		)
		(polygon
			(pts
				(arc
					(start 65.55486 -124.103638)
					(mid 64.85128 -124.103638)
					(end 65.55486 -124.103638)
				)
			)
		)
	)
	(zone
		(layers "B.Cu" "In7.Cu" "In9.Cu" "In11.Cu" "In13.Cu" "In15.Cu")
		(hatch none 0.5)
		(connect_pads
			(clearance 0)
		)
		(min_thickness 0.25)
		(keepout
			(tracks not_allowed)
			(vias allowed)
			(pads allowed)
			(copperpour not_allowed)
			(footprints allowed)
		)
		(placement
			(enabled no)
			(sheetname "")
		)
		(fill yes
			(thermal_gap 0.5)
			(thermal_bridge_width 0.5)
			(island_removal_mode 0)
		)
		(polygon
			(pts
				(arc
					(start 74.489564 -401.49018)
					(mid 73.730104 -401.49018)
					(end 74.489564 -401.49018)
				)
			)
		)
	)
	(zone
		(layers "B.Cu" "In7.Cu" "In9.Cu" "In11.Cu" "In13.Cu" "In15.Cu")
		(hatch none 0.5)
		(connect_pads
			(clearance 0)
		)
		(min_thickness 0.25)
		(keepout
			(tracks not_allowed)
			(vias allowed)
			(pads allowed)
			(copperpour not_allowed)
			(footprints allowed)
		)
		(placement
			(enabled no)
			(sheetname "")
		)
		(fill yes
			(thermal_gap 0.5)
			(thermal_bridge_width 0.5)
			(island_removal_mode 0)
		)
		(polygon
			(pts
				(arc
					(start 299.776134 -318.699896)
					(mid 299.123354 -318.699896)
					(end 299.776134 -318.699896)
				)
			)
		)
	)
	(zone
		(layers "B.Cu" "In7.Cu" "In9.Cu" "In11.Cu" "In13.Cu" "In15.Cu")
		(hatch none 0.5)
		(connect_pads
			(clearance 0)
		)
		(min_thickness 0.25)
		(keepout
			(tracks not_allowed)
			(vias allowed)
			(pads allowed)
			(copperpour not_allowed)
			(footprints allowed)
		)
		(placement
			(enabled no)
			(sheetname "")
		)
		(fill yes
			(thermal_gap 0.5)
			(thermal_bridge_width 0.5)
			(island_removal_mode 0)
		)
		(polygon
			(pts
				(arc
					(start 299.609002 -143.48714)
					(mid 298.905422 -143.48714)
					(end 299.609002 -143.48714)
				)
			)
		)
	)
	(zone
		(layers "B.Cu" "In7.Cu" "In9.Cu" "In11.Cu" "In13.Cu" "In15.Cu")
		(hatch none 0.5)
		(connect_pads
			(clearance 0)
		)
		(min_thickness 0.25)
		(keepout
			(tracks not_allowed)
			(vias allowed)
			(pads allowed)
			(copperpour not_allowed)
			(footprints allowed)
		)
		(placement
			(enabled no)
			(sheetname "")
		)
		(fill yes
			(thermal_gap 0.5)
			(thermal_bridge_width 0.5)
			(island_removal_mode 0)
		)
		(polygon
			(pts
				(arc
					(start 415.7091 -118.703598)
					(mid 415.00552 -118.703598)
					(end 415.7091 -118.703598)
				)
			)
		)
	)
	(zone
		(layers "B.Cu" "In7.Cu" "In9.Cu" "In11.Cu" "In13.Cu" "In15.Cu")
		(hatch none 0.5)
		(connect_pads
			(clearance 0)
		)
		(min_thickness 0.25)
		(keepout
			(tracks not_allowed)
			(vias allowed)
			(pads allowed)
			(copperpour not_allowed)
			(footprints allowed)
		)
		(placement
			(enabled no)
			(sheetname "")
		)
		(fill yes
			(thermal_gap 0.5)
			(thermal_bridge_width 0.5)
			(island_removal_mode 0)
		)
		(polygon
			(pts
				(arc
					(start 427.27626 -318.699896)
					(mid 426.62348 -318.699896)
					(end 427.27626 -318.699896)
				)
			)
		)
	)
	(zone
		(layers "B.Cu" "In7.Cu" "In9.Cu" "In11.Cu" "In13.Cu" "In15.Cu")
		(hatch none 0.5)
		(connect_pads
			(clearance 0)
		)
		(min_thickness 0.25)
		(keepout
			(tracks not_allowed)
			(vias allowed)
			(pads allowed)
			(copperpour not_allowed)
			(footprints allowed)
		)
		(placement
			(enabled no)
			(sheetname "")
		)
		(fill yes
			(thermal_gap 0.5)
			(thermal_bridge_width 0.5)
			(island_removal_mode 0)
		)
		(polygon
			(pts
				(arc
					(start 286.648652 -107.376214)
					(mid 285.945072 -107.376214)
					(end 286.648652 -107.376214)
				)
			)
		)
	)
	(zone
		(layers "B.Cu" "In7.Cu" "In9.Cu" "In11.Cu" "In13.Cu" "In15.Cu")
		(hatch none 0.5)
		(connect_pads
			(clearance 0)
		)
		(min_thickness 0.25)
		(keepout
			(tracks not_allowed)
			(vias allowed)
			(pads allowed)
			(copperpour not_allowed)
			(footprints allowed)
		)
		(placement
			(enabled no)
			(sheetname "")
		)
		(fill yes
			(thermal_gap 0.5)
			(thermal_bridge_width 0.5)
			(island_removal_mode 0)
		)
		(polygon
			(pts
				(arc
					(start 160.289748 -379.590046)
					(mid 159.530288 -379.590046)
					(end 160.289748 -379.590046)
				)
			)
		)
	)
	(zone
		(layers "B.Cu" "In7.Cu" "In9.Cu" "In11.Cu" "In13.Cu" "In15.Cu")
		(hatch none 0.5)
		(connect_pads
			(clearance 0)
		)
		(min_thickness 0.25)
		(keepout
			(tracks not_allowed)
			(vias allowed)
			(pads allowed)
			(copperpour not_allowed)
			(footprints allowed)
		)
		(placement
			(enabled no)
			(sheetname "")
		)
		(fill yes
			(thermal_gap 0.5)
			(thermal_bridge_width 0.5)
			(island_removal_mode 0)
		)
		(polygon
			(pts
				(arc
					(start 52.59451 -108.312712)
					(mid 51.89093 -108.312712)
					(end 52.59451 -108.312712)
				)
			)
		)
	)
	(zone
		(layers "B.Cu" "In7.Cu" "In9.Cu" "In11.Cu" "In13.Cu" "In15.Cu")
		(hatch none 0.5)
		(connect_pads
			(clearance 0)
		)
		(min_thickness 0.25)
		(keepout
			(tracks not_allowed)
			(vias allowed)
			(pads allowed)
			(copperpour not_allowed)
			(footprints allowed)
		)
		(placement
			(enabled no)
			(sheetname "")
		)
		(fill yes
			(thermal_gap 0.5)
			(thermal_bridge_width 0.5)
			(island_removal_mode 0)
		)
		(polygon
			(pts
				(arc
					(start 297.754802 -156.087318)
					(mid 297.051222 -156.087318)
					(end 297.754802 -156.087318)
				)
			)
		)
	)
	(zone
		(layers "B.Cu" "In7.Cu" "In9.Cu" "In11.Cu" "In13.Cu" "In15.Cu")
		(hatch none 0.5)
		(connect_pads
			(clearance 0)
		)
		(min_thickness 0.25)
		(keepout
			(tracks not_allowed)
			(vias allowed)
			(pads allowed)
			(copperpour not_allowed)
			(footprints allowed)
		)
		(placement
			(enabled no)
			(sheetname "")
		)
		(fill yes
			(thermal_gap 0.5)
			(thermal_bridge_width 0.5)
			(island_removal_mode 0)
		)
		(polygon
			(pts
				(arc
					(start 172.276262 -318.699896)
					(mid 171.623482 -318.699896)
					(end 172.276262 -318.699896)
				)
			)
		)
	)
	(zone
		(layers "B.Cu" "In7.Cu" "In9.Cu" "In11.Cu" "In13.Cu" "In15.Cu")
		(hatch none 0.5)
		(connect_pads
			(clearance 0)
		)
		(min_thickness 0.25)
		(keepout
			(tracks not_allowed)
			(vias allowed)
			(pads allowed)
			(copperpour not_allowed)
			(footprints allowed)
		)
		(placement
			(enabled no)
			(sheetname "")
		)
		(fill yes
			(thermal_gap 0.5)
			(thermal_bridge_width 0.5)
			(island_removal_mode 0)
		)
		(polygon
			(pts
				(arc
					(start 54.44871 -99.31273)
					(mid 53.74513 -99.31273)
					(end 54.44871 -99.31273)
				)
			)
		)
	)
	(zone
		(layers "B.Cu" "In7.Cu" "In9.Cu" "In11.Cu" "In13.Cu" "In15.Cu")
		(hatch none 0.5)
		(connect_pads
			(clearance 0)
		)
		(min_thickness 0.25)
		(keepout
			(tracks not_allowed)
			(vias allowed)
			(pads allowed)
			(copperpour not_allowed)
			(footprints allowed)
		)
		(placement
			(enabled no)
			(sheetname "")
		)
		(fill yes
			(thermal_gap 0.5)
			(thermal_bridge_width 0.5)
			(island_removal_mode 0)
		)
		(polygon
			(pts
				(arc
					(start 284.794452 -132.232908)
					(mid 284.090872 -132.232908)
					(end 284.794452 -132.232908)
				)
			)
		)
	)
	(zone
		(layers "B.Cu" "In7.Cu" "In9.Cu" "In11.Cu" "In13.Cu" "In15.Cu")
		(hatch none 0.5)
		(connect_pads
			(clearance 0)
		)
		(min_thickness 0.25)
		(keepout
			(tracks not_allowed)
			(vias allowed)
			(pads allowed)
			(copperpour not_allowed)
			(footprints allowed)
		)
		(placement
			(enabled no)
			(sheetname "")
		)
		(fill yes
			(thermal_gap 0.5)
			(thermal_bridge_width 0.5)
			(island_removal_mode 0)
		)
		(polygon
			(pts
				(arc
					(start 67.40906 -149.823678)
					(mid 66.70548 -149.823678)
					(end 67.40906 -149.823678)
				)
			)
		)
	)
	(zone
		(layers "B.Cu" "In7.Cu" "In9.Cu" "In11.Cu" "In13.Cu" "In15.Cu")
		(hatch none 0.5)
		(connect_pads
			(clearance 0)
		)
		(min_thickness 0.25)
		(keepout
			(tracks not_allowed)
			(vias allowed)
			(pads allowed)
			(copperpour not_allowed)
			(footprints allowed)
		)
		(placement
			(enabled no)
			(sheetname "")
		)
		(fill yes
			(thermal_gap 0.5)
			(thermal_bridge_width 0.5)
			(island_removal_mode 0)
		)
		(polygon
			(pts
				(arc
					(start 402.74875 -100.17633)
					(mid 402.04517 -100.17633)
					(end 402.74875 -100.17633)
				)
			)
		)
	)
	(zone
		(layers "B.Cu" "In7.Cu" "In9.Cu" "In11.Cu" "In13.Cu" "In15.Cu")
		(hatch none 0.5)
		(connect_pads
			(clearance 0)
		)
		(min_thickness 0.25)
		(keepout
			(tracks not_allowed)
			(vias allowed)
			(pads allowed)
			(copperpour not_allowed)
			(footprints allowed)
		)
		(placement
			(enabled no)
			(sheetname "")
		)
		(fill yes
			(thermal_gap 0.5)
			(thermal_bridge_width 0.5)
			(island_removal_mode 0)
		)
		(polygon
			(pts
				(arc
					(start 198.876412 -285.449772)
					(mid 198.223632 -285.449772)
					(end 198.876412 -285.449772)
				)
			)
		)
	)
	(zone
		(layers "B.Cu" "In7.Cu" "In9.Cu" "In11.Cu" "In13.Cu" "In15.Cu")
		(hatch none 0.5)
		(connect_pads
			(clearance 0)
		)
		(min_thickness 0.25)
		(keepout
			(tracks not_allowed)
			(vias allowed)
			(pads allowed)
			(copperpour not_allowed)
			(footprints allowed)
		)
		(placement
			(enabled no)
			(sheetname "")
		)
		(fill yes
			(thermal_gap 0.5)
			(thermal_bridge_width 0.5)
			(island_removal_mode 0)
		)
		(polygon
			(pts
				(arc
					(start 64.726058 -275.949664)
					(mid 64.073278 -275.949664)
					(end 64.726058 -275.949664)
				)
			)
		)
	)
	(zone
		(layers "B.Cu" "In7.Cu" "In9.Cu" "In11.Cu" "In13.Cu" "In15.Cu")
		(hatch none 0.5)
		(connect_pads
			(clearance 0)
		)
		(min_thickness 0.25)
		(keepout
			(tracks not_allowed)
			(vias allowed)
			(pads allowed)
			(copperpour not_allowed)
			(footprints allowed)
		)
		(placement
			(enabled no)
			(sheetname "")
		)
		(fill yes
			(thermal_gap 0.5)
			(thermal_bridge_width 0.5)
			(island_removal_mode 0)
		)
		(polygon
			(pts
				(arc
					(start 402.74875 -130.43281)
					(mid 402.04517 -130.43281)
					(end 402.74875 -130.43281)
				)
			)
		)
	)
	(zone
		(layers "B.Cu" "In7.Cu" "In9.Cu" "In11.Cu" "In13.Cu" "In15.Cu")
		(hatch none 0.5)
		(connect_pads
			(clearance 0)
		)
		(min_thickness 0.25)
		(keepout
			(tracks not_allowed)
			(vias allowed)
			(pads allowed)
			(copperpour not_allowed)
			(footprints allowed)
		)
		(placement
			(enabled no)
			(sheetname "")
		)
		(fill yes
			(thermal_gap 0.5)
			(thermal_bridge_width 0.5)
			(island_removal_mode 0)
		)
		(polygon
			(pts
				(arc
					(start 186.525916 -274.999958)
					(mid 185.873136 -274.999958)
					(end 186.525916 -274.999958)
				)
			)
		)
	)
	(zone
		(layers "B.Cu" "In7.Cu" "In9.Cu" "In11.Cu" "In13.Cu" "In15.Cu")
		(hatch none 0.5)
		(connect_pads
			(clearance 0)
		)
		(min_thickness 0.25)
		(keepout
			(tracks not_allowed)
			(vias allowed)
			(pads allowed)
			(copperpour not_allowed)
			(footprints allowed)
		)
		(placement
			(enabled no)
			(sheetname "")
		)
		(fill yes
			(thermal_gap 0.5)
			(thermal_bridge_width 0.5)
			(island_removal_mode 0)
		)
		(polygon
			(pts
				(arc
					(start 183.508904 -153.42362)
					(mid 182.805324 -153.42362)
					(end 183.508904 -153.42362)
				)
			)
		)
	)
	(zone
		(layers "B.Cu" "In7.Cu" "In9.Cu" "In11.Cu" "In13.Cu" "In15.Cu")
		(hatch none 0.5)
		(connect_pads
			(clearance 0)
		)
		(min_thickness 0.25)
		(keepout
			(tracks not_allowed)
			(vias allowed)
			(pads allowed)
			(copperpour not_allowed)
			(footprints allowed)
		)
		(placement
			(enabled no)
			(sheetname "")
		)
		(fill yes
			(thermal_gap 0.5)
			(thermal_bridge_width 0.5)
			(island_removal_mode 0)
		)
		(polygon
			(pts
				(arc
					(start 43.689778 -383.290064)
					(mid 42.930318 -383.290064)
					(end 43.689778 -383.290064)
				)
			)
		)
	)
	(zone
		(layers "B.Cu" "In7.Cu" "In9.Cu" "In11.Cu" "In13.Cu" "In15.Cu")
		(hatch none 0.5)
		(connect_pads
			(clearance 0)
		)
		(min_thickness 0.25)
		(keepout
			(tracks not_allowed)
			(vias allowed)
			(pads allowed)
			(copperpour not_allowed)
			(footprints allowed)
		)
		(placement
			(enabled no)
			(sheetname "")
		)
		(fill yes
			(thermal_gap 0.5)
			(thermal_bridge_width 0.5)
			(island_removal_mode 0)
		)
		(polygon
			(pts
				(arc
					(start 384.669792 -374.390158)
					(mid 383.910332 -374.390158)
					(end 384.669792 -374.390158)
				)
			)
		)
	)
	(zone
		(layers "B.Cu" "In7.Cu" "In9.Cu" "In11.Cu" "In13.Cu" "In15.Cu")
		(hatch none 0.5)
		(connect_pads
			(clearance 0)
		)
		(min_thickness 0.25)
		(keepout
			(tracks not_allowed)
			(vias allowed)
			(pads allowed)
			(copperpour not_allowed)
			(footprints allowed)
		)
		(placement
			(enabled no)
			(sheetname "")
		)
		(fill yes
			(thermal_gap 0.5)
			(thermal_bridge_width 0.5)
			(island_removal_mode 0)
		)
		(polygon
			(pts
				(arc
					(start 62.825884 -275.949918)
					(mid 62.173104 -275.949918)
					(end 62.825884 -275.949918)
				)
			)
		)
	)
	(zone
		(layers "B.Cu" "In7.Cu" "In9.Cu" "In11.Cu" "In13.Cu" "In15.Cu")
		(hatch none 0.5)
		(connect_pads
			(clearance 0)
		)
		(min_thickness 0.25)
		(keepout
			(tracks not_allowed)
			(vias allowed)
			(pads allowed)
			(copperpour not_allowed)
			(footprints allowed)
		)
		(placement
			(enabled no)
			(sheetname "")
		)
		(fill yes
			(thermal_gap 0.5)
			(thermal_bridge_width 0.5)
			(island_removal_mode 0)
		)
		(polygon
			(pts
				(arc
					(start 311.175908 -274.049744)
					(mid 310.523128 -274.049744)
					(end 311.175908 -274.049744)
				)
			)
		)
	)
	(zone
		(layers "B.Cu" "In7.Cu" "In9.Cu" "In11.Cu" "In13.Cu" "In15.Cu")
		(hatch none 0.5)
		(connect_pads
			(clearance 0)
		)
		(min_thickness 0.25)
		(keepout
			(tracks not_allowed)
			(vias allowed)
			(pads allowed)
			(copperpour not_allowed)
			(footprints allowed)
		)
		(placement
			(enabled no)
			(sheetname "")
		)
		(fill yes
			(thermal_gap 0.5)
			(thermal_bridge_width 0.5)
			(island_removal_mode 0)
		)
		(polygon
			(pts
				(arc
					(start 72.326246 -315.849762)
					(mid 71.673466 -315.849762)
					(end 72.326246 -315.849762)
				)
			)
		)
	)
	(zone
		(layers "B.Cu" "In7.Cu" "In9.Cu" "In11.Cu" "In13.Cu" "In15.Cu")
		(hatch none 0.5)
		(connect_pads
			(clearance 0)
		)
		(min_thickness 0.25)
		(keepout
			(tracks not_allowed)
			(vias allowed)
			(pads allowed)
			(copperpour not_allowed)
			(footprints allowed)
		)
		(placement
			(enabled no)
			(sheetname "")
		)
		(fill yes
			(thermal_gap 0.5)
			(thermal_bridge_width 0.5)
			(island_removal_mode 0)
		)
		(polygon
			(pts
				(arc
					(start 345.069668 -401.690078)
					(mid 344.310208 -401.690078)
					(end 345.069668 -401.690078)
				)
			)
		)
	)
	(zone
		(layers "B.Cu" "In7.Cu" "In9.Cu" "In11.Cu" "In13.Cu" "In15.Cu")
		(hatch none 0.5)
		(connect_pads
			(clearance 0)
		)
		(min_thickness 0.25)
		(keepout
			(tracks not_allowed)
			(vias allowed)
			(pads allowed)
			(copperpour not_allowed)
			(footprints allowed)
		)
		(placement
			(enabled no)
			(sheetname "")
		)
		(fill yes
			(thermal_gap 0.5)
			(thermal_bridge_width 0.5)
			(island_removal_mode 0)
		)
		(polygon
			(pts
				(arc
					(start 340.66988 -400.390106)
					(mid 339.91042 -400.390106)
					(end 340.66988 -400.390106)
				)
			)
		)
	)
	(zone
		(layers "B.Cu" "In7.Cu" "In9.Cu" "In11.Cu" "In13.Cu" "In15.Cu")
		(hatch none 0.5)
		(connect_pads
			(clearance 0)
		)
		(min_thickness 0.25)
		(keepout
			(tracks not_allowed)
			(vias allowed)
			(pads allowed)
			(copperpour not_allowed)
			(footprints allowed)
		)
		(placement
			(enabled no)
			(sheetname "")
		)
		(fill yes
			(thermal_gap 0.5)
			(thermal_bridge_width 0.5)
			(island_removal_mode 0)
		)
		(polygon
			(pts
				(arc
					(start 400.89455 -133.096508)
					(mid 400.19097 -133.096508)
					(end 400.89455 -133.096508)
				)
			)
		)
	)
	(zone
		(layers "B.Cu" "In7.Cu" "In9.Cu" "In11.Cu" "In13.Cu" "In15.Cu")
		(hatch none 0.5)
		(connect_pads
			(clearance 0)
		)
		(min_thickness 0.25)
		(keepout
			(tracks not_allowed)
			(vias allowed)
			(pads allowed)
			(copperpour not_allowed)
			(footprints allowed)
		)
		(placement
			(enabled no)
			(sheetname "")
		)
		(fill yes
			(thermal_gap 0.5)
			(thermal_bridge_width 0.5)
			(island_removal_mode 0)
		)
		(polygon
			(pts
				(arc
					(start 424.269662 -404.290022)
					(mid 423.510202 -404.290022)
					(end 424.269662 -404.290022)
				)
			)
		)
	)
	(zone
		(layers "B.Cu" "In7.Cu" "In9.Cu" "In11.Cu" "In13.Cu" "In15.Cu")
		(hatch none 0.5)
		(connect_pads
			(clearance 0)
		)
		(min_thickness 0.25)
		(keepout
			(tracks not_allowed)
			(vias allowed)
			(pads allowed)
			(copperpour not_allowed)
			(footprints allowed)
		)
		(placement
			(enabled no)
			(sheetname "")
		)
		(fill yes
			(thermal_gap 0.5)
			(thermal_bridge_width 0.5)
			(island_removal_mode 0)
		)
		(polygon
			(pts
				(arc
					(start 52.59451 -101.112828)
					(mid 51.89093 -101.112828)
					(end 52.59451 -101.112828)
				)
			)
		)
	)
	(zone
		(layers "B.Cu" "In7.Cu" "In9.Cu" "In11.Cu" "In13.Cu" "In15.Cu")
		(hatch none 0.5)
		(connect_pads
			(clearance 0)
		)
		(min_thickness 0.25)
		(keepout
			(tracks not_allowed)
			(vias allowed)
			(pads allowed)
			(copperpour not_allowed)
			(footprints allowed)
		)
		(placement
			(enabled no)
			(sheetname "")
		)
		(fill yes
			(thermal_gap 0.5)
			(thermal_bridge_width 0.5)
			(island_removal_mode 0)
		)
		(polygon
			(pts
				(arc
					(start 297.754802 -121.367296)
					(mid 297.051222 -121.367296)
					(end 297.754802 -121.367296)
				)
			)
		)
	)
	(zone
		(layers "B.Cu" "In7.Cu" "In9.Cu" "In11.Cu" "In13.Cu" "In15.Cu")
		(hatch none 0.5)
		(connect_pads
			(clearance 0)
		)
		(min_thickness 0.25)
		(keepout
			(tracks not_allowed)
			(vias allowed)
			(pads allowed)
			(copperpour not_allowed)
			(footprints allowed)
		)
		(placement
			(enabled no)
			(sheetname "")
		)
		(fill yes
			(thermal_gap 0.5)
			(thermal_bridge_width 0.5)
			(island_removal_mode 0)
		)
		(polygon
			(pts
				(arc
					(start 177.976022 -274.049744)
					(mid 177.323242 -274.049744)
					(end 177.976022 -274.049744)
				)
			)
		)
	)
	(zone
		(layers "B.Cu" "In7.Cu" "In9.Cu" "In11.Cu" "In13.Cu" "In15.Cu")
		(hatch none 0.5)
		(connect_pads
			(clearance 0)
		)
		(min_thickness 0.25)
		(keepout
			(tracks not_allowed)
			(vias allowed)
			(pads allowed)
			(copperpour not_allowed)
			(footprints allowed)
		)
		(placement
			(enabled no)
			(sheetname "")
		)
		(fill yes
			(thermal_gap 0.5)
			(thermal_bridge_width 0.5)
			(island_removal_mode 0)
		)
		(polygon
			(pts
				(arc
					(start 338.469732 -401.49018)
					(mid 337.710272 -401.49018)
					(end 338.469732 -401.49018)
				)
			)
		)
	)
	(zone
		(layers "B.Cu" "In7.Cu" "In9.Cu" "In11.Cu" "In13.Cu" "In15.Cu")
		(hatch none 0.5)
		(connect_pads
			(clearance 0)
		)
		(min_thickness 0.25)
		(keepout
			(tracks not_allowed)
			(vias allowed)
			(pads allowed)
			(copperpour not_allowed)
			(footprints allowed)
		)
		(placement
			(enabled no)
			(sheetname "")
		)
		(fill yes
			(thermal_gap 0.5)
			(thermal_bridge_width 0.5)
			(island_removal_mode 0)
		)
		(polygon
			(pts
				(arc
					(start 181.654704 -124.967238)
					(mid 180.951124 -124.967238)
					(end 181.654704 -124.967238)
				)
			)
		)
	)
	(zone
		(layers "B.Cu" "In7.Cu" "In9.Cu" "In11.Cu" "In13.Cu" "In15.Cu")
		(hatch none 0.5)
		(connect_pads
			(clearance 0)
		)
		(min_thickness 0.25)
		(keepout
			(tracks not_allowed)
			(vias allowed)
			(pads allowed)
			(copperpour not_allowed)
			(footprints allowed)
		)
		(placement
			(enabled no)
			(sheetname "")
		)
		(fill yes
			(thermal_gap 0.5)
			(thermal_bridge_width 0.5)
			(island_removal_mode 0)
		)
		(polygon
			(pts
				(arc
					(start 187.47613 -273.099784)
					(mid 186.82335 -273.099784)
					(end 187.47613 -273.099784)
				)
			)
		)
	)
	(zone
		(layers "B.Cu" "In7.Cu" "In9.Cu" "In11.Cu" "In13.Cu" "In15.Cu")
		(hatch none 0.5)
		(connect_pads
			(clearance 0)
		)
		(min_thickness 0.25)
		(keepout
			(tracks not_allowed)
			(vias allowed)
			(pads allowed)
			(copperpour not_allowed)
			(footprints allowed)
		)
		(placement
			(enabled no)
			(sheetname "")
		)
		(fill yes
			(thermal_gap 0.5)
			(thermal_bridge_width 0.5)
			(island_removal_mode 0)
		)
		(polygon
			(pts
				(arc
					(start 54.44871 -119.222774)
					(mid 53.74513 -119.222774)
					(end 54.44871 -119.222774)
				)
			)
		)
	)
	(zone
		(layers "B.Cu" "In7.Cu" "In9.Cu" "In11.Cu" "In13.Cu" "In15.Cu")
		(hatch none 0.5)
		(connect_pads
			(clearance 0)
		)
		(min_thickness 0.25)
		(keepout
			(tracks not_allowed)
			(vias allowed)
			(pads allowed)
			(copperpour not_allowed)
			(footprints allowed)
		)
		(placement
			(enabled no)
			(sheetname "")
		)
		(fill yes
			(thermal_gap 0.5)
			(thermal_bridge_width 0.5)
			(island_removal_mode 0)
		)
		(polygon
			(pts
				(arc
					(start 378.069602 -398.890236)
					(mid 377.310142 -398.890236)
					(end 378.069602 -398.890236)
				)
			)
		)
	)
	(zone
		(layers "B.Cu" "In7.Cu" "In9.Cu" "In11.Cu" "In13.Cu" "In15.Cu")
		(hatch none 0.5)
		(connect_pads
			(clearance 0)
		)
		(min_thickness 0.25)
		(keepout
			(tracks not_allowed)
			(vias allowed)
			(pads allowed)
			(copperpour not_allowed)
			(footprints allowed)
		)
		(placement
			(enabled no)
			(sheetname "")
		)
		(fill yes
			(thermal_gap 0.5)
			(thermal_bridge_width 0.5)
			(island_removal_mode 0)
		)
		(polygon
			(pts
				(arc
					(start 272.226278 -316.799722)
					(mid 271.573498 -316.799722)
					(end 272.226278 -316.799722)
				)
			)
		)
	)
	(zone
		(layers "B.Cu" "In7.Cu" "In9.Cu" "In11.Cu" "In13.Cu" "In15.Cu")
		(hatch none 0.5)
		(connect_pads
			(clearance 0)
		)
		(min_thickness 0.25)
		(keepout
			(tracks not_allowed)
			(vias allowed)
			(pads allowed)
			(copperpour not_allowed)
			(footprints allowed)
		)
		(placement
			(enabled no)
			(sheetname "")
		)
		(fill yes
			(thermal_gap 0.5)
			(thermal_bridge_width 0.5)
			(island_removal_mode 0)
		)
		(polygon
			(pts
				(arc
					(start 32.6898 -382.18999)
					(mid 31.93034 -382.18999)
					(end 32.6898 -382.18999)
				)
			)
		)
	)
	(zone
		(layers "B.Cu" "In7.Cu" "In9.Cu" "In11.Cu" "In13.Cu" "In15.Cu")
		(hatch none 0.5)
		(connect_pads
			(clearance 0)
		)
		(min_thickness 0.25)
		(keepout
			(tracks not_allowed)
			(vias allowed)
			(pads allowed)
			(copperpour not_allowed)
			(footprints allowed)
		)
		(placement
			(enabled no)
			(sheetname "")
		)
		(fill yes
			(thermal_gap 0.5)
			(thermal_bridge_width 0.5)
			(island_removal_mode 0)
		)
		(polygon
			(pts
				(arc
					(start 52.59451 -124.622814)
					(mid 51.89093 -124.622814)
					(end 52.59451 -124.622814)
				)
			)
		)
	)
	(zone
		(layers "B.Cu" "In7.Cu" "In9.Cu" "In11.Cu" "In13.Cu" "In15.Cu")
		(hatch none 0.5)
		(connect_pads
			(clearance 0)
		)
		(min_thickness 0.25)
		(keepout
			(tracks not_allowed)
			(vias allowed)
			(pads allowed)
			(copperpour not_allowed)
			(footprints allowed)
		)
		(placement
			(enabled no)
			(sheetname "")
		)
		(fill yes
			(thermal_gap 0.5)
			(thermal_bridge_width 0.5)
			(island_removal_mode 0)
		)
		(polygon
			(pts
				(arc
					(start 430.126394 -310.149748)
					(mid 429.473614 -310.149748)
					(end 430.126394 -310.149748)
				)
			)
		)
	)
	(zone
		(layers "B.Cu" "In7.Cu" "In9.Cu" "In11.Cu" "In13.Cu" "In15.Cu")
		(hatch none 0.5)
		(connect_pads
			(clearance 0)
		)
		(min_thickness 0.25)
		(keepout
			(tracks not_allowed)
			(vias allowed)
			(pads allowed)
			(copperpour not_allowed)
			(footprints allowed)
		)
		(placement
			(enabled no)
			(sheetname "")
		)
		(fill yes
			(thermal_gap 0.5)
			(thermal_bridge_width 0.5)
			(island_removal_mode 0)
		)
		(polygon
			(pts
				(arc
					(start 181.654704 -121.367296)
					(mid 180.951124 -121.367296)
					(end 181.654704 -121.367296)
				)
			)
		)
	)
	(zone
		(layers "B.Cu" "In7.Cu" "In9.Cu" "In11.Cu" "In13.Cu" "In15.Cu")
		(hatch none 0.5)
		(connect_pads
			(clearance 0)
		)
		(min_thickness 0.25)
		(keepout
			(tracks not_allowed)
			(vias allowed)
			(pads allowed)
			(copperpour not_allowed)
			(footprints allowed)
		)
		(placement
			(enabled no)
			(sheetname "")
		)
		(fill yes
			(thermal_gap 0.5)
			(thermal_bridge_width 0.5)
			(island_removal_mode 0)
		)
		(polygon
			(pts
				(arc
					(start 308.326028 -275.949664)
					(mid 307.673248 -275.949664)
					(end 308.326028 -275.949664)
				)
			)
		)
	)
	(zone
		(layers "B.Cu" "In7.Cu" "In9.Cu" "In11.Cu" "In13.Cu" "In15.Cu")
		(hatch none 0.5)
		(connect_pads
			(clearance 0)
		)
		(min_thickness 0.25)
		(keepout
			(tracks not_allowed)
			(vias allowed)
			(pads allowed)
			(copperpour not_allowed)
			(footprints allowed)
		)
		(placement
			(enabled no)
			(sheetname "")
		)
		(fill yes
			(thermal_gap 0.5)
			(thermal_bridge_width 0.5)
			(island_removal_mode 0)
		)
		(polygon
			(pts
				(arc
					(start 34.889694 -410.589984)
					(mid 34.130234 -410.589984)
					(end 34.889694 -410.589984)
				)
			)
		)
	)
	(zone
		(layers "B.Cu" "In7.Cu" "In9.Cu" "In11.Cu" "In13.Cu" "In15.Cu")
		(hatch none 0.5)
		(connect_pads
			(clearance 0)
		)
		(min_thickness 0.25)
		(keepout
			(tracks not_allowed)
			(vias allowed)
			(pads allowed)
			(copperpour not_allowed)
			(footprints allowed)
		)
		(placement
			(enabled no)
			(sheetname "")
		)
		(fill yes
			(thermal_gap 0.5)
			(thermal_bridge_width 0.5)
			(island_removal_mode 0)
		)
		(polygon
			(pts
				(arc
					(start 67.40906 -129.913634)
					(mid 66.70548 -129.913634)
					(end 67.40906 -129.913634)
				)
			)
		)
	)
	(zone
		(layers "B.Cu" "In7.Cu" "In9.Cu" "In11.Cu" "In13.Cu" "In15.Cu")
		(hatch none 0.5)
		(connect_pads
			(clearance 0)
		)
		(min_thickness 0.25)
		(keepout
			(tracks not_allowed)
			(vias allowed)
			(pads allowed)
			(copperpour not_allowed)
			(footprints allowed)
		)
		(placement
			(enabled no)
			(sheetname "")
		)
		(fill yes
			(thermal_gap 0.5)
			(thermal_bridge_width 0.5)
			(island_removal_mode 0)
		)
		(polygon
			(pts
				(arc
					(start 191.276224 -273.099784)
					(mid 190.623444 -273.099784)
					(end 191.276224 -273.099784)
				)
			)
		)
	)
	(zone
		(layers "B.Cu" "In7.Cu" "In9.Cu" "In11.Cu" "In13.Cu" "In15.Cu")
		(hatch none 0.5)
		(connect_pads
			(clearance 0)
		)
		(min_thickness 0.25)
		(keepout
			(tracks not_allowed)
			(vias allowed)
			(pads allowed)
			(copperpour not_allowed)
			(footprints allowed)
		)
		(placement
			(enabled no)
			(sheetname "")
		)
		(fill yes
			(thermal_gap 0.5)
			(thermal_bridge_width 0.5)
			(island_removal_mode 0)
		)
		(polygon
			(pts
				(arc
					(start 389.06958 -375.69013)
					(mid 388.31012 -375.69013)
					(end 389.06958 -375.69013)
				)
			)
		)
	)
	(zone
		(layers "B.Cu" "In7.Cu" "In9.Cu" "In11.Cu" "In13.Cu" "In15.Cu")
		(hatch none 0.5)
		(connect_pads
			(clearance 0)
		)
		(min_thickness 0.25)
		(keepout
			(tracks not_allowed)
			(vias allowed)
			(pads allowed)
			(copperpour not_allowed)
			(footprints allowed)
		)
		(placement
			(enabled no)
			(sheetname "")
		)
		(fill yes
			(thermal_gap 0.5)
			(thermal_bridge_width 0.5)
			(island_removal_mode 0)
		)
		(polygon
			(pts
				(arc
					(start 179.876196 -274.049744)
					(mid 179.223416 -274.049744)
					(end 179.876196 -274.049744)
				)
			)
		)
	)
	(zone
		(layers "B.Cu" "In7.Cu" "In9.Cu" "In11.Cu" "In13.Cu" "In15.Cu")
		(hatch none 0.5)
		(connect_pads
			(clearance 0)
		)
		(min_thickness 0.25)
		(keepout
			(tracks not_allowed)
			(vias allowed)
			(pads allowed)
			(copperpour not_allowed)
			(footprints allowed)
		)
		(placement
			(enabled no)
			(sheetname "")
		)
		(fill yes
			(thermal_gap 0.5)
			(thermal_bridge_width 0.5)
			(island_removal_mode 0)
		)
		(polygon
			(pts
				(arc
					(start 186.525916 -275.949918)
					(mid 185.873136 -275.949918)
					(end 186.525916 -275.949918)
				)
			)
		)
	)
	(zone
		(layers "B.Cu" "In7.Cu" "In9.Cu" "In11.Cu" "In13.Cu" "In15.Cu")
		(hatch none 0.5)
		(connect_pads
			(clearance 0)
		)
		(min_thickness 0.25)
		(keepout
			(tracks not_allowed)
			(vias allowed)
			(pads allowed)
			(copperpour not_allowed)
			(footprints allowed)
		)
		(placement
			(enabled no)
			(sheetname "")
		)
		(fill yes
			(thermal_gap 0.5)
			(thermal_bridge_width 0.5)
			(island_removal_mode 0)
		)
		(polygon
			(pts
				(arc
					(start 168.694354 -133.096508)
					(mid 167.990774 -133.096508)
					(end 168.694354 -133.096508)
				)
			)
		)
	)
	(zone
		(layers "B.Cu" "In7.Cu" "In9.Cu" "In11.Cu" "In13.Cu" "In15.Cu")
		(hatch none 0.5)
		(connect_pads
			(clearance 0)
		)
		(min_thickness 0.25)
		(keepout
			(tracks not_allowed)
			(vias allowed)
			(pads allowed)
			(copperpour not_allowed)
			(footprints allowed)
		)
		(placement
			(enabled no)
			(sheetname "")
		)
		(fill yes
			(thermal_gap 0.5)
			(thermal_bridge_width 0.5)
			(island_removal_mode 0)
		)
		(polygon
			(pts
				(arc
					(start 375.869708 -374.390158)
					(mid 375.110248 -374.390158)
					(end 375.869708 -374.390158)
				)
			)
		)
	)
	(zone
		(layers "B.Cu" "In7.Cu" "In9.Cu" "In11.Cu" "In13.Cu" "In15.Cu")
		(hatch none 0.5)
		(connect_pads
			(clearance 0)
		)
		(min_thickness 0.25)
		(keepout
			(tracks not_allowed)
			(vias allowed)
			(pads allowed)
			(copperpour not_allowed)
			(footprints allowed)
		)
		(placement
			(enabled no)
			(sheetname "")
		)
		(fill yes
			(thermal_gap 0.5)
			(thermal_bridge_width 0.5)
			(island_removal_mode 0)
		)
		(polygon
			(pts
				(arc
					(start 404.476204 -318.699896)
					(mid 403.823424 -318.699896)
					(end 404.476204 -318.699896)
				)
			)
		)
	)
	(zone
		(layers "B.Cu" "In7.Cu" "In9.Cu" "In11.Cu" "In13.Cu" "In15.Cu")
		(hatch none 0.5)
		(connect_pads
			(clearance 0)
		)
		(min_thickness 0.25)
		(keepout
			(tracks not_allowed)
			(vias allowed)
			(pads allowed)
			(copperpour not_allowed)
			(footprints allowed)
		)
		(placement
			(enabled no)
			(sheetname "")
		)
		(fill yes
			(thermal_gap 0.5)
			(thermal_bridge_width 0.5)
			(island_removal_mode 0)
		)
		(polygon
			(pts
				(arc
					(start 69.476112 -273.099784)
					(mid 68.823332 -273.099784)
					(end 69.476112 -273.099784)
				)
			)
		)
	)
	(zone
		(layers "B.Cu" "In7.Cu" "In9.Cu" "In11.Cu" "In13.Cu" "In15.Cu")
		(hatch none 0.5)
		(connect_pads
			(clearance 0)
		)
		(min_thickness 0.25)
		(keepout
			(tracks not_allowed)
			(vias allowed)
			(pads allowed)
			(copperpour not_allowed)
			(footprints allowed)
		)
		(placement
			(enabled no)
			(sheetname "")
		)
		(fill yes
			(thermal_gap 0.5)
			(thermal_bridge_width 0.5)
			(island_removal_mode 0)
		)
		(polygon
			(pts
				(arc
					(start 342.869774 -371.590062)
					(mid 342.110314 -371.590062)
					(end 342.869774 -371.590062)
				)
			)
		)
	)
	(zone
		(layers "B.Cu" "In7.Cu" "In9.Cu" "In11.Cu" "In13.Cu" "In15.Cu")
		(hatch none 0.5)
		(connect_pads
			(clearance 0)
		)
		(min_thickness 0.25)
		(keepout
			(tracks not_allowed)
			(vias allowed)
			(pads allowed)
			(copperpour not_allowed)
			(footprints allowed)
		)
		(placement
			(enabled no)
			(sheetname "")
		)
		(fill yes
			(thermal_gap 0.5)
			(thermal_bridge_width 0.5)
			(island_removal_mode 0)
		)
		(polygon
			(pts
				(arc
					(start 426.469556 -405.390096)
					(mid 425.710096 -405.390096)
					(end 426.469556 -405.390096)
				)
			)
		)
	)
	(zone
		(layers "B.Cu" "In7.Cu" "In9.Cu" "In11.Cu" "In13.Cu" "In15.Cu")
		(hatch none 0.5)
		(connect_pads
			(clearance 0)
		)
		(min_thickness 0.25)
		(keepout
			(tracks not_allowed)
			(vias allowed)
			(pads allowed)
			(copperpour not_allowed)
			(footprints allowed)
		)
		(placement
			(enabled no)
			(sheetname "")
		)
		(fill yes
			(thermal_gap 0.5)
			(thermal_bridge_width 0.5)
			(island_removal_mode 0)
		)
		(polygon
			(pts
				(arc
					(start 125.08992 -374.390158)
					(mid 124.33046 -374.390158)
					(end 125.08992 -374.390158)
				)
			)
		)
	)
	(zone
		(layers "B.Cu" "In7.Cu" "In9.Cu" "In11.Cu" "In13.Cu" "In15.Cu")
		(hatch none 0.5)
		(connect_pads
			(clearance 0)
		)
		(min_thickness 0.25)
		(keepout
			(tracks not_allowed)
			(vias allowed)
			(pads allowed)
			(copperpour not_allowed)
			(footprints allowed)
		)
		(placement
			(enabled no)
			(sheetname "")
		)
		(fill yes
			(thermal_gap 0.5)
			(thermal_bridge_width 0.5)
			(island_removal_mode 0)
		)
		(polygon
			(pts
				(arc
					(start 423.476166 -274.049744)
					(mid 422.823386 -274.049744)
					(end 423.476166 -274.049744)
				)
			)
		)
	)
	(zone
		(layers "B.Cu" "In7.Cu" "In9.Cu" "In11.Cu" "In13.Cu" "In15.Cu")
		(hatch none 0.5)
		(connect_pads
			(clearance 0)
		)
		(min_thickness 0.25)
		(keepout
			(tracks not_allowed)
			(vias allowed)
			(pads allowed)
			(copperpour not_allowed)
			(footprints allowed)
		)
		(placement
			(enabled no)
			(sheetname "")
		)
		(fill yes
			(thermal_gap 0.5)
			(thermal_bridge_width 0.5)
			(island_removal_mode 0)
		)
		(polygon
			(pts
				(arc
					(start 407.326338 -316.799722)
					(mid 406.673558 -316.799722)
					(end 407.326338 -316.799722)
				)
			)
		)
	)
	(zone
		(layers "B.Cu" "In7.Cu" "In9.Cu" "In11.Cu" "In13.Cu" "In15.Cu")
		(hatch none 0.5)
		(connect_pads
			(clearance 0)
		)
		(min_thickness 0.25)
		(keepout
			(tracks not_allowed)
			(vias allowed)
			(pads allowed)
			(copperpour not_allowed)
			(footprints allowed)
		)
		(placement
			(enabled no)
			(sheetname "")
		)
		(fill yes
			(thermal_gap 0.5)
			(thermal_bridge_width 0.5)
			(island_removal_mode 0)
		)
		(polygon
			(pts
				(arc
					(start 116.289836 -396.49019)
					(mid 115.530376 -396.49019)
					(end 116.289836 -396.49019)
				)
			)
		)
	)
	(zone
		(layers "B.Cu" "In7.Cu" "In9.Cu" "In11.Cu" "In13.Cu" "In15.Cu")
		(hatch none 0.5)
		(connect_pads
			(clearance 0)
		)
		(min_thickness 0.25)
		(keepout
			(tracks not_allowed)
			(vias allowed)
			(pads allowed)
			(copperpour not_allowed)
			(footprints allowed)
		)
		(placement
			(enabled no)
			(sheetname "")
		)
		(fill yes
			(thermal_gap 0.5)
			(thermal_bridge_width 0.5)
			(island_removal_mode 0)
		)
		(polygon
			(pts
				(arc
					(start 54.44871 -123.686316)
					(mid 53.74513 -123.686316)
					(end 54.44871 -123.686316)
				)
			)
		)
	)
	(zone
		(layers "B.Cu" "In7.Cu" "In9.Cu" "In11.Cu" "In13.Cu" "In15.Cu")
		(hatch none 0.5)
		(connect_pads
			(clearance 0)
		)
		(min_thickness 0.25)
		(keepout
			(tracks not_allowed)
			(vias allowed)
			(pads allowed)
			(copperpour not_allowed)
			(footprints allowed)
		)
		(placement
			(enabled no)
			(sheetname "")
		)
		(fill yes
			(thermal_gap 0.5)
			(thermal_bridge_width 0.5)
			(island_removal_mode 0)
		)
		(polygon
			(pts
				(arc
					(start 413.976312 -317.749936)
					(mid 413.323532 -317.749936)
					(end 413.976312 -317.749936)
				)
			)
		)
	)
	(zone
		(layers "B.Cu" "In7.Cu" "In9.Cu" "In11.Cu" "In13.Cu" "In15.Cu")
		(hatch none 0.5)
		(connect_pads
			(clearance 0)
		)
		(min_thickness 0.25)
		(keepout
			(tracks not_allowed)
			(vias allowed)
			(pads allowed)
			(copperpour not_allowed)
			(footprints allowed)
		)
		(placement
			(enabled no)
			(sheetname "")
		)
		(fill yes
			(thermal_gap 0.5)
			(thermal_bridge_width 0.5)
			(island_removal_mode 0)
		)
		(polygon
			(pts
				(arc
					(start 190.32601 -274.999958)
					(mid 189.67323 -274.999958)
					(end 190.32601 -274.999958)
				)
			)
		)
	)
	(zone
		(layers "B.Cu" "In7.Cu" "In9.Cu" "In11.Cu" "In13.Cu" "In15.Cu")
		(hatch none 0.5)
		(connect_pads
			(clearance 0)
		)
		(min_thickness 0.25)
		(keepout
			(tracks not_allowed)
			(vias allowed)
			(pads allowed)
			(copperpour not_allowed)
			(footprints allowed)
		)
		(placement
			(enabled no)
			(sheetname "")
		)
		(fill yes
			(thermal_gap 0.5)
			(thermal_bridge_width 0.5)
			(island_removal_mode 0)
		)
		(polygon
			(pts
				(arc
					(start 425.376086 -274.049744)
					(mid 424.723306 -274.049744)
					(end 425.376086 -274.049744)
				)
			)
		)
	)
	(zone
		(layers "B.Cu" "In7.Cu" "In9.Cu" "In11.Cu" "In13.Cu" "In15.Cu")
		(hatch none 0.5)
		(connect_pads
			(clearance 0)
		)
		(min_thickness 0.25)
		(keepout
			(tracks not_allowed)
			(vias allowed)
			(pads allowed)
			(copperpour not_allowed)
			(footprints allowed)
		)
		(placement
			(enabled no)
			(sheetname "")
		)
		(fill yes
			(thermal_gap 0.5)
			(thermal_bridge_width 0.5)
			(island_removal_mode 0)
		)
		(polygon
			(pts
				(arc
					(start 181.654704 -151.623776)
					(mid 180.951124 -151.623776)
					(end 181.654704 -151.623776)
				)
			)
		)
	)
	(zone
		(layers "B.Cu" "In7.Cu" "In9.Cu" "In11.Cu" "In13.Cu" "In15.Cu")
		(hatch none 0.5)
		(connect_pads
			(clearance 0)
		)
		(min_thickness 0.25)
		(keepout
			(tracks not_allowed)
			(vias allowed)
			(pads allowed)
			(copperpour not_allowed)
			(footprints allowed)
		)
		(placement
			(enabled no)
			(sheetname "")
		)
		(fill yes
			(thermal_gap 0.5)
			(thermal_bridge_width 0.5)
			(island_removal_mode 0)
		)
		(polygon
			(pts
				(arc
					(start 277.926292 -316.799722)
					(mid 277.273512 -316.799722)
					(end 277.926292 -316.799722)
				)
			)
		)
	)
	(zone
		(layers "B.Cu" "In7.Cu" "In9.Cu" "In11.Cu" "In13.Cu" "In15.Cu")
		(hatch none 0.5)
		(connect_pads
			(clearance 0)
		)
		(min_thickness 0.25)
		(keepout
			(tracks not_allowed)
			(vias allowed)
			(pads allowed)
			(copperpour not_allowed)
			(footprints allowed)
		)
		(placement
			(enabled no)
			(sheetname "")
		)
		(fill yes
			(thermal_gap 0.5)
			(thermal_bridge_width 0.5)
			(island_removal_mode 0)
		)
		(polygon
			(pts
				(arc
					(start 183.508904 -119.567198)
					(mid 182.805324 -119.567198)
					(end 183.508904 -119.567198)
				)
			)
		)
	)
	(zone
		(layers "B.Cu" "In7.Cu" "In9.Cu" "In11.Cu" "In13.Cu" "In15.Cu")
		(hatch none 0.5)
		(connect_pads
			(clearance 0)
		)
		(min_thickness 0.25)
		(keepout
			(tracks not_allowed)
			(vias allowed)
			(pads allowed)
			(copperpour not_allowed)
			(footprints allowed)
		)
		(placement
			(enabled no)
			(sheetname "")
		)
		(fill yes
			(thermal_gap 0.5)
			(thermal_bridge_width 0.5)
			(island_removal_mode 0)
		)
		(polygon
			(pts
				(arc
					(start 181.77637 -317.749936)
					(mid 181.12359 -317.749936)
					(end 181.77637 -317.749936)
				)
			)
		)
	)
	(zone
		(layers "B.Cu" "In7.Cu" "In9.Cu" "In11.Cu" "In13.Cu" "In15.Cu")
		(hatch none 0.5)
		(connect_pads
			(clearance 0)
		)
		(min_thickness 0.25)
		(keepout
			(tracks not_allowed)
			(vias allowed)
			(pads allowed)
			(copperpour not_allowed)
			(footprints allowed)
		)
		(placement
			(enabled no)
			(sheetname "")
		)
		(fill yes
			(thermal_gap 0.5)
			(thermal_bridge_width 0.5)
			(island_removal_mode 0)
		)
		(polygon
			(pts
				(arc
					(start 402.74875 -119.222774)
					(mid 402.04517 -119.222774)
					(end 402.74875 -119.222774)
				)
			)
		)
	)
	(zone
		(layers "B.Cu" "In7.Cu" "In9.Cu" "In11.Cu" "In13.Cu" "In15.Cu")
		(hatch none 0.5)
		(connect_pads
			(clearance 0)
		)
		(min_thickness 0.25)
		(keepout
			(tracks not_allowed)
			(vias allowed)
			(pads allowed)
			(copperpour not_allowed)
			(footprints allowed)
		)
		(placement
			(enabled no)
			(sheetname "")
		)
		(fill yes
			(thermal_gap 0.5)
			(thermal_bridge_width 0.5)
			(island_removal_mode 0)
		)
		(polygon
			(pts
				(arc
					(start 313.076082 -282.599892)
					(mid 312.423302 -282.599892)
					(end 313.076082 -282.599892)
				)
			)
		)
	)
	(zone
		(layers "B.Cu" "In7.Cu" "In9.Cu" "In11.Cu" "In13.Cu" "In15.Cu")
		(hatch none 0.5)
		(connect_pads
			(clearance 0)
		)
		(min_thickness 0.25)
		(keepout
			(tracks not_allowed)
			(vias allowed)
			(pads allowed)
			(copperpour not_allowed)
			(footprints allowed)
		)
		(placement
			(enabled no)
			(sheetname "")
		)
		(fill yes
			(thermal_gap 0.5)
			(thermal_bridge_width 0.5)
			(island_removal_mode 0)
		)
		(polygon
			(pts
				(arc
					(start 176.076102 -273.09953)
					(mid 175.423322 -273.09953)
					(end 176.076102 -273.09953)
				)
			)
		)
	)
	(zone
		(layers "B.Cu" "In7.Cu" "In9.Cu" "In11.Cu" "In13.Cu" "In15.Cu")
		(hatch none 0.5)
		(connect_pads
			(clearance 0)
		)
		(min_thickness 0.25)
		(keepout
			(tracks not_allowed)
			(vias allowed)
			(pads allowed)
			(copperpour not_allowed)
			(footprints allowed)
		)
		(placement
			(enabled no)
			(sheetname "")
		)
		(fill yes
			(thermal_gap 0.5)
			(thermal_bridge_width 0.5)
			(island_removal_mode 0)
		)
		(polygon
			(pts
				(arc
					(start 269.376144 -304.449734)
					(mid 268.723364 -304.449734)
					(end 269.376144 -304.449734)
				)
			)
		)
	)
	(zone
		(layers "B.Cu" "In7.Cu" "In9.Cu" "In11.Cu" "In13.Cu" "In15.Cu")
		(hatch none 0.5)
		(connect_pads
			(clearance 0)
		)
		(min_thickness 0.25)
		(keepout
			(tracks not_allowed)
			(vias allowed)
			(pads allowed)
			(copperpour not_allowed)
			(footprints allowed)
		)
		(placement
			(enabled no)
			(sheetname "")
		)
		(fill yes
			(thermal_gap 0.5)
			(thermal_bridge_width 0.5)
			(island_removal_mode 0)
		)
		(polygon
			(pts
				(arc
					(start 54.44871 -110.11281)
					(mid 53.74513 -110.11281)
					(end 54.44871 -110.11281)
				)
			)
		)
	)
	(zone
		(layers "B.Cu" "In7.Cu" "In9.Cu" "In11.Cu" "In13.Cu" "In15.Cu")
		(hatch none 0.5)
		(connect_pads
			(clearance 0)
		)
		(min_thickness 0.25)
		(keepout
			(tracks not_allowed)
			(vias allowed)
			(pads allowed)
			(copperpour not_allowed)
			(footprints allowed)
		)
		(placement
			(enabled no)
			(sheetname "")
		)
		(fill yes
			(thermal_gap 0.5)
			(thermal_bridge_width 0.5)
			(island_removal_mode 0)
		)
		(polygon
			(pts
				(arc
					(start 183.676036 -274.049744)
					(mid 183.023256 -274.049744)
					(end 183.676036 -274.049744)
				)
			)
		)
	)
	(zone
		(layers "B.Cu" "In7.Cu" "In9.Cu" "In11.Cu" "In13.Cu" "In15.Cu")
		(hatch none 0.5)
		(connect_pads
			(clearance 0)
		)
		(min_thickness 0.25)
		(keepout
			(tracks not_allowed)
			(vias allowed)
			(pads allowed)
			(copperpour not_allowed)
			(footprints allowed)
		)
		(placement
			(enabled no)
			(sheetname "")
		)
		(fill yes
			(thermal_gap 0.5)
			(thermal_bridge_width 0.5)
			(island_removal_mode 0)
		)
		(polygon
			(pts
				(arc
					(start 67.40906 -123.16714)
					(mid 66.70548 -123.16714)
					(end 67.40906 -123.16714)
				)
			)
		)
	)
	(zone
		(layers "B.Cu" "In7.Cu" "In9.Cu" "In11.Cu" "In13.Cu" "In15.Cu")
		(hatch none 0.5)
		(connect_pads
			(clearance 0)
		)
		(min_thickness 0.25)
		(keepout
			(tracks not_allowed)
			(vias allowed)
			(pads allowed)
			(copperpour not_allowed)
			(footprints allowed)
		)
		(placement
			(enabled no)
			(sheetname "")
		)
		(fill yes
			(thermal_gap 0.5)
			(thermal_bridge_width 0.5)
			(island_removal_mode 0)
		)
		(polygon
			(pts
				(arc
					(start 76.126086 -274.999704)
					(mid 75.473306 -274.999704)
					(end 76.126086 -274.999704)
				)
			)
		)
	)
	(zone
		(layers "B.Cu" "In7.Cu" "In9.Cu" "In11.Cu" "In13.Cu" "In15.Cu")
		(hatch none 0.5)
		(connect_pads
			(clearance 0)
		)
		(min_thickness 0.25)
		(keepout
			(tracks not_allowed)
			(vias allowed)
			(pads allowed)
			(copperpour not_allowed)
			(footprints allowed)
		)
		(placement
			(enabled no)
			(sheetname "")
		)
		(fill yes
			(thermal_gap 0.5)
			(thermal_bridge_width 0.5)
			(island_removal_mode 0)
		)
		(polygon
			(pts
				(arc
					(start 297.754802 -155.223718)
					(mid 297.051222 -155.223718)
					(end 297.754802 -155.223718)
				)
			)
		)
	)
	(zone
		(layers "B.Cu" "In7.Cu" "In9.Cu" "In11.Cu" "In13.Cu" "In15.Cu")
		(hatch none 0.5)
		(connect_pads
			(clearance 0)
		)
		(min_thickness 0.25)
		(keepout
			(tracks not_allowed)
			(vias allowed)
			(pads allowed)
			(copperpour not_allowed)
			(footprints allowed)
		)
		(placement
			(enabled no)
			(sheetname "")
		)
		(fill yes
			(thermal_gap 0.5)
			(thermal_bridge_width 0.5)
			(island_removal_mode 0)
		)
		(polygon
			(pts
				(arc
					(start 284.794452 -135.83285)
					(mid 284.090872 -135.83285)
					(end 284.794452 -135.83285)
				)
			)
		)
	)
	(zone
		(layers "B.Cu" "In7.Cu" "In9.Cu" "In11.Cu" "In13.Cu" "In15.Cu")
		(hatch none 0.5)
		(connect_pads
			(clearance 0)
		)
		(min_thickness 0.25)
		(keepout
			(tracks not_allowed)
			(vias allowed)
			(pads allowed)
			(copperpour not_allowed)
			(footprints allowed)
		)
		(placement
			(enabled no)
			(sheetname "")
		)
		(fill yes
			(thermal_gap 0.5)
			(thermal_bridge_width 0.5)
			(island_removal_mode 0)
		)
		(polygon
			(pts
				(arc
					(start 74.225912 -275.949918)
					(mid 73.573132 -275.949918)
					(end 74.225912 -275.949918)
				)
			)
		)
	)
	(zone
		(layers "B.Cu" "In7.Cu" "In9.Cu" "In11.Cu" "In13.Cu" "In15.Cu")
		(hatch none 0.5)
		(connect_pads
			(clearance 0)
		)
		(min_thickness 0.25)
		(keepout
			(tracks not_allowed)
			(vias allowed)
			(pads allowed)
			(copperpour not_allowed)
			(footprints allowed)
		)
		(placement
			(enabled no)
			(sheetname "")
		)
		(fill yes
			(thermal_gap 0.5)
			(thermal_bridge_width 0.5)
			(island_removal_mode 0)
		)
		(polygon
			(pts
				(arc
					(start 166.889684 -406.690068)
					(mid 166.130224 -406.690068)
					(end 166.889684 -406.690068)
				)
			)
		)
	)
	(zone
		(layers "B.Cu" "In7.Cu" "In9.Cu" "In11.Cu" "In13.Cu" "In15.Cu")
		(hatch none 0.5)
		(connect_pads
			(clearance 0)
		)
		(min_thickness 0.25)
		(keepout
			(tracks not_allowed)
			(vias allowed)
			(pads allowed)
			(copperpour not_allowed)
			(footprints allowed)
		)
		(placement
			(enabled no)
			(sheetname "")
		)
		(fill yes
			(thermal_gap 0.5)
			(thermal_bridge_width 0.5)
			(island_removal_mode 0)
		)
		(polygon
			(pts
				(arc
					(start 60.925964 -274.999704)
					(mid 60.273184 -274.999704)
					(end 60.925964 -274.999704)
				)
			)
		)
	)
	(zone
		(layers "B.Cu" "In7.Cu" "In9.Cu" "In11.Cu" "In13.Cu" "In15.Cu")
		(hatch none 0.5)
		(connect_pads
			(clearance 0)
		)
		(min_thickness 0.25)
		(keepout
			(tracks not_allowed)
			(vias allowed)
			(pads allowed)
			(copperpour not_allowed)
			(footprints allowed)
		)
		(placement
			(enabled no)
			(sheetname "")
		)
		(fill yes
			(thermal_gap 0.5)
			(thermal_bridge_width 0.5)
			(island_removal_mode 0)
		)
		(polygon
			(pts
				(arc
					(start 192.226184 -275.949664)
					(mid 191.573404 -275.949664)
					(end 192.226184 -275.949664)
				)
			)
		)
	)
	(zone
		(layers "B.Cu" "In7.Cu" "In9.Cu" "In11.Cu" "In13.Cu" "In15.Cu")
		(hatch none 0.5)
		(connect_pads
			(clearance 0)
		)
		(min_thickness 0.25)
		(keepout
			(tracks not_allowed)
			(vias allowed)
			(pads allowed)
			(copperpour not_allowed)
			(footprints allowed)
		)
		(placement
			(enabled no)
			(sheetname "")
		)
		(fill yes
			(thermal_gap 0.5)
			(thermal_bridge_width 0.5)
			(island_removal_mode 0)
		)
		(polygon
			(pts
				(arc
					(start 198.876412 -283.549852)
					(mid 198.223632 -283.549852)
					(end 198.876412 -283.549852)
				)
			)
		)
	)
	(zone
		(layers "B.Cu" "In7.Cu" "In9.Cu" "In11.Cu" "In13.Cu" "In15.Cu")
		(hatch none 0.5)
		(connect_pads
			(clearance 0)
		)
		(min_thickness 0.25)
		(keepout
			(tracks not_allowed)
			(vias allowed)
			(pads allowed)
			(copperpour not_allowed)
			(footprints allowed)
		)
		(placement
			(enabled no)
			(sheetname "")
		)
		(fill yes
			(thermal_gap 0.5)
			(thermal_bridge_width 0.5)
			(island_removal_mode 0)
		)
		(polygon
			(pts
				(arc
					(start 423.476166 -273.099784)
					(mid 422.823386 -273.099784)
					(end 423.476166 -273.099784)
				)
			)
		)
	)
	(zone
		(layers "B.Cu" "In7.Cu" "In9.Cu" "In11.Cu" "In13.Cu" "In15.Cu")
		(hatch none 0.5)
		(connect_pads
			(clearance 0)
		)
		(min_thickness 0.25)
		(keepout
			(tracks not_allowed)
			(vias allowed)
			(pads allowed)
			(copperpour not_allowed)
			(footprints allowed)
		)
		(placement
			(enabled no)
			(sheetname "")
		)
		(fill yes
			(thermal_gap 0.5)
			(thermal_bridge_width 0.5)
			(island_removal_mode 0)
		)
		(polygon
			(pts
				(arc
					(start 68.526152 -315.849762)
					(mid 67.873372 -315.849762)
					(end 68.526152 -315.849762)
				)
			)
		)
	)
	(zone
		(layers "B.Cu" "In7.Cu" "In9.Cu" "In11.Cu" "In13.Cu" "In15.Cu")
		(hatch none 0.5)
		(connect_pads
			(clearance 0)
		)
		(min_thickness 0.25)
		(keepout
			(tracks not_allowed)
			(vias allowed)
			(pads allowed)
			(copperpour not_allowed)
			(footprints allowed)
		)
		(placement
			(enabled no)
			(sheetname "")
		)
		(fill yes
			(thermal_gap 0.5)
			(thermal_bridge_width 0.5)
			(island_removal_mode 0)
		)
		(polygon
			(pts
				(arc
					(start 424.426126 -274.999704)
					(mid 423.773346 -274.999704)
					(end 424.426126 -274.999704)
				)
			)
		)
	)
	(zone
		(layers "B.Cu" "In7.Cu" "In9.Cu" "In11.Cu" "In13.Cu" "In15.Cu")
		(hatch none 0.5)
		(connect_pads
			(clearance 0)
		)
		(min_thickness 0.25)
		(keepout
			(tracks not_allowed)
			(vias allowed)
			(pads allowed)
			(copperpour not_allowed)
			(footprints allowed)
		)
		(placement
			(enabled no)
			(sheetname "")
		)
		(fill yes
			(thermal_gap 0.5)
			(thermal_bridge_width 0.5)
			(island_removal_mode 0)
		)
		(polygon
			(pts
				(arc
					(start 338.469732 -402.790152)
					(mid 337.710272 -402.790152)
					(end 338.469732 -402.790152)
				)
			)
		)
	)
	(zone
		(layers "B.Cu" "In7.Cu" "In9.Cu" "In11.Cu" "In13.Cu" "In15.Cu")
		(hatch none 0.5)
		(connect_pads
			(clearance 0)
		)
		(min_thickness 0.25)
		(keepout
			(tracks not_allowed)
			(vias allowed)
			(pads allowed)
			(copperpour not_allowed)
			(footprints allowed)
		)
		(placement
			(enabled no)
			(sheetname "")
		)
		(fill yes
			(thermal_gap 0.5)
			(thermal_bridge_width 0.5)
			(island_removal_mode 0)
		)
		(polygon
			(pts
				(arc
					(start 81.089754 -371.790214)
					(mid 80.330294 -371.790214)
					(end 81.089754 -371.790214)
				)
			)
		)
	)
	(zone
		(layers "B.Cu" "In7.Cu" "In9.Cu" "In11.Cu" "In13.Cu" "In15.Cu")
		(hatch none 0.5)
		(connect_pads
			(clearance 0)
		)
		(min_thickness 0.25)
		(keepout
			(tracks not_allowed)
			(vias allowed)
			(pads allowed)
			(copperpour not_allowed)
			(footprints allowed)
		)
		(placement
			(enabled no)
			(sheetname "")
		)
		(fill yes
			(thermal_gap 0.5)
			(thermal_bridge_width 0.5)
			(island_removal_mode 0)
		)
		(polygon
			(pts
				(arc
					(start 65.55486 -148.023834)
					(mid 64.85128 -148.023834)
					(end 65.55486 -148.023834)
				)
			)
		)
	)
	(zone
		(layers "B.Cu" "In7.Cu" "In9.Cu" "In11.Cu" "In13.Cu" "In15.Cu")
		(hatch none 0.5)
		(connect_pads
			(clearance 0)
		)
		(min_thickness 0.25)
		(keepout
			(tracks not_allowed)
			(vias allowed)
			(pads allowed)
			(copperpour not_allowed)
			(footprints allowed)
		)
		(placement
			(enabled no)
			(sheetname "")
		)
		(fill yes
			(thermal_gap 0.5)
			(thermal_bridge_width 0.5)
			(island_removal_mode 0)
		)
		(polygon
			(pts
				(arc
					(start 428.225966 -275.949918)
					(mid 427.573186 -275.949918)
					(end 428.225966 -275.949918)
				)
			)
		)
	)
	(zone
		(layers "B.Cu" "In7.Cu" "In9.Cu" "In11.Cu" "In13.Cu" "In15.Cu")
		(hatch none 0.5)
		(connect_pads
			(clearance 0)
		)
		(min_thickness 0.25)
		(keepout
			(tracks not_allowed)
			(vias allowed)
			(pads allowed)
			(copperpour not_allowed)
			(footprints allowed)
		)
		(placement
			(enabled no)
			(sheetname "")
		)
		(fill yes
			(thermal_gap 0.5)
			(thermal_bridge_width 0.5)
			(island_removal_mode 0)
		)
		(polygon
			(pts
				(arc
					(start 278.876252 -318.699896)
					(mid 278.223472 -318.699896)
					(end 278.876252 -318.699896)
				)
			)
		)
	)
	(zone
		(layers "B.Cu" "In7.Cu" "In9.Cu" "In11.Cu" "In13.Cu" "In15.Cu")
		(hatch none 0.5)
		(connect_pads
			(clearance 0)
		)
		(min_thickness 0.25)
		(keepout
			(tracks not_allowed)
			(vias allowed)
			(pads allowed)
			(copperpour not_allowed)
			(footprints allowed)
		)
		(placement
			(enabled no)
			(sheetname "")
		)
		(fill yes
			(thermal_gap 0.5)
			(thermal_bridge_width 0.5)
			(island_removal_mode 0)
		)
		(polygon
			(pts
				(arc
					(start 39.289736 -384.590036)
					(mid 38.530276 -384.590036)
					(end 39.289736 -384.590036)
				)
			)
		)
	)
	(zone
		(layers "B.Cu" "In7.Cu" "In9.Cu" "In11.Cu" "In13.Cu" "In15.Cu")
		(hatch none 0.5)
		(connect_pads
			(clearance 0)
		)
		(min_thickness 0.25)
		(keepout
			(tracks not_allowed)
			(vias allowed)
			(pads allowed)
			(copperpour not_allowed)
			(footprints allowed)
		)
		(placement
			(enabled no)
			(sheetname "")
		)
		(fill yes
			(thermal_gap 0.5)
			(thermal_bridge_width 0.5)
			(island_removal_mode 0)
		)
		(polygon
			(pts
				(arc
					(start 331.869796 -401.690078)
					(mid 331.110336 -401.690078)
					(end 331.869796 -401.690078)
				)
			)
		)
	)
	(zone
		(layers "B.Cu" "In7.Cu" "In9.Cu" "In11.Cu" "In13.Cu" "In15.Cu")
		(hatch none 0.5)
		(connect_pads
			(clearance 0)
		)
		(min_thickness 0.25)
		(keepout
			(tracks not_allowed)
			(vias allowed)
			(pads allowed)
			(copperpour not_allowed)
			(footprints allowed)
		)
		(placement
			(enabled no)
			(sheetname "")
		)
		(fill yes
			(thermal_gap 0.5)
			(thermal_bridge_width 0.5)
			(island_removal_mode 0)
		)
		(polygon
			(pts
				(arc
					(start 40.976296 -318.699896)
					(mid 40.323516 -318.699896)
					(end 40.976296 -318.699896)
				)
			)
		)
	)
	(zone
		(layers "B.Cu" "In7.Cu" "In9.Cu" "In11.Cu" "In13.Cu" "In15.Cu")
		(hatch none 0.5)
		(connect_pads
			(clearance 0)
		)
		(min_thickness 0.25)
		(keepout
			(tracks not_allowed)
			(vias allowed)
			(pads allowed)
			(copperpour not_allowed)
			(footprints allowed)
		)
		(placement
			(enabled no)
			(sheetname "")
		)
		(fill yes
			(thermal_gap 0.5)
			(thermal_bridge_width 0.5)
			(island_removal_mode 0)
		)
		(polygon
			(pts
				(arc
					(start 429.17618 -309.199788)
					(mid 428.5234 -309.199788)
					(end 429.17618 -309.199788)
				)
			)
		)
	)
	(zone
		(layers "B.Cu" "In7.Cu" "In9.Cu" "In11.Cu" "In13.Cu" "In15.Cu")
		(hatch none 0.5)
		(connect_pads
			(clearance 0)
		)
		(min_thickness 0.25)
		(keepout
			(tracks not_allowed)
			(vias allowed)
			(pads allowed)
			(copperpour not_allowed)
			(footprints allowed)
		)
		(placement
			(enabled no)
			(sheetname "")
		)
		(fill yes
			(thermal_gap 0.5)
			(thermal_bridge_width 0.5)
			(island_removal_mode 0)
		)
		(polygon
			(pts
				(arc
					(start 197.926452 -310.149748)
					(mid 197.273672 -310.149748)
					(end 197.926452 -310.149748)
				)
			)
		)
	)
	(zone
		(layers "B.Cu" "In7.Cu" "In9.Cu" "In11.Cu" "In13.Cu" "In15.Cu")
		(hatch none 0.5)
		(connect_pads
			(clearance 0)
		)
		(min_thickness 0.25)
		(keepout
			(tracks not_allowed)
			(vias allowed)
			(pads allowed)
			(copperpour not_allowed)
			(footprints allowed)
		)
		(placement
			(enabled no)
			(sheetname "")
		)
		(fill yes
			(thermal_gap 0.5)
			(thermal_bridge_width 0.5)
			(island_removal_mode 0)
		)
		(polygon
			(pts
				(arc
					(start 59.976004 -274.04949)
					(mid 59.323224 -274.04949)
					(end 59.976004 -274.04949)
				)
			)
		)
	)
	(zone
		(layers "B.Cu" "In7.Cu" "In9.Cu" "In11.Cu" "In13.Cu" "In15.Cu")
		(hatch none 0.5)
		(connect_pads
			(clearance 0)
		)
		(min_thickness 0.25)
		(keepout
			(tracks not_allowed)
			(vias allowed)
			(pads allowed)
			(copperpour not_allowed)
			(footprints allowed)
		)
		(placement
			(enabled no)
			(sheetname "")
		)
		(fill yes
			(thermal_gap 0.5)
			(thermal_bridge_width 0.5)
			(island_removal_mode 0)
		)
		(polygon
			(pts
				(arc
					(start 413.8549 -152.487376)
					(mid 413.15132 -152.487376)
					(end 413.8549 -152.487376)
				)
			)
		)
	)
	(zone
		(layers "B.Cu" "In7.Cu" "In9.Cu" "In11.Cu" "In13.Cu" "In15.Cu")
		(hatch none 0.5)
		(connect_pads
			(clearance 0)
		)
		(min_thickness 0.25)
		(keepout
			(tracks not_allowed)
			(vias allowed)
			(pads allowed)
			(copperpour not_allowed)
			(footprints allowed)
		)
		(placement
			(enabled no)
			(sheetname "")
		)
		(fill yes
			(thermal_gap 0.5)
			(thermal_bridge_width 0.5)
			(island_removal_mode 0)
		)
		(polygon
			(pts
				(arc
					(start 192.226438 -315.849762)
					(mid 191.573658 -315.849762)
					(end 192.226438 -315.849762)
				)
			)
		)
	)
	(zone
		(layers "B.Cu" "In7.Cu" "In9.Cu" "In11.Cu" "In13.Cu" "In15.Cu")
		(hatch none 0.5)
		(connect_pads
			(clearance 0)
		)
		(min_thickness 0.25)
		(keepout
			(tracks not_allowed)
			(vias allowed)
			(pads allowed)
			(copperpour not_allowed)
			(footprints allowed)
		)
		(placement
			(enabled no)
			(sheetname "")
		)
		(fill yes
			(thermal_gap 0.5)
			(thermal_bridge_width 0.5)
			(island_removal_mode 0)
		)
		(polygon
			(pts
				(arc
					(start 181.654704 -136.177274)
					(mid 180.951124 -136.177274)
					(end 181.654704 -136.177274)
				)
			)
		)
	)
	(zone
		(layers "B.Cu" "In7.Cu" "In9.Cu" "In11.Cu" "In13.Cu" "In15.Cu")
		(hatch none 0.5)
		(connect_pads
			(clearance 0)
		)
		(min_thickness 0.25)
		(keepout
			(tracks not_allowed)
			(vias allowed)
			(pads allowed)
			(copperpour not_allowed)
			(footprints allowed)
		)
		(placement
			(enabled no)
			(sheetname "")
		)
		(fill yes
			(thermal_gap 0.5)
			(thermal_bridge_width 0.5)
			(island_removal_mode 0)
		)
		(polygon
			(pts
				(arc
					(start 302.62576 -275.949918)
					(mid 301.97298 -275.949918)
					(end 302.62576 -275.949918)
				)
			)
		)
	)
	(zone
		(layers "B.Cu" "In7.Cu" "In9.Cu" "In11.Cu" "In13.Cu" "In15.Cu")
		(hatch none 0.5)
		(connect_pads
			(clearance 0)
		)
		(min_thickness 0.25)
		(keepout
			(tracks not_allowed)
			(vias allowed)
			(pads allowed)
			(copperpour not_allowed)
			(footprints allowed)
		)
		(placement
			(enabled no)
			(sheetname "")
		)
		(fill yes
			(thermal_gap 0.5)
			(thermal_bridge_width 0.5)
			(island_removal_mode 0)
		)
		(polygon
			(pts
				(arc
					(start 399.726404 -315.849762)
					(mid 399.073624 -315.849762)
					(end 399.726404 -315.849762)
				)
			)
		)
	)
	(zone
		(layers "B.Cu" "In7.Cu" "In9.Cu" "In11.Cu" "In13.Cu" "In15.Cu")
		(hatch none 0.5)
		(connect_pads
			(clearance 0)
		)
		(min_thickness 0.25)
		(keepout
			(tracks not_allowed)
			(vias allowed)
			(pads allowed)
			(copperpour not_allowed)
			(footprints allowed)
		)
		(placement
			(enabled no)
			(sheetname "")
		)
		(fill yes
			(thermal_gap 0.5)
			(thermal_bridge_width 0.5)
			(island_removal_mode 0)
		)
		(polygon
			(pts
				(arc
					(start 87.68969 -402.790152)
					(mid 86.93023 -402.790152)
					(end 87.68969 -402.790152)
				)
			)
		)
	)
	(zone
		(layers "B.Cu" "In7.Cu" "In9.Cu" "In11.Cu" "In13.Cu" "In15.Cu")
		(hatch none 0.5)
		(connect_pads
			(clearance 0)
		)
		(min_thickness 0.25)
		(keepout
			(tracks not_allowed)
			(vias allowed)
			(pads allowed)
			(copperpour not_allowed)
			(footprints allowed)
		)
		(placement
			(enabled no)
			(sheetname "")
		)
		(fill yes
			(thermal_gap 0.5)
			(thermal_bridge_width 0.5)
			(island_removal_mode 0)
		)
		(polygon
			(pts
				(arc
					(start 52.59451 -132.232908)
					(mid 51.89093 -132.232908)
					(end 52.59451 -132.232908)
				)
			)
		)
	)
	(zone
		(layers "B.Cu" "In7.Cu" "In9.Cu" "In11.Cu" "In13.Cu" "In15.Cu")
		(hatch none 0.5)
		(connect_pads
			(clearance 0)
		)
		(min_thickness 0.25)
		(keepout
			(tracks not_allowed)
			(vias allowed)
			(pads allowed)
			(copperpour not_allowed)
			(footprints allowed)
		)
		(placement
			(enabled no)
			(sheetname "")
		)
		(fill yes
			(thermal_gap 0.5)
			(thermal_bridge_width 0.5)
			(island_removal_mode 0)
		)
		(polygon
			(pts
				(arc
					(start 303.26965 -383.290064)
					(mid 302.51019 -383.290064)
					(end 303.26965 -383.290064)
				)
			)
		)
	)
	(zone
		(layers "B.Cu" "In7.Cu" "In9.Cu" "In11.Cu" "In13.Cu" "In15.Cu")
		(hatch none 0.5)
		(connect_pads
			(clearance 0)
		)
		(min_thickness 0.25)
		(keepout
			(tracks not_allowed)
			(vias allowed)
			(pads allowed)
			(copperpour not_allowed)
			(footprints allowed)
		)
		(placement
			(enabled no)
			(sheetname "")
		)
		(fill yes
			(thermal_gap 0.5)
			(thermal_bridge_width 0.5)
			(island_removal_mode 0)
		)
		(polygon
			(pts
				(arc
					(start 430.869598 -380.69012)
					(mid 430.110138 -380.69012)
					(end 430.869598 -380.69012)
				)
			)
		)
	)
	(zone
		(layers "B.Cu" "In7.Cu" "In9.Cu" "In11.Cu" "In13.Cu" "In15.Cu")
		(hatch none 0.5)
		(connect_pads
			(clearance 0)
		)
		(min_thickness 0.25)
		(keepout
			(tracks not_allowed)
			(vias allowed)
			(pads allowed)
			(copperpour not_allowed)
			(footprints allowed)
		)
		(placement
			(enabled no)
			(sheetname "")
		)
		(fill yes
			(thermal_gap 0.5)
			(thermal_bridge_width 0.5)
			(island_removal_mode 0)
		)
		(polygon
			(pts
				(arc
					(start 428.22622 -282.599892)
					(mid 427.57344 -282.599892)
					(end 428.22622 -282.599892)
				)
			)
		)
	)
	(zone
		(layers "B.Cu" "In7.Cu" "In9.Cu" "In11.Cu" "In13.Cu" "In15.Cu")
		(hatch none 0.5)
		(connect_pads
			(clearance 0)
		)
		(min_thickness 0.25)
		(keepout
			(tracks not_allowed)
			(vias allowed)
			(pads allowed)
			(copperpour not_allowed)
			(footprints allowed)
		)
		(placement
			(enabled no)
			(sheetname "")
		)
		(fill yes
			(thermal_gap 0.5)
			(thermal_bridge_width 0.5)
			(island_removal_mode 0)
		)
		(polygon
			(pts
				(arc
					(start 430.126394 -304.449734)
					(mid 429.473614 -304.449734)
					(end 430.126394 -304.449734)
				)
			)
		)
	)
	(zone
		(layers "B.Cu" "In7.Cu" "In9.Cu" "In11.Cu" "In13.Cu" "In15.Cu")
		(hatch none 0.5)
		(connect_pads
			(clearance 0)
		)
		(min_thickness 0.25)
		(keepout
			(tracks not_allowed)
			(vias allowed)
			(pads allowed)
			(copperpour not_allowed)
			(footprints allowed)
		)
		(placement
			(enabled no)
			(sheetname "")
		)
		(fill yes
			(thermal_gap 0.5)
			(thermal_bridge_width 0.5)
			(island_removal_mode 0)
		)
		(polygon
			(pts
				(arc
					(start 295.025826 -274.999958)
					(mid 294.373046 -274.999958)
					(end 295.025826 -274.999958)
				)
			)
		)
	)
	(zone
		(layers "B.Cu" "In7.Cu" "In9.Cu" "In11.Cu" "In13.Cu" "In15.Cu")
		(hatch none 0.5)
		(connect_pads
			(clearance 0)
		)
		(min_thickness 0.25)
		(keepout
			(tracks not_allowed)
			(vias allowed)
			(pads allowed)
			(copperpour not_allowed)
			(footprints allowed)
		)
		(placement
			(enabled no)
			(sheetname "")
		)
		(fill yes
			(thermal_gap 0.5)
			(thermal_bridge_width 0.5)
			(island_removal_mode 0)
		)
		(polygon
			(pts
				(arc
					(start 68.525898 -274.999704)
					(mid 67.873118 -274.999704)
					(end 68.525898 -274.999704)
				)
			)
		)
	)
	(zone
		(layers "B.Cu" "In7.Cu" "In9.Cu" "In11.Cu" "In13.Cu" "In15.Cu")
		(hatch none 0.5)
		(connect_pads
			(clearance 0)
		)
		(min_thickness 0.25)
		(keepout
			(tracks not_allowed)
			(vias allowed)
			(pads allowed)
			(copperpour not_allowed)
			(footprints allowed)
		)
		(placement
			(enabled no)
			(sheetname "")
		)
		(fill yes
			(thermal_gap 0.5)
			(thermal_bridge_width 0.5)
			(island_removal_mode 0)
		)
		(polygon
			(pts
				(arc
					(start 400.89455 -111.912908)
					(mid 400.19097 -111.912908)
					(end 400.89455 -111.912908)
				)
			)
		)
	)
	(zone
		(layers "B.Cu" "In7.Cu" "In9.Cu" "In11.Cu" "In13.Cu" "In15.Cu")
		(hatch none 0.5)
		(connect_pads
			(clearance 0)
		)
		(min_thickness 0.25)
		(keepout
			(tracks not_allowed)
			(vias allowed)
			(pads allowed)
			(copperpour not_allowed)
			(footprints allowed)
		)
		(placement
			(enabled no)
			(sheetname "")
		)
		(fill yes
			(thermal_gap 0.5)
			(thermal_bridge_width 0.5)
			(island_removal_mode 0)
		)
		(polygon
			(pts
				(arc
					(start 424.42638 -315.849762)
					(mid 423.7736 -315.849762)
					(end 424.42638 -315.849762)
				)
			)
		)
	)
	(zone
		(layers "B.Cu" "In7.Cu" "In9.Cu" "In11.Cu" "In13.Cu" "In15.Cu")
		(hatch none 0.5)
		(connect_pads
			(clearance 0)
		)
		(min_thickness 0.25)
		(keepout
			(tracks not_allowed)
			(vias allowed)
			(pads allowed)
			(copperpour not_allowed)
			(footprints allowed)
		)
		(placement
			(enabled no)
			(sheetname "")
		)
		(fill yes
			(thermal_gap 0.5)
			(thermal_bridge_width 0.5)
			(island_removal_mode 0)
		)
		(polygon
			(pts
				(arc
					(start 170.548554 -134.896352)
					(mid 169.844974 -134.896352)
					(end 170.548554 -134.896352)
				)
			)
		)
	)
	(zone
		(layers "B.Cu" "In7.Cu" "In9.Cu" "In11.Cu" "In13.Cu" "In15.Cu")
		(hatch none 0.5)
		(connect_pads
			(clearance 0)
		)
		(min_thickness 0.25)
		(keepout
			(tracks not_allowed)
			(vias allowed)
			(pads allowed)
			(copperpour not_allowed)
			(footprints allowed)
		)
		(placement
			(enabled no)
			(sheetname "")
		)
		(fill yes
			(thermal_gap 0.5)
			(thermal_bridge_width 0.5)
			(island_removal_mode 0)
		)
		(polygon
			(pts
				(arc
					(start 303.26965 -410.589984)
					(mid 302.51019 -410.589984)
					(end 303.26965 -410.589984)
				)
			)
		)
	)
	(zone
		(layers "B.Cu" "In7.Cu" "In9.Cu" "In11.Cu" "In13.Cu" "In15.Cu")
		(hatch none 0.5)
		(connect_pads
			(clearance 0)
		)
		(min_thickness 0.25)
		(keepout
			(tracks not_allowed)
			(vias allowed)
			(pads allowed)
			(copperpour not_allowed)
			(footprints allowed)
		)
		(placement
			(enabled no)
			(sheetname "")
		)
		(fill yes
			(thermal_gap 0.5)
			(thermal_bridge_width 0.5)
			(island_removal_mode 0)
		)
		(polygon
			(pts
				(arc
					(start 183.508904 -122.30354)
					(mid 182.805324 -122.30354)
					(end 183.508904 -122.30354)
				)
			)
		)
	)
	(zone
		(layers "B.Cu" "In7.Cu" "In9.Cu" "In11.Cu" "In13.Cu" "In15.Cu")
		(hatch none 0.5)
		(connect_pads
			(clearance 0)
		)
		(min_thickness 0.25)
		(keepout
			(tracks not_allowed)
			(vias allowed)
			(pads allowed)
			(copperpour not_allowed)
			(footprints allowed)
		)
		(placement
			(enabled no)
			(sheetname "")
		)
		(fill yes
			(thermal_gap 0.5)
			(thermal_bridge_width 0.5)
			(island_removal_mode 0)
		)
		(polygon
			(pts
				(arc
					(start 290.069524 -410.589984)
					(mid 289.310064 -410.589984)
					(end 290.069524 -410.589984)
				)
			)
		)
	)
	(zone
		(layers "B.Cu" "In7.Cu" "In9.Cu" "In11.Cu" "In13.Cu" "In15.Cu")
		(hatch none 0.5)
		(connect_pads
			(clearance 0)
		)
		(min_thickness 0.25)
		(keepout
			(tracks not_allowed)
			(vias allowed)
			(pads allowed)
			(copperpour not_allowed)
			(footprints allowed)
		)
		(placement
			(enabled no)
			(sheetname "")
		)
		(fill yes
			(thermal_gap 0.5)
			(thermal_bridge_width 0.5)
			(island_removal_mode 0)
		)
		(polygon
			(pts
				(arc
					(start 299.609002 -134.377176)
					(mid 298.905422 -134.377176)
					(end 299.609002 -134.377176)
				)
			)
		)
	)
	(zone
		(layers "B.Cu" "In7.Cu" "In9.Cu" "In11.Cu" "In13.Cu" "In15.Cu")
		(hatch none 0.5)
		(connect_pads
			(clearance 0)
		)
		(min_thickness 0.25)
		(keepout
			(tracks not_allowed)
			(vias allowed)
			(pads allowed)
			(copperpour not_allowed)
			(footprints allowed)
		)
		(placement
			(enabled no)
			(sheetname "")
		)
		(fill yes
			(thermal_gap 0.5)
			(thermal_bridge_width 0.5)
			(island_removal_mode 0)
		)
		(polygon
			(pts
				(arc
					(start 389.06958 -396.49019)
					(mid 388.31012 -396.49019)
					(end 389.06958 -396.49019)
				)
			)
		)
	)
	(zone
		(layers "B.Cu" "In7.Cu" "In9.Cu" "In11.Cu" "In13.Cu" "In15.Cu")
		(hatch none 0.5)
		(connect_pads
			(clearance 0)
		)
		(min_thickness 0.25)
		(keepout
			(tracks not_allowed)
			(vias allowed)
			(pads allowed)
			(copperpour not_allowed)
			(footprints allowed)
		)
		(placement
			(enabled no)
			(sheetname "")
		)
		(fill yes
			(thermal_gap 0.5)
			(thermal_bridge_width 0.5)
			(island_removal_mode 0)
		)
		(polygon
			(pts
				(arc
					(start 311.60466 18.460212)
					(mid 310.90108 18.460212)
					(end 311.60466 18.460212)
				)
			)
		)
	)
	(zone
		(layers "B.Cu" "In7.Cu" "In9.Cu" "In11.Cu" "In13.Cu" "In15.Cu")
		(hatch none 0.5)
		(connect_pads
			(clearance 0)
		)
		(min_thickness 0.25)
		(keepout
			(tracks not_allowed)
			(vias allowed)
			(pads allowed)
			(copperpour not_allowed)
			(footprints allowed)
		)
		(placement
			(enabled no)
			(sheetname "")
		)
		(fill yes
			(thermal_gap 0.5)
			(thermal_bridge_width 0.5)
			(island_removal_mode 0)
		)
		(polygon
			(pts
				(arc
					(start 191.276478 -317.749936)
					(mid 190.623698 -317.749936)
					(end 191.276478 -317.749936)
				)
			)
		)
	)
	(zone
		(layers "B.Cu" "In7.Cu" "In9.Cu" "In11.Cu" "In13.Cu" "In15.Cu")
		(hatch none 0.5)
		(connect_pads
			(clearance 0)
		)
		(min_thickness 0.25)
		(keepout
			(tracks not_allowed)
			(vias allowed)
			(pads allowed)
			(copperpour not_allowed)
			(footprints allowed)
		)
		(placement
			(enabled no)
			(sheetname "")
		)
		(fill yes
			(thermal_gap 0.5)
			(thermal_bridge_width 0.5)
			(island_removal_mode 0)
		)
		(polygon
			(pts
				(arc
					(start 168.694354 -108.312712)
					(mid 167.990774 -108.312712)
					(end 168.694354 -108.312712)
				)
			)
		)
	)
	(zone
		(layers "B.Cu" "In7.Cu" "In9.Cu" "In11.Cu" "In13.Cu" "In15.Cu")
		(hatch none 0.5)
		(connect_pads
			(clearance 0)
		)
		(min_thickness 0.25)
		(keepout
			(tracks not_allowed)
			(vias allowed)
			(pads allowed)
			(copperpour not_allowed)
			(footprints allowed)
		)
		(placement
			(enabled no)
			(sheetname "")
		)
		(fill yes
			(thermal_gap 0.5)
			(thermal_bridge_width 0.5)
			(island_removal_mode 0)
		)
		(polygon
			(pts
				(arc
					(start 52.59451 -133.096508)
					(mid 51.89093 -133.096508)
					(end 52.59451 -133.096508)
				)
			)
		)
	)
	(zone
		(layers "B.Cu" "In7.Cu" "In9.Cu" "In11.Cu" "In13.Cu" "In15.Cu")
		(hatch none 0.5)
		(connect_pads
			(clearance 0)
		)
		(min_thickness 0.25)
		(keepout
			(tracks not_allowed)
			(vias allowed)
			(pads allowed)
			(copperpour not_allowed)
			(footprints allowed)
		)
		(placement
			(enabled no)
			(sheetname "")
		)
		(fill yes
			(thermal_gap 0.5)
			(thermal_bridge_width 0.5)
			(island_removal_mode 0)
		)
		(polygon
			(pts
				(arc
					(start 32.6898 -408.190192)
					(mid 31.93034 -408.190192)
					(end 32.6898 -408.190192)
				)
			)
		)
	)
	(zone
		(layers "B.Cu" "In7.Cu" "In9.Cu" "In11.Cu" "In13.Cu" "In15.Cu")
		(hatch none 0.5)
		(connect_pads
			(clearance 0)
		)
		(min_thickness 0.25)
		(keepout
			(tracks not_allowed)
			(vias allowed)
			(pads allowed)
			(copperpour not_allowed)
			(footprints allowed)
		)
		(placement
			(enabled no)
			(sheetname "")
		)
		(fill yes
			(thermal_gap 0.5)
			(thermal_bridge_width 0.5)
			(island_removal_mode 0)
		)
		(polygon
			(pts
				(arc
					(start 300.726094 -316.799722)
					(mid 300.073314 -316.799722)
					(end 300.726094 -316.799722)
				)
			)
		)
	)
	(zone
		(layers "B.Cu" "In7.Cu" "In9.Cu" "In11.Cu" "In13.Cu" "In15.Cu")
		(hatch none 0.5)
		(connect_pads
			(clearance 0)
		)
		(min_thickness 0.25)
		(keepout
			(tracks not_allowed)
			(vias allowed)
			(pads allowed)
			(copperpour not_allowed)
			(footprints allowed)
		)
		(placement
			(enabled no)
			(sheetname "")
		)
		(fill yes
			(thermal_gap 0.5)
			(thermal_bridge_width 0.5)
			(island_removal_mode 0)
		)
		(polygon
			(pts
				(arc
					(start 173.226476 -315.849762)
					(mid 172.573696 -315.849762)
					(end 173.226476 -315.849762)
				)
			)
		)
	)
	(zone
		(layers "B.Cu" "In7.Cu" "In9.Cu" "In11.Cu" "In13.Cu" "In15.Cu")
		(hatch none 0.5)
		(connect_pads
			(clearance 0)
		)
		(min_thickness 0.25)
		(keepout
			(tracks not_allowed)
			(vias allowed)
			(pads allowed)
			(copperpour not_allowed)
			(footprints allowed)
		)
		(placement
			(enabled no)
			(sheetname "")
		)
		(fill yes
			(thermal_gap 0.5)
			(thermal_bridge_width 0.5)
			(island_removal_mode 0)
		)
		(polygon
			(pts
				(arc
					(start 52.59451 -101.976428)
					(mid 51.89093 -101.976428)
					(end 52.59451 -101.976428)
				)
			)
		)
	)
	(zone
		(layers "B.Cu" "In7.Cu" "In9.Cu" "In11.Cu" "In13.Cu" "In15.Cu")
		(hatch none 0.5)
		(connect_pads
			(clearance 0)
		)
		(min_thickness 0.25)
		(keepout
			(tracks not_allowed)
			(vias allowed)
			(pads allowed)
			(copperpour not_allowed)
			(footprints allowed)
		)
		(placement
			(enabled no)
			(sheetname "")
		)
		(fill yes
			(thermal_gap 0.5)
			(thermal_bridge_width 0.5)
			(island_removal_mode 0)
		)
		(polygon
			(pts
				(arc
					(start 196.976238 -309.199788)
					(mid 196.323458 -309.199788)
					(end 196.976238 -309.199788)
				)
			)
		)
	)
	(zone
		(layers "B.Cu" "In7.Cu" "In9.Cu" "In11.Cu" "In13.Cu" "In15.Cu")
		(hatch none 0.5)
		(connect_pads
			(clearance 0)
		)
		(min_thickness 0.25)
		(keepout
			(tracks not_allowed)
			(vias allowed)
			(pads allowed)
			(copperpour not_allowed)
			(footprints allowed)
		)
		(placement
			(enabled no)
			(sheetname "")
		)
		(fill yes
			(thermal_gap 0.5)
			(thermal_bridge_width 0.5)
			(island_removal_mode 0)
		)
		(polygon
			(pts
				(arc
					(start 75.176126 -273.099784)
					(mid 74.523346 -273.099784)
					(end 75.176126 -273.099784)
				)
			)
		)
	)
	(zone
		(layers "B.Cu" "In7.Cu" "In9.Cu" "In11.Cu" "In13.Cu" "In15.Cu")
		(hatch none 0.5)
		(connect_pads
			(clearance 0)
		)
		(min_thickness 0.25)
		(keepout
			(tracks not_allowed)
			(vias allowed)
			(pads allowed)
			(copperpour not_allowed)
			(footprints allowed)
		)
		(placement
			(enabled no)
			(sheetname "")
		)
		(fill yes
			(thermal_gap 0.5)
			(thermal_bridge_width 0.5)
			(island_removal_mode 0)
		)
		(polygon
			(pts
				(arc
					(start 428.22622 -286.399732)
					(mid 427.57344 -286.399732)
					(end 428.22622 -286.399732)
				)
			)
		)
	)
	(zone
		(layers "B.Cu" "In7.Cu" "In9.Cu" "In11.Cu" "In13.Cu" "In15.Cu")
		(hatch none 0.5)
		(connect_pads
			(clearance 0)
		)
		(min_thickness 0.25)
		(keepout
			(tracks not_allowed)
			(vias allowed)
			(pads allowed)
			(copperpour not_allowed)
			(footprints allowed)
		)
		(placement
			(enabled no)
			(sheetname "")
		)
		(fill yes
			(thermal_gap 0.5)
			(thermal_bridge_width 0.5)
			(island_removal_mode 0)
		)
		(polygon
			(pts
				(arc
					(start 286.648652 -131.29641)
					(mid 285.945072 -131.29641)
					(end 286.648652 -131.29641)
				)
			)
		)
	)
	(zone
		(layers "B.Cu" "In7.Cu" "In9.Cu" "In11.Cu" "In13.Cu" "In15.Cu")
		(hatch none 0.5)
		(connect_pads
			(clearance 0)
		)
		(min_thickness 0.25)
		(keepout
			(tracks not_allowed)
			(vias allowed)
			(pads allowed)
			(copperpour not_allowed)
			(footprints allowed)
		)
		(placement
			(enabled no)
			(sheetname "")
		)
		(fill yes
			(thermal_gap 0.5)
			(thermal_bridge_width 0.5)
			(island_removal_mode 0)
		)
		(polygon
			(pts
				(arc
					(start 416.825938 -274.999704)
					(mid 416.173158 -274.999704)
					(end 416.825938 -274.999704)
				)
			)
		)
	)
	(zone
		(layers "B.Cu" "In7.Cu" "In9.Cu" "In11.Cu" "In13.Cu" "In15.Cu")
		(hatch none 0.5)
		(connect_pads
			(clearance 0)
		)
		(min_thickness 0.25)
		(keepout
			(tracks not_allowed)
			(vias allowed)
			(pads allowed)
			(copperpour not_allowed)
			(footprints allowed)
		)
		(placement
			(enabled no)
			(sheetname "")
		)
		(fill yes
			(thermal_gap 0.5)
			(thermal_bridge_width 0.5)
			(island_removal_mode 0)
		)
		(polygon
			(pts
				(arc
					(start 181.654704 -120.503696)
					(mid 180.951124 -120.503696)
					(end 181.654704 -120.503696)
				)
			)
		)
	)
	(zone
		(layers "B.Cu" "In7.Cu" "In9.Cu" "In11.Cu" "In13.Cu" "In15.Cu")
		(hatch none 0.5)
		(connect_pads
			(clearance 0)
		)
		(min_thickness 0.25)
		(keepout
			(tracks not_allowed)
			(vias allowed)
			(pads allowed)
			(copperpour not_allowed)
			(footprints allowed)
		)
		(placement
			(enabled no)
			(sheetname "")
		)
		(fill yes
			(thermal_gap 0.5)
			(thermal_bridge_width 0.5)
			(island_removal_mode 0)
		)
		(polygon
			(pts
				(arc
					(start 30.489652 -384.590036)
					(mid 29.730192 -384.590036)
					(end 30.489652 -384.590036)
				)
			)
		)
	)
	(zone
		(layers "B.Cu" "In7.Cu" "In9.Cu" "In11.Cu" "In13.Cu" "In15.Cu")
		(hatch none 0.5)
		(connect_pads
			(clearance 0)
		)
		(min_thickness 0.25)
		(keepout
			(tracks not_allowed)
			(vias allowed)
			(pads allowed)
			(copperpour not_allowed)
			(footprints allowed)
		)
		(placement
			(enabled no)
			(sheetname "")
		)
		(fill yes
			(thermal_gap 0.5)
			(thermal_bridge_width 0.5)
			(island_removal_mode 0)
		)
		(polygon
			(pts
				(arc
					(start 386.869686 -398.890236)
					(mid 386.110226 -398.890236)
					(end 386.869686 -398.890236)
				)
			)
		)
	)
	(zone
		(layers "B.Cu" "In7.Cu" "In9.Cu" "In11.Cu" "In13.Cu" "In15.Cu")
		(hatch none 0.5)
		(connect_pads
			(clearance 0)
		)
		(min_thickness 0.25)
		(keepout
			(tracks not_allowed)
			(vias allowed)
			(pads allowed)
			(copperpour not_allowed)
			(footprints allowed)
		)
		(placement
			(enabled no)
			(sheetname "")
		)
		(fill yes
			(thermal_gap 0.5)
			(thermal_bridge_width 0.5)
			(island_removal_mode 0)
		)
		(polygon
			(pts
				(arc
					(start 196.976238 -284.499812)
					(mid 196.323458 -284.499812)
					(end 196.976238 -284.499812)
				)
			)
		)
	)
	(zone
		(layers "B.Cu" "In7.Cu" "In9.Cu" "In11.Cu" "In13.Cu" "In15.Cu")
		(hatch none 0.5)
		(connect_pads
			(clearance 0)
		)
		(min_thickness 0.25)
		(keepout
			(tracks not_allowed)
			(vias allowed)
			(pads allowed)
			(copperpour not_allowed)
			(footprints allowed)
		)
		(placement
			(enabled no)
			(sheetname "")
		)
		(fill yes
			(thermal_gap 0.5)
			(thermal_bridge_width 0.5)
			(island_removal_mode 0)
		)
		(polygon
			(pts
				(arc
					(start 82.776314 -274.999704)
					(mid 82.123534 -274.999704)
					(end 82.776314 -274.999704)
				)
			)
		)
	)
	(zone
		(layers "B.Cu" "In7.Cu" "In9.Cu" "In11.Cu" "In13.Cu" "In15.Cu")
		(hatch none 0.5)
		(connect_pads
			(clearance 0)
		)
		(min_thickness 0.25)
		(keepout
			(tracks not_allowed)
			(vias allowed)
			(pads allowed)
			(copperpour not_allowed)
			(footprints allowed)
		)
		(placement
			(enabled no)
			(sheetname "")
		)
		(fill yes
			(thermal_gap 0.5)
			(thermal_bridge_width 0.5)
			(island_removal_mode 0)
		)
		(polygon
			(pts
				(arc
					(start 272.226278 -309.199788)
					(mid 271.573498 -309.199788)
					(end 272.226278 -309.199788)
				)
			)
		)
	)
	(zone
		(layers "B.Cu" "In7.Cu" "In9.Cu" "In11.Cu" "In13.Cu" "In15.Cu")
		(hatch none 0.5)
		(connect_pads
			(clearance 0)
		)
		(min_thickness 0.25)
		(keepout
			(tracks not_allowed)
			(vias allowed)
			(pads allowed)
			(copperpour not_allowed)
			(footprints allowed)
		)
		(placement
			(enabled no)
			(sheetname "")
		)
		(fill yes
			(thermal_gap 0.5)
			(thermal_bridge_width 0.5)
			(island_removal_mode 0)
		)
		(polygon
			(pts
				(arc
					(start 181.776116 -273.099784)
					(mid 181.123336 -273.099784)
					(end 181.776116 -273.099784)
				)
			)
		)
	)
	(zone
		(layers "B.Cu" "In7.Cu" "In9.Cu" "In11.Cu" "In13.Cu" "In15.Cu")
		(hatch none 0.5)
		(connect_pads
			(clearance 0)
		)
		(min_thickness 0.25)
		(keepout
			(tracks not_allowed)
			(vias allowed)
			(pads allowed)
			(copperpour not_allowed)
			(footprints allowed)
		)
		(placement
			(enabled no)
			(sheetname "")
		)
		(fill yes
			(thermal_gap 0.5)
			(thermal_bridge_width 0.5)
			(island_removal_mode 0)
		)
		(polygon
			(pts
				(arc
					(start 67.576192 -318.699896)
					(mid 66.923412 -318.699896)
					(end 67.576192 -318.699896)
				)
			)
		)
	)
	(zone
		(layers "B.Cu" "In7.Cu" "In9.Cu" "In11.Cu" "In13.Cu" "In15.Cu")
		(hatch none 0.5)
		(connect_pads
			(clearance 0)
		)
		(min_thickness 0.25)
		(keepout
			(tracks not_allowed)
			(vias allowed)
			(pads allowed)
			(copperpour not_allowed)
			(footprints allowed)
		)
		(placement
			(enabled no)
			(sheetname "")
		)
		(fill yes
			(thermal_gap 0.5)
			(thermal_bridge_width 0.5)
			(island_removal_mode 0)
		)
		(polygon
			(pts
				(arc
					(start 296.669714 -382.18999)
					(mid 295.910254 -382.18999)
					(end 296.669714 -382.18999)
				)
			)
		)
	)
	(zone
		(layers "B.Cu" "In7.Cu" "In9.Cu" "In11.Cu" "In13.Cu" "In15.Cu")
		(hatch none 0.5)
		(connect_pads
			(clearance 0)
		)
		(min_thickness 0.25)
		(keepout
			(tracks not_allowed)
			(vias allowed)
			(pads allowed)
			(copperpour not_allowed)
			(footprints allowed)
		)
		(placement
			(enabled no)
			(sheetname "")
		)
		(fill yes
			(thermal_gap 0.5)
			(thermal_bridge_width 0.5)
			(island_removal_mode 0)
		)
		(polygon
			(pts
				(arc
					(start 286.648652 -103.776272)
					(mid 285.945072 -103.776272)
					(end 286.648652 -103.776272)
				)
			)
		)
	)
	(zone
		(layers "B.Cu" "In7.Cu" "In9.Cu" "In11.Cu" "In13.Cu" "In15.Cu")
		(hatch none 0.5)
		(connect_pads
			(clearance 0)
		)
		(min_thickness 0.25)
		(keepout
			(tracks not_allowed)
			(vias allowed)
			(pads allowed)
			(copperpour not_allowed)
			(footprints allowed)
		)
		(placement
			(enabled no)
			(sheetname "")
		)
		(fill yes
			(thermal_gap 0.5)
			(thermal_bridge_width 0.5)
			(island_removal_mode 0)
		)
		(polygon
			(pts
				(arc
					(start 40.026336 -316.799722)
					(mid 39.373556 -316.799722)
					(end 40.026336 -316.799722)
				)
			)
		)
	)
	(zone
		(layers "B.Cu" "In7.Cu" "In9.Cu" "In11.Cu" "In13.Cu" "In15.Cu")
		(hatch none 0.5)
		(connect_pads
			(clearance 0)
		)
		(min_thickness 0.25)
		(keepout
			(tracks not_allowed)
			(vias allowed)
			(pads allowed)
			(copperpour not_allowed)
			(footprints allowed)
		)
		(placement
			(enabled no)
			(sheetname "")
		)
		(fill yes
			(thermal_gap 0.5)
			(thermal_bridge_width 0.5)
			(island_removal_mode 0)
		)
		(polygon
			(pts
				(arc
					(start 65.55486 -120.503696)
					(mid 64.85128 -120.503696)
					(end 65.55486 -120.503696)
				)
			)
		)
	)
	(zone
		(layers "B.Cu" "In7.Cu" "In9.Cu" "In11.Cu" "In13.Cu" "In15.Cu")
		(hatch none 0.5)
		(connect_pads
			(clearance 0)
		)
		(min_thickness 0.25)
		(keepout
			(tracks not_allowed)
			(vias allowed)
			(pads allowed)
			(copperpour not_allowed)
			(footprints allowed)
		)
		(placement
			(enabled no)
			(sheetname "")
		)
		(fill yes
			(thermal_gap 0.5)
			(thermal_bridge_width 0.5)
			(island_removal_mode 0)
		)
		(polygon
			(pts
				(arc
					(start 375.869708 -375.69013)
					(mid 375.110248 -375.69013)
					(end 375.869708 -375.69013)
				)
			)
		)
	)
	(zone
		(layers "B.Cu" "In7.Cu" "In9.Cu" "In11.Cu" "In13.Cu" "In15.Cu")
		(hatch none 0.5)
		(connect_pads
			(clearance 0)
		)
		(min_thickness 0.25)
		(keepout
			(tracks not_allowed)
			(vias allowed)
			(pads allowed)
			(copperpour not_allowed)
			(footprints allowed)
		)
		(placement
			(enabled no)
			(sheetname "")
		)
		(fill yes
			(thermal_gap 0.5)
			(thermal_bridge_width 0.5)
			(island_removal_mode 0)
		)
		(polygon
			(pts
				(arc
					(start 41.48963 -409.490164)
					(mid 40.73017 -409.490164)
					(end 41.48963 -409.490164)
				)
			)
		)
	)
	(zone
		(layers "B.Cu" "In7.Cu" "In9.Cu" "In11.Cu" "In13.Cu" "In15.Cu")
		(hatch none 0.5)
		(connect_pads
			(clearance 0)
		)
		(min_thickness 0.25)
		(keepout
			(tracks not_allowed)
			(vias allowed)
			(pads allowed)
			(copperpour not_allowed)
			(footprints allowed)
		)
		(placement
			(enabled no)
			(sheetname "")
		)
		(fill yes
			(thermal_gap 0.5)
			(thermal_bridge_width 0.5)
			(island_removal_mode 0)
		)
		(polygon
			(pts
				(arc
					(start 413.8549 -136.177274)
					(mid 413.15132 -136.177274)
					(end 413.8549 -136.177274)
				)
			)
		)
	)
	(zone
		(layers "B.Cu" "In7.Cu" "In9.Cu" "In11.Cu" "In13.Cu" "In15.Cu")
		(hatch none 0.5)
		(connect_pads
			(clearance 0)
		)
		(min_thickness 0.25)
		(keepout
			(tracks not_allowed)
			(vias allowed)
			(pads allowed)
			(copperpour not_allowed)
			(footprints allowed)
		)
		(placement
			(enabled no)
			(sheetname "")
		)
		(fill yes
			(thermal_gap 0.5)
			(thermal_bridge_width 0.5)
			(island_removal_mode 0)
		)
		(polygon
			(pts
				(arc
					(start 402.576284 -318.699896)
					(mid 401.923504 -318.699896)
					(end 402.576284 -318.699896)
				)
			)
		)
	)
	(zone
		(layers "B.Cu" "In7.Cu" "In9.Cu" "In11.Cu" "In13.Cu" "In15.Cu")
		(hatch none 0.5)
		(connect_pads
			(clearance 0)
		)
		(min_thickness 0.25)
		(keepout
			(tracks not_allowed)
			(vias allowed)
			(pads allowed)
			(copperpour not_allowed)
			(footprints allowed)
		)
		(placement
			(enabled no)
			(sheetname "")
		)
		(fill yes
			(thermal_gap 0.5)
			(thermal_bridge_width 0.5)
			(island_removal_mode 0)
		)
		(polygon
			(pts
				(arc
					(start 314.026296 -281.649932)
					(mid 313.373516 -281.649932)
					(end 314.026296 -281.649932)
				)
			)
		)
	)
	(zone
		(layers "B.Cu" "In7.Cu" "In9.Cu" "In11.Cu" "In13.Cu" "In15.Cu")
		(hatch none 0.5)
		(connect_pads
			(clearance 0)
		)
		(min_thickness 0.25)
		(keepout
			(tracks not_allowed)
			(vias allowed)
			(pads allowed)
			(copperpour not_allowed)
			(footprints allowed)
		)
		(placement
			(enabled no)
			(sheetname "")
		)
		(fill yes
			(thermal_gap 0.5)
			(thermal_bridge_width 0.5)
			(island_removal_mode 0)
		)
		(polygon
			(pts
				(arc
					(start 284.794452 -111.912908)
					(mid 284.090872 -111.912908)
					(end 284.794452 -111.912908)
				)
			)
		)
	)
	(zone
		(layers "B.Cu" "In7.Cu" "In9.Cu" "In11.Cu" "In13.Cu" "In15.Cu")
		(hatch none 0.5)
		(connect_pads
			(clearance 0)
		)
		(min_thickness 0.25)
		(keepout
			(tracks not_allowed)
			(vias allowed)
			(pads allowed)
			(copperpour not_allowed)
			(footprints allowed)
		)
		(placement
			(enabled no)
			(sheetname "")
		)
		(fill yes
			(thermal_gap 0.5)
			(thermal_bridge_width 0.5)
			(island_removal_mode 0)
		)
		(polygon
			(pts
				(arc
					(start 286.648652 -110.11281)
					(mid 285.945072 -110.11281)
					(end 286.648652 -110.11281)
				)
			)
		)
	)
	(zone
		(layers "B.Cu" "In7.Cu" "In9.Cu" "In11.Cu" "In13.Cu" "In15.Cu")
		(hatch none 0.5)
		(connect_pads
			(clearance 0)
		)
		(min_thickness 0.25)
		(keepout
			(tracks not_allowed)
			(vias allowed)
			(pads allowed)
			(copperpour not_allowed)
			(footprints allowed)
		)
		(placement
			(enabled no)
			(sheetname "")
		)
		(fill yes
			(thermal_gap 0.5)
			(thermal_bridge_width 0.5)
			(island_removal_mode 0)
		)
		(polygon
			(pts
				(arc
					(start 400.676364 -317.749936)
					(mid 400.023584 -317.749936)
					(end 400.676364 -317.749936)
				)
			)
		)
	)
	(zone
		(layers "B.Cu" "In7.Cu" "In9.Cu" "In11.Cu" "In13.Cu" "In15.Cu")
		(hatch none 0.5)
		(connect_pads
			(clearance 0)
		)
		(min_thickness 0.25)
		(keepout
			(tracks not_allowed)
			(vias allowed)
			(pads allowed)
			(copperpour not_allowed)
			(footprints allowed)
		)
		(placement
			(enabled no)
			(sheetname "")
		)
		(fill yes
			(thermal_gap 0.5)
			(thermal_bridge_width 0.5)
			(island_removal_mode 0)
		)
		(polygon
			(pts
				(arc
					(start 429.175926 -274.049744)
					(mid 428.523146 -274.049744)
					(end 429.175926 -274.049744)
				)
			)
		)
	)
	(zone
		(layers "B.Cu" "In7.Cu" "In9.Cu" "In11.Cu" "In13.Cu" "In15.Cu")
		(hatch none 0.5)
		(connect_pads
			(clearance 0)
		)
		(min_thickness 0.25)
		(keepout
			(tracks not_allowed)
			(vias allowed)
			(pads allowed)
			(copperpour not_allowed)
			(footprints allowed)
		)
		(placement
			(enabled no)
			(sheetname "")
		)
		(fill yes
			(thermal_gap 0.5)
			(thermal_bridge_width 0.5)
			(island_removal_mode 0)
		)
		(polygon
			(pts
				(arc
					(start 304.525934 -275.949664)
					(mid 303.873154 -275.949664)
					(end 304.525934 -275.949664)
				)
			)
		)
	)
	(zone
		(layers "B.Cu" "In7.Cu" "In9.Cu" "In11.Cu" "In13.Cu" "In15.Cu")
		(hatch none 0.5)
		(connect_pads
			(clearance 0)
		)
		(min_thickness 0.25)
		(keepout
			(tracks not_allowed)
			(vias allowed)
			(pads allowed)
			(copperpour not_allowed)
			(footprints allowed)
		)
		(placement
			(enabled no)
			(sheetname "")
		)
		(fill yes
			(thermal_gap 0.5)
			(thermal_bridge_width 0.5)
			(island_removal_mode 0)
		)
		(polygon
			(pts
				(arc
					(start 412.076392 -317.749936)
					(mid 411.423612 -317.749936)
					(end 412.076392 -317.749936)
				)
			)
		)
	)
	(zone
		(layers "B.Cu" "In7.Cu" "In9.Cu" "In11.Cu" "In13.Cu" "In15.Cu")
		(hatch none 0.5)
		(connect_pads
			(clearance 0)
		)
		(min_thickness 0.25)
		(keepout
			(tracks not_allowed)
			(vias allowed)
			(pads allowed)
			(copperpour not_allowed)
			(footprints allowed)
		)
		(placement
			(enabled no)
			(sheetname "")
		)
		(fill yes
			(thermal_gap 0.5)
			(thermal_bridge_width 0.5)
			(island_removal_mode 0)
		)
		(polygon
			(pts
				(arc
					(start 69.476366 -317.749936)
					(mid 68.823586 -317.749936)
					(end 69.476366 -317.749936)
				)
			)
		)
	)
	(zone
		(layers "B.Cu" "In7.Cu" "In9.Cu" "In11.Cu" "In13.Cu" "In15.Cu")
		(hatch none 0.5)
		(connect_pads
			(clearance 0)
		)
		(min_thickness 0.25)
		(keepout
			(tracks not_allowed)
			(vias allowed)
			(pads allowed)
			(copperpour not_allowed)
			(footprints allowed)
		)
		(placement
			(enabled no)
			(sheetname "")
		)
		(fill yes
			(thermal_gap 0.5)
			(thermal_bridge_width 0.5)
			(island_removal_mode 0)
		)
		(polygon
			(pts
				(arc
					(start 40.026336 -309.199788)
					(mid 39.373556 -309.199788)
					(end 40.026336 -309.199788)
				)
			)
		)
	)
	(zone
		(layers "B.Cu" "In7.Cu" "In9.Cu" "In11.Cu" "In13.Cu" "In15.Cu")
		(hatch none 0.5)
		(connect_pads
			(clearance 0)
		)
		(min_thickness 0.25)
		(keepout
			(tracks not_allowed)
			(vias allowed)
			(pads allowed)
			(copperpour not_allowed)
			(footprints allowed)
		)
		(placement
			(enabled no)
			(sheetname "")
		)
		(fill yes
			(thermal_gap 0.5)
			(thermal_bridge_width 0.5)
			(island_removal_mode 0)
		)
		(polygon
			(pts
				(arc
					(start 66.626232 -315.849762)
					(mid 65.973452 -315.849762)
					(end 66.626232 -315.849762)
				)
			)
		)
	)
	(zone
		(layers "B.Cu" "In7.Cu" "In9.Cu" "In11.Cu" "In13.Cu" "In15.Cu")
		(hatch none 0.5)
		(connect_pads
			(clearance 0)
		)
		(min_thickness 0.25)
		(keepout
			(tracks not_allowed)
			(vias allowed)
			(pads allowed)
			(copperpour not_allowed)
			(footprints allowed)
		)
		(placement
			(enabled no)
			(sheetname "")
		)
		(fill yes
			(thermal_gap 0.5)
			(thermal_bridge_width 0.5)
			(island_removal_mode 0)
		)
		(polygon
			(pts
				(arc
					(start 298.826174 -315.849762)
					(mid 298.173394 -315.849762)
					(end 298.826174 -315.849762)
				)
			)
		)
	)
	(zone
		(layers "B.Cu" "In7.Cu" "In9.Cu" "In11.Cu" "In13.Cu" "In15.Cu")
		(hatch none 0.5)
		(connect_pads
			(clearance 0)
		)
		(min_thickness 0.25)
		(keepout
			(tracks not_allowed)
			(vias allowed)
			(pads allowed)
			(copperpour not_allowed)
			(footprints allowed)
		)
		(placement
			(enabled no)
			(sheetname "")
		)
		(fill yes
			(thermal_gap 0.5)
			(thermal_bridge_width 0.5)
			(island_removal_mode 0)
		)
		(polygon
			(pts
				(arc
					(start 402.74875 -99.31273)
					(mid 402.04517 -99.31273)
					(end 402.74875 -99.31273)
				)
			)
		)
	)
	(zone
		(layers "B.Cu" "In7.Cu" "In9.Cu" "In11.Cu" "In13.Cu" "In15.Cu")
		(hatch none 0.5)
		(connect_pads
			(clearance 0)
		)
		(min_thickness 0.25)
		(keepout
			(tracks not_allowed)
			(vias allowed)
			(pads allowed)
			(copperpour not_allowed)
			(footprints allowed)
		)
		(placement
			(enabled no)
			(sheetname "")
		)
		(fill yes
			(thermal_gap 0.5)
			(thermal_bridge_width 0.5)
			(island_removal_mode 0)
		)
		(polygon
			(pts
				(arc
					(start 299.776134 -317.749936)
					(mid 299.123354 -317.749936)
					(end 299.776134 -317.749936)
				)
			)
		)
	)
	(zone
		(layers "B.Cu" "In7.Cu" "In9.Cu" "In11.Cu" "In13.Cu" "In15.Cu")
		(hatch none 0.5)
		(connect_pads
			(clearance 0)
		)
		(min_thickness 0.25)
		(keepout
			(tracks not_allowed)
			(vias allowed)
			(pads allowed)
			(copperpour not_allowed)
			(footprints allowed)
		)
		(placement
			(enabled no)
			(sheetname "")
		)
		(fill yes
			(thermal_gap 0.5)
			(thermal_bridge_width 0.5)
			(island_removal_mode 0)
		)
		(polygon
			(pts
				(arc
					(start 67.40906 -122.30354)
					(mid 66.70548 -122.30354)
					(end 67.40906 -122.30354)
				)
			)
		)
	)
	(zone
		(layers "B.Cu" "In7.Cu" "In9.Cu" "In11.Cu" "In13.Cu" "In15.Cu")
		(hatch none 0.5)
		(connect_pads
			(clearance 0)
		)
		(min_thickness 0.25)
		(keepout
			(tracks not_allowed)
			(vias allowed)
			(pads allowed)
			(copperpour not_allowed)
			(footprints allowed)
		)
		(placement
			(enabled no)
			(sheetname "")
		)
		(fill yes
			(thermal_gap 0.5)
			(thermal_bridge_width 0.5)
			(island_removal_mode 0)
		)
		(polygon
			(pts
				(arc
					(start 427.276006 -274.049744)
					(mid 426.623226 -274.049744)
					(end 427.276006 -274.049744)
				)
			)
		)
	)
	(zone
		(layers "B.Cu" "In7.Cu" "In9.Cu" "In11.Cu" "In13.Cu" "In15.Cu")
		(hatch none 0.5)
		(connect_pads
			(clearance 0)
		)
		(min_thickness 0.25)
		(keepout
			(tracks not_allowed)
			(vias allowed)
			(pads allowed)
			(copperpour not_allowed)
			(footprints allowed)
		)
		(placement
			(enabled no)
			(sheetname "")
		)
		(fill yes
			(thermal_gap 0.5)
			(thermal_bridge_width 0.5)
			(island_removal_mode 0)
		)
		(polygon
			(pts
				(arc
					(start 402.74875 -102.912672)
					(mid 402.04517 -102.912672)
					(end 402.74875 -102.912672)
				)
			)
		)
	)
	(zone
		(layers "B.Cu" "In7.Cu" "In9.Cu" "In11.Cu" "In13.Cu" "In15.Cu")
		(hatch none 0.5)
		(connect_pads
			(clearance 0)
		)
		(min_thickness 0.25)
		(keepout
			(tracks not_allowed)
			(vias allowed)
			(pads allowed)
			(copperpour not_allowed)
			(footprints allowed)
		)
		(placement
			(enabled no)
			(sheetname "")
		)
		(fill yes
			(thermal_gap 0.5)
			(thermal_bridge_width 0.5)
			(island_removal_mode 0)
		)
		(polygon
			(pts
				(arc
					(start 171.326302 -316.799722)
					(mid 170.673522 -316.799722)
					(end 171.326302 -316.799722)
				)
			)
		)
	)
	(zone
		(layers "B.Cu" "In7.Cu" "In9.Cu" "In11.Cu" "In13.Cu" "In15.Cu")
		(hatch none 0.5)
		(connect_pads
			(clearance 0)
		)
		(min_thickness 0.25)
		(keepout
			(tracks not_allowed)
			(vias allowed)
			(pads allowed)
			(copperpour not_allowed)
			(footprints allowed)
		)
		(placement
			(enabled no)
			(sheetname "")
		)
		(fill yes
			(thermal_gap 0.5)
			(thermal_bridge_width 0.5)
			(island_removal_mode 0)
		)
		(polygon
			(pts
				(arc
					(start 66.625978 -274.999958)
					(mid 65.973198 -274.999958)
					(end 66.625978 -274.999958)
				)
			)
		)
	)
	(zone
		(layers "B.Cu" "In7.Cu" "In9.Cu" "In11.Cu" "In13.Cu" "In15.Cu")
		(hatch none 0.5)
		(connect_pads
			(clearance 0)
		)
		(min_thickness 0.25)
		(keepout
			(tracks not_allowed)
			(vias allowed)
			(pads allowed)
			(copperpour not_allowed)
			(footprints allowed)
		)
		(placement
			(enabled no)
			(sheetname "")
		)
		(fill yes
			(thermal_gap 0.5)
			(thermal_bridge_width 0.5)
			(island_removal_mode 0)
		)
		(polygon
			(pts
				(arc
					(start 183.508904 -143.48714)
					(mid 182.805324 -143.48714)
					(end 183.508904 -143.48714)
				)
			)
		)
	)
	(zone
		(layers "B.Cu" "In7.Cu" "In9.Cu" "In11.Cu" "In13.Cu" "In15.Cu")
		(hatch none 0.5)
		(connect_pads
			(clearance 0)
		)
		(min_thickness 0.25)
		(keepout
			(tracks not_allowed)
			(vias allowed)
			(pads allowed)
			(copperpour not_allowed)
			(footprints allowed)
		)
		(placement
			(enabled no)
			(sheetname "")
		)
		(fill yes
			(thermal_gap 0.5)
			(thermal_bridge_width 0.5)
			(island_removal_mode 0)
		)
		(polygon
			(pts
				(arc
					(start 294.469566 -384.590036)
					(mid 293.710106 -384.590036)
					(end 294.469566 -384.590036)
				)
			)
		)
	)
	(zone
		(layers "B.Cu" "In7.Cu" "In9.Cu" "In11.Cu" "In13.Cu" "In15.Cu")
		(hatch none 0.5)
		(connect_pads
			(clearance 0)
		)
		(min_thickness 0.25)
		(keepout
			(tracks not_allowed)
			(vias allowed)
			(pads allowed)
			(copperpour not_allowed)
			(footprints allowed)
		)
		(placement
			(enabled no)
			(sheetname "")
		)
		(fill yes
			(thermal_gap 0.5)
			(thermal_bridge_width 0.5)
			(island_removal_mode 0)
		)
		(polygon
			(pts
				(arc
					(start 306.425854 -274.999958)
					(mid 305.773074 -274.999958)
					(end 306.425854 -274.999958)
				)
			)
		)
	)
	(zone
		(layers "B.Cu" "In7.Cu" "In9.Cu" "In11.Cu" "In13.Cu" "In15.Cu")
		(hatch none 0.5)
		(connect_pads
			(clearance 0)
		)
		(min_thickness 0.25)
		(keepout
			(tracks not_allowed)
			(vias allowed)
			(pads allowed)
			(copperpour not_allowed)
			(footprints allowed)
		)
		(placement
			(enabled no)
			(sheetname "")
		)
		(fill yes
			(thermal_gap 0.5)
			(thermal_bridge_width 0.5)
			(island_removal_mode 0)
		)
		(polygon
			(pts
				(arc
					(start 80.875886 -274.049744)
					(mid 80.223106 -274.049744)
					(end 80.875886 -274.049744)
				)
			)
		)
	)
	(zone
		(layers "B.Cu" "In7.Cu" "In9.Cu" "In11.Cu" "In13.Cu" "In15.Cu")
		(hatch none 0.5)
		(connect_pads
			(clearance 0)
		)
		(min_thickness 0.25)
		(keepout
			(tracks not_allowed)
			(vias allowed)
			(pads allowed)
			(copperpour not_allowed)
			(footprints allowed)
		)
		(placement
			(enabled no)
			(sheetname "")
		)
		(fill yes
			(thermal_gap 0.5)
			(thermal_bridge_width 0.5)
			(island_removal_mode 0)
		)
		(polygon
			(pts
				(arc
					(start 70.425818 -274.999958)
					(mid 69.773038 -274.999958)
					(end 70.425818 -274.999958)
				)
			)
		)
	)
	(zone
		(layers "B.Cu" "In7.Cu" "In9.Cu" "In11.Cu" "In13.Cu" "In15.Cu")
		(hatch none 0.5)
		(connect_pads
			(clearance 0)
		)
		(min_thickness 0.25)
		(keepout
			(tracks not_allowed)
			(vias allowed)
			(pads allowed)
			(copperpour not_allowed)
			(footprints allowed)
		)
		(placement
			(enabled no)
			(sheetname "")
		)
		(fill yes
			(thermal_gap 0.5)
			(thermal_bridge_width 0.5)
			(island_removal_mode 0)
		)
		(polygon
			(pts
				(arc
					(start 429.175926 -273.099784)
					(mid 428.523146 -273.099784)
					(end 429.175926 -273.099784)
				)
			)
		)
	)
	(zone
		(layers "B.Cu" "In7.Cu" "In9.Cu" "In11.Cu" "In13.Cu" "In15.Cu")
		(hatch none 0.5)
		(connect_pads
			(clearance 0)
		)
		(min_thickness 0.25)
		(keepout
			(tracks not_allowed)
			(vias allowed)
			(pads allowed)
			(copperpour not_allowed)
			(footprints allowed)
		)
		(placement
			(enabled no)
			(sheetname "")
		)
		(fill yes
			(thermal_gap 0.5)
			(thermal_bridge_width 0.5)
			(island_removal_mode 0)
		)
		(polygon
			(pts
				(arc
					(start 43.689778 -384.590036)
					(mid 42.930318 -384.590036)
					(end 43.689778 -384.590036)
				)
			)
		)
	)
	(zone
		(layers "B.Cu" "In7.Cu" "In9.Cu" "In11.Cu" "In13.Cu" "In15.Cu")
		(hatch none 0.5)
		(connect_pads
			(clearance 0)
		)
		(min_thickness 0.25)
		(keepout
			(tracks not_allowed)
			(vias allowed)
			(pads allowed)
			(copperpour not_allowed)
			(footprints allowed)
		)
		(placement
			(enabled no)
			(sheetname "")
		)
		(fill yes
			(thermal_gap 0.5)
			(thermal_bridge_width 0.5)
			(island_removal_mode 0)
		)
		(polygon
			(pts
				(arc
					(start 340.66988 -370.489988)
					(mid 339.91042 -370.489988)
					(end 340.66988 -370.489988)
				)
			)
		)
	)
	(zone
		(layers "B.Cu" "In7.Cu" "In9.Cu" "In11.Cu" "In13.Cu" "In15.Cu")
		(hatch none 0.5)
		(connect_pads
			(clearance 0)
		)
		(min_thickness 0.25)
		(keepout
			(tracks not_allowed)
			(vias allowed)
			(pads allowed)
			(copperpour not_allowed)
			(footprints allowed)
		)
		(placement
			(enabled no)
			(sheetname "")
		)
		(fill yes
			(thermal_gap 0.5)
			(thermal_bridge_width 0.5)
			(island_removal_mode 0)
		)
		(polygon
			(pts
				(arc
					(start 196.026278 -316.799722)
					(mid 195.373498 -316.799722)
					(end 196.026278 -316.799722)
				)
			)
		)
	)
	(zone
		(layers "B.Cu" "In7.Cu" "In9.Cu" "In11.Cu" "In13.Cu" "In15.Cu")
		(hatch none 0.5)
		(connect_pads
			(clearance 0)
		)
		(min_thickness 0.25)
		(keepout
			(tracks not_allowed)
			(vias allowed)
			(pads allowed)
			(copperpour not_allowed)
			(footprints allowed)
		)
		(placement
			(enabled no)
			(sheetname "")
		)
		(fill yes
			(thermal_gap 0.5)
			(thermal_bridge_width 0.5)
			(island_removal_mode 0)
		)
		(polygon
			(pts
				(arc
					(start 407.326338 -315.849762)
					(mid 406.673558 -315.849762)
					(end 407.326338 -315.849762)
				)
			)
		)
	)
	(zone
		(layers "B.Cu" "In7.Cu" "In9.Cu" "In11.Cu" "In13.Cu" "In15.Cu")
		(hatch none 0.5)
		(connect_pads
			(clearance 0)
		)
		(min_thickness 0.25)
		(keepout
			(tracks not_allowed)
			(vias allowed)
			(pads allowed)
			(copperpour not_allowed)
			(footprints allowed)
		)
		(placement
			(enabled no)
			(sheetname "")
		)
		(fill yes
			(thermal_gap 0.5)
			(thermal_bridge_width 0.5)
			(island_removal_mode 0)
		)
		(polygon
			(pts
				(arc
					(start 415.7091 -119.567198)
					(mid 415.00552 -119.567198)
					(end 415.7091 -119.567198)
				)
			)
		)
	)
	(zone
		(layers "B.Cu" "In7.Cu" "In9.Cu" "In11.Cu" "In13.Cu" "In15.Cu")
		(hatch none 0.5)
		(connect_pads
			(clearance 0)
		)
		(min_thickness 0.25)
		(keepout
			(tracks not_allowed)
			(vias allowed)
			(pads allowed)
			(copperpour not_allowed)
			(footprints allowed)
		)
		(placement
			(enabled no)
			(sheetname "")
		)
		(fill yes
			(thermal_gap 0.5)
			(thermal_bridge_width 0.5)
			(island_removal_mode 0)
		)
		(polygon
			(pts
				(arc
					(start 65.55486 -145.287238)
					(mid 64.85128 -145.287238)
					(end 65.55486 -145.287238)
				)
			)
		)
	)
	(zone
		(layers "B.Cu" "In7.Cu" "In9.Cu" "In11.Cu" "In13.Cu" "In15.Cu")
		(hatch none 0.5)
		(connect_pads
			(clearance 0)
		)
		(min_thickness 0.25)
		(keepout
			(tracks not_allowed)
			(vias allowed)
			(pads allowed)
			(copperpour not_allowed)
			(footprints allowed)
		)
		(placement
			(enabled no)
			(sheetname "")
		)
		(fill yes
			(thermal_gap 0.5)
			(thermal_bridge_width 0.5)
			(island_removal_mode 0)
		)
		(polygon
			(pts
				(arc
					(start 34.889694 -409.290012)
					(mid 34.130234 -409.290012)
					(end 34.889694 -409.290012)
				)
			)
		)
	)
	(zone
		(layers "B.Cu" "In7.Cu" "In9.Cu" "In11.Cu" "In13.Cu" "In15.Cu")
		(hatch none 0.5)
		(connect_pads
			(clearance 0)
		)
		(min_thickness 0.25)
		(keepout
			(tracks not_allowed)
			(vias allowed)
			(pads allowed)
			(copperpour not_allowed)
			(footprints allowed)
		)
		(placement
			(enabled no)
			(sheetname "")
		)
		(fill yes
			(thermal_gap 0.5)
			(thermal_bridge_width 0.5)
			(island_removal_mode 0)
		)
		(polygon
			(pts
				(arc
					(start 274.126198 -316.799722)
					(mid 273.473418 -316.799722)
					(end 274.126198 -316.799722)
				)
			)
		)
	)
	(zone
		(layers "B.Cu" "In7.Cu" "In9.Cu" "In11.Cu" "In13.Cu" "In15.Cu")
		(hatch none 0.5)
		(connect_pads
			(clearance 0)
		)
		(min_thickness 0.25)
		(keepout
			(tracks not_allowed)
			(vias allowed)
			(pads allowed)
			(copperpour not_allowed)
			(footprints allowed)
		)
		(placement
			(enabled no)
			(sheetname "")
		)
		(fill yes
			(thermal_gap 0.5)
			(thermal_bridge_width 0.5)
			(island_removal_mode 0)
		)
		(polygon
			(pts
				(arc
					(start 168.694354 -101.112828)
					(mid 167.990774 -101.112828)
					(end 168.694354 -101.112828)
				)
			)
		)
	)
	(zone
		(layers "B.Cu" "In7.Cu" "In9.Cu" "In11.Cu" "In13.Cu" "In15.Cu")
		(hatch none 0.5)
		(connect_pads
			(clearance 0)
		)
		(min_thickness 0.25)
		(keepout
			(tracks not_allowed)
			(vias allowed)
			(pads allowed)
			(copperpour not_allowed)
			(footprints allowed)
		)
		(placement
			(enabled no)
			(sheetname "")
		)
		(fill yes
			(thermal_gap 0.5)
			(thermal_bridge_width 0.5)
			(island_removal_mode 0)
		)
		(polygon
			(pts
				(arc
					(start 413.976312 -318.699896)
					(mid 413.323532 -318.699896)
					(end 413.976312 -318.699896)
				)
			)
		)
	)
	(zone
		(layers "B.Cu" "In7.Cu" "In9.Cu" "In11.Cu" "In13.Cu" "In15.Cu")
		(hatch none 0.5)
		(connect_pads
			(clearance 0)
		)
		(min_thickness 0.25)
		(keepout
			(tracks not_allowed)
			(vias allowed)
			(pads allowed)
			(copperpour not_allowed)
			(footprints allowed)
		)
		(placement
			(enabled no)
			(sheetname "")
		)
		(fill yes
			(thermal_gap 0.5)
			(thermal_bridge_width 0.5)
			(island_removal_mode 0)
		)
		(polygon
			(pts
				(arc
					(start 170.548554 -100.17633)
					(mid 169.844974 -100.17633)
					(end 170.548554 -100.17633)
				)
			)
		)
	)
	(zone
		(layers "B.Cu" "In7.Cu" "In9.Cu" "In11.Cu" "In13.Cu" "In15.Cu")
		(hatch none 0.5)
		(connect_pads
			(clearance 0)
		)
		(min_thickness 0.25)
		(keepout
			(tracks not_allowed)
			(vias allowed)
			(pads allowed)
			(copperpour not_allowed)
			(footprints allowed)
		)
		(placement
			(enabled no)
			(sheetname "")
		)
		(fill yes
			(thermal_gap 0.5)
			(thermal_bridge_width 0.5)
			(island_removal_mode 0)
		)
		(polygon
			(pts
				(arc
					(start 413.8549 -132.577332)
					(mid 413.15132 -132.577332)
					(end 413.8549 -132.577332)
				)
			)
		)
	)
	(zone
		(layers "B.Cu" "In7.Cu" "In9.Cu" "In11.Cu" "In13.Cu" "In15.Cu")
		(hatch none 0.5)
		(connect_pads
			(clearance 0)
		)
		(min_thickness 0.25)
		(keepout
			(tracks not_allowed)
			(vias allowed)
			(pads allowed)
			(copperpour not_allowed)
			(footprints allowed)
		)
		(placement
			(enabled no)
			(sheetname "")
		)
		(fill yes
			(thermal_gap 0.5)
			(thermal_bridge_width 0.5)
			(island_removal_mode 0)
		)
		(polygon
			(pts
				(arc
					(start 196.026024 -275.949918)
					(mid 195.373244 -275.949918)
					(end 196.026024 -275.949918)
				)
			)
		)
	)
	(zone
		(layers "B.Cu" "In7.Cu" "In9.Cu" "In11.Cu" "In13.Cu" "In15.Cu")
		(hatch none 0.5)
		(connect_pads
			(clearance 0)
		)
		(min_thickness 0.25)
		(keepout
			(tracks not_allowed)
			(vias allowed)
			(pads allowed)
			(copperpour not_allowed)
			(footprints allowed)
		)
		(placement
			(enabled no)
			(sheetname "")
		)
		(fill yes
			(thermal_gap 0.5)
			(thermal_bridge_width 0.5)
			(island_removal_mode 0)
		)
		(polygon
			(pts
				(arc
					(start 404.476204 -317.749936)
					(mid 403.823424 -317.749936)
					(end 404.476204 -317.749936)
				)
			)
		)
	)
	(zone
		(layers "B.Cu" "In7.Cu" "In9.Cu" "In11.Cu" "In13.Cu" "In15.Cu")
		(hatch none 0.5)
		(connect_pads
			(clearance 0)
		)
		(min_thickness 0.25)
		(keepout
			(tracks not_allowed)
			(vias allowed)
			(pads allowed)
			(copperpour not_allowed)
			(footprints allowed)
		)
		(placement
			(enabled no)
			(sheetname "")
		)
		(fill yes
			(thermal_gap 0.5)
			(thermal_bridge_width 0.5)
			(island_removal_mode 0)
		)
		(polygon
			(pts
				(arc
					(start 279.826212 -316.799722)
					(mid 279.173432 -316.799722)
					(end 279.826212 -316.799722)
				)
			)
		)
	)
	(zone
		(layers "B.Cu" "In7.Cu" "In9.Cu" "In11.Cu" "In13.Cu" "In15.Cu")
		(hatch none 0.5)
		(connect_pads
			(clearance 0)
		)
		(min_thickness 0.25)
		(keepout
			(tracks not_allowed)
			(vias allowed)
			(pads allowed)
			(copperpour not_allowed)
			(footprints allowed)
		)
		(placement
			(enabled no)
			(sheetname "")
		)
		(fill yes
			(thermal_gap 0.5)
			(thermal_bridge_width 0.5)
			(island_removal_mode 0)
		)
		(polygon
			(pts
				(arc
					(start 180.826156 -275.949664)
					(mid 180.173376 -275.949664)
					(end 180.826156 -275.949664)
				)
			)
		)
	)
	(zone
		(layers "B.Cu" "In7.Cu" "In9.Cu" "In11.Cu" "In13.Cu" "In15.Cu")
		(hatch none 0.5)
		(connect_pads
			(clearance 0)
		)
		(min_thickness 0.25)
		(keepout
			(tracks not_allowed)
			(vias allowed)
			(pads allowed)
			(copperpour not_allowed)
			(footprints allowed)
		)
		(placement
			(enabled no)
			(sheetname "")
		)
		(fill yes
			(thermal_gap 0.5)
			(thermal_bridge_width 0.5)
			(island_removal_mode 0)
		)
		(polygon
			(pts
				(arc
					(start 37.089842 -383.490216)
					(mid 36.330382 -383.490216)
					(end 37.089842 -383.490216)
				)
			)
		)
	)
	(zone
		(layers "B.Cu" "In7.Cu" "In9.Cu" "In11.Cu" "In13.Cu" "In15.Cu")
		(hatch none 0.5)
		(connect_pads
			(clearance 0)
		)
		(min_thickness 0.25)
		(keepout
			(tracks not_allowed)
			(vias allowed)
			(pads allowed)
			(copperpour not_allowed)
			(footprints allowed)
		)
		(placement
			(enabled no)
			(sheetname "")
		)
		(fill yes
			(thermal_gap 0.5)
			(thermal_bridge_width 0.5)
			(island_removal_mode 0)
		)
		(polygon
			(pts
				(arc
					(start 170.548554 -110.11281)
					(mid 169.844974 -110.11281)
					(end 170.548554 -110.11281)
				)
			)
		)
	)
	(zone
		(layers "B.Cu" "In7.Cu" "In9.Cu" "In11.Cu" "In13.Cu" "In15.Cu")
		(hatch none 0.5)
		(connect_pads
			(clearance 0)
		)
		(min_thickness 0.25)
		(keepout
			(tracks not_allowed)
			(vias allowed)
			(pads allowed)
			(copperpour not_allowed)
			(footprints allowed)
		)
		(placement
			(enabled no)
			(sheetname "")
		)
		(fill yes
			(thermal_gap 0.5)
			(thermal_bridge_width 0.5)
			(island_removal_mode 0)
		)
		(polygon
			(pts
				(arc
					(start 39.076376 -309.199788)
					(mid 38.423596 -309.199788)
					(end 39.076376 -309.199788)
				)
			)
		)
	)
	(zone
		(layers "B.Cu" "In7.Cu" "In9.Cu" "In11.Cu" "In13.Cu" "In15.Cu")
		(hatch none 0.5)
		(connect_pads
			(clearance 0)
		)
		(min_thickness 0.25)
		(keepout
			(tracks not_allowed)
			(vias allowed)
			(pads allowed)
			(copperpour not_allowed)
			(footprints allowed)
		)
		(placement
			(enabled no)
			(sheetname "")
		)
		(fill yes
			(thermal_gap 0.5)
			(thermal_bridge_width 0.5)
			(island_removal_mode 0)
		)
		(polygon
			(pts
				(arc
					(start 416.825938 -275.949664)
					(mid 416.173158 -275.949664)
					(end 416.825938 -275.949664)
				)
			)
		)
	)
	(zone
		(layers "B.Cu" "In7.Cu" "In9.Cu" "In11.Cu" "In13.Cu" "In15.Cu")
		(hatch none 0.5)
		(connect_pads
			(clearance 0)
		)
		(min_thickness 0.25)
		(keepout
			(tracks not_allowed)
			(vias allowed)
			(pads allowed)
			(copperpour not_allowed)
			(footprints allowed)
		)
		(placement
			(enabled no)
			(sheetname "")
		)
		(fill yes
			(thermal_gap 0.5)
			(thermal_bridge_width 0.5)
			(island_removal_mode 0)
		)
		(polygon
			(pts
				(arc
					(start 400.89455 -124.622814)
					(mid 400.19097 -124.622814)
					(end 400.89455 -124.622814)
				)
			)
		)
	)
	(zone
		(layers "B.Cu" "In7.Cu" "In9.Cu" "In11.Cu" "In13.Cu" "In15.Cu")
		(hatch none 0.5)
		(connect_pads
			(clearance 0)
		)
		(min_thickness 0.25)
		(keepout
			(tracks not_allowed)
			(vias allowed)
			(pads allowed)
			(copperpour not_allowed)
			(footprints allowed)
		)
		(placement
			(enabled no)
			(sheetname "")
		)
		(fill yes
			(thermal_gap 0.5)
			(thermal_bridge_width 0.5)
			(island_removal_mode 0)
		)
		(polygon
			(pts
				(arc
					(start 400.676364 -318.699896)
					(mid 400.023584 -318.699896)
					(end 400.676364 -318.699896)
				)
			)
		)
	)
	(zone
		(layers "B.Cu" "In7.Cu" "In9.Cu" "In11.Cu" "In13.Cu" "In15.Cu")
		(hatch none 0.5)
		(connect_pads
			(clearance 0)
		)
		(min_thickness 0.25)
		(keepout
			(tracks not_allowed)
			(vias allowed)
			(pads allowed)
			(copperpour not_allowed)
			(footprints allowed)
		)
		(placement
			(enabled no)
			(sheetname "")
		)
		(fill yes
			(thermal_gap 0.5)
			(thermal_bridge_width 0.5)
			(island_removal_mode 0)
		)
		(polygon
			(pts
				(arc
					(start 299.77588 -273.099784)
					(mid 299.1231 -273.099784)
					(end 299.77588 -273.099784)
				)
			)
		)
	)
	(zone
		(layers "B.Cu" "In7.Cu" "In9.Cu" "In11.Cu" "In13.Cu" "In15.Cu")
		(hatch none 0.5)
		(connect_pads
			(clearance 0)
		)
		(min_thickness 0.25)
		(keepout
			(tracks not_allowed)
			(vias allowed)
			(pads allowed)
			(copperpour not_allowed)
			(footprints allowed)
		)
		(placement
			(enabled no)
			(sheetname "")
		)
		(fill yes
			(thermal_gap 0.5)
			(thermal_bridge_width 0.5)
			(island_removal_mode 0)
		)
		(polygon
			(pts
				(arc
					(start 181.654704 -148.023834)
					(mid 180.951124 -148.023834)
					(end 181.654704 -148.023834)
				)
			)
		)
	)
	(zone
		(layers "B.Cu" "In7.Cu" "In9.Cu" "In11.Cu" "In13.Cu" "In15.Cu")
		(hatch none 0.5)
		(connect_pads
			(clearance 0)
		)
		(min_thickness 0.25)
		(keepout
			(tracks not_allowed)
			(vias allowed)
			(pads allowed)
			(copperpour not_allowed)
			(footprints allowed)
		)
		(placement
			(enabled no)
			(sheetname "")
		)
		(fill yes
			(thermal_gap 0.5)
			(thermal_bridge_width 0.5)
			(island_removal_mode 0)
		)
		(polygon
			(pts
				(arc
					(start 389.06958 -374.390158)
					(mid 388.31012 -374.390158)
					(end 389.06958 -374.390158)
				)
			)
		)
	)
	(zone
		(layers "B.Cu" "In7.Cu" "In9.Cu" "In11.Cu" "In13.Cu" "In15.Cu")
		(hatch none 0.5)
		(connect_pads
			(clearance 0)
		)
		(min_thickness 0.25)
		(keepout
			(tracks not_allowed)
			(vias allowed)
			(pads allowed)
			(copperpour not_allowed)
			(footprints allowed)
		)
		(placement
			(enabled no)
			(sheetname "")
		)
		(fill yes
			(thermal_gap 0.5)
			(thermal_bridge_width 0.5)
			(island_removal_mode 0)
		)
		(polygon
			(pts
				(arc
					(start 299.609002 -147.087336)
					(mid 298.905422 -147.087336)
					(end 299.609002 -147.087336)
				)
			)
		)
	)
	(zone
		(layers "B.Cu" "In7.Cu" "In9.Cu" "In11.Cu" "In13.Cu" "In15.Cu")
		(hatch none 0.5)
		(connect_pads
			(clearance 0)
		)
		(min_thickness 0.25)
		(keepout
			(tracks not_allowed)
			(vias allowed)
			(pads allowed)
			(copperpour not_allowed)
			(footprints allowed)
		)
		(placement
			(enabled no)
			(sheetname "")
		)
		(fill yes
			(thermal_gap 0.5)
			(thermal_bridge_width 0.5)
			(island_removal_mode 0)
		)
		(polygon
			(pts
				(arc
					(start 175.689768 -406.690068)
					(mid 174.930308 -406.690068)
					(end 175.689768 -406.690068)
				)
			)
		)
	)
	(zone
		(layers "B.Cu" "In7.Cu" "In9.Cu" "In11.Cu" "In13.Cu" "In15.Cu")
		(hatch none 0.5)
		(connect_pads
			(clearance 0)
		)
		(min_thickness 0.25)
		(keepout
			(tracks not_allowed)
			(vias allowed)
			(pads allowed)
			(copperpour not_allowed)
			(footprints allowed)
		)
		(placement
			(enabled no)
			(sheetname "")
		)
		(fill yes
			(thermal_gap 0.5)
			(thermal_bridge_width 0.5)
			(island_removal_mode 0)
		)
		(polygon
			(pts
				(arc
					(start 116.289836 -397.790162)
					(mid 115.530376 -397.790162)
					(end 116.289836 -397.790162)
				)
			)
		)
	)
	(zone
		(layers "B.Cu" "In7.Cu" "In9.Cu" "In11.Cu" "In13.Cu" "In15.Cu")
		(hatch none 0.5)
		(connect_pads
			(clearance 0)
		)
		(min_thickness 0.25)
		(keepout
			(tracks not_allowed)
			(vias allowed)
			(pads allowed)
			(copperpour not_allowed)
			(footprints allowed)
		)
		(placement
			(enabled no)
			(sheetname "")
		)
		(fill yes
			(thermal_gap 0.5)
			(thermal_bridge_width 0.5)
			(island_removal_mode 0)
		)
		(polygon
			(pts
				(arc
					(start 63.776098 -274.049744)
					(mid 63.123318 -274.049744)
					(end 63.776098 -274.049744)
				)
			)
		)
	)
	(zone
		(layers "B.Cu" "In7.Cu" "In9.Cu" "In11.Cu" "In13.Cu" "In15.Cu")
		(hatch none 0.5)
		(connect_pads
			(clearance 0)
		)
		(min_thickness 0.25)
		(keepout
			(tracks not_allowed)
			(vias allowed)
			(pads allowed)
			(copperpour not_allowed)
			(footprints allowed)
		)
		(placement
			(enabled no)
			(sheetname "")
		)
		(fill yes
			(thermal_gap 0.5)
			(thermal_bridge_width 0.5)
			(island_removal_mode 0)
		)
		(polygon
			(pts
				(arc
					(start 198.876412 -308.249828)
					(mid 198.223632 -308.249828)
					(end 198.876412 -308.249828)
				)
			)
		)
	)
	(zone
		(layers "B.Cu" "In7.Cu" "In9.Cu" "In11.Cu" "In13.Cu" "In15.Cu")
		(hatch none 0.5)
		(connect_pads
			(clearance 0)
		)
		(min_thickness 0.25)
		(keepout
			(tracks not_allowed)
			(vias allowed)
			(pads allowed)
			(copperpour not_allowed)
			(footprints allowed)
		)
		(placement
			(enabled no)
			(sheetname "")
		)
		(fill yes
			(thermal_gap 0.5)
			(thermal_bridge_width 0.5)
			(island_removal_mode 0)
		)
		(polygon
			(pts
				(arc
					(start 314.026296 -274.999704)
					(mid 313.373516 -274.999704)
					(end 314.026296 -274.999704)
				)
			)
		)
	)
	(zone
		(layers "B.Cu" "In7.Cu" "In9.Cu" "In11.Cu" "In13.Cu" "In15.Cu")
		(hatch none 0.5)
		(connect_pads
			(clearance 0)
		)
		(min_thickness 0.25)
		(keepout
			(tracks not_allowed)
			(vias allowed)
			(pads allowed)
			(copperpour not_allowed)
			(footprints allowed)
		)
		(placement
			(enabled no)
			(sheetname "")
		)
		(fill yes
			(thermal_gap 0.5)
			(thermal_bridge_width 0.5)
			(island_removal_mode 0)
		)
		(polygon
			(pts
				(arc
					(start 415.7091 -129.913634)
					(mid 415.00552 -129.913634)
					(end 415.7091 -129.913634)
				)
			)
		)
	)
	(zone
		(layers "B.Cu" "In7.Cu" "In9.Cu" "In11.Cu" "In13.Cu" "In15.Cu")
		(hatch none 0.5)
		(connect_pads
			(clearance 0)
		)
		(min_thickness 0.25)
		(keepout
			(tracks not_allowed)
			(vias allowed)
			(pads allowed)
			(copperpour not_allowed)
			(footprints allowed)
		)
		(placement
			(enabled no)
			(sheetname "")
		)
		(fill yes
			(thermal_gap 0.5)
			(thermal_bridge_width 0.5)
			(island_removal_mode 0)
		)
		(polygon
			(pts
				(arc
					(start 54.44871 -102.912672)
					(mid 53.74513 -102.912672)
					(end 54.44871 -102.912672)
				)
			)
		)
	)
	(zone
		(layers "B.Cu" "In7.Cu" "In9.Cu" "In11.Cu" "In13.Cu" "In15.Cu")
		(hatch none 0.5)
		(connect_pads
			(clearance 0)
		)
		(min_thickness 0.25)
		(keepout
			(tracks not_allowed)
			(vias allowed)
			(pads allowed)
			(copperpour not_allowed)
			(footprints allowed)
		)
		(placement
			(enabled no)
			(sheetname "")
		)
		(fill yes
			(thermal_gap 0.5)
			(thermal_bridge_width 0.5)
			(island_removal_mode 0)
		)
		(polygon
			(pts
				(arc
					(start 336.269838 -400.390106)
					(mid 335.510378 -400.390106)
					(end 336.269838 -400.390106)
				)
			)
		)
	)
	(zone
		(layers "B.Cu" "In7.Cu" "In9.Cu" "In11.Cu" "In13.Cu" "In15.Cu")
		(hatch none 0.5)
		(connect_pads
			(clearance 0)
		)
		(min_thickness 0.25)
		(keepout
			(tracks not_allowed)
			(vias allowed)
			(pads allowed)
			(copperpour not_allowed)
			(footprints allowed)
		)
		(placement
			(enabled no)
			(sheetname "")
		)
		(fill yes
			(thermal_gap 0.5)
			(thermal_bridge_width 0.5)
			(island_removal_mode 0)
		)
		(polygon
			(pts
				(arc
					(start 295.97604 -274.049744)
					(mid 295.32326 -274.049744)
					(end 295.97604 -274.049744)
				)
			)
		)
	)
	(zone
		(layers "B.Cu" "In7.Cu" "In9.Cu" "In11.Cu" "In13.Cu" "In15.Cu")
		(hatch none 0.5)
		(connect_pads
			(clearance 0)
		)
		(min_thickness 0.25)
		(keepout
			(tracks not_allowed)
			(vias allowed)
			(pads allowed)
			(copperpour not_allowed)
			(footprints allowed)
		)
		(placement
			(enabled no)
			(sheetname "")
		)
		(fill yes
			(thermal_gap 0.5)
			(thermal_bridge_width 0.5)
			(island_removal_mode 0)
		)
		(polygon
			(pts
				(arc
					(start 423.47642 -318.699896)
					(mid 422.82364 -318.699896)
					(end 423.47642 -318.699896)
				)
			)
		)
	)
	(zone
		(layers "B.Cu" "In7.Cu" "In9.Cu" "In11.Cu" "In13.Cu" "In15.Cu")
		(hatch none 0.5)
		(connect_pads
			(clearance 0)
		)
		(min_thickness 0.25)
		(keepout
			(tracks not_allowed)
			(vias allowed)
			(pads allowed)
			(copperpour not_allowed)
			(footprints allowed)
		)
		(placement
			(enabled no)
			(sheetname "")
		)
		(fill yes
			(thermal_gap 0.5)
			(thermal_bridge_width 0.5)
			(island_removal_mode 0)
		)
		(polygon
			(pts
				(arc
					(start 290.069524 -383.290064)
					(mid 289.310064 -383.290064)
					(end 290.069524 -383.290064)
				)
			)
		)
	)
	(zone
		(layers "B.Cu" "In7.Cu" "In9.Cu" "In11.Cu" "In13.Cu" "In15.Cu")
		(hatch none 0.5)
		(connect_pads
			(clearance 0)
		)
		(min_thickness 0.25)
		(keepout
			(tracks not_allowed)
			(vias allowed)
			(pads allowed)
			(copperpour not_allowed)
			(footprints allowed)
		)
		(placement
			(enabled no)
			(sheetname "")
		)
		(fill yes
			(thermal_gap 0.5)
			(thermal_bridge_width 0.5)
			(island_removal_mode 0)
		)
		(polygon
			(pts
				(arc
					(start 347.269816 -372.890034)
					(mid 346.510356 -372.890034)
					(end 347.269816 -372.890034)
				)
			)
		)
	)
	(zone
		(layers "B.Cu" "In7.Cu" "In9.Cu" "In11.Cu" "In13.Cu" "In15.Cu")
		(hatch none 0.5)
		(connect_pads
			(clearance 0)
		)
		(min_thickness 0.25)
		(keepout
			(tracks not_allowed)
			(vias allowed)
			(pads allowed)
			(copperpour not_allowed)
			(footprints allowed)
		)
		(placement
			(enabled no)
			(sheetname "")
		)
		(fill yes
			(thermal_gap 0.5)
			(thermal_bridge_width 0.5)
			(island_removal_mode 0)
		)
		(polygon
			(pts
				(arc
					(start 334.06969 -402.790152)
					(mid 333.31023 -402.790152)
					(end 334.06969 -402.790152)
				)
			)
		)
	)
	(zone
		(layers "B.Cu" "In7.Cu" "In9.Cu" "In11.Cu" "In13.Cu" "In15.Cu")
		(hatch none 0.5)
		(connect_pads
			(clearance 0)
		)
		(min_thickness 0.25)
		(keepout
			(tracks not_allowed)
			(vias allowed)
			(pads allowed)
			(copperpour not_allowed)
			(footprints allowed)
		)
		(placement
			(enabled no)
			(sheetname "")
		)
		(fill yes
			(thermal_gap 0.5)
			(thermal_bridge_width 0.5)
			(island_removal_mode 0)
		)
		(polygon
			(pts
				(arc
					(start 402.74875 -122.822716)
					(mid 402.04517 -122.822716)
					(end 402.74875 -122.822716)
				)
			)
		)
	)
	(zone
		(layers "B.Cu" "In7.Cu" "In9.Cu" "In11.Cu" "In13.Cu" "In15.Cu")
		(hatch none 0.5)
		(connect_pads
			(clearance 0)
		)
		(min_thickness 0.25)
		(keepout
			(tracks not_allowed)
			(vias allowed)
			(pads allowed)
			(copperpour not_allowed)
			(footprints allowed)
		)
		(placement
			(enabled no)
			(sheetname "")
		)
		(fill yes
			(thermal_gap 0.5)
			(thermal_bridge_width 0.5)
			(island_removal_mode 0)
		)
		(polygon
			(pts
				(arc
					(start 276.026118 -315.849762)
					(mid 275.373338 -315.849762)
					(end 276.026118 -315.849762)
				)
			)
		)
	)
	(zone
		(layers "B.Cu" "In7.Cu" "In9.Cu" "In11.Cu" "In13.Cu" "In15.Cu")
		(hatch none 0.5)
		(connect_pads
			(clearance 0)
		)
		(min_thickness 0.25)
		(keepout
			(tracks not_allowed)
			(vias allowed)
			(pads allowed)
			(copperpour not_allowed)
			(footprints allowed)
		)
		(placement
			(enabled no)
			(sheetname "")
		)
		(fill yes
			(thermal_gap 0.5)
			(thermal_bridge_width 0.5)
			(island_removal_mode 0)
		)
		(polygon
			(pts
				(arc
					(start 269.376144 -308.249828)
					(mid 268.723364 -308.249828)
					(end 269.376144 -308.249828)
				)
			)
		)
	)
	(zone
		(layers "B.Cu" "In7.Cu" "In9.Cu" "In11.Cu" "In13.Cu" "In15.Cu")
		(hatch none 0.5)
		(connect_pads
			(clearance 0)
		)
		(min_thickness 0.25)
		(keepout
			(tracks not_allowed)
			(vias allowed)
			(pads allowed)
			(copperpour not_allowed)
			(footprints allowed)
		)
		(placement
			(enabled no)
			(sheetname "")
		)
		(fill yes
			(thermal_gap 0.5)
			(thermal_bridge_width 0.5)
			(island_removal_mode 0)
		)
		(polygon
			(pts
				(arc
					(start 41.48963 -383.490216)
					(mid 40.73017 -383.490216)
					(end 41.48963 -383.490216)
				)
			)
		)
	)
	(zone
		(layers "B.Cu" "In7.Cu" "In9.Cu" "In11.Cu" "In13.Cu" "In15.Cu")
		(hatch none 0.5)
		(connect_pads
			(clearance 0)
		)
		(min_thickness 0.25)
		(keepout
			(tracks not_allowed)
			(vias allowed)
			(pads allowed)
			(copperpour not_allowed)
			(footprints allowed)
		)
		(placement
			(enabled no)
			(sheetname "")
		)
		(fill yes
			(thermal_gap 0.5)
			(thermal_bridge_width 0.5)
			(island_removal_mode 0)
		)
		(polygon
			(pts
				(arc
					(start 314.026296 -283.549852)
					(mid 313.373516 -283.549852)
					(end 314.026296 -283.549852)
				)
			)
		)
	)
	(zone
		(layers "B.Cu" "In7.Cu" "In9.Cu" "In11.Cu" "In13.Cu" "In15.Cu")
		(hatch none 0.5)
		(connect_pads
			(clearance 0)
		)
		(min_thickness 0.25)
		(keepout
			(tracks not_allowed)
			(vias allowed)
			(pads allowed)
			(copperpour not_allowed)
			(footprints allowed)
		)
		(placement
			(enabled no)
			(sheetname "")
		)
		(fill yes
			(thermal_gap 0.5)
			(thermal_bridge_width 0.5)
			(island_removal_mode 0)
		)
		(polygon
			(pts
				(arc
					(start 83.289648 -402.790152)
					(mid 82.530188 -402.790152)
					(end 83.289648 -402.790152)
				)
			)
		)
	)
	(zone
		(layers "B.Cu" "In7.Cu" "In9.Cu" "In11.Cu" "In13.Cu" "In15.Cu")
		(hatch none 0.5)
		(connect_pads
			(clearance 0)
		)
		(min_thickness 0.25)
		(keepout
			(tracks not_allowed)
			(vias allowed)
			(pads allowed)
			(copperpour not_allowed)
			(footprints allowed)
		)
		(placement
			(enabled no)
			(sheetname "")
		)
		(fill yes
			(thermal_gap 0.5)
			(thermal_bridge_width 0.5)
			(island_removal_mode 0)
		)
		(polygon
			(pts
				(arc
					(start 179.87645 -317.749936)
					(mid 179.22367 -317.749936)
					(end 179.87645 -317.749936)
				)
			)
		)
	)
	(zone
		(layers "B.Cu" "In7.Cu" "In9.Cu" "In11.Cu" "In13.Cu" "In15.Cu")
		(hatch none 0.5)
		(connect_pads
			(clearance 0)
		)
		(min_thickness 0.25)
		(keepout
			(tracks not_allowed)
			(vias allowed)
			(pads allowed)
			(copperpour not_allowed)
			(footprints allowed)
		)
		(placement
			(enabled no)
			(sheetname "")
		)
		(fill yes
			(thermal_gap 0.5)
			(thermal_bridge_width 0.5)
			(island_removal_mode 0)
		)
		(polygon
			(pts
				(arc
					(start 52.59451 -105.57637)
					(mid 51.89093 -105.57637)
					(end 52.59451 -105.57637)
				)
			)
		)
	)
	(zone
		(layers "B.Cu" "In7.Cu" "In9.Cu" "In11.Cu" "In13.Cu" "In15.Cu")
		(hatch none 0.5)
		(connect_pads
			(clearance 0)
		)
		(min_thickness 0.25)
		(keepout
			(tracks not_allowed)
			(vias allowed)
			(pads allowed)
			(copperpour not_allowed)
			(footprints allowed)
		)
		(placement
			(enabled no)
			(sheetname "")
		)
		(fill yes
			(thermal_gap 0.5)
			(thermal_bridge_width 0.5)
			(island_removal_mode 0)
		)
		(polygon
			(pts
				(arc
					(start 193.176144 -274.049744)
					(mid 192.523364 -274.049744)
					(end 193.176144 -274.049744)
				)
			)
		)
	)
	(zone
		(layers "B.Cu" "In7.Cu" "In9.Cu" "In11.Cu" "In13.Cu" "In15.Cu")
		(hatch none 0.5)
		(connect_pads
			(clearance 0)
		)
		(min_thickness 0.25)
		(keepout
			(tracks not_allowed)
			(vias allowed)
			(pads allowed)
			(copperpour not_allowed)
			(footprints allowed)
		)
		(placement
			(enabled no)
			(sheetname "")
		)
		(fill yes
			(thermal_gap 0.5)
			(thermal_bridge_width 0.5)
			(island_removal_mode 0)
		)
		(polygon
			(pts
				(arc
					(start 304.526188 -316.799722)
					(mid 303.873408 -316.799722)
					(end 304.526188 -316.799722)
				)
			)
		)
	)
	(zone
		(layers "B.Cu" "In7.Cu" "In9.Cu" "In11.Cu" "In13.Cu" "In15.Cu")
		(hatch none 0.5)
		(connect_pads
			(clearance 0)
		)
		(min_thickness 0.25)
		(keepout
			(tracks not_allowed)
			(vias allowed)
			(pads allowed)
			(copperpour not_allowed)
			(footprints allowed)
		)
		(placement
			(enabled no)
			(sheetname "")
		)
		(fill yes
			(thermal_gap 0.5)
			(thermal_bridge_width 0.5)
			(island_removal_mode 0)
		)
		(polygon
			(pts
				(arc
					(start 168.694354 -111.912908)
					(mid 167.990774 -111.912908)
					(end 168.694354 -111.912908)
				)
			)
		)
	)
	(zone
		(layers "B.Cu" "In7.Cu" "In9.Cu" "In11.Cu" "In13.Cu" "In15.Cu")
		(hatch none 0.5)
		(connect_pads
			(clearance 0)
		)
		(min_thickness 0.25)
		(keepout
			(tracks not_allowed)
			(vias allowed)
			(pads allowed)
			(copperpour not_allowed)
			(footprints allowed)
		)
		(placement
			(enabled no)
			(sheetname "")
		)
		(fill yes
			(thermal_gap 0.5)
			(thermal_bridge_width 0.5)
			(island_removal_mode 0)
		)
		(polygon
			(pts
				(arc
					(start 345.069668 -370.489988)
					(mid 344.310208 -370.489988)
					(end 345.069668 -370.489988)
				)
			)
		)
	)
	(zone
		(layers "B.Cu" "In7.Cu" "In9.Cu" "In11.Cu" "In13.Cu" "In15.Cu")
		(hatch none 0.5)
		(connect_pads
			(clearance 0)
		)
		(min_thickness 0.25)
		(keepout
			(tracks not_allowed)
			(vias allowed)
			(pads allowed)
			(copperpour not_allowed)
			(footprints allowed)
		)
		(placement
			(enabled no)
			(sheetname "")
		)
		(fill yes
			(thermal_gap 0.5)
			(thermal_bridge_width 0.5)
			(island_removal_mode 0)
		)
		(polygon
			(pts
				(arc
					(start 413.8549 -135.313674)
					(mid 413.15132 -135.313674)
					(end 413.8549 -135.313674)
				)
			)
		)
	)
	(zone
		(layers "B.Cu" "In7.Cu" "In9.Cu" "In11.Cu" "In13.Cu" "In15.Cu")
		(hatch none 0.5)
		(connect_pads
			(clearance 0)
		)
		(min_thickness 0.25)
		(keepout
			(tracks not_allowed)
			(vias allowed)
			(pads allowed)
			(copperpour not_allowed)
			(footprints allowed)
		)
		(placement
			(enabled no)
			(sheetname "")
		)
		(fill yes
			(thermal_gap 0.5)
			(thermal_bridge_width 0.5)
			(island_removal_mode 0)
		)
		(polygon
			(pts
				(arc
					(start 310.225948 -274.999958)
					(mid 309.573168 -274.999958)
					(end 310.225948 -274.999958)
				)
			)
		)
	)
	(zone
		(layers "B.Cu" "In7.Cu" "In9.Cu" "In11.Cu" "In13.Cu" "In15.Cu")
		(hatch none 0.5)
		(connect_pads
			(clearance 0)
		)
		(min_thickness 0.25)
		(keepout
			(tracks not_allowed)
			(vias allowed)
			(pads allowed)
			(copperpour not_allowed)
			(footprints allowed)
		)
		(placement
			(enabled no)
			(sheetname "")
		)
		(fill yes
			(thermal_gap 0.5)
			(thermal_bridge_width 0.5)
			(island_removal_mode 0)
		)
		(polygon
			(pts
				(arc
					(start 313.076082 -286.399732)
					(mid 312.423302 -286.399732)
					(end 313.076082 -286.399732)
				)
			)
		)
	)
	(zone
		(layers "B.Cu" "In7.Cu" "In9.Cu" "In11.Cu" "In13.Cu" "In15.Cu")
		(hatch none 0.5)
		(connect_pads
			(clearance 0)
		)
		(min_thickness 0.25)
		(keepout
			(tracks not_allowed)
			(vias allowed)
			(pads allowed)
			(copperpour not_allowed)
			(footprints allowed)
		)
		(placement
			(enabled no)
			(sheetname "")
		)
		(fill yes
			(thermal_gap 0.5)
			(thermal_bridge_width 0.5)
			(island_removal_mode 0)
		)
		(polygon
			(pts
				(arc
					(start 196.976238 -288.299906)
					(mid 196.323458 -288.299906)
					(end 196.976238 -288.299906)
				)
			)
		)
	)
	(zone
		(layers "B.Cu" "In7.Cu" "In9.Cu" "In11.Cu" "In13.Cu" "In15.Cu")
		(hatch none 0.5)
		(connect_pads
			(clearance 0)
		)
		(min_thickness 0.25)
		(keepout
			(tracks not_allowed)
			(vias allowed)
			(pads allowed)
			(copperpour not_allowed)
			(footprints allowed)
		)
		(placement
			(enabled no)
			(sheetname "")
		)
		(fill yes
			(thermal_gap 0.5)
			(thermal_bridge_width 0.5)
			(island_removal_mode 0)
		)
		(polygon
			(pts
				(arc
					(start 180.826156 -274.999704)
					(mid 180.173376 -274.999704)
					(end 180.826156 -274.999704)
				)
			)
		)
	)
	(zone
		(layers "B.Cu" "In7.Cu" "In9.Cu" "In11.Cu" "In13.Cu" "In15.Cu")
		(hatch none 0.5)
		(connect_pads
			(clearance 0)
		)
		(min_thickness 0.25)
		(keepout
			(tracks not_allowed)
			(vias allowed)
			(pads allowed)
			(copperpour not_allowed)
			(footprints allowed)
		)
		(placement
			(enabled no)
			(sheetname "")
		)
		(fill yes
			(thermal_gap 0.5)
			(thermal_bridge_width 0.5)
			(island_removal_mode 0)
		)
		(polygon
			(pts
				(arc
					(start 271.276318 -318.699896)
					(mid 270.623538 -318.699896)
					(end 271.276318 -318.699896)
				)
			)
		)
	)
	(zone
		(layers "B.Cu" "In7.Cu" "In9.Cu" "In11.Cu" "In13.Cu" "In15.Cu")
		(hatch none 0.5)
		(connect_pads
			(clearance 0)
		)
		(min_thickness 0.25)
		(keepout
			(tracks not_allowed)
			(vias allowed)
			(pads allowed)
			(copperpour not_allowed)
			(footprints allowed)
		)
		(placement
			(enabled no)
			(sheetname "")
		)
		(fill yes
			(thermal_gap 0.5)
			(thermal_bridge_width 0.5)
			(island_removal_mode 0)
		)
		(polygon
			(pts
				(arc
					(start 168.694354 -124.622814)
					(mid 167.990774 -124.622814)
					(end 168.694354 -124.622814)
				)
			)
		)
	)
	(zone
		(layers "B.Cu" "In7.Cu" "In9.Cu" "In11.Cu" "In13.Cu" "In15.Cu")
		(hatch none 0.5)
		(connect_pads
			(clearance 0)
		)
		(min_thickness 0.25)
		(keepout
			(tracks not_allowed)
			(vias allowed)
			(pads allowed)
			(copperpour not_allowed)
			(footprints allowed)
		)
		(placement
			(enabled no)
			(sheetname "")
		)
		(fill yes
			(thermal_gap 0.5)
			(thermal_bridge_width 0.5)
			(island_removal_mode 0)
		)
		(polygon
			(pts
				(arc
					(start 39.076376 -318.699896)
					(mid 38.423596 -318.699896)
					(end 39.076376 -318.699896)
				)
			)
		)
	)
	(zone
		(layers "B.Cu" "In7.Cu" "In9.Cu" "In11.Cu" "In13.Cu" "In15.Cu")
		(hatch none 0.5)
		(connect_pads
			(clearance 0)
		)
		(min_thickness 0.25)
		(keepout
			(tracks not_allowed)
			(vias allowed)
			(pads allowed)
			(copperpour not_allowed)
			(footprints allowed)
		)
		(placement
			(enabled no)
			(sheetname "")
		)
		(fill yes
			(thermal_gap 0.5)
			(thermal_bridge_width 0.5)
			(island_removal_mode 0)
		)
		(polygon
			(pts
				(arc
					(start 191.276224 -274.049744)
					(mid 190.623444 -274.049744)
					(end 191.276224 -274.049744)
				)
			)
		)
	)
	(zone
		(layers "B.Cu" "In7.Cu" "In9.Cu" "In11.Cu" "In13.Cu" "In15.Cu")
		(hatch none 0.5)
		(connect_pads
			(clearance 0)
		)
		(min_thickness 0.25)
		(keepout
			(tracks not_allowed)
			(vias allowed)
			(pads allowed)
			(copperpour not_allowed)
			(footprints allowed)
		)
		(placement
			(enabled no)
			(sheetname "")
		)
		(fill yes
			(thermal_gap 0.5)
			(thermal_bridge_width 0.5)
			(island_removal_mode 0)
		)
		(polygon
			(pts
				(arc
					(start 49.52619 -316.799722)
					(mid 48.87341 -316.799722)
					(end 49.52619 -316.799722)
				)
			)
		)
	)
	(zone
		(layers "B.Cu" "In7.Cu" "In9.Cu" "In11.Cu" "In13.Cu" "In15.Cu")
		(hatch none 0.5)
		(connect_pads
			(clearance 0)
		)
		(min_thickness 0.25)
		(keepout
			(tracks not_allowed)
			(vias allowed)
			(pads allowed)
			(copperpour not_allowed)
			(footprints allowed)
		)
		(placement
			(enabled no)
			(sheetname "")
		)
		(fill yes
			(thermal_gap 0.5)
			(thermal_bridge_width 0.5)
			(island_removal_mode 0)
		)
		(polygon
			(pts
				(arc
					(start 78.889606 -371.590062)
					(mid 78.130146 -371.590062)
					(end 78.889606 -371.590062)
				)
			)
		)
	)
	(zone
		(layers "B.Cu" "In7.Cu" "In9.Cu" "In11.Cu" "In13.Cu" "In15.Cu")
		(hatch none 0.5)
		(connect_pads
			(clearance 0)
		)
		(min_thickness 0.25)
		(keepout
			(tracks not_allowed)
			(vias allowed)
			(pads allowed)
			(copperpour not_allowed)
			(footprints allowed)
		)
		(placement
			(enabled no)
			(sheetname "")
		)
		(fill yes
			(thermal_gap 0.5)
			(thermal_bridge_width 0.5)
			(island_removal_mode 0)
		)
		(polygon
			(pts
				(arc
					(start 280.776172 -318.699896)
					(mid 280.123392 -318.699896)
					(end 280.776172 -318.699896)
				)
			)
		)
	)
	(zone
		(layers "B.Cu" "In7.Cu" "In9.Cu" "In11.Cu" "In13.Cu" "In15.Cu")
		(hatch none 0.5)
		(connect_pads
			(clearance 0)
		)
		(min_thickness 0.25)
		(keepout
			(tracks not_allowed)
			(vias allowed)
			(pads allowed)
			(copperpour not_allowed)
			(footprints allowed)
		)
		(placement
			(enabled no)
			(sheetname "")
		)
		(fill yes
			(thermal_gap 0.5)
			(thermal_bridge_width 0.5)
			(island_removal_mode 0)
		)
		(polygon
			(pts
				(arc
					(start 48.57623 -318.699896)
					(mid 47.92345 -318.699896)
					(end 48.57623 -318.699896)
				)
			)
		)
	)
	(zone
		(layers "B.Cu" "In7.Cu" "In9.Cu" "In11.Cu" "In13.Cu" "In15.Cu")
		(hatch none 0.5)
		(connect_pads
			(clearance 0)
		)
		(min_thickness 0.25)
		(keepout
			(tracks not_allowed)
			(vias allowed)
			(pads allowed)
			(copperpour not_allowed)
			(footprints allowed)
		)
		(placement
			(enabled no)
			(sheetname "")
		)
		(fill yes
			(thermal_gap 0.5)
			(thermal_bridge_width 0.5)
			(island_removal_mode 0)
		)
		(polygon
			(pts
				(arc
					(start 162.489642 -405.390096)
					(mid 161.730182 -405.390096)
					(end 162.489642 -405.390096)
				)
			)
		)
	)
	(zone
		(layers "B.Cu" "In7.Cu" "In9.Cu" "In11.Cu" "In13.Cu" "In15.Cu")
		(hatch none 0.5)
		(connect_pads
			(clearance 0)
		)
		(min_thickness 0.25)
		(keepout
			(tracks not_allowed)
			(vias allowed)
			(pads allowed)
			(copperpour not_allowed)
			(footprints allowed)
		)
		(placement
			(enabled no)
			(sheetname "")
		)
		(fill yes
			(thermal_gap 0.5)
			(thermal_bridge_width 0.5)
			(island_removal_mode 0)
		)
		(polygon
			(pts
				(arc
					(start 310.225948 -275.949918)
					(mid 309.573168 -275.949918)
					(end 310.225948 -275.949918)
				)
			)
		)
	)
	(zone
		(layers "B.Cu" "In7.Cu" "In9.Cu" "In11.Cu" "In13.Cu" "In15.Cu")
		(hatch none 0.5)
		(connect_pads
			(clearance 0)
		)
		(min_thickness 0.25)
		(keepout
			(tracks not_allowed)
			(vias allowed)
			(pads allowed)
			(copperpour not_allowed)
			(footprints allowed)
		)
		(placement
			(enabled no)
			(sheetname "")
		)
		(fill yes
			(thermal_gap 0.5)
			(thermal_bridge_width 0.5)
			(island_removal_mode 0)
		)
		(polygon
			(pts
				(arc
					(start 41.926256 -316.799722)
					(mid 41.273476 -316.799722)
					(end 41.926256 -316.799722)
				)
			)
		)
	)
	(zone
		(layers "B.Cu" "In7.Cu" "In9.Cu" "In11.Cu" "In13.Cu" "In15.Cu")
		(hatch none 0.5)
		(connect_pads
			(clearance 0)
		)
		(min_thickness 0.25)
		(keepout
			(tracks not_allowed)
			(vias allowed)
			(pads allowed)
			(copperpour not_allowed)
			(footprints allowed)
		)
		(placement
			(enabled no)
			(sheetname "")
		)
		(fill yes
			(thermal_gap 0.5)
			(thermal_bridge_width 0.5)
			(island_removal_mode 0)
		)
		(polygon
			(pts
				(arc
					(start 190.32601 -275.949918)
					(mid 189.67323 -275.949918)
					(end 190.32601 -275.949918)
				)
			)
		)
	)
	(zone
		(layers "B.Cu" "In7.Cu" "In9.Cu" "In11.Cu" "In13.Cu" "In15.Cu")
		(hatch none 0.5)
		(connect_pads
			(clearance 0)
		)
		(min_thickness 0.25)
		(keepout
			(tracks not_allowed)
			(vias allowed)
			(pads allowed)
			(copperpour not_allowed)
			(footprints allowed)
		)
		(placement
			(enabled no)
			(sheetname "")
		)
		(fill yes
			(thermal_gap 0.5)
			(thermal_bridge_width 0.5)
			(island_removal_mode 0)
		)
		(polygon
			(pts
				(arc
					(start 52.59451 -109.176312)
					(mid 51.89093 -109.176312)
					(end 52.59451 -109.176312)
				)
			)
		)
	)
	(zone
		(layers "B.Cu" "In7.Cu" "In9.Cu" "In11.Cu" "In13.Cu" "In15.Cu")
		(hatch none 0.5)
		(connect_pads
			(clearance 0)
		)
		(min_thickness 0.25)
		(keepout
			(tracks not_allowed)
			(vias allowed)
			(pads allowed)
			(copperpour not_allowed)
			(footprints allowed)
		)
		(placement
			(enabled no)
			(sheetname "")
		)
		(fill yes
			(thermal_gap 0.5)
			(thermal_bridge_width 0.5)
			(island_removal_mode 0)
		)
		(polygon
			(pts
				(arc
					(start 82.776314 -283.549852)
					(mid 82.123534 -283.549852)
					(end 82.776314 -283.549852)
				)
			)
		)
	)
	(zone
		(layers "B.Cu" "In7.Cu" "In9.Cu" "In11.Cu" "In13.Cu" "In15.Cu")
		(hatch none 0.5)
		(connect_pads
			(clearance 0)
		)
		(min_thickness 0.25)
		(keepout
			(tracks not_allowed)
			(vias allowed)
			(pads allowed)
			(copperpour not_allowed)
			(footprints allowed)
		)
		(placement
			(enabled no)
			(sheetname "")
		)
		(fill yes
			(thermal_gap 0.5)
			(thermal_bridge_width 0.5)
			(island_removal_mode 0)
		)
		(polygon
			(pts
				(arc
					(start 48.57623 -317.749936)
					(mid 47.92345 -317.749936)
					(end 48.57623 -317.749936)
				)
			)
		)
	)
	(zone
		(layers "B.Cu" "In7.Cu" "In9.Cu" "In11.Cu" "In13.Cu" "In15.Cu")
		(hatch none 0.5)
		(connect_pads
			(clearance 0)
		)
		(min_thickness 0.25)
		(keepout
			(tracks not_allowed)
			(vias allowed)
			(pads allowed)
			(copperpour not_allowed)
			(footprints allowed)
		)
		(placement
			(enabled no)
			(sheetname "")
		)
		(fill yes
			(thermal_gap 0.5)
			(thermal_bridge_width 0.5)
			(island_removal_mode 0)
		)
		(polygon
			(pts
				(arc
					(start 297.754802 -132.577332)
					(mid 297.051222 -132.577332)
					(end 297.754802 -132.577332)
				)
			)
		)
	)
	(zone
		(layers "B.Cu" "In7.Cu" "In9.Cu" "In11.Cu" "In13.Cu" "In15.Cu")
		(hatch none 0.5)
		(connect_pads
			(clearance 0)
		)
		(min_thickness 0.25)
		(keepout
			(tracks not_allowed)
			(vias allowed)
			(pads allowed)
			(copperpour not_allowed)
			(footprints allowed)
		)
		(placement
			(enabled no)
			(sheetname "")
		)
		(fill yes
			(thermal_gap 0.5)
			(thermal_bridge_width 0.5)
			(island_removal_mode 0)
		)
		(polygon
			(pts
				(arc
					(start 429.17618 -288.299906)
					(mid 428.5234 -288.299906)
					(end 429.17618 -288.299906)
				)
			)
		)
	)
	(zone
		(layers "B.Cu" "In7.Cu" "In9.Cu" "In11.Cu" "In13.Cu" "In15.Cu")
		(hatch none 0.5)
		(connect_pads
			(clearance 0)
		)
		(min_thickness 0.25)
		(keepout
			(tracks not_allowed)
			(vias allowed)
			(pads allowed)
			(copperpour not_allowed)
			(footprints allowed)
		)
		(placement
			(enabled no)
			(sheetname "")
		)
		(fill yes
			(thermal_gap 0.5)
			(thermal_bridge_width 0.5)
			(island_removal_mode 0)
		)
		(polygon
			(pts
				(arc
					(start 40.026336 -315.849762)
					(mid 39.373556 -315.849762)
					(end 40.026336 -315.849762)
				)
			)
		)
	)
	(zone
		(layers "B.Cu" "In7.Cu" "In9.Cu" "In11.Cu" "In13.Cu" "In15.Cu")
		(hatch none 0.5)
		(connect_pads
			(clearance 0)
		)
		(min_thickness 0.25)
		(keepout
			(tracks not_allowed)
			(vias allowed)
			(pads allowed)
			(copperpour not_allowed)
			(footprints allowed)
		)
		(placement
			(enabled no)
			(sheetname "")
		)
		(fill yes
			(thermal_gap 0.5)
			(thermal_bridge_width 0.5)
			(island_removal_mode 0)
		)
		(polygon
			(pts
				(arc
					(start 400.89455 -125.486414)
					(mid 400.19097 -125.486414)
					(end 400.89455 -125.486414)
				)
			)
		)
	)
	(zone
		(layers "B.Cu" "In7.Cu" "In9.Cu" "In11.Cu" "In13.Cu" "In15.Cu")
		(hatch none 0.5)
		(connect_pads
			(clearance 0)
		)
		(min_thickness 0.25)
		(keepout
			(tracks not_allowed)
			(vias allowed)
			(pads allowed)
			(copperpour not_allowed)
			(footprints allowed)
		)
		(placement
			(enabled no)
			(sheetname "")
		)
		(fill yes
			(thermal_gap 0.5)
			(thermal_bridge_width 0.5)
			(island_removal_mode 0)
		)
		(polygon
			(pts
				(arc
					(start 296.926 -275.949664)
					(mid 296.27322 -275.949664)
					(end 296.926 -275.949664)
				)
			)
		)
	)
	(zone
		(layers "B.Cu" "In7.Cu" "In9.Cu" "In11.Cu" "In13.Cu" "In15.Cu")
		(hatch none 0.5)
		(connect_pads
			(clearance 0)
		)
		(min_thickness 0.25)
		(keepout
			(tracks not_allowed)
			(vias allowed)
			(pads allowed)
			(copperpour not_allowed)
			(footprints allowed)
		)
		(placement
			(enabled no)
			(sheetname "")
		)
		(fill yes
			(thermal_gap 0.5)
			(thermal_bridge_width 0.5)
			(island_removal_mode 0)
		)
		(polygon
			(pts
				(arc
					(start 38.126162 -302.549814)
					(mid 37.473382 -302.549814)
					(end 38.126162 -302.549814)
				)
			)
		)
	)
	(zone
		(layers "B.Cu" "In7.Cu" "In9.Cu" "In11.Cu" "In13.Cu" "In15.Cu")
		(hatch none 0.5)
		(connect_pads
			(clearance 0)
		)
		(min_thickness 0.25)
		(keepout
			(tracks not_allowed)
			(vias allowed)
			(pads allowed)
			(copperpour not_allowed)
			(footprints allowed)
		)
		(placement
			(enabled no)
			(sheetname "")
		)
		(fill yes
			(thermal_gap 0.5)
			(thermal_bridge_width 0.5)
			(island_removal_mode 0)
		)
		(polygon
			(pts
				(arc
					(start 312.126122 -282.599892)
					(mid 311.473342 -282.599892)
					(end 312.126122 -282.599892)
				)
			)
		)
	)
	(zone
		(layers "B.Cu" "In7.Cu" "In9.Cu" "In11.Cu" "In13.Cu" "In15.Cu")
		(hatch none 0.5)
		(connect_pads
			(clearance 0)
		)
		(min_thickness 0.25)
		(keepout
			(tracks not_allowed)
			(vias allowed)
			(pads allowed)
			(copperpour not_allowed)
			(footprints allowed)
		)
		(placement
			(enabled no)
			(sheetname "")
		)
		(fill yes
			(thermal_gap 0.5)
			(thermal_bridge_width 0.5)
			(island_removal_mode 0)
		)
		(polygon
			(pts
				(arc
					(start 276.026118 -316.799722)
					(mid 275.373338 -316.799722)
					(end 276.026118 -316.799722)
				)
			)
		)
	)
	(zone
		(layers "B.Cu" "In7.Cu" "In9.Cu" "In11.Cu" "In13.Cu" "In15.Cu")
		(hatch none 0.5)
		(connect_pads
			(clearance 0)
		)
		(min_thickness 0.25)
		(keepout
			(tracks not_allowed)
			(vias allowed)
			(pads allowed)
			(copperpour not_allowed)
			(footprints allowed)
		)
		(placement
			(enabled no)
			(sheetname "")
		)
		(fill yes
			(thermal_gap 0.5)
			(thermal_bridge_width 0.5)
			(island_removal_mode 0)
		)
		(polygon
			(pts
				(arc
					(start 37.176202 -316.799722)
					(mid 36.523422 -316.799722)
					(end 37.176202 -316.799722)
				)
			)
		)
	)
	(zone
		(layers "B.Cu" "In7.Cu" "In9.Cu" "In11.Cu" "In13.Cu" "In15.Cu")
		(hatch none 0.5)
		(connect_pads
			(clearance 0)
		)
		(min_thickness 0.25)
		(keepout
			(tracks not_allowed)
			(vias allowed)
			(pads allowed)
			(copperpour not_allowed)
			(footprints allowed)
		)
		(placement
			(enabled no)
			(sheetname "")
		)
		(fill yes
			(thermal_gap 0.5)
			(thermal_bridge_width 0.5)
			(island_removal_mode 0)
		)
		(polygon
			(pts
				(arc
					(start 419.86962 -405.589994)
					(mid 419.11016 -405.589994)
					(end 419.86962 -405.589994)
				)
			)
		)
	)
	(zone
		(layers "B.Cu" "In7.Cu" "In9.Cu" "In11.Cu" "In13.Cu" "In15.Cu")
		(hatch none 0.5)
		(connect_pads
			(clearance 0)
		)
		(min_thickness 0.25)
		(keepout
			(tracks not_allowed)
			(vias allowed)
			(pads allowed)
			(copperpour not_allowed)
			(footprints allowed)
		)
		(placement
			(enabled no)
			(sheetname "")
		)
		(fill yes
			(thermal_gap 0.5)
			(thermal_bridge_width 0.5)
			(island_removal_mode 0)
		)
		(polygon
			(pts
				(arc
					(start 347.269816 -371.590062)
					(mid 346.510356 -371.590062)
					(end 347.269816 -371.590062)
				)
			)
		)
	)
	(zone
		(layers "B.Cu" "In7.Cu" "In9.Cu" "In11.Cu" "In13.Cu" "In15.Cu")
		(hatch none 0.5)
		(connect_pads
			(clearance 0)
		)
		(min_thickness 0.25)
		(keepout
			(tracks not_allowed)
			(vias allowed)
			(pads allowed)
			(copperpour not_allowed)
			(footprints allowed)
		)
		(placement
			(enabled no)
			(sheetname "")
		)
		(fill yes
			(thermal_gap 0.5)
			(thermal_bridge_width 0.5)
			(island_removal_mode 0)
		)
		(polygon
			(pts
				(arc
					(start 297.754802 -151.623776)
					(mid 297.051222 -151.623776)
					(end 297.754802 -151.623776)
				)
			)
		)
	)
	(zone
		(layers "B.Cu" "In7.Cu" "In9.Cu" "In11.Cu" "In13.Cu" "In15.Cu")
		(hatch none 0.5)
		(connect_pads
			(clearance 0)
		)
		(min_thickness 0.25)
		(keepout
			(tracks not_allowed)
			(vias allowed)
			(pads allowed)
			(copperpour not_allowed)
			(footprints allowed)
		)
		(placement
			(enabled no)
			(sheetname "")
		)
		(fill yes
			(thermal_gap 0.5)
			(thermal_bridge_width 0.5)
			(island_removal_mode 0)
		)
		(polygon
			(pts
				(arc
					(start 413.8549 -144.423638)
					(mid 413.15132 -144.423638)
					(end 413.8549 -144.423638)
				)
			)
		)
	)
	(zone
		(layers "B.Cu" "In7.Cu" "In9.Cu" "In11.Cu" "In13.Cu" "In15.Cu")
		(hatch none 0.5)
		(connect_pads
			(clearance 0)
		)
		(min_thickness 0.25)
		(keepout
			(tracks not_allowed)
			(vias allowed)
			(pads allowed)
			(copperpour not_allowed)
			(footprints allowed)
		)
		(placement
			(enabled no)
			(sheetname "")
		)
		(fill yes
			(thermal_gap 0.5)
			(thermal_bridge_width 0.5)
			(island_removal_mode 0)
		)
		(polygon
			(pts
				(arc
					(start 61.875924 -273.099784)
					(mid 61.223144 -273.099784)
					(end 61.875924 -273.099784)
				)
			)
		)
	)
	(zone
		(layers "B.Cu" "In7.Cu" "In9.Cu" "In11.Cu" "In13.Cu" "In15.Cu")
		(hatch none 0.5)
		(connect_pads
			(clearance 0)
		)
		(min_thickness 0.25)
		(keepout
			(tracks not_allowed)
			(vias allowed)
			(pads allowed)
			(copperpour not_allowed)
			(footprints allowed)
		)
		(placement
			(enabled no)
			(sheetname "")
		)
		(fill yes
			(thermal_gap 0.5)
			(thermal_bridge_width 0.5)
			(island_removal_mode 0)
		)
		(polygon
			(pts
				(arc
					(start 314.026296 -287.349946)
					(mid 313.373516 -287.349946)
					(end 314.026296 -287.349946)
				)
			)
		)
	)
	(zone
		(layers "B.Cu" "In7.Cu" "In9.Cu" "In11.Cu" "In13.Cu" "In15.Cu")
		(hatch none 0.5)
		(connect_pads
			(clearance 0)
		)
		(min_thickness 0.25)
		(keepout
			(tracks not_allowed)
			(vias allowed)
			(pads allowed)
			(copperpour not_allowed)
			(footprints allowed)
		)
		(placement
			(enabled no)
			(sheetname "")
		)
		(fill yes
			(thermal_gap 0.5)
			(thermal_bridge_width 0.5)
			(island_removal_mode 0)
		)
		(polygon
			(pts
				(arc
					(start 293.125906 -275.949664)
					(mid 292.473126 -275.949664)
					(end 293.125906 -275.949664)
				)
			)
		)
	)
	(zone
		(layers "B.Cu" "In7.Cu" "In9.Cu" "In11.Cu" "In13.Cu" "In15.Cu")
		(hatch none 0.5)
		(connect_pads
			(clearance 0)
		)
		(min_thickness 0.25)
		(keepout
			(tracks not_allowed)
			(vias allowed)
			(pads allowed)
			(copperpour not_allowed)
			(footprints allowed)
		)
		(placement
			(enabled no)
			(sheetname "")
		)
		(fill yes
			(thermal_gap 0.5)
			(thermal_bridge_width 0.5)
			(island_removal_mode 0)
		)
		(polygon
			(pts
				(arc
					(start 415.7091 -143.48714)
					(mid 415.00552 -143.48714)
					(end 415.7091 -143.48714)
				)
			)
		)
	)
	(zone
		(layers "B.Cu" "In7.Cu" "In9.Cu" "In11.Cu" "In13.Cu" "In15.Cu")
		(hatch none 0.5)
		(connect_pads
			(clearance 0)
		)
		(min_thickness 0.25)
		(keepout
			(tracks not_allowed)
			(vias allowed)
			(pads allowed)
			(copperpour not_allowed)
			(footprints allowed)
		)
		(placement
			(enabled no)
			(sheetname "")
		)
		(fill yes
			(thermal_gap 0.5)
			(thermal_bridge_width 0.5)
			(island_removal_mode 0)
		)
		(polygon
			(pts
				(arc
					(start 430.126394 -316.799722)
					(mid 429.473614 -316.799722)
					(end 430.126394 -316.799722)
				)
			)
		)
	)
	(zone
		(layers "B.Cu" "In7.Cu" "In9.Cu" "In11.Cu" "In13.Cu" "In15.Cu")
		(hatch none 0.5)
		(connect_pads
			(clearance 0)
		)
		(min_thickness 0.25)
		(keepout
			(tracks not_allowed)
			(vias allowed)
			(pads allowed)
			(copperpour not_allowed)
			(footprints allowed)
		)
		(placement
			(enabled no)
			(sheetname "")
		)
		(fill yes
			(thermal_gap 0.5)
			(thermal_bridge_width 0.5)
			(island_removal_mode 0)
		)
		(polygon
			(pts
				(arc
					(start 284.794452 -121.886472)
					(mid 284.090872 -121.886472)
					(end 284.794452 -121.886472)
				)
			)
		)
	)
	(zone
		(layers "B.Cu" "In7.Cu" "In9.Cu" "In11.Cu" "In13.Cu" "In15.Cu")
		(hatch none 0.5)
		(connect_pads
			(clearance 0)
		)
		(min_thickness 0.25)
		(keepout
			(tracks not_allowed)
			(vias allowed)
			(pads allowed)
			(copperpour not_allowed)
			(footprints allowed)
		)
		(placement
			(enabled no)
			(sheetname "")
		)
		(fill yes
			(thermal_gap 0.5)
			(thermal_bridge_width 0.5)
			(island_removal_mode 0)
		)
		(polygon
			(pts
				(arc
					(start 197.926452 -304.449734)
					(mid 197.273672 -304.449734)
					(end 197.926452 -304.449734)
				)
			)
		)
	)
	(zone
		(layers "B.Cu" "In7.Cu" "In9.Cu" "In11.Cu" "In13.Cu" "In15.Cu")
		(hatch none 0.5)
		(connect_pads
			(clearance 0)
		)
		(min_thickness 0.25)
		(keepout
			(tracks not_allowed)
			(vias allowed)
			(pads allowed)
			(copperpour not_allowed)
			(footprints allowed)
		)
		(placement
			(enabled no)
			(sheetname "")
		)
		(fill yes
			(thermal_gap 0.5)
			(thermal_bridge_width 0.5)
			(island_removal_mode 0)
		)
		(polygon
			(pts
				(arc
					(start 419.86962 -379.590046)
					(mid 419.11016 -379.590046)
					(end 419.86962 -379.590046)
				)
			)
		)
	)
	(zone
		(layers "B.Cu" "In7.Cu" "In9.Cu" "In11.Cu" "In13.Cu" "In15.Cu")
		(hatch none 0.5)
		(connect_pads
			(clearance 0)
		)
		(min_thickness 0.25)
		(keepout
			(tracks not_allowed)
			(vias allowed)
			(pads allowed)
			(copperpour not_allowed)
			(footprints allowed)
		)
		(placement
			(enabled no)
			(sheetname "")
		)
		(fill yes
			(thermal_gap 0.5)
			(thermal_bridge_width 0.5)
			(island_removal_mode 0)
		)
		(polygon
			(pts
				(arc
					(start 170.548554 -99.31273)
					(mid 169.844974 -99.31273)
					(end 170.548554 -99.31273)
				)
			)
		)
	)
	(zone
		(layers "B.Cu" "In7.Cu" "In9.Cu" "In11.Cu" "In13.Cu" "In15.Cu")
		(hatch none 0.5)
		(connect_pads
			(clearance 0)
		)
		(min_thickness 0.25)
		(keepout
			(tracks not_allowed)
			(vias allowed)
			(pads allowed)
			(copperpour not_allowed)
			(footprints allowed)
		)
		(placement
			(enabled no)
			(sheetname "")
		)
		(fill yes
			(thermal_gap 0.5)
			(thermal_bridge_width 0.5)
			(island_removal_mode 0)
		)
		(polygon
			(pts
				(arc
					(start 402.74875 -123.686316)
					(mid 402.04517 -123.686316)
					(end 402.74875 -123.686316)
				)
			)
		)
	)
	(zone
		(layers "B.Cu" "In7.Cu" "In9.Cu" "In11.Cu" "In13.Cu" "In15.Cu")
		(hatch none 0.5)
		(connect_pads
			(clearance 0)
		)
		(min_thickness 0.25)
		(keepout
			(tracks not_allowed)
			(vias allowed)
			(pads allowed)
			(copperpour not_allowed)
			(footprints allowed)
		)
		(placement
			(enabled no)
			(sheetname "")
		)
		(fill yes
			(thermal_gap 0.5)
			(thermal_bridge_width 0.5)
			(island_removal_mode 0)
		)
		(polygon
			(pts
				(arc
					(start 413.8549 -120.503696)
					(mid 413.15132 -120.503696)
					(end 413.8549 -120.503696)
				)
			)
		)
	)
	(zone
		(layers "B.Cu" "In7.Cu" "In9.Cu" "In11.Cu" "In13.Cu" "In15.Cu")
		(hatch none 0.5)
		(connect_pads
			(clearance 0)
		)
		(min_thickness 0.25)
		(keepout
			(tracks not_allowed)
			(vias allowed)
			(pads allowed)
			(copperpour not_allowed)
			(footprints allowed)
		)
		(placement
			(enabled no)
			(sheetname "")
		)
		(fill yes
			(thermal_gap 0.5)
			(thermal_bridge_width 0.5)
			(island_removal_mode 0)
		)
		(polygon
			(pts
				(arc
					(start 196.026024 -274.999958)
					(mid 195.373244 -274.999958)
					(end 196.026024 -274.999958)
				)
			)
		)
	)
	(zone
		(layers "B.Cu" "In7.Cu" "In9.Cu" "In11.Cu" "In13.Cu" "In15.Cu")
		(hatch none 0.5)
		(connect_pads
			(clearance 0)
		)
		(min_thickness 0.25)
		(keepout
			(tracks not_allowed)
			(vias allowed)
			(pads allowed)
			(copperpour not_allowed)
			(footprints allowed)
		)
		(placement
			(enabled no)
			(sheetname "")
		)
		(fill yes
			(thermal_gap 0.5)
			(thermal_bridge_width 0.5)
			(island_removal_mode 0)
		)
		(polygon
			(pts
				(arc
					(start 54.44871 -103.776272)
					(mid 53.74513 -103.776272)
					(end 54.44871 -103.776272)
				)
			)
		)
	)
	(zone
		(layers "B.Cu" "In7.Cu" "In9.Cu" "In11.Cu" "In13.Cu" "In15.Cu")
		(hatch none 0.5)
		(connect_pads
			(clearance 0)
		)
		(min_thickness 0.25)
		(keepout
			(tracks not_allowed)
			(vias allowed)
			(pads allowed)
			(copperpour not_allowed)
			(footprints allowed)
		)
		(placement
			(enabled no)
			(sheetname "")
		)
		(fill yes
			(thermal_gap 0.5)
			(thermal_bridge_width 0.5)
			(island_removal_mode 0)
		)
		(polygon
			(pts
				(arc
					(start 160.289748 -405.589994)
					(mid 159.530288 -405.589994)
					(end 160.289748 -405.589994)
				)
			)
		)
	)
	(zone
		(layers "B.Cu" "In7.Cu" "In9.Cu" "In11.Cu" "In13.Cu" "In15.Cu")
		(hatch none 0.5)
		(connect_pads
			(clearance 0)
		)
		(min_thickness 0.25)
		(keepout
			(tracks not_allowed)
			(vias allowed)
			(pads allowed)
			(copperpour not_allowed)
			(footprints allowed)
		)
		(placement
			(enabled no)
			(sheetname "")
		)
		(fill yes
			(thermal_gap 0.5)
			(thermal_bridge_width 0.5)
			(island_removal_mode 0)
		)
		(polygon
			(pts
				(arc
					(start 411.125924 -274.999958)
					(mid 410.473144 -274.999958)
					(end 411.125924 -274.999958)
				)
			)
		)
	)
	(zone
		(layers "B.Cu" "In7.Cu" "In9.Cu" "In11.Cu" "In13.Cu" "In15.Cu")
		(hatch none 0.5)
		(connect_pads
			(clearance 0)
		)
		(min_thickness 0.25)
		(keepout
			(tracks not_allowed)
			(vias allowed)
			(pads allowed)
			(copperpour not_allowed)
			(footprints allowed)
		)
		(placement
			(enabled no)
			(sheetname "")
		)
		(fill yes
			(thermal_gap 0.5)
			(thermal_bridge_width 0.5)
			(island_removal_mode 0)
		)
		(polygon
			(pts
				(arc
					(start 32.6898 -409.490164)
					(mid 31.93034 -409.490164)
					(end 32.6898 -409.490164)
				)
			)
		)
	)
	(zone
		(layers "B.Cu" "In7.Cu" "In9.Cu" "In11.Cu" "In13.Cu" "In15.Cu")
		(hatch none 0.5)
		(connect_pads
			(clearance 0)
		)
		(min_thickness 0.25)
		(keepout
			(tracks not_allowed)
			(vias allowed)
			(pads allowed)
			(copperpour not_allowed)
			(footprints allowed)
		)
		(placement
			(enabled no)
			(sheetname "")
		)
		(fill yes
			(thermal_gap 0.5)
			(thermal_bridge_width 0.5)
			(island_removal_mode 0)
		)
		(polygon
			(pts
				(arc
					(start 338.469732 -372.890034)
					(mid 337.710272 -372.890034)
					(end 338.469732 -372.890034)
				)
			)
		)
	)
	(zone
		(layers "B.Cu" "In7.Cu" "In9.Cu" "In11.Cu" "In13.Cu" "In15.Cu")
		(hatch none 0.5)
		(connect_pads
			(clearance 0)
		)
		(min_thickness 0.25)
		(keepout
			(tracks not_allowed)
			(vias allowed)
			(pads allowed)
			(copperpour not_allowed)
			(footprints allowed)
		)
		(placement
			(enabled no)
			(sheetname "")
		)
		(fill yes
			(thermal_gap 0.5)
			(thermal_bridge_width 0.5)
			(island_removal_mode 0)
		)
		(polygon
			(pts
				(arc
					(start 382.469644 -376.790204)
					(mid 381.710184 -376.790204)
					(end 382.469644 -376.790204)
				)
			)
		)
	)
	(zone
		(layers "B.Cu" "In7.Cu" "In9.Cu" "In11.Cu" "In13.Cu" "In15.Cu")
		(hatch none 0.5)
		(connect_pads
			(clearance 0)
		)
		(min_thickness 0.25)
		(keepout
			(tracks not_allowed)
			(vias allowed)
			(pads allowed)
			(copperpour not_allowed)
			(footprints allowed)
		)
		(placement
			(enabled no)
			(sheetname "")
		)
		(fill yes
			(thermal_gap 0.5)
			(thermal_bridge_width 0.5)
			(island_removal_mode 0)
		)
		(polygon
			(pts
				(arc
					(start 410.176218 -318.699896)
					(mid 409.523438 -318.699896)
					(end 410.176218 -318.699896)
				)
			)
		)
	)
	(zone
		(layers "B.Cu" "In7.Cu" "In9.Cu" "In11.Cu" "In13.Cu" "In15.Cu")
		(hatch none 0.5)
		(connect_pads
			(clearance 0)
		)
		(min_thickness 0.25)
		(keepout
			(tracks not_allowed)
			(vias allowed)
			(pads allowed)
			(copperpour not_allowed)
			(footprints allowed)
		)
		(placement
			(enabled no)
			(sheetname "")
		)
		(fill yes
			(thermal_gap 0.5)
			(thermal_bridge_width 0.5)
			(island_removal_mode 0)
		)
		(polygon
			(pts
				(arc
					(start 402.74875 -107.376214)
					(mid 402.04517 -107.376214)
					(end 402.74875 -107.376214)
				)
			)
		)
	)
	(zone
		(layers "B.Cu" "In7.Cu" "In9.Cu" "In11.Cu" "In13.Cu" "In15.Cu")
		(hatch none 0.5)
		(connect_pads
			(clearance 0)
		)
		(min_thickness 0.25)
		(keepout
			(tracks not_allowed)
			(vias allowed)
			(pads allowed)
			(copperpour not_allowed)
			(footprints allowed)
		)
		(placement
			(enabled no)
			(sheetname "")
		)
		(fill yes
			(thermal_gap 0.5)
			(thermal_bridge_width 0.5)
			(island_removal_mode 0)
		)
		(polygon
			(pts
				(arc
					(start 426.469556 -406.690068)
					(mid 425.710096 -406.690068)
					(end 426.469556 -406.690068)
				)
			)
		)
	)
	(zone
		(layers "B.Cu" "In7.Cu" "In9.Cu" "In11.Cu" "In13.Cu" "In15.Cu")
		(hatch none 0.5)
		(connect_pads
			(clearance 0)
		)
		(min_thickness 0.25)
		(keepout
			(tracks not_allowed)
			(vias allowed)
			(pads allowed)
			(copperpour not_allowed)
			(footprints allowed)
		)
		(placement
			(enabled no)
			(sheetname "")
		)
		(fill yes
			(thermal_gap 0.5)
			(thermal_bridge_width 0.5)
			(island_removal_mode 0)
		)
		(polygon
			(pts
				(arc
					(start 175.689768 -379.390148)
					(mid 174.930308 -379.390148)
					(end 175.689768 -379.390148)
				)
			)
		)
	)
	(zone
		(layers "B.Cu" "In7.Cu" "In9.Cu" "In11.Cu" "In13.Cu" "In15.Cu")
		(hatch none 0.5)
		(connect_pads
			(clearance 0)
		)
		(min_thickness 0.25)
		(keepout
			(tracks not_allowed)
			(vias allowed)
			(pads allowed)
			(copperpour not_allowed)
			(footprints allowed)
		)
		(placement
			(enabled no)
			(sheetname "")
		)
		(fill yes
			(thermal_gap 0.5)
			(thermal_bridge_width 0.5)
			(island_removal_mode 0)
		)
		(polygon
			(pts
				(arc
					(start 431.076354 -287.349946)
					(mid 430.423574 -287.349946)
					(end 431.076354 -287.349946)
				)
			)
		)
	)
	(zone
		(layers "B.Cu" "In7.Cu" "In9.Cu" "In11.Cu" "In13.Cu" "In15.Cu")
		(hatch none 0.5)
		(connect_pads
			(clearance 0)
		)
		(min_thickness 0.25)
		(keepout
			(tracks not_allowed)
			(vias allowed)
			(pads allowed)
			(copperpour not_allowed)
			(footprints allowed)
		)
		(placement
			(enabled no)
			(sheetname "")
		)
		(fill yes
			(thermal_gap 0.5)
			(thermal_bridge_width 0.5)
			(island_removal_mode 0)
		)
		(polygon
			(pts
				(arc
					(start 39.076376 -305.399948)
					(mid 38.423596 -305.399948)
					(end 39.076376 -305.399948)
				)
			)
		)
	)
	(zone
		(layers "B.Cu" "In7.Cu" "In9.Cu" "In11.Cu" "In13.Cu" "In15.Cu")
		(hatch none 0.5)
		(connect_pads
			(clearance 0)
		)
		(min_thickness 0.25)
		(keepout
			(tracks not_allowed)
			(vias allowed)
			(pads allowed)
			(copperpour not_allowed)
			(footprints allowed)
		)
		(placement
			(enabled no)
			(sheetname "")
		)
		(fill yes
			(thermal_gap 0.5)
			(thermal_bridge_width 0.5)
			(island_removal_mode 0)
		)
		(polygon
			(pts
				(arc
					(start 127.289814 -397.59001)
					(mid 126.530354 -397.59001)
					(end 127.289814 -397.59001)
				)
			)
		)
	)
	(zone
		(layers "B.Cu" "In7.Cu" "In9.Cu" "In11.Cu" "In13.Cu" "In15.Cu")
		(hatch none 0.5)
		(connect_pads
			(clearance 0)
		)
		(min_thickness 0.25)
		(keepout
			(tracks not_allowed)
			(vias allowed)
			(pads allowed)
			(copperpour not_allowed)
			(footprints allowed)
		)
		(placement
			(enabled no)
			(sheetname "")
		)
		(fill yes
			(thermal_gap 0.5)
			(thermal_bridge_width 0.5)
			(island_removal_mode 0)
		)
		(polygon
			(pts
				(arc
					(start 298.869608 -383.290064)
					(mid 298.110148 -383.290064)
					(end 298.869608 -383.290064)
				)
			)
		)
	)
	(zone
		(layers "B.Cu" "In7.Cu" "In9.Cu" "In11.Cu" "In13.Cu" "In15.Cu")
		(hatch none 0.5)
		(connect_pads
			(clearance 0)
		)
		(min_thickness 0.25)
		(keepout
			(tracks not_allowed)
			(vias allowed)
			(pads allowed)
			(copperpour not_allowed)
			(footprints allowed)
		)
		(placement
			(enabled no)
			(sheetname "")
		)
		(fill yes
			(thermal_gap 0.5)
			(thermal_bridge_width 0.5)
			(island_removal_mode 0)
		)
		(polygon
			(pts
				(arc
					(start 272.226278 -301.599854)
					(mid 271.573498 -301.599854)
					(end 272.226278 -301.599854)
				)
			)
		)
	)
	(zone
		(layers "B.Cu" "In7.Cu" "In9.Cu" "In11.Cu" "In13.Cu" "In15.Cu")
		(hatch none 0.5)
		(connect_pads
			(clearance 0)
		)
		(min_thickness 0.25)
		(keepout
			(tracks not_allowed)
			(vias allowed)
			(pads allowed)
			(copperpour not_allowed)
			(footprints allowed)
		)
		(placement
			(enabled no)
			(sheetname "")
		)
		(fill yes
			(thermal_gap 0.5)
			(thermal_bridge_width 0.5)
			(island_removal_mode 0)
		)
		(polygon
			(pts
				(arc
					(start 83.289648 -401.49018)
					(mid 82.530188 -401.49018)
					(end 83.289648 -401.49018)
				)
			)
		)
	)
	(zone
		(layers "B.Cu" "In7.Cu" "In9.Cu" "In11.Cu" "In13.Cu" "In15.Cu")
		(hatch none 0.5)
		(connect_pads
			(clearance 0)
		)
		(min_thickness 0.25)
		(keepout
			(tracks not_allowed)
			(vias allowed)
			(pads allowed)
			(copperpour not_allowed)
			(footprints allowed)
		)
		(placement
			(enabled no)
			(sheetname "")
		)
		(fill yes
			(thermal_gap 0.5)
			(thermal_bridge_width 0.5)
			(island_removal_mode 0)
		)
		(polygon
			(pts
				(arc
					(start 305.476148 -317.749936)
					(mid 304.823368 -317.749936)
					(end 305.476148 -317.749936)
				)
			)
		)
	)
	(zone
		(layers "B.Cu" "In7.Cu" "In9.Cu" "In11.Cu" "In13.Cu" "In15.Cu")
		(hatch none 0.5)
		(connect_pads
			(clearance 0)
		)
		(min_thickness 0.25)
		(keepout
			(tracks not_allowed)
			(vias allowed)
			(pads allowed)
			(copperpour not_allowed)
			(footprints allowed)
		)
		(placement
			(enabled no)
			(sheetname "")
		)
		(fill yes
			(thermal_gap 0.5)
			(thermal_bridge_width 0.5)
			(island_removal_mode 0)
		)
		(polygon
			(pts
				(arc
					(start 194.126358 -316.799722)
					(mid 193.473578 -316.799722)
					(end 194.126358 -316.799722)
				)
			)
		)
	)
	(zone
		(layers "B.Cu" "In7.Cu" "In9.Cu" "In11.Cu" "In13.Cu" "In15.Cu")
		(hatch none 0.5)
		(connect_pads
			(clearance 0)
		)
		(min_thickness 0.25)
		(keepout
			(tracks not_allowed)
			(vias allowed)
			(pads allowed)
			(copperpour not_allowed)
			(footprints allowed)
		)
		(placement
			(enabled no)
			(sheetname "")
		)
		(fill yes
			(thermal_gap 0.5)
			(thermal_bridge_width 0.5)
			(island_removal_mode 0)
		)
		(polygon
			(pts
				(arc
					(start 197.926452 -274.999704)
					(mid 197.273672 -274.999704)
					(end 197.926452 -274.999704)
				)
			)
		)
	)
	(zone
		(layers "B.Cu" "In7.Cu" "In9.Cu" "In11.Cu" "In13.Cu" "In15.Cu")
		(hatch none 0.5)
		(connect_pads
			(clearance 0)
		)
		(min_thickness 0.25)
		(keepout
			(tracks not_allowed)
			(vias allowed)
			(pads allowed)
			(copperpour not_allowed)
			(footprints allowed)
		)
		(placement
			(enabled no)
			(sheetname "")
		)
		(fill yes
			(thermal_gap 0.5)
			(thermal_bridge_width 0.5)
			(island_removal_mode 0)
		)
		(polygon
			(pts
				(arc
					(start 299.609002 -119.567198)
					(mid 298.905422 -119.567198)
					(end 299.609002 -119.567198)
				)
			)
		)
	)
	(zone
		(layers "B.Cu" "In7.Cu" "In9.Cu" "In11.Cu" "In13.Cu" "In15.Cu")
		(hatch none 0.5)
		(connect_pads
			(clearance 0)
		)
		(min_thickness 0.25)
		(keepout
			(tracks not_allowed)
			(vias allowed)
			(pads allowed)
			(copperpour not_allowed)
			(footprints allowed)
		)
		(placement
			(enabled no)
			(sheetname "")
		)
		(fill yes
			(thermal_gap 0.5)
			(thermal_bridge_width 0.5)
			(island_removal_mode 0)
		)
		(polygon
			(pts
				(arc
					(start 170.548554 -103.776272)
					(mid 169.844974 -103.776272)
					(end 170.548554 -103.776272)
				)
			)
		)
	)
	(zone
		(layers "B.Cu" "In7.Cu" "In9.Cu" "In11.Cu" "In13.Cu" "In15.Cu")
		(hatch none 0.5)
		(connect_pads
			(clearance 0)
		)
		(min_thickness 0.25)
		(keepout
			(tracks not_allowed)
			(vias allowed)
			(pads allowed)
			(copperpour not_allowed)
			(footprints allowed)
		)
		(placement
			(enabled no)
			(sheetname "")
		)
		(fill yes
			(thermal_gap 0.5)
			(thermal_bridge_width 0.5)
			(island_removal_mode 0)
		)
		(polygon
			(pts
				(arc
					(start 65.55486 -148.887434)
					(mid 64.85128 -148.887434)
					(end 65.55486 -148.887434)
				)
			)
		)
	)
	(zone
		(layers "B.Cu" "In7.Cu" "In9.Cu" "In11.Cu" "In13.Cu" "In15.Cu")
		(hatch none 0.5)
		(connect_pads
			(clearance 0)
		)
		(min_thickness 0.25)
		(keepout
			(tracks not_allowed)
			(vias allowed)
			(pads allowed)
			(copperpour not_allowed)
			(footprints allowed)
		)
		(placement
			(enabled no)
			(sheetname "")
		)
		(fill yes
			(thermal_gap 0.5)
			(thermal_bridge_width 0.5)
			(island_removal_mode 0)
		)
		(polygon
			(pts
				(arc
					(start 297.754802 -124.103638)
					(mid 297.051222 -124.103638)
					(end 297.754802 -124.103638)
				)
			)
		)
	)
	(zone
		(layers "B.Cu" "In7.Cu" "In9.Cu" "In11.Cu" "In13.Cu" "In15.Cu")
		(hatch none 0.5)
		(connect_pads
			(clearance 0)
		)
		(min_thickness 0.25)
		(keepout
			(tracks not_allowed)
			(vias allowed)
			(pads allowed)
			(copperpour not_allowed)
			(footprints allowed)
		)
		(placement
			(enabled no)
			(sheetname "")
		)
		(fill yes
			(thermal_gap 0.5)
			(thermal_bridge_width 0.5)
			(island_removal_mode 0)
		)
		(polygon
			(pts
				(arc
					(start 314.976256 -285.449772)
					(mid 314.323476 -285.449772)
					(end 314.976256 -285.449772)
				)
			)
		)
	)
	(zone
		(layers "B.Cu" "In7.Cu" "In9.Cu" "In11.Cu" "In13.Cu" "In15.Cu")
		(hatch none 0.5)
		(connect_pads
			(clearance 0)
		)
		(min_thickness 0.25)
		(keepout
			(tracks not_allowed)
			(vias allowed)
			(pads allowed)
			(copperpour not_allowed)
			(footprints allowed)
		)
		(placement
			(enabled no)
			(sheetname "")
		)
		(fill yes
			(thermal_gap 0.5)
			(thermal_bridge_width 0.5)
			(island_removal_mode 0)
		)
		(polygon
			(pts
				(arc
					(start 195.076064 -273.099784)
					(mid 194.423284 -273.099784)
					(end 195.076064 -273.099784)
				)
			)
		)
	)
	(zone
		(layers "B.Cu" "In7.Cu" "In9.Cu" "In11.Cu" "In13.Cu" "In15.Cu")
		(hatch none 0.5)
		(connect_pads
			(clearance 0)
		)
		(min_thickness 0.25)
		(keepout
			(tracks not_allowed)
			(vias allowed)
			(pads allowed)
			(copperpour not_allowed)
			(footprints allowed)
		)
		(placement
			(enabled no)
			(sheetname "")
		)
		(fill yes
			(thermal_gap 0.5)
			(thermal_bridge_width 0.5)
			(island_removal_mode 0)
		)
		(polygon
			(pts
				(arc
					(start 170.548554 -131.29641)
					(mid 169.844974 -131.29641)
					(end 170.548554 -131.29641)
				)
			)
		)
	)
	(zone
		(layers "B.Cu" "In7.Cu" "In9.Cu" "In11.Cu" "In13.Cu" "In15.Cu")
		(hatch none 0.5)
		(connect_pads
			(clearance 0)
		)
		(min_thickness 0.25)
		(keepout
			(tracks not_allowed)
			(vias allowed)
			(pads allowed)
			(copperpour not_allowed)
			(footprints allowed)
		)
		(placement
			(enabled no)
			(sheetname "")
		)
		(fill yes
			(thermal_gap 0.5)
			(thermal_bridge_width 0.5)
			(island_removal_mode 0)
		)
		(polygon
			(pts
				(arc
					(start 347.269816 -401.49018)
					(mid 346.510356 -401.49018)
					(end 347.269816 -401.49018)
				)
			)
		)
	)
	(zone
		(layers "B.Cu" "In7.Cu" "In9.Cu" "In11.Cu" "In13.Cu" "In15.Cu")
		(hatch none 0.5)
		(connect_pads
			(clearance 0)
		)
		(min_thickness 0.25)
		(keepout
			(tracks not_allowed)
			(vias allowed)
			(pads allowed)
			(copperpour not_allowed)
			(footprints allowed)
		)
		(placement
			(enabled no)
			(sheetname "")
		)
		(fill yes
			(thermal_gap 0.5)
			(thermal_bridge_width 0.5)
			(island_removal_mode 0)
		)
		(polygon
			(pts
				(arc
					(start 276.976078 -318.699896)
					(mid 276.323298 -318.699896)
					(end 276.976078 -318.699896)
				)
			)
		)
	)
	(zone
		(layers "B.Cu" "In7.Cu" "In9.Cu" "In11.Cu" "In13.Cu" "In15.Cu")
		(hatch none 0.5)
		(connect_pads
			(clearance 0)
		)
		(min_thickness 0.25)
		(keepout
			(tracks not_allowed)
			(vias allowed)
			(pads allowed)
			(copperpour not_allowed)
			(footprints allowed)
		)
		(placement
			(enabled no)
			(sheetname "")
		)
		(fill yes
			(thermal_gap 0.5)
			(thermal_bridge_width 0.5)
			(island_removal_mode 0)
		)
		(polygon
			(pts
				(arc
					(start 160.289748 -378.290074)
					(mid 159.530288 -378.290074)
					(end 160.289748 -378.290074)
				)
			)
		)
	)
	(zone
		(layers "B.Cu" "In7.Cu" "In9.Cu" "In11.Cu" "In13.Cu" "In15.Cu")
		(hatch none 0.5)
		(connect_pads
			(clearance 0)
		)
		(min_thickness 0.25)
		(keepout
			(tracks not_allowed)
			(vias allowed)
			(pads allowed)
			(copperpour not_allowed)
			(footprints allowed)
		)
		(placement
			(enabled no)
			(sheetname "")
		)
		(fill yes
			(thermal_gap 0.5)
			(thermal_bridge_width 0.5)
			(island_removal_mode 0)
		)
		(polygon
			(pts
				(arc
					(start 302.626268 -315.849762)
					(mid 301.973488 -315.849762)
					(end 302.626268 -315.849762)
				)
			)
		)
	)
	(zone
		(layers "B.Cu" "In7.Cu" "In9.Cu" "In11.Cu" "In13.Cu" "In15.Cu")
		(hatch none 0.5)
		(connect_pads
			(clearance 0)
		)
		(min_thickness 0.25)
		(keepout
			(tracks not_allowed)
			(vias allowed)
			(pads allowed)
			(copperpour not_allowed)
			(footprints allowed)
		)
		(placement
			(enabled no)
			(sheetname "")
		)
		(fill yes
			(thermal_gap 0.5)
			(thermal_bridge_width 0.5)
			(island_removal_mode 0)
		)
		(polygon
			(pts
				(arc
					(start 314.976256 -283.549852)
					(mid 314.323476 -283.549852)
					(end 314.976256 -283.549852)
				)
			)
		)
	)
	(zone
		(layers "B.Cu" "In7.Cu" "In9.Cu" "In11.Cu" "In13.Cu" "In15.Cu")
		(hatch none 0.5)
		(connect_pads
			(clearance 0)
		)
		(min_thickness 0.25)
		(keepout
			(tracks not_allowed)
			(vias allowed)
			(pads allowed)
			(copperpour not_allowed)
			(footprints allowed)
		)
		(placement
			(enabled no)
			(sheetname "")
		)
		(fill yes
			(thermal_gap 0.5)
			(thermal_bridge_width 0.5)
			(island_removal_mode 0)
		)
		(polygon
			(pts
				(arc
					(start 197.926452 -283.549852)
					(mid 197.273672 -283.549852)
					(end 197.926452 -283.549852)
				)
			)
		)
	)
	(zone
		(layers "B.Cu" "In7.Cu" "In9.Cu" "In11.Cu" "In13.Cu" "In15.Cu")
		(hatch none 0.5)
		(connect_pads
			(clearance 0)
		)
		(min_thickness 0.25)
		(keepout
			(tracks not_allowed)
			(vias allowed)
			(pads allowed)
			(copperpour not_allowed)
			(footprints allowed)
		)
		(placement
			(enabled no)
			(sheetname "")
		)
		(fill yes
			(thermal_gap 0.5)
			(thermal_bridge_width 0.5)
			(island_removal_mode 0)
		)
		(polygon
			(pts
				(arc
					(start 71.376286 -317.749936)
					(mid 70.723506 -317.749936)
					(end 71.376286 -317.749936)
				)
			)
		)
	)
	(zone
		(layers "B.Cu" "In7.Cu" "In9.Cu" "In11.Cu" "In13.Cu" "In15.Cu")
		(hatch none 0.5)
		(connect_pads
			(clearance 0)
		)
		(min_thickness 0.25)
		(keepout
			(tracks not_allowed)
			(vias allowed)
			(pads allowed)
			(copperpour not_allowed)
			(footprints allowed)
		)
		(placement
			(enabled no)
			(sheetname "")
		)
		(fill yes
			(thermal_gap 0.5)
			(thermal_bridge_width 0.5)
			(island_removal_mode 0)
		)
		(polygon
			(pts
				(arc
					(start 292.269672 -383.490216)
					(mid 291.510212 -383.490216)
					(end 292.269672 -383.490216)
				)
			)
		)
	)
	(zone
		(layers "B.Cu" "In7.Cu" "In9.Cu" "In11.Cu" "In13.Cu" "In15.Cu")
		(hatch none 0.5)
		(connect_pads
			(clearance 0)
		)
		(min_thickness 0.25)
		(keepout
			(tracks not_allowed)
			(vias allowed)
			(pads allowed)
			(copperpour not_allowed)
			(footprints allowed)
		)
		(placement
			(enabled no)
			(sheetname "")
		)
		(fill yes
			(thermal_gap 0.5)
			(thermal_bridge_width 0.5)
			(island_removal_mode 0)
		)
		(polygon
			(pts
				(arc
					(start 378.069602 -397.59001)
					(mid 377.310142 -397.59001)
					(end 378.069602 -397.59001)
				)
			)
		)
	)
	(zone
		(layers "B.Cu" "In7.Cu" "In9.Cu" "In11.Cu" "In13.Cu" "In15.Cu")
		(hatch none 0.5)
		(connect_pads
			(clearance 0)
		)
		(min_thickness 0.25)
		(keepout
			(tracks not_allowed)
			(vias allowed)
			(pads allowed)
			(copperpour not_allowed)
			(footprints allowed)
		)
		(placement
			(enabled no)
			(sheetname "")
		)
		(fill yes
			(thermal_gap 0.5)
			(thermal_bridge_width 0.5)
			(island_removal_mode 0)
		)
		(polygon
			(pts
				(arc
					(start 43.826176 -315.849762)
					(mid 43.173396 -315.849762)
					(end 43.826176 -315.849762)
				)
			)
		)
	)
	(zone
		(layers "B.Cu" "In7.Cu" "In9.Cu" "In11.Cu" "In13.Cu" "In15.Cu")
		(hatch none 0.5)
		(connect_pads
			(clearance 0)
		)
		(min_thickness 0.25)
		(keepout
			(tracks not_allowed)
			(vias allowed)
			(pads allowed)
			(copperpour not_allowed)
			(footprints allowed)
		)
		(placement
			(enabled no)
			(sheetname "")
		)
		(fill yes
			(thermal_gap 0.5)
			(thermal_bridge_width 0.5)
			(island_removal_mode 0)
		)
		(polygon
			(pts
				(arc
					(start 87.68969 -401.49018)
					(mid 86.93023 -401.49018)
					(end 87.68969 -401.49018)
				)
			)
		)
	)
	(zone
		(layers "B.Cu" "In7.Cu" "In9.Cu" "In11.Cu" "In13.Cu" "In15.Cu")
		(hatch none 0.5)
		(connect_pads
			(clearance 0)
		)
		(min_thickness 0.25)
		(keepout
			(tracks not_allowed)
			(vias allowed)
			(pads allowed)
			(copperpour not_allowed)
			(footprints allowed)
		)
		(placement
			(enabled no)
			(sheetname "")
		)
		(fill yes
			(thermal_gap 0.5)
			(thermal_bridge_width 0.5)
			(island_removal_mode 0)
		)
		(polygon
			(pts
				(arc
					(start 40.026336 -303.499774)
					(mid 39.373556 -303.499774)
					(end 40.026336 -303.499774)
				)
			)
		)
	)
	(zone
		(layers "B.Cu" "In7.Cu" "In9.Cu" "In11.Cu" "In13.Cu" "In15.Cu")
		(hatch none 0.5)
		(connect_pads
			(clearance 0)
		)
		(min_thickness 0.25)
		(keepout
			(tracks not_allowed)
			(vias allowed)
			(pads allowed)
			(copperpour not_allowed)
			(footprints allowed)
		)
		(placement
			(enabled no)
			(sheetname "")
		)
		(fill yes
			(thermal_gap 0.5)
			(thermal_bridge_width 0.5)
			(island_removal_mode 0)
		)
		(polygon
			(pts
				(arc
					(start 284.794452 -136.69645)
					(mid 284.090872 -136.69645)
					(end 284.794452 -136.69645)
				)
			)
		)
	)
	(zone
		(layers "B.Cu" "In7.Cu" "In9.Cu" "In11.Cu" "In13.Cu" "In15.Cu")
		(hatch none 0.5)
		(connect_pads
			(clearance 0)
		)
		(min_thickness 0.25)
		(keepout
			(tracks not_allowed)
			(vias allowed)
			(pads allowed)
			(copperpour not_allowed)
			(footprints allowed)
		)
		(placement
			(enabled no)
			(sheetname "")
		)
		(fill yes
			(thermal_gap 0.5)
			(thermal_bridge_width 0.5)
			(island_removal_mode 0)
		)
		(polygon
			(pts
				(arc
					(start 196.976238 -282.599892)
					(mid 196.323458 -282.599892)
					(end 196.976238 -282.599892)
				)
			)
		)
	)
	(zone
		(layers "B.Cu" "In7.Cu" "In9.Cu" "In11.Cu" "In13.Cu" "In15.Cu")
		(hatch none 0.5)
		(connect_pads
			(clearance 0)
		)
		(min_thickness 0.25)
		(keepout
			(tracks not_allowed)
			(vias allowed)
			(pads allowed)
			(copperpour not_allowed)
			(footprints allowed)
		)
		(placement
			(enabled no)
			(sheetname "")
		)
		(fill yes
			(thermal_gap 0.5)
			(thermal_bridge_width 0.5)
			(island_removal_mode 0)
		)
		(polygon
			(pts
				(arc
					(start 284.794452 -133.096508)
					(mid 284.090872 -133.096508)
					(end 284.794452 -133.096508)
				)
			)
		)
	)
	(zone
		(layers "B.Cu" "In7.Cu" "In9.Cu" "In11.Cu" "In13.Cu" "In15.Cu")
		(hatch none 0.5)
		(connect_pads
			(clearance 0)
		)
		(min_thickness 0.25)
		(keepout
			(tracks not_allowed)
			(vias allowed)
			(pads allowed)
			(copperpour not_allowed)
			(footprints allowed)
		)
		(placement
			(enabled no)
			(sheetname "")
		)
		(fill yes
			(thermal_gap 0.5)
			(thermal_bridge_width 0.5)
			(island_removal_mode 0)
		)
		(polygon
			(pts
				(arc
					(start 188.42609 -275.949664)
					(mid 187.77331 -275.949664)
					(end 188.42609 -275.949664)
				)
			)
		)
	)
	(zone
		(layers "B.Cu" "In7.Cu" "In9.Cu" "In11.Cu" "In13.Cu" "In15.Cu")
		(hatch none 0.5)
		(connect_pads
			(clearance 0)
		)
		(min_thickness 0.25)
		(keepout
			(tracks not_allowed)
			(vias allowed)
			(pads allowed)
			(copperpour not_allowed)
			(footprints allowed)
		)
		(placement
			(enabled no)
			(sheetname "")
		)
		(fill yes
			(thermal_gap 0.5)
			(thermal_bridge_width 0.5)
			(island_removal_mode 0)
		)
		(polygon
			(pts
				(arc
					(start 304.525934 -274.999704)
					(mid 303.873154 -274.999704)
					(end 304.525934 -274.999704)
				)
			)
		)
	)
	(zone
		(layers "B.Cu" "In7.Cu" "In9.Cu" "In11.Cu" "In13.Cu" "In15.Cu")
		(hatch none 0.5)
		(connect_pads
			(clearance 0)
		)
		(min_thickness 0.25)
		(keepout
			(tracks not_allowed)
			(vias allowed)
			(pads allowed)
			(copperpour not_allowed)
			(footprints allowed)
		)
		(placement
			(enabled no)
			(sheetname "")
		)
		(fill yes
			(thermal_gap 0.5)
			(thermal_bridge_width 0.5)
			(island_removal_mode 0)
		)
		(polygon
			(pts
				(arc
					(start 402.74875 -110.97641)
					(mid 402.04517 -110.97641)
					(end 402.74875 -110.97641)
				)
			)
		)
	)
	(zone
		(layers "B.Cu" "In7.Cu" "In9.Cu" "In11.Cu" "In13.Cu" "In15.Cu")
		(hatch none 0.5)
		(connect_pads
			(clearance 0)
		)
		(min_thickness 0.25)
		(keepout
			(tracks not_allowed)
			(vias allowed)
			(pads allowed)
			(copperpour not_allowed)
			(footprints allowed)
		)
		(placement
			(enabled no)
			(sheetname "")
		)
		(fill yes
			(thermal_gap 0.5)
			(thermal_bridge_width 0.5)
			(island_removal_mode 0)
		)
		(polygon
			(pts
				(arc
					(start 409.226004 -275.949664)
					(mid 408.573224 -275.949664)
					(end 409.226004 -275.949664)
				)
			)
		)
	)
	(zone
		(layers "B.Cu" "In7.Cu" "In9.Cu" "In11.Cu" "In13.Cu" "In15.Cu")
		(hatch none 0.5)
		(connect_pads
			(clearance 0)
		)
		(min_thickness 0.25)
		(keepout
			(tracks not_allowed)
			(vias allowed)
			(pads allowed)
			(copperpour not_allowed)
			(footprints allowed)
		)
		(placement
			(enabled no)
			(sheetname "")
		)
		(fill yes
			(thermal_gap 0.5)
			(thermal_bridge_width 0.5)
			(island_removal_mode 0)
		)
		(polygon
			(pts
				(arc
					(start 179.87645 -318.699896)
					(mid 179.22367 -318.699896)
					(end 179.87645 -318.699896)
				)
			)
		)
	)
	(zone
		(layers "B.Cu" "In7.Cu" "In9.Cu" "In11.Cu" "In13.Cu" "In15.Cu")
		(hatch none 0.5)
		(connect_pads
			(clearance 0)
		)
		(min_thickness 0.25)
		(keepout
			(tracks not_allowed)
			(vias allowed)
			(pads allowed)
			(copperpour not_allowed)
			(footprints allowed)
		)
		(placement
			(enabled no)
			(sheetname "")
		)
		(fill yes
			(thermal_gap 0.5)
			(thermal_bridge_width 0.5)
			(island_removal_mode 0)
		)
		(polygon
			(pts
				(arc
					(start 241.494818 -225.231198)
					(mid 240.791238 -225.231198)
					(end 241.494818 -225.231198)
				)
			)
		)
	)
	(zone
		(layers "B.Cu" "In7.Cu" "In9.Cu" "In11.Cu" "In13.Cu" "In15.Cu")
		(hatch none 0.5)
		(connect_pads
			(clearance 0)
		)
		(min_thickness 0.25)
		(keepout
			(tracks not_allowed)
			(vias allowed)
			(pads allowed)
			(copperpour not_allowed)
			(footprints allowed)
		)
		(placement
			(enabled no)
			(sheetname "")
		)
		(fill yes
			(thermal_gap 0.5)
			(thermal_bridge_width 0.5)
			(island_removal_mode 0)
		)
		(polygon
			(pts
				(arc
					(start 401.626324 -316.799722)
					(mid 400.973544 -316.799722)
					(end 401.626324 -316.799722)
				)
			)
		)
	)
	(zone
		(layers "B.Cu" "In7.Cu" "In9.Cu" "In11.Cu" "In13.Cu" "In15.Cu")
		(hatch none 0.5)
		(connect_pads
			(clearance 0)
		)
		(min_thickness 0.25)
		(keepout
			(tracks not_allowed)
			(vias allowed)
			(pads allowed)
			(copperpour not_allowed)
			(footprints allowed)
		)
		(placement
			(enabled no)
			(sheetname "")
		)
		(fill yes
			(thermal_gap 0.5)
			(thermal_bridge_width 0.5)
			(island_removal_mode 0)
		)
		(polygon
			(pts
				(arc
					(start 428.669704 -405.589994)
					(mid 427.910244 -405.589994)
					(end 428.669704 -405.589994)
				)
			)
		)
	)
	(zone
		(layers "B.Cu" "In7.Cu" "In9.Cu" "In11.Cu" "In13.Cu" "In15.Cu")
		(hatch none 0.5)
		(connect_pads
			(clearance 0)
		)
		(min_thickness 0.25)
		(keepout
			(tracks not_allowed)
			(vias allowed)
			(pads allowed)
			(copperpour not_allowed)
			(footprints allowed)
		)
		(placement
			(enabled no)
			(sheetname "")
		)
		(fill yes
			(thermal_gap 0.5)
			(thermal_bridge_width 0.5)
			(island_removal_mode 0)
		)
		(polygon
			(pts
				(arc
					(start 412.076392 -318.699896)
					(mid 411.423612 -318.699896)
					(end 412.076392 -318.699896)
				)
			)
		)
	)
	(zone
		(layers "B.Cu" "In7.Cu" "In9.Cu" "In11.Cu" "In13.Cu" "In15.Cu")
		(hatch none 0.5)
		(connect_pads
			(clearance 0)
		)
		(min_thickness 0.25)
		(keepout
			(tracks not_allowed)
			(vias allowed)
			(pads allowed)
			(copperpour not_allowed)
			(footprints allowed)
		)
		(placement
			(enabled no)
			(sheetname "")
		)
		(fill yes
			(thermal_gap 0.5)
			(thermal_bridge_width 0.5)
			(island_removal_mode 0)
		)
		(polygon
			(pts
				(arc
					(start 83.289648 -371.590062)
					(mid 82.530188 -371.590062)
					(end 83.289648 -371.590062)
				)
			)
		)
	)
	(zone
		(layers "B.Cu" "In7.Cu" "In9.Cu" "In11.Cu" "In13.Cu" "In15.Cu")
		(hatch none 0.5)
		(connect_pads
			(clearance 0)
		)
		(min_thickness 0.25)
		(keepout
			(tracks not_allowed)
			(vias allowed)
			(pads allowed)
			(copperpour not_allowed)
			(footprints allowed)
		)
		(placement
			(enabled no)
			(sheetname "")
		)
		(fill yes
			(thermal_gap 0.5)
			(thermal_bridge_width 0.5)
			(island_removal_mode 0)
		)
		(polygon
			(pts
				(arc
					(start 400.89455 -109.176312)
					(mid 400.19097 -109.176312)
					(end 400.89455 -109.176312)
				)
			)
		)
	)
	(zone
		(layers "B.Cu" "In7.Cu" "In9.Cu" "In11.Cu" "In13.Cu" "In15.Cu")
		(hatch none 0.5)
		(connect_pads
			(clearance 0)
		)
		(min_thickness 0.25)
		(keepout
			(tracks not_allowed)
			(vias allowed)
			(pads allowed)
			(copperpour not_allowed)
			(footprints allowed)
		)
		(placement
			(enabled no)
			(sheetname "")
		)
		(fill yes
			(thermal_gap 0.5)
			(thermal_bridge_width 0.5)
			(island_removal_mode 0)
		)
		(polygon
			(pts
				(arc
					(start 290.069524 -384.590036)
					(mid 289.310064 -384.590036)
					(end 290.069524 -384.590036)
				)
			)
		)
	)
	(zone
		(layers "B.Cu" "In7.Cu" "In9.Cu" "In11.Cu" "In13.Cu" "In15.Cu")
		(hatch none 0.5)
		(connect_pads
			(clearance 0)
		)
		(min_thickness 0.25)
		(keepout
			(tracks not_allowed)
			(vias allowed)
			(pads allowed)
			(copperpour not_allowed)
			(footprints allowed)
		)
		(placement
			(enabled no)
			(sheetname "")
		)
		(fill yes
			(thermal_gap 0.5)
			(thermal_bridge_width 0.5)
			(island_removal_mode 0)
		)
		(polygon
			(pts
				(arc
					(start 331.869796 -400.390106)
					(mid 331.110336 -400.390106)
					(end 331.869796 -400.390106)
				)
			)
		)
	)
	(zone
		(layers "B.Cu" "In7.Cu" "In9.Cu" "In11.Cu" "In13.Cu" "In15.Cu")
		(hatch none 0.5)
		(connect_pads
			(clearance 0)
		)
		(min_thickness 0.25)
		(keepout
			(tracks not_allowed)
			(vias allowed)
			(pads allowed)
			(copperpour not_allowed)
			(footprints allowed)
		)
		(placement
			(enabled no)
			(sheetname "")
		)
		(fill yes
			(thermal_gap 0.5)
			(thermal_bridge_width 0.5)
			(island_removal_mode 0)
		)
		(polygon
			(pts
				(arc
					(start 409.226004 -274.999704)
					(mid 408.573224 -274.999704)
					(end 409.226004 -274.999704)
				)
			)
		)
	)
	(zone
		(layers "B.Cu" "In7.Cu" "In9.Cu" "In11.Cu" "In13.Cu" "In15.Cu")
		(hatch none 0.5)
		(connect_pads
			(clearance 0)
		)
		(min_thickness 0.25)
		(keepout
			(tracks not_allowed)
			(vias allowed)
			(pads allowed)
			(copperpour not_allowed)
			(footprints allowed)
		)
		(placement
			(enabled no)
			(sheetname "")
		)
		(fill yes
			(thermal_gap 0.5)
			(thermal_bridge_width 0.5)
			(island_removal_mode 0)
		)
		(polygon
			(pts
				(arc
					(start 415.7091 -142.62354)
					(mid 415.00552 -142.62354)
					(end 415.7091 -142.62354)
				)
			)
		)
	)
	(zone
		(layers "B.Cu" "In7.Cu" "In9.Cu" "In11.Cu" "In13.Cu" "In15.Cu")
		(hatch none 0.5)
		(connect_pads
			(clearance 0)
		)
		(min_thickness 0.25)
		(keepout
			(tracks not_allowed)
			(vias allowed)
			(pads allowed)
			(copperpour not_allowed)
			(footprints allowed)
		)
		(placement
			(enabled no)
			(sheetname "")
		)
		(fill yes
			(thermal_gap 0.5)
			(thermal_bridge_width 0.5)
			(island_removal_mode 0)
		)
		(polygon
			(pts
				(arc
					(start 299.609002 -129.913634)
					(mid 298.905422 -129.913634)
					(end 299.609002 -129.913634)
				)
			)
		)
	)
	(zone
		(layers "B.Cu" "In7.Cu" "In9.Cu" "In11.Cu" "In13.Cu" "In15.Cu")
		(hatch none 0.5)
		(connect_pads
			(clearance 0)
		)
		(min_thickness 0.25)
		(keepout
			(tracks not_allowed)
			(vias allowed)
			(pads allowed)
			(copperpour not_allowed)
			(footprints allowed)
		)
		(placement
			(enabled no)
			(sheetname "")
		)
		(fill yes
			(thermal_gap 0.5)
			(thermal_bridge_width 0.5)
			(island_removal_mode 0)
		)
		(polygon
			(pts
				(arc
					(start 412.076138 -274.049744)
					(mid 411.423358 -274.049744)
					(end 412.076138 -274.049744)
				)
			)
		)
	)
	(zone
		(layers "B.Cu" "In7.Cu" "In9.Cu" "In11.Cu" "In13.Cu" "In15.Cu")
		(hatch none 0.5)
		(connect_pads
			(clearance 0)
		)
		(min_thickness 0.25)
		(keepout
			(tracks not_allowed)
			(vias allowed)
			(pads allowed)
			(copperpour not_allowed)
			(footprints allowed)
		)
		(placement
			(enabled no)
			(sheetname "")
		)
		(fill yes
			(thermal_gap 0.5)
			(thermal_bridge_width 0.5)
			(island_removal_mode 0)
		)
		(polygon
			(pts
				(arc
					(start 431.076354 -316.799722)
					(mid 430.423574 -316.799722)
					(end 431.076354 -316.799722)
				)
			)
		)
	)
	(zone
		(layers "B.Cu" "In7.Cu" "In9.Cu" "In11.Cu" "In13.Cu" "In15.Cu")
		(hatch none 0.5)
		(connect_pads
			(clearance 0)
		)
		(min_thickness 0.25)
		(keepout
			(tracks not_allowed)
			(vias allowed)
			(pads allowed)
			(copperpour not_allowed)
			(footprints allowed)
		)
		(placement
			(enabled no)
			(sheetname "")
		)
		(fill yes
			(thermal_gap 0.5)
			(thermal_bridge_width 0.5)
			(island_removal_mode 0)
		)
		(polygon
			(pts
				(arc
					(start 118.48973 -376.790204)
					(mid 117.73027 -376.790204)
					(end 118.48973 -376.790204)
				)
			)
		)
	)
	(zone
		(layers "B.Cu" "In7.Cu" "In9.Cu" "In11.Cu" "In13.Cu" "In15.Cu")
		(hatch none 0.5)
		(connect_pads
			(clearance 0)
		)
		(min_thickness 0.25)
		(keepout
			(tracks not_allowed)
			(vias allowed)
			(pads allowed)
			(copperpour not_allowed)
			(footprints allowed)
		)
		(placement
			(enabled no)
			(sheetname "")
		)
		(fill yes
			(thermal_gap 0.5)
			(thermal_bridge_width 0.5)
			(island_removal_mode 0)
		)
		(polygon
			(pts
				(arc
					(start 345.069668 -400.390106)
					(mid 344.310208 -400.390106)
					(end 345.069668 -400.390106)
				)
			)
		)
	)
	(zone
		(layers "B.Cu" "In7.Cu" "In9.Cu" "In11.Cu" "In13.Cu" "In15.Cu")
		(hatch none 0.5)
		(connect_pads
			(clearance 0)
		)
		(min_thickness 0.25)
		(keepout
			(tracks not_allowed)
			(vias allowed)
			(pads allowed)
			(copperpour not_allowed)
			(footprints allowed)
		)
		(placement
			(enabled no)
			(sheetname "")
		)
		(fill yes
			(thermal_gap 0.5)
			(thermal_bridge_width 0.5)
			(island_removal_mode 0)
		)
		(polygon
			(pts
				(arc
					(start 303.575974 -273.099784)
					(mid 302.923194 -273.099784)
					(end 303.575974 -273.099784)
				)
			)
		)
	)
	(zone
		(layers "B.Cu" "In7.Cu" "In9.Cu" "In11.Cu" "In13.Cu" "In15.Cu")
		(hatch none 0.5)
		(connect_pads
			(clearance 0)
		)
		(min_thickness 0.25)
		(keepout
			(tracks not_allowed)
			(vias allowed)
			(pads allowed)
			(copperpour not_allowed)
			(footprints allowed)
		)
		(placement
			(enabled no)
			(sheetname "")
		)
		(fill yes
			(thermal_gap 0.5)
			(thermal_bridge_width 0.5)
			(island_removal_mode 0)
		)
		(polygon
			(pts
				(arc
					(start 38.126162 -304.449734)
					(mid 37.473382 -304.449734)
					(end 38.126162 -304.449734)
				)
			)
		)
	)
	(zone
		(layers "B.Cu" "In7.Cu" "In9.Cu" "In11.Cu" "In13.Cu" "In15.Cu")
		(hatch none 0.5)
		(connect_pads
			(clearance 0)
		)
		(min_thickness 0.25)
		(keepout
			(tracks not_allowed)
			(vias allowed)
			(pads allowed)
			(copperpour not_allowed)
			(footprints allowed)
		)
		(placement
			(enabled no)
			(sheetname "")
		)
		(fill yes
			(thermal_gap 0.5)
			(thermal_bridge_width 0.5)
			(island_removal_mode 0)
		)
		(polygon
			(pts
				(arc
					(start 170.548554 -130.43281)
					(mid 169.844974 -130.43281)
					(end 170.548554 -130.43281)
				)
			)
		)
	)
	(zone
		(layers "B.Cu" "In7.Cu" "In9.Cu" "In11.Cu" "In13.Cu" "In15.Cu")
		(hatch none 0.5)
		(connect_pads
			(clearance 0)
		)
		(min_thickness 0.25)
		(keepout
			(tracks not_allowed)
			(vias allowed)
			(pads allowed)
			(copperpour not_allowed)
			(footprints allowed)
		)
		(placement
			(enabled no)
			(sheetname "")
		)
		(fill yes
			(thermal_gap 0.5)
			(thermal_bridge_width 0.5)
			(island_removal_mode 0)
		)
		(polygon
			(pts
				(arc
					(start 312.965084 7.677912)
					(mid 312.261504 7.677912)
					(end 312.965084 7.677912)
				)
			)
		)
	)
	(zone
		(layers "B.Cu" "In7.Cu" "In9.Cu" "In11.Cu" "In13.Cu" "In15.Cu")
		(hatch none 0.5)
		(connect_pads
			(clearance 0)
		)
		(min_thickness 0.25)
		(keepout
			(tracks not_allowed)
			(vias allowed)
			(pads allowed)
			(copperpour not_allowed)
			(footprints allowed)
		)
		(placement
			(enabled no)
			(sheetname "")
		)
		(fill yes
			(thermal_gap 0.5)
			(thermal_bridge_width 0.5)
			(island_removal_mode 0)
		)
		(polygon
			(pts
				(arc
					(start 164.68979 -379.590046)
					(mid 163.93033 -379.590046)
					(end 164.68979 -379.590046)
				)
			)
		)
	)
	(zone
		(layers "B.Cu" "In7.Cu" "In9.Cu" "In11.Cu" "In13.Cu" "In15.Cu")
		(hatch none 0.5)
		(connect_pads
			(clearance 0)
		)
		(min_thickness 0.25)
		(keepout
			(tracks not_allowed)
			(vias allowed)
			(pads allowed)
			(copperpour not_allowed)
			(footprints allowed)
		)
		(placement
			(enabled no)
			(sheetname "")
		)
		(fill yes
			(thermal_gap 0.5)
			(thermal_bridge_width 0.5)
			(island_removal_mode 0)
		)
		(polygon
			(pts
				(arc
					(start 415.7091 -122.30354)
					(mid 415.00552 -122.30354)
					(end 415.7091 -122.30354)
				)
			)
		)
	)
	(zone
		(layers "B.Cu" "In7.Cu" "In9.Cu" "In11.Cu" "In13.Cu" "In15.Cu")
		(hatch none 0.5)
		(connect_pads
			(clearance 0)
		)
		(min_thickness 0.25)
		(keepout
			(tracks not_allowed)
			(vias allowed)
			(pads allowed)
			(copperpour not_allowed)
			(footprints allowed)
		)
		(placement
			(enabled no)
			(sheetname "")
		)
		(fill yes
			(thermal_gap 0.5)
			(thermal_bridge_width 0.5)
			(island_removal_mode 0)
		)
		(polygon
			(pts
				(arc
					(start 196.026278 -315.849762)
					(mid 195.373498 -315.849762)
					(end 196.026278 -315.849762)
				)
			)
		)
	)
	(zone
		(layers "B.Cu" "In7.Cu" "In9.Cu" "In11.Cu" "In13.Cu" "In15.Cu")
		(hatch none 0.5)
		(connect_pads
			(clearance 0)
		)
		(min_thickness 0.25)
		(keepout
			(tracks not_allowed)
			(vias allowed)
			(pads allowed)
			(copperpour not_allowed)
			(footprints allowed)
		)
		(placement
			(enabled no)
			(sheetname "")
		)
		(fill yes
			(thermal_gap 0.5)
			(thermal_bridge_width 0.5)
			(island_removal_mode 0)
		)
		(polygon
			(pts
				(arc
					(start 430.869598 -406.690068)
					(mid 430.110138 -406.690068)
					(end 430.869598 -406.690068)
				)
			)
		)
	)
	(zone
		(layers "B.Cu" "In7.Cu" "In9.Cu" "In11.Cu" "In13.Cu" "In15.Cu")
		(hatch none 0.5)
		(connect_pads
			(clearance 0)
		)
		(min_thickness 0.25)
		(keepout
			(tracks not_allowed)
			(vias allowed)
			(pads allowed)
			(copperpour not_allowed)
			(footprints allowed)
		)
		(placement
			(enabled no)
			(sheetname "")
		)
		(fill yes
			(thermal_gap 0.5)
			(thermal_bridge_width 0.5)
			(island_removal_mode 0)
		)
		(polygon
			(pts
				(arc
					(start 400.89455 -112.776508)
					(mid 400.19097 -112.776508)
					(end 400.89455 -112.776508)
				)
			)
		)
	)
	(zone
		(layers "B.Cu" "In7.Cu" "In9.Cu" "In11.Cu" "In13.Cu" "In15.Cu")
		(hatch none 0.5)
		(connect_pads
			(clearance 0)
		)
		(min_thickness 0.25)
		(keepout
			(tracks not_allowed)
			(vias allowed)
			(pads allowed)
			(copperpour not_allowed)
			(footprints allowed)
		)
		(placement
			(enabled no)
			(sheetname "")
		)
		(fill yes
			(thermal_gap 0.5)
			(thermal_bridge_width 0.5)
			(island_removal_mode 0)
		)
		(polygon
			(pts
				(arc
					(start 185.57621 -273.099784)
					(mid 184.92343 -273.099784)
					(end 185.57621 -273.099784)
				)
			)
		)
	)
	(zone
		(layers "B.Cu" "In7.Cu" "In9.Cu" "In11.Cu" "In13.Cu" "In15.Cu")
		(hatch none 0.5)
		(connect_pads
			(clearance 0)
		)
		(min_thickness 0.25)
		(keepout
			(tracks not_allowed)
			(vias allowed)
			(pads allowed)
			(copperpour not_allowed)
			(footprints allowed)
		)
		(placement
			(enabled no)
			(sheetname "")
		)
		(fill yes
			(thermal_gap 0.5)
			(thermal_bridge_width 0.5)
			(island_removal_mode 0)
		)
		(polygon
			(pts
				(arc
					(start 313.075828 -274.049744)
					(mid 312.423048 -274.049744)
					(end 313.075828 -274.049744)
				)
			)
		)
	)
	(zone
		(layers "B.Cu" "In7.Cu" "In9.Cu" "In11.Cu" "In13.Cu" "In15.Cu")
		(hatch none 0.5)
		(connect_pads
			(clearance 0)
		)
		(min_thickness 0.25)
		(keepout
			(tracks not_allowed)
			(vias allowed)
			(pads allowed)
			(copperpour not_allowed)
			(footprints allowed)
		)
		(placement
			(enabled no)
			(sheetname "")
		)
		(fill yes
			(thermal_gap 0.5)
			(thermal_bridge_width 0.5)
			(island_removal_mode 0)
		)
		(polygon
			(pts
				(arc
					(start 81.089754 -370.489988)
					(mid 80.330294 -370.489988)
					(end 81.089754 -370.489988)
				)
			)
		)
	)
	(zone
		(layers "B.Cu" "In7.Cu" "In9.Cu" "In11.Cu" "In13.Cu" "In15.Cu")
		(hatch none 0.5)
		(connect_pads
			(clearance 0)
		)
		(min_thickness 0.25)
		(keepout
			(tracks not_allowed)
			(vias allowed)
			(pads allowed)
			(copperpour not_allowed)
			(footprints allowed)
		)
		(placement
			(enabled no)
			(sheetname "")
		)
		(fill yes
			(thermal_gap 0.5)
			(thermal_bridge_width 0.5)
			(island_removal_mode 0)
		)
		(polygon
			(pts
				(arc
					(start 334.06969 -401.49018)
					(mid 333.31023 -401.49018)
					(end 334.06969 -401.49018)
				)
			)
		)
	)
	(zone
		(layers "B.Cu" "In7.Cu" "In9.Cu" "In11.Cu" "In13.Cu" "In15.Cu")
		(hatch none 0.5)
		(connect_pads
			(clearance 0)
		)
		(min_thickness 0.25)
		(keepout
			(tracks not_allowed)
			(vias allowed)
			(pads allowed)
			(copperpour not_allowed)
			(footprints allowed)
		)
		(placement
			(enabled no)
			(sheetname "")
		)
		(fill yes
			(thermal_gap 0.5)
			(thermal_bridge_width 0.5)
			(island_removal_mode 0)
		)
		(polygon
			(pts
				(arc
					(start 375.869708 -396.49019)
					(mid 375.110248 -396.49019)
					(end 375.869708 -396.49019)
				)
			)
		)
	)
	(zone
		(layers "B.Cu" "In7.Cu" "In9.Cu" "In11.Cu" "In13.Cu" "In15.Cu")
		(hatch none 0.5)
		(connect_pads
			(clearance 0)
		)
		(min_thickness 0.25)
		(keepout
			(tracks not_allowed)
			(vias allowed)
			(pads allowed)
			(copperpour not_allowed)
			(footprints allowed)
		)
		(placement
			(enabled no)
			(sheetname "")
		)
		(fill yes
			(thermal_gap 0.5)
			(thermal_bridge_width 0.5)
			(island_removal_mode 0)
		)
		(polygon
			(pts
				(arc
					(start 183.508904 -133.513576)
					(mid 182.805324 -133.513576)
					(end 183.508904 -133.513576)
				)
			)
		)
	)
	(zone
		(layers "B.Cu" "In7.Cu" "In9.Cu" "In11.Cu" "In13.Cu" "In15.Cu")
		(hatch none 0.5)
		(connect_pads
			(clearance 0)
		)
		(min_thickness 0.25)
		(keepout
			(tracks not_allowed)
			(vias allowed)
			(pads allowed)
			(copperpour not_allowed)
			(footprints allowed)
		)
		(placement
			(enabled no)
			(sheetname "")
		)
		(fill yes
			(thermal_gap 0.5)
			(thermal_bridge_width 0.5)
			(island_removal_mode 0)
		)
		(polygon
			(pts
				(arc
					(start 312.125868 -274.999958)
					(mid 311.473088 -274.999958)
					(end 312.125868 -274.999958)
				)
			)
		)
	)
	(zone
		(layers "B.Cu" "In7.Cu" "In9.Cu" "In11.Cu" "In13.Cu" "In15.Cu")
		(hatch none 0.5)
		(connect_pads
			(clearance 0)
		)
		(min_thickness 0.25)
		(keepout
			(tracks not_allowed)
			(vias allowed)
			(pads allowed)
			(copperpour not_allowed)
			(footprints allowed)
		)
		(placement
			(enabled no)
			(sheetname "")
		)
		(fill yes
			(thermal_gap 0.5)
			(thermal_bridge_width 0.5)
			(island_removal_mode 0)
		)
		(polygon
			(pts
				(arc
					(start 78.975966 -273.099784)
					(mid 78.323186 -273.099784)
					(end 78.975966 -273.099784)
				)
			)
		)
	)
	(zone
		(layers "B.Cu" "In7.Cu" "In9.Cu" "In11.Cu" "In13.Cu" "In15.Cu")
		(hatch none 0.5)
		(connect_pads
			(clearance 0)
		)
		(min_thickness 0.25)
		(keepout
			(tracks not_allowed)
			(vias allowed)
			(pads allowed)
			(copperpour not_allowed)
			(footprints allowed)
		)
		(placement
			(enabled no)
			(sheetname "")
		)
		(fill yes
			(thermal_gap 0.5)
			(thermal_bridge_width 0.5)
			(island_removal_mode 0)
		)
		(polygon
			(pts
				(arc
					(start 413.8549 -148.023834)
					(mid 413.15132 -148.023834)
					(end 413.8549 -148.023834)
				)
			)
		)
	)
	(zone
		(layers "B.Cu" "In7.Cu" "In9.Cu" "In11.Cu" "In13.Cu" "In15.Cu")
		(hatch none 0.5)
		(connect_pads
			(clearance 0)
		)
		(min_thickness 0.25)
		(keepout
			(tracks not_allowed)
			(vias allowed)
			(pads allowed)
			(copperpour not_allowed)
			(footprints allowed)
		)
		(placement
			(enabled no)
			(sheetname "")
		)
		(fill yes
			(thermal_gap 0.5)
			(thermal_bridge_width 0.5)
			(island_removal_mode 0)
		)
		(polygon
			(pts
				(arc
					(start 196.026278 -286.399732)
					(mid 195.373498 -286.399732)
					(end 196.026278 -286.399732)
				)
			)
		)
	)
	(zone
		(layers "B.Cu" "In7.Cu" "In9.Cu" "In11.Cu" "In13.Cu" "In15.Cu")
		(hatch none 0.5)
		(connect_pads
			(clearance 0)
		)
		(min_thickness 0.25)
		(keepout
			(tracks not_allowed)
			(vias allowed)
			(pads allowed)
			(copperpour not_allowed)
			(footprints allowed)
		)
		(placement
			(enabled no)
			(sheetname "")
		)
		(fill yes
			(thermal_gap 0.5)
			(thermal_bridge_width 0.5)
			(island_removal_mode 0)
		)
		(polygon
			(pts
				(arc
					(start 44.776136 -317.749936)
					(mid 44.123356 -317.749936)
					(end 44.776136 -317.749936)
				)
			)
		)
	)
	(zone
		(layers "B.Cu" "In7.Cu" "In9.Cu" "In11.Cu" "In13.Cu" "In15.Cu")
		(hatch none 0.5)
		(connect_pads
			(clearance 0)
		)
		(min_thickness 0.25)
		(keepout
			(tracks not_allowed)
			(vias allowed)
			(pads allowed)
			(copperpour not_allowed)
			(footprints allowed)
		)
		(placement
			(enabled no)
			(sheetname "")
		)
		(fill yes
			(thermal_gap 0.5)
			(thermal_bridge_width 0.5)
			(island_removal_mode 0)
		)
		(polygon
			(pts
				(arc
					(start 171.289726 -405.390096)
					(mid 170.530266 -405.390096)
					(end 171.289726 -405.390096)
				)
			)
		)
	)
	(zone
		(layers "B.Cu" "In7.Cu" "In9.Cu" "In11.Cu" "In13.Cu" "In15.Cu")
		(hatch none 0.5)
		(connect_pads
			(clearance 0)
		)
		(min_thickness 0.25)
		(keepout
			(tracks not_allowed)
			(vias allowed)
			(pads allowed)
			(copperpour not_allowed)
			(footprints allowed)
		)
		(placement
			(enabled no)
			(sheetname "")
		)
		(fill yes
			(thermal_gap 0.5)
			(thermal_bridge_width 0.5)
			(island_removal_mode 0)
		)
		(polygon
			(pts
				(arc
					(start 342.869774 -402.790152)
					(mid 342.110314 -402.790152)
					(end 342.869774 -402.790152)
				)
			)
		)
	)
	(zone
		(layers "B.Cu" "In7.Cu" "In9.Cu" "In11.Cu" "In13.Cu" "In15.Cu")
		(hatch none 0.5)
		(connect_pads
			(clearance 0)
		)
		(min_thickness 0.25)
		(keepout
			(tracks not_allowed)
			(vias allowed)
			(pads allowed)
			(copperpour not_allowed)
			(footprints allowed)
		)
		(placement
			(enabled no)
			(sheetname "")
		)
		(fill yes
			(thermal_gap 0.5)
			(thermal_bridge_width 0.5)
			(island_removal_mode 0)
		)
		(polygon
			(pts
				(arc
					(start 269.376144 -302.549814)
					(mid 268.723364 -302.549814)
					(end 269.376144 -302.549814)
				)
			)
		)
	)
	(zone
		(layers "B.Cu" "In7.Cu" "In9.Cu" "In11.Cu" "In13.Cu" "In15.Cu")
		(hatch none 0.5)
		(connect_pads
			(clearance 0)
		)
		(min_thickness 0.25)
		(keepout
			(tracks not_allowed)
			(vias allowed)
			(pads allowed)
			(copperpour not_allowed)
			(footprints allowed)
		)
		(placement
			(enabled no)
			(sheetname "")
		)
		(fill yes
			(thermal_gap 0.5)
			(thermal_bridge_width 0.5)
			(island_removal_mode 0)
		)
		(polygon
			(pts
				(arc
					(start 270.326104 -316.799722)
					(mid 269.673324 -316.799722)
					(end 270.326104 -316.799722)
				)
			)
		)
	)
	(zone
		(layers "B.Cu" "In7.Cu" "In9.Cu" "In11.Cu" "In13.Cu" "In15.Cu")
		(hatch none 0.5)
		(connect_pads
			(clearance 0)
		)
		(min_thickness 0.25)
		(keepout
			(tracks not_allowed)
			(vias allowed)
			(pads allowed)
			(copperpour not_allowed)
			(footprints allowed)
		)
		(placement
			(enabled no)
			(sheetname "")
		)
		(fill yes
			(thermal_gap 0.5)
			(thermal_bridge_width 0.5)
			(island_removal_mode 0)
		)
		(polygon
			(pts
				(arc
					(start 78.889606 -401.49018)
					(mid 78.130146 -401.49018)
					(end 78.889606 -401.49018)
				)
			)
		)
	)
	(zone
		(layers "B.Cu" "In7.Cu" "In9.Cu" "In11.Cu" "In13.Cu" "In15.Cu")
		(hatch none 0.5)
		(connect_pads
			(clearance 0)
		)
		(min_thickness 0.25)
		(keepout
			(tracks not_allowed)
			(vias allowed)
			(pads allowed)
			(copperpour not_allowed)
			(footprints allowed)
		)
		(placement
			(enabled no)
			(sheetname "")
		)
		(fill yes
			(thermal_gap 0.5)
			(thermal_bridge_width 0.5)
			(island_removal_mode 0)
		)
		(polygon
			(pts
				(arc
					(start 64.726058 -274.999704)
					(mid 64.073278 -274.999704)
					(end 64.726058 -274.999704)
				)
			)
		)
	)
	(zone
		(layers "B.Cu" "In7.Cu" "In9.Cu" "In11.Cu" "In13.Cu" "In15.Cu")
		(hatch none 0.5)
		(connect_pads
			(clearance 0)
		)
		(min_thickness 0.25)
		(keepout
			(tracks not_allowed)
			(vias allowed)
			(pads allowed)
			(copperpour not_allowed)
			(footprints allowed)
		)
		(placement
			(enabled no)
			(sheetname "")
		)
		(fill yes
			(thermal_gap 0.5)
			(thermal_bridge_width 0.5)
			(island_removal_mode 0)
		)
		(polygon
			(pts
				(arc
					(start 66.626232 -316.799722)
					(mid 65.973452 -316.799722)
					(end 66.626232 -316.799722)
				)
			)
		)
	)
	(zone
		(layers "B.Cu" "In7.Cu" "In9.Cu" "In11.Cu" "In13.Cu" "In15.Cu")
		(hatch none 0.5)
		(connect_pads
			(clearance 0)
		)
		(min_thickness 0.25)
		(keepout
			(tracks not_allowed)
			(vias allowed)
			(pads allowed)
			(copperpour not_allowed)
			(footprints allowed)
		)
		(placement
			(enabled no)
			(sheetname "")
		)
		(fill yes
			(thermal_gap 0.5)
			(thermal_bridge_width 0.5)
			(island_removal_mode 0)
		)
		(polygon
			(pts
				(arc
					(start 162.489642 -379.390148)
					(mid 161.730182 -379.390148)
					(end 162.489642 -379.390148)
				)
			)
		)
	)
	(zone
		(layers "B.Cu" "In7.Cu" "In9.Cu" "In11.Cu" "In13.Cu" "In15.Cu")
		(hatch none 0.5)
		(connect_pads
			(clearance 0)
		)
		(min_thickness 0.25)
		(keepout
			(tracks not_allowed)
			(vias allowed)
			(pads allowed)
			(copperpour not_allowed)
			(footprints allowed)
		)
		(placement
			(enabled no)
			(sheetname "")
		)
		(fill yes
			(thermal_gap 0.5)
			(thermal_bridge_width 0.5)
			(island_removal_mode 0)
		)
		(polygon
			(pts
				(arc
					(start 303.26965 -384.590036)
					(mid 302.51019 -384.590036)
					(end 303.26965 -384.590036)
				)
			)
		)
	)
	(zone
		(layers "B.Cu" "In7.Cu" "In9.Cu" "In11.Cu" "In13.Cu" "In15.Cu")
		(hatch none 0.5)
		(connect_pads
			(clearance 0)
		)
		(min_thickness 0.25)
		(keepout
			(tracks not_allowed)
			(vias allowed)
			(pads allowed)
			(copperpour not_allowed)
			(footprints allowed)
		)
		(placement
			(enabled no)
			(sheetname "")
		)
		(fill yes
			(thermal_gap 0.5)
			(thermal_bridge_width 0.5)
			(island_removal_mode 0)
		)
		(polygon
			(pts
				(arc
					(start 299.609002 -149.823678)
					(mid 298.905422 -149.823678)
					(end 299.609002 -149.823678)
				)
			)
		)
	)
	(zone
		(layers "B.Cu" "In7.Cu" "In9.Cu" "In11.Cu" "In13.Cu" "In15.Cu")
		(hatch none 0.5)
		(connect_pads
			(clearance 0)
		)
		(min_thickness 0.25)
		(keepout
			(tracks not_allowed)
			(vias allowed)
			(pads allowed)
			(copperpour not_allowed)
			(footprints allowed)
		)
		(placement
			(enabled no)
			(sheetname "")
		)
		(fill yes
			(thermal_gap 0.5)
			(thermal_bridge_width 0.5)
			(island_removal_mode 0)
		)
		(polygon
			(pts
				(arc
					(start 67.40906 -142.62354)
					(mid 66.70548 -142.62354)
					(end 67.40906 -142.62354)
				)
			)
		)
	)
	(zone
		(layers "B.Cu" "In7.Cu" "In9.Cu" "In11.Cu" "In13.Cu" "In15.Cu")
		(hatch none 0.5)
		(connect_pads
			(clearance 0)
		)
		(min_thickness 0.25)
		(keepout
			(tracks not_allowed)
			(vias allowed)
			(pads allowed)
			(copperpour not_allowed)
			(footprints allowed)
		)
		(placement
			(enabled no)
			(sheetname "")
		)
		(fill yes
			(thermal_gap 0.5)
			(thermal_bridge_width 0.5)
			(island_removal_mode 0)
		)
		(polygon
			(pts
				(arc
					(start 413.8549 -145.287238)
					(mid 413.15132 -145.287238)
					(end 413.8549 -145.287238)
				)
			)
		)
	)
	(zone
		(layers "B.Cu" "In7.Cu" "In9.Cu" "In11.Cu" "In13.Cu" "In15.Cu")
		(hatch none 0.5)
		(connect_pads
			(clearance 0)
		)
		(min_thickness 0.25)
		(keepout
			(tracks not_allowed)
			(vias allowed)
			(pads allowed)
			(copperpour not_allowed)
			(footprints allowed)
		)
		(placement
			(enabled no)
			(sheetname "")
		)
		(fill yes
			(thermal_gap 0.5)
			(thermal_bridge_width 0.5)
			(island_removal_mode 0)
		)
		(polygon
			(pts
				(arc
					(start 168.694354 -136.69645)
					(mid 167.990774 -136.69645)
					(end 168.694354 -136.69645)
				)
			)
		)
	)
	(zone
		(layers "B.Cu" "In7.Cu" "In9.Cu" "In11.Cu" "In13.Cu" "In15.Cu")
		(hatch none 0.5)
		(connect_pads
			(clearance 0)
		)
		(min_thickness 0.25)
		(keepout
			(tracks not_allowed)
			(vias allowed)
			(pads allowed)
			(copperpour not_allowed)
			(footprints allowed)
		)
		(placement
			(enabled no)
			(sheetname "")
		)
		(fill yes
			(thermal_gap 0.5)
			(thermal_bridge_width 0.5)
			(island_removal_mode 0)
		)
		(polygon
			(pts
				(arc
					(start 435.26964 -380.69012)
					(mid 434.51018 -380.69012)
					(end 435.26964 -380.69012)
				)
			)
		)
	)
	(zone
		(layers "B.Cu" "In7.Cu" "In9.Cu" "In11.Cu" "In13.Cu" "In15.Cu")
		(hatch none 0.5)
		(connect_pads
			(clearance 0)
		)
		(min_thickness 0.25)
		(keepout
			(tracks not_allowed)
			(vias allowed)
			(pads allowed)
			(copperpour not_allowed)
			(footprints allowed)
		)
		(placement
			(enabled no)
			(sheetname "")
		)
		(fill yes
			(thermal_gap 0.5)
			(thermal_bridge_width 0.5)
			(island_removal_mode 0)
		)
		(polygon
			(pts
				(arc
					(start 54.44871 -107.376214)
					(mid 53.74513 -107.376214)
					(end 54.44871 -107.376214)
				)
			)
		)
	)
	(zone
		(layers "B.Cu" "In7.Cu" "In9.Cu" "In11.Cu" "In13.Cu" "In15.Cu")
		(hatch none 0.5)
		(connect_pads
			(clearance 0)
		)
		(min_thickness 0.25)
		(keepout
			(tracks not_allowed)
			(vias allowed)
			(pads allowed)
			(copperpour not_allowed)
			(footprints allowed)
		)
		(placement
			(enabled no)
			(sheetname "")
		)
		(fill yes
			(thermal_gap 0.5)
			(thermal_bridge_width 0.5)
			(island_removal_mode 0)
		)
		(polygon
			(pts
				(arc
					(start 118.48973 -397.59001)
					(mid 117.73027 -397.59001)
					(end 118.48973 -397.59001)
				)
			)
		)
	)
	(zone
		(layers "B.Cu" "In7.Cu" "In9.Cu" "In11.Cu" "In13.Cu" "In15.Cu")
		(hatch none 0.5)
		(connect_pads
			(clearance 0)
		)
		(min_thickness 0.25)
		(keepout
			(tracks not_allowed)
			(vias allowed)
			(pads allowed)
			(copperpour not_allowed)
			(footprints allowed)
		)
		(placement
			(enabled no)
			(sheetname "")
		)
		(fill yes
			(thermal_gap 0.5)
			(thermal_bridge_width 0.5)
			(island_removal_mode 0)
		)
		(polygon
			(pts
				(arc
					(start 47.62627 -316.799722)
					(mid 46.97349 -316.799722)
					(end 47.62627 -316.799722)
				)
			)
		)
	)
	(zone
		(layers "B.Cu" "In7.Cu" "In9.Cu" "In11.Cu" "In13.Cu" "In15.Cu")
		(hatch none 0.5)
		(connect_pads
			(clearance 0)
		)
		(min_thickness 0.25)
		(keepout
			(tracks not_allowed)
			(vias allowed)
			(pads allowed)
			(copperpour not_allowed)
			(footprints allowed)
		)
		(placement
			(enabled no)
			(sheetname "")
		)
		(fill yes
			(thermal_gap 0.5)
			(thermal_bridge_width 0.5)
			(island_removal_mode 0)
		)
		(polygon
			(pts
				(arc
					(start 182.726076 -274.999958)
					(mid 182.073296 -274.999958)
					(end 182.726076 -274.999958)
				)
			)
		)
	)
	(zone
		(layers "B.Cu" "In7.Cu" "In9.Cu" "In11.Cu" "In13.Cu" "In15.Cu")
		(hatch none 0.5)
		(connect_pads
			(clearance 0)
		)
		(min_thickness 0.25)
		(keepout
			(tracks not_allowed)
			(vias allowed)
			(pads allowed)
			(copperpour not_allowed)
			(footprints allowed)
		)
		(placement
			(enabled no)
			(sheetname "")
		)
		(fill yes
			(thermal_gap 0.5)
			(thermal_bridge_width 0.5)
			(island_removal_mode 0)
		)
		(polygon
			(pts
				(arc
					(start 402.74875 -134.896352)
					(mid 402.04517 -134.896352)
					(end 402.74875 -134.896352)
				)
			)
		)
	)
	(zone
		(layers "B.Cu" "In7.Cu" "In9.Cu" "In11.Cu" "In13.Cu" "In15.Cu")
		(hatch none 0.5)
		(connect_pads
			(clearance 0)
		)
		(min_thickness 0.25)
		(keepout
			(tracks not_allowed)
			(vias allowed)
			(pads allowed)
			(copperpour not_allowed)
			(footprints allowed)
		)
		(placement
			(enabled no)
			(sheetname "")
		)
		(fill yes
			(thermal_gap 0.5)
			(thermal_bridge_width 0.5)
			(island_removal_mode 0)
		)
		(polygon
			(pts
				(arc
					(start 181.654704 -144.423638)
					(mid 180.951124 -144.423638)
					(end 181.654704 -144.423638)
				)
			)
		)
	)
	(zone
		(layers "B.Cu" "In7.Cu" "In9.Cu" "In11.Cu" "In13.Cu" "In15.Cu")
		(hatch none 0.5)
		(connect_pads
			(clearance 0)
		)
		(min_thickness 0.25)
		(keepout
			(tracks not_allowed)
			(vias allowed)
			(pads allowed)
			(copperpour not_allowed)
			(footprints allowed)
		)
		(placement
			(enabled no)
			(sheetname "")
		)
		(fill yes
			(thermal_gap 0.5)
			(thermal_bridge_width 0.5)
			(island_removal_mode 0)
		)
		(polygon
			(pts
				(arc
					(start 177.026316 -316.799722)
					(mid 176.373536 -316.799722)
					(end 177.026316 -316.799722)
				)
			)
		)
	)
	(zone
		(layers "B.Cu" "In7.Cu" "In9.Cu" "In11.Cu" "In13.Cu" "In15.Cu")
		(hatch none 0.5)
		(connect_pads
			(clearance 0)
		)
		(min_thickness 0.25)
		(keepout
			(tracks not_allowed)
			(vias allowed)
			(pads allowed)
			(copperpour not_allowed)
			(footprints allowed)
		)
		(placement
			(enabled no)
			(sheetname "")
		)
		(fill yes
			(thermal_gap 0.5)
			(thermal_bridge_width 0.5)
			(island_removal_mode 0)
		)
		(polygon
			(pts
				(arc
					(start 85.489542 -400.390106)
					(mid 84.730082 -400.390106)
					(end 85.489542 -400.390106)
				)
			)
		)
	)
	(zone
		(layers "B.Cu" "In7.Cu" "In9.Cu" "In11.Cu" "In13.Cu" "In15.Cu")
		(hatch none 0.5)
		(connect_pads
			(clearance 0)
		)
		(min_thickness 0.25)
		(keepout
			(tracks not_allowed)
			(vias allowed)
			(pads allowed)
			(copperpour not_allowed)
			(footprints allowed)
		)
		(placement
			(enabled no)
			(sheetname "")
		)
		(fill yes
			(thermal_gap 0.5)
			(thermal_bridge_width 0.5)
			(island_removal_mode 0)
		)
		(polygon
			(pts
				(arc
					(start 386.869686 -376.790204)
					(mid 386.110226 -376.790204)
					(end 386.869686 -376.790204)
				)
			)
		)
	)
	(zone
		(layers "B.Cu" "In7.Cu" "In9.Cu" "In11.Cu" "In13.Cu" "In15.Cu")
		(hatch none 0.5)
		(connect_pads
			(clearance 0)
		)
		(min_thickness 0.25)
		(keepout
			(tracks not_allowed)
			(vias allowed)
			(pads allowed)
			(copperpour not_allowed)
			(footprints allowed)
		)
		(placement
			(enabled no)
			(sheetname "")
		)
		(fill yes
			(thermal_gap 0.5)
			(thermal_bridge_width 0.5)
			(island_removal_mode 0)
		)
		(polygon
			(pts
				(arc
					(start 422.525952 -274.999958)
					(mid 421.873172 -274.999958)
					(end 422.525952 -274.999958)
				)
			)
		)
	)
	(zone
		(layers "B.Cu" "In7.Cu" "In9.Cu" "In11.Cu" "In13.Cu" "In15.Cu")
		(hatch none 0.5)
		(connect_pads
			(clearance 0)
		)
		(min_thickness 0.25)
		(keepout
			(tracks not_allowed)
			(vias allowed)
			(pads allowed)
			(copperpour not_allowed)
			(footprints allowed)
		)
		(placement
			(enabled no)
			(sheetname "")
		)
		(fill yes
			(thermal_gap 0.5)
			(thermal_bridge_width 0.5)
			(island_removal_mode 0)
		)
		(polygon
			(pts
				(arc
					(start 65.55486 -131.713732)
					(mid 64.85128 -131.713732)
					(end 65.55486 -131.713732)
				)
			)
		)
	)
	(zone
		(layers "B.Cu" "In7.Cu" "In9.Cu" "In11.Cu" "In13.Cu" "In15.Cu")
		(hatch none 0.5)
		(connect_pads
			(clearance 0)
		)
		(min_thickness 0.25)
		(keepout
			(tracks not_allowed)
			(vias allowed)
			(pads allowed)
			(copperpour not_allowed)
			(footprints allowed)
		)
		(placement
			(enabled no)
			(sheetname "")
		)
		(fill yes
			(thermal_gap 0.5)
			(thermal_bridge_width 0.5)
			(island_removal_mode 0)
		)
		(polygon
			(pts
				(arc
					(start 196.976238 -307.299868)
					(mid 196.323458 -307.299868)
					(end 196.976238 -307.299868)
				)
			)
		)
	)
	(zone
		(layers "B.Cu" "In7.Cu" "In9.Cu" "In11.Cu" "In13.Cu" "In15.Cu")
		(hatch none 0.5)
		(connect_pads
			(clearance 0)
		)
		(min_thickness 0.25)
		(keepout
			(tracks not_allowed)
			(vias allowed)
			(pads allowed)
			(copperpour not_allowed)
			(footprints allowed)
		)
		(placement
			(enabled no)
			(sheetname "")
		)
		(fill yes
			(thermal_gap 0.5)
			(thermal_bridge_width 0.5)
			(island_removal_mode 0)
		)
		(polygon
			(pts
				(arc
					(start 284.794452 -124.622814)
					(mid 284.090872 -124.622814)
					(end 284.794452 -124.622814)
				)
			)
		)
	)
	(zone
		(layers "B.Cu" "In7.Cu" "In9.Cu" "In11.Cu" "In13.Cu" "In15.Cu")
		(hatch none 0.5)
		(connect_pads
			(clearance 0)
		)
		(min_thickness 0.25)
		(keepout
			(tracks not_allowed)
			(vias allowed)
			(pads allowed)
			(copperpour not_allowed)
			(footprints allowed)
		)
		(placement
			(enabled no)
			(sheetname "")
		)
		(fill yes
			(thermal_gap 0.5)
			(thermal_bridge_width 0.5)
			(island_removal_mode 0)
		)
		(polygon
			(pts
				(arc
					(start 171.326302 -315.849762)
					(mid 170.673522 -315.849762)
					(end 171.326302 -315.849762)
				)
			)
		)
	)
	(zone
		(layers "B.Cu" "In7.Cu" "In9.Cu" "In11.Cu" "In13.Cu" "In15.Cu")
		(hatch none 0.5)
		(connect_pads
			(clearance 0)
		)
		(min_thickness 0.25)
		(keepout
			(tracks not_allowed)
			(vias allowed)
			(pads allowed)
			(copperpour not_allowed)
			(footprints allowed)
		)
		(placement
			(enabled no)
			(sheetname "")
		)
		(fill yes
			(thermal_gap 0.5)
			(thermal_bridge_width 0.5)
			(island_removal_mode 0)
		)
		(polygon
			(pts
				(arc
					(start 32.6898 -383.490216)
					(mid 31.93034 -383.490216)
					(end 32.6898 -383.490216)
				)
			)
		)
	)
	(zone
		(layers "B.Cu" "In7.Cu" "In9.Cu" "In11.Cu" "In13.Cu" "In15.Cu")
		(hatch none 0.5)
		(connect_pads
			(clearance 0)
		)
		(min_thickness 0.25)
		(keepout
			(tracks not_allowed)
			(vias allowed)
			(pads allowed)
			(copperpour not_allowed)
			(footprints allowed)
		)
		(placement
			(enabled no)
			(sheetname "")
		)
		(fill yes
			(thermal_gap 0.5)
			(thermal_bridge_width 0.5)
			(island_removal_mode 0)
		)
		(polygon
			(pts
				(arc
					(start 307.376068 -273.099784)
					(mid 306.723288 -273.099784)
					(end 307.376068 -273.099784)
				)
			)
		)
	)
	(zone
		(layers "B.Cu" "In7.Cu" "In9.Cu" "In11.Cu" "In13.Cu" "In15.Cu")
		(hatch none 0.5)
		(connect_pads
			(clearance 0)
		)
		(min_thickness 0.25)
		(keepout
			(tracks not_allowed)
			(vias allowed)
			(pads allowed)
			(copperpour not_allowed)
			(footprints allowed)
		)
		(placement
			(enabled no)
			(sheetname "")
		)
		(fill yes
			(thermal_gap 0.5)
			(thermal_bridge_width 0.5)
			(island_removal_mode 0)
		)
		(polygon
			(pts
				(arc
					(start 169.089832 -405.589994)
					(mid 168.330372 -405.589994)
					(end 169.089832 -405.589994)
				)
			)
		)
	)
	(zone
		(layers "B.Cu" "In7.Cu" "In9.Cu" "In11.Cu" "In13.Cu" "In15.Cu")
		(hatch none 0.5)
		(connect_pads
			(clearance 0)
		)
		(min_thickness 0.25)
		(keepout
			(tracks not_allowed)
			(vias allowed)
			(pads allowed)
			(copperpour not_allowed)
			(footprints allowed)
		)
		(placement
			(enabled no)
			(sheetname "")
		)
		(fill yes
			(thermal_gap 0.5)
			(thermal_bridge_width 0.5)
			(island_removal_mode 0)
		)
		(polygon
			(pts
				(arc
					(start 37.176202 -302.549814)
					(mid 36.523422 -302.549814)
					(end 37.176202 -302.549814)
				)
			)
		)
	)
	(zone
		(layers "B.Cu" "In7.Cu" "In9.Cu" "In11.Cu" "In13.Cu" "In15.Cu")
		(hatch none 0.5)
		(connect_pads
			(clearance 0)
		)
		(min_thickness 0.25)
		(keepout
			(tracks not_allowed)
			(vias allowed)
			(pads allowed)
			(copperpour not_allowed)
			(footprints allowed)
		)
		(placement
			(enabled no)
			(sheetname "")
		)
		(fill yes
			(thermal_gap 0.5)
			(thermal_bridge_width 0.5)
			(island_removal_mode 0)
		)
		(polygon
			(pts
				(arc
					(start 67.40906 -154.28722)
					(mid 66.70548 -154.28722)
					(end 67.40906 -154.28722)
				)
			)
		)
	)
	(zone
		(layers "B.Cu" "In7.Cu" "In9.Cu" "In11.Cu" "In13.Cu" "In15.Cu")
		(hatch none 0.5)
		(connect_pads
			(clearance 0)
		)
		(min_thickness 0.25)
		(keepout
			(tracks not_allowed)
			(vias allowed)
			(pads allowed)
			(copperpour not_allowed)
			(footprints allowed)
		)
		(placement
			(enabled no)
			(sheetname "")
		)
		(fill yes
			(thermal_gap 0.5)
			(thermal_bridge_width 0.5)
			(island_removal_mode 0)
		)
		(polygon
			(pts
				(arc
					(start 196.026278 -305.399948)
					(mid 195.373498 -305.399948)
					(end 196.026278 -305.399948)
				)
			)
		)
	)
	(zone
		(layers "B.Cu" "In7.Cu" "In9.Cu" "In11.Cu" "In13.Cu" "In15.Cu")
		(hatch none 0.5)
		(connect_pads
			(clearance 0)
		)
		(min_thickness 0.25)
		(keepout
			(tracks not_allowed)
			(vias allowed)
			(pads allowed)
			(copperpour not_allowed)
			(footprints allowed)
		)
		(placement
			(enabled no)
			(sheetname "")
		)
		(fill yes
			(thermal_gap 0.5)
			(thermal_bridge_width 0.5)
			(island_removal_mode 0)
		)
		(polygon
			(pts
				(arc
					(start 421.575992 -274.049744)
					(mid 420.923212 -274.049744)
					(end 421.575992 -274.049744)
				)
			)
		)
	)
	(zone
		(layers "B.Cu" "In7.Cu" "In9.Cu" "In11.Cu" "In13.Cu" "In15.Cu")
		(hatch none 0.5)
		(connect_pads
			(clearance 0)
		)
		(min_thickness 0.25)
		(keepout
			(tracks not_allowed)
			(vias allowed)
			(pads allowed)
			(copperpour not_allowed)
			(footprints allowed)
		)
		(placement
			(enabled no)
			(sheetname "")
		)
		(fill yes
			(thermal_gap 0.5)
			(thermal_bridge_width 0.5)
			(island_removal_mode 0)
		)
		(polygon
			(pts
				(arc
					(start 415.7091 -147.087336)
					(mid 415.00552 -147.087336)
					(end 415.7091 -147.087336)
				)
			)
		)
	)
	(zone
		(layers "B.Cu" "In7.Cu" "In9.Cu" "In11.Cu" "In13.Cu" "In15.Cu")
		(hatch none 0.5)
		(connect_pads
			(clearance 0)
		)
		(min_thickness 0.25)
		(keepout
			(tracks not_allowed)
			(vias allowed)
			(pads allowed)
			(copperpour not_allowed)
			(footprints allowed)
		)
		(placement
			(enabled no)
			(sheetname "")
		)
		(fill yes
			(thermal_gap 0.5)
			(thermal_bridge_width 0.5)
			(island_removal_mode 0)
		)
		(polygon
			(pts
				(arc
					(start 422.526206 -315.849762)
					(mid 421.873426 -315.849762)
					(end 422.526206 -315.849762)
				)
			)
		)
	)
	(zone
		(layers "B.Cu" "In7.Cu" "In9.Cu" "In11.Cu" "In13.Cu" "In15.Cu")
		(hatch none 0.5)
		(connect_pads
			(clearance 0)
		)
		(min_thickness 0.25)
		(keepout
			(tracks not_allowed)
			(vias allowed)
			(pads allowed)
			(copperpour not_allowed)
			(footprints allowed)
		)
		(placement
			(enabled no)
			(sheetname "")
		)
		(fill yes
			(thermal_gap 0.5)
			(thermal_bridge_width 0.5)
			(island_removal_mode 0)
		)
		(polygon
			(pts
				(arc
					(start 72.325992 -274.999704)
					(mid 71.673212 -274.999704)
					(end 72.325992 -274.999704)
				)
			)
		)
	)
	(zone
		(layers "B.Cu" "In7.Cu" "In9.Cu" "In11.Cu" "In13.Cu" "In15.Cu")
		(hatch none 0.5)
		(connect_pads
			(clearance 0)
		)
		(min_thickness 0.25)
		(keepout
			(tracks not_allowed)
			(vias allowed)
			(pads allowed)
			(copperpour not_allowed)
			(footprints allowed)
		)
		(placement
			(enabled no)
			(sheetname "")
		)
		(fill yes
			(thermal_gap 0.5)
			(thermal_bridge_width 0.5)
			(island_removal_mode 0)
		)
		(polygon
			(pts
				(arc
					(start 269.376144 -306.349908)
					(mid 268.723364 -306.349908)
					(end 269.376144 -306.349908)
				)
			)
		)
	)
	(zone
		(layers "B.Cu" "In7.Cu" "In9.Cu" "In11.Cu" "In13.Cu" "In15.Cu")
		(hatch none 0.5)
		(connect_pads
			(clearance 0)
		)
		(min_thickness 0.25)
		(keepout
			(tracks not_allowed)
			(vias allowed)
			(pads allowed)
			(copperpour not_allowed)
			(footprints allowed)
		)
		(placement
			(enabled no)
			(sheetname "")
		)
		(fill yes
			(thermal_gap 0.5)
			(thermal_bridge_width 0.5)
			(island_removal_mode 0)
		)
		(polygon
			(pts
				(arc
					(start 181.654704 -155.223718)
					(mid 180.951124 -155.223718)
					(end 181.654704 -155.223718)
				)
			)
		)
	)
	(zone
		(layers "B.Cu" "In7.Cu" "In9.Cu" "In11.Cu" "In13.Cu" "In15.Cu")
		(hatch none 0.5)
		(connect_pads
			(clearance 0)
		)
		(min_thickness 0.25)
		(keepout
			(tracks not_allowed)
			(vias allowed)
			(pads allowed)
			(copperpour not_allowed)
			(footprints allowed)
		)
		(placement
			(enabled no)
			(sheetname "")
		)
		(fill yes
			(thermal_gap 0.5)
			(thermal_bridge_width 0.5)
			(island_removal_mode 0)
		)
		(polygon
			(pts
				(arc
					(start 69.476366 -318.699896)
					(mid 68.823586 -318.699896)
					(end 69.476366 -318.699896)
				)
			)
		)
	)
	(zone
		(layers "B.Cu" "In7.Cu" "In9.Cu" "In11.Cu" "In13.Cu" "In15.Cu")
		(hatch none 0.5)
		(connect_pads
			(clearance 0)
		)
		(min_thickness 0.25)
		(keepout
			(tracks not_allowed)
			(vias allowed)
			(pads allowed)
			(copperpour not_allowed)
			(footprints allowed)
		)
		(placement
			(enabled no)
			(sheetname "")
		)
		(fill yes
			(thermal_gap 0.5)
			(thermal_bridge_width 0.5)
			(island_removal_mode 0)
		)
		(polygon
			(pts
				(arc
					(start 118.48973 -398.890236)
					(mid 117.73027 -398.890236)
					(end 118.48973 -398.890236)
				)
			)
		)
	)
	(zone
		(layers "B.Cu" "In7.Cu" "In9.Cu" "In11.Cu" "In13.Cu" "In15.Cu")
		(hatch none 0.5)
		(connect_pads
			(clearance 0)
		)
		(min_thickness 0.25)
		(keepout
			(tracks not_allowed)
			(vias allowed)
			(pads allowed)
			(copperpour not_allowed)
			(footprints allowed)
		)
		(placement
			(enabled no)
			(sheetname "")
		)
		(fill yes
			(thermal_gap 0.5)
			(thermal_bridge_width 0.5)
			(island_removal_mode 0)
		)
		(polygon
			(pts
				(arc
					(start 413.8549 -121.367296)
					(mid 413.15132 -121.367296)
					(end 413.8549 -121.367296)
				)
			)
		)
	)
	(zone
		(layers "B.Cu" "In7.Cu" "In9.Cu" "In11.Cu" "In13.Cu" "In15.Cu")
		(hatch none 0.5)
		(connect_pads
			(clearance 0)
		)
		(min_thickness 0.25)
		(keepout
			(tracks not_allowed)
			(vias allowed)
			(pads allowed)
			(copperpour not_allowed)
			(footprints allowed)
		)
		(placement
			(enabled no)
			(sheetname "")
		)
		(fill yes
			(thermal_gap 0.5)
			(thermal_bridge_width 0.5)
			(island_removal_mode 0)
		)
		(polygon
			(pts
				(arc
					(start 76.689712 -370.489988)
					(mid 75.930252 -370.489988)
					(end 76.689712 -370.489988)
				)
			)
		)
	)
	(zone
		(layers "B.Cu" "In7.Cu" "In9.Cu" "In11.Cu" "In13.Cu" "In15.Cu")
		(hatch none 0.5)
		(connect_pads
			(clearance 0)
		)
		(min_thickness 0.25)
		(keepout
			(tracks not_allowed)
			(vias allowed)
			(pads allowed)
			(copperpour not_allowed)
			(footprints allowed)
		)
		(placement
			(enabled no)
			(sheetname "")
		)
		(fill yes
			(thermal_gap 0.5)
			(thermal_bridge_width 0.5)
			(island_removal_mode 0)
		)
		(polygon
			(pts
				(arc
					(start 198.876412 -304.449734)
					(mid 198.223632 -304.449734)
					(end 198.876412 -304.449734)
				)
			)
		)
	)
	(zone
		(layers "B.Cu" "In7.Cu" "In9.Cu" "In11.Cu" "In13.Cu" "In15.Cu")
		(hatch none 0.5)
		(connect_pads
			(clearance 0)
		)
		(min_thickness 0.25)
		(keepout
			(tracks not_allowed)
			(vias allowed)
			(pads allowed)
			(copperpour not_allowed)
			(footprints allowed)
		)
		(placement
			(enabled no)
			(sheetname "")
		)
		(fill yes
			(thermal_gap 0.5)
			(thermal_bridge_width 0.5)
			(island_removal_mode 0)
		)
		(polygon
			(pts
				(arc
					(start 427.276006 -273.099784)
					(mid 426.623226 -273.099784)
					(end 427.276006 -273.099784)
				)
			)
		)
	)
	(zone
		(layers "B.Cu" "In7.Cu" "In9.Cu" "In11.Cu" "In13.Cu" "In15.Cu")
		(hatch none 0.5)
		(connect_pads
			(clearance 0)
		)
		(min_thickness 0.25)
		(keepout
			(tracks not_allowed)
			(vias allowed)
			(pads allowed)
			(copperpour not_allowed)
			(footprints allowed)
		)
		(placement
			(enabled no)
			(sheetname "")
		)
		(fill yes
			(thermal_gap 0.5)
			(thermal_bridge_width 0.5)
			(island_removal_mode 0)
		)
		(polygon
			(pts
				(arc
					(start 196.026278 -284.499812)
					(mid 195.373498 -284.499812)
					(end 196.026278 -284.499812)
				)
			)
		)
	)
	(zone
		(layers "B.Cu" "In7.Cu" "In9.Cu" "In11.Cu" "In13.Cu" "In15.Cu")
		(hatch none 0.5)
		(connect_pads
			(clearance 0)
		)
		(min_thickness 0.25)
		(keepout
			(tracks not_allowed)
			(vias allowed)
			(pads allowed)
			(copperpour not_allowed)
			(footprints allowed)
		)
		(placement
			(enabled no)
			(sheetname "")
		)
		(fill yes
			(thermal_gap 0.5)
			(thermal_bridge_width 0.5)
			(island_removal_mode 0)
		)
		(polygon
			(pts
				(arc
					(start 430.126394 -308.249828)
					(mid 429.473614 -308.249828)
					(end 430.126394 -308.249828)
				)
			)
		)
	)
	(zone
		(layers "B.Cu" "In7.Cu" "In9.Cu" "In11.Cu" "In13.Cu" "In15.Cu")
		(hatch none 0.5)
		(connect_pads
			(clearance 0)
		)
		(min_thickness 0.25)
		(keepout
			(tracks not_allowed)
			(vias allowed)
			(pads allowed)
			(copperpour not_allowed)
			(footprints allowed)
		)
		(placement
			(enabled no)
			(sheetname "")
		)
		(fill yes
			(thermal_gap 0.5)
			(thermal_bridge_width 0.5)
			(island_removal_mode 0)
		)
		(polygon
			(pts
				(arc
					(start 419.86962 -404.290022)
					(mid 419.11016 -404.290022)
					(end 419.86962 -404.290022)
				)
			)
		)
	)
	(zone
		(layers "B.Cu" "In7.Cu" "In9.Cu" "In11.Cu" "In13.Cu" "In15.Cu")
		(hatch none 0.5)
		(connect_pads
			(clearance 0)
		)
		(min_thickness 0.25)
		(keepout
			(tracks not_allowed)
			(vias allowed)
			(pads allowed)
			(copperpour not_allowed)
			(footprints allowed)
		)
		(placement
			(enabled no)
			(sheetname "")
		)
		(fill yes
			(thermal_gap 0.5)
			(thermal_bridge_width 0.5)
			(island_removal_mode 0)
		)
		(polygon
			(pts
				(arc
					(start 286.648652 -100.17633)
					(mid 285.945072 -100.17633)
					(end 286.648652 -100.17633)
				)
			)
		)
	)
	(zone
		(layers "B.Cu" "In7.Cu" "In9.Cu" "In11.Cu" "In13.Cu" "In15.Cu")
		(hatch none 0.5)
		(connect_pads
			(clearance 0)
		)
		(min_thickness 0.25)
		(keepout
			(tracks not_allowed)
			(vias allowed)
			(pads allowed)
			(copperpour not_allowed)
			(footprints allowed)
		)
		(placement
			(enabled no)
			(sheetname "")
		)
		(fill yes
			(thermal_gap 0.5)
			(thermal_bridge_width 0.5)
			(island_removal_mode 0)
		)
		(polygon
			(pts
				(arc
					(start 295.97604 -273.099784)
					(mid 295.32326 -273.099784)
					(end 295.97604 -273.099784)
				)
			)
		)
	)
	(zone
		(layers "B.Cu" "In7.Cu" "In9.Cu" "In11.Cu" "In13.Cu" "In15.Cu")
		(hatch none 0.5)
		(connect_pads
			(clearance 0)
		)
		(min_thickness 0.25)
		(keepout
			(tracks not_allowed)
			(vias allowed)
			(pads allowed)
			(copperpour not_allowed)
			(footprints allowed)
		)
		(placement
			(enabled no)
			(sheetname "")
		)
		(fill yes
			(thermal_gap 0.5)
			(thermal_bridge_width 0.5)
			(island_removal_mode 0)
		)
		(polygon
			(pts
				(arc
					(start 38.126162 -306.349908)
					(mid 37.473382 -306.349908)
					(end 38.126162 -306.349908)
				)
			)
		)
	)
	(zone
		(layers "B.Cu" "In7.Cu" "In9.Cu" "In11.Cu" "In13.Cu" "In15.Cu")
		(hatch none 0.5)
		(connect_pads
			(clearance 0)
		)
		(min_thickness 0.25)
		(keepout
			(tracks not_allowed)
			(vias allowed)
			(pads allowed)
			(copperpour not_allowed)
			(footprints allowed)
		)
		(placement
			(enabled no)
			(sheetname "")
		)
		(fill yes
			(thermal_gap 0.5)
			(thermal_bridge_width 0.5)
			(island_removal_mode 0)
		)
		(polygon
			(pts
				(arc
					(start 52.59451 -112.776508)
					(mid 51.89093 -112.776508)
					(end 52.59451 -112.776508)
				)
			)
		)
	)
	(zone
		(layers "B.Cu" "In7.Cu" "In9.Cu" "In11.Cu" "In13.Cu" "In15.Cu")
		(hatch none 0.5)
		(connect_pads
			(clearance 0)
		)
		(min_thickness 0.25)
		(keepout
			(tracks not_allowed)
			(vias allowed)
			(pads allowed)
			(copperpour not_allowed)
			(footprints allowed)
		)
		(placement
			(enabled no)
			(sheetname "")
		)
		(fill yes
			(thermal_gap 0.5)
			(thermal_bridge_width 0.5)
			(island_removal_mode 0)
		)
		(polygon
			(pts
				(arc
					(start 196.976238 -286.399732)
					(mid 196.323458 -286.399732)
					(end 196.976238 -286.399732)
				)
			)
		)
	)
	(zone
		(layers "B.Cu" "In7.Cu" "In9.Cu" "In11.Cu" "In13.Cu" "In15.Cu")
		(hatch none 0.5)
		(connect_pads
			(clearance 0)
		)
		(min_thickness 0.25)
		(keepout
			(tracks not_allowed)
			(vias allowed)
			(pads allowed)
			(copperpour not_allowed)
			(footprints allowed)
		)
		(placement
			(enabled no)
			(sheetname "")
		)
		(fill yes
			(thermal_gap 0.5)
			(thermal_bridge_width 0.5)
			(island_removal_mode 0)
		)
		(polygon
			(pts
				(arc
					(start 181.654704 -145.287238)
					(mid 180.951124 -145.287238)
					(end 181.654704 -145.287238)
				)
			)
		)
	)
	(zone
		(layers "B.Cu" "In7.Cu" "In9.Cu" "In11.Cu" "In13.Cu" "In15.Cu")
		(hatch none 0.5)
		(connect_pads
			(clearance 0)
		)
		(min_thickness 0.25)
		(keepout
			(tracks not_allowed)
			(vias allowed)
			(pads allowed)
			(copperpour not_allowed)
			(footprints allowed)
		)
		(placement
			(enabled no)
			(sheetname "")
		)
		(fill yes
			(thermal_gap 0.5)
			(thermal_bridge_width 0.5)
			(island_removal_mode 0)
		)
		(polygon
			(pts
				(arc
					(start 196.976238 -317.749936)
					(mid 196.323458 -317.749936)
					(end 196.976238 -317.749936)
				)
			)
		)
	)
	(zone
		(layers "B.Cu" "In7.Cu" "In9.Cu" "In11.Cu" "In13.Cu" "In15.Cu")
		(hatch none 0.5)
		(connect_pads
			(clearance 0)
		)
		(min_thickness 0.25)
		(keepout
			(tracks not_allowed)
			(vias allowed)
			(pads allowed)
			(copperpour not_allowed)
			(footprints allowed)
		)
		(placement
			(enabled no)
			(sheetname "")
		)
		(fill yes
			(thermal_gap 0.5)
			(thermal_bridge_width 0.5)
			(island_removal_mode 0)
		)
		(polygon
			(pts
				(arc
					(start 37.176202 -304.449734)
					(mid 36.523422 -304.449734)
					(end 37.176202 -304.449734)
				)
			)
		)
	)
	(zone
		(layers "B.Cu" "In7.Cu" "In9.Cu" "In11.Cu" "In13.Cu" "In15.Cu")
		(hatch none 0.5)
		(connect_pads
			(clearance 0)
		)
		(min_thickness 0.25)
		(keepout
			(tracks not_allowed)
			(vias allowed)
			(pads allowed)
			(copperpour not_allowed)
			(footprints allowed)
		)
		(placement
			(enabled no)
			(sheetname "")
		)
		(fill yes
			(thermal_gap 0.5)
			(thermal_bridge_width 0.5)
			(island_removal_mode 0)
		)
		(polygon
			(pts
				(arc
					(start 50.47615 -318.699896)
					(mid 49.82337 -318.699896)
					(end 50.47615 -318.699896)
				)
			)
		)
	)
	(zone
		(layers "B.Cu" "In7.Cu" "In9.Cu" "In11.Cu" "In13.Cu" "In15.Cu")
		(hatch none 0.5)
		(connect_pads
			(clearance 0)
		)
		(min_thickness 0.25)
		(keepout
			(tracks not_allowed)
			(vias allowed)
			(pads allowed)
			(copperpour not_allowed)
			(footprints allowed)
		)
		(placement
			(enabled no)
			(sheetname "")
		)
		(fill yes
			(thermal_gap 0.5)
			(thermal_bridge_width 0.5)
			(island_removal_mode 0)
		)
		(polygon
			(pts
				(arc
					(start 197.926452 -308.249828)
					(mid 197.273672 -308.249828)
					(end 197.926452 -308.249828)
				)
			)
		)
	)
	(zone
		(layers "B.Cu" "In7.Cu" "In9.Cu" "In11.Cu" "In13.Cu" "In15.Cu")
		(hatch none 0.5)
		(connect_pads
			(clearance 0)
		)
		(min_thickness 0.25)
		(keepout
			(tracks not_allowed)
			(vias allowed)
			(pads allowed)
			(copperpour not_allowed)
			(footprints allowed)
		)
		(placement
			(enabled no)
			(sheetname "")
		)
		(fill yes
			(thermal_gap 0.5)
			(thermal_bridge_width 0.5)
			(island_removal_mode 0)
		)
		(polygon
			(pts
				(arc
					(start 313.076082 -284.499812)
					(mid 312.423302 -284.499812)
					(end 313.076082 -284.499812)
				)
			)
		)
	)
	(zone
		(layers "B.Cu" "In7.Cu" "In9.Cu" "In11.Cu" "In13.Cu" "In15.Cu")
		(hatch none 0.5)
		(connect_pads
			(clearance 0)
		)
		(min_thickness 0.25)
		(keepout
			(tracks not_allowed)
			(vias allowed)
			(pads allowed)
			(copperpour not_allowed)
			(footprints allowed)
		)
		(placement
			(enabled no)
			(sheetname "")
		)
		(fill yes
			(thermal_gap 0.5)
			(thermal_bridge_width 0.5)
			(island_removal_mode 0)
		)
		(polygon
			(pts
				(arc
					(start 429.17618 -305.399948)
					(mid 428.5234 -305.399948)
					(end 429.17618 -305.399948)
				)
			)
		)
	)
	(zone
		(layers "B.Cu" "In7.Cu" "In9.Cu" "In11.Cu" "In13.Cu" "In15.Cu")
		(hatch none 0.5)
		(connect_pads
			(clearance 0)
		)
		(min_thickness 0.25)
		(keepout
			(tracks not_allowed)
			(vias allowed)
			(pads allowed)
			(copperpour not_allowed)
			(footprints allowed)
		)
		(placement
			(enabled no)
			(sheetname "")
		)
		(fill yes
			(thermal_gap 0.5)
			(thermal_bridge_width 0.5)
			(island_removal_mode 0)
		)
		(polygon
			(pts
				(arc
					(start 428.22622 -316.799722)
					(mid 427.57344 -316.799722)
					(end 428.22622 -316.799722)
				)
			)
		)
	)
	(zone
		(layers "B.Cu" "In7.Cu" "In9.Cu" "In11.Cu" "In13.Cu" "In15.Cu")
		(hatch none 0.5)
		(connect_pads
			(clearance 0)
		)
		(min_thickness 0.25)
		(keepout
			(tracks not_allowed)
			(vias allowed)
			(pads allowed)
			(copperpour not_allowed)
			(footprints allowed)
		)
		(placement
			(enabled no)
			(sheetname "")
		)
		(fill yes
			(thermal_gap 0.5)
			(thermal_bridge_width 0.5)
			(island_removal_mode 0)
		)
		(polygon
			(pts
				(arc
					(start 193.176398 -317.749936)
					(mid 192.523618 -317.749936)
					(end 193.176398 -317.749936)
				)
			)
		)
	)
	(zone
		(layers "B.Cu" "In7.Cu" "In9.Cu" "In11.Cu" "In13.Cu" "In15.Cu")
		(hatch none 0.5)
		(connect_pads
			(clearance 0)
		)
		(min_thickness 0.25)
		(keepout
			(tracks not_allowed)
			(vias allowed)
			(pads allowed)
			(copperpour not_allowed)
			(footprints allowed)
		)
		(placement
			(enabled no)
			(sheetname "")
		)
		(fill yes
			(thermal_gap 0.5)
			(thermal_bridge_width 0.5)
			(island_removal_mode 0)
		)
		(polygon
			(pts
				(arc
					(start 184.625996 -275.949664)
					(mid 183.973216 -275.949664)
					(end 184.625996 -275.949664)
				)
			)
		)
	)
	(zone
		(layers "B.Cu" "In7.Cu" "In9.Cu" "In11.Cu" "In13.Cu" "In15.Cu")
		(hatch none 0.5)
		(connect_pads
			(clearance 0)
		)
		(min_thickness 0.25)
		(keepout
			(tracks not_allowed)
			(vias allowed)
			(pads allowed)
			(copperpour not_allowed)
			(footprints allowed)
		)
		(placement
			(enabled no)
			(sheetname "")
		)
		(fill yes
			(thermal_gap 0.5)
			(thermal_bridge_width 0.5)
			(island_removal_mode 0)
		)
		(polygon
			(pts
				(arc
					(start 410.175964 -273.099784)
					(mid 409.523184 -273.099784)
					(end 410.175964 -273.099784)
				)
			)
		)
	)
	(zone
		(layers "B.Cu" "In7.Cu" "In9.Cu" "In11.Cu" "In13.Cu" "In15.Cu")
		(hatch none 0.5)
		(connect_pads
			(clearance 0)
		)
		(min_thickness 0.25)
		(keepout
			(tracks not_allowed)
			(vias allowed)
			(pads allowed)
			(copperpour not_allowed)
			(footprints allowed)
		)
		(placement
			(enabled no)
			(sheetname "")
		)
		(fill yes
			(thermal_gap 0.5)
			(thermal_bridge_width 0.5)
			(island_removal_mode 0)
		)
		(polygon
			(pts
				(arc
					(start 413.976058 -273.099784)
					(mid 413.323278 -273.099784)
					(end 413.976058 -273.099784)
				)
			)
		)
	)
	(zone
		(layers "B.Cu" "In7.Cu" "In9.Cu" "In11.Cu" "In13.Cu" "In15.Cu")
		(hatch none 0.5)
		(connect_pads
			(clearance 0)
		)
		(min_thickness 0.25)
		(keepout
			(tracks not_allowed)
			(vias allowed)
			(pads allowed)
			(copperpour not_allowed)
			(footprints allowed)
		)
		(placement
			(enabled no)
			(sheetname "")
		)
		(fill yes
			(thermal_gap 0.5)
			(thermal_bridge_width 0.5)
			(island_removal_mode 0)
		)
		(polygon
			(pts
				(arc
					(start 274.973288 17.603724)
					(mid 274.269708 17.603724)
					(end 274.973288 17.603724)
				)
			)
		)
	)
	(zone
		(layers "B.Cu" "In7.Cu" "In9.Cu" "In11.Cu" "In13.Cu" "In15.Cu")
		(hatch none 0.5)
		(connect_pads
			(clearance 0)
		)
		(min_thickness 0.25)
		(keepout
			(tracks not_allowed)
			(vias allowed)
			(pads allowed)
			(copperpour not_allowed)
			(footprints allowed)
		)
		(placement
			(enabled no)
			(sheetname "")
		)
		(fill yes
			(thermal_gap 0.5)
			(thermal_bridge_width 0.5)
			(island_removal_mode 0)
		)
		(polygon
			(pts
				(arc
					(start 284.794452 -105.57637)
					(mid 284.090872 -105.57637)
					(end 284.794452 -105.57637)
				)
			)
		)
	)
	(zone
		(layers "B.Cu" "In7.Cu" "In9.Cu" "In11.Cu" "In13.Cu" "In15.Cu")
		(hatch none 0.5)
		(connect_pads
			(clearance 0)
		)
		(min_thickness 0.25)
		(keepout
			(tracks not_allowed)
			(vias allowed)
			(pads allowed)
			(copperpour not_allowed)
			(footprints allowed)
		)
		(placement
			(enabled no)
			(sheetname "")
		)
		(fill yes
			(thermal_gap 0.5)
			(thermal_bridge_width 0.5)
			(island_removal_mode 0)
		)
		(polygon
			(pts
				(arc
					(start 424.269662 -378.290074)
					(mid 423.510202 -378.290074)
					(end 424.269662 -378.290074)
				)
			)
		)
	)
	(zone
		(layers "B.Cu" "In7.Cu" "In9.Cu" "In11.Cu" "In13.Cu" "In15.Cu")
		(hatch none 0.5)
		(connect_pads
			(clearance 0)
		)
		(min_thickness 0.25)
		(keepout
			(tracks not_allowed)
			(vias allowed)
			(pads allowed)
			(copperpour not_allowed)
			(footprints allowed)
		)
		(placement
			(enabled no)
			(sheetname "")
		)
		(fill yes
			(thermal_gap 0.5)
			(thermal_bridge_width 0.5)
			(island_removal_mode 0)
		)
		(polygon
			(pts
				(arc
					(start 81.826354 -274.999704)
					(mid 81.173574 -274.999704)
					(end 81.826354 -274.999704)
				)
			)
		)
	)
	(zone
		(layers "B.Cu" "In7.Cu" "In9.Cu" "In11.Cu" "In13.Cu" "In15.Cu")
		(hatch none 0.5)
		(connect_pads
			(clearance 0)
		)
		(min_thickness 0.25)
		(keepout
			(tracks not_allowed)
			(vias allowed)
			(pads allowed)
			(copperpour not_allowed)
			(footprints allowed)
		)
		(placement
			(enabled no)
			(sheetname "")
		)
		(fill yes
			(thermal_gap 0.5)
			(thermal_bridge_width 0.5)
			(island_removal_mode 0)
		)
		(polygon
			(pts
				(arc
					(start 286.648652 -102.912672)
					(mid 285.945072 -102.912672)
					(end 286.648652 -102.912672)
				)
			)
		)
	)
	(zone
		(layers "B.Cu" "In7.Cu" "In9.Cu" "In11.Cu" "In13.Cu" "In15.Cu")
		(hatch none 0.5)
		(connect_pads
			(clearance 0)
		)
		(min_thickness 0.25)
		(keepout
			(tracks not_allowed)
			(vias allowed)
			(pads allowed)
			(copperpour not_allowed)
			(footprints allowed)
		)
		(placement
			(enabled no)
			(sheetname "")
		)
		(fill yes
			(thermal_gap 0.5)
			(thermal_bridge_width 0.5)
			(island_removal_mode 0)
		)
		(polygon
			(pts
				(arc
					(start 40.026336 -305.399948)
					(mid 39.373556 -305.399948)
					(end 40.026336 -305.399948)
				)
			)
		)
	)
	(zone
		(layers "B.Cu" "In7.Cu" "In9.Cu" "In11.Cu" "In13.Cu" "In15.Cu")
		(hatch none 0.5)
		(connect_pads
			(clearance 0)
		)
		(min_thickness 0.25)
		(keepout
			(tracks not_allowed)
			(vias allowed)
			(pads allowed)
			(copperpour not_allowed)
			(footprints allowed)
		)
		(placement
			(enabled no)
			(sheetname "")
		)
		(fill yes
			(thermal_gap 0.5)
			(thermal_bridge_width 0.5)
			(island_removal_mode 0)
		)
		(polygon
			(pts
				(arc
					(start 301.676054 -274.049744)
					(mid 301.023274 -274.049744)
					(end 301.676054 -274.049744)
				)
			)
		)
	)
	(zone
		(layers "B.Cu" "In7.Cu" "In9.Cu" "In11.Cu" "In13.Cu" "In15.Cu")
		(hatch none 0.5)
		(connect_pads
			(clearance 0)
		)
		(min_thickness 0.25)
		(keepout
			(tracks not_allowed)
			(vias allowed)
			(pads allowed)
			(copperpour not_allowed)
			(footprints allowed)
		)
		(placement
			(enabled no)
			(sheetname "")
		)
		(fill yes
			(thermal_gap 0.5)
			(thermal_bridge_width 0.5)
			(island_removal_mode 0)
		)
		(polygon
			(pts
				(arc
					(start 433.069492 -405.589994)
					(mid 432.310032 -405.589994)
					(end 433.069492 -405.589994)
				)
			)
		)
	)
	(zone
		(layers "B.Cu" "In7.Cu" "In9.Cu" "In11.Cu" "In13.Cu" "In15.Cu")
		(hatch none 0.5)
		(connect_pads
			(clearance 0)
		)
		(min_thickness 0.25)
		(keepout
			(tracks not_allowed)
			(vias allowed)
			(pads allowed)
			(copperpour not_allowed)
			(footprints allowed)
		)
		(placement
			(enabled no)
			(sheetname "")
		)
		(fill yes
			(thermal_gap 0.5)
			(thermal_bridge_width 0.5)
			(island_removal_mode 0)
		)
		(polygon
			(pts
				(arc
					(start 70.425818 -275.949918)
					(mid 69.773038 -275.949918)
					(end 70.425818 -275.949918)
				)
			)
		)
	)
	(zone
		(layers "B.Cu" "In7.Cu" "In9.Cu" "In11.Cu" "In13.Cu" "In15.Cu")
		(hatch none 0.5)
		(connect_pads
			(clearance 0)
		)
		(min_thickness 0.25)
		(keepout
			(tracks not_allowed)
			(vias allowed)
			(pads allowed)
			(copperpour not_allowed)
			(footprints allowed)
		)
		(placement
			(enabled no)
			(sheetname "")
		)
		(fill yes
			(thermal_gap 0.5)
			(thermal_bridge_width 0.5)
			(island_removal_mode 0)
		)
		(polygon
			(pts
				(arc
					(start 59.976004 -273.09953)
					(mid 59.323224 -273.09953)
					(end 59.976004 -273.09953)
				)
			)
		)
	)
	(zone
		(layers "B.Cu" "In7.Cu" "In9.Cu" "In11.Cu" "In13.Cu" "In15.Cu")
		(hatch none 0.5)
		(connect_pads
			(clearance 0)
		)
		(min_thickness 0.25)
		(keepout
			(tracks not_allowed)
			(vias allowed)
			(pads allowed)
			(copperpour not_allowed)
			(footprints allowed)
		)
		(placement
			(enabled no)
			(sheetname "")
		)
		(fill yes
			(thermal_gap 0.5)
			(thermal_bridge_width 0.5)
			(island_removal_mode 0)
		)
		(polygon
			(pts
				(arc
					(start 429.17618 -282.599892)
					(mid 428.5234 -282.599892)
					(end 429.17618 -282.599892)
				)
			)
		)
	)
	(zone
		(layers "B.Cu" "In7.Cu" "In9.Cu" "In11.Cu" "In13.Cu" "In15.Cu")
		(hatch none 0.5)
		(connect_pads
			(clearance 0)
		)
		(min_thickness 0.25)
		(keepout
			(tracks not_allowed)
			(vias allowed)
			(pads allowed)
			(copperpour not_allowed)
			(footprints allowed)
		)
		(placement
			(enabled no)
			(sheetname "")
		)
		(fill yes
			(thermal_gap 0.5)
			(thermal_bridge_width 0.5)
			(island_removal_mode 0)
		)
		(polygon
			(pts
				(arc
					(start 384.669792 -396.49019)
					(mid 383.910332 -396.49019)
					(end 384.669792 -396.49019)
				)
			)
		)
	)
	(zone
		(layers "B.Cu" "In7.Cu" "In9.Cu" "In11.Cu" "In13.Cu" "In15.Cu")
		(hatch none 0.5)
		(connect_pads
			(clearance 0)
		)
		(min_thickness 0.25)
		(keepout
			(tracks not_allowed)
			(vias allowed)
			(pads allowed)
			(copperpour not_allowed)
			(footprints allowed)
		)
		(placement
			(enabled no)
			(sheetname "")
		)
		(fill yes
			(thermal_gap 0.5)
			(thermal_bridge_width 0.5)
			(island_removal_mode 0)
		)
		(polygon
			(pts
				(arc
					(start 409.226258 -316.799722)
					(mid 408.573478 -316.799722)
					(end 409.226258 -316.799722)
				)
			)
		)
	)
	(zone
		(layers "B.Cu" "In7.Cu" "In9.Cu" "In11.Cu" "In13.Cu" "In15.Cu")
		(hatch none 0.5)
		(connect_pads
			(clearance 0)
		)
		(min_thickness 0.25)
		(keepout
			(tracks not_allowed)
			(vias allowed)
			(pads allowed)
			(copperpour not_allowed)
			(footprints allowed)
		)
		(placement
			(enabled no)
			(sheetname "")
		)
		(fill yes
			(thermal_gap 0.5)
			(thermal_bridge_width 0.5)
			(island_removal_mode 0)
		)
		(polygon
			(pts
				(arc
					(start 297.754802 -120.503696)
					(mid 297.051222 -120.503696)
					(end 297.754802 -120.503696)
				)
			)
		)
	)
	(zone
		(layers "B.Cu" "In7.Cu" "In9.Cu" "In11.Cu" "In13.Cu" "In15.Cu")
		(hatch none 0.5)
		(connect_pads
			(clearance 0)
		)
		(min_thickness 0.25)
		(keepout
			(tracks not_allowed)
			(vias allowed)
			(pads allowed)
			(copperpour not_allowed)
			(footprints allowed)
		)
		(placement
			(enabled no)
			(sheetname "")
		)
		(fill yes
			(thermal_gap 0.5)
			(thermal_bridge_width 0.5)
			(island_removal_mode 0)
		)
		(polygon
			(pts
				(arc
					(start 292.175946 -274.04949)
					(mid 291.523166 -274.04949)
					(end 292.175946 -274.04949)
				)
			)
		)
	)
	(zone
		(layers "B.Cu" "In7.Cu" "In9.Cu" "In11.Cu" "In13.Cu" "In15.Cu")
		(hatch none 0.5)
		(connect_pads
			(clearance 0)
		)
		(min_thickness 0.25)
		(keepout
			(tracks not_allowed)
			(vias allowed)
			(pads allowed)
			(copperpour not_allowed)
			(footprints allowed)
		)
		(placement
			(enabled no)
			(sheetname "")
		)
		(fill yes
			(thermal_gap 0.5)
			(thermal_bridge_width 0.5)
			(island_removal_mode 0)
		)
		(polygon
			(pts
				(arc
					(start 60.925964 -275.949664)
					(mid 60.273184 -275.949664)
					(end 60.925964 -275.949664)
				)
			)
		)
	)
	(zone
		(layers "B.Cu" "In7.Cu" "In9.Cu" "In11.Cu" "In13.Cu" "In15.Cu")
		(hatch none 0.5)
		(connect_pads
			(clearance 0)
		)
		(min_thickness 0.25)
		(keepout
			(tracks not_allowed)
			(vias allowed)
			(pads allowed)
			(copperpour not_allowed)
			(footprints allowed)
		)
		(placement
			(enabled no)
			(sheetname "")
		)
		(fill yes
			(thermal_gap 0.5)
			(thermal_bridge_width 0.5)
			(island_removal_mode 0)
		)
		(polygon
			(pts
				(arc
					(start 414.926018 -275.949918)
					(mid 414.273238 -275.949918)
					(end 414.926018 -275.949918)
				)
			)
		)
	)
	(zone
		(layers "B.Cu" "In7.Cu" "In9.Cu" "In11.Cu" "In13.Cu" "In15.Cu")
		(hatch none 0.5)
		(connect_pads
			(clearance 0)
		)
		(min_thickness 0.25)
		(keepout
			(tracks not_allowed)
			(vias allowed)
			(pads allowed)
			(copperpour not_allowed)
			(footprints allowed)
		)
		(placement
			(enabled no)
			(sheetname "")
		)
		(fill yes
			(thermal_gap 0.5)
			(thermal_bridge_width 0.5)
			(island_removal_mode 0)
		)
		(polygon
			(pts
				(arc
					(start 418.725858 -275.949918)
					(mid 418.073078 -275.949918)
					(end 418.725858 -275.949918)
				)
			)
		)
	)
	(zone
		(layers "B.Cu" "In7.Cu" "In9.Cu" "In11.Cu" "In13.Cu" "In15.Cu")
		(hatch none 0.5)
		(connect_pads
			(clearance 0)
		)
		(min_thickness 0.25)
		(keepout
			(tracks not_allowed)
			(vias allowed)
			(pads allowed)
			(copperpour not_allowed)
			(footprints allowed)
		)
		(placement
			(enabled no)
			(sheetname "")
		)
		(fill yes
			(thermal_gap 0.5)
			(thermal_bridge_width 0.5)
			(island_removal_mode 0)
		)
		(polygon
			(pts
				(arc
					(start 72.325992 -275.949664)
					(mid 71.673212 -275.949664)
					(end 72.325992 -275.949664)
				)
			)
		)
	)
	(zone
		(layers "B.Cu" "In7.Cu" "In9.Cu" "In11.Cu" "In13.Cu" "In15.Cu")
		(hatch none 0.5)
		(connect_pads
			(clearance 0)
		)
		(min_thickness 0.25)
		(keepout
			(tracks not_allowed)
			(vias allowed)
			(pads allowed)
			(copperpour not_allowed)
			(footprints allowed)
		)
		(placement
			(enabled no)
			(sheetname "")
		)
		(fill yes
			(thermal_gap 0.5)
			(thermal_bridge_width 0.5)
			(island_removal_mode 0)
		)
		(polygon
			(pts
				(arc
					(start 423.47642 -317.749936)
					(mid 422.82364 -317.749936)
					(end 423.47642 -317.749936)
				)
			)
		)
	)
	(zone
		(layers "B.Cu" "In7.Cu" "In9.Cu" "In11.Cu" "In13.Cu" "In15.Cu")
		(hatch none 0.5)
		(connect_pads
			(clearance 0)
		)
		(min_thickness 0.25)
		(keepout
			(tracks not_allowed)
			(vias allowed)
			(pads allowed)
			(copperpour not_allowed)
			(footprints allowed)
		)
		(placement
			(enabled no)
			(sheetname "")
		)
		(fill yes
			(thermal_gap 0.5)
			(thermal_bridge_width 0.5)
			(island_removal_mode 0)
		)
		(polygon
			(pts
				(arc
					(start 67.40906 -146.223736)
					(mid 66.70548 -146.223736)
					(end 67.40906 -146.223736)
				)
			)
		)
	)
	(zone
		(layers "B.Cu" "In7.Cu" "In9.Cu" "In11.Cu" "In13.Cu" "In15.Cu")
		(hatch none 0.5)
		(connect_pads
			(clearance 0)
		)
		(min_thickness 0.25)
		(keepout
			(tracks not_allowed)
			(vias allowed)
			(pads allowed)
			(copperpour not_allowed)
			(footprints allowed)
		)
		(placement
			(enabled no)
			(sheetname "")
		)
		(fill yes
			(thermal_gap 0.5)
			(thermal_bridge_width 0.5)
			(island_removal_mode 0)
		)
		(polygon
			(pts
				(arc
					(start 170.548554 -106.512614)
					(mid 169.844974 -106.512614)
					(end 170.548554 -106.512614)
				)
			)
		)
	)
	(zone
		(layers "B.Cu" "In7.Cu" "In9.Cu" "In11.Cu" "In13.Cu" "In15.Cu")
		(hatch none 0.5)
		(connect_pads
			(clearance 0)
		)
		(min_thickness 0.25)
		(keepout
			(tracks not_allowed)
			(vias allowed)
			(pads allowed)
			(copperpour not_allowed)
			(footprints allowed)
		)
		(placement
			(enabled no)
			(sheetname "")
		)
		(fill yes
			(thermal_gap 0.5)
			(thermal_bridge_width 0.5)
			(island_removal_mode 0)
		)
		(polygon
			(pts
				(arc
					(start 302.626268 -316.799722)
					(mid 301.973488 -316.799722)
					(end 302.626268 -316.799722)
				)
			)
		)
	)
	(zone
		(layers "B.Cu" "In7.Cu" "In9.Cu" "In11.Cu" "In13.Cu" "In15.Cu")
		(hatch none 0.5)
		(connect_pads
			(clearance 0)
		)
		(min_thickness 0.25)
		(keepout
			(tracks not_allowed)
			(vias allowed)
			(pads allowed)
			(copperpour not_allowed)
			(footprints allowed)
		)
		(placement
			(enabled no)
			(sheetname "")
		)
		(fill yes
			(thermal_gap 0.5)
			(thermal_bridge_width 0.5)
			(island_removal_mode 0)
		)
		(polygon
			(pts
				(arc
					(start 431.076354 -310.149748)
					(mid 430.423574 -310.149748)
					(end 431.076354 -310.149748)
				)
			)
		)
	)
	(zone
		(layers "B.Cu" "In7.Cu" "In9.Cu" "In11.Cu" "In13.Cu" "In15.Cu")
		(hatch none 0.5)
		(connect_pads
			(clearance 0)
		)
		(min_thickness 0.25)
		(keepout
			(tracks not_allowed)
			(vias allowed)
			(pads allowed)
			(copperpour not_allowed)
			(footprints allowed)
		)
		(placement
			(enabled no)
			(sheetname "")
		)
		(fill yes
			(thermal_gap 0.5)
			(thermal_bridge_width 0.5)
			(island_removal_mode 0)
		)
		(polygon
			(pts
				(arc
					(start 301.676308 -317.749936)
					(mid 301.023528 -317.749936)
					(end 301.676308 -317.749936)
				)
			)
		)
	)
	(zone
		(layers "B.Cu" "In7.Cu" "In9.Cu" "In11.Cu" "In13.Cu" "In15.Cu")
		(hatch none 0.5)
		(connect_pads
			(clearance 0)
		)
		(min_thickness 0.25)
		(keepout
			(tracks not_allowed)
			(vias allowed)
			(pads allowed)
			(copperpour not_allowed)
			(footprints allowed)
		)
		(placement
			(enabled no)
			(sheetname "")
		)
		(fill yes
			(thermal_gap 0.5)
			(thermal_bridge_width 0.5)
			(island_removal_mode 0)
		)
		(polygon
			(pts
				(arc
					(start 422.526206 -316.799722)
					(mid 421.873426 -316.799722)
					(end 422.526206 -316.799722)
				)
			)
		)
	)
	(zone
		(layers "B.Cu" "In7.Cu" "In9.Cu" "In11.Cu" "In13.Cu" "In15.Cu")
		(hatch none 0.5)
		(connect_pads
			(clearance 0)
		)
		(min_thickness 0.25)
		(keepout
			(tracks not_allowed)
			(vias allowed)
			(pads allowed)
			(copperpour not_allowed)
			(footprints allowed)
		)
		(placement
			(enabled no)
			(sheetname "")
		)
		(fill yes
			(thermal_gap 0.5)
			(thermal_bridge_width 0.5)
			(island_removal_mode 0)
		)
		(polygon
			(pts
				(arc
					(start 389.06958 -397.790162)
					(mid 388.31012 -397.790162)
					(end 389.06958 -397.790162)
				)
			)
		)
	)
	(zone
		(layers "B.Cu" "In7.Cu" "In9.Cu" "In11.Cu" "In13.Cu" "In15.Cu")
		(hatch none 0.5)
		(connect_pads
			(clearance 0)
		)
		(min_thickness 0.25)
		(keepout
			(tracks not_allowed)
			(vias allowed)
			(pads allowed)
			(copperpour not_allowed)
			(footprints allowed)
		)
		(placement
			(enabled no)
			(sheetname "")
		)
		(fill yes
			(thermal_gap 0.5)
			(thermal_bridge_width 0.5)
			(island_removal_mode 0)
		)
		(polygon
			(pts
				(arc
					(start 131.689856 -398.890236)
					(mid 130.930396 -398.890236)
					(end 131.689856 -398.890236)
				)
			)
		)
	)
	(zone
		(layers "B.Cu" "In7.Cu" "In9.Cu" "In11.Cu" "In13.Cu" "In15.Cu")
		(hatch none 0.5)
		(connect_pads
			(clearance 0)
		)
		(min_thickness 0.25)
		(keepout
			(tracks not_allowed)
			(vias allowed)
			(pads allowed)
			(copperpour not_allowed)
			(footprints allowed)
		)
		(placement
			(enabled no)
			(sheetname "")
		)
		(fill yes
			(thermal_gap 0.5)
			(thermal_bridge_width 0.5)
			(island_removal_mode 0)
		)
		(polygon
			(pts
				(arc
					(start 430.126394 -306.349908)
					(mid 429.473614 -306.349908)
					(end 430.126394 -306.349908)
				)
			)
		)
	)
	(zone
		(layers "B.Cu" "In7.Cu" "In9.Cu" "In11.Cu" "In13.Cu" "In15.Cu")
		(hatch none 0.5)
		(connect_pads
			(clearance 0)
		)
		(min_thickness 0.25)
		(keepout
			(tracks not_allowed)
			(vias allowed)
			(pads allowed)
			(copperpour not_allowed)
			(footprints allowed)
		)
		(placement
			(enabled no)
			(sheetname "")
		)
		(fill yes
			(thermal_gap 0.5)
			(thermal_bridge_width 0.5)
			(island_removal_mode 0)
		)
		(polygon
			(pts
				(arc
					(start 428.669704 -379.590046)
					(mid 427.910244 -379.590046)
					(end 428.669704 -379.590046)
				)
			)
		)
	)
	(zone
		(layers "B.Cu" "In7.Cu" "In9.Cu" "In11.Cu" "In13.Cu" "In15.Cu")
		(hatch none 0.5)
		(connect_pads
			(clearance 0)
		)
		(min_thickness 0.25)
		(keepout
			(tracks not_allowed)
			(vias allowed)
			(pads allowed)
			(copperpour not_allowed)
			(footprints allowed)
		)
		(placement
			(enabled no)
			(sheetname "")
		)
		(fill yes
			(thermal_gap 0.5)
			(thermal_bridge_width 0.5)
			(island_removal_mode 0)
		)
		(polygon
			(pts
				(arc
					(start 196.976238 -318.699896)
					(mid 196.323458 -318.699896)
					(end 196.976238 -318.699896)
				)
			)
		)
	)
	(zone
		(layers "B.Cu" "In7.Cu" "In9.Cu" "In11.Cu" "In13.Cu" "In15.Cu")
		(hatch none 0.5)
		(connect_pads
			(clearance 0)
		)
		(min_thickness 0.25)
		(keepout
			(tracks not_allowed)
			(vias allowed)
			(pads allowed)
			(copperpour not_allowed)
			(footprints allowed)
		)
		(placement
			(enabled no)
			(sheetname "")
		)
		(fill yes
			(thermal_gap 0.5)
			(thermal_bridge_width 0.5)
			(island_removal_mode 0)
		)
		(polygon
			(pts
				(arc
					(start 273.176238 -317.749936)
					(mid 272.523458 -317.749936)
					(end 273.176238 -317.749936)
				)
			)
		)
	)
	(zone
		(layers "B.Cu" "In7.Cu" "In9.Cu" "In11.Cu" "In13.Cu" "In15.Cu")
		(hatch none 0.5)
		(connect_pads
			(clearance 0)
		)
		(min_thickness 0.25)
		(keepout
			(tracks not_allowed)
			(vias allowed)
			(pads allowed)
			(copperpour not_allowed)
			(footprints allowed)
		)
		(placement
			(enabled no)
			(sheetname "")
		)
		(fill yes
			(thermal_gap 0.5)
			(thermal_bridge_width 0.5)
			(island_removal_mode 0)
		)
		(polygon
			(pts
				(arc
					(start 81.826354 -283.549852)
					(mid 81.173574 -283.549852)
					(end 81.826354 -283.549852)
				)
			)
		)
	)
	(zone
		(layers "B.Cu" "In7.Cu" "In9.Cu" "In11.Cu" "In13.Cu" "In15.Cu")
		(hatch none 0.5)
		(connect_pads
			(clearance 0)
		)
		(min_thickness 0.25)
		(keepout
			(tracks not_allowed)
			(vias allowed)
			(pads allowed)
			(copperpour not_allowed)
			(footprints allowed)
		)
		(placement
			(enabled no)
			(sheetname "")
		)
		(fill yes
			(thermal_gap 0.5)
			(thermal_bridge_width 0.5)
			(island_removal_mode 0)
		)
		(polygon
			(pts
				(arc
					(start 314.976256 -287.349946)
					(mid 314.323476 -287.349946)
					(end 314.976256 -287.349946)
				)
			)
		)
	)
	(zone
		(layers "B.Cu" "In7.Cu" "In9.Cu" "In11.Cu" "In13.Cu" "In15.Cu")
		(hatch none 0.5)
		(connect_pads
			(clearance 0)
		)
		(min_thickness 0.25)
		(keepout
			(tracks not_allowed)
			(vias allowed)
			(pads allowed)
			(copperpour not_allowed)
			(footprints allowed)
		)
		(placement
			(enabled no)
			(sheetname "")
		)
		(fill yes
			(thermal_gap 0.5)
			(thermal_bridge_width 0.5)
			(island_removal_mode 0)
		)
		(polygon
			(pts
				(arc
					(start 292.269672 -409.490164)
					(mid 291.510212 -409.490164)
					(end 292.269672 -409.490164)
				)
			)
		)
	)
	(zone
		(layers "B.Cu" "In7.Cu" "In9.Cu" "In11.Cu" "In13.Cu" "In15.Cu")
		(hatch none 0.5)
		(connect_pads
			(clearance 0)
		)
		(min_thickness 0.25)
		(keepout
			(tracks not_allowed)
			(vias allowed)
			(pads allowed)
			(copperpour not_allowed)
			(footprints allowed)
		)
		(placement
			(enabled no)
			(sheetname "")
		)
		(fill yes
			(thermal_gap 0.5)
			(thermal_bridge_width 0.5)
			(island_removal_mode 0)
		)
		(polygon
			(pts
				(arc
					(start 308.326028 -274.999704)
					(mid 307.673248 -274.999704)
					(end 308.326028 -274.999704)
				)
			)
		)
	)
	(zone
		(layers "B.Cu" "In7.Cu" "In9.Cu" "In11.Cu" "In13.Cu" "In15.Cu")
		(hatch none 0.5)
		(connect_pads
			(clearance 0)
		)
		(min_thickness 0.25)
		(keepout
			(tracks not_allowed)
			(vias allowed)
			(pads allowed)
			(copperpour not_allowed)
			(footprints allowed)
		)
		(placement
			(enabled no)
			(sheetname "")
		)
		(fill yes
			(thermal_gap 0.5)
			(thermal_bridge_width 0.5)
			(island_removal_mode 0)
		)
		(polygon
			(pts
				(arc
					(start 270.326104 -304.449734)
					(mid 269.673324 -304.449734)
					(end 270.326104 -304.449734)
				)
			)
		)
	)
	(zone
		(layers "B.Cu" "In7.Cu" "In9.Cu" "In11.Cu" "In13.Cu" "In15.Cu")
		(hatch none 0.5)
		(connect_pads
			(clearance 0)
		)
		(min_thickness 0.25)
		(keepout
			(tracks not_allowed)
			(vias allowed)
			(pads allowed)
			(copperpour not_allowed)
			(footprints allowed)
		)
		(placement
			(enabled no)
			(sheetname "")
		)
		(fill yes
			(thermal_gap 0.5)
			(thermal_bridge_width 0.5)
			(island_removal_mode 0)
		)
		(polygon
			(pts
				(arc
					(start 68.526152 -316.799722)
					(mid 67.873372 -316.799722)
					(end 68.526152 -316.799722)
				)
			)
		)
	)
	(zone
		(layers "B.Cu" "In7.Cu" "In9.Cu" "In11.Cu" "In13.Cu" "In15.Cu")
		(hatch none 0.5)
		(connect_pads
			(clearance 0)
		)
		(min_thickness 0.25)
		(keepout
			(tracks not_allowed)
			(vias allowed)
			(pads allowed)
			(copperpour not_allowed)
			(footprints allowed)
		)
		(placement
			(enabled no)
			(sheetname "")
		)
		(fill yes
			(thermal_gap 0.5)
			(thermal_bridge_width 0.5)
			(island_removal_mode 0)
		)
		(polygon
			(pts
				(arc
					(start 412.076138 -273.099784)
					(mid 411.423358 -273.099784)
					(end 412.076138 -273.099784)
				)
			)
		)
	)
	(zone
		(layers "B.Cu" "In7.Cu" "In9.Cu" "In11.Cu" "In13.Cu" "In15.Cu")
		(hatch none 0.5)
		(connect_pads
			(clearance 0)
		)
		(min_thickness 0.25)
		(keepout
			(tracks not_allowed)
			(vias allowed)
			(pads allowed)
			(copperpour not_allowed)
			(footprints allowed)
		)
		(placement
			(enabled no)
			(sheetname "")
		)
		(fill yes
			(thermal_gap 0.5)
			(thermal_bridge_width 0.5)
			(island_removal_mode 0)
		)
		(polygon
			(pts
				(arc
					(start 168.694354 -109.176312)
					(mid 167.990774 -109.176312)
					(end 168.694354 -109.176312)
				)
			)
		)
	)
	(zone
		(layers "B.Cu" "In7.Cu" "In9.Cu" "In11.Cu" "In13.Cu" "In15.Cu")
		(hatch none 0.5)
		(connect_pads
			(clearance 0)
		)
		(min_thickness 0.25)
		(keepout
			(tracks not_allowed)
			(vias allowed)
			(pads allowed)
			(copperpour not_allowed)
			(footprints allowed)
		)
		(placement
			(enabled no)
			(sheetname "")
		)
		(fill yes
			(thermal_gap 0.5)
			(thermal_bridge_width 0.5)
			(island_removal_mode 0)
		)
		(polygon
			(pts
				(arc
					(start 433.069492 -378.290074)
					(mid 432.310032 -378.290074)
					(end 433.069492 -378.290074)
				)
			)
		)
	)
	(zone
		(layers "B.Cu" "In7.Cu" "In9.Cu" "In11.Cu" "In13.Cu" "In15.Cu")
		(hatch none 0.5)
		(connect_pads
			(clearance 0)
		)
		(min_thickness 0.25)
		(keepout
			(tracks not_allowed)
			(vias allowed)
			(pads allowed)
			(copperpour not_allowed)
			(footprints allowed)
		)
		(placement
			(enabled no)
			(sheetname "")
		)
		(fill yes
			(thermal_gap 0.5)
			(thermal_bridge_width 0.5)
			(island_removal_mode 0)
		)
		(polygon
			(pts
				(arc
					(start 415.875978 -274.049744)
					(mid 415.223198 -274.049744)
					(end 415.875978 -274.049744)
				)
			)
		)
	)
	(zone
		(layers "B.Cu" "In7.Cu" "In9.Cu" "In11.Cu" "In13.Cu" "In15.Cu")
		(hatch none 0.5)
		(connect_pads
			(clearance 0)
		)
		(min_thickness 0.25)
		(keepout
			(tracks not_allowed)
			(vias allowed)
			(pads allowed)
			(copperpour not_allowed)
			(footprints allowed)
		)
		(placement
			(enabled no)
			(sheetname "")
		)
		(fill yes
			(thermal_gap 0.5)
			(thermal_bridge_width 0.5)
			(island_removal_mode 0)
		)
		(polygon
			(pts
				(arc
					(start 301.069502 -408.190192)
					(mid 300.310042 -408.190192)
					(end 301.069502 -408.190192)
				)
			)
		)
	)
	(zone
		(layers "B.Cu" "In7.Cu" "In9.Cu" "In11.Cu" "In13.Cu" "In15.Cu")
		(hatch none 0.5)
		(connect_pads
			(clearance 0)
		)
		(min_thickness 0.25)
		(keepout
			(tracks not_allowed)
			(vias allowed)
			(pads allowed)
			(copperpour not_allowed)
			(footprints allowed)
		)
		(placement
			(enabled no)
			(sheetname "")
		)
		(fill yes
			(thermal_gap 0.5)
			(thermal_bridge_width 0.5)
			(island_removal_mode 0)
		)
		(polygon
			(pts
				(arc
					(start 408.276298 -318.699896)
					(mid 407.623518 -318.699896)
					(end 408.276298 -318.699896)
				)
			)
		)
	)
	(zone
		(layers "B.Cu" "In7.Cu" "In9.Cu" "In11.Cu" "In13.Cu" "In15.Cu")
		(hatch none 0.5)
		(connect_pads
			(clearance 0)
		)
		(min_thickness 0.25)
		(keepout
			(tracks not_allowed)
			(vias allowed)
			(pads allowed)
			(copperpour not_allowed)
			(footprints allowed)
		)
		(placement
			(enabled no)
			(sheetname "")
		)
		(fill yes
			(thermal_gap 0.5)
			(thermal_bridge_width 0.5)
			(island_removal_mode 0)
		)
		(polygon
			(pts
				(arc
					(start 421.575992 -273.099784)
					(mid 420.923212 -273.099784)
					(end 421.575992 -273.099784)
				)
			)
		)
	)
	(zone
		(layers "B.Cu" "In7.Cu" "In9.Cu" "In11.Cu" "In13.Cu" "In15.Cu")
		(hatch none 0.5)
		(connect_pads
			(clearance 0)
		)
		(min_thickness 0.25)
		(keepout
			(tracks not_allowed)
			(vias allowed)
			(pads allowed)
			(copperpour not_allowed)
			(footprints allowed)
		)
		(placement
			(enabled no)
			(sheetname "")
		)
		(fill yes
			(thermal_gap 0.5)
			(thermal_bridge_width 0.5)
			(island_removal_mode 0)
		)
		(polygon
			(pts
				(arc
					(start 76.689712 -400.390106)
					(mid 75.930252 -400.390106)
					(end 76.689712 -400.390106)
				)
			)
		)
	)
	(zone
		(layers "B.Cu" "In7.Cu" "In9.Cu" "In11.Cu" "In13.Cu" "In15.Cu")
		(hatch none 0.5)
		(connect_pads
			(clearance 0)
		)
		(min_thickness 0.25)
		(keepout
			(tracks not_allowed)
			(vias allowed)
			(pads allowed)
			(copperpour not_allowed)
			(footprints allowed)
		)
		(placement
			(enabled no)
			(sheetname "")
		)
		(fill yes
			(thermal_gap 0.5)
			(thermal_bridge_width 0.5)
			(island_removal_mode 0)
		)
		(polygon
			(pts
				(arc
					(start 313.075828 -273.099784)
					(mid 312.423048 -273.099784)
					(end 313.075828 -273.099784)
				)
			)
		)
	)
	(zone
		(layers "B.Cu" "In7.Cu" "In9.Cu" "In11.Cu" "In13.Cu" "In15.Cu")
		(hatch none 0.5)
		(connect_pads
			(clearance 0)
		)
		(min_thickness 0.25)
		(keepout
			(tracks not_allowed)
			(vias allowed)
			(pads allowed)
			(copperpour not_allowed)
			(footprints allowed)
		)
		(placement
			(enabled no)
			(sheetname "")
		)
		(fill yes
			(thermal_gap 0.5)
			(thermal_bridge_width 0.5)
			(island_removal_mode 0)
		)
		(polygon
			(pts
				(arc
					(start 170.376342 -317.749936)
					(mid 169.723562 -317.749936)
					(end 170.376342 -317.749936)
				)
			)
		)
	)
	(zone
		(layers "B.Cu" "In7.Cu" "In9.Cu" "In11.Cu" "In13.Cu" "In15.Cu")
		(hatch none 0.5)
		(connect_pads
			(clearance 0)
		)
		(min_thickness 0.25)
		(keepout
			(tracks not_allowed)
			(vias allowed)
			(pads allowed)
			(copperpour not_allowed)
			(footprints allowed)
		)
		(placement
			(enabled no)
			(sheetname "")
		)
		(fill yes
			(thermal_gap 0.5)
			(thermal_bridge_width 0.5)
			(island_removal_mode 0)
		)
		(polygon
			(pts
				(arc
					(start 189.37605 -273.099784)
					(mid 188.72327 -273.099784)
					(end 189.37605 -273.099784)
				)
			)
		)
	)
	(zone
		(layers "B.Cu" "In7.Cu" "In9.Cu" "In11.Cu" "In13.Cu" "In15.Cu")
		(hatch none 0.5)
		(connect_pads
			(clearance 0)
		)
		(min_thickness 0.25)
		(keepout
			(tracks not_allowed)
			(vias allowed)
			(pads allowed)
			(copperpour not_allowed)
			(footprints allowed)
		)
		(placement
			(enabled no)
			(sheetname "")
		)
		(fill yes
			(thermal_gap 0.5)
			(thermal_bridge_width 0.5)
			(island_removal_mode 0)
		)
		(polygon
			(pts
				(arc
					(start 400.89455 -135.83285)
					(mid 400.19097 -135.83285)
					(end 400.89455 -135.83285)
				)
			)
		)
	)
	(zone
		(layers "B.Cu" "In7.Cu" "In9.Cu" "In11.Cu" "In13.Cu" "In15.Cu")
		(hatch none 0.5)
		(connect_pads
			(clearance 0)
		)
		(min_thickness 0.25)
		(keepout
			(tracks not_allowed)
			(vias allowed)
			(pads allowed)
			(copperpour not_allowed)
			(footprints allowed)
		)
		(placement
			(enabled no)
			(sheetname "")
		)
		(fill yes
			(thermal_gap 0.5)
			(thermal_bridge_width 0.5)
			(island_removal_mode 0)
		)
		(polygon
			(pts
				(arc
					(start 40.026336 -301.599854)
					(mid 39.373556 -301.599854)
					(end 40.026336 -301.599854)
				)
			)
		)
	)
	(zone
		(layers "B.Cu" "In7.Cu" "In9.Cu" "In11.Cu" "In13.Cu" "In15.Cu")
		(hatch none 0.5)
		(connect_pads
			(clearance 0)
		)
		(min_thickness 0.25)
		(keepout
			(tracks not_allowed)
			(vias allowed)
			(pads allowed)
			(copperpour not_allowed)
			(footprints allowed)
		)
		(placement
			(enabled no)
			(sheetname "")
		)
		(fill yes
			(thermal_gap 0.5)
			(thermal_bridge_width 0.5)
			(island_removal_mode 0)
		)
		(polygon
			(pts
				(arc
					(start 413.026352 -316.799722)
					(mid 412.373572 -316.799722)
					(end 413.026352 -316.799722)
				)
			)
		)
	)
	(zone
		(layers "B.Cu" "In7.Cu" "In9.Cu" "In11.Cu" "In13.Cu" "In15.Cu")
		(hatch none 0.5)
		(connect_pads
			(clearance 0)
		)
		(min_thickness 0.25)
		(keepout
			(tracks not_allowed)
			(vias allowed)
			(pads allowed)
			(copperpour not_allowed)
			(footprints allowed)
		)
		(placement
			(enabled no)
			(sheetname "")
		)
		(fill yes
			(thermal_gap 0.5)
			(thermal_bridge_width 0.5)
			(island_removal_mode 0)
		)
		(polygon
			(pts
				(arc
					(start 78.026006 -274.999958)
					(mid 77.373226 -274.999958)
					(end 78.026006 -274.999958)
				)
			)
		)
	)
	(zone
		(layers "B.Cu" "In7.Cu" "In9.Cu" "In11.Cu" "In13.Cu" "In15.Cu")
		(hatch none 0.5)
		(connect_pads
			(clearance 0)
		)
		(min_thickness 0.25)
		(keepout
			(tracks not_allowed)
			(vias allowed)
			(pads allowed)
			(copperpour not_allowed)
			(footprints allowed)
		)
		(placement
			(enabled no)
			(sheetname "")
		)
		(fill yes
			(thermal_gap 0.5)
			(thermal_bridge_width 0.5)
			(island_removal_mode 0)
		)
		(polygon
			(pts
				(arc
					(start 160.289748 -404.290022)
					(mid 159.530288 -404.290022)
					(end 160.289748 -404.290022)
				)
			)
		)
	)
	(zone
		(layers "B.Cu" "In7.Cu" "In9.Cu" "In11.Cu" "In13.Cu" "In15.Cu")
		(hatch none 0.5)
		(connect_pads
			(clearance 0)
		)
		(min_thickness 0.25)
		(keepout
			(tracks not_allowed)
			(vias allowed)
			(pads allowed)
			(copperpour not_allowed)
			(footprints allowed)
		)
		(placement
			(enabled no)
			(sheetname "")
		)
		(fill yes
			(thermal_gap 0.5)
			(thermal_bridge_width 0.5)
			(island_removal_mode 0)
		)
		(polygon
			(pts
				(arc
					(start 314.976256 -281.649932)
					(mid 314.323476 -281.649932)
					(end 314.976256 -281.649932)
				)
			)
		)
	)
	(zone
		(layers "B.Cu" "In7.Cu" "In9.Cu" "In11.Cu" "In13.Cu" "In15.Cu")
		(hatch none 0.5)
		(connect_pads
			(clearance 0)
		)
		(min_thickness 0.25)
		(keepout
			(tracks not_allowed)
			(vias allowed)
			(pads allowed)
			(copperpour not_allowed)
			(footprints allowed)
		)
		(placement
			(enabled no)
			(sheetname "")
		)
		(fill yes
			(thermal_gap 0.5)
			(thermal_bridge_width 0.5)
			(island_removal_mode 0)
		)
		(polygon
			(pts
				(arc
					(start 403.526244 -316.799722)
					(mid 402.873464 -316.799722)
					(end 403.526244 -316.799722)
				)
			)
		)
	)
	(zone
		(layers "B.Cu" "In7.Cu" "In9.Cu" "In11.Cu" "In13.Cu" "In15.Cu")
		(hatch none 0.5)
		(connect_pads
			(clearance 0)
		)
		(min_thickness 0.25)
		(keepout
			(tracks not_allowed)
			(vias allowed)
			(pads allowed)
			(copperpour not_allowed)
			(footprints allowed)
		)
		(placement
			(enabled no)
			(sheetname "")
		)
		(fill yes
			(thermal_gap 0.5)
			(thermal_bridge_width 0.5)
			(island_removal_mode 0)
		)
		(polygon
			(pts
				(arc
					(start 415.7091 -149.823678)
					(mid 415.00552 -149.823678)
					(end 415.7091 -149.823678)
				)
			)
		)
	)
	(zone
		(layers "B.Cu" "In7.Cu" "In9.Cu" "In11.Cu" "In13.Cu" "In15.Cu")
		(hatch none 0.5)
		(connect_pads
			(clearance 0)
		)
		(min_thickness 0.25)
		(keepout
			(tracks not_allowed)
			(vias allowed)
			(pads allowed)
			(copperpour not_allowed)
			(footprints allowed)
		)
		(placement
			(enabled no)
			(sheetname "")
		)
		(fill yes
			(thermal_gap 0.5)
			(thermal_bridge_width 0.5)
			(island_removal_mode 0)
		)
		(polygon
			(pts
				(arc
					(start 305.475894 -273.099784)
					(mid 304.823114 -273.099784)
					(end 305.475894 -273.099784)
				)
			)
		)
	)
	(zone
		(layers "B.Cu" "In7.Cu" "In9.Cu" "In11.Cu" "In13.Cu" "In15.Cu")
		(hatch none 0.5)
		(connect_pads
			(clearance 0)
		)
		(min_thickness 0.25)
		(keepout
			(tracks not_allowed)
			(vias allowed)
			(pads allowed)
			(copperpour not_allowed)
			(footprints allowed)
		)
		(placement
			(enabled no)
			(sheetname "")
		)
		(fill yes
			(thermal_gap 0.5)
			(thermal_bridge_width 0.5)
			(island_removal_mode 0)
		)
		(polygon
			(pts
				(arc
					(start 415.875978 -273.099784)
					(mid 415.223198 -273.099784)
					(end 415.875978 -273.099784)
				)
			)
		)
	)
	(zone
		(layers "B.Cu" "In7.Cu" "In9.Cu" "In11.Cu" "In13.Cu" "In15.Cu")
		(hatch none 0.5)
		(connect_pads
			(clearance 0)
		)
		(min_thickness 0.25)
		(keepout
			(tracks not_allowed)
			(vias allowed)
			(pads allowed)
			(copperpour not_allowed)
			(footprints allowed)
		)
		(placement
			(enabled no)
			(sheetname "")
		)
		(fill yes
			(thermal_gap 0.5)
			(thermal_bridge_width 0.5)
			(island_removal_mode 0)
		)
		(polygon
			(pts
				(arc
					(start 177.026062 -275.949664)
					(mid 176.373282 -275.949664)
					(end 177.026062 -275.949664)
				)
			)
		)
	)
	(zone
		(layers "B.Cu" "In7.Cu" "In9.Cu" "In11.Cu" "In13.Cu" "In15.Cu")
		(hatch none 0.5)
		(connect_pads
			(clearance 0)
		)
		(min_thickness 0.25)
		(keepout
			(tracks not_allowed)
			(vias allowed)
			(pads allowed)
			(copperpour not_allowed)
			(footprints allowed)
		)
		(placement
			(enabled no)
			(sheetname "")
		)
		(fill yes
			(thermal_gap 0.5)
			(thermal_bridge_width 0.5)
			(island_removal_mode 0)
		)
		(polygon
			(pts
				(arc
					(start 415.7091 -150.687278)
					(mid 415.00552 -150.687278)
					(end 415.7091 -150.687278)
				)
			)
		)
	)
	(zone
		(layers "B.Cu" "In7.Cu" "In9.Cu" "In11.Cu" "In13.Cu" "In15.Cu")
		(hatch none 0.5)
		(connect_pads
			(clearance 0)
		)
		(min_thickness 0.25)
		(keepout
			(tracks not_allowed)
			(vias allowed)
			(pads allowed)
			(copperpour not_allowed)
			(footprints allowed)
		)
		(placement
			(enabled no)
			(sheetname "")
		)
		(fill yes
			(thermal_gap 0.5)
			(thermal_bridge_width 0.5)
			(island_removal_mode 0)
		)
		(polygon
			(pts
				(arc
					(start 296.926 -274.999704)
					(mid 296.27322 -274.999704)
					(end 296.926 -274.999704)
				)
			)
		)
	)
	(zone
		(layers "B.Cu" "In7.Cu" "In9.Cu" "In11.Cu" "In13.Cu" "In15.Cu")
		(hatch none 0.5)
		(connect_pads
			(clearance 0)
		)
		(min_thickness 0.25)
		(keepout
			(tracks not_allowed)
			(vias allowed)
			(pads allowed)
			(copperpour not_allowed)
			(footprints allowed)
		)
		(placement
			(enabled no)
			(sheetname "")
		)
		(fill yes
			(thermal_gap 0.5)
			(thermal_bridge_width 0.5)
			(island_removal_mode 0)
		)
		(polygon
			(pts
				(arc
					(start 413.8549 -131.713732)
					(mid 413.15132 -131.713732)
					(end 413.8549 -131.713732)
				)
			)
		)
	)
	(zone
		(layers "B.Cu" "In7.Cu" "In9.Cu" "In11.Cu" "In13.Cu" "In15.Cu")
		(hatch none 0.5)
		(connect_pads
			(clearance 0)
		)
		(min_thickness 0.25)
		(keepout
			(tracks not_allowed)
			(vias allowed)
			(pads allowed)
			(copperpour not_allowed)
			(footprints allowed)
		)
		(placement
			(enabled no)
			(sheetname "")
		)
		(fill yes
			(thermal_gap 0.5)
			(thermal_bridge_width 0.5)
			(island_removal_mode 0)
		)
		(polygon
			(pts
				(arc
					(start 425.376086 -273.099784)
					(mid 424.723306 -273.099784)
					(end 425.376086 -273.099784)
				)
			)
		)
	)
	(zone
		(layers "B.Cu" "In7.Cu" "In9.Cu" "In11.Cu" "In13.Cu" "In15.Cu")
		(hatch none 0.5)
		(connect_pads
			(clearance 0)
		)
		(min_thickness 0.25)
		(keepout
			(tracks not_allowed)
			(vias allowed)
			(pads allowed)
			(copperpour not_allowed)
			(footprints allowed)
		)
		(placement
			(enabled no)
			(sheetname "")
		)
		(fill yes
			(thermal_gap 0.5)
			(thermal_bridge_width 0.5)
			(island_removal_mode 0)
		)
		(polygon
			(pts
				(arc
					(start 80.87614 -282.599892)
					(mid 80.22336 -282.599892)
					(end 80.87614 -282.599892)
				)
			)
		)
	)
	(zone
		(layers "B.Cu" "In7.Cu" "In9.Cu" "In11.Cu" "In13.Cu" "In15.Cu")
		(hatch none 0.5)
		(connect_pads
			(clearance 0)
		)
		(min_thickness 0.25)
		(keepout
			(tracks not_allowed)
			(vias allowed)
			(pads allowed)
			(copperpour not_allowed)
			(footprints allowed)
		)
		(placement
			(enabled no)
			(sheetname "")
		)
		(fill yes
			(thermal_gap 0.5)
			(thermal_bridge_width 0.5)
			(island_removal_mode 0)
		)
		(polygon
			(pts
				(arc
					(start 67.40906 -134.377176)
					(mid 66.70548 -134.377176)
					(end 67.40906 -134.377176)
				)
			)
		)
	)
	(zone
		(layers "B.Cu" "In7.Cu" "In9.Cu" "In11.Cu" "In13.Cu" "In15.Cu")
		(hatch none 0.5)
		(connect_pads
			(clearance 0)
		)
		(min_thickness 0.25)
		(keepout
			(tracks not_allowed)
			(vias allowed)
			(pads allowed)
			(copperpour not_allowed)
			(footprints allowed)
		)
		(placement
			(enabled no)
			(sheetname "")
		)
		(fill yes
			(thermal_gap 0.5)
			(thermal_bridge_width 0.5)
			(island_removal_mode 0)
		)
		(polygon
			(pts
				(arc
					(start 82.776314 -281.649932)
					(mid 82.123534 -281.649932)
					(end 82.776314 -281.649932)
				)
			)
		)
	)
	(zone
		(layers "B.Cu" "In7.Cu" "In9.Cu" "In11.Cu" "In13.Cu" "In15.Cu")
		(hatch none 0.5)
		(connect_pads
			(clearance 0)
		)
		(min_thickness 0.25)
		(keepout
			(tracks not_allowed)
			(vias allowed)
			(pads allowed)
			(copperpour not_allowed)
			(footprints allowed)
		)
		(placement
			(enabled no)
			(sheetname "")
		)
		(fill yes
			(thermal_gap 0.5)
			(thermal_bridge_width 0.5)
			(island_removal_mode 0)
		)
		(polygon
			(pts
				(arc
					(start 174.176436 -317.749936)
					(mid 173.523656 -317.749936)
					(end 174.176436 -317.749936)
				)
			)
		)
	)
	(zone
		(layers "B.Cu" "In7.Cu" "In9.Cu" "In11.Cu" "In13.Cu" "In15.Cu")
		(hatch none 0.5)
		(connect_pads
			(clearance 0)
		)
		(min_thickness 0.25)
		(keepout
			(tracks not_allowed)
			(vias allowed)
			(pads allowed)
			(copperpour not_allowed)
			(footprints allowed)
		)
		(placement
			(enabled no)
			(sheetname "")
		)
		(fill yes
			(thermal_gap 0.5)
			(thermal_bridge_width 0.5)
			(island_removal_mode 0)
		)
		(polygon
			(pts
				(arc
					(start 287.86963 -383.490216)
					(mid 287.11017 -383.490216)
					(end 287.86963 -383.490216)
				)
			)
		)
	)
	(zone
		(layers "B.Cu" "In7.Cu" "In9.Cu" "In11.Cu" "In13.Cu" "In15.Cu")
		(hatch none 0.5)
		(connect_pads
			(clearance 0)
		)
		(min_thickness 0.25)
		(keepout
			(tracks not_allowed)
			(vias allowed)
			(pads allowed)
			(copperpour not_allowed)
			(footprints allowed)
		)
		(placement
			(enabled no)
			(sheetname "")
		)
		(fill yes
			(thermal_gap 0.5)
			(thermal_bridge_width 0.5)
			(island_removal_mode 0)
		)
		(polygon
			(pts
				(arc
					(start 257.193288 7.652004)
					(mid 256.489708 7.652004)
					(end 257.193288 7.652004)
				)
			)
		)
	)
	(zone
		(layers "B.Cu" "In7.Cu" "In9.Cu" "In11.Cu" "In13.Cu" "In15.Cu")
		(hatch none 0.5)
		(connect_pads
			(clearance 0)
		)
		(min_thickness 0.25)
		(keepout
			(tracks not_allowed)
			(vias allowed)
			(pads allowed)
			(copperpour not_allowed)
			(footprints allowed)
		)
		(placement
			(enabled no)
			(sheetname "")
		)
		(fill yes
			(thermal_gap 0.5)
			(thermal_bridge_width 0.5)
			(island_removal_mode 0)
		)
		(polygon
			(pts
				(arc
					(start 431.076354 -285.449772)
					(mid 430.423574 -285.449772)
					(end 431.076354 -285.449772)
				)
			)
		)
	)
	(zone
		(layers "B.Cu" "In7.Cu" "In9.Cu" "In11.Cu" "In13.Cu" "In15.Cu")
		(hatch none 0.5)
		(connect_pads
			(clearance 0)
		)
		(min_thickness 0.25)
		(keepout
			(tracks not_allowed)
			(vias allowed)
			(pads allowed)
			(copperpour not_allowed)
			(footprints allowed)
		)
		(placement
			(enabled no)
			(sheetname "")
		)
		(fill yes
			(thermal_gap 0.5)
			(thermal_bridge_width 0.5)
			(island_removal_mode 0)
		)
		(polygon
			(pts
				(arc
					(start 240.631218 -225.231198)
					(mid 239.927638 -225.231198)
					(end 240.631218 -225.231198)
				)
			)
		)
	)
	(zone
		(layers "B.Cu" "In7.Cu" "In9.Cu" "In11.Cu" "In13.Cu" "In15.Cu")
		(hatch none 0.5)
		(connect_pads
			(clearance 0)
		)
		(min_thickness 0.25)
		(keepout
			(tracks not_allowed)
			(vias allowed)
			(pads allowed)
			(copperpour not_allowed)
			(footprints allowed)
		)
		(placement
			(enabled no)
			(sheetname "")
		)
		(fill yes
			(thermal_gap 0.5)
			(thermal_bridge_width 0.5)
			(island_removal_mode 0)
		)
		(polygon
			(pts
				(arc
					(start 183.508904 -142.62354)
					(mid 182.805324 -142.62354)
					(end 183.508904 -142.62354)
				)
			)
		)
	)
	(zone
		(layers "B.Cu" "In7.Cu" "In9.Cu" "In11.Cu" "In13.Cu" "In15.Cu")
		(hatch none 0.5)
		(connect_pads
			(clearance 0)
		)
		(min_thickness 0.25)
		(keepout
			(tracks not_allowed)
			(vias allowed)
			(pads allowed)
			(copperpour not_allowed)
			(footprints allowed)
		)
		(placement
			(enabled no)
			(sheetname "")
		)
		(fill yes
			(thermal_gap 0.5)
			(thermal_bridge_width 0.5)
			(island_removal_mode 0)
		)
		(polygon
			(pts
				(arc
					(start 428.22622 -305.399948)
					(mid 427.57344 -305.399948)
					(end 428.22622 -305.399948)
				)
			)
		)
	)
	(zone
		(layers "B.Cu" "In7.Cu" "In9.Cu" "In11.Cu" "In13.Cu" "In15.Cu")
		(hatch none 0.5)
		(connect_pads
			(clearance 0)
		)
		(min_thickness 0.25)
		(keepout
			(tracks not_allowed)
			(vias allowed)
			(pads allowed)
			(copperpour not_allowed)
			(footprints allowed)
		)
		(placement
			(enabled no)
			(sheetname "")
		)
		(fill yes
			(thermal_gap 0.5)
			(thermal_bridge_width 0.5)
			(island_removal_mode 0)
		)
		(polygon
			(pts
				(arc
					(start 336.269838 -370.489988)
					(mid 335.510378 -370.489988)
					(end 336.269838 -370.489988)
				)
			)
		)
	)
	(zone
		(layers "B.Cu" "In7.Cu" "In9.Cu" "In11.Cu" "In13.Cu" "In15.Cu")
		(hatch none 0.5)
		(connect_pads
			(clearance 0)
		)
		(min_thickness 0.25)
		(keepout
			(tracks not_allowed)
			(vias allowed)
			(pads allowed)
			(copperpour not_allowed)
			(footprints allowed)
		)
		(placement
			(enabled no)
			(sheetname "")
		)
		(fill yes
			(thermal_gap 0.5)
			(thermal_bridge_width 0.5)
			(island_removal_mode 0)
		)
		(polygon
			(pts
				(arc
					(start 181.77637 -318.699896)
					(mid 181.12359 -318.699896)
					(end 181.77637 -318.699896)
				)
			)
		)
	)
	(zone
		(layers "B.Cu" "In7.Cu" "In9.Cu" "In11.Cu" "In13.Cu" "In15.Cu")
		(hatch none 0.5)
		(connect_pads
			(clearance 0)
		)
		(min_thickness 0.25)
		(keepout
			(tracks not_allowed)
			(vias allowed)
			(pads allowed)
			(copperpour not_allowed)
			(footprints allowed)
		)
		(placement
			(enabled no)
			(sheetname "")
		)
		(fill yes
			(thermal_gap 0.5)
			(thermal_bridge_width 0.5)
			(island_removal_mode 0)
		)
		(polygon
			(pts
				(arc
					(start 40.976296 -317.749936)
					(mid 40.323516 -317.749936)
					(end 40.976296 -317.749936)
				)
			)
		)
	)
	(zone
		(layers "B.Cu" "In7.Cu" "In9.Cu" "In11.Cu" "In13.Cu" "In15.Cu")
		(hatch none 0.5)
		(connect_pads
			(clearance 0)
		)
		(min_thickness 0.25)
		(keepout
			(tracks not_allowed)
			(vias allowed)
			(pads allowed)
			(copperpour not_allowed)
			(footprints allowed)
		)
		(placement
			(enabled no)
			(sheetname "")
		)
		(fill yes
			(thermal_gap 0.5)
			(thermal_bridge_width 0.5)
			(island_removal_mode 0)
		)
		(polygon
			(pts
				(arc
					(start 298.826174 -316.799722)
					(mid 298.173394 -316.799722)
					(end 298.826174 -316.799722)
				)
			)
		)
	)
	(zone
		(layers "B.Cu" "In7.Cu" "In9.Cu" "In11.Cu" "In13.Cu" "In15.Cu")
		(hatch none 0.5)
		(connect_pads
			(clearance 0)
		)
		(min_thickness 0.25)
		(keepout
			(tracks not_allowed)
			(vias allowed)
			(pads allowed)
			(copperpour not_allowed)
			(footprints allowed)
		)
		(placement
			(enabled no)
			(sheetname "")
		)
		(fill yes
			(thermal_gap 0.5)
			(thermal_bridge_width 0.5)
			(island_removal_mode 0)
		)
		(polygon
			(pts
				(arc
					(start 188.42609 -274.999704)
					(mid 187.77331 -274.999704)
					(end 188.42609 -274.999704)
				)
			)
		)
	)
	(zone
		(layers "B.Cu" "In7.Cu" "In9.Cu" "In11.Cu" "In13.Cu" "In15.Cu")
		(hatch none 0.5)
		(connect_pads
			(clearance 0)
		)
		(min_thickness 0.25)
		(keepout
			(tracks not_allowed)
			(vias allowed)
			(pads allowed)
			(copperpour not_allowed)
			(footprints allowed)
		)
		(placement
			(enabled no)
			(sheetname "")
		)
		(fill yes
			(thermal_gap 0.5)
			(thermal_bridge_width 0.5)
			(island_removal_mode 0)
		)
		(polygon
			(pts
				(arc
					(start 120.689878 -397.790162)
					(mid 119.930418 -397.790162)
					(end 120.689878 -397.790162)
				)
			)
		)
	)
	(zone
		(layers "B.Cu" "In7.Cu" "In9.Cu" "In11.Cu" "In13.Cu" "In15.Cu")
		(hatch none 0.5)
		(connect_pads
			(clearance 0)
		)
		(min_thickness 0.25)
		(keepout
			(tracks not_allowed)
			(vias allowed)
			(pads allowed)
			(copperpour not_allowed)
			(footprints allowed)
		)
		(placement
			(enabled no)
			(sheetname "")
		)
		(fill yes
			(thermal_gap 0.5)
			(thermal_bridge_width 0.5)
			(island_removal_mode 0)
		)
		(polygon
			(pts
				(arc
					(start 168.694354 -135.83285)
					(mid 167.990774 -135.83285)
					(end 168.694354 -135.83285)
				)
			)
		)
	)
	(zone
		(layers "B.Cu" "In7.Cu" "In9.Cu" "In11.Cu" "In13.Cu" "In15.Cu")
		(hatch none 0.5)
		(connect_pads
			(clearance 0)
		)
		(min_thickness 0.25)
		(keepout
			(tracks not_allowed)
			(vias allowed)
			(pads allowed)
			(copperpour not_allowed)
			(footprints allowed)
		)
		(placement
			(enabled no)
			(sheetname "")
		)
		(fill yes
			(thermal_gap 0.5)
			(thermal_bridge_width 0.5)
			(island_removal_mode 0)
		)
		(polygon
			(pts
				(arc
					(start 382.469644 -375.490232)
					(mid 381.710184 -375.490232)
					(end 382.469644 -375.490232)
				)
			)
		)
	)
	(zone
		(layers "B.Cu" "In7.Cu" "In9.Cu" "In11.Cu" "In13.Cu" "In15.Cu")
		(hatch none 0.5)
		(connect_pads
			(clearance 0)
		)
		(min_thickness 0.25)
		(keepout
			(tracks not_allowed)
			(vias allowed)
			(pads allowed)
			(copperpour not_allowed)
			(footprints allowed)
		)
		(placement
			(enabled no)
			(sheetname "")
		)
		(fill yes
			(thermal_gap 0.5)
			(thermal_bridge_width 0.5)
			(island_removal_mode 0)
		)
		(polygon
			(pts
				(arc
					(start 424.42638 -316.799722)
					(mid 423.7736 -316.799722)
					(end 424.42638 -316.799722)
				)
			)
		)
	)
	(zone
		(layers "B.Cu" "In7.Cu" "In9.Cu" "In11.Cu" "In13.Cu" "In15.Cu")
		(hatch none 0.5)
		(connect_pads
			(clearance 0)
		)
		(min_thickness 0.25)
		(keepout
			(tracks not_allowed)
			(vias allowed)
			(pads allowed)
			(copperpour not_allowed)
			(footprints allowed)
		)
		(placement
			(enabled no)
			(sheetname "")
		)
		(fill yes
			(thermal_gap 0.5)
			(thermal_bridge_width 0.5)
			(island_removal_mode 0)
		)
		(polygon
			(pts
				(arc
					(start 65.55486 -136.177274)
					(mid 64.85128 -136.177274)
					(end 65.55486 -136.177274)
				)
			)
		)
	)
	(zone
		(layers "B.Cu" "In7.Cu" "In9.Cu" "In11.Cu" "In13.Cu" "In15.Cu")
		(hatch none 0.5)
		(connect_pads
			(clearance 0)
		)
		(min_thickness 0.25)
		(keepout
			(tracks not_allowed)
			(vias allowed)
			(pads allowed)
			(copperpour not_allowed)
			(footprints allowed)
		)
		(placement
			(enabled no)
			(sheetname "")
		)
		(fill yes
			(thermal_gap 0.5)
			(thermal_bridge_width 0.5)
			(island_removal_mode 0)
		)
		(polygon
			(pts
				(arc
					(start 76.126086 -275.949664)
					(mid 75.473306 -275.949664)
					(end 76.126086 -275.949664)
				)
			)
		)
	)
	(zone
		(layers "B.Cu" "In7.Cu" "In9.Cu" "In11.Cu" "In13.Cu" "In15.Cu")
		(hatch none 0.5)
		(connect_pads
			(clearance 0)
		)
		(min_thickness 0.25)
		(keepout
			(tracks not_allowed)
			(vias allowed)
			(pads allowed)
			(copperpour not_allowed)
			(footprints allowed)
		)
		(placement
			(enabled no)
			(sheetname "")
		)
		(fill yes
			(thermal_gap 0.5)
			(thermal_bridge_width 0.5)
			(island_removal_mode 0)
		)
		(polygon
			(pts
				(arc
					(start 162.489642 -380.69012)
					(mid 161.730182 -380.69012)
					(end 162.489642 -380.69012)
				)
			)
		)
	)
	(zone
		(layers "B.Cu" "In7.Cu" "In9.Cu" "In11.Cu" "In13.Cu" "In15.Cu")
		(hatch none 0.5)
		(connect_pads
			(clearance 0)
		)
		(min_thickness 0.25)
		(keepout
			(tracks not_allowed)
			(vias allowed)
			(pads allowed)
			(copperpour not_allowed)
			(footprints allowed)
		)
		(placement
			(enabled no)
			(sheetname "")
		)
		(fill yes
			(thermal_gap 0.5)
			(thermal_bridge_width 0.5)
			(island_removal_mode 0)
		)
		(polygon
			(pts
				(arc
					(start 435.26964 -379.390148)
					(mid 434.51018 -379.390148)
					(end 435.26964 -379.390148)
				)
			)
		)
	)
	(zone
		(layers "B.Cu" "In7.Cu" "In9.Cu" "In11.Cu" "In13.Cu" "In15.Cu")
		(hatch none 0.5)
		(connect_pads
			(clearance 0)
		)
		(min_thickness 0.25)
		(keepout
			(tracks not_allowed)
			(vias allowed)
			(pads allowed)
			(copperpour not_allowed)
			(footprints allowed)
		)
		(placement
			(enabled no)
			(sheetname "")
		)
		(fill yes
			(thermal_gap 0.5)
			(thermal_bridge_width 0.5)
			(island_removal_mode 0)
		)
		(polygon
			(pts
				(arc
					(start 81.826354 -285.449772)
					(mid 81.173574 -285.449772)
					(end 81.826354 -285.449772)
				)
			)
		)
	)
	(zone
		(layers "B.Cu" "In7.Cu" "In9.Cu" "In11.Cu" "In13.Cu" "In15.Cu")
		(hatch none 0.5)
		(connect_pads
			(clearance 0)
		)
		(min_thickness 0.25)
		(keepout
			(tracks not_allowed)
			(vias allowed)
			(pads allowed)
			(copperpour not_allowed)
			(footprints allowed)
		)
		(placement
			(enabled no)
			(sheetname "")
		)
		(fill yes
			(thermal_gap 0.5)
			(thermal_bridge_width 0.5)
			(island_removal_mode 0)
		)
		(polygon
			(pts
				(arc
					(start 129.489708 -396.49019)
					(mid 128.730248 -396.49019)
					(end 129.489708 -396.49019)
				)
			)
		)
	)
	(zone
		(layers "B.Cu" "In7.Cu" "In9.Cu" "In11.Cu" "In13.Cu" "In15.Cu")
		(hatch none 0.5)
		(connect_pads
			(clearance 0)
		)
		(min_thickness 0.25)
		(keepout
			(tracks not_allowed)
			(vias allowed)
			(pads allowed)
			(copperpour not_allowed)
			(footprints allowed)
		)
		(placement
			(enabled no)
			(sheetname "")
		)
		(fill yes
			(thermal_gap 0.5)
			(thermal_bridge_width 0.5)
			(island_removal_mode 0)
		)
		(polygon
			(pts
				(arc
					(start 424.269662 -405.589994)
					(mid 423.510202 -405.589994)
					(end 424.269662 -405.589994)
				)
			)
		)
	)
	(zone
		(layers "B.Cu" "In7.Cu" "In9.Cu" "In11.Cu" "In13.Cu" "In15.Cu")
		(hatch none 0.5)
		(connect_pads
			(clearance 0)
		)
		(min_thickness 0.25)
		(keepout
			(tracks not_allowed)
			(vias allowed)
			(pads allowed)
			(copperpour not_allowed)
			(footprints allowed)
		)
		(placement
			(enabled no)
			(sheetname "")
		)
		(fill yes
			(thermal_gap 0.5)
			(thermal_bridge_width 0.5)
			(island_removal_mode 0)
		)
		(polygon
			(pts
				(arc
					(start 274.973288 18.467324)
					(mid 274.269708 18.467324)
					(end 274.973288 18.467324)
				)
			)
		)
	)
	(zone
		(layers "B.Cu" "In7.Cu" "In9.Cu" "In11.Cu" "In13.Cu" "In15.Cu")
		(hatch none 0.5)
		(connect_pads
			(clearance 0)
		)
		(min_thickness 0.25)
		(keepout
			(tracks not_allowed)
			(vias allowed)
			(pads allowed)
			(copperpour not_allowed)
			(footprints allowed)
		)
		(placement
			(enabled no)
			(sheetname "")
		)
		(fill yes
			(thermal_gap 0.5)
			(thermal_bridge_width 0.5)
			(island_removal_mode 0)
		)
		(polygon
			(pts
				(arc
					(start 164.68979 -378.290074)
					(mid 163.93033 -378.290074)
					(end 164.68979 -378.290074)
				)
			)
		)
	)
	(zone
		(layers "B.Cu" "In7.Cu" "In9.Cu" "In11.Cu" "In13.Cu" "In15.Cu")
		(hatch none 0.5)
		(connect_pads
			(clearance 0)
		)
		(min_thickness 0.25)
		(keepout
			(tracks not_allowed)
			(vias allowed)
			(pads allowed)
			(copperpour not_allowed)
			(footprints allowed)
		)
		(placement
			(enabled no)
			(sheetname "")
		)
		(fill yes
			(thermal_gap 0.5)
			(thermal_bridge_width 0.5)
			(island_removal_mode 0)
		)
		(polygon
			(pts
				(arc
					(start 298.82592 -274.999958)
					(mid 298.17314 -274.999958)
					(end 298.82592 -274.999958)
				)
			)
		)
	)
	(zone
		(layers "B.Cu" "In7.Cu" "In9.Cu" "In11.Cu" "In13.Cu" "In15.Cu")
		(hatch none 0.5)
		(connect_pads
			(clearance 0)
		)
		(min_thickness 0.25)
		(keepout
			(tracks not_allowed)
			(vias allowed)
			(pads allowed)
			(copperpour not_allowed)
			(footprints allowed)
		)
		(placement
			(enabled no)
			(sheetname "")
		)
		(fill yes
			(thermal_gap 0.5)
			(thermal_bridge_width 0.5)
			(island_removal_mode 0)
		)
		(polygon
			(pts
				(arc
					(start 270.326104 -306.349908)
					(mid 269.673324 -306.349908)
					(end 270.326104 -306.349908)
				)
			)
		)
	)
	(zone
		(layers "B.Cu" "In7.Cu" "In9.Cu" "In11.Cu" "In13.Cu" "In15.Cu")
		(hatch none 0.5)
		(connect_pads
			(clearance 0)
		)
		(min_thickness 0.25)
		(keepout
			(tracks not_allowed)
			(vias allowed)
			(pads allowed)
			(copperpour not_allowed)
			(footprints allowed)
		)
		(placement
			(enabled no)
			(sheetname "")
		)
		(fill yes
			(thermal_gap 0.5)
			(thermal_bridge_width 0.5)
			(island_removal_mode 0)
		)
		(polygon
			(pts
				(arc
					(start 78.889606 -402.790152)
					(mid 78.130146 -402.790152)
					(end 78.889606 -402.790152)
				)
			)
		)
	)
	(zone
		(layers "B.Cu" "In7.Cu" "In9.Cu" "In11.Cu" "In13.Cu" "In15.Cu")
		(hatch none 0.5)
		(connect_pads
			(clearance 0)
		)
		(min_thickness 0.25)
		(keepout
			(tracks not_allowed)
			(vias allowed)
			(pads allowed)
			(copperpour not_allowed)
			(footprints allowed)
		)
		(placement
			(enabled no)
			(sheetname "")
		)
		(fill yes
			(thermal_gap 0.5)
			(thermal_bridge_width 0.5)
			(island_removal_mode 0)
		)
		(polygon
			(pts
				(arc
					(start 173.48962 -379.590046)
					(mid 172.73016 -379.590046)
					(end 173.48962 -379.590046)
				)
			)
		)
	)
	(zone
		(layers "B.Cu" "In7.Cu" "In9.Cu" "In11.Cu" "In13.Cu" "In15.Cu")
		(hatch none 0.5)
		(connect_pads
			(clearance 0)
		)
		(min_thickness 0.25)
		(keepout
			(tracks not_allowed)
			(vias allowed)
			(pads allowed)
			(copperpour not_allowed)
			(footprints allowed)
		)
		(placement
			(enabled no)
			(sheetname "")
		)
		(fill yes
			(thermal_gap 0.5)
			(thermal_bridge_width 0.5)
			(island_removal_mode 0)
		)
		(polygon
			(pts
				(arc
					(start 284.794452 -101.112828)
					(mid 284.090872 -101.112828)
					(end 284.794452 -101.112828)
				)
			)
		)
	)
	(zone
		(layers "B.Cu" "In7.Cu" "In9.Cu" "In11.Cu" "In13.Cu" "In15.Cu")
		(hatch none 0.5)
		(connect_pads
			(clearance 0)
		)
		(min_thickness 0.25)
		(keepout
			(tracks not_allowed)
			(vias allowed)
			(pads allowed)
			(copperpour not_allowed)
			(footprints allowed)
		)
		(placement
			(enabled no)
			(sheetname "")
		)
		(fill yes
			(thermal_gap 0.5)
			(thermal_bridge_width 0.5)
			(island_removal_mode 0)
		)
		(polygon
			(pts
				(arc
					(start 71.376032 -273.099784)
					(mid 70.723252 -273.099784)
					(end 71.376032 -273.099784)
				)
			)
		)
	)
	(zone
		(layers "B.Cu" "In7.Cu" "In9.Cu" "In11.Cu" "In13.Cu" "In15.Cu")
		(hatch none 0.5)
		(connect_pads
			(clearance 0)
		)
		(min_thickness 0.25)
		(keepout
			(tracks not_allowed)
			(vias allowed)
			(pads allowed)
			(copperpour not_allowed)
			(footprints allowed)
		)
		(placement
			(enabled no)
			(sheetname "")
		)
		(fill yes
			(thermal_gap 0.5)
			(thermal_bridge_width 0.5)
			(island_removal_mode 0)
		)
		(polygon
			(pts
				(arc
					(start 197.926452 -285.449772)
					(mid 197.273672 -285.449772)
					(end 197.926452 -285.449772)
				)
			)
		)
	)
	(zone
		(layers "B.Cu" "In7.Cu" "In9.Cu" "In11.Cu" "In13.Cu" "In15.Cu")
		(hatch none 0.5)
		(connect_pads
			(clearance 0)
		)
		(min_thickness 0.25)
		(keepout
			(tracks not_allowed)
			(vias allowed)
			(pads allowed)
			(copperpour not_allowed)
			(footprints allowed)
		)
		(placement
			(enabled no)
			(sheetname "")
		)
		(fill yes
			(thermal_gap 0.5)
			(thermal_bridge_width 0.5)
			(island_removal_mode 0)
		)
		(polygon
			(pts
				(arc
					(start 299.609002 -122.30354)
					(mid 298.905422 -122.30354)
					(end 299.609002 -122.30354)
				)
			)
		)
	)
	(zone
		(layers "B.Cu" "In7.Cu" "In9.Cu" "In11.Cu" "In13.Cu" "In15.Cu")
		(hatch none 0.5)
		(connect_pads
			(clearance 0)
		)
		(min_thickness 0.25)
		(keepout
			(tracks not_allowed)
			(vias allowed)
			(pads allowed)
			(copperpour not_allowed)
			(footprints allowed)
		)
		(placement
			(enabled no)
			(sheetname "")
		)
		(fill yes
			(thermal_gap 0.5)
			(thermal_bridge_width 0.5)
			(island_removal_mode 0)
		)
		(polygon
			(pts
				(arc
					(start 411.126178 -315.849762)
					(mid 410.473398 -315.849762)
					(end 411.126178 -315.849762)
				)
			)
		)
	)
	(zone
		(layers "B.Cu" "In7.Cu" "In9.Cu" "In11.Cu" "In13.Cu" "In15.Cu")
		(hatch none 0.5)
		(connect_pads
			(clearance 0)
		)
		(min_thickness 0.25)
		(keepout
			(tracks not_allowed)
			(vias allowed)
			(pads allowed)
			(copperpour not_allowed)
			(footprints allowed)
		)
		(placement
			(enabled no)
			(sheetname "")
		)
		(fill yes
			(thermal_gap 0.5)
			(thermal_bridge_width 0.5)
			(island_removal_mode 0)
		)
		(polygon
			(pts
				(arc
					(start 429.17618 -307.299868)
					(mid 428.5234 -307.299868)
					(end 429.17618 -307.299868)
				)
			)
		)
	)
	(zone
		(layers "B.Cu" "In7.Cu" "In9.Cu" "In11.Cu" "In13.Cu" "In15.Cu")
		(hatch none 0.5)
		(connect_pads
			(clearance 0)
		)
		(min_thickness 0.25)
		(keepout
			(tracks not_allowed)
			(vias allowed)
			(pads allowed)
			(copperpour not_allowed)
			(footprints allowed)
		)
		(placement
			(enabled no)
			(sheetname "")
		)
		(fill yes
			(thermal_gap 0.5)
			(thermal_bridge_width 0.5)
			(island_removal_mode 0)
		)
		(polygon
			(pts
				(arc
					(start 73.275952 -274.049744)
					(mid 72.623172 -274.049744)
					(end 73.275952 -274.049744)
				)
			)
		)
	)
	(zone
		(layers "B.Cu" "In7.Cu" "In9.Cu" "In11.Cu" "In13.Cu" "In15.Cu")
		(hatch none 0.5)
		(connect_pads
			(clearance 0)
		)
		(min_thickness 0.25)
		(keepout
			(tracks not_allowed)
			(vias allowed)
			(pads allowed)
			(copperpour not_allowed)
			(footprints allowed)
		)
		(placement
			(enabled no)
			(sheetname "")
		)
		(fill yes
			(thermal_gap 0.5)
			(thermal_bridge_width 0.5)
			(island_removal_mode 0)
		)
		(polygon
			(pts
				(arc
					(start 37.089842 -409.490164)
					(mid 36.330382 -409.490164)
					(end 37.089842 -409.490164)
				)
			)
		)
	)
	(zone
		(layers "B.Cu" "In7.Cu" "In9.Cu" "In11.Cu" "In13.Cu" "In15.Cu")
		(hatch none 0.5)
		(connect_pads
			(clearance 0)
		)
		(min_thickness 0.25)
		(keepout
			(tracks not_allowed)
			(vias allowed)
			(pads allowed)
			(copperpour not_allowed)
			(footprints allowed)
		)
		(placement
			(enabled no)
			(sheetname "")
		)
		(fill yes
			(thermal_gap 0.5)
			(thermal_bridge_width 0.5)
			(island_removal_mode 0)
		)
		(polygon
			(pts
				(arc
					(start 281.726132 -315.849762)
					(mid 281.073352 -315.849762)
					(end 281.726132 -315.849762)
				)
			)
		)
	)
	(zone
		(layers "B.Cu" "In7.Cu" "In9.Cu" "In11.Cu" "In13.Cu" "In15.Cu")
		(hatch none 0.5)
		(connect_pads
			(clearance 0)
		)
		(min_thickness 0.25)
		(keepout
			(tracks not_allowed)
			(vias allowed)
			(pads allowed)
			(copperpour not_allowed)
			(footprints allowed)
		)
		(placement
			(enabled no)
			(sheetname "")
		)
		(fill yes
			(thermal_gap 0.5)
			(thermal_bridge_width 0.5)
			(island_removal_mode 0)
		)
		(polygon
			(pts
				(arc
					(start 419.86962 -378.290074)
					(mid 419.11016 -378.290074)
					(end 419.86962 -378.290074)
				)
			)
		)
	)
	(zone
		(layers "B.Cu" "In7.Cu" "In9.Cu" "In11.Cu" "In13.Cu" "In15.Cu")
		(hatch none 0.5)
		(connect_pads
			(clearance 0)
		)
		(min_thickness 0.25)
		(keepout
			(tracks not_allowed)
			(vias allowed)
			(pads allowed)
			(copperpour not_allowed)
			(footprints allowed)
		)
		(placement
			(enabled no)
			(sheetname "")
		)
		(fill yes
			(thermal_gap 0.5)
			(thermal_bridge_width 0.5)
			(island_removal_mode 0)
		)
		(polygon
			(pts
				(arc
					(start 70.426326 -315.849762)
					(mid 69.773546 -315.849762)
					(end 70.426326 -315.849762)
				)
			)
		)
	)
	(zone
		(layers "B.Cu" "In7.Cu" "In9.Cu" "In11.Cu" "In13.Cu" "In15.Cu")
		(hatch none 0.5)
		(connect_pads
			(clearance 0)
		)
		(min_thickness 0.25)
		(keepout
			(tracks not_allowed)
			(vias allowed)
			(pads allowed)
			(copperpour not_allowed)
			(footprints allowed)
		)
		(placement
			(enabled no)
			(sheetname "")
		)
		(fill yes
			(thermal_gap 0.5)
			(thermal_bridge_width 0.5)
			(island_removal_mode 0)
		)
		(polygon
			(pts
				(arc
					(start 39.076376 -317.749936)
					(mid 38.423596 -317.749936)
					(end 39.076376 -317.749936)
				)
			)
		)
	)
	(zone
		(layers "B.Cu" "In7.Cu" "In9.Cu" "In11.Cu" "In13.Cu" "In15.Cu")
		(hatch none 0.5)
		(connect_pads
			(clearance 0)
		)
		(min_thickness 0.25)
		(keepout
			(tracks not_allowed)
			(vias allowed)
			(pads allowed)
			(copperpour not_allowed)
			(footprints allowed)
		)
		(placement
			(enabled no)
			(sheetname "")
		)
		(fill yes
			(thermal_gap 0.5)
			(thermal_bridge_width 0.5)
			(island_removal_mode 0)
		)
		(polygon
			(pts
				(arc
					(start 422.069514 -405.390096)
					(mid 421.310054 -405.390096)
					(end 422.069514 -405.390096)
				)
			)
		)
	)
	(zone
		(layers "B.Cu" "In7.Cu" "In9.Cu" "In11.Cu" "In13.Cu" "In15.Cu")
		(hatch none 0.5)
		(connect_pads
			(clearance 0)
		)
		(min_thickness 0.25)
		(keepout
			(tracks not_allowed)
			(vias allowed)
			(pads allowed)
			(copperpour not_allowed)
			(footprints allowed)
		)
		(placement
			(enabled no)
			(sheetname "")
		)
		(fill yes
			(thermal_gap 0.5)
			(thermal_bridge_width 0.5)
			(island_removal_mode 0)
		)
		(polygon
			(pts
				(arc
					(start 402.74875 -103.776272)
					(mid 402.04517 -103.776272)
					(end 402.74875 -103.776272)
				)
			)
		)
	)
	(zone
		(layers "B.Cu" "In7.Cu" "In9.Cu" "In11.Cu" "In13.Cu" "In15.Cu")
		(hatch none 0.5)
		(connect_pads
			(clearance 0)
		)
		(min_thickness 0.25)
		(keepout
			(tracks not_allowed)
			(vias allowed)
			(pads allowed)
			(copperpour not_allowed)
			(footprints allowed)
		)
		(placement
			(enabled no)
			(sheetname "")
		)
		(fill yes
			(thermal_gap 0.5)
			(thermal_bridge_width 0.5)
			(island_removal_mode 0)
		)
		(polygon
			(pts
				(arc
					(start 80.87614 -284.499812)
					(mid 80.22336 -284.499812)
					(end 80.87614 -284.499812)
				)
			)
		)
	)
	(zone
		(layers "B.Cu" "In7.Cu" "In9.Cu" "In11.Cu" "In13.Cu" "In15.Cu")
		(hatch none 0.5)
		(connect_pads
			(clearance 0)
		)
		(min_thickness 0.25)
		(keepout
			(tracks not_allowed)
			(vias allowed)
			(pads allowed)
			(copperpour not_allowed)
			(footprints allowed)
		)
		(placement
			(enabled no)
			(sheetname "")
		)
		(fill yes
			(thermal_gap 0.5)
			(thermal_bridge_width 0.5)
			(island_removal_mode 0)
		)
		(polygon
			(pts
				(arc
					(start 419.676072 -274.049744)
					(mid 419.023292 -274.049744)
					(end 419.676072 -274.049744)
				)
			)
		)
	)
	(zone
		(layers "B.Cu" "In7.Cu" "In9.Cu" "In11.Cu" "In13.Cu" "In15.Cu")
		(hatch none 0.5)
		(connect_pads
			(clearance 0)
		)
		(min_thickness 0.25)
		(keepout
			(tracks not_allowed)
			(vias allowed)
			(pads allowed)
			(copperpour not_allowed)
			(footprints allowed)
		)
		(placement
			(enabled no)
			(sheetname "")
		)
		(fill yes
			(thermal_gap 0.5)
			(thermal_bridge_width 0.5)
			(island_removal_mode 0)
		)
		(polygon
			(pts
				(arc
					(start 37.176202 -308.249828)
					(mid 36.523422 -308.249828)
					(end 37.176202 -308.249828)
				)
			)
		)
	)
	(zone
		(layers "B.Cu" "In7.Cu" "In9.Cu" "In11.Cu" "In13.Cu" "In15.Cu")
		(hatch none 0.5)
		(connect_pads
			(clearance 0)
		)
		(min_thickness 0.25)
		(keepout
			(tracks not_allowed)
			(vias allowed)
			(pads allowed)
			(copperpour not_allowed)
			(footprints allowed)
		)
		(placement
			(enabled no)
			(sheetname "")
		)
		(fill yes
			(thermal_gap 0.5)
			(thermal_bridge_width 0.5)
			(island_removal_mode 0)
		)
		(polygon
			(pts
				(arc
					(start 67.40906 -143.48714)
					(mid 66.70548 -143.48714)
					(end 67.40906 -143.48714)
				)
			)
		)
	)
	(zone
		(layers "B.Cu" "In7.Cu" "In9.Cu" "In11.Cu" "In13.Cu" "In15.Cu")
		(hatch none 0.5)
		(connect_pads
			(clearance 0)
		)
		(min_thickness 0.25)
		(keepout
			(tracks not_allowed)
			(vias allowed)
			(pads allowed)
			(copperpour not_allowed)
			(footprints allowed)
		)
		(placement
			(enabled no)
			(sheetname "")
		)
		(fill yes
			(thermal_gap 0.5)
			(thermal_bridge_width 0.5)
			(island_removal_mode 0)
		)
		(polygon
			(pts
				(arc
					(start 294.469566 -409.290012)
					(mid 293.710106 -409.290012)
					(end 294.469566 -409.290012)
				)
			)
		)
	)
	(zone
		(layers "B.Cu" "In7.Cu" "In9.Cu" "In11.Cu" "In13.Cu" "In15.Cu")
		(hatch none 0.5)
		(connect_pads
			(clearance 0)
		)
		(min_thickness 0.25)
		(keepout
			(tracks not_allowed)
			(vias allowed)
			(pads allowed)
			(copperpour not_allowed)
			(footprints allowed)
		)
		(placement
			(enabled no)
			(sheetname "")
		)
		(fill yes
			(thermal_gap 0.5)
			(thermal_bridge_width 0.5)
			(island_removal_mode 0)
		)
		(polygon
			(pts
				(arc
					(start 391.269728 -376.790204)
					(mid 390.510268 -376.790204)
					(end 391.269728 -376.790204)
				)
			)
		)
	)
	(zone
		(layers "B.Cu" "In7.Cu" "In9.Cu" "In11.Cu" "In13.Cu" "In15.Cu")
		(hatch none 0.5)
		(connect_pads
			(clearance 0)
		)
		(min_thickness 0.25)
		(keepout
			(tracks not_allowed)
			(vias allowed)
			(pads allowed)
			(copperpour not_allowed)
			(footprints allowed)
		)
		(placement
			(enabled no)
			(sheetname "")
		)
		(fill yes
			(thermal_gap 0.5)
			(thermal_bridge_width 0.5)
			(island_removal_mode 0)
		)
		(polygon
			(pts
				(arc
					(start 169.089832 -379.590046)
					(mid 168.330372 -379.590046)
					(end 169.089832 -379.590046)
				)
			)
		)
	)
	(zone
		(layers "B.Cu" "In7.Cu" "In9.Cu" "In11.Cu" "In13.Cu" "In15.Cu")
		(hatch none 0.5)
		(connect_pads
			(clearance 0)
		)
		(min_thickness 0.25)
		(keepout
			(tracks not_allowed)
			(vias allowed)
			(pads allowed)
			(copperpour not_allowed)
			(footprints allowed)
		)
		(placement
			(enabled no)
			(sheetname "")
		)
		(fill yes
			(thermal_gap 0.5)
			(thermal_bridge_width 0.5)
			(island_removal_mode 0)
		)
		(polygon
			(pts
				(arc
					(start 292.269672 -408.190192)
					(mid 291.510212 -408.190192)
					(end 292.269672 -408.190192)
				)
			)
		)
	)
	(zone
		(layers "B.Cu" "In7.Cu" "In9.Cu" "In11.Cu" "In13.Cu" "In15.Cu")
		(hatch none 0.5)
		(connect_pads
			(clearance 0)
		)
		(min_thickness 0.25)
		(keepout
			(tracks not_allowed)
			(vias allowed)
			(pads allowed)
			(copperpour not_allowed)
			(footprints allowed)
		)
		(placement
			(enabled no)
			(sheetname "")
		)
		(fill yes
			(thermal_gap 0.5)
			(thermal_bridge_width 0.5)
			(island_removal_mode 0)
		)
		(polygon
			(pts
				(arc
					(start 177.026062 -274.999704)
					(mid 176.373282 -274.999704)
					(end 177.026062 -274.999704)
				)
			)
		)
	)
	(zone
		(layers "B.Cu" "In7.Cu" "In9.Cu" "In11.Cu" "In13.Cu" "In15.Cu")
		(hatch none 0.5)
		(connect_pads
			(clearance 0)
		)
		(min_thickness 0.25)
		(keepout
			(tracks not_allowed)
			(vias allowed)
			(pads allowed)
			(copperpour not_allowed)
			(footprints allowed)
		)
		(placement
			(enabled no)
			(sheetname "")
		)
		(fill yes
			(thermal_gap 0.5)
			(thermal_bridge_width 0.5)
			(island_removal_mode 0)
		)
		(polygon
			(pts
				(arc
					(start 54.44871 -106.512614)
					(mid 53.74513 -106.512614)
					(end 54.44871 -106.512614)
				)
			)
		)
	)
	(zone
		(layers "B.Cu" "In7.Cu" "In9.Cu" "In11.Cu" "In13.Cu" "In15.Cu")
		(hatch none 0.5)
		(connect_pads
			(clearance 0)
		)
		(min_thickness 0.25)
		(keepout
			(tracks not_allowed)
			(vias allowed)
			(pads allowed)
			(copperpour not_allowed)
			(footprints allowed)
		)
		(placement
			(enabled no)
			(sheetname "")
		)
		(fill yes
			(thermal_gap 0.5)
			(thermal_bridge_width 0.5)
			(island_removal_mode 0)
		)
		(polygon
			(pts
				(arc
					(start 430.126394 -285.449772)
					(mid 429.473614 -285.449772)
					(end 430.126394 -285.449772)
				)
			)
		)
	)
	(zone
		(layers "B.Cu" "In7.Cu" "In9.Cu" "In11.Cu" "In13.Cu" "In15.Cu")
		(hatch none 0.5)
		(connect_pads
			(clearance 0)
		)
		(min_thickness 0.25)
		(keepout
			(tracks not_allowed)
			(vias allowed)
			(pads allowed)
			(copperpour not_allowed)
			(footprints allowed)
		)
		(placement
			(enabled no)
			(sheetname "")
		)
		(fill yes
			(thermal_gap 0.5)
			(thermal_bridge_width 0.5)
			(island_removal_mode 0)
		)
		(polygon
			(pts
				(arc
					(start 414.926018 -274.999958)
					(mid 414.273238 -274.999958)
					(end 414.926018 -274.999958)
				)
			)
		)
	)
	(zone
		(layers "B.Cu" "In7.Cu" "In9.Cu" "In11.Cu" "In13.Cu" "In15.Cu")
		(hatch none 0.5)
		(connect_pads
			(clearance 0)
		)
		(min_thickness 0.25)
		(keepout
			(tracks not_allowed)
			(vias allowed)
			(pads allowed)
			(copperpour not_allowed)
			(footprints allowed)
		)
		(placement
			(enabled no)
			(sheetname "")
		)
		(fill yes
			(thermal_gap 0.5)
			(thermal_bridge_width 0.5)
			(island_removal_mode 0)
		)
		(polygon
			(pts
				(arc
					(start 271.276318 -305.399948)
					(mid 270.623538 -305.399948)
					(end 271.276318 -305.399948)
				)
			)
		)
	)
	(zone
		(layers "B.Cu" "In7.Cu" "In9.Cu" "In11.Cu" "In13.Cu" "In15.Cu")
		(hatch none 0.5)
		(connect_pads
			(clearance 0)
		)
		(min_thickness 0.25)
		(keepout
			(tracks not_allowed)
			(vias allowed)
			(pads allowed)
			(copperpour not_allowed)
			(footprints allowed)
		)
		(placement
			(enabled no)
			(sheetname "")
		)
		(fill yes
			(thermal_gap 0.5)
			(thermal_bridge_width 0.5)
			(island_removal_mode 0)
		)
		(polygon
			(pts
				(arc
					(start 194.126358 -315.849762)
					(mid 193.473578 -315.849762)
					(end 194.126358 -315.849762)
				)
			)
		)
	)
	(zone
		(layers "B.Cu" "In7.Cu" "In9.Cu" "In11.Cu" "In13.Cu" "In15.Cu")
		(hatch none 0.5)
		(connect_pads
			(clearance 0)
		)
		(min_thickness 0.25)
		(keepout
			(tracks not_allowed)
			(vias allowed)
			(pads allowed)
			(copperpour not_allowed)
			(footprints allowed)
		)
		(placement
			(enabled no)
			(sheetname "")
		)
		(fill yes
			(thermal_gap 0.5)
			(thermal_bridge_width 0.5)
			(island_removal_mode 0)
		)
		(polygon
			(pts
				(arc
					(start 294.469566 -383.290064)
					(mid 293.710106 -383.290064)
					(end 294.469566 -383.290064)
				)
			)
		)
	)
	(zone
		(layers "B.Cu" "In7.Cu" "In9.Cu" "In11.Cu" "In13.Cu" "In15.Cu")
		(hatch none 0.5)
		(connect_pads
			(clearance 0)
		)
		(min_thickness 0.25)
		(keepout
			(tracks not_allowed)
			(vias allowed)
			(pads allowed)
			(copperpour not_allowed)
			(footprints allowed)
		)
		(placement
			(enabled no)
			(sheetname "")
		)
		(fill yes
			(thermal_gap 0.5)
			(thermal_bridge_width 0.5)
			(island_removal_mode 0)
		)
		(polygon
			(pts
				(arc
					(start 65.55486 -156.087318)
					(mid 64.85128 -156.087318)
					(end 65.55486 -156.087318)
				)
			)
		)
	)
	(zone
		(layers "B.Cu" "In7.Cu" "In9.Cu" "In11.Cu" "In13.Cu" "In15.Cu")
		(hatch none 0.5)
		(connect_pads
			(clearance 0)
		)
		(min_thickness 0.25)
		(keepout
			(tracks not_allowed)
			(vias allowed)
			(pads allowed)
			(copperpour not_allowed)
			(footprints allowed)
		)
		(placement
			(enabled no)
			(sheetname "")
		)
		(fill yes
			(thermal_gap 0.5)
			(thermal_bridge_width 0.5)
			(island_removal_mode 0)
		)
		(polygon
			(pts
				(arc
					(start 79.92618 -284.499812)
					(mid 79.2734 -284.499812)
					(end 79.92618 -284.499812)
				)
			)
		)
	)
	(zone
		(layers "B.Cu" "In7.Cu" "In9.Cu" "In11.Cu" "In13.Cu" "In15.Cu")
		(hatch none 0.5)
		(connect_pads
			(clearance 0)
		)
		(min_thickness 0.25)
		(keepout
			(tracks not_allowed)
			(vias allowed)
			(pads allowed)
			(copperpour not_allowed)
			(footprints allowed)
		)
		(placement
			(enabled no)
			(sheetname "")
		)
		(fill yes
			(thermal_gap 0.5)
			(thermal_bridge_width 0.5)
			(island_removal_mode 0)
		)
		(polygon
			(pts
				(arc
					(start 424.269662 -379.590046)
					(mid 423.510202 -379.590046)
					(end 424.269662 -379.590046)
				)
			)
		)
	)
	(zone
		(layers "B.Cu" "In7.Cu" "In9.Cu" "In11.Cu" "In13.Cu" "In15.Cu")
		(hatch none 0.5)
		(connect_pads
			(clearance 0)
		)
		(min_thickness 0.25)
		(keepout
			(tracks not_allowed)
			(vias allowed)
			(pads allowed)
			(copperpour not_allowed)
			(footprints allowed)
		)
		(placement
			(enabled no)
			(sheetname "")
		)
		(fill yes
			(thermal_gap 0.5)
			(thermal_bridge_width 0.5)
			(island_removal_mode 0)
		)
		(polygon
			(pts
				(arc
					(start 297.754802 -144.423638)
					(mid 297.051222 -144.423638)
					(end 297.754802 -144.423638)
				)
			)
		)
	)
	(zone
		(layers "B.Cu" "In7.Cu" "In9.Cu" "In11.Cu" "In13.Cu" "In15.Cu")
		(hatch none 0.5)
		(connect_pads
			(clearance 0)
		)
		(min_thickness 0.25)
		(keepout
			(tracks not_allowed)
			(vias allowed)
			(pads allowed)
			(copperpour not_allowed)
			(footprints allowed)
		)
		(placement
			(enabled no)
			(sheetname "")
		)
		(fill yes
			(thermal_gap 0.5)
			(thermal_bridge_width 0.5)
			(island_removal_mode 0)
		)
		(polygon
			(pts
				(arc
					(start 39.076376 -307.299868)
					(mid 38.423596 -307.299868)
					(end 39.076376 -307.299868)
				)
			)
		)
	)
	(zone
		(layers "B.Cu" "In7.Cu" "In9.Cu" "In11.Cu" "In13.Cu" "In15.Cu")
		(hatch none 0.5)
		(connect_pads
			(clearance 0)
		)
		(min_thickness 0.25)
		(keepout
			(tracks not_allowed)
			(vias allowed)
			(pads allowed)
			(copperpour not_allowed)
			(footprints allowed)
		)
		(placement
			(enabled no)
			(sheetname "")
		)
		(fill yes
			(thermal_gap 0.5)
			(thermal_bridge_width 0.5)
			(island_removal_mode 0)
		)
		(polygon
			(pts
				(arc
					(start 294.469566 -410.589984)
					(mid 293.710106 -410.589984)
					(end 294.469566 -410.589984)
				)
			)
		)
	)
	(zone
		(layers "B.Cu" "In7.Cu" "In9.Cu" "In11.Cu" "In13.Cu" "In15.Cu")
		(hatch none 0.5)
		(connect_pads
			(clearance 0)
		)
		(min_thickness 0.25)
		(keepout
			(tracks not_allowed)
			(vias allowed)
			(pads allowed)
			(copperpour not_allowed)
			(footprints allowed)
		)
		(placement
			(enabled no)
			(sheetname "")
		)
		(fill yes
			(thermal_gap 0.5)
			(thermal_bridge_width 0.5)
			(island_removal_mode 0)
		)
		(polygon
			(pts
				(arc
					(start 284.794452 -125.486414)
					(mid 284.090872 -125.486414)
					(end 284.794452 -125.486414)
				)
			)
		)
	)
	(zone
		(layers "B.Cu" "In7.Cu" "In9.Cu" "In11.Cu" "In13.Cu" "In15.Cu")
		(hatch none 0.5)
		(connect_pads
			(clearance 0)
		)
		(min_thickness 0.25)
		(keepout
			(tracks not_allowed)
			(vias allowed)
			(pads allowed)
			(copperpour not_allowed)
			(footprints allowed)
		)
		(placement
			(enabled no)
			(sheetname "")
		)
		(fill yes
			(thermal_gap 0.5)
			(thermal_bridge_width 0.5)
			(island_removal_mode 0)
		)
		(polygon
			(pts
				(arc
					(start 73.276206 -318.699896)
					(mid 72.623426 -318.699896)
					(end 73.276206 -318.699896)
				)
			)
		)
	)
	(zone
		(layers "B.Cu" "In7.Cu" "In9.Cu" "In11.Cu" "In13.Cu" "In15.Cu")
		(hatch none 0.5)
		(connect_pads
			(clearance 0)
		)
		(min_thickness 0.25)
		(keepout
			(tracks not_allowed)
			(vias allowed)
			(pads allowed)
			(copperpour not_allowed)
			(footprints allowed)
		)
		(placement
			(enabled no)
			(sheetname "")
		)
		(fill yes
			(thermal_gap 0.5)
			(thermal_bridge_width 0.5)
			(island_removal_mode 0)
		)
		(polygon
			(pts
				(arc
					(start 295.025826 -275.949918)
					(mid 294.373046 -275.949918)
					(end 295.025826 -275.949918)
				)
			)
		)
	)
	(zone
		(layers "B.Cu" "In7.Cu" "In9.Cu" "In11.Cu" "In13.Cu" "In15.Cu")
		(hatch none 0.5)
		(connect_pads
			(clearance 0)
		)
		(min_thickness 0.25)
		(keepout
			(tracks not_allowed)
			(vias allowed)
			(pads allowed)
			(copperpour not_allowed)
			(footprints allowed)
		)
		(placement
			(enabled no)
			(sheetname "")
		)
		(fill yes
			(thermal_gap 0.5)
			(thermal_bridge_width 0.5)
			(island_removal_mode 0)
		)
		(polygon
			(pts
				(arc
					(start 30.489652 -383.290064)
					(mid 29.730192 -383.290064)
					(end 30.489652 -383.290064)
				)
			)
		)
	)
	(zone
		(layers "B.Cu" "In7.Cu" "In9.Cu" "In11.Cu" "In13.Cu" "In15.Cu")
		(hatch none 0.5)
		(connect_pads
			(clearance 0)
		)
		(min_thickness 0.25)
		(keepout
			(tracks not_allowed)
			(vias allowed)
			(pads allowed)
			(copperpour not_allowed)
			(footprints allowed)
		)
		(placement
			(enabled no)
			(sheetname "")
		)
		(fill yes
			(thermal_gap 0.5)
			(thermal_bridge_width 0.5)
			(island_removal_mode 0)
		)
		(polygon
			(pts
				(arc
					(start 292.269672 -382.18999)
					(mid 291.510212 -382.18999)
					(end 292.269672 -382.18999)
				)
			)
		)
	)
	(zone
		(layers "B.Cu" "In7.Cu" "In9.Cu" "In11.Cu" "In13.Cu" "In15.Cu")
		(hatch none 0.5)
		(connect_pads
			(clearance 0)
		)
		(min_thickness 0.25)
		(keepout
			(tracks not_allowed)
			(vias allowed)
			(pads allowed)
			(copperpour not_allowed)
			(footprints allowed)
		)
		(placement
			(enabled no)
			(sheetname "")
		)
		(fill yes
			(thermal_gap 0.5)
			(thermal_bridge_width 0.5)
			(island_removal_mode 0)
		)
		(polygon
			(pts
				(arc
					(start 284.794452 -121.022872)
					(mid 284.090872 -121.022872)
					(end 284.794452 -121.022872)
				)
			)
		)
	)
	(zone
		(layers "B.Cu" "In7.Cu" "In9.Cu" "In11.Cu" "In13.Cu" "In15.Cu")
		(hatch none 0.5)
		(connect_pads
			(clearance 0)
		)
		(min_thickness 0.25)
		(keepout
			(tracks not_allowed)
			(vias allowed)
			(pads allowed)
			(copperpour not_allowed)
			(footprints allowed)
		)
		(placement
			(enabled no)
			(sheetname "")
		)
		(fill yes
			(thermal_gap 0.5)
			(thermal_bridge_width 0.5)
			(island_removal_mode 0)
		)
		(polygon
			(pts
				(arc
					(start 167.526462 -315.849762)
					(mid 166.873682 -315.849762)
					(end 167.526462 -315.849762)
				)
			)
		)
	)
	(zone
		(layers "B.Cu" "In7.Cu" "In9.Cu" "In11.Cu" "In13.Cu" "In15.Cu")
		(hatch none 0.5)
		(connect_pads
			(clearance 0)
		)
		(min_thickness 0.25)
		(keepout
			(tracks not_allowed)
			(vias allowed)
			(pads allowed)
			(copperpour not_allowed)
			(footprints allowed)
		)
		(placement
			(enabled no)
			(sheetname "")
		)
		(fill yes
			(thermal_gap 0.5)
			(thermal_bridge_width 0.5)
			(island_removal_mode 0)
		)
		(polygon
			(pts
				(arc
					(start 52.59451 -104.71277)
					(mid 51.89093 -104.71277)
					(end 52.59451 -104.71277)
				)
			)
		)
	)
	(zone
		(layers "B.Cu" "In7.Cu" "In9.Cu" "In11.Cu" "In13.Cu" "In15.Cu")
		(hatch none 0.5)
		(connect_pads
			(clearance 0)
		)
		(min_thickness 0.25)
		(keepout
			(tracks not_allowed)
			(vias allowed)
			(pads allowed)
			(copperpour not_allowed)
			(footprints allowed)
		)
		(placement
			(enabled no)
			(sheetname "")
		)
		(fill yes
			(thermal_gap 0.5)
			(thermal_bridge_width 0.5)
			(island_removal_mode 0)
		)
		(polygon
			(pts
				(arc
					(start 281.726132 -316.799722)
					(mid 281.073352 -316.799722)
					(end 281.726132 -316.799722)
				)
			)
		)
	)
	(zone
		(layers "B.Cu" "In7.Cu" "In9.Cu" "In11.Cu" "In13.Cu" "In15.Cu")
		(hatch none 0.5)
		(connect_pads
			(clearance 0)
		)
		(min_thickness 0.25)
		(keepout
			(tracks not_allowed)
			(vias allowed)
			(pads allowed)
			(copperpour not_allowed)
			(footprints allowed)
		)
		(placement
			(enabled no)
			(sheetname "")
		)
		(fill yes
			(thermal_gap 0.5)
			(thermal_bridge_width 0.5)
			(island_removal_mode 0)
		)
		(polygon
			(pts
				(arc
					(start 391.269728 -397.59001)
					(mid 390.510268 -397.59001)
					(end 391.269728 -397.59001)
				)
			)
		)
	)
	(zone
		(layers "B.Cu" "In7.Cu" "In9.Cu" "In11.Cu" "In13.Cu" "In15.Cu")
		(hatch none 0.5)
		(connect_pads
			(clearance 0)
		)
		(min_thickness 0.25)
		(keepout
			(tracks not_allowed)
			(vias allowed)
			(pads allowed)
			(copperpour not_allowed)
			(footprints allowed)
		)
		(placement
			(enabled no)
			(sheetname "")
		)
		(fill yes
			(thermal_gap 0.5)
			(thermal_bridge_width 0.5)
			(island_removal_mode 0)
		)
		(polygon
			(pts
				(arc
					(start 411.125924 -275.949918)
					(mid 410.473144 -275.949918)
					(end 411.125924 -275.949918)
				)
			)
		)
	)
	(zone
		(layers "B.Cu" "In7.Cu" "In9.Cu" "In11.Cu" "In13.Cu" "In15.Cu")
		(hatch none 0.5)
		(connect_pads
			(clearance 0)
		)
		(min_thickness 0.25)
		(keepout
			(tracks not_allowed)
			(vias allowed)
			(pads allowed)
			(copperpour not_allowed)
			(footprints allowed)
		)
		(placement
			(enabled no)
			(sheetname "")
		)
		(fill yes
			(thermal_gap 0.5)
			(thermal_bridge_width 0.5)
			(island_removal_mode 0)
		)
		(polygon
			(pts
				(arc
					(start 52.59451 -135.83285)
					(mid 51.89093 -135.83285)
					(end 52.59451 -135.83285)
				)
			)
		)
	)
	(zone
		(layers "B.Cu" "In7.Cu" "In9.Cu" "In11.Cu" "In13.Cu" "In15.Cu")
		(hatch none 0.5)
		(connect_pads
			(clearance 0)
		)
		(min_thickness 0.25)
		(keepout
			(tracks not_allowed)
			(vias allowed)
			(pads allowed)
			(copperpour not_allowed)
			(footprints allowed)
		)
		(placement
			(enabled no)
			(sheetname "")
		)
		(fill yes
			(thermal_gap 0.5)
			(thermal_bridge_width 0.5)
			(island_removal_mode 0)
		)
		(polygon
			(pts
				(arc
					(start 65.55486 -155.223718)
					(mid 64.85128 -155.223718)
					(end 65.55486 -155.223718)
				)
			)
		)
	)
	(zone
		(layers "B.Cu" "In7.Cu" "In9.Cu" "In11.Cu" "In13.Cu" "In15.Cu")
		(hatch none 0.5)
		(connect_pads
			(clearance 0)
		)
		(min_thickness 0.25)
		(keepout
			(tracks not_allowed)
			(vias allowed)
			(pads allowed)
			(copperpour not_allowed)
			(footprints allowed)
		)
		(placement
			(enabled no)
			(sheetname "")
		)
		(fill yes
			(thermal_gap 0.5)
			(thermal_bridge_width 0.5)
			(island_removal_mode 0)
		)
		(polygon
			(pts
				(arc
					(start 293.125906 -274.999704)
					(mid 292.473126 -274.999704)
					(end 293.125906 -274.999704)
				)
			)
		)
	)
	(zone
		(layers "B.Cu" "In7.Cu" "In9.Cu" "In11.Cu" "In13.Cu" "In15.Cu")
		(hatch none 0.5)
		(connect_pads
			(clearance 0)
		)
		(min_thickness 0.25)
		(keepout
			(tracks not_allowed)
			(vias allowed)
			(pads allowed)
			(copperpour not_allowed)
			(footprints allowed)
		)
		(placement
			(enabled no)
			(sheetname "")
		)
		(fill yes
			(thermal_gap 0.5)
			(thermal_bridge_width 0.5)
			(island_removal_mode 0)
		)
		(polygon
			(pts
				(arc
					(start 72.326246 -316.799722)
					(mid 71.673466 -316.799722)
					(end 72.326246 -316.799722)
				)
			)
		)
	)
	(zone
		(layers "B.Cu" "In7.Cu" "In9.Cu" "In11.Cu" "In13.Cu" "In15.Cu")
		(hatch none 0.5)
		(connect_pads
			(clearance 0)
		)
		(min_thickness 0.25)
		(keepout
			(tracks not_allowed)
			(vias allowed)
			(pads allowed)
			(copperpour not_allowed)
			(footprints allowed)
		)
		(placement
			(enabled no)
			(sheetname "")
		)
		(fill yes
			(thermal_gap 0.5)
			(thermal_bridge_width 0.5)
			(island_removal_mode 0)
		)
		(polygon
			(pts
				(arc
					(start 298.869608 -384.590036)
					(mid 298.110148 -384.590036)
					(end 298.869608 -384.590036)
				)
			)
		)
	)
	(zone
		(layers "B.Cu" "In7.Cu" "In9.Cu" "In11.Cu" "In13.Cu" "In15.Cu")
		(hatch none 0.5)
		(connect_pads
			(clearance 0)
		)
		(min_thickness 0.25)
		(keepout
			(tracks not_allowed)
			(vias allowed)
			(pads allowed)
			(copperpour not_allowed)
			(footprints allowed)
		)
		(placement
			(enabled no)
			(sheetname "")
		)
		(fill yes
			(thermal_gap 0.5)
			(thermal_bridge_width 0.5)
			(island_removal_mode 0)
		)
		(polygon
			(pts
				(arc
					(start 176.076356 -317.749936)
					(mid 175.423576 -317.749936)
					(end 176.076356 -317.749936)
				)
			)
		)
	)
	(zone
		(layers "B.Cu" "In7.Cu" "In9.Cu" "In11.Cu" "In13.Cu" "In15.Cu")
		(hatch none 0.5)
		(connect_pads
			(clearance 0)
		)
		(min_thickness 0.25)
		(keepout
			(tracks not_allowed)
			(vias allowed)
			(pads allowed)
			(copperpour not_allowed)
			(footprints allowed)
		)
		(placement
			(enabled no)
			(sheetname "")
		)
		(fill yes
			(thermal_gap 0.5)
			(thermal_bridge_width 0.5)
			(island_removal_mode 0)
		)
		(polygon
			(pts
				(arc
					(start 79.925926 -274.999958)
					(mid 79.273146 -274.999958)
					(end 79.925926 -274.999958)
				)
			)
		)
	)
	(zone
		(layers "B.Cu" "In7.Cu" "In9.Cu" "In11.Cu" "In13.Cu" "In15.Cu")
		(hatch none 0.5)
		(connect_pads
			(clearance 0)
		)
		(min_thickness 0.25)
		(keepout
			(tracks not_allowed)
			(vias allowed)
			(pads allowed)
			(copperpour not_allowed)
			(footprints allowed)
		)
		(placement
			(enabled no)
			(sheetname "")
		)
		(fill yes
			(thermal_gap 0.5)
			(thermal_bridge_width 0.5)
			(island_removal_mode 0)
		)
		(polygon
			(pts
				(arc
					(start 431.076354 -283.549852)
					(mid 430.423574 -283.549852)
					(end 431.076354 -283.549852)
				)
			)
		)
	)
	(zone
		(layers "B.Cu" "In7.Cu" "In9.Cu" "In11.Cu" "In13.Cu" "In15.Cu")
		(hatch none 0.5)
		(connect_pads
			(clearance 0)
		)
		(min_thickness 0.25)
		(keepout
			(tracks not_allowed)
			(vias allowed)
			(pads allowed)
			(copperpour not_allowed)
			(footprints allowed)
		)
		(placement
			(enabled no)
			(sheetname "")
		)
		(fill yes
			(thermal_gap 0.5)
			(thermal_bridge_width 0.5)
			(island_removal_mode 0)
		)
		(polygon
			(pts
				(arc
					(start 269.376144 -316.799722)
					(mid 268.723364 -316.799722)
					(end 269.376144 -316.799722)
				)
			)
		)
	)
	(zone
		(layers "B.Cu" "In7.Cu" "In9.Cu" "In11.Cu" "In13.Cu" "In15.Cu")
		(hatch none 0.5)
		(connect_pads
			(clearance 0)
		)
		(min_thickness 0.25)
		(keepout
			(tracks not_allowed)
			(vias allowed)
			(pads allowed)
			(copperpour not_allowed)
			(footprints allowed)
		)
		(placement
			(enabled no)
			(sheetname "")
		)
		(fill yes
			(thermal_gap 0.5)
			(thermal_bridge_width 0.5)
			(island_removal_mode 0)
		)
		(polygon
			(pts
				(arc
					(start 178.926236 -316.799722)
					(mid 178.273456 -316.799722)
					(end 178.926236 -316.799722)
				)
			)
		)
	)
	(zone
		(layers "B.Cu" "In7.Cu" "In9.Cu" "In11.Cu" "In13.Cu" "In15.Cu")
		(hatch none 0.5)
		(connect_pads
			(clearance 0)
		)
		(min_thickness 0.25)
		(keepout
			(tracks not_allowed)
			(vias allowed)
			(pads allowed)
			(copperpour not_allowed)
			(footprints allowed)
		)
		(placement
			(enabled no)
			(sheetname "")
		)
		(fill yes
			(thermal_gap 0.5)
			(thermal_bridge_width 0.5)
			(island_removal_mode 0)
		)
		(polygon
			(pts
				(arc
					(start 65.55486 -132.577332)
					(mid 64.85128 -132.577332)
					(end 65.55486 -132.577332)
				)
			)
		)
	)
	(zone
		(layers "B.Cu" "In7.Cu" "In9.Cu" "In11.Cu" "In13.Cu" "In15.Cu")
		(hatch none 0.5)
		(connect_pads
			(clearance 0)
		)
		(min_thickness 0.25)
		(keepout
			(tracks not_allowed)
			(vias allowed)
			(pads allowed)
			(copperpour not_allowed)
			(footprints allowed)
		)
		(placement
			(enabled no)
			(sheetname "")
		)
		(fill yes
			(thermal_gap 0.5)
			(thermal_bridge_width 0.5)
			(island_removal_mode 0)
		)
		(polygon
			(pts
				(arc
					(start 409.226258 -315.849762)
					(mid 408.573478 -315.849762)
					(end 409.226258 -315.849762)
				)
			)
		)
	)
	(zone
		(layers "B.Cu" "In7.Cu" "In9.Cu" "In11.Cu" "In13.Cu" "In15.Cu")
		(hatch none 0.5)
		(connect_pads
			(clearance 0)
		)
		(min_thickness 0.25)
		(keepout
			(tracks not_allowed)
			(vias allowed)
			(pads allowed)
			(copperpour not_allowed)
			(footprints allowed)
		)
		(placement
			(enabled no)
			(sheetname "")
		)
		(fill yes
			(thermal_gap 0.5)
			(thermal_bridge_width 0.5)
			(island_removal_mode 0)
		)
		(polygon
			(pts
				(arc
					(start 269.376144 -310.149748)
					(mid 268.723364 -310.149748)
					(end 269.376144 -310.149748)
				)
			)
		)
	)
	(zone
		(layers "B.Cu" "In7.Cu" "In9.Cu" "In11.Cu" "In13.Cu" "In15.Cu")
		(hatch none 0.5)
		(connect_pads
			(clearance 0)
		)
		(min_thickness 0.25)
		(keepout
			(tracks not_allowed)
			(vias allowed)
			(pads allowed)
			(copperpour not_allowed)
			(footprints allowed)
		)
		(placement
			(enabled no)
			(sheetname "")
		)
		(fill yes
			(thermal_gap 0.5)
			(thermal_bridge_width 0.5)
			(island_removal_mode 0)
		)
		(polygon
			(pts
				(arc
					(start 46.67631 -318.699896)
					(mid 46.02353 -318.699896)
					(end 46.67631 -318.699896)
				)
			)
		)
	)
	(zone
		(layers "B.Cu" "In7.Cu" "In9.Cu" "In11.Cu" "In13.Cu" "In15.Cu")
		(hatch none 0.5)
		(connect_pads
			(clearance 0)
		)
		(min_thickness 0.25)
		(keepout
			(tracks not_allowed)
			(vias allowed)
			(pads allowed)
			(copperpour not_allowed)
			(footprints allowed)
		)
		(placement
			(enabled no)
			(sheetname "")
		)
		(fill yes
			(thermal_gap 0.5)
			(thermal_bridge_width 0.5)
			(island_removal_mode 0)
		)
		(polygon
			(pts
				(arc
					(start 301.069502 -383.490216)
					(mid 300.310042 -383.490216)
					(end 301.069502 -383.490216)
				)
			)
		)
	)
	(zone
		(layers "B.Cu" "In7.Cu" "In9.Cu" "In11.Cu" "In13.Cu" "In15.Cu")
		(hatch none 0.5)
		(connect_pads
			(clearance 0)
		)
		(min_thickness 0.25)
		(keepout
			(tracks not_allowed)
			(vias allowed)
			(pads allowed)
			(copperpour not_allowed)
			(footprints allowed)
		)
		(placement
			(enabled no)
			(sheetname "")
		)
		(fill yes
			(thermal_gap 0.5)
			(thermal_bridge_width 0.5)
			(island_removal_mode 0)
		)
		(polygon
			(pts
				(arc
					(start 44.776136 -318.699896)
					(mid 44.123356 -318.699896)
					(end 44.776136 -318.699896)
				)
			)
		)
	)
	(zone
		(layers "B.Cu" "In7.Cu" "In9.Cu" "In11.Cu" "In13.Cu" "In15.Cu")
		(hatch none 0.5)
		(connect_pads
			(clearance 0)
		)
		(min_thickness 0.25)
		(keepout
			(tracks not_allowed)
			(vias allowed)
			(pads allowed)
			(copperpour not_allowed)
			(footprints allowed)
		)
		(placement
			(enabled no)
			(sheetname "")
		)
		(fill yes
			(thermal_gap 0.5)
			(thermal_bridge_width 0.5)
			(island_removal_mode 0)
		)
		(polygon
			(pts
				(arc
					(start 294.075866 -274.049744)
					(mid 293.423086 -274.049744)
					(end 294.075866 -274.049744)
				)
			)
		)
	)
	(zone
		(layers "B.Cu" "In7.Cu" "In9.Cu" "In11.Cu" "In13.Cu" "In15.Cu")
		(hatch none 0.5)
		(connect_pads
			(clearance 0)
		)
		(min_thickness 0.25)
		(keepout
			(tracks not_allowed)
			(vias allowed)
			(pads allowed)
			(copperpour not_allowed)
			(footprints allowed)
		)
		(placement
			(enabled no)
			(sheetname "")
		)
		(fill yes
			(thermal_gap 0.5)
			(thermal_bridge_width 0.5)
			(island_removal_mode 0)
		)
		(polygon
			(pts
				(arc
					(start 197.926452 -316.799722)
					(mid 197.273672 -316.799722)
					(end 197.926452 -316.799722)
				)
			)
		)
	)
	(zone
		(layers "B.Cu" "In7.Cu" "In9.Cu" "In11.Cu" "In13.Cu" "In15.Cu")
		(hatch none 0.5)
		(connect_pads
			(clearance 0)
		)
		(min_thickness 0.25)
		(keepout
			(tracks not_allowed)
			(vias allowed)
			(pads allowed)
			(copperpour not_allowed)
			(footprints allowed)
		)
		(placement
			(enabled no)
			(sheetname "")
		)
		(fill yes
			(thermal_gap 0.5)
			(thermal_bridge_width 0.5)
			(island_removal_mode 0)
		)
		(polygon
			(pts
				(arc
					(start 183.508904 -123.16714)
					(mid 182.805324 -123.16714)
					(end 183.508904 -123.16714)
				)
			)
		)
	)
	(zone
		(layers "B.Cu" "In7.Cu" "In9.Cu" "In11.Cu" "In13.Cu" "In15.Cu")
		(hatch none 0.5)
		(connect_pads
			(clearance 0)
		)
		(min_thickness 0.25)
		(keepout
			(tracks not_allowed)
			(vias allowed)
			(pads allowed)
			(copperpour not_allowed)
			(footprints allowed)
		)
		(placement
			(enabled no)
			(sheetname "")
		)
		(fill yes
			(thermal_gap 0.5)
			(thermal_bridge_width 0.5)
			(island_removal_mode 0)
		)
		(polygon
			(pts
				(arc
					(start 299.609002 -146.223736)
					(mid 298.905422 -146.223736)
					(end 299.609002 -146.223736)
				)
			)
		)
	)
	(zone
		(layers "B.Cu" "In7.Cu" "In9.Cu" "In11.Cu" "In13.Cu" "In15.Cu")
		(hatch none 0.5)
		(connect_pads
			(clearance 0)
		)
		(min_thickness 0.25)
		(keepout
			(tracks not_allowed)
			(vias allowed)
			(pads allowed)
			(copperpour not_allowed)
			(footprints allowed)
		)
		(placement
			(enabled no)
			(sheetname "")
		)
		(fill yes
			(thermal_gap 0.5)
			(thermal_bridge_width 0.5)
			(island_removal_mode 0)
		)
		(polygon
			(pts
				(arc
					(start 400.89455 -101.112828)
					(mid 400.19097 -101.112828)
					(end 400.89455 -101.112828)
				)
			)
		)
	)
	(zone
		(layers "B.Cu" "In7.Cu" "In9.Cu" "In11.Cu" "In13.Cu" "In15.Cu")
		(hatch none 0.5)
		(connect_pads
			(clearance 0)
		)
		(min_thickness 0.25)
		(keepout
			(tracks not_allowed)
			(vias allowed)
			(pads allowed)
			(copperpour not_allowed)
			(footprints allowed)
		)
		(placement
			(enabled no)
			(sheetname "")
		)
		(fill yes
			(thermal_gap 0.5)
			(thermal_bridge_width 0.5)
			(island_removal_mode 0)
		)
		(polygon
			(pts
				(arc
					(start 431.076354 -308.249828)
					(mid 430.423574 -308.249828)
					(end 431.076354 -308.249828)
				)
			)
		)
	)
	(zone
		(layers "B.Cu" "In7.Cu" "In9.Cu" "In11.Cu" "In13.Cu" "In15.Cu")
		(hatch none 0.5)
		(connect_pads
			(clearance 0)
		)
		(min_thickness 0.25)
		(keepout
			(tracks not_allowed)
			(vias allowed)
			(pads allowed)
			(copperpour not_allowed)
			(footprints allowed)
		)
		(placement
			(enabled no)
			(sheetname "")
		)
		(fill yes
			(thermal_gap 0.5)
			(thermal_bridge_width 0.5)
			(island_removal_mode 0)
		)
		(polygon
			(pts
				(arc
					(start 298.869608 -410.589984)
					(mid 298.110148 -410.589984)
					(end 298.869608 -410.589984)
				)
			)
		)
	)
	(zone
		(layers "B.Cu" "In7.Cu" "In9.Cu" "In11.Cu" "In13.Cu" "In15.Cu")
		(hatch none 0.5)
		(connect_pads
			(clearance 0)
		)
		(min_thickness 0.25)
		(keepout
			(tracks not_allowed)
			(vias allowed)
			(pads allowed)
			(copperpour not_allowed)
			(footprints allowed)
		)
		(placement
			(enabled no)
			(sheetname "")
		)
		(fill yes
			(thermal_gap 0.5)
			(thermal_bridge_width 0.5)
			(island_removal_mode 0)
		)
		(polygon
			(pts
				(arc
					(start 116.289836 -375.69013)
					(mid 115.530376 -375.69013)
					(end 116.289836 -375.69013)
				)
			)
		)
	)
	(zone
		(layers "B.Cu" "In7.Cu" "In9.Cu" "In11.Cu" "In13.Cu" "In15.Cu")
		(hatch none 0.5)
		(connect_pads
			(clearance 0)
		)
		(min_thickness 0.25)
		(keepout
			(tracks not_allowed)
			(vias allowed)
			(pads allowed)
			(copperpour not_allowed)
			(footprints allowed)
		)
		(placement
			(enabled no)
			(sheetname "")
		)
		(fill yes
			(thermal_gap 0.5)
			(thermal_bridge_width 0.5)
			(island_removal_mode 0)
		)
		(polygon
			(pts
				(arc
					(start 410.175964 -274.049744)
					(mid 409.523184 -274.049744)
					(end 410.175964 -274.049744)
				)
			)
		)
	)
	(zone
		(layers "B.Cu" "In7.Cu" "In9.Cu" "In11.Cu" "In13.Cu" "In15.Cu")
		(hatch none 0.5)
		(connect_pads
			(clearance 0)
		)
		(min_thickness 0.25)
		(keepout
			(tracks not_allowed)
			(vias allowed)
			(pads allowed)
			(copperpour not_allowed)
			(footprints allowed)
		)
		(placement
			(enabled no)
			(sheetname "")
		)
		(fill yes
			(thermal_gap 0.5)
			(thermal_bridge_width 0.5)
			(island_removal_mode 0)
		)
		(polygon
			(pts
				(arc
					(start 312.126122 -286.399732)
					(mid 311.473342 -286.399732)
					(end 312.126122 -286.399732)
				)
			)
		)
	)
	(zone
		(layers "B.Cu" "In7.Cu" "In9.Cu" "In11.Cu" "In13.Cu" "In15.Cu")
		(hatch none 0.5)
		(connect_pads
			(clearance 0)
		)
		(min_thickness 0.25)
		(keepout
			(tracks not_allowed)
			(vias allowed)
			(pads allowed)
			(copperpour not_allowed)
			(footprints allowed)
		)
		(placement
			(enabled no)
			(sheetname "")
		)
		(fill yes
			(thermal_gap 0.5)
			(thermal_bridge_width 0.5)
			(island_removal_mode 0)
		)
		(polygon
			(pts
				(arc
					(start 131.689856 -376.790204)
					(mid 130.930396 -376.790204)
					(end 131.689856 -376.790204)
				)
			)
		)
	)
	(zone
		(layers "B.Cu" "In7.Cu" "In9.Cu" "In11.Cu" "In13.Cu" "In15.Cu")
		(hatch none 0.5)
		(connect_pads
			(clearance 0)
		)
		(min_thickness 0.25)
		(keepout
			(tracks not_allowed)
			(vias allowed)
			(pads allowed)
			(copperpour not_allowed)
			(footprints allowed)
		)
		(placement
			(enabled no)
			(sheetname "")
		)
		(fill yes
			(thermal_gap 0.5)
			(thermal_bridge_width 0.5)
			(island_removal_mode 0)
		)
		(polygon
			(pts
				(arc
					(start 185.57621 -274.049744)
					(mid 184.92343 -274.049744)
					(end 185.57621 -274.049744)
				)
			)
		)
	)
	(zone
		(layers "B.Cu" "In7.Cu" "In9.Cu" "In11.Cu" "In13.Cu" "In15.Cu")
		(hatch none 0.5)
		(connect_pads
			(clearance 0)
		)
		(min_thickness 0.25)
		(keepout
			(tracks not_allowed)
			(vias allowed)
			(pads allowed)
			(copperpour not_allowed)
			(footprints allowed)
		)
		(placement
			(enabled no)
			(sheetname "")
		)
		(fill yes
			(thermal_gap 0.5)
			(thermal_bridge_width 0.5)
			(island_removal_mode 0)
		)
		(polygon
			(pts
				(arc
					(start 303.575974 -274.049744)
					(mid 302.923194 -274.049744)
					(end 303.575974 -274.049744)
				)
			)
		)
	)
	(zone
		(layers "B.Cu" "In7.Cu" "In9.Cu" "In11.Cu" "In13.Cu" "In15.Cu")
		(hatch none 0.5)
		(connect_pads
			(clearance 0)
		)
		(min_thickness 0.25)
		(keepout
			(tracks not_allowed)
			(vias allowed)
			(pads allowed)
			(copperpour not_allowed)
			(footprints allowed)
		)
		(placement
			(enabled no)
			(sheetname "")
		)
		(fill yes
			(thermal_gap 0.5)
			(thermal_bridge_width 0.5)
			(island_removal_mode 0)
		)
		(polygon
			(pts
				(arc
					(start 116.289836 -374.390158)
					(mid 115.530376 -374.390158)
					(end 116.289836 -374.390158)
				)
			)
		)
	)
	(zone
		(layers "B.Cu" "In7.Cu" "In9.Cu" "In11.Cu" "In13.Cu" "In15.Cu")
		(hatch none 0.5)
		(connect_pads
			(clearance 0)
		)
		(min_thickness 0.25)
		(keepout
			(tracks not_allowed)
			(vias allowed)
			(pads allowed)
			(copperpour not_allowed)
			(footprints allowed)
		)
		(placement
			(enabled no)
			(sheetname "")
		)
		(fill yes
			(thermal_gap 0.5)
			(thermal_bridge_width 0.5)
			(island_removal_mode 0)
		)
		(polygon
			(pts
				(arc
					(start 41.926256 -315.849762)
					(mid 41.273476 -315.849762)
					(end 41.926256 -315.849762)
				)
			)
		)
	)
	(zone
		(layers "B.Cu" "In7.Cu" "In9.Cu" "In11.Cu" "In13.Cu" "In15.Cu")
		(hatch none 0.5)
		(connect_pads
			(clearance 0)
		)
		(min_thickness 0.25)
		(keepout
			(tracks not_allowed)
			(vias allowed)
			(pads allowed)
			(copperpour not_allowed)
			(footprints allowed)
		)
		(placement
			(enabled no)
			(sheetname "")
		)
		(fill yes
			(thermal_gap 0.5)
			(thermal_bridge_width 0.5)
			(island_removal_mode 0)
		)
		(polygon
			(pts
				(arc
					(start 413.026098 -275.949664)
					(mid 412.373318 -275.949664)
					(end 413.026098 -275.949664)
				)
			)
		)
	)
	(zone
		(layers "B.Cu" "In7.Cu" "In9.Cu" "In11.Cu" "In13.Cu" "In15.Cu")
		(hatch none 0.5)
		(connect_pads
			(clearance 0)
		)
		(min_thickness 0.25)
		(keepout
			(tracks not_allowed)
			(vias allowed)
			(pads allowed)
			(copperpour not_allowed)
			(footprints allowed)
		)
		(placement
			(enabled no)
			(sheetname "")
		)
		(fill yes
			(thermal_gap 0.5)
			(thermal_bridge_width 0.5)
			(island_removal_mode 0)
		)
		(polygon
			(pts
				(arc
					(start 413.026352 -315.849762)
					(mid 412.373572 -315.849762)
					(end 413.026352 -315.849762)
				)
			)
		)
	)
	(zone
		(layers "B.Cu" "In7.Cu" "In9.Cu" "In11.Cu" "In13.Cu" "In15.Cu")
		(hatch none 0.5)
		(connect_pads
			(clearance 0)
		)
		(min_thickness 0.25)
		(keepout
			(tracks not_allowed)
			(vias allowed)
			(pads allowed)
			(copperpour not_allowed)
			(footprints allowed)
		)
		(placement
			(enabled no)
			(sheetname "")
		)
		(fill yes
			(thermal_gap 0.5)
			(thermal_bridge_width 0.5)
			(island_removal_mode 0)
		)
		(polygon
			(pts
				(arc
					(start 168.694354 -125.486414)
					(mid 167.990774 -125.486414)
					(end 168.694354 -125.486414)
				)
			)
		)
	)
	(zone
		(layers "B.Cu" "In7.Cu" "In9.Cu" "In11.Cu" "In13.Cu" "In15.Cu")
		(hatch none 0.5)
		(connect_pads
			(clearance 0)
		)
		(min_thickness 0.25)
		(keepout
			(tracks not_allowed)
			(vias allowed)
			(pads allowed)
			(copperpour not_allowed)
			(footprints allowed)
		)
		(placement
			(enabled no)
			(sheetname "")
		)
		(fill yes
			(thermal_gap 0.5)
			(thermal_bridge_width 0.5)
			(island_removal_mode 0)
		)
		(polygon
			(pts
				(arc
					(start 73.276206 -317.749936)
					(mid 72.623426 -317.749936)
					(end 73.276206 -317.749936)
				)
			)
		)
	)
	(zone
		(layers "B.Cu" "In7.Cu" "In9.Cu" "In11.Cu" "In13.Cu" "In15.Cu")
		(hatch none 0.5)
		(connect_pads
			(clearance 0)
		)
		(min_thickness 0.25)
		(keepout
			(tracks not_allowed)
			(vias allowed)
			(pads allowed)
			(copperpour not_allowed)
			(footprints allowed)
		)
		(placement
			(enabled no)
			(sheetname "")
		)
		(fill yes
			(thermal_gap 0.5)
			(thermal_bridge_width 0.5)
			(island_removal_mode 0)
		)
		(polygon
			(pts
				(arc
					(start 300.726094 -315.849762)
					(mid 300.073314 -315.849762)
					(end 300.726094 -315.849762)
				)
			)
		)
	)
	(zone
		(layers "B.Cu" "In7.Cu" "In9.Cu" "In11.Cu" "In13.Cu" "In15.Cu")
		(hatch none 0.5)
		(connect_pads
			(clearance 0)
		)
		(min_thickness 0.25)
		(keepout
			(tracks not_allowed)
			(vias allowed)
			(pads allowed)
			(copperpour not_allowed)
			(footprints allowed)
		)
		(placement
			(enabled no)
			(sheetname "")
		)
		(fill yes
			(thermal_gap 0.5)
			(thermal_bridge_width 0.5)
			(island_removal_mode 0)
		)
		(polygon
			(pts
				(arc
					(start 43.689778 -410.589984)
					(mid 42.930318 -410.589984)
					(end 43.689778 -410.589984)
				)
			)
		)
	)
	(zone
		(layers "B.Cu" "In7.Cu" "In9.Cu" "In11.Cu" "In13.Cu" "In15.Cu")
		(hatch none 0.5)
		(connect_pads
			(clearance 0)
		)
		(min_thickness 0.25)
		(keepout
			(tracks not_allowed)
			(vias allowed)
			(pads allowed)
			(copperpour not_allowed)
			(footprints allowed)
		)
		(placement
			(enabled no)
			(sheetname "")
		)
		(fill yes
			(thermal_gap 0.5)
			(thermal_bridge_width 0.5)
			(island_removal_mode 0)
		)
		(polygon
			(pts
				(arc
					(start 311.60466 17.596612)
					(mid 310.90108 17.596612)
					(end 311.60466 17.596612)
				)
			)
		)
	)
	(zone
		(layers "B.Cu" "In7.Cu" "In9.Cu" "In11.Cu" "In13.Cu" "In15.Cu")
		(hatch none 0.5)
		(connect_pads
			(clearance 0)
		)
		(min_thickness 0.25)
		(keepout
			(tracks not_allowed)
			(vias allowed)
			(pads allowed)
			(copperpour not_allowed)
			(footprints allowed)
		)
		(placement
			(enabled no)
			(sheetname "")
		)
		(fill yes
			(thermal_gap 0.5)
			(thermal_bridge_width 0.5)
			(island_removal_mode 0)
		)
		(polygon
			(pts
				(arc
					(start 41.48963 -408.190192)
					(mid 40.73017 -408.190192)
					(end 41.48963 -408.190192)
				)
			)
		)
	)
	(zone
		(layers "B.Cu" "In7.Cu" "In9.Cu" "In11.Cu" "In13.Cu" "In15.Cu")
		(hatch none 0.5)
		(connect_pads
			(clearance 0)
		)
		(min_thickness 0.25)
		(keepout
			(tracks not_allowed)
			(vias allowed)
			(pads allowed)
			(copperpour not_allowed)
			(footprints allowed)
		)
		(placement
			(enabled no)
			(sheetname "")
		)
		(fill yes
			(thermal_gap 0.5)
			(thermal_bridge_width 0.5)
			(island_removal_mode 0)
		)
		(polygon
			(pts
				(arc
					(start 279.826212 -315.849762)
					(mid 279.173432 -315.849762)
					(end 279.826212 -315.849762)
				)
			)
		)
	)
	(zone
		(layers "B.Cu" "In7.Cu" "In9.Cu" "In11.Cu" "In13.Cu" "In15.Cu")
		(hatch none 0.5)
		(connect_pads
			(clearance 0)
		)
		(min_thickness 0.25)
		(keepout
			(tracks not_allowed)
			(vias allowed)
			(pads allowed)
			(copperpour not_allowed)
			(footprints allowed)
		)
		(placement
			(enabled no)
			(sheetname "")
		)
		(fill yes
			(thermal_gap 0.5)
			(thermal_bridge_width 0.5)
			(island_removal_mode 0)
		)
		(polygon
			(pts
				(arc
					(start 78.889606 -372.890034)
					(mid 78.130146 -372.890034)
					(end 78.889606 -372.890034)
				)
			)
		)
	)
	(zone
		(layers "B.Cu" "In7.Cu" "In9.Cu" "In11.Cu" "In13.Cu" "In15.Cu")
		(hatch none 0.5)
		(connect_pads
			(clearance 0)
		)
		(min_thickness 0.25)
		(keepout
			(tracks not_allowed)
			(vias allowed)
			(pads allowed)
			(copperpour not_allowed)
			(footprints allowed)
		)
		(placement
			(enabled no)
			(sheetname "")
		)
		(fill yes
			(thermal_gap 0.5)
			(thermal_bridge_width 0.5)
			(island_removal_mode 0)
		)
		(polygon
			(pts
				(arc
					(start 301.069502 -382.18999)
					(mid 300.310042 -382.18999)
					(end 301.069502 -382.18999)
				)
			)
		)
	)
	(zone
		(layers "B.Cu" "In7.Cu" "In9.Cu" "In11.Cu" "In13.Cu" "In15.Cu")
		(hatch none 0.5)
		(connect_pads
			(clearance 0)
		)
		(min_thickness 0.25)
		(keepout
			(tracks not_allowed)
			(vias allowed)
			(pads allowed)
			(copperpour not_allowed)
			(footprints allowed)
		)
		(placement
			(enabled no)
			(sheetname "")
		)
		(fill yes
			(thermal_gap 0.5)
			(thermal_bridge_width 0.5)
			(island_removal_mode 0)
		)
		(polygon
			(pts
				(arc
					(start 411.126178 -316.799722)
					(mid 410.473398 -316.799722)
					(end 411.126178 -316.799722)
				)
			)
		)
	)
	(zone
		(layers "B.Cu" "In7.Cu" "In9.Cu" "In11.Cu" "In13.Cu" "In15.Cu")
		(hatch none 0.5)
		(connect_pads
			(clearance 0)
		)
		(min_thickness 0.25)
		(keepout
			(tracks not_allowed)
			(vias allowed)
			(pads allowed)
			(copperpour not_allowed)
			(footprints allowed)
		)
		(placement
			(enabled no)
			(sheetname "")
		)
		(fill yes
			(thermal_gap 0.5)
			(thermal_bridge_width 0.5)
			(island_removal_mode 0)
		)
		(polygon
			(pts
				(arc
					(start 413.026098 -274.999704)
					(mid 412.373318 -274.999704)
					(end 413.026098 -274.999704)
				)
			)
		)
	)
	(zone
		(layers "B.Cu" "In7.Cu" "In9.Cu" "In11.Cu" "In13.Cu" "In15.Cu")
		(hatch none 0.5)
		(connect_pads
			(clearance 0)
		)
		(min_thickness 0.25)
		(keepout
			(tracks not_allowed)
			(vias allowed)
			(pads allowed)
			(copperpour not_allowed)
			(footprints allowed)
		)
		(placement
			(enabled no)
			(sheetname "")
		)
		(fill yes
			(thermal_gap 0.5)
			(thermal_bridge_width 0.5)
			(island_removal_mode 0)
		)
		(polygon
			(pts
				(arc
					(start 37.089842 -382.18999)
					(mid 36.330382 -382.18999)
					(end 37.089842 -382.18999)
				)
			)
		)
	)
	(zone
		(layers "B.Cu" "In7.Cu" "In9.Cu" "In11.Cu" "In13.Cu" "In15.Cu")
		(hatch none 0.5)
		(connect_pads
			(clearance 0)
		)
		(min_thickness 0.25)
		(keepout
			(tracks not_allowed)
			(vias allowed)
			(pads allowed)
			(copperpour not_allowed)
			(footprints allowed)
		)
		(placement
			(enabled no)
			(sheetname "")
		)
		(fill yes
			(thermal_gap 0.5)
			(thermal_bridge_width 0.5)
			(island_removal_mode 0)
		)
		(polygon
			(pts
				(arc
					(start 422.069514 -379.390148)
					(mid 421.310054 -379.390148)
					(end 422.069514 -379.390148)
				)
			)
		)
	)
	(zone
		(layers "B.Cu" "In7.Cu" "In9.Cu" "In11.Cu" "In13.Cu" "In15.Cu")
		(hatch none 0.5)
		(connect_pads
			(clearance 0)
		)
		(min_thickness 0.25)
		(keepout
			(tracks not_allowed)
			(vias allowed)
			(pads allowed)
			(copperpour not_allowed)
			(footprints allowed)
		)
		(placement
			(enabled no)
			(sheetname "")
		)
		(fill yes
			(thermal_gap 0.5)
			(thermal_bridge_width 0.5)
			(island_removal_mode 0)
		)
		(polygon
			(pts
				(arc
					(start 81.089754 -400.390106)
					(mid 80.330294 -400.390106)
					(end 81.089754 -400.390106)
				)
			)
		)
	)
	(zone
		(layers "B.Cu" "In7.Cu" "In9.Cu" "In11.Cu" "In13.Cu" "In15.Cu")
		(hatch none 0.5)
		(connect_pads
			(clearance 0)
		)
		(min_thickness 0.25)
		(keepout
			(tracks not_allowed)
			(vias allowed)
			(pads allowed)
			(copperpour not_allowed)
			(footprints allowed)
		)
		(placement
			(enabled no)
			(sheetname "")
		)
		(fill yes
			(thermal_gap 0.5)
			(thermal_bridge_width 0.5)
			(island_removal_mode 0)
		)
		(polygon
			(pts
				(arc
					(start 297.87596 -274.049744)
					(mid 297.22318 -274.049744)
					(end 297.87596 -274.049744)
				)
			)
		)
	)
	(zone
		(layers "B.Cu" "In7.Cu" "In9.Cu" "In11.Cu" "In13.Cu" "In15.Cu")
		(hatch none 0.5)
		(connect_pads
			(clearance 0)
		)
		(min_thickness 0.25)
		(keepout
			(tracks not_allowed)
			(vias allowed)
			(pads allowed)
			(copperpour not_allowed)
			(footprints allowed)
		)
		(placement
			(enabled no)
			(sheetname "")
		)
		(fill yes
			(thermal_gap 0.5)
			(thermal_bridge_width 0.5)
			(island_removal_mode 0)
		)
		(polygon
			(pts
				(arc
					(start 178.926236 -315.849762)
					(mid 178.273456 -315.849762)
					(end 178.926236 -315.849762)
				)
			)
		)
	)
	(zone
		(layers "B.Cu" "In7.Cu" "In9.Cu" "In11.Cu" "In13.Cu" "In15.Cu")
		(hatch none 0.5)
		(connect_pads
			(clearance 0)
		)
		(min_thickness 0.25)
		(keepout
			(tracks not_allowed)
			(vias allowed)
			(pads allowed)
			(copperpour not_allowed)
			(footprints allowed)
		)
		(placement
			(enabled no)
			(sheetname "")
		)
		(fill yes
			(thermal_gap 0.5)
			(thermal_bridge_width 0.5)
			(island_removal_mode 0)
		)
		(polygon
			(pts
				(arc
					(start 166.889684 -405.390096)
					(mid 166.130224 -405.390096)
					(end 166.889684 -405.390096)
				)
			)
		)
	)
	(zone
		(layers "B.Cu" "In7.Cu" "In9.Cu" "In11.Cu" "In13.Cu" "In15.Cu")
		(hatch none 0.5)
		(connect_pads
			(clearance 0)
		)
		(min_thickness 0.25)
		(keepout
			(tracks not_allowed)
			(vias allowed)
			(pads allowed)
			(copperpour not_allowed)
			(footprints allowed)
		)
		(placement
			(enabled no)
			(sheetname "")
		)
		(fill yes
			(thermal_gap 0.5)
			(thermal_bridge_width 0.5)
			(island_removal_mode 0)
		)
		(polygon
			(pts
				(arc
					(start 46.67631 -317.749936)
					(mid 46.02353 -317.749936)
					(end 46.67631 -317.749936)
				)
			)
		)
	)
	(zone
		(layers "B.Cu" "In7.Cu" "In9.Cu" "In11.Cu" "In13.Cu" "In15.Cu")
		(hatch none 0.5)
		(connect_pads
			(clearance 0)
		)
		(min_thickness 0.25)
		(keepout
			(tracks not_allowed)
			(vias allowed)
			(pads allowed)
			(copperpour not_allowed)
			(footprints allowed)
		)
		(placement
			(enabled no)
			(sheetname "")
		)
		(fill yes
			(thermal_gap 0.5)
			(thermal_bridge_width 0.5)
			(island_removal_mode 0)
		)
		(polygon
			(pts
				(arc
					(start 193.176144 -273.099784)
					(mid 192.523364 -273.099784)
					(end 193.176144 -273.099784)
				)
			)
		)
	)
	(zone
		(layers "B.Cu" "In7.Cu" "In9.Cu" "In11.Cu" "In13.Cu" "In15.Cu")
		(hatch none 0.5)
		(connect_pads
			(clearance 0)
		)
		(min_thickness 0.25)
		(keepout
			(tracks not_allowed)
			(vias allowed)
			(pads allowed)
			(copperpour not_allowed)
			(footprints allowed)
		)
		(placement
			(enabled no)
			(sheetname "")
		)
		(fill yes
			(thermal_gap 0.5)
			(thermal_bridge_width 0.5)
			(island_removal_mode 0)
		)
		(polygon
			(pts
				(arc
					(start 170.548554 -102.912672)
					(mid 169.844974 -102.912672)
					(end 170.548554 -102.912672)
				)
			)
		)
	)
	(zone
		(layers "B.Cu" "In7.Cu" "In9.Cu" "In11.Cu" "In13.Cu" "In15.Cu")
		(hatch none 0.5)
		(connect_pads
			(clearance 0)
		)
		(min_thickness 0.25)
		(keepout
			(tracks not_allowed)
			(vias allowed)
			(pads allowed)
			(copperpour not_allowed)
			(footprints allowed)
		)
		(placement
			(enabled no)
			(sheetname "")
		)
		(fill yes
			(thermal_gap 0.5)
			(thermal_bridge_width 0.5)
			(island_removal_mode 0)
		)
		(polygon
			(pts
				(arc
					(start 187.47613 -274.049744)
					(mid 186.82335 -274.049744)
					(end 187.47613 -274.049744)
				)
			)
		)
	)
	(zone
		(layers "B.Cu" "In7.Cu" "In9.Cu" "In11.Cu" "In13.Cu" "In15.Cu")
		(hatch none 0.5)
		(connect_pads
			(clearance 0)
		)
		(min_thickness 0.25)
		(keepout
			(tracks not_allowed)
			(vias allowed)
			(pads allowed)
			(copperpour not_allowed)
			(footprints allowed)
		)
		(placement
			(enabled no)
			(sheetname "")
		)
		(fill yes
			(thermal_gap 0.5)
			(thermal_bridge_width 0.5)
			(island_removal_mode 0)
		)
		(polygon
			(pts
				(arc
					(start 173.48962 -404.290022)
					(mid 172.73016 -404.290022)
					(end 173.48962 -404.290022)
				)
			)
		)
	)
	(zone
		(layers "B.Cu" "In7.Cu" "In9.Cu" "In11.Cu" "In13.Cu" "In15.Cu")
		(hatch none 0.5)
		(connect_pads
			(clearance 0)
		)
		(min_thickness 0.25)
		(keepout
			(tracks not_allowed)
			(vias allowed)
			(pads allowed)
			(copperpour not_allowed)
			(footprints allowed)
		)
		(placement
			(enabled no)
			(sheetname "")
		)
		(fill yes
			(thermal_gap 0.5)
			(thermal_bridge_width 0.5)
			(island_removal_mode 0)
		)
		(polygon
			(pts
				(arc
					(start 400.89455 -132.232908)
					(mid 400.19097 -132.232908)
					(end 400.89455 -132.232908)
				)
			)
		)
	)
	(zone
		(layers "B.Cu" "In7.Cu" "In9.Cu" "In11.Cu" "In13.Cu" "In15.Cu")
		(hatch none 0.5)
		(connect_pads
			(clearance 0)
		)
		(min_thickness 0.25)
		(keepout
			(tracks not_allowed)
			(vias allowed)
			(pads allowed)
			(copperpour not_allowed)
			(footprints allowed)
		)
		(placement
			(enabled no)
			(sheetname "")
		)
		(fill yes
			(thermal_gap 0.5)
			(thermal_bridge_width 0.5)
			(island_removal_mode 0)
		)
		(polygon
			(pts
				(arc
					(start 312.965084 8.541512)
					(mid 312.261504 8.541512)
					(end 312.965084 8.541512)
				)
			)
		)
	)
	(zone
		(layers "B.Cu" "In7.Cu" "In9.Cu" "In11.Cu" "In13.Cu" "In15.Cu")
		(hatch none 0.5)
		(connect_pads
			(clearance 0)
		)
		(min_thickness 0.25)
		(keepout
			(tracks not_allowed)
			(vias allowed)
			(pads allowed)
			(copperpour not_allowed)
			(footprints allowed)
		)
		(placement
			(enabled no)
			(sheetname "")
		)
		(fill yes
			(thermal_gap 0.5)
			(thermal_bridge_width 0.5)
			(island_removal_mode 0)
		)
		(polygon
			(pts
				(arc
					(start 179.876196 -273.099784)
					(mid 179.223416 -273.099784)
					(end 179.876196 -273.099784)
				)
			)
		)
	)
	(zone
		(layers "B.Cu" "In7.Cu" "In9.Cu" "In11.Cu" "In13.Cu" "In15.Cu")
		(hatch none 0.5)
		(connect_pads
			(clearance 0)
		)
		(min_thickness 0.25)
		(keepout
			(tracks not_allowed)
			(vias allowed)
			(pads allowed)
			(copperpour not_allowed)
			(footprints allowed)
		)
		(placement
			(enabled no)
			(sheetname "")
		)
		(fill yes
			(thermal_gap 0.5)
			(thermal_bridge_width 0.5)
			(island_removal_mode 0)
		)
		(polygon
			(pts
				(arc
					(start 431.076354 -281.649932)
					(mid 430.423574 -281.649932)
					(end 431.076354 -281.649932)
				)
			)
		)
	)
	(zone
		(layers "B.Cu" "In7.Cu" "In9.Cu" "In11.Cu" "In13.Cu" "In15.Cu")
		(hatch none 0.5)
		(connect_pads
			(clearance 0)
		)
		(min_thickness 0.25)
		(keepout
			(tracks not_allowed)
			(vias allowed)
			(pads allowed)
			(copperpour not_allowed)
			(footprints allowed)
		)
		(placement
			(enabled no)
			(sheetname "")
		)
		(fill yes
			(thermal_gap 0.5)
			(thermal_bridge_width 0.5)
			(island_removal_mode 0)
		)
		(polygon
			(pts
				(arc
					(start 78.975966 -274.049744)
					(mid 78.323186 -274.049744)
					(end 78.975966 -274.049744)
				)
			)
		)
	)
	(zone
		(layers "B.Cu" "In7.Cu" "In9.Cu" "In11.Cu" "In13.Cu" "In15.Cu")
		(hatch none 0.5)
		(connect_pads
			(clearance 0)
		)
		(min_thickness 0.25)
		(keepout
			(tracks not_allowed)
			(vias allowed)
			(pads allowed)
			(copperpour not_allowed)
			(footprints allowed)
		)
		(placement
			(enabled no)
			(sheetname "")
		)
		(fill yes
			(thermal_gap 0.5)
			(thermal_bridge_width 0.5)
			(island_removal_mode 0)
		)
		(polygon
			(pts
				(arc
					(start 286.648652 -122.822716)
					(mid 285.945072 -122.822716)
					(end 286.648652 -122.822716)
				)
			)
		)
	)
	(zone
		(layers "B.Cu" "In7.Cu" "In9.Cu" "In11.Cu" "In13.Cu" "In15.Cu")
		(hatch none 0.5)
		(connect_pads
			(clearance 0)
		)
		(min_thickness 0.25)
		(keepout
			(tracks not_allowed)
			(vias allowed)
			(pads allowed)
			(copperpour not_allowed)
			(footprints allowed)
		)
		(placement
			(enabled no)
			(sheetname "")
		)
		(fill yes
			(thermal_gap 0.5)
			(thermal_bridge_width 0.5)
			(island_removal_mode 0)
		)
		(polygon
			(pts
				(arc
					(start 415.7091 -153.42362)
					(mid 415.00552 -153.42362)
					(end 415.7091 -153.42362)
				)
			)
		)
	)
	(zone
		(layers "B.Cu" "In7.Cu" "In9.Cu" "In11.Cu" "In13.Cu" "In15.Cu")
		(hatch none 0.5)
		(connect_pads
			(clearance 0)
		)
		(min_thickness 0.25)
		(keepout
			(tracks not_allowed)
			(vias allowed)
			(pads allowed)
			(copperpour not_allowed)
			(footprints allowed)
		)
		(placement
			(enabled no)
			(sheetname "")
		)
		(fill yes
			(thermal_gap 0.5)
			(thermal_bridge_width 0.5)
			(island_removal_mode 0)
		)
		(polygon
			(pts
				(arc
					(start 408.276298 -317.749936)
					(mid 407.623518 -317.749936)
					(end 408.276298 -317.749936)
				)
			)
		)
	)
	(zone
		(layers "B.Cu" "In7.Cu" "In9.Cu" "In11.Cu" "In13.Cu" "In15.Cu")
		(hatch none 0.5)
		(connect_pads
			(clearance 0)
		)
		(min_thickness 0.25)
		(keepout
			(tracks not_allowed)
			(vias allowed)
			(pads allowed)
			(copperpour not_allowed)
			(footprints allowed)
		)
		(placement
			(enabled no)
			(sheetname "")
		)
		(fill yes
			(thermal_gap 0.5)
			(thermal_bridge_width 0.5)
			(island_removal_mode 0)
		)
		(polygon
			(pts
				(arc
					(start 181.654704 -132.577332)
					(mid 180.951124 -132.577332)
					(end 181.654704 -132.577332)
				)
			)
		)
	)
	(zone
		(layers "B.Cu" "In7.Cu" "In9.Cu" "In11.Cu" "In13.Cu" "In15.Cu")
		(hatch none 0.5)
		(connect_pads
			(clearance 0)
		)
		(min_thickness 0.25)
		(keepout
			(tracks not_allowed)
			(vias allowed)
			(pads allowed)
			(copperpour not_allowed)
			(footprints allowed)
		)
		(placement
			(enabled no)
			(sheetname "")
		)
		(fill yes
			(thermal_gap 0.5)
			(thermal_bridge_width 0.5)
			(island_removal_mode 0)
		)
		(polygon
			(pts
				(arc
					(start 297.754802 -152.487376)
					(mid 297.051222 -152.487376)
					(end 297.754802 -152.487376)
				)
			)
		)
	)
	(zone
		(layers "B.Cu" "In7.Cu" "In9.Cu" "In11.Cu" "In13.Cu" "In15.Cu")
		(hatch none 0.5)
		(connect_pads
			(clearance 0)
		)
		(min_thickness 0.25)
		(keepout
			(tracks not_allowed)
			(vias allowed)
			(pads allowed)
			(copperpour not_allowed)
			(footprints allowed)
		)
		(placement
			(enabled no)
			(sheetname "")
		)
		(fill yes
			(thermal_gap 0.5)
			(thermal_bridge_width 0.5)
			(island_removal_mode 0)
		)
		(polygon
			(pts
				(arc
					(start 181.776116 -274.049744)
					(mid 181.123336 -274.049744)
					(end 181.776116 -274.049744)
				)
			)
		)
	)
	(zone
		(layers "B.Cu" "In7.Cu" "In9.Cu" "In11.Cu" "In13.Cu" "In15.Cu")
		(hatch none 0.5)
		(connect_pads
			(clearance 0)
		)
		(min_thickness 0.25)
		(keepout
			(tracks not_allowed)
			(vias allowed)
			(pads allowed)
			(copperpour not_allowed)
			(footprints allowed)
		)
		(placement
			(enabled no)
			(sheetname "")
		)
		(fill yes
			(thermal_gap 0.5)
			(thermal_bridge_width 0.5)
			(island_removal_mode 0)
		)
		(polygon
			(pts
				(arc
					(start 428.22622 -284.499812)
					(mid 427.57344 -284.499812)
					(end 428.22622 -284.499812)
				)
			)
		)
	)
	(zone
		(layers "B.Cu" "In7.Cu" "In9.Cu" "In11.Cu" "In13.Cu" "In15.Cu")
		(hatch none 0.5)
		(connect_pads
			(clearance 0)
		)
		(min_thickness 0.25)
		(keepout
			(tracks not_allowed)
			(vias allowed)
			(pads allowed)
			(copperpour not_allowed)
			(footprints allowed)
		)
		(placement
			(enabled no)
			(sheetname "")
		)
		(fill yes
			(thermal_gap 0.5)
			(thermal_bridge_width 0.5)
			(island_removal_mode 0)
		)
		(polygon
			(pts
				(arc
					(start 428.225966 -274.999958)
					(mid 427.573186 -274.999958)
					(end 428.225966 -274.999958)
				)
			)
		)
	)
	(zone
		(layers "B.Cu" "In7.Cu" "In9.Cu" "In11.Cu" "In13.Cu" "In15.Cu")
		(hatch none 0.5)
		(connect_pads
			(clearance 0)
		)
		(min_thickness 0.25)
		(keepout
			(tracks not_allowed)
			(vias allowed)
			(pads allowed)
			(copperpour not_allowed)
			(footprints allowed)
		)
		(placement
			(enabled no)
			(sheetname "")
		)
		(fill yes
			(thermal_gap 0.5)
			(thermal_bridge_width 0.5)
			(island_removal_mode 0)
		)
		(polygon
			(pts
				(arc
					(start 82.776314 -285.449772)
					(mid 82.123534 -285.449772)
					(end 82.776314 -285.449772)
				)
			)
		)
	)
	(zone
		(layers "B.Cu" "In7.Cu" "In9.Cu" "In11.Cu" "In13.Cu" "In15.Cu")
		(hatch none 0.5)
		(connect_pads
			(clearance 0)
		)
		(min_thickness 0.25)
		(keepout
			(tracks not_allowed)
			(vias allowed)
			(pads allowed)
			(copperpour not_allowed)
			(footprints allowed)
		)
		(placement
			(enabled no)
			(sheetname "")
		)
		(fill yes
			(thermal_gap 0.5)
			(thermal_bridge_width 0.5)
			(island_removal_mode 0)
		)
		(polygon
			(pts
				(arc
					(start 312.126122 -288.299906)
					(mid 311.473342 -288.299906)
					(end 312.126122 -288.299906)
				)
			)
		)
	)
	(zone
		(layers "B.Cu" "In7.Cu" "In9.Cu" "In11.Cu" "In13.Cu" "In15.Cu")
		(hatch none 0.5)
		(connect_pads
			(clearance 0)
		)
		(min_thickness 0.25)
		(keepout
			(tracks not_allowed)
			(vias allowed)
			(pads allowed)
			(copperpour not_allowed)
			(footprints allowed)
		)
		(placement
			(enabled no)
			(sheetname "")
		)
		(fill yes
			(thermal_gap 0.5)
			(thermal_bridge_width 0.5)
			(island_removal_mode 0)
		)
		(polygon
			(pts
				(arc
					(start 65.676018 -273.099784)
					(mid 65.023238 -273.099784)
					(end 65.676018 -273.099784)
				)
			)
		)
	)
	(zone
		(layers "B.Cu" "In7.Cu" "In9.Cu" "In11.Cu" "In13.Cu" "In15.Cu")
		(hatch none 0.5)
		(connect_pads
			(clearance 0)
		)
		(min_thickness 0.25)
		(keepout
			(tracks not_allowed)
			(vias allowed)
			(pads allowed)
			(copperpour not_allowed)
			(footprints allowed)
		)
		(placement
			(enabled no)
			(sheetname "")
		)
		(fill yes
			(thermal_gap 0.5)
			(thermal_bridge_width 0.5)
			(island_removal_mode 0)
		)
		(polygon
			(pts
				(arc
					(start 42.876216 -318.699896)
					(mid 42.223436 -318.699896)
					(end 42.876216 -318.699896)
				)
			)
		)
	)
	(zone
		(layers "B.Cu" "In7.Cu" "In9.Cu" "In11.Cu" "In13.Cu" "In15.Cu")
		(hatch none 0.5)
		(connect_pads
			(clearance 0)
		)
		(min_thickness 0.25)
		(keepout
			(tracks not_allowed)
			(vias allowed)
			(pads allowed)
			(copperpour not_allowed)
			(footprints allowed)
		)
		(placement
			(enabled no)
			(sheetname "")
		)
		(fill yes
			(thermal_gap 0.5)
			(thermal_bridge_width 0.5)
			(island_removal_mode 0)
		)
		(polygon
			(pts
				(arc
					(start 193.176398 -318.699896)
					(mid 192.523618 -318.699896)
					(end 193.176398 -318.699896)
				)
			)
		)
	)
	(zone
		(layers "B.Cu" "In7.Cu" "In9.Cu" "In11.Cu" "In13.Cu" "In15.Cu")
		(hatch none 0.5)
		(connect_pads
			(clearance 0)
		)
		(min_thickness 0.25)
		(keepout
			(tracks not_allowed)
			(vias allowed)
			(pads allowed)
			(copperpour not_allowed)
			(footprints allowed)
		)
		(placement
			(enabled no)
			(sheetname "")
		)
		(fill yes
			(thermal_gap 0.5)
			(thermal_bridge_width 0.5)
			(island_removal_mode 0)
		)
		(polygon
			(pts
				(arc
					(start 52.59451 -121.886472)
					(mid 51.89093 -121.886472)
					(end 52.59451 -121.886472)
				)
			)
		)
	)
	(zone
		(layers "B.Cu" "In7.Cu" "In9.Cu" "In11.Cu" "In13.Cu" "In15.Cu")
		(hatch none 0.5)
		(connect_pads
			(clearance 0)
		)
		(min_thickness 0.25)
		(keepout
			(tracks not_allowed)
			(vias allowed)
			(pads allowed)
			(copperpour not_allowed)
			(footprints allowed)
		)
		(placement
			(enabled no)
			(sheetname "")
		)
		(fill yes
			(thermal_gap 0.5)
			(thermal_bridge_width 0.5)
			(island_removal_mode 0)
		)
		(polygon
			(pts
				(arc
					(start 275.076158 -317.749936)
					(mid 274.423378 -317.749936)
					(end 275.076158 -317.749936)
				)
			)
		)
	)
	(zone
		(layers "B.Cu" "In7.Cu" "In9.Cu" "In11.Cu" "In13.Cu" "In15.Cu")
		(hatch none 0.5)
		(connect_pads
			(clearance 0)
		)
		(min_thickness 0.25)
		(keepout
			(tracks not_allowed)
			(vias allowed)
			(pads allowed)
			(copperpour not_allowed)
			(footprints allowed)
		)
		(placement
			(enabled no)
			(sheetname "")
		)
		(fill yes
			(thermal_gap 0.5)
			(thermal_bridge_width 0.5)
			(island_removal_mode 0)
		)
		(polygon
			(pts
				(arc
					(start 426.326046 -275.949918)
					(mid 425.673266 -275.949918)
					(end 426.326046 -275.949918)
				)
			)
		)
	)
	(zone
		(layers "B.Cu" "In7.Cu" "In9.Cu" "In11.Cu" "In13.Cu" "In15.Cu")
		(hatch none 0.5)
		(connect_pads
			(clearance 0)
		)
		(min_thickness 0.25)
		(keepout
			(tracks not_allowed)
			(vias allowed)
			(pads allowed)
			(copperpour not_allowed)
			(footprints allowed)
		)
		(placement
			(enabled no)
			(sheetname "")
		)
		(fill yes
			(thermal_gap 0.5)
			(thermal_bridge_width 0.5)
			(island_removal_mode 0)
		)
		(polygon
			(pts
				(arc
					(start 54.44871 -122.822716)
					(mid 53.74513 -122.822716)
					(end 54.44871 -122.822716)
				)
			)
		)
	)
	(zone
		(layers "B.Cu" "In7.Cu" "In9.Cu" "In11.Cu" "In13.Cu" "In15.Cu")
		(hatch none 0.5)
		(connect_pads
			(clearance 0)
		)
		(min_thickness 0.25)
		(keepout
			(tracks not_allowed)
			(vias allowed)
			(pads allowed)
			(copperpour not_allowed)
			(footprints allowed)
		)
		(placement
			(enabled no)
			(sheetname "")
		)
		(fill yes
			(thermal_gap 0.5)
			(thermal_bridge_width 0.5)
			(island_removal_mode 0)
		)
		(polygon
			(pts
				(arc
					(start 408.276044 -274.04949)
					(mid 407.623264 -274.04949)
					(end 408.276044 -274.04949)
				)
			)
		)
	)
	(zone
		(layers "B.Cu" "In7.Cu" "In9.Cu" "In11.Cu" "In13.Cu" "In15.Cu")
		(hatch none 0.5)
		(connect_pads
			(clearance 0)
		)
		(min_thickness 0.25)
		(keepout
			(tracks not_allowed)
			(vias allowed)
			(pads allowed)
			(copperpour not_allowed)
			(footprints allowed)
		)
		(placement
			(enabled no)
			(sheetname "")
		)
		(fill yes
			(thermal_gap 0.5)
			(thermal_bridge_width 0.5)
			(island_removal_mode 0)
		)
		(polygon
			(pts
				(arc
					(start 183.508904 -134.377176)
					(mid 182.805324 -134.377176)
					(end 183.508904 -134.377176)
				)
			)
		)
	)
	(zone
		(layers "B.Cu" "In7.Cu" "In9.Cu" "In11.Cu" "In13.Cu" "In15.Cu")
		(hatch none 0.5)
		(connect_pads
			(clearance 0)
		)
		(min_thickness 0.25)
		(keepout
			(tracks not_allowed)
			(vias allowed)
			(pads allowed)
			(copperpour not_allowed)
			(footprints allowed)
		)
		(placement
			(enabled no)
			(sheetname "")
		)
		(fill yes
			(thermal_gap 0.5)
			(thermal_bridge_width 0.5)
			(island_removal_mode 0)
		)
		(polygon
			(pts
				(arc
					(start 76.689712 -371.790214)
					(mid 75.930252 -371.790214)
					(end 76.689712 -371.790214)
				)
			)
		)
	)
	(zone
		(layers "B.Cu" "In7.Cu" "In9.Cu" "In11.Cu" "In13.Cu" "In15.Cu")
		(hatch none 0.5)
		(connect_pads
			(clearance 0)
		)
		(min_thickness 0.25)
		(keepout
			(tracks not_allowed)
			(vias allowed)
			(pads allowed)
			(copperpour not_allowed)
			(footprints allowed)
		)
		(placement
			(enabled no)
			(sheetname "")
		)
		(fill yes
			(thermal_gap 0.5)
			(thermal_bridge_width 0.5)
			(island_removal_mode 0)
		)
		(polygon
			(pts
				(arc
					(start 420.626032 -275.949664)
					(mid 419.973252 -275.949664)
					(end 420.626032 -275.949664)
				)
			)
		)
	)
	(zone
		(layers "B.Cu" "In7.Cu" "In9.Cu" "In11.Cu" "In13.Cu" "In15.Cu")
		(hatch none 0.5)
		(connect_pads
			(clearance 0)
		)
		(min_thickness 0.25)
		(keepout
			(tracks not_allowed)
			(vias allowed)
			(pads allowed)
			(copperpour not_allowed)
			(footprints allowed)
		)
		(placement
			(enabled no)
			(sheetname "")
		)
		(fill yes
			(thermal_gap 0.5)
			(thermal_bridge_width 0.5)
			(island_removal_mode 0)
		)
		(polygon
			(pts
				(arc
					(start 181.654704 -152.487376)
					(mid 180.951124 -152.487376)
					(end 181.654704 -152.487376)
				)
			)
		)
	)
	(zone
		(layers "B.Cu" "In7.Cu" "In9.Cu" "In11.Cu" "In13.Cu" "In15.Cu")
		(hatch none 0.5)
		(connect_pads
			(clearance 0)
		)
		(min_thickness 0.25)
		(keepout
			(tracks not_allowed)
			(vias allowed)
			(pads allowed)
			(copperpour not_allowed)
			(footprints allowed)
		)
		(placement
			(enabled no)
			(sheetname "")
		)
		(fill yes
			(thermal_gap 0.5)
			(thermal_bridge_width 0.5)
			(island_removal_mode 0)
		)
		(polygon
			(pts
				(arc
					(start 433.069492 -379.590046)
					(mid 432.310032 -379.590046)
					(end 433.069492 -379.590046)
				)
			)
		)
	)
	(zone
		(layers "B.Cu" "In7.Cu" "In9.Cu" "In11.Cu" "In13.Cu" "In15.Cu")
		(hatch none 0.5)
		(connect_pads
			(clearance 0)
		)
		(min_thickness 0.25)
		(keepout
			(tracks not_allowed)
			(vias allowed)
			(pads allowed)
			(copperpour not_allowed)
			(footprints allowed)
		)
		(placement
			(enabled no)
			(sheetname "")
		)
		(fill yes
			(thermal_gap 0.5)
			(thermal_bridge_width 0.5)
			(island_removal_mode 0)
		)
		(polygon
			(pts
				(arc
					(start 429.17618 -286.399732)
					(mid 428.5234 -286.399732)
					(end 429.17618 -286.399732)
				)
			)
		)
	)
	(zone
		(layers "B.Cu" "In7.Cu" "In9.Cu" "In11.Cu" "In13.Cu" "In15.Cu")
		(hatch none 0.5)
		(connect_pads
			(clearance 0)
		)
		(min_thickness 0.25)
		(keepout
			(tracks not_allowed)
			(vias allowed)
			(pads allowed)
			(copperpour not_allowed)
			(footprints allowed)
		)
		(placement
			(enabled no)
			(sheetname "")
		)
		(fill yes
			(thermal_gap 0.5)
			(thermal_bridge_width 0.5)
			(island_removal_mode 0)
		)
		(polygon
			(pts
				(arc
					(start 345.069668 -371.790214)
					(mid 344.310208 -371.790214)
					(end 345.069668 -371.790214)
				)
			)
		)
	)
	(zone
		(layers "B.Cu" "In7.Cu" "In9.Cu" "In11.Cu" "In13.Cu" "In15.Cu")
		(hatch none 0.5)
		(connect_pads
			(clearance 0)
		)
		(min_thickness 0.25)
		(keepout
			(tracks not_allowed)
			(vias allowed)
			(pads allowed)
			(copperpour not_allowed)
			(footprints allowed)
		)
		(placement
			(enabled no)
			(sheetname "")
		)
		(fill yes
			(thermal_gap 0.5)
			(thermal_bridge_width 0.5)
			(island_removal_mode 0)
		)
		(polygon
			(pts
				(arc
					(start 79.92618 -286.399732)
					(mid 79.2734 -286.399732)
					(end 79.92618 -286.399732)
				)
			)
		)
	)
	(zone
		(layers "B.Cu" "In7.Cu" "In9.Cu" "In11.Cu" "In13.Cu" "In15.Cu")
		(hatch none 0.5)
		(connect_pads
			(clearance 0)
		)
		(min_thickness 0.25)
		(keepout
			(tracks not_allowed)
			(vias allowed)
			(pads allowed)
			(copperpour not_allowed)
			(footprints allowed)
		)
		(placement
			(enabled no)
			(sheetname "")
		)
		(fill yes
			(thermal_gap 0.5)
			(thermal_bridge_width 0.5)
			(island_removal_mode 0)
		)
		(polygon
			(pts
				(arc
					(start 196.975984 -273.099784)
					(mid 196.323204 -273.099784)
					(end 196.975984 -273.099784)
				)
			)
		)
	)
	(zone
		(layers "B.Cu" "In7.Cu" "In9.Cu" "In11.Cu" "In13.Cu" "In15.Cu")
		(hatch none 0.5)
		(connect_pads
			(clearance 0)
		)
		(min_thickness 0.25)
		(keepout
			(tracks not_allowed)
			(vias allowed)
			(pads allowed)
			(copperpour not_allowed)
			(footprints allowed)
		)
		(placement
			(enabled no)
			(sheetname "")
		)
		(fill yes
			(thermal_gap 0.5)
			(thermal_bridge_width 0.5)
			(island_removal_mode 0)
		)
		(polygon
			(pts
				(arc
					(start 413.8549 -124.103638)
					(mid 413.15132 -124.103638)
					(end 413.8549 -124.103638)
				)
			)
		)
	)
	(zone
		(layers "B.Cu" "In7.Cu" "In9.Cu" "In11.Cu" "In13.Cu" "In15.Cu")
		(hatch none 0.5)
		(connect_pads
			(clearance 0)
		)
		(min_thickness 0.25)
		(keepout
			(tracks not_allowed)
			(vias allowed)
			(pads allowed)
			(copperpour not_allowed)
			(footprints allowed)
		)
		(placement
			(enabled no)
			(sheetname "")
		)
		(fill yes
			(thermal_gap 0.5)
			(thermal_bridge_width 0.5)
			(island_removal_mode 0)
		)
		(polygon
			(pts
				(arc
					(start 67.40906 -118.703598)
					(mid 66.70548 -118.703598)
					(end 67.40906 -118.703598)
				)
			)
		)
	)
	(zone
		(layers "B.Cu" "In7.Cu" "In9.Cu" "In11.Cu" "In13.Cu" "In15.Cu")
		(hatch none 0.5)
		(connect_pads
			(clearance 0)
		)
		(min_thickness 0.25)
		(keepout
			(tracks not_allowed)
			(vias allowed)
			(pads allowed)
			(copperpour not_allowed)
			(footprints allowed)
		)
		(placement
			(enabled no)
			(sheetname "")
		)
		(fill yes
			(thermal_gap 0.5)
			(thermal_bridge_width 0.5)
			(island_removal_mode 0)
		)
		(polygon
			(pts
				(arc
					(start 127.289814 -398.890236)
					(mid 126.530354 -398.890236)
					(end 127.289814 -398.890236)
				)
			)
		)
	)
	(zone
		(layers "B.Cu" "In7.Cu" "In9.Cu" "In11.Cu" "In13.Cu" "In15.Cu")
		(hatch none 0.5)
		(connect_pads
			(clearance 0)
		)
		(min_thickness 0.25)
		(keepout
			(tracks not_allowed)
			(vias allowed)
			(pads allowed)
			(copperpour not_allowed)
			(footprints allowed)
		)
		(placement
			(enabled no)
			(sheetname "")
		)
		(fill yes
			(thermal_gap 0.5)
			(thermal_bridge_width 0.5)
			(island_removal_mode 0)
		)
		(polygon
			(pts
				(arc
					(start 169.426382 -315.849762)
					(mid 168.773602 -315.849762)
					(end 169.426382 -315.849762)
				)
			)
		)
	)
	(zone
		(layers "B.Cu" "In7.Cu" "In9.Cu" "In11.Cu" "In13.Cu" "In15.Cu")
		(hatch none 0.5)
		(connect_pads
			(clearance 0)
		)
		(min_thickness 0.25)
		(keepout
			(tracks not_allowed)
			(vias allowed)
			(pads allowed)
			(copperpour not_allowed)
			(footprints allowed)
		)
		(placement
			(enabled no)
			(sheetname "")
		)
		(fill yes
			(thermal_gap 0.5)
			(thermal_bridge_width 0.5)
			(island_removal_mode 0)
		)
		(polygon
			(pts
				(arc
					(start 38.126162 -308.249828)
					(mid 37.473382 -308.249828)
					(end 38.126162 -308.249828)
				)
			)
		)
	)
	(zone
		(layers "B.Cu" "In7.Cu" "In9.Cu" "In11.Cu" "In13.Cu" "In15.Cu")
		(hatch none 0.5)
		(connect_pads
			(clearance 0)
		)
		(min_thickness 0.25)
		(keepout
			(tracks not_allowed)
			(vias allowed)
			(pads allowed)
			(copperpour not_allowed)
			(footprints allowed)
		)
		(placement
			(enabled no)
			(sheetname "")
		)
		(fill yes
			(thermal_gap 0.5)
			(thermal_bridge_width 0.5)
			(island_removal_mode 0)
		)
		(polygon
			(pts
				(arc
					(start 87.68969 -372.890034)
					(mid 86.93023 -372.890034)
					(end 87.68969 -372.890034)
				)
			)
		)
	)
	(zone
		(layers "B.Cu" "In7.Cu" "In9.Cu" "In11.Cu" "In13.Cu" "In15.Cu")
		(hatch none 0.5)
		(connect_pads
			(clearance 0)
		)
		(min_thickness 0.25)
		(keepout
			(tracks not_allowed)
			(vias allowed)
			(pads allowed)
			(copperpour not_allowed)
			(footprints allowed)
		)
		(placement
			(enabled no)
			(sheetname "")
		)
		(fill yes
			(thermal_gap 0.5)
			(thermal_bridge_width 0.5)
			(island_removal_mode 0)
		)
		(polygon
			(pts
				(arc
					(start 271.276318 -301.599854)
					(mid 270.623538 -301.599854)
					(end 271.276318 -301.599854)
				)
			)
		)
	)
	(zone
		(layers "B.Cu" "In7.Cu" "In9.Cu" "In11.Cu" "In13.Cu" "In15.Cu")
		(hatch none 0.5)
		(connect_pads
			(clearance 0)
		)
		(min_thickness 0.25)
		(keepout
			(tracks not_allowed)
			(vias allowed)
			(pads allowed)
			(copperpour not_allowed)
			(footprints allowed)
		)
		(placement
			(enabled no)
			(sheetname "")
		)
		(fill yes
			(thermal_gap 0.5)
			(thermal_bridge_width 0.5)
			(island_removal_mode 0)
		)
		(polygon
			(pts
				(arc
					(start 400.89455 -121.886472)
					(mid 400.19097 -121.886472)
					(end 400.89455 -121.886472)
				)
			)
		)
	)
	(zone
		(layers "B.Cu" "In7.Cu" "In9.Cu" "In11.Cu" "In13.Cu" "In15.Cu")
		(hatch none 0.5)
		(connect_pads
			(clearance 0)
		)
		(min_thickness 0.25)
		(keepout
			(tracks not_allowed)
			(vias allowed)
			(pads allowed)
			(copperpour not_allowed)
			(footprints allowed)
		)
		(placement
			(enabled no)
			(sheetname "")
		)
		(fill yes
			(thermal_gap 0.5)
			(thermal_bridge_width 0.5)
			(island_removal_mode 0)
		)
		(polygon
			(pts
				(arc
					(start 386.869686 -375.490232)
					(mid 386.110226 -375.490232)
					(end 386.869686 -375.490232)
				)
			)
		)
	)
	(zone
		(layers "B.Cu" "In7.Cu" "In9.Cu" "In11.Cu" "In13.Cu" "In15.Cu")
		(hatch none 0.5)
		(connect_pads
			(clearance 0)
		)
		(min_thickness 0.25)
		(keepout
			(tracks not_allowed)
			(vias allowed)
			(pads allowed)
			(copperpour not_allowed)
			(footprints allowed)
		)
		(placement
			(enabled no)
			(sheetname "")
		)
		(fill yes
			(thermal_gap 0.5)
			(thermal_bridge_width 0.5)
			(island_removal_mode 0)
		)
		(polygon
			(pts
				(arc
					(start 85.489542 -371.790214)
					(mid 84.730082 -371.790214)
					(end 85.489542 -371.790214)
				)
			)
		)
	)
	(zone
		(layers "B.Cu" "In7.Cu" "In9.Cu" "In11.Cu" "In13.Cu" "In15.Cu")
		(hatch none 0.5)
		(connect_pads
			(clearance 0)
		)
		(min_thickness 0.25)
		(keepout
			(tracks not_allowed)
			(vias allowed)
			(pads allowed)
			(copperpour not_allowed)
			(footprints allowed)
		)
		(placement
			(enabled no)
			(sheetname "")
		)
		(fill yes
			(thermal_gap 0.5)
			(thermal_bridge_width 0.5)
			(island_removal_mode 0)
		)
		(polygon
			(pts
				(arc
					(start 83.289648 -372.890034)
					(mid 82.530188 -372.890034)
					(end 83.289648 -372.890034)
				)
			)
		)
	)
	(zone
		(layers "B.Cu" "In7.Cu" "In9.Cu" "In11.Cu" "In13.Cu" "In15.Cu")
		(hatch none 0.5)
		(connect_pads
			(clearance 0)
		)
		(min_thickness 0.25)
		(keepout
			(tracks not_allowed)
			(vias allowed)
			(pads allowed)
			(copperpour not_allowed)
			(footprints allowed)
		)
		(placement
			(enabled no)
			(sheetname "")
		)
		(fill yes
			(thermal_gap 0.5)
			(thermal_bridge_width 0.5)
			(island_removal_mode 0)
		)
		(polygon
			(pts
				(arc
					(start 43.689778 -409.290012)
					(mid 42.930318 -409.290012)
					(end 43.689778 -409.290012)
				)
			)
		)
	)
	(zone
		(layers "B.Cu" "In7.Cu" "In9.Cu" "In11.Cu" "In13.Cu" "In15.Cu")
		(hatch none 0.5)
		(connect_pads
			(clearance 0)
		)
		(min_thickness 0.25)
		(keepout
			(tracks not_allowed)
			(vias allowed)
			(pads allowed)
			(copperpour not_allowed)
			(footprints allowed)
		)
		(placement
			(enabled no)
			(sheetname "")
		)
		(fill yes
			(thermal_gap 0.5)
			(thermal_bridge_width 0.5)
			(island_removal_mode 0)
		)
		(polygon
			(pts
				(arc
					(start 300.72584 -275.949664)
					(mid 300.07306 -275.949664)
					(end 300.72584 -275.949664)
				)
			)
		)
	)
	(zone
		(layers "B.Cu" "In7.Cu" "In9.Cu" "In11.Cu" "In13.Cu" "In15.Cu")
		(hatch none 0.5)
		(connect_pads
			(clearance 0)
		)
		(min_thickness 0.25)
		(keepout
			(tracks not_allowed)
			(vias allowed)
			(pads allowed)
			(copperpour not_allowed)
			(footprints allowed)
		)
		(placement
			(enabled no)
			(sheetname "")
		)
		(fill yes
			(thermal_gap 0.5)
			(thermal_bridge_width 0.5)
			(island_removal_mode 0)
		)
		(polygon
			(pts
				(arc
					(start 287.86963 -409.490164)
					(mid 287.11017 -409.490164)
					(end 287.86963 -409.490164)
				)
			)
		)
	)
	(zone
		(layers "B.Cu" "In7.Cu" "In9.Cu" "In11.Cu" "In13.Cu" "In15.Cu")
		(hatch none 0.5)
		(connect_pads
			(clearance 0)
		)
		(min_thickness 0.25)
		(keepout
			(tracks not_allowed)
			(vias allowed)
			(pads allowed)
			(copperpour not_allowed)
			(footprints allowed)
		)
		(placement
			(enabled no)
			(sheetname "")
		)
		(fill yes
			(thermal_gap 0.5)
			(thermal_bridge_width 0.5)
			(island_removal_mode 0)
		)
		(polygon
			(pts
				(arc
					(start 168.694354 -104.71277)
					(mid 167.990774 -104.71277)
					(end 168.694354 -104.71277)
				)
			)
		)
	)
	(zone
		(layers "B.Cu" "In7.Cu" "In9.Cu" "In11.Cu" "In13.Cu" "In15.Cu")
		(hatch none 0.5)
		(connect_pads
			(clearance 0)
		)
		(min_thickness 0.25)
		(keepout
			(tracks not_allowed)
			(vias allowed)
			(pads allowed)
			(copperpour not_allowed)
			(footprints allowed)
		)
		(placement
			(enabled no)
			(sheetname "")
		)
		(fill yes
			(thermal_gap 0.5)
			(thermal_bridge_width 0.5)
			(island_removal_mode 0)
		)
		(polygon
			(pts
				(arc
					(start 81.089754 -401.690078)
					(mid 80.330294 -401.690078)
					(end 81.089754 -401.690078)
				)
			)
		)
	)
	(zone
		(layers "B.Cu" "In7.Cu" "In9.Cu" "In11.Cu" "In13.Cu" "In15.Cu")
		(hatch none 0.5)
		(connect_pads
			(clearance 0)
		)
		(min_thickness 0.25)
		(keepout
			(tracks not_allowed)
			(vias allowed)
			(pads allowed)
			(copperpour not_allowed)
			(footprints allowed)
		)
		(placement
			(enabled no)
			(sheetname "")
		)
		(fill yes
			(thermal_gap 0.5)
			(thermal_bridge_width 0.5)
			(island_removal_mode 0)
		)
		(polygon
			(pts
				(arc
					(start 272.226278 -307.299868)
					(mid 271.573498 -307.299868)
					(end 272.226278 -307.299868)
				)
			)
		)
	)
	(zone
		(layers "B.Cu" "In7.Cu" "In9.Cu" "In11.Cu" "In13.Cu" "In15.Cu")
		(hatch none 0.5)
		(connect_pads
			(clearance 0)
		)
		(min_thickness 0.25)
		(keepout
			(tracks not_allowed)
			(vias allowed)
			(pads allowed)
			(copperpour not_allowed)
			(footprints allowed)
		)
		(placement
			(enabled no)
			(sheetname "")
		)
		(fill yes
			(thermal_gap 0.5)
			(thermal_bridge_width 0.5)
			(island_removal_mode 0)
		)
		(polygon
			(pts
				(arc
					(start 286.648652 -119.222774)
					(mid 285.945072 -119.222774)
					(end 286.648652 -119.222774)
				)
			)
		)
	)
	(zone
		(layers "B.Cu" "In7.Cu" "In9.Cu" "In11.Cu" "In13.Cu" "In15.Cu")
		(hatch none 0.5)
		(connect_pads
			(clearance 0)
		)
		(min_thickness 0.25)
		(keepout
			(tracks not_allowed)
			(vias allowed)
			(pads allowed)
			(copperpour not_allowed)
			(footprints allowed)
		)
		(placement
			(enabled no)
			(sheetname "")
		)
		(fill yes
			(thermal_gap 0.5)
			(thermal_bridge_width 0.5)
			(island_removal_mode 0)
		)
		(polygon
			(pts
				(arc
					(start 170.548554 -122.822716)
					(mid 169.844974 -122.822716)
					(end 170.548554 -122.822716)
				)
			)
		)
	)
	(zone
		(layers "B.Cu" "In7.Cu" "In9.Cu" "In11.Cu" "In13.Cu" "In15.Cu")
		(hatch none 0.5)
		(connect_pads
			(clearance 0)
		)
		(min_thickness 0.25)
		(keepout
			(tracks not_allowed)
			(vias allowed)
			(pads allowed)
			(copperpour not_allowed)
			(footprints allowed)
		)
		(placement
			(enabled no)
			(sheetname "")
		)
		(fill yes
			(thermal_gap 0.5)
			(thermal_bridge_width 0.5)
			(island_removal_mode 0)
		)
		(polygon
			(pts
				(arc
					(start 336.269838 -401.690078)
					(mid 335.510378 -401.690078)
					(end 336.269838 -401.690078)
				)
			)
		)
	)
	(zone
		(layers "B.Cu" "In7.Cu" "In9.Cu" "In11.Cu" "In13.Cu" "In15.Cu")
		(hatch none 0.5)
		(connect_pads
			(clearance 0)
		)
		(min_thickness 0.25)
		(keepout
			(tracks not_allowed)
			(vias allowed)
			(pads allowed)
			(copperpour not_allowed)
			(footprints allowed)
		)
		(placement
			(enabled no)
			(sheetname "")
		)
		(fill yes
			(thermal_gap 0.5)
			(thermal_bridge_width 0.5)
			(island_removal_mode 0)
		)
		(polygon
			(pts
				(arc
					(start 125.08992 -375.69013)
					(mid 124.33046 -375.69013)
					(end 125.08992 -375.69013)
				)
			)
		)
	)
	(zone
		(layers "B.Cu" "In7.Cu" "In9.Cu" "In11.Cu" "In13.Cu" "In15.Cu")
		(hatch none 0.5)
		(connect_pads
			(clearance 0)
		)
		(min_thickness 0.25)
		(keepout
			(tracks not_allowed)
			(vias allowed)
			(pads allowed)
			(copperpour not_allowed)
			(footprints allowed)
		)
		(placement
			(enabled no)
			(sheetname "")
		)
		(fill yes
			(thermal_gap 0.5)
			(thermal_bridge_width 0.5)
			(island_removal_mode 0)
		)
		(polygon
			(pts
				(arc
					(start 301.676054 -273.099784)
					(mid 301.023274 -273.099784)
					(end 301.676054 -273.099784)
				)
			)
		)
	)
	(zone
		(layers "B.Cu" "In7.Cu" "In9.Cu" "In11.Cu" "In13.Cu" "In15.Cu")
		(hatch none 0.5)
		(connect_pads
			(clearance 0)
		)
		(min_thickness 0.25)
		(keepout
			(tracks not_allowed)
			(vias allowed)
			(pads allowed)
			(copperpour not_allowed)
			(footprints allowed)
		)
		(placement
			(enabled no)
			(sheetname "")
		)
		(fill yes
			(thermal_gap 0.5)
			(thermal_bridge_width 0.5)
			(island_removal_mode 0)
		)
		(polygon
			(pts
				(arc
					(start 380.26975 -397.790162)
					(mid 379.51029 -397.790162)
					(end 380.26975 -397.790162)
				)
			)
		)
	)
	(zone
		(layers "B.Cu" "In7.Cu" "In9.Cu" "In11.Cu" "In13.Cu" "In15.Cu")
		(hatch none 0.5)
		(connect_pads
			(clearance 0)
		)
		(min_thickness 0.25)
		(keepout
			(tracks not_allowed)
			(vias allowed)
			(pads allowed)
			(copperpour not_allowed)
			(footprints allowed)
		)
		(placement
			(enabled no)
			(sheetname "")
		)
		(fill yes
			(thermal_gap 0.5)
			(thermal_bridge_width 0.5)
			(island_removal_mode 0)
		)
		(polygon
			(pts
				(arc
					(start 40.026336 -307.299868)
					(mid 39.373556 -307.299868)
					(end 40.026336 -307.299868)
				)
			)
		)
	)
	(zone
		(layers "B.Cu" "In7.Cu" "In9.Cu" "In11.Cu" "In13.Cu" "In15.Cu")
		(hatch none 0.5)
		(connect_pads
			(clearance 0)
		)
		(min_thickness 0.25)
		(keepout
			(tracks not_allowed)
			(vias allowed)
			(pads allowed)
			(copperpour not_allowed)
			(footprints allowed)
		)
		(placement
			(enabled no)
			(sheetname "")
		)
		(fill yes
			(thermal_gap 0.5)
			(thermal_bridge_width 0.5)
			(island_removal_mode 0)
		)
		(polygon
			(pts
				(arc
					(start 307.376068 -274.049744)
					(mid 306.723288 -274.049744)
					(end 307.376068 -274.049744)
				)
			)
		)
	)
	(zone
		(layers "B.Cu" "In7.Cu" "In9.Cu" "In11.Cu" "In13.Cu" "In15.Cu")
		(hatch none 0.5)
		(connect_pads
			(clearance 0)
		)
		(min_thickness 0.25)
		(keepout
			(tracks not_allowed)
			(vias allowed)
			(pads allowed)
			(copperpour not_allowed)
			(footprints allowed)
		)
		(placement
			(enabled no)
			(sheetname "")
		)
		(fill yes
			(thermal_gap 0.5)
			(thermal_bridge_width 0.5)
			(island_removal_mode 0)
		)
		(polygon
			(pts
				(arc
					(start 422.069514 -380.69012)
					(mid 421.310054 -380.69012)
					(end 422.069514 -380.69012)
				)
			)
		)
	)
	(zone
		(layers "B.Cu" "In7.Cu" "In9.Cu" "In11.Cu" "In13.Cu" "In15.Cu")
		(hatch none 0.5)
		(connect_pads
			(clearance 0)
		)
		(min_thickness 0.25)
		(keepout
			(tracks not_allowed)
			(vias allowed)
			(pads allowed)
			(copperpour not_allowed)
			(footprints allowed)
		)
		(placement
			(enabled no)
			(sheetname "")
		)
		(fill yes
			(thermal_gap 0.5)
			(thermal_bridge_width 0.5)
			(island_removal_mode 0)
		)
		(polygon
			(pts
				(arc
					(start 65.55486 -124.967238)
					(mid 64.85128 -124.967238)
					(end 65.55486 -124.967238)
				)
			)
		)
	)
	(zone
		(layers "B.Cu" "In7.Cu" "In9.Cu" "In11.Cu" "In13.Cu" "In15.Cu")
		(hatch none 0.5)
		(connect_pads
			(clearance 0)
		)
		(min_thickness 0.25)
		(keepout
			(tracks not_allowed)
			(vias allowed)
			(pads allowed)
			(copperpour not_allowed)
			(footprints allowed)
		)
		(placement
			(enabled no)
			(sheetname "")
		)
		(fill yes
			(thermal_gap 0.5)
			(thermal_bridge_width 0.5)
			(island_removal_mode 0)
		)
		(polygon
			(pts
				(arc
					(start 406.376378 -317.749936)
					(mid 405.723598 -317.749936)
					(end 406.376378 -317.749936)
				)
			)
		)
	)
	(zone
		(layers "B.Cu" "In7.Cu" "In9.Cu" "In11.Cu" "In13.Cu" "In15.Cu")
		(hatch none 0.5)
		(connect_pads
			(clearance 0)
		)
		(min_thickness 0.25)
		(keepout
			(tracks not_allowed)
			(vias allowed)
			(pads allowed)
			(copperpour not_allowed)
			(footprints allowed)
		)
		(placement
			(enabled no)
			(sheetname "")
		)
		(fill yes
			(thermal_gap 0.5)
			(thermal_bridge_width 0.5)
			(island_removal_mode 0)
		)
		(polygon
			(pts
				(arc
					(start 178.925982 -274.999958)
					(mid 178.273202 -274.999958)
					(end 178.925982 -274.999958)
				)
			)
		)
	)
	(zone
		(layers "B.Cu" "In7.Cu" "In9.Cu" "In11.Cu" "In13.Cu" "In15.Cu")
		(hatch none 0.5)
		(connect_pads
			(clearance 0)
		)
		(min_thickness 0.25)
		(keepout
			(tracks not_allowed)
			(vias allowed)
			(pads allowed)
			(copperpour not_allowed)
			(footprints allowed)
		)
		(placement
			(enabled no)
			(sheetname "")
		)
		(fill yes
			(thermal_gap 0.5)
			(thermal_bridge_width 0.5)
			(island_removal_mode 0)
		)
		(polygon
			(pts
				(arc
					(start 380.26975 -396.49019)
					(mid 379.51029 -396.49019)
					(end 380.26975 -396.49019)
				)
			)
		)
	)
	(zone
		(layers "B.Cu" "In7.Cu" "In9.Cu" "In11.Cu" "In13.Cu" "In15.Cu")
		(hatch none 0.5)
		(connect_pads
			(clearance 0)
		)
		(min_thickness 0.25)
		(keepout
			(tracks not_allowed)
			(vias allowed)
			(pads allowed)
			(copperpour not_allowed)
			(footprints allowed)
		)
		(placement
			(enabled no)
			(sheetname "")
		)
		(fill yes
			(thermal_gap 0.5)
			(thermal_bridge_width 0.5)
			(island_removal_mode 0)
		)
		(polygon
			(pts
				(arc
					(start 164.68979 -405.589994)
					(mid 163.93033 -405.589994)
					(end 164.68979 -405.589994)
				)
			)
		)
	)
	(zone
		(layers "B.Cu" "In7.Cu" "In9.Cu" "In11.Cu" "In13.Cu" "In15.Cu")
		(hatch none 0.5)
		(connect_pads
			(clearance 0)
		)
		(min_thickness 0.25)
		(keepout
			(tracks not_allowed)
			(vias allowed)
			(pads allowed)
			(copperpour not_allowed)
			(footprints allowed)
		)
		(placement
			(enabled no)
			(sheetname "")
		)
		(fill yes
			(thermal_gap 0.5)
			(thermal_bridge_width 0.5)
			(island_removal_mode 0)
		)
		(polygon
			(pts
				(arc
					(start 172.276262 -317.749936)
					(mid 171.623482 -317.749936)
					(end 172.276262 -317.749936)
				)
			)
		)
	)
	(zone
		(layers "B.Cu" "In7.Cu" "In9.Cu" "In11.Cu" "In13.Cu" "In15.Cu")
		(hatch none 0.5)
		(connect_pads
			(clearance 0)
		)
		(min_thickness 0.25)
		(keepout
			(tracks not_allowed)
			(vias allowed)
			(pads allowed)
			(copperpour not_allowed)
			(footprints allowed)
		)
		(placement
			(enabled no)
			(sheetname "")
		)
		(fill yes
			(thermal_gap 0.5)
			(thermal_bridge_width 0.5)
			(island_removal_mode 0)
		)
		(polygon
			(pts
				(arc
					(start 286.648652 -120.086374)
					(mid 285.945072 -120.086374)
					(end 286.648652 -120.086374)
				)
			)
		)
	)
	(zone
		(layers "B.Cu" "In7.Cu" "In9.Cu" "In11.Cu" "In13.Cu" "In15.Cu")
		(hatch none 0.5)
		(connect_pads
			(clearance 0)
		)
		(min_thickness 0.25)
		(keepout
			(tracks not_allowed)
			(vias allowed)
			(pads allowed)
			(copperpour not_allowed)
			(footprints allowed)
		)
		(placement
			(enabled no)
			(sheetname "")
		)
		(fill yes
			(thermal_gap 0.5)
			(thermal_bridge_width 0.5)
			(island_removal_mode 0)
		)
		(polygon
			(pts
				(arc
					(start 306.425854 -275.949918)
					(mid 305.773074 -275.949918)
					(end 306.425854 -275.949918)
				)
			)
		)
	)
	(zone
		(layers "B.Cu" "In7.Cu" "In9.Cu" "In11.Cu" "In13.Cu" "In15.Cu")
		(hatch none 0.5)
		(connect_pads
			(clearance 0)
		)
		(min_thickness 0.25)
		(keepout
			(tracks not_allowed)
			(vias allowed)
			(pads allowed)
			(copperpour not_allowed)
			(footprints allowed)
		)
		(placement
			(enabled no)
			(sheetname "")
		)
		(fill yes
			(thermal_gap 0.5)
			(thermal_bridge_width 0.5)
			(island_removal_mode 0)
		)
		(polygon
			(pts
				(arc
					(start 173.226476 -316.799722)
					(mid 172.573696 -316.799722)
					(end 173.226476 -316.799722)
				)
			)
		)
	)
	(zone
		(layers "B.Cu" "In7.Cu" "In9.Cu" "In11.Cu" "In13.Cu" "In15.Cu")
		(hatch none 0.5)
		(connect_pads
			(clearance 0)
		)
		(min_thickness 0.25)
		(keepout
			(tracks not_allowed)
			(vias allowed)
			(pads allowed)
			(copperpour not_allowed)
			(footprints allowed)
		)
		(placement
			(enabled no)
			(sheetname "")
		)
		(fill yes
			(thermal_gap 0.5)
			(thermal_bridge_width 0.5)
			(island_removal_mode 0)
		)
		(polygon
			(pts
				(arc
					(start 74.225912 -274.999958)
					(mid 73.573132 -274.999958)
					(end 74.225912 -274.999958)
				)
			)
		)
	)
	(zone
		(layers "B.Cu" "In7.Cu" "In9.Cu" "In11.Cu" "In13.Cu" "In15.Cu")
		(hatch none 0.5)
		(connect_pads
			(clearance 0)
		)
		(min_thickness 0.25)
		(keepout
			(tracks not_allowed)
			(vias allowed)
			(pads allowed)
			(copperpour not_allowed)
			(footprints allowed)
		)
		(placement
			(enabled no)
			(sheetname "")
		)
		(fill yes
			(thermal_gap 0.5)
			(thermal_bridge_width 0.5)
			(island_removal_mode 0)
		)
		(polygon
			(pts
				(arc
					(start 65.676018 -274.049744)
					(mid 65.023238 -274.049744)
					(end 65.676018 -274.049744)
				)
			)
		)
	)
	(zone
		(layers "B.Cu" "In7.Cu" "In9.Cu" "In11.Cu" "In13.Cu" "In15.Cu")
		(hatch none 0.5)
		(connect_pads
			(clearance 0)
		)
		(min_thickness 0.25)
		(keepout
			(tracks not_allowed)
			(vias allowed)
			(pads allowed)
			(copperpour not_allowed)
			(footprints allowed)
		)
		(placement
			(enabled no)
			(sheetname "")
		)
		(fill yes
			(thermal_gap 0.5)
			(thermal_bridge_width 0.5)
			(island_removal_mode 0)
		)
		(polygon
			(pts
				(arc
					(start 177.976276 -317.749936)
					(mid 177.323496 -317.749936)
					(end 177.976276 -317.749936)
				)
			)
		)
	)
	(zone
		(layers "B.Cu" "In7.Cu" "In9.Cu" "In11.Cu" "In13.Cu" "In15.Cu")
		(hatch none 0.5)
		(connect_pads
			(clearance 0)
		)
		(min_thickness 0.25)
		(keepout
			(tracks not_allowed)
			(vias allowed)
			(pads allowed)
			(copperpour not_allowed)
			(footprints allowed)
		)
		(placement
			(enabled no)
			(sheetname "")
		)
		(fill yes
			(thermal_gap 0.5)
			(thermal_bridge_width 0.5)
			(island_removal_mode 0)
		)
		(polygon
			(pts
				(arc
					(start 175.689768 -380.69012)
					(mid 174.930308 -380.69012)
					(end 175.689768 -380.69012)
				)
			)
		)
	)
	(zone
		(layers "B.Cu" "In7.Cu" "In9.Cu" "In11.Cu" "In13.Cu" "In15.Cu")
		(hatch none 0.5)
		(connect_pads
			(clearance 0)
		)
		(min_thickness 0.25)
		(keepout
			(tracks not_allowed)
			(vias allowed)
			(pads allowed)
			(copperpour not_allowed)
			(footprints allowed)
		)
		(placement
			(enabled no)
			(sheetname "")
		)
		(fill yes
			(thermal_gap 0.5)
			(thermal_bridge_width 0.5)
			(island_removal_mode 0)
		)
		(polygon
			(pts
				(arc
					(start 408.276044 -273.09953)
					(mid 407.623264 -273.09953)
					(end 408.276044 -273.09953)
				)
			)
		)
	)
	(zone
		(layers "B.Cu" "In7.Cu" "In9.Cu" "In11.Cu" "In13.Cu" "In15.Cu")
		(hatch none 0.5)
		(connect_pads
			(clearance 0)
		)
		(min_thickness 0.25)
		(keepout
			(tracks not_allowed)
			(vias allowed)
			(pads allowed)
			(copperpour not_allowed)
			(footprints allowed)
		)
		(placement
			(enabled no)
			(sheetname "")
		)
		(fill yes
			(thermal_gap 0.5)
			(thermal_bridge_width 0.5)
			(island_removal_mode 0)
		)
		(polygon
			(pts
				(arc
					(start 303.576228 -317.749936)
					(mid 302.923448 -317.749936)
					(end 303.576228 -317.749936)
				)
			)
		)
	)
	(zone
		(layers "B.Cu" "In7.Cu" "In9.Cu" "In11.Cu" "In13.Cu" "In15.Cu")
		(hatch none 0.5)
		(connect_pads
			(clearance 0)
		)
		(min_thickness 0.25)
		(keepout
			(tracks not_allowed)
			(vias allowed)
			(pads allowed)
			(copperpour not_allowed)
			(footprints allowed)
		)
		(placement
			(enabled no)
			(sheetname "")
		)
		(fill yes
			(thermal_gap 0.5)
			(thermal_bridge_width 0.5)
			(island_removal_mode 0)
		)
		(polygon
			(pts
				(arc
					(start 301.069502 -409.490164)
					(mid 300.310042 -409.490164)
					(end 301.069502 -409.490164)
				)
			)
		)
	)
	(zone
		(layers "B.Cu" "In7.Cu" "In9.Cu" "In11.Cu" "In13.Cu" "In15.Cu")
		(hatch none 0.5)
		(connect_pads
			(clearance 0)
		)
		(min_thickness 0.25)
		(keepout
			(tracks not_allowed)
			(vias allowed)
			(pads allowed)
			(copperpour not_allowed)
			(footprints allowed)
		)
		(placement
			(enabled no)
			(sheetname "")
		)
		(fill yes
			(thermal_gap 0.5)
			(thermal_bridge_width 0.5)
			(island_removal_mode 0)
		)
		(polygon
			(pts
				(arc
					(start 183.508904 -130.777234)
					(mid 182.805324 -130.777234)
					(end 183.508904 -130.777234)
				)
			)
		)
	)
	(zone
		(layers "B.Cu" "In7.Cu" "In9.Cu" "In11.Cu" "In13.Cu" "In15.Cu")
		(hatch none 0.5)
		(connect_pads
			(clearance 0)
		)
		(min_thickness 0.25)
		(keepout
			(tracks not_allowed)
			(vias allowed)
			(pads allowed)
			(copperpour not_allowed)
			(footprints allowed)
		)
		(placement
			(enabled no)
			(sheetname "")
		)
		(fill yes
			(thermal_gap 0.5)
			(thermal_bridge_width 0.5)
			(island_removal_mode 0)
		)
		(polygon
			(pts
				(arc
					(start 34.889694 -383.290064)
					(mid 34.130234 -383.290064)
					(end 34.889694 -383.290064)
				)
			)
		)
	)
	(zone
		(layers "B.Cu" "In7.Cu" "In9.Cu" "In11.Cu" "In13.Cu" "In15.Cu")
		(hatch none 0.5)
		(connect_pads
			(clearance 0)
		)
		(min_thickness 0.25)
		(keepout
			(tracks not_allowed)
			(vias allowed)
			(pads allowed)
			(copperpour not_allowed)
			(footprints allowed)
		)
		(placement
			(enabled no)
			(sheetname "")
		)
		(fill yes
			(thermal_gap 0.5)
			(thermal_bridge_width 0.5)
			(island_removal_mode 0)
		)
		(polygon
			(pts
				(arc
					(start 65.55486 -121.367296)
					(mid 64.85128 -121.367296)
					(end 65.55486 -121.367296)
				)
			)
		)
	)
	(zone
		(layers "B.Cu" "In7.Cu" "In9.Cu" "In11.Cu" "In13.Cu" "In15.Cu")
		(hatch none 0.5)
		(connect_pads
			(clearance 0)
		)
		(min_thickness 0.25)
		(keepout
			(tracks not_allowed)
			(vias allowed)
			(pads allowed)
			(copperpour not_allowed)
			(footprints allowed)
		)
		(placement
			(enabled no)
			(sheetname "")
		)
		(fill yes
			(thermal_gap 0.5)
			(thermal_bridge_width 0.5)
			(island_removal_mode 0)
		)
		(polygon
			(pts
				(arc
					(start 286.648652 -123.686316)
					(mid 285.945072 -123.686316)
					(end 286.648652 -123.686316)
				)
			)
		)
	)
	(zone
		(layers "B.Cu" "In7.Cu" "In9.Cu" "In11.Cu" "In13.Cu" "In15.Cu")
		(hatch none 0.5)
		(connect_pads
			(clearance 0)
		)
		(min_thickness 0.25)
		(keepout
			(tracks not_allowed)
			(vias allowed)
			(pads allowed)
			(copperpour not_allowed)
			(footprints allowed)
		)
		(placement
			(enabled no)
			(sheetname "")
		)
		(fill yes
			(thermal_gap 0.5)
			(thermal_bridge_width 0.5)
			(island_removal_mode 0)
		)
		(polygon
			(pts
				(arc
					(start 122.889772 -375.490232)
					(mid 122.130312 -375.490232)
					(end 122.889772 -375.490232)
				)
			)
		)
	)
	(zone
		(layers "B.Cu" "In7.Cu" "In9.Cu" "In11.Cu" "In13.Cu" "In15.Cu")
		(hatch none 0.5)
		(connect_pads
			(clearance 0)
		)
		(min_thickness 0.25)
		(keepout
			(tracks not_allowed)
			(vias allowed)
			(pads allowed)
			(copperpour not_allowed)
			(footprints allowed)
		)
		(placement
			(enabled no)
			(sheetname "")
		)
		(fill yes
			(thermal_gap 0.5)
			(thermal_bridge_width 0.5)
			(island_removal_mode 0)
		)
		(polygon
			(pts
				(arc
					(start 271.276318 -307.299868)
					(mid 270.623538 -307.299868)
					(end 271.276318 -307.299868)
				)
			)
		)
	)
	(zone
		(layers "B.Cu" "In7.Cu" "In9.Cu" "In11.Cu" "In13.Cu" "In15.Cu")
		(hatch none 0.5)
		(connect_pads
			(clearance 0)
		)
		(min_thickness 0.25)
		(keepout
			(tracks not_allowed)
			(vias allowed)
			(pads allowed)
			(copperpour not_allowed)
			(footprints allowed)
		)
		(placement
			(enabled no)
			(sheetname "")
		)
		(fill yes
			(thermal_gap 0.5)
			(thermal_bridge_width 0.5)
			(island_removal_mode 0)
		)
		(polygon
			(pts
				(arc
					(start 428.669704 -404.290022)
					(mid 427.910244 -404.290022)
					(end 428.669704 -404.290022)
				)
			)
		)
	)
	(zone
		(layers "B.Cu" "In7.Cu" "In9.Cu" "In11.Cu" "In13.Cu" "In15.Cu")
		(hatch none 0.5)
		(connect_pads
			(clearance 0)
		)
		(min_thickness 0.25)
		(keepout
			(tracks not_allowed)
			(vias allowed)
			(pads allowed)
			(copperpour not_allowed)
			(footprints allowed)
		)
		(placement
			(enabled no)
			(sheetname "")
		)
		(fill yes
			(thermal_gap 0.5)
			(thermal_bridge_width 0.5)
			(island_removal_mode 0)
		)
		(polygon
			(pts
				(arc
					(start 391.269728 -375.490232)
					(mid 390.510268 -375.490232)
					(end 391.269728 -375.490232)
				)
			)
		)
	)
	(zone
		(layers "B.Cu" "In7.Cu" "In9.Cu" "In11.Cu" "In13.Cu" "In15.Cu")
		(hatch none 0.5)
		(connect_pads
			(clearance 0)
		)
		(min_thickness 0.25)
		(keepout
			(tracks not_allowed)
			(vias allowed)
			(pads allowed)
			(copperpour not_allowed)
			(footprints allowed)
		)
		(placement
			(enabled no)
			(sheetname "")
		)
		(fill yes
			(thermal_gap 0.5)
			(thermal_bridge_width 0.5)
			(island_removal_mode 0)
		)
		(polygon
			(pts
				(arc
					(start 284.794452 -109.176312)
					(mid 284.090872 -109.176312)
					(end 284.794452 -109.176312)
				)
			)
		)
	)
	(zone
		(layers "B.Cu" "In7.Cu" "In9.Cu" "In11.Cu" "In13.Cu" "In15.Cu")
		(hatch none 0.5)
		(connect_pads
			(clearance 0)
		)
		(min_thickness 0.25)
		(keepout
			(tracks not_allowed)
			(vias allowed)
			(pads allowed)
			(copperpour not_allowed)
			(footprints allowed)
		)
		(placement
			(enabled no)
			(sheetname "")
		)
		(fill yes
			(thermal_gap 0.5)
			(thermal_bridge_width 0.5)
			(island_removal_mode 0)
		)
		(polygon
			(pts
				(arc
					(start 195.076318 -318.699896)
					(mid 194.423538 -318.699896)
					(end 195.076318 -318.699896)
				)
			)
		)
	)
	(zone
		(layers "B.Cu" "In7.Cu" "In9.Cu" "In11.Cu" "In13.Cu" "In15.Cu")
		(hatch none 0.5)
		(connect_pads
			(clearance 0)
		)
		(min_thickness 0.25)
		(keepout
			(tracks not_allowed)
			(vias allowed)
			(pads allowed)
			(copperpour not_allowed)
			(footprints allowed)
		)
		(placement
			(enabled no)
			(sheetname "")
		)
		(fill yes
			(thermal_gap 0.5)
			(thermal_bridge_width 0.5)
			(island_removal_mode 0)
		)
		(polygon
			(pts
				(arc
					(start 430.126394 -287.349946)
					(mid 429.473614 -287.349946)
					(end 430.126394 -287.349946)
				)
			)
		)
	)
	(zone
		(layers "B.Cu" "In7.Cu" "In9.Cu" "In11.Cu" "In13.Cu" "In15.Cu")
		(hatch none 0.5)
		(connect_pads
			(clearance 0)
		)
		(min_thickness 0.25)
		(keepout
			(tracks not_allowed)
			(vias allowed)
			(pads allowed)
			(copperpour not_allowed)
			(footprints allowed)
		)
		(placement
			(enabled no)
			(sheetname "")
		)
		(fill yes
			(thermal_gap 0.5)
			(thermal_bridge_width 0.5)
			(island_removal_mode 0)
		)
		(polygon
			(pts
				(arc
					(start 66.625978 -275.949918)
					(mid 65.973198 -275.949918)
					(end 66.625978 -275.949918)
				)
			)
		)
	)
	(zone
		(layers "B.Cu" "In7.Cu" "In9.Cu" "In11.Cu" "In13.Cu" "In15.Cu")
		(hatch none 0.5)
		(connect_pads
			(clearance 0)
		)
		(min_thickness 0.25)
		(keepout
			(tracks not_allowed)
			(vias allowed)
			(pads allowed)
			(copperpour not_allowed)
			(footprints allowed)
		)
		(placement
			(enabled no)
			(sheetname "")
		)
		(fill yes
			(thermal_gap 0.5)
			(thermal_bridge_width 0.5)
			(island_removal_mode 0)
		)
		(polygon
			(pts
				(arc
					(start 400.89455 -108.312712)
					(mid 400.19097 -108.312712)
					(end 400.89455 -108.312712)
				)
			)
		)
	)
	(zone
		(layers "B.Cu" "In7.Cu" "In9.Cu" "In11.Cu" "In13.Cu" "In15.Cu")
		(hatch none 0.5)
		(connect_pads
			(clearance 0)
		)
		(min_thickness 0.25)
		(keepout
			(tracks not_allowed)
			(vias allowed)
			(pads allowed)
			(copperpour not_allowed)
			(footprints allowed)
		)
		(placement
			(enabled no)
			(sheetname "")
		)
		(fill yes
			(thermal_gap 0.5)
			(thermal_bridge_width 0.5)
			(island_removal_mode 0)
		)
		(polygon
			(pts
				(arc
					(start 431.076354 -306.349908)
					(mid 430.423574 -306.349908)
					(end 431.076354 -306.349908)
				)
			)
		)
	)
	(zone
		(layers "B.Cu" "In7.Cu" "In9.Cu" "In11.Cu" "In13.Cu" "In15.Cu")
		(hatch none 0.5)
		(connect_pads
			(clearance 0)
		)
		(min_thickness 0.25)
		(keepout
			(tracks not_allowed)
			(vias allowed)
			(pads allowed)
			(copperpour not_allowed)
			(footprints allowed)
		)
		(placement
			(enabled no)
			(sheetname "")
		)
		(fill yes
			(thermal_gap 0.5)
			(thermal_bridge_width 0.5)
			(island_removal_mode 0)
		)
		(polygon
			(pts
				(arc
					(start 420.626032 -274.999704)
					(mid 419.973252 -274.999704)
					(end 420.626032 -274.999704)
				)
			)
		)
	)
	(zone
		(layers "B.Cu" "In7.Cu" "In9.Cu" "In11.Cu" "In13.Cu" "In15.Cu")
		(hatch none 0.5)
		(connect_pads
			(clearance 0)
		)
		(min_thickness 0.25)
		(keepout
			(tracks not_allowed)
			(vias allowed)
			(pads allowed)
			(copperpour not_allowed)
			(footprints allowed)
		)
		(placement
			(enabled no)
			(sheetname "")
		)
		(fill yes
			(thermal_gap 0.5)
			(thermal_bridge_width 0.5)
			(island_removal_mode 0)
		)
		(polygon
			(pts
				(arc
					(start 170.376342 -318.699896)
					(mid 169.723562 -318.699896)
					(end 170.376342 -318.699896)
				)
			)
		)
	)
	(zone
		(layers "B.Cu" "In7.Cu" "In9.Cu" "In11.Cu" "In13.Cu" "In15.Cu")
		(hatch none 0.5)
		(connect_pads
			(clearance 0)
		)
		(min_thickness 0.25)
		(keepout
			(tracks not_allowed)
			(vias allowed)
			(pads allowed)
			(copperpour not_allowed)
			(footprints allowed)
		)
		(placement
			(enabled no)
			(sheetname "")
		)
		(fill yes
			(thermal_gap 0.5)
			(thermal_bridge_width 0.5)
			(island_removal_mode 0)
		)
		(polygon
			(pts
				(arc
					(start 190.326264 -315.849762)
					(mid 189.673484 -315.849762)
					(end 190.326264 -315.849762)
				)
			)
		)
	)
	(zone
		(layers "B.Cu" "In7.Cu" "In9.Cu" "In11.Cu" "In13.Cu" "In15.Cu")
		(hatch none 0.5)
		(connect_pads
			(clearance 0)
		)
		(min_thickness 0.25)
		(keepout
			(tracks not_allowed)
			(vias allowed)
			(pads allowed)
			(copperpour not_allowed)
			(footprints allowed)
		)
		(placement
			(enabled no)
			(sheetname "")
		)
		(fill yes
			(thermal_gap 0.5)
			(thermal_bridge_width 0.5)
			(island_removal_mode 0)
		)
		(polygon
			(pts
				(arc
					(start 169.426382 -316.799722)
					(mid 168.773602 -316.799722)
					(end 169.426382 -316.799722)
				)
			)
		)
	)
	(zone
		(layers "B.Cu" "In7.Cu" "In9.Cu" "In11.Cu" "In13.Cu" "In15.Cu")
		(hatch none 0.5)
		(connect_pads
			(clearance 0)
		)
		(min_thickness 0.25)
		(keepout
			(tracks not_allowed)
			(vias allowed)
			(pads allowed)
			(copperpour not_allowed)
			(footprints allowed)
		)
		(placement
			(enabled no)
			(sheetname "")
		)
		(fill yes
			(thermal_gap 0.5)
			(thermal_bridge_width 0.5)
			(island_removal_mode 0)
		)
		(polygon
			(pts
				(arc
					(start 178.925982 -275.949918)
					(mid 178.273202 -275.949918)
					(end 178.925982 -275.949918)
				)
			)
		)
	)
	(zone
		(layers "B.Cu" "In7.Cu" "In9.Cu" "In11.Cu" "In13.Cu" "In15.Cu")
		(hatch none 0.5)
		(connect_pads
			(clearance 0)
		)
		(min_thickness 0.25)
		(keepout
			(tracks not_allowed)
			(vias allowed)
			(pads allowed)
			(copperpour not_allowed)
			(footprints allowed)
		)
		(placement
			(enabled no)
			(sheetname "")
		)
		(fill yes
			(thermal_gap 0.5)
			(thermal_bridge_width 0.5)
			(island_removal_mode 0)
		)
		(polygon
			(pts
				(arc
					(start 195.076064 -274.049744)
					(mid 194.423284 -274.049744)
					(end 195.076064 -274.049744)
				)
			)
		)
	)
	(zone
		(layers "B.Cu" "In7.Cu" "In9.Cu" "In11.Cu" "In13.Cu" "In15.Cu")
		(hatch none 0.5)
		(connect_pads
			(clearance 0)
		)
		(min_thickness 0.25)
		(keepout
			(tracks not_allowed)
			(vias allowed)
			(pads allowed)
			(copperpour not_allowed)
			(footprints allowed)
		)
		(placement
			(enabled no)
			(sheetname "")
		)
		(fill yes
			(thermal_gap 0.5)
			(thermal_bridge_width 0.5)
			(island_removal_mode 0)
		)
		(polygon
			(pts
				(arc
					(start 166.889684 -380.69012)
					(mid 166.130224 -380.69012)
					(end 166.889684 -380.69012)
				)
			)
		)
	)
	(zone
		(layers "B.Cu" "In7.Cu" "In9.Cu" "In11.Cu" "In13.Cu" "In15.Cu")
		(hatch none 0.5)
		(connect_pads
			(clearance 0)
		)
		(min_thickness 0.25)
		(keepout
			(tracks not_allowed)
			(vias allowed)
			(pads allowed)
			(copperpour not_allowed)
			(footprints allowed)
		)
		(placement
			(enabled no)
			(sheetname "")
		)
		(fill yes
			(thermal_gap 0.5)
			(thermal_bridge_width 0.5)
			(island_removal_mode 0)
		)
		(polygon
			(pts
				(arc
					(start 429.17618 -318.699896)
					(mid 428.5234 -318.699896)
					(end 429.17618 -318.699896)
				)
			)
		)
	)
	(zone
		(layers "B.Cu" "In7.Cu" "In9.Cu" "In11.Cu" "In13.Cu" "In15.Cu")
		(hatch none 0.5)
		(connect_pads
			(clearance 0)
		)
		(min_thickness 0.25)
		(keepout
			(tracks not_allowed)
			(vias allowed)
			(pads allowed)
			(copperpour not_allowed)
			(footprints allowed)
		)
		(placement
			(enabled no)
			(sheetname "")
		)
		(fill yes
			(thermal_gap 0.5)
			(thermal_bridge_width 0.5)
			(island_removal_mode 0)
		)
		(polygon
			(pts
				(arc
					(start 79.92618 -282.599892)
					(mid 79.2734 -282.599892)
					(end 79.92618 -282.599892)
				)
			)
		)
	)
	(zone
		(layers "B.Cu" "In7.Cu" "In9.Cu" "In11.Cu" "In13.Cu" "In15.Cu")
		(hatch none 0.5)
		(connect_pads
			(clearance 0)
		)
		(min_thickness 0.25)
		(keepout
			(tracks not_allowed)
			(vias allowed)
			(pads allowed)
			(copperpour not_allowed)
			(footprints allowed)
		)
		(placement
			(enabled no)
			(sheetname "")
		)
		(fill yes
			(thermal_gap 0.5)
			(thermal_bridge_width 0.5)
			(island_removal_mode 0)
		)
		(polygon
			(pts
				(arc
					(start 192.226184 -274.999704)
					(mid 191.573404 -274.999704)
					(end 192.226184 -274.999704)
				)
			)
		)
	)
	(zone
		(layers "B.Cu" "In7.Cu" "In9.Cu" "In11.Cu" "In13.Cu" "In15.Cu")
		(hatch none 0.5)
		(connect_pads
			(clearance 0)
		)
		(min_thickness 0.25)
		(keepout
			(tracks not_allowed)
			(vias allowed)
			(pads allowed)
			(copperpour not_allowed)
			(footprints allowed)
		)
		(placement
			(enabled no)
			(sheetname "")
		)
		(fill yes
			(thermal_gap 0.5)
			(thermal_bridge_width 0.5)
			(island_removal_mode 0)
		)
		(polygon
			(pts
				(arc
					(start 67.575938 -274.049744)
					(mid 66.923158 -274.049744)
					(end 67.575938 -274.049744)
				)
			)
		)
	)
	(zone
		(layers "B.Cu" "In7.Cu" "In9.Cu" "In11.Cu" "In13.Cu" "In15.Cu")
		(hatch none 0.5)
		(connect_pads
			(clearance 0)
		)
		(min_thickness 0.25)
		(keepout
			(tracks not_allowed)
			(vias allowed)
			(pads allowed)
			(copperpour not_allowed)
			(footprints allowed)
		)
		(placement
			(enabled no)
			(sheetname "")
		)
		(fill yes
			(thermal_gap 0.5)
			(thermal_bridge_width 0.5)
			(island_removal_mode 0)
		)
		(polygon
			(pts
				(arc
					(start 74.489564 -372.890034)
					(mid 73.730104 -372.890034)
					(end 74.489564 -372.890034)
				)
			)
		)
	)
	(zone
		(layers "B.Cu" "In7.Cu" "In9.Cu" "In11.Cu" "In13.Cu" "In15.Cu")
		(hatch none 0.5)
		(connect_pads
			(clearance 0)
		)
		(min_thickness 0.25)
		(keepout
			(tracks not_allowed)
			(vias allowed)
			(pads allowed)
			(copperpour not_allowed)
			(footprints allowed)
		)
		(placement
			(enabled no)
			(sheetname "")
		)
		(fill yes
			(thermal_gap 0.5)
			(thermal_bridge_width 0.5)
			(island_removal_mode 0)
		)
		(polygon
			(pts
				(arc
					(start 400.89455 -105.57637)
					(mid 400.19097 -105.57637)
					(end 400.89455 -105.57637)
				)
			)
		)
	)
	(zone
		(layers "B.Cu" "In7.Cu" "In9.Cu" "In11.Cu" "In13.Cu" "In15.Cu")
		(hatch none 0.5)
		(connect_pads
			(clearance 0)
		)
		(min_thickness 0.25)
		(keepout
			(tracks not_allowed)
			(vias allowed)
			(pads allowed)
			(copperpour not_allowed)
			(footprints allowed)
		)
		(placement
			(enabled no)
			(sheetname "")
		)
		(fill yes
			(thermal_gap 0.5)
			(thermal_bridge_width 0.5)
			(island_removal_mode 0)
		)
		(polygon
			(pts
				(arc
					(start 54.44871 -134.896352)
					(mid 53.74513 -134.896352)
					(end 54.44871 -134.896352)
				)
			)
		)
	)
	(zone
		(layers "B.Cu" "In7.Cu" "In9.Cu" "In11.Cu" "In13.Cu" "In15.Cu")
		(hatch none 0.5)
		(connect_pads
			(clearance 0)
		)
		(min_thickness 0.25)
		(keepout
			(tracks not_allowed)
			(vias allowed)
			(pads allowed)
			(copperpour not_allowed)
			(footprints allowed)
		)
		(placement
			(enabled no)
			(sheetname "")
		)
		(fill yes
			(thermal_gap 0.5)
			(thermal_bridge_width 0.5)
			(island_removal_mode 0)
		)
		(polygon
			(pts
				(arc
					(start 431.076354 -304.449734)
					(mid 430.423574 -304.449734)
					(end 431.076354 -304.449734)
				)
			)
		)
	)
	(zone
		(layers "B.Cu" "In7.Cu" "In9.Cu" "In11.Cu" "In13.Cu" "In15.Cu")
		(hatch none 0.5)
		(connect_pads
			(clearance 0)
		)
		(min_thickness 0.25)
		(keepout
			(tracks not_allowed)
			(vias allowed)
			(pads allowed)
			(copperpour not_allowed)
			(footprints allowed)
		)
		(placement
			(enabled no)
			(sheetname "")
		)
		(fill yes
			(thermal_gap 0.5)
			(thermal_bridge_width 0.5)
			(island_removal_mode 0)
		)
		(polygon
			(pts
				(arc
					(start 413.8549 -155.223718)
					(mid 413.15132 -155.223718)
					(end 413.8549 -155.223718)
				)
			)
		)
	)
	(zone
		(layers "B.Cu" "In7.Cu" "In9.Cu" "In11.Cu" "In13.Cu" "In15.Cu")
		(hatch none 0.5)
		(connect_pads
			(clearance 0)
		)
		(min_thickness 0.25)
		(keepout
			(tracks not_allowed)
			(vias allowed)
			(pads allowed)
			(copperpour not_allowed)
			(footprints allowed)
		)
		(placement
			(enabled no)
			(sheetname "")
		)
		(fill yes
			(thermal_gap 0.5)
			(thermal_bridge_width 0.5)
			(island_removal_mode 0)
		)
		(polygon
			(pts
				(arc
					(start 67.575938 -273.099784)
					(mid 66.923158 -273.099784)
					(end 67.575938 -273.099784)
				)
			)
		)
	)
	(zone
		(layers "B.Cu" "In7.Cu" "In9.Cu" "In11.Cu" "In13.Cu" "In15.Cu")
		(hatch none 0.5)
		(connect_pads
			(clearance 0)
		)
		(min_thickness 0.25)
		(keepout
			(tracks not_allowed)
			(vias allowed)
			(pads allowed)
			(copperpour not_allowed)
			(footprints allowed)
		)
		(placement
			(enabled no)
			(sheetname "")
		)
		(fill yes
			(thermal_gap 0.5)
			(thermal_bridge_width 0.5)
			(island_removal_mode 0)
		)
		(polygon
			(pts
				(arc
					(start 299.609002 -118.703598)
					(mid 298.905422 -118.703598)
					(end 299.609002 -118.703598)
				)
			)
		)
	)
	(zone
		(layers "B.Cu" "In7.Cu" "In9.Cu" "In11.Cu" "In13.Cu" "In15.Cu")
		(hatch none 0.5)
		(connect_pads
			(clearance 0)
		)
		(min_thickness 0.25)
		(keepout
			(tracks not_allowed)
			(vias allowed)
			(pads allowed)
			(copperpour not_allowed)
			(footprints allowed)
		)
		(placement
			(enabled no)
			(sheetname "")
		)
		(fill yes
			(thermal_gap 0.5)
			(thermal_bridge_width 0.5)
			(island_removal_mode 0)
		)
		(polygon
			(pts
				(arc
					(start 181.654704 -131.713732)
					(mid 180.951124 -131.713732)
					(end 181.654704 -131.713732)
				)
			)
		)
	)
	(zone
		(layers "B.Cu" "In7.Cu" "In9.Cu" "In11.Cu" "In13.Cu" "In15.Cu")
		(hatch none 0.5)
		(connect_pads
			(clearance 0)
		)
		(min_thickness 0.25)
		(keepout
			(tracks not_allowed)
			(vias allowed)
			(pads allowed)
			(copperpour not_allowed)
			(footprints allowed)
		)
		(placement
			(enabled no)
			(sheetname "")
		)
		(fill yes
			(thermal_gap 0.5)
			(thermal_bridge_width 0.5)
			(island_removal_mode 0)
		)
		(polygon
			(pts
				(arc
					(start 30.489652 -410.589984)
					(mid 29.730192 -410.589984)
					(end 30.489652 -410.589984)
				)
			)
		)
	)
	(zone
		(layers "B.Cu" "In7.Cu" "In9.Cu" "In11.Cu" "In13.Cu" "In15.Cu")
		(hatch none 0.5)
		(connect_pads
			(clearance 0)
		)
		(min_thickness 0.25)
		(keepout
			(tracks not_allowed)
			(vias allowed)
			(pads allowed)
			(copperpour not_allowed)
			(footprints allowed)
		)
		(placement
			(enabled no)
			(sheetname "")
		)
		(fill yes
			(thermal_gap 0.5)
			(thermal_bridge_width 0.5)
			(island_removal_mode 0)
		)
		(polygon
			(pts
				(arc
					(start 300.72584 -274.999704)
					(mid 300.07306 -274.999704)
					(end 300.72584 -274.999704)
				)
			)
		)
	)
	(zone
		(layers "B.Cu" "In7.Cu" "In9.Cu" "In11.Cu" "In13.Cu" "In15.Cu")
		(hatch none 0.5)
		(connect_pads
			(clearance 0)
		)
		(min_thickness 0.25)
		(keepout
			(tracks not_allowed)
			(vias allowed)
			(pads allowed)
			(copperpour not_allowed)
			(footprints allowed)
		)
		(placement
			(enabled no)
			(sheetname "")
		)
		(fill yes
			(thermal_gap 0.5)
			(thermal_bridge_width 0.5)
			(island_removal_mode 0)
		)
		(polygon
			(pts
				(arc
					(start 286.648652 -99.31273)
					(mid 285.945072 -99.31273)
					(end 286.648652 -99.31273)
				)
			)
		)
	)
	(zone
		(layers "B.Cu" "In7.Cu" "In9.Cu" "In11.Cu" "In13.Cu" "In15.Cu")
		(hatch none 0.5)
		(connect_pads
			(clearance 0)
		)
		(min_thickness 0.25)
		(keepout
			(tracks not_allowed)
			(vias allowed)
			(pads allowed)
			(copperpour not_allowed)
			(footprints allowed)
		)
		(placement
			(enabled no)
			(sheetname "")
		)
		(fill yes
			(thermal_gap 0.5)
			(thermal_bridge_width 0.5)
			(island_removal_mode 0)
		)
		(polygon
			(pts
				(arc
					(start 67.40906 -130.777234)
					(mid 66.70548 -130.777234)
					(end 67.40906 -130.777234)
				)
			)
		)
	)
	(zone
		(layers "B.Cu" "In7.Cu" "In9.Cu" "In11.Cu" "In13.Cu" "In15.Cu")
		(hatch none 0.5)
		(connect_pads
			(clearance 0)
		)
		(min_thickness 0.25)
		(keepout
			(tracks not_allowed)
			(vias allowed)
			(pads allowed)
			(copperpour not_allowed)
			(footprints allowed)
		)
		(placement
			(enabled no)
			(sheetname "")
		)
		(fill yes
			(thermal_gap 0.5)
			(thermal_bridge_width 0.5)
			(island_removal_mode 0)
		)
		(polygon
			(pts
				(arc
					(start 54.44871 -110.97641)
					(mid 53.74513 -110.97641)
					(end 54.44871 -110.97641)
				)
			)
		)
	)
	(zone
		(layers "B.Cu" "In7.Cu" "In9.Cu" "In11.Cu" "In13.Cu" "In15.Cu")
		(hatch none 0.5)
		(connect_pads
			(clearance 0)
		)
		(min_thickness 0.25)
		(keepout
			(tracks not_allowed)
			(vias allowed)
			(pads allowed)
			(copperpour not_allowed)
			(footprints allowed)
		)
		(placement
			(enabled no)
			(sheetname "")
		)
		(fill yes
			(thermal_gap 0.5)
			(thermal_bridge_width 0.5)
			(island_removal_mode 0)
		)
		(polygon
			(pts
				(arc
					(start 170.548554 -134.032752)
					(mid 169.844974 -134.032752)
					(end 170.548554 -134.032752)
				)
			)
		)
	)
	(zone
		(layers "B.Cu" "In7.Cu" "In9.Cu" "In11.Cu" "In13.Cu" "In15.Cu")
		(hatch none 0.5)
		(connect_pads
			(clearance 0)
		)
		(min_thickness 0.25)
		(keepout
			(tracks not_allowed)
			(vias allowed)
			(pads allowed)
			(copperpour not_allowed)
			(footprints allowed)
		)
		(placement
			(enabled no)
			(sheetname "")
		)
		(fill yes
			(thermal_gap 0.5)
			(thermal_bridge_width 0.5)
			(island_removal_mode 0)
		)
		(polygon
			(pts
				(arc
					(start 331.869796 -370.489988)
					(mid 331.110336 -370.489988)
					(end 331.869796 -370.489988)
				)
			)
		)
	)
	(zone
		(layers "B.Cu" "In7.Cu" "In9.Cu" "In11.Cu" "In13.Cu" "In15.Cu")
		(hatch none 0.5)
		(connect_pads
			(clearance 0)
		)
		(min_thickness 0.25)
		(keepout
			(tracks not_allowed)
			(vias allowed)
			(pads allowed)
			(copperpour not_allowed)
			(footprints allowed)
		)
		(placement
			(enabled no)
			(sheetname "")
		)
		(fill yes
			(thermal_gap 0.5)
			(thermal_bridge_width 0.5)
			(island_removal_mode 0)
		)
		(polygon
			(pts
				(arc
					(start 38.126162 -310.149748)
					(mid 37.473382 -310.149748)
					(end 38.126162 -310.149748)
				)
			)
		)
	)
	(zone
		(layers "B.Cu" "In7.Cu" "In9.Cu" "In11.Cu" "In13.Cu" "In15.Cu")
		(hatch none 0.5)
		(connect_pads
			(clearance 0)
		)
		(min_thickness 0.25)
		(keepout
			(tracks not_allowed)
			(vias allowed)
			(pads allowed)
			(copperpour not_allowed)
			(footprints allowed)
		)
		(placement
			(enabled no)
			(sheetname "")
		)
		(fill yes
			(thermal_gap 0.5)
			(thermal_bridge_width 0.5)
			(island_removal_mode 0)
		)
		(polygon
			(pts
				(arc
					(start 284.794452 -104.71277)
					(mid 284.090872 -104.71277)
					(end 284.794452 -104.71277)
				)
			)
		)
	)
	(zone
		(layers "B.Cu" "In7.Cu" "In9.Cu" "In11.Cu" "In13.Cu" "In15.Cu")
		(hatch none 0.5)
		(connect_pads
			(clearance 0)
		)
		(min_thickness 0.25)
		(keepout
			(tracks not_allowed)
			(vias allowed)
			(pads allowed)
			(copperpour not_allowed)
			(footprints allowed)
		)
		(placement
			(enabled no)
			(sheetname "")
		)
		(fill yes
			(thermal_gap 0.5)
			(thermal_bridge_width 0.5)
			(island_removal_mode 0)
		)
		(polygon
			(pts
				(arc
					(start 183.508904 -149.823678)
					(mid 182.805324 -149.823678)
					(end 183.508904 -149.823678)
				)
			)
		)
	)
	(zone
		(layers "B.Cu" "In7.Cu" "In9.Cu" "In11.Cu" "In13.Cu" "In15.Cu")
		(hatch none 0.5)
		(connect_pads
			(clearance 0)
		)
		(min_thickness 0.25)
		(keepout
			(tracks not_allowed)
			(vias allowed)
			(pads allowed)
			(copperpour not_allowed)
			(footprints allowed)
		)
		(placement
			(enabled no)
			(sheetname "")
		)
		(fill yes
			(thermal_gap 0.5)
			(thermal_bridge_width 0.5)
			(island_removal_mode 0)
		)
		(polygon
			(pts
				(arc
					(start 415.7091 -123.16714)
					(mid 415.00552 -123.16714)
					(end 415.7091 -123.16714)
				)
			)
		)
	)
	(zone
		(layers "B.Cu" "In7.Cu" "In9.Cu" "In11.Cu" "In13.Cu" "In15.Cu")
		(hatch none 0.5)
		(connect_pads
			(clearance 0)
		)
		(min_thickness 0.25)
		(keepout
			(tracks not_allowed)
			(vias allowed)
			(pads allowed)
			(copperpour not_allowed)
			(footprints allowed)
		)
		(placement
			(enabled no)
			(sheetname "")
		)
		(fill yes
			(thermal_gap 0.5)
			(thermal_bridge_width 0.5)
			(island_removal_mode 0)
		)
		(polygon
			(pts
				(arc
					(start 183.508904 -150.687278)
					(mid 182.805324 -150.687278)
					(end 183.508904 -150.687278)
				)
			)
		)
	)
	(zone
		(layers "B.Cu" "In7.Cu" "In9.Cu" "In11.Cu" "In13.Cu" "In15.Cu")
		(hatch none 0.5)
		(connect_pads
			(clearance 0)
		)
		(min_thickness 0.25)
		(keepout
			(tracks not_allowed)
			(vias allowed)
			(pads allowed)
			(copperpour not_allowed)
			(footprints allowed)
		)
		(placement
			(enabled no)
			(sheetname "")
		)
		(fill yes
			(thermal_gap 0.5)
			(thermal_bridge_width 0.5)
			(island_removal_mode 0)
		)
		(polygon
			(pts
				(arc
					(start 28.289758 -409.490164)
					(mid 27.530298 -409.490164)
					(end 28.289758 -409.490164)
				)
			)
		)
	)
	(zone
		(layers "B.Cu" "In7.Cu" "In9.Cu" "In11.Cu" "In13.Cu" "In15.Cu")
		(hatch none 0.5)
		(connect_pads
			(clearance 0)
		)
		(min_thickness 0.25)
		(keepout
			(tracks not_allowed)
			(vias allowed)
			(pads allowed)
			(copperpour not_allowed)
			(footprints allowed)
		)
		(placement
			(enabled no)
			(sheetname "")
		)
		(fill yes
			(thermal_gap 0.5)
			(thermal_bridge_width 0.5)
			(island_removal_mode 0)
		)
		(polygon
			(pts
				(arc
					(start 65.55486 -151.623776)
					(mid 64.85128 -151.623776)
					(end 65.55486 -151.623776)
				)
			)
		)
	)
	(zone
		(layers "B.Cu" "In7.Cu" "In9.Cu" "In11.Cu" "In13.Cu" "In15.Cu")
		(hatch none 0.5)
		(connect_pads
			(clearance 0)
		)
		(min_thickness 0.25)
		(keepout
			(tracks not_allowed)
			(vias allowed)
			(pads allowed)
			(copperpour not_allowed)
			(footprints allowed)
		)
		(placement
			(enabled no)
			(sheetname "")
		)
		(fill yes
			(thermal_gap 0.5)
			(thermal_bridge_width 0.5)
			(island_removal_mode 0)
		)
		(polygon
			(pts
				(arc
					(start 299.609002 -153.42362)
					(mid 298.905422 -153.42362)
					(end 299.609002 -153.42362)
				)
			)
		)
	)
	(zone
		(layers "B.Cu" "In7.Cu" "In9.Cu" "In11.Cu" "In13.Cu" "In15.Cu")
		(hatch none 0.5)
		(connect_pads
			(clearance 0)
		)
		(min_thickness 0.25)
		(keepout
			(tracks not_allowed)
			(vias allowed)
			(pads allowed)
			(copperpour not_allowed)
			(footprints allowed)
		)
		(placement
			(enabled no)
			(sheetname "")
		)
		(fill yes
			(thermal_gap 0.5)
			(thermal_bridge_width 0.5)
			(island_removal_mode 0)
		)
		(polygon
			(pts
				(arc
					(start 284.794452 -112.776508)
					(mid 284.090872 -112.776508)
					(end 284.794452 -112.776508)
				)
			)
		)
	)
	(zone
		(layers "B.Cu" "In7.Cu" "In9.Cu" "In11.Cu" "In13.Cu" "In15.Cu")
		(hatch none 0.5)
		(connect_pads
			(clearance 0)
		)
		(min_thickness 0.25)
		(keepout
			(tracks not_allowed)
			(vias allowed)
			(pads allowed)
			(copperpour not_allowed)
			(footprints allowed)
		)
		(placement
			(enabled no)
			(sheetname "")
		)
		(fill yes
			(thermal_gap 0.5)
			(thermal_bridge_width 0.5)
			(island_removal_mode 0)
		)
		(polygon
			(pts
				(arc
					(start 402.74875 -106.512614)
					(mid 402.04517 -106.512614)
					(end 402.74875 -106.512614)
				)
			)
		)
	)
	(zone
		(layers "B.Cu" "In7.Cu" "In9.Cu" "In11.Cu" "In13.Cu" "In15.Cu")
		(hatch none 0.5)
		(connect_pads
			(clearance 0)
		)
		(min_thickness 0.25)
		(keepout
			(tracks not_allowed)
			(vias allowed)
			(pads allowed)
			(copperpour not_allowed)
			(footprints allowed)
		)
		(placement
			(enabled no)
			(sheetname "")
		)
		(fill yes
			(thermal_gap 0.5)
			(thermal_bridge_width 0.5)
			(island_removal_mode 0)
		)
		(polygon
			(pts
				(arc
					(start 190.326264 -316.799722)
					(mid 189.673484 -316.799722)
					(end 190.326264 -316.799722)
				)
			)
		)
	)
	(zone
		(layers "B.Cu" "In7.Cu" "In9.Cu" "In11.Cu" "In13.Cu" "In15.Cu")
		(hatch none 0.5)
		(connect_pads
			(clearance 0)
		)
		(min_thickness 0.25)
		(keepout
			(tracks not_allowed)
			(vias allowed)
			(pads allowed)
			(copperpour not_allowed)
			(footprints allowed)
		)
		(placement
			(enabled no)
			(sheetname "")
		)
		(fill yes
			(thermal_gap 0.5)
			(thermal_bridge_width 0.5)
			(island_removal_mode 0)
		)
		(polygon
			(pts
				(arc
					(start 37.089842 -408.190192)
					(mid 36.330382 -408.190192)
					(end 37.089842 -408.190192)
				)
			)
		)
	)
	(zone
		(layers "B.Cu" "In7.Cu" "In9.Cu" "In11.Cu" "In13.Cu" "In15.Cu")
		(hatch none 0.5)
		(connect_pads
			(clearance 0)
		)
		(min_thickness 0.25)
		(keepout
			(tracks not_allowed)
			(vias allowed)
			(pads allowed)
			(copperpour not_allowed)
			(footprints allowed)
		)
		(placement
			(enabled no)
			(sheetname "")
		)
		(fill yes
			(thermal_gap 0.5)
			(thermal_bridge_width 0.5)
			(island_removal_mode 0)
		)
		(polygon
			(pts
				(arc
					(start 71.376032 -274.049744)
					(mid 70.723252 -274.049744)
					(end 71.376032 -274.049744)
				)
			)
		)
	)
	(zone
		(layers "B.Cu" "In7.Cu" "In9.Cu" "In11.Cu" "In13.Cu" "In15.Cu")
		(hatch none 0.5)
		(connect_pads
			(clearance 0)
		)
		(min_thickness 0.25)
		(keepout
			(tracks not_allowed)
			(vias allowed)
			(pads allowed)
			(copperpour not_allowed)
			(footprints allowed)
		)
		(placement
			(enabled no)
			(sheetname "")
		)
		(fill yes
			(thermal_gap 0.5)
			(thermal_bridge_width 0.5)
			(island_removal_mode 0)
		)
		(polygon
			(pts
				(arc
					(start 82.776314 -287.349946)
					(mid 82.123534 -287.349946)
					(end 82.776314 -287.349946)
				)
			)
		)
	)
	(zone
		(layers "B.Cu" "In7.Cu" "In9.Cu" "In11.Cu" "In13.Cu" "In15.Cu")
		(hatch none 0.5)
		(connect_pads
			(clearance 0)
		)
		(min_thickness 0.25)
		(keepout
			(tracks not_allowed)
			(vias allowed)
			(pads allowed)
			(copperpour not_allowed)
			(footprints allowed)
		)
		(placement
			(enabled no)
			(sheetname "")
		)
		(fill yes
			(thermal_gap 0.5)
			(thermal_bridge_width 0.5)
			(island_removal_mode 0)
		)
		(polygon
			(pts
				(arc
					(start 280.776172 -317.749936)
					(mid 280.123392 -317.749936)
					(end 280.776172 -317.749936)
				)
			)
		)
	)
	(zone
		(layers "B.Cu" "In7.Cu" "In9.Cu" "In11.Cu" "In13.Cu" "In15.Cu")
		(hatch none 0.5)
		(connect_pads
			(clearance 0)
		)
		(min_thickness 0.25)
		(keepout
			(tracks not_allowed)
			(vias allowed)
			(pads allowed)
			(copperpour not_allowed)
			(footprints allowed)
		)
		(placement
			(enabled no)
			(sheetname "")
		)
		(fill yes
			(thermal_gap 0.5)
			(thermal_bridge_width 0.5)
			(island_removal_mode 0)
		)
		(polygon
			(pts
				(arc
					(start 287.86963 -382.18999)
					(mid 287.11017 -382.18999)
					(end 287.86963 -382.18999)
				)
			)
		)
	)
	(zone
		(layers "B.Cu" "In7.Cu" "In9.Cu" "In11.Cu" "In13.Cu" "In15.Cu")
		(hatch none 0.5)
		(connect_pads
			(clearance 0)
		)
		(min_thickness 0.25)
		(keepout
			(tracks not_allowed)
			(vias allowed)
			(pads allowed)
			(copperpour not_allowed)
			(footprints allowed)
		)
		(placement
			(enabled no)
			(sheetname "")
		)
		(fill yes
			(thermal_gap 0.5)
			(thermal_bridge_width 0.5)
			(island_removal_mode 0)
		)
		(polygon
			(pts
				(arc
					(start 195.076318 -317.749936)
					(mid 194.423538 -317.749936)
					(end 195.076318 -317.749936)
				)
			)
		)
	)
	(zone
		(layers "B.Cu" "In7.Cu" "In9.Cu" "In11.Cu" "In13.Cu" "In15.Cu")
		(hatch none 0.5)
		(connect_pads
			(clearance 0)
		)
		(min_thickness 0.25)
		(keepout
			(tracks not_allowed)
			(vias allowed)
			(pads allowed)
			(copperpour not_allowed)
			(footprints allowed)
		)
		(placement
			(enabled no)
			(sheetname "")
		)
		(fill yes
			(thermal_gap 0.5)
			(thermal_bridge_width 0.5)
			(island_removal_mode 0)
		)
		(polygon
			(pts
				(arc
					(start 198.876412 -310.149748)
					(mid 198.223632 -310.149748)
					(end 198.876412 -310.149748)
				)
			)
		)
	)
	(zone
		(layers "B.Cu" "In7.Cu" "In9.Cu" "In11.Cu" "In13.Cu" "In15.Cu")
		(hatch none 0.5)
		(connect_pads
			(clearance 0)
		)
		(min_thickness 0.25)
		(keepout
			(tracks not_allowed)
			(vias allowed)
			(pads allowed)
			(copperpour not_allowed)
			(footprints allowed)
		)
		(placement
			(enabled no)
			(sheetname "")
		)
		(fill yes
			(thermal_gap 0.5)
			(thermal_bridge_width 0.5)
			(island_removal_mode 0)
		)
		(polygon
			(pts
				(arc
					(start 191.276478 -318.699896)
					(mid 190.623698 -318.699896)
					(end 191.276478 -318.699896)
				)
			)
		)
	)
	(zone
		(layers "B.Cu" "In7.Cu" "In9.Cu" "In11.Cu" "In13.Cu" "In15.Cu")
		(hatch none 0.5)
		(connect_pads
			(clearance 0)
		)
		(min_thickness 0.25)
		(keepout
			(tracks not_allowed)
			(vias allowed)
			(pads allowed)
			(copperpour not_allowed)
			(footprints allowed)
		)
		(placement
			(enabled no)
			(sheetname "")
		)
		(fill yes
			(thermal_gap 0.5)
			(thermal_bridge_width 0.5)
			(island_removal_mode 0)
		)
		(polygon
			(pts
				(arc
					(start 286.648652 -130.43281)
					(mid 285.945072 -130.43281)
					(end 286.648652 -130.43281)
				)
			)
		)
	)
	(zone
		(layers "B.Cu" "In7.Cu" "In9.Cu" "In11.Cu" "In13.Cu" "In15.Cu")
		(hatch none 0.5)
		(connect_pads
			(clearance 0)
		)
		(min_thickness 0.25)
		(keepout
			(tracks not_allowed)
			(vias allowed)
			(pads allowed)
			(copperpour not_allowed)
			(footprints allowed)
		)
		(placement
			(enabled no)
			(sheetname "")
		)
		(fill yes
			(thermal_gap 0.5)
			(thermal_bridge_width 0.5)
			(island_removal_mode 0)
		)
		(polygon
			(pts
				(arc
					(start 39.289736 -383.290064)
					(mid 38.530276 -383.290064)
					(end 39.289736 -383.290064)
				)
			)
		)
	)
	(zone
		(layers "B.Cu" "In7.Cu" "In9.Cu" "In11.Cu" "In13.Cu" "In15.Cu")
		(hatch none 0.5)
		(connect_pads
			(clearance 0)
		)
		(min_thickness 0.25)
		(keepout
			(tracks not_allowed)
			(vias allowed)
			(pads allowed)
			(copperpour not_allowed)
			(footprints allowed)
		)
		(placement
			(enabled no)
			(sheetname "")
		)
		(fill yes
			(thermal_gap 0.5)
			(thermal_bridge_width 0.5)
			(island_removal_mode 0)
		)
		(polygon
			(pts
				(arc
					(start 73.275952 -273.099784)
					(mid 72.623172 -273.099784)
					(end 73.275952 -273.099784)
				)
			)
		)
	)
	(zone
		(layers "B.Cu" "In7.Cu" "In9.Cu" "In11.Cu" "In13.Cu" "In15.Cu")
		(hatch none 0.5)
		(connect_pads
			(clearance 0)
		)
		(min_thickness 0.25)
		(keepout
			(tracks not_allowed)
			(vias allowed)
			(pads allowed)
			(copperpour not_allowed)
			(footprints allowed)
		)
		(placement
			(enabled no)
			(sheetname "")
		)
		(fill yes
			(thermal_gap 0.5)
			(thermal_bridge_width 0.5)
			(island_removal_mode 0)
		)
		(polygon
			(pts
				(arc
					(start 270.326104 -308.249828)
					(mid 269.673324 -308.249828)
					(end 270.326104 -308.249828)
				)
			)
		)
	)
	(zone
		(layers "B.Cu" "In7.Cu" "In9.Cu" "In11.Cu" "In13.Cu" "In15.Cu")
		(hatch none 0.5)
		(connect_pads
			(clearance 0)
		)
		(min_thickness 0.25)
		(keepout
			(tracks not_allowed)
			(vias allowed)
			(pads allowed)
			(copperpour not_allowed)
			(footprints allowed)
		)
		(placement
			(enabled no)
			(sheetname "")
		)
		(fill yes
			(thermal_gap 0.5)
			(thermal_bridge_width 0.5)
			(island_removal_mode 0)
		)
		(polygon
			(pts
				(arc
					(start 314.026296 -285.449772)
					(mid 313.373516 -285.449772)
					(end 314.026296 -285.449772)
				)
			)
		)
	)
	(zone
		(layers "B.Cu" "In7.Cu" "In9.Cu" "In11.Cu" "In13.Cu" "In15.Cu")
		(hatch none 0.5)
		(connect_pads
			(clearance 0)
		)
		(min_thickness 0.25)
		(keepout
			(tracks not_allowed)
			(vias allowed)
			(pads allowed)
			(copperpour not_allowed)
			(footprints allowed)
		)
		(placement
			(enabled no)
			(sheetname "")
		)
		(fill yes
			(thermal_gap 0.5)
			(thermal_bridge_width 0.5)
			(island_removal_mode 0)
		)
		(polygon
			(pts
				(arc
					(start 415.7091 -154.28722)
					(mid 415.00552 -154.28722)
					(end 415.7091 -154.28722)
				)
			)
		)
	)
	(zone
		(layers "B.Cu" "In7.Cu" "In9.Cu" "In11.Cu" "In13.Cu" "In15.Cu")
		(hatch none 0.5)
		(connect_pads
			(clearance 0)
		)
		(min_thickness 0.25)
		(keepout
			(tracks not_allowed)
			(vias allowed)
			(pads allowed)
			(copperpour not_allowed)
			(footprints allowed)
		)
		(placement
			(enabled no)
			(sheetname "")
		)
		(fill yes
			(thermal_gap 0.5)
			(thermal_bridge_width 0.5)
			(island_removal_mode 0)
		)
		(polygon
			(pts
				(arc
					(start 275.076158 -318.699896)
					(mid 274.423378 -318.699896)
					(end 275.076158 -318.699896)
				)
			)
		)
	)
	(zone
		(layers "B.Cu" "In7.Cu" "In9.Cu" "In11.Cu" "In13.Cu" "In15.Cu")
		(hatch none 0.5)
		(connect_pads
			(clearance 0)
		)
		(min_thickness 0.25)
		(keepout
			(tracks not_allowed)
			(vias allowed)
			(pads allowed)
			(copperpour not_allowed)
			(footprints allowed)
		)
		(placement
			(enabled no)
			(sheetname "")
		)
		(fill yes
			(thermal_gap 0.5)
			(thermal_bridge_width 0.5)
			(island_removal_mode 0)
		)
		(polygon
			(pts
				(arc
					(start 384.669792 -375.69013)
					(mid 383.910332 -375.69013)
					(end 384.669792 -375.69013)
				)
			)
		)
	)
	(zone
		(layers "B.Cu" "In7.Cu" "In9.Cu" "In11.Cu" "In13.Cu" "In15.Cu")
		(hatch none 0.5)
		(connect_pads
			(clearance 0)
		)
		(min_thickness 0.25)
		(keepout
			(tracks not_allowed)
			(vias allowed)
			(pads allowed)
			(copperpour not_allowed)
			(footprints allowed)
		)
		(placement
			(enabled no)
			(sheetname "")
		)
		(fill yes
			(thermal_gap 0.5)
			(thermal_bridge_width 0.5)
			(island_removal_mode 0)
		)
		(polygon
			(pts
				(arc
					(start 297.87596 -273.099784)
					(mid 297.22318 -273.099784)
					(end 297.87596 -273.099784)
				)
			)
		)
	)
	(zone
		(layers "B.Cu" "In7.Cu" "In9.Cu" "In11.Cu" "In13.Cu" "In15.Cu")
		(hatch none 0.5)
		(connect_pads
			(clearance 0)
		)
		(min_thickness 0.25)
		(keepout
			(tracks not_allowed)
			(vias allowed)
			(pads allowed)
			(copperpour not_allowed)
			(footprints allowed)
		)
		(placement
			(enabled no)
			(sheetname "")
		)
		(fill yes
			(thermal_gap 0.5)
			(thermal_bridge_width 0.5)
			(island_removal_mode 0)
		)
		(polygon
			(pts
				(arc
					(start 271.276318 -309.199788)
					(mid 270.623538 -309.199788)
					(end 271.276318 -309.199788)
				)
			)
		)
	)
	(zone
		(layers "B.Cu" "In7.Cu" "In9.Cu" "In11.Cu" "In13.Cu" "In15.Cu")
		(hatch none 0.5)
		(connect_pads
			(clearance 0)
		)
		(min_thickness 0.25)
		(keepout
			(tracks not_allowed)
			(vias allowed)
			(pads allowed)
			(copperpour not_allowed)
			(footprints allowed)
		)
		(placement
			(enabled no)
			(sheetname "")
		)
		(fill yes
			(thermal_gap 0.5)
			(thermal_bridge_width 0.5)
			(island_removal_mode 0)
		)
		(polygon
			(pts
				(arc
					(start 69.476112 -274.049744)
					(mid 68.823332 -274.049744)
					(end 69.476112 -274.049744)
				)
			)
		)
	)
	(zone
		(layers "B.Cu" "In7.Cu" "In9.Cu" "In11.Cu" "In13.Cu" "In15.Cu")
		(hatch none 0.5)
		(connect_pads
			(clearance 0)
		)
		(min_thickness 0.25)
		(keepout
			(tracks not_allowed)
			(vias allowed)
			(pads allowed)
			(copperpour not_allowed)
			(footprints allowed)
		)
		(placement
			(enabled no)
			(sheetname "")
		)
		(fill yes
			(thermal_gap 0.5)
			(thermal_bridge_width 0.5)
			(island_removal_mode 0)
		)
		(polygon
			(pts
				(arc
					(start 39.076376 -301.599854)
					(mid 38.423596 -301.599854)
					(end 39.076376 -301.599854)
				)
			)
		)
	)
	(zone
		(layers "B.Cu" "In7.Cu" "In9.Cu" "In11.Cu" "In13.Cu" "In15.Cu")
		(hatch none 0.5)
		(connect_pads
			(clearance 0)
		)
		(min_thickness 0.25)
		(keepout
			(tracks not_allowed)
			(vias allowed)
			(pads allowed)
			(copperpour not_allowed)
			(footprints allowed)
		)
		(placement
			(enabled no)
			(sheetname "")
		)
		(fill yes
			(thermal_gap 0.5)
			(thermal_bridge_width 0.5)
			(island_removal_mode 0)
		)
		(polygon
			(pts
				(arc
					(start 375.869708 -397.790162)
					(mid 375.110248 -397.790162)
					(end 375.869708 -397.790162)
				)
			)
		)
	)
	(zone
		(layers "B.Cu" "In7.Cu" "In9.Cu" "In11.Cu" "In13.Cu" "In15.Cu")
		(hatch none 0.5)
		(connect_pads
			(clearance 0)
		)
		(min_thickness 0.25)
		(keepout
			(tracks not_allowed)
			(vias allowed)
			(pads allowed)
			(copperpour not_allowed)
			(footprints allowed)
		)
		(placement
			(enabled no)
			(sheetname "")
		)
		(fill yes
			(thermal_gap 0.5)
			(thermal_bridge_width 0.5)
			(island_removal_mode 0)
		)
		(polygon
			(pts
				(arc
					(start 169.089832 -378.290074)
					(mid 168.330372 -378.290074)
					(end 169.089832 -378.290074)
				)
			)
		)
	)
	(zone
		(layers "B.Cu" "In7.Cu" "In9.Cu" "In11.Cu" "In13.Cu" "In15.Cu")
		(hatch none 0.5)
		(connect_pads
			(clearance 0)
		)
		(min_thickness 0.25)
		(keepout
			(tracks not_allowed)
			(vias allowed)
			(pads allowed)
			(copperpour not_allowed)
			(footprints allowed)
		)
		(placement
			(enabled no)
			(sheetname "")
		)
		(fill yes
			(thermal_gap 0.5)
			(thermal_bridge_width 0.5)
			(island_removal_mode 0)
		)
		(polygon
			(pts
				(arc
					(start 299.77588 -274.049744)
					(mid 299.1231 -274.049744)
					(end 299.77588 -274.049744)
				)
			)
		)
	)
	(zone
		(layers "B.Cu" "In7.Cu" "In9.Cu" "In11.Cu" "In13.Cu" "In15.Cu")
		(hatch none 0.5)
		(connect_pads
			(clearance 0)
		)
		(min_thickness 0.25)
		(keepout
			(tracks not_allowed)
			(vias allowed)
			(pads allowed)
			(copperpour not_allowed)
			(footprints allowed)
		)
		(placement
			(enabled no)
			(sheetname "")
		)
		(fill yes
			(thermal_gap 0.5)
			(thermal_bridge_width 0.5)
			(island_removal_mode 0)
		)
		(polygon
			(pts
				(arc
					(start 127.289814 -376.790204)
					(mid 126.530354 -376.790204)
					(end 127.289814 -376.790204)
				)
			)
		)
	)
	(zone
		(layers "B.Cu" "In7.Cu" "In9.Cu" "In11.Cu" "In13.Cu" "In15.Cu")
		(hatch none 0.5)
		(connect_pads
			(clearance 0)
		)
		(min_thickness 0.25)
		(keepout
			(tracks not_allowed)
			(vias allowed)
			(pads allowed)
			(copperpour not_allowed)
			(footprints allowed)
		)
		(placement
			(enabled no)
			(sheetname "")
		)
		(fill yes
			(thermal_gap 0.5)
			(thermal_bridge_width 0.5)
			(island_removal_mode 0)
		)
		(polygon
			(pts
				(arc
					(start 305.476148 -318.699896)
					(mid 304.823368 -318.699896)
					(end 305.476148 -318.699896)
				)
			)
		)
	)
	(zone
		(layers "B.Cu" "In7.Cu" "In9.Cu" "In11.Cu" "In13.Cu" "In15.Cu")
		(hatch none 0.5)
		(connect_pads
			(clearance 0)
		)
		(min_thickness 0.25)
		(keepout
			(tracks not_allowed)
			(vias allowed)
			(pads allowed)
			(copperpour not_allowed)
			(footprints allowed)
		)
		(placement
			(enabled no)
			(sheetname "")
		)
		(fill yes
			(thermal_gap 0.5)
			(thermal_bridge_width 0.5)
			(island_removal_mode 0)
		)
		(polygon
			(pts
				(arc
					(start 80.875886 -273.099784)
					(mid 80.223106 -273.099784)
					(end 80.875886 -273.099784)
				)
			)
		)
	)
	(zone
		(layers "B.Cu" "In7.Cu" "In9.Cu" "In11.Cu" "In13.Cu" "In15.Cu")
		(hatch none 0.5)
		(connect_pads
			(clearance 0)
		)
		(min_thickness 0.25)
		(keepout
			(tracks not_allowed)
			(vias allowed)
			(pads allowed)
			(copperpour not_allowed)
			(footprints allowed)
		)
		(placement
			(enabled no)
			(sheetname "")
		)
		(fill yes
			(thermal_gap 0.5)
			(thermal_bridge_width 0.5)
			(island_removal_mode 0)
		)
		(polygon
			(pts
				(arc
					(start 175.689768 -405.390096)
					(mid 174.930308 -405.390096)
					(end 175.689768 -405.390096)
				)
			)
		)
	)
	(zone
		(layers "B.Cu" "In7.Cu" "In9.Cu" "In11.Cu" "In13.Cu" "In15.Cu")
		(hatch none 0.5)
		(connect_pads
			(clearance 0)
		)
		(min_thickness 0.25)
		(keepout
			(tracks not_allowed)
			(vias allowed)
			(pads allowed)
			(copperpour not_allowed)
			(footprints allowed)
		)
		(placement
			(enabled no)
			(sheetname "")
		)
		(fill yes
			(thermal_gap 0.5)
			(thermal_bridge_width 0.5)
			(island_removal_mode 0)
		)
		(polygon
			(pts
				(arc
					(start 183.508904 -154.28722)
					(mid 182.805324 -154.28722)
					(end 183.508904 -154.28722)
				)
			)
		)
	)
	(zone
		(layers "B.Cu" "In7.Cu" "In9.Cu" "In11.Cu" "In13.Cu" "In15.Cu")
		(hatch none 0.5)
		(connect_pads
			(clearance 0)
		)
		(min_thickness 0.25)
		(keepout
			(tracks not_allowed)
			(vias allowed)
			(pads allowed)
			(copperpour not_allowed)
			(footprints allowed)
		)
		(placement
			(enabled no)
			(sheetname "")
		)
		(fill yes
			(thermal_gap 0.5)
			(thermal_bridge_width 0.5)
			(island_removal_mode 0)
		)
		(polygon
			(pts
				(arc
					(start 183.508904 -147.087336)
					(mid 182.805324 -147.087336)
					(end 183.508904 -147.087336)
				)
			)
		)
	)
	(zone
		(layers "B.Cu" "In7.Cu" "In9.Cu" "In11.Cu" "In13.Cu" "In15.Cu")
		(hatch none 0.5)
		(connect_pads
			(clearance 0)
		)
		(min_thickness 0.25)
		(keepout
			(tracks not_allowed)
			(vias allowed)
			(pads allowed)
			(copperpour not_allowed)
			(footprints allowed)
		)
		(placement
			(enabled no)
			(sheetname "")
		)
		(fill yes
			(thermal_gap 0.5)
			(thermal_bridge_width 0.5)
			(island_removal_mode 0)
		)
		(polygon
			(pts
				(arc
					(start 122.889772 -376.790204)
					(mid 122.130312 -376.790204)
					(end 122.889772 -376.790204)
				)
			)
		)
	)
	(zone
		(layers "B.Cu" "In7.Cu" "In9.Cu" "In11.Cu" "In13.Cu" "In15.Cu")
		(hatch none 0.5)
		(connect_pads
			(clearance 0)
		)
		(min_thickness 0.25)
		(keepout
			(tracks not_allowed)
			(vias allowed)
			(pads allowed)
			(copperpour not_allowed)
			(footprints allowed)
		)
		(placement
			(enabled no)
			(sheetname "")
		)
		(fill yes
			(thermal_gap 0.5)
			(thermal_bridge_width 0.5)
			(island_removal_mode 0)
		)
		(polygon
			(pts
				(arc
					(start 39.289736 -410.589984)
					(mid 38.530276 -410.589984)
					(end 39.289736 -410.589984)
				)
			)
		)
	)
	(zone
		(layers "B.Cu" "In7.Cu" "In9.Cu" "In11.Cu" "In13.Cu" "In15.Cu")
		(hatch none 0.5)
		(connect_pads
			(clearance 0)
		)
		(min_thickness 0.25)
		(keepout
			(tracks not_allowed)
			(vias allowed)
			(pads allowed)
			(copperpour not_allowed)
			(footprints allowed)
		)
		(placement
			(enabled no)
			(sheetname "")
		)
		(fill yes
			(thermal_gap 0.5)
			(thermal_bridge_width 0.5)
			(island_removal_mode 0)
		)
		(polygon
			(pts
				(arc
					(start 169.089832 -404.290022)
					(mid 168.330372 -404.290022)
					(end 169.089832 -404.290022)
				)
			)
		)
	)
	(zone
		(layers "B.Cu" "In7.Cu" "In9.Cu" "In11.Cu" "In13.Cu" "In15.Cu")
		(hatch none 0.5)
		(connect_pads
			(clearance 0)
		)
		(min_thickness 0.25)
		(keepout
			(tracks not_allowed)
			(vias allowed)
			(pads allowed)
			(copperpour not_allowed)
			(footprints allowed)
		)
		(placement
			(enabled no)
			(sheetname "")
		)
		(fill yes
			(thermal_gap 0.5)
			(thermal_bridge_width 0.5)
			(island_removal_mode 0)
		)
		(polygon
			(pts
				(arc
					(start 171.289726 -380.69012)
					(mid 170.530266 -380.69012)
					(end 171.289726 -380.69012)
				)
			)
		)
	)
	(zone
		(layers "B.Cu" "In7.Cu" "In9.Cu" "In11.Cu" "In13.Cu" "In15.Cu")
		(hatch none 0.5)
		(connect_pads
			(clearance 0)
		)
		(min_thickness 0.25)
		(keepout
			(tracks not_allowed)
			(vias allowed)
			(pads allowed)
			(copperpour not_allowed)
			(footprints allowed)
		)
		(placement
			(enabled no)
			(sheetname "")
		)
		(fill yes
			(thermal_gap 0.5)
			(thermal_bridge_width 0.5)
			(island_removal_mode 0)
		)
		(polygon
			(pts
				(arc
					(start 309.275988 -274.049744)
					(mid 308.623208 -274.049744)
					(end 309.275988 -274.049744)
				)
			)
		)
	)
	(zone
		(layers "B.Cu" "In7.Cu" "In9.Cu" "In11.Cu" "In13.Cu" "In15.Cu")
		(hatch none 0.5)
		(connect_pads
			(clearance 0)
		)
		(min_thickness 0.25)
		(keepout
			(tracks not_allowed)
			(vias allowed)
			(pads allowed)
			(copperpour not_allowed)
			(footprints allowed)
		)
		(placement
			(enabled no)
			(sheetname "")
		)
		(fill yes
			(thermal_gap 0.5)
			(thermal_bridge_width 0.5)
			(island_removal_mode 0)
		)
		(polygon
			(pts
				(arc
					(start 347.269816 -402.790152)
					(mid 346.510356 -402.790152)
					(end 347.269816 -402.790152)
				)
			)
		)
	)
	(zone
		(layers "B.Cu" "In7.Cu" "In9.Cu" "In11.Cu" "In13.Cu" "In15.Cu")
		(hatch none 0.5)
		(connect_pads
			(clearance 0)
		)
		(min_thickness 0.25)
		(keepout
			(tracks not_allowed)
			(vias allowed)
			(pads allowed)
			(copperpour not_allowed)
			(footprints allowed)
		)
		(placement
			(enabled no)
			(sheetname "")
		)
		(fill yes
			(thermal_gap 0.5)
			(thermal_bridge_width 0.5)
			(island_removal_mode 0)
		)
		(polygon
			(pts
				(arc
					(start 42.876216 -317.749936)
					(mid 42.223436 -317.749936)
					(end 42.876216 -317.749936)
				)
			)
		)
	)
	(zone
		(layers "B.Cu" "In7.Cu" "In9.Cu" "In11.Cu" "In13.Cu" "In15.Cu")
		(hatch none 0.5)
		(connect_pads
			(clearance 0)
		)
		(min_thickness 0.25)
		(keepout
			(tracks not_allowed)
			(vias allowed)
			(pads allowed)
			(copperpour not_allowed)
			(footprints allowed)
		)
		(placement
			(enabled no)
			(sheetname "")
		)
		(fill yes
			(thermal_gap 0.5)
			(thermal_bridge_width 0.5)
			(island_removal_mode 0)
		)
		(polygon
			(pts
				(arc
					(start 77.076046 -273.099784)
					(mid 76.423266 -273.099784)
					(end 77.076046 -273.099784)
				)
			)
		)
	)
	(zone
		(layers "B.Cu" "In7.Cu" "In9.Cu" "In11.Cu" "In13.Cu" "In15.Cu")
		(hatch none 0.5)
		(connect_pads
			(clearance 0)
		)
		(min_thickness 0.25)
		(keepout
			(tracks not_allowed)
			(vias allowed)
			(pads allowed)
			(copperpour not_allowed)
			(footprints allowed)
		)
		(placement
			(enabled no)
			(sheetname "")
		)
		(fill yes
			(thermal_gap 0.5)
			(thermal_bridge_width 0.5)
			(island_removal_mode 0)
		)
		(polygon
			(pts
				(arc
					(start 313.076082 -288.299906)
					(mid 312.423302 -288.299906)
					(end 313.076082 -288.299906)
				)
			)
		)
	)
	(zone
		(layers "B.Cu" "In7.Cu" "In9.Cu" "In11.Cu" "In13.Cu" "In15.Cu")
		(hatch none 0.5)
		(connect_pads
			(clearance 0)
		)
		(min_thickness 0.25)
		(keepout
			(tracks not_allowed)
			(vias allowed)
			(pads allowed)
			(copperpour not_allowed)
			(footprints allowed)
		)
		(placement
			(enabled no)
			(sheetname "")
		)
		(fill yes
			(thermal_gap 0.5)
			(thermal_bridge_width 0.5)
			(island_removal_mode 0)
		)
		(polygon
			(pts
				(arc
					(start 278.876252 -317.749936)
					(mid 278.223472 -317.749936)
					(end 278.876252 -317.749936)
				)
			)
		)
	)
	(zone
		(layers "B.Cu" "In7.Cu" "In9.Cu" "In11.Cu" "In13.Cu" "In15.Cu")
		(hatch none 0.5)
		(connect_pads
			(clearance 0)
		)
		(min_thickness 0.25)
		(keepout
			(tracks not_allowed)
			(vias allowed)
			(pads allowed)
			(copperpour not_allowed)
			(footprints allowed)
		)
		(placement
			(enabled no)
			(sheetname "")
		)
		(fill yes
			(thermal_gap 0.5)
			(thermal_bridge_width 0.5)
			(island_removal_mode 0)
		)
		(polygon
			(pts
				(arc
					(start 233.819192 -215.504268)
					(mid 233.115612 -215.504268)
					(end 233.819192 -215.504268)
				)
			)
		)
	)
	(zone
		(layers "B.Cu" "In7.Cu" "In9.Cu" "In11.Cu" "In13.Cu" "In15.Cu")
		(hatch none 0.5)
		(connect_pads
			(clearance 0)
		)
		(min_thickness 0.25)
		(keepout
			(tracks not_allowed)
			(vias allowed)
			(pads allowed)
			(copperpour not_allowed)
			(footprints allowed)
		)
		(placement
			(enabled no)
			(sheetname "")
		)
		(fill yes
			(thermal_gap 0.5)
			(thermal_bridge_width 0.5)
			(island_removal_mode 0)
		)
		(polygon
			(pts
				(arc
					(start 309.275988 -273.099784)
					(mid 308.623208 -273.099784)
					(end 309.275988 -273.099784)
				)
			)
		)
	)
	(zone
		(layers "B.Cu" "In7.Cu" "In9.Cu" "In11.Cu" "In13.Cu" "In15.Cu")
		(hatch none 0.5)
		(connect_pads
			(clearance 0)
		)
		(min_thickness 0.25)
		(keepout
			(tracks not_allowed)
			(vias allowed)
			(pads allowed)
			(copperpour not_allowed)
			(footprints allowed)
		)
		(placement
			(enabled no)
			(sheetname "")
		)
		(fill yes
			(thermal_gap 0.5)
			(thermal_bridge_width 0.5)
			(island_removal_mode 0)
		)
		(polygon
			(pts
				(arc
					(start 170.548554 -119.222774)
					(mid 169.844974 -119.222774)
					(end 170.548554 -119.222774)
				)
			)
		)
	)
	(zone
		(layers "B.Cu" "In7.Cu" "In9.Cu" "In11.Cu" "In13.Cu" "In15.Cu")
		(hatch none 0.5)
		(connect_pads
			(clearance 0)
		)
		(min_thickness 0.25)
		(keepout
			(tracks not_allowed)
			(vias allowed)
			(pads allowed)
			(copperpour not_allowed)
			(footprints allowed)
		)
		(placement
			(enabled no)
			(sheetname "")
		)
		(fill yes
			(thermal_gap 0.5)
			(thermal_bridge_width 0.5)
			(island_removal_mode 0)
		)
		(polygon
			(pts
				(arc
					(start 168.476422 -317.749936)
					(mid 167.823642 -317.749936)
					(end 168.476422 -317.749936)
				)
			)
		)
	)
	(zone
		(layers "B.Cu" "In7.Cu" "In9.Cu" "In11.Cu" "In13.Cu" "In15.Cu")
		(hatch none 0.5)
		(connect_pads
			(clearance 0)
		)
		(min_thickness 0.25)
		(keepout
			(tracks not_allowed)
			(vias allowed)
			(pads allowed)
			(copperpour not_allowed)
			(footprints allowed)
		)
		(placement
			(enabled no)
			(sheetname "")
		)
		(fill yes
			(thermal_gap 0.5)
			(thermal_bridge_width 0.5)
			(island_removal_mode 0)
		)
		(polygon
			(pts
				(arc
					(start 415.7091 -146.223736)
					(mid 415.00552 -146.223736)
					(end 415.7091 -146.223736)
				)
			)
		)
	)
	(zone
		(layers "B.Cu" "In7.Cu" "In9.Cu" "In11.Cu" "In13.Cu" "In15.Cu")
		(hatch none 0.5)
		(connect_pads
			(clearance 0)
		)
		(min_thickness 0.25)
		(keepout
			(tracks not_allowed)
			(vias allowed)
			(pads allowed)
			(copperpour not_allowed)
			(footprints allowed)
		)
		(placement
			(enabled no)
			(sheetname "")
		)
		(fill yes
			(thermal_gap 0.5)
			(thermal_bridge_width 0.5)
			(island_removal_mode 0)
		)
		(polygon
			(pts
				(arc
					(start 72.28967 -400.390106)
					(mid 71.53021 -400.390106)
					(end 72.28967 -400.390106)
				)
			)
		)
	)
	(zone
		(layers "B.Cu" "In7.Cu" "In9.Cu" "In11.Cu" "In13.Cu" "In15.Cu")
		(hatch none 0.5)
		(connect_pads
			(clearance 0)
		)
		(min_thickness 0.25)
		(keepout
			(tracks not_allowed)
			(vias allowed)
			(pads allowed)
			(copperpour not_allowed)
			(footprints allowed)
		)
		(placement
			(enabled no)
			(sheetname "")
		)
		(fill yes
			(thermal_gap 0.5)
			(thermal_bridge_width 0.5)
			(island_removal_mode 0)
		)
		(polygon
			(pts
				(arc
					(start 198.876412 -316.799722)
					(mid 198.223632 -316.799722)
					(end 198.876412 -316.799722)
				)
			)
		)
	)
	(zone
		(layers "B.Cu" "In7.Cu" "In9.Cu" "In11.Cu" "In13.Cu" "In15.Cu")
		(hatch none 0.5)
		(connect_pads
			(clearance 0)
		)
		(min_thickness 0.25)
		(keepout
			(tracks not_allowed)
			(vias allowed)
			(pads allowed)
			(copperpour not_allowed)
			(footprints allowed)
		)
		(placement
			(enabled no)
			(sheetname "")
		)
		(fill yes
			(thermal_gap 0.5)
			(thermal_bridge_width 0.5)
			(island_removal_mode 0)
		)
		(polygon
			(pts
				(arc
					(start 272.226278 -305.399948)
					(mid 271.573498 -305.399948)
					(end 272.226278 -305.399948)
				)
			)
		)
	)
	(zone
		(layers "B.Cu" "In7.Cu" "In9.Cu" "In11.Cu" "In13.Cu" "In15.Cu")
		(hatch none 0.5)
		(connect_pads
			(clearance 0)
		)
		(min_thickness 0.25)
		(keepout
			(tracks not_allowed)
			(vias allowed)
			(pads allowed)
			(copperpour not_allowed)
			(footprints allowed)
		)
		(placement
			(enabled no)
			(sheetname "")
		)
		(fill yes
			(thermal_gap 0.5)
			(thermal_bridge_width 0.5)
			(island_removal_mode 0)
		)
		(polygon
			(pts
				(arc
					(start 196.976238 -305.399948)
					(mid 196.323458 -305.399948)
					(end 196.976238 -305.399948)
				)
			)
		)
	)
	(zone
		(layers "B.Cu" "In7.Cu" "In9.Cu" "In11.Cu" "In13.Cu" "In15.Cu")
		(hatch none 0.5)
		(connect_pads
			(clearance 0)
		)
		(min_thickness 0.25)
		(keepout
			(tracks not_allowed)
			(vias allowed)
			(pads allowed)
			(copperpour not_allowed)
			(footprints allowed)
		)
		(placement
			(enabled no)
			(sheetname "")
		)
		(fill yes
			(thermal_gap 0.5)
			(thermal_bridge_width 0.5)
			(island_removal_mode 0)
		)
		(polygon
			(pts
				(arc
					(start 175.126396 -315.849762)
					(mid 174.473616 -315.849762)
					(end 175.126396 -315.849762)
				)
			)
		)
	)
	(zone
		(layers "B.Cu" "In7.Cu" "In9.Cu" "In11.Cu" "In13.Cu" "In15.Cu")
		(hatch none 0.5)
		(connect_pads
			(clearance 0)
		)
		(min_thickness 0.25)
		(keepout
			(tracks not_allowed)
			(vias allowed)
			(pads allowed)
			(copperpour not_allowed)
			(footprints allowed)
		)
		(placement
			(enabled no)
			(sheetname "")
		)
		(fill yes
			(thermal_gap 0.5)
			(thermal_bridge_width 0.5)
			(island_removal_mode 0)
		)
		(polygon
			(pts
				(arc
					(start 297.754802 -136.177274)
					(mid 297.051222 -136.177274)
					(end 297.754802 -136.177274)
				)
			)
		)
	)
	(zone
		(layers "B.Cu" "In7.Cu" "In9.Cu" "In11.Cu" "In13.Cu" "In15.Cu")
		(hatch none 0.5)
		(connect_pads
			(clearance 0)
		)
		(min_thickness 0.25)
		(keepout
			(tracks not_allowed)
			(vias allowed)
			(pads allowed)
			(copperpour not_allowed)
			(footprints allowed)
		)
		(placement
			(enabled no)
			(sheetname "")
		)
		(fill yes
			(thermal_gap 0.5)
			(thermal_bridge_width 0.5)
			(island_removal_mode 0)
		)
		(polygon
			(pts
				(arc
					(start 287.86963 -408.190192)
					(mid 287.11017 -408.190192)
					(end 287.86963 -408.190192)
				)
			)
		)
	)
	(zone
		(layers "B.Cu" "In7.Cu" "In9.Cu" "In11.Cu" "In13.Cu" "In15.Cu")
		(hatch none 0.5)
		(connect_pads
			(clearance 0)
		)
		(min_thickness 0.25)
		(keepout
			(tracks not_allowed)
			(vias allowed)
			(pads allowed)
			(copperpour not_allowed)
			(footprints allowed)
		)
		(placement
			(enabled no)
			(sheetname "")
		)
		(fill yes
			(thermal_gap 0.5)
			(thermal_bridge_width 0.5)
			(island_removal_mode 0)
		)
		(polygon
			(pts
				(arc
					(start 67.40906 -150.687278)
					(mid 66.70548 -150.687278)
					(end 67.40906 -150.687278)
				)
			)
		)
	)
	(zone
		(layers "B.Cu" "In7.Cu" "In9.Cu" "In11.Cu" "In13.Cu" "In15.Cu")
		(hatch none 0.5)
		(connect_pads
			(clearance 0)
		)
		(min_thickness 0.25)
		(keepout
			(tracks not_allowed)
			(vias allowed)
			(pads allowed)
			(copperpour not_allowed)
			(footprints allowed)
		)
		(placement
			(enabled no)
			(sheetname "")
		)
		(fill yes
			(thermal_gap 0.5)
			(thermal_bridge_width 0.5)
			(island_removal_mode 0)
		)
		(polygon
			(pts
				(arc
					(start 49.52619 -315.849762)
					(mid 48.87341 -315.849762)
					(end 49.52619 -315.849762)
				)
			)
		)
	)
	(zone
		(layers "B.Cu" "In7.Cu" "In9.Cu" "In11.Cu" "In13.Cu" "In15.Cu")
		(hatch none 0.5)
		(connect_pads
			(clearance 0)
		)
		(min_thickness 0.25)
		(keepout
			(tracks not_allowed)
			(vias allowed)
			(pads allowed)
			(copperpour not_allowed)
			(footprints allowed)
		)
		(placement
			(enabled no)
			(sheetname "")
		)
		(fill yes
			(thermal_gap 0.5)
			(thermal_bridge_width 0.5)
			(island_removal_mode 0)
		)
		(polygon
			(pts
				(arc
					(start 68.525898 -275.949664)
					(mid 67.873118 -275.949664)
					(end 68.525898 -275.949664)
				)
			)
		)
	)
	(zone
		(layers "B.Cu" "In7.Cu" "In9.Cu" "In11.Cu" "In13.Cu" "In15.Cu")
		(hatch none 0.5)
		(connect_pads
			(clearance 0)
		)
		(min_thickness 0.25)
		(keepout
			(tracks not_allowed)
			(vias allowed)
			(pads allowed)
			(copperpour not_allowed)
			(footprints allowed)
		)
		(placement
			(enabled no)
			(sheetname "")
		)
		(fill yes
			(thermal_gap 0.5)
			(thermal_bridge_width 0.5)
			(island_removal_mode 0)
		)
		(polygon
			(pts
				(arc
					(start 406.376378 -318.699896)
					(mid 405.723598 -318.699896)
					(end 406.376378 -318.699896)
				)
			)
		)
	)
	(zone
		(layers "B.Cu" "In7.Cu" "In9.Cu" "In11.Cu" "In13.Cu" "In15.Cu")
		(hatch none 0.5)
		(connect_pads
			(clearance 0)
		)
		(min_thickness 0.25)
		(keepout
			(tracks not_allowed)
			(vias allowed)
			(pads allowed)
			(copperpour not_allowed)
			(footprints allowed)
		)
		(placement
			(enabled no)
			(sheetname "")
		)
		(fill yes
			(thermal_gap 0.5)
			(thermal_bridge_width 0.5)
			(island_removal_mode 0)
		)
		(polygon
			(pts
				(arc
					(start 430.869598 -405.390096)
					(mid 430.110138 -405.390096)
					(end 430.869598 -405.390096)
				)
			)
		)
	)
	(zone
		(layers "B.Cu" "In7.Cu" "In9.Cu" "In11.Cu" "In13.Cu" "In15.Cu")
		(hatch none 0.5)
		(connect_pads
			(clearance 0)
		)
		(min_thickness 0.25)
		(keepout
			(tracks not_allowed)
			(vias allowed)
			(pads allowed)
			(copperpour not_allowed)
			(footprints allowed)
		)
		(placement
			(enabled no)
			(sheetname "")
		)
		(fill yes
			(thermal_gap 0.5)
			(thermal_bridge_width 0.5)
			(island_removal_mode 0)
		)
		(polygon
			(pts
				(arc
					(start 168.694354 -101.976428)
					(mid 167.990774 -101.976428)
					(end 168.694354 -101.976428)
				)
			)
		)
	)
	(zone
		(layers "B.Cu" "In7.Cu" "In9.Cu" "In11.Cu" "In13.Cu" "In15.Cu")
		(hatch none 0.5)
		(connect_pads
			(clearance 0)
		)
		(min_thickness 0.25)
		(keepout
			(tracks not_allowed)
			(vias allowed)
			(pads allowed)
			(copperpour not_allowed)
			(footprints allowed)
		)
		(placement
			(enabled no)
			(sheetname "")
		)
		(fill yes
			(thermal_gap 0.5)
			(thermal_bridge_width 0.5)
			(island_removal_mode 0)
		)
		(polygon
			(pts
				(arc
					(start 428.22622 -307.299868)
					(mid 427.57344 -307.299868)
					(end 428.22622 -307.299868)
				)
			)
		)
	)
	(zone
		(layers "B.Cu" "In7.Cu" "In9.Cu" "In11.Cu" "In13.Cu" "In15.Cu")
		(hatch none 0.5)
		(connect_pads
			(clearance 0)
		)
		(min_thickness 0.25)
		(keepout
			(tracks not_allowed)
			(vias allowed)
			(pads allowed)
			(copperpour not_allowed)
			(footprints allowed)
		)
		(placement
			(enabled no)
			(sheetname "")
		)
		(fill yes
			(thermal_gap 0.5)
			(thermal_bridge_width 0.5)
			(island_removal_mode 0)
		)
		(polygon
			(pts
				(arc
					(start 426.3263 -315.849762)
					(mid 425.67352 -315.849762)
					(end 426.3263 -315.849762)
				)
			)
		)
	)
	(zone
		(layers "B.Cu" "In7.Cu" "In9.Cu" "In11.Cu" "In13.Cu" "In15.Cu")
		(hatch none 0.5)
		(connect_pads
			(clearance 0)
		)
		(min_thickness 0.25)
		(keepout
			(tracks not_allowed)
			(vias allowed)
			(pads allowed)
			(copperpour not_allowed)
			(footprints allowed)
		)
		(placement
			(enabled no)
			(sheetname "")
		)
		(fill yes
			(thermal_gap 0.5)
			(thermal_bridge_width 0.5)
			(island_removal_mode 0)
		)
		(polygon
			(pts
				(arc
					(start 180.82641 -316.799722)
					(mid 180.17363 -316.799722)
					(end 180.82641 -316.799722)
				)
			)
		)
	)
	(zone
		(layers "B.Cu" "In7.Cu" "In9.Cu" "In11.Cu" "In13.Cu" "In15.Cu")
		(hatch none 0.5)
		(connect_pads
			(clearance 0)
		)
		(min_thickness 0.25)
		(keepout
			(tracks not_allowed)
			(vias allowed)
			(pads allowed)
			(copperpour not_allowed)
			(footprints allowed)
		)
		(placement
			(enabled no)
			(sheetname "")
		)
		(fill yes
			(thermal_gap 0.5)
			(thermal_bridge_width 0.5)
			(island_removal_mode 0)
		)
		(polygon
			(pts
				(arc
					(start 402.74875 -110.11281)
					(mid 402.04517 -110.11281)
					(end 402.74875 -110.11281)
				)
			)
		)
	)
	(zone
		(layers "B.Cu" "In7.Cu" "In9.Cu" "In11.Cu" "In13.Cu" "In15.Cu")
		(hatch none 0.5)
		(connect_pads
			(clearance 0)
		)
		(min_thickness 0.25)
		(keepout
			(tracks not_allowed)
			(vias allowed)
			(pads allowed)
			(copperpour not_allowed)
			(footprints allowed)
		)
		(placement
			(enabled no)
			(sheetname "")
		)
		(fill yes
			(thermal_gap 0.5)
			(thermal_bridge_width 0.5)
			(island_removal_mode 0)
		)
		(polygon
			(pts
				(arc
					(start 62.825884 -274.999958)
					(mid 62.173104 -274.999958)
					(end 62.825884 -274.999958)
				)
			)
		)
	)
	(zone
		(layers "B.Cu" "In7.Cu" "In9.Cu" "In11.Cu" "In13.Cu" "In15.Cu")
		(hatch none 0.5)
		(connect_pads
			(clearance 0)
		)
		(min_thickness 0.25)
		(keepout
			(tracks not_allowed)
			(vias allowed)
			(pads allowed)
			(copperpour not_allowed)
			(footprints allowed)
		)
		(placement
			(enabled no)
			(sheetname "")
		)
		(fill yes
			(thermal_gap 0.5)
			(thermal_bridge_width 0.5)
			(island_removal_mode 0)
		)
		(polygon
			(pts
				(arc
					(start 380.26975 -375.69013)
					(mid 379.51029 -375.69013)
					(end 380.26975 -375.69013)
				)
			)
		)
	)
	(zone
		(layers "B.Cu" "In7.Cu" "In9.Cu" "In11.Cu" "In13.Cu" "In15.Cu")
		(hatch none 0.5)
		(connect_pads
			(clearance 0)
		)
		(min_thickness 0.25)
		(keepout
			(tracks not_allowed)
			(vias allowed)
			(pads allowed)
			(copperpour not_allowed)
			(footprints allowed)
		)
		(placement
			(enabled no)
			(sheetname "")
		)
		(fill yes
			(thermal_gap 0.5)
			(thermal_bridge_width 0.5)
			(island_removal_mode 0)
		)
		(polygon
			(pts
				(arc
					(start 198.876412 -274.999704)
					(mid 198.223632 -274.999704)
					(end 198.876412 -274.999704)
				)
			)
		)
	)
	(zone
		(layers "B.Cu" "In7.Cu" "In9.Cu" "In11.Cu" "In13.Cu" "In15.Cu")
		(hatch none 0.5)
		(connect_pads
			(clearance 0)
		)
		(min_thickness 0.25)
		(keepout
			(tracks not_allowed)
			(vias allowed)
			(pads allowed)
			(copperpour not_allowed)
			(footprints allowed)
		)
		(placement
			(enabled no)
			(sheetname "")
		)
		(fill yes
			(thermal_gap 0.5)
			(thermal_bridge_width 0.5)
			(island_removal_mode 0)
		)
		(polygon
			(pts
				(arc
					(start 177.976022 -273.099784)
					(mid 177.323242 -273.099784)
					(end 177.976022 -273.099784)
				)
			)
		)
	)
	(zone
		(layers "B.Cu" "In7.Cu" "In9.Cu" "In11.Cu" "In13.Cu" "In15.Cu")
		(hatch none 0.5)
		(connect_pads
			(clearance 0)
		)
		(min_thickness 0.25)
		(keepout
			(tracks not_allowed)
			(vias allowed)
			(pads allowed)
			(copperpour not_allowed)
			(footprints allowed)
		)
		(placement
			(enabled no)
			(sheetname "")
		)
		(fill yes
			(thermal_gap 0.5)
			(thermal_bridge_width 0.5)
			(island_removal_mode 0)
		)
		(polygon
			(pts
				(arc
					(start 122.889772 -398.890236)
					(mid 122.130312 -398.890236)
					(end 122.889772 -398.890236)
				)
			)
		)
	)
	(zone
		(layers "B.Cu" "In7.Cu" "In9.Cu" "In11.Cu" "In13.Cu" "In15.Cu")
		(hatch none 0.5)
		(connect_pads
			(clearance 0)
		)
		(min_thickness 0.25)
		(keepout
			(tracks not_allowed)
			(vias allowed)
			(pads allowed)
			(copperpour not_allowed)
			(footprints allowed)
		)
		(placement
			(enabled no)
			(sheetname "")
		)
		(fill yes
			(thermal_gap 0.5)
			(thermal_bridge_width 0.5)
			(island_removal_mode 0)
		)
		(polygon
			(pts
				(arc
					(start 168.476422 -318.699896)
					(mid 167.823642 -318.699896)
					(end 168.476422 -318.699896)
				)
			)
		)
	)
	(zone
		(layers "B.Cu" "In7.Cu" "In9.Cu" "In11.Cu" "In13.Cu" "In15.Cu")
		(hatch none 0.5)
		(connect_pads
			(clearance 0)
		)
		(min_thickness 0.25)
		(keepout
			(tracks not_allowed)
			(vias allowed)
			(pads allowed)
			(copperpour not_allowed)
			(footprints allowed)
		)
		(placement
			(enabled no)
			(sheetname "")
		)
		(fill yes
			(thermal_gap 0.5)
			(thermal_bridge_width 0.5)
			(island_removal_mode 0)
		)
		(polygon
			(pts
				(arc
					(start 176.076102 -274.04949)
					(mid 175.423322 -274.04949)
					(end 176.076102 -274.04949)
				)
			)
		)
	)
	(zone
		(layers "B.Cu" "In7.Cu" "In9.Cu" "In11.Cu" "In13.Cu" "In15.Cu")
		(hatch none 0.5)
		(connect_pads
			(clearance 0)
		)
		(min_thickness 0.25)
		(keepout
			(tracks not_allowed)
			(vias allowed)
			(pads allowed)
			(copperpour not_allowed)
			(footprints allowed)
		)
		(placement
			(enabled no)
			(sheetname "")
		)
		(fill yes
			(thermal_gap 0.5)
			(thermal_bridge_width 0.5)
			(island_removal_mode 0)
		)
		(polygon
			(pts
				(arc
					(start 125.08992 -397.790162)
					(mid 124.33046 -397.790162)
					(end 125.08992 -397.790162)
				)
			)
		)
	)
	(zone
		(layers "B.Cu" "In7.Cu" "In9.Cu" "In11.Cu" "In13.Cu" "In15.Cu")
		(hatch none 0.5)
		(connect_pads
			(clearance 0)
		)
		(min_thickness 0.25)
		(keepout
			(tracks not_allowed)
			(vias allowed)
			(pads allowed)
			(copperpour not_allowed)
			(footprints allowed)
		)
		(placement
			(enabled no)
			(sheetname "")
		)
		(fill yes
			(thermal_gap 0.5)
			(thermal_bridge_width 0.5)
			(island_removal_mode 0)
		)
		(polygon
			(pts
				(arc
					(start 400.89455 -101.976428)
					(mid 400.19097 -101.976428)
					(end 400.89455 -101.976428)
				)
			)
		)
	)
	(zone
		(layers "B.Cu" "In7.Cu" "In9.Cu" "In11.Cu" "In13.Cu" "In15.Cu")
		(hatch none 0.5)
		(connect_pads
			(clearance 0)
		)
		(min_thickness 0.25)
		(keepout
			(tracks not_allowed)
			(vias allowed)
			(pads allowed)
			(copperpour not_allowed)
			(footprints allowed)
		)
		(placement
			(enabled no)
			(sheetname "")
		)
		(fill yes
			(thermal_gap 0.5)
			(thermal_bridge_width 0.5)
			(island_removal_mode 0)
		)
		(polygon
			(pts
				(arc
					(start 196.975984 -274.049744)
					(mid 196.323204 -274.049744)
					(end 196.975984 -274.049744)
				)
			)
		)
	)
	(zone
		(layers "B.Cu" "In7.Cu" "In9.Cu" "In11.Cu" "In13.Cu" "In15.Cu")
		(hatch none 0.5)
		(connect_pads
			(clearance 0)
		)
		(min_thickness 0.25)
		(keepout
			(tracks not_allowed)
			(vias allowed)
			(pads allowed)
			(copperpour not_allowed)
			(footprints allowed)
		)
		(placement
			(enabled no)
			(sheetname "")
		)
		(fill yes
			(thermal_gap 0.5)
			(thermal_bridge_width 0.5)
			(island_removal_mode 0)
		)
		(polygon
			(pts
				(arc
					(start 299.609002 -123.16714)
					(mid 298.905422 -123.16714)
					(end 299.609002 -123.16714)
				)
			)
		)
	)
	(zone
		(layers "B.Cu" "In7.Cu" "In9.Cu" "In11.Cu" "In13.Cu" "In15.Cu")
		(hatch none 0.5)
		(connect_pads
			(clearance 0)
		)
		(min_thickness 0.25)
		(keepout
			(tracks not_allowed)
			(vias allowed)
			(pads allowed)
			(copperpour not_allowed)
			(footprints allowed)
		)
		(placement
			(enabled no)
			(sheetname "")
		)
		(fill yes
			(thermal_gap 0.5)
			(thermal_bridge_width 0.5)
			(island_removal_mode 0)
		)
		(polygon
			(pts
				(arc
					(start 294.075866 -273.099784)
					(mid 293.423086 -273.099784)
					(end 294.075866 -273.099784)
				)
			)
		)
	)
	(zone
		(layers "B.Cu" "In7.Cu" "In9.Cu" "In11.Cu" "In13.Cu" "In15.Cu")
		(hatch none 0.5)
		(connect_pads
			(clearance 0)
		)
		(min_thickness 0.25)
		(keepout
			(tracks not_allowed)
			(vias allowed)
			(pads allowed)
			(copperpour not_allowed)
			(footprints allowed)
		)
		(placement
			(enabled no)
			(sheetname "")
		)
		(fill yes
			(thermal_gap 0.5)
			(thermal_bridge_width 0.5)
			(island_removal_mode 0)
		)
		(polygon
			(pts
				(arc
					(start 173.48962 -378.290074)
					(mid 172.73016 -378.290074)
					(end 173.48962 -378.290074)
				)
			)
		)
	)
	(zone
		(layers "B.Cu" "In7.Cu" "In9.Cu" "In11.Cu" "In13.Cu" "In15.Cu")
		(hatch none 0.5)
		(connect_pads
			(clearance 0)
		)
		(min_thickness 0.25)
		(keepout
			(tracks not_allowed)
			(vias allowed)
			(pads allowed)
			(copperpour not_allowed)
			(footprints allowed)
		)
		(placement
			(enabled no)
			(sheetname "")
		)
		(fill yes
			(thermal_gap 0.5)
			(thermal_bridge_width 0.5)
			(island_removal_mode 0)
		)
		(polygon
			(pts
				(arc
					(start 314.976256 -274.999704)
					(mid 314.323476 -274.999704)
					(end 314.976256 -274.999704)
				)
			)
		)
	)
	(zone
		(layers "B.Cu" "In7.Cu" "In9.Cu" "In11.Cu" "In13.Cu" "In15.Cu")
		(hatch none 0.5)
		(connect_pads
			(clearance 0)
		)
		(min_thickness 0.25)
		(keepout
			(tracks not_allowed)
			(vias allowed)
			(pads allowed)
			(copperpour not_allowed)
			(footprints allowed)
		)
		(placement
			(enabled no)
			(sheetname "")
		)
		(fill yes
			(thermal_gap 0.5)
			(thermal_bridge_width 0.5)
			(island_removal_mode 0)
		)
		(polygon
			(pts
				(arc
					(start 435.26964 -405.390096)
					(mid 434.51018 -405.390096)
					(end 435.26964 -405.390096)
				)
			)
		)
	)
	(zone
		(layers "B.Cu" "In7.Cu" "In9.Cu" "In11.Cu" "In13.Cu" "In15.Cu")
		(hatch none 0.5)
		(connect_pads
			(clearance 0)
		)
		(min_thickness 0.25)
		(keepout
			(tracks not_allowed)
			(vias allowed)
			(pads allowed)
			(copperpour not_allowed)
			(footprints allowed)
		)
		(placement
			(enabled no)
			(sheetname "")
		)
		(fill yes
			(thermal_gap 0.5)
			(thermal_bridge_width 0.5)
			(island_removal_mode 0)
		)
		(polygon
			(pts
				(arc
					(start 79.92618 -288.299906)
					(mid 79.2734 -288.299906)
					(end 79.92618 -288.299906)
				)
			)
		)
	)
	(zone
		(layers "B.Cu" "In7.Cu" "In9.Cu" "In11.Cu" "In13.Cu" "In15.Cu")
		(hatch none 0.5)
		(connect_pads
			(clearance 0)
		)
		(min_thickness 0.25)
		(keepout
			(tracks not_allowed)
			(vias allowed)
			(pads allowed)
			(copperpour not_allowed)
			(footprints allowed)
		)
		(placement
			(enabled no)
			(sheetname "")
		)
		(fill yes
			(thermal_gap 0.5)
			(thermal_bridge_width 0.5)
			(island_removal_mode 0)
		)
		(polygon
			(pts
				(arc
					(start 192.226438 -316.799722)
					(mid 191.573658 -316.799722)
					(end 192.226438 -316.799722)
				)
			)
		)
	)
	(zone
		(layers "B.Cu" "In7.Cu" "In9.Cu" "In11.Cu" "In13.Cu" "In15.Cu")
		(hatch none 0.5)
		(connect_pads
			(clearance 0)
		)
		(min_thickness 0.25)
		(keepout
			(tracks not_allowed)
			(vias allowed)
			(pads allowed)
			(copperpour not_allowed)
			(footprints allowed)
		)
		(placement
			(enabled no)
			(sheetname "")
		)
		(fill yes
			(thermal_gap 0.5)
			(thermal_bridge_width 0.5)
			(island_removal_mode 0)
		)
		(polygon
			(pts
				(arc
					(start 299.609002 -154.28722)
					(mid 298.905422 -154.28722)
					(end 299.609002 -154.28722)
				)
			)
		)
	)
	(zone
		(layers "B.Cu" "In7.Cu" "In9.Cu" "In11.Cu" "In13.Cu" "In15.Cu")
		(hatch none 0.5)
		(connect_pads
			(clearance 0)
		)
		(min_thickness 0.25)
		(keepout
			(tracks not_allowed)
			(vias allowed)
			(pads allowed)
			(copperpour not_allowed)
			(footprints allowed)
		)
		(placement
			(enabled no)
			(sheetname "")
		)
		(fill yes
			(thermal_gap 0.5)
			(thermal_bridge_width 0.5)
			(island_removal_mode 0)
		)
		(polygon
			(pts
				(arc
					(start 426.469556 -380.69012)
					(mid 425.710096 -380.69012)
					(end 426.469556 -380.69012)
				)
			)
		)
	)
	(zone
		(layers "B.Cu" "In7.Cu" "In9.Cu" "In11.Cu" "In13.Cu" "In15.Cu")
		(hatch none 0.5)
		(connect_pads
			(clearance 0)
		)
		(min_thickness 0.25)
		(keepout
			(tracks not_allowed)
			(vias allowed)
			(pads allowed)
			(copperpour not_allowed)
			(footprints allowed)
		)
		(placement
			(enabled no)
			(sheetname "")
		)
		(fill yes
			(thermal_gap 0.5)
			(thermal_bridge_width 0.5)
			(island_removal_mode 0)
		)
		(polygon
			(pts
				(arc
					(start 41.48963 -382.18999)
					(mid 40.73017 -382.18999)
					(end 41.48963 -382.18999)
				)
			)
		)
	)
	(zone
		(layers "B.Cu" "In7.Cu" "In9.Cu" "In11.Cu" "In13.Cu" "In15.Cu")
		(hatch none 0.5)
		(connect_pads
			(clearance 0)
		)
		(min_thickness 0.25)
		(keepout
			(tracks not_allowed)
			(vias allowed)
			(pads allowed)
			(copperpour not_allowed)
			(footprints allowed)
		)
		(placement
			(enabled no)
			(sheetname "")
		)
		(fill yes
			(thermal_gap 0.5)
			(thermal_bridge_width 0.5)
			(island_removal_mode 0)
		)
		(polygon
			(pts
				(arc
					(start 167.526462 -316.799722)
					(mid 166.873682 -316.799722)
					(end 167.526462 -316.799722)
				)
			)
		)
	)
	(zone
		(layers "B.Cu" "In7.Cu" "In9.Cu" "In11.Cu" "In13.Cu" "In15.Cu")
		(hatch none 0.5)
		(connect_pads
			(clearance 0)
		)
		(min_thickness 0.25)
		(keepout
			(tracks not_allowed)
			(vias allowed)
			(pads allowed)
			(copperpour not_allowed)
			(footprints allowed)
		)
		(placement
			(enabled no)
			(sheetname "")
		)
		(fill yes
			(thermal_gap 0.5)
			(thermal_bridge_width 0.5)
			(island_removal_mode 0)
		)
		(polygon
			(pts
				(arc
					(start 382.469644 -398.890236)
					(mid 381.710184 -398.890236)
					(end 382.469644 -398.890236)
				)
			)
		)
	)
	(zone
		(layers "B.Cu" "In7.Cu" "In9.Cu" "In11.Cu" "In13.Cu" "In15.Cu")
		(hatch none 0.5)
		(connect_pads
			(clearance 0)
		)
		(min_thickness 0.25)
		(keepout
			(tracks not_allowed)
			(vias allowed)
			(pads allowed)
			(copperpour not_allowed)
			(footprints allowed)
		)
		(placement
			(enabled no)
			(sheetname "")
		)
		(fill yes
			(thermal_gap 0.5)
			(thermal_bridge_width 0.5)
			(island_removal_mode 0)
		)
		(polygon
			(pts
				(arc
					(start 428.22622 -309.199788)
					(mid 427.57344 -309.199788)
					(end 428.22622 -309.199788)
				)
			)
		)
	)
	(zone
		(layers "B.Cu" "In7.Cu" "In9.Cu" "In11.Cu" "In13.Cu" "In15.Cu")
		(hatch none 0.5)
		(connect_pads
			(clearance 0)
		)
		(min_thickness 0.25)
		(keepout
			(tracks not_allowed)
			(vias allowed)
			(pads allowed)
			(copperpour not_allowed)
			(footprints allowed)
		)
		(placement
			(enabled no)
			(sheetname "")
		)
		(fill yes
			(thermal_gap 0.5)
			(thermal_bridge_width 0.5)
			(island_removal_mode 0)
		)
		(polygon
			(pts
				(arc
					(start 270.326104 -302.549814)
					(mid 269.673324 -302.549814)
					(end 270.326104 -302.549814)
				)
			)
		)
	)
	(zone
		(layers "B.Cu" "In7.Cu" "In9.Cu" "In11.Cu" "In13.Cu" "In15.Cu")
		(hatch none 0.5)
		(connect_pads
			(clearance 0)
		)
		(min_thickness 0.25)
		(keepout
			(tracks not_allowed)
			(vias allowed)
			(pads allowed)
			(copperpour not_allowed)
			(footprints allowed)
		)
		(placement
			(enabled no)
			(sheetname "")
		)
		(fill yes
			(thermal_gap 0.5)
			(thermal_bridge_width 0.5)
			(island_removal_mode 0)
		)
		(polygon
			(pts
				(arc
					(start 122.889772 -397.59001)
					(mid 122.130312 -397.59001)
					(end 122.889772 -397.59001)
				)
			)
		)
	)
	(zone
		(layers "B.Cu" "In7.Cu" "In9.Cu" "In11.Cu" "In13.Cu" "In15.Cu")
		(hatch none 0.5)
		(connect_pads
			(clearance 0)
		)
		(min_thickness 0.25)
		(keepout
			(tracks not_allowed)
			(vias allowed)
			(pads allowed)
			(copperpour not_allowed)
			(footprints allowed)
		)
		(placement
			(enabled no)
			(sheetname "")
		)
		(fill yes
			(thermal_gap 0.5)
			(thermal_bridge_width 0.5)
			(island_removal_mode 0)
		)
		(polygon
			(pts
				(arc
					(start 284.794452 -108.312712)
					(mid 284.090872 -108.312712)
					(end 284.794452 -108.312712)
				)
			)
		)
	)
	(zone
		(layers "B.Cu" "In7.Cu" "In9.Cu" "In11.Cu" "In13.Cu" "In15.Cu")
		(hatch none 0.5)
		(connect_pads
			(clearance 0)
		)
		(min_thickness 0.25)
		(keepout
			(tracks not_allowed)
			(vias allowed)
			(pads allowed)
			(copperpour not_allowed)
			(footprints allowed)
		)
		(placement
			(enabled no)
			(sheetname "")
		)
		(fill yes
			(thermal_gap 0.5)
			(thermal_bridge_width 0.5)
			(island_removal_mode 0)
		)
		(polygon
			(pts
				(arc
					(start 61.875924 -274.049744)
					(mid 61.223144 -274.049744)
					(end 61.875924 -274.049744)
				)
			)
		)
	)
	(zone
		(layers "B.Cu" "In7.Cu" "In9.Cu" "In11.Cu" "In13.Cu" "In15.Cu")
		(hatch none 0.5)
		(connect_pads
			(clearance 0)
		)
		(min_thickness 0.25)
		(keepout
			(tracks not_allowed)
			(vias allowed)
			(pads allowed)
			(copperpour not_allowed)
			(footprints allowed)
		)
		(placement
			(enabled no)
			(sheetname "")
		)
		(fill yes
			(thermal_gap 0.5)
			(thermal_bridge_width 0.5)
			(island_removal_mode 0)
		)
		(polygon
			(pts
				(arc
					(start 410.176218 -317.749936)
					(mid 409.523438 -317.749936)
					(end 410.176218 -317.749936)
				)
			)
		)
	)
	(zone
		(layers "B.Cu" "In7.Cu" "In9.Cu" "In11.Cu" "In13.Cu" "In15.Cu")
		(hatch none 0.5)
		(connect_pads
			(clearance 0)
		)
		(min_thickness 0.25)
		(keepout
			(tracks not_allowed)
			(vias allowed)
			(pads allowed)
			(copperpour not_allowed)
			(footprints allowed)
		)
		(placement
			(enabled no)
			(sheetname "")
		)
		(fill yes
			(thermal_gap 0.5)
			(thermal_bridge_width 0.5)
			(island_removal_mode 0)
		)
		(polygon
			(pts
				(arc
					(start 428.22622 -288.299906)
					(mid 427.57344 -288.299906)
					(end 428.22622 -288.299906)
				)
			)
		)
	)
	(zone
		(layers "B.Cu" "In7.Cu" "In9.Cu" "In11.Cu" "In13.Cu" "In15.Cu")
		(hatch none 0.5)
		(connect_pads
			(clearance 0)
		)
		(min_thickness 0.25)
		(keepout
			(tracks not_allowed)
			(vias allowed)
			(pads allowed)
			(copperpour not_allowed)
			(footprints allowed)
		)
		(placement
			(enabled no)
			(sheetname "")
		)
		(fill yes
			(thermal_gap 0.5)
			(thermal_bridge_width 0.5)
			(island_removal_mode 0)
		)
		(polygon
			(pts
				(arc
					(start 399.726404 -316.799722)
					(mid 399.073624 -316.799722)
					(end 399.726404 -316.799722)
				)
			)
		)
	)
	(zone
		(layers "B.Cu" "In7.Cu" "In9.Cu" "In11.Cu" "In13.Cu" "In15.Cu")
		(hatch none 0.5)
		(connect_pads
			(clearance 0)
		)
		(min_thickness 0.25)
		(keepout
			(tracks not_allowed)
			(vias allowed)
			(pads allowed)
			(copperpour not_allowed)
			(footprints allowed)
		)
		(placement
			(enabled no)
			(sheetname "")
		)
		(fill yes
			(thermal_gap 0.5)
			(thermal_bridge_width 0.5)
			(island_removal_mode 0)
		)
		(polygon
			(pts
				(arc
					(start 197.926452 -287.349946)
					(mid 197.273672 -287.349946)
					(end 197.926452 -287.349946)
				)
			)
		)
	)
	(zone
		(layers "B.Cu" "In7.Cu" "In9.Cu" "In11.Cu" "In13.Cu" "In15.Cu")
		(hatch none 0.5)
		(connect_pads
			(clearance 0)
		)
		(min_thickness 0.25)
		(keepout
			(tracks not_allowed)
			(vias allowed)
			(pads allowed)
			(copperpour not_allowed)
			(footprints allowed)
		)
		(placement
			(enabled no)
			(sheetname "")
		)
		(fill yes
			(thermal_gap 0.5)
			(thermal_bridge_width 0.5)
			(island_removal_mode 0)
		)
		(polygon
			(pts
				(arc
					(start 52.59451 -136.69645)
					(mid 51.89093 -136.69645)
					(end 52.59451 -136.69645)
				)
			)
		)
	)
	(zone
		(layers "B.Cu" "In7.Cu" "In9.Cu" "In11.Cu" "In13.Cu" "In15.Cu")
		(hatch none 0.5)
		(connect_pads
			(clearance 0)
		)
		(min_thickness 0.25)
		(keepout
			(tracks not_allowed)
			(vias allowed)
			(pads allowed)
			(copperpour not_allowed)
			(footprints allowed)
		)
		(placement
			(enabled no)
			(sheetname "")
		)
		(fill yes
			(thermal_gap 0.5)
			(thermal_bridge_width 0.5)
			(island_removal_mode 0)
		)
		(polygon
			(pts
				(arc
					(start 296.669714 -408.190192)
					(mid 295.910254 -408.190192)
					(end 296.669714 -408.190192)
				)
			)
		)
	)
	(zone
		(layers "B.Cu" "In7.Cu" "In9.Cu" "In11.Cu" "In13.Cu" "In15.Cu")
		(hatch none 0.5)
		(connect_pads
			(clearance 0)
		)
		(min_thickness 0.25)
		(keepout
			(tracks not_allowed)
			(vias allowed)
			(pads allowed)
			(copperpour not_allowed)
			(footprints allowed)
		)
		(placement
			(enabled no)
			(sheetname "")
		)
		(fill yes
			(thermal_gap 0.5)
			(thermal_bridge_width 0.5)
			(island_removal_mode 0)
		)
		(polygon
			(pts
				(arc
					(start 301.676308 -318.699896)
					(mid 301.023528 -318.699896)
					(end 301.676308 -318.699896)
				)
			)
		)
	)
	(zone
		(layers "B.Cu" "In7.Cu" "In9.Cu" "In11.Cu" "In13.Cu" "In15.Cu")
		(hatch none 0.5)
		(connect_pads
			(clearance 0)
		)
		(min_thickness 0.25)
		(keepout
			(tracks not_allowed)
			(vias allowed)
			(pads allowed)
			(copperpour not_allowed)
			(footprints allowed)
		)
		(placement
			(enabled no)
			(sheetname "")
		)
		(fill yes
			(thermal_gap 0.5)
			(thermal_bridge_width 0.5)
			(island_removal_mode 0)
		)
		(polygon
			(pts
				(arc
					(start 271.276318 -317.749936)
					(mid 270.623538 -317.749936)
					(end 271.276318 -317.749936)
				)
			)
		)
	)
	(zone
		(layers "B.Cu" "In7.Cu" "In9.Cu" "In11.Cu" "In13.Cu" "In15.Cu")
		(hatch none 0.5)
		(connect_pads
			(clearance 0)
		)
		(min_thickness 0.25)
		(keepout
			(tracks not_allowed)
			(vias allowed)
			(pads allowed)
			(copperpour not_allowed)
			(footprints allowed)
		)
		(placement
			(enabled no)
			(sheetname "")
		)
		(fill yes
			(thermal_gap 0.5)
			(thermal_bridge_width 0.5)
			(island_removal_mode 0)
		)
		(polygon
			(pts
				(arc
					(start 430.126394 -281.649932)
					(mid 429.473614 -281.649932)
					(end 430.126394 -281.649932)
				)
			)
		)
	)
	(zone
		(layers "B.Cu" "In7.Cu" "In9.Cu" "In11.Cu" "In13.Cu" "In15.Cu")
		(hatch none 0.5)
		(connect_pads
			(clearance 0)
		)
		(min_thickness 0.25)
		(keepout
			(tracks not_allowed)
			(vias allowed)
			(pads allowed)
			(copperpour not_allowed)
			(footprints allowed)
		)
		(placement
			(enabled no)
			(sheetname "")
		)
		(fill yes
			(thermal_gap 0.5)
			(thermal_bridge_width 0.5)
			(island_removal_mode 0)
		)
		(polygon
			(pts
				(arc
					(start 168.694354 -121.886472)
					(mid 167.990774 -121.886472)
					(end 168.694354 -121.886472)
				)
			)
		)
	)
	(zone
		(layers "B.Cu" "In7.Cu" "In9.Cu" "In11.Cu" "In13.Cu" "In15.Cu")
		(hatch none 0.5)
		(connect_pads
			(clearance 0)
		)
		(min_thickness 0.25)
		(keepout
			(tracks not_allowed)
			(vias allowed)
			(pads allowed)
			(copperpour not_allowed)
			(footprints allowed)
		)
		(placement
			(enabled no)
			(sheetname "")
		)
		(fill yes
			(thermal_gap 0.5)
			(thermal_bridge_width 0.5)
			(island_removal_mode 0)
		)
		(polygon
			(pts
				(arc
					(start 413.8549 -124.967238)
					(mid 413.15132 -124.967238)
					(end 413.8549 -124.967238)
				)
			)
		)
	)
	(zone
		(layers "B.Cu" "In7.Cu" "In9.Cu" "In11.Cu" "In13.Cu" "In15.Cu")
		(hatch none 0.5)
		(connect_pads
			(clearance 0)
		)
		(min_thickness 0.25)
		(keepout
			(tracks not_allowed)
			(vias allowed)
			(pads allowed)
			(copperpour not_allowed)
			(footprints allowed)
		)
		(placement
			(enabled no)
			(sheetname "")
		)
		(fill yes
			(thermal_gap 0.5)
			(thermal_bridge_width 0.5)
			(island_removal_mode 0)
		)
		(polygon
			(pts
				(arc
					(start 166.889684 -379.390148)
					(mid 166.130224 -379.390148)
					(end 166.889684 -379.390148)
				)
			)
		)
	)
	(zone
		(layers "B.Cu" "In7.Cu" "In9.Cu" "In11.Cu" "In13.Cu" "In15.Cu")
		(hatch none 0.5)
		(connect_pads
			(clearance 0)
		)
		(min_thickness 0.25)
		(keepout
			(tracks not_allowed)
			(vias allowed)
			(pads allowed)
			(copperpour not_allowed)
			(footprints allowed)
		)
		(placement
			(enabled no)
			(sheetname "")
		)
		(fill yes
			(thermal_gap 0.5)
			(thermal_bridge_width 0.5)
			(island_removal_mode 0)
		)
		(polygon
			(pts
				(arc
					(start 67.40906 -119.567198)
					(mid 66.70548 -119.567198)
					(end 67.40906 -119.567198)
				)
			)
		)
	)
	(zone
		(layers "B.Cu" "In7.Cu" "In9.Cu" "In11.Cu" "In13.Cu" "In15.Cu")
		(hatch none 0.5)
		(connect_pads
			(clearance 0)
		)
		(min_thickness 0.25)
		(keepout
			(tracks not_allowed)
			(vias allowed)
			(pads allowed)
			(copperpour not_allowed)
			(footprints allowed)
		)
		(placement
			(enabled no)
			(sheetname "")
		)
		(fill yes
			(thermal_gap 0.5)
			(thermal_bridge_width 0.5)
			(island_removal_mode 0)
		)
		(polygon
			(pts
				(arc
					(start 87.68969 -371.590062)
					(mid 86.93023 -371.590062)
					(end 87.68969 -371.590062)
				)
			)
		)
	)
	(zone
		(layers "B.Cu" "In7.Cu" "In9.Cu" "In11.Cu" "In13.Cu" "In15.Cu")
		(hatch none 0.5)
		(connect_pads
			(clearance 0)
		)
		(min_thickness 0.25)
		(keepout
			(tracks not_allowed)
			(vias allowed)
			(pads allowed)
			(copperpour not_allowed)
			(footprints allowed)
		)
		(placement
			(enabled no)
			(sheetname "")
		)
		(fill yes
			(thermal_gap 0.5)
			(thermal_bridge_width 0.5)
			(island_removal_mode 0)
		)
		(polygon
			(pts
				(arc
					(start 76.689712 -401.690078)
					(mid 75.930252 -401.690078)
					(end 76.689712 -401.690078)
				)
			)
		)
	)
	(zone
		(layers "B.Cu" "In7.Cu" "In9.Cu" "In11.Cu" "In13.Cu" "In15.Cu")
		(hatch none 0.5)
		(connect_pads
			(clearance 0)
		)
		(min_thickness 0.25)
		(keepout
			(tracks not_allowed)
			(vias allowed)
			(pads allowed)
			(copperpour not_allowed)
			(footprints allowed)
		)
		(placement
			(enabled no)
			(sheetname "")
		)
		(fill yes
			(thermal_gap 0.5)
			(thermal_bridge_width 0.5)
			(island_removal_mode 0)
		)
		(polygon
			(pts
				(arc
					(start 312.126122 -284.499812)
					(mid 311.473342 -284.499812)
					(end 312.126122 -284.499812)
				)
			)
		)
	)
	(zone
		(layers "B.Cu" "In7.Cu" "In9.Cu" "In11.Cu" "In13.Cu" "In15.Cu")
		(hatch none 0.5)
		(connect_pads
			(clearance 0)
		)
		(min_thickness 0.25)
		(keepout
			(tracks not_allowed)
			(vias allowed)
			(pads allowed)
			(copperpour not_allowed)
			(footprints allowed)
		)
		(placement
			(enabled no)
			(sheetname "")
		)
		(fill yes
			(thermal_gap 0.5)
			(thermal_bridge_width 0.5)
			(island_removal_mode 0)
		)
		(polygon
			(pts
				(arc
					(start 196.026278 -309.199788)
					(mid 195.373498 -309.199788)
					(end 196.026278 -309.199788)
				)
			)
		)
	)
	(zone
		(layers "B.Cu" "In7.Cu" "In9.Cu" "In11.Cu" "In13.Cu" "In15.Cu")
		(hatch none 0.5)
		(connect_pads
			(clearance 0)
		)
		(min_thickness 0.25)
		(keepout
			(tracks not_allowed)
			(vias allowed)
			(pads allowed)
			(copperpour not_allowed)
			(footprints allowed)
		)
		(placement
			(enabled no)
			(sheetname "")
		)
		(fill yes
			(thermal_gap 0.5)
			(thermal_bridge_width 0.5)
			(island_removal_mode 0)
		)
		(polygon
			(pts
				(arc
					(start 164.68979 -404.290022)
					(mid 163.93033 -404.290022)
					(end 164.68979 -404.290022)
				)
			)
		)
	)
	(zone
		(layers "B.Cu" "In7.Cu" "In9.Cu" "In11.Cu" "In13.Cu" "In15.Cu")
		(hatch none 0.5)
		(connect_pads
			(clearance 0)
		)
		(min_thickness 0.25)
		(keepout
			(tracks not_allowed)
			(vias allowed)
			(pads allowed)
			(copperpour not_allowed)
			(footprints allowed)
		)
		(placement
			(enabled no)
			(sheetname "")
		)
		(fill yes
			(thermal_gap 0.5)
			(thermal_bridge_width 0.5)
			(island_removal_mode 0)
		)
		(polygon
			(pts
				(arc
					(start 52.59451 -111.912908)
					(mid 51.89093 -111.912908)
					(end 52.59451 -111.912908)
				)
			)
		)
	)
	(zone
		(layers "B.Cu" "In7.Cu" "In9.Cu" "In11.Cu" "In13.Cu" "In15.Cu")
		(hatch none 0.5)
		(connect_pads
			(clearance 0)
		)
		(min_thickness 0.25)
		(keepout
			(tracks not_allowed)
			(vias allowed)
			(pads allowed)
			(copperpour not_allowed)
			(footprints allowed)
		)
		(placement
			(enabled no)
			(sheetname "")
		)
		(fill yes
			(thermal_gap 0.5)
			(thermal_bridge_width 0.5)
			(island_removal_mode 0)
		)
		(polygon
			(pts
				(arc
					(start 419.676072 -273.099784)
					(mid 419.023292 -273.099784)
					(end 419.676072 -273.099784)
				)
			)
		)
	)
	(zone
		(layers "B.Cu" "In7.Cu" "In9.Cu" "In11.Cu" "In13.Cu" "In15.Cu")
		(hatch none 0.5)
		(connect_pads
			(clearance 0)
		)
		(min_thickness 0.25)
		(keepout
			(tracks not_allowed)
			(vias allowed)
			(pads allowed)
			(copperpour not_allowed)
			(footprints allowed)
		)
		(placement
			(enabled no)
			(sheetname "")
		)
		(fill yes
			(thermal_gap 0.5)
			(thermal_bridge_width 0.5)
			(island_removal_mode 0)
		)
		(polygon
			(pts
				(arc
					(start 428.22622 -315.849762)
					(mid 427.57344 -315.849762)
					(end 428.22622 -315.849762)
				)
			)
		)
	)
	(zone
		(layers "B.Cu" "In7.Cu" "In9.Cu" "In11.Cu" "In13.Cu" "In15.Cu")
		(hatch none 0.5)
		(connect_pads
			(clearance 0)
		)
		(min_thickness 0.25)
		(keepout
			(tracks not_allowed)
			(vias allowed)
			(pads allowed)
			(copperpour not_allowed)
			(footprints allowed)
		)
		(placement
			(enabled no)
			(sheetname "")
		)
		(fill yes
			(thermal_gap 0.5)
			(thermal_bridge_width 0.5)
			(island_removal_mode 0)
		)
		(polygon
			(pts
				(arc
					(start 37.176202 -306.349908)
					(mid 36.523422 -306.349908)
					(end 37.176202 -306.349908)
				)
			)
		)
	)
	(zone
		(layers "B.Cu" "In7.Cu" "In9.Cu" "In11.Cu" "In13.Cu" "In15.Cu")
		(hatch none 0.5)
		(connect_pads
			(clearance 0)
		)
		(min_thickness 0.25)
		(keepout
			(tracks not_allowed)
			(vias allowed)
			(pads allowed)
			(copperpour not_allowed)
			(footprints allowed)
		)
		(placement
			(enabled no)
			(sheetname "")
		)
		(fill yes
			(thermal_gap 0.5)
			(thermal_bridge_width 0.5)
			(island_removal_mode 0)
		)
		(polygon
			(pts
				(arc
					(start 181.654704 -124.103638)
					(mid 180.951124 -124.103638)
					(end 181.654704 -124.103638)
				)
			)
		)
	)
	(zone
		(layers "B.Cu" "In7.Cu" "In9.Cu" "In11.Cu" "In13.Cu" "In15.Cu")
		(hatch none 0.5)
		(connect_pads
			(clearance 0)
		)
		(min_thickness 0.25)
		(keepout
			(tracks not_allowed)
			(vias allowed)
			(pads allowed)
			(copperpour not_allowed)
			(footprints allowed)
		)
		(placement
			(enabled no)
			(sheetname "")
		)
		(fill yes
			(thermal_gap 0.5)
			(thermal_bridge_width 0.5)
			(island_removal_mode 0)
		)
		(polygon
			(pts
				(arc
					(start 168.694354 -105.57637)
					(mid 167.990774 -105.57637)
					(end 168.694354 -105.57637)
				)
			)
		)
	)
	(zone
		(layers "B.Cu" "In7.Cu" "In9.Cu" "In11.Cu" "In13.Cu" "In15.Cu")
		(hatch none 0.5)
		(connect_pads
			(clearance 0)
		)
		(min_thickness 0.25)
		(keepout
			(tracks not_allowed)
			(vias allowed)
			(pads allowed)
			(copperpour not_allowed)
			(footprints allowed)
		)
		(placement
			(enabled no)
			(sheetname "")
		)
		(fill yes
			(thermal_gap 0.5)
			(thermal_bridge_width 0.5)
			(island_removal_mode 0)
		)
		(polygon
			(pts
				(arc
					(start 427.27626 -317.749936)
					(mid 426.62348 -317.749936)
					(end 427.27626 -317.749936)
				)
			)
		)
	)
	(zone
		(layers "B.Cu" "In7.Cu" "In9.Cu" "In11.Cu" "In13.Cu" "In15.Cu")
		(hatch none 0.5)
		(connect_pads
			(clearance 0)
		)
		(min_thickness 0.25)
		(keepout
			(tracks not_allowed)
			(vias allowed)
			(pads allowed)
			(copperpour not_allowed)
			(footprints allowed)
		)
		(placement
			(enabled no)
			(sheetname "")
		)
		(fill yes
			(thermal_gap 0.5)
			(thermal_bridge_width 0.5)
			(island_removal_mode 0)
		)
		(polygon
			(pts
				(arc
					(start 54.44871 -130.43281)
					(mid 53.74513 -130.43281)
					(end 54.44871 -130.43281)
				)
			)
		)
	)
	(zone
		(layers "B.Cu" "In7.Cu" "In9.Cu" "In11.Cu" "In13.Cu" "In15.Cu")
		(hatch none 0.5)
		(connect_pads
			(clearance 0)
		)
		(min_thickness 0.25)
		(keepout
			(tracks not_allowed)
			(vias allowed)
			(pads allowed)
			(copperpour not_allowed)
			(footprints allowed)
		)
		(placement
			(enabled no)
			(sheetname "")
		)
		(fill yes
			(thermal_gap 0.5)
			(thermal_bridge_width 0.5)
			(island_removal_mode 0)
		)
		(polygon
			(pts
				(arc
					(start 272.226278 -303.499774)
					(mid 271.573498 -303.499774)
					(end 272.226278 -303.499774)
				)
			)
		)
	)
	(zone
		(layers "B.Cu" "In7.Cu" "In9.Cu" "In11.Cu" "In13.Cu" "In15.Cu")
		(hatch none 0.5)
		(connect_pads
			(clearance 0)
		)
		(min_thickness 0.25)
		(keepout
			(tracks not_allowed)
			(vias allowed)
			(pads allowed)
			(copperpour not_allowed)
			(footprints allowed)
		)
		(placement
			(enabled no)
			(sheetname "")
		)
		(fill yes
			(thermal_gap 0.5)
			(thermal_bridge_width 0.5)
			(island_removal_mode 0)
		)
		(polygon
			(pts
				(arc
					(start 129.489708 -374.390158)
					(mid 128.730248 -374.390158)
					(end 129.489708 -374.390158)
				)
			)
		)
	)
	(zone
		(layers "B.Cu" "In7.Cu" "In9.Cu" "In11.Cu" "In13.Cu" "In15.Cu")
		(hatch none 0.5)
		(connect_pads
			(clearance 0)
		)
		(min_thickness 0.25)
		(keepout
			(tracks not_allowed)
			(vias allowed)
			(pads allowed)
			(copperpour not_allowed)
			(footprints allowed)
		)
		(placement
			(enabled no)
			(sheetname "")
		)
		(fill yes
			(thermal_gap 0.5)
			(thermal_bridge_width 0.5)
			(island_removal_mode 0)
		)
		(polygon
			(pts
				(arc
					(start 424.426126 -275.949664)
					(mid 423.773346 -275.949664)
					(end 424.426126 -275.949664)
				)
			)
		)
	)
	(zone
		(layers "B.Cu" "In7.Cu" "In9.Cu" "In11.Cu" "In13.Cu" "In15.Cu")
		(hatch none 0.5)
		(connect_pads
			(clearance 0)
		)
		(min_thickness 0.25)
		(keepout
			(tracks not_allowed)
			(vias allowed)
			(pads allowed)
			(copperpour not_allowed)
			(footprints allowed)
		)
		(placement
			(enabled no)
			(sheetname "")
		)
		(fill yes
			(thermal_gap 0.5)
			(thermal_bridge_width 0.5)
			(island_removal_mode 0)
		)
		(polygon
			(pts
				(arc
					(start 197.926452 -306.349908)
					(mid 197.273672 -306.349908)
					(end 197.926452 -306.349908)
				)
			)
		)
	)
	(zone
		(layers "B.Cu" "In7.Cu" "In9.Cu" "In11.Cu" "In13.Cu" "In15.Cu")
		(hatch none 0.5)
		(connect_pads
			(clearance 0)
		)
		(min_thickness 0.25)
		(keepout
			(tracks not_allowed)
			(vias allowed)
			(pads allowed)
			(copperpour not_allowed)
			(footprints allowed)
		)
		(placement
			(enabled no)
			(sheetname "")
		)
		(fill yes
			(thermal_gap 0.5)
			(thermal_bridge_width 0.5)
			(island_removal_mode 0)
		)
		(polygon
			(pts
				(arc
					(start 336.269838 -371.790214)
					(mid 335.510378 -371.790214)
					(end 336.269838 -371.790214)
				)
			)
		)
	)
	(zone
		(layers "B.Cu" "In7.Cu" "In9.Cu" "In11.Cu" "In13.Cu" "In15.Cu")
		(hatch none 0.5)
		(connect_pads
			(clearance 0)
		)
		(min_thickness 0.25)
		(keepout
			(tracks not_allowed)
			(vias allowed)
			(pads allowed)
			(copperpour not_allowed)
			(footprints allowed)
		)
		(placement
			(enabled no)
			(sheetname "")
		)
		(fill yes
			(thermal_gap 0.5)
			(thermal_bridge_width 0.5)
			(island_removal_mode 0)
		)
		(polygon
			(pts
				(arc
					(start 299.609002 -130.777234)
					(mid 298.905422 -130.777234)
					(end 299.609002 -130.777234)
				)
			)
		)
	)
	(zone
		(layers "B.Cu" "In7.Cu" "In9.Cu" "In11.Cu" "In13.Cu" "In15.Cu")
		(hatch none 0.5)
		(connect_pads
			(clearance 0)
		)
		(min_thickness 0.25)
		(keepout
			(tracks not_allowed)
			(vias allowed)
			(pads allowed)
			(copperpour not_allowed)
			(footprints allowed)
		)
		(placement
			(enabled no)
			(sheetname "")
		)
		(fill yes
			(thermal_gap 0.5)
			(thermal_bridge_width 0.5)
			(island_removal_mode 0)
		)
		(polygon
			(pts
				(arc
					(start 413.976058 -274.049744)
					(mid 413.323278 -274.049744)
					(end 413.976058 -274.049744)
				)
			)
		)
	)
	(zone
		(layers "B.Cu" "In7.Cu" "In9.Cu" "In11.Cu" "In13.Cu" "In15.Cu")
		(hatch none 0.5)
		(connect_pads
			(clearance 0)
		)
		(min_thickness 0.25)
		(keepout
			(tracks not_allowed)
			(vias allowed)
			(pads allowed)
			(copperpour not_allowed)
			(footprints allowed)
		)
		(placement
			(enabled no)
			(sheetname "")
		)
		(fill yes
			(thermal_gap 0.5)
			(thermal_bridge_width 0.5)
			(island_removal_mode 0)
		)
		(polygon
			(pts
				(arc
					(start 74.489564 -371.590062)
					(mid 73.730104 -371.590062)
					(end 74.489564 -371.590062)
				)
			)
		)
	)
	(zone
		(layers "B.Cu" "In7.Cu" "In9.Cu" "In11.Cu" "In13.Cu" "In15.Cu")
		(hatch none 0.5)
		(connect_pads
			(clearance 0)
		)
		(min_thickness 0.25)
		(keepout
			(tracks not_allowed)
			(vias allowed)
			(pads allowed)
			(copperpour not_allowed)
			(footprints allowed)
		)
		(placement
			(enabled no)
			(sheetname "")
		)
		(fill yes
			(thermal_gap 0.5)
			(thermal_bridge_width 0.5)
			(island_removal_mode 0)
		)
		(polygon
			(pts
				(arc
					(start 176.076356 -318.699896)
					(mid 175.423576 -318.699896)
					(end 176.076356 -318.699896)
				)
			)
		)
	)
	(zone
		(layers "B.Cu" "In7.Cu" "In9.Cu" "In11.Cu" "In13.Cu" "In15.Cu")
		(hatch none 0.5)
		(connect_pads
			(clearance 0)
		)
		(min_thickness 0.25)
		(keepout
			(tracks not_allowed)
			(vias allowed)
			(pads allowed)
			(copperpour not_allowed)
			(footprints allowed)
		)
		(placement
			(enabled no)
			(sheetname "")
		)
		(fill yes
			(thermal_gap 0.5)
			(thermal_bridge_width 0.5)
			(island_removal_mode 0)
		)
		(polygon
			(pts
				(arc
					(start 65.55486 -135.313674)
					(mid 64.85128 -135.313674)
					(end 65.55486 -135.313674)
				)
			)
		)
	)
	(zone
		(layers "B.Cu" "In7.Cu" "In9.Cu" "In11.Cu" "In13.Cu" "In15.Cu")
		(hatch none 0.5)
		(connect_pads
			(clearance 0)
		)
		(min_thickness 0.25)
		(keepout
			(tracks not_allowed)
			(vias allowed)
			(pads allowed)
			(copperpour not_allowed)
			(footprints allowed)
		)
		(placement
			(enabled no)
			(sheetname "")
		)
		(fill yes
			(thermal_gap 0.5)
			(thermal_bridge_width 0.5)
			(island_removal_mode 0)
		)
		(polygon
			(pts
				(arc
					(start 198.876412 -306.349908)
					(mid 198.223632 -306.349908)
					(end 198.876412 -306.349908)
				)
			)
		)
	)
	(zone
		(layers "B.Cu" "In7.Cu" "In9.Cu" "In11.Cu" "In13.Cu" "In15.Cu")
		(hatch none 0.5)
		(connect_pads
			(clearance 0)
		)
		(min_thickness 0.25)
		(keepout
			(tracks not_allowed)
			(vias allowed)
			(pads allowed)
			(copperpour not_allowed)
			(footprints allowed)
		)
		(placement
			(enabled no)
			(sheetname "")
		)
		(fill yes
			(thermal_gap 0.5)
			(thermal_bridge_width 0.5)
			(island_removal_mode 0)
		)
		(polygon
			(pts
				(arc
					(start 272.226278 -315.849762)
					(mid 271.573498 -315.849762)
					(end 272.226278 -315.849762)
				)
			)
		)
	)
	(zone
		(layers "B.Cu" "In7.Cu" "In9.Cu" "In11.Cu" "In13.Cu" "In15.Cu")
		(hatch none 0.5)
		(connect_pads
			(clearance 0)
		)
		(min_thickness 0.25)
		(keepout
			(tracks not_allowed)
			(vias allowed)
			(pads allowed)
			(copperpour not_allowed)
			(footprints allowed)
		)
		(placement
			(enabled no)
			(sheetname "")
		)
		(fill yes
			(thermal_gap 0.5)
			(thermal_bridge_width 0.5)
			(island_removal_mode 0)
		)
		(polygon
			(pts
				(arc
					(start 425.37634 -318.699896)
					(mid 424.72356 -318.699896)
					(end 425.37634 -318.699896)
				)
			)
		)
	)
	(zone
		(layers "B.Cu" "In7.Cu" "In9.Cu" "In11.Cu" "In13.Cu" "In15.Cu")
		(hatch none 0.5)
		(connect_pads
			(clearance 0)
		)
		(min_thickness 0.25)
		(keepout
			(tracks not_allowed)
			(vias allowed)
			(pads allowed)
			(copperpour not_allowed)
			(footprints allowed)
		)
		(placement
			(enabled no)
			(sheetname "")
		)
		(fill yes
			(thermal_gap 0.5)
			(thermal_bridge_width 0.5)
			(island_removal_mode 0)
		)
		(polygon
			(pts
				(arc
					(start 299.609002 -133.513576)
					(mid 298.905422 -133.513576)
					(end 299.609002 -133.513576)
				)
			)
		)
	)
	(zone
		(layers "B.Cu" "In9.Cu" "In11.Cu" "In13.Cu" "In15.Cu")
		(hatch none 0.5)
		(connect_pads
			(clearance 0)
		)
		(min_thickness 0.25)
		(keepout
			(tracks not_allowed)
			(vias allowed)
			(pads allowed)
			(copperpour not_allowed)
			(footprints allowed)
		)
		(placement
			(enabled no)
			(sheetname "")
		)
		(fill yes
			(thermal_gap 0.5)
			(thermal_bridge_width 0.5)
			(island_removal_mode 0)
		)
		(polygon
			(pts
				(arc
					(start 297.876214 -312.999882)
					(mid 297.223434 -312.999882)
					(end 297.876214 -312.999882)
				)
			)
		)
	)
	(zone
		(layers "B.Cu" "In9.Cu" "In11.Cu" "In13.Cu" "In15.Cu")
		(hatch none 0.5)
		(connect_pads
			(clearance 0)
		)
		(min_thickness 0.25)
		(keepout
			(tracks not_allowed)
			(vias allowed)
			(pads allowed)
			(copperpour not_allowed)
			(footprints allowed)
		)
		(placement
			(enabled no)
			(sheetname "")
		)
		(fill yes
			(thermal_gap 0.5)
			(thermal_bridge_width 0.5)
			(island_removal_mode 0)
		)
		(polygon
			(pts
				(arc
					(start 429.17618 -313.949842)
					(mid 428.5234 -313.949842)
					(end 429.17618 -313.949842)
				)
			)
		)
	)
	(zone
		(layers "B.Cu" "In9.Cu" "In11.Cu" "In13.Cu" "In15.Cu")
		(hatch none 0.5)
		(connect_pads
			(clearance 0)
		)
		(min_thickness 0.25)
		(keepout
			(tracks not_allowed)
			(vias allowed)
			(pads allowed)
			(copperpour not_allowed)
			(footprints allowed)
		)
		(placement
			(enabled no)
			(sheetname "")
		)
		(fill yes
			(thermal_gap 0.5)
			(thermal_bridge_width 0.5)
			(island_removal_mode 0)
		)
		(polygon
			(pts
				(arc
					(start 193.176398 -305.399948)
					(mid 192.523618 -305.399948)
					(end 193.176398 -305.399948)
				)
			)
		)
	)
	(zone
		(layers "B.Cu" "In9.Cu" "In11.Cu" "In13.Cu" "In15.Cu")
		(hatch none 0.5)
		(connect_pads
			(clearance 0)
		)
		(min_thickness 0.25)
		(keepout
			(tracks not_allowed)
			(vias allowed)
			(pads allowed)
			(copperpour not_allowed)
			(footprints allowed)
		)
		(placement
			(enabled no)
			(sheetname "")
		)
		(fill yes
			(thermal_gap 0.5)
			(thermal_bridge_width 0.5)
			(island_removal_mode 0)
		)
		(polygon
			(pts
				(arc
					(start 270.326104 -312.049922)
					(mid 269.673324 -312.049922)
					(end 270.326104 -312.049922)
				)
			)
		)
	)
	(zone
		(layers "B.Cu" "In9.Cu" "In11.Cu" "In13.Cu" "In15.Cu")
		(hatch none 0.5)
		(connect_pads
			(clearance 0)
		)
		(min_thickness 0.25)
		(keepout
			(tracks not_allowed)
			(vias allowed)
			(pads allowed)
			(copperpour not_allowed)
			(footprints allowed)
		)
		(placement
			(enabled no)
			(sheetname "")
		)
		(fill yes
			(thermal_gap 0.5)
			(thermal_bridge_width 0.5)
			(island_removal_mode 0)
		)
		(polygon
			(pts
				(arc
					(start 81.089754 -379.590046)
					(mid 80.330294 -379.590046)
					(end 81.089754 -379.590046)
				)
			)
		)
	)
	(zone
		(layers "B.Cu" "In9.Cu" "In11.Cu" "In13.Cu" "In15.Cu")
		(hatch none 0.5)
		(connect_pads
			(clearance 0)
		)
		(min_thickness 0.25)
		(keepout
			(tracks not_allowed)
			(vias allowed)
			(pads allowed)
			(copperpour not_allowed)
			(footprints allowed)
		)
		(placement
			(enabled no)
			(sheetname "")
		)
		(fill yes
			(thermal_gap 0.5)
			(thermal_bridge_width 0.5)
			(island_removal_mode 0)
		)
		(polygon
			(pts
				(arc
					(start 406.376378 -312.999882)
					(mid 405.723598 -312.999882)
					(end 406.376378 -312.999882)
				)
			)
		)
	)
	(zone
		(layers "B.Cu" "In9.Cu" "In11.Cu" "In13.Cu" "In15.Cu")
		(hatch none 0.5)
		(connect_pads
			(clearance 0)
		)
		(min_thickness 0.25)
		(keepout
			(tracks not_allowed)
			(vias allowed)
			(pads allowed)
			(copperpour not_allowed)
			(footprints allowed)
		)
		(placement
			(enabled no)
			(sheetname "")
		)
		(fill yes
			(thermal_gap 0.5)
			(thermal_bridge_width 0.5)
			(island_removal_mode 0)
		)
		(polygon
			(pts
				(arc
					(start 44.776136 -306.349908)
					(mid 44.123356 -306.349908)
					(end 44.776136 -306.349908)
				)
			)
		)
	)
	(zone
		(layers "B.Cu" "In9.Cu" "In11.Cu" "In13.Cu" "In15.Cu")
		(hatch none 0.5)
		(connect_pads
			(clearance 0)
		)
		(min_thickness 0.25)
		(keepout
			(tracks not_allowed)
			(vias allowed)
			(pads allowed)
			(copperpour not_allowed)
			(footprints allowed)
		)
		(placement
			(enabled no)
			(sheetname "")
		)
		(fill yes
			(thermal_gap 0.5)
			(thermal_bridge_width 0.5)
			(island_removal_mode 0)
		)
		(polygon
			(pts
				(arc
					(start 90.568272 -357.75773)
					(mid 89.864692 -357.75773)
					(end 90.568272 -357.75773)
				)
			)
		)
	)
	(zone
		(layers "B.Cu" "In9.Cu" "In11.Cu" "In13.Cu" "In15.Cu")
		(hatch none 0.5)
		(connect_pads
			(clearance 0)
		)
		(min_thickness 0.25)
		(keepout
			(tracks not_allowed)
			(vias allowed)
			(pads allowed)
			(copperpour not_allowed)
			(footprints allowed)
		)
		(placement
			(enabled no)
			(sheetname "")
		)
		(fill yes
			(thermal_gap 0.5)
			(thermal_bridge_width 0.5)
			(island_removal_mode 0)
		)
		(polygon
			(pts
				(arc
					(start 141.058138 -357.75773)
					(mid 140.354558 -357.75773)
					(end 141.058138 -357.75773)
				)
			)
		)
	)
	(zone
		(layers "B.Cu" "In9.Cu" "In11.Cu" "In13.Cu" "In15.Cu")
		(hatch none 0.5)
		(connect_pads
			(clearance 0)
		)
		(min_thickness 0.25)
		(keepout
			(tracks not_allowed)
			(vias allowed)
			(pads allowed)
			(copperpour not_allowed)
			(footprints allowed)
		)
		(placement
			(enabled no)
			(sheetname "")
		)
		(fill yes
			(thermal_gap 0.5)
			(thermal_bridge_width 0.5)
			(island_removal_mode 0)
		)
		(polygon
			(pts
				(arc
					(start 419.86962 -397.790162)
					(mid 419.11016 -397.790162)
					(end 419.86962 -397.790162)
				)
			)
		)
	)
	(zone
		(layers "B.Cu" "In9.Cu" "In11.Cu" "In13.Cu" "In15.Cu")
		(hatch none 0.5)
		(connect_pads
			(clearance 0)
		)
		(min_thickness 0.25)
		(keepout
			(tracks not_allowed)
			(vias allowed)
			(pads allowed)
			(copperpour not_allowed)
			(footprints allowed)
		)
		(placement
			(enabled no)
			(sheetname "")
		)
		(fill yes
			(thermal_gap 0.5)
			(thermal_bridge_width 0.5)
			(island_removal_mode 0)
		)
		(polygon
			(pts
				(arc
					(start 30.489652 -376.790204)
					(mid 29.730192 -376.790204)
					(end 30.489652 -376.790204)
				)
			)
		)
	)
	(zone
		(layers "B.Cu" "In9.Cu" "In11.Cu" "In13.Cu" "In15.Cu")
		(hatch none 0.5)
		(connect_pads
			(clearance 0)
		)
		(min_thickness 0.25)
		(keepout
			(tracks not_allowed)
			(vias allowed)
			(pads allowed)
			(copperpour not_allowed)
			(footprints allowed)
		)
		(placement
			(enabled no)
			(sheetname "")
		)
		(fill yes
			(thermal_gap 0.5)
			(thermal_bridge_width 0.5)
			(island_removal_mode 0)
		)
		(polygon
			(pts
				(arc
					(start 162.537902 -348.58579)
					(mid 161.834322 -348.58579)
					(end 162.537902 -348.58579)
				)
			)
		)
	)
	(zone
		(layers "B.Cu" "In9.Cu" "In11.Cu" "In13.Cu" "In15.Cu")
		(hatch none 0.5)
		(connect_pads
			(clearance 0)
		)
		(min_thickness 0.25)
		(keepout
			(tracks not_allowed)
			(vias allowed)
			(pads allowed)
			(copperpour not_allowed)
			(footprints allowed)
		)
		(placement
			(enabled no)
			(sheetname "")
		)
		(fill yes
			(thermal_gap 0.5)
			(thermal_bridge_width 0.5)
			(island_removal_mode 0)
		)
		(polygon
			(pts
				(arc
					(start 297.093132 -357.75773)
					(mid 296.389552 -357.75773)
					(end 297.093132 -357.75773)
				)
			)
		)
	)
	(zone
		(layers "B.Cu" "In9.Cu" "In11.Cu" "In13.Cu" "In15.Cu")
		(hatch none 0.5)
		(connect_pads
			(clearance 0)
		)
		(min_thickness 0.25)
		(keepout
			(tracks not_allowed)
			(vias allowed)
			(pads allowed)
			(copperpour not_allowed)
			(footprints allowed)
		)
		(placement
			(enabled no)
			(sheetname "")
		)
		(fill yes
			(thermal_gap 0.5)
			(thermal_bridge_width 0.5)
			(island_removal_mode 0)
		)
		(polygon
			(pts
				(arc
					(start 90.568272 -342.439498)
					(mid 89.864692 -342.439498)
					(end 90.568272 -342.439498)
				)
			)
		)
	)
	(zone
		(layers "B.Cu" "In9.Cu" "In11.Cu" "In13.Cu" "In15.Cu")
		(hatch none 0.5)
		(connect_pads
			(clearance 0)
		)
		(min_thickness 0.25)
		(keepout
			(tracks not_allowed)
			(vias allowed)
			(pads allowed)
			(copperpour not_allowed)
			(footprints allowed)
		)
		(placement
			(enabled no)
			(sheetname "")
		)
		(fill yes
			(thermal_gap 0.5)
			(thermal_bridge_width 0.5)
			(island_removal_mode 0)
		)
		(polygon
			(pts
				(arc
					(start 265.762232 -33.65881)
					(mid 265.058652 -33.65881)
					(end 265.762232 -33.65881)
				)
			)
		)
	)
	(zone
		(layers "B.Cu" "In9.Cu" "In11.Cu" "In13.Cu" "In15.Cu")
		(hatch none 0.5)
		(connect_pads
			(clearance 0)
		)
		(min_thickness 0.25)
		(keepout
			(tracks not_allowed)
			(vias allowed)
			(pads allowed)
			(copperpour not_allowed)
			(footprints allowed)
		)
		(placement
			(enabled no)
			(sheetname "")
		)
		(fill yes
			(thermal_gap 0.5)
			(thermal_bridge_width 0.5)
			(island_removal_mode 0)
		)
		(polygon
			(pts
				(arc
					(start 165.646862 -342.439498)
					(mid 164.943282 -342.439498)
					(end 165.646862 -342.439498)
				)
			)
		)
	)
	(zone
		(layers "B.Cu" "In9.Cu" "In11.Cu" "In13.Cu" "In15.Cu")
		(hatch none 0.5)
		(connect_pads
			(clearance 0)
		)
		(min_thickness 0.25)
		(keepout
			(tracks not_allowed)
			(vias allowed)
			(pads allowed)
			(copperpour not_allowed)
			(footprints allowed)
		)
		(placement
			(enabled no)
			(sheetname "")
		)
		(fill yes
			(thermal_gap 0.5)
			(thermal_bridge_width 0.5)
			(island_removal_mode 0)
		)
		(polygon
			(pts
				(arc
					(start 400.676364 -274.049744)
					(mid 400.023584 -274.049744)
					(end 400.676364 -274.049744)
				)
			)
		)
	)
	(zone
		(layers "B.Cu" "In9.Cu" "In11.Cu" "In13.Cu" "In15.Cu")
		(hatch none 0.5)
		(connect_pads
			(clearance 0)
		)
		(min_thickness 0.25)
		(keepout
			(tracks not_allowed)
			(vias allowed)
			(pads allowed)
			(copperpour not_allowed)
			(footprints allowed)
		)
		(placement
			(enabled no)
			(sheetname "")
		)
		(fill yes
			(thermal_gap 0.5)
			(thermal_bridge_width 0.5)
			(island_removal_mode 0)
		)
		(polygon
			(pts
				(arc
					(start 281.548332 -351.611438)
					(mid 280.844752 -351.611438)
					(end 281.548332 -351.611438)
				)
			)
		)
	)
	(zone
		(layers "B.Cu" "In9.Cu" "In11.Cu" "In13.Cu" "In15.Cu")
		(hatch none 0.5)
		(connect_pads
			(clearance 0)
		)
		(min_thickness 0.25)
		(keepout
			(tracks not_allowed)
			(vias allowed)
			(pads allowed)
			(copperpour not_allowed)
			(footprints allowed)
		)
		(placement
			(enabled no)
			(sheetname "")
		)
		(fill yes
			(thermal_gap 0.5)
			(thermal_bridge_width 0.5)
			(island_removal_mode 0)
		)
		(polygon
			(pts
				(arc
					(start 377.75769 -348.58579)
					(mid 377.05411 -348.58579)
					(end 377.75769 -348.58579)
				)
			)
		)
	)
	(zone
		(layers "B.Cu" "In9.Cu" "In11.Cu" "In13.Cu" "In15.Cu")
		(hatch none 0.5)
		(connect_pads
			(clearance 0)
		)
		(min_thickness 0.25)
		(keepout
			(tracks not_allowed)
			(vias allowed)
			(pads allowed)
			(copperpour not_allowed)
			(footprints allowed)
		)
		(placement
			(enabled no)
			(sheetname "")
		)
		(fill yes
			(thermal_gap 0.5)
			(thermal_bridge_width 0.5)
			(island_removal_mode 0)
		)
		(polygon
			(pts
				(arc
					(start 343.944194 -351.611438)
					(mid 343.240614 -351.611438)
					(end 343.944194 -351.611438)
				)
			)
		)
	)
	(zone
		(layers "B.Cu" "In9.Cu" "In11.Cu" "In13.Cu" "In15.Cu")
		(hatch none 0.5)
		(connect_pads
			(clearance 0)
		)
		(min_thickness 0.25)
		(keepout
			(tracks not_allowed)
			(vias allowed)
			(pads allowed)
			(copperpour not_allowed)
			(footprints allowed)
		)
		(placement
			(enabled no)
			(sheetname "")
		)
		(fill yes
			(thermal_gap 0.5)
			(thermal_bridge_width 0.5)
			(island_removal_mode 0)
		)
		(polygon
			(pts
				(arc
					(start 112.213898 -351.611438)
					(mid 111.510318 -351.611438)
					(end 112.213898 -351.611438)
				)
			)
		)
	)
	(zone
		(layers "B.Cu" "In9.Cu" "In11.Cu" "In13.Cu" "In15.Cu")
		(hatch none 0.5)
		(connect_pads
			(clearance 0)
		)
		(min_thickness 0.25)
		(keepout
			(tracks not_allowed)
			(vias allowed)
			(pads allowed)
			(copperpour not_allowed)
			(footprints allowed)
		)
		(placement
			(enabled no)
			(sheetname "")
		)
		(fill yes
			(thermal_gap 0.5)
			(thermal_bridge_width 0.5)
			(island_removal_mode 0)
		)
		(polygon
			(pts
				(arc
					(start 335.480914 -357.75773)
					(mid 334.777334 -357.75773)
					(end 335.480914 -357.75773)
				)
			)
		)
	)
	(zone
		(layers "B.Cu" "In9.Cu" "In11.Cu" "In13.Cu" "In15.Cu")
		(hatch none 0.5)
		(connect_pads
			(clearance 0)
		)
		(min_thickness 0.25)
		(keepout
			(tracks not_allowed)
			(vias allowed)
			(pads allowed)
			(copperpour not_allowed)
			(footprints allowed)
		)
		(placement
			(enabled no)
			(sheetname "")
		)
		(fill yes
			(thermal_gap 0.5)
			(thermal_bridge_width 0.5)
			(island_removal_mode 0)
		)
		(polygon
			(pts
				(arc
					(start 323.045074 -345.465146)
					(mid 322.341494 -345.465146)
					(end 323.045074 -345.465146)
				)
			)
		)
	)
	(zone
		(layers "B.Cu" "In9.Cu" "In11.Cu" "In13.Cu" "In15.Cu")
		(hatch none 0.5)
		(connect_pads
			(clearance 0)
		)
		(min_thickness 0.25)
		(keepout
			(tracks not_allowed)
			(vias allowed)
			(pads allowed)
			(copperpour not_allowed)
			(footprints allowed)
		)
		(placement
			(enabled no)
			(sheetname "")
		)
		(fill yes
			(thermal_gap 0.5)
			(thermal_bridge_width 0.5)
			(island_removal_mode 0)
		)
		(polygon
			(pts
				(arc
					(start 118.48973 -383.290064)
					(mid 117.73027 -383.290064)
					(end 118.48973 -383.290064)
				)
			)
		)
	)
	(zone
		(layers "B.Cu" "In9.Cu" "In11.Cu" "In13.Cu" "In15.Cu")
		(hatch none 0.5)
		(connect_pads
			(clearance 0)
		)
		(min_thickness 0.25)
		(keepout
			(tracks not_allowed)
			(vias allowed)
			(pads allowed)
			(copperpour not_allowed)
			(footprints allowed)
		)
		(placement
			(enabled no)
			(sheetname "")
		)
		(fill yes
			(thermal_gap 0.5)
			(thermal_bridge_width 0.5)
			(island_removal_mode 0)
		)
		(polygon
			(pts
				(arc
					(start 72.28967 -404.290022)
					(mid 71.53021 -404.290022)
					(end 72.28967 -404.290022)
				)
			)
		)
	)
	(zone
		(layers "B.Cu" "In9.Cu" "In11.Cu" "In13.Cu" "In15.Cu")
		(hatch none 0.5)
		(connect_pads
			(clearance 0)
		)
		(min_thickness 0.25)
		(keepout
			(tracks not_allowed)
			(vias allowed)
			(pads allowed)
			(copperpour not_allowed)
			(footprints allowed)
		)
		(placement
			(enabled no)
			(sheetname "")
		)
		(fill yes
			(thermal_gap 0.5)
			(thermal_bridge_width 0.5)
			(island_removal_mode 0)
		)
		(polygon
			(pts
				(arc
					(start 291.22624 -311.099962)
					(mid 290.57346 -311.099962)
					(end 291.22624 -311.099962)
				)
			)
		)
	)
	(zone
		(layers "B.Cu" "In9.Cu" "In11.Cu" "In13.Cu" "In15.Cu")
		(hatch none 0.5)
		(connect_pads
			(clearance 0)
		)
		(min_thickness 0.25)
		(keepout
			(tracks not_allowed)
			(vias allowed)
			(pads allowed)
			(copperpour not_allowed)
			(footprints allowed)
		)
		(placement
			(enabled no)
			(sheetname "")
		)
		(fill yes
			(thermal_gap 0.5)
			(thermal_bridge_width 0.5)
			(island_removal_mode 0)
		)
		(polygon
			(pts
				(arc
					(start 402.62937 -351.611438)
					(mid 401.92579 -351.611438)
					(end 402.62937 -351.611438)
				)
			)
		)
	)
	(zone
		(layers "B.Cu" "In9.Cu" "In11.Cu" "In13.Cu" "In15.Cu")
		(hatch none 0.5)
		(connect_pads
			(clearance 0)
		)
		(min_thickness 0.25)
		(keepout
			(tracks not_allowed)
			(vias allowed)
			(pads allowed)
			(copperpour not_allowed)
			(footprints allowed)
		)
		(placement
			(enabled no)
			(sheetname "")
		)
		(fill yes
			(thermal_gap 0.5)
			(thermal_bridge_width 0.5)
			(island_removal_mode 0)
		)
		(polygon
			(pts
				(arc
					(start 336.269838 -378.290074)
					(mid 335.510378 -378.290074)
					(end 336.269838 -378.290074)
				)
			)
		)
	)
	(zone
		(layers "B.Cu" "In9.Cu" "In11.Cu" "In13.Cu" "In15.Cu")
		(hatch none 0.5)
		(connect_pads
			(clearance 0)
		)
		(min_thickness 0.25)
		(keepout
			(tracks not_allowed)
			(vias allowed)
			(pads allowed)
			(copperpour not_allowed)
			(footprints allowed)
		)
		(placement
			(enabled no)
			(sheetname "")
		)
		(fill yes
			(thermal_gap 0.5)
			(thermal_bridge_width 0.5)
			(island_removal_mode 0)
		)
		(polygon
			(pts
				(arc
					(start 317.762128 -34.52241)
					(mid 317.058548 -34.52241)
					(end 317.762128 -34.52241)
				)
			)
		)
	)
	(zone
		(layers "B.Cu" "In9.Cu" "In11.Cu" "In13.Cu" "In15.Cu")
		(hatch none 0.5)
		(connect_pads
			(clearance 0)
		)
		(min_thickness 0.25)
		(keepout
			(tracks not_allowed)
			(vias allowed)
			(pads allowed)
			(copperpour not_allowed)
			(footprints allowed)
		)
		(placement
			(enabled no)
			(sheetname "")
		)
		(fill yes
			(thermal_gap 0.5)
			(thermal_bridge_width 0.5)
			(island_removal_mode 0)
		)
		(polygon
			(pts
				(arc
					(start 92.813632 -348.58579)
					(mid 92.110052 -348.58579)
					(end 92.813632 -348.58579)
				)
			)
		)
	)
	(zone
		(layers "B.Cu" "In9.Cu" "In11.Cu" "In13.Cu" "In15.Cu")
		(hatch none 0.5)
		(connect_pads
			(clearance 0)
		)
		(min_thickness 0.25)
		(keepout
			(tracks not_allowed)
			(vias allowed)
			(pads allowed)
			(copperpour not_allowed)
			(footprints allowed)
		)
		(placement
			(enabled no)
			(sheetname "")
		)
		(fill yes
			(thermal_gap 0.5)
			(thermal_bridge_width 0.5)
			(island_removal_mode 0)
		)
		(polygon
			(pts
				(arc
					(start 125.08992 -382.18999)
					(mid 124.33046 -382.18999)
					(end 125.08992 -382.18999)
				)
			)
		)
	)
	(zone
		(layers "B.Cu" "In9.Cu" "In11.Cu" "In13.Cu" "In15.Cu")
		(hatch none 0.5)
		(connect_pads
			(clearance 0)
		)
		(min_thickness 0.25)
		(keepout
			(tracks not_allowed)
			(vias allowed)
			(pads allowed)
			(copperpour not_allowed)
			(footprints allowed)
		)
		(placement
			(enabled no)
			(sheetname "")
		)
		(fill yes
			(thermal_gap 0.5)
			(thermal_bridge_width 0.5)
			(island_removal_mode 0)
		)
		(polygon
			(pts
				(arc
					(start 71.914512 -354.732082)
					(mid 71.210932 -354.732082)
					(end 71.914512 -354.732082)
				)
			)
		)
	)
	(zone
		(layers "B.Cu" "In9.Cu" "In11.Cu" "In13.Cu" "In15.Cu")
		(hatch none 0.5)
		(connect_pads
			(clearance 0)
		)
		(min_thickness 0.25)
		(keepout
			(tracks not_allowed)
			(vias allowed)
			(pads allowed)
			(copperpour not_allowed)
			(footprints allowed)
		)
		(placement
			(enabled no)
			(sheetname "")
		)
		(fill yes
			(thermal_gap 0.5)
			(thermal_bridge_width 0.5)
			(island_removal_mode 0)
		)
		(polygon
			(pts
				(arc
					(start 383.71653 -31.858712)
					(mid 383.01295 -31.858712)
					(end 383.71653 -31.858712)
				)
			)
		)
	)
	(zone
		(layers "B.Cu" "In9.Cu" "In11.Cu" "In13.Cu" "In15.Cu")
		(hatch none 0.5)
		(connect_pads
			(clearance 0)
		)
		(min_thickness 0.25)
		(keepout
			(tracks not_allowed)
			(vias allowed)
			(pads allowed)
			(copperpour not_allowed)
			(footprints allowed)
		)
		(placement
			(enabled no)
			(sheetname "")
		)
		(fill yes
			(thermal_gap 0.5)
			(thermal_bridge_width 0.5)
			(island_removal_mode 0)
		)
		(polygon
			(pts
				(arc
					(start 28.289758 -374.390158)
					(mid 27.530298 -374.390158)
					(end 28.289758 -374.390158)
				)
			)
		)
	)
	(zone
		(layers "B.Cu" "In9.Cu" "In11.Cu" "In13.Cu" "In15.Cu")
		(hatch none 0.5)
		(connect_pads
			(clearance 0)
		)
		(min_thickness 0.25)
		(keepout
			(tracks not_allowed)
			(vias allowed)
			(pads allowed)
			(copperpour not_allowed)
			(footprints allowed)
		)
		(placement
			(enabled no)
			(sheetname "")
		)
		(fill yes
			(thermal_gap 0.5)
			(thermal_bridge_width 0.5)
			(island_removal_mode 0)
		)
		(polygon
			(pts
				(arc
					(start 274.466812 -351.611438)
					(mid 273.763232 -351.611438)
					(end 274.466812 -351.611438)
				)
			)
		)
	)
	(zone
		(layers "B.Cu" "In9.Cu" "In11.Cu" "In13.Cu" "In15.Cu")
		(hatch none 0.5)
		(connect_pads
			(clearance 0)
		)
		(min_thickness 0.25)
		(keepout
			(tracks not_allowed)
			(vias allowed)
			(pads allowed)
			(copperpour not_allowed)
			(footprints allowed)
		)
		(placement
			(enabled no)
			(sheetname "")
		)
		(fill yes
			(thermal_gap 0.5)
			(thermal_bridge_width 0.5)
			(island_removal_mode 0)
		)
		(polygon
			(pts
				(arc
					(start 65.696592 -342.439498)
					(mid 64.993012 -342.439498)
					(end 65.696592 -342.439498)
				)
			)
		)
	)
	(zone
		(layers "B.Cu" "In9.Cu" "In11.Cu" "In13.Cu" "In15.Cu")
		(hatch none 0.5)
		(connect_pads
			(clearance 0)
		)
		(min_thickness 0.25)
		(keepout
			(tracks not_allowed)
			(vias allowed)
			(pads allowed)
			(copperpour not_allowed)
			(footprints allowed)
		)
		(placement
			(enabled no)
			(sheetname "")
		)
		(fill yes
			(thermal_gap 0.5)
			(thermal_bridge_width 0.5)
			(island_removal_mode 0)
		)
		(polygon
			(pts
				(arc
					(start 325.290434 -351.611438)
					(mid 324.586854 -351.611438)
					(end 325.290434 -351.611438)
				)
			)
		)
	)
	(zone
		(layers "B.Cu" "In9.Cu" "In11.Cu" "In13.Cu" "In15.Cu")
		(hatch none 0.5)
		(connect_pads
			(clearance 0)
		)
		(min_thickness 0.25)
		(keepout
			(tracks not_allowed)
			(vias allowed)
			(pads allowed)
			(copperpour not_allowed)
			(footprints allowed)
		)
		(placement
			(enabled no)
			(sheetname "")
		)
		(fill yes
			(thermal_gap 0.5)
			(thermal_bridge_width 0.5)
			(island_removal_mode 0)
		)
		(polygon
			(pts
				(arc
					(start 32.6898 -401.690078)
					(mid 31.93034 -401.690078)
					(end 32.6898 -401.690078)
				)
			)
		)
	)
	(zone
		(layers "B.Cu" "In9.Cu" "In11.Cu" "In13.Cu" "In15.Cu")
		(hatch none 0.5)
		(connect_pads
			(clearance 0)
		)
		(min_thickness 0.25)
		(keepout
			(tracks not_allowed)
			(vias allowed)
			(pads allowed)
			(copperpour not_allowed)
			(footprints allowed)
		)
		(placement
			(enabled no)
			(sheetname "")
		)
		(fill yes
			(thermal_gap 0.5)
			(thermal_bridge_width 0.5)
			(island_removal_mode 0)
		)
		(polygon
			(pts
				(arc
					(start 127.289814 -383.290064)
					(mid 126.530354 -383.290064)
					(end 127.289814 -383.290064)
				)
			)
		)
	)
	(zone
		(layers "B.Cu" "In9.Cu" "In11.Cu" "In13.Cu" "In15.Cu")
		(hatch none 0.5)
		(connect_pads
			(clearance 0)
		)
		(min_thickness 0.25)
		(keepout
			(tracks not_allowed)
			(vias allowed)
			(pads allowed)
			(copperpour not_allowed)
			(footprints allowed)
		)
		(placement
			(enabled no)
			(sheetname "")
		)
		(fill yes
			(thermal_gap 0.5)
			(thermal_bridge_width 0.5)
			(island_removal_mode 0)
		)
		(polygon
			(pts
				(arc
					(start 375.869708 -404.290022)
					(mid 375.110248 -404.290022)
					(end 375.869708 -404.290022)
				)
			)
		)
	)
	(zone
		(layers "B.Cu" "In9.Cu" "In11.Cu" "In13.Cu" "In15.Cu")
		(hatch none 0.5)
		(connect_pads
			(clearance 0)
		)
		(min_thickness 0.25)
		(keepout
			(tracks not_allowed)
			(vias allowed)
			(pads allowed)
			(copperpour not_allowed)
			(footprints allowed)
		)
		(placement
			(enabled no)
			(sheetname "")
		)
		(fill yes
			(thermal_gap 0.5)
			(thermal_bridge_width 0.5)
			(island_removal_mode 0)
		)
		(polygon
			(pts
				(arc
					(start 43.689778 -402.790152)
					(mid 42.930318 -402.790152)
					(end 43.689778 -402.790152)
				)
			)
		)
	)
	(zone
		(layers "B.Cu" "In9.Cu" "In11.Cu" "In13.Cu" "In15.Cu")
		(hatch none 0.5)
		(connect_pads
			(clearance 0)
		)
		(min_thickness 0.25)
		(keepout
			(tracks not_allowed)
			(vias allowed)
			(pads allowed)
			(copperpour not_allowed)
			(footprints allowed)
		)
		(placement
			(enabled no)
			(sheetname "")
		)
		(fill yes
			(thermal_gap 0.5)
			(thermal_bridge_width 0.5)
			(island_removal_mode 0)
		)
		(polygon
			(pts
				(arc
					(start 409.716478 -28.25877)
					(mid 409.012898 -28.25877)
					(end 409.716478 -28.25877)
				)
			)
		)
	)
	(zone
		(layers "B.Cu" "In9.Cu" "In11.Cu" "In13.Cu" "In15.Cu")
		(hatch none 0.5)
		(connect_pads
			(clearance 0)
		)
		(min_thickness 0.25)
		(keepout
			(tracks not_allowed)
			(vias allowed)
			(pads allowed)
			(copperpour not_allowed)
			(footprints allowed)
		)
		(placement
			(enabled no)
			(sheetname "")
		)
		(fill yes
			(thermal_gap 0.5)
			(thermal_bridge_width 0.5)
			(island_removal_mode 0)
		)
		(polygon
			(pts
				(arc
					(start 404.476204 -313.949842)
					(mid 403.823424 -313.949842)
					(end 404.476204 -313.949842)
				)
			)
		)
	)
	(zone
		(layers "B.Cu" "In9.Cu" "In11.Cu" "In13.Cu" "In15.Cu")
		(hatch none 0.5)
		(connect_pads
			(clearance 0)
		)
		(min_thickness 0.25)
		(keepout
			(tracks not_allowed)
			(vias allowed)
			(pads allowed)
			(copperpour not_allowed)
			(footprints allowed)
		)
		(placement
			(enabled no)
			(sheetname "")
		)
		(fill yes
			(thermal_gap 0.5)
			(thermal_bridge_width 0.5)
			(island_removal_mode 0)
		)
		(polygon
			(pts
				(arc
					(start 428.669704 -370.489988)
					(mid 427.910244 -370.489988)
					(end 428.669704 -370.489988)
				)
			)
		)
	)
	(zone
		(layers "B.Cu" "In9.Cu" "In11.Cu" "In13.Cu" "In15.Cu")
		(hatch none 0.5)
		(connect_pads
			(clearance 0)
		)
		(min_thickness 0.25)
		(keepout
			(tracks not_allowed)
			(vias allowed)
			(pads allowed)
			(copperpour not_allowed)
			(footprints allowed)
		)
		(placement
			(enabled no)
			(sheetname "")
		)
		(fill yes
			(thermal_gap 0.5)
			(thermal_bridge_width 0.5)
			(island_removal_mode 0)
		)
		(polygon
			(pts
				(arc
					(start 37.089842 -400.390106)
					(mid 36.330382 -400.390106)
					(end 37.089842 -400.390106)
				)
			)
		)
	)
	(zone
		(layers "B.Cu" "In9.Cu" "In11.Cu" "In13.Cu" "In15.Cu")
		(hatch none 0.5)
		(connect_pads
			(clearance 0)
		)
		(min_thickness 0.25)
		(keepout
			(tracks not_allowed)
			(vias allowed)
			(pads allowed)
			(copperpour not_allowed)
			(footprints allowed)
		)
		(placement
			(enabled no)
			(sheetname "")
		)
		(fill yes
			(thermal_gap 0.5)
			(thermal_bridge_width 0.5)
			(island_removal_mode 0)
		)
		(polygon
			(pts
				(arc
					(start 169.089832 -370.489988)
					(mid 168.330372 -370.489988)
					(end 169.089832 -370.489988)
				)
			)
		)
	)
	(zone
		(layers "B.Cu" "In9.Cu" "In11.Cu" "In13.Cu" "In15.Cu")
		(hatch none 0.5)
		(connect_pads
			(clearance 0)
		)
		(min_thickness 0.25)
		(keepout
			(tracks not_allowed)
			(vias allowed)
			(pads allowed)
			(copperpour not_allowed)
			(footprints allowed)
		)
		(placement
			(enabled no)
			(sheetname "")
		)
		(fill yes
			(thermal_gap 0.5)
			(thermal_bridge_width 0.5)
			(island_removal_mode 0)
		)
		(polygon
			(pts
				(arc
					(start 326.154034 -348.58579)
					(mid 325.450454 -348.58579)
					(end 326.154034 -348.58579)
				)
			)
		)
	)
	(zone
		(layers "B.Cu" "In9.Cu" "In11.Cu" "In13.Cu" "In15.Cu")
		(hatch none 0.5)
		(connect_pads
			(clearance 0)
		)
		(min_thickness 0.25)
		(keepout
			(tracks not_allowed)
			(vias allowed)
			(pads allowed)
			(copperpour not_allowed)
			(footprints allowed)
		)
		(placement
			(enabled no)
			(sheetname "")
		)
		(fill yes
			(thermal_gap 0.5)
			(thermal_bridge_width 0.5)
			(island_removal_mode 0)
		)
		(polygon
			(pts
				(arc
					(start 43.689778 -375.490232)
					(mid 42.930318 -375.490232)
					(end 43.689778 -375.490232)
				)
			)
		)
	)
	(zone
		(layers "B.Cu" "In9.Cu" "In11.Cu" "In13.Cu" "In15.Cu")
		(hatch none 0.5)
		(connect_pads
			(clearance 0)
		)
		(min_thickness 0.25)
		(keepout
			(tracks not_allowed)
			(vias allowed)
			(pads allowed)
			(copperpour not_allowed)
			(footprints allowed)
		)
		(placement
			(enabled no)
			(sheetname "")
		)
		(fill yes
			(thermal_gap 0.5)
			(thermal_bridge_width 0.5)
			(island_removal_mode 0)
		)
		(polygon
			(pts
				(arc
					(start 34.889694 -376.790204)
					(mid 34.130234 -376.790204)
					(end 34.889694 -376.790204)
				)
			)
		)
	)
	(zone
		(layers "B.Cu" "In9.Cu" "In11.Cu" "In13.Cu" "In15.Cu")
		(hatch none 0.5)
		(connect_pads
			(clearance 0)
		)
		(min_thickness 0.25)
		(keepout
			(tracks not_allowed)
			(vias allowed)
			(pads allowed)
			(copperpour not_allowed)
			(footprints allowed)
		)
		(placement
			(enabled no)
			(sheetname "")
		)
		(fill yes
			(thermal_gap 0.5)
			(thermal_bridge_width 0.5)
			(island_removal_mode 0)
		)
		(polygon
			(pts
				(arc
					(start 384.669792 -383.490216)
					(mid 383.910332 -383.490216)
					(end 384.669792 -383.490216)
				)
			)
		)
	)
	(zone
		(layers "B.Cu" "In9.Cu" "In11.Cu" "In13.Cu" "In15.Cu")
		(hatch none 0.5)
		(connect_pads
			(clearance 0)
		)
		(min_thickness 0.25)
		(keepout
			(tracks not_allowed)
			(vias allowed)
			(pads allowed)
			(copperpour not_allowed)
			(footprints allowed)
		)
		(placement
			(enabled no)
			(sheetname "")
		)
		(fill yes
			(thermal_gap 0.5)
			(thermal_bridge_width 0.5)
			(island_removal_mode 0)
		)
		(polygon
			(pts
				(arc
					(start 424.42638 -312.049922)
					(mid 423.7736 -312.049922)
					(end 424.42638 -312.049922)
				)
			)
		)
	)
	(zone
		(layers "B.Cu" "In9.Cu" "In11.Cu" "In13.Cu" "In15.Cu")
		(hatch none 0.5)
		(connect_pads
			(clearance 0)
		)
		(min_thickness 0.25)
		(keepout
			(tracks not_allowed)
			(vias allowed)
			(pads allowed)
			(copperpour not_allowed)
			(footprints allowed)
		)
		(placement
			(enabled no)
			(sheetname "")
		)
		(fill yes
			(thermal_gap 0.5)
			(thermal_bridge_width 0.5)
			(island_removal_mode 0)
		)
		(polygon
			(pts
				(arc
					(start 415.864802 -351.611438)
					(mid 415.161222 -351.611438)
					(end 415.864802 -351.611438)
				)
			)
		)
	)
	(zone
		(layers "B.Cu" "In9.Cu" "In11.Cu" "In13.Cu" "In15.Cu")
		(hatch none 0.5)
		(connect_pads
			(clearance 0)
		)
		(min_thickness 0.25)
		(keepout
			(tracks not_allowed)
			(vias allowed)
			(pads allowed)
			(copperpour not_allowed)
			(footprints allowed)
		)
		(placement
			(enabled no)
			(sheetname "")
		)
		(fill yes
			(thermal_gap 0.5)
			(thermal_bridge_width 0.5)
			(island_removal_mode 0)
		)
		(polygon
			(pts
				(arc
					(start 177.516536 -31.858712)
					(mid 176.812956 -31.858712)
					(end 177.516536 -31.858712)
				)
			)
		)
	)
	(zone
		(layers "B.Cu" "In9.Cu" "In11.Cu" "In13.Cu" "In15.Cu")
		(hatch none 0.5)
		(connect_pads
			(clearance 0)
		)
		(min_thickness 0.25)
		(keepout
			(tracks not_allowed)
			(vias allowed)
			(pads allowed)
			(copperpour not_allowed)
			(footprints allowed)
		)
		(placement
			(enabled no)
			(sheetname "")
		)
		(fill yes
			(thermal_gap 0.5)
			(thermal_bridge_width 0.5)
			(island_removal_mode 0)
		)
		(polygon
			(pts
				(arc
					(start 120.689878 -404.290022)
					(mid 119.930418 -404.290022)
					(end 120.689878 -404.290022)
				)
			)
		)
	)
	(zone
		(layers "B.Cu" "In9.Cu" "In11.Cu" "In13.Cu" "In15.Cu")
		(hatch none 0.5)
		(connect_pads
			(clearance 0)
		)
		(min_thickness 0.25)
		(keepout
			(tracks not_allowed)
			(vias allowed)
			(pads allowed)
			(copperpour not_allowed)
			(footprints allowed)
		)
		(placement
			(enabled no)
			(sheetname "")
		)
		(fill yes
			(thermal_gap 0.5)
			(thermal_bridge_width 0.5)
			(island_removal_mode 0)
		)
		(polygon
			(pts
				(arc
					(start 64.726312 -312.049922)
					(mid 64.073532 -312.049922)
					(end 64.726312 -312.049922)
				)
			)
		)
	)
	(zone
		(layers "B.Cu" "In9.Cu" "In11.Cu" "In13.Cu" "In15.Cu")
		(hatch none 0.5)
		(connect_pads
			(clearance 0)
		)
		(min_thickness 0.25)
		(keepout
			(tracks not_allowed)
			(vias allowed)
			(pads allowed)
			(copperpour not_allowed)
			(footprints allowed)
		)
		(placement
			(enabled no)
			(sheetname "")
		)
		(fill yes
			(thermal_gap 0.5)
			(thermal_bridge_width 0.5)
			(island_removal_mode 0)
		)
		(polygon
			(pts
				(arc
					(start 425.191682 -357.75773)
					(mid 424.488102 -357.75773)
					(end 425.191682 -357.75773)
				)
			)
		)
	)
	(zone
		(layers "B.Cu" "In9.Cu" "In11.Cu" "In13.Cu" "In15.Cu")
		(hatch none 0.5)
		(connect_pads
			(clearance 0)
		)
		(min_thickness 0.25)
		(keepout
			(tracks not_allowed)
			(vias allowed)
			(pads allowed)
			(copperpour not_allowed)
			(footprints allowed)
		)
		(placement
			(enabled no)
			(sheetname "")
		)
		(fill yes
			(thermal_gap 0.5)
			(thermal_bridge_width 0.5)
			(island_removal_mode 0)
		)
		(polygon
			(pts
				(arc
					(start 276.026118 -306.349908)
					(mid 275.373338 -306.349908)
					(end 276.026118 -306.349908)
				)
			)
		)
	)
	(zone
		(layers "B.Cu" "In9.Cu" "In11.Cu" "In13.Cu" "In15.Cu")
		(hatch none 0.5)
		(connect_pads
			(clearance 0)
		)
		(min_thickness 0.25)
		(keepout
			(tracks not_allowed)
			(vias allowed)
			(pads allowed)
			(copperpour not_allowed)
			(footprints allowed)
		)
		(placement
			(enabled no)
			(sheetname "")
		)
		(fill yes
			(thermal_gap 0.5)
			(thermal_bridge_width 0.5)
			(island_removal_mode 0)
		)
		(polygon
			(pts
				(arc
					(start 399.726404 -274.999958)
					(mid 399.073624 -274.999958)
					(end 399.726404 -274.999958)
				)
			)
		)
	)
	(zone
		(layers "B.Cu" "In9.Cu" "In11.Cu" "In13.Cu" "In15.Cu")
		(hatch none 0.5)
		(connect_pads
			(clearance 0)
		)
		(min_thickness 0.25)
		(keepout
			(tracks not_allowed)
			(vias allowed)
			(pads allowed)
			(copperpour not_allowed)
			(footprints allowed)
		)
		(placement
			(enabled no)
			(sheetname "")
		)
		(fill yes
			(thermal_gap 0.5)
			(thermal_bridge_width 0.5)
			(island_removal_mode 0)
		)
		(polygon
			(pts
				(arc
					(start 92.813632 -351.611438)
					(mid 92.110052 -351.611438)
					(end 92.813632 -351.611438)
				)
			)
		)
	)
	(zone
		(layers "B.Cu" "In9.Cu" "In11.Cu" "In13.Cu" "In15.Cu")
		(hatch none 0.5)
		(connect_pads
			(clearance 0)
		)
		(min_thickness 0.25)
		(keepout
			(tracks not_allowed)
			(vias allowed)
			(pads allowed)
			(copperpour not_allowed)
			(footprints allowed)
		)
		(placement
			(enabled no)
			(sheetname "")
		)
		(fill yes
			(thermal_gap 0.5)
			(thermal_bridge_width 0.5)
			(island_removal_mode 0)
		)
		(polygon
			(pts
				(arc
					(start 319.616328 -28.25877)
					(mid 318.912748 -28.25877)
					(end 319.616328 -28.25877)
				)
			)
		)
	)
	(zone
		(layers "B.Cu" "In9.Cu" "In11.Cu" "In13.Cu" "In15.Cu")
		(hatch none 0.5)
		(connect_pads
			(clearance 0)
		)
		(min_thickness 0.25)
		(keepout
			(tracks not_allowed)
			(vias allowed)
			(pads allowed)
			(copperpour not_allowed)
			(footprints allowed)
		)
		(placement
			(enabled no)
			(sheetname "")
		)
		(fill yes
			(thermal_gap 0.5)
			(thermal_bridge_width 0.5)
			(island_removal_mode 0)
		)
		(polygon
			(pts
				(arc
					(start 289.32632 -275.949918)
					(mid 288.67354 -275.949918)
					(end 289.32632 -275.949918)
				)
			)
		)
	)
	(zone
		(layers "B.Cu" "In9.Cu" "In11.Cu" "In13.Cu" "In15.Cu")
		(hatch none 0.5)
		(connect_pads
			(clearance 0)
		)
		(min_thickness 0.25)
		(keepout
			(tracks not_allowed)
			(vias allowed)
			(pads allowed)
			(copperpour not_allowed)
			(footprints allowed)
		)
		(placement
			(enabled no)
			(sheetname "")
		)
		(fill yes
			(thermal_gap 0.5)
			(thermal_bridge_width 0.5)
			(island_removal_mode 0)
		)
		(polygon
			(pts
				(arc
					(start 166.889684 -398.890236)
					(mid 166.130224 -398.890236)
					(end 166.889684 -398.890236)
				)
			)
		)
	)
	(zone
		(layers "B.Cu" "In9.Cu" "In11.Cu" "In13.Cu" "In15.Cu")
		(hatch none 0.5)
		(connect_pads
			(clearance 0)
		)
		(min_thickness 0.25)
		(keepout
			(tracks not_allowed)
			(vias allowed)
			(pads allowed)
			(copperpour not_allowed)
			(footprints allowed)
		)
		(placement
			(enabled no)
			(sheetname "")
		)
		(fill yes
			(thermal_gap 0.5)
			(thermal_bridge_width 0.5)
			(island_removal_mode 0)
		)
		(polygon
			(pts
				(arc
					(start 345.069668 -405.589994)
					(mid 344.310208 -405.589994)
					(end 345.069668 -405.589994)
				)
			)
		)
	)
	(zone
		(layers "B.Cu" "In9.Cu" "In11.Cu" "In13.Cu" "In15.Cu")
		(hatch none 0.5)
		(connect_pads
			(clearance 0)
		)
		(min_thickness 0.25)
		(keepout
			(tracks not_allowed)
			(vias allowed)
			(pads allowed)
			(copperpour not_allowed)
			(footprints allowed)
		)
		(placement
			(enabled no)
			(sheetname "")
		)
		(fill yes
			(thermal_gap 0.5)
			(thermal_bridge_width 0.5)
			(island_removal_mode 0)
		)
		(polygon
			(pts
				(arc
					(start 194.126358 -309.199788)
					(mid 193.473578 -309.199788)
					(end 194.126358 -309.199788)
				)
			)
		)
	)
	(zone
		(layers "B.Cu" "In9.Cu" "In11.Cu" "In13.Cu" "In15.Cu")
		(hatch none 0.5)
		(connect_pads
			(clearance 0)
		)
		(min_thickness 0.25)
		(keepout
			(tracks not_allowed)
			(vias allowed)
			(pads allowed)
			(copperpour not_allowed)
			(footprints allowed)
		)
		(placement
			(enabled no)
			(sheetname "")
		)
		(fill yes
			(thermal_gap 0.5)
			(thermal_bridge_width 0.5)
			(island_removal_mode 0)
		)
		(polygon
			(pts
				(arc
					(start 129.489708 -382.18999)
					(mid 128.730248 -382.18999)
					(end 129.489708 -382.18999)
				)
			)
		)
	)
	(zone
		(layers "B.Cu" "In9.Cu" "In11.Cu" "In13.Cu" "In15.Cu")
		(hatch none 0.5)
		(connect_pads
			(clearance 0)
		)
		(min_thickness 0.25)
		(keepout
			(tracks not_allowed)
			(vias allowed)
			(pads allowed)
			(copperpour not_allowed)
			(footprints allowed)
		)
		(placement
			(enabled no)
			(sheetname "")
		)
		(fill yes
			(thermal_gap 0.5)
			(thermal_bridge_width 0.5)
			(island_removal_mode 0)
		)
		(polygon
			(pts
				(arc
					(start 168.755822 -351.611438)
					(mid 168.052242 -351.611438)
					(end 168.755822 -351.611438)
				)
			)
		)
	)
	(zone
		(layers "B.Cu" "In9.Cu" "In11.Cu" "In13.Cu" "In15.Cu")
		(hatch none 0.5)
		(connect_pads
			(clearance 0)
		)
		(min_thickness 0.25)
		(keepout
			(tracks not_allowed)
			(vias allowed)
			(pads allowed)
			(copperpour not_allowed)
			(footprints allowed)
		)
		(placement
			(enabled no)
			(sheetname "")
		)
		(fill yes
			(thermal_gap 0.5)
			(thermal_bridge_width 0.5)
			(island_removal_mode 0)
		)
		(polygon
			(pts
				(arc
					(start 412.755842 -345.465146)
					(mid 412.052262 -345.465146)
					(end 412.755842 -345.465146)
				)
			)
		)
	)
	(zone
		(layers "B.Cu" "In9.Cu" "In11.Cu" "In13.Cu" "In15.Cu")
		(hatch none 0.5)
		(connect_pads
			(clearance 0)
		)
		(min_thickness 0.25)
		(keepout
			(tracks not_allowed)
			(vias allowed)
			(pads allowed)
			(copperpour not_allowed)
			(footprints allowed)
		)
		(placement
			(enabled no)
			(sheetname "")
		)
		(fill yes
			(thermal_gap 0.5)
			(thermal_bridge_width 0.5)
			(island_removal_mode 0)
		)
		(polygon
			(pts
				(arc
					(start 395.92631 -274.999958)
					(mid 395.27353 -274.999958)
					(end 395.92631 -274.999958)
				)
			)
		)
	)
	(zone
		(layers "B.Cu" "In9.Cu" "In11.Cu" "In13.Cu" "In15.Cu")
		(hatch none 0.5)
		(connect_pads
			(clearance 0)
		)
		(min_thickness 0.25)
		(keepout
			(tracks not_allowed)
			(vias allowed)
			(pads allowed)
			(copperpour not_allowed)
			(footprints allowed)
		)
		(placement
			(enabled no)
			(sheetname "")
		)
		(fill yes
			(thermal_gap 0.5)
			(thermal_bridge_width 0.5)
			(island_removal_mode 0)
		)
		(polygon
			(pts
				(arc
					(start 380.26975 -404.290022)
					(mid 379.51029 -404.290022)
					(end 380.26975 -404.290022)
				)
			)
		)
	)
	(zone
		(layers "B.Cu" "In9.Cu" "In11.Cu" "In13.Cu" "In15.Cu")
		(hatch none 0.5)
		(connect_pads
			(clearance 0)
		)
		(min_thickness 0.25)
		(keepout
			(tracks not_allowed)
			(vias allowed)
			(pads allowed)
			(copperpour not_allowed)
			(footprints allowed)
		)
		(placement
			(enabled no)
			(sheetname "")
		)
		(fill yes
			(thermal_gap 0.5)
			(thermal_bridge_width 0.5)
			(island_removal_mode 0)
		)
		(polygon
			(pts
				(arc
					(start 84.350352 -342.439498)
					(mid 83.646772 -342.439498)
					(end 84.350352 -342.439498)
				)
			)
		)
	)
	(zone
		(layers "B.Cu" "In9.Cu" "In11.Cu" "In13.Cu" "In15.Cu")
		(hatch none 0.5)
		(connect_pads
			(clearance 0)
		)
		(min_thickness 0.25)
		(keepout
			(tracks not_allowed)
			(vias allowed)
			(pads allowed)
			(copperpour not_allowed)
			(footprints allowed)
		)
		(placement
			(enabled no)
			(sheetname "")
		)
		(fill yes
			(thermal_gap 0.5)
			(thermal_bridge_width 0.5)
			(island_removal_mode 0)
		)
		(polygon
			(pts
				(arc
					(start 89.704672 -345.465146)
					(mid 89.001092 -345.465146)
					(end 89.704672 -345.465146)
				)
			)
		)
	)
	(zone
		(layers "B.Cu" "In9.Cu" "In11.Cu" "In13.Cu" "In15.Cu")
		(hatch none 0.5)
		(connect_pads
			(clearance 0)
		)
		(min_thickness 0.25)
		(keepout
			(tracks not_allowed)
			(vias allowed)
			(pads allowed)
			(copperpour not_allowed)
			(footprints allowed)
		)
		(placement
			(enabled no)
			(sheetname "")
		)
		(fill yes
			(thermal_gap 0.5)
			(thermal_bridge_width 0.5)
			(island_removal_mode 0)
		)
		(polygon
			(pts
				(arc
					(start 75.023472 -348.58579)
					(mid 74.319892 -348.58579)
					(end 75.023472 -348.58579)
				)
			)
		)
	)
	(zone
		(layers "B.Cu" "In9.Cu" "In11.Cu" "In13.Cu" "In15.Cu")
		(hatch none 0.5)
		(connect_pads
			(clearance 0)
		)
		(min_thickness 0.25)
		(keepout
			(tracks not_allowed)
			(vias allowed)
			(pads allowed)
			(copperpour not_allowed)
			(footprints allowed)
		)
		(placement
			(enabled no)
			(sheetname "")
		)
		(fill yes
			(thermal_gap 0.5)
			(thermal_bridge_width 0.5)
			(island_removal_mode 0)
		)
		(polygon
			(pts
				(arc
					(start 274.126198 -303.499774)
					(mid 273.473418 -303.499774)
					(end 274.126198 -303.499774)
				)
			)
		)
	)
	(zone
		(layers "B.Cu" "In9.Cu" "In11.Cu" "In13.Cu" "In15.Cu")
		(hatch none 0.5)
		(connect_pads
			(clearance 0)
		)
		(min_thickness 0.25)
		(keepout
			(tracks not_allowed)
			(vias allowed)
			(pads allowed)
			(copperpour not_allowed)
			(footprints allowed)
		)
		(placement
			(enabled no)
			(sheetname "")
		)
		(fill yes
			(thermal_gap 0.5)
			(thermal_bridge_width 0.5)
			(island_removal_mode 0)
		)
		(polygon
			(pts
				(arc
					(start 284.576266 -274.049744)
					(mid 283.923486 -274.049744)
					(end 284.576266 -274.049744)
				)
			)
		)
	)
	(zone
		(layers "B.Cu" "In9.Cu" "In11.Cu" "In13.Cu" "In15.Cu")
		(hatch none 0.5)
		(connect_pads
			(clearance 0)
		)
		(min_thickness 0.25)
		(keepout
			(tracks not_allowed)
			(vias allowed)
			(pads allowed)
			(copperpour not_allowed)
			(footprints allowed)
		)
		(placement
			(enabled no)
			(sheetname "")
		)
		(fill yes
			(thermal_gap 0.5)
			(thermal_bridge_width 0.5)
			(island_removal_mode 0)
		)
		(polygon
			(pts
				(arc
					(start 273.176238 -313.949842)
					(mid 272.523458 -313.949842)
					(end 273.176238 -313.949842)
				)
			)
		)
	)
	(zone
		(layers "B.Cu" "In9.Cu" "In11.Cu" "In13.Cu" "In15.Cu")
		(hatch none 0.5)
		(connect_pads
			(clearance 0)
		)
		(min_thickness 0.25)
		(keepout
			(tracks not_allowed)
			(vias allowed)
			(pads allowed)
			(copperpour not_allowed)
			(footprints allowed)
		)
		(placement
			(enabled no)
			(sheetname "")
		)
		(fill yes
			(thermal_gap 0.5)
			(thermal_bridge_width 0.5)
			(island_removal_mode 0)
		)
		(polygon
			(pts
				(arc
					(start 113.077498 -351.611438)
					(mid 112.373918 -351.611438)
					(end 113.077498 -351.611438)
				)
			)
		)
	)
	(zone
		(layers "B.Cu" "In9.Cu" "In11.Cu" "In13.Cu" "In15.Cu")
		(hatch none 0.5)
		(connect_pads
			(clearance 0)
		)
		(min_thickness 0.25)
		(keepout
			(tracks not_allowed)
			(vias allowed)
			(pads allowed)
			(copperpour not_allowed)
			(footprints allowed)
		)
		(placement
			(enabled no)
			(sheetname "")
		)
		(fill yes
			(thermal_gap 0.5)
			(thermal_bridge_width 0.5)
			(island_removal_mode 0)
		)
		(polygon
			(pts
				(arc
					(start 280.684732 -351.611438)
					(mid 279.981152 -351.611438)
					(end 280.684732 -351.611438)
				)
			)
		)
	)
	(zone
		(layers "B.Cu" "In9.Cu" "In11.Cu" "In13.Cu" "In15.Cu")
		(hatch none 0.5)
		(connect_pads
			(clearance 0)
		)
		(min_thickness 0.25)
		(keepout
			(tracks not_allowed)
			(vias allowed)
			(pads allowed)
			(copperpour not_allowed)
			(footprints allowed)
		)
		(placement
			(enabled no)
			(sheetname "")
		)
		(fill yes
			(thermal_gap 0.5)
			(thermal_bridge_width 0.5)
			(island_removal_mode 0)
		)
		(polygon
			(pts
				(arc
					(start 303.26965 -376.790204)
					(mid 302.51019 -376.790204)
					(end 303.26965 -376.790204)
				)
			)
		)
	)
	(zone
		(layers "B.Cu" "In9.Cu" "In11.Cu" "In13.Cu" "In15.Cu")
		(hatch none 0.5)
		(connect_pads
			(clearance 0)
		)
		(min_thickness 0.25)
		(keepout
			(tracks not_allowed)
			(vias allowed)
			(pads allowed)
			(copperpour not_allowed)
			(footprints allowed)
		)
		(placement
			(enabled no)
			(sheetname "")
		)
		(fill yes
			(thermal_gap 0.5)
			(thermal_bridge_width 0.5)
			(island_removal_mode 0)
		)
		(polygon
			(pts
				(arc
					(start 72.28967 -379.590046)
					(mid 71.53021 -379.590046)
					(end 72.28967 -379.590046)
				)
			)
		)
	)
	(zone
		(layers "B.Cu" "In9.Cu" "In11.Cu" "In13.Cu" "In15.Cu")
		(hatch none 0.5)
		(connect_pads
			(clearance 0)
		)
		(min_thickness 0.25)
		(keepout
			(tracks not_allowed)
			(vias allowed)
			(pads allowed)
			(copperpour not_allowed)
			(footprints allowed)
		)
		(placement
			(enabled no)
			(sheetname "")
		)
		(fill yes
			(thermal_gap 0.5)
			(thermal_bridge_width 0.5)
			(island_removal_mode 0)
		)
		(polygon
			(pts
				(arc
					(start 276.976078 -273.099784)
					(mid 276.323298 -273.099784)
					(end 276.976078 -273.099784)
				)
			)
		)
	)
	(zone
		(layers "B.Cu" "In9.Cu" "In11.Cu" "In13.Cu" "In15.Cu")
		(hatch none 0.5)
		(connect_pads
			(clearance 0)
		)
		(min_thickness 0.25)
		(keepout
			(tracks not_allowed)
			(vias allowed)
			(pads allowed)
			(copperpour not_allowed)
			(footprints allowed)
		)
		(placement
			(enabled no)
			(sheetname "")
		)
		(fill yes
			(thermal_gap 0.5)
			(thermal_bridge_width 0.5)
			(island_removal_mode 0)
		)
		(polygon
			(pts
				(arc
					(start 61.416438 -29.12237)
					(mid 60.712858 -29.12237)
					(end 61.416438 -29.12237)
				)
			)
		)
	)
	(zone
		(layers "B.Cu" "In9.Cu" "In11.Cu" "In13.Cu" "In15.Cu")
		(hatch none 0.5)
		(connect_pads
			(clearance 0)
		)
		(min_thickness 0.25)
		(keepout
			(tracks not_allowed)
			(vias allowed)
			(pads allowed)
			(copperpour not_allowed)
			(footprints allowed)
		)
		(placement
			(enabled no)
			(sheetname "")
		)
		(fill yes
			(thermal_gap 0.5)
			(thermal_bridge_width 0.5)
			(island_removal_mode 0)
		)
		(polygon
			(pts
				(arc
					(start 175.837342 -351.611438)
					(mid 175.133762 -351.611438)
					(end 175.837342 -351.611438)
				)
			)
		)
	)
	(zone
		(layers "B.Cu" "In9.Cu" "In11.Cu" "In13.Cu" "In15.Cu")
		(hatch none 0.5)
		(connect_pads
			(clearance 0)
		)
		(min_thickness 0.25)
		(keepout
			(tracks not_allowed)
			(vias allowed)
			(pads allowed)
			(copperpour not_allowed)
			(footprints allowed)
		)
		(placement
			(enabled no)
			(sheetname "")
		)
		(fill yes
			(thermal_gap 0.5)
			(thermal_bridge_width 0.5)
			(island_removal_mode 0)
		)
		(polygon
			(pts
				(arc
					(start 53.326284 -274.999958)
					(mid 52.673504 -274.999958)
					(end 53.326284 -274.999958)
				)
			)
		)
	)
	(zone
		(layers "B.Cu" "In9.Cu" "In11.Cu" "In13.Cu" "In15.Cu")
		(hatch none 0.5)
		(connect_pads
			(clearance 0)
		)
		(min_thickness 0.25)
		(keepout
			(tracks not_allowed)
			(vias allowed)
			(pads allowed)
			(copperpour not_allowed)
			(footprints allowed)
		)
		(placement
			(enabled no)
			(sheetname "")
		)
		(fill yes
			(thermal_gap 0.5)
			(thermal_bridge_width 0.5)
			(island_removal_mode 0)
		)
		(polygon
			(pts
				(arc
					(start 433.862226 -34.52241)
					(mid 433.158646 -34.52241)
					(end 433.862226 -34.52241)
				)
			)
		)
	)
	(zone
		(layers "B.Cu" "In9.Cu" "In11.Cu" "In13.Cu" "In15.Cu")
		(hatch none 0.5)
		(connect_pads
			(clearance 0)
		)
		(min_thickness 0.25)
		(keepout
			(tracks not_allowed)
			(vias allowed)
			(pads allowed)
			(copperpour not_allowed)
			(footprints allowed)
		)
		(placement
			(enabled no)
			(sheetname "")
		)
		(fill yes
			(thermal_gap 0.5)
			(thermal_bridge_width 0.5)
			(island_removal_mode 0)
		)
		(polygon
			(pts
				(arc
					(start 435.26964 -371.590062)
					(mid 434.51018 -371.590062)
					(end 435.26964 -371.590062)
				)
			)
		)
	)
	(zone
		(layers "B.Cu" "In9.Cu" "In11.Cu" "In13.Cu" "In15.Cu")
		(hatch none 0.5)
		(connect_pads
			(clearance 0)
		)
		(min_thickness 0.25)
		(keepout
			(tracks not_allowed)
			(vias allowed)
			(pads allowed)
			(copperpour not_allowed)
			(footprints allowed)
		)
		(placement
			(enabled no)
			(sheetname "")
		)
		(fill yes
			(thermal_gap 0.5)
			(thermal_bridge_width 0.5)
			(island_removal_mode 0)
		)
		(polygon
			(pts
				(arc
					(start 433.069492 -370.489988)
					(mid 432.310032 -370.489988)
					(end 433.069492 -370.489988)
				)
			)
		)
	)
	(zone
		(layers "B.Cu" "In9.Cu" "In11.Cu" "In13.Cu" "In15.Cu")
		(hatch none 0.5)
		(connect_pads
			(clearance 0)
		)
		(min_thickness 0.25)
		(keepout
			(tracks not_allowed)
			(vias allowed)
			(pads allowed)
			(copperpour not_allowed)
			(footprints allowed)
		)
		(placement
			(enabled no)
			(sheetname "")
		)
		(fill yes
			(thermal_gap 0.5)
			(thermal_bridge_width 0.5)
			(island_removal_mode 0)
		)
		(polygon
			(pts
				(arc
					(start 170.376342 -312.999882)
					(mid 169.723562 -312.999882)
					(end 170.376342 -312.999882)
				)
			)
		)
	)
	(zone
		(layers "B.Cu" "In9.Cu" "In11.Cu" "In13.Cu" "In15.Cu")
		(hatch none 0.5)
		(connect_pads
			(clearance 0)
		)
		(min_thickness 0.25)
		(keepout
			(tracks not_allowed)
			(vias allowed)
			(pads allowed)
			(copperpour not_allowed)
			(footprints allowed)
		)
		(placement
			(enabled no)
			(sheetname "")
		)
		(fill yes
			(thermal_gap 0.5)
			(thermal_bridge_width 0.5)
			(island_removal_mode 0)
		)
		(polygon
			(pts
				(arc
					(start 394.97635 -274.049744)
					(mid 394.32357 -274.049744)
					(end 394.97635 -274.049744)
				)
			)
		)
	)
	(zone
		(layers "B.Cu" "In9.Cu" "In11.Cu" "In13.Cu" "In15.Cu")
		(hatch none 0.5)
		(connect_pads
			(clearance 0)
		)
		(min_thickness 0.25)
		(keepout
			(tracks not_allowed)
			(vias allowed)
			(pads allowed)
			(copperpour not_allowed)
			(footprints allowed)
		)
		(placement
			(enabled no)
			(sheetname "")
		)
		(fill yes
			(thermal_gap 0.5)
			(thermal_bridge_width 0.5)
			(island_removal_mode 0)
		)
		(polygon
			(pts
				(arc
					(start 267.616432 -31.858712)
					(mid 266.912852 -31.858712)
					(end 267.616432 -31.858712)
				)
			)
		)
	)
	(zone
		(layers "B.Cu" "In9.Cu" "In11.Cu" "In13.Cu" "In15.Cu")
		(hatch none 0.5)
		(connect_pads
			(clearance 0)
		)
		(min_thickness 0.25)
		(keepout
			(tracks not_allowed)
			(vias allowed)
			(pads allowed)
			(copperpour not_allowed)
			(footprints allowed)
		)
		(placement
			(enabled no)
			(sheetname "")
		)
		(fill yes
			(thermal_gap 0.5)
			(thermal_bridge_width 0.5)
			(island_removal_mode 0)
		)
		(polygon
			(pts
				(arc
					(start 119.295418 -351.611438)
					(mid 118.591838 -351.611438)
					(end 119.295418 -351.611438)
				)
			)
		)
	)
	(zone
		(layers "B.Cu" "In9.Cu" "In11.Cu" "In13.Cu" "In15.Cu")
		(hatch none 0.5)
		(connect_pads
			(clearance 0)
		)
		(min_thickness 0.25)
		(keepout
			(tracks not_allowed)
			(vias allowed)
			(pads allowed)
			(copperpour not_allowed)
			(footprints allowed)
		)
		(placement
			(enabled no)
			(sheetname "")
		)
		(fill yes
			(thermal_gap 0.5)
			(thermal_bridge_width 0.5)
			(island_removal_mode 0)
		)
		(polygon
			(pts
				(arc
					(start 184.300622 -354.708206)
					(mid 183.597042 -354.708206)
					(end 184.300622 -354.708206)
				)
			)
		)
	)
	(zone
		(layers "B.Cu" "In9.Cu" "In11.Cu" "In13.Cu" "In15.Cu")
		(hatch none 0.5)
		(connect_pads
			(clearance 0)
		)
		(min_thickness 0.25)
		(keepout
			(tracks not_allowed)
			(vias allowed)
			(pads allowed)
			(copperpour not_allowed)
			(footprints allowed)
		)
		(placement
			(enabled no)
			(sheetname "")
		)
		(fill yes
			(thermal_gap 0.5)
			(thermal_bridge_width 0.5)
			(island_removal_mode 0)
		)
		(polygon
			(pts
				(arc
					(start 272.221452 -354.732082)
					(mid 271.517872 -354.732082)
					(end 272.221452 -354.732082)
				)
			)
		)
	)
	(zone
		(layers "B.Cu" "In9.Cu" "In11.Cu" "In13.Cu" "In15.Cu")
		(hatch none 0.5)
		(connect_pads
			(clearance 0)
		)
		(min_thickness 0.25)
		(keepout
			(tracks not_allowed)
			(vias allowed)
			(pads allowed)
			(copperpour not_allowed)
			(footprints allowed)
		)
		(placement
			(enabled no)
			(sheetname "")
		)
		(fill yes
			(thermal_gap 0.5)
			(thermal_bridge_width 0.5)
			(island_removal_mode 0)
		)
		(polygon
			(pts
				(arc
					(start 407.326338 -311.099962)
					(mid 406.673558 -311.099962)
					(end 407.326338 -311.099962)
				)
			)
		)
	)
	(zone
		(layers "B.Cu" "In9.Cu" "In11.Cu" "In13.Cu" "In15.Cu")
		(hatch none 0.5)
		(connect_pads
			(clearance 0)
		)
		(min_thickness 0.25)
		(keepout
			(tracks not_allowed)
			(vias allowed)
			(pads allowed)
			(copperpour not_allowed)
			(footprints allowed)
		)
		(placement
			(enabled no)
			(sheetname "")
		)
		(fill yes
			(thermal_gap 0.5)
			(thermal_bridge_width 0.5)
			(island_removal_mode 0)
		)
		(polygon
			(pts
				(arc
					(start 84.350352 -345.465146)
					(mid 83.646772 -345.465146)
					(end 84.350352 -345.465146)
				)
			)
		)
	)
	(zone
		(layers "B.Cu" "In9.Cu" "In11.Cu" "In13.Cu" "In15.Cu")
		(hatch none 0.5)
		(connect_pads
			(clearance 0)
		)
		(min_thickness 0.25)
		(keepout
			(tracks not_allowed)
			(vias allowed)
			(pads allowed)
			(copperpour not_allowed)
			(footprints allowed)
		)
		(placement
			(enabled no)
			(sheetname "")
		)
		(fill yes
			(thermal_gap 0.5)
			(thermal_bridge_width 0.5)
			(island_removal_mode 0)
		)
		(polygon
			(pts
				(arc
					(start 322.181474 -345.465146)
					(mid 321.477894 -345.465146)
					(end 322.181474 -345.465146)
				)
			)
		)
	)
	(zone
		(layers "B.Cu" "In9.Cu" "In11.Cu" "In13.Cu" "In15.Cu")
		(hatch none 0.5)
		(connect_pads
			(clearance 0)
		)
		(min_thickness 0.25)
		(keepout
			(tracks not_allowed)
			(vias allowed)
			(pads allowed)
			(copperpour not_allowed)
			(footprints allowed)
		)
		(placement
			(enabled no)
			(sheetname "")
		)
		(fill yes
			(thermal_gap 0.5)
			(thermal_bridge_width 0.5)
			(island_removal_mode 0)
		)
		(polygon
			(pts
				(arc
					(start 86.595712 -348.58579)
					(mid 85.892132 -348.58579)
					(end 86.595712 -348.58579)
				)
			)
		)
	)
	(zone
		(layers "B.Cu" "In9.Cu" "In11.Cu" "In13.Cu" "In15.Cu")
		(hatch none 0.5)
		(connect_pads
			(clearance 0)
		)
		(min_thickness 0.25)
		(keepout
			(tracks not_allowed)
			(vias allowed)
			(pads allowed)
			(copperpour not_allowed)
			(footprints allowed)
		)
		(placement
			(enabled no)
			(sheetname "")
		)
		(fill yes
			(thermal_gap 0.5)
			(thermal_bridge_width 0.5)
			(island_removal_mode 0)
		)
		(polygon
			(pts
				(arc
					(start 424.42638 -306.349908)
					(mid 423.7736 -306.349908)
					(end 424.42638 -306.349908)
				)
			)
		)
	)
	(zone
		(layers "B.Cu" "In9.Cu" "In11.Cu" "In13.Cu" "In15.Cu")
		(hatch none 0.5)
		(connect_pads
			(clearance 0)
		)
		(min_thickness 0.25)
		(keepout
			(tracks not_allowed)
			(vias allowed)
			(pads allowed)
			(copperpour not_allowed)
			(footprints allowed)
		)
		(placement
			(enabled no)
			(sheetname "")
		)
		(fill yes
			(thermal_gap 0.5)
			(thermal_bridge_width 0.5)
			(island_removal_mode 0)
		)
		(polygon
			(pts
				(arc
					(start 166.510462 -345.465146)
					(mid 165.806882 -345.465146)
					(end 166.510462 -345.465146)
				)
			)
		)
	)
	(zone
		(layers "B.Cu" "In9.Cu" "In11.Cu" "In13.Cu" "In15.Cu")
		(hatch none 0.5)
		(connect_pads
			(clearance 0)
		)
		(min_thickness 0.25)
		(keepout
			(tracks not_allowed)
			(vias allowed)
			(pads allowed)
			(copperpour not_allowed)
			(footprints allowed)
		)
		(placement
			(enabled no)
			(sheetname "")
		)
		(fill yes
			(thermal_gap 0.5)
			(thermal_bridge_width 0.5)
			(island_removal_mode 0)
		)
		(polygon
			(pts
				(arc
					(start 337.726274 -348.58579)
					(mid 337.022694 -348.58579)
					(end 337.726274 -348.58579)
				)
			)
		)
	)
	(zone
		(layers "B.Cu" "In9.Cu" "In11.Cu" "In13.Cu" "In15.Cu")
		(hatch none 0.5)
		(connect_pads
			(clearance 0)
		)
		(min_thickness 0.25)
		(keepout
			(tracks not_allowed)
			(vias allowed)
			(pads allowed)
			(copperpour not_allowed)
			(footprints allowed)
		)
		(placement
			(enabled no)
			(sheetname "")
		)
		(fill yes
			(thermal_gap 0.5)
			(thermal_bridge_width 0.5)
			(island_removal_mode 0)
		)
		(polygon
			(pts
				(arc
					(start 173.48962 -370.489988)
					(mid 172.73016 -370.489988)
					(end 173.48962 -370.489988)
				)
			)
		)
	)
	(zone
		(layers "B.Cu" "In9.Cu" "In11.Cu" "In13.Cu" "In15.Cu")
		(hatch none 0.5)
		(connect_pads
			(clearance 0)
		)
		(min_thickness 0.25)
		(keepout
			(tracks not_allowed)
			(vias allowed)
			(pads allowed)
			(copperpour not_allowed)
			(footprints allowed)
		)
		(placement
			(enabled no)
			(sheetname "")
		)
		(fill yes
			(thermal_gap 0.5)
			(thermal_bridge_width 0.5)
			(island_removal_mode 0)
		)
		(polygon
			(pts
				(arc
					(start 160.876234 -274.049744)
					(mid 160.223454 -274.049744)
					(end 160.876234 -274.049744)
				)
			)
		)
	)
	(zone
		(layers "B.Cu" "In9.Cu" "In11.Cu" "In13.Cu" "In15.Cu")
		(hatch none 0.5)
		(connect_pads
			(clearance 0)
		)
		(min_thickness 0.25)
		(keepout
			(tracks not_allowed)
			(vias allowed)
			(pads allowed)
			(copperpour not_allowed)
			(footprints allowed)
		)
		(placement
			(enabled no)
			(sheetname "")
		)
		(fill yes
			(thermal_gap 0.5)
			(thermal_bridge_width 0.5)
			(island_removal_mode 0)
		)
		(polygon
			(pts
				(arc
					(start 185.164222 -357.733854)
					(mid 184.460642 -357.733854)
					(end 185.164222 -357.733854)
				)
			)
		)
	)
	(zone
		(layers "B.Cu" "In9.Cu" "In11.Cu" "In13.Cu" "In15.Cu")
		(hatch none 0.5)
		(connect_pads
			(clearance 0)
		)
		(min_thickness 0.25)
		(keepout
			(tracks not_allowed)
			(vias allowed)
			(pads allowed)
			(copperpour not_allowed)
			(footprints allowed)
		)
		(placement
			(enabled no)
			(sheetname "")
		)
		(fill yes
			(thermal_gap 0.5)
			(thermal_bridge_width 0.5)
			(island_removal_mode 0)
		)
		(polygon
			(pts
				(arc
					(start 71.376286 -312.999882)
					(mid 70.723506 -312.999882)
					(end 71.376286 -312.999882)
				)
			)
		)
	)
	(zone
		(layers "B.Cu" "In9.Cu" "In11.Cu" "In13.Cu" "In15.Cu")
		(hatch none 0.5)
		(connect_pads
			(clearance 0)
		)
		(min_thickness 0.25)
		(keepout
			(tracks not_allowed)
			(vias allowed)
			(pads allowed)
			(copperpour not_allowed)
			(footprints allowed)
		)
		(placement
			(enabled no)
			(sheetname "")
		)
		(fill yes
			(thermal_gap 0.5)
			(thermal_bridge_width 0.5)
			(island_removal_mode 0)
		)
		(polygon
			(pts
				(arc
					(start 331.508354 -348.58579)
					(mid 330.804774 -348.58579)
					(end 331.508354 -348.58579)
				)
			)
		)
	)
	(zone
		(layers "B.Cu" "In9.Cu" "In11.Cu" "In13.Cu" "In15.Cu")
		(hatch none 0.5)
		(connect_pads
			(clearance 0)
		)
		(min_thickness 0.25)
		(keepout
			(tracks not_allowed)
			(vias allowed)
			(pads allowed)
			(copperpour not_allowed)
			(footprints allowed)
		)
		(placement
			(enabled no)
			(sheetname "")
		)
		(fill yes
			(thermal_gap 0.5)
			(thermal_bridge_width 0.5)
			(island_removal_mode 0)
		)
		(polygon
			(pts
				(arc
					(start 22.793198 -354.732082)
					(mid 22.089618 -354.732082)
					(end 22.793198 -354.732082)
				)
			)
		)
	)
	(zone
		(layers "B.Cu" "In9.Cu" "In11.Cu" "In13.Cu" "In15.Cu")
		(hatch none 0.5)
		(connect_pads
			(clearance 0)
		)
		(min_thickness 0.25)
		(keepout
			(tracks not_allowed)
			(vias allowed)
			(pads allowed)
			(copperpour not_allowed)
			(footprints allowed)
		)
		(placement
			(enabled no)
			(sheetname "")
		)
		(fill yes
			(thermal_gap 0.5)
			(thermal_bridge_width 0.5)
			(island_removal_mode 0)
		)
		(polygon
			(pts
				(arc
					(start 71.050912 -357.75773)
					(mid 70.347332 -357.75773)
					(end 71.050912 -357.75773)
				)
			)
		)
	)
	(zone
		(layers "B.Cu" "In9.Cu" "In11.Cu" "In13.Cu" "In15.Cu")
		(hatch none 0.5)
		(connect_pads
			(clearance 0)
		)
		(min_thickness 0.25)
		(keepout
			(tracks not_allowed)
			(vias allowed)
			(pads allowed)
			(copperpour not_allowed)
			(footprints allowed)
		)
		(placement
			(enabled no)
			(sheetname "")
		)
		(fill yes
			(thermal_gap 0.5)
			(thermal_bridge_width 0.5)
			(island_removal_mode 0)
		)
		(polygon
			(pts
				(arc
					(start 193.176398 -313.949842)
					(mid 192.523618 -313.949842)
					(end 193.176398 -313.949842)
				)
			)
		)
	)
	(zone
		(layers "B.Cu" "In9.Cu" "In11.Cu" "In13.Cu" "In15.Cu")
		(hatch none 0.5)
		(connect_pads
			(clearance 0)
		)
		(min_thickness 0.25)
		(keepout
			(tracks not_allowed)
			(vias allowed)
			(pads allowed)
			(copperpour not_allowed)
			(footprints allowed)
		)
		(placement
			(enabled no)
			(sheetname "")
		)
		(fill yes
			(thermal_gap 0.5)
			(thermal_bridge_width 0.5)
			(island_removal_mode 0)
		)
		(polygon
			(pts
				(arc
					(start 426.3263 -307.299868)
					(mid 425.67352 -307.299868)
					(end 426.3263 -307.299868)
				)
			)
		)
	)
	(zone
		(layers "B.Cu" "In9.Cu" "In11.Cu" "In13.Cu" "In15.Cu")
		(hatch none 0.5)
		(connect_pads
			(clearance 0)
		)
		(min_thickness 0.25)
		(keepout
			(tracks not_allowed)
			(vias allowed)
			(pads allowed)
			(copperpour not_allowed)
			(footprints allowed)
		)
		(placement
			(enabled no)
			(sheetname "")
		)
		(fill yes
			(thermal_gap 0.5)
			(thermal_bridge_width 0.5)
			(island_removal_mode 0)
		)
		(polygon
			(pts
				(arc
					(start 23.656798 -342.439498)
					(mid 22.953218 -342.439498)
					(end 23.656798 -342.439498)
				)
			)
		)
	)
	(zone
		(layers "B.Cu" "In9.Cu" "In11.Cu" "In13.Cu" "In15.Cu")
		(hatch none 0.5)
		(connect_pads
			(clearance 0)
		)
		(min_thickness 0.25)
		(keepout
			(tracks not_allowed)
			(vias allowed)
			(pads allowed)
			(copperpour not_allowed)
			(footprints allowed)
		)
		(placement
			(enabled no)
			(sheetname "")
		)
		(fill yes
			(thermal_gap 0.5)
			(thermal_bridge_width 0.5)
			(island_removal_mode 0)
		)
		(polygon
			(pts
				(arc
					(start 410.510482 -351.611438)
					(mid 409.806902 -351.611438)
					(end 410.510482 -351.611438)
				)
			)
		)
	)
	(zone
		(layers "B.Cu" "In9.Cu" "In11.Cu" "In13.Cu" "In15.Cu")
		(hatch none 0.5)
		(connect_pads
			(clearance 0)
		)
		(min_thickness 0.25)
		(keepout
			(tracks not_allowed)
			(vias allowed)
			(pads allowed)
			(copperpour not_allowed)
			(footprints allowed)
		)
		(placement
			(enabled no)
			(sheetname "")
		)
		(fill yes
			(thermal_gap 0.5)
			(thermal_bridge_width 0.5)
			(island_removal_mode 0)
		)
		(polygon
			(pts
				(arc
					(start 173.48962 -371.790214)
					(mid 172.73016 -371.790214)
					(end 173.48962 -371.790214)
				)
			)
		)
	)
	(zone
		(layers "B.Cu" "In9.Cu" "In11.Cu" "In13.Cu" "In15.Cu")
		(hatch none 0.5)
		(connect_pads
			(clearance 0)
		)
		(min_thickness 0.25)
		(keepout
			(tracks not_allowed)
			(vias allowed)
			(pads allowed)
			(copperpour not_allowed)
			(footprints allowed)
		)
		(placement
			(enabled no)
			(sheetname "")
		)
		(fill yes
			(thermal_gap 0.5)
			(thermal_bridge_width 0.5)
			(island_removal_mode 0)
		)
		(polygon
			(pts
				(arc
					(start 48.528478 -342.439498)
					(mid 47.824898 -342.439498)
					(end 48.528478 -342.439498)
				)
			)
		)
	)
	(zone
		(layers "B.Cu" "In9.Cu" "In11.Cu" "In13.Cu" "In15.Cu")
		(hatch none 0.5)
		(connect_pads
			(clearance 0)
		)
		(min_thickness 0.25)
		(keepout
			(tracks not_allowed)
			(vias allowed)
			(pads allowed)
			(copperpour not_allowed)
			(footprints allowed)
		)
		(placement
			(enabled no)
			(sheetname "")
		)
		(fill yes
			(thermal_gap 0.5)
			(thermal_bridge_width 0.5)
			(island_removal_mode 0)
		)
		(polygon
			(pts
				(arc
					(start 293.120572 -351.611438)
					(mid 292.416992 -351.611438)
					(end 293.120572 -351.611438)
				)
			)
		)
	)
	(zone
		(layers "B.Cu" "In9.Cu" "In11.Cu" "In13.Cu" "In15.Cu")
		(hatch none 0.5)
		(connect_pads
			(clearance 0)
		)
		(min_thickness 0.25)
		(keepout
			(tracks not_allowed)
			(vias allowed)
			(pads allowed)
			(copperpour not_allowed)
			(footprints allowed)
		)
		(placement
			(enabled no)
			(sheetname "")
		)
		(fill yes
			(thermal_gap 0.5)
			(thermal_bridge_width 0.5)
			(island_removal_mode 0)
		)
		(polygon
			(pts
				(arc
					(start 178.946302 -357.75773)
					(mid 178.242722 -357.75773)
					(end 178.946302 -357.75773)
				)
			)
		)
	)
	(zone
		(layers "B.Cu" "In9.Cu" "In11.Cu" "In13.Cu" "In15.Cu")
		(hatch none 0.5)
		(connect_pads
			(clearance 0)
		)
		(min_thickness 0.25)
		(keepout
			(tracks not_allowed)
			(vias allowed)
			(pads allowed)
			(copperpour not_allowed)
			(footprints allowed)
		)
		(placement
			(enabled no)
			(sheetname "")
		)
		(fill yes
			(thermal_gap 0.5)
			(thermal_bridge_width 0.5)
			(island_removal_mode 0)
		)
		(polygon
			(pts
				(arc
					(start 194.126358 -312.049922)
					(mid 193.473578 -312.049922)
					(end 194.126358 -312.049922)
				)
			)
		)
	)
	(zone
		(layers "B.Cu" "In9.Cu" "In11.Cu" "In13.Cu" "In15.Cu")
		(hatch none 0.5)
		(connect_pads
			(clearance 0)
		)
		(min_thickness 0.25)
		(keepout
			(tracks not_allowed)
			(vias allowed)
			(pads allowed)
			(copperpour not_allowed)
			(footprints allowed)
		)
		(placement
			(enabled no)
			(sheetname "")
		)
		(fill yes
			(thermal_gap 0.5)
			(thermal_bridge_width 0.5)
			(island_removal_mode 0)
		)
		(polygon
			(pts
				(arc
					(start 174.176436 -312.999882)
					(mid 173.523656 -312.999882)
					(end 174.176436 -312.999882)
				)
			)
		)
	)
	(zone
		(layers "B.Cu" "In9.Cu" "In11.Cu" "In13.Cu" "In15.Cu")
		(hatch none 0.5)
		(connect_pads
			(clearance 0)
		)
		(min_thickness 0.25)
		(keepout
			(tracks not_allowed)
			(vias allowed)
			(pads allowed)
			(copperpour not_allowed)
			(footprints allowed)
		)
		(placement
			(enabled no)
			(sheetname "")
		)
		(fill yes
			(thermal_gap 0.5)
			(thermal_bridge_width 0.5)
			(island_removal_mode 0)
		)
		(polygon
			(pts
				(arc
					(start 400.38401 -345.465146)
					(mid 399.68043 -345.465146)
					(end 400.38401 -345.465146)
				)
			)
		)
	)
	(zone
		(layers "B.Cu" "In9.Cu" "In11.Cu" "In13.Cu" "In15.Cu")
		(hatch none 0.5)
		(connect_pads
			(clearance 0)
		)
		(min_thickness 0.25)
		(keepout
			(tracks not_allowed)
			(vias allowed)
			(pads allowed)
			(copperpour not_allowed)
			(footprints allowed)
		)
		(placement
			(enabled no)
			(sheetname "")
		)
		(fill yes
			(thermal_gap 0.5)
			(thermal_bridge_width 0.5)
			(island_removal_mode 0)
		)
		(polygon
			(pts
				(arc
					(start 292.269672 -401.690078)
					(mid 291.510212 -401.690078)
					(end 292.269672 -401.690078)
				)
			)
		)
	)
	(zone
		(layers "B.Cu" "In9.Cu" "In11.Cu" "In13.Cu" "In15.Cu")
		(hatch none 0.5)
		(connect_pads
			(clearance 0)
		)
		(min_thickness 0.25)
		(keepout
			(tracks not_allowed)
			(vias allowed)
			(pads allowed)
			(copperpour not_allowed)
			(footprints allowed)
		)
		(placement
			(enabled no)
			(sheetname "")
		)
		(fill yes
			(thermal_gap 0.5)
			(thermal_bridge_width 0.5)
			(island_removal_mode 0)
		)
		(polygon
			(pts
				(arc
					(start 268.248892 -348.58579)
					(mid 267.545312 -348.58579)
					(end 268.248892 -348.58579)
				)
			)
		)
	)
	(zone
		(layers "B.Cu" "In9.Cu" "In11.Cu" "In13.Cu" "In15.Cu")
		(hatch none 0.5)
		(connect_pads
			(clearance 0)
		)
		(min_thickness 0.25)
		(keepout
			(tracks not_allowed)
			(vias allowed)
			(pads allowed)
			(copperpour not_allowed)
			(footprints allowed)
		)
		(placement
			(enabled no)
			(sheetname "")
		)
		(fill yes
			(thermal_gap 0.5)
			(thermal_bridge_width 0.5)
			(island_removal_mode 0)
		)
		(polygon
			(pts
				(arc
					(start 175.126396 -312.049922)
					(mid 174.473616 -312.049922)
					(end 175.126396 -312.049922)
				)
			)
		)
	)
	(zone
		(layers "B.Cu" "In9.Cu" "In11.Cu" "In13.Cu" "In15.Cu")
		(hatch none 0.5)
		(connect_pads
			(clearance 0)
		)
		(min_thickness 0.25)
		(keepout
			(tracks not_allowed)
			(vias allowed)
			(pads allowed)
			(copperpour not_allowed)
			(footprints allowed)
		)
		(placement
			(enabled no)
			(sheetname "")
		)
		(fill yes
			(thermal_gap 0.5)
			(thermal_bridge_width 0.5)
			(island_removal_mode 0)
		)
		(polygon
			(pts
				(arc
					(start 402.576284 -274.049744)
					(mid 401.923504 -274.049744)
					(end 402.576284 -274.049744)
				)
			)
		)
	)
	(zone
		(layers "B.Cu" "In9.Cu" "In11.Cu" "In13.Cu" "In15.Cu")
		(hatch none 0.5)
		(connect_pads
			(clearance 0)
		)
		(min_thickness 0.25)
		(keepout
			(tracks not_allowed)
			(vias allowed)
			(pads allowed)
			(copperpour not_allowed)
			(footprints allowed)
		)
		(placement
			(enabled no)
			(sheetname "")
		)
		(fill yes
			(thermal_gap 0.5)
			(thermal_bridge_width 0.5)
			(island_removal_mode 0)
		)
		(polygon
			(pts
				(arc
					(start 171.326302 -312.049922)
					(mid 170.673522 -312.049922)
					(end 171.326302 -312.049922)
				)
			)
		)
	)
	(zone
		(layers "B.Cu" "In9.Cu" "In11.Cu" "In13.Cu" "In15.Cu")
		(hatch none 0.5)
		(connect_pads
			(clearance 0)
		)
		(min_thickness 0.25)
		(keepout
			(tracks not_allowed)
			(vias allowed)
			(pads allowed)
			(copperpour not_allowed)
			(footprints allowed)
		)
		(placement
			(enabled no)
			(sheetname "")
		)
		(fill yes
			(thermal_gap 0.5)
			(thermal_bridge_width 0.5)
			(island_removal_mode 0)
		)
		(polygon
			(pts
				(arc
					(start 190.518542 -345.465146)
					(mid 189.814962 -345.465146)
					(end 190.518542 -345.465146)
				)
			)
		)
	)
	(zone
		(layers "B.Cu" "In9.Cu" "In11.Cu" "In13.Cu" "In15.Cu")
		(hatch none 0.5)
		(connect_pads
			(clearance 0)
		)
		(min_thickness 0.25)
		(keepout
			(tracks not_allowed)
			(vias allowed)
			(pads allowed)
			(copperpour not_allowed)
			(footprints allowed)
		)
		(placement
			(enabled no)
			(sheetname "")
		)
		(fill yes
			(thermal_gap 0.5)
			(thermal_bridge_width 0.5)
			(island_removal_mode 0)
		)
		(polygon
			(pts
				(arc
					(start 401.626324 -311.099962)
					(mid 400.973544 -311.099962)
					(end 401.626324 -311.099962)
				)
			)
		)
	)
	(zone
		(layers "B.Cu" "In9.Cu" "In11.Cu" "In13.Cu" "In15.Cu")
		(hatch none 0.5)
		(connect_pads
			(clearance 0)
		)
		(min_thickness 0.25)
		(keepout
			(tracks not_allowed)
			(vias allowed)
			(pads allowed)
			(copperpour not_allowed)
			(footprints allowed)
		)
		(placement
			(enabled no)
			(sheetname "")
		)
		(fill yes
			(thermal_gap 0.5)
			(thermal_bridge_width 0.5)
			(island_removal_mode 0)
		)
		(polygon
			(pts
				(arc
					(start 411.126178 -311.099962)
					(mid 410.473398 -311.099962)
					(end 411.126178 -311.099962)
				)
			)
		)
	)
	(zone
		(layers "B.Cu" "In9.Cu" "In11.Cu" "In13.Cu" "In15.Cu")
		(hatch none 0.5)
		(connect_pads
			(clearance 0)
		)
		(min_thickness 0.25)
		(keepout
			(tracks not_allowed)
			(vias allowed)
			(pads allowed)
			(copperpour not_allowed)
			(footprints allowed)
		)
		(placement
			(enabled no)
			(sheetname "")
		)
		(fill yes
			(thermal_gap 0.5)
			(thermal_bridge_width 0.5)
			(island_removal_mode 0)
		)
		(polygon
			(pts
				(arc
					(start 171.289726 -371.590062)
					(mid 170.530266 -371.590062)
					(end 171.289726 -371.590062)
				)
			)
		)
	)
	(zone
		(layers "B.Cu" "In9.Cu" "In11.Cu" "In13.Cu" "In15.Cu")
		(hatch none 0.5)
		(connect_pads
			(clearance 0)
		)
		(min_thickness 0.25)
		(keepout
			(tracks not_allowed)
			(vias allowed)
			(pads allowed)
			(copperpour not_allowed)
			(footprints allowed)
		)
		(placement
			(enabled no)
			(sheetname "")
		)
		(fill yes
			(thermal_gap 0.5)
			(thermal_bridge_width 0.5)
			(island_removal_mode 0)
		)
		(polygon
			(pts
				(arc
					(start 286.902652 -351.611438)
					(mid 286.199072 -351.611438)
					(end 286.902652 -351.611438)
				)
			)
		)
	)
	(zone
		(layers "B.Cu" "In9.Cu" "In11.Cu" "In13.Cu" "In15.Cu")
		(hatch none 0.5)
		(connect_pads
			(clearance 0)
		)
		(min_thickness 0.25)
		(keepout
			(tracks not_allowed)
			(vias allowed)
			(pads allowed)
			(copperpour not_allowed)
			(footprints allowed)
		)
		(placement
			(enabled no)
			(sheetname "")
		)
		(fill yes
			(thermal_gap 0.5)
			(thermal_bridge_width 0.5)
			(island_removal_mode 0)
		)
		(polygon
			(pts
				(arc
					(start 176.076356 -312.999882)
					(mid 175.423576 -312.999882)
					(end 176.076356 -312.999882)
				)
			)
		)
	)
	(zone
		(layers "B.Cu" "In9.Cu" "In11.Cu" "In13.Cu" "In15.Cu")
		(hatch none 0.5)
		(connect_pads
			(clearance 0)
		)
		(min_thickness 0.25)
		(keepout
			(tracks not_allowed)
			(vias allowed)
			(pads allowed)
			(copperpour not_allowed)
			(footprints allowed)
		)
		(placement
			(enabled no)
			(sheetname "")
		)
		(fill yes
			(thermal_gap 0.5)
			(thermal_bridge_width 0.5)
			(island_removal_mode 0)
		)
		(polygon
			(pts
				(arc
					(start 440.736482 -348.58579)
					(mid 440.032902 -348.58579)
					(end 440.736482 -348.58579)
				)
			)
		)
	)
	(zone
		(layers "B.Cu" "In9.Cu" "In11.Cu" "In13.Cu" "In15.Cu")
		(hatch none 0.5)
		(connect_pads
			(clearance 0)
		)
		(min_thickness 0.25)
		(keepout
			(tracks not_allowed)
			(vias allowed)
			(pads allowed)
			(copperpour not_allowed)
			(footprints allowed)
		)
		(placement
			(enabled no)
			(sheetname "")
		)
		(fill yes
			(thermal_gap 0.5)
			(thermal_bridge_width 0.5)
			(island_removal_mode 0)
		)
		(polygon
			(pts
				(arc
					(start 167.526462 -311.099962)
					(mid 166.873682 -311.099962)
					(end 167.526462 -311.099962)
				)
			)
		)
	)
	(zone
		(layers "B.Cu" "In9.Cu" "In11.Cu" "In13.Cu" "In15.Cu")
		(hatch none 0.5)
		(connect_pads
			(clearance 0)
		)
		(min_thickness 0.25)
		(keepout
			(tracks not_allowed)
			(vias allowed)
			(pads allowed)
			(copperpour not_allowed)
			(footprints allowed)
		)
		(placement
			(enabled no)
			(sheetname "")
		)
		(fill yes
			(thermal_gap 0.5)
			(thermal_bridge_width 0.5)
			(island_removal_mode 0)
		)
		(polygon
			(pts
				(arc
					(start 115.322858 -357.75773)
					(mid 114.619278 -357.75773)
					(end 115.322858 -357.75773)
				)
			)
		)
	)
	(zone
		(layers "B.Cu" "In9.Cu" "In11.Cu" "In13.Cu" "In15.Cu")
		(hatch none 0.5)
		(connect_pads
			(clearance 0)
		)
		(min_thickness 0.25)
		(keepout
			(tracks not_allowed)
			(vias allowed)
			(pads allowed)
			(copperpour not_allowed)
			(footprints allowed)
		)
		(placement
			(enabled no)
			(sheetname "")
		)
		(fill yes
			(thermal_gap 0.5)
			(thermal_bridge_width 0.5)
			(island_removal_mode 0)
		)
		(polygon
			(pts
				(arc
					(start 174.973742 -351.611438)
					(mid 174.270162 -351.611438)
					(end 174.973742 -351.611438)
				)
			)
		)
	)
	(zone
		(layers "B.Cu" "In9.Cu" "In11.Cu" "In13.Cu" "In15.Cu")
		(hatch none 0.5)
		(connect_pads
			(clearance 0)
		)
		(min_thickness 0.25)
		(keepout
			(tracks not_allowed)
			(vias allowed)
			(pads allowed)
			(copperpour not_allowed)
			(footprints allowed)
		)
		(placement
			(enabled no)
			(sheetname "")
		)
		(fill yes
			(thermal_gap 0.5)
			(thermal_bridge_width 0.5)
			(island_removal_mode 0)
		)
		(polygon
			(pts
				(arc
					(start 265.762232 -34.52241)
					(mid 265.058652 -34.52241)
					(end 265.762232 -34.52241)
				)
			)
		)
	)
	(zone
		(layers "B.Cu" "In9.Cu" "In11.Cu" "In13.Cu" "In15.Cu")
		(hatch none 0.5)
		(connect_pads
			(clearance 0)
		)
		(min_thickness 0.25)
		(keepout
			(tracks not_allowed)
			(vias allowed)
			(pads allowed)
			(copperpour not_allowed)
			(footprints allowed)
		)
		(placement
			(enabled no)
			(sheetname "")
		)
		(fill yes
			(thermal_gap 0.5)
			(thermal_bridge_width 0.5)
			(island_removal_mode 0)
		)
		(polygon
			(pts
				(arc
					(start 429.17618 -312.999882)
					(mid 428.5234 -312.999882)
					(end 429.17618 -312.999882)
				)
			)
		)
	)
	(zone
		(layers "B.Cu" "In9.Cu" "In11.Cu" "In13.Cu" "In15.Cu")
		(hatch none 0.5)
		(connect_pads
			(clearance 0)
		)
		(min_thickness 0.25)
		(keepout
			(tracks not_allowed)
			(vias allowed)
			(pads allowed)
			(copperpour not_allowed)
			(footprints allowed)
		)
		(placement
			(enabled no)
			(sheetname "")
		)
		(fill yes
			(thermal_gap 0.5)
			(thermal_bridge_width 0.5)
			(island_removal_mode 0)
		)
		(polygon
			(pts
				(arc
					(start 23.656798 -345.465146)
					(mid 22.953218 -345.465146)
					(end 23.656798 -345.465146)
				)
			)
		)
	)
	(zone
		(layers "B.Cu" "In9.Cu" "In11.Cu" "In13.Cu" "In15.Cu")
		(hatch none 0.5)
		(connect_pads
			(clearance 0)
		)
		(min_thickness 0.25)
		(keepout
			(tracks not_allowed)
			(vias allowed)
			(pads allowed)
			(copperpour not_allowed)
			(footprints allowed)
		)
		(placement
			(enabled no)
			(sheetname "")
		)
		(fill yes
			(thermal_gap 0.5)
			(thermal_bridge_width 0.5)
			(island_removal_mode 0)
		)
		(polygon
			(pts
				(arc
					(start 191.276478 -312.999882)
					(mid 190.623698 -312.999882)
					(end 191.276478 -312.999882)
				)
			)
		)
	)
	(zone
		(layers "B.Cu" "In9.Cu" "In11.Cu" "In13.Cu" "In15.Cu")
		(hatch none 0.5)
		(connect_pads
			(clearance 0)
		)
		(min_thickness 0.25)
		(keepout
			(tracks not_allowed)
			(vias allowed)
			(pads allowed)
			(copperpour not_allowed)
			(footprints allowed)
		)
		(placement
			(enabled no)
			(sheetname "")
		)
		(fill yes
			(thermal_gap 0.5)
			(thermal_bridge_width 0.5)
			(island_removal_mode 0)
		)
		(polygon
			(pts
				(arc
					(start 203.516484 -32.722312)
					(mid 202.812904 -32.722312)
					(end 203.516484 -32.722312)
				)
			)
		)
	)
	(zone
		(layers "B.Cu" "In9.Cu" "In11.Cu" "In13.Cu" "In15.Cu")
		(hatch none 0.5)
		(connect_pads
			(clearance 0)
		)
		(min_thickness 0.25)
		(keepout
			(tracks not_allowed)
			(vias allowed)
			(pads allowed)
			(copperpour not_allowed)
			(footprints allowed)
		)
		(placement
			(enabled no)
			(sheetname "")
		)
		(fill yes
			(thermal_gap 0.5)
			(thermal_bridge_width 0.5)
			(island_removal_mode 0)
		)
		(polygon
			(pts
				(arc
					(start 39.289736 -375.490232)
					(mid 38.530276 -375.490232)
					(end 39.289736 -375.490232)
				)
			)
		)
	)
	(zone
		(layers "B.Cu" "In9.Cu" "In11.Cu" "In13.Cu" "In15.Cu")
		(hatch none 0.5)
		(connect_pads
			(clearance 0)
		)
		(min_thickness 0.25)
		(keepout
			(tracks not_allowed)
			(vias allowed)
			(pads allowed)
			(copperpour not_allowed)
			(footprints allowed)
		)
		(placement
			(enabled no)
			(sheetname "")
		)
		(fill yes
			(thermal_gap 0.5)
			(thermal_bridge_width 0.5)
			(island_removal_mode 0)
		)
		(polygon
			(pts
				(arc
					(start 184.300622 -357.733854)
					(mid 183.597042 -357.733854)
					(end 184.300622 -357.733854)
				)
			)
		)
	)
	(zone
		(layers "B.Cu" "In9.Cu" "In11.Cu" "In13.Cu" "In15.Cu")
		(hatch none 0.5)
		(connect_pads
			(clearance 0)
		)
		(min_thickness 0.25)
		(keepout
			(tracks not_allowed)
			(vias allowed)
			(pads allowed)
			(copperpour not_allowed)
			(footprints allowed)
		)
		(placement
			(enabled no)
			(sheetname "")
		)
		(fill yes
			(thermal_gap 0.5)
			(thermal_bridge_width 0.5)
			(island_removal_mode 0)
		)
		(polygon
			(pts
				(arc
					(start 426.3263 -311.099962)
					(mid 425.67352 -311.099962)
					(end 426.3263 -311.099962)
				)
			)
		)
	)
	(zone
		(layers "B.Cu" "In9.Cu" "In11.Cu" "In13.Cu" "In15.Cu")
		(hatch none 0.5)
		(connect_pads
			(clearance 0)
		)
		(min_thickness 0.25)
		(keepout
			(tracks not_allowed)
			(vias allowed)
			(pads allowed)
			(copperpour not_allowed)
			(footprints allowed)
		)
		(placement
			(enabled no)
			(sheetname "")
		)
		(fill yes
			(thermal_gap 0.5)
			(thermal_bridge_width 0.5)
			(island_removal_mode 0)
		)
		(polygon
			(pts
				(arc
					(start 50.773838 -348.58579)
					(mid 50.070258 -348.58579)
					(end 50.773838 -348.58579)
				)
			)
		)
	)
	(zone
		(layers "B.Cu" "In9.Cu" "In11.Cu" "In13.Cu" "In15.Cu")
		(hatch none 0.5)
		(connect_pads
			(clearance 0)
		)
		(min_thickness 0.25)
		(keepout
			(tracks not_allowed)
			(vias allowed)
			(pads allowed)
			(copperpour not_allowed)
			(footprints allowed)
		)
		(placement
			(enabled no)
			(sheetname "")
		)
		(fill yes
			(thermal_gap 0.5)
			(thermal_bridge_width 0.5)
			(island_removal_mode 0)
		)
		(polygon
			(pts
				(arc
					(start 295.976294 -313.949842)
					(mid 295.323514 -313.949842)
					(end 295.976294 -313.949842)
				)
			)
		)
	)
	(zone
		(layers "B.Cu" "In9.Cu" "In11.Cu" "In13.Cu" "In15.Cu")
		(hatch none 0.5)
		(connect_pads
			(clearance 0)
		)
		(min_thickness 0.25)
		(keepout
			(tracks not_allowed)
			(vias allowed)
			(pads allowed)
			(copperpour not_allowed)
			(footprints allowed)
		)
		(placement
			(enabled no)
			(sheetname "")
		)
		(fill yes
			(thermal_gap 0.5)
			(thermal_bridge_width 0.5)
			(island_removal_mode 0)
		)
		(polygon
			(pts
				(arc
					(start 395.92631 -275.949918)
					(mid 395.27353 -275.949918)
					(end 395.92631 -275.949918)
				)
			)
		)
	)
	(zone
		(layers "B.Cu" "In9.Cu" "In11.Cu" "In13.Cu" "In15.Cu")
		(hatch none 0.5)
		(connect_pads
			(clearance 0)
		)
		(min_thickness 0.25)
		(keepout
			(tracks not_allowed)
			(vias allowed)
			(pads allowed)
			(copperpour not_allowed)
			(footprints allowed)
		)
		(placement
			(enabled no)
			(sheetname "")
		)
		(fill yes
			(thermal_gap 0.5)
			(thermal_bridge_width 0.5)
			(island_removal_mode 0)
		)
		(polygon
			(pts
				(arc
					(start 34.889694 -402.790152)
					(mid 34.130234 -402.790152)
					(end 34.889694 -402.790152)
				)
			)
		)
	)
	(zone
		(layers "B.Cu" "In9.Cu" "In11.Cu" "In13.Cu" "In15.Cu")
		(hatch none 0.5)
		(connect_pads
			(clearance 0)
		)
		(min_thickness 0.25)
		(keepout
			(tracks not_allowed)
			(vias allowed)
			(pads allowed)
			(copperpour not_allowed)
			(footprints allowed)
		)
		(placement
			(enabled no)
			(sheetname "")
		)
		(fill yes
			(thermal_gap 0.5)
			(thermal_bridge_width 0.5)
			(island_removal_mode 0)
		)
		(polygon
			(pts
				(arc
					(start 424.42638 -308.249828)
					(mid 423.7736 -308.249828)
					(end 424.42638 -308.249828)
				)
			)
		)
	)
	(zone
		(layers "B.Cu" "In9.Cu" "In11.Cu" "In13.Cu" "In15.Cu")
		(hatch none 0.5)
		(connect_pads
			(clearance 0)
		)
		(min_thickness 0.25)
		(keepout
			(tracks not_allowed)
			(vias allowed)
			(pads allowed)
			(copperpour not_allowed)
			(footprints allowed)
		)
		(placement
			(enabled no)
			(sheetname "")
		)
		(fill yes
			(thermal_gap 0.5)
			(thermal_bridge_width 0.5)
			(island_removal_mode 0)
		)
		(polygon
			(pts
				(arc
					(start 134.840218 -354.732082)
					(mid 134.136638 -354.732082)
					(end 134.840218 -354.732082)
				)
			)
		)
	)
	(zone
		(layers "B.Cu" "In9.Cu" "In11.Cu" "In13.Cu" "In15.Cu")
		(hatch none 0.5)
		(connect_pads
			(clearance 0)
		)
		(min_thickness 0.25)
		(keepout
			(tracks not_allowed)
			(vias allowed)
			(pads allowed)
			(copperpour not_allowed)
			(footprints allowed)
		)
		(placement
			(enabled no)
			(sheetname "")
		)
		(fill yes
			(thermal_gap 0.5)
			(thermal_bridge_width 0.5)
			(island_removal_mode 0)
		)
		(polygon
			(pts
				(arc
					(start 403.526244 -275.949918)
					(mid 402.873464 -275.949918)
					(end 403.526244 -275.949918)
				)
			)
		)
	)
	(zone
		(layers "B.Cu" "In9.Cu" "In11.Cu" "In13.Cu" "In15.Cu")
		(hatch none 0.5)
		(connect_pads
			(clearance 0)
		)
		(min_thickness 0.25)
		(keepout
			(tracks not_allowed)
			(vias allowed)
			(pads allowed)
			(copperpour not_allowed)
			(footprints allowed)
		)
		(placement
			(enabled no)
			(sheetname "")
		)
		(fill yes
			(thermal_gap 0.5)
			(thermal_bridge_width 0.5)
			(island_removal_mode 0)
		)
		(polygon
			(pts
				(arc
					(start 193.627502 -351.611438)
					(mid 192.923922 -351.611438)
					(end 193.627502 -351.611438)
				)
			)
		)
	)
	(zone
		(layers "B.Cu" "In9.Cu" "In11.Cu" "In13.Cu" "In15.Cu")
		(hatch none 0.5)
		(connect_pads
			(clearance 0)
		)
		(min_thickness 0.25)
		(keepout
			(tracks not_allowed)
			(vias allowed)
			(pads allowed)
			(copperpour not_allowed)
			(footprints allowed)
		)
		(placement
			(enabled no)
			(sheetname "")
		)
		(fill yes
			(thermal_gap 0.5)
			(thermal_bridge_width 0.5)
			(island_removal_mode 0)
		)
		(polygon
			(pts
				(arc
					(start 47.62627 -275.949918)
					(mid 46.97349 -275.949918)
					(end 47.62627 -275.949918)
				)
			)
		)
	)
	(zone
		(layers "B.Cu" "In9.Cu" "In11.Cu" "In13.Cu" "In15.Cu")
		(hatch none 0.5)
		(connect_pads
			(clearance 0)
		)
		(min_thickness 0.25)
		(keepout
			(tracks not_allowed)
			(vias allowed)
			(pads allowed)
			(copperpour not_allowed)
			(footprints allowed)
		)
		(placement
			(enabled no)
			(sheetname "")
		)
		(fill yes
			(thermal_gap 0.5)
			(thermal_bridge_width 0.5)
			(island_removal_mode 0)
		)
		(polygon
			(pts
				(arc
					(start 78.132432 -357.75773)
					(mid 77.428852 -357.75773)
					(end 78.132432 -357.75773)
				)
			)
		)
	)
	(zone
		(layers "B.Cu" "In9.Cu" "In11.Cu" "In13.Cu" "In15.Cu")
		(hatch none 0.5)
		(connect_pads
			(clearance 0)
		)
		(min_thickness 0.25)
		(keepout
			(tracks not_allowed)
			(vias allowed)
			(pads allowed)
			(copperpour not_allowed)
			(footprints allowed)
		)
		(placement
			(enabled no)
			(sheetname "")
		)
		(fill yes
			(thermal_gap 0.5)
			(thermal_bridge_width 0.5)
			(island_removal_mode 0)
		)
		(polygon
			(pts
				(arc
					(start 83.486752 -357.75773)
					(mid 82.783172 -357.75773)
					(end 83.486752 -357.75773)
				)
			)
		)
	)
	(zone
		(layers "B.Cu" "In9.Cu" "In11.Cu" "In13.Cu" "In15.Cu")
		(hatch none 0.5)
		(connect_pads
			(clearance 0)
		)
		(min_thickness 0.25)
		(keepout
			(tracks not_allowed)
			(vias allowed)
			(pads allowed)
			(copperpour not_allowed)
			(footprints allowed)
		)
		(placement
			(enabled no)
			(sheetname "")
		)
		(fill yes
			(thermal_gap 0.5)
			(thermal_bridge_width 0.5)
			(island_removal_mode 0)
		)
		(polygon
			(pts
				(arc
					(start 433.069492 -397.790162)
					(mid 432.310032 -397.790162)
					(end 433.069492 -397.790162)
				)
			)
		)
	)
	(zone
		(layers "B.Cu" "In9.Cu" "In11.Cu" "In13.Cu" "In15.Cu")
		(hatch none 0.5)
		(connect_pads
			(clearance 0)
		)
		(min_thickness 0.25)
		(keepout
			(tracks not_allowed)
			(vias allowed)
			(pads allowed)
			(copperpour not_allowed)
			(footprints allowed)
		)
		(placement
			(enabled no)
			(sheetname "")
		)
		(fill yes
			(thermal_gap 0.5)
			(thermal_bridge_width 0.5)
			(island_removal_mode 0)
		)
		(polygon
			(pts
				(arc
					(start 426.055282 -354.732082)
					(mid 425.351702 -354.732082)
					(end 426.055282 -354.732082)
				)
			)
		)
	)
	(zone
		(layers "B.Cu" "In9.Cu" "In11.Cu" "In13.Cu" "In15.Cu")
		(hatch none 0.5)
		(connect_pads
			(clearance 0)
		)
		(min_thickness 0.25)
		(keepout
			(tracks not_allowed)
			(vias allowed)
			(pads allowed)
			(copperpour not_allowed)
			(footprints allowed)
		)
		(placement
			(enabled no)
			(sheetname "")
		)
		(fill yes
			(thermal_gap 0.5)
			(thermal_bridge_width 0.5)
			(island_removal_mode 0)
		)
		(polygon
			(pts
				(arc
					(start 40.026336 -312.049922)
					(mid 39.373556 -312.049922)
					(end 40.026336 -312.049922)
				)
			)
		)
	)
	(zone
		(layers "B.Cu" "In9.Cu" "In11.Cu" "In13.Cu" "In15.Cu")
		(hatch none 0.5)
		(connect_pads
			(clearance 0)
		)
		(min_thickness 0.25)
		(keepout
			(tracks not_allowed)
			(vias allowed)
			(pads allowed)
			(copperpour not_allowed)
			(footprints allowed)
		)
		(placement
			(enabled no)
			(sheetname "")
		)
		(fill yes
			(thermal_gap 0.5)
			(thermal_bridge_width 0.5)
			(island_removal_mode 0)
		)
		(polygon
			(pts
				(arc
					(start 277.926292 -274.999958)
					(mid 277.273512 -274.999958)
					(end 277.926292 -274.999958)
				)
			)
		)
	)
	(zone
		(layers "B.Cu" "In9.Cu" "In11.Cu" "In13.Cu" "In15.Cu")
		(hatch none 0.5)
		(connect_pads
			(clearance 0)
		)
		(min_thickness 0.25)
		(keepout
			(tracks not_allowed)
			(vias allowed)
			(pads allowed)
			(copperpour not_allowed)
			(footprints allowed)
		)
		(placement
			(enabled no)
			(sheetname "")
		)
		(fill yes
			(thermal_gap 0.5)
			(thermal_bridge_width 0.5)
			(island_removal_mode 0)
		)
		(polygon
			(pts
				(arc
					(start 39.076376 -313.949842)
					(mid 38.423596 -313.949842)
					(end 39.076376 -313.949842)
				)
			)
		)
	)
	(zone
		(layers "B.Cu" "In9.Cu" "In11.Cu" "In13.Cu" "In15.Cu")
		(hatch none 0.5)
		(connect_pads
			(clearance 0)
		)
		(min_thickness 0.25)
		(keepout
			(tracks not_allowed)
			(vias allowed)
			(pads allowed)
			(copperpour not_allowed)
			(footprints allowed)
		)
		(placement
			(enabled no)
			(sheetname "")
		)
		(fill yes
			(thermal_gap 0.5)
			(thermal_bridge_width 0.5)
			(island_removal_mode 0)
		)
		(polygon
			(pts
				(arc
					(start 290.875212 -345.465146)
					(mid 290.171632 -345.465146)
					(end 290.875212 -345.465146)
				)
			)
		)
	)
	(zone
		(layers "B.Cu" "In9.Cu" "In11.Cu" "In13.Cu" "In15.Cu")
		(hatch none 0.5)
		(connect_pads
			(clearance 0)
		)
		(min_thickness 0.25)
		(keepout
			(tracks not_allowed)
			(vias allowed)
			(pads allowed)
			(copperpour not_allowed)
			(footprints allowed)
		)
		(placement
			(enabled no)
			(sheetname "")
		)
		(fill yes
			(thermal_gap 0.5)
			(thermal_bridge_width 0.5)
			(island_removal_mode 0)
		)
		(polygon
			(pts
				(arc
					(start 164.676328 -273.099784)
					(mid 164.023548 -273.099784)
					(end 164.676328 -273.099784)
				)
			)
		)
	)
	(zone
		(layers "B.Cu" "In9.Cu" "In11.Cu" "In13.Cu" "In15.Cu")
		(hatch none 0.5)
		(connect_pads
			(clearance 0)
		)
		(min_thickness 0.25)
		(keepout
			(tracks not_allowed)
			(vias allowed)
			(pads allowed)
			(copperpour not_allowed)
			(footprints allowed)
		)
		(placement
			(enabled no)
			(sheetname "")
		)
		(fill yes
			(thermal_gap 0.5)
			(thermal_bridge_width 0.5)
			(island_removal_mode 0)
		)
		(polygon
			(pts
				(arc
					(start 241.616484 -29.12237)
					(mid 240.912904 -29.12237)
					(end 241.616484 -29.12237)
				)
			)
		)
	)
	(zone
		(layers "B.Cu" "In9.Cu" "In11.Cu" "In13.Cu" "In15.Cu")
		(hatch none 0.5)
		(connect_pads
			(clearance 0)
		)
		(min_thickness 0.25)
		(keepout
			(tracks not_allowed)
			(vias allowed)
			(pads allowed)
			(copperpour not_allowed)
			(footprints allowed)
		)
		(placement
			(enabled no)
			(sheetname "")
		)
		(fill yes
			(thermal_gap 0.5)
			(thermal_bridge_width 0.5)
			(island_removal_mode 0)
		)
		(polygon
			(pts
				(arc
					(start 313.718194 -348.58579)
					(mid 313.014614 -348.58579)
					(end 313.718194 -348.58579)
				)
			)
		)
	)
	(zone
		(layers "B.Cu" "In9.Cu" "In11.Cu" "In13.Cu" "In15.Cu")
		(hatch none 0.5)
		(connect_pads
			(clearance 0)
		)
		(min_thickness 0.25)
		(keepout
			(tracks not_allowed)
			(vias allowed)
			(pads allowed)
			(copperpour not_allowed)
			(footprints allowed)
		)
		(placement
			(enabled no)
			(sheetname "")
		)
		(fill yes
			(thermal_gap 0.5)
			(thermal_bridge_width 0.5)
			(island_removal_mode 0)
		)
		(polygon
			(pts
				(arc
					(start 173.226476 -311.099962)
					(mid 172.573696 -311.099962)
					(end 173.226476 -311.099962)
				)
			)
		)
	)
	(zone
		(layers "B.Cu" "In9.Cu" "In11.Cu" "In13.Cu" "In15.Cu")
		(hatch none 0.5)
		(connect_pads
			(clearance 0)
		)
		(min_thickness 0.25)
		(keepout
			(tracks not_allowed)
			(vias allowed)
			(pads allowed)
			(copperpour not_allowed)
			(footprints allowed)
		)
		(placement
			(enabled no)
			(sheetname "")
		)
		(fill yes
			(thermal_gap 0.5)
			(thermal_bridge_width 0.5)
			(island_removal_mode 0)
		)
		(polygon
			(pts
				(arc
					(start 163.726368 -275.949918)
					(mid 163.073588 -275.949918)
					(end 163.726368 -275.949918)
				)
			)
		)
	)
	(zone
		(layers "B.Cu" "In9.Cu" "In11.Cu" "In13.Cu" "In15.Cu")
		(hatch none 0.5)
		(connect_pads
			(clearance 0)
		)
		(min_thickness 0.25)
		(keepout
			(tracks not_allowed)
			(vias allowed)
			(pads allowed)
			(copperpour not_allowed)
			(footprints allowed)
		)
		(placement
			(enabled no)
			(sheetname "")
		)
		(fill yes
			(thermal_gap 0.5)
			(thermal_bridge_width 0.5)
			(island_removal_mode 0)
		)
		(polygon
			(pts
				(arc
					(start 63.776352 -312.999882)
					(mid 63.123572 -312.999882)
					(end 63.776352 -312.999882)
				)
			)
		)
	)
	(zone
		(layers "B.Cu" "In9.Cu" "In11.Cu" "In13.Cu" "In15.Cu")
		(hatch none 0.5)
		(connect_pads
			(clearance 0)
		)
		(min_thickness 0.25)
		(keepout
			(tracks not_allowed)
			(vias allowed)
			(pads allowed)
			(copperpour not_allowed)
			(footprints allowed)
		)
		(placement
			(enabled no)
			(sheetname "")
		)
		(fill yes
			(thermal_gap 0.5)
			(thermal_bridge_width 0.5)
			(island_removal_mode 0)
		)
		(polygon
			(pts
				(arc
					(start 90.568272 -354.732082)
					(mid 89.864692 -354.732082)
					(end 90.568272 -354.732082)
				)
			)
		)
	)
	(zone
		(layers "B.Cu" "In9.Cu" "In11.Cu" "In13.Cu" "In15.Cu")
		(hatch none 0.5)
		(connect_pads
			(clearance 0)
		)
		(min_thickness 0.25)
		(keepout
			(tracks not_allowed)
			(vias allowed)
			(pads allowed)
			(copperpour not_allowed)
			(footprints allowed)
		)
		(placement
			(enabled no)
			(sheetname "")
		)
		(fill yes
			(thermal_gap 0.5)
			(thermal_bridge_width 0.5)
			(island_removal_mode 0)
		)
		(polygon
			(pts
				(arc
					(start 37.176202 -312.049922)
					(mid 36.523422 -312.049922)
					(end 37.176202 -312.049922)
				)
			)
		)
	)
	(zone
		(layers "B.Cu" "In9.Cu" "In11.Cu" "In13.Cu" "In15.Cu")
		(hatch none 0.5)
		(connect_pads
			(clearance 0)
		)
		(min_thickness 0.25)
		(keepout
			(tracks not_allowed)
			(vias allowed)
			(pads allowed)
			(copperpour not_allowed)
			(footprints allowed)
		)
		(placement
			(enabled no)
			(sheetname "")
		)
		(fill yes
			(thermal_gap 0.5)
			(thermal_bridge_width 0.5)
			(island_removal_mode 0)
		)
		(polygon
			(pts
				(arc
					(start 407.326338 -275.949918)
					(mid 406.673558 -275.949918)
					(end 407.326338 -275.949918)
				)
			)
		)
	)
	(zone
		(layers "B.Cu" "In9.Cu" "In11.Cu" "In13.Cu" "In15.Cu")
		(hatch none 0.5)
		(connect_pads
			(clearance 0)
		)
		(min_thickness 0.25)
		(keepout
			(tracks not_allowed)
			(vias allowed)
			(pads allowed)
			(copperpour not_allowed)
			(footprints allowed)
		)
		(placement
			(enabled no)
			(sheetname "")
		)
		(fill yes
			(thermal_gap 0.5)
			(thermal_bridge_width 0.5)
			(island_removal_mode 0)
		)
		(polygon
			(pts
				(arc
					(start 323.045074 -342.439498)
					(mid 322.341494 -342.439498)
					(end 323.045074 -342.439498)
				)
			)
		)
	)
	(zone
		(layers "B.Cu" "In9.Cu" "In11.Cu" "In13.Cu" "In15.Cu")
		(hatch none 0.5)
		(connect_pads
			(clearance 0)
		)
		(min_thickness 0.25)
		(keepout
			(tracks not_allowed)
			(vias allowed)
			(pads allowed)
			(copperpour not_allowed)
			(footprints allowed)
		)
		(placement
			(enabled no)
			(sheetname "")
		)
		(fill yes
			(thermal_gap 0.5)
			(thermal_bridge_width 0.5)
			(island_removal_mode 0)
		)
		(polygon
			(pts
				(arc
					(start 381.86233 -30.922468)
					(mid 381.15875 -30.922468)
					(end 381.86233 -30.922468)
				)
			)
		)
	)
	(zone
		(layers "B.Cu" "In9.Cu" "In11.Cu" "In13.Cu" "In15.Cu")
		(hatch none 0.5)
		(connect_pads
			(clearance 0)
		)
		(min_thickness 0.25)
		(keepout
			(tracks not_allowed)
			(vias allowed)
			(pads allowed)
			(copperpour not_allowed)
			(footprints allowed)
		)
		(placement
			(enabled no)
			(sheetname "")
		)
		(fill yes
			(thermal_gap 0.5)
			(thermal_bridge_width 0.5)
			(island_removal_mode 0)
		)
		(polygon
			(pts
				(arc
					(start 394.16609 -345.465146)
					(mid 393.46251 -345.465146)
					(end 394.16609 -345.465146)
				)
			)
		)
	)
	(zone
		(layers "B.Cu" "In9.Cu" "In11.Cu" "In13.Cu" "In15.Cu")
		(hatch none 0.5)
		(connect_pads
			(clearance 0)
		)
		(min_thickness 0.25)
		(keepout
			(tracks not_allowed)
			(vias allowed)
			(pads allowed)
			(copperpour not_allowed)
			(footprints allowed)
		)
		(placement
			(enabled no)
			(sheetname "")
		)
		(fill yes
			(thermal_gap 0.5)
			(thermal_bridge_width 0.5)
			(island_removal_mode 0)
		)
		(polygon
			(pts
				(arc
					(start 410.176218 -313.949842)
					(mid 409.523438 -313.949842)
					(end 410.176218 -313.949842)
				)
			)
		)
	)
	(zone
		(layers "B.Cu" "In9.Cu" "In11.Cu" "In13.Cu" "In15.Cu")
		(hatch none 0.5)
		(connect_pads
			(clearance 0)
		)
		(min_thickness 0.25)
		(keepout
			(tracks not_allowed)
			(vias allowed)
			(pads allowed)
			(copperpour not_allowed)
			(footprints allowed)
		)
		(placement
			(enabled no)
			(sheetname "")
		)
		(fill yes
			(thermal_gap 0.5)
			(thermal_bridge_width 0.5)
			(island_removal_mode 0)
		)
		(polygon
			(pts
				(arc
					(start 435.26964 -397.59001)
					(mid 434.51018 -397.59001)
					(end 435.26964 -397.59001)
				)
			)
		)
	)
	(zone
		(layers "B.Cu" "In9.Cu" "In11.Cu" "In13.Cu" "In15.Cu")
		(hatch none 0.5)
		(connect_pads
			(clearance 0)
		)
		(min_thickness 0.25)
		(keepout
			(tracks not_allowed)
			(vias allowed)
			(pads allowed)
			(copperpour not_allowed)
			(footprints allowed)
		)
		(placement
			(enabled no)
			(sheetname "")
		)
		(fill yes
			(thermal_gap 0.5)
			(thermal_bridge_width 0.5)
			(island_removal_mode 0)
		)
		(polygon
			(pts
				(arc
					(start 278.876252 -274.049744)
					(mid 278.223472 -274.049744)
					(end 278.876252 -274.049744)
				)
			)
		)
	)
	(zone
		(layers "B.Cu" "In9.Cu" "In11.Cu" "In13.Cu" "In15.Cu")
		(hatch none 0.5)
		(connect_pads
			(clearance 0)
		)
		(min_thickness 0.25)
		(keepout
			(tracks not_allowed)
			(vias allowed)
			(pads allowed)
			(copperpour not_allowed)
			(footprints allowed)
		)
		(placement
			(enabled no)
			(sheetname "")
		)
		(fill yes
			(thermal_gap 0.5)
			(thermal_bridge_width 0.5)
			(island_removal_mode 0)
		)
		(polygon
			(pts
				(arc
					(start 239.762284 -33.65881)
					(mid 239.058704 -33.65881)
					(end 239.762284 -33.65881)
				)
			)
		)
	)
	(zone
		(layers "B.Cu" "In9.Cu" "In11.Cu" "In13.Cu" "In15.Cu")
		(hatch none 0.5)
		(connect_pads
			(clearance 0)
		)
		(min_thickness 0.25)
		(keepout
			(tracks not_allowed)
			(vias allowed)
			(pads allowed)
			(copperpour not_allowed)
			(footprints allowed)
		)
		(placement
			(enabled no)
			(sheetname "")
		)
		(fill yes
			(thermal_gap 0.5)
			(thermal_bridge_width 0.5)
			(island_removal_mode 0)
		)
		(polygon
			(pts
				(arc
					(start 334.617314 -342.439498)
					(mid 333.913734 -342.439498)
					(end 334.617314 -342.439498)
				)
			)
		)
	)
	(zone
		(layers "B.Cu" "In9.Cu" "In11.Cu" "In13.Cu" "In15.Cu")
		(hatch none 0.5)
		(connect_pads
			(clearance 0)
		)
		(min_thickness 0.25)
		(keepout
			(tracks not_allowed)
			(vias allowed)
			(pads allowed)
			(copperpour not_allowed)
			(footprints allowed)
		)
		(placement
			(enabled no)
			(sheetname "")
		)
		(fill yes
			(thermal_gap 0.5)
			(thermal_bridge_width 0.5)
			(island_removal_mode 0)
		)
		(polygon
			(pts
				(arc
					(start 382.469644 -384.590036)
					(mid 381.710184 -384.590036)
					(end 382.469644 -384.590036)
				)
			)
		)
	)
	(zone
		(layers "B.Cu" "In9.Cu" "In11.Cu" "In13.Cu" "In15.Cu")
		(hatch none 0.5)
		(connect_pads
			(clearance 0)
		)
		(min_thickness 0.25)
		(keepout
			(tracks not_allowed)
			(vias allowed)
			(pads allowed)
			(copperpour not_allowed)
			(footprints allowed)
		)
		(placement
			(enabled no)
			(sheetname "")
		)
		(fill yes
			(thermal_gap 0.5)
			(thermal_bridge_width 0.5)
			(island_removal_mode 0)
		)
		(polygon
			(pts
				(arc
					(start 164.68979 -370.489988)
					(mid 163.93033 -370.489988)
					(end 164.68979 -370.489988)
				)
			)
		)
	)
	(zone
		(layers "B.Cu" "In9.Cu" "In11.Cu" "In13.Cu" "In15.Cu")
		(hatch none 0.5)
		(connect_pads
			(clearance 0)
		)
		(min_thickness 0.25)
		(keepout
			(tracks not_allowed)
			(vias allowed)
			(pads allowed)
			(copperpour not_allowed)
			(footprints allowed)
		)
		(placement
			(enabled no)
			(sheetname "")
		)
		(fill yes
			(thermal_gap 0.5)
			(thermal_bridge_width 0.5)
			(island_removal_mode 0)
		)
		(polygon
			(pts
				(arc
					(start 385.736084 7.710932)
					(mid 385.032504 7.710932)
					(end 385.736084 7.710932)
				)
			)
		)
	)
	(zone
		(layers "B.Cu" "In9.Cu" "In11.Cu" "In13.Cu" "In15.Cu")
		(hatch none 0.5)
		(connect_pads
			(clearance 0)
		)
		(min_thickness 0.25)
		(keepout
			(tracks not_allowed)
			(vias allowed)
			(pads allowed)
			(copperpour not_allowed)
			(footprints allowed)
		)
		(placement
			(enabled no)
			(sheetname "")
		)
		(fill yes
			(thermal_gap 0.5)
			(thermal_bridge_width 0.5)
			(island_removal_mode 0)
		)
		(polygon
			(pts
				(arc
					(start 46.67631 -274.049744)
					(mid 46.02353 -274.049744)
					(end 46.67631 -274.049744)
				)
			)
		)
	)
	(zone
		(layers "B.Cu" "In9.Cu" "In11.Cu" "In13.Cu" "In15.Cu")
		(hatch none 0.5)
		(connect_pads
			(clearance 0)
		)
		(min_thickness 0.25)
		(keepout
			(tracks not_allowed)
			(vias allowed)
			(pads allowed)
			(copperpour not_allowed)
			(footprints allowed)
		)
		(placement
			(enabled no)
			(sheetname "")
		)
		(fill yes
			(thermal_gap 0.5)
			(thermal_bridge_width 0.5)
			(island_removal_mode 0)
		)
		(polygon
			(pts
				(arc
					(start 68.805552 -348.58579)
					(mid 68.101972 -348.58579)
					(end 68.805552 -348.58579)
				)
			)
		)
	)
	(zone
		(layers "B.Cu" "In9.Cu" "In11.Cu" "In13.Cu" "In15.Cu")
		(hatch none 0.5)
		(connect_pads
			(clearance 0)
		)
		(min_thickness 0.25)
		(keepout
			(tracks not_allowed)
			(vias allowed)
			(pads allowed)
			(copperpour not_allowed)
			(footprints allowed)
		)
		(placement
			(enabled no)
			(sheetname "")
		)
		(fill yes
			(thermal_gap 0.5)
			(thermal_bridge_width 0.5)
			(island_removal_mode 0)
		)
		(polygon
			(pts
				(arc
					(start 125.513338 -348.58579)
					(mid 124.809758 -348.58579)
					(end 125.513338 -348.58579)
				)
			)
		)
	)
	(zone
		(layers "B.Cu" "In9.Cu" "In11.Cu" "In13.Cu" "In15.Cu")
		(hatch none 0.5)
		(connect_pads
			(clearance 0)
		)
		(min_thickness 0.25)
		(keepout
			(tracks not_allowed)
			(vias allowed)
			(pads allowed)
			(copperpour not_allowed)
			(footprints allowed)
		)
		(placement
			(enabled no)
			(sheetname "")
		)
		(fill yes
			(thermal_gap 0.5)
			(thermal_bridge_width 0.5)
			(island_removal_mode 0)
		)
		(polygon
			(pts
				(arc
					(start 397.82623 -275.949918)
					(mid 397.17345 -275.949918)
					(end 397.82623 -275.949918)
				)
			)
		)
	)
	(zone
		(layers "B.Cu" "In9.Cu" "In11.Cu" "In13.Cu" "In15.Cu")
		(hatch none 0.5)
		(connect_pads
			(clearance 0)
		)
		(min_thickness 0.25)
		(keepout
			(tracks not_allowed)
			(vias allowed)
			(pads allowed)
			(copperpour not_allowed)
			(footprints allowed)
		)
		(placement
			(enabled no)
			(sheetname "")
		)
		(fill yes
			(thermal_gap 0.5)
			(thermal_bridge_width 0.5)
			(island_removal_mode 0)
		)
		(polygon
			(pts
				(arc
					(start 386.869686 -384.590036)
					(mid 386.110226 -384.590036)
					(end 386.869686 -384.590036)
				)
			)
		)
	)
	(zone
		(layers "B.Cu" "In9.Cu" "In11.Cu" "In13.Cu" "In15.Cu")
		(hatch none 0.5)
		(connect_pads
			(clearance 0)
		)
		(min_thickness 0.25)
		(keepout
			(tracks not_allowed)
			(vias allowed)
			(pads allowed)
			(copperpour not_allowed)
			(footprints allowed)
		)
		(placement
			(enabled no)
			(sheetname "")
		)
		(fill yes
			(thermal_gap 0.5)
			(thermal_bridge_width 0.5)
			(island_removal_mode 0)
		)
		(polygon
			(pts
				(arc
					(start 87.459312 -348.58579)
					(mid 86.755732 -348.58579)
					(end 87.459312 -348.58579)
				)
			)
		)
	)
	(zone
		(layers "B.Cu" "In9.Cu" "In11.Cu" "In13.Cu" "In15.Cu")
		(hatch none 0.5)
		(connect_pads
			(clearance 0)
		)
		(min_thickness 0.25)
		(keepout
			(tracks not_allowed)
			(vias allowed)
			(pads allowed)
			(copperpour not_allowed)
			(footprints allowed)
		)
		(placement
			(enabled no)
			(sheetname "")
		)
		(fill yes
			(thermal_gap 0.5)
			(thermal_bridge_width 0.5)
			(island_removal_mode 0)
		)
		(polygon
			(pts
				(arc
					(start 41.446958 -345.465146)
					(mid 40.743378 -345.465146)
					(end 41.446958 -345.465146)
				)
			)
		)
	)
	(zone
		(layers "B.Cu" "In9.Cu" "In11.Cu" "In13.Cu" "In15.Cu")
		(hatch none 0.5)
		(connect_pads
			(clearance 0)
		)
		(min_thickness 0.25)
		(keepout
			(tracks not_allowed)
			(vias allowed)
			(pads allowed)
			(copperpour not_allowed)
			(footprints allowed)
		)
		(placement
			(enabled no)
			(sheetname "")
		)
		(fill yes
			(thermal_gap 0.5)
			(thermal_bridge_width 0.5)
			(island_removal_mode 0)
		)
		(polygon
			(pts
				(arc
					(start 383.71653 -29.12237)
					(mid 383.01295 -29.12237)
					(end 383.71653 -29.12237)
				)
			)
		)
	)
	(zone
		(layers "B.Cu" "In9.Cu" "In11.Cu" "In13.Cu" "In15.Cu")
		(hatch none 0.5)
		(connect_pads
			(clearance 0)
		)
		(min_thickness 0.25)
		(keepout
			(tracks not_allowed)
			(vias allowed)
			(pads allowed)
			(copperpour not_allowed)
			(footprints allowed)
		)
		(placement
			(enabled no)
			(sheetname "")
		)
		(fill yes
			(thermal_gap 0.5)
			(thermal_bridge_width 0.5)
			(island_removal_mode 0)
		)
		(polygon
			(pts
				(arc
					(start 423.47642 -313.949842)
					(mid 422.82364 -313.949842)
					(end 423.47642 -313.949842)
				)
			)
		)
	)
	(zone
		(layers "B.Cu" "In9.Cu" "In11.Cu" "In13.Cu" "In15.Cu")
		(hatch none 0.5)
		(connect_pads
			(clearance 0)
		)
		(min_thickness 0.25)
		(keepout
			(tracks not_allowed)
			(vias allowed)
			(pads allowed)
			(copperpour not_allowed)
			(footprints allowed)
		)
		(placement
			(enabled no)
			(sheetname "")
		)
		(fill yes
			(thermal_gap 0.5)
			(thermal_bridge_width 0.5)
			(island_removal_mode 0)
		)
		(polygon
			(pts
				(arc
					(start 172.276262 -313.949842)
					(mid 171.623482 -313.949842)
					(end 172.276262 -313.949842)
				)
			)
		)
	)
	(zone
		(layers "B.Cu" "In9.Cu" "In11.Cu" "In13.Cu" "In15.Cu")
		(hatch none 0.5)
		(connect_pads
			(clearance 0)
		)
		(min_thickness 0.25)
		(keepout
			(tracks not_allowed)
			(vias allowed)
			(pads allowed)
			(copperpour not_allowed)
			(footprints allowed)
		)
		(placement
			(enabled no)
			(sheetname "")
		)
		(fill yes
			(thermal_gap 0.5)
			(thermal_bridge_width 0.5)
			(island_removal_mode 0)
		)
		(polygon
			(pts
				(arc
					(start 393.30249 -342.439498)
					(mid 392.59891 -342.439498)
					(end 393.30249 -342.439498)
				)
			)
		)
	)
	(zone
		(layers "B.Cu" "In9.Cu" "In11.Cu" "In13.Cu" "In15.Cu")
		(hatch none 0.5)
		(connect_pads
			(clearance 0)
		)
		(min_thickness 0.25)
		(keepout
			(tracks not_allowed)
			(vias allowed)
			(pads allowed)
			(copperpour not_allowed)
			(footprints allowed)
		)
		(placement
			(enabled no)
			(sheetname "")
		)
		(fill yes
			(thermal_gap 0.5)
			(thermal_bridge_width 0.5)
			(island_removal_mode 0)
		)
		(polygon
			(pts
				(arc
					(start 347.269816 -405.390096)
					(mid 346.510356 -405.390096)
					(end 347.269816 -405.390096)
				)
			)
		)
	)
	(zone
		(layers "B.Cu" "In9.Cu" "In11.Cu" "In13.Cu" "In15.Cu")
		(hatch none 0.5)
		(connect_pads
			(clearance 0)
		)
		(min_thickness 0.25)
		(keepout
			(tracks not_allowed)
			(vias allowed)
			(pads allowed)
			(copperpour not_allowed)
			(footprints allowed)
		)
		(placement
			(enabled no)
			(sheetname "")
		)
		(fill yes
			(thermal_gap 0.5)
			(thermal_bridge_width 0.5)
			(island_removal_mode 0)
		)
		(polygon
			(pts
				(arc
					(start 282.676092 -274.049744)
					(mid 282.023312 -274.049744)
					(end 282.676092 -274.049744)
				)
			)
		)
	)
	(zone
		(layers "B.Cu" "In9.Cu" "In11.Cu" "In13.Cu" "In15.Cu")
		(hatch none 0.5)
		(connect_pads
			(clearance 0)
		)
		(min_thickness 0.25)
		(keepout
			(tracks not_allowed)
			(vias allowed)
			(pads allowed)
			(copperpour not_allowed)
			(footprints allowed)
		)
		(placement
			(enabled no)
			(sheetname "")
		)
		(fill yes
			(thermal_gap 0.5)
			(thermal_bridge_width 0.5)
			(island_removal_mode 0)
		)
		(polygon
			(pts
				(arc
					(start 59.026298 -311.099962)
					(mid 58.373518 -311.099962)
					(end 59.026298 -311.099962)
				)
			)
		)
	)
	(zone
		(layers "B.Cu" "In9.Cu" "In11.Cu" "In13.Cu" "In15.Cu")
		(hatch none 0.5)
		(connect_pads
			(clearance 0)
		)
		(min_thickness 0.25)
		(keepout
			(tracks not_allowed)
			(vias allowed)
			(pads allowed)
			(copperpour not_allowed)
			(footprints allowed)
		)
		(placement
			(enabled no)
			(sheetname "")
		)
		(fill yes
			(thermal_gap 0.5)
			(thermal_bridge_width 0.5)
			(island_removal_mode 0)
		)
		(polygon
			(pts
				(arc
					(start 407.326338 -274.999958)
					(mid 406.673558 -274.999958)
					(end 407.326338 -274.999958)
				)
			)
		)
	)
	(zone
		(layers "B.Cu" "In9.Cu" "In11.Cu" "In13.Cu" "In15.Cu")
		(hatch none 0.5)
		(connect_pads
			(clearance 0)
		)
		(min_thickness 0.25)
		(keepout
			(tracks not_allowed)
			(vias allowed)
			(pads allowed)
			(copperpour not_allowed)
			(footprints allowed)
		)
		(placement
			(enabled no)
			(sheetname "")
		)
		(fill yes
			(thermal_gap 0.5)
			(thermal_bridge_width 0.5)
			(island_removal_mode 0)
		)
		(polygon
			(pts
				(arc
					(start 116.289836 -404.290022)
					(mid 115.530376 -404.290022)
					(end 116.289836 -404.290022)
				)
			)
		)
	)
	(zone
		(layers "B.Cu" "In9.Cu" "In11.Cu" "In13.Cu" "In15.Cu")
		(hatch none 0.5)
		(connect_pads
			(clearance 0)
		)
		(min_thickness 0.25)
		(keepout
			(tracks not_allowed)
			(vias allowed)
			(pads allowed)
			(copperpour not_allowed)
			(footprints allowed)
		)
		(placement
			(enabled no)
			(sheetname "")
		)
		(fill yes
			(thermal_gap 0.5)
			(thermal_bridge_width 0.5)
			(island_removal_mode 0)
		)
		(polygon
			(pts
				(arc
					(start 278.439372 -357.75773)
					(mid 277.735792 -357.75773)
					(end 278.439372 -357.75773)
				)
			)
		)
	)
	(zone
		(layers "B.Cu" "In9.Cu" "In11.Cu" "In13.Cu" "In15.Cu")
		(hatch none 0.5)
		(connect_pads
			(clearance 0)
		)
		(min_thickness 0.25)
		(keepout
			(tracks not_allowed)
			(vias allowed)
			(pads allowed)
			(copperpour not_allowed)
			(footprints allowed)
		)
		(placement
			(enabled no)
			(sheetname "")
		)
		(fill yes
			(thermal_gap 0.5)
			(thermal_bridge_width 0.5)
			(island_removal_mode 0)
		)
		(polygon
			(pts
				(arc
					(start 35.229038 -345.465146)
					(mid 34.525458 -345.465146)
					(end 35.229038 -345.465146)
				)
			)
		)
	)
	(zone
		(layers "B.Cu" "In9.Cu" "In11.Cu" "In13.Cu" "In15.Cu")
		(hatch none 0.5)
		(connect_pads
			(clearance 0)
		)
		(min_thickness 0.25)
		(keepout
			(tracks not_allowed)
			(vias allowed)
			(pads allowed)
			(copperpour not_allowed)
			(footprints allowed)
		)
		(placement
			(enabled no)
			(sheetname "")
		)
		(fill yes
			(thermal_gap 0.5)
			(thermal_bridge_width 0.5)
			(island_removal_mode 0)
		)
		(polygon
			(pts
				(arc
					(start 140.194538 -342.439498)
					(mid 139.490958 -342.439498)
					(end 140.194538 -342.439498)
				)
			)
		)
	)
	(zone
		(layers "B.Cu" "In9.Cu" "In11.Cu" "In13.Cu" "In15.Cu")
		(hatch none 0.5)
		(connect_pads
			(clearance 0)
		)
		(min_thickness 0.25)
		(keepout
			(tracks not_allowed)
			(vias allowed)
			(pads allowed)
			(copperpour not_allowed)
			(footprints allowed)
		)
		(placement
			(enabled no)
			(sheetname "")
		)
		(fill yes
			(thermal_gap 0.5)
			(thermal_bridge_width 0.5)
			(island_removal_mode 0)
		)
		(polygon
			(pts
				(arc
					(start 291.76218 -30.058868)
					(mid 291.0586 -30.058868)
					(end 291.76218 -30.058868)
				)
			)
		)
	)
	(zone
		(layers "B.Cu" "In9.Cu" "In11.Cu" "In13.Cu" "In15.Cu")
		(hatch none 0.5)
		(connect_pads
			(clearance 0)
		)
		(min_thickness 0.25)
		(keepout
			(tracks not_allowed)
			(vias allowed)
			(pads allowed)
			(copperpour not_allowed)
			(footprints allowed)
		)
		(placement
			(enabled no)
			(sheetname "")
		)
		(fill yes
			(thermal_gap 0.5)
			(thermal_bridge_width 0.5)
			(island_removal_mode 0)
		)
		(polygon
			(pts
				(arc
					(start 196.976238 -313.949842)
					(mid 196.323458 -313.949842)
					(end 196.976238 -313.949842)
				)
			)
		)
	)
	(zone
		(layers "B.Cu" "In9.Cu" "In11.Cu" "In13.Cu" "In15.Cu")
		(hatch none 0.5)
		(connect_pads
			(clearance 0)
		)
		(min_thickness 0.25)
		(keepout
			(tracks not_allowed)
			(vias allowed)
			(pads allowed)
			(copperpour not_allowed)
			(footprints allowed)
		)
		(placement
			(enabled no)
			(sheetname "")
		)
		(fill yes
			(thermal_gap 0.5)
			(thermal_bridge_width 0.5)
			(island_removal_mode 0)
		)
		(polygon
			(pts
				(arc
					(start 344.807794 -348.58579)
					(mid 344.104214 -348.58579)
					(end 344.807794 -348.58579)
				)
			)
		)
	)
	(zone
		(layers "B.Cu" "In9.Cu" "In11.Cu" "In13.Cu" "In15.Cu")
		(hatch none 0.5)
		(connect_pads
			(clearance 0)
		)
		(min_thickness 0.25)
		(keepout
			(tracks not_allowed)
			(vias allowed)
			(pads allowed)
			(copperpour not_allowed)
			(footprints allowed)
		)
		(placement
			(enabled no)
			(sheetname "")
		)
		(fill yes
			(thermal_gap 0.5)
			(thermal_bridge_width 0.5)
			(island_removal_mode 0)
		)
		(polygon
			(pts
				(arc
					(start 187.409582 -351.611438)
					(mid 186.706002 -351.611438)
					(end 187.409582 -351.611438)
				)
			)
		)
	)
	(zone
		(layers "B.Cu" "In9.Cu" "In11.Cu" "In13.Cu" "In15.Cu")
		(hatch none 0.5)
		(connect_pads
			(clearance 0)
		)
		(min_thickness 0.25)
		(keepout
			(tracks not_allowed)
			(vias allowed)
			(pads allowed)
			(copperpour not_allowed)
			(footprints allowed)
		)
		(placement
			(enabled no)
			(sheetname "")
		)
		(fill yes
			(thermal_gap 0.5)
			(thermal_bridge_width 0.5)
			(island_removal_mode 0)
		)
		(polygon
			(pts
				(arc
					(start 77.268832 -342.439498)
					(mid 76.565252 -342.439498)
					(end 77.268832 -342.439498)
				)
			)
		)
	)
	(zone
		(layers "B.Cu" "In9.Cu" "In11.Cu" "In13.Cu" "In15.Cu")
		(hatch none 0.5)
		(connect_pads
			(clearance 0)
		)
		(min_thickness 0.25)
		(keepout
			(tracks not_allowed)
			(vias allowed)
			(pads allowed)
			(copperpour not_allowed)
			(footprints allowed)
		)
		(placement
			(enabled no)
			(sheetname "")
		)
		(fill yes
			(thermal_gap 0.5)
			(thermal_bridge_width 0.5)
			(island_removal_mode 0)
		)
		(polygon
			(pts
				(arc
					(start 160.289748 -371.790214)
					(mid 159.530288 -371.790214)
					(end 160.289748 -371.790214)
				)
			)
		)
	)
	(zone
		(layers "B.Cu" "In9.Cu" "In11.Cu" "In13.Cu" "In15.Cu")
		(hatch none 0.5)
		(connect_pads
			(clearance 0)
		)
		(min_thickness 0.25)
		(keepout
			(tracks not_allowed)
			(vias allowed)
			(pads allowed)
			(copperpour not_allowed)
			(footprints allowed)
		)
		(placement
			(enabled no)
			(sheetname "")
		)
		(fill yes
			(thermal_gap 0.5)
			(thermal_bridge_width 0.5)
			(island_removal_mode 0)
		)
		(polygon
			(pts
				(arc
					(start 283.626306 -274.999958)
					(mid 282.973526 -274.999958)
					(end 283.626306 -274.999958)
				)
			)
		)
	)
	(zone
		(layers "B.Cu" "In9.Cu" "In11.Cu" "In13.Cu" "In15.Cu")
		(hatch none 0.5)
		(connect_pads
			(clearance 0)
		)
		(min_thickness 0.25)
		(keepout
			(tracks not_allowed)
			(vias allowed)
			(pads allowed)
			(copperpour not_allowed)
			(footprints allowed)
		)
		(placement
			(enabled no)
			(sheetname "")
		)
		(fill yes
			(thermal_gap 0.5)
			(thermal_bridge_width 0.5)
			(island_removal_mode 0)
		)
		(polygon
			(pts
				(arc
					(start 68.805552 -351.611438)
					(mid 68.101972 -351.611438)
					(end 68.805552 -351.611438)
				)
			)
		)
	)
	(zone
		(layers "B.Cu" "In9.Cu" "In11.Cu" "In13.Cu" "In15.Cu")
		(hatch none 0.5)
		(connect_pads
			(clearance 0)
		)
		(min_thickness 0.25)
		(keepout
			(tracks not_allowed)
			(vias allowed)
			(pads allowed)
			(copperpour not_allowed)
			(footprints allowed)
		)
		(placement
			(enabled no)
			(sheetname "")
		)
		(fill yes
			(thermal_gap 0.5)
			(thermal_bridge_width 0.5)
			(island_removal_mode 0)
		)
		(polygon
			(pts
				(arc
					(start 294.469566 -375.490232)
					(mid 293.710106 -375.490232)
					(end 294.469566 -375.490232)
				)
			)
		)
	)
	(zone
		(layers "B.Cu" "In9.Cu" "In11.Cu" "In13.Cu" "In15.Cu")
		(hatch none 0.5)
		(connect_pads
			(clearance 0)
		)
		(min_thickness 0.25)
		(keepout
			(tracks not_allowed)
			(vias allowed)
			(pads allowed)
			(copperpour not_allowed)
			(footprints allowed)
		)
		(placement
			(enabled no)
			(sheetname "")
		)
		(fill yes
			(thermal_gap 0.5)
			(thermal_bridge_width 0.5)
			(island_removal_mode 0)
		)
		(polygon
			(pts
				(arc
					(start 85.562186 -30.922468)
					(mid 84.858606 -30.922468)
					(end 85.562186 -30.922468)
				)
			)
		)
	)
	(zone
		(layers "B.Cu" "In9.Cu" "In11.Cu" "In13.Cu" "In15.Cu")
		(hatch none 0.5)
		(connect_pads
			(clearance 0)
		)
		(min_thickness 0.25)
		(keepout
			(tracks not_allowed)
			(vias allowed)
			(pads allowed)
			(copperpour not_allowed)
			(footprints allowed)
		)
		(placement
			(enabled no)
			(sheetname "")
		)
		(fill yes
			(thermal_gap 0.5)
			(thermal_bridge_width 0.5)
			(island_removal_mode 0)
		)
		(polygon
			(pts
				(arc
					(start 435.716426 -28.25877)
					(mid 435.012846 -28.25877)
					(end 435.716426 -28.25877)
				)
			)
		)
	)
	(zone
		(layers "B.Cu" "In9.Cu" "In11.Cu" "In13.Cu" "In15.Cu")
		(hatch none 0.5)
		(connect_pads
			(clearance 0)
		)
		(min_thickness 0.25)
		(keepout
			(tracks not_allowed)
			(vias allowed)
			(pads allowed)
			(copperpour not_allowed)
			(footprints allowed)
		)
		(placement
			(enabled no)
			(sheetname "")
		)
		(fill yes
			(thermal_gap 0.5)
			(thermal_bridge_width 0.5)
			(island_removal_mode 0)
		)
		(polygon
			(pts
				(arc
					(start 287.426146 -274.999958)
					(mid 286.773366 -274.999958)
					(end 287.426146 -274.999958)
				)
			)
		)
	)
	(zone
		(layers "B.Cu" "In9.Cu" "In11.Cu" "In13.Cu" "In15.Cu")
		(hatch none 0.5)
		(connect_pads
			(clearance 0)
		)
		(min_thickness 0.25)
		(keepout
			(tracks not_allowed)
			(vias allowed)
			(pads allowed)
			(copperpour not_allowed)
			(footprints allowed)
		)
		(placement
			(enabled no)
			(sheetname "")
		)
		(fill yes
			(thermal_gap 0.5)
			(thermal_bridge_width 0.5)
			(island_removal_mode 0)
		)
		(polygon
			(pts
				(arc
					(start 74.489564 -405.390096)
					(mid 73.730104 -405.390096)
					(end 74.489564 -405.390096)
				)
			)
		)
	)
	(zone
		(layers "B.Cu" "In9.Cu" "In11.Cu" "In13.Cu" "In15.Cu")
		(hatch none 0.5)
		(connect_pads
			(clearance 0)
		)
		(min_thickness 0.25)
		(keepout
			(tracks not_allowed)
			(vias allowed)
			(pads allowed)
			(copperpour not_allowed)
			(footprints allowed)
		)
		(placement
			(enabled no)
			(sheetname "")
		)
		(fill yes
			(thermal_gap 0.5)
			(thermal_bridge_width 0.5)
			(island_removal_mode 0)
		)
		(polygon
			(pts
				(arc
					(start 160.289748 -396.49019)
					(mid 159.530288 -396.49019)
					(end 160.289748 -396.49019)
				)
			)
		)
	)
	(zone
		(layers "B.Cu" "In9.Cu" "In11.Cu" "In13.Cu" "In15.Cu")
		(hatch none 0.5)
		(connect_pads
			(clearance 0)
		)
		(min_thickness 0.25)
		(keepout
			(tracks not_allowed)
			(vias allowed)
			(pads allowed)
			(copperpour not_allowed)
			(footprints allowed)
		)
		(placement
			(enabled no)
			(sheetname "")
		)
		(fill yes
			(thermal_gap 0.5)
			(thermal_bridge_width 0.5)
			(island_removal_mode 0)
		)
		(polygon
			(pts
				(arc
					(start 38.126162 -314.899802)
					(mid 37.473382 -314.899802)
					(end 38.126162 -314.899802)
				)
			)
		)
	)
	(zone
		(layers "B.Cu" "In9.Cu" "In11.Cu" "In13.Cu" "In15.Cu")
		(hatch none 0.5)
		(connect_pads
			(clearance 0)
		)
		(min_thickness 0.25)
		(keepout
			(tracks not_allowed)
			(vias allowed)
			(pads allowed)
			(copperpour not_allowed)
			(footprints allowed)
		)
		(placement
			(enabled no)
			(sheetname "")
		)
		(fill yes
			(thermal_gap 0.5)
			(thermal_bridge_width 0.5)
			(island_removal_mode 0)
		)
		(polygon
			(pts
				(arc
					(start 408.276298 -313.949842)
					(mid 407.623518 -313.949842)
					(end 408.276298 -313.949842)
				)
			)
		)
	)
	(zone
		(layers "B.Cu" "In9.Cu" "In11.Cu" "In13.Cu" "In15.Cu")
		(hatch none 0.5)
		(connect_pads
			(clearance 0)
		)
		(min_thickness 0.25)
		(keepout
			(tracks not_allowed)
			(vias allowed)
			(pads allowed)
			(copperpour not_allowed)
			(footprints allowed)
		)
		(placement
			(enabled no)
			(sheetname "")
		)
		(fill yes
			(thermal_gap 0.5)
			(thermal_bridge_width 0.5)
			(island_removal_mode 0)
		)
		(polygon
			(pts
				(arc
					(start 422.069514 -372.890034)
					(mid 421.310054 -372.890034)
					(end 422.069514 -372.890034)
				)
			)
		)
	)
	(zone
		(layers "B.Cu" "In9.Cu" "In11.Cu" "In13.Cu" "In15.Cu")
		(hatch none 0.5)
		(connect_pads
			(clearance 0)
		)
		(min_thickness 0.25)
		(keepout
			(tracks not_allowed)
			(vias allowed)
			(pads allowed)
			(copperpour not_allowed)
			(footprints allowed)
		)
		(placement
			(enabled no)
			(sheetname "")
		)
		(fill yes
			(thermal_gap 0.5)
			(thermal_bridge_width 0.5)
			(island_removal_mode 0)
		)
		(polygon
			(pts
				(arc
					(start 375.51233 -357.75773)
					(mid 374.80875 -357.75773)
					(end 375.51233 -357.75773)
				)
			)
		)
	)
	(zone
		(layers "B.Cu" "In9.Cu" "In11.Cu" "In13.Cu" "In15.Cu")
		(hatch none 0.5)
		(connect_pads
			(clearance 0)
		)
		(min_thickness 0.25)
		(keepout
			(tracks not_allowed)
			(vias allowed)
			(pads allowed)
			(copperpour not_allowed)
			(footprints allowed)
		)
		(placement
			(enabled no)
			(sheetname "")
		)
		(fill yes
			(thermal_gap 0.5)
			(thermal_bridge_width 0.5)
			(island_removal_mode 0)
		)
		(polygon
			(pts
				(arc
					(start 274.126198 -311.099962)
					(mid 273.473418 -311.099962)
					(end 274.126198 -311.099962)
				)
			)
		)
	)
	(zone
		(layers "B.Cu" "In9.Cu" "In11.Cu" "In13.Cu" "In15.Cu")
		(hatch none 0.5)
		(connect_pads
			(clearance 0)
		)
		(min_thickness 0.25)
		(keepout
			(tracks not_allowed)
			(vias allowed)
			(pads allowed)
			(copperpour not_allowed)
			(footprints allowed)
		)
		(placement
			(enabled no)
			(sheetname "")
		)
		(fill yes
			(thermal_gap 0.5)
			(thermal_bridge_width 0.5)
			(island_removal_mode 0)
		)
		(polygon
			(pts
				(arc
					(start 174.176436 -274.049744)
					(mid 173.523656 -274.049744)
					(end 174.176436 -274.049744)
				)
			)
		)
	)
	(zone
		(layers "B.Cu" "In9.Cu" "In11.Cu" "In13.Cu" "In15.Cu")
		(hatch none 0.5)
		(connect_pads
			(clearance 0)
		)
		(min_thickness 0.25)
		(keepout
			(tracks not_allowed)
			(vias allowed)
			(pads allowed)
			(copperpour not_allowed)
			(footprints allowed)
		)
		(placement
			(enabled no)
			(sheetname "")
		)
		(fill yes
			(thermal_gap 0.5)
			(thermal_bridge_width 0.5)
			(island_removal_mode 0)
		)
		(polygon
			(pts
				(arc
					(start 185.164222 -354.708206)
					(mid 184.460642 -354.708206)
					(end 185.164222 -354.708206)
				)
			)
		)
	)
	(zone
		(layers "B.Cu" "In9.Cu" "In11.Cu" "In13.Cu" "In15.Cu")
		(hatch none 0.5)
		(connect_pads
			(clearance 0)
		)
		(min_thickness 0.25)
		(keepout
			(tracks not_allowed)
			(vias allowed)
			(pads allowed)
			(copperpour not_allowed)
			(footprints allowed)
		)
		(placement
			(enabled no)
			(sheetname "")
		)
		(fill yes
			(thermal_gap 0.5)
			(thermal_bridge_width 0.5)
			(island_removal_mode 0)
		)
		(polygon
			(pts
				(arc
					(start 74.159872 -348.58579)
					(mid 73.456292 -348.58579)
					(end 74.159872 -348.58579)
				)
			)
		)
	)
	(zone
		(layers "B.Cu" "In9.Cu" "In11.Cu" "In13.Cu" "In15.Cu")
		(hatch none 0.5)
		(connect_pads
			(clearance 0)
		)
		(min_thickness 0.25)
		(keepout
			(tracks not_allowed)
			(vias allowed)
			(pads allowed)
			(copperpour not_allowed)
			(footprints allowed)
		)
		(placement
			(enabled no)
			(sheetname "")
		)
		(fill yes
			(thermal_gap 0.5)
			(thermal_bridge_width 0.5)
			(island_removal_mode 0)
		)
		(polygon
			(pts
				(arc
					(start 194.491102 -348.58579)
					(mid 193.787522 -348.58579)
					(end 194.491102 -348.58579)
				)
			)
		)
	)
	(zone
		(layers "B.Cu" "In9.Cu" "In11.Cu" "In13.Cu" "In15.Cu")
		(hatch none 0.5)
		(connect_pads
			(clearance 0)
		)
		(min_thickness 0.25)
		(keepout
			(tracks not_allowed)
			(vias allowed)
			(pads allowed)
			(copperpour not_allowed)
			(footprints allowed)
		)
		(placement
			(enabled no)
			(sheetname "")
		)
		(fill yes
			(thermal_gap 0.5)
			(thermal_bridge_width 0.5)
			(island_removal_mode 0)
		)
		(polygon
			(pts
				(arc
					(start 435.716426 -32.722312)
					(mid 435.012846 -32.722312)
					(end 435.716426 -32.722312)
				)
			)
		)
	)
	(zone
		(layers "B.Cu" "In9.Cu" "In11.Cu" "In13.Cu" "In15.Cu")
		(hatch none 0.5)
		(connect_pads
			(clearance 0)
		)
		(min_thickness 0.25)
		(keepout
			(tracks not_allowed)
			(vias allowed)
			(pads allowed)
			(copperpour not_allowed)
			(footprints allowed)
		)
		(placement
			(enabled no)
			(sheetname "")
		)
		(fill yes
			(thermal_gap 0.5)
			(thermal_bridge_width 0.5)
			(island_removal_mode 0)
		)
		(polygon
			(pts
				(arc
					(start 191.382142 -342.439498)
					(mid 190.678562 -342.439498)
					(end 191.382142 -342.439498)
				)
			)
		)
	)
	(zone
		(layers "B.Cu" "In9.Cu" "In11.Cu" "In13.Cu" "In15.Cu")
		(hatch none 0.5)
		(connect_pads
			(clearance 0)
		)
		(min_thickness 0.25)
		(keepout
			(tracks not_allowed)
			(vias allowed)
			(pads allowed)
			(copperpour not_allowed)
			(footprints allowed)
		)
		(placement
			(enabled no)
			(sheetname "")
		)
		(fill yes
			(thermal_gap 0.5)
			(thermal_bridge_width 0.5)
			(island_removal_mode 0)
		)
		(polygon
			(pts
				(arc
					(start 177.976276 -313.949842)
					(mid 177.323496 -313.949842)
					(end 177.976276 -313.949842)
				)
			)
		)
	)
	(zone
		(layers "B.Cu" "In9.Cu" "In11.Cu" "In13.Cu" "In15.Cu")
		(hatch none 0.5)
		(connect_pads
			(clearance 0)
		)
		(min_thickness 0.25)
		(keepout
			(tracks not_allowed)
			(vias allowed)
			(pads allowed)
			(copperpour not_allowed)
			(footprints allowed)
		)
		(placement
			(enabled no)
			(sheetname "")
		)
		(fill yes
			(thermal_gap 0.5)
			(thermal_bridge_width 0.5)
			(island_removal_mode 0)
		)
		(polygon
			(pts
				(arc
					(start 191.276478 -304.449734)
					(mid 190.623698 -304.449734)
					(end 191.276478 -304.449734)
				)
			)
		)
	)
	(zone
		(layers "B.Cu" "In9.Cu" "In11.Cu" "In13.Cu" "In15.Cu")
		(hatch none 0.5)
		(connect_pads
			(clearance 0)
		)
		(min_thickness 0.25)
		(keepout
			(tracks not_allowed)
			(vias allowed)
			(pads allowed)
			(copperpour not_allowed)
			(footprints allowed)
		)
		(placement
			(enabled no)
			(sheetname "")
		)
		(fill yes
			(thermal_gap 0.5)
			(thermal_bridge_width 0.5)
			(island_removal_mode 0)
		)
		(polygon
			(pts
				(arc
					(start 25.902158 -348.58579)
					(mid 25.198578 -348.58579)
					(end 25.902158 -348.58579)
				)
			)
		)
	)
	(zone
		(layers "B.Cu" "In9.Cu" "In11.Cu" "In13.Cu" "In15.Cu")
		(hatch none 0.5)
		(connect_pads
			(clearance 0)
		)
		(min_thickness 0.25)
		(keepout
			(tracks not_allowed)
			(vias allowed)
			(pads allowed)
			(copperpour not_allowed)
			(footprints allowed)
		)
		(placement
			(enabled no)
			(sheetname "")
		)
		(fill yes
			(thermal_gap 0.5)
			(thermal_bridge_width 0.5)
			(island_removal_mode 0)
		)
		(polygon
			(pts
				(arc
					(start 169.426382 -274.999958)
					(mid 168.773602 -274.999958)
					(end 169.426382 -274.999958)
				)
			)
		)
	)
	(zone
		(layers "B.Cu" "In9.Cu" "In11.Cu" "In13.Cu" "In15.Cu")
		(hatch none 0.5)
		(connect_pads
			(clearance 0)
		)
		(min_thickness 0.25)
		(keepout
			(tracks not_allowed)
			(vias allowed)
			(pads allowed)
			(copperpour not_allowed)
			(footprints allowed)
		)
		(placement
			(enabled no)
			(sheetname "")
		)
		(fill yes
			(thermal_gap 0.5)
			(thermal_bridge_width 0.5)
			(island_removal_mode 0)
		)
		(polygon
			(pts
				(arc
					(start 371.53977 -348.58579)
					(mid 370.83619 -348.58579)
					(end 371.53977 -348.58579)
				)
			)
		)
	)
	(zone
		(layers "B.Cu" "In9.Cu" "In11.Cu" "In13.Cu" "In15.Cu")
		(hatch none 0.5)
		(connect_pads
			(clearance 0)
		)
		(min_thickness 0.25)
		(keepout
			(tracks not_allowed)
			(vias allowed)
			(pads allowed)
			(copperpour not_allowed)
			(footprints allowed)
		)
		(placement
			(enabled no)
			(sheetname "")
		)
		(fill yes
			(thermal_gap 0.5)
			(thermal_bridge_width 0.5)
			(island_removal_mode 0)
		)
		(polygon
			(pts
				(arc
					(start 316.827154 -354.732082)
					(mid 316.123574 -354.732082)
					(end 316.827154 -354.732082)
				)
			)
		)
	)
	(zone
		(layers "B.Cu" "In9.Cu" "In11.Cu" "In13.Cu" "In15.Cu")
		(hatch none 0.5)
		(connect_pads
			(clearance 0)
		)
		(min_thickness 0.25)
		(keepout
			(tracks not_allowed)
			(vias allowed)
			(pads allowed)
			(copperpour not_allowed)
			(footprints allowed)
		)
		(placement
			(enabled no)
			(sheetname "")
		)
		(fill yes
			(thermal_gap 0.5)
			(thermal_bridge_width 0.5)
			(island_removal_mode 0)
		)
		(polygon
			(pts
				(arc
					(start 281.548332 -348.58579)
					(mid 280.844752 -348.58579)
					(end 281.548332 -348.58579)
				)
			)
		)
	)
	(zone
		(layers "B.Cu" "In9.Cu" "In11.Cu" "In13.Cu" "In15.Cu")
		(hatch none 0.5)
		(connect_pads
			(clearance 0)
		)
		(min_thickness 0.25)
		(keepout
			(tracks not_allowed)
			(vias allowed)
			(pads allowed)
			(copperpour not_allowed)
			(footprints allowed)
		)
		(placement
			(enabled no)
			(sheetname "")
		)
		(fill yes
			(thermal_gap 0.5)
			(thermal_bridge_width 0.5)
			(island_removal_mode 0)
		)
		(polygon
			(pts
				(arc
					(start 118.431818 -348.58579)
					(mid 117.728238 -348.58579)
					(end 118.431818 -348.58579)
				)
			)
		)
	)
	(zone
		(layers "B.Cu" "In9.Cu" "In11.Cu" "In13.Cu" "In15.Cu")
		(hatch none 0.5)
		(connect_pads
			(clearance 0)
		)
		(min_thickness 0.25)
		(keepout
			(tracks not_allowed)
			(vias allowed)
			(pads allowed)
			(copperpour not_allowed)
			(footprints allowed)
		)
		(placement
			(enabled no)
			(sheetname "")
		)
		(fill yes
			(thermal_gap 0.5)
			(thermal_bridge_width 0.5)
			(island_removal_mode 0)
		)
		(polygon
			(pts
				(arc
					(start 115.322858 -354.732082)
					(mid 114.619278 -354.732082)
					(end 115.322858 -354.732082)
				)
			)
		)
	)
	(zone
		(layers "B.Cu" "In9.Cu" "In11.Cu" "In13.Cu" "In15.Cu")
		(hatch none 0.5)
		(connect_pads
			(clearance 0)
		)
		(min_thickness 0.25)
		(keepout
			(tracks not_allowed)
			(vias allowed)
			(pads allowed)
			(copperpour not_allowed)
			(footprints allowed)
		)
		(placement
			(enabled no)
			(sheetname "")
		)
		(fill yes
			(thermal_gap 0.5)
			(thermal_bridge_width 0.5)
			(island_removal_mode 0)
		)
		(polygon
			(pts
				(arc
					(start 48.528478 -354.732082)
					(mid 47.824898 -354.732082)
					(end 48.528478 -354.732082)
				)
			)
		)
	)
	(zone
		(layers "B.Cu" "In9.Cu" "In11.Cu" "In13.Cu" "In15.Cu")
		(hatch none 0.5)
		(connect_pads
			(clearance 0)
		)
		(min_thickness 0.25)
		(keepout
			(tracks not_allowed)
			(vias allowed)
			(pads allowed)
			(copperpour not_allowed)
			(footprints allowed)
		)
		(placement
			(enabled no)
			(sheetname "")
		)
		(fill yes
			(thermal_gap 0.5)
			(thermal_bridge_width 0.5)
			(island_removal_mode 0)
		)
		(polygon
			(pts
				(arc
					(start 329.964288 7.685024)
					(mid 329.260708 7.685024)
					(end 329.964288 7.685024)
				)
			)
		)
	)
	(zone
		(layers "B.Cu" "In9.Cu" "In11.Cu" "In13.Cu" "In15.Cu")
		(hatch none 0.5)
		(connect_pads
			(clearance 0)
		)
		(min_thickness 0.25)
		(keepout
			(tracks not_allowed)
			(vias allowed)
			(pads allowed)
			(copperpour not_allowed)
			(footprints allowed)
		)
		(placement
			(enabled no)
			(sheetname "")
		)
		(fill yes
			(thermal_gap 0.5)
			(thermal_bridge_width 0.5)
			(island_removal_mode 0)
		)
		(polygon
			(pts
				(arc
					(start 19.684238 -348.58579)
					(mid 18.980658 -348.58579)
					(end 19.684238 -348.58579)
				)
			)
		)
	)
	(zone
		(layers "B.Cu" "In9.Cu" "In11.Cu" "In13.Cu" "In15.Cu")
		(hatch none 0.5)
		(connect_pads
			(clearance 0)
		)
		(min_thickness 0.25)
		(keepout
			(tracks not_allowed)
			(vias allowed)
			(pads allowed)
			(copperpour not_allowed)
			(footprints allowed)
		)
		(placement
			(enabled no)
			(sheetname "")
		)
		(fill yes
			(thermal_gap 0.5)
			(thermal_bridge_width 0.5)
			(island_removal_mode 0)
		)
		(polygon
			(pts
				(arc
					(start 149.662388 -30.922468)
					(mid 148.958808 -30.922468)
					(end 149.662388 -30.922468)
				)
			)
		)
	)
	(zone
		(layers "B.Cu" "In9.Cu" "In11.Cu" "In13.Cu" "In15.Cu")
		(hatch none 0.5)
		(connect_pads
			(clearance 0)
		)
		(min_thickness 0.25)
		(keepout
			(tracks not_allowed)
			(vias allowed)
			(pads allowed)
			(copperpour not_allowed)
			(footprints allowed)
		)
		(placement
			(enabled no)
			(sheetname "")
		)
		(fill yes
			(thermal_gap 0.5)
			(thermal_bridge_width 0.5)
			(island_removal_mode 0)
		)
		(polygon
			(pts
				(arc
					(start 437.627522 -345.465146)
					(mid 436.923942 -345.465146)
					(end 437.627522 -345.465146)
				)
			)
		)
	)
	(zone
		(layers "B.Cu" "In9.Cu" "In11.Cu" "In13.Cu" "In15.Cu")
		(hatch none 0.5)
		(connect_pads
			(clearance 0)
		)
		(min_thickness 0.25)
		(keepout
			(tracks not_allowed)
			(vias allowed)
			(pads allowed)
			(copperpour not_allowed)
			(footprints allowed)
		)
		(placement
			(enabled no)
			(sheetname "")
		)
		(fill yes
			(thermal_gap 0.5)
			(thermal_bridge_width 0.5)
			(island_removal_mode 0)
		)
		(polygon
			(pts
				(arc
					(start 386.869686 -383.290064)
					(mid 386.110226 -383.290064)
					(end 386.869686 -383.290064)
				)
			)
		)
	)
	(zone
		(layers "B.Cu" "In9.Cu" "In11.Cu" "In13.Cu" "In15.Cu")
		(hatch none 0.5)
		(connect_pads
			(clearance 0)
		)
		(min_thickness 0.25)
		(keepout
			(tracks not_allowed)
			(vias allowed)
			(pads allowed)
			(copperpour not_allowed)
			(footprints allowed)
		)
		(placement
			(enabled no)
			(sheetname "")
		)
		(fill yes
			(thermal_gap 0.5)
			(thermal_bridge_width 0.5)
			(island_removal_mode 0)
		)
		(polygon
			(pts
				(arc
					(start 196.026278 -312.049922)
					(mid 195.373498 -312.049922)
					(end 196.026278 -312.049922)
				)
			)
		)
	)
	(zone
		(layers "B.Cu" "In9.Cu" "In11.Cu" "In13.Cu" "In15.Cu")
		(hatch none 0.5)
		(connect_pads
			(clearance 0)
		)
		(min_thickness 0.25)
		(keepout
			(tracks not_allowed)
			(vias allowed)
			(pads allowed)
			(copperpour not_allowed)
			(footprints allowed)
		)
		(placement
			(enabled no)
			(sheetname "")
		)
		(fill yes
			(thermal_gap 0.5)
			(thermal_bridge_width 0.5)
			(island_removal_mode 0)
		)
		(polygon
			(pts
				(arc
					(start 316.827154 -345.465146)
					(mid 316.123574 -345.465146)
					(end 316.827154 -345.465146)
				)
			)
		)
	)
	(zone
		(layers "B.Cu" "In9.Cu" "In11.Cu" "In13.Cu" "In15.Cu")
		(hatch none 0.5)
		(connect_pads
			(clearance 0)
		)
		(min_thickness 0.25)
		(keepout
			(tracks not_allowed)
			(vias allowed)
			(pads allowed)
			(copperpour not_allowed)
			(footprints allowed)
		)
		(placement
			(enabled no)
			(sheetname "")
		)
		(fill yes
			(thermal_gap 0.5)
			(thermal_bridge_width 0.5)
			(island_removal_mode 0)
		)
		(polygon
			(pts
				(arc
					(start 181.77637 -313.949842)
					(mid 181.12359 -313.949842)
					(end 181.77637 -313.949842)
				)
			)
		)
	)
	(zone
		(layers "B.Cu" "In9.Cu" "In11.Cu" "In13.Cu" "In15.Cu")
		(hatch none 0.5)
		(connect_pads
			(clearance 0)
		)
		(min_thickness 0.25)
		(keepout
			(tracks not_allowed)
			(vias allowed)
			(pads allowed)
			(copperpour not_allowed)
			(footprints allowed)
		)
		(placement
			(enabled no)
			(sheetname "")
		)
		(fill yes
			(thermal_gap 0.5)
			(thermal_bridge_width 0.5)
			(island_removal_mode 0)
		)
		(polygon
			(pts
				(arc
					(start 437.627522 -357.75773)
					(mid 436.923942 -357.75773)
					(end 437.627522 -357.75773)
				)
			)
		)
	)
	(zone
		(layers "B.Cu" "In9.Cu" "In11.Cu" "In13.Cu" "In15.Cu")
		(hatch none 0.5)
		(connect_pads
			(clearance 0)
		)
		(min_thickness 0.25)
		(keepout
			(tracks not_allowed)
			(vias allowed)
			(pads allowed)
			(copperpour not_allowed)
			(footprints allowed)
		)
		(placement
			(enabled no)
			(sheetname "")
		)
		(fill yes
			(thermal_gap 0.5)
			(thermal_bridge_width 0.5)
			(island_removal_mode 0)
		)
		(polygon
			(pts
				(arc
					(start 290.875212 -342.439498)
					(mid 290.171632 -342.439498)
					(end 290.875212 -342.439498)
				)
			)
		)
	)
	(zone
		(layers "B.Cu" "In9.Cu" "In11.Cu" "In13.Cu" "In15.Cu")
		(hatch none 0.5)
		(connect_pads
			(clearance 0)
		)
		(min_thickness 0.25)
		(keepout
			(tracks not_allowed)
			(vias allowed)
			(pads allowed)
			(copperpour not_allowed)
			(footprints allowed)
		)
		(placement
			(enabled no)
			(sheetname "")
		)
		(fill yes
			(thermal_gap 0.5)
			(thermal_bridge_width 0.5)
			(island_removal_mode 0)
		)
		(polygon
			(pts
				(arc
					(start 167.526462 -274.999958)
					(mid 166.873682 -274.999958)
					(end 167.526462 -274.999958)
				)
			)
		)
	)
	(zone
		(layers "B.Cu" "In9.Cu" "In11.Cu" "In13.Cu" "In15.Cu")
		(hatch none 0.5)
		(connect_pads
			(clearance 0)
		)
		(min_thickness 0.25)
		(keepout
			(tracks not_allowed)
			(vias allowed)
			(pads allowed)
			(copperpour not_allowed)
			(footprints allowed)
		)
		(placement
			(enabled no)
			(sheetname "")
		)
		(fill yes
			(thermal_gap 0.5)
			(thermal_bridge_width 0.5)
			(island_removal_mode 0)
		)
		(polygon
			(pts
				(arc
					(start 44.776136 -304.449734)
					(mid 44.123356 -304.449734)
					(end 44.776136 -304.449734)
				)
			)
		)
	)
	(zone
		(layers "B.Cu" "In9.Cu" "In11.Cu" "In13.Cu" "In15.Cu")
		(hatch none 0.5)
		(connect_pads
			(clearance 0)
		)
		(min_thickness 0.25)
		(keepout
			(tracks not_allowed)
			(vias allowed)
			(pads allowed)
			(copperpour not_allowed)
			(footprints allowed)
		)
		(placement
			(enabled no)
			(sheetname "")
		)
		(fill yes
			(thermal_gap 0.5)
			(thermal_bridge_width 0.5)
			(island_removal_mode 0)
		)
		(polygon
			(pts
				(arc
					(start 378.069602 -405.390096)
					(mid 377.310142 -405.390096)
					(end 378.069602 -405.390096)
				)
			)
		)
	)
	(zone
		(layers "B.Cu" "In9.Cu" "In11.Cu" "In13.Cu" "In15.Cu")
		(hatch none 0.5)
		(connect_pads
			(clearance 0)
		)
		(min_thickness 0.25)
		(keepout
			(tracks not_allowed)
			(vias allowed)
			(pads allowed)
			(copperpour not_allowed)
			(footprints allowed)
		)
		(placement
			(enabled no)
			(sheetname "")
		)
		(fill yes
			(thermal_gap 0.5)
			(thermal_bridge_width 0.5)
			(island_removal_mode 0)
		)
		(polygon
			(pts
				(arc
					(start 39.289736 -402.790152)
					(mid 38.530276 -402.790152)
					(end 39.289736 -402.790152)
				)
			)
		)
	)
	(zone
		(layers "B.Cu" "In9.Cu" "In11.Cu" "In13.Cu" "In15.Cu")
		(hatch none 0.5)
		(connect_pads
			(clearance 0)
		)
		(min_thickness 0.25)
		(keepout
			(tracks not_allowed)
			(vias allowed)
			(pads allowed)
			(copperpour not_allowed)
			(footprints allowed)
		)
		(placement
			(enabled no)
			(sheetname "")
		)
		(fill yes
			(thermal_gap 0.5)
			(thermal_bridge_width 0.5)
			(island_removal_mode 0)
		)
		(polygon
			(pts
				(arc
					(start 81.241392 -351.611438)
					(mid 80.537812 -351.611438)
					(end 81.241392 -351.611438)
				)
			)
		)
	)
	(zone
		(layers "B.Cu" "In9.Cu" "In11.Cu" "In13.Cu" "In15.Cu")
		(hatch none 0.5)
		(connect_pads
			(clearance 0)
		)
		(min_thickness 0.25)
		(keepout
			(tracks not_allowed)
			(vias allowed)
			(pads allowed)
			(copperpour not_allowed)
			(footprints allowed)
		)
		(placement
			(enabled no)
			(sheetname "")
		)
		(fill yes
			(thermal_gap 0.5)
			(thermal_bridge_width 0.5)
			(island_removal_mode 0)
		)
		(polygon
			(pts
				(arc
					(start 134.840218 -342.439498)
					(mid 134.136638 -342.439498)
					(end 134.840218 -342.439498)
				)
			)
		)
	)
	(zone
		(layers "B.Cu" "In9.Cu" "In11.Cu" "In13.Cu" "In15.Cu")
		(hatch none 0.5)
		(connect_pads
			(clearance 0)
		)
		(min_thickness 0.25)
		(keepout
			(tracks not_allowed)
			(vias allowed)
			(pads allowed)
			(copperpour not_allowed)
			(footprints allowed)
		)
		(placement
			(enabled no)
			(sheetname "")
		)
		(fill yes
			(thermal_gap 0.5)
			(thermal_bridge_width 0.5)
			(island_removal_mode 0)
		)
		(polygon
			(pts
				(arc
					(start 292.269672 -375.69013)
					(mid 291.510212 -375.69013)
					(end 292.269672 -375.69013)
				)
			)
		)
	)
	(zone
		(layers "B.Cu" "In9.Cu" "In11.Cu" "In13.Cu" "In15.Cu")
		(hatch none 0.5)
		(connect_pads
			(clearance 0)
		)
		(min_thickness 0.25)
		(keepout
			(tracks not_allowed)
			(vias allowed)
			(pads allowed)
			(copperpour not_allowed)
			(footprints allowed)
		)
		(placement
			(enabled no)
			(sheetname "")
		)
		(fill yes
			(thermal_gap 0.5)
			(thermal_bridge_width 0.5)
			(island_removal_mode 0)
		)
		(polygon
			(pts
				(arc
					(start 336.269838 -379.590046)
					(mid 335.510378 -379.590046)
					(end 336.269838 -379.590046)
				)
			)
		)
	)
	(zone
		(layers "B.Cu" "In9.Cu" "In11.Cu" "In13.Cu" "In15.Cu")
		(hatch none 0.5)
		(connect_pads
			(clearance 0)
		)
		(min_thickness 0.25)
		(keepout
			(tracks not_allowed)
			(vias allowed)
			(pads allowed)
			(copperpour not_allowed)
			(footprints allowed)
		)
		(placement
			(enabled no)
			(sheetname "")
		)
		(fill yes
			(thermal_gap 0.5)
			(thermal_bridge_width 0.5)
			(island_removal_mode 0)
		)
		(polygon
			(pts
				(arc
					(start 431.076354 -312.049922)
					(mid 430.423574 -312.049922)
					(end 431.076354 -312.049922)
				)
			)
		)
	)
	(zone
		(layers "B.Cu" "In9.Cu" "In11.Cu" "In13.Cu" "In15.Cu")
		(hatch none 0.5)
		(connect_pads
			(clearance 0)
		)
		(min_thickness 0.25)
		(keepout
			(tracks not_allowed)
			(vias allowed)
			(pads allowed)
			(copperpour not_allowed)
			(footprints allowed)
		)
		(placement
			(enabled no)
			(sheetname "")
		)
		(fill yes
			(thermal_gap 0.5)
			(thermal_bridge_width 0.5)
			(island_removal_mode 0)
		)
		(polygon
			(pts
				(arc
					(start 59.026298 -274.999958)
					(mid 58.373518 -274.999958)
					(end 59.026298 -274.999958)
				)
			)
		)
	)
	(zone
		(layers "B.Cu" "In9.Cu" "In11.Cu" "In13.Cu" "In15.Cu")
		(hatch none 0.5)
		(connect_pads
			(clearance 0)
		)
		(min_thickness 0.25)
		(keepout
			(tracks not_allowed)
			(vias allowed)
			(pads allowed)
			(copperpour not_allowed)
			(footprints allowed)
		)
		(placement
			(enabled no)
			(sheetname "")
		)
		(fill yes
			(thermal_gap 0.5)
			(thermal_bridge_width 0.5)
			(island_removal_mode 0)
		)
		(polygon
			(pts
				(arc
					(start 65.696592 -357.75773)
					(mid 64.993012 -357.75773)
					(end 65.696592 -357.75773)
				)
			)
		)
	)
	(zone
		(layers "B.Cu" "In9.Cu" "In11.Cu" "In13.Cu" "In15.Cu")
		(hatch none 0.5)
		(connect_pads
			(clearance 0)
		)
		(min_thickness 0.25)
		(keepout
			(tracks not_allowed)
			(vias allowed)
			(pads allowed)
			(copperpour not_allowed)
			(footprints allowed)
		)
		(placement
			(enabled no)
			(sheetname "")
		)
		(fill yes
			(thermal_gap 0.5)
			(thermal_bridge_width 0.5)
			(island_removal_mode 0)
		)
		(polygon
			(pts
				(arc
					(start 391.269728 -383.290064)
					(mid 390.510268 -383.290064)
					(end 391.269728 -383.290064)
				)
			)
		)
	)
	(zone
		(layers "B.Cu" "In9.Cu" "In11.Cu" "In13.Cu" "In15.Cu")
		(hatch none 0.5)
		(connect_pads
			(clearance 0)
		)
		(min_thickness 0.25)
		(keepout
			(tracks not_allowed)
			(vias allowed)
			(pads allowed)
			(copperpour not_allowed)
			(footprints allowed)
		)
		(placement
			(enabled no)
			(sheetname "")
		)
		(fill yes
			(thermal_gap 0.5)
			(thermal_bridge_width 0.5)
			(island_removal_mode 0)
		)
		(polygon
			(pts
				(arc
					(start 422.082722 -348.58579)
					(mid 421.379142 -348.58579)
					(end 422.082722 -348.58579)
				)
			)
		)
	)
	(zone
		(layers "B.Cu" "In9.Cu" "In11.Cu" "In13.Cu" "In15.Cu")
		(hatch none 0.5)
		(connect_pads
			(clearance 0)
		)
		(min_thickness 0.25)
		(keepout
			(tracks not_allowed)
			(vias allowed)
			(pads allowed)
			(copperpour not_allowed)
			(footprints allowed)
		)
		(placement
			(enabled no)
			(sheetname "")
		)
		(fill yes
			(thermal_gap 0.5)
			(thermal_bridge_width 0.5)
			(island_removal_mode 0)
		)
		(polygon
			(pts
				(arc
					(start 426.055282 -345.465146)
					(mid 425.351702 -345.465146)
					(end 426.055282 -345.465146)
				)
			)
		)
	)
	(zone
		(layers "B.Cu" "In9.Cu" "In11.Cu" "In13.Cu" "In15.Cu")
		(hatch none 0.5)
		(connect_pads
			(clearance 0)
		)
		(min_thickness 0.25)
		(keepout
			(tracks not_allowed)
			(vias allowed)
			(pads allowed)
			(copperpour not_allowed)
			(footprints allowed)
		)
		(placement
			(enabled no)
			(sheetname "")
		)
		(fill yes
			(thermal_gap 0.5)
			(thermal_bridge_width 0.5)
			(island_removal_mode 0)
		)
		(polygon
			(pts
				(arc
					(start 384.669792 -404.290022)
					(mid 383.910332 -404.290022)
					(end 384.669792 -404.290022)
				)
			)
		)
	)
	(zone
		(layers "B.Cu" "In9.Cu" "In11.Cu" "In13.Cu" "In15.Cu")
		(hatch none 0.5)
		(connect_pads
			(clearance 0)
		)
		(min_thickness 0.25)
		(keepout
			(tracks not_allowed)
			(vias allowed)
			(pads allowed)
			(copperpour not_allowed)
			(footprints allowed)
		)
		(placement
			(enabled no)
			(sheetname "")
		)
		(fill yes
			(thermal_gap 0.5)
			(thermal_bridge_width 0.5)
			(island_removal_mode 0)
		)
		(polygon
			(pts
				(arc
					(start 64.832992 -342.439498)
					(mid 64.129412 -342.439498)
					(end 64.832992 -342.439498)
				)
			)
		)
	)
	(zone
		(layers "B.Cu" "In9.Cu" "In11.Cu" "In13.Cu" "In15.Cu")
		(hatch none 0.5)
		(connect_pads
			(clearance 0)
		)
		(min_thickness 0.25)
		(keepout
			(tracks not_allowed)
			(vias allowed)
			(pads allowed)
			(copperpour not_allowed)
			(footprints allowed)
		)
		(placement
			(enabled no)
			(sheetname "")
		)
		(fill yes
			(thermal_gap 0.5)
			(thermal_bridge_width 0.5)
			(island_removal_mode 0)
		)
		(polygon
			(pts
				(arc
					(start 115.322858 -342.439498)
					(mid 114.619278 -342.439498)
					(end 115.322858 -342.439498)
				)
			)
		)
	)
	(zone
		(layers "B.Cu" "In9.Cu" "In11.Cu" "In13.Cu" "In15.Cu")
		(hatch none 0.5)
		(connect_pads
			(clearance 0)
		)
		(min_thickness 0.25)
		(keepout
			(tracks not_allowed)
			(vias allowed)
			(pads allowed)
			(copperpour not_allowed)
			(footprints allowed)
		)
		(placement
			(enabled no)
			(sheetname "")
		)
		(fill yes
			(thermal_gap 0.5)
			(thermal_bridge_width 0.5)
			(island_removal_mode 0)
		)
		(polygon
			(pts
				(arc
					(start 315.963554 -354.732082)
					(mid 315.259974 -354.732082)
					(end 315.963554 -354.732082)
				)
			)
		)
	)
	(zone
		(layers "B.Cu" "In9.Cu" "In11.Cu" "In13.Cu" "In15.Cu")
		(hatch none 0.5)
		(connect_pads
			(clearance 0)
		)
		(min_thickness 0.25)
		(keepout
			(tracks not_allowed)
			(vias allowed)
			(pads allowed)
			(copperpour not_allowed)
			(footprints allowed)
		)
		(placement
			(enabled no)
			(sheetname "")
		)
		(fill yes
			(thermal_gap 0.5)
			(thermal_bridge_width 0.5)
			(island_removal_mode 0)
		)
		(polygon
			(pts
				(arc
					(start 55.226204 -275.949918)
					(mid 54.573424 -275.949918)
					(end 55.226204 -275.949918)
				)
			)
		)
	)
	(zone
		(layers "B.Cu" "In9.Cu" "In11.Cu" "In13.Cu" "In15.Cu")
		(hatch none 0.5)
		(connect_pads
			(clearance 0)
		)
		(min_thickness 0.25)
		(keepout
			(tracks not_allowed)
			(vias allowed)
			(pads allowed)
			(copperpour not_allowed)
			(footprints allowed)
		)
		(placement
			(enabled no)
			(sheetname "")
		)
		(fill yes
			(thermal_gap 0.5)
			(thermal_bridge_width 0.5)
			(island_removal_mode 0)
		)
		(polygon
			(pts
				(arc
					(start 42.876216 -301.599854)
					(mid 42.223436 -301.599854)
					(end 42.876216 -301.599854)
				)
			)
		)
	)
	(zone
		(layers "B.Cu" "In9.Cu" "In11.Cu" "In13.Cu" "In15.Cu")
		(hatch none 0.5)
		(connect_pads
			(clearance 0)
		)
		(min_thickness 0.25)
		(keepout
			(tracks not_allowed)
			(vias allowed)
			(pads allowed)
			(copperpour not_allowed)
			(footprints allowed)
		)
		(placement
			(enabled no)
			(sheetname "")
		)
		(fill yes
			(thermal_gap 0.5)
			(thermal_bridge_width 0.5)
			(island_removal_mode 0)
		)
		(polygon
			(pts
				(arc
					(start 122.404378 -354.732082)
					(mid 121.700798 -354.732082)
					(end 122.404378 -354.732082)
				)
			)
		)
	)
	(zone
		(layers "B.Cu" "In9.Cu" "In11.Cu" "In13.Cu" "In15.Cu")
		(hatch none 0.5)
		(connect_pads
			(clearance 0)
		)
		(min_thickness 0.25)
		(keepout
			(tracks not_allowed)
			(vias allowed)
			(pads allowed)
			(copperpour not_allowed)
			(footprints allowed)
		)
		(placement
			(enabled no)
			(sheetname "")
		)
		(fill yes
			(thermal_gap 0.5)
			(thermal_bridge_width 0.5)
			(island_removal_mode 0)
		)
		(polygon
			(pts
				(arc
					(start 319.616328 -31.858712)
					(mid 318.912748 -31.858712)
					(end 319.616328 -31.858712)
				)
			)
		)
	)
	(zone
		(layers "B.Cu" "In9.Cu" "In11.Cu" "In13.Cu" "In15.Cu")
		(hatch none 0.5)
		(connect_pads
			(clearance 0)
		)
		(min_thickness 0.25)
		(keepout
			(tracks not_allowed)
			(vias allowed)
			(pads allowed)
			(copperpour not_allowed)
			(footprints allowed)
		)
		(placement
			(enabled no)
			(sheetname "")
		)
		(fill yes
			(thermal_gap 0.5)
			(thermal_bridge_width 0.5)
			(island_removal_mode 0)
		)
		(polygon
			(pts
				(arc
					(start 78.889606 -379.390148)
					(mid 78.130146 -379.390148)
					(end 78.889606 -379.390148)
				)
			)
		)
	)
	(zone
		(layers "B.Cu" "In9.Cu" "In11.Cu" "In13.Cu" "In15.Cu")
		(hatch none 0.5)
		(connect_pads
			(clearance 0)
		)
		(min_thickness 0.25)
		(keepout
			(tracks not_allowed)
			(vias allowed)
			(pads allowed)
			(copperpour not_allowed)
			(footprints allowed)
		)
		(placement
			(enabled no)
			(sheetname "")
		)
		(fill yes
			(thermal_gap 0.5)
			(thermal_bridge_width 0.5)
			(island_removal_mode 0)
		)
		(polygon
			(pts
				(arc
					(start 48.528478 -357.75773)
					(mid 47.824898 -357.75773)
					(end 48.528478 -357.75773)
				)
			)
		)
	)
	(zone
		(layers "B.Cu" "In9.Cu" "In11.Cu" "In13.Cu" "In15.Cu")
		(hatch none 0.5)
		(connect_pads
			(clearance 0)
		)
		(min_thickness 0.25)
		(keepout
			(tracks not_allowed)
			(vias allowed)
			(pads allowed)
			(copperpour not_allowed)
			(footprints allowed)
		)
		(placement
			(enabled no)
			(sheetname "")
		)
		(fill yes
			(thermal_gap 0.5)
			(thermal_bridge_width 0.5)
			(island_removal_mode 0)
		)
		(polygon
			(pts
				(arc
					(start 29.874718 -354.732082)
					(mid 29.171138 -354.732082)
					(end 29.874718 -354.732082)
				)
			)
		)
	)
	(zone
		(layers "B.Cu" "In9.Cu" "In11.Cu" "In13.Cu" "In15.Cu")
		(hatch none 0.5)
		(connect_pads
			(clearance 0)
		)
		(min_thickness 0.25)
		(keepout
			(tracks not_allowed)
			(vias allowed)
			(pads allowed)
			(copperpour not_allowed)
			(footprints allowed)
		)
		(placement
			(enabled no)
			(sheetname "")
		)
		(fill yes
			(thermal_gap 0.5)
			(thermal_bridge_width 0.5)
			(island_removal_mode 0)
		)
		(polygon
			(pts
				(arc
					(start 59.976258 -312.999882)
					(mid 59.323478 -312.999882)
					(end 59.976258 -312.999882)
				)
			)
		)
	)
	(zone
		(layers "B.Cu" "In9.Cu" "In11.Cu" "In13.Cu" "In15.Cu")
		(hatch none 0.5)
		(connect_pads
			(clearance 0)
		)
		(min_thickness 0.25)
		(keepout
			(tracks not_allowed)
			(vias allowed)
			(pads allowed)
			(copperpour not_allowed)
			(footprints allowed)
		)
		(placement
			(enabled no)
			(sheetname "")
		)
		(fill yes
			(thermal_gap 0.5)
			(thermal_bridge_width 0.5)
			(island_removal_mode 0)
		)
		(polygon
			(pts
				(arc
					(start 432.273202 -345.465146)
					(mid 431.569622 -345.465146)
					(end 432.273202 -345.465146)
				)
			)
		)
	)
	(zone
		(layers "B.Cu" "In9.Cu" "In11.Cu" "In13.Cu" "In15.Cu")
		(hatch none 0.5)
		(connect_pads
			(clearance 0)
		)
		(min_thickness 0.25)
		(keepout
			(tracks not_allowed)
			(vias allowed)
			(pads allowed)
			(copperpour not_allowed)
			(footprints allowed)
		)
		(placement
			(enabled no)
			(sheetname "")
		)
		(fill yes
			(thermal_gap 0.5)
			(thermal_bridge_width 0.5)
			(island_removal_mode 0)
		)
		(polygon
			(pts
				(arc
					(start 394.02639 -275.949918)
					(mid 393.37361 -275.949918)
					(end 394.02639 -275.949918)
				)
			)
		)
	)
	(zone
		(layers "B.Cu" "In9.Cu" "In11.Cu" "In13.Cu" "In15.Cu")
		(hatch none 0.5)
		(connect_pads
			(clearance 0)
		)
		(min_thickness 0.25)
		(keepout
			(tracks not_allowed)
			(vias allowed)
			(pads allowed)
			(copperpour not_allowed)
			(footprints allowed)
		)
		(placement
			(enabled no)
			(sheetname "")
		)
		(fill yes
			(thermal_gap 0.5)
			(thermal_bridge_width 0.5)
			(island_removal_mode 0)
		)
		(polygon
			(pts
				(arc
					(start 276.976078 -308.249828)
					(mid 276.323298 -308.249828)
					(end 276.976078 -308.249828)
				)
			)
		)
	)
	(zone
		(layers "B.Cu" "In9.Cu" "In11.Cu" "In13.Cu" "In15.Cu")
		(hatch none 0.5)
		(connect_pads
			(clearance 0)
		)
		(min_thickness 0.25)
		(keepout
			(tracks not_allowed)
			(vias allowed)
			(pads allowed)
			(copperpour not_allowed)
			(footprints allowed)
		)
		(placement
			(enabled no)
			(sheetname "")
		)
		(fill yes
			(thermal_gap 0.5)
			(thermal_bridge_width 0.5)
			(island_removal_mode 0)
		)
		(polygon
			(pts
				(arc
					(start 422.082722 -351.611438)
					(mid 421.379142 -351.611438)
					(end 422.082722 -351.611438)
				)
			)
		)
	)
	(zone
		(layers "B.Cu" "In9.Cu" "In11.Cu" "In13.Cu" "In15.Cu")
		(hatch none 0.5)
		(connect_pads
			(clearance 0)
		)
		(min_thickness 0.25)
		(keepout
			(tracks not_allowed)
			(vias allowed)
			(pads allowed)
			(copperpour not_allowed)
			(footprints allowed)
		)
		(placement
			(enabled no)
			(sheetname "")
		)
		(fill yes
			(thermal_gap 0.5)
			(thermal_bridge_width 0.5)
			(island_removal_mode 0)
		)
		(polygon
			(pts
				(arc
					(start 74.159872 -351.611438)
					(mid 73.456292 -351.611438)
					(end 74.159872 -351.611438)
				)
			)
		)
	)
	(zone
		(layers "B.Cu" "In9.Cu" "In11.Cu" "In13.Cu" "In15.Cu")
		(hatch none 0.5)
		(connect_pads
			(clearance 0)
		)
		(min_thickness 0.25)
		(keepout
			(tracks not_allowed)
			(vias allowed)
			(pads allowed)
			(copperpour not_allowed)
			(footprints allowed)
		)
		(placement
			(enabled no)
			(sheetname "")
		)
		(fill yes
			(thermal_gap 0.5)
			(thermal_bridge_width 0.5)
			(island_removal_mode 0)
		)
		(polygon
			(pts
				(arc
					(start 391.05713 -351.611438)
					(mid 390.35355 -351.611438)
					(end 391.05713 -351.611438)
				)
			)
		)
	)
	(zone
		(layers "B.Cu" "In9.Cu" "In11.Cu" "In13.Cu" "In15.Cu")
		(hatch none 0.5)
		(connect_pads
			(clearance 0)
		)
		(min_thickness 0.25)
		(keepout
			(tracks not_allowed)
			(vias allowed)
			(pads allowed)
			(copperpour not_allowed)
			(footprints allowed)
		)
		(placement
			(enabled no)
			(sheetname "")
		)
		(fill yes
			(thermal_gap 0.5)
			(thermal_bridge_width 0.5)
			(island_removal_mode 0)
		)
		(polygon
			(pts
				(arc
					(start 178.082702 -342.439498)
					(mid 177.379122 -342.439498)
					(end 178.082702 -342.439498)
				)
			)
		)
	)
	(zone
		(layers "B.Cu" "In9.Cu" "In11.Cu" "In13.Cu" "In15.Cu")
		(hatch none 0.5)
		(connect_pads
			(clearance 0)
		)
		(min_thickness 0.25)
		(keepout
			(tracks not_allowed)
			(vias allowed)
			(pads allowed)
			(copperpour not_allowed)
			(footprints allowed)
		)
		(placement
			(enabled no)
			(sheetname "")
		)
		(fill yes
			(thermal_gap 0.5)
			(thermal_bridge_width 0.5)
			(island_removal_mode 0)
		)
		(polygon
			(pts
				(arc
					(start 64.832992 -354.732082)
					(mid 64.129412 -354.732082)
					(end 64.832992 -354.732082)
				)
			)
		)
	)
	(zone
		(layers "B.Cu" "In9.Cu" "In11.Cu" "In13.Cu" "In15.Cu")
		(hatch none 0.5)
		(connect_pads
			(clearance 0)
		)
		(min_thickness 0.25)
		(keepout
			(tracks not_allowed)
			(vias allowed)
			(pads allowed)
			(copperpour not_allowed)
			(footprints allowed)
		)
		(placement
			(enabled no)
			(sheetname "")
		)
		(fill yes
			(thermal_gap 0.5)
			(thermal_bridge_width 0.5)
			(island_removal_mode 0)
		)
		(polygon
			(pts
				(arc
					(start 287.86963 -400.390106)
					(mid 287.11017 -400.390106)
					(end 287.86963 -400.390106)
				)
			)
		)
	)
	(zone
		(layers "B.Cu" "In9.Cu" "In11.Cu" "In13.Cu" "In15.Cu")
		(hatch none 0.5)
		(connect_pads
			(clearance 0)
		)
		(min_thickness 0.25)
		(keepout
			(tracks not_allowed)
			(vias allowed)
			(pads allowed)
			(copperpour not_allowed)
			(footprints allowed)
		)
		(placement
			(enabled no)
			(sheetname "")
		)
		(fill yes
			(thermal_gap 0.5)
			(thermal_bridge_width 0.5)
			(island_removal_mode 0)
		)
		(polygon
			(pts
				(arc
					(start 116.289836 -382.18999)
					(mid 115.530376 -382.18999)
					(end 116.289836 -382.18999)
				)
			)
		)
	)
	(zone
		(layers "B.Cu" "In9.Cu" "In11.Cu" "In13.Cu" "In15.Cu")
		(hatch none 0.5)
		(connect_pads
			(clearance 0)
		)
		(min_thickness 0.25)
		(keepout
			(tracks not_allowed)
			(vias allowed)
			(pads allowed)
			(copperpour not_allowed)
			(footprints allowed)
		)
		(placement
			(enabled no)
			(sheetname "")
		)
		(fill yes
			(thermal_gap 0.5)
			(thermal_bridge_width 0.5)
			(island_removal_mode 0)
		)
		(polygon
			(pts
				(arc
					(start 357.716582 -31.858712)
					(mid 357.013002 -31.858712)
					(end 357.716582 -31.858712)
				)
			)
		)
	)
	(zone
		(layers "B.Cu" "In9.Cu" "In11.Cu" "In13.Cu" "In15.Cu")
		(hatch none 0.5)
		(connect_pads
			(clearance 0)
		)
		(min_thickness 0.25)
		(keepout
			(tracks not_allowed)
			(vias allowed)
			(pads allowed)
			(copperpour not_allowed)
			(footprints allowed)
		)
		(placement
			(enabled no)
			(sheetname "")
		)
		(fill yes
			(thermal_gap 0.5)
			(thermal_bridge_width 0.5)
			(island_removal_mode 0)
		)
		(polygon
			(pts
				(arc
					(start 56.176164 -274.049744)
					(mid 55.523384 -274.049744)
					(end 56.176164 -274.049744)
				)
			)
		)
	)
	(zone
		(layers "B.Cu" "In9.Cu" "In11.Cu" "In13.Cu" "In15.Cu")
		(hatch none 0.5)
		(connect_pads
			(clearance 0)
		)
		(min_thickness 0.25)
		(keepout
			(tracks not_allowed)
			(vias allowed)
			(pads allowed)
			(copperpour not_allowed)
			(footprints allowed)
		)
		(placement
			(enabled no)
			(sheetname "")
		)
		(fill yes
			(thermal_gap 0.5)
			(thermal_bridge_width 0.5)
			(island_removal_mode 0)
		)
		(polygon
			(pts
				(arc
					(start 287.426146 -275.949918)
					(mid 286.773366 -275.949918)
					(end 287.426146 -275.949918)
				)
			)
		)
	)
	(zone
		(layers "B.Cu" "In9.Cu" "In11.Cu" "In13.Cu" "In15.Cu")
		(hatch none 0.5)
		(connect_pads
			(clearance 0)
		)
		(min_thickness 0.25)
		(keepout
			(tracks not_allowed)
			(vias allowed)
			(pads allowed)
			(copperpour not_allowed)
			(footprints allowed)
		)
		(placement
			(enabled no)
			(sheetname "")
		)
		(fill yes
			(thermal_gap 0.5)
			(thermal_bridge_width 0.5)
			(island_removal_mode 0)
		)
		(polygon
			(pts
				(arc
					(start 41.926256 -305.399948)
					(mid 41.273476 -305.399948)
					(end 41.926256 -305.399948)
				)
			)
		)
	)
	(zone
		(layers "B.Cu" "In9.Cu" "In11.Cu" "In13.Cu" "In15.Cu")
		(hatch none 0.5)
		(connect_pads
			(clearance 0)
		)
		(min_thickness 0.25)
		(keepout
			(tracks not_allowed)
			(vias allowed)
			(pads allowed)
			(copperpour not_allowed)
			(footprints allowed)
		)
		(placement
			(enabled no)
			(sheetname "")
		)
		(fill yes
			(thermal_gap 0.5)
			(thermal_bridge_width 0.5)
			(island_removal_mode 0)
		)
		(polygon
			(pts
				(arc
					(start 418.973762 -354.732082)
					(mid 418.270182 -354.732082)
					(end 418.973762 -354.732082)
				)
			)
		)
	)
	(zone
		(layers "B.Cu" "In9.Cu" "In11.Cu" "In13.Cu" "In15.Cu")
		(hatch none 0.5)
		(connect_pads
			(clearance 0)
		)
		(min_thickness 0.25)
		(keepout
			(tracks not_allowed)
			(vias allowed)
			(pads allowed)
			(copperpour not_allowed)
			(footprints allowed)
		)
		(placement
			(enabled no)
			(sheetname "")
		)
		(fill yes
			(thermal_gap 0.5)
			(thermal_bridge_width 0.5)
			(island_removal_mode 0)
		)
		(polygon
			(pts
				(arc
					(start 424.42638 -311.099962)
					(mid 423.7736 -311.099962)
					(end 424.42638 -311.099962)
				)
			)
		)
	)
	(zone
		(layers "B.Cu" "In9.Cu" "In11.Cu" "In13.Cu" "In15.Cu")
		(hatch none 0.5)
		(connect_pads
			(clearance 0)
		)
		(min_thickness 0.25)
		(keepout
			(tracks not_allowed)
			(vias allowed)
			(pads allowed)
			(copperpour not_allowed)
			(footprints allowed)
		)
		(placement
			(enabled no)
			(sheetname "")
		)
		(fill yes
			(thermal_gap 0.5)
			(thermal_bridge_width 0.5)
			(island_removal_mode 0)
		)
		(polygon
			(pts
				(arc
					(start 181.191662 -348.58579)
					(mid 180.488082 -348.58579)
					(end 181.191662 -348.58579)
				)
			)
		)
	)
	(zone
		(layers "B.Cu" "In9.Cu" "In11.Cu" "In13.Cu" "In15.Cu")
		(hatch none 0.5)
		(connect_pads
			(clearance 0)
		)
		(min_thickness 0.25)
		(keepout
			(tracks not_allowed)
			(vias allowed)
			(pads allowed)
			(copperpour not_allowed)
			(footprints allowed)
		)
		(placement
			(enabled no)
			(sheetname "")
		)
		(fill yes
			(thermal_gap 0.5)
			(thermal_bridge_width 0.5)
			(island_removal_mode 0)
		)
		(polygon
			(pts
				(arc
					(start 438.491122 -354.732082)
					(mid 437.787542 -354.732082)
					(end 438.491122 -354.732082)
				)
			)
		)
	)
	(zone
		(layers "B.Cu" "In9.Cu" "In11.Cu" "In13.Cu" "In15.Cu")
		(hatch none 0.5)
		(connect_pads
			(clearance 0)
		)
		(min_thickness 0.25)
		(keepout
			(tracks not_allowed)
			(vias allowed)
			(pads allowed)
			(copperpour not_allowed)
			(footprints allowed)
		)
		(placement
			(enabled no)
			(sheetname "")
		)
		(fill yes
			(thermal_gap 0.5)
			(thermal_bridge_width 0.5)
			(island_removal_mode 0)
		)
		(polygon
			(pts
				(arc
					(start 85.489542 -378.290074)
					(mid 84.730082 -378.290074)
					(end 85.489542 -378.290074)
				)
			)
		)
	)
	(zone
		(layers "B.Cu" "In9.Cu" "In11.Cu" "In13.Cu" "In15.Cu")
		(hatch none 0.5)
		(connect_pads
			(clearance 0)
		)
		(min_thickness 0.25)
		(keepout
			(tracks not_allowed)
			(vias allowed)
			(pads allowed)
			(copperpour not_allowed)
			(footprints allowed)
		)
		(placement
			(enabled no)
			(sheetname "")
		)
		(fill yes
			(thermal_gap 0.5)
			(thermal_bridge_width 0.5)
			(island_removal_mode 0)
		)
		(polygon
			(pts
				(arc
					(start 403.526244 -311.099962)
					(mid 402.873464 -311.099962)
					(end 403.526244 -311.099962)
				)
			)
		)
	)
	(zone
		(layers "B.Cu" "In9.Cu" "In11.Cu" "In13.Cu" "In15.Cu")
		(hatch none 0.5)
		(connect_pads
			(clearance 0)
		)
		(min_thickness 0.25)
		(keepout
			(tracks not_allowed)
			(vias allowed)
			(pads allowed)
			(copperpour not_allowed)
			(footprints allowed)
		)
		(placement
			(enabled no)
			(sheetname "")
		)
		(fill yes
			(thermal_gap 0.5)
			(thermal_bridge_width 0.5)
			(island_removal_mode 0)
		)
		(polygon
			(pts
				(arc
					(start 433.862226 -30.058868)
					(mid 433.158646 -30.058868)
					(end 433.862226 -30.058868)
				)
			)
		)
	)
	(zone
		(layers "B.Cu" "In9.Cu" "In11.Cu" "In13.Cu" "In15.Cu")
		(hatch none 0.5)
		(connect_pads
			(clearance 0)
		)
		(min_thickness 0.25)
		(keepout
			(tracks not_allowed)
			(vias allowed)
			(pads allowed)
			(copperpour not_allowed)
			(footprints allowed)
		)
		(placement
			(enabled no)
			(sheetname "")
		)
		(fill yes
			(thermal_gap 0.5)
			(thermal_bridge_width 0.5)
			(island_removal_mode 0)
		)
		(polygon
			(pts
				(arc
					(start 437.627522 -354.732082)
					(mid 436.923942 -354.732082)
					(end 437.627522 -354.732082)
				)
			)
		)
	)
	(zone
		(layers "B.Cu" "In9.Cu" "In11.Cu" "In13.Cu" "In15.Cu")
		(hatch none 0.5)
		(connect_pads
			(clearance 0)
		)
		(min_thickness 0.25)
		(keepout
			(tracks not_allowed)
			(vias allowed)
			(pads allowed)
			(copperpour not_allowed)
			(footprints allowed)
		)
		(placement
			(enabled no)
			(sheetname "")
		)
		(fill yes
			(thermal_gap 0.5)
			(thermal_bridge_width 0.5)
			(island_removal_mode 0)
		)
		(polygon
			(pts
				(arc
					(start 190.326264 -312.049922)
					(mid 189.673484 -312.049922)
					(end 190.326264 -312.049922)
				)
			)
		)
	)
	(zone
		(layers "B.Cu" "In9.Cu" "In11.Cu" "In13.Cu" "In15.Cu")
		(hatch none 0.5)
		(connect_pads
			(clearance 0)
		)
		(min_thickness 0.25)
		(keepout
			(tracks not_allowed)
			(vias allowed)
			(pads allowed)
			(copperpour not_allowed)
			(footprints allowed)
		)
		(placement
			(enabled no)
			(sheetname "")
		)
		(fill yes
			(thermal_gap 0.5)
			(thermal_bridge_width 0.5)
			(island_removal_mode 0)
		)
		(polygon
			(pts
				(arc
					(start 195.076318 -312.999882)
					(mid 194.423538 -312.999882)
					(end 195.076318 -312.999882)
				)
			)
		)
	)
	(zone
		(layers "B.Cu" "In9.Cu" "In11.Cu" "In13.Cu" "In15.Cu")
		(hatch none 0.5)
		(connect_pads
			(clearance 0)
		)
		(min_thickness 0.25)
		(keepout
			(tracks not_allowed)
			(vias allowed)
			(pads allowed)
			(copperpour not_allowed)
			(footprints allowed)
		)
		(placement
			(enabled no)
			(sheetname "")
		)
		(fill yes
			(thermal_gap 0.5)
			(thermal_bridge_width 0.5)
			(island_removal_mode 0)
		)
		(polygon
			(pts
				(arc
					(start 151.516588 -31.858712)
					(mid 150.813008 -31.858712)
					(end 151.516588 -31.858712)
				)
			)
		)
	)
	(zone
		(layers "B.Cu" "In9.Cu" "In11.Cu" "In13.Cu" "In15.Cu")
		(hatch none 0.5)
		(connect_pads
			(clearance 0)
		)
		(min_thickness 0.25)
		(keepout
			(tracks not_allowed)
			(vias allowed)
			(pads allowed)
			(copperpour not_allowed)
			(footprints allowed)
		)
		(placement
			(enabled no)
			(sheetname "")
		)
		(fill yes
			(thermal_gap 0.5)
			(thermal_bridge_width 0.5)
			(island_removal_mode 0)
		)
		(polygon
			(pts
				(arc
					(start 121.540778 -357.75773)
					(mid 120.837198 -357.75773)
					(end 121.540778 -357.75773)
				)
			)
		)
	)
	(zone
		(layers "B.Cu" "In9.Cu" "In11.Cu" "In13.Cu" "In15.Cu")
		(hatch none 0.5)
		(connect_pads
			(clearance 0)
		)
		(min_thickness 0.25)
		(keepout
			(tracks not_allowed)
			(vias allowed)
			(pads allowed)
			(copperpour not_allowed)
			(footprints allowed)
		)
		(placement
			(enabled no)
			(sheetname "")
		)
		(fill yes
			(thermal_gap 0.5)
			(thermal_bridge_width 0.5)
			(island_removal_mode 0)
		)
		(polygon
			(pts
				(arc
					(start 383.97561 -348.58579)
					(mid 383.27203 -348.58579)
					(end 383.97561 -348.58579)
				)
			)
		)
	)
	(zone
		(layers "B.Cu" "In9.Cu" "In11.Cu" "In13.Cu" "In15.Cu")
		(hatch none 0.5)
		(connect_pads
			(clearance 0)
		)
		(min_thickness 0.25)
		(keepout
			(tracks not_allowed)
			(vias allowed)
			(pads allowed)
			(copperpour not_allowed)
			(footprints allowed)
		)
		(placement
			(enabled no)
			(sheetname "")
		)
		(fill yes
			(thermal_gap 0.5)
			(thermal_bridge_width 0.5)
			(island_removal_mode 0)
		)
		(polygon
			(pts
				(arc
					(start 71.050912 -354.732082)
					(mid 70.347332 -354.732082)
					(end 71.050912 -354.732082)
				)
			)
		)
	)
	(zone
		(layers "B.Cu" "In9.Cu" "In11.Cu" "In13.Cu" "In15.Cu")
		(hatch none 0.5)
		(connect_pads
			(clearance 0)
		)
		(min_thickness 0.25)
		(keepout
			(tracks not_allowed)
			(vias allowed)
			(pads allowed)
			(copperpour not_allowed)
			(footprints allowed)
		)
		(placement
			(enabled no)
			(sheetname "")
		)
		(fill yes
			(thermal_gap 0.5)
			(thermal_bridge_width 0.5)
			(island_removal_mode 0)
		)
		(polygon
			(pts
				(arc
					(start 35.41649 -29.12237)
					(mid 34.71291 -29.12237)
					(end 35.41649 -29.12237)
				)
			)
		)
	)
	(zone
		(layers "B.Cu" "In9.Cu" "In11.Cu" "In13.Cu" "In15.Cu")
		(hatch none 0.5)
		(connect_pads
			(clearance 0)
		)
		(min_thickness 0.25)
		(keepout
			(tracks not_allowed)
			(vias allowed)
			(pads allowed)
			(copperpour not_allowed)
			(footprints allowed)
		)
		(placement
			(enabled no)
			(sheetname "")
		)
		(fill yes
			(thermal_gap 0.5)
			(thermal_bridge_width 0.5)
			(island_removal_mode 0)
		)
		(polygon
			(pts
				(arc
					(start 118.431818 -351.611438)
					(mid 117.728238 -351.611438)
					(end 118.431818 -351.611438)
				)
			)
		)
	)
	(zone
		(layers "B.Cu" "In9.Cu" "In11.Cu" "In13.Cu" "In15.Cu")
		(hatch none 0.5)
		(connect_pads
			(clearance 0)
		)
		(min_thickness 0.25)
		(keepout
			(tracks not_allowed)
			(vias allowed)
			(pads allowed)
			(copperpour not_allowed)
			(footprints allowed)
		)
		(placement
			(enabled no)
			(sheetname "")
		)
		(fill yes
			(thermal_gap 0.5)
			(thermal_bridge_width 0.5)
			(island_removal_mode 0)
		)
		(polygon
			(pts
				(arc
					(start 87.68969 -405.390096)
					(mid 86.93023 -405.390096)
					(end 87.68969 -405.390096)
				)
			)
		)
	)
	(zone
		(layers "B.Cu" "In9.Cu" "In11.Cu" "In13.Cu" "In15.Cu")
		(hatch none 0.5)
		(connect_pads
			(clearance 0)
		)
		(min_thickness 0.25)
		(keepout
			(tracks not_allowed)
			(vias allowed)
			(pads allowed)
			(copperpour not_allowed)
			(footprints allowed)
		)
		(placement
			(enabled no)
			(sheetname "")
		)
		(fill yes
			(thermal_gap 0.5)
			(thermal_bridge_width 0.5)
			(island_removal_mode 0)
		)
		(polygon
			(pts
				(arc
					(start 296.229532 -357.75773)
					(mid 295.525952 -357.75773)
					(end 296.229532 -357.75773)
				)
			)
		)
	)
	(zone
		(layers "B.Cu" "In9.Cu" "In11.Cu" "In13.Cu" "In15.Cu")
		(hatch none 0.5)
		(connect_pads
			(clearance 0)
		)
		(min_thickness 0.25)
		(keepout
			(tracks not_allowed)
			(vias allowed)
			(pads allowed)
			(copperpour not_allowed)
			(footprints allowed)
		)
		(placement
			(enabled no)
			(sheetname "")
		)
		(fill yes
			(thermal_gap 0.5)
			(thermal_bridge_width 0.5)
			(island_removal_mode 0)
		)
		(polygon
			(pts
				(arc
					(start 143.303498 -351.611438)
					(mid 142.599918 -351.611438)
					(end 143.303498 -351.611438)
				)
			)
		)
	)
	(zone
		(layers "B.Cu" "In9.Cu" "In11.Cu" "In13.Cu" "In15.Cu")
		(hatch none 0.5)
		(connect_pads
			(clearance 0)
		)
		(min_thickness 0.25)
		(keepout
			(tracks not_allowed)
			(vias allowed)
			(pads allowed)
			(copperpour not_allowed)
			(footprints allowed)
		)
		(placement
			(enabled no)
			(sheetname "")
		)
		(fill yes
			(thermal_gap 0.5)
			(thermal_bridge_width 0.5)
			(island_removal_mode 0)
		)
		(polygon
			(pts
				(arc
					(start 173.48962 -396.49019)
					(mid 172.73016 -396.49019)
					(end 173.48962 -396.49019)
				)
			)
		)
	)
	(zone
		(layers "B.Cu" "In9.Cu" "In11.Cu" "In13.Cu" "In15.Cu")
		(hatch none 0.5)
		(connect_pads
			(clearance 0)
		)
		(min_thickness 0.25)
		(keepout
			(tracks not_allowed)
			(vias allowed)
			(pads allowed)
			(copperpour not_allowed)
			(footprints allowed)
		)
		(placement
			(enabled no)
			(sheetname "")
		)
		(fill yes
			(thermal_gap 0.5)
			(thermal_bridge_width 0.5)
			(island_removal_mode 0)
		)
		(polygon
			(pts
				(arc
					(start 403.526244 -274.999958)
					(mid 402.873464 -274.999958)
					(end 403.526244 -274.999958)
				)
			)
		)
	)
	(zone
		(layers "B.Cu" "In9.Cu" "In11.Cu" "In13.Cu" "In15.Cu")
		(hatch none 0.5)
		(connect_pads
			(clearance 0)
		)
		(min_thickness 0.25)
		(keepout
			(tracks not_allowed)
			(vias allowed)
			(pads allowed)
			(copperpour not_allowed)
			(footprints allowed)
		)
		(placement
			(enabled no)
			(sheetname "")
		)
		(fill yes
			(thermal_gap 0.5)
			(thermal_bridge_width 0.5)
			(island_removal_mode 0)
		)
		(polygon
			(pts
				(arc
					(start 382.469644 -405.390096)
					(mid 381.710184 -405.390096)
					(end 382.469644 -405.390096)
				)
			)
		)
	)
	(zone
		(layers "B.Cu" "In9.Cu" "In11.Cu" "In13.Cu" "In15.Cu")
		(hatch none 0.5)
		(connect_pads
			(clearance 0)
		)
		(min_thickness 0.25)
		(keepout
			(tracks not_allowed)
			(vias allowed)
			(pads allowed)
			(copperpour not_allowed)
			(footprints allowed)
		)
		(placement
			(enabled no)
			(sheetname "")
		)
		(fill yes
			(thermal_gap 0.5)
			(thermal_bridge_width 0.5)
			(island_removal_mode 0)
		)
		(polygon
			(pts
				(arc
					(start 47.664878 -342.439498)
					(mid 46.961298 -342.439498)
					(end 47.664878 -342.439498)
				)
			)
		)
	)
	(zone
		(layers "B.Cu" "In9.Cu" "In11.Cu" "In13.Cu" "In15.Cu")
		(hatch none 0.5)
		(connect_pads
			(clearance 0)
		)
		(min_thickness 0.25)
		(keepout
			(tracks not_allowed)
			(vias allowed)
			(pads allowed)
			(copperpour not_allowed)
			(footprints allowed)
		)
		(placement
			(enabled no)
			(sheetname "")
		)
		(fill yes
			(thermal_gap 0.5)
			(thermal_bridge_width 0.5)
			(island_removal_mode 0)
		)
		(polygon
			(pts
				(arc
					(start 44.776136 -274.049744)
					(mid 44.123356 -274.049744)
					(end 44.776136 -274.049744)
				)
			)
		)
	)
	(zone
		(layers "B.Cu" "In9.Cu" "In11.Cu" "In13.Cu" "In15.Cu")
		(hatch none 0.5)
		(connect_pads
			(clearance 0)
		)
		(min_thickness 0.25)
		(keepout
			(tracks not_allowed)
			(vias allowed)
			(pads allowed)
			(copperpour not_allowed)
			(footprints allowed)
		)
		(placement
			(enabled no)
			(sheetname "")
		)
		(fill yes
			(thermal_gap 0.5)
			(thermal_bridge_width 0.5)
			(island_removal_mode 0)
		)
		(polygon
			(pts
				(arc
					(start 72.28967 -405.589994)
					(mid 71.53021 -405.589994)
					(end 72.28967 -405.589994)
				)
			)
		)
	)
	(zone
		(layers "B.Cu" "In9.Cu" "In11.Cu" "In13.Cu" "In15.Cu")
		(hatch none 0.5)
		(connect_pads
			(clearance 0)
		)
		(min_thickness 0.25)
		(keepout
			(tracks not_allowed)
			(vias allowed)
			(pads allowed)
			(copperpour not_allowed)
			(footprints allowed)
		)
		(placement
			(enabled no)
			(sheetname "")
		)
		(fill yes
			(thermal_gap 0.5)
			(thermal_bridge_width 0.5)
			(island_removal_mode 0)
		)
		(polygon
			(pts
				(arc
					(start 286.476186 -273.099784)
					(mid 285.823406 -273.099784)
					(end 286.476186 -273.099784)
				)
			)
		)
	)
	(zone
		(layers "B.Cu" "In9.Cu" "In11.Cu" "In13.Cu" "In15.Cu")
		(hatch none 0.5)
		(connect_pads
			(clearance 0)
		)
		(min_thickness 0.25)
		(keepout
			(tracks not_allowed)
			(vias allowed)
			(pads allowed)
			(copperpour not_allowed)
			(footprints allowed)
		)
		(placement
			(enabled no)
			(sheetname "")
		)
		(fill yes
			(thermal_gap 0.5)
			(thermal_bridge_width 0.5)
			(island_removal_mode 0)
		)
		(polygon
			(pts
				(arc
					(start 56.176164 -273.099784)
					(mid 55.523384 -273.099784)
					(end 56.176164 -273.099784)
				)
			)
		)
	)
	(zone
		(layers "B.Cu" "In9.Cu" "In11.Cu" "In13.Cu" "In15.Cu")
		(hatch none 0.5)
		(connect_pads
			(clearance 0)
		)
		(min_thickness 0.25)
		(keepout
			(tracks not_allowed)
			(vias allowed)
			(pads allowed)
			(copperpour not_allowed)
			(footprints allowed)
		)
		(placement
			(enabled no)
			(sheetname "")
		)
		(fill yes
			(thermal_gap 0.5)
			(thermal_bridge_width 0.5)
			(island_removal_mode 0)
		)
		(polygon
			(pts
				(arc
					(start 297.093132 -342.439498)
					(mid 296.389552 -342.439498)
					(end 297.093132 -342.439498)
				)
			)
		)
	)
	(zone
		(layers "B.Cu" "In9.Cu" "In11.Cu" "In13.Cu" "In15.Cu")
		(hatch none 0.5)
		(connect_pads
			(clearance 0)
		)
		(min_thickness 0.25)
		(keepout
			(tracks not_allowed)
			(vias allowed)
			(pads allowed)
			(copperpour not_allowed)
			(footprints allowed)
		)
		(placement
			(enabled no)
			(sheetname "")
		)
		(fill yes
			(thermal_gap 0.5)
			(thermal_bridge_width 0.5)
			(island_removal_mode 0)
		)
		(polygon
			(pts
				(arc
					(start 272.221452 -357.75773)
					(mid 271.517872 -357.75773)
					(end 272.221452 -357.75773)
				)
			)
		)
	)
	(zone
		(layers "B.Cu" "In9.Cu" "In11.Cu" "In13.Cu" "In15.Cu")
		(hatch none 0.5)
		(connect_pads
			(clearance 0)
		)
		(min_thickness 0.25)
		(keepout
			(tracks not_allowed)
			(vias allowed)
			(pads allowed)
			(copperpour not_allowed)
			(footprints allowed)
		)
		(placement
			(enabled no)
			(sheetname "")
		)
		(fill yes
			(thermal_gap 0.5)
			(thermal_bridge_width 0.5)
			(island_removal_mode 0)
		)
		(polygon
			(pts
				(arc
					(start 355.862382 -30.058868)
					(mid 355.158802 -30.058868)
					(end 355.862382 -30.058868)
				)
			)
		)
	)
	(zone
		(layers "B.Cu" "In9.Cu" "In11.Cu" "In13.Cu" "In15.Cu")
		(hatch none 0.5)
		(connect_pads
			(clearance 0)
		)
		(min_thickness 0.25)
		(keepout
			(tracks not_allowed)
			(vias allowed)
			(pads allowed)
			(copperpour not_allowed)
			(footprints allowed)
		)
		(placement
			(enabled no)
			(sheetname "")
		)
		(fill yes
			(thermal_gap 0.5)
			(thermal_bridge_width 0.5)
			(island_removal_mode 0)
		)
		(polygon
			(pts
				(arc
					(start 43.826176 -304.449734)
					(mid 43.173396 -304.449734)
					(end 43.826176 -304.449734)
				)
			)
		)
	)
	(zone
		(layers "B.Cu" "In9.Cu" "In11.Cu" "In13.Cu" "In15.Cu")
		(hatch none 0.5)
		(connect_pads
			(clearance 0)
		)
		(min_thickness 0.25)
		(keepout
			(tracks not_allowed)
			(vias allowed)
			(pads allowed)
			(copperpour not_allowed)
			(footprints allowed)
		)
		(placement
			(enabled no)
			(sheetname "")
		)
		(fill yes
			(thermal_gap 0.5)
			(thermal_bridge_width 0.5)
			(island_removal_mode 0)
		)
		(polygon
			(pts
				(arc
					(start 407.862278 -30.058868)
					(mid 407.158698 -30.058868)
					(end 407.862278 -30.058868)
				)
			)
		)
	)
	(zone
		(layers "B.Cu" "In9.Cu" "In11.Cu" "In13.Cu" "In15.Cu")
		(hatch none 0.5)
		(connect_pads
			(clearance 0)
		)
		(min_thickness 0.25)
		(keepout
			(tracks not_allowed)
			(vias allowed)
			(pads allowed)
			(copperpour not_allowed)
			(footprints allowed)
		)
		(placement
			(enabled no)
			(sheetname "")
		)
		(fill yes
			(thermal_gap 0.5)
			(thermal_bridge_width 0.5)
			(island_removal_mode 0)
		)
		(polygon
			(pts
				(arc
					(start 121.540778 -342.439498)
					(mid 120.837198 -342.439498)
					(end 121.540778 -342.439498)
				)
			)
		)
	)
	(zone
		(layers "B.Cu" "In9.Cu" "In11.Cu" "In13.Cu" "In15.Cu")
		(hatch none 0.5)
		(connect_pads
			(clearance 0)
		)
		(min_thickness 0.25)
		(keepout
			(tracks not_allowed)
			(vias allowed)
			(pads allowed)
			(copperpour not_allowed)
			(footprints allowed)
		)
		(placement
			(enabled no)
			(sheetname "")
		)
		(fill yes
			(thermal_gap 0.5)
			(thermal_bridge_width 0.5)
			(island_removal_mode 0)
		)
		(polygon
			(pts
				(arc
					(start 441.600082 -351.611438)
					(mid 440.896502 -351.611438)
					(end 441.600082 -351.611438)
				)
			)
		)
	)
	(zone
		(layers "B.Cu" "In9.Cu" "In11.Cu" "In13.Cu" "In15.Cu")
		(hatch none 0.5)
		(connect_pads
			(clearance 0)
		)
		(min_thickness 0.25)
		(keepout
			(tracks not_allowed)
			(vias allowed)
			(pads allowed)
			(copperpour not_allowed)
			(footprints allowed)
		)
		(placement
			(enabled no)
			(sheetname "")
		)
		(fill yes
			(thermal_gap 0.5)
			(thermal_bridge_width 0.5)
			(island_removal_mode 0)
		)
		(polygon
			(pts
				(arc
					(start 61.416438 -28.25877)
					(mid 60.712858 -28.25877)
					(end 61.416438 -28.25877)
				)
			)
		)
	)
	(zone
		(layers "B.Cu" "In9.Cu" "In11.Cu" "In13.Cu" "In15.Cu")
		(hatch none 0.5)
		(connect_pads
			(clearance 0)
		)
		(min_thickness 0.25)
		(keepout
			(tracks not_allowed)
			(vias allowed)
			(pads allowed)
			(copperpour not_allowed)
			(footprints allowed)
		)
		(placement
			(enabled no)
			(sheetname "")
		)
		(fill yes
			(thermal_gap 0.5)
			(thermal_bridge_width 0.5)
			(island_removal_mode 0)
		)
		(polygon
			(pts
				(arc
					(start 410.510482 -348.58579)
					(mid 409.806902 -348.58579)
					(end 410.510482 -348.58579)
				)
			)
		)
	)
	(zone
		(layers "B.Cu" "In9.Cu" "In11.Cu" "In13.Cu" "In15.Cu")
		(hatch none 0.5)
		(connect_pads
			(clearance 0)
		)
		(min_thickness 0.25)
		(keepout
			(tracks not_allowed)
			(vias allowed)
			(pads allowed)
			(copperpour not_allowed)
			(footprints allowed)
		)
		(placement
			(enabled no)
			(sheetname "")
		)
		(fill yes
			(thermal_gap 0.5)
			(thermal_bridge_width 0.5)
			(island_removal_mode 0)
		)
		(polygon
			(pts
				(arc
					(start 381.86233 -34.52241)
					(mid 381.15875 -34.52241)
					(end 381.86233 -34.52241)
				)
			)
		)
	)
	(zone
		(layers "B.Cu" "In9.Cu" "In11.Cu" "In13.Cu" "In15.Cu")
		(hatch none 0.5)
		(connect_pads
			(clearance 0)
		)
		(min_thickness 0.25)
		(keepout
			(tracks not_allowed)
			(vias allowed)
			(pads allowed)
			(copperpour not_allowed)
			(footprints allowed)
		)
		(placement
			(enabled no)
			(sheetname "")
		)
		(fill yes
			(thermal_gap 0.5)
			(thermal_bridge_width 0.5)
			(island_removal_mode 0)
		)
		(polygon
			(pts
				(arc
					(start 297.093132 -345.465146)
					(mid 296.389552 -345.465146)
					(end 297.093132 -345.465146)
				)
			)
		)
	)
	(zone
		(layers "B.Cu" "In9.Cu" "In11.Cu" "In13.Cu" "In15.Cu")
		(hatch none 0.5)
		(connect_pads
			(clearance 0)
		)
		(min_thickness 0.25)
		(keepout
			(tracks not_allowed)
			(vias allowed)
			(pads allowed)
			(copperpour not_allowed)
			(footprints allowed)
		)
		(placement
			(enabled no)
			(sheetname "")
		)
		(fill yes
			(thermal_gap 0.5)
			(thermal_bridge_width 0.5)
			(island_removal_mode 0)
		)
		(polygon
			(pts
				(arc
					(start 277.575772 -357.75773)
					(mid 276.872192 -357.75773)
					(end 277.575772 -357.75773)
				)
			)
		)
	)
	(zone
		(layers "B.Cu" "In9.Cu" "In11.Cu" "In13.Cu" "In15.Cu")
		(hatch none 0.5)
		(connect_pads
			(clearance 0)
		)
		(min_thickness 0.25)
		(keepout
			(tracks not_allowed)
			(vias allowed)
			(pads allowed)
			(copperpour not_allowed)
			(footprints allowed)
		)
		(placement
			(enabled no)
			(sheetname "")
		)
		(fill yes
			(thermal_gap 0.5)
			(thermal_bridge_width 0.5)
			(island_removal_mode 0)
		)
		(polygon
			(pts
				(arc
					(start 299.776134 -312.999882)
					(mid 299.123354 -312.999882)
					(end 299.776134 -312.999882)
				)
			)
		)
	)
	(zone
		(layers "B.Cu" "In9.Cu" "In11.Cu" "In13.Cu" "In15.Cu")
		(hatch none 0.5)
		(connect_pads
			(clearance 0)
		)
		(min_thickness 0.25)
		(keepout
			(tracks not_allowed)
			(vias allowed)
			(pads allowed)
			(copperpour not_allowed)
			(footprints allowed)
		)
		(placement
			(enabled no)
			(sheetname "")
		)
		(fill yes
			(thermal_gap 0.5)
			(thermal_bridge_width 0.5)
			(island_removal_mode 0)
		)
		(polygon
			(pts
				(arc
					(start 430.126394 -312.049922)
					(mid 429.473614 -312.049922)
					(end 430.126394 -312.049922)
				)
			)
		)
	)
	(zone
		(layers "B.Cu" "In9.Cu" "In11.Cu" "In13.Cu" "In15.Cu")
		(hatch none 0.5)
		(connect_pads
			(clearance 0)
		)
		(min_thickness 0.25)
		(keepout
			(tracks not_allowed)
			(vias allowed)
			(pads allowed)
			(copperpour not_allowed)
			(footprints allowed)
		)
		(placement
			(enabled no)
			(sheetname "")
		)
		(fill yes
			(thermal_gap 0.5)
			(thermal_bridge_width 0.5)
			(island_removal_mode 0)
		)
		(polygon
			(pts
				(arc
					(start 283.793692 -345.465146)
					(mid 283.090112 -345.465146)
					(end 283.793692 -345.465146)
				)
			)
		)
	)
	(zone
		(layers "B.Cu" "In9.Cu" "In11.Cu" "In13.Cu" "In15.Cu")
		(hatch none 0.5)
		(connect_pads
			(clearance 0)
		)
		(min_thickness 0.25)
		(keepout
			(tracks not_allowed)
			(vias allowed)
			(pads allowed)
			(copperpour not_allowed)
			(footprints allowed)
		)
		(placement
			(enabled no)
			(sheetname "")
		)
		(fill yes
			(thermal_gap 0.5)
			(thermal_bridge_width 0.5)
			(island_removal_mode 0)
		)
		(polygon
			(pts
				(arc
					(start 299.776134 -313.949842)
					(mid 299.123354 -313.949842)
					(end 299.776134 -313.949842)
				)
			)
		)
	)
	(zone
		(layers "B.Cu" "In9.Cu" "In11.Cu" "In13.Cu" "In15.Cu")
		(hatch none 0.5)
		(connect_pads
			(clearance 0)
		)
		(min_thickness 0.25)
		(keepout
			(tracks not_allowed)
			(vias allowed)
			(pads allowed)
			(copperpour not_allowed)
			(footprints allowed)
		)
		(placement
			(enabled no)
			(sheetname "")
		)
		(fill yes
			(thermal_gap 0.5)
			(thermal_bridge_width 0.5)
			(island_removal_mode 0)
		)
		(polygon
			(pts
				(arc
					(start 169.089832 -396.49019)
					(mid 168.330372 -396.49019)
					(end 169.089832 -396.49019)
				)
			)
		)
	)
	(zone
		(layers "B.Cu" "In9.Cu" "In11.Cu" "In13.Cu" "In15.Cu")
		(hatch none 0.5)
		(connect_pads
			(clearance 0)
		)
		(min_thickness 0.25)
		(keepout
			(tracks not_allowed)
			(vias allowed)
			(pads allowed)
			(copperpour not_allowed)
			(footprints allowed)
		)
		(placement
			(enabled no)
			(sheetname "")
		)
		(fill yes
			(thermal_gap 0.5)
			(thermal_bridge_width 0.5)
			(island_removal_mode 0)
		)
		(polygon
			(pts
				(arc
					(start 378.069602 -384.590036)
					(mid 377.310142 -384.590036)
					(end 378.069602 -384.590036)
				)
			)
		)
	)
	(zone
		(layers "B.Cu" "In9.Cu" "In11.Cu" "In13.Cu" "In15.Cu")
		(hatch none 0.5)
		(connect_pads
			(clearance 0)
		)
		(min_thickness 0.25)
		(keepout
			(tracks not_allowed)
			(vias allowed)
			(pads allowed)
			(copperpour not_allowed)
			(footprints allowed)
		)
		(placement
			(enabled no)
			(sheetname "")
		)
		(fill yes
			(thermal_gap 0.5)
			(thermal_bridge_width 0.5)
			(island_removal_mode 0)
		)
		(polygon
			(pts
				(arc
					(start 387.94817 -345.465146)
					(mid 387.24459 -345.465146)
					(end 387.94817 -345.465146)
				)
			)
		)
	)
	(zone
		(layers "B.Cu" "In9.Cu" "In11.Cu" "In13.Cu" "In15.Cu")
		(hatch none 0.5)
		(connect_pads
			(clearance 0)
		)
		(min_thickness 0.25)
		(keepout
			(tracks not_allowed)
			(vias allowed)
			(pads allowed)
			(copperpour not_allowed)
			(footprints allowed)
		)
		(placement
			(enabled no)
			(sheetname "")
		)
		(fill yes
			(thermal_gap 0.5)
			(thermal_bridge_width 0.5)
			(island_removal_mode 0)
		)
		(polygon
			(pts
				(arc
					(start 304.526188 -312.049922)
					(mid 303.873408 -312.049922)
					(end 304.526188 -312.049922)
				)
			)
		)
	)
	(zone
		(layers "B.Cu" "In9.Cu" "In11.Cu" "In13.Cu" "In15.Cu")
		(hatch none 0.5)
		(connect_pads
			(clearance 0)
		)
		(min_thickness 0.25)
		(keepout
			(tracks not_allowed)
			(vias allowed)
			(pads allowed)
			(copperpour not_allowed)
			(footprints allowed)
		)
		(placement
			(enabled no)
			(sheetname "")
		)
		(fill yes
			(thermal_gap 0.5)
			(thermal_bridge_width 0.5)
			(island_removal_mode 0)
		)
		(polygon
			(pts
				(arc
					(start 378.069602 -383.290064)
					(mid 377.310142 -383.290064)
					(end 378.069602 -383.290064)
				)
			)
		)
	)
	(zone
		(layers "B.Cu" "In9.Cu" "In11.Cu" "In13.Cu" "In15.Cu")
		(hatch none 0.5)
		(connect_pads
			(clearance 0)
		)
		(min_thickness 0.25)
		(keepout
			(tracks not_allowed)
			(vias allowed)
			(pads allowed)
			(copperpour not_allowed)
			(footprints allowed)
		)
		(placement
			(enabled no)
			(sheetname "")
		)
		(fill yes
			(thermal_gap 0.5)
			(thermal_bridge_width 0.5)
			(island_removal_mode 0)
		)
		(polygon
			(pts
				(arc
					(start 428.669704 -397.790162)
					(mid 427.910244 -397.790162)
					(end 428.669704 -397.790162)
				)
			)
		)
	)
	(zone
		(layers "B.Cu" "In9.Cu" "In11.Cu" "In13.Cu" "In15.Cu")
		(hatch none 0.5)
		(connect_pads
			(clearance 0)
		)
		(min_thickness 0.25)
		(keepout
			(tracks not_allowed)
			(vias allowed)
			(pads allowed)
			(copperpour not_allowed)
			(footprints allowed)
		)
		(placement
			(enabled no)
			(sheetname "")
		)
		(fill yes
			(thermal_gap 0.5)
			(thermal_bridge_width 0.5)
			(island_removal_mode 0)
		)
		(polygon
			(pts
				(arc
					(start 295.02608 -311.099962)
					(mid 294.3733 -311.099962)
					(end 295.02608 -311.099962)
				)
			)
		)
	)
	(zone
		(layers "B.Cu" "In9.Cu" "In11.Cu" "In13.Cu" "In15.Cu")
		(hatch none 0.5)
		(connect_pads
			(clearance 0)
		)
		(min_thickness 0.25)
		(keepout
			(tracks not_allowed)
			(vias allowed)
			(pads allowed)
			(copperpour not_allowed)
			(footprints allowed)
		)
		(placement
			(enabled no)
			(sheetname "")
		)
		(fill yes
			(thermal_gap 0.5)
			(thermal_bridge_width 0.5)
			(island_removal_mode 0)
		)
		(polygon
			(pts
				(arc
					(start 131.731258 -351.611438)
					(mid 131.027678 -351.611438)
					(end 131.731258 -351.611438)
				)
			)
		)
	)
	(zone
		(layers "B.Cu" "In9.Cu" "In11.Cu" "In13.Cu" "In15.Cu")
		(hatch none 0.5)
		(connect_pads
			(clearance 0)
		)
		(min_thickness 0.25)
		(keepout
			(tracks not_allowed)
			(vias allowed)
			(pads allowed)
			(copperpour not_allowed)
			(footprints allowed)
		)
		(placement
			(enabled no)
			(sheetname "")
		)
		(fill yes
			(thermal_gap 0.5)
			(thermal_bridge_width 0.5)
			(island_removal_mode 0)
		)
		(polygon
			(pts
				(arc
					(start 51.637438 -351.611438)
					(mid 50.933858 -351.611438)
					(end 51.637438 -351.611438)
				)
			)
		)
	)
	(zone
		(layers "B.Cu" "In9.Cu" "In11.Cu" "In13.Cu" "In15.Cu")
		(hatch none 0.5)
		(connect_pads
			(clearance 0)
		)
		(min_thickness 0.25)
		(keepout
			(tracks not_allowed)
			(vias allowed)
			(pads allowed)
			(copperpour not_allowed)
			(footprints allowed)
		)
		(placement
			(enabled no)
			(sheetname "")
		)
		(fill yes
			(thermal_gap 0.5)
			(thermal_bridge_width 0.5)
			(island_removal_mode 0)
		)
		(polygon
			(pts
				(arc
					(start 283.793692 -354.732082)
					(mid 283.090112 -354.732082)
					(end 283.793692 -354.732082)
				)
			)
		)
	)
	(zone
		(layers "B.Cu" "In9.Cu" "In11.Cu" "In13.Cu" "In15.Cu")
		(hatch none 0.5)
		(connect_pads
			(clearance 0)
		)
		(min_thickness 0.25)
		(keepout
			(tracks not_allowed)
			(vias allowed)
			(pads allowed)
			(copperpour not_allowed)
			(footprints allowed)
		)
		(placement
			(enabled no)
			(sheetname "")
		)
		(fill yes
			(thermal_gap 0.5)
			(thermal_bridge_width 0.5)
			(island_removal_mode 0)
		)
		(polygon
			(pts
				(arc
					(start 340.66988 -405.589994)
					(mid 339.91042 -405.589994)
					(end 340.66988 -405.589994)
				)
			)
		)
	)
	(zone
		(layers "B.Cu" "In9.Cu" "In11.Cu" "In13.Cu" "In15.Cu")
		(hatch none 0.5)
		(connect_pads
			(clearance 0)
		)
		(min_thickness 0.25)
		(keepout
			(tracks not_allowed)
			(vias allowed)
			(pads allowed)
			(copperpour not_allowed)
			(footprints allowed)
		)
		(placement
			(enabled no)
			(sheetname "")
		)
		(fill yes
			(thermal_gap 0.5)
			(thermal_bridge_width 0.5)
			(island_removal_mode 0)
		)
		(polygon
			(pts
				(arc
					(start 413.026352 -312.049922)
					(mid 412.373572 -312.049922)
					(end 413.026352 -312.049922)
				)
			)
		)
	)
	(zone
		(layers "B.Cu" "In9.Cu" "In11.Cu" "In13.Cu" "In15.Cu")
		(hatch none 0.5)
		(connect_pads
			(clearance 0)
		)
		(min_thickness 0.25)
		(keepout
			(tracks not_allowed)
			(vias allowed)
			(pads allowed)
			(copperpour not_allowed)
			(footprints allowed)
		)
		(placement
			(enabled no)
			(sheetname "")
		)
		(fill yes
			(thermal_gap 0.5)
			(thermal_bridge_width 0.5)
			(island_removal_mode 0)
		)
		(polygon
			(pts
				(arc
					(start 9.416542 -32.722312)
					(mid 8.712962 -32.722312)
					(end 9.416542 -32.722312)
				)
			)
		)
	)
	(zone
		(layers "B.Cu" "In9.Cu" "In11.Cu" "In13.Cu" "In15.Cu")
		(hatch none 0.5)
		(connect_pads
			(clearance 0)
		)
		(min_thickness 0.25)
		(keepout
			(tracks not_allowed)
			(vias allowed)
			(pads allowed)
			(copperpour not_allowed)
			(footprints allowed)
		)
		(placement
			(enabled no)
			(sheetname "")
		)
		(fill yes
			(thermal_gap 0.5)
			(thermal_bridge_width 0.5)
			(island_removal_mode 0)
		)
		(polygon
			(pts
				(arc
					(start 385.736084 8.574532)
					(mid 385.032504 8.574532)
					(end 385.736084 8.574532)
				)
			)
		)
	)
	(zone
		(layers "B.Cu" "In9.Cu" "In11.Cu" "In13.Cu" "In15.Cu")
		(hatch none 0.5)
		(connect_pads
			(clearance 0)
		)
		(min_thickness 0.25)
		(keepout
			(tracks not_allowed)
			(vias allowed)
			(pads allowed)
			(copperpour not_allowed)
			(footprints allowed)
		)
		(placement
			(enabled no)
			(sheetname "")
		)
		(fill yes
			(thermal_gap 0.5)
			(thermal_bridge_width 0.5)
			(island_removal_mode 0)
		)
		(polygon
			(pts
				(arc
					(start 413.619442 -345.465146)
					(mid 412.915862 -345.465146)
					(end 413.619442 -345.465146)
				)
			)
		)
	)
	(zone
		(layers "B.Cu" "In9.Cu" "In11.Cu" "In13.Cu" "In15.Cu")
		(hatch none 0.5)
		(connect_pads
			(clearance 0)
		)
		(min_thickness 0.25)
		(keepout
			(tracks not_allowed)
			(vias allowed)
			(pads allowed)
			(copperpour not_allowed)
			(footprints allowed)
		)
		(placement
			(enabled no)
			(sheetname "")
		)
		(fill yes
			(thermal_gap 0.5)
			(thermal_bridge_width 0.5)
			(island_removal_mode 0)
		)
		(polygon
			(pts
				(arc
					(start 402.576284 -273.099784)
					(mid 401.923504 -273.099784)
					(end 402.576284 -273.099784)
				)
			)
		)
	)
	(zone
		(layers "B.Cu" "In9.Cu" "In11.Cu" "In13.Cu" "In15.Cu")
		(hatch none 0.5)
		(connect_pads
			(clearance 0)
		)
		(min_thickness 0.25)
		(keepout
			(tracks not_allowed)
			(vias allowed)
			(pads allowed)
			(copperpour not_allowed)
			(footprints allowed)
		)
		(placement
			(enabled no)
			(sheetname "")
		)
		(fill yes
			(thermal_gap 0.5)
			(thermal_bridge_width 0.5)
			(island_removal_mode 0)
		)
		(polygon
			(pts
				(arc
					(start 80.377792 -348.58579)
					(mid 79.674212 -348.58579)
					(end 80.377792 -348.58579)
				)
			)
		)
	)
	(zone
		(layers "B.Cu" "In9.Cu" "In11.Cu" "In13.Cu" "In15.Cu")
		(hatch none 0.5)
		(connect_pads
			(clearance 0)
		)
		(min_thickness 0.25)
		(keepout
			(tracks not_allowed)
			(vias allowed)
			(pads allowed)
			(copperpour not_allowed)
			(footprints allowed)
		)
		(placement
			(enabled no)
			(sheetname "")
		)
		(fill yes
			(thermal_gap 0.5)
			(thermal_bridge_width 0.5)
			(island_removal_mode 0)
		)
		(polygon
			(pts
				(arc
					(start 338.589874 -348.58579)
					(mid 337.886294 -348.58579)
					(end 338.589874 -348.58579)
				)
			)
		)
	)
	(zone
		(layers "B.Cu" "In9.Cu" "In11.Cu" "In13.Cu" "In15.Cu")
		(hatch none 0.5)
		(connect_pads
			(clearance 0)
		)
		(min_thickness 0.25)
		(keepout
			(tracks not_allowed)
			(vias allowed)
			(pads allowed)
			(copperpour not_allowed)
			(footprints allowed)
		)
		(placement
			(enabled no)
			(sheetname "")
		)
		(fill yes
			(thermal_gap 0.5)
			(thermal_bridge_width 0.5)
			(island_removal_mode 0)
		)
		(polygon
			(pts
				(arc
					(start 412.076392 -313.949842)
					(mid 411.423612 -313.949842)
					(end 412.076392 -313.949842)
				)
			)
		)
	)
	(zone
		(layers "B.Cu" "In9.Cu" "In11.Cu" "In13.Cu" "In15.Cu")
		(hatch none 0.5)
		(connect_pads
			(clearance 0)
		)
		(min_thickness 0.25)
		(keepout
			(tracks not_allowed)
			(vias allowed)
			(pads allowed)
			(copperpour not_allowed)
			(footprints allowed)
		)
		(placement
			(enabled no)
			(sheetname "")
		)
		(fill yes
			(thermal_gap 0.5)
			(thermal_bridge_width 0.5)
			(island_removal_mode 0)
		)
		(polygon
			(pts
				(arc
					(start 60.926218 -311.099962)
					(mid 60.273438 -311.099962)
					(end 60.926218 -311.099962)
				)
			)
		)
	)
	(zone
		(layers "B.Cu" "In9.Cu" "In11.Cu" "In13.Cu" "In15.Cu")
		(hatch none 0.5)
		(connect_pads
			(clearance 0)
		)
		(min_thickness 0.25)
		(keepout
			(tracks not_allowed)
			(vias allowed)
			(pads allowed)
			(copperpour not_allowed)
			(footprints allowed)
		)
		(placement
			(enabled no)
			(sheetname "")
		)
		(fill yes
			(thermal_gap 0.5)
			(thermal_bridge_width 0.5)
			(island_removal_mode 0)
		)
		(polygon
			(pts
				(arc
					(start 276.976078 -302.549814)
					(mid 276.323298 -302.549814)
					(end 276.976078 -302.549814)
				)
			)
		)
	)
	(zone
		(layers "B.Cu" "In9.Cu" "In11.Cu" "In13.Cu" "In15.Cu")
		(hatch none 0.5)
		(connect_pads
			(clearance 0)
		)
		(min_thickness 0.25)
		(keepout
			(tracks not_allowed)
			(vias allowed)
			(pads allowed)
			(copperpour not_allowed)
			(footprints allowed)
		)
		(placement
			(enabled no)
			(sheetname "")
		)
		(fill yes
			(thermal_gap 0.5)
			(thermal_bridge_width 0.5)
			(island_removal_mode 0)
		)
		(polygon
			(pts
				(arc
					(start 68.526152 -311.099962)
					(mid 67.873372 -311.099962)
					(end 68.526152 -311.099962)
				)
			)
		)
	)
	(zone
		(layers "B.Cu" "In9.Cu" "In11.Cu" "In13.Cu" "In15.Cu")
		(hatch none 0.5)
		(connect_pads
			(clearance 0)
		)
		(min_thickness 0.25)
		(keepout
			(tracks not_allowed)
			(vias allowed)
			(pads allowed)
			(copperpour not_allowed)
			(footprints allowed)
		)
		(placement
			(enabled no)
			(sheetname "")
		)
		(fill yes
			(thermal_gap 0.5)
			(thermal_bridge_width 0.5)
			(island_removal_mode 0)
		)
		(polygon
			(pts
				(arc
					(start 329.262994 -345.465146)
					(mid 328.559414 -345.465146)
					(end 329.262994 -345.465146)
				)
			)
		)
	)
	(zone
		(layers "B.Cu" "In9.Cu" "In11.Cu" "In13.Cu" "In15.Cu")
		(hatch none 0.5)
		(connect_pads
			(clearance 0)
		)
		(min_thickness 0.25)
		(keepout
			(tracks not_allowed)
			(vias allowed)
			(pads allowed)
			(copperpour not_allowed)
			(footprints allowed)
		)
		(placement
			(enabled no)
			(sheetname "")
		)
		(fill yes
			(thermal_gap 0.5)
			(thermal_bridge_width 0.5)
			(island_removal_mode 0)
		)
		(polygon
			(pts
				(arc
					(start 435.26964 -398.890236)
					(mid 434.51018 -398.890236)
					(end 435.26964 -398.890236)
				)
			)
		)
	)
	(zone
		(layers "B.Cu" "In9.Cu" "In11.Cu" "In13.Cu" "In15.Cu")
		(hatch none 0.5)
		(connect_pads
			(clearance 0)
		)
		(min_thickness 0.25)
		(keepout
			(tracks not_allowed)
			(vias allowed)
			(pads allowed)
			(copperpour not_allowed)
			(footprints allowed)
		)
		(placement
			(enabled no)
			(sheetname "")
		)
		(fill yes
			(thermal_gap 0.5)
			(thermal_bridge_width 0.5)
			(island_removal_mode 0)
		)
		(polygon
			(pts
				(arc
					(start 419.86962 -371.790214)
					(mid 419.11016 -371.790214)
					(end 419.86962 -371.790214)
				)
			)
		)
	)
	(zone
		(layers "B.Cu" "In9.Cu" "In11.Cu" "In13.Cu" "In15.Cu")
		(hatch none 0.5)
		(connect_pads
			(clearance 0)
		)
		(min_thickness 0.25)
		(keepout
			(tracks not_allowed)
			(vias allowed)
			(pads allowed)
			(copperpour not_allowed)
			(footprints allowed)
		)
		(placement
			(enabled no)
			(sheetname "")
		)
		(fill yes
			(thermal_gap 0.5)
			(thermal_bridge_width 0.5)
			(island_removal_mode 0)
		)
		(polygon
			(pts
				(arc
					(start 409.646882 -351.611438)
					(mid 408.943302 -351.611438)
					(end 409.646882 -351.611438)
				)
			)
		)
	)
	(zone
		(layers "B.Cu" "In9.Cu" "In11.Cu" "In13.Cu" "In15.Cu")
		(hatch none 0.5)
		(connect_pads
			(clearance 0)
		)
		(min_thickness 0.25)
		(keepout
			(tracks not_allowed)
			(vias allowed)
			(pads allowed)
			(copperpour not_allowed)
			(footprints allowed)
		)
		(placement
			(enabled no)
			(sheetname "")
		)
		(fill yes
			(thermal_gap 0.5)
			(thermal_bridge_width 0.5)
			(island_removal_mode 0)
		)
		(polygon
			(pts
				(arc
					(start 171.326302 -274.999958)
					(mid 170.673522 -274.999958)
					(end 171.326302 -274.999958)
				)
			)
		)
	)
	(zone
		(layers "B.Cu" "In9.Cu" "In11.Cu" "In13.Cu" "In15.Cu")
		(hatch none 0.5)
		(connect_pads
			(clearance 0)
		)
		(min_thickness 0.25)
		(keepout
			(tracks not_allowed)
			(vias allowed)
			(pads allowed)
			(copperpour not_allowed)
			(footprints allowed)
		)
		(placement
			(enabled no)
			(sheetname "")
		)
		(fill yes
			(thermal_gap 0.5)
			(thermal_bridge_width 0.5)
			(island_removal_mode 0)
		)
		(polygon
			(pts
				(arc
					(start 120.689878 -382.18999)
					(mid 119.930418 -382.18999)
					(end 120.689878 -382.18999)
				)
			)
		)
	)
	(zone
		(layers "B.Cu" "In9.Cu" "In11.Cu" "In13.Cu" "In15.Cu")
		(hatch none 0.5)
		(connect_pads
			(clearance 0)
		)
		(min_thickness 0.25)
		(keepout
			(tracks not_allowed)
			(vias allowed)
			(pads allowed)
			(copperpour not_allowed)
			(footprints allowed)
		)
		(placement
			(enabled no)
			(sheetname "")
		)
		(fill yes
			(thermal_gap 0.5)
			(thermal_bridge_width 0.5)
			(island_removal_mode 0)
		)
		(polygon
			(pts
				(arc
					(start 375.869708 -383.490216)
					(mid 375.110248 -383.490216)
					(end 375.869708 -383.490216)
				)
			)
		)
	)
	(zone
		(layers "B.Cu" "In9.Cu" "In11.Cu" "In13.Cu" "In15.Cu")
		(hatch none 0.5)
		(connect_pads
			(clearance 0)
		)
		(min_thickness 0.25)
		(keepout
			(tracks not_allowed)
			(vias allowed)
			(pads allowed)
			(copperpour not_allowed)
			(footprints allowed)
		)
		(placement
			(enabled no)
			(sheetname "")
		)
		(fill yes
			(thermal_gap 0.5)
			(thermal_bridge_width 0.5)
			(island_removal_mode 0)
		)
		(polygon
			(pts
				(arc
					(start 193.176398 -312.999882)
					(mid 192.523618 -312.999882)
					(end 193.176398 -312.999882)
				)
			)
		)
	)
	(zone
		(layers "B.Cu" "In9.Cu" "In11.Cu" "In13.Cu" "In15.Cu")
		(hatch none 0.5)
		(connect_pads
			(clearance 0)
		)
		(min_thickness 0.25)
		(keepout
			(tracks not_allowed)
			(vias allowed)
			(pads allowed)
			(copperpour not_allowed)
			(footprints allowed)
		)
		(placement
			(enabled no)
			(sheetname "")
		)
		(fill yes
			(thermal_gap 0.5)
			(thermal_bridge_width 0.5)
			(island_removal_mode 0)
		)
		(polygon
			(pts
				(arc
					(start 134.840218 -357.75773)
					(mid 134.136638 -357.75773)
					(end 134.840218 -357.75773)
				)
			)
		)
	)
	(zone
		(layers "B.Cu" "In9.Cu" "In11.Cu" "In13.Cu" "In15.Cu")
		(hatch none 0.5)
		(connect_pads
			(clearance 0)
		)
		(min_thickness 0.25)
		(keepout
			(tracks not_allowed)
			(vias allowed)
			(pads allowed)
			(copperpour not_allowed)
			(footprints allowed)
		)
		(placement
			(enabled no)
			(sheetname "")
		)
		(fill yes
			(thermal_gap 0.5)
			(thermal_bridge_width 0.5)
			(island_removal_mode 0)
		)
		(polygon
			(pts
				(arc
					(start 287.86963 -401.690078)
					(mid 287.11017 -401.690078)
					(end 287.86963 -401.690078)
				)
			)
		)
	)
	(zone
		(layers "B.Cu" "In9.Cu" "In11.Cu" "In13.Cu" "In15.Cu")
		(hatch none 0.5)
		(connect_pads
			(clearance 0)
		)
		(min_thickness 0.25)
		(keepout
			(tracks not_allowed)
			(vias allowed)
			(pads allowed)
			(copperpour not_allowed)
			(footprints allowed)
		)
		(placement
			(enabled no)
			(sheetname "")
		)
		(fill yes
			(thermal_gap 0.5)
			(thermal_bridge_width 0.5)
			(island_removal_mode 0)
		)
		(polygon
			(pts
				(arc
					(start 61.876178 -313.949842)
					(mid 61.223398 -313.949842)
					(end 61.876178 -313.949842)
				)
			)
		)
	)
	(zone
		(layers "B.Cu" "In9.Cu" "In11.Cu" "In13.Cu" "In15.Cu")
		(hatch none 0.5)
		(connect_pads
			(clearance 0)
		)
		(min_thickness 0.25)
		(keepout
			(tracks not_allowed)
			(vias allowed)
			(pads allowed)
			(copperpour not_allowed)
			(footprints allowed)
		)
		(placement
			(enabled no)
			(sheetname "")
		)
		(fill yes
			(thermal_gap 0.5)
			(thermal_bridge_width 0.5)
			(island_removal_mode 0)
		)
		(polygon
			(pts
				(arc
					(start 76.689712 -404.290022)
					(mid 75.930252 -404.290022)
					(end 76.689712 -404.290022)
				)
			)
		)
	)
	(zone
		(layers "B.Cu" "In9.Cu" "In11.Cu" "In13.Cu" "In15.Cu")
		(hatch none 0.5)
		(connect_pads
			(clearance 0)
		)
		(min_thickness 0.25)
		(keepout
			(tracks not_allowed)
			(vias allowed)
			(pads allowed)
			(copperpour not_allowed)
			(footprints allowed)
		)
		(placement
			(enabled no)
			(sheetname "")
		)
		(fill yes
			(thermal_gap 0.5)
			(thermal_bridge_width 0.5)
			(island_removal_mode 0)
		)
		(polygon
			(pts
				(arc
					(start 41.926256 -309.199788)
					(mid 41.273476 -309.199788)
					(end 41.926256 -309.199788)
				)
			)
		)
	)
	(zone
		(layers "B.Cu" "In9.Cu" "In11.Cu" "In13.Cu" "In15.Cu")
		(hatch none 0.5)
		(connect_pads
			(clearance 0)
		)
		(min_thickness 0.25)
		(keepout
			(tracks not_allowed)
			(vias allowed)
			(pads allowed)
			(copperpour not_allowed)
			(footprints allowed)
		)
		(placement
			(enabled no)
			(sheetname "")
		)
		(fill yes
			(thermal_gap 0.5)
			(thermal_bridge_width 0.5)
			(island_removal_mode 0)
		)
		(polygon
			(pts
				(arc
					(start 172.276262 -312.999882)
					(mid 171.623482 -312.999882)
					(end 172.276262 -312.999882)
				)
			)
		)
	)
	(zone
		(layers "B.Cu" "In9.Cu" "In11.Cu" "In13.Cu" "In15.Cu")
		(hatch none 0.5)
		(connect_pads
			(clearance 0)
		)
		(min_thickness 0.25)
		(keepout
			(tracks not_allowed)
			(vias allowed)
			(pads allowed)
			(copperpour not_allowed)
			(footprints allowed)
		)
		(placement
			(enabled no)
			(sheetname "")
		)
		(fill yes
			(thermal_gap 0.5)
			(thermal_bridge_width 0.5)
			(island_removal_mode 0)
		)
		(polygon
			(pts
				(arc
					(start 40.976296 -313.949842)
					(mid 40.323516 -313.949842)
					(end 40.976296 -313.949842)
				)
			)
		)
	)
	(zone
		(layers "B.Cu" "In9.Cu" "In11.Cu" "In13.Cu" "In15.Cu")
		(hatch none 0.5)
		(connect_pads
			(clearance 0)
		)
		(min_thickness 0.25)
		(keepout
			(tracks not_allowed)
			(vias allowed)
			(pads allowed)
			(copperpour not_allowed)
			(footprints allowed)
		)
		(placement
			(enabled no)
			(sheetname "")
		)
		(fill yes
			(thermal_gap 0.5)
			(thermal_bridge_width 0.5)
			(island_removal_mode 0)
		)
		(polygon
			(pts
				(arc
					(start 403.49297 -351.611438)
					(mid 402.78939 -351.611438)
					(end 403.49297 -351.611438)
				)
			)
		)
	)
	(zone
		(layers "B.Cu" "In9.Cu" "In11.Cu" "In13.Cu" "In15.Cu")
		(hatch none 0.5)
		(connect_pads
			(clearance 0)
		)
		(min_thickness 0.25)
		(keepout
			(tracks not_allowed)
			(vias allowed)
			(pads allowed)
			(copperpour not_allowed)
			(footprints allowed)
		)
		(placement
			(enabled no)
			(sheetname "")
		)
		(fill yes
			(thermal_gap 0.5)
			(thermal_bridge_width 0.5)
			(island_removal_mode 0)
		)
		(polygon
			(pts
				(arc
					(start 239.762284 -34.52241)
					(mid 239.058704 -34.52241)
					(end 239.762284 -34.52241)
				)
			)
		)
	)
	(zone
		(layers "B.Cu" "In9.Cu" "In11.Cu" "In13.Cu" "In15.Cu")
		(hatch none 0.5)
		(connect_pads
			(clearance 0)
		)
		(min_thickness 0.25)
		(keepout
			(tracks not_allowed)
			(vias allowed)
			(pads allowed)
			(copperpour not_allowed)
			(footprints allowed)
		)
		(placement
			(enabled no)
			(sheetname "")
		)
		(fill yes
			(thermal_gap 0.5)
			(thermal_bridge_width 0.5)
			(island_removal_mode 0)
		)
		(polygon
			(pts
				(arc
					(start 65.696592 -345.465146)
					(mid 64.993012 -345.465146)
					(end 65.696592 -345.465146)
				)
			)
		)
	)
	(zone
		(layers "B.Cu" "In9.Cu" "In11.Cu" "In13.Cu" "In15.Cu")
		(hatch none 0.5)
		(connect_pads
			(clearance 0)
		)
		(min_thickness 0.25)
		(keepout
			(tracks not_allowed)
			(vias allowed)
			(pads allowed)
			(copperpour not_allowed)
			(footprints allowed)
		)
		(placement
			(enabled no)
			(sheetname "")
		)
		(fill yes
			(thermal_gap 0.5)
			(thermal_bridge_width 0.5)
			(island_removal_mode 0)
		)
		(polygon
			(pts
				(arc
					(start 291.22624 -275.949918)
					(mid 290.57346 -275.949918)
					(end 291.22624 -275.949918)
				)
			)
		)
	)
	(zone
		(layers "B.Cu" "In9.Cu" "In11.Cu" "In13.Cu" "In15.Cu")
		(hatch none 0.5)
		(connect_pads
			(clearance 0)
		)
		(min_thickness 0.25)
		(keepout
			(tracks not_allowed)
			(vias allowed)
			(pads allowed)
			(copperpour not_allowed)
			(footprints allowed)
		)
		(placement
			(enabled no)
			(sheetname "")
		)
		(fill yes
			(thermal_gap 0.5)
			(thermal_bridge_width 0.5)
			(island_removal_mode 0)
		)
		(polygon
			(pts
				(arc
					(start 7.562342 -34.52241)
					(mid 6.858762 -34.52241)
					(end 7.562342 -34.52241)
				)
			)
		)
	)
	(zone
		(layers "B.Cu" "In9.Cu" "In11.Cu" "In13.Cu" "In15.Cu")
		(hatch none 0.5)
		(connect_pads
			(clearance 0)
		)
		(min_thickness 0.25)
		(keepout
			(tracks not_allowed)
			(vias allowed)
			(pads allowed)
			(copperpour not_allowed)
			(footprints allowed)
		)
		(placement
			(enabled no)
			(sheetname "")
		)
		(fill yes
			(thermal_gap 0.5)
			(thermal_bridge_width 0.5)
			(island_removal_mode 0)
		)
		(polygon
			(pts
				(arc
					(start 405.426418 -312.049922)
					(mid 404.773638 -312.049922)
					(end 405.426418 -312.049922)
				)
			)
		)
	)
	(zone
		(layers "B.Cu" "In9.Cu" "In11.Cu" "In13.Cu" "In15.Cu")
		(hatch none 0.5)
		(connect_pads
			(clearance 0)
		)
		(min_thickness 0.25)
		(keepout
			(tracks not_allowed)
			(vias allowed)
			(pads allowed)
			(copperpour not_allowed)
			(footprints allowed)
		)
		(placement
			(enabled no)
			(sheetname "")
		)
		(fill yes
			(thermal_gap 0.5)
			(thermal_bridge_width 0.5)
			(island_removal_mode 0)
		)
		(polygon
			(pts
				(arc
					(start 127.758698 -357.75773)
					(mid 127.055118 -357.75773)
					(end 127.758698 -357.75773)
				)
			)
		)
	)
	(zone
		(layers "B.Cu" "In9.Cu" "In11.Cu" "In13.Cu" "In15.Cu")
		(hatch none 0.5)
		(connect_pads
			(clearance 0)
		)
		(min_thickness 0.25)
		(keepout
			(tracks not_allowed)
			(vias allowed)
			(pads allowed)
			(copperpour not_allowed)
			(footprints allowed)
		)
		(placement
			(enabled no)
			(sheetname "")
		)
		(fill yes
			(thermal_gap 0.5)
			(thermal_bridge_width 0.5)
			(island_removal_mode 0)
		)
		(polygon
			(pts
				(arc
					(start 409.226258 -312.049922)
					(mid 408.573478 -312.049922)
					(end 409.226258 -312.049922)
				)
			)
		)
	)
	(zone
		(layers "B.Cu" "In9.Cu" "In11.Cu" "In13.Cu" "In15.Cu")
		(hatch none 0.5)
		(connect_pads
			(clearance 0)
		)
		(min_thickness 0.25)
		(keepout
			(tracks not_allowed)
			(vias allowed)
			(pads allowed)
			(copperpour not_allowed)
			(footprints allowed)
		)
		(placement
			(enabled no)
			(sheetname "")
		)
		(fill yes
			(thermal_gap 0.5)
			(thermal_bridge_width 0.5)
			(island_removal_mode 0)
		)
		(polygon
			(pts
				(arc
					(start 128.622298 -342.439498)
					(mid 127.918718 -342.439498)
					(end 128.622298 -342.439498)
				)
			)
		)
	)
	(zone
		(layers "B.Cu" "In9.Cu" "In11.Cu" "In13.Cu" "In15.Cu")
		(hatch none 0.5)
		(connect_pads
			(clearance 0)
		)
		(min_thickness 0.25)
		(keepout
			(tracks not_allowed)
			(vias allowed)
			(pads allowed)
			(copperpour not_allowed)
			(footprints allowed)
		)
		(placement
			(enabled no)
			(sheetname "")
		)
		(fill yes
			(thermal_gap 0.5)
			(thermal_bridge_width 0.5)
			(island_removal_mode 0)
		)
		(polygon
			(pts
				(arc
					(start 378.069602 -406.690068)
					(mid 377.310142 -406.690068)
					(end 378.069602 -406.690068)
				)
			)
		)
	)
	(zone
		(layers "B.Cu" "In9.Cu" "In11.Cu" "In13.Cu" "In15.Cu")
		(hatch none 0.5)
		(connect_pads
			(clearance 0)
		)
		(min_thickness 0.25)
		(keepout
			(tracks not_allowed)
			(vias allowed)
			(pads allowed)
			(copperpour not_allowed)
			(footprints allowed)
		)
		(placement
			(enabled no)
			(sheetname "")
		)
		(fill yes
			(thermal_gap 0.5)
			(thermal_bridge_width 0.5)
			(island_removal_mode 0)
		)
		(polygon
			(pts
				(arc
					(start 338.469732 -379.390148)
					(mid 337.710272 -379.390148)
					(end 338.469732 -379.390148)
				)
			)
		)
	)
	(zone
		(layers "B.Cu" "In9.Cu" "In11.Cu" "In13.Cu" "In15.Cu")
		(hatch none 0.5)
		(connect_pads
			(clearance 0)
		)
		(min_thickness 0.25)
		(keepout
			(tracks not_allowed)
			(vias allowed)
			(pads allowed)
			(copperpour not_allowed)
			(footprints allowed)
		)
		(placement
			(enabled no)
			(sheetname "")
		)
		(fill yes
			(thermal_gap 0.5)
			(thermal_bridge_width 0.5)
			(island_removal_mode 0)
		)
		(polygon
			(pts
				(arc
					(start 33.56229 -33.65881)
					(mid 32.85871 -33.65881)
					(end 33.56229 -33.65881)
				)
			)
		)
	)
	(zone
		(layers "B.Cu" "In9.Cu" "In11.Cu" "In13.Cu" "In15.Cu")
		(hatch none 0.5)
		(connect_pads
			(clearance 0)
		)
		(min_thickness 0.25)
		(keepout
			(tracks not_allowed)
			(vias allowed)
			(pads allowed)
			(copperpour not_allowed)
			(footprints allowed)
		)
		(placement
			(enabled no)
			(sheetname "")
		)
		(fill yes
			(thermal_gap 0.5)
			(thermal_bridge_width 0.5)
			(island_removal_mode 0)
		)
		(polygon
			(pts
				(arc
					(start 285.526226 -274.999958)
					(mid 284.873446 -274.999958)
					(end 285.526226 -274.999958)
				)
			)
		)
	)
	(zone
		(layers "B.Cu" "In9.Cu" "In11.Cu" "In13.Cu" "In15.Cu")
		(hatch none 0.5)
		(connect_pads
			(clearance 0)
		)
		(min_thickness 0.25)
		(keepout
			(tracks not_allowed)
			(vias allowed)
			(pads allowed)
			(copperpour not_allowed)
			(footprints allowed)
		)
		(placement
			(enabled no)
			(sheetname "")
		)
		(fill yes
			(thermal_gap 0.5)
			(thermal_bridge_width 0.5)
			(island_removal_mode 0)
		)
		(polygon
			(pts
				(arc
					(start 42.876216 -312.999882)
					(mid 42.223436 -312.999882)
					(end 42.876216 -312.999882)
				)
			)
		)
	)
	(zone
		(layers "B.Cu" "In9.Cu" "In11.Cu" "In13.Cu" "In15.Cu")
		(hatch none 0.5)
		(connect_pads
			(clearance 0)
		)
		(min_thickness 0.25)
		(keepout
			(tracks not_allowed)
			(vias allowed)
			(pads allowed)
			(copperpour not_allowed)
			(footprints allowed)
		)
		(placement
			(enabled no)
			(sheetname "")
		)
		(fill yes
			(thermal_gap 0.5)
			(thermal_bridge_width 0.5)
			(island_removal_mode 0)
		)
		(polygon
			(pts
				(arc
					(start 269.376144 -314.899802)
					(mid 268.723364 -314.899802)
					(end 269.376144 -314.899802)
				)
			)
		)
	)
	(zone
		(layers "B.Cu" "In9.Cu" "In11.Cu" "In13.Cu" "In15.Cu")
		(hatch none 0.5)
		(connect_pads
			(clearance 0)
		)
		(min_thickness 0.25)
		(keepout
			(tracks not_allowed)
			(vias allowed)
			(pads allowed)
			(copperpour not_allowed)
			(footprints allowed)
		)
		(placement
			(enabled no)
			(sheetname "")
		)
		(fill yes
			(thermal_gap 0.5)
			(thermal_bridge_width 0.5)
			(island_removal_mode 0)
		)
		(polygon
			(pts
				(arc
					(start 273.176238 -312.999882)
					(mid 272.523458 -312.999882)
					(end 273.176238 -312.999882)
				)
			)
		)
	)
	(zone
		(layers "B.Cu" "In9.Cu" "In11.Cu" "In13.Cu" "In15.Cu")
		(hatch none 0.5)
		(connect_pads
			(clearance 0)
		)
		(min_thickness 0.25)
		(keepout
			(tracks not_allowed)
			(vias allowed)
			(pads allowed)
			(copperpour not_allowed)
			(footprints allowed)
		)
		(placement
			(enabled no)
			(sheetname "")
		)
		(fill yes
			(thermal_gap 0.5)
			(thermal_bridge_width 0.5)
			(island_removal_mode 0)
		)
		(polygon
			(pts
				(arc
					(start 83.486752 -345.465146)
					(mid 82.783172 -345.465146)
					(end 83.486752 -345.465146)
				)
			)
		)
	)
	(zone
		(layers "B.Cu" "In9.Cu" "In11.Cu" "In13.Cu" "In15.Cu")
		(hatch none 0.5)
		(connect_pads
			(clearance 0)
		)
		(min_thickness 0.25)
		(keepout
			(tracks not_allowed)
			(vias allowed)
			(pads allowed)
			(copperpour not_allowed)
			(footprints allowed)
		)
		(placement
			(enabled no)
			(sheetname "")
		)
		(fill yes
			(thermal_gap 0.5)
			(thermal_bridge_width 0.5)
			(island_removal_mode 0)
		)
		(polygon
			(pts
				(arc
					(start 172.728382 -354.732082)
					(mid 172.024802 -354.732082)
					(end 172.728382 -354.732082)
				)
			)
		)
	)
	(zone
		(layers "B.Cu" "In9.Cu" "In11.Cu" "In13.Cu" "In15.Cu")
		(hatch none 0.5)
		(connect_pads
			(clearance 0)
		)
		(min_thickness 0.25)
		(keepout
			(tracks not_allowed)
			(vias allowed)
			(pads allowed)
			(copperpour not_allowed)
			(footprints allowed)
		)
		(placement
			(enabled no)
			(sheetname "")
		)
		(fill yes
			(thermal_gap 0.5)
			(thermal_bridge_width 0.5)
			(island_removal_mode 0)
		)
		(polygon
			(pts
				(arc
					(start 175.662336 -30.058868)
					(mid 174.958756 -30.058868)
					(end 175.662336 -30.058868)
				)
			)
		)
	)
	(zone
		(layers "B.Cu" "In9.Cu" "In11.Cu" "In13.Cu" "In15.Cu")
		(hatch none 0.5)
		(connect_pads
			(clearance 0)
		)
		(min_thickness 0.25)
		(keepout
			(tracks not_allowed)
			(vias allowed)
			(pads allowed)
			(copperpour not_allowed)
			(footprints allowed)
		)
		(placement
			(enabled no)
			(sheetname "")
		)
		(fill yes
			(thermal_gap 0.5)
			(thermal_bridge_width 0.5)
			(island_removal_mode 0)
		)
		(polygon
			(pts
				(arc
					(start 274.126198 -301.599854)
					(mid 273.473418 -301.599854)
					(end 274.126198 -301.599854)
				)
			)
		)
	)
	(zone
		(layers "B.Cu" "In9.Cu" "In11.Cu" "In13.Cu" "In15.Cu")
		(hatch none 0.5)
		(connect_pads
			(clearance 0)
		)
		(min_thickness 0.25)
		(keepout
			(tracks not_allowed)
			(vias allowed)
			(pads allowed)
			(copperpour not_allowed)
			(footprints allowed)
		)
		(placement
			(enabled no)
			(sheetname "")
		)
		(fill yes
			(thermal_gap 0.5)
			(thermal_bridge_width 0.5)
			(island_removal_mode 0)
		)
		(polygon
			(pts
				(arc
					(start 340.66988 -379.590046)
					(mid 339.91042 -379.590046)
					(end 340.66988 -379.590046)
				)
			)
		)
	)
	(zone
		(layers "B.Cu" "In9.Cu" "In11.Cu" "In13.Cu" "In15.Cu")
		(hatch none 0.5)
		(connect_pads
			(clearance 0)
		)
		(min_thickness 0.25)
		(keepout
			(tracks not_allowed)
			(vias allowed)
			(pads allowed)
			(copperpour not_allowed)
			(footprints allowed)
		)
		(placement
			(enabled no)
			(sheetname "")
		)
		(fill yes
			(thermal_gap 0.5)
			(thermal_bridge_width 0.5)
			(island_removal_mode 0)
		)
		(polygon
			(pts
				(arc
					(start 85.489542 -405.589994)
					(mid 84.730082 -405.589994)
					(end 85.489542 -405.589994)
				)
			)
		)
	)
	(zone
		(layers "B.Cu" "In9.Cu" "In11.Cu" "In13.Cu" "In15.Cu")
		(hatch none 0.5)
		(connect_pads
			(clearance 0)
		)
		(min_thickness 0.25)
		(keepout
			(tracks not_allowed)
			(vias allowed)
			(pads allowed)
			(copperpour not_allowed)
			(footprints allowed)
		)
		(placement
			(enabled no)
			(sheetname "")
		)
		(fill yes
			(thermal_gap 0.5)
			(thermal_bridge_width 0.5)
			(island_removal_mode 0)
		)
		(polygon
			(pts
				(arc
					(start 32.120078 -351.611438)
					(mid 31.416498 -351.611438)
					(end 32.120078 -351.611438)
				)
			)
		)
	)
	(zone
		(layers "B.Cu" "In9.Cu" "In11.Cu" "In13.Cu" "In15.Cu")
		(hatch none 0.5)
		(connect_pads
			(clearance 0)
		)
		(min_thickness 0.25)
		(keepout
			(tracks not_allowed)
			(vias allowed)
			(pads allowed)
			(copperpour not_allowed)
			(footprints allowed)
		)
		(placement
			(enabled no)
			(sheetname "")
		)
		(fill yes
			(thermal_gap 0.5)
			(thermal_bridge_width 0.5)
			(island_removal_mode 0)
		)
		(polygon
			(pts
				(arc
					(start 390.19353 -348.58579)
					(mid 389.48995 -348.58579)
					(end 390.19353 -348.58579)
				)
			)
		)
	)
	(zone
		(layers "B.Cu" "In9.Cu" "In11.Cu" "In13.Cu" "In15.Cu")
		(hatch none 0.5)
		(connect_pads
			(clearance 0)
		)
		(min_thickness 0.25)
		(keepout
			(tracks not_allowed)
			(vias allowed)
			(pads allowed)
			(copperpour not_allowed)
			(footprints allowed)
		)
		(placement
			(enabled no)
			(sheetname "")
		)
		(fill yes
			(thermal_gap 0.5)
			(thermal_bridge_width 0.5)
			(island_removal_mode 0)
		)
		(polygon
			(pts
				(arc
					(start 81.089754 -405.589994)
					(mid 80.330294 -405.589994)
					(end 81.089754 -405.589994)
				)
			)
		)
	)
	(zone
		(layers "B.Cu" "In9.Cu" "In11.Cu" "In13.Cu" "In15.Cu")
		(hatch none 0.5)
		(connect_pads
			(clearance 0)
		)
		(min_thickness 0.25)
		(keepout
			(tracks not_allowed)
			(vias allowed)
			(pads allowed)
			(copperpour not_allowed)
			(footprints allowed)
		)
		(placement
			(enabled no)
			(sheetname "")
		)
		(fill yes
			(thermal_gap 0.5)
			(thermal_bridge_width 0.5)
			(island_removal_mode 0)
		)
		(polygon
			(pts
				(arc
					(start 268.248892 -351.611438)
					(mid 267.545312 -351.611438)
					(end 268.248892 -351.611438)
				)
			)
		)
	)
	(zone
		(layers "B.Cu" "In9.Cu" "In11.Cu" "In13.Cu" "In15.Cu")
		(hatch none 0.5)
		(connect_pads
			(clearance 0)
		)
		(min_thickness 0.25)
		(keepout
			(tracks not_allowed)
			(vias allowed)
			(pads allowed)
			(copperpour not_allowed)
			(footprints allowed)
		)
		(placement
			(enabled no)
			(sheetname "")
		)
		(fill yes
			(thermal_gap 0.5)
			(thermal_bridge_width 0.5)
			(island_removal_mode 0)
		)
		(polygon
			(pts
				(arc
					(start 127.758698 -354.732082)
					(mid 127.055118 -354.732082)
					(end 127.758698 -354.732082)
				)
			)
		)
	)
	(zone
		(layers "B.Cu" "In9.Cu" "In11.Cu" "In13.Cu" "In15.Cu")
		(hatch none 0.5)
		(connect_pads
			(clearance 0)
		)
		(min_thickness 0.25)
		(keepout
			(tracks not_allowed)
			(vias allowed)
			(pads allowed)
			(copperpour not_allowed)
			(footprints allowed)
		)
		(placement
			(enabled no)
			(sheetname "")
		)
		(fill yes
			(thermal_gap 0.5)
			(thermal_bridge_width 0.5)
			(island_removal_mode 0)
		)
		(polygon
			(pts
				(arc
					(start 428.22622 -311.099962)
					(mid 427.57344 -311.099962)
					(end 428.22622 -311.099962)
				)
			)
		)
	)
	(zone
		(layers "B.Cu" "In9.Cu" "In11.Cu" "In13.Cu" "In15.Cu")
		(hatch none 0.5)
		(connect_pads
			(clearance 0)
		)
		(min_thickness 0.25)
		(keepout
			(tracks not_allowed)
			(vias allowed)
			(pads allowed)
			(copperpour not_allowed)
			(footprints allowed)
		)
		(placement
			(enabled no)
			(sheetname "")
		)
		(fill yes
			(thermal_gap 0.5)
			(thermal_bridge_width 0.5)
			(island_removal_mode 0)
		)
		(polygon
			(pts
				(arc
					(start 133.976618 -345.465146)
					(mid 133.273038 -345.465146)
					(end 133.976618 -345.465146)
				)
			)
		)
	)
	(zone
		(layers "B.Cu" "In9.Cu" "In11.Cu" "In13.Cu" "In15.Cu")
		(hatch none 0.5)
		(connect_pads
			(clearance 0)
		)
		(min_thickness 0.25)
		(keepout
			(tracks not_allowed)
			(vias allowed)
			(pads allowed)
			(copperpour not_allowed)
			(footprints allowed)
		)
		(placement
			(enabled no)
			(sheetname "")
		)
		(fill yes
			(thermal_gap 0.5)
			(thermal_bridge_width 0.5)
			(island_removal_mode 0)
		)
		(polygon
			(pts
				(arc
					(start 301.069502 -374.390158)
					(mid 300.310042 -374.390158)
					(end 301.069502 -374.390158)
				)
			)
		)
	)
	(zone
		(layers "B.Cu" "In9.Cu" "In11.Cu" "In13.Cu" "In15.Cu")
		(hatch none 0.5)
		(connect_pads
			(clearance 0)
		)
		(min_thickness 0.25)
		(keepout
			(tracks not_allowed)
			(vias allowed)
			(pads allowed)
			(copperpour not_allowed)
			(footprints allowed)
		)
		(placement
			(enabled no)
			(sheetname "")
		)
		(fill yes
			(thermal_gap 0.5)
			(thermal_bridge_width 0.5)
			(island_removal_mode 0)
		)
		(polygon
			(pts
				(arc
					(start 35.229038 -354.732082)
					(mid 34.525458 -354.732082)
					(end 35.229038 -354.732082)
				)
			)
		)
	)
	(zone
		(layers "B.Cu" "In9.Cu" "In11.Cu" "In13.Cu" "In15.Cu")
		(hatch none 0.5)
		(connect_pads
			(clearance 0)
		)
		(min_thickness 0.25)
		(keepout
			(tracks not_allowed)
			(vias allowed)
			(pads allowed)
			(copperpour not_allowed)
			(footprints allowed)
		)
		(placement
			(enabled no)
			(sheetname "")
		)
		(fill yes
			(thermal_gap 0.5)
			(thermal_bridge_width 0.5)
			(island_removal_mode 0)
		)
		(polygon
			(pts
				(arc
					(start 41.48963 -401.690078)
					(mid 40.73017 -401.690078)
					(end 41.48963 -401.690078)
				)
			)
		)
	)
	(zone
		(layers "B.Cu" "In9.Cu" "In11.Cu" "In13.Cu" "In15.Cu")
		(hatch none 0.5)
		(connect_pads
			(clearance 0)
		)
		(min_thickness 0.25)
		(keepout
			(tracks not_allowed)
			(vias allowed)
			(pads allowed)
			(copperpour not_allowed)
			(footprints allowed)
		)
		(placement
			(enabled no)
			(sheetname "")
		)
		(fill yes
			(thermal_gap 0.5)
			(thermal_bridge_width 0.5)
			(island_removal_mode 0)
		)
		(polygon
			(pts
				(arc
					(start 394.97635 -273.099784)
					(mid 394.32357 -273.099784)
					(end 394.97635 -273.099784)
				)
			)
		)
	)
	(zone
		(layers "B.Cu" "In9.Cu" "In11.Cu" "In13.Cu" "In15.Cu")
		(hatch none 0.5)
		(connect_pads
			(clearance 0)
		)
		(min_thickness 0.25)
		(keepout
			(tracks not_allowed)
			(vias allowed)
			(pads allowed)
			(copperpour not_allowed)
			(footprints allowed)
		)
		(placement
			(enabled no)
			(sheetname "")
		)
		(fill yes
			(thermal_gap 0.5)
			(thermal_bridge_width 0.5)
			(island_removal_mode 0)
		)
		(polygon
			(pts
				(arc
					(start 267.616432 -29.12237)
					(mid 266.912852 -29.12237)
					(end 267.616432 -29.12237)
				)
			)
		)
	)
	(zone
		(layers "B.Cu" "In9.Cu" "In11.Cu" "In13.Cu" "In15.Cu")
		(hatch none 0.5)
		(connect_pads
			(clearance 0)
		)
		(min_thickness 0.25)
		(keepout
			(tracks not_allowed)
			(vias allowed)
			(pads allowed)
			(copperpour not_allowed)
			(footprints allowed)
		)
		(placement
			(enabled no)
			(sheetname "")
		)
		(fill yes
			(thermal_gap 0.5)
			(thermal_bridge_width 0.5)
			(island_removal_mode 0)
		)
		(polygon
			(pts
				(arc
					(start 168.755822 -348.58579)
					(mid 168.052242 -348.58579)
					(end 168.755822 -348.58579)
				)
			)
		)
	)
	(zone
		(layers "B.Cu" "In9.Cu" "In11.Cu" "In13.Cu" "In15.Cu")
		(hatch none 0.5)
		(connect_pads
			(clearance 0)
		)
		(min_thickness 0.25)
		(keepout
			(tracks not_allowed)
			(vias allowed)
			(pads allowed)
			(copperpour not_allowed)
			(footprints allowed)
		)
		(placement
			(enabled no)
			(sheetname "")
		)
		(fill yes
			(thermal_gap 0.5)
			(thermal_bridge_width 0.5)
			(island_removal_mode 0)
		)
		(polygon
			(pts
				(arc
					(start 48.57623 -273.099784)
					(mid 47.92345 -273.099784)
					(end 48.57623 -273.099784)
				)
			)
		)
	)
	(zone
		(layers "B.Cu" "In9.Cu" "In11.Cu" "In13.Cu" "In15.Cu")
		(hatch none 0.5)
		(connect_pads
			(clearance 0)
		)
		(min_thickness 0.25)
		(keepout
			(tracks not_allowed)
			(vias allowed)
			(pads allowed)
			(copperpour not_allowed)
			(footprints allowed)
		)
		(placement
			(enabled no)
			(sheetname "")
		)
		(fill yes
			(thermal_gap 0.5)
			(thermal_bridge_width 0.5)
			(island_removal_mode 0)
		)
		(polygon
			(pts
				(arc
					(start 338.469732 -380.69012)
					(mid 337.710272 -380.69012)
					(end 338.469732 -380.69012)
				)
			)
		)
	)
	(zone
		(layers "B.Cu" "In9.Cu" "In11.Cu" "In13.Cu" "In15.Cu")
		(hatch none 0.5)
		(connect_pads
			(clearance 0)
		)
		(min_thickness 0.25)
		(keepout
			(tracks not_allowed)
			(vias allowed)
			(pads allowed)
			(copperpour not_allowed)
			(footprints allowed)
		)
		(placement
			(enabled no)
			(sheetname "")
		)
		(fill yes
			(thermal_gap 0.5)
			(thermal_bridge_width 0.5)
			(island_removal_mode 0)
		)
		(polygon
			(pts
				(arc
					(start 428.300642 -348.58579)
					(mid 427.597062 -348.58579)
					(end 428.300642 -348.58579)
				)
			)
		)
	)
	(zone
		(layers "B.Cu" "In9.Cu" "In11.Cu" "In13.Cu" "In15.Cu")
		(hatch none 0.5)
		(connect_pads
			(clearance 0)
		)
		(min_thickness 0.25)
		(keepout
			(tracks not_allowed)
			(vias allowed)
			(pads allowed)
			(copperpour not_allowed)
			(footprints allowed)
		)
		(placement
			(enabled no)
			(sheetname "")
		)
		(fill yes
			(thermal_gap 0.5)
			(thermal_bridge_width 0.5)
			(island_removal_mode 0)
		)
		(polygon
			(pts
				(arc
					(start 275.330412 -351.611438)
					(mid 274.626832 -351.611438)
					(end 275.330412 -351.611438)
				)
			)
		)
	)
	(zone
		(layers "B.Cu" "In9.Cu" "In11.Cu" "In13.Cu" "In15.Cu")
		(hatch none 0.5)
		(connect_pads
			(clearance 0)
		)
		(min_thickness 0.25)
		(keepout
			(tracks not_allowed)
			(vias allowed)
			(pads allowed)
			(copperpour not_allowed)
			(footprints allowed)
		)
		(placement
			(enabled no)
			(sheetname "")
		)
		(fill yes
			(thermal_gap 0.5)
			(thermal_bridge_width 0.5)
			(island_removal_mode 0)
		)
		(polygon
			(pts
				(arc
					(start 290.011612 -357.75773)
					(mid 289.308032 -357.75773)
					(end 290.011612 -357.75773)
				)
			)
		)
	)
	(zone
		(layers "B.Cu" "In9.Cu" "In11.Cu" "In13.Cu" "In15.Cu")
		(hatch none 0.5)
		(connect_pads
			(clearance 0)
		)
		(min_thickness 0.25)
		(keepout
			(tracks not_allowed)
			(vias allowed)
			(pads allowed)
			(copperpour not_allowed)
			(footprints allowed)
		)
		(placement
			(enabled no)
			(sheetname "")
		)
		(fill yes
			(thermal_gap 0.5)
			(thermal_bridge_width 0.5)
			(island_removal_mode 0)
		)
		(polygon
			(pts
				(arc
					(start 300.726094 -312.049922)
					(mid 300.073314 -312.049922)
					(end 300.726094 -312.049922)
				)
			)
		)
	)
	(zone
		(layers "B.Cu" "In9.Cu" "In11.Cu" "In13.Cu" "In15.Cu")
		(hatch none 0.5)
		(connect_pads
			(clearance 0)
		)
		(min_thickness 0.25)
		(keepout
			(tracks not_allowed)
			(vias allowed)
			(pads allowed)
			(copperpour not_allowed)
			(footprints allowed)
		)
		(placement
			(enabled no)
			(sheetname "")
		)
		(fill yes
			(thermal_gap 0.5)
			(thermal_bridge_width 0.5)
			(island_removal_mode 0)
		)
		(polygon
			(pts
				(arc
					(start 73.276206 -313.949842)
					(mid 72.623426 -313.949842)
					(end 73.276206 -313.949842)
				)
			)
		)
	)
	(zone
		(layers "B.Cu" "In9.Cu" "In11.Cu" "In13.Cu" "In15.Cu")
		(hatch none 0.5)
		(connect_pads
			(clearance 0)
		)
		(min_thickness 0.25)
		(keepout
			(tracks not_allowed)
			(vias allowed)
			(pads allowed)
			(copperpour not_allowed)
			(footprints allowed)
		)
		(placement
			(enabled no)
			(sheetname "")
		)
		(fill yes
			(thermal_gap 0.5)
			(thermal_bridge_width 0.5)
			(island_removal_mode 0)
		)
		(polygon
			(pts
				(arc
					(start 125.08992 -405.589994)
					(mid 124.33046 -405.589994)
					(end 125.08992 -405.589994)
				)
			)
		)
	)
	(zone
		(layers "B.Cu" "In9.Cu" "In11.Cu" "In13.Cu" "In15.Cu")
		(hatch none 0.5)
		(connect_pads
			(clearance 0)
		)
		(min_thickness 0.25)
		(keepout
			(tracks not_allowed)
			(vias allowed)
			(pads allowed)
			(copperpour not_allowed)
			(footprints allowed)
		)
		(placement
			(enabled no)
			(sheetname "")
		)
		(fill yes
			(thermal_gap 0.5)
			(thermal_bridge_width 0.5)
			(island_removal_mode 0)
		)
		(polygon
			(pts
				(arc
					(start 57.126378 -274.999958)
					(mid 56.473598 -274.999958)
					(end 57.126378 -274.999958)
				)
			)
		)
	)
	(zone
		(layers "B.Cu" "In9.Cu" "In11.Cu" "In13.Cu" "In15.Cu")
		(hatch none 0.5)
		(connect_pads
			(clearance 0)
		)
		(min_thickness 0.25)
		(keepout
			(tracks not_allowed)
			(vias allowed)
			(pads allowed)
			(copperpour not_allowed)
			(footprints allowed)
		)
		(placement
			(enabled no)
			(sheetname "")
		)
		(fill yes
			(thermal_gap 0.5)
			(thermal_bridge_width 0.5)
			(island_removal_mode 0)
		)
		(polygon
			(pts
				(arc
					(start 400.38401 -354.732082)
					(mid 399.68043 -354.732082)
					(end 400.38401 -354.732082)
				)
			)
		)
	)
	(zone
		(layers "B.Cu" "In9.Cu" "In11.Cu" "In13.Cu" "In15.Cu")
		(hatch none 0.5)
		(connect_pads
			(clearance 0)
		)
		(min_thickness 0.25)
		(keepout
			(tracks not_allowed)
			(vias allowed)
			(pads allowed)
			(copperpour not_allowed)
			(footprints allowed)
		)
		(placement
			(enabled no)
			(sheetname "")
		)
		(fill yes
			(thermal_gap 0.5)
			(thermal_bridge_width 0.5)
			(island_removal_mode 0)
		)
		(polygon
			(pts
				(arc
					(start 81.089754 -378.290074)
					(mid 80.330294 -378.290074)
					(end 81.089754 -378.290074)
				)
			)
		)
	)
	(zone
		(layers "B.Cu" "In9.Cu" "In11.Cu" "In13.Cu" "In15.Cu")
		(hatch none 0.5)
		(connect_pads
			(clearance 0)
		)
		(min_thickness 0.25)
		(keepout
			(tracks not_allowed)
			(vias allowed)
			(pads allowed)
			(copperpour not_allowed)
			(footprints allowed)
		)
		(placement
			(enabled no)
			(sheetname "")
		)
		(fill yes
			(thermal_gap 0.5)
			(thermal_bridge_width 0.5)
			(island_removal_mode 0)
		)
		(polygon
			(pts
				(arc
					(start 43.826176 -308.249828)
					(mid 43.173396 -308.249828)
					(end 43.826176 -308.249828)
				)
			)
		)
	)
	(zone
		(layers "B.Cu" "In9.Cu" "In11.Cu" "In13.Cu" "In15.Cu")
		(hatch none 0.5)
		(connect_pads
			(clearance 0)
		)
		(min_thickness 0.25)
		(keepout
			(tracks not_allowed)
			(vias allowed)
			(pads allowed)
			(copperpour not_allowed)
			(footprints allowed)
		)
		(placement
			(enabled no)
			(sheetname "")
		)
		(fill yes
			(thermal_gap 0.5)
			(thermal_bridge_width 0.5)
			(island_removal_mode 0)
		)
		(polygon
			(pts
				(arc
					(start 293.12616 -311.099962)
					(mid 292.47338 -311.099962)
					(end 293.12616 -311.099962)
				)
			)
		)
	)
	(zone
		(layers "B.Cu" "In9.Cu" "In11.Cu" "In13.Cu" "In15.Cu")
		(hatch none 0.5)
		(connect_pads
			(clearance 0)
		)
		(min_thickness 0.25)
		(keepout
			(tracks not_allowed)
			(vias allowed)
			(pads allowed)
			(copperpour not_allowed)
			(footprints allowed)
		)
		(placement
			(enabled no)
			(sheetname "")
		)
		(fill yes
			(thermal_gap 0.5)
			(thermal_bridge_width 0.5)
			(island_removal_mode 0)
		)
		(polygon
			(pts
				(arc
					(start 37.089842 -375.69013)
					(mid 36.330382 -375.69013)
					(end 37.089842 -375.69013)
				)
			)
		)
	)
	(zone
		(layers "B.Cu" "In9.Cu" "In11.Cu" "In13.Cu" "In15.Cu")
		(hatch none 0.5)
		(connect_pads
			(clearance 0)
		)
		(min_thickness 0.25)
		(keepout
			(tracks not_allowed)
			(vias allowed)
			(pads allowed)
			(copperpour not_allowed)
			(footprints allowed)
		)
		(placement
			(enabled no)
			(sheetname "")
		)
		(fill yes
			(thermal_gap 0.5)
			(thermal_bridge_width 0.5)
			(island_removal_mode 0)
		)
		(polygon
			(pts
				(arc
					(start 175.689768 -398.890236)
					(mid 174.930308 -398.890236)
					(end 175.689768 -398.890236)
				)
			)
		)
	)
	(zone
		(layers "B.Cu" "In9.Cu" "In11.Cu" "In13.Cu" "In15.Cu")
		(hatch none 0.5)
		(connect_pads
			(clearance 0)
		)
		(min_thickness 0.25)
		(keepout
			(tracks not_allowed)
			(vias allowed)
			(pads allowed)
			(copperpour not_allowed)
			(footprints allowed)
		)
		(placement
			(enabled no)
			(sheetname "")
		)
		(fill yes
			(thermal_gap 0.5)
			(thermal_bridge_width 0.5)
			(island_removal_mode 0)
		)
		(polygon
			(pts
				(arc
					(start 128.622298 -345.465146)
					(mid 127.918718 -345.465146)
					(end 128.622298 -345.465146)
				)
			)
		)
	)
	(zone
		(layers "B.Cu" "In9.Cu" "In11.Cu" "In13.Cu" "In15.Cu")
		(hatch none 0.5)
		(connect_pads
			(clearance 0)
		)
		(min_thickness 0.25)
		(keepout
			(tracks not_allowed)
			(vias allowed)
			(pads allowed)
			(copperpour not_allowed)
			(footprints allowed)
		)
		(placement
			(enabled no)
			(sheetname "")
		)
		(fill yes
			(thermal_gap 0.5)
			(thermal_bridge_width 0.5)
			(island_removal_mode 0)
		)
		(polygon
			(pts
				(arc
					(start 407.862278 -33.65881)
					(mid 407.158698 -33.65881)
					(end 407.862278 -33.65881)
				)
			)
		)
	)
	(zone
		(layers "B.Cu" "In9.Cu" "In11.Cu" "In13.Cu" "In15.Cu")
		(hatch none 0.5)
		(connect_pads
			(clearance 0)
		)
		(min_thickness 0.25)
		(keepout
			(tracks not_allowed)
			(vias allowed)
			(pads allowed)
			(copperpour not_allowed)
			(footprints allowed)
		)
		(placement
			(enabled no)
			(sheetname "")
		)
		(fill yes
			(thermal_gap 0.5)
			(thermal_bridge_width 0.5)
			(island_removal_mode 0)
		)
		(polygon
			(pts
				(arc
					(start 67.576192 -312.999882)
					(mid 66.923412 -312.999882)
					(end 67.576192 -312.999882)
				)
			)
		)
	)
	(zone
		(layers "B.Cu" "In9.Cu" "In11.Cu" "In13.Cu" "In15.Cu")
		(hatch none 0.5)
		(connect_pads
			(clearance 0)
		)
		(min_thickness 0.25)
		(keepout
			(tracks not_allowed)
			(vias allowed)
			(pads allowed)
			(copperpour not_allowed)
			(footprints allowed)
		)
		(placement
			(enabled no)
			(sheetname "")
		)
		(fill yes
			(thermal_gap 0.5)
			(thermal_bridge_width 0.5)
			(island_removal_mode 0)
		)
		(polygon
			(pts
				(arc
					(start 293.61638 -29.12237)
					(mid 292.9128 -29.12237)
					(end 293.61638 -29.12237)
				)
			)
		)
	)
	(zone
		(layers "B.Cu" "In9.Cu" "In11.Cu" "In13.Cu" "In15.Cu")
		(hatch none 0.5)
		(connect_pads
			(clearance 0)
		)
		(min_thickness 0.25)
		(keepout
			(tracks not_allowed)
			(vias allowed)
			(pads allowed)
			(copperpour not_allowed)
			(footprints allowed)
		)
		(placement
			(enabled no)
			(sheetname "")
		)
		(fill yes
			(thermal_gap 0.5)
			(thermal_bridge_width 0.5)
			(island_removal_mode 0)
		)
		(polygon
			(pts
				(arc
					(start 164.68979 -397.790162)
					(mid 163.93033 -397.790162)
					(end 164.68979 -397.790162)
				)
			)
		)
	)
	(zone
		(layers "B.Cu" "In9.Cu" "In11.Cu" "In13.Cu" "In15.Cu")
		(hatch none 0.5)
		(connect_pads
			(clearance 0)
		)
		(min_thickness 0.25)
		(keepout
			(tracks not_allowed)
			(vias allowed)
			(pads allowed)
			(copperpour not_allowed)
			(footprints allowed)
		)
		(placement
			(enabled no)
			(sheetname "")
		)
		(fill yes
			(thermal_gap 0.5)
			(thermal_bridge_width 0.5)
			(island_removal_mode 0)
		)
		(polygon
			(pts
				(arc
					(start 191.276478 -306.349908)
					(mid 190.623698 -306.349908)
					(end 191.276478 -306.349908)
				)
			)
		)
	)
	(zone
		(layers "B.Cu" "In9.Cu" "In11.Cu" "In13.Cu" "In15.Cu")
		(hatch none 0.5)
		(connect_pads
			(clearance 0)
		)
		(min_thickness 0.25)
		(keepout
			(tracks not_allowed)
			(vias allowed)
			(pads allowed)
			(copperpour not_allowed)
			(footprints allowed)
		)
		(placement
			(enabled no)
			(sheetname "")
		)
		(fill yes
			(thermal_gap 0.5)
			(thermal_bridge_width 0.5)
			(island_removal_mode 0)
		)
		(polygon
			(pts
				(arc
					(start 425.37634 -309.199788)
					(mid 424.72356 -309.199788)
					(end 425.37634 -309.199788)
				)
			)
		)
	)
	(zone
		(layers "B.Cu" "In9.Cu" "In11.Cu" "In13.Cu" "In15.Cu")
		(hatch none 0.5)
		(connect_pads
			(clearance 0)
		)
		(min_thickness 0.25)
		(keepout
			(tracks not_allowed)
			(vias allowed)
			(pads allowed)
			(copperpour not_allowed)
			(footprints allowed)
		)
		(placement
			(enabled no)
			(sheetname "")
		)
		(fill yes
			(thermal_gap 0.5)
			(thermal_bridge_width 0.5)
			(island_removal_mode 0)
		)
		(polygon
			(pts
				(arc
					(start 394.16609 -342.439498)
					(mid 393.46251 -342.439498)
					(end 394.16609 -342.439498)
				)
			)
		)
	)
	(zone
		(layers "B.Cu" "In9.Cu" "In11.Cu" "In13.Cu" "In15.Cu")
		(hatch none 0.5)
		(connect_pads
			(clearance 0)
		)
		(min_thickness 0.25)
		(keepout
			(tracks not_allowed)
			(vias allowed)
			(pads allowed)
			(copperpour not_allowed)
			(footprints allowed)
		)
		(placement
			(enabled no)
			(sheetname "")
		)
		(fill yes
			(thermal_gap 0.5)
			(thermal_bridge_width 0.5)
			(island_removal_mode 0)
		)
		(polygon
			(pts
				(arc
					(start 378.62129 -351.611438)
					(mid 377.91771 -351.611438)
					(end 378.62129 -351.611438)
				)
			)
		)
	)
	(zone
		(layers "B.Cu" "In9.Cu" "In11.Cu" "In13.Cu" "In15.Cu")
		(hatch none 0.5)
		(connect_pads
			(clearance 0)
		)
		(min_thickness 0.25)
		(keepout
			(tracks not_allowed)
			(vias allowed)
			(pads allowed)
			(copperpour not_allowed)
			(footprints allowed)
		)
		(placement
			(enabled no)
			(sheetname "")
		)
		(fill yes
			(thermal_gap 0.5)
			(thermal_bridge_width 0.5)
			(island_removal_mode 0)
		)
		(polygon
			(pts
				(arc
					(start 190.518542 -342.439498)
					(mid 189.814962 -342.439498)
					(end 190.518542 -342.439498)
				)
			)
		)
	)
	(zone
		(layers "B.Cu" "In9.Cu" "In11.Cu" "In13.Cu" "In15.Cu")
		(hatch none 0.5)
		(connect_pads
			(clearance 0)
		)
		(min_thickness 0.25)
		(keepout
			(tracks not_allowed)
			(vias allowed)
			(pads allowed)
			(copperpour not_allowed)
			(footprints allowed)
		)
		(placement
			(enabled no)
			(sheetname "")
		)
		(fill yes
			(thermal_gap 0.5)
			(thermal_bridge_width 0.5)
			(island_removal_mode 0)
		)
		(polygon
			(pts
				(arc
					(start 173.226476 -275.949918)
					(mid 172.573696 -275.949918)
					(end 173.226476 -275.949918)
				)
			)
		)
	)
	(zone
		(layers "B.Cu" "In9.Cu" "In11.Cu" "In13.Cu" "In15.Cu")
		(hatch none 0.5)
		(connect_pads
			(clearance 0)
		)
		(min_thickness 0.25)
		(keepout
			(tracks not_allowed)
			(vias allowed)
			(pads allowed)
			(copperpour not_allowed)
			(footprints allowed)
		)
		(placement
			(enabled no)
			(sheetname "")
		)
		(fill yes
			(thermal_gap 0.5)
			(thermal_bridge_width 0.5)
			(island_removal_mode 0)
		)
		(polygon
			(pts
				(arc
					(start 175.126396 -274.999958)
					(mid 174.473616 -274.999958)
					(end 175.126396 -274.999958)
				)
			)
		)
	)
	(zone
		(layers "B.Cu" "In9.Cu" "In11.Cu" "In13.Cu" "In15.Cu")
		(hatch none 0.5)
		(connect_pads
			(clearance 0)
		)
		(min_thickness 0.25)
		(keepout
			(tracks not_allowed)
			(vias allowed)
			(pads allowed)
			(copperpour not_allowed)
			(footprints allowed)
		)
		(placement
			(enabled no)
			(sheetname "")
		)
		(fill yes
			(thermal_gap 0.5)
			(thermal_bridge_width 0.5)
			(island_removal_mode 0)
		)
		(polygon
			(pts
				(arc
					(start 357.716582 -29.12237)
					(mid 357.013002 -29.12237)
					(end 357.716582 -29.12237)
				)
			)
		)
	)
	(zone
		(layers "B.Cu" "In9.Cu" "In11.Cu" "In13.Cu" "In15.Cu")
		(hatch none 0.5)
		(connect_pads
			(clearance 0)
		)
		(min_thickness 0.25)
		(keepout
			(tracks not_allowed)
			(vias allowed)
			(pads allowed)
			(copperpour not_allowed)
			(footprints allowed)
		)
		(placement
			(enabled no)
			(sheetname "")
		)
		(fill yes
			(thermal_gap 0.5)
			(thermal_bridge_width 0.5)
			(island_removal_mode 0)
		)
		(polygon
			(pts
				(arc
					(start 428.300642 -351.611438)
					(mid 427.597062 -351.611438)
					(end 428.300642 -351.611438)
				)
			)
		)
	)
	(zone
		(layers "B.Cu" "In9.Cu" "In11.Cu" "In13.Cu" "In15.Cu")
		(hatch none 0.5)
		(connect_pads
			(clearance 0)
		)
		(min_thickness 0.25)
		(keepout
			(tracks not_allowed)
			(vias allowed)
			(pads allowed)
			(copperpour not_allowed)
			(footprints allowed)
		)
		(placement
			(enabled no)
			(sheetname "")
		)
		(fill yes
			(thermal_gap 0.5)
			(thermal_bridge_width 0.5)
			(island_removal_mode 0)
		)
		(polygon
			(pts
				(arc
					(start 163.401502 -351.611438)
					(mid 162.697922 -351.611438)
					(end 163.401502 -351.611438)
				)
			)
		)
	)
	(zone
		(layers "B.Cu" "In9.Cu" "In11.Cu" "In13.Cu" "In15.Cu")
		(hatch none 0.5)
		(connect_pads
			(clearance 0)
		)
		(min_thickness 0.25)
		(keepout
			(tracks not_allowed)
			(vias allowed)
			(pads allowed)
			(copperpour not_allowed)
			(footprints allowed)
		)
		(placement
			(enabled no)
			(sheetname "")
		)
		(fill yes
			(thermal_gap 0.5)
			(thermal_bridge_width 0.5)
			(island_removal_mode 0)
		)
		(polygon
			(pts
				(arc
					(start 412.755842 -357.75773)
					(mid 412.052262 -357.75773)
					(end 412.755842 -357.75773)
				)
			)
		)
	)
	(zone
		(layers "B.Cu" "In9.Cu" "In11.Cu" "In13.Cu" "In15.Cu")
		(hatch none 0.5)
		(connect_pads
			(clearance 0)
		)
		(min_thickness 0.25)
		(keepout
			(tracks not_allowed)
			(vias allowed)
			(pads allowed)
			(copperpour not_allowed)
			(footprints allowed)
		)
		(placement
			(enabled no)
			(sheetname "")
		)
		(fill yes
			(thermal_gap 0.5)
			(thermal_bridge_width 0.5)
			(island_removal_mode 0)
		)
		(polygon
			(pts
				(arc
					(start 296.926254 -311.099962)
					(mid 296.273474 -311.099962)
					(end 296.926254 -311.099962)
				)
			)
		)
	)
	(zone
		(layers "B.Cu" "In9.Cu" "In11.Cu" "In13.Cu" "In15.Cu")
		(hatch none 0.5)
		(connect_pads
			(clearance 0)
		)
		(min_thickness 0.25)
		(keepout
			(tracks not_allowed)
			(vias allowed)
			(pads allowed)
			(copperpour not_allowed)
			(footprints allowed)
		)
		(placement
			(enabled no)
			(sheetname "")
		)
		(fill yes
			(thermal_gap 0.5)
			(thermal_bridge_width 0.5)
			(island_removal_mode 0)
		)
		(polygon
			(pts
				(arc
					(start 34.889694 -375.490232)
					(mid 34.130234 -375.490232)
					(end 34.889694 -375.490232)
				)
			)
		)
	)
	(zone
		(layers "B.Cu" "In9.Cu" "In11.Cu" "In13.Cu" "In15.Cu")
		(hatch none 0.5)
		(connect_pads
			(clearance 0)
		)
		(min_thickness 0.25)
		(keepout
			(tracks not_allowed)
			(vias allowed)
			(pads allowed)
			(copperpour not_allowed)
			(footprints allowed)
		)
		(placement
			(enabled no)
			(sheetname "")
		)
		(fill yes
			(thermal_gap 0.5)
			(thermal_bridge_width 0.5)
			(island_removal_mode 0)
		)
		(polygon
			(pts
				(arc
					(start 85.562186 -34.52241)
					(mid 84.858606 -34.52241)
					(end 85.562186 -34.52241)
				)
			)
		)
	)
	(zone
		(layers "B.Cu" "In9.Cu" "In11.Cu" "In13.Cu" "In15.Cu")
		(hatch none 0.5)
		(connect_pads
			(clearance 0)
		)
		(min_thickness 0.25)
		(keepout
			(tracks not_allowed)
			(vias allowed)
			(pads allowed)
			(copperpour not_allowed)
			(footprints allowed)
		)
		(placement
			(enabled no)
			(sheetname "")
		)
		(fill yes
			(thermal_gap 0.5)
			(thermal_bridge_width 0.5)
			(island_removal_mode 0)
		)
		(polygon
			(pts
				(arc
					(start 294.469566 -376.790204)
					(mid 293.710106 -376.790204)
					(end 294.469566 -376.790204)
				)
			)
		)
	)
	(zone
		(layers "B.Cu" "In9.Cu" "In11.Cu" "In13.Cu" "In15.Cu")
		(hatch none 0.5)
		(connect_pads
			(clearance 0)
		)
		(min_thickness 0.25)
		(keepout
			(tracks not_allowed)
			(vias allowed)
			(pads allowed)
			(copperpour not_allowed)
			(footprints allowed)
		)
		(placement
			(enabled no)
			(sheetname "")
		)
		(fill yes
			(thermal_gap 0.5)
			(thermal_bridge_width 0.5)
			(island_removal_mode 0)
		)
		(polygon
			(pts
				(arc
					(start 78.132432 -354.732082)
					(mid 77.428852 -354.732082)
					(end 78.132432 -354.732082)
				)
			)
		)
	)
	(zone
		(layers "B.Cu" "In9.Cu" "In11.Cu" "In13.Cu" "In15.Cu")
		(hatch none 0.5)
		(connect_pads
			(clearance 0)
		)
		(min_thickness 0.25)
		(keepout
			(tracks not_allowed)
			(vias allowed)
			(pads allowed)
			(copperpour not_allowed)
			(footprints allowed)
		)
		(placement
			(enabled no)
			(sheetname "")
		)
		(fill yes
			(thermal_gap 0.5)
			(thermal_bridge_width 0.5)
			(island_removal_mode 0)
		)
		(polygon
			(pts
				(arc
					(start 424.269662 -371.790214)
					(mid 423.510202 -371.790214)
					(end 424.269662 -371.790214)
				)
			)
		)
	)
	(zone
		(layers "B.Cu" "In9.Cu" "In11.Cu" "In13.Cu" "In15.Cu")
		(hatch none 0.5)
		(connect_pads
			(clearance 0)
		)
		(min_thickness 0.25)
		(keepout
			(tracks not_allowed)
			(vias allowed)
			(pads allowed)
			(copperpour not_allowed)
			(footprints allowed)
		)
		(placement
			(enabled no)
			(sheetname "")
		)
		(fill yes
			(thermal_gap 0.5)
			(thermal_bridge_width 0.5)
			(island_removal_mode 0)
		)
		(polygon
			(pts
				(arc
					(start 165.626288 -274.999958)
					(mid 164.973508 -274.999958)
					(end 165.626288 -274.999958)
				)
			)
		)
	)
	(zone
		(layers "B.Cu" "In9.Cu" "In11.Cu" "In13.Cu" "In15.Cu")
		(hatch none 0.5)
		(connect_pads
			(clearance 0)
		)
		(min_thickness 0.25)
		(keepout
			(tracks not_allowed)
			(vias allowed)
			(pads allowed)
			(copperpour not_allowed)
			(footprints allowed)
		)
		(placement
			(enabled no)
			(sheetname "")
		)
		(fill yes
			(thermal_gap 0.5)
			(thermal_bridge_width 0.5)
			(island_removal_mode 0)
		)
		(polygon
			(pts
				(arc
					(start 125.51664 -28.25877)
					(mid 124.81306 -28.25877)
					(end 125.51664 -28.25877)
				)
			)
		)
	)
	(zone
		(layers "B.Cu" "In9.Cu" "In11.Cu" "In13.Cu" "In15.Cu")
		(hatch none 0.5)
		(connect_pads
			(clearance 0)
		)
		(min_thickness 0.25)
		(keepout
			(tracks not_allowed)
			(vias allowed)
			(pads allowed)
			(copperpour not_allowed)
			(footprints allowed)
		)
		(placement
			(enabled no)
			(sheetname "")
		)
		(fill yes
			(thermal_gap 0.5)
			(thermal_bridge_width 0.5)
			(island_removal_mode 0)
		)
		(polygon
			(pts
				(arc
					(start 317.762128 -30.058868)
					(mid 317.058548 -30.058868)
					(end 317.762128 -30.058868)
				)
			)
		)
	)
	(zone
		(layers "B.Cu" "In9.Cu" "In11.Cu" "In13.Cu" "In15.Cu")
		(hatch none 0.5)
		(connect_pads
			(clearance 0)
		)
		(min_thickness 0.25)
		(keepout
			(tracks not_allowed)
			(vias allowed)
			(pads allowed)
			(copperpour not_allowed)
			(footprints allowed)
		)
		(placement
			(enabled no)
			(sheetname "")
		)
		(fill yes
			(thermal_gap 0.5)
			(thermal_bridge_width 0.5)
			(island_removal_mode 0)
		)
		(polygon
			(pts
				(arc
					(start 46.67631 -273.099784)
					(mid 46.02353 -273.099784)
					(end 46.67631 -273.099784)
				)
			)
		)
	)
	(zone
		(layers "B.Cu" "In9.Cu" "In11.Cu" "In13.Cu" "In15.Cu")
		(hatch none 0.5)
		(connect_pads
			(clearance 0)
		)
		(min_thickness 0.25)
		(keepout
			(tracks not_allowed)
			(vias allowed)
			(pads allowed)
			(copperpour not_allowed)
			(footprints allowed)
		)
		(placement
			(enabled no)
			(sheetname "")
		)
		(fill yes
			(thermal_gap 0.5)
			(thermal_bridge_width 0.5)
			(island_removal_mode 0)
		)
		(polygon
			(pts
				(arc
					(start 185.164222 -342.439498)
					(mid 184.460642 -342.439498)
					(end 185.164222 -342.439498)
				)
			)
		)
	)
	(zone
		(layers "B.Cu" "In9.Cu" "In11.Cu" "In13.Cu" "In15.Cu")
		(hatch none 0.5)
		(connect_pads
			(clearance 0)
		)
		(min_thickness 0.25)
		(keepout
			(tracks not_allowed)
			(vias allowed)
			(pads allowed)
			(copperpour not_allowed)
			(footprints allowed)
		)
		(placement
			(enabled no)
			(sheetname "")
		)
		(fill yes
			(thermal_gap 0.5)
			(thermal_bridge_width 0.5)
			(island_removal_mode 0)
		)
		(polygon
			(pts
				(arc
					(start 301.069502 -375.69013)
					(mid 300.310042 -375.69013)
					(end 301.069502 -375.69013)
				)
			)
		)
	)
	(zone
		(layers "B.Cu" "In9.Cu" "In11.Cu" "In13.Cu" "In15.Cu")
		(hatch none 0.5)
		(connect_pads
			(clearance 0)
		)
		(min_thickness 0.25)
		(keepout
			(tracks not_allowed)
			(vias allowed)
			(pads allowed)
			(copperpour not_allowed)
			(footprints allowed)
		)
		(placement
			(enabled no)
			(sheetname "")
		)
		(fill yes
			(thermal_gap 0.5)
			(thermal_bridge_width 0.5)
			(island_removal_mode 0)
		)
		(polygon
			(pts
				(arc
					(start 194.126358 -311.099962)
					(mid 193.473578 -311.099962)
					(end 194.126358 -311.099962)
				)
			)
		)
	)
	(zone
		(layers "B.Cu" "In9.Cu" "In11.Cu" "In13.Cu" "In15.Cu")
		(hatch none 0.5)
		(connect_pads
			(clearance 0)
		)
		(min_thickness 0.25)
		(keepout
			(tracks not_allowed)
			(vias allowed)
			(pads allowed)
			(copperpour not_allowed)
			(footprints allowed)
		)
		(placement
			(enabled no)
			(sheetname "")
		)
		(fill yes
			(thermal_gap 0.5)
			(thermal_bridge_width 0.5)
			(island_removal_mode 0)
		)
		(polygon
			(pts
				(arc
					(start 83.486752 -354.732082)
					(mid 82.783172 -354.732082)
					(end 83.486752 -354.732082)
				)
			)
		)
	)
	(zone
		(layers "B.Cu" "In9.Cu" "In11.Cu" "In13.Cu" "In15.Cu")
		(hatch none 0.5)
		(connect_pads
			(clearance 0)
		)
		(min_thickness 0.25)
		(keepout
			(tracks not_allowed)
			(vias allowed)
			(pads allowed)
			(copperpour not_allowed)
			(footprints allowed)
		)
		(placement
			(enabled no)
			(sheetname "")
		)
		(fill yes
			(thermal_gap 0.5)
			(thermal_bridge_width 0.5)
			(island_removal_mode 0)
		)
		(polygon
			(pts
				(arc
					(start 323.045074 -357.75773)
					(mid 322.341494 -357.75773)
					(end 323.045074 -357.75773)
				)
			)
		)
	)
	(zone
		(layers "B.Cu" "In9.Cu" "In11.Cu" "In13.Cu" "In15.Cu")
		(hatch none 0.5)
		(connect_pads
			(clearance 0)
		)
		(min_thickness 0.25)
		(keepout
			(tracks not_allowed)
			(vias allowed)
			(pads allowed)
			(copperpour not_allowed)
			(footprints allowed)
		)
		(placement
			(enabled no)
			(sheetname "")
		)
		(fill yes
			(thermal_gap 0.5)
			(thermal_bridge_width 0.5)
			(island_removal_mode 0)
		)
		(polygon
			(pts
				(arc
					(start 418.973762 -345.465146)
					(mid 418.270182 -345.465146)
					(end 418.973762 -345.465146)
				)
			)
		)
	)
	(zone
		(layers "B.Cu" "In9.Cu" "In11.Cu" "In13.Cu" "In15.Cu")
		(hatch none 0.5)
		(connect_pads
			(clearance 0)
		)
		(min_thickness 0.25)
		(keepout
			(tracks not_allowed)
			(vias allowed)
			(pads allowed)
			(copperpour not_allowed)
			(footprints allowed)
		)
		(placement
			(enabled no)
			(sheetname "")
		)
		(fill yes
			(thermal_gap 0.5)
			(thermal_bridge_width 0.5)
			(island_removal_mode 0)
		)
		(polygon
			(pts
				(arc
					(start 193.627502 -348.58579)
					(mid 192.923922 -348.58579)
					(end 193.627502 -348.58579)
				)
			)
		)
	)
	(zone
		(layers "B.Cu" "In9.Cu" "In11.Cu" "In13.Cu" "In15.Cu")
		(hatch none 0.5)
		(connect_pads
			(clearance 0)
		)
		(min_thickness 0.25)
		(keepout
			(tracks not_allowed)
			(vias allowed)
			(pads allowed)
			(copperpour not_allowed)
			(footprints allowed)
		)
		(placement
			(enabled no)
			(sheetname "")
		)
		(fill yes
			(thermal_gap 0.5)
			(thermal_bridge_width 0.5)
			(island_removal_mode 0)
		)
		(polygon
			(pts
				(arc
					(start 49.52619 -275.949918)
					(mid 48.87341 -275.949918)
					(end 49.52619 -275.949918)
				)
			)
		)
	)
	(zone
		(layers "B.Cu" "In9.Cu" "In11.Cu" "In13.Cu" "In15.Cu")
		(hatch none 0.5)
		(connect_pads
			(clearance 0)
		)
		(min_thickness 0.25)
		(keepout
			(tracks not_allowed)
			(vias allowed)
			(pads allowed)
			(copperpour not_allowed)
			(footprints allowed)
		)
		(placement
			(enabled no)
			(sheetname "")
		)
		(fill yes
			(thermal_gap 0.5)
			(thermal_bridge_width 0.5)
			(island_removal_mode 0)
		)
		(polygon
			(pts
				(arc
					(start 171.326302 -275.949918)
					(mid 170.673522 -275.949918)
					(end 171.326302 -275.949918)
				)
			)
		)
	)
	(zone
		(layers "B.Cu" "In9.Cu" "In11.Cu" "In13.Cu" "In15.Cu")
		(hatch none 0.5)
		(connect_pads
			(clearance 0)
		)
		(min_thickness 0.25)
		(keepout
			(tracks not_allowed)
			(vias allowed)
			(pads allowed)
			(copperpour not_allowed)
			(footprints allowed)
		)
		(placement
			(enabled no)
			(sheetname "")
		)
		(fill yes
			(thermal_gap 0.5)
			(thermal_bridge_width 0.5)
			(island_removal_mode 0)
		)
		(polygon
			(pts
				(arc
					(start 191.276478 -308.249828)
					(mid 190.623698 -308.249828)
					(end 191.276478 -308.249828)
				)
			)
		)
	)
	(zone
		(layers "B.Cu" "In9.Cu" "In11.Cu" "In13.Cu" "In15.Cu")
		(hatch none 0.5)
		(connect_pads
			(clearance 0)
		)
		(min_thickness 0.25)
		(keepout
			(tracks not_allowed)
			(vias allowed)
			(pads allowed)
			(copperpour not_allowed)
			(footprints allowed)
		)
		(placement
			(enabled no)
			(sheetname "")
		)
		(fill yes
			(thermal_gap 0.5)
			(thermal_bridge_width 0.5)
			(island_removal_mode 0)
		)
		(polygon
			(pts
				(arc
					(start 169.426382 -275.949918)
					(mid 168.773602 -275.949918)
					(end 169.426382 -275.949918)
				)
			)
		)
	)
	(zone
		(layers "B.Cu" "In9.Cu" "In11.Cu" "In13.Cu" "In15.Cu")
		(hatch none 0.5)
		(connect_pads
			(clearance 0)
		)
		(min_thickness 0.25)
		(keepout
			(tracks not_allowed)
			(vias allowed)
			(pads allowed)
			(copperpour not_allowed)
			(footprints allowed)
		)
		(placement
			(enabled no)
			(sheetname "")
		)
		(fill yes
			(thermal_gap 0.5)
			(thermal_bridge_width 0.5)
			(island_removal_mode 0)
		)
		(polygon
			(pts
				(arc
					(start 285.526226 -275.949918)
					(mid 284.873446 -275.949918)
					(end 285.526226 -275.949918)
				)
			)
		)
	)
	(zone
		(layers "B.Cu" "In9.Cu" "In11.Cu" "In13.Cu" "In15.Cu")
		(hatch none 0.5)
		(connect_pads
			(clearance 0)
		)
		(min_thickness 0.25)
		(keepout
			(tracks not_allowed)
			(vias allowed)
			(pads allowed)
			(copperpour not_allowed)
			(footprints allowed)
		)
		(placement
			(enabled no)
			(sheetname "")
		)
		(fill yes
			(thermal_gap 0.5)
			(thermal_bridge_width 0.5)
			(island_removal_mode 0)
		)
		(polygon
			(pts
				(arc
					(start 315.963554 -342.439498)
					(mid 315.259974 -342.439498)
					(end 315.963554 -342.439498)
				)
			)
		)
	)
	(zone
		(layers "B.Cu" "In9.Cu" "In11.Cu" "In13.Cu" "In15.Cu")
		(hatch none 0.5)
		(connect_pads
			(clearance 0)
		)
		(min_thickness 0.25)
		(keepout
			(tracks not_allowed)
			(vias allowed)
			(pads allowed)
			(copperpour not_allowed)
			(footprints allowed)
		)
		(placement
			(enabled no)
			(sheetname "")
		)
		(fill yes
			(thermal_gap 0.5)
			(thermal_bridge_width 0.5)
			(island_removal_mode 0)
		)
		(polygon
			(pts
				(arc
					(start 167.526462 -275.949918)
					(mid 166.873682 -275.949918)
					(end 167.526462 -275.949918)
				)
			)
		)
	)
	(zone
		(layers "B.Cu" "In9.Cu" "In11.Cu" "In13.Cu" "In15.Cu")
		(hatch none 0.5)
		(connect_pads
			(clearance 0)
		)
		(min_thickness 0.25)
		(keepout
			(tracks not_allowed)
			(vias allowed)
			(pads allowed)
			(copperpour not_allowed)
			(footprints allowed)
		)
		(placement
			(enabled no)
			(sheetname "")
		)
		(fill yes
			(thermal_gap 0.5)
			(thermal_bridge_width 0.5)
			(island_removal_mode 0)
		)
		(polygon
			(pts
				(arc
					(start 171.289726 -372.890034)
					(mid 170.530266 -372.890034)
					(end 171.289726 -372.890034)
				)
			)
		)
	)
	(zone
		(layers "B.Cu" "In9.Cu" "In11.Cu" "In13.Cu" "In15.Cu")
		(hatch none 0.5)
		(connect_pads
			(clearance 0)
		)
		(min_thickness 0.25)
		(keepout
			(tracks not_allowed)
			(vias allowed)
			(pads allowed)
			(copperpour not_allowed)
			(footprints allowed)
		)
		(placement
			(enabled no)
			(sheetname "")
		)
		(fill yes
			(thermal_gap 0.5)
			(thermal_bridge_width 0.5)
			(island_removal_mode 0)
		)
		(polygon
			(pts
				(arc
					(start 413.976312 -312.999882)
					(mid 413.323532 -312.999882)
					(end 413.976312 -312.999882)
				)
			)
		)
	)
	(zone
		(layers "B.Cu" "In9.Cu" "In11.Cu" "In13.Cu" "In15.Cu")
		(hatch none 0.5)
		(connect_pads
			(clearance 0)
		)
		(min_thickness 0.25)
		(keepout
			(tracks not_allowed)
			(vias allowed)
			(pads allowed)
			(copperpour not_allowed)
			(footprints allowed)
		)
		(placement
			(enabled no)
			(sheetname "")
		)
		(fill yes
			(thermal_gap 0.5)
			(thermal_bridge_width 0.5)
			(island_removal_mode 0)
		)
		(polygon
			(pts
				(arc
					(start 72.326246 -311.099962)
					(mid 71.673466 -311.099962)
					(end 72.326246 -311.099962)
				)
			)
		)
	)
	(zone
		(layers "B.Cu" "In9.Cu" "In11.Cu" "In13.Cu" "In15.Cu")
		(hatch none 0.5)
		(connect_pads
			(clearance 0)
		)
		(min_thickness 0.25)
		(keepout
			(tracks not_allowed)
			(vias allowed)
			(pads allowed)
			(copperpour not_allowed)
			(footprints allowed)
		)
		(placement
			(enabled no)
			(sheetname "")
		)
		(fill yes
			(thermal_gap 0.5)
			(thermal_bridge_width 0.5)
			(island_removal_mode 0)
		)
		(polygon
			(pts
				(arc
					(start 389.06958 -382.18999)
					(mid 388.31012 -382.18999)
					(end 389.06958 -382.18999)
				)
			)
		)
	)
	(zone
		(layers "B.Cu" "In9.Cu" "In11.Cu" "In13.Cu" "In15.Cu")
		(hatch none 0.5)
		(connect_pads
			(clearance 0)
		)
		(min_thickness 0.25)
		(keepout
			(tracks not_allowed)
			(vias allowed)
			(pads allowed)
			(copperpour not_allowed)
			(footprints allowed)
		)
		(placement
			(enabled no)
			(sheetname "")
		)
		(fill yes
			(thermal_gap 0.5)
			(thermal_bridge_width 0.5)
			(island_removal_mode 0)
		)
		(polygon
			(pts
				(arc
					(start 196.736462 -345.465146)
					(mid 196.032882 -345.465146)
					(end 196.736462 -345.465146)
				)
			)
		)
	)
	(zone
		(layers "B.Cu" "In9.Cu" "In11.Cu" "In13.Cu" "In15.Cu")
		(hatch none 0.5)
		(connect_pads
			(clearance 0)
		)
		(min_thickness 0.25)
		(keepout
			(tracks not_allowed)
			(vias allowed)
			(pads allowed)
			(copperpour not_allowed)
			(footprints allowed)
		)
		(placement
			(enabled no)
			(sheetname "")
		)
		(fill yes
			(thermal_gap 0.5)
			(thermal_bridge_width 0.5)
			(island_removal_mode 0)
		)
		(polygon
			(pts
				(arc
					(start 112.213898 -348.58579)
					(mid 111.510318 -348.58579)
					(end 112.213898 -348.58579)
				)
			)
		)
	)
	(zone
		(layers "B.Cu" "In9.Cu" "In11.Cu" "In13.Cu" "In15.Cu")
		(hatch none 0.5)
		(connect_pads
			(clearance 0)
		)
		(min_thickness 0.25)
		(keepout
			(tracks not_allowed)
			(vias allowed)
			(pads allowed)
			(copperpour not_allowed)
			(footprints allowed)
		)
		(placement
			(enabled no)
			(sheetname "")
		)
		(fill yes
			(thermal_gap 0.5)
			(thermal_bridge_width 0.5)
			(island_removal_mode 0)
		)
		(polygon
			(pts
				(arc
					(start 171.864782 -342.439498)
					(mid 171.161202 -342.439498)
					(end 171.864782 -342.439498)
				)
			)
		)
	)
	(zone
		(layers "B.Cu" "In9.Cu" "In11.Cu" "In13.Cu" "In15.Cu")
		(hatch none 0.5)
		(connect_pads
			(clearance 0)
		)
		(min_thickness 0.25)
		(keepout
			(tracks not_allowed)
			(vias allowed)
			(pads allowed)
			(copperpour not_allowed)
			(footprints allowed)
		)
		(placement
			(enabled no)
			(sheetname "")
		)
		(fill yes
			(thermal_gap 0.5)
			(thermal_bridge_width 0.5)
			(island_removal_mode 0)
		)
		(polygon
			(pts
				(arc
					(start 426.469556 -372.890034)
					(mid 425.710096 -372.890034)
					(end 426.469556 -372.890034)
				)
			)
		)
	)
	(zone
		(layers "B.Cu" "In9.Cu" "In11.Cu" "In13.Cu" "In15.Cu")
		(hatch none 0.5)
		(connect_pads
			(clearance 0)
		)
		(min_thickness 0.25)
		(keepout
			(tracks not_allowed)
			(vias allowed)
			(pads allowed)
			(copperpour not_allowed)
			(footprints allowed)
		)
		(placement
			(enabled no)
			(sheetname "")
		)
		(fill yes
			(thermal_gap 0.5)
			(thermal_bridge_width 0.5)
			(island_removal_mode 0)
		)
		(polygon
			(pts
				(arc
					(start 434.518562 -351.611438)
					(mid 433.814982 -351.611438)
					(end 434.518562 -351.611438)
				)
			)
		)
	)
	(zone
		(layers "B.Cu" "In9.Cu" "In11.Cu" "In13.Cu" "In15.Cu")
		(hatch none 0.5)
		(connect_pads
			(clearance 0)
		)
		(min_thickness 0.25)
		(keepout
			(tracks not_allowed)
			(vias allowed)
			(pads allowed)
			(copperpour not_allowed)
			(footprints allowed)
		)
		(placement
			(enabled no)
			(sheetname "")
		)
		(fill yes
			(thermal_gap 0.5)
			(thermal_bridge_width 0.5)
			(island_removal_mode 0)
		)
		(polygon
			(pts
				(arc
					(start 279.826212 -275.949918)
					(mid 279.173432 -275.949918)
					(end 279.826212 -275.949918)
				)
			)
		)
	)
	(zone
		(layers "B.Cu" "In9.Cu" "In11.Cu" "In13.Cu" "In15.Cu")
		(hatch none 0.5)
		(connect_pads
			(clearance 0)
		)
		(min_thickness 0.25)
		(keepout
			(tracks not_allowed)
			(vias allowed)
			(pads allowed)
			(copperpour not_allowed)
			(footprints allowed)
		)
		(placement
			(enabled no)
			(sheetname "")
		)
		(fill yes
			(thermal_gap 0.5)
			(thermal_bridge_width 0.5)
			(island_removal_mode 0)
		)
		(polygon
			(pts
				(arc
					(start 78.889606 -380.69012)
					(mid 78.130146 -380.69012)
					(end 78.889606 -380.69012)
				)
			)
		)
	)
	(zone
		(layers "B.Cu" "In9.Cu" "In11.Cu" "In13.Cu" "In15.Cu")
		(hatch none 0.5)
		(connect_pads
			(clearance 0)
		)
		(min_thickness 0.25)
		(keepout
			(tracks not_allowed)
			(vias allowed)
			(pads allowed)
			(copperpour not_allowed)
			(footprints allowed)
		)
		(placement
			(enabled no)
			(sheetname "")
		)
		(fill yes
			(thermal_gap 0.5)
			(thermal_bridge_width 0.5)
			(island_removal_mode 0)
		)
		(polygon
			(pts
				(arc
					(start 172.276262 -274.049744)
					(mid 171.623482 -274.049744)
					(end 172.276262 -274.049744)
				)
			)
		)
	)
	(zone
		(layers "B.Cu" "In9.Cu" "In11.Cu" "In13.Cu" "In15.Cu")
		(hatch none 0.5)
		(connect_pads
			(clearance 0)
		)
		(min_thickness 0.25)
		(keepout
			(tracks not_allowed)
			(vias allowed)
			(pads allowed)
			(copperpour not_allowed)
			(footprints allowed)
		)
		(placement
			(enabled no)
			(sheetname "")
		)
		(fill yes
			(thermal_gap 0.5)
			(thermal_bridge_width 0.5)
			(island_removal_mode 0)
		)
		(polygon
			(pts
				(arc
					(start 284.657292 -354.732082)
					(mid 283.953712 -354.732082)
					(end 284.657292 -354.732082)
				)
			)
		)
	)
	(zone
		(layers "B.Cu" "In9.Cu" "In11.Cu" "In13.Cu" "In15.Cu")
		(hatch none 0.5)
		(connect_pads
			(clearance 0)
		)
		(min_thickness 0.25)
		(keepout
			(tracks not_allowed)
			(vias allowed)
			(pads allowed)
			(copperpour not_allowed)
			(footprints allowed)
		)
		(placement
			(enabled no)
			(sheetname "")
		)
		(fill yes
			(thermal_gap 0.5)
			(thermal_bridge_width 0.5)
			(island_removal_mode 0)
		)
		(polygon
			(pts
				(arc
					(start 341.698834 -342.439498)
					(mid 340.995254 -342.439498)
					(end 341.698834 -342.439498)
				)
			)
		)
	)
	(zone
		(layers "B.Cu" "In9.Cu" "In11.Cu" "In13.Cu" "In15.Cu")
		(hatch none 0.5)
		(connect_pads
			(clearance 0)
		)
		(min_thickness 0.25)
		(keepout
			(tracks not_allowed)
			(vias allowed)
			(pads allowed)
			(copperpour not_allowed)
			(footprints allowed)
		)
		(placement
			(enabled no)
			(sheetname "")
		)
		(fill yes
			(thermal_gap 0.5)
			(thermal_bridge_width 0.5)
			(island_removal_mode 0)
		)
		(polygon
			(pts
				(arc
					(start 127.289814 -384.590036)
					(mid 126.530354 -384.590036)
					(end 127.289814 -384.590036)
				)
			)
		)
	)
	(zone
		(layers "B.Cu" "In9.Cu" "In11.Cu" "In13.Cu" "In15.Cu")
		(hatch none 0.5)
		(connect_pads
			(clearance 0)
		)
		(min_thickness 0.25)
		(keepout
			(tracks not_allowed)
			(vias allowed)
			(pads allowed)
			(copperpour not_allowed)
			(footprints allowed)
		)
		(placement
			(enabled no)
			(sheetname "")
		)
		(fill yes
			(thermal_gap 0.5)
			(thermal_bridge_width 0.5)
			(island_removal_mode 0)
		)
		(polygon
			(pts
				(arc
					(start 161.826448 -274.999958)
					(mid 161.173668 -274.999958)
					(end 161.826448 -274.999958)
				)
			)
		)
	)
	(zone
		(layers "B.Cu" "In9.Cu" "In11.Cu" "In13.Cu" "In15.Cu")
		(hatch none 0.5)
		(connect_pads
			(clearance 0)
		)
		(min_thickness 0.25)
		(keepout
			(tracks not_allowed)
			(vias allowed)
			(pads allowed)
			(copperpour not_allowed)
			(footprints allowed)
		)
		(placement
			(enabled no)
			(sheetname "")
		)
		(fill yes
			(thermal_gap 0.5)
			(thermal_bridge_width 0.5)
			(island_removal_mode 0)
		)
		(polygon
			(pts
				(arc
					(start 120.689878 -405.589994)
					(mid 119.930418 -405.589994)
					(end 120.689878 -405.589994)
				)
			)
		)
	)
	(zone
		(layers "B.Cu" "In9.Cu" "In11.Cu" "In13.Cu" "In15.Cu")
		(hatch none 0.5)
		(connect_pads
			(clearance 0)
		)
		(min_thickness 0.25)
		(keepout
			(tracks not_allowed)
			(vias allowed)
			(pads allowed)
			(copperpour not_allowed)
			(footprints allowed)
		)
		(placement
			(enabled no)
			(sheetname "")
		)
		(fill yes
			(thermal_gap 0.5)
			(thermal_bridge_width 0.5)
			(island_removal_mode 0)
		)
		(polygon
			(pts
				(arc
					(start 381.73025 -354.732082)
					(mid 381.02667 -354.732082)
					(end 381.73025 -354.732082)
				)
			)
		)
	)
	(zone
		(layers "B.Cu" "In9.Cu" "In11.Cu" "In13.Cu" "In15.Cu")
		(hatch none 0.5)
		(connect_pads
			(clearance 0)
		)
		(min_thickness 0.25)
		(keepout
			(tracks not_allowed)
			(vias allowed)
			(pads allowed)
			(copperpour not_allowed)
			(footprints allowed)
		)
		(placement
			(enabled no)
			(sheetname "")
		)
		(fill yes
			(thermal_gap 0.5)
			(thermal_bridge_width 0.5)
			(island_removal_mode 0)
		)
		(polygon
			(pts
				(arc
					(start 23.656798 -354.732082)
					(mid 22.953218 -354.732082)
					(end 23.656798 -354.732082)
				)
			)
		)
	)
	(zone
		(layers "B.Cu" "In9.Cu" "In11.Cu" "In13.Cu" "In15.Cu")
		(hatch none 0.5)
		(connect_pads
			(clearance 0)
		)
		(min_thickness 0.25)
		(keepout
			(tracks not_allowed)
			(vias allowed)
			(pads allowed)
			(copperpour not_allowed)
			(footprints allowed)
		)
		(placement
			(enabled no)
			(sheetname "")
		)
		(fill yes
			(thermal_gap 0.5)
			(thermal_bridge_width 0.5)
			(island_removal_mode 0)
		)
		(polygon
			(pts
				(arc
					(start 61.416438 -31.858712)
					(mid 60.712858 -31.858712)
					(end 61.416438 -31.858712)
				)
			)
		)
	)
	(zone
		(layers "B.Cu" "In9.Cu" "In11.Cu" "In13.Cu" "In15.Cu")
		(hatch none 0.5)
		(connect_pads
			(clearance 0)
		)
		(min_thickness 0.25)
		(keepout
			(tracks not_allowed)
			(vias allowed)
			(pads allowed)
			(copperpour not_allowed)
			(footprints allowed)
		)
		(placement
			(enabled no)
			(sheetname "")
		)
		(fill yes
			(thermal_gap 0.5)
			(thermal_bridge_width 0.5)
			(island_removal_mode 0)
		)
		(polygon
			(pts
				(arc
					(start 433.069492 -371.790214)
					(mid 432.310032 -371.790214)
					(end 433.069492 -371.790214)
				)
			)
		)
	)
	(zone
		(layers "B.Cu" "In9.Cu" "In11.Cu" "In13.Cu" "In15.Cu")
		(hatch none 0.5)
		(connect_pads
			(clearance 0)
		)
		(min_thickness 0.25)
		(keepout
			(tracks not_allowed)
			(vias allowed)
			(pads allowed)
			(copperpour not_allowed)
			(footprints allowed)
		)
		(placement
			(enabled no)
			(sheetname "")
		)
		(fill yes
			(thermal_gap 0.5)
			(thermal_bridge_width 0.5)
			(island_removal_mode 0)
		)
		(polygon
			(pts
				(arc
					(start 50.773838 -351.611438)
					(mid 50.070258 -351.611438)
					(end 50.773838 -351.611438)
				)
			)
		)
	)
	(zone
		(layers "B.Cu" "In9.Cu" "In11.Cu" "In13.Cu" "In15.Cu")
		(hatch none 0.5)
		(connect_pads
			(clearance 0)
		)
		(min_thickness 0.25)
		(keepout
			(tracks not_allowed)
			(vias allowed)
			(pads allowed)
			(copperpour not_allowed)
			(footprints allowed)
		)
		(placement
			(enabled no)
			(sheetname "")
		)
		(fill yes
			(thermal_gap 0.5)
			(thermal_bridge_width 0.5)
			(island_removal_mode 0)
		)
		(polygon
			(pts
				(arc
					(start 70.426326 -312.049922)
					(mid 69.773546 -312.049922)
					(end 70.426326 -312.049922)
				)
			)
		)
	)
	(zone
		(layers "B.Cu" "In9.Cu" "In11.Cu" "In13.Cu" "In15.Cu")
		(hatch none 0.5)
		(connect_pads
			(clearance 0)
		)
		(min_thickness 0.25)
		(keepout
			(tracks not_allowed)
			(vias allowed)
			(pads allowed)
			(copperpour not_allowed)
			(footprints allowed)
		)
		(placement
			(enabled no)
			(sheetname "")
		)
		(fill yes
			(thermal_gap 0.5)
			(thermal_bridge_width 0.5)
			(island_removal_mode 0)
		)
		(polygon
			(pts
				(arc
					(start 328.399394 -357.75773)
					(mid 327.695814 -357.75773)
					(end 328.399394 -357.75773)
				)
			)
		)
	)
	(zone
		(layers "B.Cu" "In9.Cu" "In11.Cu" "In13.Cu" "In15.Cu")
		(hatch none 0.5)
		(connect_pads
			(clearance 0)
		)
		(min_thickness 0.25)
		(keepout
			(tracks not_allowed)
			(vias allowed)
			(pads allowed)
			(copperpour not_allowed)
			(footprints allowed)
		)
		(placement
			(enabled no)
			(sheetname "")
		)
		(fill yes
			(thermal_gap 0.5)
			(thermal_bridge_width 0.5)
			(island_removal_mode 0)
		)
		(polygon
			(pts
				(arc
					(start 116.186458 -357.75773)
					(mid 115.482878 -357.75773)
					(end 116.186458 -357.75773)
				)
			)
		)
	)
	(zone
		(layers "B.Cu" "In9.Cu" "In11.Cu" "In13.Cu" "In15.Cu")
		(hatch none 0.5)
		(connect_pads
			(clearance 0)
		)
		(min_thickness 0.25)
		(keepout
			(tracks not_allowed)
			(vias allowed)
			(pads allowed)
			(copperpour not_allowed)
			(footprints allowed)
		)
		(placement
			(enabled no)
			(sheetname "")
		)
		(fill yes
			(thermal_gap 0.5)
			(thermal_bridge_width 0.5)
			(island_removal_mode 0)
		)
		(polygon
			(pts
				(arc
					(start 380.26975 -405.589994)
					(mid 379.51029 -405.589994)
					(end 380.26975 -405.589994)
				)
			)
		)
	)
	(zone
		(layers "B.Cu" "In9.Cu" "In11.Cu" "In13.Cu" "In15.Cu")
		(hatch none 0.5)
		(connect_pads
			(clearance 0)
		)
		(min_thickness 0.25)
		(keepout
			(tracks not_allowed)
			(vias allowed)
			(pads allowed)
			(copperpour not_allowed)
			(footprints allowed)
		)
		(placement
			(enabled no)
			(sheetname "")
		)
		(fill yes
			(thermal_gap 0.5)
			(thermal_bridge_width 0.5)
			(island_removal_mode 0)
		)
		(polygon
			(pts
				(arc
					(start 166.510462 -357.75773)
					(mid 165.806882 -357.75773)
					(end 166.510462 -357.75773)
				)
			)
		)
	)
	(zone
		(layers "B.Cu" "In9.Cu" "In11.Cu" "In13.Cu" "In15.Cu")
		(hatch none 0.5)
		(connect_pads
			(clearance 0)
		)
		(min_thickness 0.25)
		(keepout
			(tracks not_allowed)
			(vias allowed)
			(pads allowed)
			(copperpour not_allowed)
			(footprints allowed)
		)
		(placement
			(enabled no)
			(sheetname "")
		)
		(fill yes
			(thermal_gap 0.5)
			(thermal_bridge_width 0.5)
			(island_removal_mode 0)
		)
		(polygon
			(pts
				(arc
					(start 198.876412 -314.899802)
					(mid 198.223632 -314.899802)
					(end 198.876412 -314.899802)
				)
			)
		)
	)
	(zone
		(layers "B.Cu" "In9.Cu" "In11.Cu" "In13.Cu" "In15.Cu")
		(hatch none 0.5)
		(connect_pads
			(clearance 0)
		)
		(min_thickness 0.25)
		(keepout
			(tracks not_allowed)
			(vias allowed)
			(pads allowed)
			(copperpour not_allowed)
			(footprints allowed)
		)
		(placement
			(enabled no)
			(sheetname "")
		)
		(fill yes
			(thermal_gap 0.5)
			(thermal_bridge_width 0.5)
			(island_removal_mode 0)
		)
		(polygon
			(pts
				(arc
					(start 140.194538 -345.465146)
					(mid 139.490958 -345.465146)
					(end 140.194538 -345.465146)
				)
			)
		)
	)
	(zone
		(layers "B.Cu" "In9.Cu" "In11.Cu" "In13.Cu" "In15.Cu")
		(hatch none 0.5)
		(connect_pads
			(clearance 0)
		)
		(min_thickness 0.25)
		(keepout
			(tracks not_allowed)
			(vias allowed)
			(pads allowed)
			(copperpour not_allowed)
			(footprints allowed)
		)
		(placement
			(enabled no)
			(sheetname "")
		)
		(fill yes
			(thermal_gap 0.5)
			(thermal_bridge_width 0.5)
			(island_removal_mode 0)
		)
		(polygon
			(pts
				(arc
					(start 191.276478 -313.949842)
					(mid 190.623698 -313.949842)
					(end 191.276478 -313.949842)
				)
			)
		)
	)
	(zone
		(layers "B.Cu" "In9.Cu" "In11.Cu" "In13.Cu" "In15.Cu")
		(hatch none 0.5)
		(connect_pads
			(clearance 0)
		)
		(min_thickness 0.25)
		(keepout
			(tracks not_allowed)
			(vias allowed)
			(pads allowed)
			(copperpour not_allowed)
			(footprints allowed)
		)
		(placement
			(enabled no)
			(sheetname "")
		)
		(fill yes
			(thermal_gap 0.5)
			(thermal_bridge_width 0.5)
			(island_removal_mode 0)
		)
		(polygon
			(pts
				(arc
					(start 89.704672 -354.732082)
					(mid 89.001092 -354.732082)
					(end 89.704672 -354.732082)
				)
			)
		)
	)
	(zone
		(layers "B.Cu" "In9.Cu" "In11.Cu" "In13.Cu" "In15.Cu")
		(hatch none 0.5)
		(connect_pads
			(clearance 0)
		)
		(min_thickness 0.25)
		(keepout
			(tracks not_allowed)
			(vias allowed)
			(pads allowed)
			(copperpour not_allowed)
			(footprints allowed)
		)
		(placement
			(enabled no)
			(sheetname "")
		)
		(fill yes
			(thermal_gap 0.5)
			(thermal_bridge_width 0.5)
			(island_removal_mode 0)
		)
		(polygon
			(pts
				(arc
					(start 275.076158 -313.949842)
					(mid 274.423378 -313.949842)
					(end 275.076158 -313.949842)
				)
			)
		)
	)
	(zone
		(layers "B.Cu" "In9.Cu" "In11.Cu" "In13.Cu" "In15.Cu")
		(hatch none 0.5)
		(connect_pads
			(clearance 0)
		)
		(min_thickness 0.25)
		(keepout
			(tracks not_allowed)
			(vias allowed)
			(pads allowed)
			(copperpour not_allowed)
			(footprints allowed)
		)
		(placement
			(enabled no)
			(sheetname "")
		)
		(fill yes
			(thermal_gap 0.5)
			(thermal_bridge_width 0.5)
			(island_removal_mode 0)
		)
		(polygon
			(pts
				(arc
					(start 334.06969 -405.390096)
					(mid 333.31023 -405.390096)
					(end 334.06969 -405.390096)
				)
			)
		)
	)
	(zone
		(layers "B.Cu" "In9.Cu" "In11.Cu" "In13.Cu" "In15.Cu")
		(hatch none 0.5)
		(connect_pads
			(clearance 0)
		)
		(min_thickness 0.25)
		(keepout
			(tracks not_allowed)
			(vias allowed)
			(pads allowed)
			(copperpour not_allowed)
			(footprints allowed)
		)
		(placement
			(enabled no)
			(sheetname "")
		)
		(fill yes
			(thermal_gap 0.5)
			(thermal_bridge_width 0.5)
			(island_removal_mode 0)
		)
		(polygon
			(pts
				(arc
					(start 315.963554 -345.465146)
					(mid 315.259974 -345.465146)
					(end 315.963554 -345.465146)
				)
			)
		)
	)
	(zone
		(layers "B.Cu" "In9.Cu" "In11.Cu" "In13.Cu" "In15.Cu")
		(hatch none 0.5)
		(connect_pads
			(clearance 0)
		)
		(min_thickness 0.25)
		(keepout
			(tracks not_allowed)
			(vias allowed)
			(pads allowed)
			(copperpour not_allowed)
			(footprints allowed)
		)
		(placement
			(enabled no)
			(sheetname "")
		)
		(fill yes
			(thermal_gap 0.5)
			(thermal_bridge_width 0.5)
			(island_removal_mode 0)
		)
		(polygon
			(pts
				(arc
					(start 133.976618 -357.75773)
					(mid 133.273038 -357.75773)
					(end 133.976618 -357.75773)
				)
			)
		)
	)
	(zone
		(layers "B.Cu" "In9.Cu" "In11.Cu" "In13.Cu" "In15.Cu")
		(hatch none 0.5)
		(connect_pads
			(clearance 0)
		)
		(min_thickness 0.25)
		(keepout
			(tracks not_allowed)
			(vias allowed)
			(pads allowed)
			(copperpour not_allowed)
			(footprints allowed)
		)
		(placement
			(enabled no)
			(sheetname "")
		)
		(fill yes
			(thermal_gap 0.5)
			(thermal_bridge_width 0.5)
			(island_removal_mode 0)
		)
		(polygon
			(pts
				(arc
					(start 331.508354 -351.611438)
					(mid 330.804774 -351.611438)
					(end 331.508354 -351.611438)
				)
			)
		)
	)
	(zone
		(layers "B.Cu" "In9.Cu" "In11.Cu" "In13.Cu" "In15.Cu")
		(hatch none 0.5)
		(connect_pads
			(clearance 0)
		)
		(min_thickness 0.25)
		(keepout
			(tracks not_allowed)
			(vias allowed)
			(pads allowed)
			(copperpour not_allowed)
			(footprints allowed)
		)
		(placement
			(enabled no)
			(sheetname "")
		)
		(fill yes
			(thermal_gap 0.5)
			(thermal_bridge_width 0.5)
			(island_removal_mode 0)
		)
		(polygon
			(pts
				(arc
					(start 391.269728 -384.590036)
					(mid 390.510268 -384.590036)
					(end 391.269728 -384.590036)
				)
			)
		)
	)
	(zone
		(layers "B.Cu" "In9.Cu" "In11.Cu" "In13.Cu" "In15.Cu")
		(hatch none 0.5)
		(connect_pads
			(clearance 0)
		)
		(min_thickness 0.25)
		(keepout
			(tracks not_allowed)
			(vias allowed)
			(pads allowed)
			(copperpour not_allowed)
			(footprints allowed)
		)
		(placement
			(enabled no)
			(sheetname "")
		)
		(fill yes
			(thermal_gap 0.5)
			(thermal_bridge_width 0.5)
			(island_removal_mode 0)
		)
		(polygon
			(pts
				(arc
					(start 328.399394 -342.439498)
					(mid 327.695814 -342.439498)
					(end 328.399394 -342.439498)
				)
			)
		)
	)
	(zone
		(layers "B.Cu" "In9.Cu" "In11.Cu" "In13.Cu" "In15.Cu")
		(hatch none 0.5)
		(connect_pads
			(clearance 0)
		)
		(min_thickness 0.25)
		(keepout
			(tracks not_allowed)
			(vias allowed)
			(pads allowed)
			(copperpour not_allowed)
			(footprints allowed)
		)
		(placement
			(enabled no)
			(sheetname "")
		)
		(fill yes
			(thermal_gap 0.5)
			(thermal_bridge_width 0.5)
			(island_removal_mode 0)
		)
		(polygon
			(pts
				(arc
					(start 380.86665 -354.732082)
					(mid 380.16307 -354.732082)
					(end 380.86665 -354.732082)
				)
			)
		)
	)
	(zone
		(layers "B.Cu" "In9.Cu" "In11.Cu" "In13.Cu" "In15.Cu")
		(hatch none 0.5)
		(connect_pads
			(clearance 0)
		)
		(min_thickness 0.25)
		(keepout
			(tracks not_allowed)
			(vias allowed)
			(pads allowed)
			(copperpour not_allowed)
			(footprints allowed)
		)
		(placement
			(enabled no)
			(sheetname "")
		)
		(fill yes
			(thermal_gap 0.5)
			(thermal_bridge_width 0.5)
			(island_removal_mode 0)
		)
		(polygon
			(pts
				(arc
					(start 44.776136 -273.099784)
					(mid 44.123356 -273.099784)
					(end 44.776136 -273.099784)
				)
			)
		)
	)
	(zone
		(layers "B.Cu" "In9.Cu" "In11.Cu" "In13.Cu" "In15.Cu")
		(hatch none 0.5)
		(connect_pads
			(clearance 0)
		)
		(min_thickness 0.25)
		(keepout
			(tracks not_allowed)
			(vias allowed)
			(pads allowed)
			(copperpour not_allowed)
			(footprints allowed)
		)
		(placement
			(enabled no)
			(sheetname "")
		)
		(fill yes
			(thermal_gap 0.5)
			(thermal_bridge_width 0.5)
			(island_removal_mode 0)
		)
		(polygon
			(pts
				(arc
					(start 127.289814 -406.690068)
					(mid 126.530354 -406.690068)
					(end 127.289814 -406.690068)
				)
			)
		)
	)
	(zone
		(layers "B.Cu" "In9.Cu" "In11.Cu" "In13.Cu" "In15.Cu")
		(hatch none 0.5)
		(connect_pads
			(clearance 0)
		)
		(min_thickness 0.25)
		(keepout
			(tracks not_allowed)
			(vias allowed)
			(pads allowed)
			(copperpour not_allowed)
			(footprints allowed)
		)
		(placement
			(enabled no)
			(sheetname "")
		)
		(fill yes
			(thermal_gap 0.5)
			(thermal_bridge_width 0.5)
			(island_removal_mode 0)
		)
		(polygon
			(pts
				(arc
					(start 170.376342 -313.949842)
					(mid 169.723562 -313.949842)
					(end 170.376342 -313.949842)
				)
			)
		)
	)
	(zone
		(layers "B.Cu" "In9.Cu" "In11.Cu" "In13.Cu" "In15.Cu")
		(hatch none 0.5)
		(connect_pads
			(clearance 0)
		)
		(min_thickness 0.25)
		(keepout
			(tracks not_allowed)
			(vias allowed)
			(pads allowed)
			(copperpour not_allowed)
			(footprints allowed)
		)
		(placement
			(enabled no)
			(sheetname "")
		)
		(fill yes
			(thermal_gap 0.5)
			(thermal_bridge_width 0.5)
			(island_removal_mode 0)
		)
		(polygon
			(pts
				(arc
					(start 71.376286 -313.949842)
					(mid 70.723506 -313.949842)
					(end 71.376286 -313.949842)
				)
			)
		)
	)
	(zone
		(layers "B.Cu" "In9.Cu" "In11.Cu" "In13.Cu" "In15.Cu")
		(hatch none 0.5)
		(connect_pads
			(clearance 0)
		)
		(min_thickness 0.25)
		(keepout
			(tracks not_allowed)
			(vias allowed)
			(pads allowed)
			(copperpour not_allowed)
			(footprints allowed)
		)
		(placement
			(enabled no)
			(sheetname "")
		)
		(fill yes
			(thermal_gap 0.5)
			(thermal_bridge_width 0.5)
			(island_removal_mode 0)
		)
		(polygon
			(pts
				(arc
					(start 89.704672 -342.439498)
					(mid 89.001092 -342.439498)
					(end 89.704672 -342.439498)
				)
			)
		)
	)
	(zone
		(layers "B.Cu" "In9.Cu" "In11.Cu" "In13.Cu" "In15.Cu")
		(hatch none 0.5)
		(connect_pads
			(clearance 0)
		)
		(min_thickness 0.25)
		(keepout
			(tracks not_allowed)
			(vias allowed)
			(pads allowed)
			(copperpour not_allowed)
			(footprints allowed)
		)
		(placement
			(enabled no)
			(sheetname "")
		)
		(fill yes
			(thermal_gap 0.5)
			(thermal_bridge_width 0.5)
			(island_removal_mode 0)
		)
		(polygon
			(pts
				(arc
					(start 61.876178 -312.999882)
					(mid 61.223398 -312.999882)
					(end 61.876178 -312.999882)
				)
			)
		)
	)
	(zone
		(layers "B.Cu" "In9.Cu" "In11.Cu" "In13.Cu" "In15.Cu")
		(hatch none 0.5)
		(connect_pads
			(clearance 0)
		)
		(min_thickness 0.25)
		(keepout
			(tracks not_allowed)
			(vias allowed)
			(pads allowed)
			(copperpour not_allowed)
			(footprints allowed)
		)
		(placement
			(enabled no)
			(sheetname "")
		)
		(fill yes
			(thermal_gap 0.5)
			(thermal_bridge_width 0.5)
			(island_removal_mode 0)
		)
		(polygon
			(pts
				(arc
					(start 301.069502 -401.690078)
					(mid 300.310042 -401.690078)
					(end 301.069502 -401.690078)
				)
			)
		)
	)
	(zone
		(layers "B.Cu" "In9.Cu" "In11.Cu" "In13.Cu" "In15.Cu")
		(hatch none 0.5)
		(connect_pads
			(clearance 0)
		)
		(min_thickness 0.25)
		(keepout
			(tracks not_allowed)
			(vias allowed)
			(pads allowed)
			(copperpour not_allowed)
			(footprints allowed)
		)
		(placement
			(enabled no)
			(sheetname "")
		)
		(fill yes
			(thermal_gap 0.5)
			(thermal_bridge_width 0.5)
			(island_removal_mode 0)
		)
		(polygon
			(pts
				(arc
					(start 170.376342 -274.049744)
					(mid 169.723562 -274.049744)
					(end 170.376342 -274.049744)
				)
			)
		)
	)
	(zone
		(layers "B.Cu" "In9.Cu" "In11.Cu" "In13.Cu" "In15.Cu")
		(hatch none 0.5)
		(connect_pads
			(clearance 0)
		)
		(min_thickness 0.25)
		(keepout
			(tracks not_allowed)
			(vias allowed)
			(pads allowed)
			(copperpour not_allowed)
			(footprints allowed)
		)
		(placement
			(enabled no)
			(sheetname "")
		)
		(fill yes
			(thermal_gap 0.5)
			(thermal_bridge_width 0.5)
			(island_removal_mode 0)
		)
		(polygon
			(pts
				(arc
					(start 319.936114 -351.611438)
					(mid 319.232534 -351.611438)
					(end 319.936114 -351.611438)
				)
			)
		)
	)
	(zone
		(layers "B.Cu" "In9.Cu" "In11.Cu" "In13.Cu" "In15.Cu")
		(hatch none 0.5)
		(connect_pads
			(clearance 0)
		)
		(min_thickness 0.25)
		(keepout
			(tracks not_allowed)
			(vias allowed)
			(pads allowed)
			(copperpour not_allowed)
			(footprints allowed)
		)
		(placement
			(enabled no)
			(sheetname "")
		)
		(fill yes
			(thermal_gap 0.5)
			(thermal_bridge_width 0.5)
			(island_removal_mode 0)
		)
		(polygon
			(pts
				(arc
					(start 196.736462 -342.439498)
					(mid 196.032882 -342.439498)
					(end 196.736462 -342.439498)
				)
			)
		)
	)
	(zone
		(layers "B.Cu" "In9.Cu" "In11.Cu" "In13.Cu" "In15.Cu")
		(hatch none 0.5)
		(connect_pads
			(clearance 0)
		)
		(min_thickness 0.25)
		(keepout
			(tracks not_allowed)
			(vias allowed)
			(pads allowed)
			(copperpour not_allowed)
			(footprints allowed)
		)
		(placement
			(enabled no)
			(sheetname "")
		)
		(fill yes
			(thermal_gap 0.5)
			(thermal_bridge_width 0.5)
			(island_removal_mode 0)
		)
		(polygon
			(pts
				(arc
					(start 182.055262 -348.58579)
					(mid 181.351682 -348.58579)
					(end 182.055262 -348.58579)
				)
			)
		)
	)
	(zone
		(layers "B.Cu" "In9.Cu" "In11.Cu" "In13.Cu" "In15.Cu")
		(hatch none 0.5)
		(connect_pads
			(clearance 0)
		)
		(min_thickness 0.25)
		(keepout
			(tracks not_allowed)
			(vias allowed)
			(pads allowed)
			(copperpour not_allowed)
			(footprints allowed)
		)
		(placement
			(enabled no)
			(sheetname "")
		)
		(fill yes
			(thermal_gap 0.5)
			(thermal_bridge_width 0.5)
			(island_removal_mode 0)
		)
		(polygon
			(pts
				(arc
					(start 275.330412 -348.58579)
					(mid 274.626832 -348.58579)
					(end 275.330412 -348.58579)
				)
			)
		)
	)
	(zone
		(layers "B.Cu" "In9.Cu" "In11.Cu" "In13.Cu" "In15.Cu")
		(hatch none 0.5)
		(connect_pads
			(clearance 0)
		)
		(min_thickness 0.25)
		(keepout
			(tracks not_allowed)
			(vias allowed)
			(pads allowed)
			(copperpour not_allowed)
			(footprints allowed)
		)
		(placement
			(enabled no)
			(sheetname "")
		)
		(fill yes
			(thermal_gap 0.5)
			(thermal_bridge_width 0.5)
			(island_removal_mode 0)
		)
		(polygon
			(pts
				(arc
					(start 437.627522 -342.439498)
					(mid 436.923942 -342.439498)
					(end 437.627522 -342.439498)
				)
			)
		)
	)
	(zone
		(layers "B.Cu" "In9.Cu" "In11.Cu" "In13.Cu" "In15.Cu")
		(hatch none 0.5)
		(connect_pads
			(clearance 0)
		)
		(min_thickness 0.25)
		(keepout
			(tracks not_allowed)
			(vias allowed)
			(pads allowed)
			(copperpour not_allowed)
			(footprints allowed)
		)
		(placement
			(enabled no)
			(sheetname "")
		)
		(fill yes
			(thermal_gap 0.5)
			(thermal_bridge_width 0.5)
			(island_removal_mode 0)
		)
		(polygon
			(pts
				(arc
					(start 380.86665 -345.465146)
					(mid 380.16307 -345.465146)
					(end 380.86665 -345.465146)
				)
			)
		)
	)
	(zone
		(layers "B.Cu" "In9.Cu" "In11.Cu" "In13.Cu" "In15.Cu")
		(hatch none 0.5)
		(connect_pads
			(clearance 0)
		)
		(min_thickness 0.25)
		(keepout
			(tracks not_allowed)
			(vias allowed)
			(pads allowed)
			(copperpour not_allowed)
			(footprints allowed)
		)
		(placement
			(enabled no)
			(sheetname "")
		)
		(fill yes
			(thermal_gap 0.5)
			(thermal_bridge_width 0.5)
			(island_removal_mode 0)
		)
		(polygon
			(pts
				(arc
					(start 341.698834 -354.732082)
					(mid 340.995254 -354.732082)
					(end 341.698834 -354.732082)
				)
			)
		)
	)
	(zone
		(layers "B.Cu" "In9.Cu" "In11.Cu" "In13.Cu" "In15.Cu")
		(hatch none 0.5)
		(connect_pads
			(clearance 0)
		)
		(min_thickness 0.25)
		(keepout
			(tracks not_allowed)
			(vias allowed)
			(pads allowed)
			(copperpour not_allowed)
			(footprints allowed)
		)
		(placement
			(enabled no)
			(sheetname "")
		)
		(fill yes
			(thermal_gap 0.5)
			(thermal_bridge_width 0.5)
			(island_removal_mode 0)
		)
		(polygon
			(pts
				(arc
					(start 428.22622 -312.049922)
					(mid 427.57344 -312.049922)
					(end 428.22622 -312.049922)
				)
			)
		)
	)
	(zone
		(layers "B.Cu" "In9.Cu" "In11.Cu" "In13.Cu" "In15.Cu")
		(hatch none 0.5)
		(connect_pads
			(clearance 0)
		)
		(min_thickness 0.25)
		(keepout
			(tracks not_allowed)
			(vias allowed)
			(pads allowed)
			(copperpour not_allowed)
			(footprints allowed)
		)
		(placement
			(enabled no)
			(sheetname "")
		)
		(fill yes
			(thermal_gap 0.5)
			(thermal_bridge_width 0.5)
			(island_removal_mode 0)
		)
		(polygon
			(pts
				(arc
					(start 340.66988 -378.290074)
					(mid 339.91042 -378.290074)
					(end 340.66988 -378.290074)
				)
			)
		)
	)
	(zone
		(layers "B.Cu" "In9.Cu" "In11.Cu" "In13.Cu" "In15.Cu")
		(hatch none 0.5)
		(connect_pads
			(clearance 0)
		)
		(min_thickness 0.25)
		(keepout
			(tracks not_allowed)
			(vias allowed)
			(pads allowed)
			(copperpour not_allowed)
			(footprints allowed)
		)
		(placement
			(enabled no)
			(sheetname "")
		)
		(fill yes
			(thermal_gap 0.5)
			(thermal_bridge_width 0.5)
			(island_removal_mode 0)
		)
		(polygon
			(pts
				(arc
					(start 81.241392 -348.58579)
					(mid 80.537812 -348.58579)
					(end 81.241392 -348.58579)
				)
			)
		)
	)
	(zone
		(layers "B.Cu" "In9.Cu" "In11.Cu" "In13.Cu" "In15.Cu")
		(hatch none 0.5)
		(connect_pads
			(clearance 0)
		)
		(min_thickness 0.25)
		(keepout
			(tracks not_allowed)
			(vias allowed)
			(pads allowed)
			(copperpour not_allowed)
			(footprints allowed)
		)
		(placement
			(enabled no)
			(sheetname "")
		)
		(fill yes
			(thermal_gap 0.5)
			(thermal_bridge_width 0.5)
			(island_removal_mode 0)
		)
		(polygon
			(pts
				(arc
					(start 59.976258 -313.949842)
					(mid 59.323478 -313.949842)
					(end 59.976258 -313.949842)
				)
			)
		)
	)
	(zone
		(layers "B.Cu" "In9.Cu" "In11.Cu" "In13.Cu" "In15.Cu")
		(hatch none 0.5)
		(connect_pads
			(clearance 0)
		)
		(min_thickness 0.25)
		(keepout
			(tracks not_allowed)
			(vias allowed)
			(pads allowed)
			(copperpour not_allowed)
			(footprints allowed)
		)
		(placement
			(enabled no)
			(sheetname "")
		)
		(fill yes
			(thermal_gap 0.5)
			(thermal_bridge_width 0.5)
			(island_removal_mode 0)
		)
		(polygon
			(pts
				(arc
					(start 278.439372 -345.465146)
					(mid 277.735792 -345.465146)
					(end 278.439372 -345.465146)
				)
			)
		)
	)
	(zone
		(layers "B.Cu" "In9.Cu" "In11.Cu" "In13.Cu" "In15.Cu")
		(hatch none 0.5)
		(connect_pads
			(clearance 0)
		)
		(min_thickness 0.25)
		(keepout
			(tracks not_allowed)
			(vias allowed)
			(pads allowed)
			(copperpour not_allowed)
			(footprints allowed)
		)
		(placement
			(enabled no)
			(sheetname "")
		)
		(fill yes
			(thermal_gap 0.5)
			(thermal_bridge_width 0.5)
			(island_removal_mode 0)
		)
		(polygon
			(pts
				(arc
					(start 171.326302 -311.099962)
					(mid 170.673522 -311.099962)
					(end 171.326302 -311.099962)
				)
			)
		)
	)
	(zone
		(layers "B.Cu" "In9.Cu" "In11.Cu" "In13.Cu" "In15.Cu")
		(hatch none 0.5)
		(connect_pads
			(clearance 0)
		)
		(min_thickness 0.25)
		(keepout
			(tracks not_allowed)
			(vias allowed)
			(pads allowed)
			(copperpour not_allowed)
			(footprints allowed)
		)
		(placement
			(enabled no)
			(sheetname "")
		)
		(fill yes
			(thermal_gap 0.5)
			(thermal_bridge_width 0.5)
			(island_removal_mode 0)
		)
		(polygon
			(pts
				(arc
					(start 376.75566 18.460212)
					(mid 376.05208 18.460212)
					(end 376.75566 18.460212)
				)
			)
		)
	)
	(zone
		(layers "B.Cu" "In9.Cu" "In11.Cu" "In13.Cu" "In15.Cu")
		(hatch none 0.5)
		(connect_pads
			(clearance 0)
		)
		(min_thickness 0.25)
		(keepout
			(tracks not_allowed)
			(vias allowed)
			(pads allowed)
			(copperpour not_allowed)
			(footprints allowed)
		)
		(placement
			(enabled no)
			(sheetname "")
		)
		(fill yes
			(thermal_gap 0.5)
			(thermal_bridge_width 0.5)
			(island_removal_mode 0)
		)
		(polygon
			(pts
				(arc
					(start 383.71653 -28.25877)
					(mid 383.01295 -28.25877)
					(end 383.71653 -28.25877)
				)
			)
		)
	)
	(zone
		(layers "B.Cu" "In9.Cu" "In11.Cu" "In13.Cu" "In15.Cu")
		(hatch none 0.5)
		(connect_pads
			(clearance 0)
		)
		(min_thickness 0.25)
		(keepout
			(tracks not_allowed)
			(vias allowed)
			(pads allowed)
			(copperpour not_allowed)
			(footprints allowed)
		)
		(placement
			(enabled no)
			(sheetname "")
		)
		(fill yes
			(thermal_gap 0.5)
			(thermal_bridge_width 0.5)
			(island_removal_mode 0)
		)
		(polygon
			(pts
				(arc
					(start 303.576228 -312.999882)
					(mid 302.923448 -312.999882)
					(end 303.576228 -312.999882)
				)
			)
		)
	)
	(zone
		(layers "B.Cu" "In9.Cu" "In11.Cu" "In13.Cu" "In15.Cu")
		(hatch none 0.5)
		(connect_pads
			(clearance 0)
		)
		(min_thickness 0.25)
		(keepout
			(tracks not_allowed)
			(vias allowed)
			(pads allowed)
			(copperpour not_allowed)
			(footprints allowed)
		)
		(placement
			(enabled no)
			(sheetname "")
		)
		(fill yes
			(thermal_gap 0.5)
			(thermal_bridge_width 0.5)
			(island_removal_mode 0)
		)
		(polygon
			(pts
				(arc
					(start 329.262994 -354.732082)
					(mid 328.559414 -354.732082)
					(end 329.262994 -354.732082)
				)
			)
		)
	)
	(zone
		(layers "B.Cu" "In9.Cu" "In11.Cu" "In13.Cu" "In15.Cu")
		(hatch none 0.5)
		(connect_pads
			(clearance 0)
		)
		(min_thickness 0.25)
		(keepout
			(tracks not_allowed)
			(vias allowed)
			(pads allowed)
			(copperpour not_allowed)
			(footprints allowed)
		)
		(placement
			(enabled no)
			(sheetname "")
		)
		(fill yes
			(thermal_gap 0.5)
			(thermal_bridge_width 0.5)
			(island_removal_mode 0)
		)
		(polygon
			(pts
				(arc
					(start 32.6898 -375.69013)
					(mid 31.93034 -375.69013)
					(end 32.6898 -375.69013)
				)
			)
		)
	)
	(zone
		(layers "B.Cu" "In9.Cu" "In11.Cu" "In13.Cu" "In15.Cu")
		(hatch none 0.5)
		(connect_pads
			(clearance 0)
		)
		(min_thickness 0.25)
		(keepout
			(tracks not_allowed)
			(vias allowed)
			(pads allowed)
			(copperpour not_allowed)
			(footprints allowed)
		)
		(placement
			(enabled no)
			(sheetname "")
		)
		(fill yes
			(thermal_gap 0.5)
			(thermal_bridge_width 0.5)
			(island_removal_mode 0)
		)
		(polygon
			(pts
				(arc
					(start 322.181474 -342.439498)
					(mid 321.477894 -342.439498)
					(end 322.181474 -342.439498)
				)
			)
		)
	)
	(zone
		(layers "B.Cu" "In9.Cu" "In11.Cu" "In13.Cu" "In15.Cu")
		(hatch none 0.5)
		(connect_pads
			(clearance 0)
		)
		(min_thickness 0.25)
		(keepout
			(tracks not_allowed)
			(vias allowed)
			(pads allowed)
			(copperpour not_allowed)
			(footprints allowed)
		)
		(placement
			(enabled no)
			(sheetname "")
		)
		(fill yes
			(thermal_gap 0.5)
			(thermal_bridge_width 0.5)
			(island_removal_mode 0)
		)
		(polygon
			(pts
				(arc
					(start 172.728382 -357.75773)
					(mid 172.024802 -357.75773)
					(end 172.728382 -357.75773)
				)
			)
		)
	)
	(zone
		(layers "B.Cu" "In9.Cu" "In11.Cu" "In13.Cu" "In15.Cu")
		(hatch none 0.5)
		(connect_pads
			(clearance 0)
		)
		(min_thickness 0.25)
		(keepout
			(tracks not_allowed)
			(vias allowed)
			(pads allowed)
			(copperpour not_allowed)
			(footprints allowed)
		)
		(placement
			(enabled no)
			(sheetname "")
		)
		(fill yes
			(thermal_gap 0.5)
			(thermal_bridge_width 0.5)
			(island_removal_mode 0)
		)
		(polygon
			(pts
				(arc
					(start 93.677232 -348.58579)
					(mid 92.973652 -348.58579)
					(end 93.677232 -348.58579)
				)
			)
		)
	)
	(zone
		(layers "B.Cu" "In9.Cu" "In11.Cu" "In13.Cu" "In15.Cu")
		(hatch none 0.5)
		(connect_pads
			(clearance 0)
		)
		(min_thickness 0.25)
		(keepout
			(tracks not_allowed)
			(vias allowed)
			(pads allowed)
			(copperpour not_allowed)
			(footprints allowed)
		)
		(placement
			(enabled no)
			(sheetname "")
		)
		(fill yes
			(thermal_gap 0.5)
			(thermal_bridge_width 0.5)
			(island_removal_mode 0)
		)
		(polygon
			(pts
				(arc
					(start 125.51664 -32.722312)
					(mid 124.81306 -32.722312)
					(end 125.51664 -32.722312)
				)
			)
		)
	)
	(zone
		(layers "B.Cu" "In9.Cu" "In11.Cu" "In13.Cu" "In15.Cu")
		(hatch none 0.5)
		(connect_pads
			(clearance 0)
		)
		(min_thickness 0.25)
		(keepout
			(tracks not_allowed)
			(vias allowed)
			(pads allowed)
			(copperpour not_allowed)
			(footprints allowed)
		)
		(placement
			(enabled no)
			(sheetname "")
		)
		(fill yes
			(thermal_gap 0.5)
			(thermal_bridge_width 0.5)
			(island_removal_mode 0)
		)
		(polygon
			(pts
				(arc
					(start 293.984172 -351.611438)
					(mid 293.280592 -351.611438)
					(end 293.984172 -351.611438)
				)
			)
		)
	)
	(zone
		(layers "B.Cu" "In9.Cu" "In11.Cu" "In13.Cu" "In15.Cu")
		(hatch none 0.5)
		(connect_pads
			(clearance 0)
		)
		(min_thickness 0.25)
		(keepout
			(tracks not_allowed)
			(vias allowed)
			(pads allowed)
			(copperpour not_allowed)
			(footprints allowed)
		)
		(placement
			(enabled no)
			(sheetname "")
		)
		(fill yes
			(thermal_gap 0.5)
			(thermal_bridge_width 0.5)
			(island_removal_mode 0)
		)
		(polygon
			(pts
				(arc
					(start 29.011118 -342.439498)
					(mid 28.307538 -342.439498)
					(end 29.011118 -342.439498)
				)
			)
		)
	)
	(zone
		(layers "B.Cu" "In9.Cu" "In11.Cu" "In13.Cu" "In15.Cu")
		(hatch none 0.5)
		(connect_pads
			(clearance 0)
		)
		(min_thickness 0.25)
		(keepout
			(tracks not_allowed)
			(vias allowed)
			(pads allowed)
			(copperpour not_allowed)
			(footprints allowed)
		)
		(placement
			(enabled no)
			(sheetname "")
		)
		(fill yes
			(thermal_gap 0.5)
			(thermal_bridge_width 0.5)
			(island_removal_mode 0)
		)
		(polygon
			(pts
				(arc
					(start 397.27505 -348.58579)
					(mid 396.57147 -348.58579)
					(end 397.27505 -348.58579)
				)
			)
		)
	)
	(zone
		(layers "B.Cu" "In9.Cu" "In11.Cu" "In13.Cu" "In15.Cu")
		(hatch none 0.5)
		(connect_pads
			(clearance 0)
		)
		(min_thickness 0.25)
		(keepout
			(tracks not_allowed)
			(vias allowed)
			(pads allowed)
			(copperpour not_allowed)
			(footprints allowed)
		)
		(placement
			(enabled no)
			(sheetname "")
		)
		(fill yes
			(thermal_gap 0.5)
			(thermal_bridge_width 0.5)
			(island_removal_mode 0)
		)
		(polygon
			(pts
				(arc
					(start 399.52041 -354.732082)
					(mid 398.81683 -354.732082)
					(end 399.52041 -354.732082)
				)
			)
		)
	)
	(zone
		(layers "B.Cu" "In9.Cu" "In11.Cu" "In13.Cu" "In15.Cu")
		(hatch none 0.5)
		(connect_pads
			(clearance 0)
		)
		(min_thickness 0.25)
		(keepout
			(tracks not_allowed)
			(vias allowed)
			(pads allowed)
			(copperpour not_allowed)
			(footprints allowed)
		)
		(placement
			(enabled no)
			(sheetname "")
		)
		(fill yes
			(thermal_gap 0.5)
			(thermal_bridge_width 0.5)
			(island_removal_mode 0)
		)
		(polygon
			(pts
				(arc
					(start 338.589874 -351.611438)
					(mid 337.886294 -351.611438)
					(end 338.589874 -351.611438)
				)
			)
		)
	)
	(zone
		(layers "B.Cu" "In9.Cu" "In11.Cu" "In13.Cu" "In15.Cu")
		(hatch none 0.5)
		(connect_pads
			(clearance 0)
		)
		(min_thickness 0.25)
		(keepout
			(tracks not_allowed)
			(vias allowed)
			(pads allowed)
			(copperpour not_allowed)
			(footprints allowed)
		)
		(placement
			(enabled no)
			(sheetname "")
		)
		(fill yes
			(thermal_gap 0.5)
			(thermal_bridge_width 0.5)
			(island_removal_mode 0)
		)
		(polygon
			(pts
				(arc
					(start 347.269816 -379.390148)
					(mid 346.510356 -379.390148)
					(end 347.269816 -379.390148)
				)
			)
		)
	)
	(zone
		(layers "B.Cu" "In9.Cu" "In11.Cu" "In13.Cu" "In15.Cu")
		(hatch none 0.5)
		(connect_pads
			(clearance 0)
		)
		(min_thickness 0.25)
		(keepout
			(tracks not_allowed)
			(vias allowed)
			(pads allowed)
			(copperpour not_allowed)
			(footprints allowed)
		)
		(placement
			(enabled no)
			(sheetname "")
		)
		(fill yes
			(thermal_gap 0.5)
			(thermal_bridge_width 0.5)
			(island_removal_mode 0)
		)
		(polygon
			(pts
				(arc
					(start 84.350352 -354.732082)
					(mid 83.646772 -354.732082)
					(end 84.350352 -354.732082)
				)
			)
		)
	)
	(zone
		(layers "B.Cu" "In9.Cu" "In11.Cu" "In13.Cu" "In15.Cu")
		(hatch none 0.5)
		(connect_pads
			(clearance 0)
		)
		(min_thickness 0.25)
		(keepout
			(tracks not_allowed)
			(vias allowed)
			(pads allowed)
			(copperpour not_allowed)
			(footprints allowed)
		)
		(placement
			(enabled no)
			(sheetname "")
		)
		(fill yes
			(thermal_gap 0.5)
			(thermal_bridge_width 0.5)
			(island_removal_mode 0)
		)
		(polygon
			(pts
				(arc
					(start 48.57623 -274.049744)
					(mid 47.92345 -274.049744)
					(end 48.57623 -274.049744)
				)
			)
		)
	)
	(zone
		(layers "B.Cu" "In9.Cu" "In11.Cu" "In13.Cu" "In15.Cu")
		(hatch none 0.5)
		(connect_pads
			(clearance 0)
		)
		(min_thickness 0.25)
		(keepout
			(tracks not_allowed)
			(vias allowed)
			(pads allowed)
			(copperpour not_allowed)
			(footprints allowed)
		)
		(placement
			(enabled no)
			(sheetname "")
		)
		(fill yes
			(thermal_gap 0.5)
			(thermal_bridge_width 0.5)
			(island_removal_mode 0)
		)
		(polygon
			(pts
				(arc
					(start 297.093132 -354.732082)
					(mid 296.389552 -354.732082)
					(end 297.093132 -354.732082)
				)
			)
		)
	)
	(zone
		(layers "B.Cu" "In9.Cu" "In11.Cu" "In13.Cu" "In15.Cu")
		(hatch none 0.5)
		(connect_pads
			(clearance 0)
		)
		(min_thickness 0.25)
		(keepout
			(tracks not_allowed)
			(vias allowed)
			(pads allowed)
			(copperpour not_allowed)
			(footprints allowed)
		)
		(placement
			(enabled no)
			(sheetname "")
		)
		(fill yes
			(thermal_gap 0.5)
			(thermal_bridge_width 0.5)
			(island_removal_mode 0)
		)
		(polygon
			(pts
				(arc
					(start 422.526206 -312.049922)
					(mid 421.873426 -312.049922)
					(end 422.526206 -312.049922)
				)
			)
		)
	)
	(zone
		(layers "B.Cu" "In9.Cu" "In11.Cu" "In13.Cu" "In15.Cu")
		(hatch none 0.5)
		(connect_pads
			(clearance 0)
		)
		(min_thickness 0.25)
		(keepout
			(tracks not_allowed)
			(vias allowed)
			(pads allowed)
			(copperpour not_allowed)
			(footprints allowed)
		)
		(placement
			(enabled no)
			(sheetname "")
		)
		(fill yes
			(thermal_gap 0.5)
			(thermal_bridge_width 0.5)
			(island_removal_mode 0)
		)
		(polygon
			(pts
				(arc
					(start 334.06969 -380.69012)
					(mid 333.31023 -380.69012)
					(end 334.06969 -380.69012)
				)
			)
		)
	)
	(zone
		(layers "B.Cu" "In9.Cu" "In11.Cu" "In13.Cu" "In15.Cu")
		(hatch none 0.5)
		(connect_pads
			(clearance 0)
		)
		(min_thickness 0.25)
		(keepout
			(tracks not_allowed)
			(vias allowed)
			(pads allowed)
			(copperpour not_allowed)
			(footprints allowed)
		)
		(placement
			(enabled no)
			(sheetname "")
		)
		(fill yes
			(thermal_gap 0.5)
			(thermal_bridge_width 0.5)
			(island_removal_mode 0)
		)
		(polygon
			(pts
				(arc
					(start 71.914512 -345.465146)
					(mid 71.210932 -345.465146)
					(end 71.914512 -345.465146)
				)
			)
		)
	)
	(zone
		(layers "B.Cu" "In9.Cu" "In11.Cu" "In13.Cu" "In15.Cu")
		(hatch none 0.5)
		(connect_pads
			(clearance 0)
		)
		(min_thickness 0.25)
		(keepout
			(tracks not_allowed)
			(vias allowed)
			(pads allowed)
			(copperpour not_allowed)
			(footprints allowed)
		)
		(placement
			(enabled no)
			(sheetname "")
		)
		(fill yes
			(thermal_gap 0.5)
			(thermal_bridge_width 0.5)
			(island_removal_mode 0)
		)
		(polygon
			(pts
				(arc
					(start 272.221452 -342.439498)
					(mid 271.517872 -342.439498)
					(end 272.221452 -342.439498)
				)
			)
		)
	)
	(zone
		(layers "B.Cu" "In9.Cu" "In11.Cu" "In13.Cu" "In15.Cu")
		(hatch none 0.5)
		(connect_pads
			(clearance 0)
		)
		(min_thickness 0.25)
		(keepout
			(tracks not_allowed)
			(vias allowed)
			(pads allowed)
			(copperpour not_allowed)
			(footprints allowed)
		)
		(placement
			(enabled no)
			(sheetname "")
		)
		(fill yes
			(thermal_gap 0.5)
			(thermal_bridge_width 0.5)
			(island_removal_mode 0)
		)
		(polygon
			(pts
				(arc
					(start 52.376324 -274.049744)
					(mid 51.723544 -274.049744)
					(end 52.376324 -274.049744)
				)
			)
		)
	)
	(zone
		(layers "B.Cu" "In9.Cu" "In11.Cu" "In13.Cu" "In15.Cu")
		(hatch none 0.5)
		(connect_pads
			(clearance 0)
		)
		(min_thickness 0.25)
		(keepout
			(tracks not_allowed)
			(vias allowed)
			(pads allowed)
			(copperpour not_allowed)
			(footprints allowed)
		)
		(placement
			(enabled no)
			(sheetname "")
		)
		(fill yes
			(thermal_gap 0.5)
			(thermal_bridge_width 0.5)
			(island_removal_mode 0)
		)
		(polygon
			(pts
				(arc
					(start 41.446958 -342.439498)
					(mid 40.743378 -342.439498)
					(end 41.446958 -342.439498)
				)
			)
		)
	)
	(zone
		(layers "B.Cu" "In9.Cu" "In11.Cu" "In13.Cu" "In15.Cu")
		(hatch none 0.5)
		(connect_pads
			(clearance 0)
		)
		(min_thickness 0.25)
		(keepout
			(tracks not_allowed)
			(vias allowed)
			(pads allowed)
			(copperpour not_allowed)
			(footprints allowed)
		)
		(placement
			(enabled no)
			(sheetname "")
		)
		(fill yes
			(thermal_gap 0.5)
			(thermal_bridge_width 0.5)
			(island_removal_mode 0)
		)
		(polygon
			(pts
				(arc
					(start 194.126358 -307.299868)
					(mid 193.473578 -307.299868)
					(end 194.126358 -307.299868)
				)
			)
		)
	)
	(zone
		(layers "B.Cu" "In9.Cu" "In11.Cu" "In13.Cu" "In15.Cu")
		(hatch none 0.5)
		(connect_pads
			(clearance 0)
		)
		(min_thickness 0.25)
		(keepout
			(tracks not_allowed)
			(vias allowed)
			(pads allowed)
			(copperpour not_allowed)
			(footprints allowed)
		)
		(placement
			(enabled no)
			(sheetname "")
		)
		(fill yes
			(thermal_gap 0.5)
			(thermal_bridge_width 0.5)
			(island_removal_mode 0)
		)
		(polygon
			(pts
				(arc
					(start 302.626268 -311.099962)
					(mid 301.973488 -311.099962)
					(end 302.626268 -311.099962)
				)
			)
		)
	)
	(zone
		(layers "B.Cu" "In9.Cu" "In11.Cu" "In13.Cu" "In15.Cu")
		(hatch none 0.5)
		(connect_pads
			(clearance 0)
		)
		(min_thickness 0.25)
		(keepout
			(tracks not_allowed)
			(vias allowed)
			(pads allowed)
			(copperpour not_allowed)
			(footprints allowed)
		)
		(placement
			(enabled no)
			(sheetname "")
		)
		(fill yes
			(thermal_gap 0.5)
			(thermal_bridge_width 0.5)
			(island_removal_mode 0)
		)
		(polygon
			(pts
				(arc
					(start 387.08457 -357.75773)
					(mid 386.38099 -357.75773)
					(end 387.08457 -357.75773)
				)
			)
		)
	)
	(zone
		(layers "B.Cu" "In9.Cu" "In11.Cu" "In13.Cu" "In15.Cu")
		(hatch none 0.5)
		(connect_pads
			(clearance 0)
		)
		(min_thickness 0.25)
		(keepout
			(tracks not_allowed)
			(vias allowed)
			(pads allowed)
			(copperpour not_allowed)
			(footprints allowed)
		)
		(placement
			(enabled no)
			(sheetname "")
		)
		(fill yes
			(thermal_gap 0.5)
			(thermal_bridge_width 0.5)
			(island_removal_mode 0)
		)
		(polygon
			(pts
				(arc
					(start 35.41649 -32.722312)
					(mid 34.71291 -32.722312)
					(end 35.41649 -32.722312)
				)
			)
		)
	)
	(zone
		(layers "B.Cu" "In9.Cu" "In11.Cu" "In13.Cu" "In15.Cu")
		(hatch none 0.5)
		(connect_pads
			(clearance 0)
		)
		(min_thickness 0.25)
		(keepout
			(tracks not_allowed)
			(vias allowed)
			(pads allowed)
			(copperpour not_allowed)
			(footprints allowed)
		)
		(placement
			(enabled no)
			(sheetname "")
		)
		(fill yes
			(thermal_gap 0.5)
			(thermal_bridge_width 0.5)
			(island_removal_mode 0)
		)
		(polygon
			(pts
				(arc
					(start 422.526206 -311.099962)
					(mid 421.873426 -311.099962)
					(end 422.526206 -311.099962)
				)
			)
		)
	)
	(zone
		(layers "B.Cu" "In9.Cu" "In11.Cu" "In13.Cu" "In15.Cu")
		(hatch none 0.5)
		(connect_pads
			(clearance 0)
		)
		(min_thickness 0.25)
		(keepout
			(tracks not_allowed)
			(vias allowed)
			(pads allowed)
			(copperpour not_allowed)
			(footprints allowed)
		)
		(placement
			(enabled no)
			(sheetname "")
		)
		(fill yes
			(thermal_gap 0.5)
			(thermal_bridge_width 0.5)
			(island_removal_mode 0)
		)
		(polygon
			(pts
				(arc
					(start 26.765758 -348.58579)
					(mid 26.062178 -348.58579)
					(end 26.765758 -348.58579)
				)
			)
		)
	)
	(zone
		(layers "B.Cu" "In9.Cu" "In11.Cu" "In13.Cu" "In15.Cu")
		(hatch none 0.5)
		(connect_pads
			(clearance 0)
		)
		(min_thickness 0.25)
		(keepout
			(tracks not_allowed)
			(vias allowed)
			(pads allowed)
			(copperpour not_allowed)
			(footprints allowed)
		)
		(placement
			(enabled no)
			(sheetname "")
		)
		(fill yes
			(thermal_gap 0.5)
			(thermal_bridge_width 0.5)
			(island_removal_mode 0)
		)
		(polygon
			(pts
				(arc
					(start 284.657292 -345.465146)
					(mid 283.953712 -345.465146)
					(end 284.657292 -345.465146)
				)
			)
		)
	)
	(zone
		(layers "B.Cu" "In9.Cu" "In11.Cu" "In13.Cu" "In15.Cu")
		(hatch none 0.5)
		(connect_pads
			(clearance 0)
		)
		(min_thickness 0.25)
		(keepout
			(tracks not_allowed)
			(vias allowed)
			(pads allowed)
			(copperpour not_allowed)
			(footprints allowed)
		)
		(placement
			(enabled no)
			(sheetname "")
		)
		(fill yes
			(thermal_gap 0.5)
			(thermal_bridge_width 0.5)
			(island_removal_mode 0)
		)
		(polygon
			(pts
				(arc
					(start 305.476148 -312.999882)
					(mid 304.823368 -312.999882)
					(end 305.476148 -312.999882)
				)
			)
		)
	)
	(zone
		(layers "B.Cu" "In9.Cu" "In11.Cu" "In13.Cu" "In15.Cu")
		(hatch none 0.5)
		(connect_pads
			(clearance 0)
		)
		(min_thickness 0.25)
		(keepout
			(tracks not_allowed)
			(vias allowed)
			(pads allowed)
			(copperpour not_allowed)
			(footprints allowed)
		)
		(placement
			(enabled no)
			(sheetname "")
		)
		(fill yes
			(thermal_gap 0.5)
			(thermal_bridge_width 0.5)
			(island_removal_mode 0)
		)
		(polygon
			(pts
				(arc
					(start 197.926452 -312.049922)
					(mid 197.273672 -312.049922)
					(end 197.926452 -312.049922)
				)
			)
		)
	)
	(zone
		(layers "B.Cu" "In9.Cu" "In11.Cu" "In13.Cu" "In15.Cu")
		(hatch none 0.5)
		(connect_pads
			(clearance 0)
		)
		(min_thickness 0.25)
		(keepout
			(tracks not_allowed)
			(vias allowed)
			(pads allowed)
			(copperpour not_allowed)
			(footprints allowed)
		)
		(placement
			(enabled no)
			(sheetname "")
		)
		(fill yes
			(thermal_gap 0.5)
			(thermal_bridge_width 0.5)
			(island_removal_mode 0)
		)
		(polygon
			(pts
				(arc
					(start 41.926256 -303.499774)
					(mid 41.273476 -303.499774)
					(end 41.926256 -303.499774)
				)
			)
		)
	)
	(zone
		(layers "B.Cu" "In9.Cu" "In11.Cu" "In13.Cu" "In15.Cu")
		(hatch none 0.5)
		(connect_pads
			(clearance 0)
		)
		(min_thickness 0.25)
		(keepout
			(tracks not_allowed)
			(vias allowed)
			(pads allowed)
			(copperpour not_allowed)
			(footprints allowed)
		)
		(placement
			(enabled no)
			(sheetname "")
		)
		(fill yes
			(thermal_gap 0.5)
			(thermal_bridge_width 0.5)
			(island_removal_mode 0)
		)
		(polygon
			(pts
				(arc
					(start 291.76218 -34.52241)
					(mid 291.0586 -34.52241)
					(end 291.76218 -34.52241)
				)
			)
		)
	)
	(zone
		(layers "B.Cu" "In9.Cu" "In11.Cu" "In13.Cu" "In15.Cu")
		(hatch none 0.5)
		(connect_pads
			(clearance 0)
		)
		(min_thickness 0.25)
		(keepout
			(tracks not_allowed)
			(vias allowed)
			(pads allowed)
			(copperpour not_allowed)
			(footprints allowed)
		)
		(placement
			(enabled no)
			(sheetname "")
		)
		(fill yes
			(thermal_gap 0.5)
			(thermal_bridge_width 0.5)
			(island_removal_mode 0)
		)
		(polygon
			(pts
				(arc
					(start 401.626324 -312.049922)
					(mid 400.973544 -312.049922)
					(end 401.626324 -312.049922)
				)
			)
		)
	)
	(zone
		(layers "B.Cu" "In9.Cu" "In11.Cu" "In13.Cu" "In15.Cu")
		(hatch none 0.5)
		(connect_pads
			(clearance 0)
		)
		(min_thickness 0.25)
		(keepout
			(tracks not_allowed)
			(vias allowed)
			(pads allowed)
			(copperpour not_allowed)
			(footprints allowed)
		)
		(placement
			(enabled no)
			(sheetname "")
		)
		(fill yes
			(thermal_gap 0.5)
			(thermal_bridge_width 0.5)
			(island_removal_mode 0)
		)
		(polygon
			(pts
				(arc
					(start 337.726274 -351.611438)
					(mid 337.022694 -351.611438)
					(end 337.726274 -351.611438)
				)
			)
		)
	)
	(zone
		(layers "B.Cu" "In9.Cu" "In11.Cu" "In13.Cu" "In15.Cu")
		(hatch none 0.5)
		(connect_pads
			(clearance 0)
		)
		(min_thickness 0.25)
		(keepout
			(tracks not_allowed)
			(vias allowed)
			(pads allowed)
			(copperpour not_allowed)
			(footprints allowed)
		)
		(placement
			(enabled no)
			(sheetname "")
		)
		(fill yes
			(thermal_gap 0.5)
			(thermal_bridge_width 0.5)
			(island_removal_mode 0)
		)
		(polygon
			(pts
				(arc
					(start 41.446958 -357.75773)
					(mid 40.743378 -357.75773)
					(end 41.446958 -357.75773)
				)
			)
		)
	)
	(zone
		(layers "B.Cu" "In9.Cu" "In11.Cu" "In13.Cu" "In15.Cu")
		(hatch none 0.5)
		(connect_pads
			(clearance 0)
		)
		(min_thickness 0.25)
		(keepout
			(tracks not_allowed)
			(vias allowed)
			(pads allowed)
			(copperpour not_allowed)
			(footprints allowed)
		)
		(placement
			(enabled no)
			(sheetname "")
		)
		(fill yes
			(thermal_gap 0.5)
			(thermal_bridge_width 0.5)
			(island_removal_mode 0)
		)
		(polygon
			(pts
				(arc
					(start 133.976618 -354.732082)
					(mid 133.273038 -354.732082)
					(end 133.976618 -354.732082)
				)
			)
		)
	)
	(zone
		(layers "B.Cu" "In9.Cu" "In11.Cu" "In13.Cu" "In15.Cu")
		(hatch none 0.5)
		(connect_pads
			(clearance 0)
		)
		(min_thickness 0.25)
		(keepout
			(tracks not_allowed)
			(vias allowed)
			(pads allowed)
			(copperpour not_allowed)
			(footprints allowed)
		)
		(placement
			(enabled no)
			(sheetname "")
		)
		(fill yes
			(thermal_gap 0.5)
			(thermal_bridge_width 0.5)
			(island_removal_mode 0)
		)
		(polygon
			(pts
				(arc
					(start 130.867658 -351.611438)
					(mid 130.164078 -351.611438)
					(end 130.867658 -351.611438)
				)
			)
		)
	)
	(zone
		(layers "B.Cu" "In9.Cu" "In11.Cu" "In13.Cu" "In15.Cu")
		(hatch none 0.5)
		(connect_pads
			(clearance 0)
		)
		(min_thickness 0.25)
		(keepout
			(tracks not_allowed)
			(vias allowed)
			(pads allowed)
			(copperpour not_allowed)
			(footprints allowed)
		)
		(placement
			(enabled no)
			(sheetname "")
		)
		(fill yes
			(thermal_gap 0.5)
			(thermal_bridge_width 0.5)
			(island_removal_mode 0)
		)
		(polygon
			(pts
				(arc
					(start 425.37634 -313.949842)
					(mid 424.72356 -313.949842)
					(end 425.37634 -313.949842)
				)
			)
		)
	)
	(zone
		(layers "B.Cu" "In9.Cu" "In11.Cu" "In13.Cu" "In15.Cu")
		(hatch none 0.5)
		(connect_pads
			(clearance 0)
		)
		(min_thickness 0.25)
		(keepout
			(tracks not_allowed)
			(vias allowed)
			(pads allowed)
			(copperpour not_allowed)
			(footprints allowed)
		)
		(placement
			(enabled no)
			(sheetname "")
		)
		(fill yes
			(thermal_gap 0.5)
			(thermal_bridge_width 0.5)
			(island_removal_mode 0)
		)
		(polygon
			(pts
				(arc
					(start 201.662284 -34.52241)
					(mid 200.958704 -34.52241)
					(end 201.662284 -34.52241)
				)
			)
		)
	)
	(zone
		(layers "B.Cu" "In9.Cu" "In11.Cu" "In13.Cu" "In15.Cu")
		(hatch none 0.5)
		(connect_pads
			(clearance 0)
		)
		(min_thickness 0.25)
		(keepout
			(tracks not_allowed)
			(vias allowed)
			(pads allowed)
			(copperpour not_allowed)
			(footprints allowed)
		)
		(placement
			(enabled no)
			(sheetname "")
		)
		(fill yes
			(thermal_gap 0.5)
			(thermal_bridge_width 0.5)
			(island_removal_mode 0)
		)
		(polygon
			(pts
				(arc
					(start 29.011118 -354.732082)
					(mid 28.307538 -354.732082)
					(end 29.011118 -354.732082)
				)
			)
		)
	)
	(zone
		(layers "B.Cu" "In9.Cu" "In11.Cu" "In13.Cu" "In15.Cu")
		(hatch none 0.5)
		(connect_pads
			(clearance 0)
		)
		(min_thickness 0.25)
		(keepout
			(tracks not_allowed)
			(vias allowed)
			(pads allowed)
			(copperpour not_allowed)
			(footprints allowed)
		)
		(placement
			(enabled no)
			(sheetname "")
		)
		(fill yes
			(thermal_gap 0.5)
			(thermal_bridge_width 0.5)
			(island_removal_mode 0)
		)
		(polygon
			(pts
				(arc
					(start 357.716582 -28.25877)
					(mid 357.013002 -28.25877)
					(end 357.716582 -28.25877)
				)
			)
		)
	)
	(zone
		(layers "B.Cu" "In9.Cu" "In11.Cu" "In13.Cu" "In15.Cu")
		(hatch none 0.5)
		(connect_pads
			(clearance 0)
		)
		(min_thickness 0.25)
		(keepout
			(tracks not_allowed)
			(vias allowed)
			(pads allowed)
			(copperpour not_allowed)
			(footprints allowed)
		)
		(placement
			(enabled no)
			(sheetname "")
		)
		(fill yes
			(thermal_gap 0.5)
			(thermal_bridge_width 0.5)
			(island_removal_mode 0)
		)
		(polygon
			(pts
				(arc
					(start 294.469566 -401.49018)
					(mid 293.710106 -401.49018)
					(end 294.469566 -401.49018)
				)
			)
		)
	)
	(zone
		(layers "B.Cu" "In9.Cu" "In11.Cu" "In13.Cu" "In15.Cu")
		(hatch none 0.5)
		(connect_pads
			(clearance 0)
		)
		(min_thickness 0.25)
		(keepout
			(tracks not_allowed)
			(vias allowed)
			(pads allowed)
			(copperpour not_allowed)
			(footprints allowed)
		)
		(placement
			(enabled no)
			(sheetname "")
		)
		(fill yes
			(thermal_gap 0.5)
			(thermal_bridge_width 0.5)
			(island_removal_mode 0)
		)
		(polygon
			(pts
				(arc
					(start 174.176436 -313.949842)
					(mid 173.523656 -313.949842)
					(end 174.176436 -313.949842)
				)
			)
		)
	)
	(zone
		(layers "B.Cu" "In9.Cu" "In11.Cu" "In13.Cu" "In15.Cu")
		(hatch none 0.5)
		(connect_pads
			(clearance 0)
		)
		(min_thickness 0.25)
		(keepout
			(tracks not_allowed)
			(vias allowed)
			(pads allowed)
			(copperpour not_allowed)
			(footprints allowed)
		)
		(placement
			(enabled no)
			(sheetname "")
		)
		(fill yes
			(thermal_gap 0.5)
			(thermal_bridge_width 0.5)
			(island_removal_mode 0)
		)
		(polygon
			(pts
				(arc
					(start 168.476422 -273.099784)
					(mid 167.823642 -273.099784)
					(end 168.476422 -273.099784)
				)
			)
		)
	)
	(zone
		(layers "B.Cu" "In9.Cu" "In11.Cu" "In13.Cu" "In15.Cu")
		(hatch none 0.5)
		(connect_pads
			(clearance 0)
		)
		(min_thickness 0.25)
		(keepout
			(tracks not_allowed)
			(vias allowed)
			(pads allowed)
			(copperpour not_allowed)
			(footprints allowed)
		)
		(placement
			(enabled no)
			(sheetname "")
		)
		(fill yes
			(thermal_gap 0.5)
			(thermal_bridge_width 0.5)
			(island_removal_mode 0)
		)
		(polygon
			(pts
				(arc
					(start 165.646862 -354.732082)
					(mid 164.943282 -354.732082)
					(end 165.646862 -354.732082)
				)
			)
		)
	)
	(zone
		(layers "B.Cu" "In9.Cu" "In11.Cu" "In13.Cu" "In15.Cu")
		(hatch none 0.5)
		(connect_pads
			(clearance 0)
		)
		(min_thickness 0.25)
		(keepout
			(tracks not_allowed)
			(vias allowed)
			(pads allowed)
			(copperpour not_allowed)
			(footprints allowed)
		)
		(placement
			(enabled no)
			(sheetname "")
		)
		(fill yes
			(thermal_gap 0.5)
			(thermal_bridge_width 0.5)
			(island_removal_mode 0)
		)
		(polygon
			(pts
				(arc
					(start 165.626288 -275.949918)
					(mid 164.973508 -275.949918)
					(end 165.626288 -275.949918)
				)
			)
		)
	)
	(zone
		(layers "B.Cu" "In9.Cu" "In11.Cu" "In13.Cu" "In15.Cu")
		(hatch none 0.5)
		(connect_pads
			(clearance 0)
		)
		(min_thickness 0.25)
		(keepout
			(tracks not_allowed)
			(vias allowed)
			(pads allowed)
			(copperpour not_allowed)
			(footprints allowed)
		)
		(placement
			(enabled no)
			(sheetname "")
		)
		(fill yes
			(thermal_gap 0.5)
			(thermal_bridge_width 0.5)
			(island_removal_mode 0)
		)
		(polygon
			(pts
				(arc
					(start 296.229532 -354.732082)
					(mid 295.525952 -354.732082)
					(end 296.229532 -354.732082)
				)
			)
		)
	)
	(zone
		(layers "B.Cu" "In9.Cu" "In11.Cu" "In13.Cu" "In15.Cu")
		(hatch none 0.5)
		(connect_pads
			(clearance 0)
		)
		(min_thickness 0.25)
		(keepout
			(tracks not_allowed)
			(vias allowed)
			(pads allowed)
			(copperpour not_allowed)
			(footprints allowed)
		)
		(placement
			(enabled no)
			(sheetname "")
		)
		(fill yes
			(thermal_gap 0.5)
			(thermal_bridge_width 0.5)
			(island_removal_mode 0)
		)
		(polygon
			(pts
				(arc
					(start 419.837362 -345.465146)
					(mid 419.133782 -345.465146)
					(end 419.837362 -345.465146)
				)
			)
		)
	)
	(zone
		(layers "B.Cu" "In9.Cu" "In11.Cu" "In13.Cu" "In15.Cu")
		(hatch none 0.5)
		(connect_pads
			(clearance 0)
		)
		(min_thickness 0.25)
		(keepout
			(tracks not_allowed)
			(vias allowed)
			(pads allowed)
			(copperpour not_allowed)
			(footprints allowed)
		)
		(placement
			(enabled no)
			(sheetname "")
		)
		(fill yes
			(thermal_gap 0.5)
			(thermal_bridge_width 0.5)
			(island_removal_mode 0)
		)
		(polygon
			(pts
				(arc
					(start 375.51233 -342.439498)
					(mid 374.80875 -342.439498)
					(end 375.51233 -342.439498)
				)
			)
		)
	)
	(zone
		(layers "B.Cu" "In9.Cu" "In11.Cu" "In13.Cu" "In15.Cu")
		(hatch none 0.5)
		(connect_pads
			(clearance 0)
		)
		(min_thickness 0.25)
		(keepout
			(tracks not_allowed)
			(vias allowed)
			(pads allowed)
			(copperpour not_allowed)
			(footprints allowed)
		)
		(placement
			(enabled no)
			(sheetname "")
		)
		(fill yes
			(thermal_gap 0.5)
			(thermal_bridge_width 0.5)
			(island_removal_mode 0)
		)
		(polygon
			(pts
				(arc
					(start 125.51664 -29.12237)
					(mid 124.81306 -29.12237)
					(end 125.51664 -29.12237)
				)
			)
		)
	)
	(zone
		(layers "B.Cu" "In9.Cu" "In11.Cu" "In13.Cu" "In15.Cu")
		(hatch none 0.5)
		(connect_pads
			(clearance 0)
		)
		(min_thickness 0.25)
		(keepout
			(tracks not_allowed)
			(vias allowed)
			(pads allowed)
			(copperpour not_allowed)
			(footprints allowed)
		)
		(placement
			(enabled no)
			(sheetname "")
		)
		(fill yes
			(thermal_gap 0.5)
			(thermal_bridge_width 0.5)
			(island_removal_mode 0)
		)
		(polygon
			(pts
				(arc
					(start 162.489642 -371.590062)
					(mid 161.730182 -371.590062)
					(end 162.489642 -371.590062)
				)
			)
		)
	)
	(zone
		(layers "B.Cu" "In9.Cu" "In11.Cu" "In13.Cu" "In15.Cu")
		(hatch none 0.5)
		(connect_pads
			(clearance 0)
		)
		(min_thickness 0.25)
		(keepout
			(tracks not_allowed)
			(vias allowed)
			(pads allowed)
			(copperpour not_allowed)
			(footprints allowed)
		)
		(placement
			(enabled no)
			(sheetname "")
		)
		(fill yes
			(thermal_gap 0.5)
			(thermal_bridge_width 0.5)
			(island_removal_mode 0)
		)
		(polygon
			(pts
				(arc
					(start 39.289736 -401.49018)
					(mid 38.530276 -401.49018)
					(end 39.289736 -401.49018)
				)
			)
		)
	)
	(zone
		(layers "B.Cu" "In9.Cu" "In11.Cu" "In13.Cu" "In15.Cu")
		(hatch none 0.5)
		(connect_pads
			(clearance 0)
		)
		(min_thickness 0.25)
		(keepout
			(tracks not_allowed)
			(vias allowed)
			(pads allowed)
			(copperpour not_allowed)
			(footprints allowed)
		)
		(placement
			(enabled no)
			(sheetname "")
		)
		(fill yes
			(thermal_gap 0.5)
			(thermal_bridge_width 0.5)
			(island_removal_mode 0)
		)
		(polygon
			(pts
				(arc
					(start 418.973762 -342.439498)
					(mid 418.270182 -342.439498)
					(end 418.973762 -342.439498)
				)
			)
		)
	)
	(zone
		(layers "B.Cu" "In9.Cu" "In11.Cu" "In13.Cu" "In15.Cu")
		(hatch none 0.5)
		(connect_pads
			(clearance 0)
		)
		(min_thickness 0.25)
		(keepout
			(tracks not_allowed)
			(vias allowed)
			(pads allowed)
			(copperpour not_allowed)
			(footprints allowed)
		)
		(placement
			(enabled no)
			(sheetname "")
		)
		(fill yes
			(thermal_gap 0.5)
			(thermal_bridge_width 0.5)
			(island_removal_mode 0)
		)
		(polygon
			(pts
				(arc
					(start 53.326284 -275.949918)
					(mid 52.673504 -275.949918)
					(end 53.326284 -275.949918)
				)
			)
		)
	)
	(zone
		(layers "B.Cu" "In9.Cu" "In11.Cu" "In13.Cu" "In15.Cu")
		(hatch none 0.5)
		(connect_pads
			(clearance 0)
		)
		(min_thickness 0.25)
		(keepout
			(tracks not_allowed)
			(vias allowed)
			(pads allowed)
			(copperpour not_allowed)
			(footprints allowed)
		)
		(placement
			(enabled no)
			(sheetname "")
		)
		(fill yes
			(thermal_gap 0.5)
			(thermal_bridge_width 0.5)
			(island_removal_mode 0)
		)
		(polygon
			(pts
				(arc
					(start 433.069492 -396.49019)
					(mid 432.310032 -396.49019)
					(end 433.069492 -396.49019)
				)
			)
		)
	)
	(zone
		(layers "B.Cu" "In9.Cu" "In11.Cu" "In13.Cu" "In15.Cu")
		(hatch none 0.5)
		(connect_pads
			(clearance 0)
		)
		(min_thickness 0.25)
		(keepout
			(tracks not_allowed)
			(vias allowed)
			(pads allowed)
			(copperpour not_allowed)
			(footprints allowed)
		)
		(placement
			(enabled no)
			(sheetname "")
		)
		(fill yes
			(thermal_gap 0.5)
			(thermal_bridge_width 0.5)
			(island_removal_mode 0)
		)
		(polygon
			(pts
				(arc
					(start 319.616328 -32.722312)
					(mid 318.912748 -32.722312)
					(end 319.616328 -32.722312)
				)
			)
		)
	)
	(zone
		(layers "B.Cu" "In9.Cu" "In11.Cu" "In13.Cu" "In15.Cu")
		(hatch none 0.5)
		(connect_pads
			(clearance 0)
		)
		(min_thickness 0.25)
		(keepout
			(tracks not_allowed)
			(vias allowed)
			(pads allowed)
			(copperpour not_allowed)
			(footprints allowed)
		)
		(placement
			(enabled no)
			(sheetname "")
		)
		(fill yes
			(thermal_gap 0.5)
			(thermal_bridge_width 0.5)
			(island_removal_mode 0)
		)
		(polygon
			(pts
				(arc
					(start 42.876216 -309.199788)
					(mid 42.223436 -309.199788)
					(end 42.876216 -309.199788)
				)
			)
		)
	)
	(zone
		(layers "B.Cu" "In9.Cu" "In11.Cu" "In13.Cu" "In15.Cu")
		(hatch none 0.5)
		(connect_pads
			(clearance 0)
		)
		(min_thickness 0.25)
		(keepout
			(tracks not_allowed)
			(vias allowed)
			(pads allowed)
			(copperpour not_allowed)
			(footprints allowed)
		)
		(placement
			(enabled no)
			(sheetname "")
		)
		(fill yes
			(thermal_gap 0.5)
			(thermal_bridge_width 0.5)
			(island_removal_mode 0)
		)
		(polygon
			(pts
				(arc
					(start 48.528478 -345.465146)
					(mid 47.824898 -345.465146)
					(end 48.528478 -345.465146)
				)
			)
		)
	)
	(zone
		(layers "B.Cu" "In9.Cu" "In11.Cu" "In13.Cu" "In15.Cu")
		(hatch none 0.5)
		(connect_pads
			(clearance 0)
		)
		(min_thickness 0.25)
		(keepout
			(tracks not_allowed)
			(vias allowed)
			(pads allowed)
			(copperpour not_allowed)
			(footprints allowed)
		)
		(placement
			(enabled no)
			(sheetname "")
		)
		(fill yes
			(thermal_gap 0.5)
			(thermal_bridge_width 0.5)
			(island_removal_mode 0)
		)
		(polygon
			(pts
				(arc
					(start 383.97561 -351.611438)
					(mid 383.27203 -351.611438)
					(end 383.97561 -351.611438)
				)
			)
		)
	)
	(zone
		(layers "B.Cu" "In9.Cu" "In11.Cu" "In13.Cu" "In15.Cu")
		(hatch none 0.5)
		(connect_pads
			(clearance 0)
		)
		(min_thickness 0.25)
		(keepout
			(tracks not_allowed)
			(vias allowed)
			(pads allowed)
			(copperpour not_allowed)
			(footprints allowed)
		)
		(placement
			(enabled no)
			(sheetname "")
		)
		(fill yes
			(thermal_gap 0.5)
			(thermal_bridge_width 0.5)
			(island_removal_mode 0)
		)
		(polygon
			(pts
				(arc
					(start 125.513338 -351.611438)
					(mid 124.809758 -351.611438)
					(end 125.513338 -351.611438)
				)
			)
		)
	)
	(zone
		(layers "B.Cu" "In9.Cu" "In11.Cu" "In13.Cu" "In15.Cu")
		(hatch none 0.5)
		(connect_pads
			(clearance 0)
		)
		(min_thickness 0.25)
		(keepout
			(tracks not_allowed)
			(vias allowed)
			(pads allowed)
			(copperpour not_allowed)
			(footprints allowed)
		)
		(placement
			(enabled no)
			(sheetname "")
		)
		(fill yes
			(thermal_gap 0.5)
			(thermal_bridge_width 0.5)
			(island_removal_mode 0)
		)
		(polygon
			(pts
				(arc
					(start 387.08457 -345.465146)
					(mid 386.38099 -345.465146)
					(end 387.08457 -345.465146)
				)
			)
		)
	)
	(zone
		(layers "B.Cu" "In9.Cu" "In11.Cu" "In13.Cu" "In15.Cu")
		(hatch none 0.5)
		(connect_pads
			(clearance 0)
		)
		(min_thickness 0.25)
		(keepout
			(tracks not_allowed)
			(vias allowed)
			(pads allowed)
			(copperpour not_allowed)
			(footprints allowed)
		)
		(placement
			(enabled no)
			(sheetname "")
		)
		(fill yes
			(thermal_gap 0.5)
			(thermal_bridge_width 0.5)
			(island_removal_mode 0)
		)
		(polygon
			(pts
				(arc
					(start 151.516588 -28.25877)
					(mid 150.813008 -28.25877)
					(end 151.516588 -28.25877)
				)
			)
		)
	)
	(zone
		(layers "B.Cu" "In9.Cu" "In11.Cu" "In13.Cu" "In15.Cu")
		(hatch none 0.5)
		(connect_pads
			(clearance 0)
		)
		(min_thickness 0.25)
		(keepout
			(tracks not_allowed)
			(vias allowed)
			(pads allowed)
			(copperpour not_allowed)
			(footprints allowed)
		)
		(placement
			(enabled no)
			(sheetname "")
		)
		(fill yes
			(thermal_gap 0.5)
			(thermal_bridge_width 0.5)
			(island_removal_mode 0)
		)
		(polygon
			(pts
				(arc
					(start 137.949178 -351.611438)
					(mid 137.245598 -351.611438)
					(end 137.949178 -351.611438)
				)
			)
		)
	)
	(zone
		(layers "B.Cu" "In9.Cu" "In11.Cu" "In13.Cu" "In15.Cu")
		(hatch none 0.5)
		(connect_pads
			(clearance 0)
		)
		(min_thickness 0.25)
		(keepout
			(tracks not_allowed)
			(vias allowed)
			(pads allowed)
			(copperpour not_allowed)
			(footprints allowed)
		)
		(placement
			(enabled no)
			(sheetname "")
		)
		(fill yes
			(thermal_gap 0.5)
			(thermal_bridge_width 0.5)
			(island_removal_mode 0)
		)
		(polygon
			(pts
				(arc
					(start 405.426418 -311.099962)
					(mid 404.773638 -311.099962)
					(end 405.426418 -311.099962)
				)
			)
		)
	)
	(zone
		(layers "B.Cu" "In9.Cu" "In11.Cu" "In13.Cu" "In15.Cu")
		(hatch none 0.5)
		(connect_pads
			(clearance 0)
		)
		(min_thickness 0.25)
		(keepout
			(tracks not_allowed)
			(vias allowed)
			(pads allowed)
			(copperpour not_allowed)
			(footprints allowed)
		)
		(placement
			(enabled no)
			(sheetname "")
		)
		(fill yes
			(thermal_gap 0.5)
			(thermal_bridge_width 0.5)
			(island_removal_mode 0)
		)
		(polygon
			(pts
				(arc
					(start 162.489642 -372.890034)
					(mid 161.730182 -372.890034)
					(end 162.489642 -372.890034)
				)
			)
		)
	)
	(zone
		(layers "B.Cu" "In9.Cu" "In11.Cu" "In13.Cu" "In15.Cu")
		(hatch none 0.5)
		(connect_pads
			(clearance 0)
		)
		(min_thickness 0.25)
		(keepout
			(tracks not_allowed)
			(vias allowed)
			(pads allowed)
			(copperpour not_allowed)
			(footprints allowed)
		)
		(placement
			(enabled no)
			(sheetname "")
		)
		(fill yes
			(thermal_gap 0.5)
			(thermal_bridge_width 0.5)
			(island_removal_mode 0)
		)
		(polygon
			(pts
				(arc
					(start 380.86665 -357.75773)
					(mid 380.16307 -357.75773)
					(end 380.86665 -357.75773)
				)
			)
		)
	)
	(zone
		(layers "B.Cu" "In9.Cu" "In11.Cu" "In13.Cu" "In15.Cu")
		(hatch none 0.5)
		(connect_pads
			(clearance 0)
		)
		(min_thickness 0.25)
		(keepout
			(tracks not_allowed)
			(vias allowed)
			(pads allowed)
			(copperpour not_allowed)
			(footprints allowed)
		)
		(placement
			(enabled no)
			(sheetname "")
		)
		(fill yes
			(thermal_gap 0.5)
			(thermal_bridge_width 0.5)
			(island_removal_mode 0)
		)
		(polygon
			(pts
				(arc
					(start 25.902158 -351.611438)
					(mid 25.198578 -351.611438)
					(end 25.902158 -351.611438)
				)
			)
		)
	)
	(zone
		(layers "B.Cu" "In9.Cu" "In11.Cu" "In13.Cu" "In15.Cu")
		(hatch none 0.5)
		(connect_pads
			(clearance 0)
		)
		(min_thickness 0.25)
		(keepout
			(tracks not_allowed)
			(vias allowed)
			(pads allowed)
			(copperpour not_allowed)
			(footprints allowed)
		)
		(placement
			(enabled no)
			(sheetname "")
		)
		(fill yes
			(thermal_gap 0.5)
			(thermal_bridge_width 0.5)
			(island_removal_mode 0)
		)
		(polygon
			(pts
				(arc
					(start 435.26964 -372.890034)
					(mid 434.51018 -372.890034)
					(end 435.26964 -372.890034)
				)
			)
		)
	)
	(zone
		(layers "B.Cu" "In9.Cu" "In11.Cu" "In13.Cu" "In15.Cu")
		(hatch none 0.5)
		(connect_pads
			(clearance 0)
		)
		(min_thickness 0.25)
		(keepout
			(tracks not_allowed)
			(vias allowed)
			(pads allowed)
			(copperpour not_allowed)
			(footprints allowed)
		)
		(placement
			(enabled no)
			(sheetname "")
		)
		(fill yes
			(thermal_gap 0.5)
			(thermal_bridge_width 0.5)
			(island_removal_mode 0)
		)
		(polygon
			(pts
				(arc
					(start 122.889772 -406.690068)
					(mid 122.130312 -406.690068)
					(end 122.889772 -406.690068)
				)
			)
		)
	)
	(zone
		(layers "B.Cu" "In9.Cu" "In11.Cu" "In13.Cu" "In15.Cu")
		(hatch none 0.5)
		(connect_pads
			(clearance 0)
		)
		(min_thickness 0.25)
		(keepout
			(tracks not_allowed)
			(vias allowed)
			(pads allowed)
			(copperpour not_allowed)
			(footprints allowed)
		)
		(placement
			(enabled no)
			(sheetname "")
		)
		(fill yes
			(thermal_gap 0.5)
			(thermal_bridge_width 0.5)
			(island_removal_mode 0)
		)
		(polygon
			(pts
				(arc
					(start 430.869598 -398.890236)
					(mid 430.110138 -398.890236)
					(end 430.869598 -398.890236)
				)
			)
		)
	)
	(zone
		(layers "B.Cu" "In9.Cu" "In11.Cu" "In13.Cu" "In15.Cu")
		(hatch none 0.5)
		(connect_pads
			(clearance 0)
		)
		(min_thickness 0.25)
		(keepout
			(tracks not_allowed)
			(vias allowed)
			(pads allowed)
			(copperpour not_allowed)
			(footprints allowed)
		)
		(placement
			(enabled no)
			(sheetname "")
		)
		(fill yes
			(thermal_gap 0.5)
			(thermal_bridge_width 0.5)
			(island_removal_mode 0)
		)
		(polygon
			(pts
				(arc
					(start 74.489564 -379.390148)
					(mid 73.730104 -379.390148)
					(end 74.489564 -379.390148)
				)
			)
		)
	)
	(zone
		(layers "B.Cu" "In9.Cu" "In11.Cu" "In13.Cu" "In15.Cu")
		(hatch none 0.5)
		(connect_pads
			(clearance 0)
		)
		(min_thickness 0.25)
		(keepout
			(tracks not_allowed)
			(vias allowed)
			(pads allowed)
			(copperpour not_allowed)
			(footprints allowed)
		)
		(placement
			(enabled no)
			(sheetname "")
		)
		(fill yes
			(thermal_gap 0.5)
			(thermal_bridge_width 0.5)
			(island_removal_mode 0)
		)
		(polygon
			(pts
				(arc
					(start 272.226278 -312.049922)
					(mid 271.573498 -312.049922)
					(end 272.226278 -312.049922)
				)
			)
		)
	)
	(zone
		(layers "B.Cu" "In9.Cu" "In11.Cu" "In13.Cu" "In15.Cu")
		(hatch none 0.5)
		(connect_pads
			(clearance 0)
		)
		(min_thickness 0.25)
		(keepout
			(tracks not_allowed)
			(vias allowed)
			(pads allowed)
			(copperpour not_allowed)
			(footprints allowed)
		)
		(placement
			(enabled no)
			(sheetname "")
		)
		(fill yes
			(thermal_gap 0.5)
			(thermal_bridge_width 0.5)
			(island_removal_mode 0)
		)
		(polygon
			(pts
				(arc
					(start 387.94817 -357.75773)
					(mid 387.24459 -357.75773)
					(end 387.94817 -357.75773)
				)
			)
		)
	)
	(zone
		(layers "B.Cu" "In9.Cu" "In11.Cu" "In13.Cu" "In15.Cu")
		(hatch none 0.5)
		(connect_pads
			(clearance 0)
		)
		(min_thickness 0.25)
		(keepout
			(tracks not_allowed)
			(vias allowed)
			(pads allowed)
			(copperpour not_allowed)
			(footprints allowed)
		)
		(placement
			(enabled no)
			(sheetname "")
		)
		(fill yes
			(thermal_gap 0.5)
			(thermal_bridge_width 0.5)
			(island_removal_mode 0)
		)
		(polygon
			(pts
				(arc
					(start 93.677232 -351.611438)
					(mid 92.973652 -351.611438)
					(end 93.677232 -351.611438)
				)
			)
		)
	)
	(zone
		(layers "B.Cu" "In9.Cu" "In11.Cu" "In13.Cu" "In15.Cu")
		(hatch none 0.5)
		(connect_pads
			(clearance 0)
		)
		(min_thickness 0.25)
		(keepout
			(tracks not_allowed)
			(vias allowed)
			(pads allowed)
			(copperpour not_allowed)
			(footprints allowed)
		)
		(placement
			(enabled no)
			(sheetname "")
		)
		(fill yes
			(thermal_gap 0.5)
			(thermal_bridge_width 0.5)
			(island_removal_mode 0)
		)
		(polygon
			(pts
				(arc
					(start 176.076356 -313.949842)
					(mid 175.423576 -313.949842)
					(end 176.076356 -313.949842)
				)
			)
		)
	)
	(zone
		(layers "B.Cu" "In9.Cu" "In11.Cu" "In13.Cu" "In15.Cu")
		(hatch none 0.5)
		(connect_pads
			(clearance 0)
		)
		(min_thickness 0.25)
		(keepout
			(tracks not_allowed)
			(vias allowed)
			(pads allowed)
			(copperpour not_allowed)
			(footprints allowed)
		)
		(placement
			(enabled no)
			(sheetname "")
		)
		(fill yes
			(thermal_gap 0.5)
			(thermal_bridge_width 0.5)
			(island_removal_mode 0)
		)
		(polygon
			(pts
				(arc
					(start 197.600062 -345.465146)
					(mid 196.896482 -345.465146)
					(end 197.600062 -345.465146)
				)
			)
		)
	)
	(zone
		(layers "B.Cu" "In9.Cu" "In11.Cu" "In13.Cu" "In15.Cu")
		(hatch none 0.5)
		(connect_pads
			(clearance 0)
		)
		(min_thickness 0.25)
		(keepout
			(tracks not_allowed)
			(vias allowed)
			(pads allowed)
			(copperpour not_allowed)
			(footprints allowed)
		)
		(placement
			(enabled no)
			(sheetname "")
		)
		(fill yes
			(thermal_gap 0.5)
			(thermal_bridge_width 0.5)
			(island_removal_mode 0)
		)
		(polygon
			(pts
				(arc
					(start 322.181474 -357.75773)
					(mid 321.477894 -357.75773)
					(end 322.181474 -357.75773)
				)
			)
		)
	)
	(zone
		(layers "B.Cu" "In9.Cu" "In11.Cu" "In13.Cu" "In15.Cu")
		(hatch none 0.5)
		(connect_pads
			(clearance 0)
		)
		(min_thickness 0.25)
		(keepout
			(tracks not_allowed)
			(vias allowed)
			(pads allowed)
			(copperpour not_allowed)
			(footprints allowed)
		)
		(placement
			(enabled no)
			(sheetname "")
		)
		(fill yes
			(thermal_gap 0.5)
			(thermal_bridge_width 0.5)
			(island_removal_mode 0)
		)
		(polygon
			(pts
				(arc
					(start 45.419518 -351.611438)
					(mid 44.715938 -351.611438)
					(end 45.419518 -351.611438)
				)
			)
		)
	)
	(zone
		(layers "B.Cu" "In9.Cu" "In11.Cu" "In13.Cu" "In15.Cu")
		(hatch none 0.5)
		(connect_pads
			(clearance 0)
		)
		(min_thickness 0.25)
		(keepout
			(tracks not_allowed)
			(vias allowed)
			(pads allowed)
			(copperpour not_allowed)
			(footprints allowed)
		)
		(placement
			(enabled no)
			(sheetname "")
		)
		(fill yes
			(thermal_gap 0.5)
			(thermal_bridge_width 0.5)
			(island_removal_mode 0)
		)
		(polygon
			(pts
				(arc
					(start 141.058138 -354.732082)
					(mid 140.354558 -354.732082)
					(end 141.058138 -354.732082)
				)
			)
		)
	)
	(zone
		(layers "B.Cu" "In9.Cu" "In11.Cu" "In13.Cu" "In15.Cu")
		(hatch none 0.5)
		(connect_pads
			(clearance 0)
		)
		(min_thickness 0.25)
		(keepout
			(tracks not_allowed)
			(vias allowed)
			(pads allowed)
			(copperpour not_allowed)
			(footprints allowed)
		)
		(placement
			(enabled no)
			(sheetname "")
		)
		(fill yes
			(thermal_gap 0.5)
			(thermal_bridge_width 0.5)
			(island_removal_mode 0)
		)
		(polygon
			(pts
				(arc
					(start 399.726404 -275.949918)
					(mid 399.073624 -275.949918)
					(end 399.726404 -275.949918)
				)
			)
		)
	)
	(zone
		(layers "B.Cu" "In9.Cu" "In11.Cu" "In13.Cu" "In15.Cu")
		(hatch none 0.5)
		(connect_pads
			(clearance 0)
		)
		(min_thickness 0.25)
		(keepout
			(tracks not_allowed)
			(vias allowed)
			(pads allowed)
			(copperpour not_allowed)
			(footprints allowed)
		)
		(placement
			(enabled no)
			(sheetname "")
		)
		(fill yes
			(thermal_gap 0.5)
			(thermal_bridge_width 0.5)
			(island_removal_mode 0)
		)
		(polygon
			(pts
				(arc
					(start 301.676308 -312.999882)
					(mid 301.023528 -312.999882)
					(end 301.676308 -312.999882)
				)
			)
		)
	)
	(zone
		(layers "B.Cu" "In9.Cu" "In11.Cu" "In13.Cu" "In15.Cu")
		(hatch none 0.5)
		(connect_pads
			(clearance 0)
		)
		(min_thickness 0.25)
		(keepout
			(tracks not_allowed)
			(vias allowed)
			(pads allowed)
			(copperpour not_allowed)
			(footprints allowed)
		)
		(placement
			(enabled no)
			(sheetname "")
		)
		(fill yes
			(thermal_gap 0.5)
			(thermal_bridge_width 0.5)
			(island_removal_mode 0)
		)
		(polygon
			(pts
				(arc
					(start 371.53977 -351.611438)
					(mid 370.83619 -351.611438)
					(end 371.53977 -351.611438)
				)
			)
		)
	)
	(zone
		(layers "B.Cu" "In9.Cu" "In11.Cu" "In13.Cu" "In15.Cu")
		(hatch none 0.5)
		(connect_pads
			(clearance 0)
		)
		(min_thickness 0.25)
		(keepout
			(tracks not_allowed)
			(vias allowed)
			(pads allowed)
			(copperpour not_allowed)
			(footprints allowed)
		)
		(placement
			(enabled no)
			(sheetname "")
		)
		(fill yes
			(thermal_gap 0.5)
			(thermal_bridge_width 0.5)
			(island_removal_mode 0)
		)
		(polygon
			(pts
				(arc
					(start 66.626232 -312.049922)
					(mid 65.973452 -312.049922)
					(end 66.626232 -312.049922)
				)
			)
		)
	)
	(zone
		(layers "B.Cu" "In9.Cu" "In11.Cu" "In13.Cu" "In15.Cu")
		(hatch none 0.5)
		(connect_pads
			(clearance 0)
		)
		(min_thickness 0.25)
		(keepout
			(tracks not_allowed)
			(vias allowed)
			(pads allowed)
			(copperpour not_allowed)
			(footprints allowed)
		)
		(placement
			(enabled no)
			(sheetname "")
		)
		(fill yes
			(thermal_gap 0.5)
			(thermal_bridge_width 0.5)
			(island_removal_mode 0)
		)
		(polygon
			(pts
				(arc
					(start 423.47642 -312.999882)
					(mid 422.82364 -312.999882)
					(end 423.47642 -312.999882)
				)
			)
		)
	)
	(zone
		(layers "B.Cu" "In9.Cu" "In11.Cu" "In13.Cu" "In15.Cu")
		(hatch none 0.5)
		(connect_pads
			(clearance 0)
		)
		(min_thickness 0.25)
		(keepout
			(tracks not_allowed)
			(vias allowed)
			(pads allowed)
			(copperpour not_allowed)
			(footprints allowed)
		)
		(placement
			(enabled no)
			(sheetname "")
		)
		(fill yes
			(thermal_gap 0.5)
			(thermal_bridge_width 0.5)
			(island_removal_mode 0)
		)
		(polygon
			(pts
				(arc
					(start 178.082702 -354.732082)
					(mid 177.379122 -354.732082)
					(end 178.082702 -354.732082)
				)
			)
		)
	)
	(zone
		(layers "B.Cu" "In9.Cu" "In11.Cu" "In13.Cu" "In15.Cu")
		(hatch none 0.5)
		(connect_pads
			(clearance 0)
		)
		(min_thickness 0.25)
		(keepout
			(tracks not_allowed)
			(vias allowed)
			(pads allowed)
			(copperpour not_allowed)
			(footprints allowed)
		)
		(placement
			(enabled no)
			(sheetname "")
		)
		(fill yes
			(thermal_gap 0.5)
			(thermal_bridge_width 0.5)
			(island_removal_mode 0)
		)
		(polygon
			(pts
				(arc
					(start 409.716478 -29.12237)
					(mid 409.012898 -29.12237)
					(end 409.716478 -29.12237)
				)
			)
		)
	)
	(zone
		(layers "B.Cu" "In9.Cu" "In11.Cu" "In13.Cu" "In15.Cu")
		(hatch none 0.5)
		(connect_pads
			(clearance 0)
		)
		(min_thickness 0.25)
		(keepout
			(tracks not_allowed)
			(vias allowed)
			(pads allowed)
			(copperpour not_allowed)
			(footprints allowed)
		)
		(placement
			(enabled no)
			(sheetname "")
		)
		(fill yes
			(thermal_gap 0.5)
			(thermal_bridge_width 0.5)
			(island_removal_mode 0)
		)
		(polygon
			(pts
				(arc
					(start 386.869686 -406.690068)
					(mid 386.110226 -406.690068)
					(end 386.869686 -406.690068)
				)
			)
		)
	)
	(zone
		(layers "B.Cu" "In9.Cu" "In11.Cu" "In13.Cu" "In15.Cu")
		(hatch none 0.5)
		(connect_pads
			(clearance 0)
		)
		(min_thickness 0.25)
		(keepout
			(tracks not_allowed)
			(vias allowed)
			(pads allowed)
			(copperpour not_allowed)
			(footprints allowed)
		)
		(placement
			(enabled no)
			(sheetname "")
		)
		(fill yes
			(thermal_gap 0.5)
			(thermal_bridge_width 0.5)
			(island_removal_mode 0)
		)
		(polygon
			(pts
				(arc
					(start 290.011612 -342.439498)
					(mid 289.308032 -342.439498)
					(end 290.011612 -342.439498)
				)
			)
		)
	)
	(zone
		(layers "B.Cu" "In9.Cu" "In11.Cu" "In13.Cu" "In15.Cu")
		(hatch none 0.5)
		(connect_pads
			(clearance 0)
		)
		(min_thickness 0.25)
		(keepout
			(tracks not_allowed)
			(vias allowed)
			(pads allowed)
			(copperpour not_allowed)
			(footprints allowed)
		)
		(placement
			(enabled no)
			(sheetname "")
		)
		(fill yes
			(thermal_gap 0.5)
			(thermal_bridge_width 0.5)
			(island_removal_mode 0)
		)
		(polygon
			(pts
				(arc
					(start 47.62627 -274.999958)
					(mid 46.97349 -274.999958)
					(end 47.62627 -274.999958)
				)
			)
		)
	)
	(zone
		(layers "B.Cu" "In9.Cu" "In11.Cu" "In13.Cu" "In15.Cu")
		(hatch none 0.5)
		(connect_pads
			(clearance 0)
		)
		(min_thickness 0.25)
		(keepout
			(tracks not_allowed)
			(vias allowed)
			(pads allowed)
			(copperpour not_allowed)
			(footprints allowed)
		)
		(placement
			(enabled no)
			(sheetname "")
		)
		(fill yes
			(thermal_gap 0.5)
			(thermal_bridge_width 0.5)
			(island_removal_mode 0)
		)
		(polygon
			(pts
				(arc
					(start 374.64873 -342.439498)
					(mid 373.94515 -342.439498)
					(end 374.64873 -342.439498)
				)
			)
		)
	)
	(zone
		(layers "B.Cu" "In9.Cu" "In11.Cu" "In13.Cu" "In15.Cu")
		(hatch none 0.5)
		(connect_pads
			(clearance 0)
		)
		(min_thickness 0.25)
		(keepout
			(tracks not_allowed)
			(vias allowed)
			(pads allowed)
			(copperpour not_allowed)
			(footprints allowed)
		)
		(placement
			(enabled no)
			(sheetname "")
		)
		(fill yes
			(thermal_gap 0.5)
			(thermal_bridge_width 0.5)
			(island_removal_mode 0)
		)
		(polygon
			(pts
				(arc
					(start 331.869796 -378.290074)
					(mid 331.110336 -378.290074)
					(end 331.869796 -378.290074)
				)
			)
		)
	)
	(zone
		(layers "B.Cu" "In9.Cu" "In11.Cu" "In13.Cu" "In15.Cu")
		(hatch none 0.5)
		(connect_pads
			(clearance 0)
		)
		(min_thickness 0.25)
		(keepout
			(tracks not_allowed)
			(vias allowed)
			(pads allowed)
			(copperpour not_allowed)
			(footprints allowed)
		)
		(placement
			(enabled no)
			(sheetname "")
		)
		(fill yes
			(thermal_gap 0.5)
			(thermal_bridge_width 0.5)
			(island_removal_mode 0)
		)
		(polygon
			(pts
				(arc
					(start 175.689768 -372.890034)
					(mid 174.930308 -372.890034)
					(end 175.689768 -372.890034)
				)
			)
		)
	)
	(zone
		(layers "B.Cu" "In9.Cu" "In11.Cu" "In13.Cu" "In15.Cu")
		(hatch none 0.5)
		(connect_pads
			(clearance 0)
		)
		(min_thickness 0.25)
		(keepout
			(tracks not_allowed)
			(vias allowed)
			(pads allowed)
			(copperpour not_allowed)
			(footprints allowed)
		)
		(placement
			(enabled no)
			(sheetname "")
		)
		(fill yes
			(thermal_gap 0.5)
			(thermal_bridge_width 0.5)
			(island_removal_mode 0)
		)
		(polygon
			(pts
				(arc
					(start 296.669714 -375.69013)
					(mid 295.910254 -375.69013)
					(end 296.669714 -375.69013)
				)
			)
		)
	)
	(zone
		(layers "B.Cu" "In9.Cu" "In11.Cu" "In13.Cu" "In15.Cu")
		(hatch none 0.5)
		(connect_pads
			(clearance 0)
		)
		(min_thickness 0.25)
		(keepout
			(tracks not_allowed)
			(vias allowed)
			(pads allowed)
			(copperpour not_allowed)
			(footprints allowed)
		)
		(placement
			(enabled no)
			(sheetname "")
		)
		(fill yes
			(thermal_gap 0.5)
			(thermal_bridge_width 0.5)
			(island_removal_mode 0)
		)
		(polygon
			(pts
				(arc
					(start 149.662388 -30.058868)
					(mid 148.958808 -30.058868)
					(end 149.662388 -30.058868)
				)
			)
		)
	)
	(zone
		(layers "B.Cu" "In9.Cu" "In11.Cu" "In13.Cu" "In15.Cu")
		(hatch none 0.5)
		(connect_pads
			(clearance 0)
		)
		(min_thickness 0.25)
		(keepout
			(tracks not_allowed)
			(vias allowed)
			(pads allowed)
			(copperpour not_allowed)
			(footprints allowed)
		)
		(placement
			(enabled no)
			(sheetname "")
		)
		(fill yes
			(thermal_gap 0.5)
			(thermal_bridge_width 0.5)
			(island_removal_mode 0)
		)
		(polygon
			(pts
				(arc
					(start 415.864802 -348.58579)
					(mid 415.161222 -348.58579)
					(end 415.864802 -348.58579)
				)
			)
		)
	)
	(zone
		(layers "B.Cu" "In9.Cu" "In11.Cu" "In13.Cu" "In15.Cu")
		(hatch none 0.5)
		(connect_pads
			(clearance 0)
		)
		(min_thickness 0.25)
		(keepout
			(tracks not_allowed)
			(vias allowed)
			(pads allowed)
			(copperpour not_allowed)
			(footprints allowed)
		)
		(placement
			(enabled no)
			(sheetname "")
		)
		(fill yes
			(thermal_gap 0.5)
			(thermal_bridge_width 0.5)
			(island_removal_mode 0)
		)
		(polygon
			(pts
				(arc
					(start 177.026316 -312.049922)
					(mid 176.373536 -312.049922)
					(end 177.026316 -312.049922)
				)
			)
		)
	)
	(zone
		(layers "B.Cu" "In9.Cu" "In11.Cu" "In13.Cu" "In15.Cu")
		(hatch none 0.5)
		(connect_pads
			(clearance 0)
		)
		(min_thickness 0.25)
		(keepout
			(tracks not_allowed)
			(vias allowed)
			(pads allowed)
			(copperpour not_allowed)
			(footprints allowed)
		)
		(placement
			(enabled no)
			(sheetname "")
		)
		(fill yes
			(thermal_gap 0.5)
			(thermal_bridge_width 0.5)
			(island_removal_mode 0)
		)
		(polygon
			(pts
				(arc
					(start 35.41649 -28.25877)
					(mid 34.71291 -28.25877)
					(end 35.41649 -28.25877)
				)
			)
		)
	)
	(zone
		(layers "B.Cu" "In9.Cu" "In11.Cu" "In13.Cu" "In15.Cu")
		(hatch none 0.5)
		(connect_pads
			(clearance 0)
		)
		(min_thickness 0.25)
		(keepout
			(tracks not_allowed)
			(vias allowed)
			(pads allowed)
			(copperpour not_allowed)
			(footprints allowed)
		)
		(placement
			(enabled no)
			(sheetname "")
		)
		(fill yes
			(thermal_gap 0.5)
			(thermal_bridge_width 0.5)
			(island_removal_mode 0)
		)
		(polygon
			(pts
				(arc
					(start 76.689712 -379.590046)
					(mid 75.930252 -379.590046)
					(end 76.689712 -379.590046)
				)
			)
		)
	)
	(zone
		(layers "B.Cu" "In9.Cu" "In11.Cu" "In13.Cu" "In15.Cu")
		(hatch none 0.5)
		(connect_pads
			(clearance 0)
		)
		(min_thickness 0.25)
		(keepout
			(tracks not_allowed)
			(vias allowed)
			(pads allowed)
			(copperpour not_allowed)
			(footprints allowed)
		)
		(placement
			(enabled no)
			(sheetname "")
		)
		(fill yes
			(thermal_gap 0.5)
			(thermal_bridge_width 0.5)
			(island_removal_mode 0)
		)
		(polygon
			(pts
				(arc
					(start 192.226438 -306.349908)
					(mid 191.573658 -306.349908)
					(end 192.226438 -306.349908)
				)
			)
		)
	)
	(zone
		(layers "B.Cu" "In9.Cu" "In11.Cu" "In13.Cu" "In15.Cu")
		(hatch none 0.5)
		(connect_pads
			(clearance 0)
		)
		(min_thickness 0.25)
		(keepout
			(tracks not_allowed)
			(vias allowed)
			(pads allowed)
			(copperpour not_allowed)
			(footprints allowed)
		)
		(placement
			(enabled no)
			(sheetname "")
		)
		(fill yes
			(thermal_gap 0.5)
			(thermal_bridge_width 0.5)
			(island_removal_mode 0)
		)
		(polygon
			(pts
				(arc
					(start 298.826174 -311.099962)
					(mid 298.173394 -311.099962)
					(end 298.826174 -311.099962)
				)
			)
		)
	)
	(zone
		(layers "B.Cu" "In9.Cu" "In11.Cu" "In13.Cu" "In15.Cu")
		(hatch none 0.5)
		(connect_pads
			(clearance 0)
		)
		(min_thickness 0.25)
		(keepout
			(tracks not_allowed)
			(vias allowed)
			(pads allowed)
			(copperpour not_allowed)
			(footprints allowed)
		)
		(placement
			(enabled no)
			(sheetname "")
		)
		(fill yes
			(thermal_gap 0.5)
			(thermal_bridge_width 0.5)
			(island_removal_mode 0)
		)
		(polygon
			(pts
				(arc
					(start 432.273202 -357.75773)
					(mid 431.569622 -357.75773)
					(end 432.273202 -357.75773)
				)
			)
		)
	)
	(zone
		(layers "B.Cu" "In9.Cu" "In11.Cu" "In13.Cu" "In15.Cu")
		(hatch none 0.5)
		(connect_pads
			(clearance 0)
		)
		(min_thickness 0.25)
		(keepout
			(tracks not_allowed)
			(vias allowed)
			(pads allowed)
			(copperpour not_allowed)
			(footprints allowed)
		)
		(placement
			(enabled no)
			(sheetname "")
		)
		(fill yes
			(thermal_gap 0.5)
			(thermal_bridge_width 0.5)
			(island_removal_mode 0)
		)
		(polygon
			(pts
				(arc
					(start 30.489652 -402.790152)
					(mid 29.730192 -402.790152)
					(end 30.489652 -402.790152)
				)
			)
		)
	)
	(zone
		(layers "B.Cu" "In9.Cu" "In11.Cu" "In13.Cu" "In15.Cu")
		(hatch none 0.5)
		(connect_pads
			(clearance 0)
		)
		(min_thickness 0.25)
		(keepout
			(tracks not_allowed)
			(vias allowed)
			(pads allowed)
			(copperpour not_allowed)
			(footprints allowed)
		)
		(placement
			(enabled no)
			(sheetname "")
		)
		(fill yes
			(thermal_gap 0.5)
			(thermal_bridge_width 0.5)
			(island_removal_mode 0)
		)
		(polygon
			(pts
				(arc
					(start 44.776136 -308.249828)
					(mid 44.123356 -308.249828)
					(end 44.776136 -308.249828)
				)
			)
		)
	)
	(zone
		(layers "B.Cu" "In9.Cu" "In11.Cu" "In13.Cu" "In15.Cu")
		(hatch none 0.5)
		(connect_pads
			(clearance 0)
		)
		(min_thickness 0.25)
		(keepout
			(tracks not_allowed)
			(vias allowed)
			(pads allowed)
			(copperpour not_allowed)
			(footprints allowed)
		)
		(placement
			(enabled no)
			(sheetname "")
		)
		(fill yes
			(thermal_gap 0.5)
			(thermal_bridge_width 0.5)
			(island_removal_mode 0)
		)
		(polygon
			(pts
				(arc
					(start 203.516484 -29.12237)
					(mid 202.812904 -29.12237)
					(end 203.516484 -29.12237)
				)
			)
		)
	)
	(zone
		(layers "B.Cu" "In9.Cu" "In11.Cu" "In13.Cu" "In15.Cu")
		(hatch none 0.5)
		(connect_pads
			(clearance 0)
		)
		(min_thickness 0.25)
		(keepout
			(tracks not_allowed)
			(vias allowed)
			(pads allowed)
			(copperpour not_allowed)
			(footprints allowed)
		)
		(placement
			(enabled no)
			(sheetname "")
		)
		(fill yes
			(thermal_gap 0.5)
			(thermal_bridge_width 0.5)
			(island_removal_mode 0)
		)
		(polygon
			(pts
				(arc
					(start 182.055262 -351.611438)
					(mid 181.351682 -351.611438)
					(end 182.055262 -351.611438)
				)
			)
		)
	)
	(zone
		(layers "B.Cu" "In9.Cu" "In11.Cu" "In13.Cu" "In15.Cu")
		(hatch none 0.5)
		(connect_pads
			(clearance 0)
		)
		(min_thickness 0.25)
		(keepout
			(tracks not_allowed)
			(vias allowed)
			(pads allowed)
			(copperpour not_allowed)
			(footprints allowed)
		)
		(placement
			(enabled no)
			(sheetname "")
		)
		(fill yes
			(thermal_gap 0.5)
			(thermal_bridge_width 0.5)
			(island_removal_mode 0)
		)
		(polygon
			(pts
				(arc
					(start 345.069668 -378.290074)
					(mid 344.310208 -378.290074)
					(end 345.069668 -378.290074)
				)
			)
		)
	)
	(zone
		(layers "B.Cu" "In9.Cu" "In11.Cu" "In13.Cu" "In15.Cu")
		(hatch none 0.5)
		(connect_pads
			(clearance 0)
		)
		(min_thickness 0.25)
		(keepout
			(tracks not_allowed)
			(vias allowed)
			(pads allowed)
			(copperpour not_allowed)
			(footprints allowed)
		)
		(placement
			(enabled no)
			(sheetname "")
		)
		(fill yes
			(thermal_gap 0.5)
			(thermal_bridge_width 0.5)
			(island_removal_mode 0)
		)
		(polygon
			(pts
				(arc
					(start 74.489564 -406.690068)
					(mid 73.730104 -406.690068)
					(end 74.489564 -406.690068)
				)
			)
		)
	)
	(zone
		(layers "B.Cu" "In9.Cu" "In11.Cu" "In13.Cu" "In15.Cu")
		(hatch none 0.5)
		(connect_pads
			(clearance 0)
		)
		(min_thickness 0.25)
		(keepout
			(tracks not_allowed)
			(vias allowed)
			(pads allowed)
			(copperpour not_allowed)
			(footprints allowed)
		)
		(placement
			(enabled no)
			(sheetname "")
		)
		(fill yes
			(thermal_gap 0.5)
			(thermal_bridge_width 0.5)
			(island_removal_mode 0)
		)
		(polygon
			(pts
				(arc
					(start 393.076176 -274.049744)
					(mid 392.423396 -274.049744)
					(end 393.076176 -274.049744)
				)
			)
		)
	)
	(zone
		(layers "B.Cu" "In9.Cu" "In11.Cu" "In13.Cu" "In15.Cu")
		(hatch none 0.5)
		(connect_pads
			(clearance 0)
		)
		(min_thickness 0.25)
		(keepout
			(tracks not_allowed)
			(vias allowed)
			(pads allowed)
			(copperpour not_allowed)
			(footprints allowed)
		)
		(placement
			(enabled no)
			(sheetname "")
		)
		(fill yes
			(thermal_gap 0.5)
			(thermal_bridge_width 0.5)
			(island_removal_mode 0)
		)
		(polygon
			(pts
				(arc
					(start 116.289836 -383.490216)
					(mid 115.530376 -383.490216)
					(end 116.289836 -383.490216)
				)
			)
		)
	)
	(zone
		(layers "B.Cu" "In9.Cu" "In11.Cu" "In13.Cu" "In15.Cu")
		(hatch none 0.5)
		(connect_pads
			(clearance 0)
		)
		(min_thickness 0.25)
		(keepout
			(tracks not_allowed)
			(vias allowed)
			(pads allowed)
			(copperpour not_allowed)
			(footprints allowed)
		)
		(placement
			(enabled no)
			(sheetname "")
		)
		(fill yes
			(thermal_gap 0.5)
			(thermal_bridge_width 0.5)
			(island_removal_mode 0)
		)
		(polygon
			(pts
				(arc
					(start 283.626306 -275.949918)
					(mid 282.973526 -275.949918)
					(end 283.626306 -275.949918)
				)
			)
		)
	)
	(zone
		(layers "B.Cu" "In9.Cu" "In11.Cu" "In13.Cu" "In15.Cu")
		(hatch none 0.5)
		(connect_pads
			(clearance 0)
		)
		(min_thickness 0.25)
		(keepout
			(tracks not_allowed)
			(vias allowed)
			(pads allowed)
			(copperpour not_allowed)
			(footprints allowed)
		)
		(placement
			(enabled no)
			(sheetname "")
		)
		(fill yes
			(thermal_gap 0.5)
			(thermal_bridge_width 0.5)
			(island_removal_mode 0)
		)
		(polygon
			(pts
				(arc
					(start 431.409602 -354.732082)
					(mid 430.706022 -354.732082)
					(end 431.409602 -354.732082)
				)
			)
		)
	)
	(zone
		(layers "B.Cu" "In9.Cu" "In11.Cu" "In13.Cu" "In15.Cu")
		(hatch none 0.5)
		(connect_pads
			(clearance 0)
		)
		(min_thickness 0.25)
		(keepout
			(tracks not_allowed)
			(vias allowed)
			(pads allowed)
			(copperpour not_allowed)
			(footprints allowed)
		)
		(placement
			(enabled no)
			(sheetname "")
		)
		(fill yes
			(thermal_gap 0.5)
			(thermal_bridge_width 0.5)
			(island_removal_mode 0)
		)
		(polygon
			(pts
				(arc
					(start 181.77637 -312.999882)
					(mid 181.12359 -312.999882)
					(end 181.77637 -312.999882)
				)
			)
		)
	)
	(zone
		(layers "B.Cu" "In9.Cu" "In11.Cu" "In13.Cu" "In15.Cu")
		(hatch none 0.5)
		(connect_pads
			(clearance 0)
		)
		(min_thickness 0.25)
		(keepout
			(tracks not_allowed)
			(vias allowed)
			(pads allowed)
			(copperpour not_allowed)
			(footprints allowed)
		)
		(placement
			(enabled no)
			(sheetname "")
		)
		(fill yes
			(thermal_gap 0.5)
			(thermal_bridge_width 0.5)
			(island_removal_mode 0)
		)
		(polygon
			(pts
				(arc
					(start 290.069524 -401.49018)
					(mid 289.310064 -401.49018)
					(end 290.069524 -401.49018)
				)
			)
		)
	)
	(zone
		(layers "B.Cu" "In9.Cu" "In11.Cu" "In13.Cu" "In15.Cu")
		(hatch none 0.5)
		(connect_pads
			(clearance 0)
		)
		(min_thickness 0.25)
		(keepout
			(tracks not_allowed)
			(vias allowed)
			(pads allowed)
			(copperpour not_allowed)
			(footprints allowed)
		)
		(placement
			(enabled no)
			(sheetname "")
		)
		(fill yes
			(thermal_gap 0.5)
			(thermal_bridge_width 0.5)
			(island_removal_mode 0)
		)
		(polygon
			(pts
				(arc
					(start 119.295418 -348.58579)
					(mid 118.591838 -348.58579)
					(end 119.295418 -348.58579)
				)
			)
		)
	)
	(zone
		(layers "B.Cu" "In9.Cu" "In11.Cu" "In13.Cu" "In15.Cu")
		(hatch none 0.5)
		(connect_pads
			(clearance 0)
		)
		(min_thickness 0.25)
		(keepout
			(tracks not_allowed)
			(vias allowed)
			(pads allowed)
			(copperpour not_allowed)
			(footprints allowed)
		)
		(placement
			(enabled no)
			(sheetname "")
		)
		(fill yes
			(thermal_gap 0.5)
			(thermal_bridge_width 0.5)
			(island_removal_mode 0)
		)
		(polygon
			(pts
				(arc
					(start 384.669792 -405.589994)
					(mid 383.910332 -405.589994)
					(end 384.669792 -405.589994)
				)
			)
		)
	)
	(zone
		(layers "B.Cu" "In9.Cu" "In11.Cu" "In13.Cu" "In15.Cu")
		(hatch none 0.5)
		(connect_pads
			(clearance 0)
		)
		(min_thickness 0.25)
		(keepout
			(tracks not_allowed)
			(vias allowed)
			(pads allowed)
			(copperpour not_allowed)
			(footprints allowed)
		)
		(placement
			(enabled no)
			(sheetname "")
		)
		(fill yes
			(thermal_gap 0.5)
			(thermal_bridge_width 0.5)
			(island_removal_mode 0)
		)
		(polygon
			(pts
				(arc
					(start 286.902652 -348.58579)
					(mid 286.199072 -348.58579)
					(end 286.902652 -348.58579)
				)
			)
		)
	)
	(zone
		(layers "B.Cu" "In9.Cu" "In11.Cu" "In13.Cu" "In15.Cu")
		(hatch none 0.5)
		(connect_pads
			(clearance 0)
		)
		(min_thickness 0.25)
		(keepout
			(tracks not_allowed)
			(vias allowed)
			(pads allowed)
			(copperpour not_allowed)
			(footprints allowed)
		)
		(placement
			(enabled no)
			(sheetname "")
		)
		(fill yes
			(thermal_gap 0.5)
			(thermal_bridge_width 0.5)
			(island_removal_mode 0)
		)
		(polygon
			(pts
				(arc
					(start 331.869796 -379.590046)
					(mid 331.110336 -379.590046)
					(end 331.869796 -379.590046)
				)
			)
		)
	)
	(zone
		(layers "B.Cu" "In9.Cu" "In11.Cu" "In13.Cu" "In15.Cu")
		(hatch none 0.5)
		(connect_pads
			(clearance 0)
		)
		(min_thickness 0.25)
		(keepout
			(tracks not_allowed)
			(vias allowed)
			(pads allowed)
			(copperpour not_allowed)
			(footprints allowed)
		)
		(placement
			(enabled no)
			(sheetname "")
		)
		(fill yes
			(thermal_gap 0.5)
			(thermal_bridge_width 0.5)
			(island_removal_mode 0)
		)
		(polygon
			(pts
				(arc
					(start 431.409602 -342.439498)
					(mid 430.706022 -342.439498)
					(end 431.409602 -342.439498)
				)
			)
		)
	)
	(zone
		(layers "B.Cu" "In9.Cu" "In11.Cu" "In13.Cu" "In15.Cu")
		(hatch none 0.5)
		(connect_pads
			(clearance 0)
		)
		(min_thickness 0.25)
		(keepout
			(tracks not_allowed)
			(vias allowed)
			(pads allowed)
			(copperpour not_allowed)
			(footprints allowed)
		)
		(placement
			(enabled no)
			(sheetname "")
		)
		(fill yes
			(thermal_gap 0.5)
			(thermal_bridge_width 0.5)
			(island_removal_mode 0)
		)
		(polygon
			(pts
				(arc
					(start 197.926452 -314.899802)
					(mid 197.273672 -314.899802)
					(end 197.926452 -314.899802)
				)
			)
		)
	)
	(zone
		(layers "B.Cu" "In9.Cu" "In11.Cu" "In13.Cu" "In15.Cu")
		(hatch none 0.5)
		(connect_pads
			(clearance 0)
		)
		(min_thickness 0.25)
		(keepout
			(tracks not_allowed)
			(vias allowed)
			(pads allowed)
			(copperpour not_allowed)
			(footprints allowed)
		)
		(placement
			(enabled no)
			(sheetname "")
		)
		(fill yes
			(thermal_gap 0.5)
			(thermal_bridge_width 0.5)
			(island_removal_mode 0)
		)
		(polygon
			(pts
				(arc
					(start 59.562238 -33.65881)
					(mid 58.858658 -33.65881)
					(end 59.562238 -33.65881)
				)
			)
		)
	)
	(zone
		(layers "B.Cu" "In9.Cu" "In11.Cu" "In13.Cu" "In15.Cu")
		(hatch none 0.5)
		(connect_pads
			(clearance 0)
		)
		(min_thickness 0.25)
		(keepout
			(tracks not_allowed)
			(vias allowed)
			(pads allowed)
			(copperpour not_allowed)
			(footprints allowed)
		)
		(placement
			(enabled no)
			(sheetname "")
		)
		(fill yes
			(thermal_gap 0.5)
			(thermal_bridge_width 0.5)
			(island_removal_mode 0)
		)
		(polygon
			(pts
				(arc
					(start 77.268832 -354.732082)
					(mid 76.565252 -354.732082)
					(end 77.268832 -354.732082)
				)
			)
		)
	)
	(zone
		(layers "B.Cu" "In9.Cu" "In11.Cu" "In13.Cu" "In15.Cu")
		(hatch none 0.5)
		(connect_pads
			(clearance 0)
		)
		(min_thickness 0.25)
		(keepout
			(tracks not_allowed)
			(vias allowed)
			(pads allowed)
			(copperpour not_allowed)
			(footprints allowed)
		)
		(placement
			(enabled no)
			(sheetname "")
		)
		(fill yes
			(thermal_gap 0.5)
			(thermal_bridge_width 0.5)
			(island_removal_mode 0)
		)
		(polygon
			(pts
				(arc
					(start 141.058138 -345.465146)
					(mid 140.354558 -345.465146)
					(end 141.058138 -345.465146)
				)
			)
		)
	)
	(zone
		(layers "B.Cu" "In9.Cu" "In11.Cu" "In13.Cu" "In15.Cu")
		(hatch none 0.5)
		(connect_pads
			(clearance 0)
		)
		(min_thickness 0.25)
		(keepout
			(tracks not_allowed)
			(vias allowed)
			(pads allowed)
			(copperpour not_allowed)
			(footprints allowed)
		)
		(placement
			(enabled no)
			(sheetname "")
		)
		(fill yes
			(thermal_gap 0.5)
			(thermal_bridge_width 0.5)
			(island_removal_mode 0)
		)
		(polygon
			(pts
				(arc
					(start 304.526188 -311.099962)
					(mid 303.873408 -311.099962)
					(end 304.526188 -311.099962)
				)
			)
		)
	)
	(zone
		(layers "B.Cu" "In9.Cu" "In11.Cu" "In13.Cu" "In15.Cu")
		(hatch none 0.5)
		(connect_pads
			(clearance 0)
		)
		(min_thickness 0.25)
		(keepout
			(tracks not_allowed)
			(vias allowed)
			(pads allowed)
			(copperpour not_allowed)
			(footprints allowed)
		)
		(placement
			(enabled no)
			(sheetname "")
		)
		(fill yes
			(thermal_gap 0.5)
			(thermal_bridge_width 0.5)
			(island_removal_mode 0)
		)
		(polygon
			(pts
				(arc
					(start 380.26975 -383.490216)
					(mid 379.51029 -383.490216)
					(end 380.26975 -383.490216)
				)
			)
		)
	)
	(zone
		(layers "B.Cu" "In9.Cu" "In11.Cu" "In13.Cu" "In15.Cu")
		(hatch none 0.5)
		(connect_pads
			(clearance 0)
		)
		(min_thickness 0.25)
		(keepout
			(tracks not_allowed)
			(vias allowed)
			(pads allowed)
			(copperpour not_allowed)
			(footprints allowed)
		)
		(placement
			(enabled no)
			(sheetname "")
		)
		(fill yes
			(thermal_gap 0.5)
			(thermal_bridge_width 0.5)
			(island_removal_mode 0)
		)
		(polygon
			(pts
				(arc
					(start 345.069668 -404.290022)
					(mid 344.310208 -404.290022)
					(end 345.069668 -404.290022)
				)
			)
		)
	)
	(zone
		(layers "B.Cu" "In9.Cu" "In11.Cu" "In13.Cu" "In15.Cu")
		(hatch none 0.5)
		(connect_pads
			(clearance 0)
		)
		(min_thickness 0.25)
		(keepout
			(tracks not_allowed)
			(vias allowed)
			(pads allowed)
			(copperpour not_allowed)
			(footprints allowed)
		)
		(placement
			(enabled no)
			(sheetname "")
		)
		(fill yes
			(thermal_gap 0.5)
			(thermal_bridge_width 0.5)
			(island_removal_mode 0)
		)
		(polygon
			(pts
				(arc
					(start 290.069524 -402.790152)
					(mid 289.310064 -402.790152)
					(end 290.069524 -402.790152)
				)
			)
		)
	)
	(zone
		(layers "B.Cu" "In9.Cu" "In11.Cu" "In13.Cu" "In15.Cu")
		(hatch none 0.5)
		(connect_pads
			(clearance 0)
		)
		(min_thickness 0.25)
		(keepout
			(tracks not_allowed)
			(vias allowed)
			(pads allowed)
			(copperpour not_allowed)
			(footprints allowed)
		)
		(placement
			(enabled no)
			(sheetname "")
		)
		(fill yes
			(thermal_gap 0.5)
			(thermal_bridge_width 0.5)
			(island_removal_mode 0)
		)
		(polygon
			(pts
				(arc
					(start 375.869708 -382.18999)
					(mid 375.110248 -382.18999)
					(end 375.869708 -382.18999)
				)
			)
		)
	)
	(zone
		(layers "B.Cu" "In9.Cu" "In11.Cu" "In13.Cu" "In15.Cu")
		(hatch none 0.5)
		(connect_pads
			(clearance 0)
		)
		(min_thickness 0.25)
		(keepout
			(tracks not_allowed)
			(vias allowed)
			(pads allowed)
			(copperpour not_allowed)
			(footprints allowed)
		)
		(placement
			(enabled no)
			(sheetname "")
		)
		(fill yes
			(thermal_gap 0.5)
			(thermal_bridge_width 0.5)
			(island_removal_mode 0)
		)
		(polygon
			(pts
				(arc
					(start 144.167098 -351.611438)
					(mid 143.463518 -351.611438)
					(end 144.167098 -351.611438)
				)
			)
		)
	)
	(zone
		(layers "B.Cu" "In9.Cu" "In11.Cu" "In13.Cu" "In15.Cu")
		(hatch none 0.5)
		(connect_pads
			(clearance 0)
		)
		(min_thickness 0.25)
		(keepout
			(tracks not_allowed)
			(vias allowed)
			(pads allowed)
			(copperpour not_allowed)
			(footprints allowed)
		)
		(placement
			(enabled no)
			(sheetname "")
		)
		(fill yes
			(thermal_gap 0.5)
			(thermal_bridge_width 0.5)
			(island_removal_mode 0)
		)
		(polygon
			(pts
				(arc
					(start 391.269728 -405.390096)
					(mid 390.510268 -405.390096)
					(end 391.269728 -405.390096)
				)
			)
		)
	)
	(zone
		(layers "B.Cu" "In9.Cu" "In11.Cu" "In13.Cu" "In15.Cu")
		(hatch none 0.5)
		(connect_pads
			(clearance 0)
		)
		(min_thickness 0.25)
		(keepout
			(tracks not_allowed)
			(vias allowed)
			(pads allowed)
			(copperpour not_allowed)
			(footprints allowed)
		)
		(placement
			(enabled no)
			(sheetname "")
		)
		(fill yes
			(thermal_gap 0.5)
			(thermal_bridge_width 0.5)
			(island_removal_mode 0)
		)
		(polygon
			(pts
				(arc
					(start 387.08457 -342.439498)
					(mid 386.38099 -342.439498)
					(end 387.08457 -342.439498)
				)
			)
		)
	)
	(zone
		(layers "B.Cu" "In9.Cu" "In11.Cu" "In13.Cu" "In15.Cu")
		(hatch none 0.5)
		(connect_pads
			(clearance 0)
		)
		(min_thickness 0.25)
		(keepout
			(tracks not_allowed)
			(vias allowed)
			(pads allowed)
			(copperpour not_allowed)
			(footprints allowed)
		)
		(placement
			(enabled no)
			(sheetname "")
		)
		(fill yes
			(thermal_gap 0.5)
			(thermal_bridge_width 0.5)
			(island_removal_mode 0)
		)
		(polygon
			(pts
				(arc
					(start 394.16609 -357.75773)
					(mid 393.46251 -357.75773)
					(end 394.16609 -357.75773)
				)
			)
		)
	)
	(zone
		(layers "B.Cu" "In9.Cu" "In11.Cu" "In13.Cu" "In15.Cu")
		(hatch none 0.5)
		(connect_pads
			(clearance 0)
		)
		(min_thickness 0.25)
		(keepout
			(tracks not_allowed)
			(vias allowed)
			(pads allowed)
			(copperpour not_allowed)
			(footprints allowed)
		)
		(placement
			(enabled no)
			(sheetname "")
		)
		(fill yes
			(thermal_gap 0.5)
			(thermal_bridge_width 0.5)
			(island_removal_mode 0)
		)
		(polygon
			(pts
				(arc
					(start 131.689856 -383.290064)
					(mid 130.930396 -383.290064)
					(end 131.689856 -383.290064)
				)
			)
		)
	)
	(zone
		(layers "B.Cu" "In9.Cu" "In11.Cu" "In13.Cu" "In15.Cu")
		(hatch none 0.5)
		(connect_pads
			(clearance 0)
		)
		(min_thickness 0.25)
		(keepout
			(tracks not_allowed)
			(vias allowed)
			(pads allowed)
			(copperpour not_allowed)
			(footprints allowed)
		)
		(placement
			(enabled no)
			(sheetname "")
		)
		(fill yes
			(thermal_gap 0.5)
			(thermal_bridge_width 0.5)
			(island_removal_mode 0)
		)
		(polygon
			(pts
				(arc
					(start 290.069524 -376.790204)
					(mid 289.310064 -376.790204)
					(end 290.069524 -376.790204)
				)
			)
		)
	)
	(zone
		(layers "B.Cu" "In9.Cu" "In11.Cu" "In13.Cu" "In15.Cu")
		(hatch none 0.5)
		(connect_pads
			(clearance 0)
		)
		(min_thickness 0.25)
		(keepout
			(tracks not_allowed)
			(vias allowed)
			(pads allowed)
			(copperpour not_allowed)
			(footprints allowed)
		)
		(placement
			(enabled no)
			(sheetname "")
		)
		(fill yes
			(thermal_gap 0.5)
			(thermal_bridge_width 0.5)
			(island_removal_mode 0)
		)
		(polygon
			(pts
				(arc
					(start 402.576284 -312.999882)
					(mid 401.923504 -312.999882)
					(end 402.576284 -312.999882)
				)
			)
		)
	)
	(zone
		(layers "B.Cu" "In9.Cu" "In11.Cu" "In13.Cu" "In15.Cu")
		(hatch none 0.5)
		(connect_pads
			(clearance 0)
		)
		(min_thickness 0.25)
		(keepout
			(tracks not_allowed)
			(vias allowed)
			(pads allowed)
			(copperpour not_allowed)
			(footprints allowed)
		)
		(placement
			(enabled no)
			(sheetname "")
		)
		(fill yes
			(thermal_gap 0.5)
			(thermal_bridge_width 0.5)
			(island_removal_mode 0)
		)
		(polygon
			(pts
				(arc
					(start 398.77619 -273.099784)
					(mid 398.12341 -273.099784)
					(end 398.77619 -273.099784)
				)
			)
		)
	)
	(zone
		(layers "B.Cu" "In9.Cu" "In11.Cu" "In13.Cu" "In15.Cu")
		(hatch none 0.5)
		(connect_pads
			(clearance 0)
		)
		(min_thickness 0.25)
		(keepout
			(tracks not_allowed)
			(vias allowed)
			(pads allowed)
			(copperpour not_allowed)
			(footprints allowed)
		)
		(placement
			(enabled no)
			(sheetname "")
		)
		(fill yes
			(thermal_gap 0.5)
			(thermal_bridge_width 0.5)
			(island_removal_mode 0)
		)
		(polygon
			(pts
				(arc
					(start 175.662336 -33.65881)
					(mid 174.958756 -33.65881)
					(end 175.662336 -33.65881)
				)
			)
		)
	)
	(zone
		(layers "B.Cu" "In9.Cu" "In11.Cu" "In13.Cu" "In15.Cu")
		(hatch none 0.5)
		(connect_pads
			(clearance 0)
		)
		(min_thickness 0.25)
		(keepout
			(tracks not_allowed)
			(vias allowed)
			(pads allowed)
			(copperpour not_allowed)
			(footprints allowed)
		)
		(placement
			(enabled no)
			(sheetname "")
		)
		(fill yes
			(thermal_gap 0.5)
			(thermal_bridge_width 0.5)
			(island_removal_mode 0)
		)
		(polygon
			(pts
				(arc
					(start 85.489542 -379.590046)
					(mid 84.730082 -379.590046)
					(end 85.489542 -379.590046)
				)
			)
		)
	)
	(zone
		(layers "B.Cu" "In9.Cu" "In11.Cu" "In13.Cu" "In15.Cu")
		(hatch none 0.5)
		(connect_pads
			(clearance 0)
		)
		(min_thickness 0.25)
		(keepout
			(tracks not_allowed)
			(vias allowed)
			(pads allowed)
			(copperpour not_allowed)
			(footprints allowed)
		)
		(placement
			(enabled no)
			(sheetname "")
		)
		(fill yes
			(thermal_gap 0.5)
			(thermal_bridge_width 0.5)
			(island_removal_mode 0)
		)
		(polygon
			(pts
				(arc
					(start 426.055282 -342.439498)
					(mid 425.351702 -342.439498)
					(end 426.055282 -342.439498)
				)
			)
		)
	)
	(zone
		(layers "B.Cu" "In9.Cu" "In11.Cu" "In13.Cu" "In15.Cu")
		(hatch none 0.5)
		(connect_pads
			(clearance 0)
		)
		(min_thickness 0.25)
		(keepout
			(tracks not_allowed)
			(vias allowed)
			(pads allowed)
			(copperpour not_allowed)
			(footprints allowed)
		)
		(placement
			(enabled no)
			(sheetname "")
		)
		(fill yes
			(thermal_gap 0.5)
			(thermal_bridge_width 0.5)
			(island_removal_mode 0)
		)
		(polygon
			(pts
				(arc
					(start 276.026118 -302.549814)
					(mid 275.373338 -302.549814)
					(end 276.026118 -302.549814)
				)
			)
		)
	)
	(zone
		(layers "B.Cu" "In9.Cu" "In11.Cu" "In13.Cu" "In15.Cu")
		(hatch none 0.5)
		(connect_pads
			(clearance 0)
		)
		(min_thickness 0.25)
		(keepout
			(tracks not_allowed)
			(vias allowed)
			(pads allowed)
			(copperpour not_allowed)
			(footprints allowed)
		)
		(placement
			(enabled no)
			(sheetname "")
		)
		(fill yes
			(thermal_gap 0.5)
			(thermal_bridge_width 0.5)
			(island_removal_mode 0)
		)
		(polygon
			(pts
				(arc
					(start 131.689856 -406.690068)
					(mid 130.930396 -406.690068)
					(end 131.689856 -406.690068)
				)
			)
		)
	)
	(zone
		(layers "B.Cu" "In9.Cu" "In11.Cu" "In13.Cu" "In15.Cu")
		(hatch none 0.5)
		(connect_pads
			(clearance 0)
		)
		(min_thickness 0.25)
		(keepout
			(tracks not_allowed)
			(vias allowed)
			(pads allowed)
			(copperpour not_allowed)
			(footprints allowed)
		)
		(placement
			(enabled no)
			(sheetname "")
		)
		(fill yes
			(thermal_gap 0.5)
			(thermal_bridge_width 0.5)
			(island_removal_mode 0)
		)
		(polygon
			(pts
				(arc
					(start 26.765758 -351.611438)
					(mid 26.062178 -351.611438)
					(end 26.765758 -351.611438)
				)
			)
		)
	)
	(zone
		(layers "B.Cu" "In9.Cu" "In11.Cu" "In13.Cu" "In15.Cu")
		(hatch none 0.5)
		(connect_pads
			(clearance 0)
		)
		(min_thickness 0.25)
		(keepout
			(tracks not_allowed)
			(vias allowed)
			(pads allowed)
			(copperpour not_allowed)
			(footprints allowed)
		)
		(placement
			(enabled no)
			(sheetname "")
		)
		(fill yes
			(thermal_gap 0.5)
			(thermal_bridge_width 0.5)
			(island_removal_mode 0)
		)
		(polygon
			(pts
				(arc
					(start 399.52041 -342.439498)
					(mid 398.81683 -342.439498)
					(end 399.52041 -342.439498)
				)
			)
		)
	)
	(zone
		(layers "B.Cu" "In9.Cu" "In11.Cu" "In13.Cu" "In15.Cu")
		(hatch none 0.5)
		(connect_pads
			(clearance 0)
		)
		(min_thickness 0.25)
		(keepout
			(tracks not_allowed)
			(vias allowed)
			(pads allowed)
			(copperpour not_allowed)
			(footprints allowed)
		)
		(placement
			(enabled no)
			(sheetname "")
		)
		(fill yes
			(thermal_gap 0.5)
			(thermal_bridge_width 0.5)
			(island_removal_mode 0)
		)
		(polygon
			(pts
				(arc
					(start 278.439372 -342.439498)
					(mid 277.735792 -342.439498)
					(end 278.439372 -342.439498)
				)
			)
		)
	)
	(zone
		(layers "B.Cu" "In9.Cu" "In11.Cu" "In13.Cu" "In15.Cu")
		(hatch none 0.5)
		(connect_pads
			(clearance 0)
		)
		(min_thickness 0.25)
		(keepout
			(tracks not_allowed)
			(vias allowed)
			(pads allowed)
			(copperpour not_allowed)
			(footprints allowed)
		)
		(placement
			(enabled no)
			(sheetname "")
		)
		(fill yes
			(thermal_gap 0.5)
			(thermal_bridge_width 0.5)
			(island_removal_mode 0)
		)
		(polygon
			(pts
				(arc
					(start 164.676328 -274.049744)
					(mid 164.023548 -274.049744)
					(end 164.676328 -274.049744)
				)
			)
		)
	)
	(zone
		(layers "B.Cu" "In9.Cu" "In11.Cu" "In13.Cu" "In15.Cu")
		(hatch none 0.5)
		(connect_pads
			(clearance 0)
		)
		(min_thickness 0.25)
		(keepout
			(tracks not_allowed)
			(vias allowed)
			(pads allowed)
			(copperpour not_allowed)
			(footprints allowed)
		)
		(placement
			(enabled no)
			(sheetname "")
		)
		(fill yes
			(thermal_gap 0.5)
			(thermal_bridge_width 0.5)
			(island_removal_mode 0)
		)
		(polygon
			(pts
				(arc
					(start 160.876234 -273.099784)
					(mid 160.223454 -273.099784)
					(end 160.876234 -273.099784)
				)
			)
		)
	)
	(zone
		(layers "B.Cu" "In9.Cu" "In11.Cu" "In13.Cu" "In15.Cu")
		(hatch none 0.5)
		(connect_pads
			(clearance 0)
		)
		(min_thickness 0.25)
		(keepout
			(tracks not_allowed)
			(vias allowed)
			(pads allowed)
			(copperpour not_allowed)
			(footprints allowed)
		)
		(placement
			(enabled no)
			(sheetname "")
		)
		(fill yes
			(thermal_gap 0.5)
			(thermal_bridge_width 0.5)
			(island_removal_mode 0)
		)
		(polygon
			(pts
				(arc
					(start 375.869708 -405.589994)
					(mid 375.110248 -405.589994)
					(end 375.869708 -405.589994)
				)
			)
		)
	)
	(zone
		(layers "B.Cu" "In9.Cu" "In11.Cu" "In13.Cu" "In15.Cu")
		(hatch none 0.5)
		(connect_pads
			(clearance 0)
		)
		(min_thickness 0.25)
		(keepout
			(tracks not_allowed)
			(vias allowed)
			(pads allowed)
			(copperpour not_allowed)
			(footprints allowed)
		)
		(placement
			(enabled no)
			(sheetname "")
		)
		(fill yes
			(thermal_gap 0.5)
			(thermal_bridge_width 0.5)
			(island_removal_mode 0)
		)
		(polygon
			(pts
				(arc
					(start 41.48963 -374.390158)
					(mid 40.73017 -374.390158)
					(end 41.48963 -374.390158)
				)
			)
		)
	)
	(zone
		(layers "B.Cu" "In9.Cu" "In11.Cu" "In13.Cu" "In15.Cu")
		(hatch none 0.5)
		(connect_pads
			(clearance 0)
		)
		(min_thickness 0.25)
		(keepout
			(tracks not_allowed)
			(vias allowed)
			(pads allowed)
			(copperpour not_allowed)
			(footprints allowed)
		)
		(placement
			(enabled no)
			(sheetname "")
		)
		(fill yes
			(thermal_gap 0.5)
			(thermal_bridge_width 0.5)
			(island_removal_mode 0)
		)
		(polygon
			(pts
				(arc
					(start 180.82641 -311.099962)
					(mid 180.17363 -311.099962)
					(end 180.82641 -311.099962)
				)
			)
		)
	)
	(zone
		(layers "B.Cu" "In9.Cu" "In11.Cu" "In13.Cu" "In15.Cu")
		(hatch none 0.5)
		(connect_pads
			(clearance 0)
		)
		(min_thickness 0.25)
		(keepout
			(tracks not_allowed)
			(vias allowed)
			(pads allowed)
			(copperpour not_allowed)
			(footprints allowed)
		)
		(placement
			(enabled no)
			(sheetname "")
		)
		(fill yes
			(thermal_gap 0.5)
			(thermal_bridge_width 0.5)
			(island_removal_mode 0)
		)
		(polygon
			(pts
				(arc
					(start 332.371954 -348.58579)
					(mid 331.668374 -348.58579)
					(end 332.371954 -348.58579)
				)
			)
		)
	)
	(zone
		(layers "B.Cu" "In9.Cu" "In11.Cu" "In13.Cu" "In15.Cu")
		(hatch none 0.5)
		(connect_pads
			(clearance 0)
		)
		(min_thickness 0.25)
		(keepout
			(tracks not_allowed)
			(vias allowed)
			(pads allowed)
			(copperpour not_allowed)
			(footprints allowed)
		)
		(placement
			(enabled no)
			(sheetname "")
		)
		(fill yes
			(thermal_gap 0.5)
			(thermal_bridge_width 0.5)
			(island_removal_mode 0)
		)
		(polygon
			(pts
				(arc
					(start 86.595712 -351.611438)
					(mid 85.892132 -351.611438)
					(end 86.595712 -351.611438)
				)
			)
		)
	)
	(zone
		(layers "B.Cu" "In9.Cu" "In11.Cu" "In13.Cu" "In15.Cu")
		(hatch none 0.5)
		(connect_pads
			(clearance 0)
		)
		(min_thickness 0.25)
		(keepout
			(tracks not_allowed)
			(vias allowed)
			(pads allowed)
			(copperpour not_allowed)
			(footprints allowed)
		)
		(placement
			(enabled no)
			(sheetname "")
		)
		(fill yes
			(thermal_gap 0.5)
			(thermal_bridge_width 0.5)
			(island_removal_mode 0)
		)
		(polygon
			(pts
				(arc
					(start 59.562238 -30.922468)
					(mid 58.858658 -30.922468)
					(end 59.562238 -30.922468)
				)
			)
		)
	)
	(zone
		(layers "B.Cu" "In9.Cu" "In11.Cu" "In13.Cu" "In15.Cu")
		(hatch none 0.5)
		(connect_pads
			(clearance 0)
		)
		(min_thickness 0.25)
		(keepout
			(tracks not_allowed)
			(vias allowed)
			(pads allowed)
			(copperpour not_allowed)
			(footprints allowed)
		)
		(placement
			(enabled no)
			(sheetname "")
		)
		(fill yes
			(thermal_gap 0.5)
			(thermal_bridge_width 0.5)
			(island_removal_mode 0)
		)
		(polygon
			(pts
				(arc
					(start 340.124288 18.467324)
					(mid 339.420708 18.467324)
					(end 340.124288 18.467324)
				)
			)
		)
	)
	(zone
		(layers "B.Cu" "In9.Cu" "In11.Cu" "In13.Cu" "In15.Cu")
		(hatch none 0.5)
		(connect_pads
			(clearance 0)
		)
		(min_thickness 0.25)
		(keepout
			(tracks not_allowed)
			(vias allowed)
			(pads allowed)
			(copperpour not_allowed)
			(footprints allowed)
		)
		(placement
			(enabled no)
			(sheetname "")
		)
		(fill yes
			(thermal_gap 0.5)
			(thermal_bridge_width 0.5)
			(island_removal_mode 0)
		)
		(polygon
			(pts
				(arc
					(start 416.728402 -348.58579)
					(mid 416.024822 -348.58579)
					(end 416.728402 -348.58579)
				)
			)
		)
	)
	(zone
		(layers "B.Cu" "In9.Cu" "In11.Cu" "In13.Cu" "In15.Cu")
		(hatch none 0.5)
		(connect_pads
			(clearance 0)
		)
		(min_thickness 0.25)
		(keepout
			(tracks not_allowed)
			(vias allowed)
			(pads allowed)
			(copperpour not_allowed)
			(footprints allowed)
		)
		(placement
			(enabled no)
			(sheetname "")
		)
		(fill yes
			(thermal_gap 0.5)
			(thermal_bridge_width 0.5)
			(island_removal_mode 0)
		)
		(polygon
			(pts
				(arc
					(start 277.926292 -275.949918)
					(mid 277.273512 -275.949918)
					(end 277.926292 -275.949918)
				)
			)
		)
	)
	(zone
		(layers "B.Cu" "In9.Cu" "In11.Cu" "In13.Cu" "In15.Cu")
		(hatch none 0.5)
		(connect_pads
			(clearance 0)
		)
		(min_thickness 0.25)
		(keepout
			(tracks not_allowed)
			(vias allowed)
			(pads allowed)
			(copperpour not_allowed)
			(footprints allowed)
		)
		(placement
			(enabled no)
			(sheetname "")
		)
		(fill yes
			(thermal_gap 0.5)
			(thermal_bridge_width 0.5)
			(island_removal_mode 0)
		)
		(polygon
			(pts
				(arc
					(start 41.926256 -311.099962)
					(mid 41.273476 -311.099962)
					(end 41.926256 -311.099962)
				)
			)
		)
	)
	(zone
		(layers "B.Cu" "In9.Cu" "In11.Cu" "In13.Cu" "In15.Cu")
		(hatch none 0.5)
		(connect_pads
			(clearance 0)
		)
		(min_thickness 0.25)
		(keepout
			(tracks not_allowed)
			(vias allowed)
			(pads allowed)
			(copperpour not_allowed)
			(footprints allowed)
		)
		(placement
			(enabled no)
			(sheetname "")
		)
		(fill yes
			(thermal_gap 0.5)
			(thermal_bridge_width 0.5)
			(island_removal_mode 0)
		)
		(polygon
			(pts
				(arc
					(start 384.669792 -382.18999)
					(mid 383.910332 -382.18999)
					(end 384.669792 -382.18999)
				)
			)
		)
	)
	(zone
		(layers "B.Cu" "In9.Cu" "In11.Cu" "In13.Cu" "In15.Cu")
		(hatch none 0.5)
		(connect_pads
			(clearance 0)
		)
		(min_thickness 0.25)
		(keepout
			(tracks not_allowed)
			(vias allowed)
			(pads allowed)
			(copperpour not_allowed)
			(footprints allowed)
		)
		(placement
			(enabled no)
			(sheetname "")
		)
		(fill yes
			(thermal_gap 0.5)
			(thermal_bridge_width 0.5)
			(island_removal_mode 0)
		)
		(polygon
			(pts
				(arc
					(start 39.201598 -351.611438)
					(mid 38.498018 -351.611438)
					(end 39.201598 -351.611438)
				)
			)
		)
	)
	(zone
		(layers "B.Cu" "In9.Cu" "In11.Cu" "In13.Cu" "In15.Cu")
		(hatch none 0.5)
		(connect_pads
			(clearance 0)
		)
		(min_thickness 0.25)
		(keepout
			(tracks not_allowed)
			(vias allowed)
			(pads allowed)
			(copperpour not_allowed)
			(footprints allowed)
		)
		(placement
			(enabled no)
			(sheetname "")
		)
		(fill yes
			(thermal_gap 0.5)
			(thermal_bridge_width 0.5)
			(island_removal_mode 0)
		)
		(polygon
			(pts
				(arc
					(start 342.869774 -405.390096)
					(mid 342.110314 -405.390096)
					(end 342.869774 -405.390096)
				)
			)
		)
	)
	(zone
		(layers "B.Cu" "In9.Cu" "In11.Cu" "In13.Cu" "In15.Cu")
		(hatch none 0.5)
		(connect_pads
			(clearance 0)
		)
		(min_thickness 0.25)
		(keepout
			(tracks not_allowed)
			(vias allowed)
			(pads allowed)
			(copperpour not_allowed)
			(footprints allowed)
		)
		(placement
			(enabled no)
			(sheetname "")
		)
		(fill yes
			(thermal_gap 0.5)
			(thermal_bridge_width 0.5)
			(island_removal_mode 0)
		)
		(polygon
			(pts
				(arc
					(start 41.926256 -312.049922)
					(mid 41.273476 -312.049922)
					(end 41.926256 -312.049922)
				)
			)
		)
	)
	(zone
		(layers "B.Cu" "In9.Cu" "In11.Cu" "In13.Cu" "In15.Cu")
		(hatch none 0.5)
		(connect_pads
			(clearance 0)
		)
		(min_thickness 0.25)
		(keepout
			(tracks not_allowed)
			(vias allowed)
			(pads allowed)
			(copperpour not_allowed)
			(footprints allowed)
		)
		(placement
			(enabled no)
			(sheetname "")
		)
		(fill yes
			(thermal_gap 0.5)
			(thermal_bridge_width 0.5)
			(island_removal_mode 0)
		)
		(polygon
			(pts
				(arc
					(start 375.51233 -345.465146)
					(mid 374.80875 -345.465146)
					(end 375.51233 -345.465146)
				)
			)
		)
	)
	(zone
		(layers "B.Cu" "In9.Cu" "In11.Cu" "In13.Cu" "In15.Cu")
		(hatch none 0.5)
		(connect_pads
			(clearance 0)
		)
		(min_thickness 0.25)
		(keepout
			(tracks not_allowed)
			(vias allowed)
			(pads allowed)
			(copperpour not_allowed)
			(footprints allowed)
		)
		(placement
			(enabled no)
			(sheetname "")
		)
		(fill yes
			(thermal_gap 0.5)
			(thermal_bridge_width 0.5)
			(island_removal_mode 0)
		)
		(polygon
			(pts
				(arc
					(start 404.476204 -312.999882)
					(mid 403.823424 -312.999882)
					(end 404.476204 -312.999882)
				)
			)
		)
	)
	(zone
		(layers "B.Cu" "In9.Cu" "In11.Cu" "In13.Cu" "In15.Cu")
		(hatch none 0.5)
		(connect_pads
			(clearance 0)
		)
		(min_thickness 0.25)
		(keepout
			(tracks not_allowed)
			(vias allowed)
			(pads allowed)
			(copperpour not_allowed)
			(footprints allowed)
		)
		(placement
			(enabled no)
			(sheetname "")
		)
		(fill yes
			(thermal_gap 0.5)
			(thermal_bridge_width 0.5)
			(island_removal_mode 0)
		)
		(polygon
			(pts
				(arc
					(start 340.124288 17.603724)
					(mid 339.420708 17.603724)
					(end 340.124288 17.603724)
				)
			)
		)
	)
	(zone
		(layers "B.Cu" "In9.Cu" "In11.Cu" "In13.Cu" "In15.Cu")
		(hatch none 0.5)
		(connect_pads
			(clearance 0)
		)
		(min_thickness 0.25)
		(keepout
			(tracks not_allowed)
			(vias allowed)
			(pads allowed)
			(copperpour not_allowed)
			(footprints allowed)
		)
		(placement
			(enabled no)
			(sheetname "")
		)
		(fill yes
			(thermal_gap 0.5)
			(thermal_bridge_width 0.5)
			(island_removal_mode 0)
		)
		(polygon
			(pts
				(arc
					(start 433.862226 -30.922468)
					(mid 433.158646 -30.922468)
					(end 433.862226 -30.922468)
				)
			)
		)
	)
	(zone
		(layers "B.Cu" "In9.Cu" "In11.Cu" "In13.Cu" "In15.Cu")
		(hatch none 0.5)
		(connect_pads
			(clearance 0)
		)
		(min_thickness 0.25)
		(keepout
			(tracks not_allowed)
			(vias allowed)
			(pads allowed)
			(copperpour not_allowed)
			(footprints allowed)
		)
		(placement
			(enabled no)
			(sheetname "")
		)
		(fill yes
			(thermal_gap 0.5)
			(thermal_bridge_width 0.5)
			(island_removal_mode 0)
		)
		(polygon
			(pts
				(arc
					(start 407.862278 -34.52241)
					(mid 407.158698 -34.52241)
					(end 407.862278 -34.52241)
				)
			)
		)
	)
	(zone
		(layers "B.Cu" "In9.Cu" "In11.Cu" "In13.Cu" "In15.Cu")
		(hatch none 0.5)
		(connect_pads
			(clearance 0)
		)
		(min_thickness 0.25)
		(keepout
			(tracks not_allowed)
			(vias allowed)
			(pads allowed)
			(copperpour not_allowed)
			(footprints allowed)
		)
		(placement
			(enabled no)
			(sheetname "")
		)
		(fill yes
			(thermal_gap 0.5)
			(thermal_bridge_width 0.5)
			(island_removal_mode 0)
		)
		(polygon
			(pts
				(arc
					(start 303.26965 -401.49018)
					(mid 302.51019 -401.49018)
					(end 303.26965 -401.49018)
				)
			)
		)
	)
	(zone
		(layers "B.Cu" "In9.Cu" "In11.Cu" "In13.Cu" "In15.Cu")
		(hatch none 0.5)
		(connect_pads
			(clearance 0)
		)
		(min_thickness 0.25)
		(keepout
			(tracks not_allowed)
			(vias allowed)
			(pads allowed)
			(copperpour not_allowed)
			(footprints allowed)
		)
		(placement
			(enabled no)
			(sheetname "")
		)
		(fill yes
			(thermal_gap 0.5)
			(thermal_bridge_width 0.5)
			(island_removal_mode 0)
		)
		(polygon
			(pts
				(arc
					(start 20.547838 -348.58579)
					(mid 19.844258 -348.58579)
					(end 20.547838 -348.58579)
				)
			)
		)
	)
	(zone
		(layers "B.Cu" "In9.Cu" "In11.Cu" "In13.Cu" "In15.Cu")
		(hatch none 0.5)
		(connect_pads
			(clearance 0)
		)
		(min_thickness 0.25)
		(keepout
			(tracks not_allowed)
			(vias allowed)
			(pads allowed)
			(copperpour not_allowed)
			(footprints allowed)
		)
		(placement
			(enabled no)
			(sheetname "")
		)
		(fill yes
			(thermal_gap 0.5)
			(thermal_bridge_width 0.5)
			(island_removal_mode 0)
		)
		(polygon
			(pts
				(arc
					(start 80.377792 -351.611438)
					(mid 79.674212 -351.611438)
					(end 80.377792 -351.611438)
				)
			)
		)
	)
	(zone
		(layers "B.Cu" "In9.Cu" "In11.Cu" "In13.Cu" "In15.Cu")
		(hatch none 0.5)
		(connect_pads
			(clearance 0)
		)
		(min_thickness 0.25)
		(keepout
			(tracks not_allowed)
			(vias allowed)
			(pads allowed)
			(copperpour not_allowed)
			(footprints allowed)
		)
		(placement
			(enabled no)
			(sheetname "")
		)
		(fill yes
			(thermal_gap 0.5)
			(thermal_bridge_width 0.5)
			(island_removal_mode 0)
		)
		(polygon
			(pts
				(arc
					(start 401.626324 -274.999958)
					(mid 400.973544 -274.999958)
					(end 401.626324 -274.999958)
				)
			)
		)
	)
	(zone
		(layers "B.Cu" "In9.Cu" "In11.Cu" "In13.Cu" "In15.Cu")
		(hatch none 0.5)
		(connect_pads
			(clearance 0)
		)
		(min_thickness 0.25)
		(keepout
			(tracks not_allowed)
			(vias allowed)
			(pads allowed)
			(copperpour not_allowed)
			(footprints allowed)
		)
		(placement
			(enabled no)
			(sheetname "")
		)
		(fill yes
			(thermal_gap 0.5)
			(thermal_bridge_width 0.5)
			(island_removal_mode 0)
		)
		(polygon
			(pts
				(arc
					(start 294.07612 -313.949842)
					(mid 293.42334 -313.949842)
					(end 294.07612 -313.949842)
				)
			)
		)
	)
	(zone
		(layers "B.Cu" "In9.Cu" "In11.Cu" "In13.Cu" "In15.Cu")
		(hatch none 0.5)
		(connect_pads
			(clearance 0)
		)
		(min_thickness 0.25)
		(keepout
			(tracks not_allowed)
			(vias allowed)
			(pads allowed)
			(copperpour not_allowed)
			(footprints allowed)
		)
		(placement
			(enabled no)
			(sheetname "")
		)
		(fill yes
			(thermal_gap 0.5)
			(thermal_bridge_width 0.5)
			(island_removal_mode 0)
		)
		(polygon
			(pts
				(arc
					(start 68.526152 -312.049922)
					(mid 67.873372 -312.049922)
					(end 68.526152 -312.049922)
				)
			)
		)
	)
	(zone
		(layers "B.Cu" "In9.Cu" "In11.Cu" "In13.Cu" "In15.Cu")
		(hatch none 0.5)
		(connect_pads
			(clearance 0)
		)
		(min_thickness 0.25)
		(keepout
			(tracks not_allowed)
			(vias allowed)
			(pads allowed)
			(copperpour not_allowed)
			(footprints allowed)
		)
		(placement
			(enabled no)
			(sheetname "")
		)
		(fill yes
			(thermal_gap 0.5)
			(thermal_bridge_width 0.5)
			(island_removal_mode 0)
		)
		(polygon
			(pts
				(arc
					(start 426.469556 -371.590062)
					(mid 425.710096 -371.590062)
					(end 426.469556 -371.590062)
				)
			)
		)
	)
	(zone
		(layers "B.Cu" "In9.Cu" "In11.Cu" "In13.Cu" "In15.Cu")
		(hatch none 0.5)
		(connect_pads
			(clearance 0)
		)
		(min_thickness 0.25)
		(keepout
			(tracks not_allowed)
			(vias allowed)
			(pads allowed)
			(copperpour not_allowed)
			(footprints allowed)
		)
		(placement
			(enabled no)
			(sheetname "")
		)
		(fill yes
			(thermal_gap 0.5)
			(thermal_bridge_width 0.5)
			(island_removal_mode 0)
		)
		(polygon
			(pts
				(arc
					(start 431.409602 -345.465146)
					(mid 430.706022 -345.465146)
					(end 431.409602 -345.465146)
				)
			)
		)
	)
	(zone
		(layers "B.Cu" "In9.Cu" "In11.Cu" "In13.Cu" "In15.Cu")
		(hatch none 0.5)
		(connect_pads
			(clearance 0)
		)
		(min_thickness 0.25)
		(keepout
			(tracks not_allowed)
			(vias allowed)
			(pads allowed)
			(copperpour not_allowed)
			(footprints allowed)
		)
		(placement
			(enabled no)
			(sheetname "")
		)
		(fill yes
			(thermal_gap 0.5)
			(thermal_bridge_width 0.5)
			(island_removal_mode 0)
		)
		(polygon
			(pts
				(arc
					(start 39.289736 -376.790204)
					(mid 38.530276 -376.790204)
					(end 39.289736 -376.790204)
				)
			)
		)
	)
	(zone
		(layers "B.Cu" "In9.Cu" "In11.Cu" "In13.Cu" "In15.Cu")
		(hatch none 0.5)
		(connect_pads
			(clearance 0)
		)
		(min_thickness 0.25)
		(keepout
			(tracks not_allowed)
			(vias allowed)
			(pads allowed)
			(copperpour not_allowed)
			(footprints allowed)
		)
		(placement
			(enabled no)
			(sheetname "")
		)
		(fill yes
			(thermal_gap 0.5)
			(thermal_bridge_width 0.5)
			(island_removal_mode 0)
		)
		(polygon
			(pts
				(arc
					(start 32.983678 -351.611438)
					(mid 32.280098 -351.611438)
					(end 32.983678 -351.611438)
				)
			)
		)
	)
	(zone
		(layers "B.Cu" "In9.Cu" "In11.Cu" "In13.Cu" "In15.Cu")
		(hatch none 0.5)
		(connect_pads
			(clearance 0)
		)
		(min_thickness 0.25)
		(keepout
			(tracks not_allowed)
			(vias allowed)
			(pads allowed)
			(copperpour not_allowed)
			(footprints allowed)
		)
		(placement
			(enabled no)
			(sheetname "")
		)
		(fill yes
			(thermal_gap 0.5)
			(thermal_bridge_width 0.5)
			(island_removal_mode 0)
		)
		(polygon
			(pts
				(arc
					(start 315.963554 -357.75773)
					(mid 315.259974 -357.75773)
					(end 315.963554 -357.75773)
				)
			)
		)
	)
	(zone
		(layers "B.Cu" "In9.Cu" "In11.Cu" "In13.Cu" "In15.Cu")
		(hatch none 0.5)
		(connect_pads
			(clearance 0)
		)
		(min_thickness 0.25)
		(keepout
			(tracks not_allowed)
			(vias allowed)
			(pads allowed)
			(copperpour not_allowed)
			(footprints allowed)
		)
		(placement
			(enabled no)
			(sheetname "")
		)
		(fill yes
			(thermal_gap 0.5)
			(thermal_bridge_width 0.5)
			(island_removal_mode 0)
		)
		(polygon
			(pts
				(arc
					(start 162.776408 -274.049744)
					(mid 162.123628 -274.049744)
					(end 162.776408 -274.049744)
				)
			)
		)
	)
	(zone
		(layers "B.Cu" "In9.Cu" "In11.Cu" "In13.Cu" "In15.Cu")
		(hatch none 0.5)
		(connect_pads
			(clearance 0)
		)
		(min_thickness 0.25)
		(keepout
			(tracks not_allowed)
			(vias allowed)
			(pads allowed)
			(copperpour not_allowed)
			(footprints allowed)
		)
		(placement
			(enabled no)
			(sheetname "")
		)
		(fill yes
			(thermal_gap 0.5)
			(thermal_bridge_width 0.5)
			(island_removal_mode 0)
		)
		(polygon
			(pts
				(arc
					(start 409.716478 -31.858712)
					(mid 409.012898 -31.858712)
					(end 409.716478 -31.858712)
				)
			)
		)
	)
	(zone
		(layers "B.Cu" "In9.Cu" "In11.Cu" "In13.Cu" "In15.Cu")
		(hatch none 0.5)
		(connect_pads
			(clearance 0)
		)
		(min_thickness 0.25)
		(keepout
			(tracks not_allowed)
			(vias allowed)
			(pads allowed)
			(copperpour not_allowed)
			(footprints allowed)
		)
		(placement
			(enabled no)
			(sheetname "")
		)
		(fill yes
			(thermal_gap 0.5)
			(thermal_bridge_width 0.5)
			(island_removal_mode 0)
		)
		(polygon
			(pts
				(arc
					(start 35.41649 -31.858712)
					(mid 34.71291 -31.858712)
					(end 35.41649 -31.858712)
				)
			)
		)
	)
	(zone
		(layers "B.Cu" "In9.Cu" "In11.Cu" "In13.Cu" "In15.Cu")
		(hatch none 0.5)
		(connect_pads
			(clearance 0)
		)
		(min_thickness 0.25)
		(keepout
			(tracks not_allowed)
			(vias allowed)
			(pads allowed)
			(copperpour not_allowed)
			(footprints allowed)
		)
		(placement
			(enabled no)
			(sheetname "")
		)
		(fill yes
			(thermal_gap 0.5)
			(thermal_bridge_width 0.5)
			(island_removal_mode 0)
		)
		(polygon
			(pts
				(arc
					(start 51.426364 -274.999958)
					(mid 50.773584 -274.999958)
					(end 51.426364 -274.999958)
				)
			)
		)
	)
	(zone
		(layers "B.Cu" "In9.Cu" "In11.Cu" "In13.Cu" "In15.Cu")
		(hatch none 0.5)
		(connect_pads
			(clearance 0)
		)
		(min_thickness 0.25)
		(keepout
			(tracks not_allowed)
			(vias allowed)
			(pads allowed)
			(copperpour not_allowed)
			(footprints allowed)
		)
		(placement
			(enabled no)
			(sheetname "")
		)
		(fill yes
			(thermal_gap 0.5)
			(thermal_bridge_width 0.5)
			(island_removal_mode 0)
		)
		(polygon
			(pts
				(arc
					(start 178.946302 -342.439498)
					(mid 178.242722 -342.439498)
					(end 178.946302 -342.439498)
				)
			)
		)
	)
	(zone
		(layers "B.Cu" "In9.Cu" "In11.Cu" "In13.Cu" "In15.Cu")
		(hatch none 0.5)
		(connect_pads
			(clearance 0)
		)
		(min_thickness 0.25)
		(keepout
			(tracks not_allowed)
			(vias allowed)
			(pads allowed)
			(copperpour not_allowed)
			(footprints allowed)
		)
		(placement
			(enabled no)
			(sheetname "")
		)
		(fill yes
			(thermal_gap 0.5)
			(thermal_bridge_width 0.5)
			(island_removal_mode 0)
		)
		(polygon
			(pts
				(arc
					(start 87.68969 -379.390148)
					(mid 86.93023 -379.390148)
					(end 87.68969 -379.390148)
				)
			)
		)
	)
	(zone
		(layers "B.Cu" "In9.Cu" "In11.Cu" "In13.Cu" "In15.Cu")
		(hatch none 0.5)
		(connect_pads
			(clearance 0)
		)
		(min_thickness 0.25)
		(keepout
			(tracks not_allowed)
			(vias allowed)
			(pads allowed)
			(copperpour not_allowed)
			(footprints allowed)
		)
		(placement
			(enabled no)
			(sheetname "")
		)
		(fill yes
			(thermal_gap 0.5)
			(thermal_bridge_width 0.5)
			(island_removal_mode 0)
		)
		(polygon
			(pts
				(arc
					(start 271.276318 -312.999882)
					(mid 270.623538 -312.999882)
					(end 271.276318 -312.999882)
				)
			)
		)
	)
	(zone
		(layers "B.Cu" "In9.Cu" "In11.Cu" "In13.Cu" "In15.Cu")
		(hatch none 0.5)
		(connect_pads
			(clearance 0)
		)
		(min_thickness 0.25)
		(keepout
			(tracks not_allowed)
			(vias allowed)
			(pads allowed)
			(copperpour not_allowed)
			(footprints allowed)
		)
		(placement
			(enabled no)
			(sheetname "")
		)
		(fill yes
			(thermal_gap 0.5)
			(thermal_bridge_width 0.5)
			(island_removal_mode 0)
		)
		(polygon
			(pts
				(arc
					(start 185.164222 -345.465146)
					(mid 184.460642 -345.465146)
					(end 185.164222 -345.465146)
				)
			)
		)
	)
	(zone
		(layers "B.Cu" "In9.Cu" "In11.Cu" "In13.Cu" "In15.Cu")
		(hatch none 0.5)
		(connect_pads
			(clearance 0)
		)
		(min_thickness 0.25)
		(keepout
			(tracks not_allowed)
			(vias allowed)
			(pads allowed)
			(copperpour not_allowed)
			(footprints allowed)
		)
		(placement
			(enabled no)
			(sheetname "")
		)
		(fill yes
			(thermal_gap 0.5)
			(thermal_bridge_width 0.5)
			(island_removal_mode 0)
		)
		(polygon
			(pts
				(arc
					(start 87.416386 -32.722312)
					(mid 86.712806 -32.722312)
					(end 87.416386 -32.722312)
				)
			)
		)
	)
	(zone
		(layers "B.Cu" "In9.Cu" "In11.Cu" "In13.Cu" "In15.Cu")
		(hatch none 0.5)
		(connect_pads
			(clearance 0)
		)
		(min_thickness 0.25)
		(keepout
			(tracks not_allowed)
			(vias allowed)
			(pads allowed)
			(copperpour not_allowed)
			(footprints allowed)
		)
		(placement
			(enabled no)
			(sheetname "")
		)
		(fill yes
			(thermal_gap 0.5)
			(thermal_bridge_width 0.5)
			(island_removal_mode 0)
		)
		(polygon
			(pts
				(arc
					(start 425.37634 -307.299868)
					(mid 424.72356 -307.299868)
					(end 425.37634 -307.299868)
				)
			)
		)
	)
	(zone
		(layers "B.Cu" "In9.Cu" "In11.Cu" "In13.Cu" "In15.Cu")
		(hatch none 0.5)
		(connect_pads
			(clearance 0)
		)
		(min_thickness 0.25)
		(keepout
			(tracks not_allowed)
			(vias allowed)
			(pads allowed)
			(copperpour not_allowed)
			(footprints allowed)
		)
		(placement
			(enabled no)
			(sheetname "")
		)
		(fill yes
			(thermal_gap 0.5)
			(thermal_bridge_width 0.5)
			(island_removal_mode 0)
		)
		(polygon
			(pts
				(arc
					(start 391.05713 -348.58579)
					(mid 390.35355 -348.58579)
					(end 391.05713 -348.58579)
				)
			)
		)
	)
	(zone
		(layers "B.Cu" "In9.Cu" "In11.Cu" "In13.Cu" "In15.Cu")
		(hatch none 0.5)
		(connect_pads
			(clearance 0)
		)
		(min_thickness 0.25)
		(keepout
			(tracks not_allowed)
			(vias allowed)
			(pads allowed)
			(copperpour not_allowed)
			(footprints allowed)
		)
		(placement
			(enabled no)
			(sheetname "")
		)
		(fill yes
			(thermal_gap 0.5)
			(thermal_bridge_width 0.5)
			(island_removal_mode 0)
		)
		(polygon
			(pts
				(arc
					(start 326.154034 -351.611438)
					(mid 325.450454 -351.611438)
					(end 326.154034 -351.611438)
				)
			)
		)
	)
	(zone
		(layers "B.Cu" "In9.Cu" "In11.Cu" "In13.Cu" "In15.Cu")
		(hatch none 0.5)
		(connect_pads
			(clearance 0)
		)
		(min_thickness 0.25)
		(keepout
			(tracks not_allowed)
			(vias allowed)
			(pads allowed)
			(copperpour not_allowed)
			(footprints allowed)
		)
		(placement
			(enabled no)
			(sheetname "")
		)
		(fill yes
			(thermal_gap 0.5)
			(thermal_bridge_width 0.5)
			(island_removal_mode 0)
		)
		(polygon
			(pts
				(arc
					(start 393.30249 -354.732082)
					(mid 392.59891 -354.732082)
					(end 393.30249 -354.732082)
				)
			)
		)
	)
	(zone
		(layers "B.Cu" "In9.Cu" "In11.Cu" "In13.Cu" "In15.Cu")
		(hatch none 0.5)
		(connect_pads
			(clearance 0)
		)
		(min_thickness 0.25)
		(keepout
			(tracks not_allowed)
			(vias allowed)
			(pads allowed)
			(copperpour not_allowed)
			(footprints allowed)
		)
		(placement
			(enabled no)
			(sheetname "")
		)
		(fill yes
			(thermal_gap 0.5)
			(thermal_bridge_width 0.5)
			(island_removal_mode 0)
		)
		(polygon
			(pts
				(arc
					(start 336.269838 -405.589994)
					(mid 335.510378 -405.589994)
					(end 336.269838 -405.589994)
				)
			)
		)
	)
	(zone
		(layers "B.Cu" "In9.Cu" "In11.Cu" "In13.Cu" "In15.Cu")
		(hatch none 0.5)
		(connect_pads
			(clearance 0)
		)
		(min_thickness 0.25)
		(keepout
			(tracks not_allowed)
			(vias allowed)
			(pads allowed)
			(copperpour not_allowed)
			(footprints allowed)
		)
		(placement
			(enabled no)
			(sheetname "")
		)
		(fill yes
			(thermal_gap 0.5)
			(thermal_bridge_width 0.5)
			(island_removal_mode 0)
		)
		(polygon
			(pts
				(arc
					(start 410.176218 -312.999882)
					(mid 409.523438 -312.999882)
					(end 410.176218 -312.999882)
				)
			)
		)
	)
	(zone
		(layers "B.Cu" "In9.Cu" "In11.Cu" "In13.Cu" "In15.Cu")
		(hatch none 0.5)
		(connect_pads
			(clearance 0)
		)
		(min_thickness 0.25)
		(keepout
			(tracks not_allowed)
			(vias allowed)
			(pads allowed)
			(copperpour not_allowed)
			(footprints allowed)
		)
		(placement
			(enabled no)
			(sheetname "")
		)
		(fill yes
			(thermal_gap 0.5)
			(thermal_bridge_width 0.5)
			(island_removal_mode 0)
		)
		(polygon
			(pts
				(arc
					(start 42.876216 -307.299868)
					(mid 42.223436 -307.299868)
					(end 42.876216 -307.299868)
				)
			)
		)
	)
	(zone
		(layers "B.Cu" "In9.Cu" "In11.Cu" "In13.Cu" "In15.Cu")
		(hatch none 0.5)
		(connect_pads
			(clearance 0)
		)
		(min_thickness 0.25)
		(keepout
			(tracks not_allowed)
			(vias allowed)
			(pads allowed)
			(copperpour not_allowed)
			(footprints allowed)
		)
		(placement
			(enabled no)
			(sheetname "")
		)
		(fill yes
			(thermal_gap 0.5)
			(thermal_bridge_width 0.5)
			(island_removal_mode 0)
		)
		(polygon
			(pts
				(arc
					(start 287.766252 -351.611438)
					(mid 287.062672 -351.611438)
					(end 287.766252 -351.611438)
				)
			)
		)
	)
	(zone
		(layers "B.Cu" "In9.Cu" "In11.Cu" "In13.Cu" "In15.Cu")
		(hatch none 0.5)
		(connect_pads
			(clearance 0)
		)
		(min_thickness 0.25)
		(keepout
			(tracks not_allowed)
			(vias allowed)
			(pads allowed)
			(copperpour not_allowed)
			(footprints allowed)
		)
		(placement
			(enabled no)
			(sheetname "")
		)
		(fill yes
			(thermal_gap 0.5)
			(thermal_bridge_width 0.5)
			(island_removal_mode 0)
		)
		(polygon
			(pts
				(arc
					(start 133.976618 -342.439498)
					(mid 133.273038 -342.439498)
					(end 133.976618 -342.439498)
				)
			)
		)
	)
	(zone
		(layers "B.Cu" "In9.Cu" "In11.Cu" "In13.Cu" "In15.Cu")
		(hatch none 0.5)
		(connect_pads
			(clearance 0)
		)
		(min_thickness 0.25)
		(keepout
			(tracks not_allowed)
			(vias allowed)
			(pads allowed)
			(copperpour not_allowed)
			(footprints allowed)
		)
		(placement
			(enabled no)
			(sheetname "")
		)
		(fill yes
			(thermal_gap 0.5)
			(thermal_bridge_width 0.5)
			(island_removal_mode 0)
		)
		(polygon
			(pts
				(arc
					(start 134.840218 -345.465146)
					(mid 134.136638 -345.465146)
					(end 134.840218 -345.465146)
				)
			)
		)
	)
	(zone
		(layers "B.Cu" "In9.Cu" "In11.Cu" "In13.Cu" "In15.Cu")
		(hatch none 0.5)
		(connect_pads
			(clearance 0)
		)
		(min_thickness 0.25)
		(keepout
			(tracks not_allowed)
			(vias allowed)
			(pads allowed)
			(copperpour not_allowed)
			(footprints allowed)
		)
		(placement
			(enabled no)
			(sheetname "")
		)
		(fill yes
			(thermal_gap 0.5)
			(thermal_bridge_width 0.5)
			(island_removal_mode 0)
		)
		(polygon
			(pts
				(arc
					(start 164.68979 -371.790214)
					(mid 163.93033 -371.790214)
					(end 164.68979 -371.790214)
				)
			)
		)
	)
	(zone
		(layers "B.Cu" "In9.Cu" "In11.Cu" "In13.Cu" "In15.Cu")
		(hatch none 0.5)
		(connect_pads
			(clearance 0)
		)
		(min_thickness 0.25)
		(keepout
			(tracks not_allowed)
			(vias allowed)
			(pads allowed)
			(copperpour not_allowed)
			(footprints allowed)
		)
		(placement
			(enabled no)
			(sheetname "")
		)
		(fill yes
			(thermal_gap 0.5)
			(thermal_bridge_width 0.5)
			(island_removal_mode 0)
		)
		(polygon
			(pts
				(arc
					(start 274.126198 -309.199788)
					(mid 273.473418 -309.199788)
					(end 274.126198 -309.199788)
				)
			)
		)
	)
	(zone
		(layers "B.Cu" "In9.Cu" "In11.Cu" "In13.Cu" "In15.Cu")
		(hatch none 0.5)
		(connect_pads
			(clearance 0)
		)
		(min_thickness 0.25)
		(keepout
			(tracks not_allowed)
			(vias allowed)
			(pads allowed)
			(copperpour not_allowed)
			(footprints allowed)
		)
		(placement
			(enabled no)
			(sheetname "")
		)
		(fill yes
			(thermal_gap 0.5)
			(thermal_bridge_width 0.5)
			(island_removal_mode 0)
		)
		(polygon
			(pts
				(arc
					(start 275.076158 -303.499774)
					(mid 274.423378 -303.499774)
					(end 275.076158 -303.499774)
				)
			)
		)
	)
	(zone
		(layers "B.Cu" "In9.Cu" "In11.Cu" "In13.Cu" "In15.Cu")
		(hatch none 0.5)
		(connect_pads
			(clearance 0)
		)
		(min_thickness 0.25)
		(keepout
			(tracks not_allowed)
			(vias allowed)
			(pads allowed)
			(copperpour not_allowed)
			(footprints allowed)
		)
		(placement
			(enabled no)
			(sheetname "")
		)
		(fill yes
			(thermal_gap 0.5)
			(thermal_bridge_width 0.5)
			(island_removal_mode 0)
		)
		(polygon
			(pts
				(arc
					(start 296.669714 -401.690078)
					(mid 295.910254 -401.690078)
					(end 296.669714 -401.690078)
				)
			)
		)
	)
	(zone
		(layers "B.Cu" "In9.Cu" "In11.Cu" "In13.Cu" "In15.Cu")
		(hatch none 0.5)
		(connect_pads
			(clearance 0)
		)
		(min_thickness 0.25)
		(keepout
			(tracks not_allowed)
			(vias allowed)
			(pads allowed)
			(copperpour not_allowed)
			(footprints allowed)
		)
		(placement
			(enabled no)
			(sheetname "")
		)
		(fill yes
			(thermal_gap 0.5)
			(thermal_bridge_width 0.5)
			(island_removal_mode 0)
		)
		(polygon
			(pts
				(arc
					(start 283.793692 -357.75773)
					(mid 283.090112 -357.75773)
					(end 283.793692 -357.75773)
				)
			)
		)
	)
	(zone
		(layers "B.Cu" "In9.Cu" "In11.Cu" "In13.Cu" "In15.Cu")
		(hatch none 0.5)
		(connect_pads
			(clearance 0)
		)
		(min_thickness 0.25)
		(keepout
			(tracks not_allowed)
			(vias allowed)
			(pads allowed)
			(copperpour not_allowed)
			(footprints allowed)
		)
		(placement
			(enabled no)
			(sheetname "")
		)
		(fill yes
			(thermal_gap 0.5)
			(thermal_bridge_width 0.5)
			(island_removal_mode 0)
		)
		(polygon
			(pts
				(arc
					(start 419.86962 -396.49019)
					(mid 419.11016 -396.49019)
					(end 419.86962 -396.49019)
				)
			)
		)
	)
	(zone
		(layers "B.Cu" "In9.Cu" "In11.Cu" "In13.Cu" "In15.Cu")
		(hatch none 0.5)
		(connect_pads
			(clearance 0)
		)
		(min_thickness 0.25)
		(keepout
			(tracks not_allowed)
			(vias allowed)
			(pads allowed)
			(copperpour not_allowed)
			(footprints allowed)
		)
		(placement
			(enabled no)
			(sheetname "")
		)
		(fill yes
			(thermal_gap 0.5)
			(thermal_bridge_width 0.5)
			(island_removal_mode 0)
		)
		(polygon
			(pts
				(arc
					(start 187.409582 -348.58579)
					(mid 186.706002 -348.58579)
					(end 187.409582 -348.58579)
				)
			)
		)
	)
	(zone
		(layers "B.Cu" "In9.Cu" "In11.Cu" "In13.Cu" "In15.Cu")
		(hatch none 0.5)
		(connect_pads
			(clearance 0)
		)
		(min_thickness 0.25)
		(keepout
			(tracks not_allowed)
			(vias allowed)
			(pads allowed)
			(copperpour not_allowed)
			(footprints allowed)
		)
		(placement
			(enabled no)
			(sheetname "")
		)
		(fill yes
			(thermal_gap 0.5)
			(thermal_bridge_width 0.5)
			(island_removal_mode 0)
		)
		(polygon
			(pts
				(arc
					(start 276.976078 -306.349908)
					(mid 276.323298 -306.349908)
					(end 276.976078 -306.349908)
				)
			)
		)
	)
	(zone
		(layers "B.Cu" "In9.Cu" "In11.Cu" "In13.Cu" "In15.Cu")
		(hatch none 0.5)
		(connect_pads
			(clearance 0)
		)
		(min_thickness 0.25)
		(keepout
			(tracks not_allowed)
			(vias allowed)
			(pads allowed)
			(copperpour not_allowed)
			(footprints allowed)
		)
		(placement
			(enabled no)
			(sheetname "")
		)
		(fill yes
			(thermal_gap 0.5)
			(thermal_bridge_width 0.5)
			(island_removal_mode 0)
		)
		(polygon
			(pts
				(arc
					(start 391.269728 -406.690068)
					(mid 390.510268 -406.690068)
					(end 391.269728 -406.690068)
				)
			)
		)
	)
	(zone
		(layers "B.Cu" "In9.Cu" "In11.Cu" "In13.Cu" "In15.Cu")
		(hatch none 0.5)
		(connect_pads
			(clearance 0)
		)
		(min_thickness 0.25)
		(keepout
			(tracks not_allowed)
			(vias allowed)
			(pads allowed)
			(copperpour not_allowed)
			(footprints allowed)
		)
		(placement
			(enabled no)
			(sheetname "")
		)
		(fill yes
			(thermal_gap 0.5)
			(thermal_bridge_width 0.5)
			(island_removal_mode 0)
		)
		(polygon
			(pts
				(arc
					(start 296.669714 -400.390106)
					(mid 295.910254 -400.390106)
					(end 296.669714 -400.390106)
				)
			)
		)
	)
	(zone
		(layers "B.Cu" "In9.Cu" "In11.Cu" "In13.Cu" "In15.Cu")
		(hatch none 0.5)
		(connect_pads
			(clearance 0)
		)
		(min_thickness 0.25)
		(keepout
			(tracks not_allowed)
			(vias allowed)
			(pads allowed)
			(copperpour not_allowed)
			(footprints allowed)
		)
		(placement
			(enabled no)
			(sheetname "")
		)
		(fill yes
			(thermal_gap 0.5)
			(thermal_bridge_width 0.5)
			(island_removal_mode 0)
		)
		(polygon
			(pts
				(arc
					(start 441.600082 -348.58579)
					(mid 440.896502 -348.58579)
					(end 441.600082 -348.58579)
				)
			)
		)
	)
	(zone
		(layers "B.Cu" "In9.Cu" "In11.Cu" "In13.Cu" "In15.Cu")
		(hatch none 0.5)
		(connect_pads
			(clearance 0)
		)
		(min_thickness 0.25)
		(keepout
			(tracks not_allowed)
			(vias allowed)
			(pads allowed)
			(copperpour not_allowed)
			(footprints allowed)
		)
		(placement
			(enabled no)
			(sheetname "")
		)
		(fill yes
			(thermal_gap 0.5)
			(thermal_bridge_width 0.5)
			(island_removal_mode 0)
		)
		(polygon
			(pts
				(arc
					(start 400.676364 -312.999882)
					(mid 400.023584 -312.999882)
					(end 400.676364 -312.999882)
				)
			)
		)
	)
	(zone
		(layers "B.Cu" "In9.Cu" "In11.Cu" "In13.Cu" "In15.Cu")
		(hatch none 0.5)
		(connect_pads
			(clearance 0)
		)
		(min_thickness 0.25)
		(keepout
			(tracks not_allowed)
			(vias allowed)
			(pads allowed)
			(copperpour not_allowed)
			(footprints allowed)
		)
		(placement
			(enabled no)
			(sheetname "")
		)
		(fill yes
			(thermal_gap 0.5)
			(thermal_bridge_width 0.5)
			(island_removal_mode 0)
		)
		(polygon
			(pts
				(arc
					(start 45.72635 -275.949918)
					(mid 45.07357 -275.949918)
					(end 45.72635 -275.949918)
				)
			)
		)
	)
	(zone
		(layers "B.Cu" "In9.Cu" "In11.Cu" "In13.Cu" "In15.Cu")
		(hatch none 0.5)
		(connect_pads
			(clearance 0)
		)
		(min_thickness 0.25)
		(keepout
			(tracks not_allowed)
			(vias allowed)
			(pads allowed)
			(copperpour not_allowed)
			(footprints allowed)
		)
		(placement
			(enabled no)
			(sheetname "")
		)
		(fill yes
			(thermal_gap 0.5)
			(thermal_bridge_width 0.5)
			(island_removal_mode 0)
		)
		(polygon
			(pts
				(arc
					(start 194.126358 -305.399948)
					(mid 193.473578 -305.399948)
					(end 194.126358 -305.399948)
				)
			)
		)
	)
	(zone
		(layers "B.Cu" "In9.Cu" "In11.Cu" "In13.Cu" "In15.Cu")
		(hatch none 0.5)
		(connect_pads
			(clearance 0)
		)
		(min_thickness 0.25)
		(keepout
			(tracks not_allowed)
			(vias allowed)
			(pads allowed)
			(copperpour not_allowed)
			(footprints allowed)
		)
		(placement
			(enabled no)
			(sheetname "")
		)
		(fill yes
			(thermal_gap 0.5)
			(thermal_bridge_width 0.5)
			(island_removal_mode 0)
		)
		(polygon
			(pts
				(arc
					(start 125.08992 -404.290022)
					(mid 124.33046 -404.290022)
					(end 125.08992 -404.290022)
				)
			)
		)
	)
	(zone
		(layers "B.Cu" "In9.Cu" "In11.Cu" "In13.Cu" "In15.Cu")
		(hatch none 0.5)
		(connect_pads
			(clearance 0)
		)
		(min_thickness 0.25)
		(keepout
			(tracks not_allowed)
			(vias allowed)
			(pads allowed)
			(copperpour not_allowed)
			(footprints allowed)
		)
		(placement
			(enabled no)
			(sheetname "")
		)
		(fill yes
			(thermal_gap 0.5)
			(thermal_bridge_width 0.5)
			(island_removal_mode 0)
		)
		(polygon
			(pts
				(arc
					(start 298.869608 -402.790152)
					(mid 298.110148 -402.790152)
					(end 298.869608 -402.790152)
				)
			)
		)
	)
	(zone
		(layers "B.Cu" "In9.Cu" "In11.Cu" "In13.Cu" "In15.Cu")
		(hatch none 0.5)
		(connect_pads
			(clearance 0)
		)
		(min_thickness 0.25)
		(keepout
			(tracks not_allowed)
			(vias allowed)
			(pads allowed)
			(copperpour not_allowed)
			(footprints allowed)
		)
		(placement
			(enabled no)
			(sheetname "")
		)
		(fill yes
			(thermal_gap 0.5)
			(thermal_bridge_width 0.5)
			(island_removal_mode 0)
		)
		(polygon
			(pts
				(arc
					(start 173.226476 -312.049922)
					(mid 172.573696 -312.049922)
					(end 173.226476 -312.049922)
				)
			)
		)
	)
	(zone
		(layers "B.Cu" "In9.Cu" "In11.Cu" "In13.Cu" "In15.Cu")
		(hatch none 0.5)
		(connect_pads
			(clearance 0)
		)
		(min_thickness 0.25)
		(keepout
			(tracks not_allowed)
			(vias allowed)
			(pads allowed)
			(copperpour not_allowed)
			(footprints allowed)
		)
		(placement
			(enabled no)
			(sheetname "")
		)
		(fill yes
			(thermal_gap 0.5)
			(thermal_bridge_width 0.5)
			(island_removal_mode 0)
		)
		(polygon
			(pts
				(arc
					(start 389.06958 -405.589994)
					(mid 388.31012 -405.589994)
					(end 389.06958 -405.589994)
				)
			)
		)
	)
	(zone
		(layers "B.Cu" "In9.Cu" "In11.Cu" "In13.Cu" "In15.Cu")
		(hatch none 0.5)
		(connect_pads
			(clearance 0)
		)
		(min_thickness 0.25)
		(keepout
			(tracks not_allowed)
			(vias allowed)
			(pads allowed)
			(copperpour not_allowed)
			(footprints allowed)
		)
		(placement
			(enabled no)
			(sheetname "")
		)
		(fill yes
			(thermal_gap 0.5)
			(thermal_bridge_width 0.5)
			(island_removal_mode 0)
		)
		(polygon
			(pts
				(arc
					(start 123.66244 -30.058868)
					(mid 122.95886 -30.058868)
					(end 123.66244 -30.058868)
				)
			)
		)
	)
	(zone
		(layers "B.Cu" "In9.Cu" "In11.Cu" "In13.Cu" "In15.Cu")
		(hatch none 0.5)
		(connect_pads
			(clearance 0)
		)
		(min_thickness 0.25)
		(keepout
			(tracks not_allowed)
			(vias allowed)
			(pads allowed)
			(copperpour not_allowed)
			(footprints allowed)
		)
		(placement
			(enabled no)
			(sheetname "")
		)
		(fill yes
			(thermal_gap 0.5)
			(thermal_bridge_width 0.5)
			(island_removal_mode 0)
		)
		(polygon
			(pts
				(arc
					(start 296.229532 -342.439498)
					(mid 295.525952 -342.439498)
					(end 296.229532 -342.439498)
				)
			)
		)
	)
	(zone
		(layers "B.Cu" "In9.Cu" "In11.Cu" "In13.Cu" "In15.Cu")
		(hatch none 0.5)
		(connect_pads
			(clearance 0)
		)
		(min_thickness 0.25)
		(keepout
			(tracks not_allowed)
			(vias allowed)
			(pads allowed)
			(copperpour not_allowed)
			(footprints allowed)
		)
		(placement
			(enabled no)
			(sheetname "")
		)
		(fill yes
			(thermal_gap 0.5)
			(thermal_bridge_width 0.5)
			(island_removal_mode 0)
		)
		(polygon
			(pts
				(arc
					(start 78.132432 -345.465146)
					(mid 77.428852 -345.465146)
					(end 78.132432 -345.465146)
				)
			)
		)
	)
	(zone
		(layers "B.Cu" "In9.Cu" "In11.Cu" "In13.Cu" "In15.Cu")
		(hatch none 0.5)
		(connect_pads
			(clearance 0)
		)
		(min_thickness 0.25)
		(keepout
			(tracks not_allowed)
			(vias allowed)
			(pads allowed)
			(copperpour not_allowed)
			(footprints allowed)
		)
		(placement
			(enabled no)
			(sheetname "")
		)
		(fill yes
			(thermal_gap 0.5)
			(thermal_bridge_width 0.5)
			(island_removal_mode 0)
		)
		(polygon
			(pts
				(arc
					(start 59.026298 -275.949918)
					(mid 58.373518 -275.949918)
					(end 59.026298 -275.949918)
				)
			)
		)
	)
	(zone
		(layers "B.Cu" "In9.Cu" "In11.Cu" "In13.Cu" "In15.Cu")
		(hatch none 0.5)
		(connect_pads
			(clearance 0)
		)
		(min_thickness 0.25)
		(keepout
			(tracks not_allowed)
			(vias allowed)
			(pads allowed)
			(copperpour not_allowed)
			(footprints allowed)
		)
		(placement
			(enabled no)
			(sheetname "")
		)
		(fill yes
			(thermal_gap 0.5)
			(thermal_bridge_width 0.5)
			(island_removal_mode 0)
		)
		(polygon
			(pts
				(arc
					(start 129.489708 -405.589994)
					(mid 128.730248 -405.589994)
					(end 129.489708 -405.589994)
				)
			)
		)
	)
	(zone
		(layers "B.Cu" "In9.Cu" "In11.Cu" "In13.Cu" "In15.Cu")
		(hatch none 0.5)
		(connect_pads
			(clearance 0)
		)
		(min_thickness 0.25)
		(keepout
			(tracks not_allowed)
			(vias allowed)
			(pads allowed)
			(copperpour not_allowed)
			(footprints allowed)
		)
		(placement
			(enabled no)
			(sheetname "")
		)
		(fill yes
			(thermal_gap 0.5)
			(thermal_bridge_width 0.5)
			(island_removal_mode 0)
		)
		(polygon
			(pts
				(arc
					(start 399.726404 -311.099962)
					(mid 399.073624 -311.099962)
					(end 399.726404 -311.099962)
				)
			)
		)
	)
	(zone
		(layers "B.Cu" "In9.Cu" "In11.Cu" "In13.Cu" "In15.Cu")
		(hatch none 0.5)
		(connect_pads
			(clearance 0)
		)
		(min_thickness 0.25)
		(keepout
			(tracks not_allowed)
			(vias allowed)
			(pads allowed)
			(copperpour not_allowed)
			(footprints allowed)
		)
		(placement
			(enabled no)
			(sheetname "")
		)
		(fill yes
			(thermal_gap 0.5)
			(thermal_bridge_width 0.5)
			(island_removal_mode 0)
		)
		(polygon
			(pts
				(arc
					(start 71.050912 -345.465146)
					(mid 70.347332 -345.465146)
					(end 71.050912 -345.465146)
				)
			)
		)
	)
	(zone
		(layers "B.Cu" "In9.Cu" "In11.Cu" "In13.Cu" "In15.Cu")
		(hatch none 0.5)
		(connect_pads
			(clearance 0)
		)
		(min_thickness 0.25)
		(keepout
			(tracks not_allowed)
			(vias allowed)
			(pads allowed)
			(copperpour not_allowed)
			(footprints allowed)
		)
		(placement
			(enabled no)
			(sheetname "")
		)
		(fill yes
			(thermal_gap 0.5)
			(thermal_bridge_width 0.5)
			(island_removal_mode 0)
		)
		(polygon
			(pts
				(arc
					(start 62.826138 -311.099962)
					(mid 62.173358 -311.099962)
					(end 62.826138 -311.099962)
				)
			)
		)
	)
	(zone
		(layers "B.Cu" "In9.Cu" "In11.Cu" "In13.Cu" "In15.Cu")
		(hatch none 0.5)
		(connect_pads
			(clearance 0)
		)
		(min_thickness 0.25)
		(keepout
			(tracks not_allowed)
			(vias allowed)
			(pads allowed)
			(copperpour not_allowed)
			(footprints allowed)
		)
		(placement
			(enabled no)
			(sheetname "")
		)
		(fill yes
			(thermal_gap 0.5)
			(thermal_bridge_width 0.5)
			(island_removal_mode 0)
		)
		(polygon
			(pts
				(arc
					(start 170.376342 -273.099784)
					(mid 169.723562 -273.099784)
					(end 170.376342 -273.099784)
				)
			)
		)
	)
	(zone
		(layers "B.Cu" "In9.Cu" "In11.Cu" "In13.Cu" "In15.Cu")
		(hatch none 0.5)
		(connect_pads
			(clearance 0)
		)
		(min_thickness 0.25)
		(keepout
			(tracks not_allowed)
			(vias allowed)
			(pads allowed)
			(copperpour not_allowed)
			(footprints allowed)
		)
		(placement
			(enabled no)
			(sheetname "")
		)
		(fill yes
			(thermal_gap 0.5)
			(thermal_bridge_width 0.5)
			(island_removal_mode 0)
		)
		(polygon
			(pts
				(arc
					(start 422.069514 -397.59001)
					(mid 421.310054 -397.59001)
					(end 422.069514 -397.59001)
				)
			)
		)
	)
	(zone
		(layers "B.Cu" "In9.Cu" "In11.Cu" "In13.Cu" "In15.Cu")
		(hatch none 0.5)
		(connect_pads
			(clearance 0)
		)
		(min_thickness 0.25)
		(keepout
			(tracks not_allowed)
			(vias allowed)
			(pads allowed)
			(copperpour not_allowed)
			(footprints allowed)
		)
		(placement
			(enabled no)
			(sheetname "")
		)
		(fill yes
			(thermal_gap 0.5)
			(thermal_bridge_width 0.5)
			(island_removal_mode 0)
		)
		(polygon
			(pts
				(arc
					(start 380.86665 -342.439498)
					(mid 380.16307 -342.439498)
					(end 380.86665 -342.439498)
				)
			)
		)
	)
	(zone
		(layers "B.Cu" "In9.Cu" "In11.Cu" "In13.Cu" "In15.Cu")
		(hatch none 0.5)
		(connect_pads
			(clearance 0)
		)
		(min_thickness 0.25)
		(keepout
			(tracks not_allowed)
			(vias allowed)
			(pads allowed)
			(copperpour not_allowed)
			(footprints allowed)
		)
		(placement
			(enabled no)
			(sheetname "")
		)
		(fill yes
			(thermal_gap 0.5)
			(thermal_bridge_width 0.5)
			(island_removal_mode 0)
		)
		(polygon
			(pts
				(arc
					(start 87.416386 -31.858712)
					(mid 86.712806 -31.858712)
					(end 87.416386 -31.858712)
				)
			)
		)
	)
	(zone
		(layers "B.Cu" "In9.Cu" "In11.Cu" "In13.Cu" "In15.Cu")
		(hatch none 0.5)
		(connect_pads
			(clearance 0)
		)
		(min_thickness 0.25)
		(keepout
			(tracks not_allowed)
			(vias allowed)
			(pads allowed)
			(copperpour not_allowed)
			(footprints allowed)
		)
		(placement
			(enabled no)
			(sheetname "")
		)
		(fill yes
			(thermal_gap 0.5)
			(thermal_bridge_width 0.5)
			(island_removal_mode 0)
		)
		(polygon
			(pts
				(arc
					(start 78.889606 -406.690068)
					(mid 78.130146 -406.690068)
					(end 78.889606 -406.690068)
				)
			)
		)
	)
	(zone
		(layers "B.Cu" "In9.Cu" "In11.Cu" "In13.Cu" "In15.Cu")
		(hatch none 0.5)
		(connect_pads
			(clearance 0)
		)
		(min_thickness 0.25)
		(keepout
			(tracks not_allowed)
			(vias allowed)
			(pads allowed)
			(copperpour not_allowed)
			(footprints allowed)
		)
		(placement
			(enabled no)
			(sheetname "")
		)
		(fill yes
			(thermal_gap 0.5)
			(thermal_bridge_width 0.5)
			(island_removal_mode 0)
		)
		(polygon
			(pts
				(arc
					(start 28.289758 -401.690078)
					(mid 27.530298 -401.690078)
					(end 28.289758 -401.690078)
				)
			)
		)
	)
	(zone
		(layers "B.Cu" "In9.Cu" "In11.Cu" "In13.Cu" "In15.Cu")
		(hatch none 0.5)
		(connect_pads
			(clearance 0)
		)
		(min_thickness 0.25)
		(keepout
			(tracks not_allowed)
			(vias allowed)
			(pads allowed)
			(copperpour not_allowed)
			(footprints allowed)
		)
		(placement
			(enabled no)
			(sheetname "")
		)
		(fill yes
			(thermal_gap 0.5)
			(thermal_bridge_width 0.5)
			(island_removal_mode 0)
		)
		(polygon
			(pts
				(arc
					(start 272.226278 -311.099962)
					(mid 271.573498 -311.099962)
					(end 272.226278 -311.099962)
				)
			)
		)
	)
	(zone
		(layers "B.Cu" "In9.Cu" "In11.Cu" "In13.Cu" "In15.Cu")
		(hatch none 0.5)
		(connect_pads
			(clearance 0)
		)
		(min_thickness 0.25)
		(keepout
			(tracks not_allowed)
			(vias allowed)
			(pads allowed)
			(copperpour not_allowed)
			(footprints allowed)
		)
		(placement
			(enabled no)
			(sheetname "")
		)
		(fill yes
			(thermal_gap 0.5)
			(thermal_bridge_width 0.5)
			(island_removal_mode 0)
		)
		(polygon
			(pts
				(arc
					(start 291.22624 -274.999958)
					(mid 290.57346 -274.999958)
					(end 291.22624 -274.999958)
				)
			)
		)
	)
	(zone
		(layers "B.Cu" "In9.Cu" "In11.Cu" "In13.Cu" "In15.Cu")
		(hatch none 0.5)
		(connect_pads
			(clearance 0)
		)
		(min_thickness 0.25)
		(keepout
			(tracks not_allowed)
			(vias allowed)
			(pads allowed)
			(copperpour not_allowed)
			(footprints allowed)
		)
		(placement
			(enabled no)
			(sheetname "")
		)
		(fill yes
			(thermal_gap 0.5)
			(thermal_bridge_width 0.5)
			(island_removal_mode 0)
		)
		(polygon
			(pts
				(arc
					(start 39.201598 -348.58579)
					(mid 38.498018 -348.58579)
					(end 39.201598 -348.58579)
				)
			)
		)
	)
	(zone
		(layers "B.Cu" "In9.Cu" "In11.Cu" "In13.Cu" "In15.Cu")
		(hatch none 0.5)
		(connect_pads
			(clearance 0)
		)
		(min_thickness 0.25)
		(keepout
			(tracks not_allowed)
			(vias allowed)
			(pads allowed)
			(copperpour not_allowed)
			(footprints allowed)
		)
		(placement
			(enabled no)
			(sheetname "")
		)
		(fill yes
			(thermal_gap 0.5)
			(thermal_bridge_width 0.5)
			(island_removal_mode 0)
		)
		(polygon
			(pts
				(arc
					(start 319.616328 -29.12237)
					(mid 318.912748 -29.12237)
					(end 319.616328 -29.12237)
				)
			)
		)
	)
	(zone
		(layers "B.Cu" "In9.Cu" "In11.Cu" "In13.Cu" "In15.Cu")
		(hatch none 0.5)
		(connect_pads
			(clearance 0)
		)
		(min_thickness 0.25)
		(keepout
			(tracks not_allowed)
			(vias allowed)
			(pads allowed)
			(copperpour not_allowed)
			(footprints allowed)
		)
		(placement
			(enabled no)
			(sheetname "")
		)
		(fill yes
			(thermal_gap 0.5)
			(thermal_bridge_width 0.5)
			(island_removal_mode 0)
		)
		(polygon
			(pts
				(arc
					(start 178.082702 -357.75773)
					(mid 177.379122 -357.75773)
					(end 178.082702 -357.75773)
				)
			)
		)
	)
	(zone
		(layers "B.Cu" "In9.Cu" "In11.Cu" "In13.Cu" "In15.Cu")
		(hatch none 0.5)
		(connect_pads
			(clearance 0)
		)
		(min_thickness 0.25)
		(keepout
			(tracks not_allowed)
			(vias allowed)
			(pads allowed)
			(copperpour not_allowed)
			(footprints allowed)
		)
		(placement
			(enabled no)
			(sheetname "")
		)
		(fill yes
			(thermal_gap 0.5)
			(thermal_bridge_width 0.5)
			(island_removal_mode 0)
		)
		(polygon
			(pts
				(arc
					(start 39.076376 -312.999882)
					(mid 38.423596 -312.999882)
					(end 39.076376 -312.999882)
				)
			)
		)
	)
	(zone
		(layers "B.Cu" "In9.Cu" "In11.Cu" "In13.Cu" "In15.Cu")
		(hatch none 0.5)
		(connect_pads
			(clearance 0)
		)
		(min_thickness 0.25)
		(keepout
			(tracks not_allowed)
			(vias allowed)
			(pads allowed)
			(copperpour not_allowed)
			(footprints allowed)
		)
		(placement
			(enabled no)
			(sheetname "")
		)
		(fill yes
			(thermal_gap 0.5)
			(thermal_bridge_width 0.5)
			(island_removal_mode 0)
		)
		(polygon
			(pts
				(arc
					(start 276.026118 -304.449734)
					(mid 275.373338 -304.449734)
					(end 276.026118 -304.449734)
				)
			)
		)
	)
	(zone
		(layers "B.Cu" "In9.Cu" "In11.Cu" "In13.Cu" "In15.Cu")
		(hatch none 0.5)
		(connect_pads
			(clearance 0)
		)
		(min_thickness 0.25)
		(keepout
			(tracks not_allowed)
			(vias allowed)
			(pads allowed)
			(copperpour not_allowed)
			(footprints allowed)
		)
		(placement
			(enabled no)
			(sheetname "")
		)
		(fill yes
			(thermal_gap 0.5)
			(thermal_bridge_width 0.5)
			(island_removal_mode 0)
		)
		(polygon
			(pts
				(arc
					(start 166.889684 -397.59001)
					(mid 166.130224 -397.59001)
					(end 166.889684 -397.59001)
				)
			)
		)
	)
	(zone
		(layers "B.Cu" "In9.Cu" "In11.Cu" "In13.Cu" "In15.Cu")
		(hatch none 0.5)
		(connect_pads
			(clearance 0)
		)
		(min_thickness 0.25)
		(keepout
			(tracks not_allowed)
			(vias allowed)
			(pads allowed)
			(copperpour not_allowed)
			(footprints allowed)
		)
		(placement
			(enabled no)
			(sheetname "")
		)
		(fill yes
			(thermal_gap 0.5)
			(thermal_bridge_width 0.5)
			(island_removal_mode 0)
		)
		(polygon
			(pts
				(arc
					(start 178.082702 -345.465146)
					(mid 177.379122 -345.465146)
					(end 178.082702 -345.465146)
				)
			)
		)
	)
	(zone
		(layers "B.Cu" "In9.Cu" "In11.Cu" "In13.Cu" "In15.Cu")
		(hatch none 0.5)
		(connect_pads
			(clearance 0)
		)
		(min_thickness 0.25)
		(keepout
			(tracks not_allowed)
			(vias allowed)
			(pads allowed)
			(copperpour not_allowed)
			(footprints allowed)
		)
		(placement
			(enabled no)
			(sheetname "")
		)
		(fill yes
			(thermal_gap 0.5)
			(thermal_bridge_width 0.5)
			(island_removal_mode 0)
		)
		(polygon
			(pts
				(arc
					(start 191.382142 -345.465146)
					(mid 190.678562 -345.465146)
					(end 191.382142 -345.465146)
				)
			)
		)
	)
	(zone
		(layers "B.Cu" "In9.Cu" "In11.Cu" "In13.Cu" "In15.Cu")
		(hatch none 0.5)
		(connect_pads
			(clearance 0)
		)
		(min_thickness 0.25)
		(keepout
			(tracks not_allowed)
			(vias allowed)
			(pads allowed)
			(copperpour not_allowed)
			(footprints allowed)
		)
		(placement
			(enabled no)
			(sheetname "")
		)
		(fill yes
			(thermal_gap 0.5)
			(thermal_bridge_width 0.5)
			(island_removal_mode 0)
		)
		(polygon
			(pts
				(arc
					(start 67.576192 -313.949842)
					(mid 66.923412 -313.949842)
					(end 67.576192 -313.949842)
				)
			)
		)
	)
	(zone
		(layers "B.Cu" "In9.Cu" "In11.Cu" "In13.Cu" "In15.Cu")
		(hatch none 0.5)
		(connect_pads
			(clearance 0)
		)
		(min_thickness 0.25)
		(keepout
			(tracks not_allowed)
			(vias allowed)
			(pads allowed)
			(copperpour not_allowed)
			(footprints allowed)
		)
		(placement
			(enabled no)
			(sheetname "")
		)
		(fill yes
			(thermal_gap 0.5)
			(thermal_bridge_width 0.5)
			(island_removal_mode 0)
		)
		(polygon
			(pts
				(arc
					(start 400.676364 -313.949842)
					(mid 400.023584 -313.949842)
					(end 400.676364 -313.949842)
				)
			)
		)
	)
	(zone
		(layers "B.Cu" "In9.Cu" "In11.Cu" "In13.Cu" "In15.Cu")
		(hatch none 0.5)
		(connect_pads
			(clearance 0)
		)
		(min_thickness 0.25)
		(keepout
			(tracks not_allowed)
			(vias allowed)
			(pads allowed)
			(copperpour not_allowed)
			(footprints allowed)
		)
		(placement
			(enabled no)
			(sheetname "")
		)
		(fill yes
			(thermal_gap 0.5)
			(thermal_bridge_width 0.5)
			(island_removal_mode 0)
		)
		(polygon
			(pts
				(arc
					(start 168.476422 -313.949842)
					(mid 167.823642 -313.949842)
					(end 168.476422 -313.949842)
				)
			)
		)
	)
	(zone
		(layers "B.Cu" "In9.Cu" "In11.Cu" "In13.Cu" "In15.Cu")
		(hatch none 0.5)
		(connect_pads
			(clearance 0)
		)
		(min_thickness 0.25)
		(keepout
			(tracks not_allowed)
			(vias allowed)
			(pads allowed)
			(copperpour not_allowed)
			(footprints allowed)
		)
		(placement
			(enabled no)
			(sheetname "")
		)
		(fill yes
			(thermal_gap 0.5)
			(thermal_bridge_width 0.5)
			(island_removal_mode 0)
		)
		(polygon
			(pts
				(arc
					(start 390.19353 -351.611438)
					(mid 389.48995 -351.611438)
					(end 390.19353 -351.611438)
				)
			)
		)
	)
	(zone
		(layers "B.Cu" "In9.Cu" "In11.Cu" "In13.Cu" "In15.Cu")
		(hatch none 0.5)
		(connect_pads
			(clearance 0)
		)
		(min_thickness 0.25)
		(keepout
			(tracks not_allowed)
			(vias allowed)
			(pads allowed)
			(copperpour not_allowed)
			(footprints allowed)
		)
		(placement
			(enabled no)
			(sheetname "")
		)
		(fill yes
			(thermal_gap 0.5)
			(thermal_bridge_width 0.5)
			(island_removal_mode 0)
		)
		(polygon
			(pts
				(arc
					(start 280.776172 -273.099784)
					(mid 280.123392 -273.099784)
					(end 280.776172 -273.099784)
				)
			)
		)
	)
	(zone
		(layers "B.Cu" "In9.Cu" "In11.Cu" "In13.Cu" "In15.Cu")
		(hatch none 0.5)
		(connect_pads
			(clearance 0)
		)
		(min_thickness 0.25)
		(keepout
			(tracks not_allowed)
			(vias allowed)
			(pads allowed)
			(copperpour not_allowed)
			(footprints allowed)
		)
		(placement
			(enabled no)
			(sheetname "")
		)
		(fill yes
			(thermal_gap 0.5)
			(thermal_bridge_width 0.5)
			(island_removal_mode 0)
		)
		(polygon
			(pts
				(arc
					(start 62.826138 -312.049922)
					(mid 62.173358 -312.049922)
					(end 62.826138 -312.049922)
				)
			)
		)
	)
	(zone
		(layers "B.Cu" "In9.Cu" "In11.Cu" "In13.Cu" "In15.Cu")
		(hatch none 0.5)
		(connect_pads
			(clearance 0)
		)
		(min_thickness 0.25)
		(keepout
			(tracks not_allowed)
			(vias allowed)
			(pads allowed)
			(copperpour not_allowed)
			(footprints allowed)
		)
		(placement
			(enabled no)
			(sheetname "")
		)
		(fill yes
			(thermal_gap 0.5)
			(thermal_bridge_width 0.5)
			(island_removal_mode 0)
		)
		(polygon
			(pts
				(arc
					(start 340.835234 -342.439498)
					(mid 340.131654 -342.439498)
					(end 340.835234 -342.439498)
				)
			)
		)
	)
	(zone
		(layers "B.Cu" "In9.Cu" "In11.Cu" "In13.Cu" "In15.Cu")
		(hatch none 0.5)
		(connect_pads
			(clearance 0)
		)
		(min_thickness 0.25)
		(keepout
			(tracks not_allowed)
			(vias allowed)
			(pads allowed)
			(copperpour not_allowed)
			(footprints allowed)
		)
		(placement
			(enabled no)
			(sheetname "")
		)
		(fill yes
			(thermal_gap 0.5)
			(thermal_bridge_width 0.5)
			(island_removal_mode 0)
		)
		(polygon
			(pts
				(arc
					(start 151.516588 -32.722312)
					(mid 150.813008 -32.722312)
					(end 151.516588 -32.722312)
				)
			)
		)
	)
	(zone
		(layers "B.Cu" "In9.Cu" "In11.Cu" "In13.Cu" "In15.Cu")
		(hatch none 0.5)
		(connect_pads
			(clearance 0)
		)
		(min_thickness 0.25)
		(keepout
			(tracks not_allowed)
			(vias allowed)
			(pads allowed)
			(copperpour not_allowed)
			(footprints allowed)
		)
		(placement
			(enabled no)
			(sheetname "")
		)
		(fill yes
			(thermal_gap 0.5)
			(thermal_bridge_width 0.5)
			(island_removal_mode 0)
		)
		(polygon
			(pts
				(arc
					(start 69.476366 -313.949842)
					(mid 68.823586 -313.949842)
					(end 69.476366 -313.949842)
				)
			)
		)
	)
	(zone
		(layers "B.Cu" "In9.Cu" "In11.Cu" "In13.Cu" "In15.Cu")
		(hatch none 0.5)
		(connect_pads
			(clearance 0)
		)
		(min_thickness 0.25)
		(keepout
			(tracks not_allowed)
			(vias allowed)
			(pads allowed)
			(copperpour not_allowed)
			(footprints allowed)
		)
		(placement
			(enabled no)
			(sheetname "")
		)
		(fill yes
			(thermal_gap 0.5)
			(thermal_bridge_width 0.5)
			(island_removal_mode 0)
		)
		(polygon
			(pts
				(arc
					(start 403.49297 -348.58579)
					(mid 402.78939 -348.58579)
					(end 403.49297 -348.58579)
				)
			)
		)
	)
	(zone
		(layers "B.Cu" "In9.Cu" "In11.Cu" "In13.Cu" "In15.Cu")
		(hatch none 0.5)
		(connect_pads
			(clearance 0)
		)
		(min_thickness 0.25)
		(keepout
			(tracks not_allowed)
			(vias allowed)
			(pads allowed)
			(copperpour not_allowed)
			(footprints allowed)
		)
		(placement
			(enabled no)
			(sheetname "")
		)
		(fill yes
			(thermal_gap 0.5)
			(thermal_bridge_width 0.5)
			(island_removal_mode 0)
		)
		(polygon
			(pts
				(arc
					(start 81.089754 -404.290022)
					(mid 80.330294 -404.290022)
					(end 81.089754 -404.290022)
				)
			)
		)
	)
	(zone
		(layers "B.Cu" "In9.Cu" "In11.Cu" "In13.Cu" "In15.Cu")
		(hatch none 0.5)
		(connect_pads
			(clearance 0)
		)
		(min_thickness 0.25)
		(keepout
			(tracks not_allowed)
			(vias allowed)
			(pads allowed)
			(copperpour not_allowed)
			(footprints allowed)
		)
		(placement
			(enabled no)
			(sheetname "")
		)
		(fill yes
			(thermal_gap 0.5)
			(thermal_bridge_width 0.5)
			(island_removal_mode 0)
		)
		(polygon
			(pts
				(arc
					(start 293.120572 -348.58579)
					(mid 292.416992 -348.58579)
					(end 293.120572 -348.58579)
				)
			)
		)
	)
	(zone
		(layers "B.Cu" "In9.Cu" "In11.Cu" "In13.Cu" "In15.Cu")
		(hatch none 0.5)
		(connect_pads
			(clearance 0)
		)
		(min_thickness 0.25)
		(keepout
			(tracks not_allowed)
			(vias allowed)
			(pads allowed)
			(copperpour not_allowed)
			(footprints allowed)
		)
		(placement
			(enabled no)
			(sheetname "")
		)
		(fill yes
			(thermal_gap 0.5)
			(thermal_bridge_width 0.5)
			(island_removal_mode 0)
		)
		(polygon
			(pts
				(arc
					(start 387.94817 -342.439498)
					(mid 387.24459 -342.439498)
					(end 387.94817 -342.439498)
				)
			)
		)
	)
	(zone
		(layers "B.Cu" "In9.Cu" "In11.Cu" "In13.Cu" "In15.Cu")
		(hatch none 0.5)
		(connect_pads
			(clearance 0)
		)
		(min_thickness 0.25)
		(keepout
			(tracks not_allowed)
			(vias allowed)
			(pads allowed)
			(copperpour not_allowed)
			(footprints allowed)
		)
		(placement
			(enabled no)
			(sheetname "")
		)
		(fill yes
			(thermal_gap 0.5)
			(thermal_bridge_width 0.5)
			(island_removal_mode 0)
		)
		(polygon
			(pts
				(arc
					(start 47.664878 -345.465146)
					(mid 46.961298 -345.465146)
					(end 47.664878 -345.465146)
				)
			)
		)
	)
	(zone
		(layers "B.Cu" "In9.Cu" "In11.Cu" "In13.Cu" "In15.Cu")
		(hatch none 0.5)
		(connect_pads
			(clearance 0)
		)
		(min_thickness 0.25)
		(keepout
			(tracks not_allowed)
			(vias allowed)
			(pads allowed)
			(copperpour not_allowed)
			(footprints allowed)
		)
		(placement
			(enabled no)
			(sheetname "")
		)
		(fill yes
			(thermal_gap 0.5)
			(thermal_bridge_width 0.5)
			(island_removal_mode 0)
		)
		(polygon
			(pts
				(arc
					(start 280.684732 -348.58579)
					(mid 279.981152 -348.58579)
					(end 280.684732 -348.58579)
				)
			)
		)
	)
	(zone
		(layers "B.Cu" "In9.Cu" "In11.Cu" "In13.Cu" "In15.Cu")
		(hatch none 0.5)
		(connect_pads
			(clearance 0)
		)
		(min_thickness 0.25)
		(keepout
			(tracks not_allowed)
			(vias allowed)
			(pads allowed)
			(copperpour not_allowed)
			(footprints allowed)
		)
		(placement
			(enabled no)
			(sheetname "")
		)
		(fill yes
			(thermal_gap 0.5)
			(thermal_bridge_width 0.5)
			(island_removal_mode 0)
		)
		(polygon
			(pts
				(arc
					(start 194.491102 -351.611438)
					(mid 193.787522 -351.611438)
					(end 194.491102 -351.611438)
				)
			)
		)
	)
	(zone
		(layers "B.Cu" "In9.Cu" "In11.Cu" "In13.Cu" "In15.Cu")
		(hatch none 0.5)
		(connect_pads
			(clearance 0)
		)
		(min_thickness 0.25)
		(keepout
			(tracks not_allowed)
			(vias allowed)
			(pads allowed)
			(copperpour not_allowed)
			(footprints allowed)
		)
		(placement
			(enabled no)
			(sheetname "")
		)
		(fill yes
			(thermal_gap 0.5)
			(thermal_bridge_width 0.5)
			(island_removal_mode 0)
		)
		(polygon
			(pts
				(arc
					(start 428.669704 -371.790214)
					(mid 427.910244 -371.790214)
					(end 428.669704 -371.790214)
				)
			)
		)
	)
	(zone
		(layers "B.Cu" "In9.Cu" "In11.Cu" "In13.Cu" "In15.Cu")
		(hatch none 0.5)
		(connect_pads
			(clearance 0)
		)
		(min_thickness 0.25)
		(keepout
			(tracks not_allowed)
			(vias allowed)
			(pads allowed)
			(copperpour not_allowed)
			(footprints allowed)
		)
		(placement
			(enabled no)
			(sheetname "")
		)
		(fill yes
			(thermal_gap 0.5)
			(thermal_bridge_width 0.5)
			(island_removal_mode 0)
		)
		(polygon
			(pts
				(arc
					(start 393.30249 -345.465146)
					(mid 392.59891 -345.465146)
					(end 393.30249 -345.465146)
				)
			)
		)
	)
	(zone
		(layers "B.Cu" "In9.Cu" "In11.Cu" "In13.Cu" "In15.Cu")
		(hatch none 0.5)
		(connect_pads
			(clearance 0)
		)
		(min_thickness 0.25)
		(keepout
			(tracks not_allowed)
			(vias allowed)
			(pads allowed)
			(copperpour not_allowed)
			(footprints allowed)
		)
		(placement
			(enabled no)
			(sheetname "")
		)
		(fill yes
			(thermal_gap 0.5)
			(thermal_bridge_width 0.5)
			(island_removal_mode 0)
		)
		(polygon
			(pts
				(arc
					(start 394.16609 -354.732082)
					(mid 393.46251 -354.732082)
					(end 394.16609 -354.732082)
				)
			)
		)
	)
	(zone
		(layers "B.Cu" "In9.Cu" "In11.Cu" "In13.Cu" "In15.Cu")
		(hatch none 0.5)
		(connect_pads
			(clearance 0)
		)
		(min_thickness 0.25)
		(keepout
			(tracks not_allowed)
			(vias allowed)
			(pads allowed)
			(copperpour not_allowed)
			(footprints allowed)
		)
		(placement
			(enabled no)
			(sheetname "")
		)
		(fill yes
			(thermal_gap 0.5)
			(thermal_bridge_width 0.5)
			(island_removal_mode 0)
		)
		(polygon
			(pts
				(arc
					(start 275.076158 -301.599854)
					(mid 274.423378 -301.599854)
					(end 275.076158 -301.599854)
				)
			)
		)
	)
	(zone
		(layers "B.Cu" "In9.Cu" "In11.Cu" "In13.Cu" "In15.Cu")
		(hatch none 0.5)
		(connect_pads
			(clearance 0)
		)
		(min_thickness 0.25)
		(keepout
			(tracks not_allowed)
			(vias allowed)
			(pads allowed)
			(copperpour not_allowed)
			(footprints allowed)
		)
		(placement
			(enabled no)
			(sheetname "")
		)
		(fill yes
			(thermal_gap 0.5)
			(thermal_bridge_width 0.5)
			(island_removal_mode 0)
		)
		(polygon
			(pts
				(arc
					(start 162.537902 -351.611438)
					(mid 161.834322 -351.611438)
					(end 162.537902 -351.611438)
				)
			)
		)
	)
	(zone
		(layers "B.Cu" "In9.Cu" "In11.Cu" "In13.Cu" "In15.Cu")
		(hatch none 0.5)
		(connect_pads
			(clearance 0)
		)
		(min_thickness 0.25)
		(keepout
			(tracks not_allowed)
			(vias allowed)
			(pads allowed)
			(copperpour not_allowed)
			(footprints allowed)
		)
		(placement
			(enabled no)
			(sheetname "")
		)
		(fill yes
			(thermal_gap 0.5)
			(thermal_bridge_width 0.5)
			(island_removal_mode 0)
		)
		(polygon
			(pts
				(arc
					(start 192.226438 -312.049922)
					(mid 191.573658 -312.049922)
					(end 192.226438 -312.049922)
				)
			)
		)
	)
	(zone
		(layers "B.Cu" "In9.Cu" "In11.Cu" "In13.Cu" "In15.Cu")
		(hatch none 0.5)
		(connect_pads
			(clearance 0)
		)
		(min_thickness 0.25)
		(keepout
			(tracks not_allowed)
			(vias allowed)
			(pads allowed)
			(copperpour not_allowed)
			(footprints allowed)
		)
		(placement
			(enabled no)
			(sheetname "")
		)
		(fill yes
			(thermal_gap 0.5)
			(thermal_bridge_width 0.5)
			(island_removal_mode 0)
		)
		(polygon
			(pts
				(arc
					(start 427.27626 -313.949842)
					(mid 426.62348 -313.949842)
					(end 427.27626 -313.949842)
				)
			)
		)
	)
	(zone
		(layers "B.Cu" "In9.Cu" "In11.Cu" "In13.Cu" "In15.Cu")
		(hatch none 0.5)
		(connect_pads
			(clearance 0)
		)
		(min_thickness 0.25)
		(keepout
			(tracks not_allowed)
			(vias allowed)
			(pads allowed)
			(copperpour not_allowed)
			(footprints allowed)
		)
		(placement
			(enabled no)
			(sheetname "")
		)
		(fill yes
			(thermal_gap 0.5)
			(thermal_bridge_width 0.5)
			(island_removal_mode 0)
		)
		(polygon
			(pts
				(arc
					(start 37.089842 -374.390158)
					(mid 36.330382 -374.390158)
					(end 37.089842 -374.390158)
				)
			)
		)
	)
	(zone
		(layers "B.Cu" "In9.Cu" "In11.Cu" "In13.Cu" "In15.Cu")
		(hatch none 0.5)
		(connect_pads
			(clearance 0)
		)
		(min_thickness 0.25)
		(keepout
			(tracks not_allowed)
			(vias allowed)
			(pads allowed)
			(copperpour not_allowed)
			(footprints allowed)
		)
		(placement
			(enabled no)
			(sheetname "")
		)
		(fill yes
			(thermal_gap 0.5)
			(thermal_bridge_width 0.5)
			(island_removal_mode 0)
		)
		(polygon
			(pts
				(arc
					(start 36.092638 -354.732082)
					(mid 35.389058 -354.732082)
					(end 36.092638 -354.732082)
				)
			)
		)
	)
	(zone
		(layers "B.Cu" "In9.Cu" "In11.Cu" "In13.Cu" "In15.Cu")
		(hatch none 0.5)
		(connect_pads
			(clearance 0)
		)
		(min_thickness 0.25)
		(keepout
			(tracks not_allowed)
			(vias allowed)
			(pads allowed)
			(copperpour not_allowed)
			(footprints allowed)
		)
		(placement
			(enabled no)
			(sheetname "")
		)
		(fill yes
			(thermal_gap 0.5)
			(thermal_bridge_width 0.5)
			(island_removal_mode 0)
		)
		(polygon
			(pts
				(arc
					(start 396.87627 -274.049744)
					(mid 396.22349 -274.049744)
					(end 396.87627 -274.049744)
				)
			)
		)
	)
	(zone
		(layers "B.Cu" "In9.Cu" "In11.Cu" "In13.Cu" "In15.Cu")
		(hatch none 0.5)
		(connect_pads
			(clearance 0)
		)
		(min_thickness 0.25)
		(keepout
			(tracks not_allowed)
			(vias allowed)
			(pads allowed)
			(copperpour not_allowed)
			(footprints allowed)
		)
		(placement
			(enabled no)
			(sheetname "")
		)
		(fill yes
			(thermal_gap 0.5)
			(thermal_bridge_width 0.5)
			(island_removal_mode 0)
		)
		(polygon
			(pts
				(arc
					(start 334.617314 -354.732082)
					(mid 333.913734 -354.732082)
					(end 334.617314 -354.732082)
				)
			)
		)
	)
	(zone
		(layers "B.Cu" "In9.Cu" "In11.Cu" "In13.Cu" "In15.Cu")
		(hatch none 0.5)
		(connect_pads
			(clearance 0)
		)
		(min_thickness 0.25)
		(keepout
			(tracks not_allowed)
			(vias allowed)
			(pads allowed)
			(copperpour not_allowed)
			(footprints allowed)
		)
		(placement
			(enabled no)
			(sheetname "")
		)
		(fill yes
			(thermal_gap 0.5)
			(thermal_bridge_width 0.5)
			(island_removal_mode 0)
		)
		(polygon
			(pts
				(arc
					(start 241.616484 -31.858712)
					(mid 240.912904 -31.858712)
					(end 241.616484 -31.858712)
				)
			)
		)
	)
	(zone
		(layers "B.Cu" "In9.Cu" "In11.Cu" "In13.Cu" "In15.Cu")
		(hatch none 0.5)
		(connect_pads
			(clearance 0)
		)
		(min_thickness 0.25)
		(keepout
			(tracks not_allowed)
			(vias allowed)
			(pads allowed)
			(copperpour not_allowed)
			(footprints allowed)
		)
		(placement
			(enabled no)
			(sheetname "")
		)
		(fill yes
			(thermal_gap 0.5)
			(thermal_bridge_width 0.5)
			(island_removal_mode 0)
		)
		(polygon
			(pts
				(arc
					(start 67.941952 -348.58579)
					(mid 67.238372 -348.58579)
					(end 67.941952 -348.58579)
				)
			)
		)
	)
	(zone
		(layers "B.Cu" "In9.Cu" "In11.Cu" "In13.Cu" "In15.Cu")
		(hatch none 0.5)
		(connect_pads
			(clearance 0)
		)
		(min_thickness 0.25)
		(keepout
			(tracks not_allowed)
			(vias allowed)
			(pads allowed)
			(copperpour not_allowed)
			(footprints allowed)
		)
		(placement
			(enabled no)
			(sheetname "")
		)
		(fill yes
			(thermal_gap 0.5)
			(thermal_bridge_width 0.5)
			(island_removal_mode 0)
		)
		(polygon
			(pts
				(arc
					(start 426.469556 -398.890236)
					(mid 425.710096 -398.890236)
					(end 426.469556 -398.890236)
				)
			)
		)
	)
	(zone
		(layers "B.Cu" "In9.Cu" "In11.Cu" "In13.Cu" "In15.Cu")
		(hatch none 0.5)
		(connect_pads
			(clearance 0)
		)
		(min_thickness 0.25)
		(keepout
			(tracks not_allowed)
			(vias allowed)
			(pads allowed)
			(copperpour not_allowed)
			(footprints allowed)
		)
		(placement
			(enabled no)
			(sheetname "")
		)
		(fill yes
			(thermal_gap 0.5)
			(thermal_bridge_width 0.5)
			(island_removal_mode 0)
		)
		(polygon
			(pts
				(arc
					(start 71.914512 -342.439498)
					(mid 71.210932 -342.439498)
					(end 71.914512 -342.439498)
				)
			)
		)
	)
	(zone
		(layers "B.Cu" "In9.Cu" "In11.Cu" "In13.Cu" "In15.Cu")
		(hatch none 0.5)
		(connect_pads
			(clearance 0)
		)
		(min_thickness 0.25)
		(keepout
			(tracks not_allowed)
			(vias allowed)
			(pads allowed)
			(copperpour not_allowed)
			(footprints allowed)
		)
		(placement
			(enabled no)
			(sheetname "")
		)
		(fill yes
			(thermal_gap 0.5)
			(thermal_bridge_width 0.5)
			(island_removal_mode 0)
		)
		(polygon
			(pts
				(arc
					(start 178.926236 -311.099962)
					(mid 178.273456 -311.099962)
					(end 178.926236 -311.099962)
				)
			)
		)
	)
	(zone
		(layers "B.Cu" "In9.Cu" "In11.Cu" "In13.Cu" "In15.Cu")
		(hatch none 0.5)
		(connect_pads
			(clearance 0)
		)
		(min_thickness 0.25)
		(keepout
			(tracks not_allowed)
			(vias allowed)
			(pads allowed)
			(copperpour not_allowed)
			(footprints allowed)
		)
		(placement
			(enabled no)
			(sheetname "")
		)
		(fill yes
			(thermal_gap 0.5)
			(thermal_bridge_width 0.5)
			(island_removal_mode 0)
		)
		(polygon
			(pts
				(arc
					(start 29.011118 -345.465146)
					(mid 28.307538 -345.465146)
					(end 29.011118 -345.465146)
				)
			)
		)
	)
	(zone
		(layers "B.Cu" "In9.Cu" "In11.Cu" "In13.Cu" "In15.Cu")
		(hatch none 0.5)
		(connect_pads
			(clearance 0)
		)
		(min_thickness 0.25)
		(keepout
			(tracks not_allowed)
			(vias allowed)
			(pads allowed)
			(copperpour not_allowed)
			(footprints allowed)
		)
		(placement
			(enabled no)
			(sheetname "")
		)
		(fill yes
			(thermal_gap 0.5)
			(thermal_bridge_width 0.5)
			(island_removal_mode 0)
		)
		(polygon
			(pts
				(arc
					(start 42.876216 -313.949842)
					(mid 42.223436 -313.949842)
					(end 42.876216 -313.949842)
				)
			)
		)
	)
	(zone
		(layers "B.Cu" "In9.Cu" "In11.Cu" "In13.Cu" "In15.Cu")
		(hatch none 0.5)
		(connect_pads
			(clearance 0)
		)
		(min_thickness 0.25)
		(keepout
			(tracks not_allowed)
			(vias allowed)
			(pads allowed)
			(copperpour not_allowed)
			(footprints allowed)
		)
		(placement
			(enabled no)
			(sheetname "")
		)
		(fill yes
			(thermal_gap 0.5)
			(thermal_bridge_width 0.5)
			(island_removal_mode 0)
		)
		(polygon
			(pts
				(arc
					(start 435.382162 -351.611438)
					(mid 434.678582 -351.611438)
					(end 435.382162 -351.611438)
				)
			)
		)
	)
	(zone
		(layers "B.Cu" "In9.Cu" "In11.Cu" "In13.Cu" "In15.Cu")
		(hatch none 0.5)
		(connect_pads
			(clearance 0)
		)
		(min_thickness 0.25)
		(keepout
			(tracks not_allowed)
			(vias allowed)
			(pads allowed)
			(copperpour not_allowed)
			(footprints allowed)
		)
		(placement
			(enabled no)
			(sheetname "")
		)
		(fill yes
			(thermal_gap 0.5)
			(thermal_bridge_width 0.5)
			(island_removal_mode 0)
		)
		(polygon
			(pts
				(arc
					(start 37.176202 -314.899802)
					(mid 36.523422 -314.899802)
					(end 37.176202 -314.899802)
				)
			)
		)
	)
	(zone
		(layers "B.Cu" "In9.Cu" "In11.Cu" "In13.Cu" "In15.Cu")
		(hatch none 0.5)
		(connect_pads
			(clearance 0)
		)
		(min_thickness 0.25)
		(keepout
			(tracks not_allowed)
			(vias allowed)
			(pads allowed)
			(copperpour not_allowed)
			(footprints allowed)
		)
		(placement
			(enabled no)
			(sheetname "")
		)
		(fill yes
			(thermal_gap 0.5)
			(thermal_bridge_width 0.5)
			(island_removal_mode 0)
		)
		(polygon
			(pts
				(arc
					(start 175.662336 -30.922468)
					(mid 174.958756 -30.922468)
					(end 175.662336 -30.922468)
				)
			)
		)
	)
	(zone
		(layers "B.Cu" "In9.Cu" "In11.Cu" "In13.Cu" "In15.Cu")
		(hatch none 0.5)
		(connect_pads
			(clearance 0)
		)
		(min_thickness 0.25)
		(keepout
			(tracks not_allowed)
			(vias allowed)
			(pads allowed)
			(copperpour not_allowed)
			(footprints allowed)
		)
		(placement
			(enabled no)
			(sheetname "")
		)
		(fill yes
			(thermal_gap 0.5)
			(thermal_bridge_width 0.5)
			(island_removal_mode 0)
		)
		(polygon
			(pts
				(arc
					(start 184.300622 -342.439498)
					(mid 183.597042 -342.439498)
					(end 184.300622 -342.439498)
				)
			)
		)
	)
	(zone
		(layers "B.Cu" "In9.Cu" "In11.Cu" "In13.Cu" "In15.Cu")
		(hatch none 0.5)
		(connect_pads
			(clearance 0)
		)
		(min_thickness 0.25)
		(keepout
			(tracks not_allowed)
			(vias allowed)
			(pads allowed)
			(copperpour not_allowed)
			(footprints allowed)
		)
		(placement
			(enabled no)
			(sheetname "")
		)
		(fill yes
			(thermal_gap 0.5)
			(thermal_bridge_width 0.5)
			(island_removal_mode 0)
		)
		(polygon
			(pts
				(arc
					(start 317.762128 -30.922468)
					(mid 317.058548 -30.922468)
					(end 317.762128 -30.922468)
				)
			)
		)
	)
	(zone
		(layers "B.Cu" "In9.Cu" "In11.Cu" "In13.Cu" "In15.Cu")
		(hatch none 0.5)
		(connect_pads
			(clearance 0)
		)
		(min_thickness 0.25)
		(keepout
			(tracks not_allowed)
			(vias allowed)
			(pads allowed)
			(copperpour not_allowed)
			(footprints allowed)
		)
		(placement
			(enabled no)
			(sheetname "")
		)
		(fill yes
			(thermal_gap 0.5)
			(thermal_bridge_width 0.5)
			(island_removal_mode 0)
		)
		(polygon
			(pts
				(arc
					(start 45.419518 -348.58579)
					(mid 44.715938 -348.58579)
					(end 45.419518 -348.58579)
				)
			)
		)
	)
	(zone
		(layers "B.Cu" "In9.Cu" "In11.Cu" "In13.Cu" "In15.Cu")
		(hatch none 0.5)
		(connect_pads
			(clearance 0)
		)
		(min_thickness 0.25)
		(keepout
			(tracks not_allowed)
			(vias allowed)
			(pads allowed)
			(copperpour not_allowed)
			(footprints allowed)
		)
		(placement
			(enabled no)
			(sheetname "")
		)
		(fill yes
			(thermal_gap 0.5)
			(thermal_bridge_width 0.5)
			(island_removal_mode 0)
		)
		(polygon
			(pts
				(arc
					(start 399.52041 -357.75773)
					(mid 398.81683 -357.75773)
					(end 399.52041 -357.75773)
				)
			)
		)
	)
	(zone
		(layers "B.Cu" "In9.Cu" "In11.Cu" "In13.Cu" "In15.Cu")
		(hatch none 0.5)
		(connect_pads
			(clearance 0)
		)
		(min_thickness 0.25)
		(keepout
			(tracks not_allowed)
			(vias allowed)
			(pads allowed)
			(copperpour not_allowed)
			(footprints allowed)
		)
		(placement
			(enabled no)
			(sheetname "")
		)
		(fill yes
			(thermal_gap 0.5)
			(thermal_bridge_width 0.5)
			(island_removal_mode 0)
		)
		(polygon
			(pts
				(arc
					(start 428.669704 -396.49019)
					(mid 427.910244 -396.49019)
					(end 428.669704 -396.49019)
				)
			)
		)
	)
	(zone
		(layers "B.Cu" "In9.Cu" "In11.Cu" "In13.Cu" "In15.Cu")
		(hatch none 0.5)
		(connect_pads
			(clearance 0)
		)
		(min_thickness 0.25)
		(keepout
			(tracks not_allowed)
			(vias allowed)
			(pads allowed)
			(copperpour not_allowed)
			(footprints allowed)
		)
		(placement
			(enabled no)
			(sheetname "")
		)
		(fill yes
			(thermal_gap 0.5)
			(thermal_bridge_width 0.5)
			(island_removal_mode 0)
		)
		(polygon
			(pts
				(arc
					(start 344.807794 -351.611438)
					(mid 344.104214 -351.611438)
					(end 344.807794 -351.611438)
				)
			)
		)
	)
	(zone
		(layers "B.Cu" "In9.Cu" "In11.Cu" "In13.Cu" "In15.Cu")
		(hatch none 0.5)
		(connect_pads
			(clearance 0)
		)
		(min_thickness 0.25)
		(keepout
			(tracks not_allowed)
			(vias allowed)
			(pads allowed)
			(copperpour not_allowed)
			(footprints allowed)
		)
		(placement
			(enabled no)
			(sheetname "")
		)
		(fill yes
			(thermal_gap 0.5)
			(thermal_bridge_width 0.5)
			(island_removal_mode 0)
		)
		(polygon
			(pts
				(arc
					(start 175.126396 -311.099962)
					(mid 174.473616 -311.099962)
					(end 175.126396 -311.099962)
				)
			)
		)
	)
	(zone
		(layers "B.Cu" "In9.Cu" "In11.Cu" "In13.Cu" "In15.Cu")
		(hatch none 0.5)
		(connect_pads
			(clearance 0)
		)
		(min_thickness 0.25)
		(keepout
			(tracks not_allowed)
			(vias allowed)
			(pads allowed)
			(copperpour not_allowed)
			(footprints allowed)
		)
		(placement
			(enabled no)
			(sheetname "")
		)
		(fill yes
			(thermal_gap 0.5)
			(thermal_bridge_width 0.5)
			(island_removal_mode 0)
		)
		(polygon
			(pts
				(arc
					(start 201.662284 -30.922468)
					(mid 200.958704 -30.922468)
					(end 201.662284 -30.922468)
				)
			)
		)
	)
	(zone
		(layers "B.Cu" "In9.Cu" "In11.Cu" "In13.Cu" "In15.Cu")
		(hatch none 0.5)
		(connect_pads
			(clearance 0)
		)
		(min_thickness 0.25)
		(keepout
			(tracks not_allowed)
			(vias allowed)
			(pads allowed)
			(copperpour not_allowed)
			(footprints allowed)
		)
		(placement
			(enabled no)
			(sheetname "")
		)
		(fill yes
			(thermal_gap 0.5)
			(thermal_bridge_width 0.5)
			(island_removal_mode 0)
		)
		(polygon
			(pts
				(arc
					(start 160.289748 -370.489988)
					(mid 159.530288 -370.489988)
					(end 160.289748 -370.489988)
				)
			)
		)
	)
	(zone
		(layers "B.Cu" "In9.Cu" "In11.Cu" "In13.Cu" "In15.Cu")
		(hatch none 0.5)
		(connect_pads
			(clearance 0)
		)
		(min_thickness 0.25)
		(keepout
			(tracks not_allowed)
			(vias allowed)
			(pads allowed)
			(copperpour not_allowed)
			(footprints allowed)
		)
		(placement
			(enabled no)
			(sheetname "")
		)
		(fill yes
			(thermal_gap 0.5)
			(thermal_bridge_width 0.5)
			(island_removal_mode 0)
		)
		(polygon
			(pts
				(arc
					(start 29.874718 -345.465146)
					(mid 29.171138 -345.465146)
					(end 29.874718 -345.465146)
				)
			)
		)
	)
	(zone
		(layers "B.Cu" "In9.Cu" "In11.Cu" "In13.Cu" "In15.Cu")
		(hatch none 0.5)
		(connect_pads
			(clearance 0)
		)
		(min_thickness 0.25)
		(keepout
			(tracks not_allowed)
			(vias allowed)
			(pads allowed)
			(copperpour not_allowed)
			(footprints allowed)
		)
		(placement
			(enabled no)
			(sheetname "")
		)
		(fill yes
			(thermal_gap 0.5)
			(thermal_bridge_width 0.5)
			(island_removal_mode 0)
		)
		(polygon
			(pts
				(arc
					(start 162.776408 -273.099784)
					(mid 162.123628 -273.099784)
					(end 162.776408 -273.099784)
				)
			)
		)
	)
	(zone
		(layers "B.Cu" "In9.Cu" "In11.Cu" "In13.Cu" "In15.Cu")
		(hatch none 0.5)
		(connect_pads
			(clearance 0)
		)
		(min_thickness 0.25)
		(keepout
			(tracks not_allowed)
			(vias allowed)
			(pads allowed)
			(copperpour not_allowed)
			(footprints allowed)
		)
		(placement
			(enabled no)
			(sheetname "")
		)
		(fill yes
			(thermal_gap 0.5)
			(thermal_bridge_width 0.5)
			(island_removal_mode 0)
		)
		(polygon
			(pts
				(arc
					(start 406.376378 -273.099784)
					(mid 405.723598 -273.099784)
					(end 406.376378 -273.099784)
				)
			)
		)
	)
	(zone
		(layers "B.Cu" "In9.Cu" "In11.Cu" "In13.Cu" "In15.Cu")
		(hatch none 0.5)
		(connect_pads
			(clearance 0)
		)
		(min_thickness 0.25)
		(keepout
			(tracks not_allowed)
			(vias allowed)
			(pads allowed)
			(copperpour not_allowed)
			(footprints allowed)
		)
		(placement
			(enabled no)
			(sheetname "")
		)
		(fill yes
			(thermal_gap 0.5)
			(thermal_bridge_width 0.5)
			(island_removal_mode 0)
		)
		(polygon
			(pts
				(arc
					(start 19.684238 -351.611438)
					(mid 18.980658 -351.611438)
					(end 19.684238 -351.611438)
				)
			)
		)
	)
	(zone
		(layers "B.Cu" "In9.Cu" "In11.Cu" "In13.Cu" "In15.Cu")
		(hatch none 0.5)
		(connect_pads
			(clearance 0)
		)
		(min_thickness 0.25)
		(keepout
			(tracks not_allowed)
			(vias allowed)
			(pads allowed)
			(copperpour not_allowed)
			(footprints allowed)
		)
		(placement
			(enabled no)
			(sheetname "")
		)
		(fill yes
			(thermal_gap 0.5)
			(thermal_bridge_width 0.5)
			(island_removal_mode 0)
		)
		(polygon
			(pts
				(arc
					(start 163.401502 -348.58579)
					(mid 162.697922 -348.58579)
					(end 163.401502 -348.58579)
				)
			)
		)
	)
	(zone
		(layers "B.Cu" "In9.Cu" "In11.Cu" "In13.Cu" "In15.Cu")
		(hatch none 0.5)
		(connect_pads
			(clearance 0)
		)
		(min_thickness 0.25)
		(keepout
			(tracks not_allowed)
			(vias allowed)
			(pads allowed)
			(copperpour not_allowed)
			(footprints allowed)
		)
		(placement
			(enabled no)
			(sheetname "")
		)
		(fill yes
			(thermal_gap 0.5)
			(thermal_bridge_width 0.5)
			(island_removal_mode 0)
		)
		(polygon
			(pts
				(arc
					(start 172.728382 -345.465146)
					(mid 172.024802 -345.465146)
					(end 172.728382 -345.465146)
				)
			)
		)
	)
	(zone
		(layers "B.Cu" "In9.Cu" "In11.Cu" "In13.Cu" "In15.Cu")
		(hatch none 0.5)
		(connect_pads
			(clearance 0)
		)
		(min_thickness 0.25)
		(keepout
			(tracks not_allowed)
			(vias allowed)
			(pads allowed)
			(copperpour not_allowed)
			(footprints allowed)
		)
		(placement
			(enabled no)
			(sheetname "")
		)
		(fill yes
			(thermal_gap 0.5)
			(thermal_bridge_width 0.5)
			(island_removal_mode 0)
		)
		(polygon
			(pts
				(arc
					(start 430.869598 -372.890034)
					(mid 430.110138 -372.890034)
					(end 430.869598 -372.890034)
				)
			)
		)
	)
	(zone
		(layers "B.Cu" "In9.Cu" "In11.Cu" "In13.Cu" "In15.Cu")
		(hatch none 0.5)
		(connect_pads
			(clearance 0)
		)
		(min_thickness 0.25)
		(keepout
			(tracks not_allowed)
			(vias allowed)
			(pads allowed)
			(copperpour not_allowed)
			(footprints allowed)
		)
		(placement
			(enabled no)
			(sheetname "")
		)
		(fill yes
			(thermal_gap 0.5)
			(thermal_bridge_width 0.5)
			(island_removal_mode 0)
		)
		(polygon
			(pts
				(arc
					(start 424.269662 -397.790162)
					(mid 423.510202 -397.790162)
					(end 424.269662 -397.790162)
				)
			)
		)
	)
	(zone
		(layers "B.Cu" "In9.Cu" "In11.Cu" "In13.Cu" "In15.Cu")
		(hatch none 0.5)
		(connect_pads
			(clearance 0)
		)
		(min_thickness 0.25)
		(keepout
			(tracks not_allowed)
			(vias allowed)
			(pads allowed)
			(copperpour not_allowed)
			(footprints allowed)
		)
		(placement
			(enabled no)
			(sheetname "")
		)
		(fill yes
			(thermal_gap 0.5)
			(thermal_bridge_width 0.5)
			(island_removal_mode 0)
		)
		(polygon
			(pts
				(arc
					(start 71.050912 -342.439498)
					(mid 70.347332 -342.439498)
					(end 71.050912 -342.439498)
				)
			)
		)
	)
	(zone
		(layers "B.Cu" "In9.Cu" "In11.Cu" "In13.Cu" "In15.Cu")
		(hatch none 0.5)
		(connect_pads
			(clearance 0)
		)
		(min_thickness 0.25)
		(keepout
			(tracks not_allowed)
			(vias allowed)
			(pads allowed)
			(copperpour not_allowed)
			(footprints allowed)
		)
		(placement
			(enabled no)
			(sheetname "")
		)
		(fill yes
			(thermal_gap 0.5)
			(thermal_bridge_width 0.5)
			(island_removal_mode 0)
		)
		(polygon
			(pts
				(arc
					(start 143.303498 -348.58579)
					(mid 142.599918 -348.58579)
					(end 143.303498 -348.58579)
				)
			)
		)
	)
	(zone
		(layers "B.Cu" "In9.Cu" "In11.Cu" "In13.Cu" "In15.Cu")
		(hatch none 0.5)
		(connect_pads
			(clearance 0)
		)
		(min_thickness 0.25)
		(keepout
			(tracks not_allowed)
			(vias allowed)
			(pads allowed)
			(copperpour not_allowed)
			(footprints allowed)
		)
		(placement
			(enabled no)
			(sheetname "")
		)
		(fill yes
			(thermal_gap 0.5)
			(thermal_bridge_width 0.5)
			(island_removal_mode 0)
		)
		(polygon
			(pts
				(arc
					(start 72.28967 -378.290074)
					(mid 71.53021 -378.290074)
					(end 72.28967 -378.290074)
				)
			)
		)
	)
	(zone
		(layers "B.Cu" "In9.Cu" "In11.Cu" "In13.Cu" "In15.Cu")
		(hatch none 0.5)
		(connect_pads
			(clearance 0)
		)
		(min_thickness 0.25)
		(keepout
			(tracks not_allowed)
			(vias allowed)
			(pads allowed)
			(copperpour not_allowed)
			(footprints allowed)
		)
		(placement
			(enabled no)
			(sheetname "")
		)
		(fill yes
			(thermal_gap 0.5)
			(thermal_bridge_width 0.5)
			(island_removal_mode 0)
		)
		(polygon
			(pts
				(arc
					(start 265.762232 -30.058868)
					(mid 265.058652 -30.058868)
					(end 265.762232 -30.058868)
				)
			)
		)
	)
	(zone
		(layers "B.Cu" "In9.Cu" "In11.Cu" "In13.Cu" "In15.Cu")
		(hatch none 0.5)
		(connect_pads
			(clearance 0)
		)
		(min_thickness 0.25)
		(keepout
			(tracks not_allowed)
			(vias allowed)
			(pads allowed)
			(copperpour not_allowed)
			(footprints allowed)
		)
		(placement
			(enabled no)
			(sheetname "")
		)
		(fill yes
			(thermal_gap 0.5)
			(thermal_bridge_width 0.5)
			(island_removal_mode 0)
		)
		(polygon
			(pts
				(arc
					(start 430.869598 -371.590062)
					(mid 430.110138 -371.590062)
					(end 430.869598 -371.590062)
				)
			)
		)
	)
	(zone
		(layers "B.Cu" "In9.Cu" "In11.Cu" "In13.Cu" "In15.Cu")
		(hatch none 0.5)
		(connect_pads
			(clearance 0)
		)
		(min_thickness 0.25)
		(keepout
			(tracks not_allowed)
			(vias allowed)
			(pads allowed)
			(copperpour not_allowed)
			(footprints allowed)
		)
		(placement
			(enabled no)
			(sheetname "")
		)
		(fill yes
			(thermal_gap 0.5)
			(thermal_bridge_width 0.5)
			(island_removal_mode 0)
		)
		(polygon
			(pts
				(arc
					(start 275.076158 -312.999882)
					(mid 274.423378 -312.999882)
					(end 275.076158 -312.999882)
				)
			)
		)
	)
	(zone
		(layers "B.Cu" "In9.Cu" "In11.Cu" "In13.Cu" "In15.Cu")
		(hatch none 0.5)
		(connect_pads
			(clearance 0)
		)
		(min_thickness 0.25)
		(keepout
			(tracks not_allowed)
			(vias allowed)
			(pads allowed)
			(copperpour not_allowed)
			(footprints allowed)
		)
		(placement
			(enabled no)
			(sheetname "")
		)
		(fill yes
			(thermal_gap 0.5)
			(thermal_bridge_width 0.5)
			(island_removal_mode 0)
		)
		(polygon
			(pts
				(arc
					(start 375.51233 -354.732082)
					(mid 374.80875 -354.732082)
					(end 375.51233 -354.732082)
				)
			)
		)
	)
	(zone
		(layers "B.Cu" "In9.Cu" "In11.Cu" "In13.Cu" "In15.Cu")
		(hatch none 0.5)
		(connect_pads
			(clearance 0)
		)
		(min_thickness 0.25)
		(keepout
			(tracks not_allowed)
			(vias allowed)
			(pads allowed)
			(copperpour not_allowed)
			(footprints allowed)
		)
		(placement
			(enabled no)
			(sheetname "")
		)
		(fill yes
			(thermal_gap 0.5)
			(thermal_bridge_width 0.5)
			(island_removal_mode 0)
		)
		(polygon
			(pts
				(arc
					(start 293.61638 -31.858712)
					(mid 292.9128 -31.858712)
					(end 293.61638 -31.858712)
				)
			)
		)
	)
	(zone
		(layers "B.Cu" "In9.Cu" "In11.Cu" "In13.Cu" "In15.Cu")
		(hatch none 0.5)
		(connect_pads
			(clearance 0)
		)
		(min_thickness 0.25)
		(keepout
			(tracks not_allowed)
			(vias allowed)
			(pads allowed)
			(copperpour not_allowed)
			(footprints allowed)
		)
		(placement
			(enabled no)
			(sheetname "")
		)
		(fill yes
			(thermal_gap 0.5)
			(thermal_bridge_width 0.5)
			(island_removal_mode 0)
		)
		(polygon
			(pts
				(arc
					(start 313.718194 -351.611438)
					(mid 313.014614 -351.611438)
					(end 313.718194 -351.611438)
				)
			)
		)
	)
	(zone
		(layers "B.Cu" "In9.Cu" "In11.Cu" "In13.Cu" "In15.Cu")
		(hatch none 0.5)
		(connect_pads
			(clearance 0)
		)
		(min_thickness 0.25)
		(keepout
			(tracks not_allowed)
			(vias allowed)
			(pads allowed)
			(copperpour not_allowed)
			(footprints allowed)
		)
		(placement
			(enabled no)
			(sheetname "")
		)
		(fill yes
			(thermal_gap 0.5)
			(thermal_bridge_width 0.5)
			(island_removal_mode 0)
		)
		(polygon
			(pts
				(arc
					(start 28.289758 -375.69013)
					(mid 27.530298 -375.69013)
					(end 28.289758 -375.69013)
				)
			)
		)
	)
	(zone
		(layers "B.Cu" "In9.Cu" "In11.Cu" "In13.Cu" "In15.Cu")
		(hatch none 0.5)
		(connect_pads
			(clearance 0)
		)
		(min_thickness 0.25)
		(keepout
			(tracks not_allowed)
			(vias allowed)
			(pads allowed)
			(copperpour not_allowed)
			(footprints allowed)
		)
		(placement
			(enabled no)
			(sheetname "")
		)
		(fill yes
			(thermal_gap 0.5)
			(thermal_bridge_width 0.5)
			(island_removal_mode 0)
		)
		(polygon
			(pts
				(arc
					(start 190.326264 -311.099962)
					(mid 189.673484 -311.099962)
					(end 190.326264 -311.099962)
				)
			)
		)
	)
	(zone
		(layers "B.Cu" "In9.Cu" "In11.Cu" "In13.Cu" "In15.Cu")
		(hatch none 0.5)
		(connect_pads
			(clearance 0)
		)
		(min_thickness 0.25)
		(keepout
			(tracks not_allowed)
			(vias allowed)
			(pads allowed)
			(copperpour not_allowed)
			(footprints allowed)
		)
		(placement
			(enabled no)
			(sheetname "")
		)
		(fill yes
			(thermal_gap 0.5)
			(thermal_bridge_width 0.5)
			(island_removal_mode 0)
		)
		(polygon
			(pts
				(arc
					(start 424.269662 -396.49019)
					(mid 423.510202 -396.49019)
					(end 424.269662 -396.49019)
				)
			)
		)
	)
	(zone
		(layers "B.Cu" "In9.Cu" "In11.Cu" "In13.Cu" "In15.Cu")
		(hatch none 0.5)
		(connect_pads
			(clearance 0)
		)
		(min_thickness 0.25)
		(keepout
			(tracks not_allowed)
			(vias allowed)
			(pads allowed)
			(copperpour not_allowed)
			(footprints allowed)
		)
		(placement
			(enabled no)
			(sheetname "")
		)
		(fill yes
			(thermal_gap 0.5)
			(thermal_bridge_width 0.5)
			(island_removal_mode 0)
		)
		(polygon
			(pts
				(arc
					(start 405.426418 -274.999958)
					(mid 404.773638 -274.999958)
					(end 405.426418 -274.999958)
				)
			)
		)
	)
	(zone
		(layers "B.Cu" "In9.Cu" "In11.Cu" "In13.Cu" "In15.Cu")
		(hatch none 0.5)
		(connect_pads
			(clearance 0)
		)
		(min_thickness 0.25)
		(keepout
			(tracks not_allowed)
			(vias allowed)
			(pads allowed)
			(copperpour not_allowed)
			(footprints allowed)
		)
		(placement
			(enabled no)
			(sheetname "")
		)
		(fill yes
			(thermal_gap 0.5)
			(thermal_bridge_width 0.5)
			(island_removal_mode 0)
		)
		(polygon
			(pts
				(arc
					(start 407.326338 -312.049922)
					(mid 406.673558 -312.049922)
					(end 407.326338 -312.049922)
				)
			)
		)
	)
	(zone
		(layers "B.Cu" "In9.Cu" "In11.Cu" "In13.Cu" "In15.Cu")
		(hatch none 0.5)
		(connect_pads
			(clearance 0)
		)
		(min_thickness 0.25)
		(keepout
			(tracks not_allowed)
			(vias allowed)
			(pads allowed)
			(copperpour not_allowed)
			(footprints allowed)
		)
		(placement
			(enabled no)
			(sheetname "")
		)
		(fill yes
			(thermal_gap 0.5)
			(thermal_bridge_width 0.5)
			(island_removal_mode 0)
		)
		(polygon
			(pts
				(arc
					(start 425.191682 -345.465146)
					(mid 424.488102 -345.465146)
					(end 425.191682 -345.465146)
				)
			)
		)
	)
	(zone
		(layers "B.Cu" "In9.Cu" "In11.Cu" "In13.Cu" "In15.Cu")
		(hatch none 0.5)
		(connect_pads
			(clearance 0)
		)
		(min_thickness 0.25)
		(keepout
			(tracks not_allowed)
			(vias allowed)
			(pads allowed)
			(copperpour not_allowed)
			(footprints allowed)
		)
		(placement
			(enabled no)
			(sheetname "")
		)
		(fill yes
			(thermal_gap 0.5)
			(thermal_bridge_width 0.5)
			(island_removal_mode 0)
		)
		(polygon
			(pts
				(arc
					(start 300.202092 -351.611438)
					(mid 299.498512 -351.611438)
					(end 300.202092 -351.611438)
				)
			)
		)
	)
	(zone
		(layers "B.Cu" "In9.Cu" "In11.Cu" "In13.Cu" "In15.Cu")
		(hatch none 0.5)
		(connect_pads
			(clearance 0)
		)
		(min_thickness 0.25)
		(keepout
			(tracks not_allowed)
			(vias allowed)
			(pads allowed)
			(copperpour not_allowed)
			(footprints allowed)
		)
		(placement
			(enabled no)
			(sheetname "")
		)
		(fill yes
			(thermal_gap 0.5)
			(thermal_bridge_width 0.5)
			(island_removal_mode 0)
		)
		(polygon
			(pts
				(arc
					(start 341.698834 -345.465146)
					(mid 340.995254 -345.465146)
					(end 341.698834 -345.465146)
				)
			)
		)
	)
	(zone
		(layers "B.Cu" "In9.Cu" "In11.Cu" "In13.Cu" "In15.Cu")
		(hatch none 0.5)
		(connect_pads
			(clearance 0)
		)
		(min_thickness 0.25)
		(keepout
			(tracks not_allowed)
			(vias allowed)
			(pads allowed)
			(copperpour not_allowed)
			(footprints allowed)
		)
		(placement
			(enabled no)
			(sheetname "")
		)
		(fill yes
			(thermal_gap 0.5)
			(thermal_bridge_width 0.5)
			(island_removal_mode 0)
		)
		(polygon
			(pts
				(arc
					(start 316.827154 -357.75773)
					(mid 316.123574 -357.75773)
					(end 316.827154 -357.75773)
				)
			)
		)
	)
	(zone
		(layers "B.Cu" "In9.Cu" "In11.Cu" "In13.Cu" "In15.Cu")
		(hatch none 0.5)
		(connect_pads
			(clearance 0)
		)
		(min_thickness 0.25)
		(keepout
			(tracks not_allowed)
			(vias allowed)
			(pads allowed)
			(copperpour not_allowed)
			(footprints allowed)
		)
		(placement
			(enabled no)
			(sheetname "")
		)
		(fill yes
			(thermal_gap 0.5)
			(thermal_bridge_width 0.5)
			(island_removal_mode 0)
		)
		(polygon
			(pts
				(arc
					(start 432.273202 -354.732082)
					(mid 431.569622 -354.732082)
					(end 432.273202 -354.732082)
				)
			)
		)
	)
	(zone
		(layers "B.Cu" "In9.Cu" "In11.Cu" "In13.Cu" "In15.Cu")
		(hatch none 0.5)
		(connect_pads
			(clearance 0)
		)
		(min_thickness 0.25)
		(keepout
			(tracks not_allowed)
			(vias allowed)
			(pads allowed)
			(copperpour not_allowed)
			(footprints allowed)
		)
		(placement
			(enabled no)
			(sheetname "")
		)
		(fill yes
			(thermal_gap 0.5)
			(thermal_bridge_width 0.5)
			(island_removal_mode 0)
		)
		(polygon
			(pts
				(arc
					(start 41.926256 -301.599854)
					(mid 41.273476 -301.599854)
					(end 41.926256 -301.599854)
				)
			)
		)
	)
	(zone
		(layers "B.Cu" "In9.Cu" "In11.Cu" "In13.Cu" "In15.Cu")
		(hatch none 0.5)
		(connect_pads
			(clearance 0)
		)
		(min_thickness 0.25)
		(keepout
			(tracks not_allowed)
			(vias allowed)
			(pads allowed)
			(copperpour not_allowed)
			(footprints allowed)
		)
		(placement
			(enabled no)
			(sheetname "")
		)
		(fill yes
			(thermal_gap 0.5)
			(thermal_bridge_width 0.5)
			(island_removal_mode 0)
		)
		(polygon
			(pts
				(arc
					(start 381.86233 -33.65881)
					(mid 381.15875 -33.65881)
					(end 381.86233 -33.65881)
				)
			)
		)
	)
	(zone
		(layers "B.Cu" "In9.Cu" "In11.Cu" "In13.Cu" "In15.Cu")
		(hatch none 0.5)
		(connect_pads
			(clearance 0)
		)
		(min_thickness 0.25)
		(keepout
			(tracks not_allowed)
			(vias allowed)
			(pads allowed)
			(copperpour not_allowed)
			(footprints allowed)
		)
		(placement
			(enabled no)
			(sheetname "")
		)
		(fill yes
			(thermal_gap 0.5)
			(thermal_bridge_width 0.5)
			(island_removal_mode 0)
		)
		(polygon
			(pts
				(arc
					(start 193.176398 -309.199788)
					(mid 192.523618 -309.199788)
					(end 193.176398 -309.199788)
				)
			)
		)
	)
	(zone
		(layers "B.Cu" "In9.Cu" "In11.Cu" "In13.Cu" "In15.Cu")
		(hatch none 0.5)
		(connect_pads
			(clearance 0)
		)
		(min_thickness 0.25)
		(keepout
			(tracks not_allowed)
			(vias allowed)
			(pads allowed)
			(copperpour not_allowed)
			(footprints allowed)
		)
		(placement
			(enabled no)
			(sheetname "")
		)
		(fill yes
			(thermal_gap 0.5)
			(thermal_bridge_width 0.5)
			(island_removal_mode 0)
		)
		(polygon
			(pts
				(arc
					(start 282.676092 -273.099784)
					(mid 282.023312 -273.099784)
					(end 282.676092 -273.099784)
				)
			)
		)
	)
	(zone
		(layers "B.Cu" "In9.Cu" "In11.Cu" "In13.Cu" "In15.Cu")
		(hatch none 0.5)
		(connect_pads
			(clearance 0)
		)
		(min_thickness 0.25)
		(keepout
			(tracks not_allowed)
			(vias allowed)
			(pads allowed)
			(copperpour not_allowed)
			(footprints allowed)
		)
		(placement
			(enabled no)
			(sheetname "")
		)
		(fill yes
			(thermal_gap 0.5)
			(thermal_bridge_width 0.5)
			(island_removal_mode 0)
		)
		(polygon
			(pts
				(arc
					(start 122.404378 -357.75773)
					(mid 121.700798 -357.75773)
					(end 122.404378 -357.75773)
				)
			)
		)
	)
	(zone
		(layers "B.Cu" "In9.Cu" "In11.Cu" "In13.Cu" "In15.Cu")
		(hatch none 0.5)
		(connect_pads
			(clearance 0)
		)
		(min_thickness 0.25)
		(keepout
			(tracks not_allowed)
			(vias allowed)
			(pads allowed)
			(copperpour not_allowed)
			(footprints allowed)
		)
		(placement
			(enabled no)
			(sheetname "")
		)
		(fill yes
			(thermal_gap 0.5)
			(thermal_bridge_width 0.5)
			(island_removal_mode 0)
		)
		(polygon
			(pts
				(arc
					(start 334.06969 -379.390148)
					(mid 333.31023 -379.390148)
					(end 334.06969 -379.390148)
				)
			)
		)
	)
	(zone
		(layers "B.Cu" "In9.Cu" "In11.Cu" "In13.Cu" "In15.Cu")
		(hatch none 0.5)
		(connect_pads
			(clearance 0)
		)
		(min_thickness 0.25)
		(keepout
			(tracks not_allowed)
			(vias allowed)
			(pads allowed)
			(copperpour not_allowed)
			(footprints allowed)
		)
		(placement
			(enabled no)
			(sheetname "")
		)
		(fill yes
			(thermal_gap 0.5)
			(thermal_bridge_width 0.5)
			(island_removal_mode 0)
		)
		(polygon
			(pts
				(arc
					(start 47.664878 -357.75773)
					(mid 46.961298 -357.75773)
					(end 47.664878 -357.75773)
				)
			)
		)
	)
	(zone
		(layers "B.Cu" "In9.Cu" "In11.Cu" "In13.Cu" "In15.Cu")
		(hatch none 0.5)
		(connect_pads
			(clearance 0)
		)
		(min_thickness 0.25)
		(keepout
			(tracks not_allowed)
			(vias allowed)
			(pads allowed)
			(copperpour not_allowed)
			(footprints allowed)
		)
		(placement
			(enabled no)
			(sheetname "")
		)
		(fill yes
			(thermal_gap 0.5)
			(thermal_bridge_width 0.5)
			(island_removal_mode 0)
		)
		(polygon
			(pts
				(arc
					(start 276.976078 -304.449734)
					(mid 276.323298 -304.449734)
					(end 276.976078 -304.449734)
				)
			)
		)
	)
	(zone
		(layers "B.Cu" "In9.Cu" "In11.Cu" "In13.Cu" "In15.Cu")
		(hatch none 0.5)
		(connect_pads
			(clearance 0)
		)
		(min_thickness 0.25)
		(keepout
			(tracks not_allowed)
			(vias allowed)
			(pads allowed)
			(copperpour not_allowed)
			(footprints allowed)
		)
		(placement
			(enabled no)
			(sheetname "")
		)
		(fill yes
			(thermal_gap 0.5)
			(thermal_bridge_width 0.5)
			(island_removal_mode 0)
		)
		(polygon
			(pts
				(arc
					(start 123.66244 -34.52241)
					(mid 122.95886 -34.52241)
					(end 123.66244 -34.52241)
				)
			)
		)
	)
	(zone
		(layers "B.Cu" "In9.Cu" "In11.Cu" "In13.Cu" "In15.Cu")
		(hatch none 0.5)
		(connect_pads
			(clearance 0)
		)
		(min_thickness 0.25)
		(keepout
			(tracks not_allowed)
			(vias allowed)
			(pads allowed)
			(copperpour not_allowed)
			(footprints allowed)
		)
		(placement
			(enabled no)
			(sheetname "")
		)
		(fill yes
			(thermal_gap 0.5)
			(thermal_bridge_width 0.5)
			(island_removal_mode 0)
		)
		(polygon
			(pts
				(arc
					(start 286.476186 -274.049744)
					(mid 285.823406 -274.049744)
					(end 286.476186 -274.049744)
				)
			)
		)
	)
	(zone
		(layers "B.Cu" "In9.Cu" "In11.Cu" "In13.Cu" "In15.Cu")
		(hatch none 0.5)
		(connect_pads
			(clearance 0)
		)
		(min_thickness 0.25)
		(keepout
			(tracks not_allowed)
			(vias allowed)
			(pads allowed)
			(copperpour not_allowed)
			(footprints allowed)
		)
		(placement
			(enabled no)
			(sheetname "")
		)
		(fill yes
			(thermal_gap 0.5)
			(thermal_bridge_width 0.5)
			(island_removal_mode 0)
		)
		(polygon
			(pts
				(arc
					(start 290.069524 -375.490232)
					(mid 289.310064 -375.490232)
					(end 290.069524 -375.490232)
				)
			)
		)
	)
	(zone
		(layers "B.Cu" "In9.Cu" "In11.Cu" "In13.Cu" "In15.Cu")
		(hatch none 0.5)
		(connect_pads
			(clearance 0)
		)
		(min_thickness 0.25)
		(keepout
			(tracks not_allowed)
			(vias allowed)
			(pads allowed)
			(copperpour not_allowed)
			(footprints allowed)
		)
		(placement
			(enabled no)
			(sheetname "")
		)
		(fill yes
			(thermal_gap 0.5)
			(thermal_bridge_width 0.5)
			(island_removal_mode 0)
		)
		(polygon
			(pts
				(arc
					(start 419.837362 -342.439498)
					(mid 419.133782 -342.439498)
					(end 419.837362 -342.439498)
				)
			)
		)
	)
	(zone
		(layers "B.Cu" "In9.Cu" "In11.Cu" "In13.Cu" "In15.Cu")
		(hatch none 0.5)
		(connect_pads
			(clearance 0)
		)
		(min_thickness 0.25)
		(keepout
			(tracks not_allowed)
			(vias allowed)
			(pads allowed)
			(copperpour not_allowed)
			(footprints allowed)
		)
		(placement
			(enabled no)
			(sheetname "")
		)
		(fill yes
			(thermal_gap 0.5)
			(thermal_bridge_width 0.5)
			(island_removal_mode 0)
		)
		(polygon
			(pts
				(arc
					(start 396.87627 -273.099784)
					(mid 396.22349 -273.099784)
					(end 396.87627 -273.099784)
				)
			)
		)
	)
	(zone
		(layers "B.Cu" "In9.Cu" "In11.Cu" "In13.Cu" "In15.Cu")
		(hatch none 0.5)
		(connect_pads
			(clearance 0)
		)
		(min_thickness 0.25)
		(keepout
			(tracks not_allowed)
			(vias allowed)
			(pads allowed)
			(copperpour not_allowed)
			(footprints allowed)
		)
		(placement
			(enabled no)
			(sheetname "")
		)
		(fill yes
			(thermal_gap 0.5)
			(thermal_bridge_width 0.5)
			(island_removal_mode 0)
		)
		(polygon
			(pts
				(arc
					(start 331.869796 -404.290022)
					(mid 331.110336 -404.290022)
					(end 331.869796 -404.290022)
				)
			)
		)
	)
	(zone
		(layers "B.Cu" "In9.Cu" "In11.Cu" "In13.Cu" "In15.Cu")
		(hatch none 0.5)
		(connect_pads
			(clearance 0)
		)
		(min_thickness 0.25)
		(keepout
			(tracks not_allowed)
			(vias allowed)
			(pads allowed)
			(copperpour not_allowed)
			(footprints allowed)
		)
		(placement
			(enabled no)
			(sheetname "")
		)
		(fill yes
			(thermal_gap 0.5)
			(thermal_bridge_width 0.5)
			(island_removal_mode 0)
		)
		(polygon
			(pts
				(arc
					(start 298.869608 -401.49018)
					(mid 298.110148 -401.49018)
					(end 298.869608 -401.49018)
				)
			)
		)
	)
	(zone
		(layers "B.Cu" "In9.Cu" "In11.Cu" "In13.Cu" "In15.Cu")
		(hatch none 0.5)
		(connect_pads
			(clearance 0)
		)
		(min_thickness 0.25)
		(keepout
			(tracks not_allowed)
			(vias allowed)
			(pads allowed)
			(copperpour not_allowed)
			(footprints allowed)
		)
		(placement
			(enabled no)
			(sheetname "")
		)
		(fill yes
			(thermal_gap 0.5)
			(thermal_bridge_width 0.5)
			(island_removal_mode 0)
		)
		(polygon
			(pts
				(arc
					(start 137.085578 -348.58579)
					(mid 136.381998 -348.58579)
					(end 137.085578 -348.58579)
				)
			)
		)
	)
	(zone
		(layers "B.Cu" "In9.Cu" "In11.Cu" "In13.Cu" "In15.Cu")
		(hatch none 0.5)
		(connect_pads
			(clearance 0)
		)
		(min_thickness 0.25)
		(keepout
			(tracks not_allowed)
			(vias allowed)
			(pads allowed)
			(copperpour not_allowed)
			(footprints allowed)
		)
		(placement
			(enabled no)
			(sheetname "")
		)
		(fill yes
			(thermal_gap 0.5)
			(thermal_bridge_width 0.5)
			(island_removal_mode 0)
		)
		(polygon
			(pts
				(arc
					(start 294.469566 -402.790152)
					(mid 293.710106 -402.790152)
					(end 294.469566 -402.790152)
				)
			)
		)
	)
	(zone
		(layers "B.Cu" "In9.Cu" "In11.Cu" "In13.Cu" "In15.Cu")
		(hatch none 0.5)
		(connect_pads
			(clearance 0)
		)
		(min_thickness 0.25)
		(keepout
			(tracks not_allowed)
			(vias allowed)
			(pads allowed)
			(copperpour not_allowed)
			(footprints allowed)
		)
		(placement
			(enabled no)
			(sheetname "")
		)
		(fill yes
			(thermal_gap 0.5)
			(thermal_bridge_width 0.5)
			(island_removal_mode 0)
		)
		(polygon
			(pts
				(arc
					(start 435.716426 -29.12237)
					(mid 435.012846 -29.12237)
					(end 435.716426 -29.12237)
				)
			)
		)
	)
	(zone
		(layers "B.Cu" "In9.Cu" "In11.Cu" "In13.Cu" "In15.Cu")
		(hatch none 0.5)
		(connect_pads
			(clearance 0)
		)
		(min_thickness 0.25)
		(keepout
			(tracks not_allowed)
			(vias allowed)
			(pads allowed)
			(copperpour not_allowed)
			(footprints allowed)
		)
		(placement
			(enabled no)
			(sheetname "")
		)
		(fill yes
			(thermal_gap 0.5)
			(thermal_bridge_width 0.5)
			(island_removal_mode 0)
		)
		(polygon
			(pts
				(arc
					(start 405.426418 -275.949918)
					(mid 404.773638 -275.949918)
					(end 405.426418 -275.949918)
				)
			)
		)
	)
	(zone
		(layers "B.Cu" "In9.Cu" "In11.Cu" "In13.Cu" "In15.Cu")
		(hatch none 0.5)
		(connect_pads
			(clearance 0)
		)
		(min_thickness 0.25)
		(keepout
			(tracks not_allowed)
			(vias allowed)
			(pads allowed)
			(copperpour not_allowed)
			(footprints allowed)
		)
		(placement
			(enabled no)
			(sheetname "")
		)
		(fill yes
			(thermal_gap 0.5)
			(thermal_bridge_width 0.5)
			(island_removal_mode 0)
		)
		(polygon
			(pts
				(arc
					(start 302.626268 -312.049922)
					(mid 301.973488 -312.049922)
					(end 302.626268 -312.049922)
				)
			)
		)
	)
	(zone
		(layers "B.Cu" "In9.Cu" "In11.Cu" "In13.Cu" "In15.Cu")
		(hatch none 0.5)
		(connect_pads
			(clearance 0)
		)
		(min_thickness 0.25)
		(keepout
			(tracks not_allowed)
			(vias allowed)
			(pads allowed)
			(copperpour not_allowed)
			(footprints allowed)
		)
		(placement
			(enabled no)
			(sheetname "")
		)
		(fill yes
			(thermal_gap 0.5)
			(thermal_bridge_width 0.5)
			(island_removal_mode 0)
		)
		(polygon
			(pts
				(arc
					(start 422.946322 -348.58579)
					(mid 422.242742 -348.58579)
					(end 422.946322 -348.58579)
				)
			)
		)
	)
	(zone
		(layers "B.Cu" "In9.Cu" "In11.Cu" "In13.Cu" "In15.Cu")
		(hatch none 0.5)
		(connect_pads
			(clearance 0)
		)
		(min_thickness 0.25)
		(keepout
			(tracks not_allowed)
			(vias allowed)
			(pads allowed)
			(copperpour not_allowed)
			(footprints allowed)
		)
		(placement
			(enabled no)
			(sheetname "")
		)
		(fill yes
			(thermal_gap 0.5)
			(thermal_bridge_width 0.5)
			(island_removal_mode 0)
		)
		(polygon
			(pts
				(arc
					(start 83.289648 -380.69012)
					(mid 82.530188 -380.69012)
					(end 83.289648 -380.69012)
				)
			)
		)
	)
	(zone
		(layers "B.Cu" "In9.Cu" "In11.Cu" "In13.Cu" "In15.Cu")
		(hatch none 0.5)
		(connect_pads
			(clearance 0)
		)
		(min_thickness 0.25)
		(keepout
			(tracks not_allowed)
			(vias allowed)
			(pads allowed)
			(copperpour not_allowed)
			(footprints allowed)
		)
		(placement
			(enabled no)
			(sheetname "")
		)
		(fill yes
			(thermal_gap 0.5)
			(thermal_bridge_width 0.5)
			(island_removal_mode 0)
		)
		(polygon
			(pts
				(arc
					(start 355.862382 -34.52241)
					(mid 355.158802 -34.52241)
					(end 355.862382 -34.52241)
				)
			)
		)
	)
	(zone
		(layers "B.Cu" "In9.Cu" "In11.Cu" "In13.Cu" "In15.Cu")
		(hatch none 0.5)
		(connect_pads
			(clearance 0)
		)
		(min_thickness 0.25)
		(keepout
			(tracks not_allowed)
			(vias allowed)
			(pads allowed)
			(copperpour not_allowed)
			(footprints allowed)
		)
		(placement
			(enabled no)
			(sheetname "")
		)
		(fill yes
			(thermal_gap 0.5)
			(thermal_bridge_width 0.5)
			(island_removal_mode 0)
		)
		(polygon
			(pts
				(arc
					(start 295.976294 -312.999882)
					(mid 295.323514 -312.999882)
					(end 295.976294 -312.999882)
				)
			)
		)
	)
	(zone
		(layers "B.Cu" "In9.Cu" "In11.Cu" "In13.Cu" "In15.Cu")
		(hatch none 0.5)
		(connect_pads
			(clearance 0)
		)
		(min_thickness 0.25)
		(keepout
			(tracks not_allowed)
			(vias allowed)
			(pads allowed)
			(copperpour not_allowed)
			(footprints allowed)
		)
		(placement
			(enabled no)
			(sheetname "")
		)
		(fill yes
			(thermal_gap 0.5)
			(thermal_bridge_width 0.5)
			(island_removal_mode 0)
		)
		(polygon
			(pts
				(arc
					(start 290.011612 -354.732082)
					(mid 289.308032 -354.732082)
					(end 290.011612 -354.732082)
				)
			)
		)
	)
	(zone
		(layers "B.Cu" "In9.Cu" "In11.Cu" "In13.Cu" "In15.Cu")
		(hatch none 0.5)
		(connect_pads
			(clearance 0)
		)
		(min_thickness 0.25)
		(keepout
			(tracks not_allowed)
			(vias allowed)
			(pads allowed)
			(copperpour not_allowed)
			(footprints allowed)
		)
		(placement
			(enabled no)
			(sheetname "")
		)
		(fill yes
			(thermal_gap 0.5)
			(thermal_bridge_width 0.5)
			(island_removal_mode 0)
		)
		(polygon
			(pts
				(arc
					(start 166.889684 -371.590062)
					(mid 166.130224 -371.590062)
					(end 166.889684 -371.590062)
				)
			)
		)
	)
	(zone
		(layers "B.Cu" "In9.Cu" "In11.Cu" "In13.Cu" "In15.Cu")
		(hatch none 0.5)
		(connect_pads
			(clearance 0)
		)
		(min_thickness 0.25)
		(keepout
			(tracks not_allowed)
			(vias allowed)
			(pads allowed)
			(copperpour not_allowed)
			(footprints allowed)
		)
		(placement
			(enabled no)
			(sheetname "")
		)
		(fill yes
			(thermal_gap 0.5)
			(thermal_bridge_width 0.5)
			(island_removal_mode 0)
		)
		(polygon
			(pts
				(arc
					(start 290.875212 -357.75773)
					(mid 290.171632 -357.75773)
					(end 290.875212 -357.75773)
				)
			)
		)
	)
	(zone
		(layers "B.Cu" "In9.Cu" "In11.Cu" "In13.Cu" "In15.Cu")
		(hatch none 0.5)
		(connect_pads
			(clearance 0)
		)
		(min_thickness 0.25)
		(keepout
			(tracks not_allowed)
			(vias allowed)
			(pads allowed)
			(copperpour not_allowed)
			(footprints allowed)
		)
		(placement
			(enabled no)
			(sheetname "")
		)
		(fill yes
			(thermal_gap 0.5)
			(thermal_bridge_width 0.5)
			(island_removal_mode 0)
		)
		(polygon
			(pts
				(arc
					(start 42.876216 -305.399948)
					(mid 42.223436 -305.399948)
					(end 42.876216 -305.399948)
				)
			)
		)
	)
	(zone
		(layers "B.Cu" "In9.Cu" "In11.Cu" "In13.Cu" "In15.Cu")
		(hatch none 0.5)
		(connect_pads
			(clearance 0)
		)
		(min_thickness 0.25)
		(keepout
			(tracks not_allowed)
			(vias allowed)
			(pads allowed)
			(copperpour not_allowed)
			(footprints allowed)
		)
		(placement
			(enabled no)
			(sheetname "")
		)
		(fill yes
			(thermal_gap 0.5)
			(thermal_bridge_width 0.5)
			(island_removal_mode 0)
		)
		(polygon
			(pts
				(arc
					(start 382.469644 -383.290064)
					(mid 381.710184 -383.290064)
					(end 382.469644 -383.290064)
				)
			)
		)
	)
	(zone
		(layers "B.Cu" "In9.Cu" "In11.Cu" "In13.Cu" "In15.Cu")
		(hatch none 0.5)
		(connect_pads
			(clearance 0)
		)
		(min_thickness 0.25)
		(keepout
			(tracks not_allowed)
			(vias allowed)
			(pads allowed)
			(copperpour not_allowed)
			(footprints allowed)
		)
		(placement
			(enabled no)
			(sheetname "")
		)
		(fill yes
			(thermal_gap 0.5)
			(thermal_bridge_width 0.5)
			(island_removal_mode 0)
		)
		(polygon
			(pts
				(arc
					(start 412.755842 -354.732082)
					(mid 412.052262 -354.732082)
					(end 412.755842 -354.732082)
				)
			)
		)
	)
	(zone
		(layers "B.Cu" "In9.Cu" "In11.Cu" "In13.Cu" "In15.Cu")
		(hatch none 0.5)
		(connect_pads
			(clearance 0)
		)
		(min_thickness 0.25)
		(keepout
			(tracks not_allowed)
			(vias allowed)
			(pads allowed)
			(copperpour not_allowed)
			(footprints allowed)
		)
		(placement
			(enabled no)
			(sheetname "")
		)
		(fill yes
			(thermal_gap 0.5)
			(thermal_bridge_width 0.5)
			(island_removal_mode 0)
		)
		(polygon
			(pts
				(arc
					(start 118.48973 -405.390096)
					(mid 117.73027 -405.390096)
					(end 118.48973 -405.390096)
				)
			)
		)
	)
	(zone
		(layers "B.Cu" "In9.Cu" "In11.Cu" "In13.Cu" "In15.Cu")
		(hatch none 0.5)
		(connect_pads
			(clearance 0)
		)
		(min_thickness 0.25)
		(keepout
			(tracks not_allowed)
			(vias allowed)
			(pads allowed)
			(copperpour not_allowed)
			(footprints allowed)
		)
		(placement
			(enabled no)
			(sheetname "")
		)
		(fill yes
			(thermal_gap 0.5)
			(thermal_bridge_width 0.5)
			(island_removal_mode 0)
		)
		(polygon
			(pts
				(arc
					(start 78.132432 -342.439498)
					(mid 77.428852 -342.439498)
					(end 78.132432 -342.439498)
				)
			)
		)
	)
	(zone
		(layers "B.Cu" "In9.Cu" "In11.Cu" "In13.Cu" "In15.Cu")
		(hatch none 0.5)
		(connect_pads
			(clearance 0)
		)
		(min_thickness 0.25)
		(keepout
			(tracks not_allowed)
			(vias allowed)
			(pads allowed)
			(copperpour not_allowed)
			(footprints allowed)
		)
		(placement
			(enabled no)
			(sheetname "")
		)
		(fill yes
			(thermal_gap 0.5)
			(thermal_bridge_width 0.5)
			(island_removal_mode 0)
		)
		(polygon
			(pts
				(arc
					(start 173.226476 -274.999958)
					(mid 172.573696 -274.999958)
					(end 173.226476 -274.999958)
				)
			)
		)
	)
	(zone
		(layers "B.Cu" "In9.Cu" "In11.Cu" "In13.Cu" "In15.Cu")
		(hatch none 0.5)
		(connect_pads
			(clearance 0)
		)
		(min_thickness 0.25)
		(keepout
			(tracks not_allowed)
			(vias allowed)
			(pads allowed)
			(copperpour not_allowed)
			(footprints allowed)
		)
		(placement
			(enabled no)
			(sheetname "")
		)
		(fill yes
			(thermal_gap 0.5)
			(thermal_bridge_width 0.5)
			(island_removal_mode 0)
		)
		(polygon
			(pts
				(arc
					(start 413.619442 -342.439498)
					(mid 412.915862 -342.439498)
					(end 413.619442 -342.439498)
				)
			)
		)
	)
	(zone
		(layers "B.Cu" "In9.Cu" "In11.Cu" "In13.Cu" "In15.Cu")
		(hatch none 0.5)
		(connect_pads
			(clearance 0)
		)
		(min_thickness 0.25)
		(keepout
			(tracks not_allowed)
			(vias allowed)
			(pads allowed)
			(copperpour not_allowed)
			(footprints allowed)
		)
		(placement
			(enabled no)
			(sheetname "")
		)
		(fill yes
			(thermal_gap 0.5)
			(thermal_bridge_width 0.5)
			(island_removal_mode 0)
		)
		(polygon
			(pts
				(arc
					(start 38.126162 -312.049922)
					(mid 37.473382 -312.049922)
					(end 38.126162 -312.049922)
				)
			)
		)
	)
	(zone
		(layers "B.Cu" "In9.Cu" "In11.Cu" "In13.Cu" "In15.Cu")
		(hatch none 0.5)
		(connect_pads
			(clearance 0)
		)
		(min_thickness 0.25)
		(keepout
			(tracks not_allowed)
			(vias allowed)
			(pads allowed)
			(copperpour not_allowed)
			(footprints allowed)
		)
		(placement
			(enabled no)
			(sheetname "")
		)
		(fill yes
			(thermal_gap 0.5)
			(thermal_bridge_width 0.5)
			(island_removal_mode 0)
		)
		(polygon
			(pts
				(arc
					(start 83.486752 -342.439498)
					(mid 82.783172 -342.439498)
					(end 83.486752 -342.439498)
				)
			)
		)
	)
	(zone
		(layers "B.Cu" "In9.Cu" "In11.Cu" "In13.Cu" "In15.Cu")
		(hatch none 0.5)
		(connect_pads
			(clearance 0)
		)
		(min_thickness 0.25)
		(keepout
			(tracks not_allowed)
			(vias allowed)
			(pads allowed)
			(copperpour not_allowed)
			(footprints allowed)
		)
		(placement
			(enabled no)
			(sheetname "")
		)
		(fill yes
			(thermal_gap 0.5)
			(thermal_bridge_width 0.5)
			(island_removal_mode 0)
		)
		(polygon
			(pts
				(arc
					(start 192.226438 -308.249828)
					(mid 191.573658 -308.249828)
					(end 192.226438 -308.249828)
				)
			)
		)
	)
	(zone
		(layers "B.Cu" "In9.Cu" "In11.Cu" "In13.Cu" "In15.Cu")
		(hatch none 0.5)
		(connect_pads
			(clearance 0)
		)
		(min_thickness 0.25)
		(keepout
			(tracks not_allowed)
			(vias allowed)
			(pads allowed)
			(copperpour not_allowed)
			(footprints allowed)
		)
		(placement
			(enabled no)
			(sheetname "")
		)
		(fill yes
			(thermal_gap 0.5)
			(thermal_bridge_width 0.5)
			(island_removal_mode 0)
		)
		(polygon
			(pts
				(arc
					(start 399.52041 -345.465146)
					(mid 398.81683 -345.465146)
					(end 399.52041 -345.465146)
				)
			)
		)
	)
	(zone
		(layers "B.Cu" "In9.Cu" "In11.Cu" "In13.Cu" "In15.Cu")
		(hatch none 0.5)
		(connect_pads
			(clearance 0)
		)
		(min_thickness 0.25)
		(keepout
			(tracks not_allowed)
			(vias allowed)
			(pads allowed)
			(copperpour not_allowed)
			(footprints allowed)
		)
		(placement
			(enabled no)
			(sheetname "")
		)
		(fill yes
			(thermal_gap 0.5)
			(thermal_bridge_width 0.5)
			(island_removal_mode 0)
		)
		(polygon
			(pts
				(arc
					(start 38.337998 -348.58579)
					(mid 37.634418 -348.58579)
					(end 38.337998 -348.58579)
				)
			)
		)
	)
	(zone
		(layers "B.Cu" "In9.Cu" "In11.Cu" "In13.Cu" "In15.Cu")
		(hatch none 0.5)
		(connect_pads
			(clearance 0)
		)
		(min_thickness 0.25)
		(keepout
			(tracks not_allowed)
			(vias allowed)
			(pads allowed)
			(copperpour not_allowed)
			(footprints allowed)
		)
		(placement
			(enabled no)
			(sheetname "")
		)
		(fill yes
			(thermal_gap 0.5)
			(thermal_bridge_width 0.5)
			(island_removal_mode 0)
		)
		(polygon
			(pts
				(arc
					(start 50.47615 -273.099784)
					(mid 49.82337 -273.099784)
					(end 50.47615 -273.099784)
				)
			)
		)
	)
	(zone
		(layers "B.Cu" "In9.Cu" "In11.Cu" "In13.Cu" "In15.Cu")
		(hatch none 0.5)
		(connect_pads
			(clearance 0)
		)
		(min_thickness 0.25)
		(keepout
			(tracks not_allowed)
			(vias allowed)
			(pads allowed)
			(copperpour not_allowed)
			(footprints allowed)
		)
		(placement
			(enabled no)
			(sheetname "")
		)
		(fill yes
			(thermal_gap 0.5)
			(thermal_bridge_width 0.5)
			(island_removal_mode 0)
		)
		(polygon
			(pts
				(arc
					(start 171.864782 -354.732082)
					(mid 171.161202 -354.732082)
					(end 171.864782 -354.732082)
				)
			)
		)
	)
	(zone
		(layers "B.Cu" "In9.Cu" "In11.Cu" "In13.Cu" "In15.Cu")
		(hatch none 0.5)
		(connect_pads
			(clearance 0)
		)
		(min_thickness 0.25)
		(keepout
			(tracks not_allowed)
			(vias allowed)
			(pads allowed)
			(copperpour not_allowed)
			(footprints allowed)
		)
		(placement
			(enabled no)
			(sheetname "")
		)
		(fill yes
			(thermal_gap 0.5)
			(thermal_bridge_width 0.5)
			(island_removal_mode 0)
		)
		(polygon
			(pts
				(arc
					(start 287.86963 -375.69013)
					(mid 287.11017 -375.69013)
					(end 287.86963 -375.69013)
				)
			)
		)
	)
	(zone
		(layers "B.Cu" "In9.Cu" "In11.Cu" "In13.Cu" "In15.Cu")
		(hatch none 0.5)
		(connect_pads
			(clearance 0)
		)
		(min_thickness 0.25)
		(keepout
			(tracks not_allowed)
			(vias allowed)
			(pads allowed)
			(copperpour not_allowed)
			(footprints allowed)
		)
		(placement
			(enabled no)
			(sheetname "")
		)
		(fill yes
			(thermal_gap 0.5)
			(thermal_bridge_width 0.5)
			(island_removal_mode 0)
		)
		(polygon
			(pts
				(arc
					(start 178.946302 -345.465146)
					(mid 178.242722 -345.465146)
					(end 178.946302 -345.465146)
				)
			)
		)
	)
	(zone
		(layers "B.Cu" "In9.Cu" "In11.Cu" "In13.Cu" "In15.Cu")
		(hatch none 0.5)
		(connect_pads
			(clearance 0)
		)
		(min_thickness 0.25)
		(keepout
			(tracks not_allowed)
			(vias allowed)
			(pads allowed)
			(copperpour not_allowed)
			(footprints allowed)
		)
		(placement
			(enabled no)
			(sheetname "")
		)
		(fill yes
			(thermal_gap 0.5)
			(thermal_bridge_width 0.5)
			(island_removal_mode 0)
		)
		(polygon
			(pts
				(arc
					(start 166.576248 -273.099784)
					(mid 165.923468 -273.099784)
					(end 166.576248 -273.099784)
				)
			)
		)
	)
	(zone
		(layers "B.Cu" "In9.Cu" "In11.Cu" "In13.Cu" "In15.Cu")
		(hatch none 0.5)
		(connect_pads
			(clearance 0)
		)
		(min_thickness 0.25)
		(keepout
			(tracks not_allowed)
			(vias allowed)
			(pads allowed)
			(copperpour not_allowed)
			(footprints allowed)
		)
		(placement
			(enabled no)
			(sheetname "")
		)
		(fill yes
			(thermal_gap 0.5)
			(thermal_bridge_width 0.5)
			(island_removal_mode 0)
		)
		(polygon
			(pts
				(arc
					(start 33.56229 -30.058868)
					(mid 32.85871 -30.058868)
					(end 33.56229 -30.058868)
				)
			)
		)
	)
	(zone
		(layers "B.Cu" "In9.Cu" "In11.Cu" "In13.Cu" "In15.Cu")
		(hatch none 0.5)
		(connect_pads
			(clearance 0)
		)
		(min_thickness 0.25)
		(keepout
			(tracks not_allowed)
			(vias allowed)
			(pads allowed)
			(copperpour not_allowed)
			(footprints allowed)
		)
		(placement
			(enabled no)
			(sheetname "")
		)
		(fill yes
			(thermal_gap 0.5)
			(thermal_bridge_width 0.5)
			(island_removal_mode 0)
		)
		(polygon
			(pts
				(arc
					(start 162.489642 -398.890236)
					(mid 161.730182 -398.890236)
					(end 162.489642 -398.890236)
				)
			)
		)
	)
	(zone
		(layers "B.Cu" "In9.Cu" "In11.Cu" "In13.Cu" "In15.Cu")
		(hatch none 0.5)
		(connect_pads
			(clearance 0)
		)
		(min_thickness 0.25)
		(keepout
			(tracks not_allowed)
			(vias allowed)
			(pads allowed)
			(copperpour not_allowed)
			(footprints allowed)
		)
		(placement
			(enabled no)
			(sheetname "")
		)
		(fill yes
			(thermal_gap 0.5)
			(thermal_bridge_width 0.5)
			(island_removal_mode 0)
		)
		(polygon
			(pts
				(arc
					(start 277.575772 -345.465146)
					(mid 276.872192 -345.465146)
					(end 277.575772 -345.465146)
				)
			)
		)
	)
	(zone
		(layers "B.Cu" "In9.Cu" "In11.Cu" "In13.Cu" "In15.Cu")
		(hatch none 0.5)
		(connect_pads
			(clearance 0)
		)
		(min_thickness 0.25)
		(keepout
			(tracks not_allowed)
			(vias allowed)
			(pads allowed)
			(copperpour not_allowed)
			(footprints allowed)
		)
		(placement
			(enabled no)
			(sheetname "")
		)
		(fill yes
			(thermal_gap 0.5)
			(thermal_bridge_width 0.5)
			(island_removal_mode 0)
		)
		(polygon
			(pts
				(arc
					(start 175.662336 -34.52241)
					(mid 174.958756 -34.52241)
					(end 175.662336 -34.52241)
				)
			)
		)
	)
	(zone
		(layers "B.Cu" "In9.Cu" "In11.Cu" "In13.Cu" "In15.Cu")
		(hatch none 0.5)
		(connect_pads
			(clearance 0)
		)
		(min_thickness 0.25)
		(keepout
			(tracks not_allowed)
			(vias allowed)
			(pads allowed)
			(copperpour not_allowed)
			(footprints allowed)
		)
		(placement
			(enabled no)
			(sheetname "")
		)
		(fill yes
			(thermal_gap 0.5)
			(thermal_bridge_width 0.5)
			(island_removal_mode 0)
		)
		(polygon
			(pts
				(arc
					(start 58.076338 -274.049744)
					(mid 57.423558 -274.049744)
					(end 58.076338 -274.049744)
				)
			)
		)
	)
	(zone
		(layers "B.Cu" "In9.Cu" "In11.Cu" "In13.Cu" "In15.Cu")
		(hatch none 0.5)
		(connect_pads
			(clearance 0)
		)
		(min_thickness 0.25)
		(keepout
			(tracks not_allowed)
			(vias allowed)
			(pads allowed)
			(copperpour not_allowed)
			(footprints allowed)
		)
		(placement
			(enabled no)
			(sheetname "")
		)
		(fill yes
			(thermal_gap 0.5)
			(thermal_bridge_width 0.5)
			(island_removal_mode 0)
		)
		(polygon
			(pts
				(arc
					(start 197.600062 -342.439498)
					(mid 196.896482 -342.439498)
					(end 197.600062 -342.439498)
				)
			)
		)
	)
	(zone
		(layers "B.Cu" "In9.Cu" "In11.Cu" "In13.Cu" "In15.Cu")
		(hatch none 0.5)
		(connect_pads
			(clearance 0)
		)
		(min_thickness 0.25)
		(keepout
			(tracks not_allowed)
			(vias allowed)
			(pads allowed)
			(copperpour not_allowed)
			(footprints allowed)
		)
		(placement
			(enabled no)
			(sheetname "")
		)
		(fill yes
			(thermal_gap 0.5)
			(thermal_bridge_width 0.5)
			(island_removal_mode 0)
		)
		(polygon
			(pts
				(arc
					(start 383.71653 -32.722312)
					(mid 383.01295 -32.722312)
					(end 383.71653 -32.722312)
				)
			)
		)
	)
	(zone
		(layers "B.Cu" "In9.Cu" "In11.Cu" "In13.Cu" "In15.Cu")
		(hatch none 0.5)
		(connect_pads
			(clearance 0)
		)
		(min_thickness 0.25)
		(keepout
			(tracks not_allowed)
			(vias allowed)
			(pads allowed)
			(copperpour not_allowed)
			(footprints allowed)
		)
		(placement
			(enabled no)
			(sheetname "")
		)
		(fill yes
			(thermal_gap 0.5)
			(thermal_bridge_width 0.5)
			(island_removal_mode 0)
		)
		(polygon
			(pts
				(arc
					(start 271.357852 -342.439498)
					(mid 270.654272 -342.439498)
					(end 271.357852 -342.439498)
				)
			)
		)
	)
	(zone
		(layers "B.Cu" "In9.Cu" "In11.Cu" "In13.Cu" "In15.Cu")
		(hatch none 0.5)
		(connect_pads
			(clearance 0)
		)
		(min_thickness 0.25)
		(keepout
			(tracks not_allowed)
			(vias allowed)
			(pads allowed)
			(copperpour not_allowed)
			(footprints allowed)
		)
		(placement
			(enabled no)
			(sheetname "")
		)
		(fill yes
			(thermal_gap 0.5)
			(thermal_bridge_width 0.5)
			(island_removal_mode 0)
		)
		(polygon
			(pts
				(arc
					(start 404.476204 -274.049744)
					(mid 403.823424 -274.049744)
					(end 404.476204 -274.049744)
				)
			)
		)
	)
	(zone
		(layers "B.Cu" "In9.Cu" "In11.Cu" "In13.Cu" "In15.Cu")
		(hatch none 0.5)
		(connect_pads
			(clearance 0)
		)
		(min_thickness 0.25)
		(keepout
			(tracks not_allowed)
			(vias allowed)
			(pads allowed)
			(copperpour not_allowed)
			(footprints allowed)
		)
		(placement
			(enabled no)
			(sheetname "")
		)
		(fill yes
			(thermal_gap 0.5)
			(thermal_bridge_width 0.5)
			(island_removal_mode 0)
		)
		(polygon
			(pts
				(arc
					(start 52.376324 -273.099784)
					(mid 51.723544 -273.099784)
					(end 52.376324 -273.099784)
				)
			)
		)
	)
	(zone
		(layers "B.Cu" "In9.Cu" "In11.Cu" "In13.Cu" "In15.Cu")
		(hatch none 0.5)
		(connect_pads
			(clearance 0)
		)
		(min_thickness 0.25)
		(keepout
			(tracks not_allowed)
			(vias allowed)
			(pads allowed)
			(copperpour not_allowed)
			(footprints allowed)
		)
		(placement
			(enabled no)
			(sheetname "")
		)
		(fill yes
			(thermal_gap 0.5)
			(thermal_bridge_width 0.5)
			(island_removal_mode 0)
		)
		(polygon
			(pts
				(arc
					(start 61.724032 -351.611438)
					(mid 61.020452 -351.611438)
					(end 61.724032 -351.611438)
				)
			)
		)
	)
	(zone
		(layers "B.Cu" "In9.Cu" "In11.Cu" "In13.Cu" "In15.Cu")
		(hatch none 0.5)
		(connect_pads
			(clearance 0)
		)
		(min_thickness 0.25)
		(keepout
			(tracks not_allowed)
			(vias allowed)
			(pads allowed)
			(copperpour not_allowed)
			(footprints allowed)
		)
		(placement
			(enabled no)
			(sheetname "")
		)
		(fill yes
			(thermal_gap 0.5)
			(thermal_bridge_width 0.5)
			(island_removal_mode 0)
		)
		(polygon
			(pts
				(arc
					(start 32.983678 -348.58579)
					(mid 32.280098 -348.58579)
					(end 32.983678 -348.58579)
				)
			)
		)
	)
	(zone
		(layers "B.Cu" "In9.Cu" "In11.Cu" "In13.Cu" "In15.Cu")
		(hatch none 0.5)
		(connect_pads
			(clearance 0)
		)
		(min_thickness 0.25)
		(keepout
			(tracks not_allowed)
			(vias allowed)
			(pads allowed)
			(copperpour not_allowed)
			(footprints allowed)
		)
		(placement
			(enabled no)
			(sheetname "")
		)
		(fill yes
			(thermal_gap 0.5)
			(thermal_bridge_width 0.5)
			(island_removal_mode 0)
		)
		(polygon
			(pts
				(arc
					(start 265.762232 -30.922468)
					(mid 265.058652 -30.922468)
					(end 265.762232 -30.922468)
				)
			)
		)
	)
	(zone
		(layers "B.Cu" "In9.Cu" "In11.Cu" "In13.Cu" "In15.Cu")
		(hatch none 0.5)
		(connect_pads
			(clearance 0)
		)
		(min_thickness 0.25)
		(keepout
			(tracks not_allowed)
			(vias allowed)
			(pads allowed)
			(copperpour not_allowed)
			(footprints allowed)
		)
		(placement
			(enabled no)
			(sheetname "")
		)
		(fill yes
			(thermal_gap 0.5)
			(thermal_bridge_width 0.5)
			(island_removal_mode 0)
		)
		(polygon
			(pts
				(arc
					(start 58.076338 -273.099784)
					(mid 57.423558 -273.099784)
					(end 58.076338 -273.099784)
				)
			)
		)
	)
	(zone
		(layers "B.Cu" "In9.Cu" "In11.Cu" "In13.Cu" "In15.Cu")
		(hatch none 0.5)
		(connect_pads
			(clearance 0)
		)
		(min_thickness 0.25)
		(keepout
			(tracks not_allowed)
			(vias allowed)
			(pads allowed)
			(copperpour not_allowed)
			(footprints allowed)
		)
		(placement
			(enabled no)
			(sheetname "")
		)
		(fill yes
			(thermal_gap 0.5)
			(thermal_bridge_width 0.5)
			(island_removal_mode 0)
		)
		(polygon
			(pts
				(arc
					(start 64.832992 -357.75773)
					(mid 64.129412 -357.75773)
					(end 64.832992 -357.75773)
				)
			)
		)
	)
	(zone
		(layers "B.Cu" "In9.Cu" "In11.Cu" "In13.Cu" "In15.Cu")
		(hatch none 0.5)
		(connect_pads
			(clearance 0)
		)
		(min_thickness 0.25)
		(keepout
			(tracks not_allowed)
			(vias allowed)
			(pads allowed)
			(copperpour not_allowed)
			(footprints allowed)
		)
		(placement
			(enabled no)
			(sheetname "")
		)
		(fill yes
			(thermal_gap 0.5)
			(thermal_bridge_width 0.5)
			(island_removal_mode 0)
		)
		(polygon
			(pts
				(arc
					(start 177.516536 -28.25877)
					(mid 176.812956 -28.25877)
					(end 177.516536 -28.25877)
				)
			)
		)
	)
	(zone
		(layers "B.Cu" "In9.Cu" "In11.Cu" "In13.Cu" "In15.Cu")
		(hatch none 0.5)
		(connect_pads
			(clearance 0)
		)
		(min_thickness 0.25)
		(keepout
			(tracks not_allowed)
			(vias allowed)
			(pads allowed)
			(copperpour not_allowed)
			(footprints allowed)
		)
		(placement
			(enabled no)
			(sheetname "")
		)
		(fill yes
			(thermal_gap 0.5)
			(thermal_bridge_width 0.5)
			(island_removal_mode 0)
		)
		(polygon
			(pts
				(arc
					(start 267.616432 -32.722312)
					(mid 266.912852 -32.722312)
					(end 267.616432 -32.722312)
				)
			)
		)
	)
	(zone
		(layers "B.Cu" "In9.Cu" "In11.Cu" "In13.Cu" "In15.Cu")
		(hatch none 0.5)
		(connect_pads
			(clearance 0)
		)
		(min_thickness 0.25)
		(keepout
			(tracks not_allowed)
			(vias allowed)
			(pads allowed)
			(copperpour not_allowed)
			(footprints allowed)
		)
		(placement
			(enabled no)
			(sheetname "")
		)
		(fill yes
			(thermal_gap 0.5)
			(thermal_bridge_width 0.5)
			(island_removal_mode 0)
		)
		(polygon
			(pts
				(arc
					(start 165.646862 -345.465146)
					(mid 164.943282 -345.465146)
					(end 165.646862 -345.465146)
				)
			)
		)
	)
	(zone
		(layers "B.Cu" "In9.Cu" "In11.Cu" "In13.Cu" "In15.Cu")
		(hatch none 0.5)
		(connect_pads
			(clearance 0)
		)
		(min_thickness 0.25)
		(keepout
			(tracks not_allowed)
			(vias allowed)
			(pads allowed)
			(copperpour not_allowed)
			(footprints allowed)
		)
		(placement
			(enabled no)
			(sheetname "")
		)
		(fill yes
			(thermal_gap 0.5)
			(thermal_bridge_width 0.5)
			(island_removal_mode 0)
		)
		(polygon
			(pts
				(arc
					(start 131.731258 -348.58579)
					(mid 131.027678 -348.58579)
					(end 131.731258 -348.58579)
				)
			)
		)
	)
	(zone
		(layers "B.Cu" "In9.Cu" "In11.Cu" "In13.Cu" "In15.Cu")
		(hatch none 0.5)
		(connect_pads
			(clearance 0)
		)
		(min_thickness 0.25)
		(keepout
			(tracks not_allowed)
			(vias allowed)
			(pads allowed)
			(copperpour not_allowed)
			(footprints allowed)
		)
		(placement
			(enabled no)
			(sheetname "")
		)
		(fill yes
			(thermal_gap 0.5)
			(thermal_bridge_width 0.5)
			(island_removal_mode 0)
		)
		(polygon
			(pts
				(arc
					(start 116.186458 -345.465146)
					(mid 115.482878 -345.465146)
					(end 116.186458 -345.465146)
				)
			)
		)
	)
	(zone
		(layers "B.Cu" "In9.Cu" "In11.Cu" "In13.Cu" "In15.Cu")
		(hatch none 0.5)
		(connect_pads
			(clearance 0)
		)
		(min_thickness 0.25)
		(keepout
			(tracks not_allowed)
			(vias allowed)
			(pads allowed)
			(copperpour not_allowed)
			(footprints allowed)
		)
		(placement
			(enabled no)
			(sheetname "")
		)
		(fill yes
			(thermal_gap 0.5)
			(thermal_bridge_width 0.5)
			(island_removal_mode 0)
		)
		(polygon
			(pts
				(arc
					(start 434.518562 -348.58579)
					(mid 433.814982 -348.58579)
					(end 434.518562 -348.58579)
				)
			)
		)
	)
	(zone
		(layers "B.Cu" "In9.Cu" "In11.Cu" "In13.Cu" "In15.Cu")
		(hatch none 0.5)
		(connect_pads
			(clearance 0)
		)
		(min_thickness 0.25)
		(keepout
			(tracks not_allowed)
			(vias allowed)
			(pads allowed)
			(copperpour not_allowed)
			(footprints allowed)
		)
		(placement
			(enabled no)
			(sheetname "")
		)
		(fill yes
			(thermal_gap 0.5)
			(thermal_bridge_width 0.5)
			(island_removal_mode 0)
		)
		(polygon
			(pts
				(arc
					(start 140.194538 -354.732082)
					(mid 139.490958 -354.732082)
					(end 140.194538 -354.732082)
				)
			)
		)
	)
	(zone
		(layers "B.Cu" "In9.Cu" "In11.Cu" "In13.Cu" "In15.Cu")
		(hatch none 0.5)
		(connect_pads
			(clearance 0)
		)
		(min_thickness 0.25)
		(keepout
			(tracks not_allowed)
			(vias allowed)
			(pads allowed)
			(copperpour not_allowed)
			(footprints allowed)
		)
		(placement
			(enabled no)
			(sheetname "")
		)
		(fill yes
			(thermal_gap 0.5)
			(thermal_bridge_width 0.5)
			(island_removal_mode 0)
		)
		(polygon
			(pts
				(arc
					(start 387.08457 -354.732082)
					(mid 386.38099 -354.732082)
					(end 387.08457 -354.732082)
				)
			)
		)
	)
	(zone
		(layers "B.Cu" "In9.Cu" "In11.Cu" "In13.Cu" "In15.Cu")
		(hatch none 0.5)
		(connect_pads
			(clearance 0)
		)
		(min_thickness 0.25)
		(keepout
			(tracks not_allowed)
			(vias allowed)
			(pads allowed)
			(copperpour not_allowed)
			(footprints allowed)
		)
		(placement
			(enabled no)
			(sheetname "")
		)
		(fill yes
			(thermal_gap 0.5)
			(thermal_bridge_width 0.5)
			(island_removal_mode 0)
		)
		(polygon
			(pts
				(arc
					(start 281.726132 -274.999958)
					(mid 281.073352 -274.999958)
					(end 281.726132 -274.999958)
				)
			)
		)
	)
	(zone
		(layers "B.Cu" "In9.Cu" "In11.Cu" "In13.Cu" "In15.Cu")
		(hatch none 0.5)
		(connect_pads
			(clearance 0)
		)
		(min_thickness 0.25)
		(keepout
			(tracks not_allowed)
			(vias allowed)
			(pads allowed)
			(copperpour not_allowed)
			(footprints allowed)
		)
		(placement
			(enabled no)
			(sheetname "")
		)
		(fill yes
			(thermal_gap 0.5)
			(thermal_bridge_width 0.5)
			(island_removal_mode 0)
		)
		(polygon
			(pts
				(arc
					(start 294.07612 -312.999882)
					(mid 293.42334 -312.999882)
					(end 294.07612 -312.999882)
				)
			)
		)
	)
	(zone
		(layers "B.Cu" "In9.Cu" "In11.Cu" "In13.Cu" "In15.Cu")
		(hatch none 0.5)
		(connect_pads
			(clearance 0)
		)
		(min_thickness 0.25)
		(keepout
			(tracks not_allowed)
			(vias allowed)
			(pads allowed)
			(copperpour not_allowed)
			(footprints allowed)
		)
		(placement
			(enabled no)
			(sheetname "")
		)
		(fill yes
			(thermal_gap 0.5)
			(thermal_bridge_width 0.5)
			(island_removal_mode 0)
		)
		(polygon
			(pts
				(arc
					(start 9.416542 -31.858712)
					(mid 8.712962 -31.858712)
					(end 9.416542 -31.858712)
				)
			)
		)
	)
	(zone
		(layers "B.Cu" "In9.Cu" "In11.Cu" "In13.Cu" "In15.Cu")
		(hatch none 0.5)
		(connect_pads
			(clearance 0)
		)
		(min_thickness 0.25)
		(keepout
			(tracks not_allowed)
			(vias allowed)
			(pads allowed)
			(copperpour not_allowed)
			(footprints allowed)
		)
		(placement
			(enabled no)
			(sheetname "")
		)
		(fill yes
			(thermal_gap 0.5)
			(thermal_bridge_width 0.5)
			(island_removal_mode 0)
		)
		(polygon
			(pts
				(arc
					(start 20.547838 -351.611438)
					(mid 19.844258 -351.611438)
					(end 20.547838 -351.611438)
				)
			)
		)
	)
	(zone
		(layers "B.Cu" "In9.Cu" "In11.Cu" "In13.Cu" "In15.Cu")
		(hatch none 0.5)
		(connect_pads
			(clearance 0)
		)
		(min_thickness 0.25)
		(keepout
			(tracks not_allowed)
			(vias allowed)
			(pads allowed)
			(copperpour not_allowed)
			(footprints allowed)
		)
		(placement
			(enabled no)
			(sheetname "")
		)
		(fill yes
			(thermal_gap 0.5)
			(thermal_bridge_width 0.5)
			(island_removal_mode 0)
		)
		(polygon
			(pts
				(arc
					(start 397.82623 -274.999958)
					(mid 397.17345 -274.999958)
					(end 397.82623 -274.999958)
				)
			)
		)
	)
	(zone
		(layers "B.Cu" "In9.Cu" "In11.Cu" "In13.Cu" "In15.Cu")
		(hatch none 0.5)
		(connect_pads
			(clearance 0)
		)
		(min_thickness 0.25)
		(keepout
			(tracks not_allowed)
			(vias allowed)
			(pads allowed)
			(copperpour not_allowed)
			(footprints allowed)
		)
		(placement
			(enabled no)
			(sheetname "")
		)
		(fill yes
			(thermal_gap 0.5)
			(thermal_bridge_width 0.5)
			(island_removal_mode 0)
		)
		(polygon
			(pts
				(arc
					(start 161.826448 -275.949918)
					(mid 161.173668 -275.949918)
					(end 161.826448 -275.949918)
				)
			)
		)
	)
	(zone
		(layers "B.Cu" "In9.Cu" "In11.Cu" "In13.Cu" "In15.Cu")
		(hatch none 0.5)
		(connect_pads
			(clearance 0)
		)
		(min_thickness 0.25)
		(keepout
			(tracks not_allowed)
			(vias allowed)
			(pads allowed)
			(copperpour not_allowed)
			(footprints allowed)
		)
		(placement
			(enabled no)
			(sheetname "")
		)
		(fill yes
			(thermal_gap 0.5)
			(thermal_bridge_width 0.5)
			(island_removal_mode 0)
		)
		(polygon
			(pts
				(arc
					(start 47.664878 -354.732082)
					(mid 46.961298 -354.732082)
					(end 47.664878 -354.732082)
				)
			)
		)
	)
	(zone
		(layers "B.Cu" "In9.Cu" "In11.Cu" "In13.Cu" "In15.Cu")
		(hatch none 0.5)
		(connect_pads
			(clearance 0)
		)
		(min_thickness 0.25)
		(keepout
			(tracks not_allowed)
			(vias allowed)
			(pads allowed)
			(copperpour not_allowed)
			(footprints allowed)
		)
		(placement
			(enabled no)
			(sheetname "")
		)
		(fill yes
			(thermal_gap 0.5)
			(thermal_bridge_width 0.5)
			(island_removal_mode 0)
		)
		(polygon
			(pts
				(arc
					(start 426.055282 -357.75773)
					(mid 425.351702 -357.75773)
					(end 426.055282 -357.75773)
				)
			)
		)
	)
	(zone
		(layers "B.Cu" "In9.Cu" "In11.Cu" "In13.Cu" "In15.Cu")
		(hatch none 0.5)
		(connect_pads
			(clearance 0)
		)
		(min_thickness 0.25)
		(keepout
			(tracks not_allowed)
			(vias allowed)
			(pads allowed)
			(copperpour not_allowed)
			(footprints allowed)
		)
		(placement
			(enabled no)
			(sheetname "")
		)
		(fill yes
			(thermal_gap 0.5)
			(thermal_bridge_width 0.5)
			(island_removal_mode 0)
		)
		(polygon
			(pts
				(arc
					(start 425.191682 -342.439498)
					(mid 424.488102 -342.439498)
					(end 425.191682 -342.439498)
				)
			)
		)
	)
	(zone
		(layers "B.Cu" "In9.Cu" "In11.Cu" "In13.Cu" "In15.Cu")
		(hatch none 0.5)
		(connect_pads
			(clearance 0)
		)
		(min_thickness 0.25)
		(keepout
			(tracks not_allowed)
			(vias allowed)
			(pads allowed)
			(copperpour not_allowed)
			(footprints allowed)
		)
		(placement
			(enabled no)
			(sheetname "")
		)
		(fill yes
			(thermal_gap 0.5)
			(thermal_bridge_width 0.5)
			(island_removal_mode 0)
		)
		(polygon
			(pts
				(arc
					(start 331.869796 -405.589994)
					(mid 331.110336 -405.589994)
					(end 331.869796 -405.589994)
				)
			)
		)
	)
	(zone
		(layers "B.Cu" "In9.Cu" "In11.Cu" "In13.Cu" "In15.Cu")
		(hatch none 0.5)
		(connect_pads
			(clearance 0)
		)
		(min_thickness 0.25)
		(keepout
			(tracks not_allowed)
			(vias allowed)
			(pads allowed)
			(copperpour not_allowed)
			(footprints allowed)
		)
		(placement
			(enabled no)
			(sheetname "")
		)
		(fill yes
			(thermal_gap 0.5)
			(thermal_bridge_width 0.5)
			(island_removal_mode 0)
		)
		(polygon
			(pts
				(arc
					(start 378.62129 -348.58579)
					(mid 377.91771 -348.58579)
					(end 378.62129 -348.58579)
				)
			)
		)
	)
	(zone
		(layers "B.Cu" "In9.Cu" "In11.Cu" "In13.Cu" "In15.Cu")
		(hatch none 0.5)
		(connect_pads
			(clearance 0)
		)
		(min_thickness 0.25)
		(keepout
			(tracks not_allowed)
			(vias allowed)
			(pads allowed)
			(copperpour not_allowed)
			(footprints allowed)
		)
		(placement
			(enabled no)
			(sheetname "")
		)
		(fill yes
			(thermal_gap 0.5)
			(thermal_bridge_width 0.5)
			(island_removal_mode 0)
		)
		(polygon
			(pts
				(arc
					(start 423.47642 -308.249828)
					(mid 422.82364 -308.249828)
					(end 423.47642 -308.249828)
				)
			)
		)
	)
	(zone
		(layers "B.Cu" "In9.Cu" "In11.Cu" "In13.Cu" "In15.Cu")
		(hatch none 0.5)
		(connect_pads
			(clearance 0)
		)
		(min_thickness 0.25)
		(keepout
			(tracks not_allowed)
			(vias allowed)
			(pads allowed)
			(copperpour not_allowed)
			(footprints allowed)
		)
		(placement
			(enabled no)
			(sheetname "")
		)
		(fill yes
			(thermal_gap 0.5)
			(thermal_bridge_width 0.5)
			(island_removal_mode 0)
		)
		(polygon
			(pts
				(arc
					(start 169.089832 -371.790214)
					(mid 168.330372 -371.790214)
					(end 169.089832 -371.790214)
				)
			)
		)
	)
	(zone
		(layers "B.Cu" "In9.Cu" "In11.Cu" "In13.Cu" "In15.Cu")
		(hatch none 0.5)
		(connect_pads
			(clearance 0)
		)
		(min_thickness 0.25)
		(keepout
			(tracks not_allowed)
			(vias allowed)
			(pads allowed)
			(copperpour not_allowed)
			(footprints allowed)
		)
		(placement
			(enabled no)
			(sheetname "")
		)
		(fill yes
			(thermal_gap 0.5)
			(thermal_bridge_width 0.5)
			(island_removal_mode 0)
		)
		(polygon
			(pts
				(arc
					(start 9.416542 -29.12237)
					(mid 8.712962 -29.12237)
					(end 9.416542 -29.12237)
				)
			)
		)
	)
	(zone
		(layers "B.Cu" "In9.Cu" "In11.Cu" "In13.Cu" "In15.Cu")
		(hatch none 0.5)
		(connect_pads
			(clearance 0)
		)
		(min_thickness 0.25)
		(keepout
			(tracks not_allowed)
			(vias allowed)
			(pads allowed)
			(copperpour not_allowed)
			(footprints allowed)
		)
		(placement
			(enabled no)
			(sheetname "")
		)
		(fill yes
			(thermal_gap 0.5)
			(thermal_bridge_width 0.5)
			(island_removal_mode 0)
		)
		(polygon
			(pts
				(arc
					(start 277.575772 -354.732082)
					(mid 276.872192 -354.732082)
					(end 277.575772 -354.732082)
				)
			)
		)
	)
	(zone
		(layers "B.Cu" "In9.Cu" "In11.Cu" "In13.Cu" "In15.Cu")
		(hatch none 0.5)
		(connect_pads
			(clearance 0)
		)
		(min_thickness 0.25)
		(keepout
			(tracks not_allowed)
			(vias allowed)
			(pads allowed)
			(copperpour not_allowed)
			(footprints allowed)
		)
		(placement
			(enabled no)
			(sheetname "")
		)
		(fill yes
			(thermal_gap 0.5)
			(thermal_bridge_width 0.5)
			(island_removal_mode 0)
		)
		(polygon
			(pts
				(arc
					(start 340.66988 -404.290022)
					(mid 339.91042 -404.290022)
					(end 340.66988 -404.290022)
				)
			)
		)
	)
	(zone
		(layers "B.Cu" "In9.Cu" "In11.Cu" "In13.Cu" "In15.Cu")
		(hatch none 0.5)
		(connect_pads
			(clearance 0)
		)
		(min_thickness 0.25)
		(keepout
			(tracks not_allowed)
			(vias allowed)
			(pads allowed)
			(copperpour not_allowed)
			(footprints allowed)
		)
		(placement
			(enabled no)
			(sheetname "")
		)
		(fill yes
			(thermal_gap 0.5)
			(thermal_bridge_width 0.5)
			(island_removal_mode 0)
		)
		(polygon
			(pts
				(arc
					(start 113.077498 -348.58579)
					(mid 112.373918 -348.58579)
					(end 113.077498 -348.58579)
				)
			)
		)
	)
	(zone
		(layers "B.Cu" "In9.Cu" "In11.Cu" "In13.Cu" "In15.Cu")
		(hatch none 0.5)
		(connect_pads
			(clearance 0)
		)
		(min_thickness 0.25)
		(keepout
			(tracks not_allowed)
			(vias allowed)
			(pads allowed)
			(copperpour not_allowed)
			(footprints allowed)
		)
		(placement
			(enabled no)
			(sheetname "")
		)
		(fill yes
			(thermal_gap 0.5)
			(thermal_bridge_width 0.5)
			(island_removal_mode 0)
		)
		(polygon
			(pts
				(arc
					(start 122.889772 -384.590036)
					(mid 122.130312 -384.590036)
					(end 122.889772 -384.590036)
				)
			)
		)
	)
	(zone
		(layers "B.Cu" "In9.Cu" "In11.Cu" "In13.Cu" "In15.Cu")
		(hatch none 0.5)
		(connect_pads
			(clearance 0)
		)
		(min_thickness 0.25)
		(keepout
			(tracks not_allowed)
			(vias allowed)
			(pads allowed)
			(copperpour not_allowed)
			(footprints allowed)
		)
		(placement
			(enabled no)
			(sheetname "")
		)
		(fill yes
			(thermal_gap 0.5)
			(thermal_bridge_width 0.5)
			(island_removal_mode 0)
		)
		(polygon
			(pts
				(arc
					(start 203.516484 -28.25877)
					(mid 202.812904 -28.25877)
					(end 203.516484 -28.25877)
				)
			)
		)
	)
	(zone
		(layers "B.Cu" "In9.Cu" "In11.Cu" "In13.Cu" "In15.Cu")
		(hatch none 0.5)
		(connect_pads
			(clearance 0)
		)
		(min_thickness 0.25)
		(keepout
			(tracks not_allowed)
			(vias allowed)
			(pads allowed)
			(copperpour not_allowed)
			(footprints allowed)
		)
		(placement
			(enabled no)
			(sheetname "")
		)
		(fill yes
			(thermal_gap 0.5)
			(thermal_bridge_width 0.5)
			(island_removal_mode 0)
		)
		(polygon
			(pts
				(arc
					(start 166.889684 -372.890034)
					(mid 166.130224 -372.890034)
					(end 166.889684 -372.890034)
				)
			)
		)
	)
	(zone
		(layers "B.Cu" "In9.Cu" "In11.Cu" "In13.Cu" "In15.Cu")
		(hatch none 0.5)
		(connect_pads
			(clearance 0)
		)
		(min_thickness 0.25)
		(keepout
			(tracks not_allowed)
			(vias allowed)
			(pads allowed)
			(copperpour not_allowed)
			(footprints allowed)
		)
		(placement
			(enabled no)
			(sheetname "")
		)
		(fill yes
			(thermal_gap 0.5)
			(thermal_bridge_width 0.5)
			(island_removal_mode 0)
		)
		(polygon
			(pts
				(arc
					(start 274.466812 -348.58579)
					(mid 273.763232 -348.58579)
					(end 274.466812 -348.58579)
				)
			)
		)
	)
	(zone
		(layers "B.Cu" "In9.Cu" "In11.Cu" "In13.Cu" "In15.Cu")
		(hatch none 0.5)
		(connect_pads
			(clearance 0)
		)
		(min_thickness 0.25)
		(keepout
			(tracks not_allowed)
			(vias allowed)
			(pads allowed)
			(copperpour not_allowed)
			(footprints allowed)
		)
		(placement
			(enabled no)
			(sheetname "")
		)
		(fill yes
			(thermal_gap 0.5)
			(thermal_bridge_width 0.5)
			(island_removal_mode 0)
		)
		(polygon
			(pts
				(arc
					(start 422.069514 -398.890236)
					(mid 421.310054 -398.890236)
					(end 422.069514 -398.890236)
				)
			)
		)
	)
	(zone
		(layers "B.Cu" "In9.Cu" "In11.Cu" "In13.Cu" "In15.Cu")
		(hatch none 0.5)
		(connect_pads
			(clearance 0)
		)
		(min_thickness 0.25)
		(keepout
			(tracks not_allowed)
			(vias allowed)
			(pads allowed)
			(copperpour not_allowed)
			(footprints allowed)
		)
		(placement
			(enabled no)
			(sheetname "")
		)
		(fill yes
			(thermal_gap 0.5)
			(thermal_bridge_width 0.5)
			(island_removal_mode 0)
		)
		(polygon
			(pts
				(arc
					(start 298.826174 -312.049922)
					(mid 298.173394 -312.049922)
					(end 298.826174 -312.049922)
				)
			)
		)
	)
	(zone
		(layers "B.Cu" "In9.Cu" "In11.Cu" "In13.Cu" "In15.Cu")
		(hatch none 0.5)
		(connect_pads
			(clearance 0)
		)
		(min_thickness 0.25)
		(keepout
			(tracks not_allowed)
			(vias allowed)
			(pads allowed)
			(copperpour not_allowed)
			(footprints allowed)
		)
		(placement
			(enabled no)
			(sheetname "")
		)
		(fill yes
			(thermal_gap 0.5)
			(thermal_bridge_width 0.5)
			(island_removal_mode 0)
		)
		(polygon
			(pts
				(arc
					(start 413.976312 -313.949842)
					(mid 413.323532 -313.949842)
					(end 413.976312 -313.949842)
				)
			)
		)
	)
	(zone
		(layers "B.Cu" "In9.Cu" "In11.Cu" "In13.Cu" "In15.Cu")
		(hatch none 0.5)
		(connect_pads
			(clearance 0)
		)
		(min_thickness 0.25)
		(keepout
			(tracks not_allowed)
			(vias allowed)
			(pads allowed)
			(copperpour not_allowed)
			(footprints allowed)
		)
		(placement
			(enabled no)
			(sheetname "")
		)
		(fill yes
			(thermal_gap 0.5)
			(thermal_bridge_width 0.5)
			(island_removal_mode 0)
		)
		(polygon
			(pts
				(arc
					(start 201.662284 -30.058868)
					(mid 200.958704 -30.058868)
					(end 201.662284 -30.058868)
				)
			)
		)
	)
	(zone
		(layers "B.Cu" "In9.Cu" "In11.Cu" "In13.Cu" "In15.Cu")
		(hatch none 0.5)
		(connect_pads
			(clearance 0)
		)
		(min_thickness 0.25)
		(keepout
			(tracks not_allowed)
			(vias allowed)
			(pads allowed)
			(copperpour not_allowed)
			(footprints allowed)
		)
		(placement
			(enabled no)
			(sheetname "")
		)
		(fill yes
			(thermal_gap 0.5)
			(thermal_bridge_width 0.5)
			(island_removal_mode 0)
		)
		(polygon
			(pts
				(arc
					(start 171.864782 -357.75773)
					(mid 171.161202 -357.75773)
					(end 171.864782 -357.75773)
				)
			)
		)
	)
	(zone
		(layers "B.Cu" "In9.Cu" "In11.Cu" "In13.Cu" "In15.Cu")
		(hatch none 0.5)
		(connect_pads
			(clearance 0)
		)
		(min_thickness 0.25)
		(keepout
			(tracks not_allowed)
			(vias allowed)
			(pads allowed)
			(copperpour not_allowed)
			(footprints allowed)
		)
		(placement
			(enabled no)
			(sheetname "")
		)
		(fill yes
			(thermal_gap 0.5)
			(thermal_bridge_width 0.5)
			(island_removal_mode 0)
		)
		(polygon
			(pts
				(arc
					(start 279.826212 -274.999958)
					(mid 279.173432 -274.999958)
					(end 279.826212 -274.999958)
				)
			)
		)
	)
	(zone
		(layers "B.Cu" "In9.Cu" "In11.Cu" "In13.Cu" "In15.Cu")
		(hatch none 0.5)
		(connect_pads
			(clearance 0)
		)
		(min_thickness 0.25)
		(keepout
			(tracks not_allowed)
			(vias allowed)
			(pads allowed)
			(copperpour not_allowed)
			(footprints allowed)
		)
		(placement
			(enabled no)
			(sheetname "")
		)
		(fill yes
			(thermal_gap 0.5)
			(thermal_bridge_width 0.5)
			(island_removal_mode 0)
		)
		(polygon
			(pts
				(arc
					(start 34.889694 -401.49018)
					(mid 34.130234 -401.49018)
					(end 34.889694 -401.49018)
				)
			)
		)
	)
	(zone
		(layers "B.Cu" "In9.Cu" "In11.Cu" "In13.Cu" "In15.Cu")
		(hatch none 0.5)
		(connect_pads
			(clearance 0)
		)
		(min_thickness 0.25)
		(keepout
			(tracks not_allowed)
			(vias allowed)
			(pads allowed)
			(copperpour not_allowed)
			(footprints allowed)
		)
		(placement
			(enabled no)
			(sheetname "")
		)
		(fill yes
			(thermal_gap 0.5)
			(thermal_bridge_width 0.5)
			(island_removal_mode 0)
		)
		(polygon
			(pts
				(arc
					(start 62.587632 -351.611438)
					(mid 61.884052 -351.611438)
					(end 62.587632 -351.611438)
				)
			)
		)
	)
	(zone
		(layers "B.Cu" "In9.Cu" "In11.Cu" "In13.Cu" "In15.Cu")
		(hatch none 0.5)
		(connect_pads
			(clearance 0)
		)
		(min_thickness 0.25)
		(keepout
			(tracks not_allowed)
			(vias allowed)
			(pads allowed)
			(copperpour not_allowed)
			(footprints allowed)
		)
		(placement
			(enabled no)
			(sheetname "")
		)
		(fill yes
			(thermal_gap 0.5)
			(thermal_bridge_width 0.5)
			(island_removal_mode 0)
		)
		(polygon
			(pts
				(arc
					(start 198.876412 -312.049922)
					(mid 198.223632 -312.049922)
					(end 198.876412 -312.049922)
				)
			)
		)
	)
	(zone
		(layers "B.Cu" "In9.Cu" "In11.Cu" "In13.Cu" "In15.Cu")
		(hatch none 0.5)
		(connect_pads
			(clearance 0)
		)
		(min_thickness 0.25)
		(keepout
			(tracks not_allowed)
			(vias allowed)
			(pads allowed)
			(copperpour not_allowed)
			(footprints allowed)
		)
		(placement
			(enabled no)
			(sheetname "")
		)
		(fill yes
			(thermal_gap 0.5)
			(thermal_bridge_width 0.5)
			(island_removal_mode 0)
		)
		(polygon
			(pts
				(arc
					(start 196.976238 -312.999882)
					(mid 196.323458 -312.999882)
					(end 196.976238 -312.999882)
				)
			)
		)
	)
	(zone
		(layers "B.Cu" "In9.Cu" "In11.Cu" "In13.Cu" "In15.Cu")
		(hatch none 0.5)
		(connect_pads
			(clearance 0)
		)
		(min_thickness 0.25)
		(keepout
			(tracks not_allowed)
			(vias allowed)
			(pads allowed)
			(copperpour not_allowed)
			(footprints allowed)
		)
		(placement
			(enabled no)
			(sheetname "")
		)
		(fill yes
			(thermal_gap 0.5)
			(thermal_bridge_width 0.5)
			(island_removal_mode 0)
		)
		(polygon
			(pts
				(arc
					(start 75.023472 -351.611438)
					(mid 74.319892 -351.611438)
					(end 75.023472 -351.611438)
				)
			)
		)
	)
	(zone
		(layers "B.Cu" "In9.Cu" "In11.Cu" "In13.Cu" "In15.Cu")
		(hatch none 0.5)
		(connect_pads
			(clearance 0)
		)
		(min_thickness 0.25)
		(keepout
			(tracks not_allowed)
			(vias allowed)
			(pads allowed)
			(copperpour not_allowed)
			(footprints allowed)
		)
		(placement
			(enabled no)
			(sheetname "")
		)
		(fill yes
			(thermal_gap 0.5)
			(thermal_bridge_width 0.5)
			(island_removal_mode 0)
		)
		(polygon
			(pts
				(arc
					(start 73.276206 -312.999882)
					(mid 72.623426 -312.999882)
					(end 73.276206 -312.999882)
				)
			)
		)
	)
	(zone
		(layers "B.Cu" "In9.Cu" "In11.Cu" "In13.Cu" "In15.Cu")
		(hatch none 0.5)
		(connect_pads
			(clearance 0)
		)
		(min_thickness 0.25)
		(keepout
			(tracks not_allowed)
			(vias allowed)
			(pads allowed)
			(copperpour not_allowed)
			(footprints allowed)
		)
		(placement
			(enabled no)
			(sheetname "")
		)
		(fill yes
			(thermal_gap 0.5)
			(thermal_bridge_width 0.5)
			(island_removal_mode 0)
		)
		(polygon
			(pts
				(arc
					(start 179.87645 -312.999882)
					(mid 179.22367 -312.999882)
					(end 179.87645 -312.999882)
				)
			)
		)
	)
	(zone
		(layers "B.Cu" "In9.Cu" "In11.Cu" "In13.Cu" "In15.Cu")
		(hatch none 0.5)
		(connect_pads
			(clearance 0)
		)
		(min_thickness 0.25)
		(keepout
			(tracks not_allowed)
			(vias allowed)
			(pads allowed)
			(copperpour not_allowed)
			(footprints allowed)
		)
		(placement
			(enabled no)
			(sheetname "")
		)
		(fill yes
			(thermal_gap 0.5)
			(thermal_bridge_width 0.5)
			(island_removal_mode 0)
		)
		(polygon
			(pts
				(arc
					(start 50.47615 -274.049744)
					(mid 49.82337 -274.049744)
					(end 50.47615 -274.049744)
				)
			)
		)
	)
	(zone
		(layers "B.Cu" "In9.Cu" "In11.Cu" "In13.Cu" "In15.Cu")
		(hatch none 0.5)
		(connect_pads
			(clearance 0)
		)
		(min_thickness 0.25)
		(keepout
			(tracks not_allowed)
			(vias allowed)
			(pads allowed)
			(copperpour not_allowed)
			(footprints allowed)
		)
		(placement
			(enabled no)
			(sheetname "")
		)
		(fill yes
			(thermal_gap 0.5)
			(thermal_bridge_width 0.5)
			(island_removal_mode 0)
		)
		(polygon
			(pts
				(arc
					(start 169.089832 -397.790162)
					(mid 168.330372 -397.790162)
					(end 169.089832 -397.790162)
				)
			)
		)
	)
	(zone
		(layers "B.Cu" "In9.Cu" "In11.Cu" "In13.Cu" "In15.Cu")
		(hatch none 0.5)
		(connect_pads
			(clearance 0)
		)
		(min_thickness 0.25)
		(keepout
			(tracks not_allowed)
			(vias allowed)
			(pads allowed)
			(copperpour not_allowed)
			(footprints allowed)
		)
		(placement
			(enabled no)
			(sheetname "")
		)
		(fill yes
			(thermal_gap 0.5)
			(thermal_bridge_width 0.5)
			(island_removal_mode 0)
		)
		(polygon
			(pts
				(arc
					(start 66.626232 -311.099962)
					(mid 65.973452 -311.099962)
					(end 66.626232 -311.099962)
				)
			)
		)
	)
	(zone
		(layers "B.Cu" "In9.Cu" "In11.Cu" "In13.Cu" "In15.Cu")
		(hatch none 0.5)
		(connect_pads
			(clearance 0)
		)
		(min_thickness 0.25)
		(keepout
			(tracks not_allowed)
			(vias allowed)
			(pads allowed)
			(copperpour not_allowed)
			(footprints allowed)
		)
		(placement
			(enabled no)
			(sheetname "")
		)
		(fill yes
			(thermal_gap 0.5)
			(thermal_bridge_width 0.5)
			(island_removal_mode 0)
		)
		(polygon
			(pts
				(arc
					(start 270.326104 -314.899802)
					(mid 269.673324 -314.899802)
					(end 270.326104 -314.899802)
				)
			)
		)
	)
	(zone
		(layers "B.Cu" "In9.Cu" "In11.Cu" "In13.Cu" "In15.Cu")
		(hatch none 0.5)
		(connect_pads
			(clearance 0)
		)
		(min_thickness 0.25)
		(keepout
			(tracks not_allowed)
			(vias allowed)
			(pads allowed)
			(copperpour not_allowed)
			(footprints allowed)
		)
		(placement
			(enabled no)
			(sheetname "")
		)
		(fill yes
			(thermal_gap 0.5)
			(thermal_bridge_width 0.5)
			(island_removal_mode 0)
		)
		(polygon
			(pts
				(arc
					(start 32.120078 -348.58579)
					(mid 31.416498 -348.58579)
					(end 32.120078 -348.58579)
				)
			)
		)
	)
	(zone
		(layers "B.Cu" "In9.Cu" "In11.Cu" "In13.Cu" "In15.Cu")
		(hatch none 0.5)
		(connect_pads
			(clearance 0)
		)
		(min_thickness 0.25)
		(keepout
			(tracks not_allowed)
			(vias allowed)
			(pads allowed)
			(copperpour not_allowed)
			(footprints allowed)
		)
		(placement
			(enabled no)
			(sheetname "")
		)
		(fill yes
			(thermal_gap 0.5)
			(thermal_bridge_width 0.5)
			(island_removal_mode 0)
		)
		(polygon
			(pts
				(arc
					(start 192.226438 -304.449734)
					(mid 191.573658 -304.449734)
					(end 192.226438 -304.449734)
				)
			)
		)
	)
	(zone
		(layers "B.Cu" "In9.Cu" "In11.Cu" "In13.Cu" "In15.Cu")
		(hatch none 0.5)
		(connect_pads
			(clearance 0)
		)
		(min_thickness 0.25)
		(keepout
			(tracks not_allowed)
			(vias allowed)
			(pads allowed)
			(copperpour not_allowed)
			(footprints allowed)
		)
		(placement
			(enabled no)
			(sheetname "")
		)
		(fill yes
			(thermal_gap 0.5)
			(thermal_bridge_width 0.5)
			(island_removal_mode 0)
		)
		(polygon
			(pts
				(arc
					(start 201.662284 -33.65881)
					(mid 200.958704 -33.65881)
					(end 201.662284 -33.65881)
				)
			)
		)
	)
	(zone
		(layers "B.Cu" "In9.Cu" "In11.Cu" "In13.Cu" "In15.Cu")
		(hatch none 0.5)
		(connect_pads
			(clearance 0)
		)
		(min_thickness 0.25)
		(keepout
			(tracks not_allowed)
			(vias allowed)
			(pads allowed)
			(copperpour not_allowed)
			(footprints allowed)
		)
		(placement
			(enabled no)
			(sheetname "")
		)
		(fill yes
			(thermal_gap 0.5)
			(thermal_bridge_width 0.5)
			(island_removal_mode 0)
		)
		(polygon
			(pts
				(arc
					(start 174.176436 -273.099784)
					(mid 173.523656 -273.099784)
					(end 174.176436 -273.099784)
				)
			)
		)
	)
	(zone
		(layers "B.Cu" "In9.Cu" "In11.Cu" "In13.Cu" "In15.Cu")
		(hatch none 0.5)
		(connect_pads
			(clearance 0)
		)
		(min_thickness 0.25)
		(keepout
			(tracks not_allowed)
			(vias allowed)
			(pads allowed)
			(copperpour not_allowed)
			(footprints allowed)
		)
		(placement
			(enabled no)
			(sheetname "")
		)
		(fill yes
			(thermal_gap 0.5)
			(thermal_bridge_width 0.5)
			(island_removal_mode 0)
		)
		(polygon
			(pts
				(arc
					(start 131.689856 -405.390096)
					(mid 130.930396 -405.390096)
					(end 131.689856 -405.390096)
				)
			)
		)
	)
	(zone
		(layers "B.Cu" "In9.Cu" "In11.Cu" "In13.Cu" "In15.Cu")
		(hatch none 0.5)
		(connect_pads
			(clearance 0)
		)
		(min_thickness 0.25)
		(keepout
			(tracks not_allowed)
			(vias allowed)
			(pads allowed)
			(copperpour not_allowed)
			(footprints allowed)
		)
		(placement
			(enabled no)
			(sheetname "")
		)
		(fill yes
			(thermal_gap 0.5)
			(thermal_bridge_width 0.5)
			(island_removal_mode 0)
		)
		(polygon
			(pts
				(arc
					(start 424.42638 -304.449734)
					(mid 423.7736 -304.449734)
					(end 424.42638 -304.449734)
				)
			)
		)
	)
	(zone
		(layers "B.Cu" "In9.Cu" "In11.Cu" "In13.Cu" "In15.Cu")
		(hatch none 0.5)
		(connect_pads
			(clearance 0)
		)
		(min_thickness 0.25)
		(keepout
			(tracks not_allowed)
			(vias allowed)
			(pads allowed)
			(copperpour not_allowed)
			(footprints allowed)
		)
		(placement
			(enabled no)
			(sheetname "")
		)
		(fill yes
			(thermal_gap 0.5)
			(thermal_bridge_width 0.5)
			(island_removal_mode 0)
		)
		(polygon
			(pts
				(arc
					(start 406.376378 -274.049744)
					(mid 405.723598 -274.049744)
					(end 406.376378 -274.049744)
				)
			)
		)
	)
	(zone
		(layers "B.Cu" "In9.Cu" "In11.Cu" "In13.Cu" "In15.Cu")
		(hatch none 0.5)
		(connect_pads
			(clearance 0)
		)
		(min_thickness 0.25)
		(keepout
			(tracks not_allowed)
			(vias allowed)
			(pads allowed)
			(copperpour not_allowed)
			(footprints allowed)
		)
		(placement
			(enabled no)
			(sheetname "")
		)
		(fill yes
			(thermal_gap 0.5)
			(thermal_bridge_width 0.5)
			(island_removal_mode 0)
		)
		(polygon
			(pts
				(arc
					(start 277.575772 -342.439498)
					(mid 276.872192 -342.439498)
					(end 277.575772 -342.439498)
				)
			)
		)
	)
	(zone
		(layers "B.Cu" "In9.Cu" "In11.Cu" "In13.Cu" "In15.Cu")
		(hatch none 0.5)
		(connect_pads
			(clearance 0)
		)
		(min_thickness 0.25)
		(keepout
			(tracks not_allowed)
			(vias allowed)
			(pads allowed)
			(copperpour not_allowed)
			(footprints allowed)
		)
		(placement
			(enabled no)
			(sheetname "")
		)
		(fill yes
			(thermal_gap 0.5)
			(thermal_bridge_width 0.5)
			(island_removal_mode 0)
		)
		(polygon
			(pts
				(arc
					(start 269.376144 -312.049922)
					(mid 268.723364 -312.049922)
					(end 269.376144 -312.049922)
				)
			)
		)
	)
	(zone
		(layers "B.Cu" "In9.Cu" "In11.Cu" "In13.Cu" "In15.Cu")
		(hatch none 0.5)
		(connect_pads
			(clearance 0)
		)
		(min_thickness 0.25)
		(keepout
			(tracks not_allowed)
			(vias allowed)
			(pads allowed)
			(copperpour not_allowed)
			(footprints allowed)
		)
		(placement
			(enabled no)
			(sheetname "")
		)
		(fill yes
			(thermal_gap 0.5)
			(thermal_bridge_width 0.5)
			(island_removal_mode 0)
		)
		(polygon
			(pts
				(arc
					(start 116.186458 -342.439498)
					(mid 115.482878 -342.439498)
					(end 116.186458 -342.439498)
				)
			)
		)
	)
	(zone
		(layers "B.Cu" "In9.Cu" "In11.Cu" "In13.Cu" "In15.Cu")
		(hatch none 0.5)
		(connect_pads
			(clearance 0)
		)
		(min_thickness 0.25)
		(keepout
			(tracks not_allowed)
			(vias allowed)
			(pads allowed)
			(copperpour not_allowed)
			(footprints allowed)
		)
		(placement
			(enabled no)
			(sheetname "")
		)
		(fill yes
			(thermal_gap 0.5)
			(thermal_bridge_width 0.5)
			(island_removal_mode 0)
		)
		(polygon
			(pts
				(arc
					(start 325.290434 -348.58579)
					(mid 324.586854 -348.58579)
					(end 325.290434 -348.58579)
				)
			)
		)
	)
	(zone
		(layers "B.Cu" "In9.Cu" "In11.Cu" "In13.Cu" "In15.Cu")
		(hatch none 0.5)
		(connect_pads
			(clearance 0)
		)
		(min_thickness 0.25)
		(keepout
			(tracks not_allowed)
			(vias allowed)
			(pads allowed)
			(copperpour not_allowed)
			(footprints allowed)
		)
		(placement
			(enabled no)
			(sheetname "")
		)
		(fill yes
			(thermal_gap 0.5)
			(thermal_bridge_width 0.5)
			(island_removal_mode 0)
		)
		(polygon
			(pts
				(arc
					(start 130.867658 -348.58579)
					(mid 130.164078 -348.58579)
					(end 130.867658 -348.58579)
				)
			)
		)
	)
	(zone
		(layers "B.Cu" "In9.Cu" "In11.Cu" "In13.Cu" "In15.Cu")
		(hatch none 0.5)
		(connect_pads
			(clearance 0)
		)
		(min_thickness 0.25)
		(keepout
			(tracks not_allowed)
			(vias allowed)
			(pads allowed)
			(copperpour not_allowed)
			(footprints allowed)
		)
		(placement
			(enabled no)
			(sheetname "")
		)
		(fill yes
			(thermal_gap 0.5)
			(thermal_bridge_width 0.5)
			(island_removal_mode 0)
		)
		(polygon
			(pts
				(arc
					(start 173.48962 -397.790162)
					(mid 172.73016 -397.790162)
					(end 173.48962 -397.790162)
				)
			)
		)
	)
	(zone
		(layers "B.Cu" "In9.Cu" "In11.Cu" "In13.Cu" "In15.Cu")
		(hatch none 0.5)
		(connect_pads
			(clearance 0)
		)
		(min_thickness 0.25)
		(keepout
			(tracks not_allowed)
			(vias allowed)
			(pads allowed)
			(copperpour not_allowed)
			(footprints allowed)
		)
		(placement
			(enabled no)
			(sheetname "")
		)
		(fill yes
			(thermal_gap 0.5)
			(thermal_bridge_width 0.5)
			(island_removal_mode 0)
		)
		(polygon
			(pts
				(arc
					(start 241.616484 -32.722312)
					(mid 240.912904 -32.722312)
					(end 241.616484 -32.722312)
				)
			)
		)
	)
	(zone
		(layers "B.Cu" "In9.Cu" "In11.Cu" "In13.Cu" "In15.Cu")
		(hatch none 0.5)
		(connect_pads
			(clearance 0)
		)
		(min_thickness 0.25)
		(keepout
			(tracks not_allowed)
			(vias allowed)
			(pads allowed)
			(copperpour not_allowed)
			(footprints allowed)
		)
		(placement
			(enabled no)
			(sheetname "")
		)
		(fill yes
			(thermal_gap 0.5)
			(thermal_bridge_width 0.5)
			(island_removal_mode 0)
		)
		(polygon
			(pts
				(arc
					(start 296.926254 -312.049922)
					(mid 296.273474 -312.049922)
					(end 296.926254 -312.049922)
				)
			)
		)
	)
	(zone
		(layers "B.Cu" "In9.Cu" "In11.Cu" "In13.Cu" "In15.Cu")
		(hatch none 0.5)
		(connect_pads
			(clearance 0)
		)
		(min_thickness 0.25)
		(keepout
			(tracks not_allowed)
			(vias allowed)
			(pads allowed)
			(copperpour not_allowed)
			(footprints allowed)
		)
		(placement
			(enabled no)
			(sheetname "")
		)
		(fill yes
			(thermal_gap 0.5)
			(thermal_bridge_width 0.5)
			(island_removal_mode 0)
		)
		(polygon
			(pts
				(arc
					(start 276.976078 -274.049744)
					(mid 276.323298 -274.049744)
					(end 276.976078 -274.049744)
				)
			)
		)
	)
	(zone
		(layers "B.Cu" "In9.Cu" "In11.Cu" "In13.Cu" "In15.Cu")
		(hatch none 0.5)
		(connect_pads
			(clearance 0)
		)
		(min_thickness 0.25)
		(keepout
			(tracks not_allowed)
			(vias allowed)
			(pads allowed)
			(copperpour not_allowed)
			(footprints allowed)
		)
		(placement
			(enabled no)
			(sheetname "")
		)
		(fill yes
			(thermal_gap 0.5)
			(thermal_bridge_width 0.5)
			(island_removal_mode 0)
		)
		(polygon
			(pts
				(arc
					(start 54.276244 -274.049744)
					(mid 53.623464 -274.049744)
					(end 54.276244 -274.049744)
				)
			)
		)
	)
	(zone
		(layers "B.Cu" "In9.Cu" "In11.Cu" "In13.Cu" "In15.Cu")
		(hatch none 0.5)
		(connect_pads
			(clearance 0)
		)
		(min_thickness 0.25)
		(keepout
			(tracks not_allowed)
			(vias allowed)
			(pads allowed)
			(copperpour not_allowed)
			(footprints allowed)
		)
		(placement
			(enabled no)
			(sheetname "")
		)
		(fill yes
			(thermal_gap 0.5)
			(thermal_bridge_width 0.5)
			(island_removal_mode 0)
		)
		(polygon
			(pts
				(arc
					(start 29.011118 -357.75773)
					(mid 28.307538 -357.75773)
					(end 29.011118 -357.75773)
				)
			)
		)
	)
	(zone
		(layers "B.Cu" "In9.Cu" "In11.Cu" "In13.Cu" "In15.Cu")
		(hatch none 0.5)
		(connect_pads
			(clearance 0)
		)
		(min_thickness 0.25)
		(keepout
			(tracks not_allowed)
			(vias allowed)
			(pads allowed)
			(copperpour not_allowed)
			(footprints allowed)
		)
		(placement
			(enabled no)
			(sheetname "")
		)
		(fill yes
			(thermal_gap 0.5)
			(thermal_bridge_width 0.5)
			(island_removal_mode 0)
		)
		(polygon
			(pts
				(arc
					(start 87.416386 -29.12237)
					(mid 86.712806 -29.12237)
					(end 87.416386 -29.12237)
				)
			)
		)
	)
	(zone
		(layers "B.Cu" "In9.Cu" "In11.Cu" "In13.Cu" "In15.Cu")
		(hatch none 0.5)
		(connect_pads
			(clearance 0)
		)
		(min_thickness 0.25)
		(keepout
			(tracks not_allowed)
			(vias allowed)
			(pads allowed)
			(copperpour not_allowed)
			(footprints allowed)
		)
		(placement
			(enabled no)
			(sheetname "")
		)
		(fill yes
			(thermal_gap 0.5)
			(thermal_bridge_width 0.5)
			(island_removal_mode 0)
		)
		(polygon
			(pts
				(arc
					(start 357.716582 -32.722312)
					(mid 357.013002 -32.722312)
					(end 357.716582 -32.722312)
				)
			)
		)
	)
	(zone
		(layers "B.Cu" "In9.Cu" "In11.Cu" "In13.Cu" "In15.Cu")
		(hatch none 0.5)
		(connect_pads
			(clearance 0)
		)
		(min_thickness 0.25)
		(keepout
			(tracks not_allowed)
			(vias allowed)
			(pads allowed)
			(copperpour not_allowed)
			(footprints allowed)
		)
		(placement
			(enabled no)
			(sheetname "")
		)
		(fill yes
			(thermal_gap 0.5)
			(thermal_bridge_width 0.5)
			(island_removal_mode 0)
		)
		(polygon
			(pts
				(arc
					(start 287.86963 -374.390158)
					(mid 287.11017 -374.390158)
					(end 287.86963 -374.390158)
				)
			)
		)
	)
	(zone
		(layers "B.Cu" "In9.Cu" "In11.Cu" "In13.Cu" "In15.Cu")
		(hatch none 0.5)
		(connect_pads
			(clearance 0)
		)
		(min_thickness 0.25)
		(keepout
			(tracks not_allowed)
			(vias allowed)
			(pads allowed)
			(copperpour not_allowed)
			(footprints allowed)
		)
		(placement
			(enabled no)
			(sheetname "")
		)
		(fill yes
			(thermal_gap 0.5)
			(thermal_bridge_width 0.5)
			(island_removal_mode 0)
		)
		(polygon
			(pts
				(arc
					(start 61.724032 -348.58579)
					(mid 61.020452 -348.58579)
					(end 61.724032 -348.58579)
				)
			)
		)
	)
	(zone
		(layers "B.Cu" "In9.Cu" "In11.Cu" "In13.Cu" "In15.Cu")
		(hatch none 0.5)
		(connect_pads
			(clearance 0)
		)
		(min_thickness 0.25)
		(keepout
			(tracks not_allowed)
			(vias allowed)
			(pads allowed)
			(copperpour not_allowed)
			(footprints allowed)
		)
		(placement
			(enabled no)
			(sheetname "")
		)
		(fill yes
			(thermal_gap 0.5)
			(thermal_bridge_width 0.5)
			(island_removal_mode 0)
		)
		(polygon
			(pts
				(arc
					(start 177.516536 -29.12237)
					(mid 176.812956 -29.12237)
					(end 177.516536 -29.12237)
				)
			)
		)
	)
	(zone
		(layers "B.Cu" "In9.Cu" "In11.Cu" "In13.Cu" "In15.Cu")
		(hatch none 0.5)
		(connect_pads
			(clearance 0)
		)
		(min_thickness 0.25)
		(keepout
			(tracks not_allowed)
			(vias allowed)
			(pads allowed)
			(copperpour not_allowed)
			(footprints allowed)
		)
		(placement
			(enabled no)
			(sheetname "")
		)
		(fill yes
			(thermal_gap 0.5)
			(thermal_bridge_width 0.5)
			(island_removal_mode 0)
		)
		(polygon
			(pts
				(arc
					(start 413.026352 -311.099962)
					(mid 412.373572 -311.099962)
					(end 413.026352 -311.099962)
				)
			)
		)
	)
	(zone
		(layers "B.Cu" "In9.Cu" "In11.Cu" "In13.Cu" "In15.Cu")
		(hatch none 0.5)
		(connect_pads
			(clearance 0)
		)
		(min_thickness 0.25)
		(keepout
			(tracks not_allowed)
			(vias allowed)
			(pads allowed)
			(copperpour not_allowed)
			(footprints allowed)
		)
		(placement
			(enabled no)
			(sheetname "")
		)
		(fill yes
			(thermal_gap 0.5)
			(thermal_bridge_width 0.5)
			(island_removal_mode 0)
		)
		(polygon
			(pts
				(arc
					(start 57.126378 -275.949918)
					(mid 56.473598 -275.949918)
					(end 57.126378 -275.949918)
				)
			)
		)
	)
	(zone
		(layers "B.Cu" "In9.Cu" "In11.Cu" "In13.Cu" "In15.Cu")
		(hatch none 0.5)
		(connect_pads
			(clearance 0)
		)
		(min_thickness 0.25)
		(keepout
			(tracks not_allowed)
			(vias allowed)
			(pads allowed)
			(copperpour not_allowed)
			(footprints allowed)
		)
		(placement
			(enabled no)
			(sheetname "")
		)
		(fill yes
			(thermal_gap 0.5)
			(thermal_bridge_width 0.5)
			(island_removal_mode 0)
		)
		(polygon
			(pts
				(arc
					(start 292.269672 -400.390106)
					(mid 291.510212 -400.390106)
					(end 292.269672 -400.390106)
				)
			)
		)
	)
	(zone
		(layers "B.Cu" "In9.Cu" "In11.Cu" "In13.Cu" "In15.Cu")
		(hatch none 0.5)
		(connect_pads
			(clearance 0)
		)
		(min_thickness 0.25)
		(keepout
			(tracks not_allowed)
			(vias allowed)
			(pads allowed)
			(copperpour not_allowed)
			(footprints allowed)
		)
		(placement
			(enabled no)
			(sheetname "")
		)
		(fill yes
			(thermal_gap 0.5)
			(thermal_bridge_width 0.5)
			(island_removal_mode 0)
		)
		(polygon
			(pts
				(arc
					(start 59.562238 -34.52241)
					(mid 58.858658 -34.52241)
					(end 59.562238 -34.52241)
				)
			)
		)
	)
	(zone
		(layers "B.Cu" "In9.Cu" "In11.Cu" "In13.Cu" "In15.Cu")
		(hatch none 0.5)
		(connect_pads
			(clearance 0)
		)
		(min_thickness 0.25)
		(keepout
			(tracks not_allowed)
			(vias allowed)
			(pads allowed)
			(copperpour not_allowed)
			(footprints allowed)
		)
		(placement
			(enabled no)
			(sheetname "")
		)
		(fill yes
			(thermal_gap 0.5)
			(thermal_bridge_width 0.5)
			(island_removal_mode 0)
		)
		(polygon
			(pts
				(arc
					(start 116.289836 -405.589994)
					(mid 115.530376 -405.589994)
					(end 116.289836 -405.589994)
				)
			)
		)
	)
	(zone
		(layers "B.Cu" "In9.Cu" "In11.Cu" "In13.Cu" "In15.Cu")
		(hatch none 0.5)
		(connect_pads
			(clearance 0)
		)
		(min_thickness 0.25)
		(keepout
			(tracks not_allowed)
			(vias allowed)
			(pads allowed)
			(copperpour not_allowed)
			(footprints allowed)
		)
		(placement
			(enabled no)
			(sheetname "")
		)
		(fill yes
			(thermal_gap 0.5)
			(thermal_bridge_width 0.5)
			(island_removal_mode 0)
		)
		(polygon
			(pts
				(arc
					(start 43.689778 -376.790204)
					(mid 42.930318 -376.790204)
					(end 43.689778 -376.790204)
				)
			)
		)
	)
	(zone
		(layers "B.Cu" "In9.Cu" "In11.Cu" "In13.Cu" "In15.Cu")
		(hatch none 0.5)
		(connect_pads
			(clearance 0)
		)
		(min_thickness 0.25)
		(keepout
			(tracks not_allowed)
			(vias allowed)
			(pads allowed)
			(copperpour not_allowed)
			(footprints allowed)
		)
		(placement
			(enabled no)
			(sheetname "")
		)
		(fill yes
			(thermal_gap 0.5)
			(thermal_bridge_width 0.5)
			(island_removal_mode 0)
		)
		(polygon
			(pts
				(arc
					(start 275.076158 -307.299868)
					(mid 274.423378 -307.299868)
					(end 275.076158 -307.299868)
				)
			)
		)
	)
	(zone
		(layers "B.Cu" "In9.Cu" "In11.Cu" "In13.Cu" "In15.Cu")
		(hatch none 0.5)
		(connect_pads
			(clearance 0)
		)
		(min_thickness 0.25)
		(keepout
			(tracks not_allowed)
			(vias allowed)
			(pads allowed)
			(copperpour not_allowed)
			(footprints allowed)
		)
		(placement
			(enabled no)
			(sheetname "")
		)
		(fill yes
			(thermal_gap 0.5)
			(thermal_bridge_width 0.5)
			(island_removal_mode 0)
		)
		(polygon
			(pts
				(arc
					(start 425.191682 -354.732082)
					(mid 424.488102 -354.732082)
					(end 425.191682 -354.732082)
				)
			)
		)
	)
	(zone
		(layers "B.Cu" "In9.Cu" "In11.Cu" "In13.Cu" "In15.Cu")
		(hatch none 0.5)
		(connect_pads
			(clearance 0)
		)
		(min_thickness 0.25)
		(keepout
			(tracks not_allowed)
			(vias allowed)
			(pads allowed)
			(copperpour not_allowed)
			(footprints allowed)
		)
		(placement
			(enabled no)
			(sheetname "")
		)
		(fill yes
			(thermal_gap 0.5)
			(thermal_bridge_width 0.5)
			(island_removal_mode 0)
		)
		(polygon
			(pts
				(arc
					(start 169.619422 -348.58579)
					(mid 168.915842 -348.58579)
					(end 169.619422 -348.58579)
				)
			)
		)
	)
	(zone
		(layers "B.Cu" "In9.Cu" "In11.Cu" "In13.Cu" "In15.Cu")
		(hatch none 0.5)
		(connect_pads
			(clearance 0)
		)
		(min_thickness 0.25)
		(keepout
			(tracks not_allowed)
			(vias allowed)
			(pads allowed)
			(copperpour not_allowed)
			(footprints allowed)
		)
		(placement
			(enabled no)
			(sheetname "")
		)
		(fill yes
			(thermal_gap 0.5)
			(thermal_bridge_width 0.5)
			(island_removal_mode 0)
		)
		(polygon
			(pts
				(arc
					(start 141.058138 -342.439498)
					(mid 140.354558 -342.439498)
					(end 141.058138 -342.439498)
				)
			)
		)
	)
	(zone
		(layers "B.Cu" "In9.Cu" "In11.Cu" "In13.Cu" "In15.Cu")
		(hatch none 0.5)
		(connect_pads
			(clearance 0)
		)
		(min_thickness 0.25)
		(keepout
			(tracks not_allowed)
			(vias allowed)
			(pads allowed)
			(copperpour not_allowed)
			(footprints allowed)
		)
		(placement
			(enabled no)
			(sheetname "")
		)
		(fill yes
			(thermal_gap 0.5)
			(thermal_bridge_width 0.5)
			(island_removal_mode 0)
		)
		(polygon
			(pts
				(arc
					(start 125.08992 -383.490216)
					(mid 124.33046 -383.490216)
					(end 125.08992 -383.490216)
				)
			)
		)
	)
	(zone
		(layers "B.Cu" "In9.Cu" "In11.Cu" "In13.Cu" "In15.Cu")
		(hatch none 0.5)
		(connect_pads
			(clearance 0)
		)
		(min_thickness 0.25)
		(keepout
			(tracks not_allowed)
			(vias allowed)
			(pads allowed)
			(copperpour not_allowed)
			(footprints allowed)
		)
		(placement
			(enabled no)
			(sheetname "")
		)
		(fill yes
			(thermal_gap 0.5)
			(thermal_bridge_width 0.5)
			(island_removal_mode 0)
		)
		(polygon
			(pts
				(arc
					(start 30.489652 -401.49018)
					(mid 29.730192 -401.49018)
					(end 30.489652 -401.49018)
				)
			)
		)
	)
	(zone
		(layers "B.Cu" "In9.Cu" "In11.Cu" "In13.Cu" "In15.Cu")
		(hatch none 0.5)
		(connect_pads
			(clearance 0)
		)
		(min_thickness 0.25)
		(keepout
			(tracks not_allowed)
			(vias allowed)
			(pads allowed)
			(copperpour not_allowed)
			(footprints allowed)
		)
		(placement
			(enabled no)
			(sheetname "")
		)
		(fill yes
			(thermal_gap 0.5)
			(thermal_bridge_width 0.5)
			(island_removal_mode 0)
		)
		(polygon
			(pts
				(arc
					(start 372.40337 -351.611438)
					(mid 371.69979 -351.611438)
					(end 372.40337 -351.611438)
				)
			)
		)
	)
	(zone
		(layers "B.Cu" "In9.Cu" "In11.Cu" "In13.Cu" "In15.Cu")
		(hatch none 0.5)
		(connect_pads
			(clearance 0)
		)
		(min_thickness 0.25)
		(keepout
			(tracks not_allowed)
			(vias allowed)
			(pads allowed)
			(copperpour not_allowed)
			(footprints allowed)
		)
		(placement
			(enabled no)
			(sheetname "")
		)
		(fill yes
			(thermal_gap 0.5)
			(thermal_bridge_width 0.5)
			(island_removal_mode 0)
		)
		(polygon
			(pts
				(arc
					(start 275.076158 -309.199788)
					(mid 274.423378 -309.199788)
					(end 275.076158 -309.199788)
				)
			)
		)
	)
	(zone
		(layers "B.Cu" "In9.Cu" "In11.Cu" "In13.Cu" "In15.Cu")
		(hatch none 0.5)
		(connect_pads
			(clearance 0)
		)
		(min_thickness 0.25)
		(keepout
			(tracks not_allowed)
			(vias allowed)
			(pads allowed)
			(copperpour not_allowed)
			(footprints allowed)
		)
		(placement
			(enabled no)
			(sheetname "")
		)
		(fill yes
			(thermal_gap 0.5)
			(thermal_bridge_width 0.5)
			(island_removal_mode 0)
		)
		(polygon
			(pts
				(arc
					(start 40.976296 -312.999882)
					(mid 40.323516 -312.999882)
					(end 40.976296 -312.999882)
				)
			)
		)
	)
	(zone
		(layers "B.Cu" "In9.Cu" "In11.Cu" "In13.Cu" "In15.Cu")
		(hatch none 0.5)
		(connect_pads
			(clearance 0)
		)
		(min_thickness 0.25)
		(keepout
			(tracks not_allowed)
			(vias allowed)
			(pads allowed)
			(copperpour not_allowed)
			(footprints allowed)
		)
		(placement
			(enabled no)
			(sheetname "")
		)
		(fill yes
			(thermal_gap 0.5)
			(thermal_bridge_width 0.5)
			(island_removal_mode 0)
		)
		(polygon
			(pts
				(arc
					(start 423.47642 -306.349908)
					(mid 422.82364 -306.349908)
					(end 423.47642 -306.349908)
				)
			)
		)
	)
	(zone
		(layers "B.Cu" "In9.Cu" "In11.Cu" "In13.Cu" "In15.Cu")
		(hatch none 0.5)
		(connect_pads
			(clearance 0)
		)
		(min_thickness 0.25)
		(keepout
			(tracks not_allowed)
			(vias allowed)
			(pads allowed)
			(copperpour not_allowed)
			(footprints allowed)
		)
		(placement
			(enabled no)
			(sheetname "")
		)
		(fill yes
			(thermal_gap 0.5)
			(thermal_bridge_width 0.5)
			(island_removal_mode 0)
		)
		(polygon
			(pts
				(arc
					(start 419.837362 -354.732082)
					(mid 419.133782 -354.732082)
					(end 419.837362 -354.732082)
				)
			)
		)
	)
	(zone
		(layers "B.Cu" "In9.Cu" "In11.Cu" "In13.Cu" "In15.Cu")
		(hatch none 0.5)
		(connect_pads
			(clearance 0)
		)
		(min_thickness 0.25)
		(keepout
			(tracks not_allowed)
			(vias allowed)
			(pads allowed)
			(copperpour not_allowed)
			(footprints allowed)
		)
		(placement
			(enabled no)
			(sheetname "")
		)
		(fill yes
			(thermal_gap 0.5)
			(thermal_bridge_width 0.5)
			(island_removal_mode 0)
		)
		(polygon
			(pts
				(arc
					(start 65.696592 -354.732082)
					(mid 64.993012 -354.732082)
					(end 65.696592 -354.732082)
				)
			)
		)
	)
	(zone
		(layers "B.Cu" "In9.Cu" "In11.Cu" "In13.Cu" "In15.Cu")
		(hatch none 0.5)
		(connect_pads
			(clearance 0)
		)
		(min_thickness 0.25)
		(keepout
			(tracks not_allowed)
			(vias allowed)
			(pads allowed)
			(copperpour not_allowed)
			(footprints allowed)
		)
		(placement
			(enabled no)
			(sheetname "")
		)
		(fill yes
			(thermal_gap 0.5)
			(thermal_bridge_width 0.5)
			(island_removal_mode 0)
		)
		(polygon
			(pts
				(arc
					(start 74.489564 -380.69012)
					(mid 73.730104 -380.69012)
					(end 74.489564 -380.69012)
				)
			)
		)
	)
	(zone
		(layers "B.Cu" "In9.Cu" "In11.Cu" "In13.Cu" "In15.Cu")
		(hatch none 0.5)
		(connect_pads
			(clearance 0)
		)
		(min_thickness 0.25)
		(keepout
			(tracks not_allowed)
			(vias allowed)
			(pads allowed)
			(copperpour not_allowed)
			(footprints allowed)
		)
		(placement
			(enabled no)
			(sheetname "")
		)
		(fill yes
			(thermal_gap 0.5)
			(thermal_bridge_width 0.5)
			(island_removal_mode 0)
		)
		(polygon
			(pts
				(arc
					(start 122.889772 -383.290064)
					(mid 122.130312 -383.290064)
					(end 122.889772 -383.290064)
				)
			)
		)
	)
	(zone
		(layers "B.Cu" "In9.Cu" "In11.Cu" "In13.Cu" "In15.Cu")
		(hatch none 0.5)
		(connect_pads
			(clearance 0)
		)
		(min_thickness 0.25)
		(keepout
			(tracks not_allowed)
			(vias allowed)
			(pads allowed)
			(copperpour not_allowed)
			(footprints allowed)
		)
		(placement
			(enabled no)
			(sheetname "")
		)
		(fill yes
			(thermal_gap 0.5)
			(thermal_bridge_width 0.5)
			(island_removal_mode 0)
		)
		(polygon
			(pts
				(arc
					(start 335.480914 -354.732082)
					(mid 334.777334 -354.732082)
					(end 335.480914 -354.732082)
				)
			)
		)
	)
	(zone
		(layers "B.Cu" "In9.Cu" "In11.Cu" "In13.Cu" "In15.Cu")
		(hatch none 0.5)
		(connect_pads
			(clearance 0)
		)
		(min_thickness 0.25)
		(keepout
			(tracks not_allowed)
			(vias allowed)
			(pads allowed)
			(copperpour not_allowed)
			(footprints allowed)
		)
		(placement
			(enabled no)
			(sheetname "")
		)
		(fill yes
			(thermal_gap 0.5)
			(thermal_bridge_width 0.5)
			(island_removal_mode 0)
		)
		(polygon
			(pts
				(arc
					(start 160.289748 -397.790162)
					(mid 159.530288 -397.790162)
					(end 160.289748 -397.790162)
				)
			)
		)
	)
	(zone
		(layers "B.Cu" "In9.Cu" "In11.Cu" "In13.Cu" "In15.Cu")
		(hatch none 0.5)
		(connect_pads
			(clearance 0)
		)
		(min_thickness 0.25)
		(keepout
			(tracks not_allowed)
			(vias allowed)
			(pads allowed)
			(copperpour not_allowed)
			(footprints allowed)
		)
		(placement
			(enabled no)
			(sheetname "")
		)
		(fill yes
			(thermal_gap 0.5)
			(thermal_bridge_width 0.5)
			(island_removal_mode 0)
		)
		(polygon
			(pts
				(arc
					(start 338.469732 -405.390096)
					(mid 337.710272 -405.390096)
					(end 338.469732 -405.390096)
				)
			)
		)
	)
	(zone
		(layers "B.Cu" "In9.Cu" "In11.Cu" "In13.Cu" "In15.Cu")
		(hatch none 0.5)
		(connect_pads
			(clearance 0)
		)
		(min_thickness 0.25)
		(keepout
			(tracks not_allowed)
			(vias allowed)
			(pads allowed)
			(copperpour not_allowed)
			(footprints allowed)
		)
		(placement
			(enabled no)
			(sheetname "")
		)
		(fill yes
			(thermal_gap 0.5)
			(thermal_bridge_width 0.5)
			(island_removal_mode 0)
		)
		(polygon
			(pts
				(arc
					(start 116.186458 -354.732082)
					(mid 115.482878 -354.732082)
					(end 116.186458 -354.732082)
				)
			)
		)
	)
	(zone
		(layers "B.Cu" "In9.Cu" "In11.Cu" "In13.Cu" "In15.Cu")
		(hatch none 0.5)
		(connect_pads
			(clearance 0)
		)
		(min_thickness 0.25)
		(keepout
			(tracks not_allowed)
			(vias allowed)
			(pads allowed)
			(copperpour not_allowed)
			(footprints allowed)
		)
		(placement
			(enabled no)
			(sheetname "")
		)
		(fill yes
			(thermal_gap 0.5)
			(thermal_bridge_width 0.5)
			(island_removal_mode 0)
		)
		(polygon
			(pts
				(arc
					(start 384.83921 -351.611438)
					(mid 384.13563 -351.611438)
					(end 384.83921 -351.611438)
				)
			)
		)
	)
	(zone
		(layers "B.Cu" "In9.Cu" "In11.Cu" "In13.Cu" "In15.Cu")
		(hatch none 0.5)
		(connect_pads
			(clearance 0)
		)
		(min_thickness 0.25)
		(keepout
			(tracks not_allowed)
			(vias allowed)
			(pads allowed)
			(copperpour not_allowed)
			(footprints allowed)
		)
		(placement
			(enabled no)
			(sheetname "")
		)
		(fill yes
			(thermal_gap 0.5)
			(thermal_bridge_width 0.5)
			(island_removal_mode 0)
		)
		(polygon
			(pts
				(arc
					(start 64.726312 -311.099962)
					(mid 64.073532 -311.099962)
					(end 64.726312 -311.099962)
				)
			)
		)
	)
	(zone
		(layers "B.Cu" "In9.Cu" "In11.Cu" "In13.Cu" "In15.Cu")
		(hatch none 0.5)
		(connect_pads
			(clearance 0)
		)
		(min_thickness 0.25)
		(keepout
			(tracks not_allowed)
			(vias allowed)
			(pads allowed)
			(copperpour not_allowed)
			(footprints allowed)
		)
		(placement
			(enabled no)
			(sheetname "")
		)
		(fill yes
			(thermal_gap 0.5)
			(thermal_bridge_width 0.5)
			(island_removal_mode 0)
		)
		(polygon
			(pts
				(arc
					(start 76.689712 -378.290074)
					(mid 75.930252 -378.290074)
					(end 76.689712 -378.290074)
				)
			)
		)
	)
	(zone
		(layers "B.Cu" "In9.Cu" "In11.Cu" "In13.Cu" "In15.Cu")
		(hatch none 0.5)
		(connect_pads
			(clearance 0)
		)
		(min_thickness 0.25)
		(keepout
			(tracks not_allowed)
			(vias allowed)
			(pads allowed)
			(copperpour not_allowed)
			(footprints allowed)
		)
		(placement
			(enabled no)
			(sheetname "")
		)
		(fill yes
			(thermal_gap 0.5)
			(thermal_bridge_width 0.5)
			(island_removal_mode 0)
		)
		(polygon
			(pts
				(arc
					(start 166.576248 -274.049744)
					(mid 165.923468 -274.049744)
					(end 166.576248 -274.049744)
				)
			)
		)
	)
	(zone
		(layers "B.Cu" "In9.Cu" "In11.Cu" "In13.Cu" "In15.Cu")
		(hatch none 0.5)
		(connect_pads
			(clearance 0)
		)
		(min_thickness 0.25)
		(keepout
			(tracks not_allowed)
			(vias allowed)
			(pads allowed)
			(copperpour not_allowed)
			(footprints allowed)
		)
		(placement
			(enabled no)
			(sheetname "")
		)
		(fill yes
			(thermal_gap 0.5)
			(thermal_bridge_width 0.5)
			(island_removal_mode 0)
		)
		(polygon
			(pts
				(arc
					(start 329.964288 8.548624)
					(mid 329.260708 8.548624)
					(end 329.964288 8.548624)
				)
			)
		)
	)
	(zone
		(layers "B.Cu" "In9.Cu" "In11.Cu" "In13.Cu" "In15.Cu")
		(hatch none 0.5)
		(connect_pads
			(clearance 0)
		)
		(min_thickness 0.25)
		(keepout
			(tracks not_allowed)
			(vias allowed)
			(pads allowed)
			(copperpour not_allowed)
			(footprints allowed)
		)
		(placement
			(enabled no)
			(sheetname "")
		)
		(fill yes
			(thermal_gap 0.5)
			(thermal_bridge_width 0.5)
			(island_removal_mode 0)
		)
		(polygon
			(pts
				(arc
					(start 123.66244 -30.922468)
					(mid 122.95886 -30.922468)
					(end 123.66244 -30.922468)
				)
			)
		)
	)
	(zone
		(layers "B.Cu" "In9.Cu" "In11.Cu" "In13.Cu" "In15.Cu")
		(hatch none 0.5)
		(connect_pads
			(clearance 0)
		)
		(min_thickness 0.25)
		(keepout
			(tracks not_allowed)
			(vias allowed)
			(pads allowed)
			(copperpour not_allowed)
			(footprints allowed)
		)
		(placement
			(enabled no)
			(sheetname "")
		)
		(fill yes
			(thermal_gap 0.5)
			(thermal_bridge_width 0.5)
			(island_removal_mode 0)
		)
		(polygon
			(pts
				(arc
					(start 65.676272 -312.999882)
					(mid 65.023492 -312.999882)
					(end 65.676272 -312.999882)
				)
			)
		)
	)
	(zone
		(layers "B.Cu" "In9.Cu" "In11.Cu" "In13.Cu" "In15.Cu")
		(hatch none 0.5)
		(connect_pads
			(clearance 0)
		)
		(min_thickness 0.25)
		(keepout
			(tracks not_allowed)
			(vias allowed)
			(pads allowed)
			(copperpour not_allowed)
			(footprints allowed)
		)
		(placement
			(enabled no)
			(sheetname "")
		)
		(fill yes
			(thermal_gap 0.5)
			(thermal_bridge_width 0.5)
			(island_removal_mode 0)
		)
		(polygon
			(pts
				(arc
					(start 342.869774 -380.69012)
					(mid 342.110314 -380.69012)
					(end 342.869774 -380.69012)
				)
			)
		)
	)
	(zone
		(layers "B.Cu" "In9.Cu" "In11.Cu" "In13.Cu" "In15.Cu")
		(hatch none 0.5)
		(connect_pads
			(clearance 0)
		)
		(min_thickness 0.25)
		(keepout
			(tracks not_allowed)
			(vias allowed)
			(pads allowed)
			(copperpour not_allowed)
			(footprints allowed)
		)
		(placement
			(enabled no)
			(sheetname "")
		)
		(fill yes
			(thermal_gap 0.5)
			(thermal_bridge_width 0.5)
			(island_removal_mode 0)
		)
		(polygon
			(pts
				(arc
					(start 342.869774 -379.390148)
					(mid 342.110314 -379.390148)
					(end 342.869774 -379.390148)
				)
			)
		)
	)
	(zone
		(layers "B.Cu" "In9.Cu" "In11.Cu" "In13.Cu" "In15.Cu")
		(hatch none 0.5)
		(connect_pads
			(clearance 0)
		)
		(min_thickness 0.25)
		(keepout
			(tracks not_allowed)
			(vias allowed)
			(pads allowed)
			(copperpour not_allowed)
			(footprints allowed)
		)
		(placement
			(enabled no)
			(sheetname "")
		)
		(fill yes
			(thermal_gap 0.5)
			(thermal_bridge_width 0.5)
			(island_removal_mode 0)
		)
		(polygon
			(pts
				(arc
					(start 435.382162 -348.58579)
					(mid 434.678582 -348.58579)
					(end 435.382162 -348.58579)
				)
			)
		)
	)
	(zone
		(layers "B.Cu" "In9.Cu" "In11.Cu" "In13.Cu" "In15.Cu")
		(hatch none 0.5)
		(connect_pads
			(clearance 0)
		)
		(min_thickness 0.25)
		(keepout
			(tracks not_allowed)
			(vias allowed)
			(pads allowed)
			(copperpour not_allowed)
			(footprints allowed)
		)
		(placement
			(enabled no)
			(sheetname "")
		)
		(fill yes
			(thermal_gap 0.5)
			(thermal_bridge_width 0.5)
			(island_removal_mode 0)
		)
		(polygon
			(pts
				(arc
					(start 83.289648 -406.690068)
					(mid 82.530188 -406.690068)
					(end 83.289648 -406.690068)
				)
			)
		)
	)
	(zone
		(layers "B.Cu" "In9.Cu" "In11.Cu" "In13.Cu" "In15.Cu")
		(hatch none 0.5)
		(connect_pads
			(clearance 0)
		)
		(min_thickness 0.25)
		(keepout
			(tracks not_allowed)
			(vias allowed)
			(pads allowed)
			(copperpour not_allowed)
			(footprints allowed)
		)
		(placement
			(enabled no)
			(sheetname "")
		)
		(fill yes
			(thermal_gap 0.5)
			(thermal_bridge_width 0.5)
			(island_removal_mode 0)
		)
		(polygon
			(pts
				(arc
					(start 54.276244 -273.099784)
					(mid 53.623464 -273.099784)
					(end 54.276244 -273.099784)
				)
			)
		)
	)
	(zone
		(layers "B.Cu" "In9.Cu" "In11.Cu" "In13.Cu" "In15.Cu")
		(hatch none 0.5)
		(connect_pads
			(clearance 0)
		)
		(min_thickness 0.25)
		(keepout
			(tracks not_allowed)
			(vias allowed)
			(pads allowed)
			(copperpour not_allowed)
			(footprints allowed)
		)
		(placement
			(enabled no)
			(sheetname "")
		)
		(fill yes
			(thermal_gap 0.5)
			(thermal_bridge_width 0.5)
			(island_removal_mode 0)
		)
		(polygon
			(pts
				(arc
					(start 340.835234 -354.732082)
					(mid 340.131654 -354.732082)
					(end 340.835234 -354.732082)
				)
			)
		)
	)
	(zone
		(layers "B.Cu" "In9.Cu" "In11.Cu" "In13.Cu" "In15.Cu")
		(hatch none 0.5)
		(connect_pads
			(clearance 0)
		)
		(min_thickness 0.25)
		(keepout
			(tracks not_allowed)
			(vias allowed)
			(pads allowed)
			(copperpour not_allowed)
			(footprints allowed)
		)
		(placement
			(enabled no)
			(sheetname "")
		)
		(fill yes
			(thermal_gap 0.5)
			(thermal_bridge_width 0.5)
			(island_removal_mode 0)
		)
		(polygon
			(pts
				(arc
					(start 404.476204 -273.099784)
					(mid 403.823424 -273.099784)
					(end 404.476204 -273.099784)
				)
			)
		)
	)
	(zone
		(layers "B.Cu" "In9.Cu" "In11.Cu" "In13.Cu" "In15.Cu")
		(hatch none 0.5)
		(connect_pads
			(clearance 0)
		)
		(min_thickness 0.25)
		(keepout
			(tracks not_allowed)
			(vias allowed)
			(pads allowed)
			(copperpour not_allowed)
			(footprints allowed)
		)
		(placement
			(enabled no)
			(sheetname "")
		)
		(fill yes
			(thermal_gap 0.5)
			(thermal_bridge_width 0.5)
			(island_removal_mode 0)
		)
		(polygon
			(pts
				(arc
					(start 425.37634 -305.399948)
					(mid 424.72356 -305.399948)
					(end 425.37634 -305.399948)
				)
			)
		)
	)
	(zone
		(layers "B.Cu" "In9.Cu" "In11.Cu" "In13.Cu" "In15.Cu")
		(hatch none 0.5)
		(connect_pads
			(clearance 0)
		)
		(min_thickness 0.25)
		(keepout
			(tracks not_allowed)
			(vias allowed)
			(pads allowed)
			(copperpour not_allowed)
			(footprints allowed)
		)
		(placement
			(enabled no)
			(sheetname "")
		)
		(fill yes
			(thermal_gap 0.5)
			(thermal_bridge_width 0.5)
			(island_removal_mode 0)
		)
		(polygon
			(pts
				(arc
					(start 41.48963 -400.390106)
					(mid 40.73017 -400.390106)
					(end 41.48963 -400.390106)
				)
			)
		)
	)
	(zone
		(layers "B.Cu" "In9.Cu" "In11.Cu" "In13.Cu" "In15.Cu")
		(hatch none 0.5)
		(connect_pads
			(clearance 0)
		)
		(min_thickness 0.25)
		(keepout
			(tracks not_allowed)
			(vias allowed)
			(pads allowed)
			(copperpour not_allowed)
			(footprints allowed)
		)
		(placement
			(enabled no)
			(sheetname "")
		)
		(fill yes
			(thermal_gap 0.5)
			(thermal_bridge_width 0.5)
			(island_removal_mode 0)
		)
		(polygon
			(pts
				(arc
					(start 284.657292 -342.439498)
					(mid 283.953712 -342.439498)
					(end 284.657292 -342.439498)
				)
			)
		)
	)
	(zone
		(layers "B.Cu" "In9.Cu" "In11.Cu" "In13.Cu" "In15.Cu")
		(hatch none 0.5)
		(connect_pads
			(clearance 0)
		)
		(min_thickness 0.25)
		(keepout
			(tracks not_allowed)
			(vias allowed)
			(pads allowed)
			(copperpour not_allowed)
			(footprints allowed)
		)
		(placement
			(enabled no)
			(sheetname "")
		)
		(fill yes
			(thermal_gap 0.5)
			(thermal_bridge_width 0.5)
			(island_removal_mode 0)
		)
		(polygon
			(pts
				(arc
					(start 122.404378 -342.439498)
					(mid 121.700798 -342.439498)
					(end 122.404378 -342.439498)
				)
			)
		)
	)
	(zone
		(layers "B.Cu" "In9.Cu" "In11.Cu" "In13.Cu" "In15.Cu")
		(hatch none 0.5)
		(connect_pads
			(clearance 0)
		)
		(min_thickness 0.25)
		(keepout
			(tracks not_allowed)
			(vias allowed)
			(pads allowed)
			(copperpour not_allowed)
			(footprints allowed)
		)
		(placement
			(enabled no)
			(sheetname "")
		)
		(fill yes
			(thermal_gap 0.5)
			(thermal_bridge_width 0.5)
			(island_removal_mode 0)
		)
		(polygon
			(pts
				(arc
					(start 59.562238 -30.058868)
					(mid 58.858658 -30.058868)
					(end 59.562238 -30.058868)
				)
			)
		)
	)
	(zone
		(layers "B.Cu" "In9.Cu" "In11.Cu" "In13.Cu" "In15.Cu")
		(hatch none 0.5)
		(connect_pads
			(clearance 0)
		)
		(min_thickness 0.25)
		(keepout
			(tracks not_allowed)
			(vias allowed)
			(pads allowed)
			(copperpour not_allowed)
			(footprints allowed)
		)
		(placement
			(enabled no)
			(sheetname "")
		)
		(fill yes
			(thermal_gap 0.5)
			(thermal_bridge_width 0.5)
			(island_removal_mode 0)
		)
		(polygon
			(pts
				(arc
					(start 35.229038 -342.439498)
					(mid 34.525458 -342.439498)
					(end 35.229038 -342.439498)
				)
			)
		)
	)
	(zone
		(layers "B.Cu" "In9.Cu" "In11.Cu" "In13.Cu" "In15.Cu")
		(hatch none 0.5)
		(connect_pads
			(clearance 0)
		)
		(min_thickness 0.25)
		(keepout
			(tracks not_allowed)
			(vias allowed)
			(pads allowed)
			(copperpour not_allowed)
			(footprints allowed)
		)
		(placement
			(enabled no)
			(sheetname "")
		)
		(fill yes
			(thermal_gap 0.5)
			(thermal_bridge_width 0.5)
			(island_removal_mode 0)
		)
		(polygon
			(pts
				(arc
					(start 283.793692 -342.439498)
					(mid 283.090112 -342.439498)
					(end 283.793692 -342.439498)
				)
			)
		)
	)
	(zone
		(layers "B.Cu" "In9.Cu" "In11.Cu" "In13.Cu" "In15.Cu")
		(hatch none 0.5)
		(connect_pads
			(clearance 0)
		)
		(min_thickness 0.25)
		(keepout
			(tracks not_allowed)
			(vias allowed)
			(pads allowed)
			(copperpour not_allowed)
			(footprints allowed)
		)
		(placement
			(enabled no)
			(sheetname "")
		)
		(fill yes
			(thermal_gap 0.5)
			(thermal_bridge_width 0.5)
			(island_removal_mode 0)
		)
		(polygon
			(pts
				(arc
					(start 377.75769 -351.611438)
					(mid 377.05411 -351.611438)
					(end 377.75769 -351.611438)
				)
			)
		)
	)
	(zone
		(layers "B.Cu" "In9.Cu" "In11.Cu" "In13.Cu" "In15.Cu")
		(hatch none 0.5)
		(connect_pads
			(clearance 0)
		)
		(min_thickness 0.25)
		(keepout
			(tracks not_allowed)
			(vias allowed)
			(pads allowed)
			(copperpour not_allowed)
			(footprints allowed)
		)
		(placement
			(enabled no)
			(sheetname "")
		)
		(fill yes
			(thermal_gap 0.5)
			(thermal_bridge_width 0.5)
			(island_removal_mode 0)
		)
		(polygon
			(pts
				(arc
					(start 416.728402 -351.611438)
					(mid 416.024822 -351.611438)
					(end 416.728402 -351.611438)
				)
			)
		)
	)
	(zone
		(layers "B.Cu" "In9.Cu" "In11.Cu" "In13.Cu" "In15.Cu")
		(hatch none 0.5)
		(connect_pads
			(clearance 0)
		)
		(min_thickness 0.25)
		(keepout
			(tracks not_allowed)
			(vias allowed)
			(pads allowed)
			(copperpour not_allowed)
			(footprints allowed)
		)
		(placement
			(enabled no)
			(sheetname "")
		)
		(fill yes
			(thermal_gap 0.5)
			(thermal_bridge_width 0.5)
			(island_removal_mode 0)
		)
		(polygon
			(pts
				(arc
					(start 169.426382 -311.099962)
					(mid 168.773602 -311.099962)
					(end 169.426382 -311.099962)
				)
			)
		)
	)
	(zone
		(layers "B.Cu" "In9.Cu" "In11.Cu" "In13.Cu" "In15.Cu")
		(hatch none 0.5)
		(connect_pads
			(clearance 0)
		)
		(min_thickness 0.25)
		(keepout
			(tracks not_allowed)
			(vias allowed)
			(pads allowed)
			(copperpour not_allowed)
			(footprints allowed)
		)
		(placement
			(enabled no)
			(sheetname "")
		)
		(fill yes
			(thermal_gap 0.5)
			(thermal_bridge_width 0.5)
			(island_removal_mode 0)
		)
		(polygon
			(pts
				(arc
					(start 42.310558 -354.732082)
					(mid 41.606978 -354.732082)
					(end 42.310558 -354.732082)
				)
			)
		)
	)
	(zone
		(layers "B.Cu" "In9.Cu" "In11.Cu" "In13.Cu" "In15.Cu")
		(hatch none 0.5)
		(connect_pads
			(clearance 0)
		)
		(min_thickness 0.25)
		(keepout
			(tracks not_allowed)
			(vias allowed)
			(pads allowed)
			(copperpour not_allowed)
			(footprints allowed)
		)
		(placement
			(enabled no)
			(sheetname "")
		)
		(fill yes
			(thermal_gap 0.5)
			(thermal_bridge_width 0.5)
			(island_removal_mode 0)
		)
		(polygon
			(pts
				(arc
					(start 409.226258 -311.099962)
					(mid 408.573478 -311.099962)
					(end 409.226258 -311.099962)
				)
			)
		)
	)
	(zone
		(layers "B.Cu" "In9.Cu" "In11.Cu" "In13.Cu" "In15.Cu")
		(hatch none 0.5)
		(connect_pads
			(clearance 0)
		)
		(min_thickness 0.25)
		(keepout
			(tracks not_allowed)
			(vias allowed)
			(pads allowed)
			(copperpour not_allowed)
			(footprints allowed)
		)
		(placement
			(enabled no)
			(sheetname "")
		)
		(fill yes
			(thermal_gap 0.5)
			(thermal_bridge_width 0.5)
			(island_removal_mode 0)
		)
		(polygon
			(pts
				(arc
					(start 121.540778 -354.732082)
					(mid 120.837198 -354.732082)
					(end 121.540778 -354.732082)
				)
			)
		)
	)
	(zone
		(layers "B.Cu" "In9.Cu" "In11.Cu" "In13.Cu" "In15.Cu")
		(hatch none 0.5)
		(connect_pads
			(clearance 0)
		)
		(min_thickness 0.25)
		(keepout
			(tracks not_allowed)
			(vias allowed)
			(pads allowed)
			(copperpour not_allowed)
			(footprints allowed)
		)
		(placement
			(enabled no)
			(sheetname "")
		)
		(fill yes
			(thermal_gap 0.5)
			(thermal_bridge_width 0.5)
			(island_removal_mode 0)
		)
		(polygon
			(pts
				(arc
					(start 169.619422 -351.611438)
					(mid 168.915842 -351.611438)
					(end 169.619422 -351.611438)
				)
			)
		)
	)
	(zone
		(layers "B.Cu" "In9.Cu" "In11.Cu" "In13.Cu" "In15.Cu")
		(hatch none 0.5)
		(connect_pads
			(clearance 0)
		)
		(min_thickness 0.25)
		(keepout
			(tracks not_allowed)
			(vias allowed)
			(pads allowed)
			(copperpour not_allowed)
			(footprints allowed)
		)
		(placement
			(enabled no)
			(sheetname "")
		)
		(fill yes
			(thermal_gap 0.5)
			(thermal_bridge_width 0.5)
			(island_removal_mode 0)
		)
		(polygon
			(pts
				(arc
					(start 328.399394 -354.732082)
					(mid 327.695814 -354.732082)
					(end 328.399394 -354.732082)
				)
			)
		)
	)
	(zone
		(layers "B.Cu" "In9.Cu" "In11.Cu" "In13.Cu" "In15.Cu")
		(hatch none 0.5)
		(connect_pads
			(clearance 0)
		)
		(min_thickness 0.25)
		(keepout
			(tracks not_allowed)
			(vias allowed)
			(pads allowed)
			(copperpour not_allowed)
			(footprints allowed)
		)
		(placement
			(enabled no)
			(sheetname "")
		)
		(fill yes
			(thermal_gap 0.5)
			(thermal_bridge_width 0.5)
			(island_removal_mode 0)
		)
		(polygon
			(pts
				(arc
					(start 36.092638 -357.75773)
					(mid 35.389058 -357.75773)
					(end 36.092638 -357.75773)
				)
			)
		)
	)
	(zone
		(layers "B.Cu" "In9.Cu" "In11.Cu" "In13.Cu" "In15.Cu")
		(hatch none 0.5)
		(connect_pads
			(clearance 0)
		)
		(min_thickness 0.25)
		(keepout
			(tracks not_allowed)
			(vias allowed)
			(pads allowed)
			(copperpour not_allowed)
			(footprints allowed)
		)
		(placement
			(enabled no)
			(sheetname "")
		)
		(fill yes
			(thermal_gap 0.5)
			(thermal_bridge_width 0.5)
			(island_removal_mode 0)
		)
		(polygon
			(pts
				(arc
					(start 319.936114 -348.58579)
					(mid 319.232534 -348.58579)
					(end 319.936114 -348.58579)
				)
			)
		)
	)
	(zone
		(layers "B.Cu" "In9.Cu" "In11.Cu" "In13.Cu" "In15.Cu")
		(hatch none 0.5)
		(connect_pads
			(clearance 0)
		)
		(min_thickness 0.25)
		(keepout
			(tracks not_allowed)
			(vias allowed)
			(pads allowed)
			(copperpour not_allowed)
			(footprints allowed)
		)
		(placement
			(enabled no)
			(sheetname "")
		)
		(fill yes
			(thermal_gap 0.5)
			(thermal_bridge_width 0.5)
			(island_removal_mode 0)
		)
		(polygon
			(pts
				(arc
					(start 40.026336 -311.099962)
					(mid 39.373556 -311.099962)
					(end 40.026336 -311.099962)
				)
			)
		)
	)
	(zone
		(layers "B.Cu" "In9.Cu" "In11.Cu" "In13.Cu" "In15.Cu")
		(hatch none 0.5)
		(connect_pads
			(clearance 0)
		)
		(min_thickness 0.25)
		(keepout
			(tracks not_allowed)
			(vias allowed)
			(pads allowed)
			(copperpour not_allowed)
			(footprints allowed)
		)
		(placement
			(enabled no)
			(sheetname "")
		)
		(fill yes
			(thermal_gap 0.5)
			(thermal_bridge_width 0.5)
			(island_removal_mode 0)
		)
		(polygon
			(pts
				(arc
					(start 413.619442 -354.732082)
					(mid 412.915862 -354.732082)
					(end 413.619442 -354.732082)
				)
			)
		)
	)
	(zone
		(layers "B.Cu" "In9.Cu" "In11.Cu" "In13.Cu" "In15.Cu")
		(hatch none 0.5)
		(connect_pads
			(clearance 0)
		)
		(min_thickness 0.25)
		(keepout
			(tracks not_allowed)
			(vias allowed)
			(pads allowed)
			(copperpour not_allowed)
			(footprints allowed)
		)
		(placement
			(enabled no)
			(sheetname "")
		)
		(fill yes
			(thermal_gap 0.5)
			(thermal_bridge_width 0.5)
			(island_removal_mode 0)
		)
		(polygon
			(pts
				(arc
					(start 284.657292 -357.75773)
					(mid 283.953712 -357.75773)
					(end 284.657292 -357.75773)
				)
			)
		)
	)
	(zone
		(layers "B.Cu" "In9.Cu" "In11.Cu" "In13.Cu" "In15.Cu")
		(hatch none 0.5)
		(connect_pads
			(clearance 0)
		)
		(min_thickness 0.25)
		(keepout
			(tracks not_allowed)
			(vias allowed)
			(pads allowed)
			(copperpour not_allowed)
			(footprints allowed)
		)
		(placement
			(enabled no)
			(sheetname "")
		)
		(fill yes
			(thermal_gap 0.5)
			(thermal_bridge_width 0.5)
			(island_removal_mode 0)
		)
		(polygon
			(pts
				(arc
					(start 42.310558 -357.75773)
					(mid 41.606978 -357.75773)
					(end 42.310558 -357.75773)
				)
			)
		)
	)
	(zone
		(layers "B.Cu" "In9.Cu" "In11.Cu" "In13.Cu" "In15.Cu")
		(hatch none 0.5)
		(connect_pads
			(clearance 0)
		)
		(min_thickness 0.25)
		(keepout
			(tracks not_allowed)
			(vias allowed)
			(pads allowed)
			(copperpour not_allowed)
			(footprints allowed)
		)
		(placement
			(enabled no)
			(sheetname "")
		)
		(fill yes
			(thermal_gap 0.5)
			(thermal_bridge_width 0.5)
			(island_removal_mode 0)
		)
		(polygon
			(pts
				(arc
					(start 42.310558 -345.465146)
					(mid 41.606978 -345.465146)
					(end 42.310558 -345.465146)
				)
			)
		)
	)
	(zone
		(layers "B.Cu" "In9.Cu" "In11.Cu" "In13.Cu" "In15.Cu")
		(hatch none 0.5)
		(connect_pads
			(clearance 0)
		)
		(min_thickness 0.25)
		(keepout
			(tracks not_allowed)
			(vias allowed)
			(pads allowed)
			(copperpour not_allowed)
			(footprints allowed)
		)
		(placement
			(enabled no)
			(sheetname "")
		)
		(fill yes
			(thermal_gap 0.5)
			(thermal_bridge_width 0.5)
			(island_removal_mode 0)
		)
		(polygon
			(pts
				(arc
					(start 272.221452 -345.465146)
					(mid 271.517872 -345.465146)
					(end 272.221452 -345.465146)
				)
			)
		)
	)
	(zone
		(layers "B.Cu" "In9.Cu" "In11.Cu" "In13.Cu" "In15.Cu")
		(hatch none 0.5)
		(connect_pads
			(clearance 0)
		)
		(min_thickness 0.25)
		(keepout
			(tracks not_allowed)
			(vias allowed)
			(pads allowed)
			(copperpour not_allowed)
			(footprints allowed)
		)
		(placement
			(enabled no)
			(sheetname "")
		)
		(fill yes
			(thermal_gap 0.5)
			(thermal_bridge_width 0.5)
			(island_removal_mode 0)
		)
		(polygon
			(pts
				(arc
					(start 64.832992 -345.465146)
					(mid 64.129412 -345.465146)
					(end 64.832992 -345.465146)
				)
			)
		)
	)
	(zone
		(layers "B.Cu" "In9.Cu" "In11.Cu" "In13.Cu" "In15.Cu")
		(hatch none 0.5)
		(connect_pads
			(clearance 0)
		)
		(min_thickness 0.25)
		(keepout
			(tracks not_allowed)
			(vias allowed)
			(pads allowed)
			(copperpour not_allowed)
			(footprints allowed)
		)
		(placement
			(enabled no)
			(sheetname "")
		)
		(fill yes
			(thermal_gap 0.5)
			(thermal_bridge_width 0.5)
			(island_removal_mode 0)
		)
		(polygon
			(pts
				(arc
					(start 295.02608 -312.049922)
					(mid 294.3733 -312.049922)
					(end 295.02608 -312.049922)
				)
			)
		)
	)
	(zone
		(layers "B.Cu" "In9.Cu" "In11.Cu" "In13.Cu" "In15.Cu")
		(hatch none 0.5)
		(connect_pads
			(clearance 0)
		)
		(min_thickness 0.25)
		(keepout
			(tracks not_allowed)
			(vias allowed)
			(pads allowed)
			(copperpour not_allowed)
			(footprints allowed)
		)
		(placement
			(enabled no)
			(sheetname "")
		)
		(fill yes
			(thermal_gap 0.5)
			(thermal_bridge_width 0.5)
			(island_removal_mode 0)
		)
		(polygon
			(pts
				(arc
					(start 87.68969 -406.690068)
					(mid 86.93023 -406.690068)
					(end 87.68969 -406.690068)
				)
			)
		)
	)
	(zone
		(layers "B.Cu" "In9.Cu" "In11.Cu" "In13.Cu" "In15.Cu")
		(hatch none 0.5)
		(connect_pads
			(clearance 0)
		)
		(min_thickness 0.25)
		(keepout
			(tracks not_allowed)
			(vias allowed)
			(pads allowed)
			(copperpour not_allowed)
			(footprints allowed)
		)
		(placement
			(enabled no)
			(sheetname "")
		)
		(fill yes
			(thermal_gap 0.5)
			(thermal_bridge_width 0.5)
			(island_removal_mode 0)
		)
		(polygon
			(pts
				(arc
					(start 374.64873 -354.732082)
					(mid 373.94515 -354.732082)
					(end 374.64873 -354.732082)
				)
			)
		)
	)
	(zone
		(layers "B.Cu" "In9.Cu" "In11.Cu" "In13.Cu" "In15.Cu")
		(hatch none 0.5)
		(connect_pads
			(clearance 0)
		)
		(min_thickness 0.25)
		(keepout
			(tracks not_allowed)
			(vias allowed)
			(pads allowed)
			(copperpour not_allowed)
			(footprints allowed)
		)
		(placement
			(enabled no)
			(sheetname "")
		)
		(fill yes
			(thermal_gap 0.5)
			(thermal_bridge_width 0.5)
			(island_removal_mode 0)
		)
		(polygon
			(pts
				(arc
					(start 85.562186 -30.058868)
					(mid 84.858606 -30.058868)
					(end 85.562186 -30.058868)
				)
			)
		)
	)
	(zone
		(layers "B.Cu" "In9.Cu" "In11.Cu" "In13.Cu" "In15.Cu")
		(hatch none 0.5)
		(connect_pads
			(clearance 0)
		)
		(min_thickness 0.25)
		(keepout
			(tracks not_allowed)
			(vias allowed)
			(pads allowed)
			(copperpour not_allowed)
			(footprints allowed)
		)
		(placement
			(enabled no)
			(sheetname "")
		)
		(fill yes
			(thermal_gap 0.5)
			(thermal_bridge_width 0.5)
			(island_removal_mode 0)
		)
		(polygon
			(pts
				(arc
					(start 316.827154 -342.439498)
					(mid 316.123574 -342.439498)
					(end 316.827154 -342.439498)
				)
			)
		)
	)
	(zone
		(layers "B.Cu" "In9.Cu" "In11.Cu" "In13.Cu" "In15.Cu")
		(hatch none 0.5)
		(connect_pads
			(clearance 0)
		)
		(min_thickness 0.25)
		(keepout
			(tracks not_allowed)
			(vias allowed)
			(pads allowed)
			(copperpour not_allowed)
			(footprints allowed)
		)
		(placement
			(enabled no)
			(sheetname "")
		)
		(fill yes
			(thermal_gap 0.5)
			(thermal_bridge_width 0.5)
			(island_removal_mode 0)
		)
		(polygon
			(pts
				(arc
					(start 278.439372 -354.732082)
					(mid 277.735792 -354.732082)
					(end 278.439372 -354.732082)
				)
			)
		)
	)
	(zone
		(layers "B.Cu" "In9.Cu" "In11.Cu" "In13.Cu" "In15.Cu")
		(hatch none 0.5)
		(connect_pads
			(clearance 0)
		)
		(min_thickness 0.25)
		(keepout
			(tracks not_allowed)
			(vias allowed)
			(pads allowed)
			(copperpour not_allowed)
			(footprints allowed)
		)
		(placement
			(enabled no)
			(sheetname "")
		)
		(fill yes
			(thermal_gap 0.5)
			(thermal_bridge_width 0.5)
			(island_removal_mode 0)
		)
		(polygon
			(pts
				(arc
					(start 300.726094 -311.099962)
					(mid 300.073314 -311.099962)
					(end 300.726094 -311.099962)
				)
			)
		)
	)
	(zone
		(layers "B.Cu" "In9.Cu" "In11.Cu" "In13.Cu" "In15.Cu")
		(hatch none 0.5)
		(connect_pads
			(clearance 0)
		)
		(min_thickness 0.25)
		(keepout
			(tracks not_allowed)
			(vias allowed)
			(pads allowed)
			(copperpour not_allowed)
			(footprints allowed)
		)
		(placement
			(enabled no)
			(sheetname "")
		)
		(fill yes
			(thermal_gap 0.5)
			(thermal_bridge_width 0.5)
			(island_removal_mode 0)
		)
		(polygon
			(pts
				(arc
					(start 427.27626 -312.999882)
					(mid 426.62348 -312.999882)
					(end 427.27626 -312.999882)
				)
			)
		)
	)
	(zone
		(layers "B.Cu" "In9.Cu" "In11.Cu" "In13.Cu" "In15.Cu")
		(hatch none 0.5)
		(connect_pads
			(clearance 0)
		)
		(min_thickness 0.25)
		(keepout
			(tracks not_allowed)
			(vias allowed)
			(pads allowed)
			(copperpour not_allowed)
			(footprints allowed)
		)
		(placement
			(enabled no)
			(sheetname "")
		)
		(fill yes
			(thermal_gap 0.5)
			(thermal_bridge_width 0.5)
			(island_removal_mode 0)
		)
		(polygon
			(pts
				(arc
					(start 122.889772 -405.390096)
					(mid 122.130312 -405.390096)
					(end 122.889772 -405.390096)
				)
			)
		)
	)
	(zone
		(layers "B.Cu" "In9.Cu" "In11.Cu" "In13.Cu" "In15.Cu")
		(hatch none 0.5)
		(connect_pads
			(clearance 0)
		)
		(min_thickness 0.25)
		(keepout
			(tracks not_allowed)
			(vias allowed)
			(pads allowed)
			(copperpour not_allowed)
			(footprints allowed)
		)
		(placement
			(enabled no)
			(sheetname "")
		)
		(fill yes
			(thermal_gap 0.5)
			(thermal_bridge_width 0.5)
			(island_removal_mode 0)
		)
		(polygon
			(pts
				(arc
					(start 90.568272 -345.465146)
					(mid 89.864692 -345.465146)
					(end 90.568272 -345.465146)
				)
			)
		)
	)
	(zone
		(layers "B.Cu" "In9.Cu" "In11.Cu" "In13.Cu" "In15.Cu")
		(hatch none 0.5)
		(connect_pads
			(clearance 0)
		)
		(min_thickness 0.25)
		(keepout
			(tracks not_allowed)
			(vias allowed)
			(pads allowed)
			(copperpour not_allowed)
			(footprints allowed)
		)
		(placement
			(enabled no)
			(sheetname "")
		)
		(fill yes
			(thermal_gap 0.5)
			(thermal_bridge_width 0.5)
			(island_removal_mode 0)
		)
		(polygon
			(pts
				(arc
					(start 293.61638 -28.25877)
					(mid 292.9128 -28.25877)
					(end 293.61638 -28.25877)
				)
			)
		)
	)
	(zone
		(layers "B.Cu" "In9.Cu" "In11.Cu" "In13.Cu" "In15.Cu")
		(hatch none 0.5)
		(connect_pads
			(clearance 0)
		)
		(min_thickness 0.25)
		(keepout
			(tracks not_allowed)
			(vias allowed)
			(pads allowed)
			(copperpour not_allowed)
			(footprints allowed)
		)
		(placement
			(enabled no)
			(sheetname "")
		)
		(fill yes
			(thermal_gap 0.5)
			(thermal_bridge_width 0.5)
			(island_removal_mode 0)
		)
		(polygon
			(pts
				(arc
					(start 278.876252 -273.099784)
					(mid 278.223472 -273.099784)
					(end 278.876252 -273.099784)
				)
			)
		)
	)
	(zone
		(layers "B.Cu" "In9.Cu" "In11.Cu" "In13.Cu" "In15.Cu")
		(hatch none 0.5)
		(connect_pads
			(clearance 0)
		)
		(min_thickness 0.25)
		(keepout
			(tracks not_allowed)
			(vias allowed)
			(pads allowed)
			(copperpour not_allowed)
			(footprints allowed)
		)
		(placement
			(enabled no)
			(sheetname "")
		)
		(fill yes
			(thermal_gap 0.5)
			(thermal_bridge_width 0.5)
			(island_removal_mode 0)
		)
		(polygon
			(pts
				(arc
					(start 65.676272 -313.949842)
					(mid 65.023492 -313.949842)
					(end 65.676272 -313.949842)
				)
			)
		)
	)
	(zone
		(layers "B.Cu" "In9.Cu" "In11.Cu" "In13.Cu" "In15.Cu")
		(hatch none 0.5)
		(connect_pads
			(clearance 0)
		)
		(min_thickness 0.25)
		(keepout
			(tracks not_allowed)
			(vias allowed)
			(pads allowed)
			(copperpour not_allowed)
			(footprints allowed)
		)
		(placement
			(enabled no)
			(sheetname "")
		)
		(fill yes
			(thermal_gap 0.5)
			(thermal_bridge_width 0.5)
			(island_removal_mode 0)
		)
		(polygon
			(pts
				(arc
					(start 288.376106 -274.049744)
					(mid 287.723326 -274.049744)
					(end 288.376106 -274.049744)
				)
			)
		)
	)
	(zone
		(layers "B.Cu" "In9.Cu" "In11.Cu" "In13.Cu" "In15.Cu")
		(hatch none 0.5)
		(connect_pads
			(clearance 0)
		)
		(min_thickness 0.25)
		(keepout
			(tracks not_allowed)
			(vias allowed)
			(pads allowed)
			(copperpour not_allowed)
			(footprints allowed)
		)
		(placement
			(enabled no)
			(sheetname "")
		)
		(fill yes
			(thermal_gap 0.5)
			(thermal_bridge_width 0.5)
			(island_removal_mode 0)
		)
		(polygon
			(pts
				(arc
					(start 342.869774 -406.690068)
					(mid 342.110314 -406.690068)
					(end 342.869774 -406.690068)
				)
			)
		)
	)
	(zone
		(layers "B.Cu" "In9.Cu" "In11.Cu" "In13.Cu" "In15.Cu")
		(hatch none 0.5)
		(connect_pads
			(clearance 0)
		)
		(min_thickness 0.25)
		(keepout
			(tracks not_allowed)
			(vias allowed)
			(pads allowed)
			(copperpour not_allowed)
			(footprints allowed)
		)
		(placement
			(enabled no)
			(sheetname "")
		)
		(fill yes
			(thermal_gap 0.5)
			(thermal_bridge_width 0.5)
			(island_removal_mode 0)
		)
		(polygon
			(pts
				(arc
					(start 419.837362 -357.75773)
					(mid 419.133782 -357.75773)
					(end 419.837362 -357.75773)
				)
			)
		)
	)
	(zone
		(layers "B.Cu" "In9.Cu" "In11.Cu" "In13.Cu" "In15.Cu")
		(hatch none 0.5)
		(connect_pads
			(clearance 0)
		)
		(min_thickness 0.25)
		(keepout
			(tracks not_allowed)
			(vias allowed)
			(pads allowed)
			(copperpour not_allowed)
			(footprints allowed)
		)
		(placement
			(enabled no)
			(sheetname "")
		)
		(fill yes
			(thermal_gap 0.5)
			(thermal_bridge_width 0.5)
			(island_removal_mode 0)
		)
		(polygon
			(pts
				(arc
					(start 299.338492 -348.58579)
					(mid 298.634912 -348.58579)
					(end 299.338492 -348.58579)
				)
			)
		)
	)
	(zone
		(layers "B.Cu" "In9.Cu" "In11.Cu" "In13.Cu" "In15.Cu")
		(hatch none 0.5)
		(connect_pads
			(clearance 0)
		)
		(min_thickness 0.25)
		(keepout
			(tracks not_allowed)
			(vias allowed)
			(pads allowed)
			(copperpour not_allowed)
			(footprints allowed)
		)
		(placement
			(enabled no)
			(sheetname "")
		)
		(fill yes
			(thermal_gap 0.5)
			(thermal_bridge_width 0.5)
			(island_removal_mode 0)
		)
		(polygon
			(pts
				(arc
					(start 271.357852 -354.732082)
					(mid 270.654272 -354.732082)
					(end 271.357852 -354.732082)
				)
			)
		)
	)
	(zone
		(layers "B.Cu" "In9.Cu" "In11.Cu" "In13.Cu" "In15.Cu")
		(hatch none 0.5)
		(connect_pads
			(clearance 0)
		)
		(min_thickness 0.25)
		(keepout
			(tracks not_allowed)
			(vias allowed)
			(pads allowed)
			(copperpour not_allowed)
			(footprints allowed)
		)
		(placement
			(enabled no)
			(sheetname "")
		)
		(fill yes
			(thermal_gap 0.5)
			(thermal_bridge_width 0.5)
			(island_removal_mode 0)
		)
		(polygon
			(pts
				(arc
					(start 374.64873 -345.465146)
					(mid 373.94515 -345.465146)
					(end 374.64873 -345.465146)
				)
			)
		)
	)
	(zone
		(layers "B.Cu" "In9.Cu" "In11.Cu" "In13.Cu" "In15.Cu")
		(hatch none 0.5)
		(connect_pads
			(clearance 0)
		)
		(min_thickness 0.25)
		(keepout
			(tracks not_allowed)
			(vias allowed)
			(pads allowed)
			(copperpour not_allowed)
			(footprints allowed)
		)
		(placement
			(enabled no)
			(sheetname "")
		)
		(fill yes
			(thermal_gap 0.5)
			(thermal_bridge_width 0.5)
			(island_removal_mode 0)
		)
		(polygon
			(pts
				(arc
					(start 432.273202 -342.439498)
					(mid 431.569622 -342.439498)
					(end 432.273202 -342.439498)
				)
			)
		)
	)
	(zone
		(layers "B.Cu" "In9.Cu" "In11.Cu" "In13.Cu" "In15.Cu")
		(hatch none 0.5)
		(connect_pads
			(clearance 0)
		)
		(min_thickness 0.25)
		(keepout
			(tracks not_allowed)
			(vias allowed)
			(pads allowed)
			(copperpour not_allowed)
			(footprints allowed)
		)
		(placement
			(enabled no)
			(sheetname "")
		)
		(fill yes
			(thermal_gap 0.5)
			(thermal_bridge_width 0.5)
			(island_removal_mode 0)
		)
		(polygon
			(pts
				(arc
					(start 267.616432 -28.25877)
					(mid 266.912852 -28.25877)
					(end 267.616432 -28.25877)
				)
			)
		)
	)
	(zone
		(layers "B.Cu" "In9.Cu" "In11.Cu" "In13.Cu" "In15.Cu")
		(hatch none 0.5)
		(connect_pads
			(clearance 0)
		)
		(min_thickness 0.25)
		(keepout
			(tracks not_allowed)
			(vias allowed)
			(pads allowed)
			(copperpour not_allowed)
			(footprints allowed)
		)
		(placement
			(enabled no)
			(sheetname "")
		)
		(fill yes
			(thermal_gap 0.5)
			(thermal_bridge_width 0.5)
			(island_removal_mode 0)
		)
		(polygon
			(pts
				(arc
					(start 280.776172 -274.049744)
					(mid 280.123392 -274.049744)
					(end 280.776172 -274.049744)
				)
			)
		)
	)
	(zone
		(layers "B.Cu" "In9.Cu" "In11.Cu" "In13.Cu" "In15.Cu")
		(hatch none 0.5)
		(connect_pads
			(clearance 0)
		)
		(min_thickness 0.25)
		(keepout
			(tracks not_allowed)
			(vias allowed)
			(pads allowed)
			(copperpour not_allowed)
			(footprints allowed)
		)
		(placement
			(enabled no)
			(sheetname "")
		)
		(fill yes
			(thermal_gap 0.5)
			(thermal_bridge_width 0.5)
			(island_removal_mode 0)
		)
		(polygon
			(pts
				(arc
					(start 175.126396 -275.949918)
					(mid 174.473616 -275.949918)
					(end 175.126396 -275.949918)
				)
			)
		)
	)
	(zone
		(layers "B.Cu" "In9.Cu" "In11.Cu" "In13.Cu" "In15.Cu")
		(hatch none 0.5)
		(connect_pads
			(clearance 0)
		)
		(min_thickness 0.25)
		(keepout
			(tracks not_allowed)
			(vias allowed)
			(pads allowed)
			(copperpour not_allowed)
			(footprints allowed)
		)
		(placement
			(enabled no)
			(sheetname "")
		)
		(fill yes
			(thermal_gap 0.5)
			(thermal_bridge_width 0.5)
			(island_removal_mode 0)
		)
		(polygon
			(pts
				(arc
					(start 85.489542 -404.290022)
					(mid 84.730082 -404.290022)
					(end 85.489542 -404.290022)
				)
			)
		)
	)
	(zone
		(layers "B.Cu" "In9.Cu" "In11.Cu" "In13.Cu" "In15.Cu")
		(hatch none 0.5)
		(connect_pads
			(clearance 0)
		)
		(min_thickness 0.25)
		(keepout
			(tracks not_allowed)
			(vias allowed)
			(pads allowed)
			(copperpour not_allowed)
			(footprints allowed)
		)
		(placement
			(enabled no)
			(sheetname "")
		)
		(fill yes
			(thermal_gap 0.5)
			(thermal_bridge_width 0.5)
			(island_removal_mode 0)
		)
		(polygon
			(pts
				(arc
					(start 381.86233 -30.058868)
					(mid 381.15875 -30.058868)
					(end 381.86233 -30.058868)
				)
			)
		)
	)
	(zone
		(layers "B.Cu" "In9.Cu" "In11.Cu" "In13.Cu" "In15.Cu")
		(hatch none 0.5)
		(connect_pads
			(clearance 0)
		)
		(min_thickness 0.25)
		(keepout
			(tracks not_allowed)
			(vias allowed)
			(pads allowed)
			(copperpour not_allowed)
			(footprints allowed)
		)
		(placement
			(enabled no)
			(sheetname "")
		)
		(fill yes
			(thermal_gap 0.5)
			(thermal_bridge_width 0.5)
			(island_removal_mode 0)
		)
		(polygon
			(pts
				(arc
					(start 144.167098 -348.58579)
					(mid 143.463518 -348.58579)
					(end 144.167098 -348.58579)
				)
			)
		)
	)
	(zone
		(layers "B.Cu" "In9.Cu" "In11.Cu" "In13.Cu" "In15.Cu")
		(hatch none 0.5)
		(connect_pads
			(clearance 0)
		)
		(min_thickness 0.25)
		(keepout
			(tracks not_allowed)
			(vias allowed)
			(pads allowed)
			(copperpour not_allowed)
			(footprints allowed)
		)
		(placement
			(enabled no)
			(sheetname "")
		)
		(fill yes
			(thermal_gap 0.5)
			(thermal_bridge_width 0.5)
			(island_removal_mode 0)
		)
		(polygon
			(pts
				(arc
					(start 386.869686 -405.390096)
					(mid 386.110226 -405.390096)
					(end 386.869686 -405.390096)
				)
			)
		)
	)
	(zone
		(layers "B.Cu" "In9.Cu" "In11.Cu" "In13.Cu" "In15.Cu")
		(hatch none 0.5)
		(connect_pads
			(clearance 0)
		)
		(min_thickness 0.25)
		(keepout
			(tracks not_allowed)
			(vias allowed)
			(pads allowed)
			(copperpour not_allowed)
			(footprints allowed)
		)
		(placement
			(enabled no)
			(sheetname "")
		)
		(fill yes
			(thermal_gap 0.5)
			(thermal_bridge_width 0.5)
			(island_removal_mode 0)
		)
		(polygon
			(pts
				(arc
					(start 55.226204 -274.999958)
					(mid 54.573424 -274.999958)
					(end 55.226204 -274.999958)
				)
			)
		)
	)
	(zone
		(layers "B.Cu" "In9.Cu" "In11.Cu" "In13.Cu" "In15.Cu")
		(hatch none 0.5)
		(connect_pads
			(clearance 0)
		)
		(min_thickness 0.25)
		(keepout
			(tracks not_allowed)
			(vias allowed)
			(pads allowed)
			(copperpour not_allowed)
			(footprints allowed)
		)
		(placement
			(enabled no)
			(sheetname "")
		)
		(fill yes
			(thermal_gap 0.5)
			(thermal_bridge_width 0.5)
			(island_removal_mode 0)
		)
		(polygon
			(pts
				(arc
					(start 271.357852 -357.75773)
					(mid 270.654272 -357.75773)
					(end 271.357852 -357.75773)
				)
			)
		)
	)
	(zone
		(layers "B.Cu" "In9.Cu" "In11.Cu" "In13.Cu" "In15.Cu")
		(hatch none 0.5)
		(connect_pads
			(clearance 0)
		)
		(min_thickness 0.25)
		(keepout
			(tracks not_allowed)
			(vias allowed)
			(pads allowed)
			(copperpour not_allowed)
			(footprints allowed)
		)
		(placement
			(enabled no)
			(sheetname "")
		)
		(fill yes
			(thermal_gap 0.5)
			(thermal_bridge_width 0.5)
			(island_removal_mode 0)
		)
		(polygon
			(pts
				(arc
					(start 343.944194 -348.58579)
					(mid 343.240614 -348.58579)
					(end 343.944194 -348.58579)
				)
			)
		)
	)
	(zone
		(layers "B.Cu" "In9.Cu" "In11.Cu" "In13.Cu" "In15.Cu")
		(hatch none 0.5)
		(connect_pads
			(clearance 0)
		)
		(min_thickness 0.25)
		(keepout
			(tracks not_allowed)
			(vias allowed)
			(pads allowed)
			(copperpour not_allowed)
			(footprints allowed)
		)
		(placement
			(enabled no)
			(sheetname "")
		)
		(fill yes
			(thermal_gap 0.5)
			(thermal_bridge_width 0.5)
			(island_removal_mode 0)
		)
		(polygon
			(pts
				(arc
					(start 376.75566 17.596612)
					(mid 376.05208 17.596612)
					(end 376.75566 17.596612)
				)
			)
		)
	)
	(zone
		(layers "B.Cu" "In9.Cu" "In11.Cu" "In13.Cu" "In15.Cu")
		(hatch none 0.5)
		(connect_pads
			(clearance 0)
		)
		(min_thickness 0.25)
		(keepout
			(tracks not_allowed)
			(vias allowed)
			(pads allowed)
			(copperpour not_allowed)
			(footprints allowed)
		)
		(placement
			(enabled no)
			(sheetname "")
		)
		(fill yes
			(thermal_gap 0.5)
			(thermal_bridge_width 0.5)
			(island_removal_mode 0)
		)
		(polygon
			(pts
				(arc
					(start 340.835234 -357.75773)
					(mid 340.131654 -357.75773)
					(end 340.835234 -357.75773)
				)
			)
		)
	)
	(zone
		(layers "B.Cu" "In9.Cu" "In11.Cu" "In13.Cu" "In15.Cu")
		(hatch none 0.5)
		(connect_pads
			(clearance 0)
		)
		(min_thickness 0.25)
		(keepout
			(tracks not_allowed)
			(vias allowed)
			(pads allowed)
			(copperpour not_allowed)
			(footprints allowed)
		)
		(placement
			(enabled no)
			(sheetname "")
		)
		(fill yes
			(thermal_gap 0.5)
			(thermal_bridge_width 0.5)
			(island_removal_mode 0)
		)
		(polygon
			(pts
				(arc
					(start 334.06969 -406.690068)
					(mid 333.31023 -406.690068)
					(end 334.06969 -406.690068)
				)
			)
		)
	)
	(zone
		(layers "B.Cu" "In9.Cu" "In11.Cu" "In13.Cu" "In15.Cu")
		(hatch none 0.5)
		(connect_pads
			(clearance 0)
		)
		(min_thickness 0.25)
		(keepout
			(tracks not_allowed)
			(vias allowed)
			(pads allowed)
			(copperpour not_allowed)
			(footprints allowed)
		)
		(placement
			(enabled no)
			(sheetname "")
		)
		(fill yes
			(thermal_gap 0.5)
			(thermal_bridge_width 0.5)
			(island_removal_mode 0)
		)
		(polygon
			(pts
				(arc
					(start 129.489708 -404.290022)
					(mid 128.730248 -404.290022)
					(end 129.489708 -404.290022)
				)
			)
		)
	)
	(zone
		(layers "B.Cu" "In9.Cu" "In11.Cu" "In13.Cu" "In15.Cu")
		(hatch none 0.5)
		(connect_pads
			(clearance 0)
		)
		(min_thickness 0.25)
		(keepout
			(tracks not_allowed)
			(vias allowed)
			(pads allowed)
			(copperpour not_allowed)
			(footprints allowed)
		)
		(placement
			(enabled no)
			(sheetname "")
		)
		(fill yes
			(thermal_gap 0.5)
			(thermal_bridge_width 0.5)
			(island_removal_mode 0)
		)
		(polygon
			(pts
				(arc
					(start 188.273182 -351.611438)
					(mid 187.569602 -351.611438)
					(end 188.273182 -351.611438)
				)
			)
		)
	)
	(zone
		(layers "B.Cu" "In9.Cu" "In11.Cu" "In13.Cu" "In15.Cu")
		(hatch none 0.5)
		(connect_pads
			(clearance 0)
		)
		(min_thickness 0.25)
		(keepout
			(tracks not_allowed)
			(vias allowed)
			(pads allowed)
			(copperpour not_allowed)
			(footprints allowed)
		)
		(placement
			(enabled no)
			(sheetname "")
		)
		(fill yes
			(thermal_gap 0.5)
			(thermal_bridge_width 0.5)
			(island_removal_mode 0)
		)
		(polygon
			(pts
				(arc
					(start 70.426326 -311.099962)
					(mid 69.773546 -311.099962)
					(end 70.426326 -311.099962)
				)
			)
		)
	)
	(zone
		(layers "B.Cu" "In9.Cu" "In11.Cu" "In13.Cu" "In15.Cu")
		(hatch none 0.5)
		(connect_pads
			(clearance 0)
		)
		(min_thickness 0.25)
		(keepout
			(tracks not_allowed)
			(vias allowed)
			(pads allowed)
			(copperpour not_allowed)
			(footprints allowed)
		)
		(placement
			(enabled no)
			(sheetname "")
		)
		(fill yes
			(thermal_gap 0.5)
			(thermal_bridge_width 0.5)
			(island_removal_mode 0)
		)
		(polygon
			(pts
				(arc
					(start 174.973742 -348.58579)
					(mid 174.270162 -348.58579)
					(end 174.973742 -348.58579)
				)
			)
		)
	)
	(zone
		(layers "B.Cu" "In9.Cu" "In11.Cu" "In13.Cu" "In15.Cu")
		(hatch none 0.5)
		(connect_pads
			(clearance 0)
		)
		(min_thickness 0.25)
		(keepout
			(tracks not_allowed)
			(vias allowed)
			(pads allowed)
			(copperpour not_allowed)
			(footprints allowed)
		)
		(placement
			(enabled no)
			(sheetname "")
		)
		(fill yes
			(thermal_gap 0.5)
			(thermal_bridge_width 0.5)
			(island_removal_mode 0)
		)
		(polygon
			(pts
				(arc
					(start 271.357852 -345.465146)
					(mid 270.654272 -345.465146)
					(end 271.357852 -345.465146)
				)
			)
		)
	)
	(zone
		(layers "B.Cu" "In9.Cu" "In11.Cu" "In13.Cu" "In15.Cu")
		(hatch none 0.5)
		(connect_pads
			(clearance 0)
		)
		(min_thickness 0.25)
		(keepout
			(tracks not_allowed)
			(vias allowed)
			(pads allowed)
			(copperpour not_allowed)
			(footprints allowed)
		)
		(placement
			(enabled no)
			(sheetname "")
		)
		(fill yes
			(thermal_gap 0.5)
			(thermal_bridge_width 0.5)
			(island_removal_mode 0)
		)
		(polygon
			(pts
				(arc
					(start 23.656798 -357.75773)
					(mid 22.953218 -357.75773)
					(end 23.656798 -357.75773)
				)
			)
		)
	)
	(zone
		(layers "B.Cu" "In9.Cu" "In11.Cu" "In13.Cu" "In15.Cu")
		(hatch none 0.5)
		(connect_pads
			(clearance 0)
		)
		(min_thickness 0.25)
		(keepout
			(tracks not_allowed)
			(vias allowed)
			(pads allowed)
			(copperpour not_allowed)
			(footprints allowed)
		)
		(placement
			(enabled no)
			(sheetname "")
		)
		(fill yes
			(thermal_gap 0.5)
			(thermal_bridge_width 0.5)
			(island_removal_mode 0)
		)
		(polygon
			(pts
				(arc
					(start 45.72635 -274.999958)
					(mid 45.07357 -274.999958)
					(end 45.72635 -274.999958)
				)
			)
		)
	)
	(zone
		(layers "B.Cu" "In9.Cu" "In11.Cu" "In13.Cu" "In15.Cu")
		(hatch none 0.5)
		(connect_pads
			(clearance 0)
		)
		(min_thickness 0.25)
		(keepout
			(tracks not_allowed)
			(vias allowed)
			(pads allowed)
			(copperpour not_allowed)
			(footprints allowed)
		)
		(placement
			(enabled no)
			(sheetname "")
		)
		(fill yes
			(thermal_gap 0.5)
			(thermal_bridge_width 0.5)
			(island_removal_mode 0)
		)
		(polygon
			(pts
				(arc
					(start 44.776136 -302.549814)
					(mid 44.123356 -302.549814)
					(end 44.776136 -302.549814)
				)
			)
		)
	)
	(zone
		(layers "B.Cu" "In9.Cu" "In11.Cu" "In13.Cu" "In15.Cu")
		(hatch none 0.5)
		(connect_pads
			(clearance 0)
		)
		(min_thickness 0.25)
		(keepout
			(tracks not_allowed)
			(vias allowed)
			(pads allowed)
			(copperpour not_allowed)
			(footprints allowed)
		)
		(placement
			(enabled no)
			(sheetname "")
		)
		(fill yes
			(thermal_gap 0.5)
			(thermal_bridge_width 0.5)
			(island_removal_mode 0)
		)
		(polygon
			(pts
				(arc
					(start 124.649738 -348.58579)
					(mid 123.946158 -348.58579)
					(end 124.649738 -348.58579)
				)
			)
		)
	)
	(zone
		(layers "B.Cu" "In9.Cu" "In11.Cu" "In13.Cu" "In15.Cu")
		(hatch none 0.5)
		(connect_pads
			(clearance 0)
		)
		(min_thickness 0.25)
		(keepout
			(tracks not_allowed)
			(vias allowed)
			(pads allowed)
			(copperpour not_allowed)
			(footprints allowed)
		)
		(placement
			(enabled no)
			(sheetname "")
		)
		(fill yes
			(thermal_gap 0.5)
			(thermal_bridge_width 0.5)
			(island_removal_mode 0)
		)
		(polygon
			(pts
				(arc
					(start 300.202092 -348.58579)
					(mid 299.498512 -348.58579)
					(end 300.202092 -348.58579)
				)
			)
		)
	)
	(zone
		(layers "B.Cu" "In9.Cu" "In11.Cu" "In13.Cu" "In15.Cu")
		(hatch none 0.5)
		(connect_pads
			(clearance 0)
		)
		(min_thickness 0.25)
		(keepout
			(tracks not_allowed)
			(vias allowed)
			(pads allowed)
			(copperpour not_allowed)
			(footprints allowed)
		)
		(placement
			(enabled no)
			(sheetname "")
		)
		(fill yes
			(thermal_gap 0.5)
			(thermal_bridge_width 0.5)
			(island_removal_mode 0)
		)
		(polygon
			(pts
				(arc
					(start 418.973762 -357.75773)
					(mid 418.270182 -357.75773)
					(end 418.973762 -357.75773)
				)
			)
		)
	)
	(zone
		(layers "B.Cu" "In9.Cu" "In11.Cu" "In13.Cu" "In15.Cu")
		(hatch none 0.5)
		(connect_pads
			(clearance 0)
		)
		(min_thickness 0.25)
		(keepout
			(tracks not_allowed)
			(vias allowed)
			(pads allowed)
			(copperpour not_allowed)
			(footprints allowed)
		)
		(placement
			(enabled no)
			(sheetname "")
		)
		(fill yes
			(thermal_gap 0.5)
			(thermal_bridge_width 0.5)
			(island_removal_mode 0)
		)
		(polygon
			(pts
				(arc
					(start 124.649738 -351.611438)
					(mid 123.946158 -351.611438)
					(end 124.649738 -351.611438)
				)
			)
		)
	)
	(zone
		(layers "B.Cu" "In9.Cu" "In11.Cu" "In13.Cu" "In15.Cu")
		(hatch none 0.5)
		(connect_pads
			(clearance 0)
		)
		(min_thickness 0.25)
		(keepout
			(tracks not_allowed)
			(vias allowed)
			(pads allowed)
			(copperpour not_allowed)
			(footprints allowed)
		)
		(placement
			(enabled no)
			(sheetname "")
		)
		(fill yes
			(thermal_gap 0.5)
			(thermal_bridge_width 0.5)
			(island_removal_mode 0)
		)
		(polygon
			(pts
				(arc
					(start 389.06958 -383.490216)
					(mid 388.31012 -383.490216)
					(end 389.06958 -383.490216)
				)
			)
		)
	)
	(zone
		(layers "B.Cu" "In9.Cu" "In11.Cu" "In13.Cu" "In15.Cu")
		(hatch none 0.5)
		(connect_pads
			(clearance 0)
		)
		(min_thickness 0.25)
		(keepout
			(tracks not_allowed)
			(vias allowed)
			(pads allowed)
			(copperpour not_allowed)
			(footprints allowed)
		)
		(placement
			(enabled no)
			(sheetname "")
		)
		(fill yes
			(thermal_gap 0.5)
			(thermal_bridge_width 0.5)
			(island_removal_mode 0)
		)
		(polygon
			(pts
				(arc
					(start 332.371954 -351.611438)
					(mid 331.668374 -351.611438)
					(end 332.371954 -351.611438)
				)
			)
		)
	)
	(zone
		(layers "B.Cu" "In9.Cu" "In11.Cu" "In13.Cu" "In15.Cu")
		(hatch none 0.5)
		(connect_pads
			(clearance 0)
		)
		(min_thickness 0.25)
		(keepout
			(tracks not_allowed)
			(vias allowed)
			(pads allowed)
			(copperpour not_allowed)
			(footprints allowed)
		)
		(placement
			(enabled no)
			(sheetname "")
		)
		(fill yes
			(thermal_gap 0.5)
			(thermal_bridge_width 0.5)
			(island_removal_mode 0)
		)
		(polygon
			(pts
				(arc
					(start 33.56229 -34.52241)
					(mid 32.85871 -34.52241)
					(end 33.56229 -34.52241)
				)
			)
		)
	)
	(zone
		(layers "B.Cu" "In9.Cu" "In11.Cu" "In13.Cu" "In15.Cu")
		(hatch none 0.5)
		(connect_pads
			(clearance 0)
		)
		(min_thickness 0.25)
		(keepout
			(tracks not_allowed)
			(vias allowed)
			(pads allowed)
			(copperpour not_allowed)
			(footprints allowed)
		)
		(placement
			(enabled no)
			(sheetname "")
		)
		(fill yes
			(thermal_gap 0.5)
			(thermal_bridge_width 0.5)
			(island_removal_mode 0)
		)
		(polygon
			(pts
				(arc
					(start 296.669714 -374.390158)
					(mid 295.910254 -374.390158)
					(end 296.669714 -374.390158)
				)
			)
		)
	)
	(zone
		(layers "B.Cu" "In9.Cu" "In11.Cu" "In13.Cu" "In15.Cu")
		(hatch none 0.5)
		(connect_pads
			(clearance 0)
		)
		(min_thickness 0.25)
		(keepout
			(tracks not_allowed)
			(vias allowed)
			(pads allowed)
			(copperpour not_allowed)
			(footprints allowed)
		)
		(placement
			(enabled no)
			(sheetname "")
		)
		(fill yes
			(thermal_gap 0.5)
			(thermal_bridge_width 0.5)
			(island_removal_mode 0)
		)
		(polygon
			(pts
				(arc
					(start 347.269816 -406.690068)
					(mid 346.510356 -406.690068)
					(end 347.269816 -406.690068)
				)
			)
		)
	)
	(zone
		(layers "B.Cu" "In9.Cu" "In11.Cu" "In13.Cu" "In15.Cu")
		(hatch none 0.5)
		(connect_pads
			(clearance 0)
		)
		(min_thickness 0.25)
		(keepout
			(tracks not_allowed)
			(vias allowed)
			(pads allowed)
			(copperpour not_allowed)
			(footprints allowed)
		)
		(placement
			(enabled no)
			(sheetname "")
		)
		(fill yes
			(thermal_gap 0.5)
			(thermal_bridge_width 0.5)
			(island_removal_mode 0)
		)
		(polygon
			(pts
				(arc
					(start 409.716478 -32.722312)
					(mid 409.012898 -32.722312)
					(end 409.716478 -32.722312)
				)
			)
		)
	)
	(zone
		(layers "B.Cu" "In9.Cu" "In11.Cu" "In13.Cu" "In15.Cu")
		(hatch none 0.5)
		(connect_pads
			(clearance 0)
		)
		(min_thickness 0.25)
		(keepout
			(tracks not_allowed)
			(vias allowed)
			(pads allowed)
			(copperpour not_allowed)
			(footprints allowed)
		)
		(placement
			(enabled no)
			(sheetname "")
		)
		(fill yes
			(thermal_gap 0.5)
			(thermal_bridge_width 0.5)
			(island_removal_mode 0)
		)
		(polygon
			(pts
				(arc
					(start 166.510462 -354.732082)
					(mid 165.806882 -354.732082)
					(end 166.510462 -354.732082)
				)
			)
		)
	)
	(zone
		(layers "B.Cu" "In9.Cu" "In11.Cu" "In13.Cu" "In15.Cu")
		(hatch none 0.5)
		(connect_pads
			(clearance 0)
		)
		(min_thickness 0.25)
		(keepout
			(tracks not_allowed)
			(vias allowed)
			(pads allowed)
			(copperpour not_allowed)
			(footprints allowed)
		)
		(placement
			(enabled no)
			(sheetname "")
		)
		(fill yes
			(thermal_gap 0.5)
			(thermal_bridge_width 0.5)
			(island_removal_mode 0)
		)
		(polygon
			(pts
				(arc
					(start 274.126198 -305.399948)
					(mid 273.473418 -305.399948)
					(end 274.126198 -305.399948)
				)
			)
		)
	)
	(zone
		(layers "B.Cu" "In9.Cu" "In11.Cu" "In13.Cu" "In15.Cu")
		(hatch none 0.5)
		(connect_pads
			(clearance 0)
		)
		(min_thickness 0.25)
		(keepout
			(tracks not_allowed)
			(vias allowed)
			(pads allowed)
			(copperpour not_allowed)
			(footprints allowed)
		)
		(placement
			(enabled no)
			(sheetname "")
		)
		(fill yes
			(thermal_gap 0.5)
			(thermal_bridge_width 0.5)
			(island_removal_mode 0)
		)
		(polygon
			(pts
				(arc
					(start 33.56229 -30.922468)
					(mid 32.85871 -30.922468)
					(end 33.56229 -30.922468)
				)
			)
		)
	)
	(zone
		(layers "B.Cu" "In9.Cu" "In11.Cu" "In13.Cu" "In15.Cu")
		(hatch none 0.5)
		(connect_pads
			(clearance 0)
		)
		(min_thickness 0.25)
		(keepout
			(tracks not_allowed)
			(vias allowed)
			(pads allowed)
			(copperpour not_allowed)
			(footprints allowed)
		)
		(placement
			(enabled no)
			(sheetname "")
		)
		(fill yes
			(thermal_gap 0.5)
			(thermal_bridge_width 0.5)
			(island_removal_mode 0)
		)
		(polygon
			(pts
				(arc
					(start 438.491122 -345.465146)
					(mid 437.787542 -345.465146)
					(end 438.491122 -345.465146)
				)
			)
		)
	)
	(zone
		(layers "B.Cu" "In9.Cu" "In11.Cu" "In13.Cu" "In15.Cu")
		(hatch none 0.5)
		(connect_pads
			(clearance 0)
		)
		(min_thickness 0.25)
		(keepout
			(tracks not_allowed)
			(vias allowed)
			(pads allowed)
			(copperpour not_allowed)
			(footprints allowed)
		)
		(placement
			(enabled no)
			(sheetname "")
		)
		(fill yes
			(thermal_gap 0.5)
			(thermal_bridge_width 0.5)
			(island_removal_mode 0)
		)
		(polygon
			(pts
				(arc
					(start 166.510462 -342.439498)
					(mid 165.806882 -342.439498)
					(end 166.510462 -342.439498)
				)
			)
		)
	)
	(zone
		(layers "B.Cu" "In9.Cu" "In11.Cu" "In13.Cu" "In15.Cu")
		(hatch none 0.5)
		(connect_pads
			(clearance 0)
		)
		(min_thickness 0.25)
		(keepout
			(tracks not_allowed)
			(vias allowed)
			(pads allowed)
			(copperpour not_allowed)
			(footprints allowed)
		)
		(placement
			(enabled no)
			(sheetname "")
		)
		(fill yes
			(thermal_gap 0.5)
			(thermal_bridge_width 0.5)
			(island_removal_mode 0)
		)
		(polygon
			(pts
				(arc
					(start 51.426364 -275.949918)
					(mid 50.773584 -275.949918)
					(end 51.426364 -275.949918)
				)
			)
		)
	)
	(zone
		(layers "B.Cu" "In9.Cu" "In11.Cu" "In13.Cu" "In15.Cu")
		(hatch none 0.5)
		(connect_pads
			(clearance 0)
		)
		(min_thickness 0.25)
		(keepout
			(tracks not_allowed)
			(vias allowed)
			(pads allowed)
			(copperpour not_allowed)
			(footprints allowed)
		)
		(placement
			(enabled no)
			(sheetname "")
		)
		(fill yes
			(thermal_gap 0.5)
			(thermal_bridge_width 0.5)
			(island_removal_mode 0)
		)
		(polygon
			(pts
				(arc
					(start 400.38401 -342.439498)
					(mid 399.68043 -342.439498)
					(end 400.38401 -342.439498)
				)
			)
		)
	)
	(zone
		(layers "B.Cu" "In9.Cu" "In11.Cu" "In13.Cu" "In15.Cu")
		(hatch none 0.5)
		(connect_pads
			(clearance 0)
		)
		(min_thickness 0.25)
		(keepout
			(tracks not_allowed)
			(vias allowed)
			(pads allowed)
			(copperpour not_allowed)
			(footprints allowed)
		)
		(placement
			(enabled no)
			(sheetname "")
		)
		(fill yes
			(thermal_gap 0.5)
			(thermal_bridge_width 0.5)
			(island_removal_mode 0)
		)
		(polygon
			(pts
				(arc
					(start 172.276262 -273.099784)
					(mid 171.623482 -273.099784)
					(end 172.276262 -273.099784)
				)
			)
		)
	)
	(zone
		(layers "B.Cu" "In9.Cu" "In11.Cu" "In13.Cu" "In15.Cu")
		(hatch none 0.5)
		(connect_pads
			(clearance 0)
		)
		(min_thickness 0.25)
		(keepout
			(tracks not_allowed)
			(vias allowed)
			(pads allowed)
			(copperpour not_allowed)
			(footprints allowed)
		)
		(placement
			(enabled no)
			(sheetname "")
		)
		(fill yes
			(thermal_gap 0.5)
			(thermal_bridge_width 0.5)
			(island_removal_mode 0)
		)
		(polygon
			(pts
				(arc
					(start 347.269816 -380.69012)
					(mid 346.510356 -380.69012)
					(end 347.269816 -380.69012)
				)
			)
		)
	)
	(zone
		(layers "B.Cu" "In9.Cu" "In11.Cu" "In13.Cu" "In15.Cu")
		(hatch none 0.5)
		(connect_pads
			(clearance 0)
		)
		(min_thickness 0.25)
		(keepout
			(tracks not_allowed)
			(vias allowed)
			(pads allowed)
			(copperpour not_allowed)
			(footprints allowed)
		)
		(placement
			(enabled no)
			(sheetname "")
		)
		(fill yes
			(thermal_gap 0.5)
			(thermal_bridge_width 0.5)
			(island_removal_mode 0)
		)
		(polygon
			(pts
				(arc
					(start 127.289814 -405.390096)
					(mid 126.530354 -405.390096)
					(end 127.289814 -405.390096)
				)
			)
		)
	)
	(zone
		(layers "B.Cu" "In9.Cu" "In11.Cu" "In13.Cu" "In15.Cu")
		(hatch none 0.5)
		(connect_pads
			(clearance 0)
		)
		(min_thickness 0.25)
		(keepout
			(tracks not_allowed)
			(vias allowed)
			(pads allowed)
			(copperpour not_allowed)
			(footprints allowed)
		)
		(placement
			(enabled no)
			(sheetname "")
		)
		(fill yes
			(thermal_gap 0.5)
			(thermal_bridge_width 0.5)
			(island_removal_mode 0)
		)
		(polygon
			(pts
				(arc
					(start 334.617314 -357.75773)
					(mid 333.913734 -357.75773)
					(end 334.617314 -357.75773)
				)
			)
		)
	)
	(zone
		(layers "B.Cu" "In9.Cu" "In11.Cu" "In13.Cu" "In15.Cu")
		(hatch none 0.5)
		(connect_pads
			(clearance 0)
		)
		(min_thickness 0.25)
		(keepout
			(tracks not_allowed)
			(vias allowed)
			(pads allowed)
			(copperpour not_allowed)
			(footprints allowed)
		)
		(placement
			(enabled no)
			(sheetname "")
		)
		(fill yes
			(thermal_gap 0.5)
			(thermal_bridge_width 0.5)
			(island_removal_mode 0)
		)
		(polygon
			(pts
				(arc
					(start 411.126178 -312.049922)
					(mid 410.473398 -312.049922)
					(end 411.126178 -312.049922)
				)
			)
		)
	)
	(zone
		(layers "B.Cu" "In9.Cu" "In11.Cu" "In13.Cu" "In15.Cu")
		(hatch none 0.5)
		(connect_pads
			(clearance 0)
		)
		(min_thickness 0.25)
		(keepout
			(tracks not_allowed)
			(vias allowed)
			(pads allowed)
			(copperpour not_allowed)
			(footprints allowed)
		)
		(placement
			(enabled no)
			(sheetname "")
		)
		(fill yes
			(thermal_gap 0.5)
			(thermal_bridge_width 0.5)
			(island_removal_mode 0)
		)
		(polygon
			(pts
				(arc
					(start 121.540778 -345.465146)
					(mid 120.837198 -345.465146)
					(end 121.540778 -345.465146)
				)
			)
		)
	)
	(zone
		(layers "B.Cu" "In9.Cu" "In11.Cu" "In13.Cu" "In15.Cu")
		(hatch none 0.5)
		(connect_pads
			(clearance 0)
		)
		(min_thickness 0.25)
		(keepout
			(tracks not_allowed)
			(vias allowed)
			(pads allowed)
			(copperpour not_allowed)
			(footprints allowed)
		)
		(placement
			(enabled no)
			(sheetname "")
		)
		(fill yes
			(thermal_gap 0.5)
			(thermal_bridge_width 0.5)
			(island_removal_mode 0)
		)
		(polygon
			(pts
				(arc
					(start 62.587632 -348.58579)
					(mid 61.884052 -348.58579)
					(end 62.587632 -348.58579)
				)
			)
		)
	)
	(zone
		(layers "B.Cu" "In9.Cu" "In11.Cu" "In13.Cu" "In15.Cu")
		(hatch none 0.5)
		(connect_pads
			(clearance 0)
		)
		(min_thickness 0.25)
		(keepout
			(tracks not_allowed)
			(vias allowed)
			(pads allowed)
			(copperpour not_allowed)
			(footprints allowed)
		)
		(placement
			(enabled no)
			(sheetname "")
		)
		(fill yes
			(thermal_gap 0.5)
			(thermal_bridge_width 0.5)
			(island_removal_mode 0)
		)
		(polygon
			(pts
				(arc
					(start 241.616484 -28.25877)
					(mid 240.912904 -28.25877)
					(end 241.616484 -28.25877)
				)
			)
		)
	)
	(zone
		(layers "B.Cu" "In9.Cu" "In11.Cu" "In13.Cu" "In15.Cu")
		(hatch none 0.5)
		(connect_pads
			(clearance 0)
		)
		(min_thickness 0.25)
		(keepout
			(tracks not_allowed)
			(vias allowed)
			(pads allowed)
			(copperpour not_allowed)
			(footprints allowed)
		)
		(placement
			(enabled no)
			(sheetname "")
		)
		(fill yes
			(thermal_gap 0.5)
			(thermal_bridge_width 0.5)
			(island_removal_mode 0)
		)
		(polygon
			(pts
				(arc
					(start 38.337998 -351.611438)
					(mid 37.634418 -351.611438)
					(end 38.337998 -351.611438)
				)
			)
		)
	)
	(zone
		(layers "B.Cu" "In9.Cu" "In11.Cu" "In13.Cu" "In15.Cu")
		(hatch none 0.5)
		(connect_pads
			(clearance 0)
		)
		(min_thickness 0.25)
		(keepout
			(tracks not_allowed)
			(vias allowed)
			(pads allowed)
			(copperpour not_allowed)
			(footprints allowed)
		)
		(placement
			(enabled no)
			(sheetname "")
		)
		(fill yes
			(thermal_gap 0.5)
			(thermal_bridge_width 0.5)
			(island_removal_mode 0)
		)
		(polygon
			(pts
				(arc
					(start 44.555918 -351.611438)
					(mid 43.852338 -351.611438)
					(end 44.555918 -351.611438)
				)
			)
		)
	)
	(zone
		(layers "B.Cu" "In9.Cu" "In11.Cu" "In13.Cu" "In15.Cu")
		(hatch none 0.5)
		(connect_pads
			(clearance 0)
		)
		(min_thickness 0.25)
		(keepout
			(tracks not_allowed)
			(vias allowed)
			(pads allowed)
			(copperpour not_allowed)
			(footprints allowed)
		)
		(placement
			(enabled no)
			(sheetname "")
		)
		(fill yes
			(thermal_gap 0.5)
			(thermal_bridge_width 0.5)
			(island_removal_mode 0)
		)
		(polygon
			(pts
				(arc
					(start 290.27628 -274.049744)
					(mid 289.6235 -274.049744)
					(end 290.27628 -274.049744)
				)
			)
		)
	)
	(zone
		(layers "B.Cu" "In9.Cu" "In11.Cu" "In13.Cu" "In15.Cu")
		(hatch none 0.5)
		(connect_pads
			(clearance 0)
		)
		(min_thickness 0.25)
		(keepout
			(tracks not_allowed)
			(vias allowed)
			(pads allowed)
			(copperpour not_allowed)
			(footprints allowed)
		)
		(placement
			(enabled no)
			(sheetname "")
		)
		(fill yes
			(thermal_gap 0.5)
			(thermal_bridge_width 0.5)
			(island_removal_mode 0)
		)
		(polygon
			(pts
				(arc
					(start 29.874718 -357.75773)
					(mid 29.171138 -357.75773)
					(end 29.874718 -357.75773)
				)
			)
		)
	)
	(zone
		(layers "B.Cu" "In9.Cu" "In11.Cu" "In13.Cu" "In15.Cu")
		(hatch none 0.5)
		(connect_pads
			(clearance 0)
		)
		(min_thickness 0.25)
		(keepout
			(tracks not_allowed)
			(vias allowed)
			(pads allowed)
			(copperpour not_allowed)
			(footprints allowed)
		)
		(placement
			(enabled no)
			(sheetname "")
		)
		(fill yes
			(thermal_gap 0.5)
			(thermal_bridge_width 0.5)
			(island_removal_mode 0)
		)
		(polygon
			(pts
				(arc
					(start 296.229532 -345.465146)
					(mid 295.525952 -345.465146)
					(end 296.229532 -345.465146)
				)
			)
		)
	)
	(zone
		(layers "B.Cu" "In9.Cu" "In11.Cu" "In13.Cu" "In15.Cu")
		(hatch none 0.5)
		(connect_pads
			(clearance 0)
		)
		(min_thickness 0.25)
		(keepout
			(tracks not_allowed)
			(vias allowed)
			(pads allowed)
			(copperpour not_allowed)
			(footprints allowed)
		)
		(placement
			(enabled no)
			(sheetname "")
		)
		(fill yes
			(thermal_gap 0.5)
			(thermal_bridge_width 0.5)
			(island_removal_mode 0)
		)
		(polygon
			(pts
				(arc
					(start 192.226438 -311.099962)
					(mid 191.573658 -311.099962)
					(end 192.226438 -311.099962)
				)
			)
		)
	)
	(zone
		(layers "B.Cu" "In9.Cu" "In11.Cu" "In13.Cu" "In15.Cu")
		(hatch none 0.5)
		(connect_pads
			(clearance 0)
		)
		(min_thickness 0.25)
		(keepout
			(tracks not_allowed)
			(vias allowed)
			(pads allowed)
			(copperpour not_allowed)
			(footprints allowed)
		)
		(placement
			(enabled no)
			(sheetname "")
		)
		(fill yes
			(thermal_gap 0.5)
			(thermal_bridge_width 0.5)
			(island_removal_mode 0)
		)
		(polygon
			(pts
				(arc
					(start 319.072514 -348.58579)
					(mid 318.368934 -348.58579)
					(end 319.072514 -348.58579)
				)
			)
		)
	)
	(zone
		(layers "B.Cu" "In9.Cu" "In11.Cu" "In13.Cu" "In15.Cu")
		(hatch none 0.5)
		(connect_pads
			(clearance 0)
		)
		(min_thickness 0.25)
		(keepout
			(tracks not_allowed)
			(vias allowed)
			(pads allowed)
			(copperpour not_allowed)
			(footprints allowed)
		)
		(placement
			(enabled no)
			(sheetname "")
		)
		(fill yes
			(thermal_gap 0.5)
			(thermal_bridge_width 0.5)
			(island_removal_mode 0)
		)
		(polygon
			(pts
				(arc
					(start 423.47642 -304.449734)
					(mid 422.82364 -304.449734)
					(end 423.47642 -304.449734)
				)
			)
		)
	)
	(zone
		(layers "B.Cu" "In9.Cu" "In11.Cu" "In13.Cu" "In15.Cu")
		(hatch none 0.5)
		(connect_pads
			(clearance 0)
		)
		(min_thickness 0.25)
		(keepout
			(tracks not_allowed)
			(vias allowed)
			(pads allowed)
			(copperpour not_allowed)
			(footprints allowed)
		)
		(placement
			(enabled no)
			(sheetname "")
		)
		(fill yes
			(thermal_gap 0.5)
			(thermal_bridge_width 0.5)
			(island_removal_mode 0)
		)
		(polygon
			(pts
				(arc
					(start 43.689778 -401.49018)
					(mid 42.930318 -401.49018)
					(end 43.689778 -401.49018)
				)
			)
		)
	)
	(zone
		(layers "B.Cu" "In9.Cu" "In11.Cu" "In13.Cu" "In15.Cu")
		(hatch none 0.5)
		(connect_pads
			(clearance 0)
		)
		(min_thickness 0.25)
		(keepout
			(tracks not_allowed)
			(vias allowed)
			(pads allowed)
			(copperpour not_allowed)
			(footprints allowed)
		)
		(placement
			(enabled no)
			(sheetname "")
		)
		(fill yes
			(thermal_gap 0.5)
			(thermal_bridge_width 0.5)
			(island_removal_mode 0)
		)
		(polygon
			(pts
				(arc
					(start 372.40337 -348.58579)
					(mid 371.69979 -348.58579)
					(end 372.40337 -348.58579)
				)
			)
		)
	)
	(zone
		(layers "B.Cu" "In9.Cu" "In11.Cu" "In13.Cu" "In15.Cu")
		(hatch none 0.5)
		(connect_pads
			(clearance 0)
		)
		(min_thickness 0.25)
		(keepout
			(tracks not_allowed)
			(vias allowed)
			(pads allowed)
			(copperpour not_allowed)
			(footprints allowed)
		)
		(placement
			(enabled no)
			(sheetname "")
		)
		(fill yes
			(thermal_gap 0.5)
			(thermal_bridge_width 0.5)
			(island_removal_mode 0)
		)
		(polygon
			(pts
				(arc
					(start 274.126198 -307.299868)
					(mid 273.473418 -307.299868)
					(end 274.126198 -307.299868)
				)
			)
		)
	)
	(zone
		(layers "B.Cu" "In9.Cu" "In11.Cu" "In13.Cu" "In15.Cu")
		(hatch none 0.5)
		(connect_pads
			(clearance 0)
		)
		(min_thickness 0.25)
		(keepout
			(tracks not_allowed)
			(vias allowed)
			(pads allowed)
			(copperpour not_allowed)
			(footprints allowed)
		)
		(placement
			(enabled no)
			(sheetname "")
		)
		(fill yes
			(thermal_gap 0.5)
			(thermal_bridge_width 0.5)
			(island_removal_mode 0)
		)
		(polygon
			(pts
				(arc
					(start 335.480914 -345.465146)
					(mid 334.777334 -345.465146)
					(end 335.480914 -345.465146)
				)
			)
		)
	)
	(zone
		(layers "B.Cu" "In9.Cu" "In11.Cu" "In13.Cu" "In15.Cu")
		(hatch none 0.5)
		(connect_pads
			(clearance 0)
		)
		(min_thickness 0.25)
		(keepout
			(tracks not_allowed)
			(vias allowed)
			(pads allowed)
			(copperpour not_allowed)
			(footprints allowed)
		)
		(placement
			(enabled no)
			(sheetname "")
		)
		(fill yes
			(thermal_gap 0.5)
			(thermal_bridge_width 0.5)
			(island_removal_mode 0)
		)
		(polygon
			(pts
				(arc
					(start 203.516484 -31.858712)
					(mid 202.812904 -31.858712)
					(end 203.516484 -31.858712)
				)
			)
		)
	)
	(zone
		(layers "B.Cu" "In9.Cu" "In11.Cu" "In13.Cu" "In15.Cu")
		(hatch none 0.5)
		(connect_pads
			(clearance 0)
		)
		(min_thickness 0.25)
		(keepout
			(tracks not_allowed)
			(vias allowed)
			(pads allowed)
			(copperpour not_allowed)
			(footprints allowed)
		)
		(placement
			(enabled no)
			(sheetname "")
		)
		(fill yes
			(thermal_gap 0.5)
			(thermal_bridge_width 0.5)
			(island_removal_mode 0)
		)
		(polygon
			(pts
				(arc
					(start 36.092638 -342.439498)
					(mid 35.389058 -342.439498)
					(end 36.092638 -342.439498)
				)
			)
		)
	)
	(zone
		(layers "B.Cu" "In9.Cu" "In11.Cu" "In13.Cu" "In15.Cu")
		(hatch none 0.5)
		(connect_pads
			(clearance 0)
		)
		(min_thickness 0.25)
		(keepout
			(tracks not_allowed)
			(vias allowed)
			(pads allowed)
			(copperpour not_allowed)
			(footprints allowed)
		)
		(placement
			(enabled no)
			(sheetname "")
		)
		(fill yes
			(thermal_gap 0.5)
			(thermal_bridge_width 0.5)
			(island_removal_mode 0)
		)
		(polygon
			(pts
				(arc
					(start 431.076354 -314.899802)
					(mid 430.423574 -314.899802)
					(end 431.076354 -314.899802)
				)
			)
		)
	)
	(zone
		(layers "B.Cu" "In9.Cu" "In11.Cu" "In13.Cu" "In15.Cu")
		(hatch none 0.5)
		(connect_pads
			(clearance 0)
		)
		(min_thickness 0.25)
		(keepout
			(tracks not_allowed)
			(vias allowed)
			(pads allowed)
			(copperpour not_allowed)
			(footprints allowed)
		)
		(placement
			(enabled no)
			(sheetname "")
		)
		(fill yes
			(thermal_gap 0.5)
			(thermal_bridge_width 0.5)
			(island_removal_mode 0)
		)
		(polygon
			(pts
				(arc
					(start 303.26965 -402.790152)
					(mid 302.51019 -402.790152)
					(end 303.26965 -402.790152)
				)
			)
		)
	)
	(zone
		(layers "B.Cu" "In9.Cu" "In11.Cu" "In13.Cu" "In15.Cu")
		(hatch none 0.5)
		(connect_pads
			(clearance 0)
		)
		(min_thickness 0.25)
		(keepout
			(tracks not_allowed)
			(vias allowed)
			(pads allowed)
			(copperpour not_allowed)
			(footprints allowed)
		)
		(placement
			(enabled no)
			(sheetname "")
		)
		(fill yes
			(thermal_gap 0.5)
			(thermal_bridge_width 0.5)
			(island_removal_mode 0)
		)
		(polygon
			(pts
				(arc
					(start 281.726132 -275.949918)
					(mid 281.073352 -275.949918)
					(end 281.726132 -275.949918)
				)
			)
		)
	)
	(zone
		(layers "B.Cu" "In9.Cu" "In11.Cu" "In13.Cu" "In15.Cu")
		(hatch none 0.5)
		(connect_pads
			(clearance 0)
		)
		(min_thickness 0.25)
		(keepout
			(tracks not_allowed)
			(vias allowed)
			(pads allowed)
			(copperpour not_allowed)
			(footprints allowed)
		)
		(placement
			(enabled no)
			(sheetname "")
		)
		(fill yes
			(thermal_gap 0.5)
			(thermal_bridge_width 0.5)
			(island_removal_mode 0)
		)
		(polygon
			(pts
				(arc
					(start 276.026118 -308.249828)
					(mid 275.373338 -308.249828)
					(end 276.026118 -308.249828)
				)
			)
		)
	)
	(zone
		(layers "B.Cu" "In9.Cu" "In11.Cu" "In13.Cu" "In15.Cu")
		(hatch none 0.5)
		(connect_pads
			(clearance 0)
		)
		(min_thickness 0.25)
		(keepout
			(tracks not_allowed)
			(vias allowed)
			(pads allowed)
			(copperpour not_allowed)
			(footprints allowed)
		)
		(placement
			(enabled no)
			(sheetname "")
		)
		(fill yes
			(thermal_gap 0.5)
			(thermal_bridge_width 0.5)
			(island_removal_mode 0)
		)
		(polygon
			(pts
				(arc
					(start 67.941952 -351.611438)
					(mid 67.238372 -351.611438)
					(end 67.941952 -351.611438)
				)
			)
		)
	)
	(zone
		(layers "B.Cu" "In9.Cu" "In11.Cu" "In13.Cu" "In15.Cu")
		(hatch none 0.5)
		(connect_pads
			(clearance 0)
		)
		(min_thickness 0.25)
		(keepout
			(tracks not_allowed)
			(vias allowed)
			(pads allowed)
			(copperpour not_allowed)
			(footprints allowed)
		)
		(placement
			(enabled no)
			(sheetname "")
		)
		(fill yes
			(thermal_gap 0.5)
			(thermal_bridge_width 0.5)
			(island_removal_mode 0)
		)
		(polygon
			(pts
				(arc
					(start 389.06958 -404.290022)
					(mid 388.31012 -404.290022)
					(end 389.06958 -404.290022)
				)
			)
		)
	)
	(zone
		(layers "B.Cu" "In9.Cu" "In11.Cu" "In13.Cu" "In15.Cu")
		(hatch none 0.5)
		(connect_pads
			(clearance 0)
		)
		(min_thickness 0.25)
		(keepout
			(tracks not_allowed)
			(vias allowed)
			(pads allowed)
			(copperpour not_allowed)
			(footprints allowed)
		)
		(placement
			(enabled no)
			(sheetname "")
		)
		(fill yes
			(thermal_gap 0.5)
			(thermal_bridge_width 0.5)
			(island_removal_mode 0)
		)
		(polygon
			(pts
				(arc
					(start 129.489708 -383.490216)
					(mid 128.730248 -383.490216)
					(end 129.489708 -383.490216)
				)
			)
		)
	)
	(zone
		(layers "B.Cu" "In9.Cu" "In11.Cu" "In13.Cu" "In15.Cu")
		(hatch none 0.5)
		(connect_pads
			(clearance 0)
		)
		(min_thickness 0.25)
		(keepout
			(tracks not_allowed)
			(vias allowed)
			(pads allowed)
			(copperpour not_allowed)
			(footprints allowed)
		)
		(placement
			(enabled no)
			(sheetname "")
		)
		(fill yes
			(thermal_gap 0.5)
			(thermal_bridge_width 0.5)
			(island_removal_mode 0)
		)
		(polygon
			(pts
				(arc
					(start 400.676364 -273.099784)
					(mid 400.023584 -273.099784)
					(end 400.676364 -273.099784)
				)
			)
		)
	)
	(zone
		(layers "B.Cu" "In9.Cu" "In11.Cu" "In13.Cu" "In15.Cu")
		(hatch none 0.5)
		(connect_pads
			(clearance 0)
		)
		(min_thickness 0.25)
		(keepout
			(tracks not_allowed)
			(vias allowed)
			(pads allowed)
			(copperpour not_allowed)
			(footprints allowed)
		)
		(placement
			(enabled no)
			(sheetname "")
		)
		(fill yes
			(thermal_gap 0.5)
			(thermal_bridge_width 0.5)
			(island_removal_mode 0)
		)
		(polygon
			(pts
				(arc
					(start 87.68969 -380.69012)
					(mid 86.93023 -380.69012)
					(end 87.68969 -380.69012)
				)
			)
		)
	)
	(zone
		(layers "B.Cu" "In9.Cu" "In11.Cu" "In13.Cu" "In15.Cu")
		(hatch none 0.5)
		(connect_pads
			(clearance 0)
		)
		(min_thickness 0.25)
		(keepout
			(tracks not_allowed)
			(vias allowed)
			(pads allowed)
			(copperpour not_allowed)
			(footprints allowed)
		)
		(placement
			(enabled no)
			(sheetname "")
		)
		(fill yes
			(thermal_gap 0.5)
			(thermal_bridge_width 0.5)
			(island_removal_mode 0)
		)
		(polygon
			(pts
				(arc
					(start 406.376378 -313.949842)
					(mid 405.723598 -313.949842)
					(end 406.376378 -313.949842)
				)
			)
		)
	)
	(zone
		(layers "B.Cu" "In9.Cu" "In11.Cu" "In13.Cu" "In15.Cu")
		(hatch none 0.5)
		(connect_pads
			(clearance 0)
		)
		(min_thickness 0.25)
		(keepout
			(tracks not_allowed)
			(vias allowed)
			(pads allowed)
			(copperpour not_allowed)
			(footprints allowed)
		)
		(placement
			(enabled no)
			(sheetname "")
		)
		(fill yes
			(thermal_gap 0.5)
			(thermal_bridge_width 0.5)
			(island_removal_mode 0)
		)
		(polygon
			(pts
				(arc
					(start 287.766252 -348.58579)
					(mid 287.062672 -348.58579)
					(end 287.766252 -348.58579)
				)
			)
		)
	)
	(zone
		(layers "B.Cu" "In9.Cu" "In11.Cu" "In13.Cu" "In15.Cu")
		(hatch none 0.5)
		(connect_pads
			(clearance 0)
		)
		(min_thickness 0.25)
		(keepout
			(tracks not_allowed)
			(vias allowed)
			(pads allowed)
			(copperpour not_allowed)
			(footprints allowed)
		)
		(placement
			(enabled no)
			(sheetname "")
		)
		(fill yes
			(thermal_gap 0.5)
			(thermal_bridge_width 0.5)
			(island_removal_mode 0)
		)
		(polygon
			(pts
				(arc
					(start 169.426382 -312.049922)
					(mid 168.773602 -312.049922)
					(end 169.426382 -312.049922)
				)
			)
		)
	)
	(zone
		(layers "B.Cu" "In9.Cu" "In11.Cu" "In13.Cu" "In15.Cu")
		(hatch none 0.5)
		(connect_pads
			(clearance 0)
		)
		(min_thickness 0.25)
		(keepout
			(tracks not_allowed)
			(vias allowed)
			(pads allowed)
			(copperpour not_allowed)
			(footprints allowed)
		)
		(placement
			(enabled no)
			(sheetname "")
		)
		(fill yes
			(thermal_gap 0.5)
			(thermal_bridge_width 0.5)
			(island_removal_mode 0)
		)
		(polygon
			(pts
				(arc
					(start 22.793198 -342.439498)
					(mid 22.089618 -342.439498)
					(end 22.793198 -342.439498)
				)
			)
		)
	)
	(zone
		(layers "B.Cu" "In9.Cu" "In11.Cu" "In13.Cu" "In15.Cu")
		(hatch none 0.5)
		(connect_pads
			(clearance 0)
		)
		(min_thickness 0.25)
		(keepout
			(tracks not_allowed)
			(vias allowed)
			(pads allowed)
			(copperpour not_allowed)
			(footprints allowed)
		)
		(placement
			(enabled no)
			(sheetname "")
		)
		(fill yes
			(thermal_gap 0.5)
			(thermal_bridge_width 0.5)
			(island_removal_mode 0)
		)
		(polygon
			(pts
				(arc
					(start 149.662388 -33.65881)
					(mid 148.958808 -33.65881)
					(end 149.662388 -33.65881)
				)
			)
		)
	)
	(zone
		(layers "B.Cu" "In9.Cu" "In11.Cu" "In13.Cu" "In15.Cu")
		(hatch none 0.5)
		(connect_pads
			(clearance 0)
		)
		(min_thickness 0.25)
		(keepout
			(tracks not_allowed)
			(vias allowed)
			(pads allowed)
			(copperpour not_allowed)
			(footprints allowed)
		)
		(placement
			(enabled no)
			(sheetname "")
		)
		(fill yes
			(thermal_gap 0.5)
			(thermal_bridge_width 0.5)
			(island_removal_mode 0)
		)
		(polygon
			(pts
				(arc
					(start 323.045074 -354.732082)
					(mid 322.341494 -354.732082)
					(end 323.045074 -354.732082)
				)
			)
		)
	)
	(zone
		(layers "B.Cu" "In9.Cu" "In11.Cu" "In13.Cu" "In15.Cu")
		(hatch none 0.5)
		(connect_pads
			(clearance 0)
		)
		(min_thickness 0.25)
		(keepout
			(tracks not_allowed)
			(vias allowed)
			(pads allowed)
			(copperpour not_allowed)
			(footprints allowed)
		)
		(placement
			(enabled no)
			(sheetname "")
		)
		(fill yes
			(thermal_gap 0.5)
			(thermal_bridge_width 0.5)
			(island_removal_mode 0)
		)
		(polygon
			(pts
				(arc
					(start 128.622298 -357.75773)
					(mid 127.918718 -357.75773)
					(end 128.622298 -357.75773)
				)
			)
		)
	)
	(zone
		(layers "B.Cu" "In9.Cu" "In11.Cu" "In13.Cu" "In15.Cu")
		(hatch none 0.5)
		(connect_pads
			(clearance 0)
		)
		(min_thickness 0.25)
		(keepout
			(tracks not_allowed)
			(vias allowed)
			(pads allowed)
			(copperpour not_allowed)
			(footprints allowed)
		)
		(placement
			(enabled no)
			(sheetname "")
		)
		(fill yes
			(thermal_gap 0.5)
			(thermal_bridge_width 0.5)
			(island_removal_mode 0)
		)
		(polygon
			(pts
				(arc
					(start 398.77619 -274.049744)
					(mid 398.12341 -274.049744)
					(end 398.77619 -274.049744)
				)
			)
		)
	)
	(zone
		(layers "B.Cu" "In9.Cu" "In11.Cu" "In13.Cu" "In15.Cu")
		(hatch none 0.5)
		(connect_pads
			(clearance 0)
		)
		(min_thickness 0.25)
		(keepout
			(tracks not_allowed)
			(vias allowed)
			(pads allowed)
			(copperpour not_allowed)
			(footprints allowed)
		)
		(placement
			(enabled no)
			(sheetname "")
		)
		(fill yes
			(thermal_gap 0.5)
			(thermal_bridge_width 0.5)
			(island_removal_mode 0)
		)
		(polygon
			(pts
				(arc
					(start 284.576266 -273.099784)
					(mid 283.923486 -273.099784)
					(end 284.576266 -273.099784)
				)
			)
		)
	)
	(zone
		(layers "B.Cu" "In9.Cu" "In11.Cu" "In13.Cu" "In15.Cu")
		(hatch none 0.5)
		(connect_pads
			(clearance 0)
		)
		(min_thickness 0.25)
		(keepout
			(tracks not_allowed)
			(vias allowed)
			(pads allowed)
			(copperpour not_allowed)
			(footprints allowed)
		)
		(placement
			(enabled no)
			(sheetname "")
		)
		(fill yes
			(thermal_gap 0.5)
			(thermal_bridge_width 0.5)
			(island_removal_mode 0)
		)
		(polygon
			(pts
				(arc
					(start 290.875212 -354.732082)
					(mid 290.171632 -354.732082)
					(end 290.875212 -354.732082)
				)
			)
		)
	)
	(zone
		(layers "B.Cu" "In9.Cu" "In11.Cu" "In13.Cu" "In15.Cu")
		(hatch none 0.5)
		(connect_pads
			(clearance 0)
		)
		(min_thickness 0.25)
		(keepout
			(tracks not_allowed)
			(vias allowed)
			(pads allowed)
			(copperpour not_allowed)
			(footprints allowed)
		)
		(placement
			(enabled no)
			(sheetname "")
		)
		(fill yes
			(thermal_gap 0.5)
			(thermal_bridge_width 0.5)
			(island_removal_mode 0)
		)
		(polygon
			(pts
				(arc
					(start 181.191662 -351.611438)
					(mid 180.488082 -351.611438)
					(end 181.191662 -351.611438)
				)
			)
		)
	)
	(zone
		(layers "B.Cu" "In9.Cu" "In11.Cu" "In13.Cu" "In15.Cu")
		(hatch none 0.5)
		(connect_pads
			(clearance 0)
		)
		(min_thickness 0.25)
		(keepout
			(tracks not_allowed)
			(vias allowed)
			(pads allowed)
			(copperpour not_allowed)
			(footprints allowed)
		)
		(placement
			(enabled no)
			(sheetname "")
		)
		(fill yes
			(thermal_gap 0.5)
			(thermal_bridge_width 0.5)
			(island_removal_mode 0)
		)
		(polygon
			(pts
				(arc
					(start 303.576228 -313.949842)
					(mid 302.923448 -313.949842)
					(end 303.576228 -313.949842)
				)
			)
		)
	)
	(zone
		(layers "B.Cu" "In9.Cu" "In11.Cu" "In13.Cu" "In15.Cu")
		(hatch none 0.5)
		(connect_pads
			(clearance 0)
		)
		(min_thickness 0.25)
		(keepout
			(tracks not_allowed)
			(vias allowed)
			(pads allowed)
			(copperpour not_allowed)
			(footprints allowed)
		)
		(placement
			(enabled no)
			(sheetname "")
		)
		(fill yes
			(thermal_gap 0.5)
			(thermal_bridge_width 0.5)
			(island_removal_mode 0)
		)
		(polygon
			(pts
				(arc
					(start 424.269662 -370.489988)
					(mid 423.510202 -370.489988)
					(end 424.269662 -370.489988)
				)
			)
		)
	)
	(zone
		(layers "B.Cu" "In9.Cu" "In11.Cu" "In13.Cu" "In15.Cu")
		(hatch none 0.5)
		(connect_pads
			(clearance 0)
		)
		(min_thickness 0.25)
		(keepout
			(tracks not_allowed)
			(vias allowed)
			(pads allowed)
			(copperpour not_allowed)
			(footprints allowed)
		)
		(placement
			(enabled no)
			(sheetname "")
		)
		(fill yes
			(thermal_gap 0.5)
			(thermal_bridge_width 0.5)
			(island_removal_mode 0)
		)
		(polygon
			(pts
				(arc
					(start 293.12616 -312.049922)
					(mid 292.47338 -312.049922)
					(end 293.12616 -312.049922)
				)
			)
		)
	)
	(zone
		(layers "B.Cu" "In9.Cu" "In11.Cu" "In13.Cu" "In15.Cu")
		(hatch none 0.5)
		(connect_pads
			(clearance 0)
		)
		(min_thickness 0.25)
		(keepout
			(tracks not_allowed)
			(vias allowed)
			(pads allowed)
			(copperpour not_allowed)
			(footprints allowed)
		)
		(placement
			(enabled no)
			(sheetname "")
		)
		(fill yes
			(thermal_gap 0.5)
			(thermal_bridge_width 0.5)
			(island_removal_mode 0)
		)
		(polygon
			(pts
				(arc
					(start 7.562342 -33.65881)
					(mid 6.858762 -33.65881)
					(end 7.562342 -33.65881)
				)
			)
		)
	)
	(zone
		(layers "B.Cu" "In9.Cu" "In11.Cu" "In13.Cu" "In15.Cu")
		(hatch none 0.5)
		(connect_pads
			(clearance 0)
		)
		(min_thickness 0.25)
		(keepout
			(tracks not_allowed)
			(vias allowed)
			(pads allowed)
			(copperpour not_allowed)
			(footprints allowed)
		)
		(placement
			(enabled no)
			(sheetname "")
		)
		(fill yes
			(thermal_gap 0.5)
			(thermal_bridge_width 0.5)
			(island_removal_mode 0)
		)
		(polygon
			(pts
				(arc
					(start 77.268832 -357.75773)
					(mid 76.565252 -357.75773)
					(end 77.268832 -357.75773)
				)
			)
		)
	)
	(zone
		(layers "B.Cu" "In9.Cu" "In11.Cu" "In13.Cu" "In15.Cu")
		(hatch none 0.5)
		(connect_pads
			(clearance 0)
		)
		(min_thickness 0.25)
		(keepout
			(tracks not_allowed)
			(vias allowed)
			(pads allowed)
			(copperpour not_allowed)
			(footprints allowed)
		)
		(placement
			(enabled no)
			(sheetname "")
		)
		(fill yes
			(thermal_gap 0.5)
			(thermal_bridge_width 0.5)
			(island_removal_mode 0)
		)
		(polygon
			(pts
				(arc
					(start 89.704672 -357.75773)
					(mid 89.001092 -357.75773)
					(end 89.704672 -357.75773)
				)
			)
		)
	)
	(zone
		(layers "B.Cu" "In9.Cu" "In11.Cu" "In13.Cu" "In15.Cu")
		(hatch none 0.5)
		(connect_pads
			(clearance 0)
		)
		(min_thickness 0.25)
		(keepout
			(tracks not_allowed)
			(vias allowed)
			(pads allowed)
			(copperpour not_allowed)
			(footprints allowed)
		)
		(placement
			(enabled no)
			(sheetname "")
		)
		(fill yes
			(thermal_gap 0.5)
			(thermal_bridge_width 0.5)
			(island_removal_mode 0)
		)
		(polygon
			(pts
				(arc
					(start 7.562342 -30.058868)
					(mid 6.858762 -30.058868)
					(end 7.562342 -30.058868)
				)
			)
		)
	)
	(zone
		(layers "B.Cu" "In9.Cu" "In11.Cu" "In13.Cu" "In15.Cu")
		(hatch none 0.5)
		(connect_pads
			(clearance 0)
		)
		(min_thickness 0.25)
		(keepout
			(tracks not_allowed)
			(vias allowed)
			(pads allowed)
			(copperpour not_allowed)
			(footprints allowed)
		)
		(placement
			(enabled no)
			(sheetname "")
		)
		(fill yes
			(thermal_gap 0.5)
			(thermal_bridge_width 0.5)
			(island_removal_mode 0)
		)
		(polygon
			(pts
				(arc
					(start 128.622298 -354.732082)
					(mid 127.918718 -354.732082)
					(end 128.622298 -354.732082)
				)
			)
		)
	)
	(zone
		(layers "B.Cu" "In9.Cu" "In11.Cu" "In13.Cu" "In15.Cu")
		(hatch none 0.5)
		(connect_pads
			(clearance 0)
		)
		(min_thickness 0.25)
		(keepout
			(tracks not_allowed)
			(vias allowed)
			(pads allowed)
			(copperpour not_allowed)
			(footprints allowed)
		)
		(placement
			(enabled no)
			(sheetname "")
		)
		(fill yes
			(thermal_gap 0.5)
			(thermal_bridge_width 0.5)
			(island_removal_mode 0)
		)
		(polygon
			(pts
				(arc
					(start 303.26965 -375.490232)
					(mid 302.51019 -375.490232)
					(end 303.26965 -375.490232)
				)
			)
		)
	)
	(zone
		(layers "B.Cu" "In9.Cu" "In11.Cu" "In13.Cu" "In15.Cu")
		(hatch none 0.5)
		(connect_pads
			(clearance 0)
		)
		(min_thickness 0.25)
		(keepout
			(tracks not_allowed)
			(vias allowed)
			(pads allowed)
			(copperpour not_allowed)
			(footprints allowed)
		)
		(placement
			(enabled no)
			(sheetname "")
		)
		(fill yes
			(thermal_gap 0.5)
			(thermal_bridge_width 0.5)
			(island_removal_mode 0)
		)
		(polygon
			(pts
				(arc
					(start 293.61638 -32.722312)
					(mid 292.9128 -32.722312)
					(end 293.61638 -32.722312)
				)
			)
		)
	)
	(zone
		(layers "B.Cu" "In9.Cu" "In11.Cu" "In13.Cu" "In15.Cu")
		(hatch none 0.5)
		(connect_pads
			(clearance 0)
		)
		(min_thickness 0.25)
		(keepout
			(tracks not_allowed)
			(vias allowed)
			(pads allowed)
			(copperpour not_allowed)
			(footprints allowed)
		)
		(placement
			(enabled no)
			(sheetname "")
		)
		(fill yes
			(thermal_gap 0.5)
			(thermal_bridge_width 0.5)
			(island_removal_mode 0)
		)
		(polygon
			(pts
				(arc
					(start 165.646862 -357.75773)
					(mid 164.943282 -357.75773)
					(end 165.646862 -357.75773)
				)
			)
		)
	)
	(zone
		(layers "B.Cu" "In9.Cu" "In11.Cu" "In13.Cu" "In15.Cu")
		(hatch none 0.5)
		(connect_pads
			(clearance 0)
		)
		(min_thickness 0.25)
		(keepout
			(tracks not_allowed)
			(vias allowed)
			(pads allowed)
			(copperpour not_allowed)
			(footprints allowed)
		)
		(placement
			(enabled no)
			(sheetname "")
		)
		(fill yes
			(thermal_gap 0.5)
			(thermal_bridge_width 0.5)
			(island_removal_mode 0)
		)
		(polygon
			(pts
				(arc
					(start 78.889606 -405.390096)
					(mid 78.130146 -405.390096)
					(end 78.889606 -405.390096)
				)
			)
		)
	)
	(zone
		(layers "B.Cu" "In9.Cu" "In11.Cu" "In13.Cu" "In15.Cu")
		(hatch none 0.5)
		(connect_pads
			(clearance 0)
		)
		(min_thickness 0.25)
		(keepout
			(tracks not_allowed)
			(vias allowed)
			(pads allowed)
			(copperpour not_allowed)
			(footprints allowed)
		)
		(placement
			(enabled no)
			(sheetname "")
		)
		(fill yes
			(thermal_gap 0.5)
			(thermal_bridge_width 0.5)
			(island_removal_mode 0)
		)
		(polygon
			(pts
				(arc
					(start 177.976276 -312.999882)
					(mid 177.323496 -312.999882)
					(end 177.976276 -312.999882)
				)
			)
		)
	)
	(zone
		(layers "B.Cu" "In9.Cu" "In11.Cu" "In13.Cu" "In15.Cu")
		(hatch none 0.5)
		(connect_pads
			(clearance 0)
		)
		(min_thickness 0.25)
		(keepout
			(tracks not_allowed)
			(vias allowed)
			(pads allowed)
			(copperpour not_allowed)
			(footprints allowed)
		)
		(placement
			(enabled no)
			(sheetname "")
		)
		(fill yes
			(thermal_gap 0.5)
			(thermal_bridge_width 0.5)
			(island_removal_mode 0)
		)
		(polygon
			(pts
				(arc
					(start 431.409602 -357.75773)
					(mid 430.706022 -357.75773)
					(end 431.409602 -357.75773)
				)
			)
		)
	)
	(zone
		(layers "B.Cu" "In9.Cu" "In11.Cu" "In13.Cu" "In15.Cu")
		(hatch none 0.5)
		(connect_pads
			(clearance 0)
		)
		(min_thickness 0.25)
		(keepout
			(tracks not_allowed)
			(vias allowed)
			(pads allowed)
			(copperpour not_allowed)
			(footprints allowed)
		)
		(placement
			(enabled no)
			(sheetname "")
		)
		(fill yes
			(thermal_gap 0.5)
			(thermal_bridge_width 0.5)
			(island_removal_mode 0)
		)
		(polygon
			(pts
				(arc
					(start 407.862278 -30.922468)
					(mid 407.158698 -30.922468)
					(end 407.862278 -30.922468)
				)
			)
		)
	)
	(zone
		(layers "B.Cu" "In9.Cu" "In11.Cu" "In13.Cu" "In15.Cu")
		(hatch none 0.5)
		(connect_pads
			(clearance 0)
		)
		(min_thickness 0.25)
		(keepout
			(tracks not_allowed)
			(vias allowed)
			(pads allowed)
			(copperpour not_allowed)
			(footprints allowed)
		)
		(placement
			(enabled no)
			(sheetname "")
		)
		(fill yes
			(thermal_gap 0.5)
			(thermal_bridge_width 0.5)
			(island_removal_mode 0)
		)
		(polygon
			(pts
				(arc
					(start 430.869598 -397.59001)
					(mid 430.110138 -397.59001)
					(end 430.869598 -397.59001)
				)
			)
		)
	)
	(zone
		(layers "B.Cu" "In9.Cu" "In11.Cu" "In13.Cu" "In15.Cu")
		(hatch none 0.5)
		(connect_pads
			(clearance 0)
		)
		(min_thickness 0.25)
		(keepout
			(tracks not_allowed)
			(vias allowed)
			(pads allowed)
			(copperpour not_allowed)
			(footprints allowed)
		)
		(placement
			(enabled no)
			(sheetname "")
		)
		(fill yes
			(thermal_gap 0.5)
			(thermal_bridge_width 0.5)
			(island_removal_mode 0)
		)
		(polygon
			(pts
				(arc
					(start 345.069668 -379.590046)
					(mid 344.310208 -379.590046)
					(end 345.069668 -379.590046)
				)
			)
		)
	)
	(zone
		(layers "B.Cu" "In9.Cu" "In11.Cu" "In13.Cu" "In15.Cu")
		(hatch none 0.5)
		(connect_pads
			(clearance 0)
		)
		(min_thickness 0.25)
		(keepout
			(tracks not_allowed)
			(vias allowed)
			(pads allowed)
			(copperpour not_allowed)
			(footprints allowed)
		)
		(placement
			(enabled no)
			(sheetname "")
		)
		(fill yes
			(thermal_gap 0.5)
			(thermal_bridge_width 0.5)
			(island_removal_mode 0)
		)
		(polygon
			(pts
				(arc
					(start 274.126198 -312.049922)
					(mid 273.473418 -312.049922)
					(end 274.126198 -312.049922)
				)
			)
		)
	)
	(zone
		(layers "B.Cu" "In9.Cu" "In11.Cu" "In13.Cu" "In15.Cu")
		(hatch none 0.5)
		(connect_pads
			(clearance 0)
		)
		(min_thickness 0.25)
		(keepout
			(tracks not_allowed)
			(vias allowed)
			(pads allowed)
			(copperpour not_allowed)
			(footprints allowed)
		)
		(placement
			(enabled no)
			(sheetname "")
		)
		(fill yes
			(thermal_gap 0.5)
			(thermal_bridge_width 0.5)
			(island_removal_mode 0)
		)
		(polygon
			(pts
				(arc
					(start 84.350352 -357.75773)
					(mid 83.646772 -357.75773)
					(end 84.350352 -357.75773)
				)
			)
		)
	)
	(zone
		(layers "B.Cu" "In9.Cu" "In11.Cu" "In13.Cu" "In15.Cu")
		(hatch none 0.5)
		(connect_pads
			(clearance 0)
		)
		(min_thickness 0.25)
		(keepout
			(tracks not_allowed)
			(vias allowed)
			(pads allowed)
			(copperpour not_allowed)
			(footprints allowed)
		)
		(placement
			(enabled no)
			(sheetname "")
		)
		(fill yes
			(thermal_gap 0.5)
			(thermal_bridge_width 0.5)
			(island_removal_mode 0)
		)
		(polygon
			(pts
				(arc
					(start 329.262994 -357.75773)
					(mid 328.559414 -357.75773)
					(end 329.262994 -357.75773)
				)
			)
		)
	)
	(zone
		(layers "B.Cu" "In9.Cu" "In11.Cu" "In13.Cu" "In15.Cu")
		(hatch none 0.5)
		(connect_pads
			(clearance 0)
		)
		(min_thickness 0.25)
		(keepout
			(tracks not_allowed)
			(vias allowed)
			(pads allowed)
			(copperpour not_allowed)
			(footprints allowed)
		)
		(placement
			(enabled no)
			(sheetname "")
		)
		(fill yes
			(thermal_gap 0.5)
			(thermal_bridge_width 0.5)
			(island_removal_mode 0)
		)
		(polygon
			(pts
				(arc
					(start 269.112492 -351.611438)
					(mid 268.408912 -351.611438)
					(end 269.112492 -351.611438)
				)
			)
		)
	)
	(zone
		(layers "B.Cu" "In9.Cu" "In11.Cu" "In13.Cu" "In15.Cu")
		(hatch none 0.5)
		(connect_pads
			(clearance 0)
		)
		(min_thickness 0.25)
		(keepout
			(tracks not_allowed)
			(vias allowed)
			(pads allowed)
			(copperpour not_allowed)
			(footprints allowed)
		)
		(placement
			(enabled no)
			(sheetname "")
		)
		(fill yes
			(thermal_gap 0.5)
			(thermal_bridge_width 0.5)
			(island_removal_mode 0)
		)
		(polygon
			(pts
				(arc
					(start 193.176398 -307.299868)
					(mid 192.523618 -307.299868)
					(end 193.176398 -307.299868)
				)
			)
		)
	)
	(zone
		(layers "B.Cu" "In9.Cu" "In11.Cu" "In13.Cu" "In15.Cu")
		(hatch none 0.5)
		(connect_pads
			(clearance 0)
		)
		(min_thickness 0.25)
		(keepout
			(tracks not_allowed)
			(vias allowed)
			(pads allowed)
			(copperpour not_allowed)
			(footprints allowed)
		)
		(placement
			(enabled no)
			(sheetname "")
		)
		(fill yes
			(thermal_gap 0.5)
			(thermal_bridge_width 0.5)
			(island_removal_mode 0)
		)
		(polygon
			(pts
				(arc
					(start 289.32632 -274.999958)
					(mid 288.67354 -274.999958)
					(end 289.32632 -274.999958)
				)
			)
		)
	)
	(zone
		(layers "B.Cu" "In9.Cu" "In11.Cu" "In13.Cu" "In15.Cu")
		(hatch none 0.5)
		(connect_pads
			(clearance 0)
		)
		(min_thickness 0.25)
		(keepout
			(tracks not_allowed)
			(vias allowed)
			(pads allowed)
			(copperpour not_allowed)
			(footprints allowed)
		)
		(placement
			(enabled no)
			(sheetname "")
		)
		(fill yes
			(thermal_gap 0.5)
			(thermal_bridge_width 0.5)
			(island_removal_mode 0)
		)
		(polygon
			(pts
				(arc
					(start 312.854594 -351.611438)
					(mid 312.151014 -351.611438)
					(end 312.854594 -351.611438)
				)
			)
		)
	)
	(zone
		(layers "B.Cu" "In9.Cu" "In11.Cu" "In13.Cu" "In15.Cu")
		(hatch none 0.5)
		(connect_pads
			(clearance 0)
		)
		(min_thickness 0.25)
		(keepout
			(tracks not_allowed)
			(vias allowed)
			(pads allowed)
			(copperpour not_allowed)
			(footprints allowed)
		)
		(placement
			(enabled no)
			(sheetname "")
		)
		(fill yes
			(thermal_gap 0.5)
			(thermal_bridge_width 0.5)
			(island_removal_mode 0)
		)
		(polygon
			(pts
				(arc
					(start 42.310558 -342.439498)
					(mid 41.606978 -342.439498)
					(end 42.310558 -342.439498)
				)
			)
		)
	)
	(zone
		(layers "B.Cu" "In9.Cu" "In11.Cu" "In13.Cu" "In15.Cu")
		(hatch none 0.5)
		(connect_pads
			(clearance 0)
		)
		(min_thickness 0.25)
		(keepout
			(tracks not_allowed)
			(vias allowed)
			(pads allowed)
			(copperpour not_allowed)
			(footprints allowed)
		)
		(placement
			(enabled no)
			(sheetname "")
		)
		(fill yes
			(thermal_gap 0.5)
			(thermal_bridge_width 0.5)
			(island_removal_mode 0)
		)
		(polygon
			(pts
				(arc
					(start 195.076318 -313.949842)
					(mid 194.423538 -313.949842)
					(end 195.076318 -313.949842)
				)
			)
		)
	)
	(zone
		(layers "B.Cu" "In9.Cu" "In11.Cu" "In13.Cu" "In15.Cu")
		(hatch none 0.5)
		(connect_pads
			(clearance 0)
		)
		(min_thickness 0.25)
		(keepout
			(tracks not_allowed)
			(vias allowed)
			(pads allowed)
			(copperpour not_allowed)
			(footprints allowed)
		)
		(placement
			(enabled no)
			(sheetname "")
		)
		(fill yes
			(thermal_gap 0.5)
			(thermal_bridge_width 0.5)
			(island_removal_mode 0)
		)
		(polygon
			(pts
				(arc
					(start 401.626324 -275.949918)
					(mid 400.973544 -275.949918)
					(end 401.626324 -275.949918)
				)
			)
		)
	)
	(zone
		(layers "B.Cu" "In9.Cu" "In11.Cu" "In13.Cu" "In15.Cu")
		(hatch none 0.5)
		(connect_pads
			(clearance 0)
		)
		(min_thickness 0.25)
		(keepout
			(tracks not_allowed)
			(vias allowed)
			(pads allowed)
			(copperpour not_allowed)
			(footprints allowed)
		)
		(placement
			(enabled no)
			(sheetname "")
		)
		(fill yes
			(thermal_gap 0.5)
			(thermal_bridge_width 0.5)
			(island_removal_mode 0)
		)
		(polygon
			(pts
				(arc
					(start 397.27505 -351.611438)
					(mid 396.57147 -351.611438)
					(end 397.27505 -351.611438)
				)
			)
		)
	)
	(zone
		(layers "B.Cu" "In9.Cu" "In11.Cu" "In13.Cu" "In15.Cu")
		(hatch none 0.5)
		(connect_pads
			(clearance 0)
		)
		(min_thickness 0.25)
		(keepout
			(tracks not_allowed)
			(vias allowed)
			(pads allowed)
			(copperpour not_allowed)
			(footprints allowed)
		)
		(placement
			(enabled no)
			(sheetname "")
		)
		(fill yes
			(thermal_gap 0.5)
			(thermal_bridge_width 0.5)
			(island_removal_mode 0)
		)
		(polygon
			(pts
				(arc
					(start 72.326246 -312.049922)
					(mid 71.673466 -312.049922)
					(end 72.326246 -312.049922)
				)
			)
		)
	)
	(zone
		(layers "B.Cu" "In9.Cu" "In11.Cu" "In13.Cu" "In15.Cu")
		(hatch none 0.5)
		(connect_pads
			(clearance 0)
		)
		(min_thickness 0.25)
		(keepout
			(tracks not_allowed)
			(vias allowed)
			(pads allowed)
			(copperpour not_allowed)
			(footprints allowed)
		)
		(placement
			(enabled no)
			(sheetname "")
		)
		(fill yes
			(thermal_gap 0.5)
			(thermal_bridge_width 0.5)
			(island_removal_mode 0)
		)
		(polygon
			(pts
				(arc
					(start 77.268832 -345.465146)
					(mid 76.565252 -345.465146)
					(end 77.268832 -345.465146)
				)
			)
		)
	)
	(zone
		(layers "B.Cu" "In9.Cu" "In11.Cu" "In13.Cu" "In15.Cu")
		(hatch none 0.5)
		(connect_pads
			(clearance 0)
		)
		(min_thickness 0.25)
		(keepout
			(tracks not_allowed)
			(vias allowed)
			(pads allowed)
			(copperpour not_allowed)
			(footprints allowed)
		)
		(placement
			(enabled no)
			(sheetname "")
		)
		(fill yes
			(thermal_gap 0.5)
			(thermal_bridge_width 0.5)
			(island_removal_mode 0)
		)
		(polygon
			(pts
				(arc
					(start 29.874718 -342.439498)
					(mid 29.171138 -342.439498)
					(end 29.874718 -342.439498)
				)
			)
		)
	)
	(zone
		(layers "B.Cu" "In9.Cu" "In11.Cu" "In13.Cu" "In15.Cu")
		(hatch none 0.5)
		(connect_pads
			(clearance 0)
		)
		(min_thickness 0.25)
		(keepout
			(tracks not_allowed)
			(vias allowed)
			(pads allowed)
			(copperpour not_allowed)
			(footprints allowed)
		)
		(placement
			(enabled no)
			(sheetname "")
		)
		(fill yes
			(thermal_gap 0.5)
			(thermal_bridge_width 0.5)
			(island_removal_mode 0)
		)
		(polygon
			(pts
				(arc
					(start 341.698834 -357.75773)
					(mid 340.995254 -357.75773)
					(end 341.698834 -357.75773)
				)
			)
		)
	)
	(zone
		(layers "B.Cu" "In9.Cu" "In11.Cu" "In13.Cu" "In15.Cu")
		(hatch none 0.5)
		(connect_pads
			(clearance 0)
		)
		(min_thickness 0.25)
		(keepout
			(tracks not_allowed)
			(vias allowed)
			(pads allowed)
			(copperpour not_allowed)
			(footprints allowed)
		)
		(placement
			(enabled no)
			(sheetname "")
		)
		(fill yes
			(thermal_gap 0.5)
			(thermal_bridge_width 0.5)
			(island_removal_mode 0)
		)
		(polygon
			(pts
				(arc
					(start 413.619442 -357.75773)
					(mid 412.915862 -357.75773)
					(end 413.619442 -357.75773)
				)
			)
		)
	)
	(zone
		(layers "B.Cu" "In9.Cu" "In11.Cu" "In13.Cu" "In15.Cu")
		(hatch none 0.5)
		(connect_pads
			(clearance 0)
		)
		(min_thickness 0.25)
		(keepout
			(tracks not_allowed)
			(vias allowed)
			(pads allowed)
			(copperpour not_allowed)
			(footprints allowed)
		)
		(placement
			(enabled no)
			(sheetname "")
		)
		(fill yes
			(thermal_gap 0.5)
			(thermal_bridge_width 0.5)
			(island_removal_mode 0)
		)
		(polygon
			(pts
				(arc
					(start 399.726404 -312.049922)
					(mid 399.073624 -312.049922)
					(end 399.726404 -312.049922)
				)
			)
		)
	)
	(zone
		(layers "B.Cu" "In9.Cu" "In11.Cu" "In13.Cu" "In15.Cu")
		(hatch none 0.5)
		(connect_pads
			(clearance 0)
		)
		(min_thickness 0.25)
		(keepout
			(tracks not_allowed)
			(vias allowed)
			(pads allowed)
			(copperpour not_allowed)
			(footprints allowed)
		)
		(placement
			(enabled no)
			(sheetname "")
		)
		(fill yes
			(thermal_gap 0.5)
			(thermal_bridge_width 0.5)
			(island_removal_mode 0)
		)
		(polygon
			(pts
				(arc
					(start 44.555918 -348.58579)
					(mid 43.852338 -348.58579)
					(end 44.555918 -348.58579)
				)
			)
		)
	)
	(zone
		(layers "B.Cu" "In9.Cu" "In11.Cu" "In13.Cu" "In15.Cu")
		(hatch none 0.5)
		(connect_pads
			(clearance 0)
		)
		(min_thickness 0.25)
		(keepout
			(tracks not_allowed)
			(vias allowed)
			(pads allowed)
			(copperpour not_allowed)
			(footprints allowed)
		)
		(placement
			(enabled no)
			(sheetname "")
		)
		(fill yes
			(thermal_gap 0.5)
			(thermal_bridge_width 0.5)
			(island_removal_mode 0)
		)
		(polygon
			(pts
				(arc
					(start 412.755842 -342.439498)
					(mid 412.052262 -342.439498)
					(end 412.755842 -342.439498)
				)
			)
		)
	)
	(zone
		(layers "B.Cu" "In9.Cu" "In11.Cu" "In13.Cu" "In15.Cu")
		(hatch none 0.5)
		(connect_pads
			(clearance 0)
		)
		(min_thickness 0.25)
		(keepout
			(tracks not_allowed)
			(vias allowed)
			(pads allowed)
			(copperpour not_allowed)
			(footprints allowed)
		)
		(placement
			(enabled no)
			(sheetname "")
		)
		(fill yes
			(thermal_gap 0.5)
			(thermal_bridge_width 0.5)
			(island_removal_mode 0)
		)
		(polygon
			(pts
				(arc
					(start 85.562186 -33.65881)
					(mid 84.858606 -33.65881)
					(end 85.562186 -33.65881)
				)
			)
		)
	)
	(zone
		(layers "B.Cu" "In9.Cu" "In11.Cu" "In13.Cu" "In15.Cu")
		(hatch none 0.5)
		(connect_pads
			(clearance 0)
		)
		(min_thickness 0.25)
		(keepout
			(tracks not_allowed)
			(vias allowed)
			(pads allowed)
			(copperpour not_allowed)
			(footprints allowed)
		)
		(placement
			(enabled no)
			(sheetname "")
		)
		(fill yes
			(thermal_gap 0.5)
			(thermal_bridge_width 0.5)
			(island_removal_mode 0)
		)
		(polygon
			(pts
				(arc
					(start 35.229038 -357.75773)
					(mid 34.525458 -357.75773)
					(end 35.229038 -357.75773)
				)
			)
		)
	)
	(zone
		(layers "B.Cu" "In9.Cu" "In11.Cu" "In13.Cu" "In15.Cu")
		(hatch none 0.5)
		(connect_pads
			(clearance 0)
		)
		(min_thickness 0.25)
		(keepout
			(tracks not_allowed)
			(vias allowed)
			(pads allowed)
			(copperpour not_allowed)
			(footprints allowed)
		)
		(placement
			(enabled no)
			(sheetname "")
		)
		(fill yes
			(thermal_gap 0.5)
			(thermal_bridge_width 0.5)
			(island_removal_mode 0)
		)
		(polygon
			(pts
				(arc
					(start 336.269838 -404.290022)
					(mid 335.510378 -404.290022)
					(end 336.269838 -404.290022)
				)
			)
		)
	)
	(zone
		(layers "B.Cu" "In9.Cu" "In11.Cu" "In13.Cu" "In15.Cu")
		(hatch none 0.5)
		(connect_pads
			(clearance 0)
		)
		(min_thickness 0.25)
		(keepout
			(tracks not_allowed)
			(vias allowed)
			(pads allowed)
			(copperpour not_allowed)
			(footprints allowed)
		)
		(placement
			(enabled no)
			(sheetname "")
		)
		(fill yes
			(thermal_gap 0.5)
			(thermal_bridge_width 0.5)
			(island_removal_mode 0)
		)
		(polygon
			(pts
				(arc
					(start 178.926236 -312.049922)
					(mid 178.273456 -312.049922)
					(end 178.926236 -312.049922)
				)
			)
		)
	)
	(zone
		(layers "B.Cu" "In9.Cu" "In11.Cu" "In13.Cu" "In15.Cu")
		(hatch none 0.5)
		(connect_pads
			(clearance 0)
		)
		(min_thickness 0.25)
		(keepout
			(tracks not_allowed)
			(vias allowed)
			(pads allowed)
			(copperpour not_allowed)
			(footprints allowed)
		)
		(placement
			(enabled no)
			(sheetname "")
		)
		(fill yes
			(thermal_gap 0.5)
			(thermal_bridge_width 0.5)
			(island_removal_mode 0)
		)
		(polygon
			(pts
				(arc
					(start 312.854594 -348.58579)
					(mid 312.151014 -348.58579)
					(end 312.854594 -348.58579)
				)
			)
		)
	)
	(zone
		(layers "B.Cu" "In9.Cu" "In11.Cu" "In13.Cu" "In15.Cu")
		(hatch none 0.5)
		(connect_pads
			(clearance 0)
		)
		(min_thickness 0.25)
		(keepout
			(tracks not_allowed)
			(vias allowed)
			(pads allowed)
			(copperpour not_allowed)
			(footprints allowed)
		)
		(placement
			(enabled no)
			(sheetname "")
		)
		(fill yes
			(thermal_gap 0.5)
			(thermal_bridge_width 0.5)
			(island_removal_mode 0)
		)
		(polygon
			(pts
				(arc
					(start 435.716426 -31.858712)
					(mid 435.012846 -31.858712)
					(end 435.716426 -31.858712)
				)
			)
		)
	)
	(zone
		(layers "B.Cu" "In9.Cu" "In11.Cu" "In13.Cu" "In15.Cu")
		(hatch none 0.5)
		(connect_pads
			(clearance 0)
		)
		(min_thickness 0.25)
		(keepout
			(tracks not_allowed)
			(vias allowed)
			(pads allowed)
			(copperpour not_allowed)
			(footprints allowed)
		)
		(placement
			(enabled no)
			(sheetname "")
		)
		(fill yes
			(thermal_gap 0.5)
			(thermal_bridge_width 0.5)
			(island_removal_mode 0)
		)
		(polygon
			(pts
				(arc
					(start 163.726368 -274.999958)
					(mid 163.073588 -274.999958)
					(end 163.726368 -274.999958)
				)
			)
		)
	)
	(zone
		(layers "B.Cu" "In9.Cu" "In11.Cu" "In13.Cu" "In15.Cu")
		(hatch none 0.5)
		(connect_pads
			(clearance 0)
		)
		(min_thickness 0.25)
		(keepout
			(tracks not_allowed)
			(vias allowed)
			(pads allowed)
			(copperpour not_allowed)
			(footprints allowed)
		)
		(placement
			(enabled no)
			(sheetname "")
		)
		(fill yes
			(thermal_gap 0.5)
			(thermal_bridge_width 0.5)
			(island_removal_mode 0)
		)
		(polygon
			(pts
				(arc
					(start 396.41145 -351.611438)
					(mid 395.70787 -351.611438)
					(end 396.41145 -351.611438)
				)
			)
		)
	)
	(zone
		(layers "B.Cu" "In9.Cu" "In11.Cu" "In13.Cu" "In15.Cu")
		(hatch none 0.5)
		(connect_pads
			(clearance 0)
		)
		(min_thickness 0.25)
		(keepout
			(tracks not_allowed)
			(vias allowed)
			(pads allowed)
			(copperpour not_allowed)
			(footprints allowed)
		)
		(placement
			(enabled no)
			(sheetname "")
		)
		(fill yes
			(thermal_gap 0.5)
			(thermal_bridge_width 0.5)
			(island_removal_mode 0)
		)
		(polygon
			(pts
				(arc
					(start 400.38401 -357.75773)
					(mid 399.68043 -357.75773)
					(end 400.38401 -357.75773)
				)
			)
		)
	)
	(zone
		(layers "B.Cu" "In9.Cu" "In11.Cu" "In13.Cu" "In15.Cu")
		(hatch none 0.5)
		(connect_pads
			(clearance 0)
		)
		(min_thickness 0.25)
		(keepout
			(tracks not_allowed)
			(vias allowed)
			(pads allowed)
			(copperpour not_allowed)
			(footprints allowed)
		)
		(placement
			(enabled no)
			(sheetname "")
		)
		(fill yes
			(thermal_gap 0.5)
			(thermal_bridge_width 0.5)
			(island_removal_mode 0)
		)
		(polygon
			(pts
				(arc
					(start 429.164242 -351.611438)
					(mid 428.460662 -351.611438)
					(end 429.164242 -351.611438)
				)
			)
		)
	)
	(zone
		(layers "B.Cu" "In9.Cu" "In11.Cu" "In13.Cu" "In15.Cu")
		(hatch none 0.5)
		(connect_pads
			(clearance 0)
		)
		(min_thickness 0.25)
		(keepout
			(tracks not_allowed)
			(vias allowed)
			(pads allowed)
			(copperpour not_allowed)
			(footprints allowed)
		)
		(placement
			(enabled no)
			(sheetname "")
		)
		(fill yes
			(thermal_gap 0.5)
			(thermal_bridge_width 0.5)
			(island_removal_mode 0)
		)
		(polygon
			(pts
				(arc
					(start 380.26975 -382.18999)
					(mid 379.51029 -382.18999)
					(end 380.26975 -382.18999)
				)
			)
		)
	)
	(zone
		(layers "B.Cu" "In9.Cu" "In11.Cu" "In13.Cu" "In15.Cu")
		(hatch none 0.5)
		(connect_pads
			(clearance 0)
		)
		(min_thickness 0.25)
		(keepout
			(tracks not_allowed)
			(vias allowed)
			(pads allowed)
			(copperpour not_allowed)
			(footprints allowed)
		)
		(placement
			(enabled no)
			(sheetname "")
		)
		(fill yes
			(thermal_gap 0.5)
			(thermal_bridge_width 0.5)
			(island_removal_mode 0)
		)
		(polygon
			(pts
				(arc
					(start 36.092638 -345.465146)
					(mid 35.389058 -345.465146)
					(end 36.092638 -345.465146)
				)
			)
		)
	)
	(zone
		(layers "B.Cu" "In9.Cu" "In11.Cu" "In13.Cu" "In15.Cu")
		(hatch none 0.5)
		(connect_pads
			(clearance 0)
		)
		(min_thickness 0.25)
		(keepout
			(tracks not_allowed)
			(vias allowed)
			(pads allowed)
			(copperpour not_allowed)
			(footprints allowed)
		)
		(placement
			(enabled no)
			(sheetname "")
		)
		(fill yes
			(thermal_gap 0.5)
			(thermal_bridge_width 0.5)
			(island_removal_mode 0)
		)
		(polygon
			(pts
				(arc
					(start 291.76218 -30.922468)
					(mid 291.0586 -30.922468)
					(end 291.76218 -30.922468)
				)
			)
		)
	)
	(zone
		(layers "B.Cu" "In9.Cu" "In11.Cu" "In13.Cu" "In15.Cu")
		(hatch none 0.5)
		(connect_pads
			(clearance 0)
		)
		(min_thickness 0.25)
		(keepout
			(tracks not_allowed)
			(vias allowed)
			(pads allowed)
			(copperpour not_allowed)
			(footprints allowed)
		)
		(placement
			(enabled no)
			(sheetname "")
		)
		(fill yes
			(thermal_gap 0.5)
			(thermal_bridge_width 0.5)
			(island_removal_mode 0)
		)
		(polygon
			(pts
				(arc
					(start 171.289726 -397.59001)
					(mid 170.530266 -397.59001)
					(end 171.289726 -397.59001)
				)
			)
		)
	)
	(zone
		(layers "B.Cu" "In9.Cu" "In11.Cu" "In13.Cu" "In15.Cu")
		(hatch none 0.5)
		(connect_pads
			(clearance 0)
		)
		(min_thickness 0.25)
		(keepout
			(tracks not_allowed)
			(vias allowed)
			(pads allowed)
			(copperpour not_allowed)
			(footprints allowed)
		)
		(placement
			(enabled no)
			(sheetname "")
		)
		(fill yes
			(thermal_gap 0.5)
			(thermal_bridge_width 0.5)
			(island_removal_mode 0)
		)
		(polygon
			(pts
				(arc
					(start 59.026298 -312.049922)
					(mid 58.373518 -312.049922)
					(end 59.026298 -312.049922)
				)
			)
		)
	)
	(zone
		(layers "B.Cu" "In9.Cu" "In11.Cu" "In13.Cu" "In15.Cu")
		(hatch none 0.5)
		(connect_pads
			(clearance 0)
		)
		(min_thickness 0.25)
		(keepout
			(tracks not_allowed)
			(vias allowed)
			(pads allowed)
			(copperpour not_allowed)
			(footprints allowed)
		)
		(placement
			(enabled no)
			(sheetname "")
		)
		(fill yes
			(thermal_gap 0.5)
			(thermal_bridge_width 0.5)
			(island_removal_mode 0)
		)
		(polygon
			(pts
				(arc
					(start 409.646882 -348.58579)
					(mid 408.943302 -348.58579)
					(end 409.646882 -348.58579)
				)
			)
		)
	)
	(zone
		(layers "B.Cu" "In9.Cu" "In11.Cu" "In13.Cu" "In15.Cu")
		(hatch none 0.5)
		(connect_pads
			(clearance 0)
		)
		(min_thickness 0.25)
		(keepout
			(tracks not_allowed)
			(vias allowed)
			(pads allowed)
			(copperpour not_allowed)
			(footprints allowed)
		)
		(placement
			(enabled no)
			(sheetname "")
		)
		(fill yes
			(thermal_gap 0.5)
			(thermal_bridge_width 0.5)
			(island_removal_mode 0)
		)
		(polygon
			(pts
				(arc
					(start 149.662388 -34.52241)
					(mid 148.958808 -34.52241)
					(end 149.662388 -34.52241)
				)
			)
		)
	)
	(zone
		(layers "B.Cu" "In9.Cu" "In11.Cu" "In13.Cu" "In15.Cu")
		(hatch none 0.5)
		(connect_pads
			(clearance 0)
		)
		(min_thickness 0.25)
		(keepout
			(tracks not_allowed)
			(vias allowed)
			(pads allowed)
			(copperpour not_allowed)
			(footprints allowed)
		)
		(placement
			(enabled no)
			(sheetname "")
		)
		(fill yes
			(thermal_gap 0.5)
			(thermal_bridge_width 0.5)
			(island_removal_mode 0)
		)
		(polygon
			(pts
				(arc
					(start 355.862382 -33.65881)
					(mid 355.158802 -33.65881)
					(end 355.862382 -33.65881)
				)
			)
		)
	)
	(zone
		(layers "B.Cu" "In9.Cu" "In11.Cu" "In13.Cu" "In15.Cu")
		(hatch none 0.5)
		(connect_pads
			(clearance 0)
		)
		(min_thickness 0.25)
		(keepout
			(tracks not_allowed)
			(vias allowed)
			(pads allowed)
			(copperpour not_allowed)
			(footprints allowed)
		)
		(placement
			(enabled no)
			(sheetname "")
		)
		(fill yes
			(thermal_gap 0.5)
			(thermal_bridge_width 0.5)
			(island_removal_mode 0)
		)
		(polygon
			(pts
				(arc
					(start 275.076158 -305.399948)
					(mid 274.423378 -305.399948)
					(end 275.076158 -305.399948)
				)
			)
		)
	)
	(zone
		(layers "B.Cu" "In9.Cu" "In11.Cu" "In13.Cu" "In15.Cu")
		(hatch none 0.5)
		(connect_pads
			(clearance 0)
		)
		(min_thickness 0.25)
		(keepout
			(tracks not_allowed)
			(vias allowed)
			(pads allowed)
			(copperpour not_allowed)
			(footprints allowed)
		)
		(placement
			(enabled no)
			(sheetname "")
		)
		(fill yes
			(thermal_gap 0.5)
			(thermal_bridge_width 0.5)
			(island_removal_mode 0)
		)
		(polygon
			(pts
				(arc
					(start 239.762284 -30.058868)
					(mid 239.058704 -30.058868)
					(end 239.762284 -30.058868)
				)
			)
		)
	)
	(zone
		(layers "B.Cu" "In9.Cu" "In11.Cu" "In13.Cu" "In15.Cu")
		(hatch none 0.5)
		(connect_pads
			(clearance 0)
		)
		(min_thickness 0.25)
		(keepout
			(tracks not_allowed)
			(vias allowed)
			(pads allowed)
			(copperpour not_allowed)
			(footprints allowed)
		)
		(placement
			(enabled no)
			(sheetname "")
		)
		(fill yes
			(thermal_gap 0.5)
			(thermal_bridge_width 0.5)
			(island_removal_mode 0)
		)
		(polygon
			(pts
				(arc
					(start 175.689768 -397.59001)
					(mid 174.930308 -397.59001)
					(end 175.689768 -397.59001)
				)
			)
		)
	)
	(zone
		(layers "B.Cu" "In9.Cu" "In11.Cu" "In13.Cu" "In15.Cu")
		(hatch none 0.5)
		(connect_pads
			(clearance 0)
		)
		(min_thickness 0.25)
		(keepout
			(tracks not_allowed)
			(vias allowed)
			(pads allowed)
			(copperpour not_allowed)
			(footprints allowed)
		)
		(placement
			(enabled no)
			(sheetname "")
		)
		(fill yes
			(thermal_gap 0.5)
			(thermal_bridge_width 0.5)
			(island_removal_mode 0)
		)
		(polygon
			(pts
				(arc
					(start 118.48973 -384.590036)
					(mid 117.73027 -384.590036)
					(end 118.48973 -384.590036)
				)
			)
		)
	)
	(zone
		(layers "B.Cu" "In9.Cu" "In11.Cu" "In13.Cu" "In15.Cu")
		(hatch none 0.5)
		(connect_pads
			(clearance 0)
		)
		(min_thickness 0.25)
		(keepout
			(tracks not_allowed)
			(vias allowed)
			(pads allowed)
			(copperpour not_allowed)
			(footprints allowed)
		)
		(placement
			(enabled no)
			(sheetname "")
		)
		(fill yes
			(thermal_gap 0.5)
			(thermal_bridge_width 0.5)
			(island_removal_mode 0)
		)
		(polygon
			(pts
				(arc
					(start 301.069502 -400.390106)
					(mid 300.310042 -400.390106)
					(end 301.069502 -400.390106)
				)
			)
		)
	)
	(zone
		(layers "B.Cu" "In9.Cu" "In11.Cu" "In13.Cu" "In15.Cu")
		(hatch none 0.5)
		(connect_pads
			(clearance 0)
		)
		(min_thickness 0.25)
		(keepout
			(tracks not_allowed)
			(vias allowed)
			(pads allowed)
			(copperpour not_allowed)
			(footprints allowed)
		)
		(placement
			(enabled no)
			(sheetname "")
		)
		(fill yes
			(thermal_gap 0.5)
			(thermal_bridge_width 0.5)
			(island_removal_mode 0)
		)
		(polygon
			(pts
				(arc
					(start 239.762284 -30.922468)
					(mid 239.058704 -30.922468)
					(end 239.762284 -30.922468)
				)
			)
		)
	)
	(zone
		(layers "B.Cu" "In9.Cu" "In11.Cu" "In13.Cu" "In15.Cu")
		(hatch none 0.5)
		(connect_pads
			(clearance 0)
		)
		(min_thickness 0.25)
		(keepout
			(tracks not_allowed)
			(vias allowed)
			(pads allowed)
			(copperpour not_allowed)
			(footprints allowed)
		)
		(placement
			(enabled no)
			(sheetname "")
		)
		(fill yes
			(thermal_gap 0.5)
			(thermal_bridge_width 0.5)
			(island_removal_mode 0)
		)
		(polygon
			(pts
				(arc
					(start 83.289648 -405.390096)
					(mid 82.530188 -405.390096)
					(end 83.289648 -405.390096)
				)
			)
		)
	)
	(zone
		(layers "B.Cu" "In9.Cu" "In11.Cu" "In13.Cu" "In15.Cu")
		(hatch none 0.5)
		(connect_pads
			(clearance 0)
		)
		(min_thickness 0.25)
		(keepout
			(tracks not_allowed)
			(vias allowed)
			(pads allowed)
			(copperpour not_allowed)
			(footprints allowed)
		)
		(placement
			(enabled no)
			(sheetname "")
		)
		(fill yes
			(thermal_gap 0.5)
			(thermal_bridge_width 0.5)
			(island_removal_mode 0)
		)
		(polygon
			(pts
				(arc
					(start 387.94817 -354.732082)
					(mid 387.24459 -354.732082)
					(end 387.94817 -354.732082)
				)
			)
		)
	)
	(zone
		(layers "B.Cu" "In9.Cu" "In11.Cu" "In13.Cu" "In15.Cu")
		(hatch none 0.5)
		(connect_pads
			(clearance 0)
		)
		(min_thickness 0.25)
		(keepout
			(tracks not_allowed)
			(vias allowed)
			(pads allowed)
			(copperpour not_allowed)
			(footprints allowed)
		)
		(placement
			(enabled no)
			(sheetname "")
		)
		(fill yes
			(thermal_gap 0.5)
			(thermal_bridge_width 0.5)
			(island_removal_mode 0)
		)
		(polygon
			(pts
				(arc
					(start 137.085578 -351.611438)
					(mid 136.381998 -351.611438)
					(end 137.085578 -351.611438)
				)
			)
		)
	)
	(zone
		(layers "B.Cu" "In9.Cu" "In11.Cu" "In13.Cu" "In15.Cu")
		(hatch none 0.5)
		(connect_pads
			(clearance 0)
		)
		(min_thickness 0.25)
		(keepout
			(tracks not_allowed)
			(vias allowed)
			(pads allowed)
			(copperpour not_allowed)
			(footprints allowed)
		)
		(placement
			(enabled no)
			(sheetname "")
		)
		(fill yes
			(thermal_gap 0.5)
			(thermal_bridge_width 0.5)
			(island_removal_mode 0)
		)
		(polygon
			(pts
				(arc
					(start 328.399394 -345.465146)
					(mid 327.695814 -345.465146)
					(end 328.399394 -345.465146)
				)
			)
		)
	)
	(zone
		(layers "B.Cu" "In9.Cu" "In11.Cu" "In13.Cu" "In15.Cu")
		(hatch none 0.5)
		(connect_pads
			(clearance 0)
		)
		(min_thickness 0.25)
		(keepout
			(tracks not_allowed)
			(vias allowed)
			(pads allowed)
			(copperpour not_allowed)
			(footprints allowed)
		)
		(placement
			(enabled no)
			(sheetname "")
		)
		(fill yes
			(thermal_gap 0.5)
			(thermal_bridge_width 0.5)
			(island_removal_mode 0)
		)
		(polygon
			(pts
				(arc
					(start 393.30249 -357.75773)
					(mid 392.59891 -357.75773)
					(end 393.30249 -357.75773)
				)
			)
		)
	)
	(zone
		(layers "B.Cu" "In9.Cu" "In11.Cu" "In13.Cu" "In15.Cu")
		(hatch none 0.5)
		(connect_pads
			(clearance 0)
		)
		(min_thickness 0.25)
		(keepout
			(tracks not_allowed)
			(vias allowed)
			(pads allowed)
			(copperpour not_allowed)
			(footprints allowed)
		)
		(placement
			(enabled no)
			(sheetname "")
		)
		(fill yes
			(thermal_gap 0.5)
			(thermal_bridge_width 0.5)
			(island_removal_mode 0)
		)
		(polygon
			(pts
				(arc
					(start 43.826176 -306.349908)
					(mid 43.173396 -306.349908)
					(end 43.826176 -306.349908)
				)
			)
		)
	)
	(zone
		(layers "B.Cu" "In9.Cu" "In11.Cu" "In13.Cu" "In15.Cu")
		(hatch none 0.5)
		(connect_pads
			(clearance 0)
		)
		(min_thickness 0.25)
		(keepout
			(tracks not_allowed)
			(vias allowed)
			(pads allowed)
			(copperpour not_allowed)
			(footprints allowed)
		)
		(placement
			(enabled no)
			(sheetname "")
		)
		(fill yes
			(thermal_gap 0.5)
			(thermal_bridge_width 0.5)
			(island_removal_mode 0)
		)
		(polygon
			(pts
				(arc
					(start 329.262994 -342.439498)
					(mid 328.559414 -342.439498)
					(end 329.262994 -342.439498)
				)
			)
		)
	)
	(zone
		(layers "B.Cu" "In9.Cu" "In11.Cu" "In13.Cu" "In15.Cu")
		(hatch none 0.5)
		(connect_pads
			(clearance 0)
		)
		(min_thickness 0.25)
		(keepout
			(tracks not_allowed)
			(vias allowed)
			(pads allowed)
			(copperpour not_allowed)
			(footprints allowed)
		)
		(placement
			(enabled no)
			(sheetname "")
		)
		(fill yes
			(thermal_gap 0.5)
			(thermal_bridge_width 0.5)
			(island_removal_mode 0)
		)
		(polygon
			(pts
				(arc
					(start 168.476422 -312.999882)
					(mid 167.823642 -312.999882)
					(end 168.476422 -312.999882)
				)
			)
		)
	)
	(zone
		(layers "B.Cu" "In9.Cu" "In11.Cu" "In13.Cu" "In15.Cu")
		(hatch none 0.5)
		(connect_pads
			(clearance 0)
		)
		(min_thickness 0.25)
		(keepout
			(tracks not_allowed)
			(vias allowed)
			(pads allowed)
			(copperpour not_allowed)
			(footprints allowed)
		)
		(placement
			(enabled no)
			(sheetname "")
		)
		(fill yes
			(thermal_gap 0.5)
			(thermal_bridge_width 0.5)
			(island_removal_mode 0)
		)
		(polygon
			(pts
				(arc
					(start 291.76218 -33.65881)
					(mid 291.0586 -33.65881)
					(end 291.76218 -33.65881)
				)
			)
		)
	)
	(zone
		(layers "B.Cu" "In9.Cu" "In11.Cu" "In13.Cu" "In15.Cu")
		(hatch none 0.5)
		(connect_pads
			(clearance 0)
		)
		(min_thickness 0.25)
		(keepout
			(tracks not_allowed)
			(vias allowed)
			(pads allowed)
			(copperpour not_allowed)
			(footprints allowed)
		)
		(placement
			(enabled no)
			(sheetname "")
		)
		(fill yes
			(thermal_gap 0.5)
			(thermal_bridge_width 0.5)
			(island_removal_mode 0)
		)
		(polygon
			(pts
				(arc
					(start 301.676308 -313.949842)
					(mid 301.023528 -313.949842)
					(end 301.676308 -313.949842)
				)
			)
		)
	)
	(zone
		(layers "B.Cu" "In9.Cu" "In11.Cu" "In13.Cu" "In15.Cu")
		(hatch none 0.5)
		(connect_pads
			(clearance 0)
		)
		(min_thickness 0.25)
		(keepout
			(tracks not_allowed)
			(vias allowed)
			(pads allowed)
			(copperpour not_allowed)
			(footprints allowed)
		)
		(placement
			(enabled no)
			(sheetname "")
		)
		(fill yes
			(thermal_gap 0.5)
			(thermal_bridge_width 0.5)
			(island_removal_mode 0)
		)
		(polygon
			(pts
				(arc
					(start 140.194538 -357.75773)
					(mid 139.490958 -357.75773)
					(end 140.194538 -357.75773)
				)
			)
		)
	)
	(zone
		(layers "B.Cu" "In9.Cu" "In11.Cu" "In13.Cu" "In15.Cu")
		(hatch none 0.5)
		(connect_pads
			(clearance 0)
		)
		(min_thickness 0.25)
		(keepout
			(tracks not_allowed)
			(vias allowed)
			(pads allowed)
			(copperpour not_allowed)
			(footprints allowed)
		)
		(placement
			(enabled no)
			(sheetname "")
		)
		(fill yes
			(thermal_gap 0.5)
			(thermal_bridge_width 0.5)
			(island_removal_mode 0)
		)
		(polygon
			(pts
				(arc
					(start 426.3263 -312.049922)
					(mid 425.67352 -312.049922)
					(end 426.3263 -312.049922)
				)
			)
		)
	)
	(zone
		(layers "B.Cu" "In9.Cu" "In11.Cu" "In13.Cu" "In15.Cu")
		(hatch none 0.5)
		(connect_pads
			(clearance 0)
		)
		(min_thickness 0.25)
		(keepout
			(tracks not_allowed)
			(vias allowed)
			(pads allowed)
			(copperpour not_allowed)
			(footprints allowed)
		)
		(placement
			(enabled no)
			(sheetname "")
		)
		(fill yes
			(thermal_gap 0.5)
			(thermal_bridge_width 0.5)
			(island_removal_mode 0)
		)
		(polygon
			(pts
				(arc
					(start 334.617314 -345.465146)
					(mid 333.913734 -345.465146)
					(end 334.617314 -345.465146)
				)
			)
		)
	)
	(zone
		(layers "B.Cu" "In9.Cu" "In11.Cu" "In13.Cu" "In15.Cu")
		(hatch none 0.5)
		(connect_pads
			(clearance 0)
		)
		(min_thickness 0.25)
		(keepout
			(tracks not_allowed)
			(vias allowed)
			(pads allowed)
			(copperpour not_allowed)
			(footprints allowed)
		)
		(placement
			(enabled no)
			(sheetname "")
		)
		(fill yes
			(thermal_gap 0.5)
			(thermal_bridge_width 0.5)
			(island_removal_mode 0)
		)
		(polygon
			(pts
				(arc
					(start 317.762128 -33.65881)
					(mid 317.058548 -33.65881)
					(end 317.762128 -33.65881)
				)
			)
		)
	)
	(zone
		(layers "B.Cu" "In9.Cu" "In11.Cu" "In13.Cu" "In15.Cu")
		(hatch none 0.5)
		(connect_pads
			(clearance 0)
		)
		(min_thickness 0.25)
		(keepout
			(tracks not_allowed)
			(vias allowed)
			(pads allowed)
			(copperpour not_allowed)
			(footprints allowed)
		)
		(placement
			(enabled no)
			(sheetname "")
		)
		(fill yes
			(thermal_gap 0.5)
			(thermal_bridge_width 0.5)
			(island_removal_mode 0)
		)
		(polygon
			(pts
				(arc
					(start 292.1762 -313.949842)
					(mid 291.52342 -313.949842)
					(end 292.1762 -313.949842)
				)
			)
		)
	)
	(zone
		(layers "B.Cu" "In9.Cu" "In11.Cu" "In13.Cu" "In15.Cu")
		(hatch none 0.5)
		(connect_pads
			(clearance 0)
		)
		(min_thickness 0.25)
		(keepout
			(tracks not_allowed)
			(vias allowed)
			(pads allowed)
			(copperpour not_allowed)
			(footprints allowed)
		)
		(placement
			(enabled no)
			(sheetname "")
		)
		(fill yes
			(thermal_gap 0.5)
			(thermal_bridge_width 0.5)
			(island_removal_mode 0)
		)
		(polygon
			(pts
				(arc
					(start 374.64873 -357.75773)
					(mid 373.94515 -357.75773)
					(end 374.64873 -357.75773)
				)
			)
		)
	)
	(zone
		(layers "B.Cu" "In9.Cu" "In11.Cu" "In13.Cu" "In15.Cu")
		(hatch none 0.5)
		(connect_pads
			(clearance 0)
		)
		(min_thickness 0.25)
		(keepout
			(tracks not_allowed)
			(vias allowed)
			(pads allowed)
			(copperpour not_allowed)
			(footprints allowed)
		)
		(placement
			(enabled no)
			(sheetname "")
		)
		(fill yes
			(thermal_gap 0.5)
			(thermal_bridge_width 0.5)
			(island_removal_mode 0)
		)
		(polygon
			(pts
				(arc
					(start 292.269672 -374.390158)
					(mid 291.510212 -374.390158)
					(end 292.269672 -374.390158)
				)
			)
		)
	)
	(zone
		(layers "B.Cu" "In9.Cu" "In11.Cu" "In13.Cu" "In15.Cu")
		(hatch none 0.5)
		(connect_pads
			(clearance 0)
		)
		(min_thickness 0.25)
		(keepout
			(tracks not_allowed)
			(vias allowed)
			(pads allowed)
			(copperpour not_allowed)
			(footprints allowed)
		)
		(placement
			(enabled no)
			(sheetname "")
		)
		(fill yes
			(thermal_gap 0.5)
			(thermal_bridge_width 0.5)
			(island_removal_mode 0)
		)
		(polygon
			(pts
				(arc
					(start 394.02639 -274.999958)
					(mid 393.37361 -274.999958)
					(end 394.02639 -274.999958)
				)
			)
		)
	)
	(zone
		(layers "B.Cu" "In9.Cu" "In11.Cu" "In13.Cu" "In15.Cu")
		(hatch none 0.5)
		(connect_pads
			(clearance 0)
		)
		(min_thickness 0.25)
		(keepout
			(tracks not_allowed)
			(vias allowed)
			(pads allowed)
			(copperpour not_allowed)
			(footprints allowed)
		)
		(placement
			(enabled no)
			(sheetname "")
		)
		(fill yes
			(thermal_gap 0.5)
			(thermal_bridge_width 0.5)
			(island_removal_mode 0)
		)
		(polygon
			(pts
				(arc
					(start 131.689856 -384.590036)
					(mid 130.930396 -384.590036)
					(end 131.689856 -384.590036)
				)
			)
		)
	)
	(zone
		(layers "B.Cu" "In9.Cu" "In11.Cu" "In13.Cu" "In15.Cu")
		(hatch none 0.5)
		(connect_pads
			(clearance 0)
		)
		(min_thickness 0.25)
		(keepout
			(tracks not_allowed)
			(vias allowed)
			(pads allowed)
			(copperpour not_allowed)
			(footprints allowed)
		)
		(placement
			(enabled no)
			(sheetname "")
		)
		(fill yes
			(thermal_gap 0.5)
			(thermal_bridge_width 0.5)
			(island_removal_mode 0)
		)
		(polygon
			(pts
				(arc
					(start 429.164242 -348.58579)
					(mid 428.460662 -348.58579)
					(end 429.164242 -348.58579)
				)
			)
		)
	)
	(zone
		(layers "B.Cu" "In9.Cu" "In11.Cu" "In13.Cu" "In15.Cu")
		(hatch none 0.5)
		(connect_pads
			(clearance 0)
		)
		(min_thickness 0.25)
		(keepout
			(tracks not_allowed)
			(vias allowed)
			(pads allowed)
			(copperpour not_allowed)
			(footprints allowed)
		)
		(placement
			(enabled no)
			(sheetname "")
		)
		(fill yes
			(thermal_gap 0.5)
			(thermal_bridge_width 0.5)
			(island_removal_mode 0)
		)
		(polygon
			(pts
				(arc
					(start 430.126394 -314.899802)
					(mid 429.473614 -314.899802)
					(end 430.126394 -314.899802)
				)
			)
		)
	)
	(zone
		(layers "B.Cu" "In9.Cu" "In11.Cu" "In13.Cu" "In15.Cu")
		(hatch none 0.5)
		(connect_pads
			(clearance 0)
		)
		(min_thickness 0.25)
		(keepout
			(tracks not_allowed)
			(vias allowed)
			(pads allowed)
			(copperpour not_allowed)
			(footprints allowed)
		)
		(placement
			(enabled no)
			(sheetname "")
		)
		(fill yes
			(thermal_gap 0.5)
			(thermal_bridge_width 0.5)
			(island_removal_mode 0)
		)
		(polygon
			(pts
				(arc
					(start 426.3263 -309.199788)
					(mid 425.67352 -309.199788)
					(end 426.3263 -309.199788)
				)
			)
		)
	)
	(zone
		(layers "B.Cu" "In9.Cu" "In11.Cu" "In13.Cu" "In15.Cu")
		(hatch none 0.5)
		(connect_pads
			(clearance 0)
		)
		(min_thickness 0.25)
		(keepout
			(tracks not_allowed)
			(vias allowed)
			(pads allowed)
			(copperpour not_allowed)
			(footprints allowed)
		)
		(placement
			(enabled no)
			(sheetname "")
		)
		(fill yes
			(thermal_gap 0.5)
			(thermal_bridge_width 0.5)
			(island_removal_mode 0)
		)
		(polygon
			(pts
				(arc
					(start 87.459312 -351.611438)
					(mid 86.755732 -351.611438)
					(end 87.459312 -351.611438)
				)
			)
		)
	)
	(zone
		(layers "B.Cu" "In9.Cu" "In11.Cu" "In13.Cu" "In15.Cu")
		(hatch none 0.5)
		(connect_pads
			(clearance 0)
		)
		(min_thickness 0.25)
		(keepout
			(tracks not_allowed)
			(vias allowed)
			(pads allowed)
			(copperpour not_allowed)
			(footprints allowed)
		)
		(placement
			(enabled no)
			(sheetname "")
		)
		(fill yes
			(thermal_gap 0.5)
			(thermal_bridge_width 0.5)
			(island_removal_mode 0)
		)
		(polygon
			(pts
				(arc
					(start 305.476148 -313.949842)
					(mid 304.823368 -313.949842)
					(end 305.476148 -313.949842)
				)
			)
		)
	)
	(zone
		(layers "B.Cu" "In9.Cu" "In11.Cu" "In13.Cu" "In15.Cu")
		(hatch none 0.5)
		(connect_pads
			(clearance 0)
		)
		(min_thickness 0.25)
		(keepout
			(tracks not_allowed)
			(vias allowed)
			(pads allowed)
			(copperpour not_allowed)
			(footprints allowed)
		)
		(placement
			(enabled no)
			(sheetname "")
		)
		(fill yes
			(thermal_gap 0.5)
			(thermal_bridge_width 0.5)
			(island_removal_mode 0)
		)
		(polygon
			(pts
				(arc
					(start 41.926256 -307.299868)
					(mid 41.273476 -307.299868)
					(end 41.926256 -307.299868)
				)
			)
		)
	)
	(zone
		(layers "B.Cu" "In9.Cu" "In11.Cu" "In13.Cu" "In15.Cu")
		(hatch none 0.5)
		(connect_pads
			(clearance 0)
		)
		(min_thickness 0.25)
		(keepout
			(tracks not_allowed)
			(vias allowed)
			(pads allowed)
			(copperpour not_allowed)
			(footprints allowed)
		)
		(placement
			(enabled no)
			(sheetname "")
		)
		(fill yes
			(thermal_gap 0.5)
			(thermal_bridge_width 0.5)
			(island_removal_mode 0)
		)
		(polygon
			(pts
				(arc
					(start 402.62937 -348.58579)
					(mid 401.92579 -348.58579)
					(end 402.62937 -348.58579)
				)
			)
		)
	)
	(zone
		(layers "B.Cu" "In9.Cu" "In11.Cu" "In13.Cu" "In15.Cu")
		(hatch none 0.5)
		(connect_pads
			(clearance 0)
		)
		(min_thickness 0.25)
		(keepout
			(tracks not_allowed)
			(vias allowed)
			(pads allowed)
			(copperpour not_allowed)
			(footprints allowed)
		)
		(placement
			(enabled no)
			(sheetname "")
		)
		(fill yes
			(thermal_gap 0.5)
			(thermal_bridge_width 0.5)
			(island_removal_mode 0)
		)
		(polygon
			(pts
				(arc
					(start 419.86962 -370.489988)
					(mid 419.11016 -370.489988)
					(end 419.86962 -370.489988)
				)
			)
		)
	)
	(zone
		(layers "B.Cu" "In9.Cu" "In11.Cu" "In13.Cu" "In15.Cu")
		(hatch none 0.5)
		(connect_pads
			(clearance 0)
		)
		(min_thickness 0.25)
		(keepout
			(tracks not_allowed)
			(vias allowed)
			(pads allowed)
			(copperpour not_allowed)
			(footprints allowed)
		)
		(placement
			(enabled no)
			(sheetname "")
		)
		(fill yes
			(thermal_gap 0.5)
			(thermal_bridge_width 0.5)
			(island_removal_mode 0)
		)
		(polygon
			(pts
				(arc
					(start 83.289648 -379.390148)
					(mid 82.530188 -379.390148)
					(end 83.289648 -379.390148)
				)
			)
		)
	)
	(zone
		(layers "B.Cu" "In9.Cu" "In11.Cu" "In13.Cu" "In15.Cu")
		(hatch none 0.5)
		(connect_pads
			(clearance 0)
		)
		(min_thickness 0.25)
		(keepout
			(tracks not_allowed)
			(vias allowed)
			(pads allowed)
			(copperpour not_allowed)
			(footprints allowed)
		)
		(placement
			(enabled no)
			(sheetname "")
		)
		(fill yes
			(thermal_gap 0.5)
			(thermal_bridge_width 0.5)
			(island_removal_mode 0)
		)
		(polygon
			(pts
				(arc
					(start 127.758698 -345.465146)
					(mid 127.055118 -345.465146)
					(end 127.758698 -345.465146)
				)
			)
		)
	)
	(zone
		(layers "B.Cu" "In9.Cu" "In11.Cu" "In13.Cu" "In15.Cu")
		(hatch none 0.5)
		(connect_pads
			(clearance 0)
		)
		(min_thickness 0.25)
		(keepout
			(tracks not_allowed)
			(vias allowed)
			(pads allowed)
			(copperpour not_allowed)
			(footprints allowed)
		)
		(placement
			(enabled no)
			(sheetname "")
		)
		(fill yes
			(thermal_gap 0.5)
			(thermal_bridge_width 0.5)
			(island_removal_mode 0)
		)
		(polygon
			(pts
				(arc
					(start 271.276318 -313.949842)
					(mid 270.623538 -313.949842)
					(end 271.276318 -313.949842)
				)
			)
		)
	)
	(zone
		(layers "B.Cu" "In9.Cu" "In11.Cu" "In13.Cu" "In15.Cu")
		(hatch none 0.5)
		(connect_pads
			(clearance 0)
		)
		(min_thickness 0.25)
		(keepout
			(tracks not_allowed)
			(vias allowed)
			(pads allowed)
			(copperpour not_allowed)
			(footprints allowed)
		)
		(placement
			(enabled no)
			(sheetname "")
		)
		(fill yes
			(thermal_gap 0.5)
			(thermal_bridge_width 0.5)
			(island_removal_mode 0)
		)
		(polygon
			(pts
				(arc
					(start 425.37634 -312.999882)
					(mid 424.72356 -312.999882)
					(end 425.37634 -312.999882)
				)
			)
		)
	)
	(zone
		(layers "B.Cu" "In9.Cu" "In11.Cu" "In13.Cu" "In15.Cu")
		(hatch none 0.5)
		(connect_pads
			(clearance 0)
		)
		(min_thickness 0.25)
		(keepout
			(tracks not_allowed)
			(vias allowed)
			(pads allowed)
			(copperpour not_allowed)
			(footprints allowed)
		)
		(placement
			(enabled no)
			(sheetname "")
		)
		(fill yes
			(thermal_gap 0.5)
			(thermal_bridge_width 0.5)
			(island_removal_mode 0)
		)
		(polygon
			(pts
				(arc
					(start 137.949178 -348.58579)
					(mid 137.245598 -348.58579)
					(end 137.949178 -348.58579)
				)
			)
		)
	)
	(zone
		(layers "B.Cu" "In9.Cu" "In11.Cu" "In13.Cu" "In15.Cu")
		(hatch none 0.5)
		(connect_pads
			(clearance 0)
		)
		(min_thickness 0.25)
		(keepout
			(tracks not_allowed)
			(vias allowed)
			(pads allowed)
			(copperpour not_allowed)
			(footprints allowed)
		)
		(placement
			(enabled no)
			(sheetname "")
		)
		(fill yes
			(thermal_gap 0.5)
			(thermal_bridge_width 0.5)
			(island_removal_mode 0)
		)
		(polygon
			(pts
				(arc
					(start 291.22624 -312.049922)
					(mid 290.57346 -312.049922)
					(end 291.22624 -312.049922)
				)
			)
		)
	)
	(zone
		(layers "B.Cu" "In9.Cu" "In11.Cu" "In13.Cu" "In15.Cu")
		(hatch none 0.5)
		(connect_pads
			(clearance 0)
		)
		(min_thickness 0.25)
		(keepout
			(tracks not_allowed)
			(vias allowed)
			(pads allowed)
			(copperpour not_allowed)
			(footprints allowed)
		)
		(placement
			(enabled no)
			(sheetname "")
		)
		(fill yes
			(thermal_gap 0.5)
			(thermal_bridge_width 0.5)
			(island_removal_mode 0)
		)
		(polygon
			(pts
				(arc
					(start 433.862226 -33.65881)
					(mid 433.158646 -33.65881)
					(end 433.862226 -33.65881)
				)
			)
		)
	)
	(zone
		(layers "B.Cu" "In9.Cu" "In11.Cu" "In13.Cu" "In15.Cu")
		(hatch none 0.5)
		(connect_pads
			(clearance 0)
		)
		(min_thickness 0.25)
		(keepout
			(tracks not_allowed)
			(vias allowed)
			(pads allowed)
			(copperpour not_allowed)
			(footprints allowed)
		)
		(placement
			(enabled no)
			(sheetname "")
		)
		(fill yes
			(thermal_gap 0.5)
			(thermal_bridge_width 0.5)
			(island_removal_mode 0)
		)
		(polygon
			(pts
				(arc
					(start 299.338492 -351.611438)
					(mid 298.634912 -351.611438)
					(end 299.338492 -351.611438)
				)
			)
		)
	)
	(zone
		(layers "B.Cu" "In9.Cu" "In11.Cu" "In13.Cu" "In15.Cu")
		(hatch none 0.5)
		(connect_pads
			(clearance 0)
		)
		(min_thickness 0.25)
		(keepout
			(tracks not_allowed)
			(vias allowed)
			(pads allowed)
			(copperpour not_allowed)
			(footprints allowed)
		)
		(placement
			(enabled no)
			(sheetname "")
		)
		(fill yes
			(thermal_gap 0.5)
			(thermal_bridge_width 0.5)
			(island_removal_mode 0)
		)
		(polygon
			(pts
				(arc
					(start 178.946302 -354.732082)
					(mid 178.242722 -354.732082)
					(end 178.946302 -354.732082)
				)
			)
		)
	)
	(zone
		(layers "B.Cu" "In9.Cu" "In11.Cu" "In13.Cu" "In15.Cu")
		(hatch none 0.5)
		(connect_pads
			(clearance 0)
		)
		(min_thickness 0.25)
		(keepout
			(tracks not_allowed)
			(vias allowed)
			(pads allowed)
			(copperpour not_allowed)
			(footprints allowed)
		)
		(placement
			(enabled no)
			(sheetname "")
		)
		(fill yes
			(thermal_gap 0.5)
			(thermal_bridge_width 0.5)
			(island_removal_mode 0)
		)
		(polygon
			(pts
				(arc
					(start 175.689768 -371.590062)
					(mid 174.930308 -371.590062)
					(end 175.689768 -371.590062)
				)
			)
		)
	)
	(zone
		(layers "B.Cu" "In9.Cu" "In11.Cu" "In13.Cu" "In15.Cu")
		(hatch none 0.5)
		(connect_pads
			(clearance 0)
		)
		(min_thickness 0.25)
		(keepout
			(tracks not_allowed)
			(vias allowed)
			(pads allowed)
			(copperpour not_allowed)
			(footprints allowed)
		)
		(placement
			(enabled no)
			(sheetname "")
		)
		(fill yes
			(thermal_gap 0.5)
			(thermal_bridge_width 0.5)
			(island_removal_mode 0)
		)
		(polygon
			(pts
				(arc
					(start 28.289758 -400.390106)
					(mid 27.530298 -400.390106)
					(end 28.289758 -400.390106)
				)
			)
		)
	)
	(zone
		(layers "B.Cu" "In9.Cu" "In11.Cu" "In13.Cu" "In15.Cu")
		(hatch none 0.5)
		(connect_pads
			(clearance 0)
		)
		(min_thickness 0.25)
		(keepout
			(tracks not_allowed)
			(vias allowed)
			(pads allowed)
			(copperpour not_allowed)
			(footprints allowed)
		)
		(placement
			(enabled no)
			(sheetname "")
		)
		(fill yes
			(thermal_gap 0.5)
			(thermal_bridge_width 0.5)
			(island_removal_mode 0)
		)
		(polygon
			(pts
				(arc
					(start 297.876214 -313.949842)
					(mid 297.223434 -313.949842)
					(end 297.876214 -313.949842)
				)
			)
		)
	)
	(zone
		(layers "B.Cu" "In9.Cu" "In11.Cu" "In13.Cu" "In15.Cu")
		(hatch none 0.5)
		(connect_pads
			(clearance 0)
		)
		(min_thickness 0.25)
		(keepout
			(tracks not_allowed)
			(vias allowed)
			(pads allowed)
			(copperpour not_allowed)
			(footprints allowed)
		)
		(placement
			(enabled no)
			(sheetname "")
		)
		(fill yes
			(thermal_gap 0.5)
			(thermal_bridge_width 0.5)
			(island_removal_mode 0)
		)
		(polygon
			(pts
				(arc
					(start 60.926218 -312.049922)
					(mid 60.273438 -312.049922)
					(end 60.926218 -312.049922)
				)
			)
		)
	)
	(zone
		(layers "B.Cu" "In9.Cu" "In11.Cu" "In13.Cu" "In15.Cu")
		(hatch none 0.5)
		(connect_pads
			(clearance 0)
		)
		(min_thickness 0.25)
		(keepout
			(tracks not_allowed)
			(vias allowed)
			(pads allowed)
			(copperpour not_allowed)
			(footprints allowed)
		)
		(placement
			(enabled no)
			(sheetname "")
		)
		(fill yes
			(thermal_gap 0.5)
			(thermal_bridge_width 0.5)
			(island_removal_mode 0)
		)
		(polygon
			(pts
				(arc
					(start 292.1762 -312.999882)
					(mid 291.52342 -312.999882)
					(end 292.1762 -312.999882)
				)
			)
		)
	)
	(zone
		(layers "B.Cu" "In9.Cu" "In11.Cu" "In13.Cu" "In15.Cu")
		(hatch none 0.5)
		(connect_pads
			(clearance 0)
		)
		(min_thickness 0.25)
		(keepout
			(tracks not_allowed)
			(vias allowed)
			(pads allowed)
			(copperpour not_allowed)
			(footprints allowed)
		)
		(placement
			(enabled no)
			(sheetname "")
		)
		(fill yes
			(thermal_gap 0.5)
			(thermal_bridge_width 0.5)
			(island_removal_mode 0)
		)
		(polygon
			(pts
				(arc
					(start 22.793198 -357.75773)
					(mid 22.089618 -357.75773)
					(end 22.793198 -357.75773)
				)
			)
		)
	)
	(zone
		(layers "B.Cu" "In9.Cu" "In11.Cu" "In13.Cu" "In15.Cu")
		(hatch none 0.5)
		(connect_pads
			(clearance 0)
		)
		(min_thickness 0.25)
		(keepout
			(tracks not_allowed)
			(vias allowed)
			(pads allowed)
			(copperpour not_allowed)
			(footprints allowed)
		)
		(placement
			(enabled no)
			(sheetname "")
		)
		(fill yes
			(thermal_gap 0.5)
			(thermal_bridge_width 0.5)
			(island_removal_mode 0)
		)
		(polygon
			(pts
				(arc
					(start 115.322858 -345.465146)
					(mid 114.619278 -345.465146)
					(end 115.322858 -345.465146)
				)
			)
		)
	)
	(zone
		(layers "B.Cu" "In9.Cu" "In11.Cu" "In13.Cu" "In15.Cu")
		(hatch none 0.5)
		(connect_pads
			(clearance 0)
		)
		(min_thickness 0.25)
		(keepout
			(tracks not_allowed)
			(vias allowed)
			(pads allowed)
			(copperpour not_allowed)
			(footprints allowed)
		)
		(placement
			(enabled no)
			(sheetname "")
		)
		(fill yes
			(thermal_gap 0.5)
			(thermal_bridge_width 0.5)
			(island_removal_mode 0)
		)
		(polygon
			(pts
				(arc
					(start 438.491122 -342.439498)
					(mid 437.787542 -342.439498)
					(end 438.491122 -342.439498)
				)
			)
		)
	)
	(zone
		(layers "B.Cu" "In9.Cu" "In11.Cu" "In13.Cu" "In15.Cu")
		(hatch none 0.5)
		(connect_pads
			(clearance 0)
		)
		(min_thickness 0.25)
		(keepout
			(tracks not_allowed)
			(vias allowed)
			(pads allowed)
			(copperpour not_allowed)
			(footprints allowed)
		)
		(placement
			(enabled no)
			(sheetname "")
		)
		(fill yes
			(thermal_gap 0.5)
			(thermal_bridge_width 0.5)
			(island_removal_mode 0)
		)
		(polygon
			(pts
				(arc
					(start 7.562342 -30.922468)
					(mid 6.858762 -30.922468)
					(end 7.562342 -30.922468)
				)
			)
		)
	)
	(zone
		(layers "B.Cu" "In9.Cu" "In11.Cu" "In13.Cu" "In15.Cu")
		(hatch none 0.5)
		(connect_pads
			(clearance 0)
		)
		(min_thickness 0.25)
		(keepout
			(tracks not_allowed)
			(vias allowed)
			(pads allowed)
			(copperpour not_allowed)
			(footprints allowed)
		)
		(placement
			(enabled no)
			(sheetname "")
		)
		(fill yes
			(thermal_gap 0.5)
			(thermal_bridge_width 0.5)
			(island_removal_mode 0)
		)
		(polygon
			(pts
				(arc
					(start 381.73025 -357.75773)
					(mid 381.02667 -357.75773)
					(end 381.73025 -357.75773)
				)
			)
		)
	)
	(zone
		(layers "B.Cu" "In9.Cu" "In11.Cu" "In13.Cu" "In15.Cu")
		(hatch none 0.5)
		(connect_pads
			(clearance 0)
		)
		(min_thickness 0.25)
		(keepout
			(tracks not_allowed)
			(vias allowed)
			(pads allowed)
			(copperpour not_allowed)
			(footprints allowed)
		)
		(placement
			(enabled no)
			(sheetname "")
		)
		(fill yes
			(thermal_gap 0.5)
			(thermal_bridge_width 0.5)
			(island_removal_mode 0)
		)
		(polygon
			(pts
				(arc
					(start 76.689712 -405.589994)
					(mid 75.930252 -405.589994)
					(end 76.689712 -405.589994)
				)
			)
		)
	)
	(zone
		(layers "B.Cu" "In9.Cu" "In11.Cu" "In13.Cu" "In15.Cu")
		(hatch none 0.5)
		(connect_pads
			(clearance 0)
		)
		(min_thickness 0.25)
		(keepout
			(tracks not_allowed)
			(vias allowed)
			(pads allowed)
			(copperpour not_allowed)
			(footprints allowed)
		)
		(placement
			(enabled no)
			(sheetname "")
		)
		(fill yes
			(thermal_gap 0.5)
			(thermal_bridge_width 0.5)
			(island_removal_mode 0)
		)
		(polygon
			(pts
				(arc
					(start 440.736482 -351.611438)
					(mid 440.032902 -351.611438)
					(end 440.736482 -351.611438)
				)
			)
		)
	)
	(zone
		(layers "B.Cu" "In9.Cu" "In11.Cu" "In13.Cu" "In15.Cu")
		(hatch none 0.5)
		(connect_pads
			(clearance 0)
		)
		(min_thickness 0.25)
		(keepout
			(tracks not_allowed)
			(vias allowed)
			(pads allowed)
			(copperpour not_allowed)
			(footprints allowed)
		)
		(placement
			(enabled no)
			(sheetname "")
		)
		(fill yes
			(thermal_gap 0.5)
			(thermal_bridge_width 0.5)
			(island_removal_mode 0)
		)
		(polygon
			(pts
				(arc
					(start 87.416386 -28.25877)
					(mid 86.712806 -28.25877)
					(end 87.416386 -28.25877)
				)
			)
		)
	)
	(zone
		(layers "B.Cu" "In9.Cu" "In11.Cu" "In13.Cu" "In15.Cu")
		(hatch none 0.5)
		(connect_pads
			(clearance 0)
		)
		(min_thickness 0.25)
		(keepout
			(tracks not_allowed)
			(vias allowed)
			(pads allowed)
			(copperpour not_allowed)
			(footprints allowed)
		)
		(placement
			(enabled no)
			(sheetname "")
		)
		(fill yes
			(thermal_gap 0.5)
			(thermal_bridge_width 0.5)
			(island_removal_mode 0)
		)
		(polygon
			(pts
				(arc
					(start 340.835234 -345.465146)
					(mid 340.131654 -345.465146)
					(end 340.835234 -345.465146)
				)
			)
		)
	)
	(zone
		(layers "B.Cu" "In9.Cu" "In11.Cu" "In13.Cu" "In15.Cu")
		(hatch none 0.5)
		(connect_pads
			(clearance 0)
		)
		(min_thickness 0.25)
		(keepout
			(tracks not_allowed)
			(vias allowed)
			(pads allowed)
			(copperpour not_allowed)
			(footprints allowed)
		)
		(placement
			(enabled no)
			(sheetname "")
		)
		(fill yes
			(thermal_gap 0.5)
			(thermal_bridge_width 0.5)
			(island_removal_mode 0)
		)
		(polygon
			(pts
				(arc
					(start 177.026316 -311.099962)
					(mid 176.373536 -311.099962)
					(end 177.026316 -311.099962)
				)
			)
		)
	)
	(zone
		(layers "B.Cu" "In9.Cu" "In11.Cu" "In13.Cu" "In15.Cu")
		(hatch none 0.5)
		(connect_pads
			(clearance 0)
		)
		(min_thickness 0.25)
		(keepout
			(tracks not_allowed)
			(vias allowed)
			(pads allowed)
			(copperpour not_allowed)
			(footprints allowed)
		)
		(placement
			(enabled no)
			(sheetname "")
		)
		(fill yes
			(thermal_gap 0.5)
			(thermal_bridge_width 0.5)
			(island_removal_mode 0)
		)
		(polygon
			(pts
				(arc
					(start 269.112492 -348.58579)
					(mid 268.408912 -348.58579)
					(end 269.112492 -348.58579)
				)
			)
		)
	)
	(zone
		(layers "B.Cu" "In9.Cu" "In11.Cu" "In13.Cu" "In15.Cu")
		(hatch none 0.5)
		(connect_pads
			(clearance 0)
		)
		(min_thickness 0.25)
		(keepout
			(tracks not_allowed)
			(vias allowed)
			(pads allowed)
			(copperpour not_allowed)
			(footprints allowed)
		)
		(placement
			(enabled no)
			(sheetname "")
		)
		(fill yes
			(thermal_gap 0.5)
			(thermal_bridge_width 0.5)
			(island_removal_mode 0)
		)
		(polygon
			(pts
				(arc
					(start 30.489652 -375.490232)
					(mid 29.730192 -375.490232)
					(end 30.489652 -375.490232)
				)
			)
		)
	)
	(zone
		(layers "B.Cu" "In9.Cu" "In11.Cu" "In13.Cu" "In15.Cu")
		(hatch none 0.5)
		(connect_pads
			(clearance 0)
		)
		(min_thickness 0.25)
		(keepout
			(tracks not_allowed)
			(vias allowed)
			(pads allowed)
			(copperpour not_allowed)
			(footprints allowed)
		)
		(placement
			(enabled no)
			(sheetname "")
		)
		(fill yes
			(thermal_gap 0.5)
			(thermal_bridge_width 0.5)
			(island_removal_mode 0)
		)
		(polygon
			(pts
				(arc
					(start 71.914512 -357.75773)
					(mid 71.210932 -357.75773)
					(end 71.914512 -357.75773)
				)
			)
		)
	)
	(zone
		(layers "B.Cu" "In9.Cu" "In11.Cu" "In13.Cu" "In15.Cu")
		(hatch none 0.5)
		(connect_pads
			(clearance 0)
		)
		(min_thickness 0.25)
		(keepout
			(tracks not_allowed)
			(vias allowed)
			(pads allowed)
			(copperpour not_allowed)
			(footprints allowed)
		)
		(placement
			(enabled no)
			(sheetname "")
		)
		(fill yes
			(thermal_gap 0.5)
			(thermal_bridge_width 0.5)
			(island_removal_mode 0)
		)
		(polygon
			(pts
				(arc
					(start 426.3263 -305.399948)
					(mid 425.67352 -305.399948)
					(end 426.3263 -305.399948)
				)
			)
		)
	)
	(zone
		(layers "B.Cu" "In9.Cu" "In11.Cu" "In13.Cu" "In15.Cu")
		(hatch none 0.5)
		(connect_pads
			(clearance 0)
		)
		(min_thickness 0.25)
		(keepout
			(tracks not_allowed)
			(vias allowed)
			(pads allowed)
			(copperpour not_allowed)
			(footprints allowed)
		)
		(placement
			(enabled no)
			(sheetname "")
		)
		(fill yes
			(thermal_gap 0.5)
			(thermal_bridge_width 0.5)
			(island_removal_mode 0)
		)
		(polygon
			(pts
				(arc
					(start 122.404378 -345.465146)
					(mid 121.700798 -345.465146)
					(end 122.404378 -345.465146)
				)
			)
		)
	)
	(zone
		(layers "B.Cu" "In9.Cu" "In11.Cu" "In13.Cu" "In15.Cu")
		(hatch none 0.5)
		(connect_pads
			(clearance 0)
		)
		(min_thickness 0.25)
		(keepout
			(tracks not_allowed)
			(vias allowed)
			(pads allowed)
			(copperpour not_allowed)
			(footprints allowed)
		)
		(placement
			(enabled no)
			(sheetname "")
		)
		(fill yes
			(thermal_gap 0.5)
			(thermal_bridge_width 0.5)
			(island_removal_mode 0)
		)
		(polygon
			(pts
				(arc
					(start 32.6898 -374.390158)
					(mid 31.93034 -374.390158)
					(end 32.6898 -374.390158)
				)
			)
		)
	)
	(zone
		(layers "B.Cu" "In9.Cu" "In11.Cu" "In13.Cu" "In15.Cu")
		(hatch none 0.5)
		(connect_pads
			(clearance 0)
		)
		(min_thickness 0.25)
		(keepout
			(tracks not_allowed)
			(vias allowed)
			(pads allowed)
			(copperpour not_allowed)
			(footprints allowed)
		)
		(placement
			(enabled no)
			(sheetname "")
		)
		(fill yes
			(thermal_gap 0.5)
			(thermal_bridge_width 0.5)
			(island_removal_mode 0)
		)
		(polygon
			(pts
				(arc
					(start 41.48963 -375.69013)
					(mid 40.73017 -375.69013)
					(end 41.48963 -375.69013)
				)
			)
		)
	)
	(zone
		(layers "B.Cu" "In9.Cu" "In11.Cu" "In13.Cu" "In15.Cu")
		(hatch none 0.5)
		(connect_pads
			(clearance 0)
		)
		(min_thickness 0.25)
		(keepout
			(tracks not_allowed)
			(vias allowed)
			(pads allowed)
			(copperpour not_allowed)
			(footprints allowed)
		)
		(placement
			(enabled no)
			(sheetname "")
		)
		(fill yes
			(thermal_gap 0.5)
			(thermal_bridge_width 0.5)
			(island_removal_mode 0)
		)
		(polygon
			(pts
				(arc
					(start 168.476422 -274.049744)
					(mid 167.823642 -274.049744)
					(end 168.476422 -274.049744)
				)
			)
		)
	)
	(zone
		(layers "B.Cu" "In9.Cu" "In11.Cu" "In13.Cu" "In15.Cu")
		(hatch none 0.5)
		(connect_pads
			(clearance 0)
		)
		(min_thickness 0.25)
		(keepout
			(tracks not_allowed)
			(vias allowed)
			(pads allowed)
			(copperpour not_allowed)
			(footprints allowed)
		)
		(placement
			(enabled no)
			(sheetname "")
		)
		(fill yes
			(thermal_gap 0.5)
			(thermal_bridge_width 0.5)
			(island_removal_mode 0)
		)
		(polygon
			(pts
				(arc
					(start 69.476366 -312.999882)
					(mid 68.823586 -312.999882)
					(end 69.476366 -312.999882)
				)
			)
		)
	)
	(zone
		(layers "B.Cu" "In9.Cu" "In11.Cu" "In13.Cu" "In15.Cu")
		(hatch none 0.5)
		(connect_pads
			(clearance 0)
		)
		(min_thickness 0.25)
		(keepout
			(tracks not_allowed)
			(vias allowed)
			(pads allowed)
			(copperpour not_allowed)
			(footprints allowed)
		)
		(placement
			(enabled no)
			(sheetname "")
		)
		(fill yes
			(thermal_gap 0.5)
			(thermal_bridge_width 0.5)
			(island_removal_mode 0)
		)
		(polygon
			(pts
				(arc
					(start 293.984172 -348.58579)
					(mid 293.280592 -348.58579)
					(end 293.984172 -348.58579)
				)
			)
		)
	)
	(zone
		(layers "B.Cu" "In9.Cu" "In11.Cu" "In13.Cu" "In15.Cu")
		(hatch none 0.5)
		(connect_pads
			(clearance 0)
		)
		(min_thickness 0.25)
		(keepout
			(tracks not_allowed)
			(vias allowed)
			(pads allowed)
			(copperpour not_allowed)
			(footprints allowed)
		)
		(placement
			(enabled no)
			(sheetname "")
		)
		(fill yes
			(thermal_gap 0.5)
			(thermal_bridge_width 0.5)
			(island_removal_mode 0)
		)
		(polygon
			(pts
				(arc
					(start 171.864782 -345.465146)
					(mid 171.161202 -345.465146)
					(end 171.864782 -345.465146)
				)
			)
		)
	)
	(zone
		(layers "B.Cu" "In9.Cu" "In11.Cu" "In13.Cu" "In15.Cu")
		(hatch none 0.5)
		(connect_pads
			(clearance 0)
		)
		(min_thickness 0.25)
		(keepout
			(tracks not_allowed)
			(vias allowed)
			(pads allowed)
			(copperpour not_allowed)
			(footprints allowed)
		)
		(placement
			(enabled no)
			(sheetname "")
		)
		(fill yes
			(thermal_gap 0.5)
			(thermal_bridge_width 0.5)
			(island_removal_mode 0)
		)
		(polygon
			(pts
				(arc
					(start 125.51664 -31.858712)
					(mid 124.81306 -31.858712)
					(end 125.51664 -31.858712)
				)
			)
		)
	)
	(zone
		(layers "B.Cu" "In9.Cu" "In11.Cu" "In13.Cu" "In15.Cu")
		(hatch none 0.5)
		(connect_pads
			(clearance 0)
		)
		(min_thickness 0.25)
		(keepout
			(tracks not_allowed)
			(vias allowed)
			(pads allowed)
			(copperpour not_allowed)
			(footprints allowed)
		)
		(placement
			(enabled no)
			(sheetname "")
		)
		(fill yes
			(thermal_gap 0.5)
			(thermal_bridge_width 0.5)
			(island_removal_mode 0)
		)
		(polygon
			(pts
				(arc
					(start 319.072514 -351.611438)
					(mid 318.368934 -351.611438)
					(end 319.072514 -351.611438)
				)
			)
		)
	)
	(zone
		(layers "B.Cu" "In9.Cu" "In11.Cu" "In13.Cu" "In15.Cu")
		(hatch none 0.5)
		(connect_pads
			(clearance 0)
		)
		(min_thickness 0.25)
		(keepout
			(tracks not_allowed)
			(vias allowed)
			(pads allowed)
			(copperpour not_allowed)
			(footprints allowed)
		)
		(placement
			(enabled no)
			(sheetname "")
		)
		(fill yes
			(thermal_gap 0.5)
			(thermal_bridge_width 0.5)
			(island_removal_mode 0)
		)
		(polygon
			(pts
				(arc
					(start 381.73025 -342.439498)
					(mid 381.02667 -342.439498)
					(end 381.73025 -342.439498)
				)
			)
		)
	)
	(zone
		(layers "B.Cu" "In9.Cu" "In11.Cu" "In13.Cu" "In15.Cu")
		(hatch none 0.5)
		(connect_pads
			(clearance 0)
		)
		(min_thickness 0.25)
		(keepout
			(tracks not_allowed)
			(vias allowed)
			(pads allowed)
			(copperpour not_allowed)
			(footprints allowed)
		)
		(placement
			(enabled no)
			(sheetname "")
		)
		(fill yes
			(thermal_gap 0.5)
			(thermal_bridge_width 0.5)
			(island_removal_mode 0)
		)
		(polygon
			(pts
				(arc
					(start 322.181474 -354.732082)
					(mid 321.477894 -354.732082)
					(end 322.181474 -354.732082)
				)
			)
		)
	)
	(zone
		(layers "B.Cu" "In9.Cu" "In11.Cu" "In13.Cu" "In15.Cu")
		(hatch none 0.5)
		(connect_pads
			(clearance 0)
		)
		(min_thickness 0.25)
		(keepout
			(tracks not_allowed)
			(vias allowed)
			(pads allowed)
			(copperpour not_allowed)
			(footprints allowed)
		)
		(placement
			(enabled no)
			(sheetname "")
		)
		(fill yes
			(thermal_gap 0.5)
			(thermal_bridge_width 0.5)
			(island_removal_mode 0)
		)
		(polygon
			(pts
				(arc
					(start 335.480914 -342.439498)
					(mid 334.777334 -342.439498)
					(end 335.480914 -342.439498)
				)
			)
		)
	)
	(zone
		(layers "B.Cu" "In9.Cu" "In11.Cu" "In13.Cu" "In15.Cu")
		(hatch none 0.5)
		(connect_pads
			(clearance 0)
		)
		(min_thickness 0.25)
		(keepout
			(tracks not_allowed)
			(vias allowed)
			(pads allowed)
			(copperpour not_allowed)
			(footprints allowed)
		)
		(placement
			(enabled no)
			(sheetname "")
		)
		(fill yes
			(thermal_gap 0.5)
			(thermal_bridge_width 0.5)
			(island_removal_mode 0)
		)
		(polygon
			(pts
				(arc
					(start 290.27628 -273.099784)
					(mid 289.6235 -273.099784)
					(end 290.27628 -273.099784)
				)
			)
		)
	)
	(zone
		(layers "B.Cu" "In9.Cu" "In11.Cu" "In13.Cu" "In15.Cu")
		(hatch none 0.5)
		(connect_pads
			(clearance 0)
		)
		(min_thickness 0.25)
		(keepout
			(tracks not_allowed)
			(vias allowed)
			(pads allowed)
			(copperpour not_allowed)
			(footprints allowed)
		)
		(placement
			(enabled no)
			(sheetname "")
		)
		(fill yes
			(thermal_gap 0.5)
			(thermal_bridge_width 0.5)
			(island_removal_mode 0)
		)
		(polygon
			(pts
				(arc
					(start 384.83921 -348.58579)
					(mid 384.13563 -348.58579)
					(end 384.83921 -348.58579)
				)
			)
		)
	)
	(zone
		(layers "B.Cu" "In9.Cu" "In11.Cu" "In13.Cu" "In15.Cu")
		(hatch none 0.5)
		(connect_pads
			(clearance 0)
		)
		(min_thickness 0.25)
		(keepout
			(tracks not_allowed)
			(vias allowed)
			(pads allowed)
			(copperpour not_allowed)
			(footprints allowed)
		)
		(placement
			(enabled no)
			(sheetname "")
		)
		(fill yes
			(thermal_gap 0.5)
			(thermal_bridge_width 0.5)
			(island_removal_mode 0)
		)
		(polygon
			(pts
				(arc
					(start 298.869608 -376.790204)
					(mid 298.110148 -376.790204)
					(end 298.869608 -376.790204)
				)
			)
		)
	)
	(zone
		(layers "B.Cu" "In9.Cu" "In11.Cu" "In13.Cu" "In15.Cu")
		(hatch none 0.5)
		(connect_pads
			(clearance 0)
		)
		(min_thickness 0.25)
		(keepout
			(tracks not_allowed)
			(vias allowed)
			(pads allowed)
			(copperpour not_allowed)
			(footprints allowed)
		)
		(placement
			(enabled no)
			(sheetname "")
		)
		(fill yes
			(thermal_gap 0.5)
			(thermal_bridge_width 0.5)
			(island_removal_mode 0)
		)
		(polygon
			(pts
				(arc
					(start 61.416438 -32.722312)
					(mid 60.712858 -32.722312)
					(end 61.416438 -32.722312)
				)
			)
		)
	)
	(zone
		(layers "B.Cu" "In9.Cu" "In11.Cu" "In13.Cu" "In15.Cu")
		(hatch none 0.5)
		(connect_pads
			(clearance 0)
		)
		(min_thickness 0.25)
		(keepout
			(tracks not_allowed)
			(vias allowed)
			(pads allowed)
			(copperpour not_allowed)
			(footprints allowed)
		)
		(placement
			(enabled no)
			(sheetname "")
		)
		(fill yes
			(thermal_gap 0.5)
			(thermal_bridge_width 0.5)
			(island_removal_mode 0)
		)
		(polygon
			(pts
				(arc
					(start 188.273182 -348.58579)
					(mid 187.569602 -348.58579)
					(end 188.273182 -348.58579)
				)
			)
		)
	)
	(zone
		(layers "B.Cu" "In9.Cu" "In11.Cu" "In13.Cu" "In15.Cu")
		(hatch none 0.5)
		(connect_pads
			(clearance 0)
		)
		(min_thickness 0.25)
		(keepout
			(tracks not_allowed)
			(vias allowed)
			(pads allowed)
			(copperpour not_allowed)
			(footprints allowed)
		)
		(placement
			(enabled no)
			(sheetname "")
		)
		(fill yes
			(thermal_gap 0.5)
			(thermal_bridge_width 0.5)
			(island_removal_mode 0)
		)
		(polygon
			(pts
				(arc
					(start 338.469732 -406.690068)
					(mid 337.710272 -406.690068)
					(end 338.469732 -406.690068)
				)
			)
		)
	)
	(zone
		(layers "B.Cu" "In9.Cu" "In11.Cu" "In13.Cu" "In15.Cu")
		(hatch none 0.5)
		(connect_pads
			(clearance 0)
		)
		(min_thickness 0.25)
		(keepout
			(tracks not_allowed)
			(vias allowed)
			(pads allowed)
			(copperpour not_allowed)
			(footprints allowed)
		)
		(placement
			(enabled no)
			(sheetname "")
		)
		(fill yes
			(thermal_gap 0.5)
			(thermal_bridge_width 0.5)
			(island_removal_mode 0)
		)
		(polygon
			(pts
				(arc
					(start 408.276298 -312.999882)
					(mid 407.623518 -312.999882)
					(end 408.276298 -312.999882)
				)
			)
		)
	)
	(zone
		(layers "B.Cu" "In9.Cu" "In11.Cu" "In13.Cu" "In15.Cu")
		(hatch none 0.5)
		(connect_pads
			(clearance 0)
		)
		(min_thickness 0.25)
		(keepout
			(tracks not_allowed)
			(vias allowed)
			(pads allowed)
			(copperpour not_allowed)
			(footprints allowed)
		)
		(placement
			(enabled no)
			(sheetname "")
		)
		(fill yes
			(thermal_gap 0.5)
			(thermal_bridge_width 0.5)
			(island_removal_mode 0)
		)
		(polygon
			(pts
				(arc
					(start 355.862382 -30.922468)
					(mid 355.158802 -30.922468)
					(end 355.862382 -30.922468)
				)
			)
		)
	)
	(zone
		(layers "B.Cu" "In9.Cu" "In11.Cu" "In13.Cu" "In15.Cu")
		(hatch none 0.5)
		(connect_pads
			(clearance 0)
		)
		(min_thickness 0.25)
		(keepout
			(tracks not_allowed)
			(vias allowed)
			(pads allowed)
			(copperpour not_allowed)
			(footprints allowed)
		)
		(placement
			(enabled no)
			(sheetname "")
		)
		(fill yes
			(thermal_gap 0.5)
			(thermal_bridge_width 0.5)
			(island_removal_mode 0)
		)
		(polygon
			(pts
				(arc
					(start 175.837342 -348.58579)
					(mid 175.133762 -348.58579)
					(end 175.837342 -348.58579)
				)
			)
		)
	)
	(zone
		(layers "B.Cu" "In9.Cu" "In11.Cu" "In13.Cu" "In15.Cu")
		(hatch none 0.5)
		(connect_pads
			(clearance 0)
		)
		(min_thickness 0.25)
		(keepout
			(tracks not_allowed)
			(vias allowed)
			(pads allowed)
			(copperpour not_allowed)
			(footprints allowed)
		)
		(placement
			(enabled no)
			(sheetname "")
		)
		(fill yes
			(thermal_gap 0.5)
			(thermal_bridge_width 0.5)
			(island_removal_mode 0)
		)
		(polygon
			(pts
				(arc
					(start 43.826176 -302.549814)
					(mid 43.173396 -302.549814)
					(end 43.826176 -302.549814)
				)
			)
		)
	)
	(zone
		(layers "B.Cu" "In9.Cu" "In11.Cu" "In13.Cu" "In15.Cu")
		(hatch none 0.5)
		(connect_pads
			(clearance 0)
		)
		(min_thickness 0.25)
		(keepout
			(tracks not_allowed)
			(vias allowed)
			(pads allowed)
			(copperpour not_allowed)
			(footprints allowed)
		)
		(placement
			(enabled no)
			(sheetname "")
		)
		(fill yes
			(thermal_gap 0.5)
			(thermal_bridge_width 0.5)
			(island_removal_mode 0)
		)
		(polygon
			(pts
				(arc
					(start 179.87645 -313.949842)
					(mid 179.22367 -313.949842)
					(end 179.87645 -313.949842)
				)
			)
		)
	)
	(zone
		(layers "B.Cu" "In9.Cu" "In11.Cu" "In13.Cu" "In15.Cu")
		(hatch none 0.5)
		(connect_pads
			(clearance 0)
		)
		(min_thickness 0.25)
		(keepout
			(tracks not_allowed)
			(vias allowed)
			(pads allowed)
			(copperpour not_allowed)
			(footprints allowed)
		)
		(placement
			(enabled no)
			(sheetname "")
		)
		(fill yes
			(thermal_gap 0.5)
			(thermal_bridge_width 0.5)
			(island_removal_mode 0)
		)
		(polygon
			(pts
				(arc
					(start 403.526244 -312.049922)
					(mid 402.873464 -312.049922)
					(end 403.526244 -312.049922)
				)
			)
		)
	)
	(zone
		(layers "B.Cu" "In9.Cu" "In11.Cu" "In13.Cu" "In15.Cu")
		(hatch none 0.5)
		(connect_pads
			(clearance 0)
		)
		(min_thickness 0.25)
		(keepout
			(tracks not_allowed)
			(vias allowed)
			(pads allowed)
			(copperpour not_allowed)
			(footprints allowed)
		)
		(placement
			(enabled no)
			(sheetname "")
		)
		(fill yes
			(thermal_gap 0.5)
			(thermal_bridge_width 0.5)
			(island_removal_mode 0)
		)
		(polygon
			(pts
				(arc
					(start 51.637438 -348.58579)
					(mid 50.933858 -348.58579)
					(end 51.637438 -348.58579)
				)
			)
		)
	)
	(zone
		(layers "B.Cu" "In9.Cu" "In11.Cu" "In13.Cu" "In15.Cu")
		(hatch none 0.5)
		(connect_pads
			(clearance 0)
		)
		(min_thickness 0.25)
		(keepout
			(tracks not_allowed)
			(vias allowed)
			(pads allowed)
			(copperpour not_allowed)
			(footprints allowed)
		)
		(placement
			(enabled no)
			(sheetname "")
		)
		(fill yes
			(thermal_gap 0.5)
			(thermal_bridge_width 0.5)
			(island_removal_mode 0)
		)
		(polygon
			(pts
				(arc
					(start 177.516536 -32.722312)
					(mid 176.812956 -32.722312)
					(end 177.516536 -32.722312)
				)
			)
		)
	)
	(zone
		(layers "B.Cu" "In9.Cu" "In11.Cu" "In13.Cu" "In15.Cu")
		(hatch none 0.5)
		(connect_pads
			(clearance 0)
		)
		(min_thickness 0.25)
		(keepout
			(tracks not_allowed)
			(vias allowed)
			(pads allowed)
			(copperpour not_allowed)
			(footprints allowed)
		)
		(placement
			(enabled no)
			(sheetname "")
		)
		(fill yes
			(thermal_gap 0.5)
			(thermal_bridge_width 0.5)
			(island_removal_mode 0)
		)
		(polygon
			(pts
				(arc
					(start 196.026278 -311.099962)
					(mid 195.373498 -311.099962)
					(end 196.026278 -311.099962)
				)
			)
		)
	)
	(zone
		(layers "B.Cu" "In9.Cu" "In11.Cu" "In13.Cu" "In15.Cu")
		(hatch none 0.5)
		(connect_pads
			(clearance 0)
		)
		(min_thickness 0.25)
		(keepout
			(tracks not_allowed)
			(vias allowed)
			(pads allowed)
			(copperpour not_allowed)
			(footprints allowed)
		)
		(placement
			(enabled no)
			(sheetname "")
		)
		(fill yes
			(thermal_gap 0.5)
			(thermal_bridge_width 0.5)
			(island_removal_mode 0)
		)
		(polygon
			(pts
				(arc
					(start 164.68979 -396.49019)
					(mid 163.93033 -396.49019)
					(end 164.68979 -396.49019)
				)
			)
		)
	)
	(zone
		(layers "B.Cu" "In9.Cu" "In11.Cu" "In13.Cu" "In15.Cu")
		(hatch none 0.5)
		(connect_pads
			(clearance 0)
		)
		(min_thickness 0.25)
		(keepout
			(tracks not_allowed)
			(vias allowed)
			(pads allowed)
			(copperpour not_allowed)
			(footprints allowed)
		)
		(placement
			(enabled no)
			(sheetname "")
		)
		(fill yes
			(thermal_gap 0.5)
			(thermal_bridge_width 0.5)
			(island_removal_mode 0)
		)
		(polygon
			(pts
				(arc
					(start 290.011612 -345.465146)
					(mid 289.308032 -345.465146)
					(end 290.011612 -345.465146)
				)
			)
		)
	)
	(zone
		(layers "B.Cu" "In9.Cu" "In11.Cu" "In13.Cu" "In15.Cu")
		(hatch none 0.5)
		(connect_pads
			(clearance 0)
		)
		(min_thickness 0.25)
		(keepout
			(tracks not_allowed)
			(vias allowed)
			(pads allowed)
			(copperpour not_allowed)
			(footprints allowed)
		)
		(placement
			(enabled no)
			(sheetname "")
		)
		(fill yes
			(thermal_gap 0.5)
			(thermal_bridge_width 0.5)
			(island_removal_mode 0)
		)
		(polygon
			(pts
				(arc
					(start 396.41145 -348.58579)
					(mid 395.70787 -348.58579)
					(end 396.41145 -348.58579)
				)
			)
		)
	)
	(zone
		(layers "B.Cu" "In9.Cu" "In11.Cu" "In13.Cu" "In15.Cu")
		(hatch none 0.5)
		(connect_pads
			(clearance 0)
		)
		(min_thickness 0.25)
		(keepout
			(tracks not_allowed)
			(vias allowed)
			(pads allowed)
			(copperpour not_allowed)
			(footprints allowed)
		)
		(placement
			(enabled no)
			(sheetname "")
		)
		(fill yes
			(thermal_gap 0.5)
			(thermal_bridge_width 0.5)
			(island_removal_mode 0)
		)
		(polygon
			(pts
				(arc
					(start 127.758698 -342.439498)
					(mid 127.055118 -342.439498)
					(end 127.758698 -342.439498)
				)
			)
		)
	)
	(zone
		(layers "B.Cu" "In9.Cu" "In11.Cu" "In13.Cu" "In15.Cu")
		(hatch none 0.5)
		(connect_pads
			(clearance 0)
		)
		(min_thickness 0.25)
		(keepout
			(tracks not_allowed)
			(vias allowed)
			(pads allowed)
			(copperpour not_allowed)
			(footprints allowed)
		)
		(placement
			(enabled no)
			(sheetname "")
		)
		(fill yes
			(thermal_gap 0.5)
			(thermal_bridge_width 0.5)
			(island_removal_mode 0)
		)
		(polygon
			(pts
				(arc
					(start 22.793198 -345.465146)
					(mid 22.089618 -345.465146)
					(end 22.793198 -345.465146)
				)
			)
		)
	)
	(zone
		(layers "B.Cu" "In9.Cu" "In11.Cu" "In13.Cu" "In15.Cu")
		(hatch none 0.5)
		(connect_pads
			(clearance 0)
		)
		(min_thickness 0.25)
		(keepout
			(tracks not_allowed)
			(vias allowed)
			(pads allowed)
			(copperpour not_allowed)
			(footprints allowed)
		)
		(placement
			(enabled no)
			(sheetname "")
		)
		(fill yes
			(thermal_gap 0.5)
			(thermal_bridge_width 0.5)
			(island_removal_mode 0)
		)
		(polygon
			(pts
				(arc
					(start 42.876216 -303.499774)
					(mid 42.223436 -303.499774)
					(end 42.876216 -303.499774)
				)
			)
		)
	)
	(zone
		(layers "B.Cu" "In9.Cu" "In11.Cu" "In13.Cu" "In15.Cu")
		(hatch none 0.5)
		(connect_pads
			(clearance 0)
		)
		(min_thickness 0.25)
		(keepout
			(tracks not_allowed)
			(vias allowed)
			(pads allowed)
			(copperpour not_allowed)
			(footprints allowed)
		)
		(placement
			(enabled no)
			(sheetname "")
		)
		(fill yes
			(thermal_gap 0.5)
			(thermal_bridge_width 0.5)
			(island_removal_mode 0)
		)
		(polygon
			(pts
				(arc
					(start 393.076176 -273.099784)
					(mid 392.423396 -273.099784)
					(end 393.076176 -273.099784)
				)
			)
		)
	)
	(zone
		(layers "B.Cu" "In9.Cu" "In11.Cu" "In13.Cu" "In15.Cu")
		(hatch none 0.5)
		(connect_pads
			(clearance 0)
		)
		(min_thickness 0.25)
		(keepout
			(tracks not_allowed)
			(vias allowed)
			(pads allowed)
			(copperpour not_allowed)
			(footprints allowed)
		)
		(placement
			(enabled no)
			(sheetname "")
		)
		(fill yes
			(thermal_gap 0.5)
			(thermal_bridge_width 0.5)
			(island_removal_mode 0)
		)
		(polygon
			(pts
				(arc
					(start 171.289726 -398.890236)
					(mid 170.530266 -398.890236)
					(end 171.289726 -398.890236)
				)
			)
		)
	)
	(zone
		(layers "B.Cu" "In9.Cu" "In11.Cu" "In13.Cu" "In15.Cu")
		(hatch none 0.5)
		(connect_pads
			(clearance 0)
		)
		(min_thickness 0.25)
		(keepout
			(tracks not_allowed)
			(vias allowed)
			(pads allowed)
			(copperpour not_allowed)
			(footprints allowed)
		)
		(placement
			(enabled no)
			(sheetname "")
		)
		(fill yes
			(thermal_gap 0.5)
			(thermal_bridge_width 0.5)
			(island_removal_mode 0)
		)
		(polygon
			(pts
				(arc
					(start 422.946322 -351.611438)
					(mid 422.242742 -351.611438)
					(end 422.946322 -351.611438)
				)
			)
		)
	)
	(zone
		(layers "B.Cu" "In9.Cu" "In11.Cu" "In13.Cu" "In15.Cu")
		(hatch none 0.5)
		(connect_pads
			(clearance 0)
		)
		(min_thickness 0.25)
		(keepout
			(tracks not_allowed)
			(vias allowed)
			(pads allowed)
			(copperpour not_allowed)
			(footprints allowed)
		)
		(placement
			(enabled no)
			(sheetname "")
		)
		(fill yes
			(thermal_gap 0.5)
			(thermal_bridge_width 0.5)
			(island_removal_mode 0)
		)
		(polygon
			(pts
				(arc
					(start 438.491122 -357.75773)
					(mid 437.787542 -357.75773)
					(end 438.491122 -357.75773)
				)
			)
		)
	)
	(zone
		(layers "B.Cu" "In9.Cu" "In11.Cu" "In13.Cu" "In15.Cu")
		(hatch none 0.5)
		(connect_pads
			(clearance 0)
		)
		(min_thickness 0.25)
		(keepout
			(tracks not_allowed)
			(vias allowed)
			(pads allowed)
			(copperpour not_allowed)
			(footprints allowed)
		)
		(placement
			(enabled no)
			(sheetname "")
		)
		(fill yes
			(thermal_gap 0.5)
			(thermal_bridge_width 0.5)
			(island_removal_mode 0)
		)
		(polygon
			(pts
				(arc
					(start 381.73025 -345.465146)
					(mid 381.02667 -345.465146)
					(end 381.73025 -345.465146)
				)
			)
		)
	)
	(zone
		(layers "B.Cu" "In9.Cu" "In11.Cu" "In13.Cu" "In15.Cu")
		(hatch none 0.5)
		(connect_pads
			(clearance 0)
		)
		(min_thickness 0.25)
		(keepout
			(tracks not_allowed)
			(vias allowed)
			(pads allowed)
			(copperpour not_allowed)
			(footprints allowed)
		)
		(placement
			(enabled no)
			(sheetname "")
		)
		(fill yes
			(thermal_gap 0.5)
			(thermal_bridge_width 0.5)
			(island_removal_mode 0)
		)
		(polygon
			(pts
				(arc
					(start 184.300622 -345.465146)
					(mid 183.597042 -345.465146)
					(end 184.300622 -345.465146)
				)
			)
		)
	)
	(zone
		(layers "B.Cu" "In9.Cu" "In11.Cu" "In13.Cu" "In15.Cu")
		(hatch none 0.5)
		(connect_pads
			(clearance 0)
		)
		(min_thickness 0.25)
		(keepout
			(tracks not_allowed)
			(vias allowed)
			(pads allowed)
			(copperpour not_allowed)
			(footprints allowed)
		)
		(placement
			(enabled no)
			(sheetname "")
		)
		(fill yes
			(thermal_gap 0.5)
			(thermal_bridge_width 0.5)
			(island_removal_mode 0)
		)
		(polygon
			(pts
				(arc
					(start 41.446958 -354.732082)
					(mid 40.743378 -354.732082)
					(end 41.446958 -354.732082)
				)
			)
		)
	)
	(zone
		(layers "B.Cu" "In9.Cu" "In11.Cu" "In13.Cu" "In15.Cu")
		(hatch none 0.5)
		(connect_pads
			(clearance 0)
		)
		(min_thickness 0.25)
		(keepout
			(tracks not_allowed)
			(vias allowed)
			(pads allowed)
			(copperpour not_allowed)
			(footprints allowed)
		)
		(placement
			(enabled no)
			(sheetname "")
		)
		(fill yes
			(thermal_gap 0.5)
			(thermal_bridge_width 0.5)
			(island_removal_mode 0)
		)
		(polygon
			(pts
				(arc
					(start 37.089842 -401.690078)
					(mid 36.330382 -401.690078)
					(end 37.089842 -401.690078)
				)
			)
		)
	)
	(zone
		(layers "B.Cu" "In9.Cu" "In11.Cu" "In13.Cu" "In15.Cu")
		(hatch none 0.5)
		(connect_pads
			(clearance 0)
		)
		(min_thickness 0.25)
		(keepout
			(tracks not_allowed)
			(vias allowed)
			(pads allowed)
			(copperpour not_allowed)
			(footprints allowed)
		)
		(placement
			(enabled no)
			(sheetname "")
		)
		(fill yes
			(thermal_gap 0.5)
			(thermal_bridge_width 0.5)
			(island_removal_mode 0)
		)
		(polygon
			(pts
				(arc
					(start 180.82641 -312.049922)
					(mid 180.17363 -312.049922)
					(end 180.82641 -312.049922)
				)
			)
		)
	)
	(zone
		(layers "B.Cu" "In9.Cu" "In11.Cu" "In13.Cu" "In15.Cu")
		(hatch none 0.5)
		(connect_pads
			(clearance 0)
		)
		(min_thickness 0.25)
		(keepout
			(tracks not_allowed)
			(vias allowed)
			(pads allowed)
			(copperpour not_allowed)
			(footprints allowed)
		)
		(placement
			(enabled no)
			(sheetname "")
		)
		(fill yes
			(thermal_gap 0.5)
			(thermal_bridge_width 0.5)
			(island_removal_mode 0)
		)
		(polygon
			(pts
				(arc
					(start 151.516588 -29.12237)
					(mid 150.813008 -29.12237)
					(end 151.516588 -29.12237)
				)
			)
		)
	)
	(zone
		(layers "B.Cu" "In9.Cu" "In11.Cu" "In13.Cu" "In15.Cu")
		(hatch none 0.5)
		(connect_pads
			(clearance 0)
		)
		(min_thickness 0.25)
		(keepout
			(tracks not_allowed)
			(vias allowed)
			(pads allowed)
			(copperpour not_allowed)
			(footprints allowed)
		)
		(placement
			(enabled no)
			(sheetname "")
		)
		(fill yes
			(thermal_gap 0.5)
			(thermal_bridge_width 0.5)
			(island_removal_mode 0)
		)
		(polygon
			(pts
				(arc
					(start 288.376106 -273.099784)
					(mid 287.723326 -273.099784)
					(end 288.376106 -273.099784)
				)
			)
		)
	)
	(zone
		(layers "B.Cu" "In9.Cu" "In11.Cu" "In13.Cu" "In15.Cu")
		(hatch none 0.5)
		(connect_pads
			(clearance 0)
		)
		(min_thickness 0.25)
		(keepout
			(tracks not_allowed)
			(vias allowed)
			(pads allowed)
			(copperpour not_allowed)
			(footprints allowed)
		)
		(placement
			(enabled no)
			(sheetname "")
		)
		(fill yes
			(thermal_gap 0.5)
			(thermal_bridge_width 0.5)
			(island_removal_mode 0)
		)
		(polygon
			(pts
				(arc
					(start 32.6898 -400.390106)
					(mid 31.93034 -400.390106)
					(end 32.6898 -400.390106)
				)
			)
		)
	)
	(zone
		(layers "B.Cu" "In9.Cu" "In11.Cu" "In13.Cu" "In15.Cu")
		(hatch none 0.5)
		(connect_pads
			(clearance 0)
		)
		(min_thickness 0.25)
		(keepout
			(tracks not_allowed)
			(vias allowed)
			(pads allowed)
			(copperpour not_allowed)
			(footprints allowed)
		)
		(placement
			(enabled no)
			(sheetname "")
		)
		(fill yes
			(thermal_gap 0.5)
			(thermal_bridge_width 0.5)
			(island_removal_mode 0)
		)
		(polygon
			(pts
				(arc
					(start 167.526462 -312.049922)
					(mid 166.873682 -312.049922)
					(end 167.526462 -312.049922)
				)
			)
		)
	)
	(zone
		(layers "B.Cu" "In9.Cu" "In11.Cu" "In13.Cu" "In15.Cu")
		(hatch none 0.5)
		(connect_pads
			(clearance 0)
		)
		(min_thickness 0.25)
		(keepout
			(tracks not_allowed)
			(vias allowed)
			(pads allowed)
			(copperpour not_allowed)
			(footprints allowed)
		)
		(placement
			(enabled no)
			(sheetname "")
		)
		(fill yes
			(thermal_gap 0.5)
			(thermal_bridge_width 0.5)
			(island_removal_mode 0)
		)
		(polygon
			(pts
				(arc
					(start 382.469644 -406.690068)
					(mid 381.710184 -406.690068)
					(end 382.469644 -406.690068)
				)
			)
		)
	)
	(zone
		(layers "B.Cu" "In9.Cu" "In11.Cu" "In13.Cu" "In15.Cu")
		(hatch none 0.5)
		(connect_pads
			(clearance 0)
		)
		(min_thickness 0.25)
		(keepout
			(tracks not_allowed)
			(vias allowed)
			(pads allowed)
			(copperpour not_allowed)
			(footprints allowed)
		)
		(placement
			(enabled no)
			(sheetname "")
		)
		(fill yes
			(thermal_gap 0.5)
			(thermal_bridge_width 0.5)
			(island_removal_mode 0)
		)
		(polygon
			(pts
				(arc
					(start 422.069514 -371.590062)
					(mid 421.310054 -371.590062)
					(end 422.069514 -371.590062)
				)
			)
		)
	)
	(zone
		(layers "B.Cu" "In9.Cu" "In11.Cu" "In13.Cu" "In15.Cu")
		(hatch none 0.5)
		(connect_pads
			(clearance 0)
		)
		(min_thickness 0.25)
		(keepout
			(tracks not_allowed)
			(vias allowed)
			(pads allowed)
			(copperpour not_allowed)
			(footprints allowed)
		)
		(placement
			(enabled no)
			(sheetname "")
		)
		(fill yes
			(thermal_gap 0.5)
			(thermal_bridge_width 0.5)
			(island_removal_mode 0)
		)
		(polygon
			(pts
				(arc
					(start 118.48973 -406.690068)
					(mid 117.73027 -406.690068)
					(end 118.48973 -406.690068)
				)
			)
		)
	)
	(zone
		(layers "B.Cu" "In9.Cu" "In11.Cu" "In13.Cu" "In15.Cu")
		(hatch none 0.5)
		(connect_pads
			(clearance 0)
		)
		(min_thickness 0.25)
		(keepout
			(tracks not_allowed)
			(vias allowed)
			(pads allowed)
			(copperpour not_allowed)
			(footprints allowed)
		)
		(placement
			(enabled no)
			(sheetname "")
		)
		(fill yes
			(thermal_gap 0.5)
			(thermal_bridge_width 0.5)
			(island_removal_mode 0)
		)
		(polygon
			(pts
				(arc
					(start 298.869608 -375.490232)
					(mid 298.110148 -375.490232)
					(end 298.869608 -375.490232)
				)
			)
		)
	)
	(zone
		(layers "B.Cu" "In9.Cu" "In11.Cu" "In13.Cu" "In15.Cu")
		(hatch none 0.5)
		(connect_pads
			(clearance 0)
		)
		(min_thickness 0.25)
		(keepout
			(tracks not_allowed)
			(vias allowed)
			(pads allowed)
			(copperpour not_allowed)
			(footprints allowed)
		)
		(placement
			(enabled no)
			(sheetname "")
		)
		(fill yes
			(thermal_gap 0.5)
			(thermal_bridge_width 0.5)
			(island_removal_mode 0)
		)
		(polygon
			(pts
				(arc
					(start 120.689878 -383.490216)
					(mid 119.930418 -383.490216)
					(end 120.689878 -383.490216)
				)
			)
		)
	)
	(zone
		(layers "B.Cu" "In9.Cu" "In11.Cu" "In13.Cu" "In15.Cu")
		(hatch none 0.5)
		(connect_pads
			(clearance 0)
		)
		(min_thickness 0.25)
		(keepout
			(tracks not_allowed)
			(vias allowed)
			(pads allowed)
			(copperpour not_allowed)
			(footprints allowed)
		)
		(placement
			(enabled no)
			(sheetname "")
		)
		(fill yes
			(thermal_gap 0.5)
			(thermal_bridge_width 0.5)
			(island_removal_mode 0)
		)
		(polygon
			(pts
				(arc
					(start 49.52619 -274.999958)
					(mid 48.87341 -274.999958)
					(end 49.52619 -274.999958)
				)
			)
		)
	)
	(zone
		(layers "B.Cu" "In9.Cu" "In11.Cu" "In13.Cu" "In15.Cu")
		(hatch none 0.5)
		(connect_pads
			(clearance 0)
		)
		(min_thickness 0.25)
		(keepout
			(tracks not_allowed)
			(vias allowed)
			(pads allowed)
			(copperpour not_allowed)
			(footprints allowed)
		)
		(placement
			(enabled no)
			(sheetname "")
		)
		(fill yes
			(thermal_gap 0.5)
			(thermal_bridge_width 0.5)
			(island_removal_mode 0)
		)
		(polygon
			(pts
				(arc
					(start 426.469556 -397.59001)
					(mid 425.710096 -397.59001)
					(end 426.469556 -397.59001)
				)
			)
		)
	)
	(zone
		(layers "B.Cu" "In9.Cu" "In11.Cu" "In13.Cu" "In15.Cu")
		(hatch none 0.5)
		(connect_pads
			(clearance 0)
		)
		(min_thickness 0.25)
		(keepout
			(tracks not_allowed)
			(vias allowed)
			(pads allowed)
			(copperpour not_allowed)
			(footprints allowed)
		)
		(placement
			(enabled no)
			(sheetname "")
		)
		(fill yes
			(thermal_gap 0.5)
			(thermal_bridge_width 0.5)
			(island_removal_mode 0)
		)
		(polygon
			(pts
				(arc
					(start 172.728382 -342.439498)
					(mid 172.024802 -342.439498)
					(end 172.728382 -342.439498)
				)
			)
		)
	)
	(zone
		(layers "B.Cu" "In9.Cu" "In11.Cu" "In13.Cu" "In15.Cu")
		(hatch none 0.5)
		(connect_pads
			(clearance 0)
		)
		(min_thickness 0.25)
		(keepout
			(tracks not_allowed)
			(vias allowed)
			(pads allowed)
			(copperpour not_allowed)
			(footprints allowed)
		)
		(placement
			(enabled no)
			(sheetname "")
		)
		(fill yes
			(thermal_gap 0.5)
			(thermal_bridge_width 0.5)
			(island_removal_mode 0)
		)
		(polygon
			(pts
				(arc
					(start 162.489642 -397.59001)
					(mid 161.730182 -397.59001)
					(end 162.489642 -397.59001)
				)
			)
		)
	)
	(zone
		(layers "B.Cu" "In9.Cu" "In11.Cu" "In13.Cu" "In15.Cu")
		(hatch none 0.5)
		(connect_pads
			(clearance 0)
		)
		(min_thickness 0.25)
		(keepout
			(tracks not_allowed)
			(vias allowed)
			(pads allowed)
			(copperpour not_allowed)
			(footprints allowed)
		)
		(placement
			(enabled no)
			(sheetname "")
		)
		(fill yes
			(thermal_gap 0.5)
			(thermal_bridge_width 0.5)
			(island_removal_mode 0)
		)
		(polygon
			(pts
				(arc
					(start 123.66244 -33.65881)
					(mid 122.95886 -33.65881)
					(end 123.66244 -33.65881)
				)
			)
		)
	)
	(zone
		(layers "B.Cu" "In9.Cu" "In11.Cu" "In13.Cu" "In15.Cu")
		(hatch none 0.5)
		(connect_pads
			(clearance 0)
		)
		(min_thickness 0.25)
		(keepout
			(tracks not_allowed)
			(vias allowed)
			(pads allowed)
			(copperpour not_allowed)
			(footprints allowed)
		)
		(placement
			(enabled no)
			(sheetname "")
		)
		(fill yes
			(thermal_gap 0.5)
			(thermal_bridge_width 0.5)
			(island_removal_mode 0)
		)
		(polygon
			(pts
				(arc
					(start 63.776352 -313.949842)
					(mid 63.123572 -313.949842)
					(end 63.776352 -313.949842)
				)
			)
		)
	)
	(zone
		(layers "B.Cu" "In9.Cu" "In11.Cu" "In13.Cu" "In15.Cu")
		(hatch none 0.5)
		(connect_pads
			(clearance 0)
		)
		(min_thickness 0.25)
		(keepout
			(tracks not_allowed)
			(vias allowed)
			(pads allowed)
			(copperpour not_allowed)
			(footprints allowed)
		)
		(placement
			(enabled no)
			(sheetname "")
		)
		(fill yes
			(thermal_gap 0.5)
			(thermal_bridge_width 0.5)
			(island_removal_mode 0)
		)
		(polygon
			(pts
				(arc
					(start 402.576284 -313.949842)
					(mid 401.923504 -313.949842)
					(end 402.576284 -313.949842)
				)
			)
		)
	)
	(zone
		(layers "B.Cu" "In9.Cu" "In11.Cu" "In13.Cu" "In15.Cu")
		(hatch none 0.5)
		(connect_pads
			(clearance 0)
		)
		(min_thickness 0.25)
		(keepout
			(tracks not_allowed)
			(vias allowed)
			(pads allowed)
			(copperpour not_allowed)
			(footprints allowed)
		)
		(placement
			(enabled no)
			(sheetname "")
		)
		(fill yes
			(thermal_gap 0.5)
			(thermal_bridge_width 0.5)
			(island_removal_mode 0)
		)
		(polygon
			(pts
				(arc
					(start 9.416542 -28.25877)
					(mid 8.712962 -28.25877)
					(end 9.416542 -28.25877)
				)
			)
		)
	)
	(zone
		(layers "B.Cu" "In9.Cu" "In11.Cu" "In13.Cu" "In15.Cu")
		(hatch none 0.5)
		(connect_pads
			(clearance 0)
		)
		(min_thickness 0.25)
		(keepout
			(tracks not_allowed)
			(vias allowed)
			(pads allowed)
			(copperpour not_allowed)
			(footprints allowed)
		)
		(placement
			(enabled no)
			(sheetname "")
		)
		(fill yes
			(thermal_gap 0.5)
			(thermal_bridge_width 0.5)
			(island_removal_mode 0)
		)
		(polygon
			(pts
				(arc
					(start 412.076392 -312.999882)
					(mid 411.423612 -312.999882)
					(end 412.076392 -312.999882)
				)
			)
		)
	)
	(zone
		(layers "B.Cu" "In11.Cu" "In13.Cu" "In15.Cu")
		(hatch none 0.5)
		(connect_pads
			(clearance 0)
		)
		(min_thickness 0.25)
		(keepout
			(tracks not_allowed)
			(vias allowed)
			(pads allowed)
			(copperpour not_allowed)
			(footprints allowed)
		)
		(placement
			(enabled no)
			(sheetname "")
		)
		(fill yes
			(thermal_gap 0.5)
			(thermal_bridge_width 0.5)
			(island_removal_mode 0)
		)
		(polygon
			(pts
				(arc
					(start 309.276242 -284.499812)
					(mid 308.623462 -284.499812)
					(end 309.276242 -284.499812)
				)
			)
		)
	)
	(zone
		(layers "B.Cu" "In11.Cu" "In13.Cu" "In15.Cu")
		(hatch none 0.5)
		(connect_pads
			(clearance 0)
		)
		(min_thickness 0.25)
		(keepout
			(tracks not_allowed)
			(vias allowed)
			(pads allowed)
			(copperpour not_allowed)
			(footprints allowed)
		)
		(placement
			(enabled no)
			(sheetname "")
		)
		(fill yes
			(thermal_gap 0.5)
			(thermal_bridge_width 0.5)
			(island_removal_mode 0)
		)
		(polygon
			(pts
				(arc
					(start 430.126394 -276.899878)
					(mid 429.473614 -276.899878)
					(end 430.126394 -276.899878)
				)
			)
		)
	)
	(zone
		(layers "B.Cu" "In11.Cu" "In13.Cu" "In15.Cu")
		(hatch none 0.5)
		(connect_pads
			(clearance 0)
		)
		(min_thickness 0.25)
		(keepout
			(tracks not_allowed)
			(vias allowed)
			(pads allowed)
			(copperpour not_allowed)
			(footprints allowed)
		)
		(placement
			(enabled no)
			(sheetname "")
		)
		(fill yes
			(thermal_gap 0.5)
			(thermal_bridge_width 0.5)
			(island_removal_mode 0)
		)
		(polygon
			(pts
				(arc
					(start 283.626306 -316.799722)
					(mid 282.973526 -316.799722)
					(end 283.626306 -316.799722)
				)
			)
		)
	)
	(zone
		(layers "B.Cu" "In11.Cu" "In13.Cu" "In15.Cu")
		(hatch none 0.5)
		(connect_pads
			(clearance 0)
		)
		(min_thickness 0.25)
		(keepout
			(tracks not_allowed)
			(vias allowed)
			(pads allowed)
			(copperpour not_allowed)
			(footprints allowed)
		)
		(placement
			(enabled no)
			(sheetname "")
		)
		(fill yes
			(thermal_gap 0.5)
			(thermal_bridge_width 0.5)
			(island_removal_mode 0)
		)
		(polygon
			(pts
				(arc
					(start 63.776098 -278.799798)
					(mid 63.123318 -278.799798)
					(end 63.776098 -278.799798)
				)
			)
		)
	)
	(zone
		(layers "B.Cu" "In11.Cu" "In13.Cu" "In15.Cu")
		(hatch none 0.5)
		(connect_pads
			(clearance 0)
		)
		(min_thickness 0.25)
		(keepout
			(tracks not_allowed)
			(vias allowed)
			(pads allowed)
			(copperpour not_allowed)
			(footprints allowed)
		)
		(placement
			(enabled no)
			(sheetname "")
		)
		(fill yes
			(thermal_gap 0.5)
			(thermal_bridge_width 0.5)
			(island_removal_mode 0)
		)
		(polygon
			(pts
				(arc
					(start 267.677392 -104.720898)
					(mid 266.973812 -104.720898)
					(end 267.677392 -104.720898)
				)
			)
		)
	)
	(zone
		(layers "B.Cu" "In11.Cu" "In13.Cu" "In15.Cu")
		(hatch none 0.5)
		(connect_pads
			(clearance 0)
		)
		(min_thickness 0.25)
		(keepout
			(tracks not_allowed)
			(vias allowed)
			(pads allowed)
			(copperpour not_allowed)
			(footprints allowed)
		)
		(placement
			(enabled no)
			(sheetname "")
		)
		(fill yes
			(thermal_gap 0.5)
			(thermal_bridge_width 0.5)
			(island_removal_mode 0)
		)
		(polygon
			(pts
				(arc
					(start 197.983856 -122.295666)
					(mid 197.280276 -122.295666)
					(end 197.983856 -122.295666)
				)
			)
		)
	)
	(zone
		(layers "B.Cu" "In11.Cu" "In13.Cu" "In15.Cu")
		(hatch none 0.5)
		(connect_pads
			(clearance 0)
		)
		(min_thickness 0.25)
		(keepout
			(tracks not_allowed)
			(vias allowed)
			(pads allowed)
			(copperpour not_allowed)
			(footprints allowed)
		)
		(placement
			(enabled no)
			(sheetname "")
		)
		(fill yes
			(thermal_gap 0.5)
			(thermal_bridge_width 0.5)
			(island_removal_mode 0)
		)
		(polygon
			(pts
				(arc
					(start 422.069514 -384.590036)
					(mid 421.310054 -384.590036)
					(end 422.069514 -384.590036)
				)
			)
		)
	)
	(zone
		(layers "B.Cu" "In11.Cu" "In13.Cu" "In15.Cu")
		(hatch none 0.5)
		(connect_pads
			(clearance 0)
		)
		(min_thickness 0.25)
		(keepout
			(tracks not_allowed)
			(vias allowed)
			(pads allowed)
			(copperpour not_allowed)
			(footprints allowed)
		)
		(placement
			(enabled no)
			(sheetname "")
		)
		(fill yes
			(thermal_gap 0.5)
			(thermal_bridge_width 0.5)
			(island_removal_mode 0)
		)
		(polygon
			(pts
				(arc
					(start 423.476166 -283.549852)
					(mid 422.823386 -283.549852)
					(end 423.476166 -283.549852)
				)
			)
		)
	)
	(zone
		(layers "B.Cu" "In11.Cu" "In13.Cu" "In15.Cu")
		(hatch none 0.5)
		(connect_pads
			(clearance 0)
		)
		(min_thickness 0.25)
		(keepout
			(tracks not_allowed)
			(vias allowed)
			(pads allowed)
			(copperpour not_allowed)
			(footprints allowed)
		)
		(placement
			(enabled no)
			(sheetname "")
		)
		(fill yes
			(thermal_gap 0.5)
			(thermal_bridge_width 0.5)
			(island_removal_mode 0)
		)
		(polygon
			(pts
				(arc
					(start 38.119558 -102.914196)
					(mid 37.415978 -102.914196)
					(end 38.119558 -102.914196)
				)
			)
		)
	)
	(zone
		(layers "B.Cu" "In11.Cu" "In13.Cu" "In15.Cu")
		(hatch none 0.5)
		(connect_pads
			(clearance 0)
		)
		(min_thickness 0.25)
		(keepout
			(tracks not_allowed)
			(vias allowed)
			(pads allowed)
			(copperpour not_allowed)
			(footprints allowed)
		)
		(placement
			(enabled no)
			(sheetname "")
		)
		(fill yes
			(thermal_gap 0.5)
			(thermal_bridge_width 0.5)
			(island_removal_mode 0)
		)
		(polygon
			(pts
				(arc
					(start 270.3195 -110.114334)
					(mid 269.61592 -110.114334)
					(end 270.3195 -110.114334)
				)
			)
		)
	)
	(zone
		(layers "B.Cu" "In11.Cu" "In13.Cu" "In15.Cu")
		(hatch none 0.5)
		(connect_pads
			(clearance 0)
		)
		(min_thickness 0.25)
		(keepout
			(tracks not_allowed)
			(vias allowed)
			(pads allowed)
			(copperpour not_allowed)
			(footprints allowed)
		)
		(placement
			(enabled no)
			(sheetname "")
		)
		(fill yes
			(thermal_gap 0.5)
			(thermal_bridge_width 0.5)
			(island_removal_mode 0)
		)
		(polygon
			(pts
				(arc
					(start 306.426108 -280.699718)
					(mid 305.773328 -280.699718)
					(end 306.426108 -280.699718)
				)
			)
		)
	)
	(zone
		(layers "B.Cu" "In11.Cu" "In13.Cu" "In15.Cu")
		(hatch none 0.5)
		(connect_pads
			(clearance 0)
		)
		(min_thickness 0.25)
		(keepout
			(tracks not_allowed)
			(vias allowed)
			(pads allowed)
			(copperpour not_allowed)
			(footprints allowed)
		)
		(placement
			(enabled no)
			(sheetname "")
		)
		(fill yes
			(thermal_gap 0.5)
			(thermal_bridge_width 0.5)
			(island_removal_mode 0)
		)
		(polygon
			(pts
				(arc
					(start 432.82616 -136.17575)
					(mid 432.12258 -136.17575)
					(end 432.82616 -136.17575)
				)
			)
		)
	)
	(zone
		(layers "B.Cu" "In11.Cu" "In13.Cu" "In15.Cu")
		(hatch none 0.5)
		(connect_pads
			(clearance 0)
		)
		(min_thickness 0.25)
		(keepout
			(tracks not_allowed)
			(vias allowed)
			(pads allowed)
			(copperpour not_allowed)
			(footprints allowed)
		)
		(placement
			(enabled no)
			(sheetname "")
		)
		(fill yes
			(thermal_gap 0.5)
			(thermal_bridge_width 0.5)
			(island_removal_mode 0)
		)
		(polygon
			(pts
				(arc
					(start 151.577294 -122.82424)
					(mid 150.873714 -122.82424)
					(end 151.577294 -122.82424)
				)
			)
		)
	)
	(zone
		(layers "B.Cu" "In11.Cu" "In13.Cu" "In15.Cu")
		(hatch none 0.5)
		(connect_pads
			(clearance 0)
		)
		(min_thickness 0.25)
		(keepout
			(tracks not_allowed)
			(vias allowed)
			(pads allowed)
			(copperpour not_allowed)
			(footprints allowed)
		)
		(placement
			(enabled no)
			(sheetname "")
		)
		(fill yes
			(thermal_gap 0.5)
			(thermal_bridge_width 0.5)
			(island_removal_mode 0)
		)
		(polygon
			(pts
				(arc
					(start 154.22626 -304.449734)
					(mid 153.57348 -304.449734)
					(end 154.22626 -304.449734)
				)
			)
		)
	)
	(zone
		(layers "B.Cu" "In11.Cu" "In13.Cu" "In15.Cu")
		(hatch none 0.5)
		(connect_pads
			(clearance 0)
		)
		(min_thickness 0.25)
		(keepout
			(tracks not_allowed)
			(vias allowed)
			(pads allowed)
			(copperpour not_allowed)
			(footprints allowed)
		)
		(placement
			(enabled no)
			(sheetname "")
		)
		(fill yes
			(thermal_gap 0.5)
			(thermal_bridge_width 0.5)
			(island_removal_mode 0)
		)
		(polygon
			(pts
				(arc
					(start 200.625964 -120.502172)
					(mid 199.922384 -120.502172)
					(end 200.625964 -120.502172)
				)
			)
		)
	)
	(zone
		(layers "B.Cu" "In11.Cu" "In13.Cu" "In15.Cu")
		(hatch none 0.5)
		(connect_pads
			(clearance 0)
		)
		(min_thickness 0.25)
		(keepout
			(tracks not_allowed)
			(vias allowed)
			(pads allowed)
			(copperpour not_allowed)
			(footprints allowed)
		)
		(placement
			(enabled no)
			(sheetname "")
		)
		(fill yes
			(thermal_gap 0.5)
			(thermal_bridge_width 0.5)
			(island_removal_mode 0)
		)
		(polygon
			(pts
				(arc
					(start 175.689768 -409.290012)
					(mid 174.930308 -409.290012)
					(end 175.689768 -409.290012)
				)
			)
		)
	)
	(zone
		(layers "B.Cu" "In11.Cu" "In13.Cu" "In15.Cu")
		(hatch none 0.5)
		(connect_pads
			(clearance 0)
		)
		(min_thickness 0.25)
		(keepout
			(tracks not_allowed)
			(vias allowed)
			(pads allowed)
			(copperpour not_allowed)
			(footprints allowed)
		)
		(placement
			(enabled no)
			(sheetname "")
		)
		(fill yes
			(thermal_gap 0.5)
			(thermal_bridge_width 0.5)
			(island_removal_mode 0)
		)
		(polygon
			(pts
				(arc
					(start 151.577294 -130.434334)
					(mid 150.873714 -130.434334)
					(end 151.577294 -130.434334)
				)
			)
		)
	)
	(zone
		(layers "B.Cu" "In11.Cu" "In13.Cu" "In15.Cu")
		(hatch none 0.5)
		(connect_pads
			(clearance 0)
		)
		(min_thickness 0.25)
		(keepout
			(tracks not_allowed)
			(vias allowed)
			(pads allowed)
			(copperpour not_allowed)
			(footprints allowed)
		)
		(placement
			(enabled no)
			(sheetname "")
		)
		(fill yes
			(thermal_gap 0.5)
			(thermal_bridge_width 0.5)
			(island_removal_mode 0)
		)
		(polygon
			(pts
				(arc
					(start 389.276336 -317.749936)
					(mid 388.623556 -317.749936)
					(end 389.276336 -317.749936)
				)
			)
		)
	)
	(zone
		(layers "B.Cu" "In11.Cu" "In13.Cu" "In15.Cu")
		(hatch none 0.5)
		(connect_pads
			(clearance 0)
		)
		(min_thickness 0.25)
		(keepout
			(tracks not_allowed)
			(vias allowed)
			(pads allowed)
			(copperpour not_allowed)
			(footprints allowed)
		)
		(placement
			(enabled no)
			(sheetname "")
		)
		(fill yes
			(thermal_gap 0.5)
			(thermal_bridge_width 0.5)
			(island_removal_mode 0)
		)
		(polygon
			(pts
				(arc
					(start 57.126378 -315.849762)
					(mid 56.473598 -315.849762)
					(end 57.126378 -315.849762)
				)
			)
		)
	)
	(zone
		(layers "B.Cu" "In11.Cu" "In13.Cu" "In15.Cu")
		(hatch none 0.5)
		(connect_pads
			(clearance 0)
		)
		(min_thickness 0.25)
		(keepout
			(tracks not_allowed)
			(vias allowed)
			(pads allowed)
			(copperpour not_allowed)
			(footprints allowed)
		)
		(placement
			(enabled no)
			(sheetname "")
		)
		(fill yes
			(thermal_gap 0.5)
			(thermal_bridge_width 0.5)
			(island_removal_mode 0)
		)
		(polygon
			(pts
				(arc
					(start 151.577294 -120.087898)
					(mid 150.873714 -120.087898)
					(end 151.577294 -120.087898)
				)
			)
		)
	)
	(zone
		(layers "B.Cu" "In11.Cu" "In13.Cu" "In15.Cu")
		(hatch none 0.5)
		(connect_pads
			(clearance 0)
		)
		(min_thickness 0.25)
		(keepout
			(tracks not_allowed)
			(vias allowed)
			(pads allowed)
			(copperpour not_allowed)
			(footprints allowed)
		)
		(placement
			(enabled no)
			(sheetname "")
		)
		(fill yes
			(thermal_gap 0.5)
			(thermal_bridge_width 0.5)
			(island_removal_mode 0)
		)
		(polygon
			(pts
				(arc
					(start 430.184052 -147.079208)
					(mid 429.480472 -147.079208)
					(end 430.184052 -147.079208)
				)
			)
		)
	)
	(zone
		(layers "B.Cu" "In11.Cu" "In13.Cu" "In15.Cu")
		(hatch none 0.5)
		(connect_pads
			(clearance 0)
		)
		(min_thickness 0.25)
		(keepout
			(tracks not_allowed)
			(vias allowed)
			(pads allowed)
			(copperpour not_allowed)
			(footprints allowed)
		)
		(placement
			(enabled no)
			(sheetname "")
		)
		(fill yes
			(thermal_gap 0.5)
			(thermal_bridge_width 0.5)
			(island_removal_mode 0)
		)
		(polygon
			(pts
				(arc
					(start 171.289726 -410.589984)
					(mid 170.530266 -410.589984)
					(end 171.289726 -410.589984)
				)
			)
		)
	)
	(zone
		(layers "B.Cu" "In11.Cu" "In13.Cu" "In15.Cu")
		(hatch none 0.5)
		(connect_pads
			(clearance 0)
		)
		(min_thickness 0.25)
		(keepout
			(tracks not_allowed)
			(vias allowed)
			(pads allowed)
			(copperpour not_allowed)
			(footprints allowed)
		)
		(placement
			(enabled no)
			(sheetname "")
		)
		(fill yes
			(thermal_gap 0.5)
			(thermal_bridge_width 0.5)
			(island_removal_mode 0)
		)
		(polygon
			(pts
				(arc
					(start 386.419598 -124.630942)
					(mid 385.716018 -124.630942)
					(end 386.419598 -124.630942)
				)
			)
		)
	)
	(zone
		(layers "B.Cu" "In11.Cu" "In13.Cu" "In15.Cu")
		(hatch none 0.5)
		(connect_pads
			(clearance 0)
		)
		(min_thickness 0.25)
		(keepout
			(tracks not_allowed)
			(vias allowed)
			(pads allowed)
			(copperpour not_allowed)
			(footprints allowed)
		)
		(placement
			(enabled no)
			(sheetname "")
		)
		(fill yes
			(thermal_gap 0.5)
			(thermal_bridge_width 0.5)
			(island_removal_mode 0)
		)
		(polygon
			(pts
				(arc
					(start 267.677392 -120.087898)
					(mid 266.973812 -120.087898)
					(end 267.677392 -120.087898)
				)
			)
		)
	)
	(zone
		(layers "B.Cu" "In11.Cu" "In13.Cu" "In15.Cu")
		(hatch none 0.5)
		(connect_pads
			(clearance 0)
		)
		(min_thickness 0.25)
		(keepout
			(tracks not_allowed)
			(vias allowed)
			(pads allowed)
			(copperpour not_allowed)
			(footprints allowed)
		)
		(placement
			(enabled no)
			(sheetname "")
		)
		(fill yes
			(thermal_gap 0.5)
			(thermal_bridge_width 0.5)
			(island_removal_mode 0)
		)
		(polygon
			(pts
				(arc
					(start 428.22622 -280.699718)
					(mid 427.57344 -280.699718)
					(end 428.22622 -280.699718)
				)
			)
		)
	)
	(zone
		(layers "B.Cu" "In11.Cu" "In13.Cu" "In15.Cu")
		(hatch none 0.5)
		(connect_pads
			(clearance 0)
		)
		(min_thickness 0.25)
		(keepout
			(tracks not_allowed)
			(vias allowed)
			(pads allowed)
			(copperpour not_allowed)
			(footprints allowed)
		)
		(placement
			(enabled no)
			(sheetname "")
		)
		(fill yes
			(thermal_gap 0.5)
			(thermal_bridge_width 0.5)
			(island_removal_mode 0)
		)
		(polygon
			(pts
				(arc
					(start 441.39866 18.460212)
					(mid 440.69508 18.460212)
					(end 441.39866 18.460212)
				)
			)
		)
	)
	(zone
		(layers "B.Cu" "In11.Cu" "In13.Cu" "In15.Cu")
		(hatch none 0.5)
		(connect_pads
			(clearance 0)
		)
		(min_thickness 0.25)
		(keepout
			(tracks not_allowed)
			(vias allowed)
			(pads allowed)
			(copperpour not_allowed)
			(footprints allowed)
		)
		(placement
			(enabled no)
			(sheetname "")
		)
		(fill yes
			(thermal_gap 0.5)
			(thermal_bridge_width 0.5)
			(island_removal_mode 0)
		)
		(polygon
			(pts
				(arc
					(start 316.726062 -145.285714)
					(mid 316.022482 -145.285714)
					(end 316.726062 -145.285714)
				)
			)
		)
	)
	(zone
		(layers "B.Cu" "In11.Cu" "In13.Cu" "In15.Cu")
		(hatch none 0.5)
		(connect_pads
			(clearance 0)
		)
		(min_thickness 0.25)
		(keepout
			(tracks not_allowed)
			(vias allowed)
			(pads allowed)
			(copperpour not_allowed)
			(footprints allowed)
		)
		(placement
			(enabled no)
			(sheetname "")
		)
		(fill yes
			(thermal_gap 0.5)
			(thermal_bridge_width 0.5)
			(island_removal_mode 0)
		)
		(polygon
			(pts
				(arc
					(start 386.419598 -121.030746)
					(mid 385.716018 -121.030746)
					(end 386.419598 -121.030746)
				)
			)
		)
	)
	(zone
		(layers "B.Cu" "In11.Cu" "In13.Cu" "In15.Cu")
		(hatch none 0.5)
		(connect_pads
			(clearance 0)
		)
		(min_thickness 0.25)
		(keepout
			(tracks not_allowed)
			(vias allowed)
			(pads allowed)
			(copperpour not_allowed)
			(footprints allowed)
		)
		(placement
			(enabled no)
			(sheetname "")
		)
		(fill yes
			(thermal_gap 0.5)
			(thermal_bridge_width 0.5)
			(island_removal_mode 0)
		)
		(polygon
			(pts
				(arc
					(start 200.625964 -132.575808)
					(mid 199.922384 -132.575808)
					(end 200.625964 -132.575808)
				)
			)
		)
	)
	(zone
		(layers "B.Cu" "In11.Cu" "In13.Cu" "In15.Cu")
		(hatch none 0.5)
		(connect_pads
			(clearance 0)
		)
		(min_thickness 0.25)
		(keepout
			(tracks not_allowed)
			(vias allowed)
			(pads allowed)
			(copperpour not_allowed)
			(footprints allowed)
		)
		(placement
			(enabled no)
			(sheetname "")
		)
		(fill yes
			(thermal_gap 0.5)
			(thermal_bridge_width 0.5)
			(island_removal_mode 0)
		)
		(polygon
			(pts
				(arc
					(start 71.376032 -278.799798)
					(mid 70.723252 -278.799798)
					(end 71.376032 -278.799798)
				)
			)
		)
	)
	(zone
		(layers "B.Cu" "In11.Cu" "In13.Cu" "In15.Cu")
		(hatch none 0.5)
		(connect_pads
			(clearance 0)
		)
		(min_thickness 0.25)
		(keepout
			(tracks not_allowed)
			(vias allowed)
			(pads allowed)
			(copperpour not_allowed)
			(footprints allowed)
		)
		(placement
			(enabled no)
			(sheetname "")
		)
		(fill yes
			(thermal_gap 0.5)
			(thermal_bridge_width 0.5)
			(island_removal_mode 0)
		)
		(polygon
			(pts
				(arc
					(start 314.083954 -153.415746)
					(mid 313.380374 -153.415746)
					(end 314.083954 -153.415746)
				)
			)
		)
	)
	(zone
		(layers "B.Cu" "In11.Cu" "In13.Cu" "In15.Cu")
		(hatch none 0.5)
		(connect_pads
			(clearance 0)
		)
		(min_thickness 0.25)
		(keepout
			(tracks not_allowed)
			(vias allowed)
			(pads allowed)
			(copperpour not_allowed)
			(footprints allowed)
		)
		(placement
			(enabled no)
			(sheetname "")
		)
		(fill yes
			(thermal_gap 0.5)
			(thermal_bridge_width 0.5)
			(island_removal_mode 0)
		)
		(polygon
			(pts
				(arc
					(start 2.379472 -388.37489)
					(mid 1.675892 -388.37489)
					(end 2.379472 -388.37489)
				)
			)
		)
	)
	(zone
		(layers "B.Cu" "In11.Cu" "In13.Cu" "In15.Cu")
		(hatch none 0.5)
		(connect_pads
			(clearance 0)
		)
		(min_thickness 0.25)
		(keepout
			(tracks not_allowed)
			(vias allowed)
			(pads allowed)
			(copperpour not_allowed)
			(footprints allowed)
		)
		(placement
			(enabled no)
			(sheetname "")
		)
		(fill yes
			(thermal_gap 0.5)
			(thermal_bridge_width 0.5)
			(island_removal_mode 0)
		)
		(polygon
			(pts
				(arc
					(start 430.184052 -134.369302)
					(mid 429.480472 -134.369302)
					(end 430.184052 -134.369302)
				)
			)
		)
	)
	(zone
		(layers "B.Cu" "In11.Cu" "In13.Cu" "In15.Cu")
		(hatch none 0.5)
		(connect_pads
			(clearance 0)
		)
		(min_thickness 0.25)
		(keepout
			(tracks not_allowed)
			(vias allowed)
			(pads allowed)
			(copperpour not_allowed)
			(footprints allowed)
		)
		(placement
			(enabled no)
			(sheetname "")
		)
		(fill yes
			(thermal_gap 0.5)
			(thermal_bridge_width 0.5)
			(island_removal_mode 0)
		)
		(polygon
			(pts
				(arc
					(start 38.119558 -106.514138)
					(mid 37.415978 -106.514138)
					(end 38.119558 -106.514138)
				)
			)
		)
	)
	(zone
		(layers "B.Cu" "In11.Cu" "In13.Cu" "In15.Cu")
		(hatch none 0.5)
		(connect_pads
			(clearance 0)
		)
		(min_thickness 0.25)
		(keepout
			(tracks not_allowed)
			(vias allowed)
			(pads allowed)
			(copperpour not_allowed)
			(footprints allowed)
		)
		(placement
			(enabled no)
			(sheetname "")
		)
		(fill yes
			(thermal_gap 0.5)
			(thermal_bridge_width 0.5)
			(island_removal_mode 0)
		)
		(polygon
			(pts
				(arc
					(start 297.87596 -278.799798)
					(mid 297.22318 -278.799798)
					(end 297.87596 -278.799798)
				)
			)
		)
	)
	(zone
		(layers "B.Cu" "In11.Cu" "In13.Cu" "In15.Cu")
		(hatch none 0.5)
		(connect_pads
			(clearance 0)
		)
		(min_thickness 0.25)
		(keepout
			(tracks not_allowed)
			(vias allowed)
			(pads allowed)
			(copperpour not_allowed)
			(footprints allowed)
		)
		(placement
			(enabled no)
			(sheetname "")
		)
		(fill yes
			(thermal_gap 0.5)
			(thermal_bridge_width 0.5)
			(island_removal_mode 0)
		)
		(polygon
			(pts
				(arc
					(start 293.12616 -316.799722)
					(mid 292.47338 -316.799722)
					(end 293.12616 -316.799722)
				)
			)
		)
	)
	(zone
		(layers "B.Cu" "In11.Cu" "In13.Cu" "In15.Cu")
		(hatch none 0.5)
		(connect_pads
			(clearance 0)
		)
		(min_thickness 0.25)
		(keepout
			(tracks not_allowed)
			(vias allowed)
			(pads allowed)
			(copperpour not_allowed)
			(footprints allowed)
		)
		(placement
			(enabled no)
			(sheetname "")
		)
		(fill yes
			(thermal_gap 0.5)
			(thermal_bridge_width 0.5)
			(island_removal_mode 0)
		)
		(polygon
			(pts
				(arc
					(start 417.776152 -278.799798)
					(mid 417.123372 -278.799798)
					(end 417.776152 -278.799798)
				)
			)
		)
	)
	(zone
		(layers "B.Cu" "In11.Cu" "In13.Cu" "In15.Cu")
		(hatch none 0.5)
		(connect_pads
			(clearance 0)
		)
		(min_thickness 0.25)
		(keepout
			(tracks not_allowed)
			(vias allowed)
			(pads allowed)
			(copperpour not_allowed)
			(footprints allowed)
		)
		(placement
			(enabled no)
			(sheetname "")
		)
		(fill yes
			(thermal_gap 0.5)
			(thermal_bridge_width 0.5)
			(island_removal_mode 0)
		)
		(polygon
			(pts
				(arc
					(start 9.45134 -372.07063)
					(mid 8.74776 -372.07063)
					(end 9.45134 -372.07063)
				)
			)
		)
	)
	(zone
		(layers "B.Cu" "In11.Cu" "In13.Cu" "In15.Cu")
		(hatch none 0.5)
		(connect_pads
			(clearance 0)
		)
		(min_thickness 0.25)
		(keepout
			(tracks not_allowed)
			(vias allowed)
			(pads allowed)
			(copperpour not_allowed)
			(footprints allowed)
		)
		(placement
			(enabled no)
			(sheetname "")
		)
		(fill yes
			(thermal_gap 0.5)
			(thermal_bridge_width 0.5)
			(island_removal_mode 0)
		)
		(polygon
			(pts
				(arc
					(start 200.625964 -121.365772)
					(mid 199.922384 -121.365772)
					(end 200.625964 -121.365772)
				)
			)
		)
	)
	(zone
		(layers "B.Cu" "In11.Cu" "In13.Cu" "In15.Cu")
		(hatch none 0.5)
		(connect_pads
			(clearance 0)
		)
		(min_thickness 0.25)
		(keepout
			(tracks not_allowed)
			(vias allowed)
			(pads allowed)
			(copperpour not_allowed)
			(footprints allowed)
		)
		(placement
			(enabled no)
			(sheetname "")
		)
		(fill yes
			(thermal_gap 0.5)
			(thermal_bridge_width 0.5)
			(island_removal_mode 0)
		)
		(polygon
			(pts
				(arc
					(start 295.02608 -279.749504)
					(mid 294.3733 -279.749504)
					(end 295.02608 -279.749504)
				)
			)
		)
	)
	(zone
		(layers "B.Cu" "In11.Cu" "In13.Cu" "In15.Cu")
		(hatch none 0.5)
		(connect_pads
			(clearance 0)
		)
		(min_thickness 0.25)
		(keepout
			(tracks not_allowed)
			(vias allowed)
			(pads allowed)
			(copperpour not_allowed)
			(footprints allowed)
		)
		(placement
			(enabled no)
			(sheetname "")
		)
		(fill yes
			(thermal_gap 0.5)
			(thermal_bridge_width 0.5)
			(island_removal_mode 0)
		)
		(polygon
			(pts
				(arc
					(start 419.86962 -408.190192)
					(mid 419.11016 -408.190192)
					(end 419.86962 -408.190192)
				)
			)
		)
	)
	(zone
		(layers "B.Cu" "In11.Cu" "In13.Cu" "In15.Cu")
		(hatch none 0.5)
		(connect_pads
			(clearance 0)
		)
		(min_thickness 0.25)
		(keepout
			(tracks not_allowed)
			(vias allowed)
			(pads allowed)
			(copperpour not_allowed)
			(footprints allowed)
		)
		(placement
			(enabled no)
			(sheetname "")
		)
		(fill yes
			(thermal_gap 0.5)
			(thermal_bridge_width 0.5)
			(island_removal_mode 0)
		)
		(polygon
			(pts
				(arc
					(start 81.884012 -146.215608)
					(mid 81.180432 -146.215608)
					(end 81.884012 -146.215608)
				)
			)
		)
	)
	(zone
		(layers "B.Cu" "In11.Cu" "In13.Cu" "In15.Cu")
		(hatch none 0.5)
		(connect_pads
			(clearance 0)
		)
		(min_thickness 0.25)
		(keepout
			(tracks not_allowed)
			(vias allowed)
			(pads allowed)
			(copperpour not_allowed)
			(footprints allowed)
		)
		(placement
			(enabled no)
			(sheetname "")
		)
		(fill yes
			(thermal_gap 0.5)
			(thermal_bridge_width 0.5)
			(island_removal_mode 0)
		)
		(polygon
			(pts
				(arc
					(start 72.28967 -375.69013)
					(mid 71.53021 -375.69013)
					(end 72.28967 -375.69013)
				)
			)
		)
	)
	(zone
		(layers "B.Cu" "In11.Cu" "In13.Cu" "In15.Cu")
		(hatch none 0.5)
		(connect_pads
			(clearance 0)
		)
		(min_thickness 0.25)
		(keepout
			(tracks not_allowed)
			(vias allowed)
			(pads allowed)
			(copperpour not_allowed)
			(footprints allowed)
		)
		(placement
			(enabled no)
			(sheetname "")
		)
		(fill yes
			(thermal_gap 0.5)
			(thermal_bridge_width 0.5)
			(island_removal_mode 0)
		)
		(polygon
			(pts
				(arc
					(start 386.419598 -121.894346)
					(mid 385.716018 -121.894346)
					(end 386.419598 -121.894346)
				)
			)
		)
	)
	(zone
		(layers "B.Cu" "In11.Cu" "In13.Cu" "In15.Cu")
		(hatch none 0.5)
		(connect_pads
			(clearance 0)
		)
		(min_thickness 0.25)
		(keepout
			(tracks not_allowed)
			(vias allowed)
			(pads allowed)
			(copperpour not_allowed)
			(footprints allowed)
		)
		(placement
			(enabled no)
			(sheetname "")
		)
		(fill yes
			(thermal_gap 0.5)
			(thermal_bridge_width 0.5)
			(island_removal_mode 0)
		)
		(polygon
			(pts
				(arc
					(start 295.97604 -277.849838)
					(mid 295.32326 -277.849838)
					(end 295.97604 -277.849838)
				)
			)
		)
	)
	(zone
		(layers "B.Cu" "In11.Cu" "In13.Cu" "In15.Cu")
		(hatch none 0.5)
		(connect_pads
			(clearance 0)
		)
		(min_thickness 0.25)
		(keepout
			(tracks not_allowed)
			(vias allowed)
			(pads allowed)
			(copperpour not_allowed)
			(footprints allowed)
		)
		(placement
			(enabled no)
			(sheetname "")
		)
		(fill yes
			(thermal_gap 0.5)
			(thermal_bridge_width 0.5)
			(island_removal_mode 0)
		)
		(polygon
			(pts
				(arc
					(start 309.276242 -282.599892)
					(mid 308.623462 -282.599892)
					(end 309.276242 -282.599892)
				)
			)
		)
	)
	(zone
		(layers "B.Cu" "In11.Cu" "In13.Cu" "In15.Cu")
		(hatch none 0.5)
		(connect_pads
			(clearance 0)
		)
		(min_thickness 0.25)
		(keepout
			(tracks not_allowed)
			(vias allowed)
			(pads allowed)
			(copperpour not_allowed)
			(footprints allowed)
		)
		(placement
			(enabled no)
			(sheetname "")
		)
		(fill yes
			(thermal_gap 0.5)
			(thermal_bridge_width 0.5)
			(island_removal_mode 0)
		)
		(polygon
			(pts
				(arc
					(start 391.176256 -317.749936)
					(mid 390.523476 -317.749936)
					(end 391.176256 -317.749936)
				)
			)
		)
	)
	(zone
		(layers "B.Cu" "In11.Cu" "In13.Cu" "In15.Cu")
		(hatch none 0.5)
		(connect_pads
			(clearance 0)
		)
		(min_thickness 0.25)
		(keepout
			(tracks not_allowed)
			(vias allowed)
			(pads allowed)
			(copperpour not_allowed)
			(footprints allowed)
		)
		(placement
			(enabled no)
			(sheetname "")
		)
		(fill yes
			(thermal_gap 0.5)
			(thermal_bridge_width 0.5)
			(island_removal_mode 0)
		)
		(polygon
			(pts
				(arc
					(start 316.726062 -121.365772)
					(mid 316.022482 -121.365772)
					(end 316.726062 -121.365772)
				)
			)
		)
	)
	(zone
		(layers "B.Cu" "In11.Cu" "In13.Cu" "In15.Cu")
		(hatch none 0.5)
		(connect_pads
			(clearance 0)
		)
		(min_thickness 0.25)
		(keepout
			(tracks not_allowed)
			(vias allowed)
			(pads allowed)
			(copperpour not_allowed)
			(footprints allowed)
		)
		(placement
			(enabled no)
			(sheetname "")
		)
		(fill yes
			(thermal_gap 0.5)
			(thermal_bridge_width 0.5)
			(island_removal_mode 0)
		)
		(polygon
			(pts
				(arc
					(start 390.226296 -316.799722)
					(mid 389.573516 -316.799722)
					(end 390.226296 -316.799722)
				)
			)
		)
	)
	(zone
		(layers "B.Cu" "In11.Cu" "In13.Cu" "In15.Cu")
		(hatch none 0.5)
		(connect_pads
			(clearance 0)
		)
		(min_thickness 0.25)
		(keepout
			(tracks not_allowed)
			(vias allowed)
			(pads allowed)
			(copperpour not_allowed)
			(footprints allowed)
		)
		(placement
			(enabled no)
			(sheetname "")
		)
		(fill yes
			(thermal_gap 0.5)
			(thermal_bridge_width 0.5)
			(island_removal_mode 0)
		)
		(polygon
			(pts
				(arc
					(start 81.884012 -129.905506)
					(mid 81.180432 -129.905506)
					(end 81.884012 -129.905506)
				)
			)
		)
	)
	(zone
		(layers "B.Cu" "In11.Cu" "In13.Cu" "In15.Cu")
		(hatch none 0.5)
		(connect_pads
			(clearance 0)
		)
		(min_thickness 0.25)
		(keepout
			(tracks not_allowed)
			(vias allowed)
			(pads allowed)
			(copperpour not_allowed)
			(footprints allowed)
		)
		(placement
			(enabled no)
			(sheetname "")
		)
		(fill yes
			(thermal_gap 0.5)
			(thermal_bridge_width 0.5)
			(island_removal_mode 0)
		)
		(polygon
			(pts
				(arc
					(start 77.0763 -288.299906)
					(mid 76.42352 -288.299906)
					(end 77.0763 -288.299906)
				)
			)
		)
	)
	(zone
		(layers "B.Cu" "In11.Cu" "In13.Cu" "In15.Cu")
		(hatch none 0.5)
		(connect_pads
			(clearance 0)
		)
		(min_thickness 0.25)
		(keepout
			(tracks not_allowed)
			(vias allowed)
			(pads allowed)
			(copperpour not_allowed)
			(footprints allowed)
		)
		(placement
			(enabled no)
			(sheetname "")
		)
		(fill yes
			(thermal_gap 0.5)
			(thermal_bridge_width 0.5)
			(island_removal_mode 0)
		)
		(polygon
			(pts
				(arc
					(start 190.326264 -279.749504)
					(mid 189.673484 -279.749504)
					(end 190.326264 -279.749504)
				)
			)
		)
	)
	(zone
		(layers "B.Cu" "In11.Cu" "In13.Cu" "In15.Cu")
		(hatch none 0.5)
		(connect_pads
			(clearance 0)
		)
		(min_thickness 0.25)
		(keepout
			(tracks not_allowed)
			(vias allowed)
			(pads allowed)
			(copperpour not_allowed)
			(footprints allowed)
		)
		(placement
			(enabled no)
			(sheetname "")
		)
		(fill yes
			(thermal_gap 0.5)
			(thermal_bridge_width 0.5)
			(island_removal_mode 0)
		)
		(polygon
			(pts
				(arc
					(start 297.87596 -277.849838)
					(mid 297.22318 -277.849838)
					(end 297.87596 -277.849838)
				)
			)
		)
	)
	(zone
		(layers "B.Cu" "In11.Cu" "In13.Cu" "In15.Cu")
		(hatch none 0.5)
		(connect_pads
			(clearance 0)
		)
		(min_thickness 0.25)
		(keepout
			(tracks not_allowed)
			(vias allowed)
			(pads allowed)
			(copperpour not_allowed)
			(footprints allowed)
		)
		(placement
			(enabled no)
			(sheetname "")
		)
		(fill yes
			(thermal_gap 0.5)
			(thermal_bridge_width 0.5)
			(island_removal_mode 0)
		)
		(polygon
			(pts
				(arc
					(start 383.77749 -104.720898)
					(mid 383.07391 -104.720898)
					(end 383.77749 -104.720898)
				)
			)
		)
	)
	(zone
		(layers "B.Cu" "In11.Cu" "In13.Cu" "In15.Cu")
		(hatch none 0.5)
		(connect_pads
			(clearance 0)
		)
		(min_thickness 0.25)
		(keepout
			(tracks not_allowed)
			(vias allowed)
			(pads allowed)
			(copperpour not_allowed)
			(footprints allowed)
		)
		(placement
			(enabled no)
			(sheetname "")
		)
		(fill yes
			(thermal_gap 0.5)
			(thermal_bridge_width 0.5)
			(island_removal_mode 0)
		)
		(polygon
			(pts
				(arc
					(start 432.82616 -121.365772)
					(mid 432.12258 -121.365772)
					(end 432.82616 -121.365772)
				)
			)
		)
	)
	(zone
		(layers "B.Cu" "In11.Cu" "In13.Cu" "In15.Cu")
		(hatch none 0.5)
		(connect_pads
			(clearance 0)
		)
		(min_thickness 0.25)
		(keepout
			(tracks not_allowed)
			(vias allowed)
			(pads allowed)
			(copperpour not_allowed)
			(footprints allowed)
		)
		(placement
			(enabled no)
			(sheetname "")
		)
		(fill yes
			(thermal_gap 0.5)
			(thermal_bridge_width 0.5)
			(island_removal_mode 0)
		)
		(polygon
			(pts
				(arc
					(start 81.884012 -122.295666)
					(mid 81.180432 -122.295666)
					(end 81.884012 -122.295666)
				)
			)
		)
	)
	(zone
		(layers "B.Cu" "In11.Cu" "In13.Cu" "In15.Cu")
		(hatch none 0.5)
		(connect_pads
			(clearance 0)
		)
		(min_thickness 0.25)
		(keepout
			(tracks not_allowed)
			(vias allowed)
			(pads allowed)
			(copperpour not_allowed)
			(footprints allowed)
		)
		(placement
			(enabled no)
			(sheetname "")
		)
		(fill yes
			(thermal_gap 0.5)
			(thermal_bridge_width 0.5)
			(island_removal_mode 0)
		)
		(polygon
			(pts
				(arc
					(start 60.926218 -315.849762)
					(mid 60.273438 -315.849762)
					(end 60.926218 -315.849762)
				)
			)
		)
	)
	(zone
		(layers "B.Cu" "In11.Cu" "In13.Cu" "In15.Cu")
		(hatch none 0.5)
		(connect_pads
			(clearance 0)
		)
		(min_thickness 0.25)
		(keepout
			(tracks not_allowed)
			(vias allowed)
			(pads allowed)
			(copperpour not_allowed)
			(footprints allowed)
		)
		(placement
			(enabled no)
			(sheetname "")
		)
		(fill yes
			(thermal_gap 0.5)
			(thermal_bridge_width 0.5)
			(island_removal_mode 0)
		)
		(polygon
			(pts
				(arc
					(start 200.625964 -156.085794)
					(mid 199.922384 -156.085794)
					(end 200.625964 -156.085794)
				)
			)
		)
	)
	(zone
		(layers "B.Cu" "In11.Cu" "In13.Cu" "In15.Cu")
		(hatch none 0.5)
		(connect_pads
			(clearance 0)
		)
		(min_thickness 0.25)
		(keepout
			(tracks not_allowed)
			(vias allowed)
			(pads allowed)
			(copperpour not_allowed)
			(footprints allowed)
		)
		(placement
			(enabled no)
			(sheetname "")
		)
		(fill yes
			(thermal_gap 0.5)
			(thermal_bridge_width 0.5)
			(island_removal_mode 0)
		)
		(polygon
			(pts
				(arc
					(start 70.426326 -280.699718)
					(mid 69.773546 -280.699718)
					(end 70.426326 -280.699718)
				)
			)
		)
	)
	(zone
		(layers "B.Cu" "In11.Cu" "In13.Cu" "In15.Cu")
		(hatch none 0.5)
		(connect_pads
			(clearance 0)
		)
		(min_thickness 0.25)
		(keepout
			(tracks not_allowed)
			(vias allowed)
			(pads allowed)
			(copperpour not_allowed)
			(footprints allowed)
		)
		(placement
			(enabled no)
			(sheetname "")
		)
		(fill yes
			(thermal_gap 0.5)
			(thermal_bridge_width 0.5)
			(island_removal_mode 0)
		)
		(polygon
			(pts
				(arc
					(start 158.976314 -317.749936)
					(mid 158.323534 -317.749936)
					(end 158.976314 -317.749936)
				)
			)
		)
	)
	(zone
		(layers "B.Cu" "In11.Cu" "In13.Cu" "In15.Cu")
		(hatch none 0.5)
		(connect_pads
			(clearance 0)
		)
		(min_thickness 0.25)
		(keepout
			(tracks not_allowed)
			(vias allowed)
			(pads allowed)
			(copperpour not_allowed)
			(footprints allowed)
		)
		(placement
			(enabled no)
			(sheetname "")
		)
		(fill yes
			(thermal_gap 0.5)
			(thermal_bridge_width 0.5)
			(island_removal_mode 0)
		)
		(polygon
			(pts
				(arc
					(start 267.677392 -109.18444)
					(mid 266.973812 -109.18444)
					(end 267.677392 -109.18444)
				)
			)
		)
	)
	(zone
		(layers "B.Cu" "In11.Cu" "In13.Cu" "In15.Cu")
		(hatch none 0.5)
		(connect_pads
			(clearance 0)
		)
		(min_thickness 0.25)
		(keepout
			(tracks not_allowed)
			(vias allowed)
			(pads allowed)
			(copperpour not_allowed)
			(footprints allowed)
		)
		(placement
			(enabled no)
			(sheetname "")
		)
		(fill yes
			(thermal_gap 0.5)
			(thermal_bridge_width 0.5)
			(island_removal_mode 0)
		)
		(polygon
			(pts
				(arc
					(start 432.82616 -151.622252)
					(mid 432.12258 -151.622252)
					(end 432.82616 -151.622252)
				)
			)
		)
	)
	(zone
		(layers "B.Cu" "In11.Cu" "In13.Cu" "In15.Cu")
		(hatch none 0.5)
		(connect_pads
			(clearance 0)
		)
		(min_thickness 0.25)
		(keepout
			(tracks not_allowed)
			(vias allowed)
			(pads allowed)
			(copperpour not_allowed)
			(footprints allowed)
		)
		(placement
			(enabled no)
			(sheetname "")
		)
		(fill yes
			(thermal_gap 0.5)
			(thermal_bridge_width 0.5)
			(island_removal_mode 0)
		)
		(polygon
			(pts
				(arc
					(start 62.826138 -316.799722)
					(mid 62.173358 -316.799722)
					(end 62.826138 -316.799722)
				)
			)
		)
	)
	(zone
		(layers "B.Cu" "In11.Cu" "In13.Cu" "In15.Cu")
		(hatch none 0.5)
		(connect_pads
			(clearance 0)
		)
		(min_thickness 0.25)
		(keepout
			(tracks not_allowed)
			(vias allowed)
			(pads allowed)
			(copperpour not_allowed)
			(footprints allowed)
		)
		(placement
			(enabled no)
			(sheetname "")
		)
		(fill yes
			(thermal_gap 0.5)
			(thermal_bridge_width 0.5)
			(island_removal_mode 0)
		)
		(polygon
			(pts
				(arc
					(start 81.884012 -143.479266)
					(mid 81.180432 -143.479266)
					(end 81.884012 -143.479266)
				)
			)
		)
	)
	(zone
		(layers "B.Cu" "In11.Cu" "In13.Cu" "In15.Cu")
		(hatch none 0.5)
		(connect_pads
			(clearance 0)
		)
		(min_thickness 0.25)
		(keepout
			(tracks not_allowed)
			(vias allowed)
			(pads allowed)
			(copperpour not_allowed)
			(footprints allowed)
		)
		(placement
			(enabled no)
			(sheetname "")
		)
		(fill yes
			(thermal_gap 0.5)
			(thermal_bridge_width 0.5)
			(island_removal_mode 0)
		)
		(polygon
			(pts
				(arc
					(start 386.419598 -136.704324)
					(mid 385.716018 -136.704324)
					(end 386.419598 -136.704324)
				)
			)
		)
	)
	(zone
		(layers "B.Cu" "In11.Cu" "In13.Cu" "In15.Cu")
		(hatch none 0.5)
		(connect_pads
			(clearance 0)
		)
		(min_thickness 0.25)
		(keepout
			(tracks not_allowed)
			(vias allowed)
			(pads allowed)
			(copperpour not_allowed)
			(footprints allowed)
		)
		(placement
			(enabled no)
			(sheetname "")
		)
		(fill yes
			(thermal_gap 0.5)
			(thermal_bridge_width 0.5)
			(island_removal_mode 0)
		)
		(polygon
			(pts
				(arc
					(start 154.219402 -121.030746)
					(mid 153.515822 -121.030746)
					(end 154.219402 -121.030746)
				)
			)
		)
	)
	(zone
		(layers "B.Cu" "In11.Cu" "In13.Cu" "In15.Cu")
		(hatch none 0.5)
		(connect_pads
			(clearance 0)
		)
		(min_thickness 0.25)
		(keepout
			(tracks not_allowed)
			(vias allowed)
			(pads allowed)
			(copperpour not_allowed)
			(footprints allowed)
		)
		(placement
			(enabled no)
			(sheetname "")
		)
		(fill yes
			(thermal_gap 0.5)
			(thermal_bridge_width 0.5)
			(island_removal_mode 0)
		)
		(polygon
			(pts
				(arc
					(start 267.677392 -130.434334)
					(mid 266.973812 -130.434334)
					(end 267.677392 -130.434334)
				)
			)
		)
	)
	(zone
		(layers "B.Cu" "In11.Cu" "In13.Cu" "In15.Cu")
		(hatch none 0.5)
		(connect_pads
			(clearance 0)
		)
		(min_thickness 0.25)
		(keepout
			(tracks not_allowed)
			(vias allowed)
			(pads allowed)
			(copperpour not_allowed)
			(footprints allowed)
		)
		(placement
			(enabled no)
			(sheetname "")
		)
		(fill yes
			(thermal_gap 0.5)
			(thermal_bridge_width 0.5)
			(island_removal_mode 0)
		)
		(polygon
			(pts
				(arc
					(start 151.577294 -112.784382)
					(mid 150.873714 -112.784382)
					(end 151.577294 -112.784382)
				)
			)
		)
	)
	(zone
		(layers "B.Cu" "In11.Cu" "In13.Cu" "In15.Cu")
		(hatch none 0.5)
		(connect_pads
			(clearance 0)
		)
		(min_thickness 0.25)
		(keepout
			(tracks not_allowed)
			(vias allowed)
			(pads allowed)
			(copperpour not_allowed)
			(footprints allowed)
		)
		(placement
			(enabled no)
			(sheetname "")
		)
		(fill yes
			(thermal_gap 0.5)
			(thermal_bridge_width 0.5)
			(island_removal_mode 0)
		)
		(polygon
			(pts
				(arc
					(start 70.426326 -279.749504)
					(mid 69.773546 -279.749504)
					(end 70.426326 -279.749504)
				)
			)
		)
	)
	(zone
		(layers "B.Cu" "In11.Cu" "In13.Cu" "In15.Cu")
		(hatch none 0.5)
		(connect_pads
			(clearance 0)
		)
		(min_thickness 0.25)
		(keepout
			(tracks not_allowed)
			(vias allowed)
			(pads allowed)
			(copperpour not_allowed)
			(footprints allowed)
		)
		(placement
			(enabled no)
			(sheetname "")
		)
		(fill yes
			(thermal_gap 0.5)
			(thermal_bridge_width 0.5)
			(island_removal_mode 0)
		)
		(polygon
			(pts
				(arc
					(start 411.126178 -279.749504)
					(mid 410.473398 -279.749504)
					(end 411.126178 -279.749504)
				)
			)
		)
	)
	(zone
		(layers "B.Cu" "In11.Cu" "In13.Cu" "In15.Cu")
		(hatch none 0.5)
		(connect_pads
			(clearance 0)
		)
		(min_thickness 0.25)
		(keepout
			(tracks not_allowed)
			(vias allowed)
			(pads allowed)
			(copperpour not_allowed)
			(footprints allowed)
		)
		(placement
			(enabled no)
			(sheetname "")
		)
		(fill yes
			(thermal_gap 0.5)
			(thermal_bridge_width 0.5)
			(island_removal_mode 0)
		)
		(polygon
			(pts
				(arc
					(start 430.184052 -119.559324)
					(mid 429.480472 -119.559324)
					(end 430.184052 -119.559324)
				)
			)
		)
	)
	(zone
		(layers "B.Cu" "In11.Cu" "In13.Cu" "In15.Cu")
		(hatch none 0.5)
		(connect_pads
			(clearance 0)
		)
		(min_thickness 0.25)
		(keepout
			(tracks not_allowed)
			(vias allowed)
			(pads allowed)
			(copperpour not_allowed)
			(footprints allowed)
		)
		(placement
			(enabled no)
			(sheetname "")
		)
		(fill yes
			(thermal_gap 0.5)
			(thermal_bridge_width 0.5)
			(island_removal_mode 0)
		)
		(polygon
			(pts
				(arc
					(start 74.489564 -398.890236)
					(mid 73.730104 -398.890236)
					(end 74.489564 -398.890236)
				)
			)
		)
	)
	(zone
		(layers "B.Cu" "In11.Cu" "In13.Cu" "In15.Cu")
		(hatch none 0.5)
		(connect_pads
			(clearance 0)
		)
		(min_thickness 0.25)
		(keepout
			(tracks not_allowed)
			(vias allowed)
			(pads allowed)
			(copperpour not_allowed)
			(footprints allowed)
		)
		(placement
			(enabled no)
			(sheetname "")
		)
		(fill yes
			(thermal_gap 0.5)
			(thermal_bridge_width 0.5)
			(island_removal_mode 0)
		)
		(polygon
			(pts
				(arc
					(start 75.176126 -278.799798)
					(mid 74.523346 -278.799798)
					(end 75.176126 -278.799798)
				)
			)
		)
	)
	(zone
		(layers "B.Cu" "In11.Cu" "In13.Cu" "In15.Cu")
		(hatch none 0.5)
		(connect_pads
			(clearance 0)
		)
		(min_thickness 0.25)
		(keepout
			(tracks not_allowed)
			(vias allowed)
			(pads allowed)
			(copperpour not_allowed)
			(footprints allowed)
		)
		(placement
			(enabled no)
			(sheetname "")
		)
		(fill yes
			(thermal_gap 0.5)
			(thermal_bridge_width 0.5)
			(island_removal_mode 0)
		)
		(polygon
			(pts
				(arc
					(start 385.476242 -316.799722)
					(mid 384.823462 -316.799722)
					(end 385.476242 -316.799722)
				)
			)
		)
	)
	(zone
		(layers "B.Cu" "In11.Cu" "In13.Cu" "In15.Cu")
		(hatch none 0.5)
		(connect_pads
			(clearance 0)
		)
		(min_thickness 0.25)
		(keepout
			(tracks not_allowed)
			(vias allowed)
			(pads allowed)
			(copperpour not_allowed)
			(footprints allowed)
		)
		(placement
			(enabled no)
			(sheetname "")
		)
		(fill yes
			(thermal_gap 0.5)
			(thermal_bridge_width 0.5)
			(island_removal_mode 0)
		)
		(polygon
			(pts
				(arc
					(start 164.68979 -382.18999)
					(mid 163.93033 -382.18999)
					(end 164.68979 -382.18999)
				)
			)
		)
	)
	(zone
		(layers "B.Cu" "In11.Cu" "In13.Cu" "In15.Cu")
		(hatch none 0.5)
		(connect_pads
			(clearance 0)
		)
		(min_thickness 0.25)
		(keepout
			(tracks not_allowed)
			(vias allowed)
			(pads allowed)
			(copperpour not_allowed)
			(footprints allowed)
		)
		(placement
			(enabled no)
			(sheetname "")
		)
		(fill yes
			(thermal_gap 0.5)
			(thermal_bridge_width 0.5)
			(island_removal_mode 0)
		)
		(polygon
			(pts
				(arc
					(start 420.626286 -280.699718)
					(mid 419.973506 -280.699718)
					(end 420.626286 -280.699718)
				)
			)
		)
	)
	(zone
		(layers "B.Cu" "In11.Cu" "In13.Cu" "In15.Cu")
		(hatch none 0.5)
		(connect_pads
			(clearance 0)
		)
		(min_thickness 0.25)
		(keepout
			(tracks not_allowed)
			(vias allowed)
			(pads allowed)
			(copperpour not_allowed)
			(footprints allowed)
		)
		(placement
			(enabled no)
			(sheetname "")
		)
		(fill yes
			(thermal_gap 0.5)
			(thermal_bridge_width 0.5)
			(island_removal_mode 0)
		)
		(polygon
			(pts
				(arc
					(start 192.226438 -279.749504)
					(mid 191.573658 -279.749504)
					(end 192.226438 -279.749504)
				)
			)
		)
	)
	(zone
		(layers "B.Cu" "In11.Cu" "In13.Cu" "In15.Cu")
		(hatch none 0.5)
		(connect_pads
			(clearance 0)
		)
		(min_thickness 0.25)
		(keepout
			(tracks not_allowed)
			(vias allowed)
			(pads allowed)
			(copperpour not_allowed)
			(footprints allowed)
		)
		(placement
			(enabled no)
			(sheetname "")
		)
		(fill yes
			(thermal_gap 0.5)
			(thermal_bridge_width 0.5)
			(island_removal_mode 0)
		)
		(polygon
			(pts
				(arc
					(start 191.276224 -285.449772)
					(mid 190.623444 -285.449772)
					(end 191.276224 -285.449772)
				)
			)
		)
	)
	(zone
		(layers "B.Cu" "In11.Cu" "In13.Cu" "In15.Cu")
		(hatch none 0.5)
		(connect_pads
			(clearance 0)
		)
		(min_thickness 0.25)
		(keepout
			(tracks not_allowed)
			(vias allowed)
			(pads allowed)
			(copperpour not_allowed)
			(footprints allowed)
		)
		(placement
			(enabled no)
			(sheetname "")
		)
		(fill yes
			(thermal_gap 0.5)
			(thermal_bridge_width 0.5)
			(island_removal_mode 0)
		)
		(polygon
			(pts
				(arc
					(start 314.083954 -119.559324)
					(mid 313.380374 -119.559324)
					(end 314.083954 -119.559324)
				)
			)
		)
	)
	(zone
		(layers "B.Cu" "In11.Cu" "In13.Cu" "In15.Cu")
		(hatch none 0.5)
		(connect_pads
			(clearance 0)
		)
		(min_thickness 0.25)
		(keepout
			(tracks not_allowed)
			(vias allowed)
			(pads allowed)
			(copperpour not_allowed)
			(footprints allowed)
		)
		(placement
			(enabled no)
			(sheetname "")
		)
		(fill yes
			(thermal_gap 0.5)
			(thermal_bridge_width 0.5)
			(island_removal_mode 0)
		)
		(polygon
			(pts
				(arc
					(start 433.069492 -408.190192)
					(mid 432.310032 -408.190192)
					(end 433.069492 -408.190192)
				)
			)
		)
	)
	(zone
		(layers "B.Cu" "In11.Cu" "In13.Cu" "In15.Cu")
		(hatch none 0.5)
		(connect_pads
			(clearance 0)
		)
		(min_thickness 0.25)
		(keepout
			(tracks not_allowed)
			(vias allowed)
			(pads allowed)
			(copperpour not_allowed)
			(footprints allowed)
		)
		(placement
			(enabled no)
			(sheetname "")
		)
		(fill yes
			(thermal_gap 0.5)
			(thermal_bridge_width 0.5)
			(island_removal_mode 0)
		)
		(polygon
			(pts
				(arc
					(start 435.26964 -409.290012)
					(mid 434.51018 -409.290012)
					(end 435.26964 -409.290012)
				)
			)
		)
	)
	(zone
		(layers "B.Cu" "In11.Cu" "In13.Cu" "In15.Cu")
		(hatch none 0.5)
		(connect_pads
			(clearance 0)
		)
		(min_thickness 0.25)
		(keepout
			(tracks not_allowed)
			(vias allowed)
			(pads allowed)
			(copperpour not_allowed)
			(footprints allowed)
		)
		(placement
			(enabled no)
			(sheetname "")
		)
		(fill yes
			(thermal_gap 0.5)
			(thermal_bridge_width 0.5)
			(island_removal_mode 0)
		)
		(polygon
			(pts
				(arc
					(start 197.983856 -134.369302)
					(mid 197.280276 -134.369302)
					(end 197.983856 -134.369302)
				)
			)
		)
	)
	(zone
		(layers "B.Cu" "In11.Cu" "In13.Cu" "In15.Cu")
		(hatch none 0.5)
		(connect_pads
			(clearance 0)
		)
		(min_thickness 0.25)
		(keepout
			(tracks not_allowed)
			(vias allowed)
			(pads allowed)
			(copperpour not_allowed)
			(footprints allowed)
		)
		(placement
			(enabled no)
			(sheetname "")
		)
		(fill yes
			(thermal_gap 0.5)
			(thermal_bridge_width 0.5)
			(island_removal_mode 0)
		)
		(polygon
			(pts
				(arc
					(start 386.426202 -304.449734)
					(mid 385.773422 -304.449734)
					(end 386.426202 -304.449734)
				)
			)
		)
	)
	(zone
		(layers "B.Cu" "In11.Cu" "In13.Cu" "In15.Cu")
		(hatch none 0.5)
		(connect_pads
			(clearance 0)
		)
		(min_thickness 0.25)
		(keepout
			(tracks not_allowed)
			(vias allowed)
			(pads allowed)
			(copperpour not_allowed)
			(footprints allowed)
		)
		(placement
			(enabled no)
			(sheetname "")
		)
		(fill yes
			(thermal_gap 0.5)
			(thermal_bridge_width 0.5)
			(island_removal_mode 0)
		)
		(polygon
			(pts
				(arc
					(start 288.376106 -317.749936)
					(mid 287.723326 -317.749936)
					(end 288.376106 -317.749936)
				)
			)
		)
	)
	(zone
		(layers "B.Cu" "In11.Cu" "In13.Cu" "In15.Cu")
		(hatch none 0.5)
		(connect_pads
			(clearance 0)
		)
		(min_thickness 0.25)
		(keepout
			(tracks not_allowed)
			(vias allowed)
			(pads allowed)
			(copperpour not_allowed)
			(footprints allowed)
		)
		(placement
			(enabled no)
			(sheetname "")
		)
		(fill yes
			(thermal_gap 0.5)
			(thermal_bridge_width 0.5)
			(island_removal_mode 0)
		)
		(polygon
			(pts
				(arc
					(start 267.677392 -108.32084)
					(mid 266.973812 -108.32084)
					(end 267.677392 -108.32084)
				)
			)
		)
	)
	(zone
		(layers "B.Cu" "In11.Cu" "In13.Cu" "In15.Cu")
		(hatch none 0.5)
		(connect_pads
			(clearance 0)
		)
		(min_thickness 0.25)
		(keepout
			(tracks not_allowed)
			(vias allowed)
			(pads allowed)
			(copperpour not_allowed)
			(footprints allowed)
		)
		(placement
			(enabled no)
			(sheetname "")
		)
		(fill yes
			(thermal_gap 0.5)
			(thermal_bridge_width 0.5)
			(island_removal_mode 0)
		)
		(polygon
			(pts
				(arc
					(start 171.289726 -409.290012)
					(mid 170.530266 -409.290012)
					(end 171.289726 -409.290012)
				)
			)
		)
	)
	(zone
		(layers "B.Cu" "In11.Cu" "In13.Cu" "In15.Cu")
		(hatch none 0.5)
		(connect_pads
			(clearance 0)
		)
		(min_thickness 0.25)
		(keepout
			(tracks not_allowed)
			(vias allowed)
			(pads allowed)
			(copperpour not_allowed)
			(footprints allowed)
		)
		(placement
			(enabled no)
			(sheetname "")
		)
		(fill yes
			(thermal_gap 0.5)
			(thermal_bridge_width 0.5)
			(island_removal_mode 0)
		)
		(polygon
			(pts
				(arc
					(start 386.426202 -308.249828)
					(mid 385.773422 -308.249828)
					(end 386.426202 -308.249828)
				)
			)
		)
	)
	(zone
		(layers "B.Cu" "In11.Cu" "In13.Cu" "In15.Cu")
		(hatch none 0.5)
		(connect_pads
			(clearance 0)
		)
		(min_thickness 0.25)
		(keepout
			(tracks not_allowed)
			(vias allowed)
			(pads allowed)
			(copperpour not_allowed)
			(footprints allowed)
		)
		(placement
			(enabled no)
			(sheetname "")
		)
		(fill yes
			(thermal_gap 0.5)
			(thermal_bridge_width 0.5)
			(island_removal_mode 0)
		)
		(polygon
			(pts
				(arc
					(start 78.889606 -376.790204)
					(mid 78.130146 -376.790204)
					(end 78.889606 -376.790204)
				)
			)
		)
	)
	(zone
		(layers "B.Cu" "In11.Cu" "In13.Cu" "In15.Cu")
		(hatch none 0.5)
		(connect_pads
			(clearance 0)
		)
		(min_thickness 0.25)
		(keepout
			(tracks not_allowed)
			(vias allowed)
			(pads allowed)
			(copperpour not_allowed)
			(footprints allowed)
		)
		(placement
			(enabled no)
			(sheetname "")
		)
		(fill yes
			(thermal_gap 0.5)
			(thermal_bridge_width 0.5)
			(island_removal_mode 0)
		)
		(polygon
			(pts
				(arc
					(start 424.42638 -283.549852)
					(mid 423.7736 -283.549852)
					(end 424.42638 -283.549852)
				)
			)
		)
	)
	(zone
		(layers "B.Cu" "In11.Cu" "In13.Cu" "In15.Cu")
		(hatch none 0.5)
		(connect_pads
			(clearance 0)
		)
		(min_thickness 0.25)
		(keepout
			(tracks not_allowed)
			(vias allowed)
			(pads allowed)
			(copperpour not_allowed)
			(footprints allowed)
		)
		(placement
			(enabled no)
			(sheetname "")
		)
		(fill yes
			(thermal_gap 0.5)
			(thermal_bridge_width 0.5)
			(island_removal_mode 0)
		)
		(polygon
			(pts
				(arc
					(start 58.076338 -317.749936)
					(mid 57.423558 -317.749936)
					(end 58.076338 -317.749936)
				)
			)
		)
	)
	(zone
		(layers "B.Cu" "In11.Cu" "In13.Cu" "In15.Cu")
		(hatch none 0.5)
		(connect_pads
			(clearance 0)
		)
		(min_thickness 0.25)
		(keepout
			(tracks not_allowed)
			(vias allowed)
			(pads allowed)
			(copperpour not_allowed)
			(footprints allowed)
		)
		(placement
			(enabled no)
			(sheetname "")
		)
		(fill yes
			(thermal_gap 0.5)
			(thermal_bridge_width 0.5)
			(island_removal_mode 0)
		)
		(polygon
			(pts
				(arc
					(start 267.677392 -131.297934)
					(mid 266.973812 -131.297934)
					(end 267.677392 -131.297934)
				)
			)
		)
	)
	(zone
		(layers "B.Cu" "In11.Cu" "In13.Cu" "In15.Cu")
		(hatch none 0.5)
		(connect_pads
			(clearance 0)
		)
		(min_thickness 0.25)
		(keepout
			(tracks not_allowed)
			(vias allowed)
			(pads allowed)
			(copperpour not_allowed)
			(footprints allowed)
		)
		(placement
			(enabled no)
			(sheetname "")
		)
		(fill yes
			(thermal_gap 0.5)
			(thermal_bridge_width 0.5)
			(island_removal_mode 0)
		)
		(polygon
			(pts
				(arc
					(start 65.676272 -317.749936)
					(mid 65.023492 -317.749936)
					(end 65.676272 -317.749936)
				)
			)
		)
	)
	(zone
		(layers "B.Cu" "In11.Cu" "In13.Cu" "In15.Cu")
		(hatch none 0.5)
		(connect_pads
			(clearance 0)
		)
		(min_thickness 0.25)
		(keepout
			(tracks not_allowed)
			(vias allowed)
			(pads allowed)
			(copperpour not_allowed)
			(footprints allowed)
		)
		(placement
			(enabled no)
			(sheetname "")
		)
		(fill yes
			(thermal_gap 0.5)
			(thermal_bridge_width 0.5)
			(island_removal_mode 0)
		)
		(polygon
			(pts
				(arc
					(start 314.083954 -154.279346)
					(mid 313.380374 -154.279346)
					(end 314.083954 -154.279346)
				)
			)
		)
	)
	(zone
		(layers "B.Cu" "In11.Cu" "In13.Cu" "In15.Cu")
		(hatch none 0.5)
		(connect_pads
			(clearance 0)
		)
		(min_thickness 0.25)
		(keepout
			(tracks not_allowed)
			(vias allowed)
			(pads allowed)
			(copperpour not_allowed)
			(footprints allowed)
		)
		(placement
			(enabled no)
			(sheetname "")
		)
		(fill yes
			(thermal_gap 0.5)
			(thermal_bridge_width 0.5)
			(island_removal_mode 0)
		)
		(polygon
			(pts
				(arc
					(start 312.126122 -280.699718)
					(mid 311.473342 -280.699718)
					(end 312.126122 -280.699718)
				)
			)
		)
	)
	(zone
		(layers "B.Cu" "In11.Cu" "In13.Cu" "In15.Cu")
		(hatch none 0.5)
		(connect_pads
			(clearance 0)
		)
		(min_thickness 0.25)
		(keepout
			(tracks not_allowed)
			(vias allowed)
			(pads allowed)
			(copperpour not_allowed)
			(footprints allowed)
		)
		(placement
			(enabled no)
			(sheetname "")
		)
		(fill yes
			(thermal_gap 0.5)
			(thermal_bridge_width 0.5)
			(island_removal_mode 0)
		)
		(polygon
			(pts
				(arc
					(start 100.0252 -201.35215)
					(mid 99.32162 -201.35215)
					(end 100.0252 -201.35215)
				)
			)
		)
	)
	(zone
		(layers "B.Cu" "In11.Cu" "In13.Cu" "In15.Cu")
		(hatch none 0.5)
		(connect_pads
			(clearance 0)
		)
		(min_thickness 0.25)
		(keepout
			(tracks not_allowed)
			(vias allowed)
			(pads allowed)
			(copperpour not_allowed)
			(footprints allowed)
		)
		(placement
			(enabled no)
			(sheetname "")
		)
		(fill yes
			(thermal_gap 0.5)
			(thermal_bridge_width 0.5)
			(island_removal_mode 0)
		)
		(polygon
			(pts
				(arc
					(start 59.976258 -318.699896)
					(mid 59.323478 -318.699896)
					(end 59.976258 -318.699896)
				)
			)
		)
	)
	(zone
		(layers "B.Cu" "In11.Cu" "In13.Cu" "In15.Cu")
		(hatch none 0.5)
		(connect_pads
			(clearance 0)
		)
		(min_thickness 0.25)
		(keepout
			(tracks not_allowed)
			(vias allowed)
			(pads allowed)
			(copperpour not_allowed)
			(footprints allowed)
		)
		(placement
			(enabled no)
			(sheetname "")
		)
		(fill yes
			(thermal_gap 0.5)
			(thermal_bridge_width 0.5)
			(island_removal_mode 0)
		)
		(polygon
			(pts
				(arc
					(start 38.119558 -110.977934)
					(mid 37.415978 -110.977934)
					(end 38.119558 -110.977934)
				)
			)
		)
	)
	(zone
		(layers "B.Cu" "In11.Cu" "In13.Cu" "In15.Cu")
		(hatch none 0.5)
		(connect_pads
			(clearance 0)
		)
		(min_thickness 0.25)
		(keepout
			(tracks not_allowed)
			(vias allowed)
			(pads allowed)
			(copperpour not_allowed)
			(footprints allowed)
		)
		(placement
			(enabled no)
			(sheetname "")
		)
		(fill yes
			(thermal_gap 0.5)
			(thermal_bridge_width 0.5)
			(island_removal_mode 0)
		)
		(polygon
			(pts
				(arc
					(start 72.326246 -279.749504)
					(mid 71.673466 -279.749504)
					(end 72.326246 -279.749504)
				)
			)
		)
	)
	(zone
		(layers "B.Cu" "In11.Cu" "In13.Cu" "In15.Cu")
		(hatch none 0.5)
		(connect_pads
			(clearance 0)
		)
		(min_thickness 0.25)
		(keepout
			(tracks not_allowed)
			(vias allowed)
			(pads allowed)
			(copperpour not_allowed)
			(footprints allowed)
		)
		(placement
			(enabled no)
			(sheetname "")
		)
		(fill yes
			(thermal_gap 0.5)
			(thermal_bridge_width 0.5)
			(island_removal_mode 0)
		)
		(polygon
			(pts
				(arc
					(start 423.476166 -278.799798)
					(mid 422.823386 -278.799798)
					(end 423.476166 -278.799798)
				)
			)
		)
	)
	(zone
		(layers "B.Cu" "In11.Cu" "In13.Cu" "In15.Cu")
		(hatch none 0.5)
		(connect_pads
			(clearance 0)
		)
		(min_thickness 0.25)
		(keepout
			(tracks not_allowed)
			(vias allowed)
			(pads allowed)
			(copperpour not_allowed)
			(footprints allowed)
		)
		(placement
			(enabled no)
			(sheetname "")
		)
		(fill yes
			(thermal_gap 0.5)
			(thermal_bridge_width 0.5)
			(island_removal_mode 0)
		)
		(polygon
			(pts
				(arc
					(start 54.276244 -318.699896)
					(mid 53.623464 -318.699896)
					(end 54.276244 -318.699896)
				)
			)
		)
	)
	(zone
		(layers "B.Cu" "In11.Cu" "In13.Cu" "In15.Cu")
		(hatch none 0.5)
		(connect_pads
			(clearance 0)
		)
		(min_thickness 0.25)
		(keepout
			(tracks not_allowed)
			(vias allowed)
			(pads allowed)
			(copperpour not_allowed)
			(footprints allowed)
		)
		(placement
			(enabled no)
			(sheetname "")
		)
		(fill yes
			(thermal_gap 0.5)
			(thermal_bridge_width 0.5)
			(island_removal_mode 0)
		)
		(polygon
			(pts
				(arc
					(start 313.076082 -277.849838)
					(mid 312.423302 -277.849838)
					(end 313.076082 -277.849838)
				)
			)
		)
	)
	(zone
		(layers "B.Cu" "In11.Cu" "In13.Cu" "In15.Cu")
		(hatch none 0.5)
		(connect_pads
			(clearance 0)
		)
		(min_thickness 0.25)
		(keepout
			(tracks not_allowed)
			(vias allowed)
			(pads allowed)
			(copperpour not_allowed)
			(footprints allowed)
		)
		(placement
			(enabled no)
			(sheetname "")
		)
		(fill yes
			(thermal_gap 0.5)
			(thermal_bridge_width 0.5)
			(island_removal_mode 0)
		)
		(polygon
			(pts
				(arc
					(start 154.22626 -302.549814)
					(mid 153.57348 -302.549814)
					(end 154.22626 -302.549814)
				)
			)
		)
	)
	(zone
		(layers "B.Cu" "In11.Cu" "In13.Cu" "In15.Cu")
		(hatch none 0.5)
		(connect_pads
			(clearance 0)
		)
		(min_thickness 0.25)
		(keepout
			(tracks not_allowed)
			(vias allowed)
			(pads allowed)
			(copperpour not_allowed)
			(footprints allowed)
		)
		(placement
			(enabled no)
			(sheetname "")
		)
		(fill yes
			(thermal_gap 0.5)
			(thermal_bridge_width 0.5)
			(island_removal_mode 0)
		)
		(polygon
			(pts
				(arc
					(start 424.42638 -287.349946)
					(mid 423.7736 -287.349946)
					(end 424.42638 -287.349946)
				)
			)
		)
	)
	(zone
		(layers "B.Cu" "In11.Cu" "In13.Cu" "In15.Cu")
		(hatch none 0.5)
		(connect_pads
			(clearance 0)
		)
		(min_thickness 0.25)
		(keepout
			(tracks not_allowed)
			(vias allowed)
			(pads allowed)
			(copperpour not_allowed)
			(footprints allowed)
		)
		(placement
			(enabled no)
			(sheetname "")
		)
		(fill yes
			(thermal_gap 0.5)
			(thermal_bridge_width 0.5)
			(island_removal_mode 0)
		)
		(polygon
			(pts
				(arc
					(start 293.12616 -279.749504)
					(mid 292.47338 -279.749504)
					(end 293.12616 -279.749504)
				)
			)
		)
	)
	(zone
		(layers "B.Cu" "In11.Cu" "In13.Cu" "In15.Cu")
		(hatch none 0.5)
		(connect_pads
			(clearance 0)
		)
		(min_thickness 0.25)
		(keepout
			(tracks not_allowed)
			(vias allowed)
			(pads allowed)
			(copperpour not_allowed)
			(footprints allowed)
		)
		(placement
			(enabled no)
			(sheetname "")
		)
		(fill yes
			(thermal_gap 0.5)
			(thermal_bridge_width 0.5)
			(island_removal_mode 0)
		)
		(polygon
			(pts
				(arc
					(start 342.869774 -375.490232)
					(mid 342.110314 -375.490232)
					(end 342.869774 -375.490232)
				)
			)
		)
	)
	(zone
		(layers "B.Cu" "In11.Cu" "In13.Cu" "In15.Cu")
		(hatch none 0.5)
		(connect_pads
			(clearance 0)
		)
		(min_thickness 0.25)
		(keepout
			(tracks not_allowed)
			(vias allowed)
			(pads allowed)
			(copperpour not_allowed)
			(footprints allowed)
		)
		(placement
			(enabled no)
			(sheetname "")
		)
		(fill yes
			(thermal_gap 0.5)
			(thermal_bridge_width 0.5)
			(island_removal_mode 0)
		)
		(polygon
			(pts
				(arc
					(start 421.575992 -277.849838)
					(mid 420.923212 -277.849838)
					(end 421.575992 -277.849838)
				)
			)
		)
	)
	(zone
		(layers "B.Cu" "In11.Cu" "In13.Cu" "In15.Cu")
		(hatch none 0.5)
		(connect_pads
			(clearance 0)
		)
		(min_thickness 0.25)
		(keepout
			(tracks not_allowed)
			(vias allowed)
			(pads allowed)
			(copperpour not_allowed)
			(footprints allowed)
		)
		(placement
			(enabled no)
			(sheetname "")
		)
		(fill yes
			(thermal_gap 0.5)
			(thermal_bridge_width 0.5)
			(island_removal_mode 0)
		)
		(polygon
			(pts
				(arc
					(start 154.219402 -99.314254)
					(mid 153.515822 -99.314254)
					(end 154.219402 -99.314254)
				)
			)
		)
	)
	(zone
		(layers "B.Cu" "In11.Cu" "In13.Cu" "In15.Cu")
		(hatch none 0.5)
		(connect_pads
			(clearance 0)
		)
		(min_thickness 0.25)
		(keepout
			(tracks not_allowed)
			(vias allowed)
			(pads allowed)
			(copperpour not_allowed)
			(footprints allowed)
		)
		(placement
			(enabled no)
			(sheetname "")
		)
		(fill yes
			(thermal_gap 0.5)
			(thermal_bridge_width 0.5)
			(island_removal_mode 0)
		)
		(polygon
			(pts
				(arc
					(start 285.526226 -316.799722)
					(mid 284.873446 -316.799722)
					(end 285.526226 -316.799722)
				)
			)
		)
	)
	(zone
		(layers "B.Cu" "In11.Cu" "In13.Cu" "In15.Cu")
		(hatch none 0.5)
		(connect_pads
			(clearance 0)
		)
		(min_thickness 0.25)
		(keepout
			(tracks not_allowed)
			(vias allowed)
			(pads allowed)
			(copperpour not_allowed)
			(footprints allowed)
		)
		(placement
			(enabled no)
			(sheetname "")
		)
		(fill yes
			(thermal_gap 0.5)
			(thermal_bridge_width 0.5)
			(island_removal_mode 0)
		)
		(polygon
			(pts
				(arc
					(start 426.3263 -279.749504)
					(mid 425.67352 -279.749504)
					(end 426.3263 -279.749504)
				)
			)
		)
	)
	(zone
		(layers "B.Cu" "In11.Cu" "In13.Cu" "In15.Cu")
		(hatch none 0.5)
		(connect_pads
			(clearance 0)
		)
		(min_thickness 0.25)
		(keepout
			(tracks not_allowed)
			(vias allowed)
			(pads allowed)
			(copperpour not_allowed)
			(footprints allowed)
		)
		(placement
			(enabled no)
			(sheetname "")
		)
		(fill yes
			(thermal_gap 0.5)
			(thermal_bridge_width 0.5)
			(island_removal_mode 0)
		)
		(polygon
			(pts
				(arc
					(start 426.3263 -282.599892)
					(mid 425.67352 -282.599892)
					(end 426.3263 -282.599892)
				)
			)
		)
	)
	(zone
		(layers "B.Cu" "In11.Cu" "In13.Cu" "In15.Cu")
		(hatch none 0.5)
		(connect_pads
			(clearance 0)
		)
		(min_thickness 0.25)
		(keepout
			(tracks not_allowed)
			(vias allowed)
			(pads allowed)
			(copperpour not_allowed)
			(footprints allowed)
		)
		(placement
			(enabled no)
			(sheetname "")
		)
		(fill yes
			(thermal_gap 0.5)
			(thermal_bridge_width 0.5)
			(island_removal_mode 0)
		)
		(polygon
			(pts
				(arc
					(start 200.625964 -145.285714)
					(mid 199.922384 -145.285714)
					(end 200.625964 -145.285714)
				)
			)
		)
	)
	(zone
		(layers "B.Cu" "In11.Cu" "In13.Cu" "In15.Cu")
		(hatch none 0.5)
		(connect_pads
			(clearance 0)
		)
		(min_thickness 0.25)
		(keepout
			(tracks not_allowed)
			(vias allowed)
			(pads allowed)
			(copperpour not_allowed)
			(footprints allowed)
		)
		(placement
			(enabled no)
			(sheetname "")
		)
		(fill yes
			(thermal_gap 0.5)
			(thermal_bridge_width 0.5)
			(island_removal_mode 0)
		)
		(polygon
			(pts
				(arc
					(start 426.469556 -409.290012)
					(mid 425.710096 -409.290012)
					(end 426.469556 -409.290012)
				)
			)
		)
	)
	(zone
		(layers "B.Cu" "In11.Cu" "In13.Cu" "In15.Cu")
		(hatch none 0.5)
		(connect_pads
			(clearance 0)
		)
		(min_thickness 0.25)
		(keepout
			(tracks not_allowed)
			(vias allowed)
			(pads allowed)
			(copperpour not_allowed)
			(footprints allowed)
		)
		(placement
			(enabled no)
			(sheetname "")
		)
		(fill yes
			(thermal_gap 0.5)
			(thermal_bridge_width 0.5)
			(island_removal_mode 0)
		)
		(polygon
			(pts
				(arc
					(start 304.526188 -279.749504)
					(mid 303.873408 -279.749504)
					(end 304.526188 -279.749504)
				)
			)
		)
	)
	(zone
		(layers "B.Cu" "In11.Cu" "In13.Cu" "In15.Cu")
		(hatch none 0.5)
		(connect_pads
			(clearance 0)
		)
		(min_thickness 0.25)
		(keepout
			(tracks not_allowed)
			(vias allowed)
			(pads allowed)
			(copperpour not_allowed)
			(footprints allowed)
		)
		(placement
			(enabled no)
			(sheetname "")
		)
		(fill yes
			(thermal_gap 0.5)
			(thermal_bridge_width 0.5)
			(island_removal_mode 0)
		)
		(polygon
			(pts
				(arc
					(start 267.677392 -112.784382)
					(mid 266.973812 -112.784382)
					(end 267.677392 -112.784382)
				)
			)
		)
	)
	(zone
		(layers "B.Cu" "In11.Cu" "In13.Cu" "In15.Cu")
		(hatch none 0.5)
		(connect_pads
			(clearance 0)
		)
		(min_thickness 0.25)
		(keepout
			(tracks not_allowed)
			(vias allowed)
			(pads allowed)
			(copperpour not_allowed)
			(footprints allowed)
		)
		(placement
			(enabled no)
			(sheetname "")
		)
		(fill yes
			(thermal_gap 0.5)
			(thermal_bridge_width 0.5)
			(island_removal_mode 0)
		)
		(polygon
			(pts
				(arc
					(start 294.075866 -277.849838)
					(mid 293.423086 -277.849838)
					(end 294.075866 -277.849838)
				)
			)
		)
	)
	(zone
		(layers "B.Cu" "In11.Cu" "In13.Cu" "In15.Cu")
		(hatch none 0.5)
		(connect_pads
			(clearance 0)
		)
		(min_thickness 0.25)
		(keepout
			(tracks not_allowed)
			(vias allowed)
			(pads allowed)
			(copperpour not_allowed)
			(footprints allowed)
		)
		(placement
			(enabled no)
			(sheetname "")
		)
		(fill yes
			(thermal_gap 0.5)
			(thermal_bridge_width 0.5)
			(island_removal_mode 0)
		)
		(polygon
			(pts
				(arc
					(start 308.326282 -283.549852)
					(mid 307.673502 -283.549852)
					(end 308.326282 -283.549852)
				)
			)
		)
	)
	(zone
		(layers "B.Cu" "In11.Cu" "In13.Cu" "In15.Cu")
		(hatch none 0.5)
		(connect_pads
			(clearance 0)
		)
		(min_thickness 0.25)
		(keepout
			(tracks not_allowed)
			(vias allowed)
			(pads allowed)
			(copperpour not_allowed)
			(footprints allowed)
		)
		(placement
			(enabled no)
			(sheetname "")
		)
		(fill yes
			(thermal_gap 0.5)
			(thermal_bridge_width 0.5)
			(island_removal_mode 0)
		)
		(polygon
			(pts
				(arc
					(start 410.175964 -277.849838)
					(mid 409.523184 -277.849838)
					(end 410.175964 -277.849838)
				)
			)
		)
	)
	(zone
		(layers "B.Cu" "In11.Cu" "In13.Cu" "In15.Cu")
		(hatch none 0.5)
		(connect_pads
			(clearance 0)
		)
		(min_thickness 0.25)
		(keepout
			(tracks not_allowed)
			(vias allowed)
			(pads allowed)
			(copperpour not_allowed)
			(footprints allowed)
		)
		(placement
			(enabled no)
			(sheetname "")
		)
		(fill yes
			(thermal_gap 0.5)
			(thermal_bridge_width 0.5)
			(island_removal_mode 0)
		)
		(polygon
			(pts
				(arc
					(start 59.026298 -316.799722)
					(mid 58.373518 -316.799722)
					(end 59.026298 -316.799722)
				)
			)
		)
	)
	(zone
		(layers "B.Cu" "In11.Cu" "In13.Cu" "In15.Cu")
		(hatch none 0.5)
		(connect_pads
			(clearance 0)
		)
		(min_thickness 0.25)
		(keepout
			(tracks not_allowed)
			(vias allowed)
			(pads allowed)
			(copperpour not_allowed)
			(footprints allowed)
		)
		(placement
			(enabled no)
			(sheetname "")
		)
		(fill yes
			(thermal_gap 0.5)
			(thermal_bridge_width 0.5)
			(island_removal_mode 0)
		)
		(polygon
			(pts
				(arc
					(start 54.276244 -317.749936)
					(mid 53.623464 -317.749936)
					(end 54.276244 -317.749936)
				)
			)
		)
	)
	(zone
		(layers "B.Cu" "In11.Cu" "In13.Cu" "In15.Cu")
		(hatch none 0.5)
		(connect_pads
			(clearance 0)
		)
		(min_thickness 0.25)
		(keepout
			(tracks not_allowed)
			(vias allowed)
			(pads allowed)
			(copperpour not_allowed)
			(footprints allowed)
		)
		(placement
			(enabled no)
			(sheetname "")
		)
		(fill yes
			(thermal_gap 0.5)
			(thermal_bridge_width 0.5)
			(island_removal_mode 0)
		)
		(polygon
			(pts
				(arc
					(start 284.576266 -317.749936)
					(mid 283.923486 -317.749936)
					(end 284.576266 -317.749936)
				)
			)
		)
	)
	(zone
		(layers "B.Cu" "In11.Cu" "In13.Cu" "In15.Cu")
		(hatch none 0.5)
		(connect_pads
			(clearance 0)
		)
		(min_thickness 0.25)
		(keepout
			(tracks not_allowed)
			(vias allowed)
			(pads allowed)
			(copperpour not_allowed)
			(footprints allowed)
		)
		(placement
			(enabled no)
			(sheetname "")
		)
		(fill yes
			(thermal_gap 0.5)
			(thermal_bridge_width 0.5)
			(island_removal_mode 0)
		)
		(polygon
			(pts
				(arc
					(start 287.426146 -316.799722)
					(mid 286.773366 -316.799722)
					(end 287.426146 -316.799722)
				)
			)
		)
	)
	(zone
		(layers "B.Cu" "In11.Cu" "In13.Cu" "In15.Cu")
		(hatch none 0.5)
		(connect_pads
			(clearance 0)
		)
		(min_thickness 0.25)
		(keepout
			(tracks not_allowed)
			(vias allowed)
			(pads allowed)
			(copperpour not_allowed)
			(footprints allowed)
		)
		(placement
			(enabled no)
			(sheetname "")
		)
		(fill yes
			(thermal_gap 0.5)
			(thermal_bridge_width 0.5)
			(island_removal_mode 0)
		)
		(polygon
			(pts
				(arc
					(start 81.884012 -123.159266)
					(mid 81.180432 -123.159266)
					(end 81.884012 -123.159266)
				)
			)
		)
	)
	(zone
		(layers "B.Cu" "In11.Cu" "In13.Cu" "In15.Cu")
		(hatch none 0.5)
		(connect_pads
			(clearance 0)
		)
		(min_thickness 0.25)
		(keepout
			(tracks not_allowed)
			(vias allowed)
			(pads allowed)
			(copperpour not_allowed)
			(footprints allowed)
		)
		(placement
			(enabled no)
			(sheetname "")
		)
		(fill yes
			(thermal_gap 0.5)
			(thermal_bridge_width 0.5)
			(island_removal_mode 0)
		)
		(polygon
			(pts
				(arc
					(start 83.289648 -397.59001)
					(mid 82.530188 -397.59001)
					(end 83.289648 -397.59001)
				)
			)
		)
	)
	(zone
		(layers "B.Cu" "In11.Cu" "In13.Cu" "In15.Cu")
		(hatch none 0.5)
		(connect_pads
			(clearance 0)
		)
		(min_thickness 0.25)
		(keepout
			(tracks not_allowed)
			(vias allowed)
			(pads allowed)
			(copperpour not_allowed)
			(footprints allowed)
		)
		(placement
			(enabled no)
			(sheetname "")
		)
		(fill yes
			(thermal_gap 0.5)
			(thermal_bridge_width 0.5)
			(island_removal_mode 0)
		)
		(polygon
			(pts
				(arc
					(start 430.184052 -154.279346)
					(mid 429.480472 -154.279346)
					(end 430.184052 -154.279346)
				)
			)
		)
	)
	(zone
		(layers "B.Cu" "In11.Cu" "In13.Cu" "In15.Cu")
		(hatch none 0.5)
		(connect_pads
			(clearance 0)
		)
		(min_thickness 0.25)
		(keepout
			(tracks not_allowed)
			(vias allowed)
			(pads allowed)
			(copperpour not_allowed)
			(footprints allowed)
		)
		(placement
			(enabled no)
			(sheetname "")
		)
		(fill yes
			(thermal_gap 0.5)
			(thermal_bridge_width 0.5)
			(island_removal_mode 0)
		)
		(polygon
			(pts
				(arc
					(start 155.176474 -301.599854)
					(mid 154.523694 -301.599854)
					(end 155.176474 -301.599854)
				)
			)
		)
	)
	(zone
		(layers "B.Cu" "In11.Cu" "In13.Cu" "In15.Cu")
		(hatch none 0.5)
		(connect_pads
			(clearance 0)
		)
		(min_thickness 0.25)
		(keepout
			(tracks not_allowed)
			(vias allowed)
			(pads allowed)
			(copperpour not_allowed)
			(footprints allowed)
		)
		(placement
			(enabled no)
			(sheetname "")
		)
		(fill yes
			(thermal_gap 0.5)
			(thermal_bridge_width 0.5)
			(island_removal_mode 0)
		)
		(polygon
			(pts
				(arc
					(start 386.419598 -110.114334)
					(mid 385.716018 -110.114334)
					(end 386.419598 -110.114334)
				)
			)
		)
	)
	(zone
		(layers "B.Cu" "In11.Cu" "In13.Cu" "In15.Cu")
		(hatch none 0.5)
		(connect_pads
			(clearance 0)
		)
		(min_thickness 0.25)
		(keepout
			(tracks not_allowed)
			(vias allowed)
			(pads allowed)
			(copperpour not_allowed)
			(footprints allowed)
		)
		(placement
			(enabled no)
			(sheetname "")
		)
		(fill yes
			(thermal_gap 0.5)
			(thermal_bridge_width 0.5)
			(island_removal_mode 0)
		)
		(polygon
			(pts
				(arc
					(start 334.06969 -397.59001)
					(mid 333.31023 -397.59001)
					(end 334.06969 -397.59001)
				)
			)
		)
	)
	(zone
		(layers "B.Cu" "In11.Cu" "In13.Cu" "In15.Cu")
		(hatch none 0.5)
		(connect_pads
			(clearance 0)
		)
		(min_thickness 0.25)
		(keepout
			(tracks not_allowed)
			(vias allowed)
			(pads allowed)
			(copperpour not_allowed)
			(footprints allowed)
		)
		(placement
			(enabled no)
			(sheetname "")
		)
		(fill yes
			(thermal_gap 0.5)
			(thermal_bridge_width 0.5)
			(island_removal_mode 0)
		)
		(polygon
			(pts
				(arc
					(start 152.186894 -101.984302)
					(mid 151.483314 -101.984302)
					(end 152.186894 -101.984302)
				)
			)
		)
	)
	(zone
		(layers "B.Cu" "In11.Cu" "In13.Cu" "In15.Cu")
		(hatch none 0.5)
		(connect_pads
			(clearance 0)
		)
		(min_thickness 0.25)
		(keepout
			(tracks not_allowed)
			(vias allowed)
			(pads allowed)
			(copperpour not_allowed)
			(footprints allowed)
		)
		(placement
			(enabled no)
			(sheetname "")
		)
		(fill yes
			(thermal_gap 0.5)
			(thermal_bridge_width 0.5)
			(island_removal_mode 0)
		)
		(polygon
			(pts
				(arc
					(start 156.126434 -303.499774)
					(mid 155.473654 -303.499774)
					(end 156.126434 -303.499774)
				)
			)
		)
	)
	(zone
		(layers "B.Cu" "In11.Cu" "In13.Cu" "In15.Cu")
		(hatch none 0.5)
		(connect_pads
			(clearance 0)
		)
		(min_thickness 0.25)
		(keepout
			(tracks not_allowed)
			(vias allowed)
			(pads allowed)
			(copperpour not_allowed)
			(footprints allowed)
		)
		(placement
			(enabled no)
			(sheetname "")
		)
		(fill yes
			(thermal_gap 0.5)
			(thermal_bridge_width 0.5)
			(island_removal_mode 0)
		)
		(polygon
			(pts
				(arc
					(start 200.625964 -144.422114)
					(mid 199.922384 -144.422114)
					(end 200.625964 -144.422114)
				)
			)
		)
	)
	(zone
		(layers "B.Cu" "In11.Cu" "In13.Cu" "In15.Cu")
		(hatch none 0.5)
		(connect_pads
			(clearance 0)
		)
		(min_thickness 0.25)
		(keepout
			(tracks not_allowed)
			(vias allowed)
			(pads allowed)
			(copperpour not_allowed)
			(footprints allowed)
		)
		(placement
			(enabled no)
			(sheetname "")
		)
		(fill yes
			(thermal_gap 0.5)
			(thermal_bridge_width 0.5)
			(island_removal_mode 0)
		)
		(polygon
			(pts
				(arc
					(start 53.326284 -315.849762)
					(mid 52.673504 -315.849762)
					(end 53.326284 -315.849762)
				)
			)
		)
	)
	(zone
		(layers "B.Cu" "In11.Cu" "In13.Cu" "In15.Cu")
		(hatch none 0.5)
		(connect_pads
			(clearance 0)
		)
		(min_thickness 0.25)
		(keepout
			(tracks not_allowed)
			(vias allowed)
			(pads allowed)
			(copperpour not_allowed)
			(footprints allowed)
		)
		(placement
			(enabled no)
			(sheetname "")
		)
		(fill yes
			(thermal_gap 0.5)
			(thermal_bridge_width 0.5)
			(island_removal_mode 0)
		)
		(polygon
			(pts
				(arc
					(start 388.326376 -303.499774)
					(mid 387.673596 -303.499774)
					(end 388.326376 -303.499774)
				)
			)
		)
	)
	(zone
		(layers "B.Cu" "In11.Cu" "In13.Cu" "In15.Cu")
		(hatch none 0.5)
		(connect_pads
			(clearance 0)
		)
		(min_thickness 0.25)
		(keepout
			(tracks not_allowed)
			(vias allowed)
			(pads allowed)
			(copperpour not_allowed)
			(footprints allowed)
		)
		(placement
			(enabled no)
			(sheetname "")
		)
		(fill yes
			(thermal_gap 0.5)
			(thermal_bridge_width 0.5)
			(island_removal_mode 0)
		)
		(polygon
			(pts
				(arc
					(start 59.976258 -317.749936)
					(mid 59.323478 -317.749936)
					(end 59.976258 -317.749936)
				)
			)
		)
	)
	(zone
		(layers "B.Cu" "In11.Cu" "In13.Cu" "In15.Cu")
		(hatch none 0.5)
		(connect_pads
			(clearance 0)
		)
		(min_thickness 0.25)
		(keepout
			(tracks not_allowed)
			(vias allowed)
			(pads allowed)
			(copperpour not_allowed)
			(footprints allowed)
		)
		(placement
			(enabled no)
			(sheetname "")
		)
		(fill yes
			(thermal_gap 0.5)
			(thermal_bridge_width 0.5)
			(island_removal_mode 0)
		)
		(polygon
			(pts
				(arc
					(start 73.275952 -278.799798)
					(mid 72.623172 -278.799798)
					(end 73.275952 -278.799798)
				)
			)
		)
	)
	(zone
		(layers "B.Cu" "In11.Cu" "In13.Cu" "In15.Cu")
		(hatch none 0.5)
		(connect_pads
			(clearance 0)
		)
		(min_thickness 0.25)
		(keepout
			(tracks not_allowed)
			(vias allowed)
			(pads allowed)
			(copperpour not_allowed)
			(footprints allowed)
		)
		(placement
			(enabled no)
			(sheetname "")
		)
		(fill yes
			(thermal_gap 0.5)
			(thermal_bridge_width 0.5)
			(island_removal_mode 0)
		)
		(polygon
			(pts
				(arc
					(start 87.68969 -376.790204)
					(mid 86.93023 -376.790204)
					(end 87.68969 -376.790204)
				)
			)
		)
	)
	(zone
		(layers "B.Cu" "In11.Cu" "In13.Cu" "In15.Cu")
		(hatch none 0.5)
		(connect_pads
			(clearance 0)
		)
		(min_thickness 0.25)
		(keepout
			(tracks not_allowed)
			(vias allowed)
			(pads allowed)
			(copperpour not_allowed)
			(footprints allowed)
		)
		(placement
			(enabled no)
			(sheetname "")
		)
		(fill yes
			(thermal_gap 0.5)
			(thermal_bridge_width 0.5)
			(island_removal_mode 0)
		)
		(polygon
			(pts
				(arc
					(start 428.669704 -408.190192)
					(mid 427.910244 -408.190192)
					(end 428.669704 -408.190192)
				)
			)
		)
	)
	(zone
		(layers "B.Cu" "In11.Cu" "In13.Cu" "In15.Cu")
		(hatch none 0.5)
		(connect_pads
			(clearance 0)
		)
		(min_thickness 0.25)
		(keepout
			(tracks not_allowed)
			(vias allowed)
			(pads allowed)
			(copperpour not_allowed)
			(footprints allowed)
		)
		(placement
			(enabled no)
			(sheetname "")
		)
		(fill yes
			(thermal_gap 0.5)
			(thermal_bridge_width 0.5)
			(island_removal_mode 0)
		)
		(polygon
			(pts
				(arc
					(start 154.219402 -135.840724)
					(mid 153.515822 -135.840724)
					(end 154.219402 -135.840724)
				)
			)
		)
	)
	(zone
		(layers "B.Cu" "In11.Cu" "In13.Cu" "In15.Cu")
		(hatch none 0.5)
		(connect_pads
			(clearance 0)
		)
		(min_thickness 0.25)
		(keepout
			(tracks not_allowed)
			(vias allowed)
			(pads allowed)
			(copperpour not_allowed)
			(footprints allowed)
		)
		(placement
			(enabled no)
			(sheetname "")
		)
		(fill yes
			(thermal_gap 0.5)
			(thermal_bridge_width 0.5)
			(island_removal_mode 0)
		)
		(polygon
			(pts
				(arc
					(start 75.176126 -287.349946)
					(mid 74.523346 -287.349946)
					(end 75.176126 -287.349946)
				)
			)
		)
	)
	(zone
		(layers "B.Cu" "In11.Cu" "In13.Cu" "In15.Cu")
		(hatch none 0.5)
		(connect_pads
			(clearance 0)
		)
		(min_thickness 0.25)
		(keepout
			(tracks not_allowed)
			(vias allowed)
			(pads allowed)
			(copperpour not_allowed)
			(footprints allowed)
		)
		(placement
			(enabled no)
			(sheetname "")
		)
		(fill yes
			(thermal_gap 0.5)
			(thermal_bridge_width 0.5)
			(island_removal_mode 0)
		)
		(polygon
			(pts
				(arc
					(start 412.076138 -278.799798)
					(mid 411.423358 -278.799798)
					(end 412.076138 -278.799798)
				)
			)
		)
	)
	(zone
		(layers "B.Cu" "In11.Cu" "In13.Cu" "In15.Cu")
		(hatch none 0.5)
		(connect_pads
			(clearance 0)
		)
		(min_thickness 0.25)
		(keepout
			(tracks not_allowed)
			(vias allowed)
			(pads allowed)
			(copperpour not_allowed)
			(footprints allowed)
		)
		(placement
			(enabled no)
			(sheetname "")
		)
		(fill yes
			(thermal_gap 0.5)
			(thermal_bridge_width 0.5)
			(island_removal_mode 0)
		)
		(polygon
			(pts
				(arc
					(start 305.475894 -278.799798)
					(mid 304.823114 -278.799798)
					(end 305.475894 -278.799798)
				)
			)
		)
	)
	(zone
		(layers "B.Cu" "In11.Cu" "In13.Cu" "In15.Cu")
		(hatch none 0.5)
		(connect_pads
			(clearance 0)
		)
		(min_thickness 0.25)
		(keepout
			(tracks not_allowed)
			(vias allowed)
			(pads allowed)
			(copperpour not_allowed)
			(footprints allowed)
		)
		(placement
			(enabled no)
			(sheetname "")
		)
		(fill yes
			(thermal_gap 0.5)
			(thermal_bridge_width 0.5)
			(island_removal_mode 0)
		)
		(polygon
			(pts
				(arc
					(start 197.983856 -150.67915)
					(mid 197.280276 -150.67915)
					(end 197.983856 -150.67915)
				)
			)
		)
	)
	(zone
		(layers "B.Cu" "In11.Cu" "In13.Cu" "In15.Cu")
		(hatch none 0.5)
		(connect_pads
			(clearance 0)
		)
		(min_thickness 0.25)
		(keepout
			(tracks not_allowed)
			(vias allowed)
			(pads allowed)
			(copperpour not_allowed)
			(footprints allowed)
		)
		(placement
			(enabled no)
			(sheetname "")
		)
		(fill yes
			(thermal_gap 0.5)
			(thermal_bridge_width 0.5)
			(island_removal_mode 0)
		)
		(polygon
			(pts
				(arc
					(start 155.176474 -317.749936)
					(mid 154.523694 -317.749936)
					(end 155.176474 -317.749936)
				)
			)
		)
	)
	(zone
		(layers "B.Cu" "In11.Cu" "In13.Cu" "In15.Cu")
		(hatch none 0.5)
		(connect_pads
			(clearance 0)
		)
		(min_thickness 0.25)
		(keepout
			(tracks not_allowed)
			(vias allowed)
			(pads allowed)
			(copperpour not_allowed)
			(footprints allowed)
		)
		(placement
			(enabled no)
			(sheetname "")
		)
		(fill yes
			(thermal_gap 0.5)
			(thermal_bridge_width 0.5)
			(island_removal_mode 0)
		)
		(polygon
			(pts
				(arc
					(start 61.875924 -277.849838)
					(mid 61.223144 -277.849838)
					(end 61.875924 -277.849838)
				)
			)
		)
	)
	(zone
		(layers "B.Cu" "In11.Cu" "In13.Cu" "In15.Cu")
		(hatch none 0.5)
		(connect_pads
			(clearance 0)
		)
		(min_thickness 0.25)
		(keepout
			(tracks not_allowed)
			(vias allowed)
			(pads allowed)
			(copperpour not_allowed)
			(footprints allowed)
		)
		(placement
			(enabled no)
			(sheetname "")
		)
		(fill yes
			(thermal_gap 0.5)
			(thermal_bridge_width 0.5)
			(island_removal_mode 0)
		)
		(polygon
			(pts
				(arc
					(start 197.983856 -149.81555)
					(mid 197.280276 -149.81555)
					(end 197.983856 -149.81555)
				)
			)
		)
	)
	(zone
		(layers "B.Cu" "In11.Cu" "In13.Cu" "In15.Cu")
		(hatch none 0.5)
		(connect_pads
			(clearance 0)
		)
		(min_thickness 0.25)
		(keepout
			(tracks not_allowed)
			(vias allowed)
			(pads allowed)
			(copperpour not_allowed)
			(footprints allowed)
		)
		(placement
			(enabled no)
			(sheetname "")
		)
		(fill yes
			(thermal_gap 0.5)
			(thermal_bridge_width 0.5)
			(island_removal_mode 0)
		)
		(polygon
			(pts
				(arc
					(start 426.3263 -286.399986)
					(mid 425.67352 -286.399986)
					(end 426.3263 -286.399986)
				)
			)
		)
	)
	(zone
		(layers "B.Cu" "In11.Cu" "In13.Cu" "In15.Cu")
		(hatch none 0.5)
		(connect_pads
			(clearance 0)
		)
		(min_thickness 0.25)
		(keepout
			(tracks not_allowed)
			(vias allowed)
			(pads allowed)
			(copperpour not_allowed)
			(footprints allowed)
		)
		(placement
			(enabled no)
			(sheetname "")
		)
		(fill yes
			(thermal_gap 0.5)
			(thermal_bridge_width 0.5)
			(island_removal_mode 0)
		)
		(polygon
			(pts
				(arc
					(start 270.3195 -106.514138)
					(mid 269.61592 -106.514138)
					(end 270.3195 -106.514138)
				)
			)
		)
	)
	(zone
		(layers "B.Cu" "In11.Cu" "In13.Cu" "In15.Cu")
		(hatch none 0.5)
		(connect_pads
			(clearance 0)
		)
		(min_thickness 0.25)
		(keepout
			(tracks not_allowed)
			(vias allowed)
			(pads allowed)
			(copperpour not_allowed)
			(footprints allowed)
		)
		(placement
			(enabled no)
			(sheetname "")
		)
		(fill yes
			(thermal_gap 0.5)
			(thermal_bridge_width 0.5)
			(island_removal_mode 0)
		)
		(polygon
			(pts
				(arc
					(start 197.983856 -154.279346)
					(mid 197.280276 -154.279346)
					(end 197.983856 -154.279346)
				)
			)
		)
	)
	(zone
		(layers "B.Cu" "In11.Cu" "In13.Cu" "In15.Cu")
		(hatch none 0.5)
		(connect_pads
			(clearance 0)
		)
		(min_thickness 0.25)
		(keepout
			(tracks not_allowed)
			(vias allowed)
			(pads allowed)
			(copperpour not_allowed)
			(footprints allowed)
		)
		(placement
			(enabled no)
			(sheetname "")
		)
		(fill yes
			(thermal_gap 0.5)
			(thermal_bridge_width 0.5)
			(island_removal_mode 0)
		)
		(polygon
			(pts
				(arc
					(start 287.426146 -315.849762)
					(mid 286.773366 -315.849762)
					(end 287.426146 -315.849762)
				)
			)
		)
	)
	(zone
		(layers "B.Cu" "In11.Cu" "In13.Cu" "In15.Cu")
		(hatch none 0.5)
		(connect_pads
			(clearance 0)
		)
		(min_thickness 0.25)
		(keepout
			(tracks not_allowed)
			(vias allowed)
			(pads allowed)
			(copperpour not_allowed)
			(footprints allowed)
		)
		(placement
			(enabled no)
			(sheetname "")
		)
		(fill yes
			(thermal_gap 0.5)
			(thermal_bridge_width 0.5)
			(island_removal_mode 0)
		)
		(polygon
			(pts
				(arc
					(start 156.126434 -307.299868)
					(mid 155.473654 -307.299868)
					(end 156.126434 -307.299868)
				)
			)
		)
	)
	(zone
		(layers "B.Cu" "In11.Cu" "In13.Cu" "In15.Cu")
		(hatch none 0.5)
		(connect_pads
			(clearance 0)
		)
		(min_thickness 0.25)
		(keepout
			(tracks not_allowed)
			(vias allowed)
			(pads allowed)
			(copperpour not_allowed)
			(footprints allowed)
		)
		(placement
			(enabled no)
			(sheetname "")
		)
		(fill yes
			(thermal_gap 0.5)
			(thermal_bridge_width 0.5)
			(island_removal_mode 0)
		)
		(polygon
			(pts
				(arc
					(start 331.869796 -374.390158)
					(mid 331.110336 -374.390158)
					(end 331.869796 -374.390158)
				)
			)
		)
	)
	(zone
		(layers "B.Cu" "In11.Cu" "In13.Cu" "In15.Cu")
		(hatch none 0.5)
		(connect_pads
			(clearance 0)
		)
		(min_thickness 0.25)
		(keepout
			(tracks not_allowed)
			(vias allowed)
			(pads allowed)
			(copperpour not_allowed)
			(footprints allowed)
		)
		(placement
			(enabled no)
			(sheetname "")
		)
		(fill yes
			(thermal_gap 0.5)
			(thermal_bridge_width 0.5)
			(island_removal_mode 0)
		)
		(polygon
			(pts
				(arc
					(start 76.689712 -396.49019)
					(mid 75.930252 -396.49019)
					(end 76.689712 -396.49019)
				)
			)
		)
	)
	(zone
		(layers "B.Cu" "In11.Cu" "In13.Cu" "In15.Cu")
		(hatch none 0.5)
		(connect_pads
			(clearance 0)
		)
		(min_thickness 0.25)
		(keepout
			(tracks not_allowed)
			(vias allowed)
			(pads allowed)
			(copperpour not_allowed)
			(footprints allowed)
		)
		(placement
			(enabled no)
			(sheetname "")
		)
		(fill yes
			(thermal_gap 0.5)
			(thermal_bridge_width 0.5)
			(island_removal_mode 0)
		)
		(polygon
			(pts
				(arc
					(start 62.826138 -315.849762)
					(mid 62.173358 -315.849762)
					(end 62.826138 -315.849762)
				)
			)
		)
	)
	(zone
		(layers "B.Cu" "In11.Cu" "In13.Cu" "In15.Cu")
		(hatch none 0.5)
		(connect_pads
			(clearance 0)
		)
		(min_thickness 0.25)
		(keepout
			(tracks not_allowed)
			(vias allowed)
			(pads allowed)
			(copperpour not_allowed)
			(footprints allowed)
		)
		(placement
			(enabled no)
			(sheetname "")
		)
		(fill yes
			(thermal_gap 0.5)
			(thermal_bridge_width 0.5)
			(island_removal_mode 0)
		)
		(polygon
			(pts
				(arc
					(start 188.426344 -280.699718)
					(mid 187.773564 -280.699718)
					(end 188.426344 -280.699718)
				)
			)
		)
	)
	(zone
		(layers "B.Cu" "In11.Cu" "In13.Cu" "In15.Cu")
		(hatch none 0.5)
		(connect_pads
			(clearance 0)
		)
		(min_thickness 0.25)
		(keepout
			(tracks not_allowed)
			(vias allowed)
			(pads allowed)
			(copperpour not_allowed)
			(footprints allowed)
		)
		(placement
			(enabled no)
			(sheetname "")
		)
		(fill yes
			(thermal_gap 0.5)
			(thermal_bridge_width 0.5)
			(island_removal_mode 0)
		)
		(polygon
			(pts
				(arc
					(start 187.47613 -277.849838)
					(mid 186.82335 -277.849838)
					(end 187.47613 -277.849838)
				)
			)
		)
	)
	(zone
		(layers "B.Cu" "In11.Cu" "In13.Cu" "In15.Cu")
		(hatch none 0.5)
		(connect_pads
			(clearance 0)
		)
		(min_thickness 0.25)
		(keepout
			(tracks not_allowed)
			(vias allowed)
			(pads allowed)
			(copperpour not_allowed)
			(footprints allowed)
		)
		(placement
			(enabled no)
			(sheetname "")
		)
		(fill yes
			(thermal_gap 0.5)
			(thermal_bridge_width 0.5)
			(island_removal_mode 0)
		)
		(polygon
			(pts
				(arc
					(start 340.66988 -396.49019)
					(mid 339.91042 -396.49019)
					(end 340.66988 -396.49019)
				)
			)
		)
	)
	(zone
		(layers "B.Cu" "In11.Cu" "In13.Cu" "In15.Cu")
		(hatch none 0.5)
		(connect_pads
			(clearance 0)
		)
		(min_thickness 0.25)
		(keepout
			(tracks not_allowed)
			(vias allowed)
			(pads allowed)
			(copperpour not_allowed)
			(footprints allowed)
		)
		(placement
			(enabled no)
			(sheetname "")
		)
		(fill yes
			(thermal_gap 0.5)
			(thermal_bridge_width 0.5)
			(island_removal_mode 0)
		)
		(polygon
			(pts
				(arc
					(start 284.576266 -318.699896)
					(mid 283.923486 -318.699896)
					(end 284.576266 -318.699896)
				)
			)
		)
	)
	(zone
		(layers "B.Cu" "In11.Cu" "In13.Cu" "In15.Cu")
		(hatch none 0.5)
		(connect_pads
			(clearance 0)
		)
		(min_thickness 0.25)
		(keepout
			(tracks not_allowed)
			(vias allowed)
			(pads allowed)
			(copperpour not_allowed)
			(footprints allowed)
		)
		(placement
			(enabled no)
			(sheetname "")
		)
		(fill yes
			(thermal_gap 0.5)
			(thermal_bridge_width 0.5)
			(island_removal_mode 0)
		)
		(polygon
			(pts
				(arc
					(start 75.176126 -285.449772)
					(mid 74.523346 -285.449772)
					(end 75.176126 -285.449772)
				)
			)
		)
	)
	(zone
		(layers "B.Cu" "In11.Cu" "In13.Cu" "In15.Cu")
		(hatch none 0.5)
		(connect_pads
			(clearance 0)
		)
		(min_thickness 0.25)
		(keepout
			(tracks not_allowed)
			(vias allowed)
			(pads allowed)
			(copperpour not_allowed)
			(footprints allowed)
		)
		(placement
			(enabled no)
			(sheetname "")
		)
		(fill yes
			(thermal_gap 0.5)
			(thermal_bridge_width 0.5)
			(island_removal_mode 0)
		)
		(polygon
			(pts
				(arc
					(start 160.289748 -409.490164)
					(mid 159.530288 -409.490164)
					(end 160.289748 -409.490164)
				)
			)
		)
	)
	(zone
		(layers "B.Cu" "In11.Cu" "In13.Cu" "In15.Cu")
		(hatch none 0.5)
		(connect_pads
			(clearance 0)
		)
		(min_thickness 0.25)
		(keepout
			(tracks not_allowed)
			(vias allowed)
			(pads allowed)
			(copperpour not_allowed)
			(footprints allowed)
		)
		(placement
			(enabled no)
			(sheetname "")
		)
		(fill yes
			(thermal_gap 0.5)
			(thermal_bridge_width 0.5)
			(island_removal_mode 0)
		)
		(polygon
			(pts
				(arc
					(start 38.119558 -100.177854)
					(mid 37.415978 -100.177854)
					(end 38.119558 -100.177854)
				)
			)
		)
	)
	(zone
		(layers "B.Cu" "In11.Cu" "In13.Cu" "In15.Cu")
		(hatch none 0.5)
		(connect_pads
			(clearance 0)
		)
		(min_thickness 0.25)
		(keepout
			(tracks not_allowed)
			(vias allowed)
			(pads allowed)
			(copperpour not_allowed)
			(footprints allowed)
		)
		(placement
			(enabled no)
			(sheetname "")
		)
		(fill yes
			(thermal_gap 0.5)
			(thermal_bridge_width 0.5)
			(island_removal_mode 0)
		)
		(polygon
			(pts
				(arc
					(start 290.27628 -318.699896)
					(mid 289.6235 -318.699896)
					(end 290.27628 -318.699896)
				)
			)
		)
	)
	(zone
		(layers "B.Cu" "In11.Cu" "In13.Cu" "In15.Cu")
		(hatch none 0.5)
		(connect_pads
			(clearance 0)
		)
		(min_thickness 0.25)
		(keepout
			(tracks not_allowed)
			(vias allowed)
			(pads allowed)
			(copperpour not_allowed)
			(footprints allowed)
		)
		(placement
			(enabled no)
			(sheetname "")
		)
		(fill yes
			(thermal_gap 0.5)
			(thermal_bridge_width 0.5)
			(island_removal_mode 0)
		)
		(polygon
			(pts
				(arc
					(start 387.376416 -318.699896)
					(mid 386.723636 -318.699896)
					(end 387.376416 -318.699896)
				)
			)
		)
	)
	(zone
		(layers "B.Cu" "In11.Cu" "In13.Cu" "In15.Cu")
		(hatch none 0.5)
		(connect_pads
			(clearance 0)
		)
		(min_thickness 0.25)
		(keepout
			(tracks not_allowed)
			(vias allowed)
			(pads allowed)
			(copperpour not_allowed)
			(footprints allowed)
		)
		(placement
			(enabled no)
			(sheetname "")
		)
		(fill yes
			(thermal_gap 0.5)
			(thermal_bridge_width 0.5)
			(island_removal_mode 0)
		)
		(polygon
			(pts
				(arc
					(start 432.82616 -131.712208)
					(mid 432.12258 -131.712208)
					(end 432.82616 -131.712208)
				)
			)
		)
	)
	(zone
		(layers "B.Cu" "In11.Cu" "In13.Cu" "In15.Cu")
		(hatch none 0.5)
		(connect_pads
			(clearance 0)
		)
		(min_thickness 0.25)
		(keepout
			(tracks not_allowed)
			(vias allowed)
			(pads allowed)
			(copperpour not_allowed)
			(footprints allowed)
		)
		(placement
			(enabled no)
			(sheetname "")
		)
		(fill yes
			(thermal_gap 0.5)
			(thermal_bridge_width 0.5)
			(island_removal_mode 0)
		)
		(polygon
			(pts
				(arc
					(start 169.089832 -383.490216)
					(mid 168.330372 -383.490216)
					(end 169.089832 -383.490216)
				)
			)
		)
	)
	(zone
		(layers "B.Cu" "In11.Cu" "In13.Cu" "In15.Cu")
		(hatch none 0.5)
		(connect_pads
			(clearance 0)
		)
		(min_thickness 0.25)
		(keepout
			(tracks not_allowed)
			(vias allowed)
			(pads allowed)
			(copperpour not_allowed)
			(footprints allowed)
		)
		(placement
			(enabled no)
			(sheetname "")
		)
		(fill yes
			(thermal_gap 0.5)
			(thermal_bridge_width 0.5)
			(island_removal_mode 0)
		)
		(polygon
			(pts
				(arc
					(start 77.0763 -282.599892)
					(mid 76.42352 -282.599892)
					(end 77.0763 -282.599892)
				)
			)
		)
	)
	(zone
		(layers "B.Cu" "In11.Cu" "In13.Cu" "In15.Cu")
		(hatch none 0.5)
		(connect_pads
			(clearance 0)
		)
		(min_thickness 0.25)
		(keepout
			(tracks not_allowed)
			(vias allowed)
			(pads allowed)
			(copperpour not_allowed)
			(footprints allowed)
		)
		(placement
			(enabled no)
			(sheetname "")
		)
		(fill yes
			(thermal_gap 0.5)
			(thermal_bridge_width 0.5)
			(island_removal_mode 0)
		)
		(polygon
			(pts
				(arc
					(start 342.869774 -397.59001)
					(mid 342.110314 -397.59001)
					(end 342.869774 -397.59001)
				)
			)
		)
	)
	(zone
		(layers "B.Cu" "In11.Cu" "In13.Cu" "In15.Cu")
		(hatch none 0.5)
		(connect_pads
			(clearance 0)
		)
		(min_thickness 0.25)
		(keepout
			(tracks not_allowed)
			(vias allowed)
			(pads allowed)
			(copperpour not_allowed)
			(footprints allowed)
		)
		(placement
			(enabled no)
			(sheetname "")
		)
		(fill yes
			(thermal_gap 0.5)
			(thermal_bridge_width 0.5)
			(island_removal_mode 0)
		)
		(polygon
			(pts
				(arc
					(start 419.86962 -409.490164)
					(mid 419.11016 -409.490164)
					(end 419.86962 -409.490164)
				)
			)
		)
	)
	(zone
		(layers "B.Cu" "In11.Cu" "In13.Cu" "In15.Cu")
		(hatch none 0.5)
		(connect_pads
			(clearance 0)
		)
		(min_thickness 0.25)
		(keepout
			(tracks not_allowed)
			(vias allowed)
			(pads allowed)
			(copperpour not_allowed)
			(footprints allowed)
		)
		(placement
			(enabled no)
			(sheetname "")
		)
		(fill yes
			(thermal_gap 0.5)
			(thermal_bridge_width 0.5)
			(island_removal_mode 0)
		)
		(polygon
			(pts
				(arc
					(start 171.289726 -384.590036)
					(mid 170.530266 -384.590036)
					(end 171.289726 -384.590036)
				)
			)
		)
	)
	(zone
		(layers "B.Cu" "In11.Cu" "In13.Cu" "In15.Cu")
		(hatch none 0.5)
		(connect_pads
			(clearance 0)
		)
		(min_thickness 0.25)
		(keepout
			(tracks not_allowed)
			(vias allowed)
			(pads allowed)
			(copperpour not_allowed)
			(footprints allowed)
		)
		(placement
			(enabled no)
			(sheetname "")
		)
		(fill yes
			(thermal_gap 0.5)
			(thermal_bridge_width 0.5)
			(island_removal_mode 0)
		)
		(polygon
			(pts
				(arc
					(start 196.976238 -277.849838)
					(mid 196.323458 -277.849838)
					(end 196.976238 -277.849838)
				)
			)
		)
	)
	(zone
		(layers "B.Cu" "In11.Cu" "In13.Cu" "In15.Cu")
		(hatch none 0.5)
		(connect_pads
			(clearance 0)
		)
		(min_thickness 0.25)
		(keepout
			(tracks not_allowed)
			(vias allowed)
			(pads allowed)
			(copperpour not_allowed)
			(footprints allowed)
		)
		(placement
			(enabled no)
			(sheetname "")
		)
		(fill yes
			(thermal_gap 0.5)
			(thermal_bridge_width 0.5)
			(island_removal_mode 0)
		)
		(polygon
			(pts
				(arc
					(start 59.026298 -315.849762)
					(mid 58.373518 -315.849762)
					(end 59.026298 -315.849762)
				)
			)
		)
	)
	(zone
		(layers "B.Cu" "In11.Cu" "In13.Cu" "In15.Cu")
		(hatch none 0.5)
		(connect_pads
			(clearance 0)
		)
		(min_thickness 0.25)
		(keepout
			(tracks not_allowed)
			(vias allowed)
			(pads allowed)
			(copperpour not_allowed)
			(footprints allowed)
		)
		(placement
			(enabled no)
			(sheetname "")
		)
		(fill yes
			(thermal_gap 0.5)
			(thermal_bridge_width 0.5)
			(island_removal_mode 0)
		)
		(polygon
			(pts
				(arc
					(start 160.289748 -383.490216)
					(mid 159.530288 -383.490216)
					(end 160.289748 -383.490216)
				)
			)
		)
	)
	(zone
		(layers "B.Cu" "In11.Cu" "In13.Cu" "In15.Cu")
		(hatch none 0.5)
		(connect_pads
			(clearance 0)
		)
		(min_thickness 0.25)
		(keepout
			(tracks not_allowed)
			(vias allowed)
			(pads allowed)
			(copperpour not_allowed)
			(footprints allowed)
		)
		(placement
			(enabled no)
			(sheetname "")
		)
		(fill yes
			(thermal_gap 0.5)
			(thermal_bridge_width 0.5)
			(island_removal_mode 0)
		)
		(polygon
			(pts
				(arc
					(start 151.577294 -111.920782)
					(mid 150.873714 -111.920782)
					(end 151.577294 -111.920782)
				)
			)
		)
	)
	(zone
		(layers "B.Cu" "In11.Cu" "In13.Cu" "In15.Cu")
		(hatch none 0.5)
		(connect_pads
			(clearance 0)
		)
		(min_thickness 0.25)
		(keepout
			(tracks not_allowed)
			(vias allowed)
			(pads allowed)
			(copperpour not_allowed)
			(footprints allowed)
		)
		(placement
			(enabled no)
			(sheetname "")
		)
		(fill yes
			(thermal_gap 0.5)
			(thermal_bridge_width 0.5)
			(island_removal_mode 0)
		)
		(polygon
			(pts
				(arc
					(start 426.469556 -383.290064)
					(mid 425.710096 -383.290064)
					(end 426.469556 -383.290064)
				)
			)
		)
	)
	(zone
		(layers "B.Cu" "In11.Cu" "In13.Cu" "In15.Cu")
		(hatch none 0.5)
		(connect_pads
			(clearance 0)
		)
		(min_thickness 0.25)
		(keepout
			(tracks not_allowed)
			(vias allowed)
			(pads allowed)
			(copperpour not_allowed)
			(footprints allowed)
		)
		(placement
			(enabled no)
			(sheetname "")
		)
		(fill yes
			(thermal_gap 0.5)
			(thermal_bridge_width 0.5)
			(island_removal_mode 0)
		)
		(polygon
			(pts
				(arc
					(start 38.119558 -121.030746)
					(mid 37.415978 -121.030746)
					(end 38.119558 -121.030746)
				)
			)
		)
	)
	(zone
		(layers "B.Cu" "In11.Cu" "In13.Cu" "In15.Cu")
		(hatch none 0.5)
		(connect_pads
			(clearance 0)
		)
		(min_thickness 0.25)
		(keepout
			(tracks not_allowed)
			(vias allowed)
			(pads allowed)
			(copperpour not_allowed)
			(footprints allowed)
		)
		(placement
			(enabled no)
			(sheetname "")
		)
		(fill yes
			(thermal_gap 0.5)
			(thermal_bridge_width 0.5)
			(island_removal_mode 0)
		)
		(polygon
			(pts
				(arc
					(start 305.475894 -277.849838)
					(mid 304.823114 -277.849838)
					(end 305.475894 -277.849838)
				)
			)
		)
	)
	(zone
		(layers "B.Cu" "In11.Cu" "In13.Cu" "In15.Cu")
		(hatch none 0.5)
		(connect_pads
			(clearance 0)
		)
		(min_thickness 0.25)
		(keepout
			(tracks not_allowed)
			(vias allowed)
			(pads allowed)
			(copperpour not_allowed)
			(footprints allowed)
		)
		(placement
			(enabled no)
			(sheetname "")
		)
		(fill yes
			(thermal_gap 0.5)
			(thermal_bridge_width 0.5)
			(island_removal_mode 0)
		)
		(polygon
			(pts
				(arc
					(start 430.184052 -123.159266)
					(mid 429.480472 -123.159266)
					(end 430.184052 -123.159266)
				)
			)
		)
	)
	(zone
		(layers "B.Cu" "In11.Cu" "In13.Cu" "In15.Cu")
		(hatch none 0.5)
		(connect_pads
			(clearance 0)
		)
		(min_thickness 0.25)
		(keepout
			(tracks not_allowed)
			(vias allowed)
			(pads allowed)
			(copperpour not_allowed)
			(footprints allowed)
		)
		(placement
			(enabled no)
			(sheetname "")
		)
		(fill yes
			(thermal_gap 0.5)
			(thermal_bridge_width 0.5)
			(island_removal_mode 0)
		)
		(polygon
			(pts
				(arc
					(start 154.219402 -100.177854)
					(mid 153.515822 -100.177854)
					(end 154.219402 -100.177854)
				)
			)
		)
	)
	(zone
		(layers "B.Cu" "In11.Cu" "In13.Cu" "In15.Cu")
		(hatch none 0.5)
		(connect_pads
			(clearance 0)
		)
		(min_thickness 0.25)
		(keepout
			(tracks not_allowed)
			(vias allowed)
			(pads allowed)
			(copperpour not_allowed)
			(footprints allowed)
		)
		(placement
			(enabled no)
			(sheetname "")
		)
		(fill yes
			(thermal_gap 0.5)
			(thermal_bridge_width 0.5)
			(island_removal_mode 0)
		)
		(polygon
			(pts
				(arc
					(start 67.575938 -277.849838)
					(mid 66.923158 -277.849838)
					(end 67.575938 -277.849838)
				)
			)
		)
	)
	(zone
		(layers "B.Cu" "In11.Cu" "In13.Cu" "In15.Cu")
		(hatch none 0.5)
		(connect_pads
			(clearance 0)
		)
		(min_thickness 0.25)
		(keepout
			(tracks not_allowed)
			(vias allowed)
			(pads allowed)
			(copperpour not_allowed)
			(footprints allowed)
		)
		(placement
			(enabled no)
			(sheetname "")
		)
		(fill yes
			(thermal_gap 0.5)
			(thermal_bridge_width 0.5)
			(island_removal_mode 0)
		)
		(polygon
			(pts
				(arc
					(start 84.52612 -135.31215)
					(mid 83.82254 -135.31215)
					(end 84.52612 -135.31215)
				)
			)
		)
	)
	(zone
		(layers "B.Cu" "In11.Cu" "In13.Cu" "In15.Cu")
		(hatch none 0.5)
		(connect_pads
			(clearance 0)
		)
		(min_thickness 0.25)
		(keepout
			(tracks not_allowed)
			(vias allowed)
			(pads allowed)
			(copperpour not_allowed)
			(footprints allowed)
		)
		(placement
			(enabled no)
			(sheetname "")
		)
		(fill yes
			(thermal_gap 0.5)
			(thermal_bridge_width 0.5)
			(island_removal_mode 0)
		)
		(polygon
			(pts
				(arc
					(start 154.219402 -121.894346)
					(mid 153.515822 -121.894346)
					(end 154.219402 -121.894346)
				)
			)
		)
	)
	(zone
		(layers "B.Cu" "In11.Cu" "In13.Cu" "In15.Cu")
		(hatch none 0.5)
		(connect_pads
			(clearance 0)
		)
		(min_thickness 0.25)
		(keepout
			(tracks not_allowed)
			(vias allowed)
			(pads allowed)
			(copperpour not_allowed)
			(footprints allowed)
		)
		(placement
			(enabled no)
			(sheetname "")
		)
		(fill yes
			(thermal_gap 0.5)
			(thermal_bridge_width 0.5)
			(island_removal_mode 0)
		)
		(polygon
			(pts
				(arc
					(start 52.376324 -318.699896)
					(mid 51.723544 -318.699896)
					(end 52.376324 -318.699896)
				)
			)
		)
	)
	(zone
		(layers "B.Cu" "In11.Cu" "In13.Cu" "In15.Cu")
		(hatch none 0.5)
		(connect_pads
			(clearance 0)
		)
		(min_thickness 0.25)
		(keepout
			(tracks not_allowed)
			(vias allowed)
			(pads allowed)
			(copperpour not_allowed)
			(footprints allowed)
		)
		(placement
			(enabled no)
			(sheetname "")
		)
		(fill yes
			(thermal_gap 0.5)
			(thermal_bridge_width 0.5)
			(island_removal_mode 0)
		)
		(polygon
			(pts
				(arc
					(start 311.175908 -278.799798)
					(mid 310.523128 -278.799798)
					(end 311.175908 -278.799798)
				)
			)
		)
	)
	(zone
		(layers "B.Cu" "In11.Cu" "In13.Cu" "In15.Cu")
		(hatch none 0.5)
		(connect_pads
			(clearance 0)
		)
		(min_thickness 0.25)
		(keepout
			(tracks not_allowed)
			(vias allowed)
			(pads allowed)
			(copperpour not_allowed)
			(footprints allowed)
		)
		(placement
			(enabled no)
			(sheetname "")
		)
		(fill yes
			(thermal_gap 0.5)
			(thermal_bridge_width 0.5)
			(island_removal_mode 0)
		)
		(polygon
			(pts
				(arc
					(start 153.2763 -308.249828)
					(mid 152.62352 -308.249828)
					(end 153.2763 -308.249828)
				)
			)
		)
	)
	(zone
		(layers "B.Cu" "In11.Cu" "In13.Cu" "In15.Cu")
		(hatch none 0.5)
		(connect_pads
			(clearance 0)
		)
		(min_thickness 0.25)
		(keepout
			(tracks not_allowed)
			(vias allowed)
			(pads allowed)
			(copperpour not_allowed)
			(footprints allowed)
		)
		(placement
			(enabled no)
			(sheetname "")
		)
		(fill yes
			(thermal_gap 0.5)
			(thermal_bridge_width 0.5)
			(island_removal_mode 0)
		)
		(polygon
			(pts
				(arc
					(start 52.376324 -317.749936)
					(mid 51.723544 -317.749936)
					(end 52.376324 -317.749936)
				)
			)
		)
	)
	(zone
		(layers "B.Cu" "In11.Cu" "In13.Cu" "In15.Cu")
		(hatch none 0.5)
		(connect_pads
			(clearance 0)
		)
		(min_thickness 0.25)
		(keepout
			(tracks not_allowed)
			(vias allowed)
			(pads allowed)
			(copperpour not_allowed)
			(footprints allowed)
		)
		(placement
			(enabled no)
			(sheetname "")
		)
		(fill yes
			(thermal_gap 0.5)
			(thermal_bridge_width 0.5)
			(island_removal_mode 0)
		)
		(polygon
			(pts
				(arc
					(start 59.976004 -277.849838)
					(mid 59.323224 -277.849838)
					(end 59.976004 -277.849838)
				)
			)
		)
	)
	(zone
		(layers "B.Cu" "In11.Cu" "In13.Cu" "In15.Cu")
		(hatch none 0.5)
		(connect_pads
			(clearance 0)
		)
		(min_thickness 0.25)
		(keepout
			(tracks not_allowed)
			(vias allowed)
			(pads allowed)
			(copperpour not_allowed)
			(footprints allowed)
		)
		(placement
			(enabled no)
			(sheetname "")
		)
		(fill yes
			(thermal_gap 0.5)
			(thermal_bridge_width 0.5)
			(island_removal_mode 0)
		)
		(polygon
			(pts
				(arc
					(start 306.426108 -279.749504)
					(mid 305.773328 -279.749504)
					(end 306.426108 -279.749504)
				)
			)
		)
	)
	(zone
		(layers "B.Cu" "In11.Cu" "In13.Cu" "In15.Cu")
		(hatch none 0.5)
		(connect_pads
			(clearance 0)
		)
		(min_thickness 0.25)
		(keepout
			(tracks not_allowed)
			(vias allowed)
			(pads allowed)
			(copperpour not_allowed)
			(footprints allowed)
		)
		(placement
			(enabled no)
			(sheetname "")
		)
		(fill yes
			(thermal_gap 0.5)
			(thermal_bridge_width 0.5)
			(island_removal_mode 0)
		)
		(polygon
			(pts
				(arc
					(start 35.47745 -123.68784)
					(mid 34.77387 -123.68784)
					(end 35.47745 -123.68784)
				)
			)
		)
	)
	(zone
		(layers "B.Cu" "In11.Cu" "In13.Cu" "In15.Cu")
		(hatch none 0.5)
		(connect_pads
			(clearance 0)
		)
		(min_thickness 0.25)
		(keepout
			(tracks not_allowed)
			(vias allowed)
			(pads allowed)
			(copperpour not_allowed)
			(footprints allowed)
		)
		(placement
			(enabled no)
			(sheetname "")
		)
		(fill yes
			(thermal_gap 0.5)
			(thermal_bridge_width 0.5)
			(island_removal_mode 0)
		)
		(polygon
			(pts
				(arc
					(start 198.876412 -276.899878)
					(mid 198.223632 -276.899878)
					(end 198.876412 -276.899878)
				)
			)
		)
	)
	(zone
		(layers "B.Cu" "In11.Cu" "In13.Cu" "In15.Cu")
		(hatch none 0.5)
		(connect_pads
			(clearance 0)
		)
		(min_thickness 0.25)
		(keepout
			(tracks not_allowed)
			(vias allowed)
			(pads allowed)
			(copperpour not_allowed)
			(footprints allowed)
		)
		(placement
			(enabled no)
			(sheetname "")
		)
		(fill yes
			(thermal_gap 0.5)
			(thermal_bridge_width 0.5)
			(island_removal_mode 0)
		)
		(polygon
			(pts
				(arc
					(start 427.276006 -278.799798)
					(mid 426.623226 -278.799798)
					(end 427.276006 -278.799798)
				)
			)
		)
	)
	(zone
		(layers "B.Cu" "In11.Cu" "In13.Cu" "In15.Cu")
		(hatch none 0.5)
		(connect_pads
			(clearance 0)
		)
		(min_thickness 0.25)
		(keepout
			(tracks not_allowed)
			(vias allowed)
			(pads allowed)
			(copperpour not_allowed)
			(footprints allowed)
		)
		(placement
			(enabled no)
			(sheetname "")
		)
		(fill yes
			(thermal_gap 0.5)
			(thermal_bridge_width 0.5)
			(island_removal_mode 0)
		)
		(polygon
			(pts
				(arc
					(start 51.426364 -316.799722)
					(mid 50.773584 -316.799722)
					(end 51.426364 -316.799722)
				)
			)
		)
	)
	(zone
		(layers "B.Cu" "In11.Cu" "In13.Cu" "In15.Cu")
		(hatch none 0.5)
		(connect_pads
			(clearance 0)
		)
		(min_thickness 0.25)
		(keepout
			(tracks not_allowed)
			(vias allowed)
			(pads allowed)
			(copperpour not_allowed)
			(footprints allowed)
		)
		(placement
			(enabled no)
			(sheetname "")
		)
		(fill yes
			(thermal_gap 0.5)
			(thermal_bridge_width 0.5)
			(island_removal_mode 0)
		)
		(polygon
			(pts
				(arc
					(start 78.02626 -286.399986)
					(mid 77.37348 -286.399986)
					(end 78.02626 -286.399986)
				)
			)
		)
	)
	(zone
		(layers "B.Cu" "In11.Cu" "In13.Cu" "In15.Cu")
		(hatch none 0.5)
		(connect_pads
			(clearance 0)
		)
		(min_thickness 0.25)
		(keepout
			(tracks not_allowed)
			(vias allowed)
			(pads allowed)
			(copperpour not_allowed)
			(footprints allowed)
		)
		(placement
			(enabled no)
			(sheetname "")
		)
		(fill yes
			(thermal_gap 0.5)
			(thermal_bridge_width 0.5)
			(island_removal_mode 0)
		)
		(polygon
			(pts
				(arc
					(start 386.419598 -99.314254)
					(mid 385.716018 -99.314254)
					(end 386.419598 -99.314254)
				)
			)
		)
	)
	(zone
		(layers "B.Cu" "In11.Cu" "In13.Cu" "In15.Cu")
		(hatch none 0.5)
		(connect_pads
			(clearance 0)
		)
		(min_thickness 0.25)
		(keepout
			(tracks not_allowed)
			(vias allowed)
			(pads allowed)
			(copperpour not_allowed)
			(footprints allowed)
		)
		(placement
			(enabled no)
			(sheetname "")
		)
		(fill yes
			(thermal_gap 0.5)
			(thermal_bridge_width 0.5)
			(island_removal_mode 0)
		)
		(polygon
			(pts
				(arc
					(start 308.326282 -279.749504)
					(mid 307.673502 -279.749504)
					(end 308.326282 -279.749504)
				)
			)
		)
	)
	(zone
		(layers "B.Cu" "In11.Cu" "In13.Cu" "In15.Cu")
		(hatch none 0.5)
		(connect_pads
			(clearance 0)
		)
		(min_thickness 0.25)
		(keepout
			(tracks not_allowed)
			(vias allowed)
			(pads allowed)
			(copperpour not_allowed)
			(footprints allowed)
		)
		(placement
			(enabled no)
			(sheetname "")
		)
		(fill yes
			(thermal_gap 0.5)
			(thermal_bridge_width 0.5)
			(island_removal_mode 0)
		)
		(polygon
			(pts
				(arc
					(start 347.269816 -397.59001)
					(mid 346.510356 -397.59001)
					(end 347.269816 -397.59001)
				)
			)
		)
	)
	(zone
		(layers "B.Cu" "In11.Cu" "In13.Cu" "In15.Cu")
		(hatch none 0.5)
		(connect_pads
			(clearance 0)
		)
		(min_thickness 0.25)
		(keepout
			(tracks not_allowed)
			(vias allowed)
			(pads allowed)
			(copperpour not_allowed)
			(footprints allowed)
		)
		(placement
			(enabled no)
			(sheetname "")
		)
		(fill yes
			(thermal_gap 0.5)
			(thermal_bridge_width 0.5)
			(island_removal_mode 0)
		)
		(polygon
			(pts
				(arc
					(start 384.38709 -101.984302)
					(mid 383.68351 -101.984302)
					(end 384.38709 -101.984302)
				)
			)
		)
	)
	(zone
		(layers "B.Cu" "In11.Cu" "In13.Cu" "In15.Cu")
		(hatch none 0.5)
		(connect_pads
			(clearance 0)
		)
		(min_thickness 0.25)
		(keepout
			(tracks not_allowed)
			(vias allowed)
			(pads allowed)
			(copperpour not_allowed)
			(footprints allowed)
		)
		(placement
			(enabled no)
			(sheetname "")
		)
		(fill yes
			(thermal_gap 0.5)
			(thermal_bridge_width 0.5)
			(island_removal_mode 0)
		)
		(polygon
			(pts
				(arc
					(start 295.02608 -280.699718)
					(mid 294.3733 -280.699718)
					(end 295.02608 -280.699718)
				)
			)
		)
	)
	(zone
		(layers "B.Cu" "In11.Cu" "In13.Cu" "In15.Cu")
		(hatch none 0.5)
		(connect_pads
			(clearance 0)
		)
		(min_thickness 0.25)
		(keepout
			(tracks not_allowed)
			(vias allowed)
			(pads allowed)
			(copperpour not_allowed)
			(footprints allowed)
		)
		(placement
			(enabled no)
			(sheetname "")
		)
		(fill yes
			(thermal_gap 0.5)
			(thermal_bridge_width 0.5)
			(island_removal_mode 0)
		)
		(polygon
			(pts
				(arc
					(start 289.32632 -315.849762)
					(mid 288.67354 -315.849762)
					(end 289.32632 -315.849762)
				)
			)
		)
	)
	(zone
		(layers "B.Cu" "In11.Cu" "In13.Cu" "In15.Cu")
		(hatch none 0.5)
		(connect_pads
			(clearance 0)
		)
		(min_thickness 0.25)
		(keepout
			(tracks not_allowed)
			(vias allowed)
			(pads allowed)
			(copperpour not_allowed)
			(footprints allowed)
		)
		(placement
			(enabled no)
			(sheetname "")
		)
		(fill yes
			(thermal_gap 0.5)
			(thermal_bridge_width 0.5)
			(island_removal_mode 0)
		)
		(polygon
			(pts
				(arc
					(start 331.869796 -375.69013)
					(mid 331.110336 -375.69013)
					(end 331.869796 -375.69013)
				)
			)
		)
	)
	(zone
		(layers "B.Cu" "In11.Cu" "In13.Cu" "In15.Cu")
		(hatch none 0.5)
		(connect_pads
			(clearance 0)
		)
		(min_thickness 0.25)
		(keepout
			(tracks not_allowed)
			(vias allowed)
			(pads allowed)
			(copperpour not_allowed)
			(footprints allowed)
		)
		(placement
			(enabled no)
			(sheetname "")
		)
		(fill yes
			(thermal_gap 0.5)
			(thermal_bridge_width 0.5)
			(island_removal_mode 0)
		)
		(polygon
			(pts
				(arc
					(start 197.983856 -147.079208)
					(mid 197.280276 -147.079208)
					(end 197.983856 -147.079208)
				)
			)
		)
	)
	(zone
		(layers "B.Cu" "In11.Cu" "In13.Cu" "In15.Cu")
		(hatch none 0.5)
		(connect_pads
			(clearance 0)
		)
		(min_thickness 0.25)
		(keepout
			(tracks not_allowed)
			(vias allowed)
			(pads allowed)
			(copperpour not_allowed)
			(footprints allowed)
		)
		(placement
			(enabled no)
			(sheetname "")
		)
		(fill yes
			(thermal_gap 0.5)
			(thermal_bridge_width 0.5)
			(island_removal_mode 0)
		)
		(polygon
			(pts
				(arc
					(start 64.726312 -315.849762)
					(mid 64.073532 -315.849762)
					(end 64.726312 -315.849762)
				)
			)
		)
	)
	(zone
		(layers "B.Cu" "In11.Cu" "In13.Cu" "In15.Cu")
		(hatch none 0.5)
		(connect_pads
			(clearance 0)
		)
		(min_thickness 0.25)
		(keepout
			(tracks not_allowed)
			(vias allowed)
			(pads allowed)
			(copperpour not_allowed)
			(footprints allowed)
		)
		(placement
			(enabled no)
			(sheetname "")
		)
		(fill yes
			(thermal_gap 0.5)
			(thermal_bridge_width 0.5)
			(island_removal_mode 0)
		)
		(polygon
			(pts
				(arc
					(start 87.68969 -397.59001)
					(mid 86.93023 -397.59001)
					(end 87.68969 -397.59001)
				)
			)
		)
	)
	(zone
		(layers "B.Cu" "In11.Cu" "In13.Cu" "In15.Cu")
		(hatch none 0.5)
		(connect_pads
			(clearance 0)
		)
		(min_thickness 0.25)
		(keepout
			(tracks not_allowed)
			(vias allowed)
			(pads allowed)
			(copperpour not_allowed)
			(footprints allowed)
		)
		(placement
			(enabled no)
			(sheetname "")
		)
		(fill yes
			(thermal_gap 0.5)
			(thermal_bridge_width 0.5)
			(island_removal_mode 0)
		)
		(polygon
			(pts
				(arc
					(start 293.12616 -315.849762)
					(mid 292.47338 -315.849762)
					(end 293.12616 -315.849762)
				)
			)
		)
	)
	(zone
		(layers "B.Cu" "In11.Cu" "In13.Cu" "In15.Cu")
		(hatch none 0.5)
		(connect_pads
			(clearance 0)
		)
		(min_thickness 0.25)
		(keepout
			(tracks not_allowed)
			(vias allowed)
			(pads allowed)
			(copperpour not_allowed)
			(footprints allowed)
		)
		(placement
			(enabled no)
			(sheetname "")
		)
		(fill yes
			(thermal_gap 0.5)
			(thermal_bridge_width 0.5)
			(island_removal_mode 0)
		)
		(polygon
			(pts
				(arc
					(start 56.176164 -318.699896)
					(mid 55.523384 -318.699896)
					(end 56.176164 -318.699896)
				)
			)
		)
	)
	(zone
		(layers "B.Cu" "In11.Cu" "In13.Cu" "In15.Cu")
		(hatch none 0.5)
		(connect_pads
			(clearance 0)
		)
		(min_thickness 0.25)
		(keepout
			(tracks not_allowed)
			(vias allowed)
			(pads allowed)
			(copperpour not_allowed)
			(footprints allowed)
		)
		(placement
			(enabled no)
			(sheetname "")
		)
		(fill yes
			(thermal_gap 0.5)
			(thermal_bridge_width 0.5)
			(island_removal_mode 0)
		)
		(polygon
			(pts
				(arc
					(start 35.47745 -105.584498)
					(mid 34.77387 -105.584498)
					(end 35.47745 -105.584498)
				)
			)
		)
	)
	(zone
		(layers "B.Cu" "In11.Cu" "In13.Cu" "In15.Cu")
		(hatch none 0.5)
		(connect_pads
			(clearance 0)
		)
		(min_thickness 0.25)
		(keepout
			(tracks not_allowed)
			(vias allowed)
			(pads allowed)
			(copperpour not_allowed)
			(footprints allowed)
		)
		(placement
			(enabled no)
			(sheetname "")
		)
		(fill yes
			(thermal_gap 0.5)
			(thermal_bridge_width 0.5)
			(island_removal_mode 0)
		)
		(polygon
			(pts
				(arc
					(start 429.17618 -277.849838)
					(mid 428.5234 -277.849838)
					(end 429.17618 -277.849838)
				)
			)
		)
	)
	(zone
		(layers "B.Cu" "In11.Cu" "In13.Cu" "In15.Cu")
		(hatch none 0.5)
		(connect_pads
			(clearance 0)
		)
		(min_thickness 0.25)
		(keepout
			(tracks not_allowed)
			(vias allowed)
			(pads allowed)
			(copperpour not_allowed)
			(footprints allowed)
		)
		(placement
			(enabled no)
			(sheetname "")
		)
		(fill yes
			(thermal_gap 0.5)
			(thermal_bridge_width 0.5)
			(island_removal_mode 0)
		)
		(polygon
			(pts
				(arc
					(start 297.876214 -318.699896)
					(mid 297.223434 -318.699896)
					(end 297.876214 -318.699896)
				)
			)
		)
	)
	(zone
		(layers "B.Cu" "In11.Cu" "In13.Cu" "In15.Cu")
		(hatch none 0.5)
		(connect_pads
			(clearance 0)
		)
		(min_thickness 0.25)
		(keepout
			(tracks not_allowed)
			(vias allowed)
			(pads allowed)
			(copperpour not_allowed)
			(footprints allowed)
		)
		(placement
			(enabled no)
			(sheetname "")
		)
		(fill yes
			(thermal_gap 0.5)
			(thermal_bridge_width 0.5)
			(island_removal_mode 0)
		)
		(polygon
			(pts
				(arc
					(start 307.376068 -285.449772)
					(mid 306.723288 -285.449772)
					(end 307.376068 -285.449772)
				)
			)
		)
	)
	(zone
		(layers "B.Cu" "In11.Cu" "In13.Cu" "In15.Cu")
		(hatch none 0.5)
		(connect_pads
			(clearance 0)
		)
		(min_thickness 0.25)
		(keepout
			(tracks not_allowed)
			(vias allowed)
			(pads allowed)
			(copperpour not_allowed)
			(footprints allowed)
		)
		(placement
			(enabled no)
			(sheetname "")
		)
		(fill yes
			(thermal_gap 0.5)
			(thermal_bridge_width 0.5)
			(island_removal_mode 0)
		)
		(polygon
			(pts
				(arc
					(start 425.37634 -284.499812)
					(mid 424.72356 -284.499812)
					(end 425.37634 -284.499812)
				)
			)
		)
	)
	(zone
		(layers "B.Cu" "In11.Cu" "In13.Cu" "In15.Cu")
		(hatch none 0.5)
		(connect_pads
			(clearance 0)
		)
		(min_thickness 0.25)
		(keepout
			(tracks not_allowed)
			(vias allowed)
			(pads allowed)
			(copperpour not_allowed)
			(footprints allowed)
		)
		(placement
			(enabled no)
			(sheetname "")
		)
		(fill yes
			(thermal_gap 0.5)
			(thermal_bridge_width 0.5)
			(island_removal_mode 0)
		)
		(polygon
			(pts
				(arc
					(start 270.3195 -121.894346)
					(mid 269.61592 -121.894346)
					(end 270.3195 -121.894346)
				)
			)
		)
	)
	(zone
		(layers "B.Cu" "In11.Cu" "In13.Cu" "In15.Cu")
		(hatch none 0.5)
		(connect_pads
			(clearance 0)
		)
		(min_thickness 0.25)
		(keepout
			(tracks not_allowed)
			(vias allowed)
			(pads allowed)
			(copperpour not_allowed)
			(footprints allowed)
		)
		(placement
			(enabled no)
			(sheetname "")
		)
		(fill yes
			(thermal_gap 0.5)
			(thermal_bridge_width 0.5)
			(island_removal_mode 0)
		)
		(polygon
			(pts
				(arc
					(start 294.07612 -318.699896)
					(mid 293.42334 -318.699896)
					(end 294.07612 -318.699896)
				)
			)
		)
	)
	(zone
		(layers "B.Cu" "In11.Cu" "In13.Cu" "In15.Cu")
		(hatch none 0.5)
		(connect_pads
			(clearance 0)
		)
		(min_thickness 0.25)
		(keepout
			(tracks not_allowed)
			(vias allowed)
			(pads allowed)
			(copperpour not_allowed)
			(footprints allowed)
		)
		(placement
			(enabled no)
			(sheetname "")
		)
		(fill yes
			(thermal_gap 0.5)
			(thermal_bridge_width 0.5)
			(island_removal_mode 0)
		)
		(polygon
			(pts
				(arc
					(start 154.219402 -110.114334)
					(mid 153.515822 -110.114334)
					(end 154.219402 -110.114334)
				)
			)
		)
	)
	(zone
		(layers "B.Cu" "In11.Cu" "In13.Cu" "In15.Cu")
		(hatch none 0.5)
		(connect_pads
			(clearance 0)
		)
		(min_thickness 0.25)
		(keepout
			(tracks not_allowed)
			(vias allowed)
			(pads allowed)
			(copperpour not_allowed)
			(footprints allowed)
		)
		(placement
			(enabled no)
			(sheetname "")
		)
		(fill yes
			(thermal_gap 0.5)
			(thermal_bridge_width 0.5)
			(island_removal_mode 0)
		)
		(polygon
			(pts
				(arc
					(start 38.119558 -107.377738)
					(mid 37.415978 -107.377738)
					(end 38.119558 -107.377738)
				)
			)
		)
	)
	(zone
		(layers "B.Cu" "In11.Cu" "In13.Cu" "In15.Cu")
		(hatch none 0.5)
		(connect_pads
			(clearance 0)
		)
		(min_thickness 0.25)
		(keepout
			(tracks not_allowed)
			(vias allowed)
			(pads allowed)
			(copperpour not_allowed)
			(footprints allowed)
		)
		(placement
			(enabled no)
			(sheetname "")
		)
		(fill yes
			(thermal_gap 0.5)
			(thermal_bridge_width 0.5)
			(island_removal_mode 0)
		)
		(polygon
			(pts
				(arc
					(start 425.37634 -282.599892)
					(mid 424.72356 -282.599892)
					(end 425.37634 -282.599892)
				)
			)
		)
	)
	(zone
		(layers "B.Cu" "In11.Cu" "In13.Cu" "In15.Cu")
		(hatch none 0.5)
		(connect_pads
			(clearance 0)
		)
		(min_thickness 0.25)
		(keepout
			(tracks not_allowed)
			(vias allowed)
			(pads allowed)
			(copperpour not_allowed)
			(footprints allowed)
		)
		(placement
			(enabled no)
			(sheetname "")
		)
		(fill yes
			(thermal_gap 0.5)
			(thermal_bridge_width 0.5)
			(island_removal_mode 0)
		)
		(polygon
			(pts
				(arc
					(start 314.083954 -122.295666)
					(mid 313.380374 -122.295666)
					(end 314.083954 -122.295666)
				)
			)
		)
	)
	(zone
		(layers "B.Cu" "In11.Cu" "In13.Cu" "In15.Cu")
		(hatch none 0.5)
		(connect_pads
			(clearance 0)
		)
		(min_thickness 0.25)
		(keepout
			(tracks not_allowed)
			(vias allowed)
			(pads allowed)
			(copperpour not_allowed)
			(footprints allowed)
		)
		(placement
			(enabled no)
			(sheetname "")
		)
		(fill yes
			(thermal_gap 0.5)
			(thermal_bridge_width 0.5)
			(island_removal_mode 0)
		)
		(polygon
			(pts
				(arc
					(start 419.86962 -382.18999)
					(mid 419.11016 -382.18999)
					(end 419.86962 -382.18999)
				)
			)
		)
	)
	(zone
		(layers "B.Cu" "In11.Cu" "In13.Cu" "In15.Cu")
		(hatch none 0.5)
		(connect_pads
			(clearance 0)
		)
		(min_thickness 0.25)
		(keepout
			(tracks not_allowed)
			(vias allowed)
			(pads allowed)
			(copperpour not_allowed)
			(footprints allowed)
		)
		(placement
			(enabled no)
			(sheetname "")
		)
		(fill yes
			(thermal_gap 0.5)
			(thermal_bridge_width 0.5)
			(island_removal_mode 0)
		)
		(polygon
			(pts
				(arc
					(start 153.2763 -304.449734)
					(mid 152.62352 -304.449734)
					(end 153.2763 -304.449734)
				)
			)
		)
	)
	(zone
		(layers "B.Cu" "In11.Cu" "In13.Cu" "In15.Cu")
		(hatch none 0.5)
		(connect_pads
			(clearance 0)
		)
		(min_thickness 0.25)
		(keepout
			(tracks not_allowed)
			(vias allowed)
			(pads allowed)
			(copperpour not_allowed)
			(footprints allowed)
		)
		(placement
			(enabled no)
			(sheetname "")
		)
		(fill yes
			(thermal_gap 0.5)
			(thermal_bridge_width 0.5)
			(island_removal_mode 0)
		)
		(polygon
			(pts
				(arc
					(start 77.0763 -284.499812)
					(mid 76.42352 -284.499812)
					(end 77.0763 -284.499812)
				)
			)
		)
	)
	(zone
		(layers "B.Cu" "In11.Cu" "In13.Cu" "In15.Cu")
		(hatch none 0.5)
		(connect_pads
			(clearance 0)
		)
		(min_thickness 0.25)
		(keepout
			(tracks not_allowed)
			(vias allowed)
			(pads allowed)
			(copperpour not_allowed)
			(footprints allowed)
		)
		(placement
			(enabled no)
			(sheetname "")
		)
		(fill yes
			(thermal_gap 0.5)
			(thermal_bridge_width 0.5)
			(island_removal_mode 0)
		)
		(polygon
			(pts
				(arc
					(start 76.12634 -287.349946)
					(mid 75.47356 -287.349946)
					(end 76.12634 -287.349946)
				)
			)
		)
	)
	(zone
		(layers "B.Cu" "In11.Cu" "In13.Cu" "In15.Cu")
		(hatch none 0.5)
		(connect_pads
			(clearance 0)
		)
		(min_thickness 0.25)
		(keepout
			(tracks not_allowed)
			(vias allowed)
			(pads allowed)
			(copperpour not_allowed)
			(footprints allowed)
		)
		(placement
			(enabled no)
			(sheetname "")
		)
		(fill yes
			(thermal_gap 0.5)
			(thermal_bridge_width 0.5)
			(island_removal_mode 0)
		)
		(polygon
			(pts
				(arc
					(start 78.02626 -284.499812)
					(mid 77.37348 -284.499812)
					(end 78.02626 -284.499812)
				)
			)
		)
	)
	(zone
		(layers "B.Cu" "In11.Cu" "In13.Cu" "In15.Cu")
		(hatch none 0.5)
		(connect_pads
			(clearance 0)
		)
		(min_thickness 0.25)
		(keepout
			(tracks not_allowed)
			(vias allowed)
			(pads allowed)
			(copperpour not_allowed)
			(footprints allowed)
		)
		(placement
			(enabled no)
			(sheetname "")
		)
		(fill yes
			(thermal_gap 0.5)
			(thermal_bridge_width 0.5)
			(island_removal_mode 0)
		)
		(polygon
			(pts
				(arc
					(start 303.575974 -278.799798)
					(mid 302.923194 -278.799798)
					(end 303.575974 -278.799798)
				)
			)
		)
	)
	(zone
		(layers "B.Cu" "In11.Cu" "In13.Cu" "In15.Cu")
		(hatch none 0.5)
		(connect_pads
			(clearance 0)
		)
		(min_thickness 0.25)
		(keepout
			(tracks not_allowed)
			(vias allowed)
			(pads allowed)
			(copperpour not_allowed)
			(footprints allowed)
		)
		(placement
			(enabled no)
			(sheetname "")
		)
		(fill yes
			(thermal_gap 0.5)
			(thermal_bridge_width 0.5)
			(island_removal_mode 0)
		)
		(polygon
			(pts
				(arc
					(start 316.726062 -155.222194)
					(mid 316.022482 -155.222194)
					(end 316.726062 -155.222194)
				)
			)
		)
	)
	(zone
		(layers "B.Cu" "In11.Cu" "In13.Cu" "In15.Cu")
		(hatch none 0.5)
		(connect_pads
			(clearance 0)
		)
		(min_thickness 0.25)
		(keepout
			(tracks not_allowed)
			(vias allowed)
			(pads allowed)
			(copperpour not_allowed)
			(footprints allowed)
		)
		(placement
			(enabled no)
			(sheetname "")
		)
		(fill yes
			(thermal_gap 0.5)
			(thermal_bridge_width 0.5)
			(island_removal_mode 0)
		)
		(polygon
			(pts
				(arc
					(start 426.3263 -284.499812)
					(mid 425.67352 -284.499812)
					(end 426.3263 -284.499812)
				)
			)
		)
	)
	(zone
		(layers "B.Cu" "In11.Cu" "In13.Cu" "In15.Cu")
		(hatch none 0.5)
		(connect_pads
			(clearance 0)
		)
		(min_thickness 0.25)
		(keepout
			(tracks not_allowed)
			(vias allowed)
			(pads allowed)
			(copperpour not_allowed)
			(footprints allowed)
		)
		(placement
			(enabled no)
			(sheetname "")
		)
		(fill yes
			(thermal_gap 0.5)
			(thermal_bridge_width 0.5)
			(island_removal_mode 0)
		)
		(polygon
			(pts
				(arc
					(start 267.677392 -105.584498)
					(mid 266.973812 -105.584498)
					(end 267.677392 -105.584498)
				)
			)
		)
	)
	(zone
		(layers "B.Cu" "In11.Cu" "In13.Cu" "In15.Cu")
		(hatch none 0.5)
		(connect_pads
			(clearance 0)
		)
		(min_thickness 0.25)
		(keepout
			(tracks not_allowed)
			(vias allowed)
			(pads allowed)
			(copperpour not_allowed)
			(footprints allowed)
		)
		(placement
			(enabled no)
			(sheetname "")
		)
		(fill yes
			(thermal_gap 0.5)
			(thermal_bridge_width 0.5)
			(island_removal_mode 0)
		)
		(polygon
			(pts
				(arc
					(start 80.87614 -278.799798)
					(mid 80.22336 -278.799798)
					(end 80.87614 -278.799798)
				)
			)
		)
	)
	(zone
		(layers "B.Cu" "In11.Cu" "In13.Cu" "In15.Cu")
		(hatch none 0.5)
		(connect_pads
			(clearance 0)
		)
		(min_thickness 0.25)
		(keepout
			(tracks not_allowed)
			(vias allowed)
			(pads allowed)
			(copperpour not_allowed)
			(footprints allowed)
		)
		(placement
			(enabled no)
			(sheetname "")
		)
		(fill yes
			(thermal_gap 0.5)
			(thermal_bridge_width 0.5)
			(island_removal_mode 0)
		)
		(polygon
			(pts
				(arc
					(start 76.689712 -375.69013)
					(mid 75.930252 -375.69013)
					(end 76.689712 -375.69013)
				)
			)
		)
	)
	(zone
		(layers "B.Cu" "In11.Cu" "In13.Cu" "In15.Cu")
		(hatch none 0.5)
		(connect_pads
			(clearance 0)
		)
		(min_thickness 0.25)
		(keepout
			(tracks not_allowed)
			(vias allowed)
			(pads allowed)
			(copperpour not_allowed)
			(footprints allowed)
		)
		(placement
			(enabled no)
			(sheetname "")
		)
		(fill yes
			(thermal_gap 0.5)
			(thermal_bridge_width 0.5)
			(island_removal_mode 0)
		)
		(polygon
			(pts
				(arc
					(start 425.37634 -286.399986)
					(mid 424.72356 -286.399986)
					(end 425.37634 -286.399986)
				)
			)
		)
	)
	(zone
		(layers "B.Cu" "In11.Cu" "In13.Cu" "In15.Cu")
		(hatch none 0.5)
		(connect_pads
			(clearance 0)
		)
		(min_thickness 0.25)
		(keepout
			(tracks not_allowed)
			(vias allowed)
			(pads allowed)
			(copperpour not_allowed)
			(footprints allowed)
		)
		(placement
			(enabled no)
			(sheetname "")
		)
		(fill yes
			(thermal_gap 0.5)
			(thermal_bridge_width 0.5)
			(island_removal_mode 0)
		)
		(polygon
			(pts
				(arc
					(start 51.426364 -315.849762)
					(mid 50.773584 -315.849762)
					(end 51.426364 -315.849762)
				)
			)
		)
	)
	(zone
		(layers "B.Cu" "In11.Cu" "In13.Cu" "In15.Cu")
		(hatch none 0.5)
		(connect_pads
			(clearance 0)
		)
		(min_thickness 0.25)
		(keepout
			(tracks not_allowed)
			(vias allowed)
			(pads allowed)
			(copperpour not_allowed)
			(footprints allowed)
		)
		(placement
			(enabled no)
			(sheetname "")
		)
		(fill yes
			(thermal_gap 0.5)
			(thermal_bridge_width 0.5)
			(island_removal_mode 0)
		)
		(polygon
			(pts
				(arc
					(start 430.184052 -133.505702)
					(mid 429.480472 -133.505702)
					(end 430.184052 -133.505702)
				)
			)
		)
	)
	(zone
		(layers "B.Cu" "In11.Cu" "In13.Cu" "In15.Cu")
		(hatch none 0.5)
		(connect_pads
			(clearance 0)
		)
		(min_thickness 0.25)
		(keepout
			(tracks not_allowed)
			(vias allowed)
			(pads allowed)
			(copperpour not_allowed)
			(footprints allowed)
		)
		(placement
			(enabled no)
			(sheetname "")
		)
		(fill yes
			(thermal_gap 0.5)
			(thermal_bridge_width 0.5)
			(island_removal_mode 0)
		)
		(polygon
			(pts
				(arc
					(start 189.37605 -277.849838)
					(mid 188.72327 -277.849838)
					(end 189.37605 -277.849838)
				)
			)
		)
	)
	(zone
		(layers "B.Cu" "In11.Cu" "In13.Cu" "In15.Cu")
		(hatch none 0.5)
		(connect_pads
			(clearance 0)
		)
		(min_thickness 0.25)
		(keepout
			(tracks not_allowed)
			(vias allowed)
			(pads allowed)
			(copperpour not_allowed)
			(footprints allowed)
		)
		(placement
			(enabled no)
			(sheetname "")
		)
		(fill yes
			(thermal_gap 0.5)
			(thermal_bridge_width 0.5)
			(island_removal_mode 0)
		)
		(polygon
			(pts
				(arc
					(start 61.876178 -318.699896)
					(mid 61.223398 -318.699896)
					(end 61.876178 -318.699896)
				)
			)
		)
	)
	(zone
		(layers "B.Cu" "In11.Cu" "In13.Cu" "In15.Cu")
		(hatch none 0.5)
		(connect_pads
			(clearance 0)
		)
		(min_thickness 0.25)
		(keepout
			(tracks not_allowed)
			(vias allowed)
			(pads allowed)
			(copperpour not_allowed)
			(footprints allowed)
		)
		(placement
			(enabled no)
			(sheetname "")
		)
		(fill yes
			(thermal_gap 0.5)
			(thermal_bridge_width 0.5)
			(island_removal_mode 0)
		)
		(polygon
			(pts
				(arc
					(start 10.31494 -372.07063)
					(mid 9.61136 -372.07063)
					(end 10.31494 -372.07063)
				)
			)
		)
	)
	(zone
		(layers "B.Cu" "In11.Cu" "In13.Cu" "In15.Cu")
		(hatch none 0.5)
		(connect_pads
			(clearance 0)
		)
		(min_thickness 0.25)
		(keepout
			(tracks not_allowed)
			(vias allowed)
			(pads allowed)
			(copperpour not_allowed)
			(footprints allowed)
		)
		(placement
			(enabled no)
			(sheetname "")
		)
		(fill yes
			(thermal_gap 0.5)
			(thermal_bridge_width 0.5)
			(island_removal_mode 0)
		)
		(polygon
			(pts
				(arc
					(start 156.126434 -305.399948)
					(mid 155.473654 -305.399948)
					(end 156.126434 -305.399948)
				)
			)
		)
	)
	(zone
		(layers "B.Cu" "In11.Cu" "In13.Cu" "In15.Cu")
		(hatch none 0.5)
		(connect_pads
			(clearance 0)
		)
		(min_thickness 0.25)
		(keepout
			(tracks not_allowed)
			(vias allowed)
			(pads allowed)
			(copperpour not_allowed)
			(footprints allowed)
		)
		(placement
			(enabled no)
			(sheetname "")
		)
		(fill yes
			(thermal_gap 0.5)
			(thermal_bridge_width 0.5)
			(island_removal_mode 0)
		)
		(polygon
			(pts
				(arc
					(start 154.22626 -316.799722)
					(mid 153.57348 -316.799722)
					(end 154.22626 -316.799722)
				)
			)
		)
	)
	(zone
		(layers "B.Cu" "In11.Cu" "In13.Cu" "In15.Cu")
		(hatch none 0.5)
		(connect_pads
			(clearance 0)
		)
		(min_thickness 0.25)
		(keepout
			(tracks not_allowed)
			(vias allowed)
			(pads allowed)
			(copperpour not_allowed)
			(footprints allowed)
		)
		(placement
			(enabled no)
			(sheetname "")
		)
		(fill yes
			(thermal_gap 0.5)
			(thermal_bridge_width 0.5)
			(island_removal_mode 0)
		)
		(polygon
			(pts
				(arc
					(start 38.119558 -124.630942)
					(mid 37.415978 -124.630942)
					(end 38.119558 -124.630942)
				)
			)
		)
	)
	(zone
		(layers "B.Cu" "In11.Cu" "In13.Cu" "In15.Cu")
		(hatch none 0.5)
		(connect_pads
			(clearance 0)
		)
		(min_thickness 0.25)
		(keepout
			(tracks not_allowed)
			(vias allowed)
			(pads allowed)
			(copperpour not_allowed)
			(footprints allowed)
		)
		(placement
			(enabled no)
			(sheetname "")
		)
		(fill yes
			(thermal_gap 0.5)
			(thermal_bridge_width 0.5)
			(island_removal_mode 0)
		)
		(polygon
			(pts
				(arc
					(start 309.275988 -277.849838)
					(mid 308.623208 -277.849838)
					(end 309.275988 -277.849838)
				)
			)
		)
	)
	(zone
		(layers "B.Cu" "In11.Cu" "In13.Cu" "In15.Cu")
		(hatch none 0.5)
		(connect_pads
			(clearance 0)
		)
		(min_thickness 0.25)
		(keepout
			(tracks not_allowed)
			(vias allowed)
			(pads allowed)
			(copperpour not_allowed)
			(footprints allowed)
		)
		(placement
			(enabled no)
			(sheetname "")
		)
		(fill yes
			(thermal_gap 0.5)
			(thermal_bridge_width 0.5)
			(island_removal_mode 0)
		)
		(polygon
			(pts
				(arc
					(start 184.62625 -280.699718)
					(mid 183.97347 -280.699718)
					(end 184.62625 -280.699718)
				)
			)
		)
	)
	(zone
		(layers "B.Cu" "In11.Cu" "In13.Cu" "In15.Cu")
		(hatch none 0.5)
		(connect_pads
			(clearance 0)
		)
		(min_thickness 0.25)
		(keepout
			(tracks not_allowed)
			(vias allowed)
			(pads allowed)
			(copperpour not_allowed)
			(footprints allowed)
		)
		(placement
			(enabled no)
			(sheetname "")
		)
		(fill yes
			(thermal_gap 0.5)
			(thermal_bridge_width 0.5)
			(island_removal_mode 0)
		)
		(polygon
			(pts
				(arc
					(start 422.069514 -409.290012)
					(mid 421.310054 -409.290012)
					(end 422.069514 -409.290012)
				)
			)
		)
	)
	(zone
		(layers "B.Cu" "In11.Cu" "In13.Cu" "In15.Cu")
		(hatch none 0.5)
		(connect_pads
			(clearance 0)
		)
		(min_thickness 0.25)
		(keepout
			(tracks not_allowed)
			(vias allowed)
			(pads allowed)
			(copperpour not_allowed)
			(footprints allowed)
		)
		(placement
			(enabled no)
			(sheetname "")
		)
		(fill yes
			(thermal_gap 0.5)
			(thermal_bridge_width 0.5)
			(island_removal_mode 0)
		)
		(polygon
			(pts
				(arc
					(start 64.726312 -280.699718)
					(mid 64.073532 -280.699718)
					(end 64.726312 -280.699718)
				)
			)
		)
	)
	(zone
		(layers "B.Cu" "In11.Cu" "In13.Cu" "In15.Cu")
		(hatch none 0.5)
		(connect_pads
			(clearance 0)
		)
		(min_thickness 0.25)
		(keepout
			(tracks not_allowed)
			(vias allowed)
			(pads allowed)
			(copperpour not_allowed)
			(footprints allowed)
		)
		(placement
			(enabled no)
			(sheetname "")
		)
		(fill yes
			(thermal_gap 0.5)
			(thermal_bridge_width 0.5)
			(island_removal_mode 0)
		)
		(polygon
			(pts
				(arc
					(start 316.726062 -148.88591)
					(mid 316.022482 -148.88591)
					(end 316.726062 -148.88591)
				)
			)
		)
	)
	(zone
		(layers "B.Cu" "In11.Cu" "In13.Cu" "In15.Cu")
		(hatch none 0.5)
		(connect_pads
			(clearance 0)
		)
		(min_thickness 0.25)
		(keepout
			(tracks not_allowed)
			(vias allowed)
			(pads allowed)
			(copperpour not_allowed)
			(footprints allowed)
		)
		(placement
			(enabled no)
			(sheetname "")
		)
		(fill yes
			(thermal_gap 0.5)
			(thermal_bridge_width 0.5)
			(island_removal_mode 0)
		)
		(polygon
			(pts
				(arc
					(start 200.625964 -136.17575)
					(mid 199.922384 -136.17575)
					(end 200.625964 -136.17575)
				)
			)
		)
	)
	(zone
		(layers "B.Cu" "In11.Cu" "In13.Cu" "In15.Cu")
		(hatch none 0.5)
		(connect_pads
			(clearance 0)
		)
		(min_thickness 0.25)
		(keepout
			(tracks not_allowed)
			(vias allowed)
			(pads allowed)
			(copperpour not_allowed)
			(footprints allowed)
		)
		(placement
			(enabled no)
			(sheetname "")
		)
		(fill yes
			(thermal_gap 0.5)
			(thermal_bridge_width 0.5)
			(island_removal_mode 0)
		)
		(polygon
			(pts
				(arc
					(start 193.176398 -288.299906)
					(mid 192.523618 -288.299906)
					(end 193.176398 -288.299906)
				)
			)
		)
	)
	(zone
		(layers "B.Cu" "In11.Cu" "In13.Cu" "In15.Cu")
		(hatch none 0.5)
		(connect_pads
			(clearance 0)
		)
		(min_thickness 0.25)
		(keepout
			(tracks not_allowed)
			(vias allowed)
			(pads allowed)
			(copperpour not_allowed)
			(footprints allowed)
		)
		(placement
			(enabled no)
			(sheetname "")
		)
		(fill yes
			(thermal_gap 0.5)
			(thermal_bridge_width 0.5)
			(island_removal_mode 0)
		)
		(polygon
			(pts
				(arc
					(start 76.689712 -374.390158)
					(mid 75.930252 -374.390158)
					(end 76.689712 -374.390158)
				)
			)
		)
	)
	(zone
		(layers "B.Cu" "In11.Cu" "In13.Cu" "In15.Cu")
		(hatch none 0.5)
		(connect_pads
			(clearance 0)
		)
		(min_thickness 0.25)
		(keepout
			(tracks not_allowed)
			(vias allowed)
			(pads allowed)
			(copperpour not_allowed)
			(footprints allowed)
		)
		(placement
			(enabled no)
			(sheetname "")
		)
		(fill yes
			(thermal_gap 0.5)
			(thermal_bridge_width 0.5)
			(island_removal_mode 0)
		)
		(polygon
			(pts
				(arc
					(start 432.82616 -145.285714)
					(mid 432.12258 -145.285714)
					(end 432.82616 -145.285714)
				)
			)
		)
	)
	(zone
		(layers "B.Cu" "In11.Cu" "In13.Cu" "In15.Cu")
		(hatch none 0.5)
		(connect_pads
			(clearance 0)
		)
		(min_thickness 0.25)
		(keepout
			(tracks not_allowed)
			(vias allowed)
			(pads allowed)
			(copperpour not_allowed)
			(footprints allowed)
		)
		(placement
			(enabled no)
			(sheetname "")
		)
		(fill yes
			(thermal_gap 0.5)
			(thermal_bridge_width 0.5)
			(island_removal_mode 0)
		)
		(polygon
			(pts
				(arc
					(start 84.52612 -132.575808)
					(mid 83.82254 -132.575808)
					(end 84.52612 -132.575808)
				)
			)
		)
	)
	(zone
		(layers "B.Cu" "In11.Cu" "In13.Cu" "In15.Cu")
		(hatch none 0.5)
		(connect_pads
			(clearance 0)
		)
		(min_thickness 0.25)
		(keepout
			(tracks not_allowed)
			(vias allowed)
			(pads allowed)
			(copperpour not_allowed)
			(footprints allowed)
		)
		(placement
			(enabled no)
			(sheetname "")
		)
		(fill yes
			(thermal_gap 0.5)
			(thermal_bridge_width 0.5)
			(island_removal_mode 0)
		)
		(polygon
			(pts
				(arc
					(start 428.669704 -382.18999)
					(mid 427.910244 -382.18999)
					(end 428.669704 -382.18999)
				)
			)
		)
	)
	(zone
		(layers "B.Cu" "In11.Cu" "In13.Cu" "In15.Cu")
		(hatch none 0.5)
		(connect_pads
			(clearance 0)
		)
		(min_thickness 0.25)
		(keepout
			(tracks not_allowed)
			(vias allowed)
			(pads allowed)
			(copperpour not_allowed)
			(footprints allowed)
		)
		(placement
			(enabled no)
			(sheetname "")
		)
		(fill yes
			(thermal_gap 0.5)
			(thermal_bridge_width 0.5)
			(island_removal_mode 0)
		)
		(polygon
			(pts
				(arc
					(start 177.976022 -277.849838)
					(mid 177.323242 -277.849838)
					(end 177.976022 -277.849838)
				)
			)
		)
	)
	(zone
		(layers "B.Cu" "In11.Cu" "In13.Cu" "In15.Cu")
		(hatch none 0.5)
		(connect_pads
			(clearance 0)
		)
		(min_thickness 0.25)
		(keepout
			(tracks not_allowed)
			(vias allowed)
			(pads allowed)
			(copperpour not_allowed)
			(footprints allowed)
		)
		(placement
			(enabled no)
			(sheetname "")
		)
		(fill yes
			(thermal_gap 0.5)
			(thermal_bridge_width 0.5)
			(island_removal_mode 0)
		)
		(polygon
			(pts
				(arc
					(start 68.526152 -279.749504)
					(mid 67.873372 -279.749504)
					(end 68.526152 -279.749504)
				)
			)
		)
	)
	(zone
		(layers "B.Cu" "In11.Cu" "In13.Cu" "In15.Cu")
		(hatch none 0.5)
		(connect_pads
			(clearance 0)
		)
		(min_thickness 0.25)
		(keepout
			(tracks not_allowed)
			(vias allowed)
			(pads allowed)
			(copperpour not_allowed)
			(footprints allowed)
		)
		(placement
			(enabled no)
			(sheetname "")
		)
		(fill yes
			(thermal_gap 0.5)
			(thermal_bridge_width 0.5)
			(island_removal_mode 0)
		)
		(polygon
			(pts
				(arc
					(start 310.226202 -280.699718)
					(mid 309.573422 -280.699718)
					(end 310.226202 -280.699718)
				)
			)
		)
	)
	(zone
		(layers "B.Cu" "In11.Cu" "In13.Cu" "In15.Cu")
		(hatch none 0.5)
		(connect_pads
			(clearance 0)
		)
		(min_thickness 0.25)
		(keepout
			(tracks not_allowed)
			(vias allowed)
			(pads allowed)
			(copperpour not_allowed)
			(footprints allowed)
		)
		(placement
			(enabled no)
			(sheetname "")
		)
		(fill yes
			(thermal_gap 0.5)
			(thermal_bridge_width 0.5)
			(island_removal_mode 0)
		)
		(polygon
			(pts
				(arc
					(start 430.184052 -150.67915)
					(mid 429.480472 -150.67915)
					(end 430.184052 -150.67915)
				)
			)
		)
	)
	(zone
		(layers "B.Cu" "In11.Cu" "In13.Cu" "In15.Cu")
		(hatch none 0.5)
		(connect_pads
			(clearance 0)
		)
		(min_thickness 0.25)
		(keepout
			(tracks not_allowed)
			(vias allowed)
			(pads allowed)
			(copperpour not_allowed)
			(footprints allowed)
		)
		(placement
			(enabled no)
			(sheetname "")
		)
		(fill yes
			(thermal_gap 0.5)
			(thermal_bridge_width 0.5)
			(island_removal_mode 0)
		)
		(polygon
			(pts
				(arc
					(start 334.06969 -398.890236)
					(mid 333.31023 -398.890236)
					(end 334.06969 -398.890236)
				)
			)
		)
	)
	(zone
		(layers "B.Cu" "In11.Cu" "In13.Cu" "In15.Cu")
		(hatch none 0.5)
		(connect_pads
			(clearance 0)
		)
		(min_thickness 0.25)
		(keepout
			(tracks not_allowed)
			(vias allowed)
			(pads allowed)
			(copperpour not_allowed)
			(footprints allowed)
		)
		(placement
			(enabled no)
			(sheetname "")
		)
		(fill yes
			(thermal_gap 0.5)
			(thermal_bridge_width 0.5)
			(island_removal_mode 0)
		)
		(polygon
			(pts
				(arc
					(start 423.476166 -287.349946)
					(mid 422.823386 -287.349946)
					(end 423.476166 -287.349946)
				)
			)
		)
	)
	(zone
		(layers "B.Cu" "In11.Cu" "In13.Cu" "In15.Cu")
		(hatch none 0.5)
		(connect_pads
			(clearance 0)
		)
		(min_thickness 0.25)
		(keepout
			(tracks not_allowed)
			(vias allowed)
			(pads allowed)
			(copperpour not_allowed)
			(footprints allowed)
		)
		(placement
			(enabled no)
			(sheetname "")
		)
		(fill yes
			(thermal_gap 0.5)
			(thermal_bridge_width 0.5)
			(island_removal_mode 0)
		)
		(polygon
			(pts
				(arc
					(start 386.419598 -100.177854)
					(mid 385.716018 -100.177854)
					(end 386.419598 -100.177854)
				)
			)
		)
	)
	(zone
		(layers "B.Cu" "In11.Cu" "In13.Cu" "In15.Cu")
		(hatch none 0.5)
		(connect_pads
			(clearance 0)
		)
		(min_thickness 0.25)
		(keepout
			(tracks not_allowed)
			(vias allowed)
			(pads allowed)
			(copperpour not_allowed)
			(footprints allowed)
		)
		(placement
			(enabled no)
			(sheetname "")
		)
		(fill yes
			(thermal_gap 0.5)
			(thermal_bridge_width 0.5)
			(island_removal_mode 0)
		)
		(polygon
			(pts
				(arc
					(start 166.889684 -383.290064)
					(mid 166.130224 -383.290064)
					(end 166.889684 -383.290064)
				)
			)
		)
	)
	(zone
		(layers "B.Cu" "In11.Cu" "In13.Cu" "In15.Cu")
		(hatch none 0.5)
		(connect_pads
			(clearance 0)
		)
		(min_thickness 0.25)
		(keepout
			(tracks not_allowed)
			(vias allowed)
			(pads allowed)
			(copperpour not_allowed)
			(footprints allowed)
		)
		(placement
			(enabled no)
			(sheetname "")
		)
		(fill yes
			(thermal_gap 0.5)
			(thermal_bridge_width 0.5)
			(island_removal_mode 0)
		)
		(polygon
			(pts
				(arc
					(start 267.677392 -134.897876)
					(mid 266.973812 -134.897876)
					(end 267.677392 -134.897876)
				)
			)
		)
	)
	(zone
		(layers "B.Cu" "In11.Cu" "In13.Cu" "In15.Cu")
		(hatch none 0.5)
		(connect_pads
			(clearance 0)
		)
		(min_thickness 0.25)
		(keepout
			(tracks not_allowed)
			(vias allowed)
			(pads allowed)
			(copperpour not_allowed)
			(footprints allowed)
		)
		(placement
			(enabled no)
			(sheetname "")
		)
		(fill yes
			(thermal_gap 0.5)
			(thermal_bridge_width 0.5)
			(island_removal_mode 0)
		)
		(polygon
			(pts
				(arc
					(start 408.276044 -278.799798)
					(mid 407.623264 -278.799798)
					(end 408.276044 -278.799798)
				)
			)
		)
	)
	(zone
		(layers "B.Cu" "In11.Cu" "In13.Cu" "In15.Cu")
		(hatch none 0.5)
		(connect_pads
			(clearance 0)
		)
		(min_thickness 0.25)
		(keepout
			(tracks not_allowed)
			(vias allowed)
			(pads allowed)
			(copperpour not_allowed)
			(footprints allowed)
		)
		(placement
			(enabled no)
			(sheetname "")
		)
		(fill yes
			(thermal_gap 0.5)
			(thermal_bridge_width 0.5)
			(island_removal_mode 0)
		)
		(polygon
			(pts
				(arc
					(start 164.68979 -383.490216)
					(mid 163.93033 -383.490216)
					(end 164.68979 -383.490216)
				)
			)
		)
	)
	(zone
		(layers "B.Cu" "In11.Cu" "In13.Cu" "In15.Cu")
		(hatch none 0.5)
		(connect_pads
			(clearance 0)
		)
		(min_thickness 0.25)
		(keepout
			(tracks not_allowed)
			(vias allowed)
			(pads allowed)
			(copperpour not_allowed)
			(footprints allowed)
		)
		(placement
			(enabled no)
			(sheetname "")
		)
		(fill yes
			(thermal_gap 0.5)
			(thermal_bridge_width 0.5)
			(island_removal_mode 0)
		)
		(polygon
			(pts
				(arc
					(start 84.52612 -148.88591)
					(mid 83.82254 -148.88591)
					(end 84.52612 -148.88591)
				)
			)
		)
	)
	(zone
		(layers "B.Cu" "In11.Cu" "In13.Cu" "In15.Cu")
		(hatch none 0.5)
		(connect_pads
			(clearance 0)
		)
		(min_thickness 0.25)
		(keepout
			(tracks not_allowed)
			(vias allowed)
			(pads allowed)
			(copperpour not_allowed)
			(footprints allowed)
		)
		(placement
			(enabled no)
			(sheetname "")
		)
		(fill yes
			(thermal_gap 0.5)
			(thermal_bridge_width 0.5)
			(island_removal_mode 0)
		)
		(polygon
			(pts
				(arc
					(start 193.176144 -278.799798)
					(mid 192.523364 -278.799798)
					(end 193.176144 -278.799798)
				)
			)
		)
	)
	(zone
		(layers "B.Cu" "In11.Cu" "In13.Cu" "In15.Cu")
		(hatch none 0.5)
		(connect_pads
			(clearance 0)
		)
		(min_thickness 0.25)
		(keepout
			(tracks not_allowed)
			(vias allowed)
			(pads allowed)
			(copperpour not_allowed)
			(footprints allowed)
		)
		(placement
			(enabled no)
			(sheetname "")
		)
		(fill yes
			(thermal_gap 0.5)
			(thermal_bridge_width 0.5)
			(island_removal_mode 0)
		)
		(polygon
			(pts
				(arc
					(start 314.026296 -279.749758)
					(mid 313.373516 -279.749758)
					(end 314.026296 -279.749758)
				)
			)
		)
	)
	(zone
		(layers "B.Cu" "In11.Cu" "In13.Cu" "In15.Cu")
		(hatch none 0.5)
		(connect_pads
			(clearance 0)
		)
		(min_thickness 0.25)
		(keepout
			(tracks not_allowed)
			(vias allowed)
			(pads allowed)
			(copperpour not_allowed)
			(footprints allowed)
		)
		(placement
			(enabled no)
			(sheetname "")
		)
		(fill yes
			(thermal_gap 0.5)
			(thermal_bridge_width 0.5)
			(island_removal_mode 0)
		)
		(polygon
			(pts
				(arc
					(start 154.219402 -107.377738)
					(mid 153.515822 -107.377738)
					(end 154.219402 -107.377738)
				)
			)
		)
	)
	(zone
		(layers "B.Cu" "In11.Cu" "In13.Cu" "In15.Cu")
		(hatch none 0.5)
		(connect_pads
			(clearance 0)
		)
		(min_thickness 0.25)
		(keepout
			(tracks not_allowed)
			(vias allowed)
			(pads allowed)
			(copperpour not_allowed)
			(footprints allowed)
		)
		(placement
			(enabled no)
			(sheetname "")
		)
		(fill yes
			(thermal_gap 0.5)
			(thermal_bridge_width 0.5)
			(island_removal_mode 0)
		)
		(polygon
			(pts
				(arc
					(start 171.289726 -383.290064)
					(mid 170.530266 -383.290064)
					(end 171.289726 -383.290064)
				)
			)
		)
	)
	(zone
		(layers "B.Cu" "In11.Cu" "In13.Cu" "In15.Cu")
		(hatch none 0.5)
		(connect_pads
			(clearance 0)
		)
		(min_thickness 0.25)
		(keepout
			(tracks not_allowed)
			(vias allowed)
			(pads allowed)
			(copperpour not_allowed)
			(footprints allowed)
		)
		(placement
			(enabled no)
			(sheetname "")
		)
		(fill yes
			(thermal_gap 0.5)
			(thermal_bridge_width 0.5)
			(island_removal_mode 0)
		)
		(polygon
			(pts
				(arc
					(start 307.376068 -277.849838)
					(mid 306.723288 -277.849838)
					(end 307.376068 -277.849838)
				)
			)
		)
	)
	(zone
		(layers "B.Cu" "In11.Cu" "In13.Cu" "In15.Cu")
		(hatch none 0.5)
		(connect_pads
			(clearance 0)
		)
		(min_thickness 0.25)
		(keepout
			(tracks not_allowed)
			(vias allowed)
			(pads allowed)
			(copperpour not_allowed)
			(footprints allowed)
		)
		(placement
			(enabled no)
			(sheetname "")
		)
		(fill yes
			(thermal_gap 0.5)
			(thermal_bridge_width 0.5)
			(island_removal_mode 0)
		)
		(polygon
			(pts
				(arc
					(start 432.82616 -156.085794)
					(mid 432.12258 -156.085794)
					(end 432.82616 -156.085794)
				)
			)
		)
	)
	(zone
		(layers "B.Cu" "In11.Cu" "In13.Cu" "In15.Cu")
		(hatch none 0.5)
		(connect_pads
			(clearance 0)
		)
		(min_thickness 0.25)
		(keepout
			(tracks not_allowed)
			(vias allowed)
			(pads allowed)
			(copperpour not_allowed)
			(footprints allowed)
		)
		(placement
			(enabled no)
			(sheetname "")
		)
		(fill yes
			(thermal_gap 0.5)
			(thermal_bridge_width 0.5)
			(island_removal_mode 0)
		)
		(polygon
			(pts
				(arc
					(start 432.82616 -148.88591)
					(mid 432.12258 -148.88591)
					(end 432.82616 -148.88591)
				)
			)
		)
	)
	(zone
		(layers "B.Cu" "In11.Cu" "In13.Cu" "In15.Cu")
		(hatch none 0.5)
		(connect_pads
			(clearance 0)
		)
		(min_thickness 0.25)
		(keepout
			(tracks not_allowed)
			(vias allowed)
			(pads allowed)
			(copperpour not_allowed)
			(footprints allowed)
		)
		(placement
			(enabled no)
			(sheetname "")
		)
		(fill yes
			(thermal_gap 0.5)
			(thermal_bridge_width 0.5)
			(island_removal_mode 0)
		)
		(polygon
			(pts
				(arc
					(start 191.276224 -287.349946)
					(mid 190.623444 -287.349946)
					(end 191.276224 -287.349946)
				)
			)
		)
	)
	(zone
		(layers "B.Cu" "In11.Cu" "In13.Cu" "In15.Cu")
		(hatch none 0.5)
		(connect_pads
			(clearance 0)
		)
		(min_thickness 0.25)
		(keepout
			(tracks not_allowed)
			(vias allowed)
			(pads allowed)
			(copperpour not_allowed)
			(footprints allowed)
		)
		(placement
			(enabled no)
			(sheetname "")
		)
		(fill yes
			(thermal_gap 0.5)
			(thermal_bridge_width 0.5)
			(island_removal_mode 0)
		)
		(polygon
			(pts
				(arc
					(start 238.93399 -87.976202)
					(mid 238.23041 -87.976202)
					(end 238.93399 -87.976202)
				)
			)
		)
	)
	(zone
		(layers "B.Cu" "In11.Cu" "In13.Cu" "In15.Cu")
		(hatch none 0.5)
		(connect_pads
			(clearance 0)
		)
		(min_thickness 0.25)
		(keepout
			(tracks not_allowed)
			(vias allowed)
			(pads allowed)
			(copperpour not_allowed)
			(footprints allowed)
		)
		(placement
			(enabled no)
			(sheetname "")
		)
		(fill yes
			(thermal_gap 0.5)
			(thermal_bridge_width 0.5)
			(island_removal_mode 0)
		)
		(polygon
			(pts
				(arc
					(start 158.026354 -315.849762)
					(mid 157.373574 -315.849762)
					(end 158.026354 -315.849762)
				)
			)
		)
	)
	(zone
		(layers "B.Cu" "In11.Cu" "In13.Cu" "In15.Cu")
		(hatch none 0.5)
		(connect_pads
			(clearance 0)
		)
		(min_thickness 0.25)
		(keepout
			(tracks not_allowed)
			(vias allowed)
			(pads allowed)
			(copperpour not_allowed)
			(footprints allowed)
		)
		(placement
			(enabled no)
			(sheetname "")
		)
		(fill yes
			(thermal_gap 0.5)
			(thermal_bridge_width 0.5)
			(island_removal_mode 0)
		)
		(polygon
			(pts
				(arc
					(start 81.884012 -142.615666)
					(mid 81.180432 -142.615666)
					(end 81.884012 -142.615666)
				)
			)
		)
	)
	(zone
		(layers "B.Cu" "In11.Cu" "In13.Cu" "In15.Cu")
		(hatch none 0.5)
		(connect_pads
			(clearance 0)
		)
		(min_thickness 0.25)
		(keepout
			(tracks not_allowed)
			(vias allowed)
			(pads allowed)
			(copperpour not_allowed)
			(footprints allowed)
		)
		(placement
			(enabled no)
			(sheetname "")
		)
		(fill yes
			(thermal_gap 0.5)
			(thermal_bridge_width 0.5)
			(island_removal_mode 0)
		)
		(polygon
			(pts
				(arc
					(start 180.82641 -280.699718)
					(mid 180.17363 -280.699718)
					(end 180.82641 -280.699718)
				)
			)
		)
	)
	(zone
		(layers "B.Cu" "In11.Cu" "In13.Cu" "In15.Cu")
		(hatch none 0.5)
		(connect_pads
			(clearance 0)
		)
		(min_thickness 0.25)
		(keepout
			(tracks not_allowed)
			(vias allowed)
			(pads allowed)
			(copperpour not_allowed)
			(footprints allowed)
		)
		(placement
			(enabled no)
			(sheetname "")
		)
		(fill yes
			(thermal_gap 0.5)
			(thermal_bridge_width 0.5)
			(island_removal_mode 0)
		)
		(polygon
			(pts
				(arc
					(start 175.689768 -383.290064)
					(mid 174.930308 -383.290064)
					(end 175.689768 -383.290064)
				)
			)
		)
	)
	(zone
		(layers "B.Cu" "In11.Cu" "In13.Cu" "In15.Cu")
		(hatch none 0.5)
		(connect_pads
			(clearance 0)
		)
		(min_thickness 0.25)
		(keepout
			(tracks not_allowed)
			(vias allowed)
			(pads allowed)
			(copperpour not_allowed)
			(footprints allowed)
		)
		(placement
			(enabled no)
			(sheetname "")
		)
		(fill yes
			(thermal_gap 0.5)
			(thermal_bridge_width 0.5)
			(island_removal_mode 0)
		)
		(polygon
			(pts
				(arc
					(start 435.26964 -383.290064)
					(mid 434.51018 -383.290064)
					(end 435.26964 -383.290064)
				)
			)
		)
	)
	(zone
		(layers "B.Cu" "In11.Cu" "In13.Cu" "In15.Cu")
		(hatch none 0.5)
		(connect_pads
			(clearance 0)
		)
		(min_thickness 0.25)
		(keepout
			(tracks not_allowed)
			(vias allowed)
			(pads allowed)
			(copperpour not_allowed)
			(footprints allowed)
		)
		(placement
			(enabled no)
			(sheetname "")
		)
		(fill yes
			(thermal_gap 0.5)
			(thermal_bridge_width 0.5)
			(island_removal_mode 0)
		)
		(polygon
			(pts
				(arc
					(start 157.076394 -318.699896)
					(mid 156.423614 -318.699896)
					(end 157.076394 -318.699896)
				)
			)
		)
	)
	(zone
		(layers "B.Cu" "In11.Cu" "In13.Cu" "In15.Cu")
		(hatch none 0.5)
		(connect_pads
			(clearance 0)
		)
		(min_thickness 0.25)
		(keepout
			(tracks not_allowed)
			(vias allowed)
			(pads allowed)
			(copperpour not_allowed)
			(footprints allowed)
		)
		(placement
			(enabled no)
			(sheetname "")
		)
		(fill yes
			(thermal_gap 0.5)
			(thermal_bridge_width 0.5)
			(island_removal_mode 0)
		)
		(polygon
			(pts
				(arc
					(start 173.48962 -383.490216)
					(mid 172.73016 -383.490216)
					(end 173.48962 -383.490216)
				)
			)
		)
	)
	(zone
		(layers "B.Cu" "In11.Cu" "In13.Cu" "In15.Cu")
		(hatch none 0.5)
		(connect_pads
			(clearance 0)
		)
		(min_thickness 0.25)
		(keepout
			(tracks not_allowed)
			(vias allowed)
			(pads allowed)
			(copperpour not_allowed)
			(footprints allowed)
		)
		(placement
			(enabled no)
			(sheetname "")
		)
		(fill yes
			(thermal_gap 0.5)
			(thermal_bridge_width 0.5)
			(island_removal_mode 0)
		)
		(polygon
			(pts
				(arc
					(start 151.577294 -109.18444)
					(mid 150.873714 -109.18444)
					(end 151.577294 -109.18444)
				)
			)
		)
	)
	(zone
		(layers "B.Cu" "In11.Cu" "In13.Cu" "In15.Cu")
		(hatch none 0.5)
		(connect_pads
			(clearance 0)
		)
		(min_thickness 0.25)
		(keepout
			(tracks not_allowed)
			(vias allowed)
			(pads allowed)
			(copperpour not_allowed)
			(footprints allowed)
		)
		(placement
			(enabled no)
			(sheetname "")
		)
		(fill yes
			(thermal_gap 0.5)
			(thermal_bridge_width 0.5)
			(island_removal_mode 0)
		)
		(polygon
			(pts
				(arc
					(start 336.269838 -375.69013)
					(mid 335.510378 -375.69013)
					(end 336.269838 -375.69013)
				)
			)
		)
	)
	(zone
		(layers "B.Cu" "In11.Cu" "In13.Cu" "In15.Cu")
		(hatch none 0.5)
		(connect_pads
			(clearance 0)
		)
		(min_thickness 0.25)
		(keepout
			(tracks not_allowed)
			(vias allowed)
			(pads allowed)
			(copperpour not_allowed)
			(footprints allowed)
		)
		(placement
			(enabled no)
			(sheetname "")
		)
		(fill yes
			(thermal_gap 0.5)
			(thermal_bridge_width 0.5)
			(island_removal_mode 0)
		)
		(polygon
			(pts
				(arc
					(start 310.226202 -284.499812)
					(mid 309.573422 -284.499812)
					(end 310.226202 -284.499812)
				)
			)
		)
	)
	(zone
		(layers "B.Cu" "In11.Cu" "In13.Cu" "In15.Cu")
		(hatch none 0.5)
		(connect_pads
			(clearance 0)
		)
		(min_thickness 0.25)
		(keepout
			(tracks not_allowed)
			(vias allowed)
			(pads allowed)
			(copperpour not_allowed)
			(footprints allowed)
		)
		(placement
			(enabled no)
			(sheetname "")
		)
		(fill yes
			(thermal_gap 0.5)
			(thermal_bridge_width 0.5)
			(island_removal_mode 0)
		)
		(polygon
			(pts
				(arc
					(start 157.076394 -317.749936)
					(mid 156.423614 -317.749936)
					(end 157.076394 -317.749936)
				)
			)
		)
	)
	(zone
		(layers "B.Cu" "In11.Cu" "In13.Cu" "In15.Cu")
		(hatch none 0.5)
		(connect_pads
			(clearance 0)
		)
		(min_thickness 0.25)
		(keepout
			(tracks not_allowed)
			(vias allowed)
			(pads allowed)
			(copperpour not_allowed)
			(footprints allowed)
		)
		(placement
			(enabled no)
			(sheetname "")
		)
		(fill yes
			(thermal_gap 0.5)
			(thermal_bridge_width 0.5)
			(island_removal_mode 0)
		)
		(polygon
			(pts
				(arc
					(start 298.826174 -279.749504)
					(mid 298.173394 -279.749504)
					(end 298.826174 -279.749504)
				)
			)
		)
	)
	(zone
		(layers "B.Cu" "In11.Cu" "In13.Cu" "In15.Cu")
		(hatch none 0.5)
		(connect_pads
			(clearance 0)
		)
		(min_thickness 0.25)
		(keepout
			(tracks not_allowed)
			(vias allowed)
			(pads allowed)
			(copperpour not_allowed)
			(footprints allowed)
		)
		(placement
			(enabled no)
			(sheetname "")
		)
		(fill yes
			(thermal_gap 0.5)
			(thermal_bridge_width 0.5)
			(island_removal_mode 0)
		)
		(polygon
			(pts
				(arc
					(start 340.66988 -375.69013)
					(mid 339.91042 -375.69013)
					(end 340.66988 -375.69013)
				)
			)
		)
	)
	(zone
		(layers "B.Cu" "In11.Cu" "In13.Cu" "In15.Cu")
		(hatch none 0.5)
		(connect_pads
			(clearance 0)
		)
		(min_thickness 0.25)
		(keepout
			(tracks not_allowed)
			(vias allowed)
			(pads allowed)
			(copperpour not_allowed)
			(footprints allowed)
		)
		(placement
			(enabled no)
			(sheetname "")
		)
		(fill yes
			(thermal_gap 0.5)
			(thermal_bridge_width 0.5)
			(island_removal_mode 0)
		)
		(polygon
			(pts
				(arc
					(start 428.669704 -383.490216)
					(mid 427.910244 -383.490216)
					(end 428.669704 -383.490216)
				)
			)
		)
	)
	(zone
		(layers "B.Cu" "In11.Cu" "In13.Cu" "In15.Cu")
		(hatch none 0.5)
		(connect_pads
			(clearance 0)
		)
		(min_thickness 0.25)
		(keepout
			(tracks not_allowed)
			(vias allowed)
			(pads allowed)
			(copperpour not_allowed)
			(footprints allowed)
		)
		(placement
			(enabled no)
			(sheetname "")
		)
		(fill yes
			(thermal_gap 0.5)
			(thermal_bridge_width 0.5)
			(island_removal_mode 0)
		)
		(polygon
			(pts
				(arc
					(start 424.269662 -408.190192)
					(mid 423.510202 -408.190192)
					(end 424.269662 -408.190192)
				)
			)
		)
	)
	(zone
		(layers "B.Cu" "In11.Cu" "In13.Cu" "In15.Cu")
		(hatch none 0.5)
		(connect_pads
			(clearance 0)
		)
		(min_thickness 0.25)
		(keepout
			(tracks not_allowed)
			(vias allowed)
			(pads allowed)
			(copperpour not_allowed)
			(footprints allowed)
		)
		(placement
			(enabled no)
			(sheetname "")
		)
		(fill yes
			(thermal_gap 0.5)
			(thermal_bridge_width 0.5)
			(island_removal_mode 0)
		)
		(polygon
			(pts
				(arc
					(start 85.489542 -397.790162)
					(mid 84.730082 -397.790162)
					(end 85.489542 -397.790162)
				)
			)
		)
	)
	(zone
		(layers "B.Cu" "In11.Cu" "In13.Cu" "In15.Cu")
		(hatch none 0.5)
		(connect_pads
			(clearance 0)
		)
		(min_thickness 0.25)
		(keepout
			(tracks not_allowed)
			(vias allowed)
			(pads allowed)
			(copperpour not_allowed)
			(footprints allowed)
		)
		(placement
			(enabled no)
			(sheetname "")
		)
		(fill yes
			(thermal_gap 0.5)
			(thermal_bridge_width 0.5)
			(island_removal_mode 0)
		)
		(polygon
			(pts
				(arc
					(start 69.476112 -278.799798)
					(mid 68.823332 -278.799798)
					(end 69.476112 -278.799798)
				)
			)
		)
	)
	(zone
		(layers "B.Cu" "In11.Cu" "In13.Cu" "In15.Cu")
		(hatch none 0.5)
		(connect_pads
			(clearance 0)
		)
		(min_thickness 0.25)
		(keepout
			(tracks not_allowed)
			(vias allowed)
			(pads allowed)
			(copperpour not_allowed)
			(footprints allowed)
		)
		(placement
			(enabled no)
			(sheetname "")
		)
		(fill yes
			(thermal_gap 0.5)
			(thermal_bridge_width 0.5)
			(island_removal_mode 0)
		)
		(polygon
			(pts
				(arc
					(start 38.119558 -103.777796)
					(mid 37.415978 -103.777796)
					(end 38.119558 -103.777796)
				)
			)
		)
	)
	(zone
		(layers "B.Cu" "In11.Cu" "In13.Cu" "In15.Cu")
		(hatch none 0.5)
		(connect_pads
			(clearance 0)
		)
		(min_thickness 0.25)
		(keepout
			(tracks not_allowed)
			(vias allowed)
			(pads allowed)
			(copperpour not_allowed)
			(footprints allowed)
		)
		(placement
			(enabled no)
			(sheetname "")
		)
		(fill yes
			(thermal_gap 0.5)
			(thermal_bridge_width 0.5)
			(island_removal_mode 0)
		)
		(polygon
			(pts
				(arc
					(start 66.626232 -279.749504)
					(mid 65.973452 -279.749504)
					(end 66.626232 -279.749504)
				)
			)
		)
	)
	(zone
		(layers "B.Cu" "In11.Cu" "In13.Cu" "In15.Cu")
		(hatch none 0.5)
		(connect_pads
			(clearance 0)
		)
		(min_thickness 0.25)
		(keepout
			(tracks not_allowed)
			(vias allowed)
			(pads allowed)
			(copperpour not_allowed)
			(footprints allowed)
		)
		(placement
			(enabled no)
			(sheetname "")
		)
		(fill yes
			(thermal_gap 0.5)
			(thermal_bridge_width 0.5)
			(island_removal_mode 0)
		)
		(polygon
			(pts
				(arc
					(start 153.2763 -316.799722)
					(mid 152.62352 -316.799722)
					(end 153.2763 -316.799722)
				)
			)
		)
	)
	(zone
		(layers "B.Cu" "In11.Cu" "In13.Cu" "In15.Cu")
		(hatch none 0.5)
		(connect_pads
			(clearance 0)
		)
		(min_thickness 0.25)
		(keepout
			(tracks not_allowed)
			(vias allowed)
			(pads allowed)
			(copperpour not_allowed)
			(footprints allowed)
		)
		(placement
			(enabled no)
			(sheetname "")
		)
		(fill yes
			(thermal_gap 0.5)
			(thermal_bridge_width 0.5)
			(island_removal_mode 0)
		)
		(polygon
			(pts
				(arc
					(start 283.626306 -315.849762)
					(mid 282.973526 -315.849762)
					(end 283.626306 -315.849762)
				)
			)
		)
	)
	(zone
		(layers "B.Cu" "In11.Cu" "In13.Cu" "In15.Cu")
		(hatch none 0.5)
		(connect_pads
			(clearance 0)
		)
		(min_thickness 0.25)
		(keepout
			(tracks not_allowed)
			(vias allowed)
			(pads allowed)
			(copperpour not_allowed)
			(footprints allowed)
		)
		(placement
			(enabled no)
			(sheetname "")
		)
		(fill yes
			(thermal_gap 0.5)
			(thermal_bridge_width 0.5)
			(island_removal_mode 0)
		)
		(polygon
			(pts
				(arc
					(start 151.577294 -105.584498)
					(mid 150.873714 -105.584498)
					(end 151.577294 -105.584498)
				)
			)
		)
	)
	(zone
		(layers "B.Cu" "In11.Cu" "In13.Cu" "In15.Cu")
		(hatch none 0.5)
		(connect_pads
			(clearance 0)
		)
		(min_thickness 0.25)
		(keepout
			(tracks not_allowed)
			(vias allowed)
			(pads allowed)
			(copperpour not_allowed)
			(footprints allowed)
		)
		(placement
			(enabled no)
			(sheetname "")
		)
		(fill yes
			(thermal_gap 0.5)
			(thermal_bridge_width 0.5)
			(island_removal_mode 0)
		)
		(polygon
			(pts
				(arc
					(start 291.22624 -316.799722)
					(mid 290.57346 -316.799722)
					(end 291.22624 -316.799722)
				)
			)
		)
	)
	(zone
		(layers "B.Cu" "In11.Cu" "In13.Cu" "In15.Cu")
		(hatch none 0.5)
		(connect_pads
			(clearance 0)
		)
		(min_thickness 0.25)
		(keepout
			(tracks not_allowed)
			(vias allowed)
			(pads allowed)
			(copperpour not_allowed)
			(footprints allowed)
		)
		(placement
			(enabled no)
			(sheetname "")
		)
		(fill yes
			(thermal_gap 0.5)
			(thermal_bridge_width 0.5)
			(island_removal_mode 0)
		)
		(polygon
			(pts
				(arc
					(start 200.625964 -148.02231)
					(mid 199.922384 -148.02231)
					(end 200.625964 -148.02231)
				)
			)
		)
	)
	(zone
		(layers "B.Cu" "In11.Cu" "In13.Cu" "In15.Cu")
		(hatch none 0.5)
		(connect_pads
			(clearance 0)
		)
		(min_thickness 0.25)
		(keepout
			(tracks not_allowed)
			(vias allowed)
			(pads allowed)
			(copperpour not_allowed)
			(footprints allowed)
		)
		(placement
			(enabled no)
			(sheetname "")
		)
		(fill yes
			(thermal_gap 0.5)
			(thermal_bridge_width 0.5)
			(island_removal_mode 0)
		)
		(polygon
			(pts
				(arc
					(start 191.276224 -283.549852)
					(mid 190.623444 -283.549852)
					(end 191.276224 -283.549852)
				)
			)
		)
	)
	(zone
		(layers "B.Cu" "In11.Cu" "In13.Cu" "In15.Cu")
		(hatch none 0.5)
		(connect_pads
			(clearance 0)
		)
		(min_thickness 0.25)
		(keepout
			(tracks not_allowed)
			(vias allowed)
			(pads allowed)
			(copperpour not_allowed)
			(footprints allowed)
		)
		(placement
			(enabled no)
			(sheetname "")
		)
		(fill yes
			(thermal_gap 0.5)
			(thermal_bridge_width 0.5)
			(island_removal_mode 0)
		)
		(polygon
			(pts
				(arc
					(start 84.52612 -120.502172)
					(mid 83.82254 -120.502172)
					(end 84.52612 -120.502172)
				)
			)
		)
	)
	(zone
		(layers "B.Cu" "In11.Cu" "In13.Cu" "In15.Cu")
		(hatch none 0.5)
		(connect_pads
			(clearance 0)
		)
		(min_thickness 0.25)
		(keepout
			(tracks not_allowed)
			(vias allowed)
			(pads allowed)
			(copperpour not_allowed)
			(footprints allowed)
		)
		(placement
			(enabled no)
			(sheetname "")
		)
		(fill yes
			(thermal_gap 0.5)
			(thermal_bridge_width 0.5)
			(island_removal_mode 0)
		)
		(polygon
			(pts
				(arc
					(start 433.069492 -409.490164)
					(mid 432.310032 -409.490164)
					(end 433.069492 -409.490164)
				)
			)
		)
	)
	(zone
		(layers "B.Cu" "In11.Cu" "In13.Cu" "In15.Cu")
		(hatch none 0.5)
		(connect_pads
			(clearance 0)
		)
		(min_thickness 0.25)
		(keepout
			(tracks not_allowed)
			(vias allowed)
			(pads allowed)
			(copperpour not_allowed)
			(footprints allowed)
		)
		(placement
			(enabled no)
			(sheetname "")
		)
		(fill yes
			(thermal_gap 0.5)
			(thermal_bridge_width 0.5)
			(island_removal_mode 0)
		)
		(polygon
			(pts
				(arc
					(start 99.1616 -201.35215)
					(mid 98.45802 -201.35215)
					(end 99.1616 -201.35215)
				)
			)
		)
	)
	(zone
		(layers "B.Cu" "In11.Cu" "In13.Cu" "In15.Cu")
		(hatch none 0.5)
		(connect_pads
			(clearance 0)
		)
		(min_thickness 0.25)
		(keepout
			(tracks not_allowed)
			(vias allowed)
			(pads allowed)
			(copperpour not_allowed)
			(footprints allowed)
		)
		(placement
			(enabled no)
			(sheetname "")
		)
		(fill yes
			(thermal_gap 0.5)
			(thermal_bridge_width 0.5)
			(island_removal_mode 0)
		)
		(polygon
			(pts
				(arc
					(start 176.076102 -277.849838)
					(mid 175.423322 -277.849838)
					(end 176.076102 -277.849838)
				)
			)
		)
	)
	(zone
		(layers "B.Cu" "In11.Cu" "In13.Cu" "In15.Cu")
		(hatch none 0.5)
		(connect_pads
			(clearance 0)
		)
		(min_thickness 0.25)
		(keepout
			(tracks not_allowed)
			(vias allowed)
			(pads allowed)
			(copperpour not_allowed)
			(footprints allowed)
		)
		(placement
			(enabled no)
			(sheetname "")
		)
		(fill yes
			(thermal_gap 0.5)
			(thermal_bridge_width 0.5)
			(island_removal_mode 0)
		)
		(polygon
			(pts
				(arc
					(start 35.47745 -111.920782)
					(mid 34.77387 -111.920782)
					(end 35.47745 -111.920782)
				)
			)
		)
	)
	(zone
		(layers "B.Cu" "In11.Cu" "In13.Cu" "In15.Cu")
		(hatch none 0.5)
		(connect_pads
			(clearance 0)
		)
		(min_thickness 0.25)
		(keepout
			(tracks not_allowed)
			(vias allowed)
			(pads allowed)
			(copperpour not_allowed)
			(footprints allowed)
		)
		(placement
			(enabled no)
			(sheetname "")
		)
		(fill yes
			(thermal_gap 0.5)
			(thermal_bridge_width 0.5)
			(island_removal_mode 0)
		)
		(polygon
			(pts
				(arc
					(start 158.976314 -318.699896)
					(mid 158.323534 -318.699896)
					(end 158.976314 -318.699896)
				)
			)
		)
	)
	(zone
		(layers "B.Cu" "In11.Cu" "In13.Cu" "In15.Cu")
		(hatch none 0.5)
		(connect_pads
			(clearance 0)
		)
		(min_thickness 0.25)
		(keepout
			(tracks not_allowed)
			(vias allowed)
			(pads allowed)
			(copperpour not_allowed)
			(footprints allowed)
		)
		(placement
			(enabled no)
			(sheetname "")
		)
		(fill yes
			(thermal_gap 0.5)
			(thermal_bridge_width 0.5)
			(island_removal_mode 0)
		)
		(polygon
			(pts
				(arc
					(start 433.069492 -383.490216)
					(mid 432.310032 -383.490216)
					(end 433.069492 -383.490216)
				)
			)
		)
	)
	(zone
		(layers "B.Cu" "In11.Cu" "In13.Cu" "In15.Cu")
		(hatch none 0.5)
		(connect_pads
			(clearance 0)
		)
		(min_thickness 0.25)
		(keepout
			(tracks not_allowed)
			(vias allowed)
			(pads allowed)
			(copperpour not_allowed)
			(footprints allowed)
		)
		(placement
			(enabled no)
			(sheetname "")
		)
		(fill yes
			(thermal_gap 0.5)
			(thermal_bridge_width 0.5)
			(island_removal_mode 0)
		)
		(polygon
			(pts
				(arc
					(start 418.726366 -279.749504)
					(mid 418.073586 -279.749504)
					(end 418.726366 -279.749504)
				)
			)
		)
	)
	(zone
		(layers "B.Cu" "In11.Cu" "In13.Cu" "In15.Cu")
		(hatch none 0.5)
		(connect_pads
			(clearance 0)
		)
		(min_thickness 0.25)
		(keepout
			(tracks not_allowed)
			(vias allowed)
			(pads allowed)
			(copperpour not_allowed)
			(footprints allowed)
		)
		(placement
			(enabled no)
			(sheetname "")
		)
		(fill yes
			(thermal_gap 0.5)
			(thermal_bridge_width 0.5)
			(island_removal_mode 0)
		)
		(polygon
			(pts
				(arc
					(start 154.219402 -133.104382)
					(mid 153.515822 -133.104382)
					(end 154.219402 -133.104382)
				)
			)
		)
	)
	(zone
		(layers "B.Cu" "In11.Cu" "In13.Cu" "In15.Cu")
		(hatch none 0.5)
		(connect_pads
			(clearance 0)
		)
		(min_thickness 0.25)
		(keepout
			(tracks not_allowed)
			(vias allowed)
			(pads allowed)
			(copperpour not_allowed)
			(footprints allowed)
		)
		(placement
			(enabled no)
			(sheetname "")
		)
		(fill yes
			(thermal_gap 0.5)
			(thermal_bridge_width 0.5)
			(island_removal_mode 0)
		)
		(polygon
			(pts
				(arc
					(start 178.926236 -279.749504)
					(mid 178.273456 -279.749504)
					(end 178.926236 -279.749504)
				)
			)
		)
	)
	(zone
		(layers "B.Cu" "In11.Cu" "In13.Cu" "In15.Cu")
		(hatch none 0.5)
		(connect_pads
			(clearance 0)
		)
		(min_thickness 0.25)
		(keepout
			(tracks not_allowed)
			(vias allowed)
			(pads allowed)
			(copperpour not_allowed)
			(footprints allowed)
		)
		(placement
			(enabled no)
			(sheetname "")
		)
		(fill yes
			(thermal_gap 0.5)
			(thermal_bridge_width 0.5)
			(island_removal_mode 0)
		)
		(polygon
			(pts
				(arc
					(start 314.083954 -130.769106)
					(mid 313.380374 -130.769106)
					(end 314.083954 -130.769106)
				)
			)
		)
	)
	(zone
		(layers "B.Cu" "In11.Cu" "In13.Cu" "In15.Cu")
		(hatch none 0.5)
		(connect_pads
			(clearance 0)
		)
		(min_thickness 0.25)
		(keepout
			(tracks not_allowed)
			(vias allowed)
			(pads allowed)
			(copperpour not_allowed)
			(footprints allowed)
		)
		(placement
			(enabled no)
			(sheetname "")
		)
		(fill yes
			(thermal_gap 0.5)
			(thermal_bridge_width 0.5)
			(island_removal_mode 0)
		)
		(polygon
			(pts
				(arc
					(start 87.68969 -398.890236)
					(mid 86.93023 -398.890236)
					(end 87.68969 -398.890236)
				)
			)
		)
	)
	(zone
		(layers "B.Cu" "In11.Cu" "In13.Cu" "In15.Cu")
		(hatch none 0.5)
		(connect_pads
			(clearance 0)
		)
		(min_thickness 0.25)
		(keepout
			(tracks not_allowed)
			(vias allowed)
			(pads allowed)
			(copperpour not_allowed)
			(footprints allowed)
		)
		(placement
			(enabled no)
			(sheetname "")
		)
		(fill yes
			(thermal_gap 0.5)
			(thermal_bridge_width 0.5)
			(island_removal_mode 0)
		)
		(polygon
			(pts
				(arc
					(start 314.083954 -142.615666)
					(mid 313.380374 -142.615666)
					(end 314.083954 -142.615666)
				)
			)
		)
	)
	(zone
		(layers "B.Cu" "In11.Cu" "In13.Cu" "In15.Cu")
		(hatch none 0.5)
		(connect_pads
			(clearance 0)
		)
		(min_thickness 0.25)
		(keepout
			(tracks not_allowed)
			(vias allowed)
			(pads allowed)
			(copperpour not_allowed)
			(footprints allowed)
		)
		(placement
			(enabled no)
			(sheetname "")
		)
		(fill yes
			(thermal_gap 0.5)
			(thermal_bridge_width 0.5)
			(island_removal_mode 0)
		)
		(polygon
			(pts
				(arc
					(start 385.476242 -310.149748)
					(mid 384.823462 -310.149748)
					(end 385.476242 -310.149748)
				)
			)
		)
	)
	(zone
		(layers "B.Cu" "In11.Cu" "In13.Cu" "In15.Cu")
		(hatch none 0.5)
		(connect_pads
			(clearance 0)
		)
		(min_thickness 0.25)
		(keepout
			(tracks not_allowed)
			(vias allowed)
			(pads allowed)
			(copperpour not_allowed)
			(footprints allowed)
		)
		(placement
			(enabled no)
			(sheetname "")
		)
		(fill yes
			(thermal_gap 0.5)
			(thermal_bridge_width 0.5)
			(island_removal_mode 0)
		)
		(polygon
			(pts
				(arc
					(start 35.47745 -130.434334)
					(mid 34.77387 -130.434334)
					(end 35.47745 -130.434334)
				)
			)
		)
	)
	(zone
		(layers "B.Cu" "In11.Cu" "In13.Cu" "In15.Cu")
		(hatch none 0.5)
		(connect_pads
			(clearance 0)
		)
		(min_thickness 0.25)
		(keepout
			(tracks not_allowed)
			(vias allowed)
			(pads allowed)
			(copperpour not_allowed)
			(footprints allowed)
		)
		(placement
			(enabled no)
			(sheetname "")
		)
		(fill yes
			(thermal_gap 0.5)
			(thermal_bridge_width 0.5)
			(island_removal_mode 0)
		)
		(polygon
			(pts
				(arc
					(start 307.376068 -278.799798)
					(mid 306.723288 -278.799798)
					(end 307.376068 -278.799798)
				)
			)
		)
	)
	(zone
		(layers "B.Cu" "In11.Cu" "In13.Cu" "In15.Cu")
		(hatch none 0.5)
		(connect_pads
			(clearance 0)
		)
		(min_thickness 0.25)
		(keepout
			(tracks not_allowed)
			(vias allowed)
			(pads allowed)
			(copperpour not_allowed)
			(footprints allowed)
		)
		(placement
			(enabled no)
			(sheetname "")
		)
		(fill yes
			(thermal_gap 0.5)
			(thermal_bridge_width 0.5)
			(island_removal_mode 0)
		)
		(polygon
			(pts
				(arc
					(start 270.3195 -125.494542)
					(mid 269.61592 -125.494542)
					(end 270.3195 -125.494542)
				)
			)
		)
	)
	(zone
		(layers "B.Cu" "In11.Cu" "In13.Cu" "In15.Cu")
		(hatch none 0.5)
		(connect_pads
			(clearance 0)
		)
		(min_thickness 0.25)
		(keepout
			(tracks not_allowed)
			(vias allowed)
			(pads allowed)
			(copperpour not_allowed)
			(footprints allowed)
		)
		(placement
			(enabled no)
			(sheetname "")
		)
		(fill yes
			(thermal_gap 0.5)
			(thermal_bridge_width 0.5)
			(island_removal_mode 0)
		)
		(polygon
			(pts
				(arc
					(start 295.976294 -318.699896)
					(mid 295.323514 -318.699896)
					(end 295.976294 -318.699896)
				)
			)
		)
	)
	(zone
		(layers "B.Cu" "In11.Cu" "In13.Cu" "In15.Cu")
		(hatch none 0.5)
		(connect_pads
			(clearance 0)
		)
		(min_thickness 0.25)
		(keepout
			(tracks not_allowed)
			(vias allowed)
			(pads allowed)
			(copperpour not_allowed)
			(footprints allowed)
		)
		(placement
			(enabled no)
			(sheetname "")
		)
		(fill yes
			(thermal_gap 0.5)
			(thermal_bridge_width 0.5)
			(island_removal_mode 0)
		)
		(polygon
			(pts
				(arc
					(start 413.976058 -278.799798)
					(mid 413.323278 -278.799798)
					(end 413.976058 -278.799798)
				)
			)
		)
	)
	(zone
		(layers "B.Cu" "In11.Cu" "In13.Cu" "In15.Cu")
		(hatch none 0.5)
		(connect_pads
			(clearance 0)
		)
		(min_thickness 0.25)
		(keepout
			(tracks not_allowed)
			(vias allowed)
			(pads allowed)
			(copperpour not_allowed)
			(footprints allowed)
		)
		(placement
			(enabled no)
			(sheetname "")
		)
		(fill yes
			(thermal_gap 0.5)
			(thermal_bridge_width 0.5)
			(island_removal_mode 0)
		)
		(polygon
			(pts
				(arc
					(start 385.476242 -304.449734)
					(mid 384.823462 -304.449734)
					(end 385.476242 -304.449734)
				)
			)
		)
	)
	(zone
		(layers "B.Cu" "In11.Cu" "In13.Cu" "In15.Cu")
		(hatch none 0.5)
		(connect_pads
			(clearance 0)
		)
		(min_thickness 0.25)
		(keepout
			(tracks not_allowed)
			(vias allowed)
			(pads allowed)
			(copperpour not_allowed)
			(footprints allowed)
		)
		(placement
			(enabled no)
			(sheetname "")
		)
		(fill yes
			(thermal_gap 0.5)
			(thermal_bridge_width 0.5)
			(island_removal_mode 0)
		)
		(polygon
			(pts
				(arc
					(start 297.876214 -317.749936)
					(mid 297.223434 -317.749936)
					(end 297.876214 -317.749936)
				)
			)
		)
	)
	(zone
		(layers "B.Cu" "In11.Cu" "In13.Cu" "In15.Cu")
		(hatch none 0.5)
		(connect_pads
			(clearance 0)
		)
		(min_thickness 0.25)
		(keepout
			(tracks not_allowed)
			(vias allowed)
			(pads allowed)
			(copperpour not_allowed)
			(footprints allowed)
		)
		(placement
			(enabled no)
			(sheetname "")
		)
		(fill yes
			(thermal_gap 0.5)
			(thermal_bridge_width 0.5)
			(island_removal_mode 0)
		)
		(polygon
			(pts
				(arc
					(start 83.289648 -375.490232)
					(mid 82.530188 -375.490232)
					(end 83.289648 -375.490232)
				)
			)
		)
	)
	(zone
		(layers "B.Cu" "In11.Cu" "In13.Cu" "In15.Cu")
		(hatch none 0.5)
		(connect_pads
			(clearance 0)
		)
		(min_thickness 0.25)
		(keepout
			(tracks not_allowed)
			(vias allowed)
			(pads allowed)
			(copperpour not_allowed)
			(footprints allowed)
		)
		(placement
			(enabled no)
			(sheetname "")
		)
		(fill yes
			(thermal_gap 0.5)
			(thermal_bridge_width 0.5)
			(island_removal_mode 0)
		)
		(polygon
			(pts
				(arc
					(start 200.625964 -131.712208)
					(mid 199.922384 -131.712208)
					(end 200.625964 -131.712208)
				)
			)
		)
	)
	(zone
		(layers "B.Cu" "In11.Cu" "In13.Cu" "In15.Cu")
		(hatch none 0.5)
		(connect_pads
			(clearance 0)
		)
		(min_thickness 0.25)
		(keepout
			(tracks not_allowed)
			(vias allowed)
			(pads allowed)
			(copperpour not_allowed)
			(footprints allowed)
		)
		(placement
			(enabled no)
			(sheetname "")
		)
		(fill yes
			(thermal_gap 0.5)
			(thermal_bridge_width 0.5)
			(island_removal_mode 0)
		)
		(polygon
			(pts
				(arc
					(start 270.3195 -103.777796)
					(mid 269.61592 -103.777796)
					(end 270.3195 -103.777796)
				)
			)
		)
	)
	(zone
		(layers "B.Cu" "In11.Cu" "In13.Cu" "In15.Cu")
		(hatch none 0.5)
		(connect_pads
			(clearance 0)
		)
		(min_thickness 0.25)
		(keepout
			(tracks not_allowed)
			(vias allowed)
			(pads allowed)
			(copperpour not_allowed)
			(footprints allowed)
		)
		(placement
			(enabled no)
			(sheetname "")
		)
		(fill yes
			(thermal_gap 0.5)
			(thermal_bridge_width 0.5)
			(island_removal_mode 0)
		)
		(polygon
			(pts
				(arc
					(start 84.52612 -148.02231)
					(mid 83.82254 -148.02231)
					(end 84.52612 -148.02231)
				)
			)
		)
	)
	(zone
		(layers "B.Cu" "In11.Cu" "In13.Cu" "In15.Cu")
		(hatch none 0.5)
		(connect_pads
			(clearance 0)
		)
		(min_thickness 0.25)
		(keepout
			(tracks not_allowed)
			(vias allowed)
			(pads allowed)
			(copperpour not_allowed)
			(footprints allowed)
		)
		(placement
			(enabled no)
			(sheetname "")
		)
		(fill yes
			(thermal_gap 0.5)
			(thermal_bridge_width 0.5)
			(island_removal_mode 0)
		)
		(polygon
			(pts
				(arc
					(start 155.176474 -303.499774)
					(mid 154.523694 -303.499774)
					(end 155.176474 -303.499774)
				)
			)
		)
	)
	(zone
		(layers "B.Cu" "In11.Cu" "In13.Cu" "In15.Cu")
		(hatch none 0.5)
		(connect_pads
			(clearance 0)
		)
		(min_thickness 0.25)
		(keepout
			(tracks not_allowed)
			(vias allowed)
			(pads allowed)
			(copperpour not_allowed)
			(footprints allowed)
		)
		(placement
			(enabled no)
			(sheetname "")
		)
		(fill yes
			(thermal_gap 0.5)
			(thermal_bridge_width 0.5)
			(island_removal_mode 0)
		)
		(polygon
			(pts
				(arc
					(start 173.48962 -382.18999)
					(mid 172.73016 -382.18999)
					(end 173.48962 -382.18999)
				)
			)
		)
	)
	(zone
		(layers "B.Cu" "In11.Cu" "In13.Cu" "In15.Cu")
		(hatch none 0.5)
		(connect_pads
			(clearance 0)
		)
		(min_thickness 0.25)
		(keepout
			(tracks not_allowed)
			(vias allowed)
			(pads allowed)
			(copperpour not_allowed)
			(footprints allowed)
		)
		(placement
			(enabled no)
			(sheetname "")
		)
		(fill yes
			(thermal_gap 0.5)
			(thermal_bridge_width 0.5)
			(island_removal_mode 0)
		)
		(polygon
			(pts
				(arc
					(start 200.625964 -152.485852)
					(mid 199.922384 -152.485852)
					(end 200.625964 -152.485852)
				)
			)
		)
	)
	(zone
		(layers "B.Cu" "In11.Cu" "In13.Cu" "In15.Cu")
		(hatch none 0.5)
		(connect_pads
			(clearance 0)
		)
		(min_thickness 0.25)
		(keepout
			(tracks not_allowed)
			(vias allowed)
			(pads allowed)
			(copperpour not_allowed)
			(footprints allowed)
		)
		(placement
			(enabled no)
			(sheetname "")
		)
		(fill yes
			(thermal_gap 0.5)
			(thermal_bridge_width 0.5)
			(island_removal_mode 0)
		)
		(polygon
			(pts
				(arc
					(start 296.926254 -280.699718)
					(mid 296.273474 -280.699718)
					(end 296.926254 -280.699718)
				)
			)
		)
	)
	(zone
		(layers "B.Cu" "In11.Cu" "In13.Cu" "In15.Cu")
		(hatch none 0.5)
		(connect_pads
			(clearance 0)
		)
		(min_thickness 0.25)
		(keepout
			(tracks not_allowed)
			(vias allowed)
			(pads allowed)
			(copperpour not_allowed)
			(footprints allowed)
		)
		(placement
			(enabled no)
			(sheetname "")
		)
		(fill yes
			(thermal_gap 0.5)
			(thermal_bridge_width 0.5)
			(island_removal_mode 0)
		)
		(polygon
			(pts
				(arc
					(start 85.489542 -375.69013)
					(mid 84.730082 -375.69013)
					(end 85.489542 -375.69013)
				)
			)
		)
	)
	(zone
		(layers "B.Cu" "In11.Cu" "In13.Cu" "In15.Cu")
		(hatch none 0.5)
		(connect_pads
			(clearance 0)
		)
		(min_thickness 0.25)
		(keepout
			(tracks not_allowed)
			(vias allowed)
			(pads allowed)
			(copperpour not_allowed)
			(footprints allowed)
		)
		(placement
			(enabled no)
			(sheetname "")
		)
		(fill yes
			(thermal_gap 0.5)
			(thermal_bridge_width 0.5)
			(island_removal_mode 0)
		)
		(polygon
			(pts
				(arc
					(start 312.126122 -279.749758)
					(mid 311.473342 -279.749758)
					(end 312.126122 -279.749758)
				)
			)
		)
	)
	(zone
		(layers "B.Cu" "In11.Cu" "In13.Cu" "In15.Cu")
		(hatch none 0.5)
		(connect_pads
			(clearance 0)
		)
		(min_thickness 0.25)
		(keepout
			(tracks not_allowed)
			(vias allowed)
			(pads allowed)
			(copperpour not_allowed)
			(footprints allowed)
		)
		(placement
			(enabled no)
			(sheetname "")
		)
		(fill yes
			(thermal_gap 0.5)
			(thermal_bridge_width 0.5)
			(island_removal_mode 0)
		)
		(polygon
			(pts
				(arc
					(start 185.57621 -277.849838)
					(mid 184.92343 -277.849838)
					(end 185.57621 -277.849838)
				)
			)
		)
	)
	(zone
		(layers "B.Cu" "In11.Cu" "In13.Cu" "In15.Cu")
		(hatch none 0.5)
		(connect_pads
			(clearance 0)
		)
		(min_thickness 0.25)
		(keepout
			(tracks not_allowed)
			(vias allowed)
			(pads allowed)
			(copperpour not_allowed)
			(footprints allowed)
		)
		(placement
			(enabled no)
			(sheetname "")
		)
		(fill yes
			(thermal_gap 0.5)
			(thermal_bridge_width 0.5)
			(island_removal_mode 0)
		)
		(polygon
			(pts
				(arc
					(start 430.869598 -383.290064)
					(mid 430.110138 -383.290064)
					(end 430.869598 -383.290064)
				)
			)
		)
	)
	(zone
		(layers "B.Cu" "In11.Cu" "In13.Cu" "In15.Cu")
		(hatch none 0.5)
		(connect_pads
			(clearance 0)
		)
		(min_thickness 0.25)
		(keepout
			(tracks not_allowed)
			(vias allowed)
			(pads allowed)
			(copperpour not_allowed)
			(footprints allowed)
		)
		(placement
			(enabled no)
			(sheetname "")
		)
		(fill yes
			(thermal_gap 0.5)
			(thermal_bridge_width 0.5)
			(island_removal_mode 0)
		)
		(polygon
			(pts
				(arc
					(start 402.227288 8.581644)
					(mid 401.523708 8.581644)
					(end 402.227288 8.581644)
				)
			)
		)
	)
	(zone
		(layers "B.Cu" "In11.Cu" "In13.Cu" "In15.Cu")
		(hatch none 0.5)
		(connect_pads
			(clearance 0)
		)
		(min_thickness 0.25)
		(keepout
			(tracks not_allowed)
			(vias allowed)
			(pads allowed)
			(copperpour not_allowed)
			(footprints allowed)
		)
		(placement
			(enabled no)
			(sheetname "")
		)
		(fill yes
			(thermal_gap 0.5)
			(thermal_bridge_width 0.5)
			(island_removal_mode 0)
		)
		(polygon
			(pts
				(arc
					(start 420.626286 -279.749504)
					(mid 419.973506 -279.749504)
					(end 420.626286 -279.749504)
				)
			)
		)
	)
	(zone
		(layers "B.Cu" "In11.Cu" "In13.Cu" "In15.Cu")
		(hatch none 0.5)
		(connect_pads
			(clearance 0)
		)
		(min_thickness 0.25)
		(keepout
			(tracks not_allowed)
			(vias allowed)
			(pads allowed)
			(copperpour not_allowed)
			(footprints allowed)
		)
		(placement
			(enabled no)
			(sheetname "")
		)
		(fill yes
			(thermal_gap 0.5)
			(thermal_bridge_width 0.5)
			(island_removal_mode 0)
		)
		(polygon
			(pts
				(arc
					(start 267.677392 -122.82424)
					(mid 266.973812 -122.82424)
					(end 267.677392 -122.82424)
				)
			)
		)
	)
	(zone
		(layers "B.Cu" "In11.Cu" "In13.Cu" "In15.Cu")
		(hatch none 0.5)
		(connect_pads
			(clearance 0)
		)
		(min_thickness 0.25)
		(keepout
			(tracks not_allowed)
			(vias allowed)
			(pads allowed)
			(copperpour not_allowed)
			(footprints allowed)
		)
		(placement
			(enabled no)
			(sheetname "")
		)
		(fill yes
			(thermal_gap 0.5)
			(thermal_bridge_width 0.5)
			(island_removal_mode 0)
		)
		(polygon
			(pts
				(arc
					(start 82.776314 -279.749758)
					(mid 82.123534 -279.749758)
					(end 82.776314 -279.749758)
				)
			)
		)
	)
	(zone
		(layers "B.Cu" "In11.Cu" "In13.Cu" "In15.Cu")
		(hatch none 0.5)
		(connect_pads
			(clearance 0)
		)
		(min_thickness 0.25)
		(keepout
			(tracks not_allowed)
			(vias allowed)
			(pads allowed)
			(copperpour not_allowed)
			(footprints allowed)
		)
		(placement
			(enabled no)
			(sheetname "")
		)
		(fill yes
			(thermal_gap 0.5)
			(thermal_bridge_width 0.5)
			(island_removal_mode 0)
		)
		(polygon
			(pts
				(arc
					(start 63.776098 -277.849838)
					(mid 63.123318 -277.849838)
					(end 63.776098 -277.849838)
				)
			)
		)
	)
	(zone
		(layers "B.Cu" "In11.Cu" "In13.Cu" "In15.Cu")
		(hatch none 0.5)
		(connect_pads
			(clearance 0)
		)
		(min_thickness 0.25)
		(keepout
			(tracks not_allowed)
			(vias allowed)
			(pads allowed)
			(copperpour not_allowed)
			(footprints allowed)
		)
		(placement
			(enabled no)
			(sheetname "")
		)
		(fill yes
			(thermal_gap 0.5)
			(thermal_bridge_width 0.5)
			(island_removal_mode 0)
		)
		(polygon
			(pts
				(arc
					(start 2.379472 -387.51129)
					(mid 1.675892 -387.51129)
					(end 2.379472 -387.51129)
				)
			)
		)
	)
	(zone
		(layers "B.Cu" "In11.Cu" "In13.Cu" "In15.Cu")
		(hatch none 0.5)
		(connect_pads
			(clearance 0)
		)
		(min_thickness 0.25)
		(keepout
			(tracks not_allowed)
			(vias allowed)
			(pads allowed)
			(copperpour not_allowed)
			(footprints allowed)
		)
		(placement
			(enabled no)
			(sheetname "")
		)
		(fill yes
			(thermal_gap 0.5)
			(thermal_bridge_width 0.5)
			(island_removal_mode 0)
		)
		(polygon
			(pts
				(arc
					(start 66.626232 -280.699718)
					(mid 65.973452 -280.699718)
					(end 66.626232 -280.699718)
				)
			)
		)
	)
	(zone
		(layers "B.Cu" "In11.Cu" "In13.Cu" "In15.Cu")
		(hatch none 0.5)
		(connect_pads
			(clearance 0)
		)
		(min_thickness 0.25)
		(keepout
			(tracks not_allowed)
			(vias allowed)
			(pads allowed)
			(copperpour not_allowed)
			(footprints allowed)
		)
		(placement
			(enabled no)
			(sheetname "")
		)
		(fill yes
			(thermal_gap 0.5)
			(thermal_bridge_width 0.5)
			(island_removal_mode 0)
		)
		(polygon
			(pts
				(arc
					(start 63.776352 -318.699896)
					(mid 63.123572 -318.699896)
					(end 63.776352 -318.699896)
				)
			)
		)
	)
	(zone
		(layers "B.Cu" "In11.Cu" "In13.Cu" "In15.Cu")
		(hatch none 0.5)
		(connect_pads
			(clearance 0)
		)
		(min_thickness 0.25)
		(keepout
			(tracks not_allowed)
			(vias allowed)
			(pads allowed)
			(copperpour not_allowed)
			(footprints allowed)
		)
		(placement
			(enabled no)
			(sheetname "")
		)
		(fill yes
			(thermal_gap 0.5)
			(thermal_bridge_width 0.5)
			(island_removal_mode 0)
		)
		(polygon
			(pts
				(arc
					(start 154.219402 -125.494542)
					(mid 153.515822 -125.494542)
					(end 154.219402 -125.494542)
				)
			)
		)
	)
	(zone
		(layers "B.Cu" "In11.Cu" "In13.Cu" "In15.Cu")
		(hatch none 0.5)
		(connect_pads
			(clearance 0)
		)
		(min_thickness 0.25)
		(keepout
			(tracks not_allowed)
			(vias allowed)
			(pads allowed)
			(copperpour not_allowed)
			(footprints allowed)
		)
		(placement
			(enabled no)
			(sheetname "")
		)
		(fill yes
			(thermal_gap 0.5)
			(thermal_bridge_width 0.5)
			(island_removal_mode 0)
		)
		(polygon
			(pts
				(arc
					(start 84.52612 -152.485852)
					(mid 83.82254 -152.485852)
					(end 84.52612 -152.485852)
				)
			)
		)
	)
	(zone
		(layers "B.Cu" "In11.Cu" "In13.Cu" "In15.Cu")
		(hatch none 0.5)
		(connect_pads
			(clearance 0)
		)
		(min_thickness 0.25)
		(keepout
			(tracks not_allowed)
			(vias allowed)
			(pads allowed)
			(copperpour not_allowed)
			(footprints allowed)
		)
		(placement
			(enabled no)
			(sheetname "")
		)
		(fill yes
			(thermal_gap 0.5)
			(thermal_bridge_width 0.5)
			(island_removal_mode 0)
		)
		(polygon
			(pts
				(arc
					(start 153.2763 -302.549814)
					(mid 152.62352 -302.549814)
					(end 153.2763 -302.549814)
				)
			)
		)
	)
	(zone
		(layers "B.Cu" "In11.Cu" "In13.Cu" "In15.Cu")
		(hatch none 0.5)
		(connect_pads
			(clearance 0)
		)
		(min_thickness 0.25)
		(keepout
			(tracks not_allowed)
			(vias allowed)
			(pads allowed)
			(copperpour not_allowed)
			(footprints allowed)
		)
		(placement
			(enabled no)
			(sheetname "")
		)
		(fill yes
			(thermal_gap 0.5)
			(thermal_bridge_width 0.5)
			(island_removal_mode 0)
		)
		(polygon
			(pts
				(arc
					(start 78.975966 -278.799798)
					(mid 78.323186 -278.799798)
					(end 78.975966 -278.799798)
				)
			)
		)
	)
	(zone
		(layers "B.Cu" "In11.Cu" "In13.Cu" "In15.Cu")
		(hatch none 0.5)
		(connect_pads
			(clearance 0)
		)
		(min_thickness 0.25)
		(keepout
			(tracks not_allowed)
			(vias allowed)
			(pads allowed)
			(copperpour not_allowed)
			(footprints allowed)
		)
		(placement
			(enabled no)
			(sheetname "")
		)
		(fill yes
			(thermal_gap 0.5)
			(thermal_bridge_width 0.5)
			(island_removal_mode 0)
		)
		(polygon
			(pts
				(arc
					(start 316.726062 -151.622252)
					(mid 316.022482 -151.622252)
					(end 316.726062 -151.622252)
				)
			)
		)
	)
	(zone
		(layers "B.Cu" "In11.Cu" "In13.Cu" "In15.Cu")
		(hatch none 0.5)
		(connect_pads
			(clearance 0)
		)
		(min_thickness 0.25)
		(keepout
			(tracks not_allowed)
			(vias allowed)
			(pads allowed)
			(copperpour not_allowed)
			(footprints allowed)
		)
		(placement
			(enabled no)
			(sheetname "")
		)
		(fill yes
			(thermal_gap 0.5)
			(thermal_bridge_width 0.5)
			(island_removal_mode 0)
		)
		(polygon
			(pts
				(arc
					(start 430.184052 -118.695724)
					(mid 429.480472 -118.695724)
					(end 430.184052 -118.695724)
				)
			)
		)
	)
	(zone
		(layers "B.Cu" "In11.Cu" "In13.Cu" "In15.Cu")
		(hatch none 0.5)
		(connect_pads
			(clearance 0)
		)
		(min_thickness 0.25)
		(keepout
			(tracks not_allowed)
			(vias allowed)
			(pads allowed)
			(copperpour not_allowed)
			(footprints allowed)
		)
		(placement
			(enabled no)
			(sheetname "")
		)
		(fill yes
			(thermal_gap 0.5)
			(thermal_bridge_width 0.5)
			(island_removal_mode 0)
		)
		(polygon
			(pts
				(arc
					(start 181.776116 -278.799798)
					(mid 181.123336 -278.799798)
					(end 181.776116 -278.799798)
				)
			)
		)
	)
	(zone
		(layers "B.Cu" "In11.Cu" "In13.Cu" "In15.Cu")
		(hatch none 0.5)
		(connect_pads
			(clearance 0)
		)
		(min_thickness 0.25)
		(keepout
			(tracks not_allowed)
			(vias allowed)
			(pads allowed)
			(copperpour not_allowed)
			(footprints allowed)
		)
		(placement
			(enabled no)
			(sheetname "")
		)
		(fill yes
			(thermal_gap 0.5)
			(thermal_bridge_width 0.5)
			(island_removal_mode 0)
		)
		(polygon
			(pts
				(arc
					(start 432.82616 -135.31215)
					(mid 432.12258 -135.31215)
					(end 432.82616 -135.31215)
				)
			)
		)
	)
	(zone
		(layers "B.Cu" "In11.Cu" "In13.Cu" "In15.Cu")
		(hatch none 0.5)
		(connect_pads
			(clearance 0)
		)
		(min_thickness 0.25)
		(keepout
			(tracks not_allowed)
			(vias allowed)
			(pads allowed)
			(copperpour not_allowed)
			(footprints allowed)
		)
		(placement
			(enabled no)
			(sheetname "")
		)
		(fill yes
			(thermal_gap 0.5)
			(thermal_bridge_width 0.5)
			(island_removal_mode 0)
		)
		(polygon
			(pts
				(arc
					(start 308.326282 -287.349946)
					(mid 307.673502 -287.349946)
					(end 308.326282 -287.349946)
				)
			)
		)
	)
	(zone
		(layers "B.Cu" "In11.Cu" "In13.Cu" "In15.Cu")
		(hatch none 0.5)
		(connect_pads
			(clearance 0)
		)
		(min_thickness 0.25)
		(keepout
			(tracks not_allowed)
			(vias allowed)
			(pads allowed)
			(copperpour not_allowed)
			(footprints allowed)
		)
		(placement
			(enabled no)
			(sheetname "")
		)
		(fill yes
			(thermal_gap 0.5)
			(thermal_bridge_width 0.5)
			(island_removal_mode 0)
		)
		(polygon
			(pts
				(arc
					(start 192.226438 -280.699718)
					(mid 191.573658 -280.699718)
					(end 192.226438 -280.699718)
				)
			)
		)
	)
	(zone
		(layers "B.Cu" "In11.Cu" "In13.Cu" "In15.Cu")
		(hatch none 0.5)
		(connect_pads
			(clearance 0)
		)
		(min_thickness 0.25)
		(keepout
			(tracks not_allowed)
			(vias allowed)
			(pads allowed)
			(copperpour not_allowed)
			(footprints allowed)
		)
		(placement
			(enabled no)
			(sheetname "")
		)
		(fill yes
			(thermal_gap 0.5)
			(thermal_bridge_width 0.5)
			(island_removal_mode 0)
		)
		(polygon
			(pts
				(arc
					(start 178.926236 -280.699718)
					(mid 178.273456 -280.699718)
					(end 178.926236 -280.699718)
				)
			)
		)
	)
	(zone
		(layers "B.Cu" "In11.Cu" "In13.Cu" "In15.Cu")
		(hatch none 0.5)
		(connect_pads
			(clearance 0)
		)
		(min_thickness 0.25)
		(keepout
			(tracks not_allowed)
			(vias allowed)
			(pads allowed)
			(copperpour not_allowed)
			(footprints allowed)
		)
		(placement
			(enabled no)
			(sheetname "")
		)
		(fill yes
			(thermal_gap 0.5)
			(thermal_bridge_width 0.5)
			(island_removal_mode 0)
		)
		(polygon
			(pts
				(arc
					(start 35.47745 -109.18444)
					(mid 34.77387 -109.18444)
					(end 35.47745 -109.18444)
				)
			)
		)
	)
	(zone
		(layers "B.Cu" "In11.Cu" "In13.Cu" "In15.Cu")
		(hatch none 0.5)
		(connect_pads
			(clearance 0)
		)
		(min_thickness 0.25)
		(keepout
			(tracks not_allowed)
			(vias allowed)
			(pads allowed)
			(copperpour not_allowed)
			(footprints allowed)
		)
		(placement
			(enabled no)
			(sheetname "")
		)
		(fill yes
			(thermal_gap 0.5)
			(thermal_bridge_width 0.5)
			(island_removal_mode 0)
		)
		(polygon
			(pts
				(arc
					(start 270.3195 -121.030746)
					(mid 269.61592 -121.030746)
					(end 270.3195 -121.030746)
				)
			)
		)
	)
	(zone
		(layers "B.Cu" "In11.Cu" "In13.Cu" "In15.Cu")
		(hatch none 0.5)
		(connect_pads
			(clearance 0)
		)
		(min_thickness 0.25)
		(keepout
			(tracks not_allowed)
			(vias allowed)
			(pads allowed)
			(copperpour not_allowed)
			(footprints allowed)
		)
		(placement
			(enabled no)
			(sheetname "")
		)
		(fill yes
			(thermal_gap 0.5)
			(thermal_bridge_width 0.5)
			(island_removal_mode 0)
		)
		(polygon
			(pts
				(arc
					(start 432.82616 -132.575808)
					(mid 432.12258 -132.575808)
					(end 432.82616 -132.575808)
				)
			)
		)
	)
	(zone
		(layers "B.Cu" "In11.Cu" "In13.Cu" "In15.Cu")
		(hatch none 0.5)
		(connect_pads
			(clearance 0)
		)
		(min_thickness 0.25)
		(keepout
			(tracks not_allowed)
			(vias allowed)
			(pads allowed)
			(copperpour not_allowed)
			(footprints allowed)
		)
		(placement
			(enabled no)
			(sheetname "")
		)
		(fill yes
			(thermal_gap 0.5)
			(thermal_bridge_width 0.5)
			(island_removal_mode 0)
		)
		(polygon
			(pts
				(arc
					(start 385.476242 -306.349908)
					(mid 384.823462 -306.349908)
					(end 385.476242 -306.349908)
				)
			)
		)
	)
	(zone
		(layers "B.Cu" "In11.Cu" "In13.Cu" "In15.Cu")
		(hatch none 0.5)
		(connect_pads
			(clearance 0)
		)
		(min_thickness 0.25)
		(keepout
			(tracks not_allowed)
			(vias allowed)
			(pads allowed)
			(copperpour not_allowed)
			(footprints allowed)
		)
		(placement
			(enabled no)
			(sheetname "")
		)
		(fill yes
			(thermal_gap 0.5)
			(thermal_bridge_width 0.5)
			(island_removal_mode 0)
		)
		(polygon
			(pts
				(arc
					(start 179.876196 -277.849838)
					(mid 179.223416 -277.849838)
					(end 179.876196 -277.849838)
				)
			)
		)
	)
	(zone
		(layers "B.Cu" "In11.Cu" "In13.Cu" "In15.Cu")
		(hatch none 0.5)
		(connect_pads
			(clearance 0)
		)
		(min_thickness 0.25)
		(keepout
			(tracks not_allowed)
			(vias allowed)
			(pads allowed)
			(copperpour not_allowed)
			(footprints allowed)
		)
		(placement
			(enabled no)
			(sheetname "")
		)
		(fill yes
			(thermal_gap 0.5)
			(thermal_bridge_width 0.5)
			(island_removal_mode 0)
		)
		(polygon
			(pts
				(arc
					(start 388.326376 -309.199788)
					(mid 387.673596 -309.199788)
					(end 388.326376 -309.199788)
				)
			)
		)
	)
	(zone
		(layers "B.Cu" "In11.Cu" "In13.Cu" "In15.Cu")
		(hatch none 0.5)
		(connect_pads
			(clearance 0)
		)
		(min_thickness 0.25)
		(keepout
			(tracks not_allowed)
			(vias allowed)
			(pads allowed)
			(copperpour not_allowed)
			(footprints allowed)
		)
		(placement
			(enabled no)
			(sheetname "")
		)
		(fill yes
			(thermal_gap 0.5)
			(thermal_bridge_width 0.5)
			(island_removal_mode 0)
		)
		(polygon
			(pts
				(arc
					(start 71.376032 -277.849838)
					(mid 70.723252 -277.849838)
					(end 71.376032 -277.849838)
				)
			)
		)
	)
	(zone
		(layers "B.Cu" "In11.Cu" "In13.Cu" "In15.Cu")
		(hatch none 0.5)
		(connect_pads
			(clearance 0)
		)
		(min_thickness 0.25)
		(keepout
			(tracks not_allowed)
			(vias allowed)
			(pads allowed)
			(copperpour not_allowed)
			(footprints allowed)
		)
		(placement
			(enabled no)
			(sheetname "")
		)
		(fill yes
			(thermal_gap 0.5)
			(thermal_bridge_width 0.5)
			(island_removal_mode 0)
		)
		(polygon
			(pts
				(arc
					(start 426.469556 -410.589984)
					(mid 425.710096 -410.589984)
					(end 426.469556 -410.589984)
				)
			)
		)
	)
	(zone
		(layers "B.Cu" "In11.Cu" "In13.Cu" "In15.Cu")
		(hatch none 0.5)
		(connect_pads
			(clearance 0)
		)
		(min_thickness 0.25)
		(keepout
			(tracks not_allowed)
			(vias allowed)
			(pads allowed)
			(copperpour not_allowed)
			(footprints allowed)
		)
		(placement
			(enabled no)
			(sheetname "")
		)
		(fill yes
			(thermal_gap 0.5)
			(thermal_bridge_width 0.5)
			(island_removal_mode 0)
		)
		(polygon
			(pts
				(arc
					(start 35.47745 -134.034276)
					(mid 34.77387 -134.034276)
					(end 35.47745 -134.034276)
				)
			)
		)
	)
	(zone
		(layers "B.Cu" "In11.Cu" "In13.Cu" "In15.Cu")
		(hatch none 0.5)
		(connect_pads
			(clearance 0)
		)
		(min_thickness 0.25)
		(keepout
			(tracks not_allowed)
			(vias allowed)
			(pads allowed)
			(copperpour not_allowed)
			(footprints allowed)
		)
		(placement
			(enabled no)
			(sheetname "")
		)
		(fill yes
			(thermal_gap 0.5)
			(thermal_bridge_width 0.5)
			(island_removal_mode 0)
		)
		(polygon
			(pts
				(arc
					(start 409.226258 -279.749504)
					(mid 408.573478 -279.749504)
					(end 409.226258 -279.749504)
				)
			)
		)
	)
	(zone
		(layers "B.Cu" "In11.Cu" "In13.Cu" "In15.Cu")
		(hatch none 0.5)
		(connect_pads
			(clearance 0)
		)
		(min_thickness 0.25)
		(keepout
			(tracks not_allowed)
			(vias allowed)
			(pads allowed)
			(copperpour not_allowed)
			(footprints allowed)
		)
		(placement
			(enabled no)
			(sheetname "")
		)
		(fill yes
			(thermal_gap 0.5)
			(thermal_bridge_width 0.5)
			(island_removal_mode 0)
		)
		(polygon
			(pts
				(arc
					(start 430.184052 -146.215608)
					(mid 429.480472 -146.215608)
					(end 430.184052 -146.215608)
				)
			)
		)
	)
	(zone
		(layers "B.Cu" "In11.Cu" "In13.Cu" "In15.Cu")
		(hatch none 0.5)
		(connect_pads
			(clearance 0)
		)
		(min_thickness 0.25)
		(keepout
			(tracks not_allowed)
			(vias allowed)
			(pads allowed)
			(copperpour not_allowed)
			(footprints allowed)
		)
		(placement
			(enabled no)
			(sheetname "")
		)
		(fill yes
			(thermal_gap 0.5)
			(thermal_bridge_width 0.5)
			(island_removal_mode 0)
		)
		(polygon
			(pts
				(arc
					(start 72.28967 -374.390158)
					(mid 71.53021 -374.390158)
					(end 72.28967 -374.390158)
				)
			)
		)
	)
	(zone
		(layers "B.Cu" "In11.Cu" "In13.Cu" "In15.Cu")
		(hatch none 0.5)
		(connect_pads
			(clearance 0)
		)
		(min_thickness 0.25)
		(keepout
			(tracks not_allowed)
			(vias allowed)
			(pads allowed)
			(copperpour not_allowed)
			(footprints allowed)
		)
		(placement
			(enabled no)
			(sheetname "")
		)
		(fill yes
			(thermal_gap 0.5)
			(thermal_bridge_width 0.5)
			(island_removal_mode 0)
		)
		(polygon
			(pts
				(arc
					(start 173.48962 -408.190192)
					(mid 172.73016 -408.190192)
					(end 173.48962 -408.190192)
				)
			)
		)
	)
	(zone
		(layers "B.Cu" "In11.Cu" "In13.Cu" "In15.Cu")
		(hatch none 0.5)
		(connect_pads
			(clearance 0)
		)
		(min_thickness 0.25)
		(keepout
			(tracks not_allowed)
			(vias allowed)
			(pads allowed)
			(copperpour not_allowed)
			(footprints allowed)
		)
		(placement
			(enabled no)
			(sheetname "")
		)
		(fill yes
			(thermal_gap 0.5)
			(thermal_bridge_width 0.5)
			(island_removal_mode 0)
		)
		(polygon
			(pts
				(arc
					(start 38.119558 -110.114334)
					(mid 37.415978 -110.114334)
					(end 38.119558 -110.114334)
				)
			)
		)
	)
	(zone
		(layers "B.Cu" "In11.Cu" "In13.Cu" "In15.Cu")
		(hatch none 0.5)
		(connect_pads
			(clearance 0)
		)
		(min_thickness 0.25)
		(keepout
			(tracks not_allowed)
			(vias allowed)
			(pads allowed)
			(copperpour not_allowed)
			(footprints allowed)
		)
		(placement
			(enabled no)
			(sheetname "")
		)
		(fill yes
			(thermal_gap 0.5)
			(thermal_bridge_width 0.5)
			(island_removal_mode 0)
		)
		(polygon
			(pts
				(arc
					(start 286.476186 -318.699896)
					(mid 285.823406 -318.699896)
					(end 286.476186 -318.699896)
				)
			)
		)
	)
	(zone
		(layers "B.Cu" "In11.Cu" "In13.Cu" "In15.Cu")
		(hatch none 0.5)
		(connect_pads
			(clearance 0)
		)
		(min_thickness 0.25)
		(keepout
			(tracks not_allowed)
			(vias allowed)
			(pads allowed)
			(copperpour not_allowed)
			(footprints allowed)
		)
		(placement
			(enabled no)
			(sheetname "")
		)
		(fill yes
			(thermal_gap 0.5)
			(thermal_bridge_width 0.5)
			(island_removal_mode 0)
		)
		(polygon
			(pts
				(arc
					(start 391.176256 -318.699896)
					(mid 390.523476 -318.699896)
					(end 391.176256 -318.699896)
				)
			)
		)
	)
	(zone
		(layers "B.Cu" "In11.Cu" "In13.Cu" "In15.Cu")
		(hatch none 0.5)
		(connect_pads
			(clearance 0)
		)
		(min_thickness 0.25)
		(keepout
			(tracks not_allowed)
			(vias allowed)
			(pads allowed)
			(copperpour not_allowed)
			(footprints allowed)
		)
		(placement
			(enabled no)
			(sheetname "")
		)
		(fill yes
			(thermal_gap 0.5)
			(thermal_bridge_width 0.5)
			(island_removal_mode 0)
		)
		(polygon
			(pts
				(arc
					(start 151.577294 -104.720898)
					(mid 150.873714 -104.720898)
					(end 151.577294 -104.720898)
				)
			)
		)
	)
	(zone
		(layers "B.Cu" "In11.Cu" "In13.Cu" "In15.Cu")
		(hatch none 0.5)
		(connect_pads
			(clearance 0)
		)
		(min_thickness 0.25)
		(keepout
			(tracks not_allowed)
			(vias allowed)
			(pads allowed)
			(copperpour not_allowed)
			(footprints allowed)
		)
		(placement
			(enabled no)
			(sheetname "")
		)
		(fill yes
			(thermal_gap 0.5)
			(thermal_bridge_width 0.5)
			(island_removal_mode 0)
		)
		(polygon
			(pts
				(arc
					(start 316.726062 -120.502172)
					(mid 316.022482 -120.502172)
					(end 316.726062 -120.502172)
				)
			)
		)
	)
	(zone
		(layers "B.Cu" "In11.Cu" "In13.Cu" "In15.Cu")
		(hatch none 0.5)
		(connect_pads
			(clearance 0)
		)
		(min_thickness 0.25)
		(keepout
			(tracks not_allowed)
			(vias allowed)
			(pads allowed)
			(copperpour not_allowed)
			(footprints allowed)
		)
		(placement
			(enabled no)
			(sheetname "")
		)
		(fill yes
			(thermal_gap 0.5)
			(thermal_bridge_width 0.5)
			(island_removal_mode 0)
		)
		(polygon
			(pts
				(arc
					(start 35.47745 -104.720898)
					(mid 34.77387 -104.720898)
					(end 35.47745 -104.720898)
				)
			)
		)
	)
	(zone
		(layers "B.Cu" "In11.Cu" "In13.Cu" "In15.Cu")
		(hatch none 0.5)
		(connect_pads
			(clearance 0)
		)
		(min_thickness 0.25)
		(keepout
			(tracks not_allowed)
			(vias allowed)
			(pads allowed)
			(copperpour not_allowed)
			(footprints allowed)
		)
		(placement
			(enabled no)
			(sheetname "")
		)
		(fill yes
			(thermal_gap 0.5)
			(thermal_bridge_width 0.5)
			(island_removal_mode 0)
		)
		(polygon
			(pts
				(arc
					(start 162.489642 -410.589984)
					(mid 161.730182 -410.589984)
					(end 162.489642 -410.589984)
				)
			)
		)
	)
	(zone
		(layers "B.Cu" "In11.Cu" "In13.Cu" "In15.Cu")
		(hatch none 0.5)
		(connect_pads
			(clearance 0)
		)
		(min_thickness 0.25)
		(keepout
			(tracks not_allowed)
			(vias allowed)
			(pads allowed)
			(copperpour not_allowed)
			(footprints allowed)
		)
		(placement
			(enabled no)
			(sheetname "")
		)
		(fill yes
			(thermal_gap 0.5)
			(thermal_bridge_width 0.5)
			(island_removal_mode 0)
		)
		(polygon
			(pts
				(arc
					(start 60.926218 -280.699718)
					(mid 60.273438 -280.699718)
					(end 60.926218 -280.699718)
				)
			)
		)
	)
	(zone
		(layers "B.Cu" "In11.Cu" "In13.Cu" "In15.Cu")
		(hatch none 0.5)
		(connect_pads
			(clearance 0)
		)
		(min_thickness 0.25)
		(keepout
			(tracks not_allowed)
			(vias allowed)
			(pads allowed)
			(copperpour not_allowed)
			(footprints allowed)
		)
		(placement
			(enabled no)
			(sheetname "")
		)
		(fill yes
			(thermal_gap 0.5)
			(thermal_bridge_width 0.5)
			(island_removal_mode 0)
		)
		(polygon
			(pts
				(arc
					(start 298.826174 -280.699718)
					(mid 298.173394 -280.699718)
					(end 298.826174 -280.699718)
				)
			)
		)
	)
	(zone
		(layers "B.Cu" "In11.Cu" "In13.Cu" "In15.Cu")
		(hatch none 0.5)
		(connect_pads
			(clearance 0)
		)
		(min_thickness 0.25)
		(keepout
			(tracks not_allowed)
			(vias allowed)
			(pads allowed)
			(copperpour not_allowed)
			(footprints allowed)
		)
		(placement
			(enabled no)
			(sheetname "")
		)
		(fill yes
			(thermal_gap 0.5)
			(thermal_bridge_width 0.5)
			(island_removal_mode 0)
		)
		(polygon
			(pts
				(arc
					(start 182.72633 -279.749504)
					(mid 182.07355 -279.749504)
					(end 182.72633 -279.749504)
				)
			)
		)
	)
	(zone
		(layers "B.Cu" "In11.Cu" "In13.Cu" "In15.Cu")
		(hatch none 0.5)
		(connect_pads
			(clearance 0)
		)
		(min_thickness 0.25)
		(keepout
			(tracks not_allowed)
			(vias allowed)
			(pads allowed)
			(copperpour not_allowed)
			(footprints allowed)
		)
		(placement
			(enabled no)
			(sheetname "")
		)
		(fill yes
			(thermal_gap 0.5)
			(thermal_bridge_width 0.5)
			(island_removal_mode 0)
		)
		(polygon
			(pts
				(arc
					(start 197.983856 -133.505702)
					(mid 197.280276 -133.505702)
					(end 197.983856 -133.505702)
				)
			)
		)
	)
	(zone
		(layers "B.Cu" "In11.Cu" "In13.Cu" "In15.Cu")
		(hatch none 0.5)
		(connect_pads
			(clearance 0)
		)
		(min_thickness 0.25)
		(keepout
			(tracks not_allowed)
			(vias allowed)
			(pads allowed)
			(copperpour not_allowed)
			(footprints allowed)
		)
		(placement
			(enabled no)
			(sheetname "")
		)
		(fill yes
			(thermal_gap 0.5)
			(thermal_bridge_width 0.5)
			(island_removal_mode 0)
		)
		(polygon
			(pts
				(arc
					(start 386.419598 -107.377738)
					(mid 385.716018 -107.377738)
					(end 386.419598 -107.377738)
				)
			)
		)
	)
	(zone
		(layers "B.Cu" "In11.Cu" "In13.Cu" "In15.Cu")
		(hatch none 0.5)
		(connect_pads
			(clearance 0)
		)
		(min_thickness 0.25)
		(keepout
			(tracks not_allowed)
			(vias allowed)
			(pads allowed)
			(copperpour not_allowed)
			(footprints allowed)
		)
		(placement
			(enabled no)
			(sheetname "")
		)
		(fill yes
			(thermal_gap 0.5)
			(thermal_bridge_width 0.5)
			(island_removal_mode 0)
		)
		(polygon
			(pts
				(arc
					(start 194.126358 -288.299906)
					(mid 193.473578 -288.299906)
					(end 194.126358 -288.299906)
				)
			)
		)
	)
	(zone
		(layers "B.Cu" "In11.Cu" "In13.Cu" "In15.Cu")
		(hatch none 0.5)
		(connect_pads
			(clearance 0)
		)
		(min_thickness 0.25)
		(keepout
			(tracks not_allowed)
			(vias allowed)
			(pads allowed)
			(copperpour not_allowed)
			(footprints allowed)
		)
		(placement
			(enabled no)
			(sheetname "")
		)
		(fill yes
			(thermal_gap 0.5)
			(thermal_bridge_width 0.5)
			(island_removal_mode 0)
		)
		(polygon
			(pts
				(arc
					(start 300.726094 -279.749504)
					(mid 300.073314 -279.749504)
					(end 300.726094 -279.749504)
				)
			)
		)
	)
	(zone
		(layers "B.Cu" "In11.Cu" "In13.Cu" "In15.Cu")
		(hatch none 0.5)
		(connect_pads
			(clearance 0)
		)
		(min_thickness 0.25)
		(keepout
			(tracks not_allowed)
			(vias allowed)
			(pads allowed)
			(copperpour not_allowed)
			(footprints allowed)
		)
		(placement
			(enabled no)
			(sheetname "")
		)
		(fill yes
			(thermal_gap 0.5)
			(thermal_bridge_width 0.5)
			(island_removal_mode 0)
		)
		(polygon
			(pts
				(arc
					(start 193.176398 -284.499812)
					(mid 192.523618 -284.499812)
					(end 193.176398 -284.499812)
				)
			)
		)
	)
	(zone
		(layers "B.Cu" "In11.Cu" "In13.Cu" "In15.Cu")
		(hatch none 0.5)
		(connect_pads
			(clearance 0)
		)
		(min_thickness 0.25)
		(keepout
			(tracks not_allowed)
			(vias allowed)
			(pads allowed)
			(copperpour not_allowed)
			(footprints allowed)
		)
		(placement
			(enabled no)
			(sheetname "")
		)
		(fill yes
			(thermal_gap 0.5)
			(thermal_bridge_width 0.5)
			(island_removal_mode 0)
		)
		(polygon
			(pts
				(arc
					(start 415.875978 -278.799798)
					(mid 415.223198 -278.799798)
					(end 415.875978 -278.799798)
				)
			)
		)
	)
	(zone
		(layers "B.Cu" "In11.Cu" "In13.Cu" "In15.Cu")
		(hatch none 0.5)
		(connect_pads
			(clearance 0)
		)
		(min_thickness 0.25)
		(keepout
			(tracks not_allowed)
			(vias allowed)
			(pads allowed)
			(copperpour not_allowed)
			(footprints allowed)
		)
		(placement
			(enabled no)
			(sheetname "")
		)
		(fill yes
			(thermal_gap 0.5)
			(thermal_bridge_width 0.5)
			(island_removal_mode 0)
		)
		(polygon
			(pts
				(arc
					(start 184.62625 -279.749504)
					(mid 183.97347 -279.749504)
					(end 184.62625 -279.749504)
				)
			)
		)
	)
	(zone
		(layers "B.Cu" "In11.Cu" "In13.Cu" "In15.Cu")
		(hatch none 0.5)
		(connect_pads
			(clearance 0)
		)
		(min_thickness 0.25)
		(keepout
			(tracks not_allowed)
			(vias allowed)
			(pads allowed)
			(copperpour not_allowed)
			(footprints allowed)
		)
		(placement
			(enabled no)
			(sheetname "")
		)
		(fill yes
			(thermal_gap 0.5)
			(thermal_bridge_width 0.5)
			(island_removal_mode 0)
		)
		(polygon
			(pts
				(arc
					(start 169.089832 -409.490164)
					(mid 168.330372 -409.490164)
					(end 169.089832 -409.490164)
				)
			)
		)
	)
	(zone
		(layers "B.Cu" "In11.Cu" "In13.Cu" "In15.Cu")
		(hatch none 0.5)
		(connect_pads
			(clearance 0)
		)
		(min_thickness 0.25)
		(keepout
			(tracks not_allowed)
			(vias allowed)
			(pads allowed)
			(copperpour not_allowed)
			(footprints allowed)
		)
		(placement
			(enabled no)
			(sheetname "")
		)
		(fill yes
			(thermal_gap 0.5)
			(thermal_bridge_width 0.5)
			(island_removal_mode 0)
		)
		(polygon
			(pts
				(arc
					(start 414.926272 -280.699718)
					(mid 414.273492 -280.699718)
					(end 414.926272 -280.699718)
				)
			)
		)
	)
	(zone
		(layers "B.Cu" "In11.Cu" "In13.Cu" "In15.Cu")
		(hatch none 0.5)
		(connect_pads
			(clearance 0)
		)
		(min_thickness 0.25)
		(keepout
			(tracks not_allowed)
			(vias allowed)
			(pads allowed)
			(copperpour not_allowed)
			(footprints allowed)
		)
		(placement
			(enabled no)
			(sheetname "")
		)
		(fill yes
			(thermal_gap 0.5)
			(thermal_bridge_width 0.5)
			(island_removal_mode 0)
		)
		(polygon
			(pts
				(arc
					(start 310.226202 -279.749504)
					(mid 309.573422 -279.749504)
					(end 310.226202 -279.749504)
				)
			)
		)
	)
	(zone
		(layers "B.Cu" "In11.Cu" "In13.Cu" "In15.Cu")
		(hatch none 0.5)
		(connect_pads
			(clearance 0)
		)
		(min_thickness 0.25)
		(keepout
			(tracks not_allowed)
			(vias allowed)
			(pads allowed)
			(copperpour not_allowed)
			(footprints allowed)
		)
		(placement
			(enabled no)
			(sheetname "")
		)
		(fill yes
			(thermal_gap 0.5)
			(thermal_bridge_width 0.5)
			(island_removal_mode 0)
		)
		(polygon
			(pts
				(arc
					(start 35.47745 -108.32084)
					(mid 34.77387 -108.32084)
					(end 35.47745 -108.32084)
				)
			)
		)
	)
	(zone
		(layers "B.Cu" "In11.Cu" "In13.Cu" "In15.Cu")
		(hatch none 0.5)
		(connect_pads
			(clearance 0)
		)
		(min_thickness 0.25)
		(keepout
			(tracks not_allowed)
			(vias allowed)
			(pads allowed)
			(copperpour not_allowed)
			(footprints allowed)
		)
		(placement
			(enabled no)
			(sheetname "")
		)
		(fill yes
			(thermal_gap 0.5)
			(thermal_bridge_width 0.5)
			(island_removal_mode 0)
		)
		(polygon
			(pts
				(arc
					(start 154.219402 -136.704324)
					(mid 153.515822 -136.704324)
					(end 154.219402 -136.704324)
				)
			)
		)
	)
	(zone
		(layers "B.Cu" "In11.Cu" "In13.Cu" "In15.Cu")
		(hatch none 0.5)
		(connect_pads
			(clearance 0)
		)
		(min_thickness 0.25)
		(keepout
			(tracks not_allowed)
			(vias allowed)
			(pads allowed)
			(copperpour not_allowed)
			(footprints allowed)
		)
		(placement
			(enabled no)
			(sheetname "")
		)
		(fill yes
			(thermal_gap 0.5)
			(thermal_bridge_width 0.5)
			(island_removal_mode 0)
		)
		(polygon
			(pts
				(arc
					(start 38.119558 -136.704324)
					(mid 37.415978 -136.704324)
					(end 38.119558 -136.704324)
				)
			)
		)
	)
	(zone
		(layers "B.Cu" "In11.Cu" "In13.Cu" "In15.Cu")
		(hatch none 0.5)
		(connect_pads
			(clearance 0)
		)
		(min_thickness 0.25)
		(keepout
			(tracks not_allowed)
			(vias allowed)
			(pads allowed)
			(copperpour not_allowed)
			(footprints allowed)
		)
		(placement
			(enabled no)
			(sheetname "")
		)
		(fill yes
			(thermal_gap 0.5)
			(thermal_bridge_width 0.5)
			(island_removal_mode 0)
		)
		(polygon
			(pts
				(arc
					(start 59.976004 -278.799798)
					(mid 59.323224 -278.799798)
					(end 59.976004 -278.799798)
				)
			)
		)
	)
	(zone
		(layers "B.Cu" "In11.Cu" "In13.Cu" "In15.Cu")
		(hatch none 0.5)
		(connect_pads
			(clearance 0)
		)
		(min_thickness 0.25)
		(keepout
			(tracks not_allowed)
			(vias allowed)
			(pads allowed)
			(copperpour not_allowed)
			(footprints allowed)
		)
		(placement
			(enabled no)
			(sheetname "")
		)
		(fill yes
			(thermal_gap 0.5)
			(thermal_bridge_width 0.5)
			(island_removal_mode 0)
		)
		(polygon
			(pts
				(arc
					(start 58.076338 -318.699896)
					(mid 57.423558 -318.699896)
					(end 58.076338 -318.699896)
				)
			)
		)
	)
	(zone
		(layers "B.Cu" "In11.Cu" "In13.Cu" "In15.Cu")
		(hatch none 0.5)
		(connect_pads
			(clearance 0)
		)
		(min_thickness 0.25)
		(keepout
			(tracks not_allowed)
			(vias allowed)
			(pads allowed)
			(copperpour not_allowed)
			(footprints allowed)
		)
		(placement
			(enabled no)
			(sheetname "")
		)
		(fill yes
			(thermal_gap 0.5)
			(thermal_bridge_width 0.5)
			(island_removal_mode 0)
		)
		(polygon
			(pts
				(arc
					(start 166.889684 -384.590036)
					(mid 166.130224 -384.590036)
					(end 166.889684 -384.590036)
				)
			)
		)
	)
	(zone
		(layers "B.Cu" "In11.Cu" "In13.Cu" "In15.Cu")
		(hatch none 0.5)
		(connect_pads
			(clearance 0)
		)
		(min_thickness 0.25)
		(keepout
			(tracks not_allowed)
			(vias allowed)
			(pads allowed)
			(copperpour not_allowed)
			(footprints allowed)
		)
		(placement
			(enabled no)
			(sheetname "")
		)
		(fill yes
			(thermal_gap 0.5)
			(thermal_bridge_width 0.5)
			(island_removal_mode 0)
		)
		(polygon
			(pts
				(arc
					(start 176.076102 -278.799798)
					(mid 175.423322 -278.799798)
					(end 176.076102 -278.799798)
				)
			)
		)
	)
	(zone
		(layers "B.Cu" "In11.Cu" "In13.Cu" "In15.Cu")
		(hatch none 0.5)
		(connect_pads
			(clearance 0)
		)
		(min_thickness 0.25)
		(keepout
			(tracks not_allowed)
			(vias allowed)
			(pads allowed)
			(copperpour not_allowed)
			(footprints allowed)
		)
		(placement
			(enabled no)
			(sheetname "")
		)
		(fill yes
			(thermal_gap 0.5)
			(thermal_bridge_width 0.5)
			(island_removal_mode 0)
		)
		(polygon
			(pts
				(arc
					(start 432.82616 -124.965714)
					(mid 432.12258 -124.965714)
					(end 432.82616 -124.965714)
				)
			)
		)
	)
	(zone
		(layers "B.Cu" "In11.Cu" "In13.Cu" "In15.Cu")
		(hatch none 0.5)
		(connect_pads
			(clearance 0)
		)
		(min_thickness 0.25)
		(keepout
			(tracks not_allowed)
			(vias allowed)
			(pads allowed)
			(copperpour not_allowed)
			(footprints allowed)
		)
		(placement
			(enabled no)
			(sheetname "")
		)
		(fill yes
			(thermal_gap 0.5)
			(thermal_bridge_width 0.5)
			(island_removal_mode 0)
		)
		(polygon
			(pts
				(arc
					(start 425.376086 -277.849838)
					(mid 424.723306 -277.849838)
					(end 425.376086 -277.849838)
				)
			)
		)
	)
	(zone
		(layers "B.Cu" "In11.Cu" "In13.Cu" "In15.Cu")
		(hatch none 0.5)
		(connect_pads
			(clearance 0)
		)
		(min_thickness 0.25)
		(keepout
			(tracks not_allowed)
			(vias allowed)
			(pads allowed)
			(copperpour not_allowed)
			(footprints allowed)
		)
		(placement
			(enabled no)
			(sheetname "")
		)
		(fill yes
			(thermal_gap 0.5)
			(thermal_bridge_width 0.5)
			(island_removal_mode 0)
		)
		(polygon
			(pts
				(arc
					(start 424.269662 -383.490216)
					(mid 423.510202 -383.490216)
					(end 424.269662 -383.490216)
				)
			)
		)
	)
	(zone
		(layers "B.Cu" "In11.Cu" "In13.Cu" "In15.Cu")
		(hatch none 0.5)
		(connect_pads
			(clearance 0)
		)
		(min_thickness 0.25)
		(keepout
			(tracks not_allowed)
			(vias allowed)
			(pads allowed)
			(copperpour not_allowed)
			(footprints allowed)
		)
		(placement
			(enabled no)
			(sheetname "")
		)
		(fill yes
			(thermal_gap 0.5)
			(thermal_bridge_width 0.5)
			(island_removal_mode 0)
		)
		(polygon
			(pts
				(arc
					(start 426.3263 -280.699718)
					(mid 425.67352 -280.699718)
					(end 426.3263 -280.699718)
				)
			)
		)
	)
	(zone
		(layers "B.Cu" "In11.Cu" "In13.Cu" "In15.Cu")
		(hatch none 0.5)
		(connect_pads
			(clearance 0)
		)
		(min_thickness 0.25)
		(keepout
			(tracks not_allowed)
			(vias allowed)
			(pads allowed)
			(copperpour not_allowed)
			(footprints allowed)
		)
		(placement
			(enabled no)
			(sheetname "")
		)
		(fill yes
			(thermal_gap 0.5)
			(thermal_bridge_width 0.5)
			(island_removal_mode 0)
		)
		(polygon
			(pts
				(arc
					(start 386.426202 -306.349908)
					(mid 385.773422 -306.349908)
					(end 386.426202 -306.349908)
				)
			)
		)
	)
	(zone
		(layers "B.Cu" "In11.Cu" "In13.Cu" "In15.Cu")
		(hatch none 0.5)
		(connect_pads
			(clearance 0)
		)
		(min_thickness 0.25)
		(keepout
			(tracks not_allowed)
			(vias allowed)
			(pads allowed)
			(copperpour not_allowed)
			(footprints allowed)
		)
		(placement
			(enabled no)
			(sheetname "")
		)
		(fill yes
			(thermal_gap 0.5)
			(thermal_bridge_width 0.5)
			(island_removal_mode 0)
		)
		(polygon
			(pts
				(arc
					(start 190.326264 -280.699718)
					(mid 189.673484 -280.699718)
					(end 190.326264 -280.699718)
				)
			)
		)
	)
	(zone
		(layers "B.Cu" "In11.Cu" "In13.Cu" "In15.Cu")
		(hatch none 0.5)
		(connect_pads
			(clearance 0)
		)
		(min_thickness 0.25)
		(keepout
			(tracks not_allowed)
			(vias allowed)
			(pads allowed)
			(copperpour not_allowed)
			(footprints allowed)
		)
		(placement
			(enabled no)
			(sheetname "")
		)
		(fill yes
			(thermal_gap 0.5)
			(thermal_bridge_width 0.5)
			(island_removal_mode 0)
		)
		(polygon
			(pts
				(arc
					(start 423.476166 -285.449772)
					(mid 422.823386 -285.449772)
					(end 423.476166 -285.449772)
				)
			)
		)
	)
	(zone
		(layers "B.Cu" "In11.Cu" "In13.Cu" "In15.Cu")
		(hatch none 0.5)
		(connect_pads
			(clearance 0)
		)
		(min_thickness 0.25)
		(keepout
			(tracks not_allowed)
			(vias allowed)
			(pads allowed)
			(copperpour not_allowed)
			(footprints allowed)
		)
		(placement
			(enabled no)
			(sheetname "")
		)
		(fill yes
			(thermal_gap 0.5)
			(thermal_bridge_width 0.5)
			(island_removal_mode 0)
		)
		(polygon
			(pts
				(arc
					(start 336.269838 -397.790162)
					(mid 335.510378 -397.790162)
					(end 336.269838 -397.790162)
				)
			)
		)
	)
	(zone
		(layers "B.Cu" "In11.Cu" "In13.Cu" "In15.Cu")
		(hatch none 0.5)
		(connect_pads
			(clearance 0)
		)
		(min_thickness 0.25)
		(keepout
			(tracks not_allowed)
			(vias allowed)
			(pads allowed)
			(copperpour not_allowed)
			(footprints allowed)
		)
		(placement
			(enabled no)
			(sheetname "")
		)
		(fill yes
			(thermal_gap 0.5)
			(thermal_bridge_width 0.5)
			(island_removal_mode 0)
		)
		(polygon
			(pts
				(arc
					(start 38.119558 -121.894346)
					(mid 37.415978 -121.894346)
					(end 38.119558 -121.894346)
				)
			)
		)
	)
	(zone
		(layers "B.Cu" "In11.Cu" "In13.Cu" "In15.Cu")
		(hatch none 0.5)
		(connect_pads
			(clearance 0)
		)
		(min_thickness 0.25)
		(keepout
			(tracks not_allowed)
			(vias allowed)
			(pads allowed)
			(copperpour not_allowed)
			(footprints allowed)
		)
		(placement
			(enabled no)
			(sheetname "")
		)
		(fill yes
			(thermal_gap 0.5)
			(thermal_bridge_width 0.5)
			(island_removal_mode 0)
		)
		(polygon
			(pts
				(arc
					(start 189.37605 -278.799798)
					(mid 188.72327 -278.799798)
					(end 189.37605 -278.799798)
				)
			)
		)
	)
	(zone
		(layers "B.Cu" "In11.Cu" "In13.Cu" "In15.Cu")
		(hatch none 0.5)
		(connect_pads
			(clearance 0)
		)
		(min_thickness 0.25)
		(keepout
			(tracks not_allowed)
			(vias allowed)
			(pads allowed)
			(copperpour not_allowed)
			(footprints allowed)
		)
		(placement
			(enabled no)
			(sheetname "")
		)
		(fill yes
			(thermal_gap 0.5)
			(thermal_bridge_width 0.5)
			(island_removal_mode 0)
		)
		(polygon
			(pts
				(arc
					(start 36.08705 -101.984302)
					(mid 35.38347 -101.984302)
					(end 36.08705 -101.984302)
				)
			)
		)
	)
	(zone
		(layers "B.Cu" "In11.Cu" "In13.Cu" "In15.Cu")
		(hatch none 0.5)
		(connect_pads
			(clearance 0)
		)
		(min_thickness 0.25)
		(keepout
			(tracks not_allowed)
			(vias allowed)
			(pads allowed)
			(copperpour not_allowed)
			(footprints allowed)
		)
		(placement
			(enabled no)
			(sheetname "")
		)
		(fill yes
			(thermal_gap 0.5)
			(thermal_bridge_width 0.5)
			(island_removal_mode 0)
		)
		(polygon
			(pts
				(arc
					(start 191.276224 -278.799798)
					(mid 190.623444 -278.799798)
					(end 191.276224 -278.799798)
				)
			)
		)
	)
	(zone
		(layers "B.Cu" "In11.Cu" "In13.Cu" "In15.Cu")
		(hatch none 0.5)
		(connect_pads
			(clearance 0)
		)
		(min_thickness 0.25)
		(keepout
			(tracks not_allowed)
			(vias allowed)
			(pads allowed)
			(copperpour not_allowed)
			(footprints allowed)
		)
		(placement
			(enabled no)
			(sheetname "")
		)
		(fill yes
			(thermal_gap 0.5)
			(thermal_bridge_width 0.5)
			(island_removal_mode 0)
		)
		(polygon
			(pts
				(arc
					(start 308.326282 -285.449772)
					(mid 307.673502 -285.449772)
					(end 308.326282 -285.449772)
				)
			)
		)
	)
	(zone
		(layers "B.Cu" "In11.Cu" "In13.Cu" "In15.Cu")
		(hatch none 0.5)
		(connect_pads
			(clearance 0)
		)
		(min_thickness 0.25)
		(keepout
			(tracks not_allowed)
			(vias allowed)
			(pads allowed)
			(copperpour not_allowed)
			(footprints allowed)
		)
		(placement
			(enabled no)
			(sheetname "")
		)
		(fill yes
			(thermal_gap 0.5)
			(thermal_bridge_width 0.5)
			(island_removal_mode 0)
		)
		(polygon
			(pts
				(arc
					(start 81.884012 -118.695724)
					(mid 81.180432 -118.695724)
					(end 81.884012 -118.695724)
				)
			)
		)
	)
	(zone
		(layers "B.Cu" "In11.Cu" "In13.Cu" "In15.Cu")
		(hatch none 0.5)
		(connect_pads
			(clearance 0)
		)
		(min_thickness 0.25)
		(keepout
			(tracks not_allowed)
			(vias allowed)
			(pads allowed)
			(copperpour not_allowed)
			(footprints allowed)
		)
		(placement
			(enabled no)
			(sheetname "")
		)
		(fill yes
			(thermal_gap 0.5)
			(thermal_bridge_width 0.5)
			(island_removal_mode 0)
		)
		(polygon
			(pts
				(arc
					(start 296.926254 -315.849762)
					(mid 296.273474 -315.849762)
					(end 296.926254 -315.849762)
				)
			)
		)
	)
	(zone
		(layers "B.Cu" "In11.Cu" "In13.Cu" "In15.Cu")
		(hatch none 0.5)
		(connect_pads
			(clearance 0)
		)
		(min_thickness 0.25)
		(keepout
			(tracks not_allowed)
			(vias allowed)
			(pads allowed)
			(copperpour not_allowed)
			(footprints allowed)
		)
		(placement
			(enabled no)
			(sheetname "")
		)
		(fill yes
			(thermal_gap 0.5)
			(thermal_bridge_width 0.5)
			(island_removal_mode 0)
		)
		(polygon
			(pts
				(arc
					(start 38.119558 -132.240782)
					(mid 37.415978 -132.240782)
					(end 38.119558 -132.240782)
				)
			)
		)
	)
	(zone
		(layers "B.Cu" "In11.Cu" "In13.Cu" "In15.Cu")
		(hatch none 0.5)
		(connect_pads
			(clearance 0)
		)
		(min_thickness 0.25)
		(keepout
			(tracks not_allowed)
			(vias allowed)
			(pads allowed)
			(copperpour not_allowed)
			(footprints allowed)
		)
		(placement
			(enabled no)
			(sheetname "")
		)
		(fill yes
			(thermal_gap 0.5)
			(thermal_bridge_width 0.5)
			(island_removal_mode 0)
		)
		(polygon
			(pts
				(arc
					(start 200.625964 -135.31215)
					(mid 199.922384 -135.31215)
					(end 200.625964 -135.31215)
				)
			)
		)
	)
	(zone
		(layers "B.Cu" "In11.Cu" "In13.Cu" "In15.Cu")
		(hatch none 0.5)
		(connect_pads
			(clearance 0)
		)
		(min_thickness 0.25)
		(keepout
			(tracks not_allowed)
			(vias allowed)
			(pads allowed)
			(copperpour not_allowed)
			(footprints allowed)
		)
		(placement
			(enabled no)
			(sheetname "")
		)
		(fill yes
			(thermal_gap 0.5)
			(thermal_bridge_width 0.5)
			(island_removal_mode 0)
		)
		(polygon
			(pts
				(arc
					(start 426.469556 -384.590036)
					(mid 425.710096 -384.590036)
					(end 426.469556 -384.590036)
				)
			)
		)
	)
	(zone
		(layers "B.Cu" "In11.Cu" "In13.Cu" "In15.Cu")
		(hatch none 0.5)
		(connect_pads
			(clearance 0)
		)
		(min_thickness 0.25)
		(keepout
			(tracks not_allowed)
			(vias allowed)
			(pads allowed)
			(copperpour not_allowed)
			(footprints allowed)
		)
		(placement
			(enabled no)
			(sheetname "")
		)
		(fill yes
			(thermal_gap 0.5)
			(thermal_bridge_width 0.5)
			(island_removal_mode 0)
		)
		(polygon
			(pts
				(arc
					(start 78.889606 -397.59001)
					(mid 78.130146 -397.59001)
					(end 78.889606 -397.59001)
				)
			)
		)
	)
	(zone
		(layers "B.Cu" "In11.Cu" "In13.Cu" "In15.Cu")
		(hatch none 0.5)
		(connect_pads
			(clearance 0)
		)
		(min_thickness 0.25)
		(keepout
			(tracks not_allowed)
			(vias allowed)
			(pads allowed)
			(copperpour not_allowed)
			(footprints allowed)
		)
		(placement
			(enabled no)
			(sheetname "")
		)
		(fill yes
			(thermal_gap 0.5)
			(thermal_bridge_width 0.5)
			(island_removal_mode 0)
		)
		(polygon
			(pts
				(arc
					(start 347.269816 -375.490232)
					(mid 346.510356 -375.490232)
					(end 347.269816 -375.490232)
				)
			)
		)
	)
	(zone
		(layers "B.Cu" "In11.Cu" "In13.Cu" "In15.Cu")
		(hatch none 0.5)
		(connect_pads
			(clearance 0)
		)
		(min_thickness 0.25)
		(keepout
			(tracks not_allowed)
			(vias allowed)
			(pads allowed)
			(copperpour not_allowed)
			(footprints allowed)
		)
		(placement
			(enabled no)
			(sheetname "")
		)
		(fill yes
			(thermal_gap 0.5)
			(thermal_bridge_width 0.5)
			(island_removal_mode 0)
		)
		(polygon
			(pts
				(arc
					(start 412.076138 -277.849838)
					(mid 411.423358 -277.849838)
					(end 412.076138 -277.849838)
				)
			)
		)
	)
	(zone
		(layers "B.Cu" "In11.Cu" "In13.Cu" "In15.Cu")
		(hatch none 0.5)
		(connect_pads
			(clearance 0)
		)
		(min_thickness 0.25)
		(keepout
			(tracks not_allowed)
			(vias allowed)
			(pads allowed)
			(copperpour not_allowed)
			(footprints allowed)
		)
		(placement
			(enabled no)
			(sheetname "")
		)
		(fill yes
			(thermal_gap 0.5)
			(thermal_bridge_width 0.5)
			(island_removal_mode 0)
		)
		(polygon
			(pts
				(arc
					(start 87.68969 -375.490232)
					(mid 86.93023 -375.490232)
					(end 87.68969 -375.490232)
				)
			)
		)
	)
	(zone
		(layers "B.Cu" "In11.Cu" "In13.Cu" "In15.Cu")
		(hatch none 0.5)
		(connect_pads
			(clearance 0)
		)
		(min_thickness 0.25)
		(keepout
			(tracks not_allowed)
			(vias allowed)
			(pads allowed)
			(copperpour not_allowed)
			(footprints allowed)
		)
		(placement
			(enabled no)
			(sheetname "")
		)
		(fill yes
			(thermal_gap 0.5)
			(thermal_bridge_width 0.5)
			(island_removal_mode 0)
		)
		(polygon
			(pts
				(arc
					(start 194.126358 -286.399986)
					(mid 193.473578 -286.399986)
					(end 194.126358 -286.399986)
				)
			)
		)
	)
	(zone
		(layers "B.Cu" "In11.Cu" "In13.Cu" "In15.Cu")
		(hatch none 0.5)
		(connect_pads
			(clearance 0)
		)
		(min_thickness 0.25)
		(keepout
			(tracks not_allowed)
			(vias allowed)
			(pads allowed)
			(copperpour not_allowed)
			(footprints allowed)
		)
		(placement
			(enabled no)
			(sheetname "")
		)
		(fill yes
			(thermal_gap 0.5)
			(thermal_bridge_width 0.5)
			(island_removal_mode 0)
		)
		(polygon
			(pts
				(arc
					(start 74.489564 -376.790204)
					(mid 73.730104 -376.790204)
					(end 74.489564 -376.790204)
				)
			)
		)
	)
	(zone
		(layers "B.Cu" "In11.Cu" "In13.Cu" "In15.Cu")
		(hatch none 0.5)
		(connect_pads
			(clearance 0)
		)
		(min_thickness 0.25)
		(keepout
			(tracks not_allowed)
			(vias allowed)
			(pads allowed)
			(copperpour not_allowed)
			(footprints allowed)
		)
		(placement
			(enabled no)
			(sheetname "")
		)
		(fill yes
			(thermal_gap 0.5)
			(thermal_bridge_width 0.5)
			(island_removal_mode 0)
		)
		(polygon
			(pts
				(arc
					(start 169.089832 -408.190192)
					(mid 168.330372 -408.190192)
					(end 169.089832 -408.190192)
				)
			)
		)
	)
	(zone
		(layers "B.Cu" "In11.Cu" "In13.Cu" "In15.Cu")
		(hatch none 0.5)
		(connect_pads
			(clearance 0)
		)
		(min_thickness 0.25)
		(keepout
			(tracks not_allowed)
			(vias allowed)
			(pads allowed)
			(copperpour not_allowed)
			(footprints allowed)
		)
		(placement
			(enabled no)
			(sheetname "")
		)
		(fill yes
			(thermal_gap 0.5)
			(thermal_bridge_width 0.5)
			(island_removal_mode 0)
		)
		(polygon
			(pts
				(arc
					(start 56.176164 -317.749936)
					(mid 55.523384 -317.749936)
					(end 56.176164 -317.749936)
				)
			)
		)
	)
	(zone
		(layers "B.Cu" "In11.Cu" "In13.Cu" "In15.Cu")
		(hatch none 0.5)
		(connect_pads
			(clearance 0)
		)
		(min_thickness 0.25)
		(keepout
			(tracks not_allowed)
			(vias allowed)
			(pads allowed)
			(copperpour not_allowed)
			(footprints allowed)
		)
		(placement
			(enabled no)
			(sheetname "")
		)
		(fill yes
			(thermal_gap 0.5)
			(thermal_bridge_width 0.5)
			(island_removal_mode 0)
		)
		(polygon
			(pts
				(arc
					(start 316.726062 -135.31215)
					(mid 316.022482 -135.31215)
					(end 316.726062 -135.31215)
				)
			)
		)
	)
	(zone
		(layers "B.Cu" "In11.Cu" "In13.Cu" "In15.Cu")
		(hatch none 0.5)
		(connect_pads
			(clearance 0)
		)
		(min_thickness 0.25)
		(keepout
			(tracks not_allowed)
			(vias allowed)
			(pads allowed)
			(copperpour not_allowed)
			(footprints allowed)
		)
		(placement
			(enabled no)
			(sheetname "")
		)
		(fill yes
			(thermal_gap 0.5)
			(thermal_bridge_width 0.5)
			(island_removal_mode 0)
		)
		(polygon
			(pts
				(arc
					(start 175.689768 -410.589984)
					(mid 174.930308 -410.589984)
					(end 175.689768 -410.589984)
				)
			)
		)
	)
	(zone
		(layers "B.Cu" "In11.Cu" "In13.Cu" "In15.Cu")
		(hatch none 0.5)
		(connect_pads
			(clearance 0)
		)
		(min_thickness 0.25)
		(keepout
			(tracks not_allowed)
			(vias allowed)
			(pads allowed)
			(copperpour not_allowed)
			(footprints allowed)
		)
		(placement
			(enabled no)
			(sheetname "")
		)
		(fill yes
			(thermal_gap 0.5)
			(thermal_bridge_width 0.5)
			(island_removal_mode 0)
		)
		(polygon
			(pts
				(arc
					(start 386.419598 -102.914196)
					(mid 385.716018 -102.914196)
					(end 386.419598 -102.914196)
				)
			)
		)
	)
	(zone
		(layers "B.Cu" "In11.Cu" "In13.Cu" "In15.Cu")
		(hatch none 0.5)
		(connect_pads
			(clearance 0)
		)
		(min_thickness 0.25)
		(keepout
			(tracks not_allowed)
			(vias allowed)
			(pads allowed)
			(copperpour not_allowed)
			(footprints allowed)
		)
		(placement
			(enabled no)
			(sheetname "")
		)
		(fill yes
			(thermal_gap 0.5)
			(thermal_bridge_width 0.5)
			(island_removal_mode 0)
		)
		(polygon
			(pts
				(arc
					(start 61.876178 -317.749936)
					(mid 61.223398 -317.749936)
					(end 61.876178 -317.749936)
				)
			)
		)
	)
	(zone
		(layers "B.Cu" "In11.Cu" "In13.Cu" "In15.Cu")
		(hatch none 0.5)
		(connect_pads
			(clearance 0)
		)
		(min_thickness 0.25)
		(keepout
			(tracks not_allowed)
			(vias allowed)
			(pads allowed)
			(copperpour not_allowed)
			(footprints allowed)
		)
		(placement
			(enabled no)
			(sheetname "")
		)
		(fill yes
			(thermal_gap 0.5)
			(thermal_bridge_width 0.5)
			(island_removal_mode 0)
		)
		(polygon
			(pts
				(arc
					(start 383.77749 -119.224298)
					(mid 383.07391 -119.224298)
					(end 383.77749 -119.224298)
				)
			)
		)
	)
	(zone
		(layers "B.Cu" "In11.Cu" "In13.Cu" "In15.Cu")
		(hatch none 0.5)
		(connect_pads
			(clearance 0)
		)
		(min_thickness 0.25)
		(keepout
			(tracks not_allowed)
			(vias allowed)
			(pads allowed)
			(copperpour not_allowed)
			(footprints allowed)
		)
		(placement
			(enabled no)
			(sheetname "")
		)
		(fill yes
			(thermal_gap 0.5)
			(thermal_bridge_width 0.5)
			(island_removal_mode 0)
		)
		(polygon
			(pts
				(arc
					(start 83.289648 -376.790204)
					(mid 82.530188 -376.790204)
					(end 83.289648 -376.790204)
				)
			)
		)
	)
	(zone
		(layers "B.Cu" "In11.Cu" "In13.Cu" "In15.Cu")
		(hatch none 0.5)
		(connect_pads
			(clearance 0)
		)
		(min_thickness 0.25)
		(keepout
			(tracks not_allowed)
			(vias allowed)
			(pads allowed)
			(copperpour not_allowed)
			(footprints allowed)
		)
		(placement
			(enabled no)
			(sheetname "")
		)
		(fill yes
			(thermal_gap 0.5)
			(thermal_bridge_width 0.5)
			(island_removal_mode 0)
		)
		(polygon
			(pts
				(arc
					(start 200.625964 -124.102114)
					(mid 199.922384 -124.102114)
					(end 200.625964 -124.102114)
				)
			)
		)
	)
	(zone
		(layers "B.Cu" "In11.Cu" "In13.Cu" "In15.Cu")
		(hatch none 0.5)
		(connect_pads
			(clearance 0)
		)
		(min_thickness 0.25)
		(keepout
			(tracks not_allowed)
			(vias allowed)
			(pads allowed)
			(copperpour not_allowed)
			(footprints allowed)
		)
		(placement
			(enabled no)
			(sheetname "")
		)
		(fill yes
			(thermal_gap 0.5)
			(thermal_bridge_width 0.5)
			(island_removal_mode 0)
		)
		(polygon
			(pts
				(arc
					(start 422.526206 -279.749504)
					(mid 421.873426 -279.749504)
					(end 422.526206 -279.749504)
				)
			)
		)
	)
	(zone
		(layers "B.Cu" "In11.Cu" "In13.Cu" "In15.Cu")
		(hatch none 0.5)
		(connect_pads
			(clearance 0)
		)
		(min_thickness 0.25)
		(keepout
			(tracks not_allowed)
			(vias allowed)
			(pads allowed)
			(copperpour not_allowed)
			(footprints allowed)
		)
		(placement
			(enabled no)
			(sheetname "")
		)
		(fill yes
			(thermal_gap 0.5)
			(thermal_bridge_width 0.5)
			(island_removal_mode 0)
		)
		(polygon
			(pts
				(arc
					(start 185.57621 -278.799798)
					(mid 184.92343 -278.799798)
					(end 185.57621 -278.799798)
				)
			)
		)
	)
	(zone
		(layers "B.Cu" "In11.Cu" "In13.Cu" "In15.Cu")
		(hatch none 0.5)
		(connect_pads
			(clearance 0)
		)
		(min_thickness 0.25)
		(keepout
			(tracks not_allowed)
			(vias allowed)
			(pads allowed)
			(copperpour not_allowed)
			(footprints allowed)
		)
		(placement
			(enabled no)
			(sheetname "")
		)
		(fill yes
			(thermal_gap 0.5)
			(thermal_bridge_width 0.5)
			(island_removal_mode 0)
		)
		(polygon
			(pts
				(arc
					(start 61.875924 -278.799798)
					(mid 61.223144 -278.799798)
					(end 61.875924 -278.799798)
				)
			)
		)
	)
	(zone
		(layers "B.Cu" "In11.Cu" "In13.Cu" "In15.Cu")
		(hatch none 0.5)
		(connect_pads
			(clearance 0)
		)
		(min_thickness 0.25)
		(keepout
			(tracks not_allowed)
			(vias allowed)
			(pads allowed)
			(copperpour not_allowed)
			(footprints allowed)
		)
		(placement
			(enabled no)
			(sheetname "")
		)
		(fill yes
			(thermal_gap 0.5)
			(thermal_bridge_width 0.5)
			(island_removal_mode 0)
		)
		(polygon
			(pts
				(arc
					(start 293.12616 -280.699718)
					(mid 292.47338 -280.699718)
					(end 293.12616 -280.699718)
				)
			)
		)
	)
	(zone
		(layers "B.Cu" "In11.Cu" "In13.Cu" "In15.Cu")
		(hatch none 0.5)
		(connect_pads
			(clearance 0)
		)
		(min_thickness 0.25)
		(keepout
			(tracks not_allowed)
			(vias allowed)
			(pads allowed)
			(copperpour not_allowed)
			(footprints allowed)
		)
		(placement
			(enabled no)
			(sheetname "")
		)
		(fill yes
			(thermal_gap 0.5)
			(thermal_bridge_width 0.5)
			(island_removal_mode 0)
		)
		(polygon
			(pts
				(arc
					(start 300.726094 -280.699718)
					(mid 300.073314 -280.699718)
					(end 300.726094 -280.699718)
				)
			)
		)
	)
	(zone
		(layers "B.Cu" "In11.Cu" "In13.Cu" "In15.Cu")
		(hatch none 0.5)
		(connect_pads
			(clearance 0)
		)
		(min_thickness 0.25)
		(keepout
			(tracks not_allowed)
			(vias allowed)
			(pads allowed)
			(copperpour not_allowed)
			(footprints allowed)
		)
		(placement
			(enabled no)
			(sheetname "")
		)
		(fill yes
			(thermal_gap 0.5)
			(thermal_bridge_width 0.5)
			(island_removal_mode 0)
		)
		(polygon
			(pts
				(arc
					(start 295.97604 -278.799798)
					(mid 295.32326 -278.799798)
					(end 295.97604 -278.799798)
				)
			)
		)
	)
	(zone
		(layers "B.Cu" "In11.Cu" "In13.Cu" "In15.Cu")
		(hatch none 0.5)
		(connect_pads
			(clearance 0)
		)
		(min_thickness 0.25)
		(keepout
			(tracks not_allowed)
			(vias allowed)
			(pads allowed)
			(copperpour not_allowed)
			(footprints allowed)
		)
		(placement
			(enabled no)
			(sheetname "")
		)
		(fill yes
			(thermal_gap 0.5)
			(thermal_bridge_width 0.5)
			(island_removal_mode 0)
		)
		(polygon
			(pts
				(arc
					(start 85.489542 -396.49019)
					(mid 84.730082 -396.49019)
					(end 85.489542 -396.49019)
				)
			)
		)
	)
	(zone
		(layers "B.Cu" "In11.Cu" "In13.Cu" "In15.Cu")
		(hatch none 0.5)
		(connect_pads
			(clearance 0)
		)
		(min_thickness 0.25)
		(keepout
			(tracks not_allowed)
			(vias allowed)
			(pads allowed)
			(copperpour not_allowed)
			(footprints allowed)
		)
		(placement
			(enabled no)
			(sheetname "")
		)
		(fill yes
			(thermal_gap 0.5)
			(thermal_bridge_width 0.5)
			(island_removal_mode 0)
		)
		(polygon
			(pts
				(arc
					(start 316.726062 -144.422114)
					(mid 316.022482 -144.422114)
					(end 316.726062 -144.422114)
				)
			)
		)
	)
	(zone
		(layers "B.Cu" "In11.Cu" "In13.Cu" "In15.Cu")
		(hatch none 0.5)
		(connect_pads
			(clearance 0)
		)
		(min_thickness 0.25)
		(keepout
			(tracks not_allowed)
			(vias allowed)
			(pads allowed)
			(copperpour not_allowed)
			(footprints allowed)
		)
		(placement
			(enabled no)
			(sheetname "")
		)
		(fill yes
			(thermal_gap 0.5)
			(thermal_bridge_width 0.5)
			(island_removal_mode 0)
		)
		(polygon
			(pts
				(arc
					(start 431.076354 -276.899878)
					(mid 430.423574 -276.899878)
					(end 431.076354 -276.899878)
				)
			)
		)
	)
	(zone
		(layers "B.Cu" "In11.Cu" "In13.Cu" "In15.Cu")
		(hatch none 0.5)
		(connect_pads
			(clearance 0)
		)
		(min_thickness 0.25)
		(keepout
			(tracks not_allowed)
			(vias allowed)
			(pads allowed)
			(copperpour not_allowed)
			(footprints allowed)
		)
		(placement
			(enabled no)
			(sheetname "")
		)
		(fill yes
			(thermal_gap 0.5)
			(thermal_bridge_width 0.5)
			(island_removal_mode 0)
		)
		(polygon
			(pts
				(arc
					(start 292.175946 -278.799798)
					(mid 291.523166 -278.799798)
					(end 292.175946 -278.799798)
				)
			)
		)
	)
	(zone
		(layers "B.Cu" "In11.Cu" "In13.Cu" "In15.Cu")
		(hatch none 0.5)
		(connect_pads
			(clearance 0)
		)
		(min_thickness 0.25)
		(keepout
			(tracks not_allowed)
			(vias allowed)
			(pads allowed)
			(copperpour not_allowed)
			(footprints allowed)
		)
		(placement
			(enabled no)
			(sheetname "")
		)
		(fill yes
			(thermal_gap 0.5)
			(thermal_bridge_width 0.5)
			(island_removal_mode 0)
		)
		(polygon
			(pts
				(arc
					(start 156.126434 -301.599854)
					(mid 155.473654 -301.599854)
					(end 156.126434 -301.599854)
				)
			)
		)
	)
	(zone
		(layers "B.Cu" "In11.Cu" "In13.Cu" "In15.Cu")
		(hatch none 0.5)
		(connect_pads
			(clearance 0)
		)
		(min_thickness 0.25)
		(keepout
			(tracks not_allowed)
			(vias allowed)
			(pads allowed)
			(copperpour not_allowed)
			(footprints allowed)
		)
		(placement
			(enabled no)
			(sheetname "")
		)
		(fill yes
			(thermal_gap 0.5)
			(thermal_bridge_width 0.5)
			(island_removal_mode 0)
		)
		(polygon
			(pts
				(arc
					(start 409.226258 -280.699718)
					(mid 408.573478 -280.699718)
					(end 409.226258 -280.699718)
				)
			)
		)
	)
	(zone
		(layers "B.Cu" "In11.Cu" "In13.Cu" "In15.Cu")
		(hatch none 0.5)
		(connect_pads
			(clearance 0)
		)
		(min_thickness 0.25)
		(keepout
			(tracks not_allowed)
			(vias allowed)
			(pads allowed)
			(copperpour not_allowed)
			(footprints allowed)
		)
		(placement
			(enabled no)
			(sheetname "")
		)
		(fill yes
			(thermal_gap 0.5)
			(thermal_bridge_width 0.5)
			(island_removal_mode 0)
		)
		(polygon
			(pts
				(arc
					(start 193.176144 -277.849838)
					(mid 192.523364 -277.849838)
					(end 193.176144 -277.849838)
				)
			)
		)
	)
	(zone
		(layers "B.Cu" "In11.Cu" "In13.Cu" "In15.Cu")
		(hatch none 0.5)
		(connect_pads
			(clearance 0)
		)
		(min_thickness 0.25)
		(keepout
			(tracks not_allowed)
			(vias allowed)
			(pads allowed)
			(copperpour not_allowed)
			(footprints allowed)
		)
		(placement
			(enabled no)
			(sheetname "")
		)
		(fill yes
			(thermal_gap 0.5)
			(thermal_bridge_width 0.5)
			(island_removal_mode 0)
		)
		(polygon
			(pts
				(arc
					(start 316.726062 -124.102114)
					(mid 316.022482 -124.102114)
					(end 316.726062 -124.102114)
				)
			)
		)
	)
	(zone
		(layers "B.Cu" "In11.Cu" "In13.Cu" "In15.Cu")
		(hatch none 0.5)
		(connect_pads
			(clearance 0)
		)
		(min_thickness 0.25)
		(keepout
			(tracks not_allowed)
			(vias allowed)
			(pads allowed)
			(copperpour not_allowed)
			(footprints allowed)
		)
		(placement
			(enabled no)
			(sheetname "")
		)
		(fill yes
			(thermal_gap 0.5)
			(thermal_bridge_width 0.5)
			(island_removal_mode 0)
		)
		(polygon
			(pts
				(arc
					(start 314.083954 -129.905506)
					(mid 313.380374 -129.905506)
					(end 314.083954 -129.905506)
				)
			)
		)
	)
	(zone
		(layers "B.Cu" "In11.Cu" "In13.Cu" "In15.Cu")
		(hatch none 0.5)
		(connect_pads
			(clearance 0)
		)
		(min_thickness 0.25)
		(keepout
			(tracks not_allowed)
			(vias allowed)
			(pads allowed)
			(copperpour not_allowed)
			(footprints allowed)
		)
		(placement
			(enabled no)
			(sheetname "")
		)
		(fill yes
			(thermal_gap 0.5)
			(thermal_bridge_width 0.5)
			(island_removal_mode 0)
		)
		(polygon
			(pts
				(arc
					(start 197.983856 -143.479266)
					(mid 197.280276 -143.479266)
					(end 197.983856 -143.479266)
				)
			)
		)
	)
	(zone
		(layers "B.Cu" "In11.Cu" "In13.Cu" "In15.Cu")
		(hatch none 0.5)
		(connect_pads
			(clearance 0)
		)
		(min_thickness 0.25)
		(keepout
			(tracks not_allowed)
			(vias allowed)
			(pads allowed)
			(copperpour not_allowed)
			(footprints allowed)
		)
		(placement
			(enabled no)
			(sheetname "")
		)
		(fill yes
			(thermal_gap 0.5)
			(thermal_bridge_width 0.5)
			(island_removal_mode 0)
		)
		(polygon
			(pts
				(arc
					(start 387.376416 -309.199788)
					(mid 386.723636 -309.199788)
					(end 387.376416 -309.199788)
				)
			)
		)
	)
	(zone
		(layers "B.Cu" "In11.Cu" "In13.Cu" "In15.Cu")
		(hatch none 0.5)
		(connect_pads
			(clearance 0)
		)
		(min_thickness 0.25)
		(keepout
			(tracks not_allowed)
			(vias allowed)
			(pads allowed)
			(copperpour not_allowed)
			(footprints allowed)
		)
		(placement
			(enabled no)
			(sheetname "")
		)
		(fill yes
			(thermal_gap 0.5)
			(thermal_bridge_width 0.5)
			(island_removal_mode 0)
		)
		(polygon
			(pts
				(arc
					(start 419.86962 -383.490216)
					(mid 419.11016 -383.490216)
					(end 419.86962 -383.490216)
				)
			)
		)
	)
	(zone
		(layers "B.Cu" "In11.Cu" "In13.Cu" "In15.Cu")
		(hatch none 0.5)
		(connect_pads
			(clearance 0)
		)
		(min_thickness 0.25)
		(keepout
			(tracks not_allowed)
			(vias allowed)
			(pads allowed)
			(copperpour not_allowed)
			(footprints allowed)
		)
		(placement
			(enabled no)
			(sheetname "")
		)
		(fill yes
			(thermal_gap 0.5)
			(thermal_bridge_width 0.5)
			(island_removal_mode 0)
		)
		(polygon
			(pts
				(arc
					(start 314.976256 -279.749758)
					(mid 314.323476 -279.749758)
					(end 314.976256 -279.749758)
				)
			)
		)
	)
	(zone
		(layers "B.Cu" "In11.Cu" "In13.Cu" "In15.Cu")
		(hatch none 0.5)
		(connect_pads
			(clearance 0)
		)
		(min_thickness 0.25)
		(keepout
			(tracks not_allowed)
			(vias allowed)
			(pads allowed)
			(copperpour not_allowed)
			(footprints allowed)
		)
		(placement
			(enabled no)
			(sheetname "")
		)
		(fill yes
			(thermal_gap 0.5)
			(thermal_bridge_width 0.5)
			(island_removal_mode 0)
		)
		(polygon
			(pts
				(arc
					(start 413.026352 -280.699718)
					(mid 412.373572 -280.699718)
					(end 413.026352 -280.699718)
				)
			)
		)
	)
	(zone
		(layers "B.Cu" "In11.Cu" "In13.Cu" "In15.Cu")
		(hatch none 0.5)
		(connect_pads
			(clearance 0)
		)
		(min_thickness 0.25)
		(keepout
			(tracks not_allowed)
			(vias allowed)
			(pads allowed)
			(copperpour not_allowed)
			(footprints allowed)
		)
		(placement
			(enabled no)
			(sheetname "")
		)
		(fill yes
			(thermal_gap 0.5)
			(thermal_bridge_width 0.5)
			(island_removal_mode 0)
		)
		(polygon
			(pts
				(arc
					(start 155.176474 -309.199788)
					(mid 154.523694 -309.199788)
					(end 155.176474 -309.199788)
				)
			)
		)
	)
	(zone
		(layers "B.Cu" "In11.Cu" "In13.Cu" "In15.Cu")
		(hatch none 0.5)
		(connect_pads
			(clearance 0)
		)
		(min_thickness 0.25)
		(keepout
			(tracks not_allowed)
			(vias allowed)
			(pads allowed)
			(copperpour not_allowed)
			(footprints allowed)
		)
		(placement
			(enabled no)
			(sheetname "")
		)
		(fill yes
			(thermal_gap 0.5)
			(thermal_bridge_width 0.5)
			(island_removal_mode 0)
		)
		(polygon
			(pts
				(arc
					(start 426.3263 -288.299906)
					(mid 425.67352 -288.299906)
					(end 426.3263 -288.299906)
				)
			)
		)
	)
	(zone
		(layers "B.Cu" "In11.Cu" "In13.Cu" "In15.Cu")
		(hatch none 0.5)
		(connect_pads
			(clearance 0)
		)
		(min_thickness 0.25)
		(keepout
			(tracks not_allowed)
			(vias allowed)
			(pads allowed)
			(copperpour not_allowed)
			(footprints allowed)
		)
		(placement
			(enabled no)
			(sheetname "")
		)
		(fill yes
			(thermal_gap 0.5)
			(thermal_bridge_width 0.5)
			(island_removal_mode 0)
		)
		(polygon
			(pts
				(arc
					(start 424.42638 -285.449772)
					(mid 423.7736 -285.449772)
					(end 424.42638 -285.449772)
				)
			)
		)
	)
	(zone
		(layers "B.Cu" "In11.Cu" "In13.Cu" "In15.Cu")
		(hatch none 0.5)
		(connect_pads
			(clearance 0)
		)
		(min_thickness 0.25)
		(keepout
			(tracks not_allowed)
			(vias allowed)
			(pads allowed)
			(copperpour not_allowed)
			(footprints allowed)
		)
		(placement
			(enabled no)
			(sheetname "")
		)
		(fill yes
			(thermal_gap 0.5)
			(thermal_bridge_width 0.5)
			(island_removal_mode 0)
		)
		(polygon
			(pts
				(arc
					(start 84.52612 -145.285714)
					(mid 83.82254 -145.285714)
					(end 84.52612 -145.285714)
				)
			)
		)
	)
	(zone
		(layers "B.Cu" "In11.Cu" "In13.Cu" "In15.Cu")
		(hatch none 0.5)
		(connect_pads
			(clearance 0)
		)
		(min_thickness 0.25)
		(keepout
			(tracks not_allowed)
			(vias allowed)
			(pads allowed)
			(copperpour not_allowed)
			(footprints allowed)
		)
		(placement
			(enabled no)
			(sheetname "")
		)
		(fill yes
			(thermal_gap 0.5)
			(thermal_bridge_width 0.5)
			(island_removal_mode 0)
		)
		(polygon
			(pts
				(arc
					(start 81.826354 -276.899878)
					(mid 81.173574 -276.899878)
					(end 81.826354 -276.899878)
				)
			)
		)
	)
	(zone
		(layers "B.Cu" "In11.Cu" "In13.Cu" "In15.Cu")
		(hatch none 0.5)
		(connect_pads
			(clearance 0)
		)
		(min_thickness 0.25)
		(keepout
			(tracks not_allowed)
			(vias allowed)
			(pads allowed)
			(copperpour not_allowed)
			(footprints allowed)
		)
		(placement
			(enabled no)
			(sheetname "")
		)
		(fill yes
			(thermal_gap 0.5)
			(thermal_bridge_width 0.5)
			(island_removal_mode 0)
		)
		(polygon
			(pts
				(arc
					(start 154.219402 -132.240782)
					(mid 153.515822 -132.240782)
					(end 154.219402 -132.240782)
				)
			)
		)
	)
	(zone
		(layers "B.Cu" "In11.Cu" "In13.Cu" "In15.Cu")
		(hatch none 0.5)
		(connect_pads
			(clearance 0)
		)
		(min_thickness 0.25)
		(keepout
			(tracks not_allowed)
			(vias allowed)
			(pads allowed)
			(copperpour not_allowed)
			(footprints allowed)
		)
		(placement
			(enabled no)
			(sheetname "")
		)
		(fill yes
			(thermal_gap 0.5)
			(thermal_bridge_width 0.5)
			(island_removal_mode 0)
		)
		(polygon
			(pts
				(arc
					(start 164.68979 -409.490164)
					(mid 163.93033 -409.490164)
					(end 164.68979 -409.490164)
				)
			)
		)
	)
	(zone
		(layers "B.Cu" "In11.Cu" "In13.Cu" "In15.Cu")
		(hatch none 0.5)
		(connect_pads
			(clearance 0)
		)
		(min_thickness 0.25)
		(keepout
			(tracks not_allowed)
			(vias allowed)
			(pads allowed)
			(copperpour not_allowed)
			(footprints allowed)
		)
		(placement
			(enabled no)
			(sheetname "")
		)
		(fill yes
			(thermal_gap 0.5)
			(thermal_bridge_width 0.5)
			(island_removal_mode 0)
		)
		(polygon
			(pts
				(arc
					(start 314.083954 -123.159266)
					(mid 313.380374 -123.159266)
					(end 314.083954 -123.159266)
				)
			)
		)
	)
	(zone
		(layers "B.Cu" "In11.Cu" "In13.Cu" "In15.Cu")
		(hatch none 0.5)
		(connect_pads
			(clearance 0)
		)
		(min_thickness 0.25)
		(keepout
			(tracks not_allowed)
			(vias allowed)
			(pads allowed)
			(copperpour not_allowed)
			(footprints allowed)
		)
		(placement
			(enabled no)
			(sheetname "")
		)
		(fill yes
			(thermal_gap 0.5)
			(thermal_bridge_width 0.5)
			(island_removal_mode 0)
		)
		(polygon
			(pts
				(arc
					(start 310.226202 -286.399986)
					(mid 309.573422 -286.399986)
					(end 310.226202 -286.399986)
				)
			)
		)
	)
	(zone
		(layers "B.Cu" "In11.Cu" "In13.Cu" "In15.Cu")
		(hatch none 0.5)
		(connect_pads
			(clearance 0)
		)
		(min_thickness 0.25)
		(keepout
			(tracks not_allowed)
			(vias allowed)
			(pads allowed)
			(copperpour not_allowed)
			(footprints allowed)
		)
		(placement
			(enabled no)
			(sheetname "")
		)
		(fill yes
			(thermal_gap 0.5)
			(thermal_bridge_width 0.5)
			(island_removal_mode 0)
		)
		(polygon
			(pts
				(arc
					(start 81.884012 -150.67915)
					(mid 81.180432 -150.67915)
					(end 81.884012 -150.67915)
				)
			)
		)
	)
	(zone
		(layers "B.Cu" "In11.Cu" "In13.Cu" "In15.Cu")
		(hatch none 0.5)
		(connect_pads
			(clearance 0)
		)
		(min_thickness 0.25)
		(keepout
			(tracks not_allowed)
			(vias allowed)
			(pads allowed)
			(copperpour not_allowed)
			(footprints allowed)
		)
		(placement
			(enabled no)
			(sheetname "")
		)
		(fill yes
			(thermal_gap 0.5)
			(thermal_bridge_width 0.5)
			(island_removal_mode 0)
		)
		(polygon
			(pts
				(arc
					(start 200.625964 -148.88591)
					(mid 199.922384 -148.88591)
					(end 200.625964 -148.88591)
				)
			)
		)
	)
	(zone
		(layers "B.Cu" "In11.Cu" "In13.Cu" "In15.Cu")
		(hatch none 0.5)
		(connect_pads
			(clearance 0)
		)
		(min_thickness 0.25)
		(keepout
			(tracks not_allowed)
			(vias allowed)
			(pads allowed)
			(copperpour not_allowed)
			(footprints allowed)
		)
		(placement
			(enabled no)
			(sheetname "")
		)
		(fill yes
			(thermal_gap 0.5)
			(thermal_bridge_width 0.5)
			(island_removal_mode 0)
		)
		(polygon
			(pts
				(arc
					(start 197.983856 -119.559324)
					(mid 197.280276 -119.559324)
					(end 197.983856 -119.559324)
				)
			)
		)
	)
	(zone
		(layers "B.Cu" "In11.Cu" "In13.Cu" "In15.Cu")
		(hatch none 0.5)
		(connect_pads
			(clearance 0)
		)
		(min_thickness 0.25)
		(keepout
			(tracks not_allowed)
			(vias allowed)
			(pads allowed)
			(copperpour not_allowed)
			(footprints allowed)
		)
		(placement
			(enabled no)
			(sheetname "")
		)
		(fill yes
			(thermal_gap 0.5)
			(thermal_bridge_width 0.5)
			(island_removal_mode 0)
		)
		(polygon
			(pts
				(arc
					(start 295.02608 -316.799722)
					(mid 294.3733 -316.799722)
					(end 295.02608 -316.799722)
				)
			)
		)
	)
	(zone
		(layers "B.Cu" "In11.Cu" "In13.Cu" "In15.Cu")
		(hatch none 0.5)
		(connect_pads
			(clearance 0)
		)
		(min_thickness 0.25)
		(keepout
			(tracks not_allowed)
			(vias allowed)
			(pads allowed)
			(copperpour not_allowed)
			(footprints allowed)
		)
		(placement
			(enabled no)
			(sheetname "")
		)
		(fill yes
			(thermal_gap 0.5)
			(thermal_bridge_width 0.5)
			(island_removal_mode 0)
		)
		(polygon
			(pts
				(arc
					(start 156.126434 -309.199788)
					(mid 155.473654 -309.199788)
					(end 156.126434 -309.199788)
				)
			)
		)
	)
	(zone
		(layers "B.Cu" "In11.Cu" "In13.Cu" "In15.Cu")
		(hatch none 0.5)
		(connect_pads
			(clearance 0)
		)
		(min_thickness 0.25)
		(keepout
			(tracks not_allowed)
			(vias allowed)
			(pads allowed)
			(copperpour not_allowed)
			(footprints allowed)
		)
		(placement
			(enabled no)
			(sheetname "")
		)
		(fill yes
			(thermal_gap 0.5)
			(thermal_bridge_width 0.5)
			(island_removal_mode 0)
		)
		(polygon
			(pts
				(arc
					(start 432.82616 -155.222194)
					(mid 432.12258 -155.222194)
					(end 432.82616 -155.222194)
				)
			)
		)
	)
	(zone
		(layers "B.Cu" "In11.Cu" "In13.Cu" "In15.Cu")
		(hatch none 0.5)
		(connect_pads
			(clearance 0)
		)
		(min_thickness 0.25)
		(keepout
			(tracks not_allowed)
			(vias allowed)
			(pads allowed)
			(copperpour not_allowed)
			(footprints allowed)
		)
		(placement
			(enabled no)
			(sheetname "")
		)
		(fill yes
			(thermal_gap 0.5)
			(thermal_bridge_width 0.5)
			(island_removal_mode 0)
		)
		(polygon
			(pts
				(arc
					(start 387.376416 -305.399948)
					(mid 386.723636 -305.399948)
					(end 387.376416 -305.399948)
				)
			)
		)
	)
	(zone
		(layers "B.Cu" "In11.Cu" "In13.Cu" "In15.Cu")
		(hatch none 0.5)
		(connect_pads
			(clearance 0)
		)
		(min_thickness 0.25)
		(keepout
			(tracks not_allowed)
			(vias allowed)
			(pads allowed)
			(copperpour not_allowed)
			(footprints allowed)
		)
		(placement
			(enabled no)
			(sheetname "")
		)
		(fill yes
			(thermal_gap 0.5)
			(thermal_bridge_width 0.5)
			(island_removal_mode 0)
		)
		(polygon
			(pts
				(arc
					(start 81.884012 -134.369302)
					(mid 81.180432 -134.369302)
					(end 81.884012 -134.369302)
				)
			)
		)
	)
	(zone
		(layers "B.Cu" "In11.Cu" "In13.Cu" "In15.Cu")
		(hatch none 0.5)
		(connect_pads
			(clearance 0)
		)
		(min_thickness 0.25)
		(keepout
			(tracks not_allowed)
			(vias allowed)
			(pads allowed)
			(copperpour not_allowed)
			(footprints allowed)
		)
		(placement
			(enabled no)
			(sheetname "")
		)
		(fill yes
			(thermal_gap 0.5)
			(thermal_bridge_width 0.5)
			(island_removal_mode 0)
		)
		(polygon
			(pts
				(arc
					(start 270.3195 -102.914196)
					(mid 269.61592 -102.914196)
					(end 270.3195 -102.914196)
				)
			)
		)
	)
	(zone
		(layers "B.Cu" "In11.Cu" "In13.Cu" "In15.Cu")
		(hatch none 0.5)
		(connect_pads
			(clearance 0)
		)
		(min_thickness 0.25)
		(keepout
			(tracks not_allowed)
			(vias allowed)
			(pads allowed)
			(copperpour not_allowed)
			(footprints allowed)
		)
		(placement
			(enabled no)
			(sheetname "")
		)
		(fill yes
			(thermal_gap 0.5)
			(thermal_bridge_width 0.5)
			(island_removal_mode 0)
		)
		(polygon
			(pts
				(arc
					(start 191.276224 -277.849838)
					(mid 190.623444 -277.849838)
					(end 191.276224 -277.849838)
				)
			)
		)
	)
	(zone
		(layers "B.Cu" "In11.Cu" "In13.Cu" "In15.Cu")
		(hatch none 0.5)
		(connect_pads
			(clearance 0)
		)
		(min_thickness 0.25)
		(keepout
			(tracks not_allowed)
			(vias allowed)
			(pads allowed)
			(copperpour not_allowed)
			(footprints allowed)
		)
		(placement
			(enabled no)
			(sheetname "")
		)
		(fill yes
			(thermal_gap 0.5)
			(thermal_bridge_width 0.5)
			(island_removal_mode 0)
		)
		(polygon
			(pts
				(arc
					(start 65.676018 -278.799798)
					(mid 65.023238 -278.799798)
					(end 65.676018 -278.799798)
				)
			)
		)
	)
	(zone
		(layers "B.Cu" "In11.Cu" "In13.Cu" "In15.Cu")
		(hatch none 0.5)
		(connect_pads
			(clearance 0)
		)
		(min_thickness 0.25)
		(keepout
			(tracks not_allowed)
			(vias allowed)
			(pads allowed)
			(copperpour not_allowed)
			(footprints allowed)
		)
		(placement
			(enabled no)
			(sheetname "")
		)
		(fill yes
			(thermal_gap 0.5)
			(thermal_bridge_width 0.5)
			(island_removal_mode 0)
		)
		(polygon
			(pts
				(arc
					(start 197.983856 -118.695724)
					(mid 197.280276 -118.695724)
					(end 197.983856 -118.695724)
				)
			)
		)
	)
	(zone
		(layers "B.Cu" "In11.Cu" "In13.Cu" "In15.Cu")
		(hatch none 0.5)
		(connect_pads
			(clearance 0)
		)
		(min_thickness 0.25)
		(keepout
			(tracks not_allowed)
			(vias allowed)
			(pads allowed)
			(copperpour not_allowed)
			(footprints allowed)
		)
		(placement
			(enabled no)
			(sheetname "")
		)
		(fill yes
			(thermal_gap 0.5)
			(thermal_bridge_width 0.5)
			(island_removal_mode 0)
		)
		(polygon
			(pts
				(arc
					(start 416.826192 -279.749504)
					(mid 416.173412 -279.749504)
					(end 416.826192 -279.749504)
				)
			)
		)
	)
	(zone
		(layers "B.Cu" "In11.Cu" "In13.Cu" "In15.Cu")
		(hatch none 0.5)
		(connect_pads
			(clearance 0)
		)
		(min_thickness 0.25)
		(keepout
			(tracks not_allowed)
			(vias allowed)
			(pads allowed)
			(copperpour not_allowed)
			(footprints allowed)
		)
		(placement
			(enabled no)
			(sheetname "")
		)
		(fill yes
			(thermal_gap 0.5)
			(thermal_bridge_width 0.5)
			(island_removal_mode 0)
		)
		(polygon
			(pts
				(arc
					(start 302.626268 -280.699718)
					(mid 301.973488 -280.699718)
					(end 302.626268 -280.699718)
				)
			)
		)
	)
	(zone
		(layers "B.Cu" "In11.Cu" "In13.Cu" "In15.Cu")
		(hatch none 0.5)
		(connect_pads
			(clearance 0)
		)
		(min_thickness 0.25)
		(keepout
			(tracks not_allowed)
			(vias allowed)
			(pads allowed)
			(copperpour not_allowed)
			(footprints allowed)
		)
		(placement
			(enabled no)
			(sheetname "")
		)
		(fill yes
			(thermal_gap 0.5)
			(thermal_bridge_width 0.5)
			(island_removal_mode 0)
		)
		(polygon
			(pts
				(arc
					(start 175.689768 -384.590036)
					(mid 174.930308 -384.590036)
					(end 175.689768 -384.590036)
				)
			)
		)
	)
	(zone
		(layers "B.Cu" "In11.Cu" "In13.Cu" "In15.Cu")
		(hatch none 0.5)
		(connect_pads
			(clearance 0)
		)
		(min_thickness 0.25)
		(keepout
			(tracks not_allowed)
			(vias allowed)
			(pads allowed)
			(copperpour not_allowed)
			(footprints allowed)
		)
		(placement
			(enabled no)
			(sheetname "")
		)
		(fill yes
			(thermal_gap 0.5)
			(thermal_bridge_width 0.5)
			(island_removal_mode 0)
		)
		(polygon
			(pts
				(arc
					(start 424.269662 -409.490164)
					(mid 423.510202 -409.490164)
					(end 424.269662 -409.490164)
				)
			)
		)
	)
	(zone
		(layers "B.Cu" "In11.Cu" "In13.Cu" "In15.Cu")
		(hatch none 0.5)
		(connect_pads
			(clearance 0)
		)
		(min_thickness 0.25)
		(keepout
			(tracks not_allowed)
			(vias allowed)
			(pads allowed)
			(copperpour not_allowed)
			(footprints allowed)
		)
		(placement
			(enabled no)
			(sheetname "")
		)
		(fill yes
			(thermal_gap 0.5)
			(thermal_bridge_width 0.5)
			(island_removal_mode 0)
		)
		(polygon
			(pts
				(arc
					(start 432.82616 -120.502172)
					(mid 432.12258 -120.502172)
					(end 432.82616 -120.502172)
				)
			)
		)
	)
	(zone
		(layers "B.Cu" "In11.Cu" "In13.Cu" "In15.Cu")
		(hatch none 0.5)
		(connect_pads
			(clearance 0)
		)
		(min_thickness 0.25)
		(keepout
			(tracks not_allowed)
			(vias allowed)
			(pads allowed)
			(copperpour not_allowed)
			(footprints allowed)
		)
		(placement
			(enabled no)
			(sheetname "")
		)
		(fill yes
			(thermal_gap 0.5)
			(thermal_bridge_width 0.5)
			(island_removal_mode 0)
		)
		(polygon
			(pts
				(arc
					(start 267.677392 -134.034276)
					(mid 266.973812 -134.034276)
					(end 267.677392 -134.034276)
				)
			)
		)
	)
	(zone
		(layers "B.Cu" "In11.Cu" "In13.Cu" "In15.Cu")
		(hatch none 0.5)
		(connect_pads
			(clearance 0)
		)
		(min_thickness 0.25)
		(keepout
			(tracks not_allowed)
			(vias allowed)
			(pads allowed)
			(copperpour not_allowed)
			(footprints allowed)
		)
		(placement
			(enabled no)
			(sheetname "")
		)
		(fill yes
			(thermal_gap 0.5)
			(thermal_bridge_width 0.5)
			(island_removal_mode 0)
		)
		(polygon
			(pts
				(arc
					(start 84.52612 -144.422114)
					(mid 83.82254 -144.422114)
					(end 84.52612 -144.422114)
				)
			)
		)
	)
	(zone
		(layers "B.Cu" "In11.Cu" "In13.Cu" "In15.Cu")
		(hatch none 0.5)
		(connect_pads
			(clearance 0)
		)
		(min_thickness 0.25)
		(keepout
			(tracks not_allowed)
			(vias allowed)
			(pads allowed)
			(copperpour not_allowed)
			(footprints allowed)
		)
		(placement
			(enabled no)
			(sheetname "")
		)
		(fill yes
			(thermal_gap 0.5)
			(thermal_bridge_width 0.5)
			(island_removal_mode 0)
		)
		(polygon
			(pts
				(arc
					(start 79.92618 -279.749758)
					(mid 79.2734 -279.749758)
					(end 79.92618 -279.749758)
				)
			)
		)
	)
	(zone
		(layers "B.Cu" "In11.Cu" "In13.Cu" "In15.Cu")
		(hatch none 0.5)
		(connect_pads
			(clearance 0)
		)
		(min_thickness 0.25)
		(keepout
			(tracks not_allowed)
			(vias allowed)
			(pads allowed)
			(copperpour not_allowed)
			(footprints allowed)
		)
		(placement
			(enabled no)
			(sheetname "")
		)
		(fill yes
			(thermal_gap 0.5)
			(thermal_bridge_width 0.5)
			(island_removal_mode 0)
		)
		(polygon
			(pts
				(arc
					(start 386.419598 -110.977934)
					(mid 385.716018 -110.977934)
					(end 386.419598 -110.977934)
				)
			)
		)
	)
	(zone
		(layers "B.Cu" "In11.Cu" "In13.Cu" "In15.Cu")
		(hatch none 0.5)
		(connect_pads
			(clearance 0)
		)
		(min_thickness 0.25)
		(keepout
			(tracks not_allowed)
			(vias allowed)
			(pads allowed)
			(copperpour not_allowed)
			(footprints allowed)
		)
		(placement
			(enabled no)
			(sheetname "")
		)
		(fill yes
			(thermal_gap 0.5)
			(thermal_bridge_width 0.5)
			(island_removal_mode 0)
		)
		(polygon
			(pts
				(arc
					(start 413.026352 -279.749504)
					(mid 412.373572 -279.749504)
					(end 413.026352 -279.749504)
				)
			)
		)
	)
	(zone
		(layers "B.Cu" "In11.Cu" "In13.Cu" "In15.Cu")
		(hatch none 0.5)
		(connect_pads
			(clearance 0)
		)
		(min_thickness 0.25)
		(keepout
			(tracks not_allowed)
			(vias allowed)
			(pads allowed)
			(copperpour not_allowed)
			(footprints allowed)
		)
		(placement
			(enabled no)
			(sheetname "")
		)
		(fill yes
			(thermal_gap 0.5)
			(thermal_bridge_width 0.5)
			(island_removal_mode 0)
		)
		(polygon
			(pts
				(arc
					(start 196.026278 -279.749758)
					(mid 195.373498 -279.749758)
					(end 196.026278 -279.749758)
				)
			)
		)
	)
	(zone
		(layers "B.Cu" "In11.Cu" "In13.Cu" "In15.Cu")
		(hatch none 0.5)
		(connect_pads
			(clearance 0)
		)
		(min_thickness 0.25)
		(keepout
			(tracks not_allowed)
			(vias allowed)
			(pads allowed)
			(copperpour not_allowed)
			(footprints allowed)
		)
		(placement
			(enabled no)
			(sheetname "")
		)
		(fill yes
			(thermal_gap 0.5)
			(thermal_bridge_width 0.5)
			(island_removal_mode 0)
		)
		(polygon
			(pts
				(arc
					(start 197.983856 -129.905506)
					(mid 197.280276 -129.905506)
					(end 197.983856 -129.905506)
				)
			)
		)
	)
	(zone
		(layers "B.Cu" "In11.Cu" "In13.Cu" "In15.Cu")
		(hatch none 0.5)
		(connect_pads
			(clearance 0)
		)
		(min_thickness 0.25)
		(keepout
			(tracks not_allowed)
			(vias allowed)
			(pads allowed)
			(copperpour not_allowed)
			(footprints allowed)
		)
		(placement
			(enabled no)
			(sheetname "")
		)
		(fill yes
			(thermal_gap 0.5)
			(thermal_bridge_width 0.5)
			(island_removal_mode 0)
		)
		(polygon
			(pts
				(arc
					(start 299.77588 -277.849838)
					(mid 299.1231 -277.849838)
					(end 299.77588 -277.849838)
				)
			)
		)
	)
	(zone
		(layers "B.Cu" "In11.Cu" "In13.Cu" "In15.Cu")
		(hatch none 0.5)
		(connect_pads
			(clearance 0)
		)
		(min_thickness 0.25)
		(keepout
			(tracks not_allowed)
			(vias allowed)
			(pads allowed)
			(copperpour not_allowed)
			(footprints allowed)
		)
		(placement
			(enabled no)
			(sheetname "")
		)
		(fill yes
			(thermal_gap 0.5)
			(thermal_bridge_width 0.5)
			(island_removal_mode 0)
		)
		(polygon
			(pts
				(arc
					(start 429.17618 -278.799798)
					(mid 428.5234 -278.799798)
					(end 429.17618 -278.799798)
				)
			)
		)
	)
	(zone
		(layers "B.Cu" "In11.Cu" "In13.Cu" "In15.Cu")
		(hatch none 0.5)
		(connect_pads
			(clearance 0)
		)
		(min_thickness 0.25)
		(keepout
			(tracks not_allowed)
			(vias allowed)
			(pads allowed)
			(copperpour not_allowed)
			(footprints allowed)
		)
		(placement
			(enabled no)
			(sheetname "")
		)
		(fill yes
			(thermal_gap 0.5)
			(thermal_bridge_width 0.5)
			(island_removal_mode 0)
		)
		(polygon
			(pts
				(arc
					(start 388.326376 -305.399948)
					(mid 387.673596 -305.399948)
					(end 388.326376 -305.399948)
				)
			)
		)
	)
	(zone
		(layers "B.Cu" "In11.Cu" "In13.Cu" "In15.Cu")
		(hatch none 0.5)
		(connect_pads
			(clearance 0)
		)
		(min_thickness 0.25)
		(keepout
			(tracks not_allowed)
			(vias allowed)
			(pads allowed)
			(copperpour not_allowed)
			(footprints allowed)
		)
		(placement
			(enabled no)
			(sheetname "")
		)
		(fill yes
			(thermal_gap 0.5)
			(thermal_bridge_width 0.5)
			(island_removal_mode 0)
		)
		(polygon
			(pts
				(arc
					(start 195.076064 -278.799798)
					(mid 194.423284 -278.799798)
					(end 195.076064 -278.799798)
				)
			)
		)
	)
	(zone
		(layers "B.Cu" "In11.Cu" "In13.Cu" "In15.Cu")
		(hatch none 0.5)
		(connect_pads
			(clearance 0)
		)
		(min_thickness 0.25)
		(keepout
			(tracks not_allowed)
			(vias allowed)
			(pads allowed)
			(copperpour not_allowed)
			(footprints allowed)
		)
		(placement
			(enabled no)
			(sheetname "")
		)
		(fill yes
			(thermal_gap 0.5)
			(thermal_bridge_width 0.5)
			(island_removal_mode 0)
		)
		(polygon
			(pts
				(arc
					(start 316.726062 -152.485852)
					(mid 316.022482 -152.485852)
					(end 316.726062 -152.485852)
				)
			)
		)
	)
	(zone
		(layers "B.Cu" "In11.Cu" "In13.Cu" "In15.Cu")
		(hatch none 0.5)
		(connect_pads
			(clearance 0)
		)
		(min_thickness 0.25)
		(keepout
			(tracks not_allowed)
			(vias allowed)
			(pads allowed)
			(copperpour not_allowed)
			(footprints allowed)
		)
		(placement
			(enabled no)
			(sheetname "")
		)
		(fill yes
			(thermal_gap 0.5)
			(thermal_bridge_width 0.5)
			(island_removal_mode 0)
		)
		(polygon
			(pts
				(arc
					(start 388.326376 -316.799722)
					(mid 387.673596 -316.799722)
					(end 388.326376 -316.799722)
				)
			)
		)
	)
	(zone
		(layers "B.Cu" "In11.Cu" "In13.Cu" "In15.Cu")
		(hatch none 0.5)
		(connect_pads
			(clearance 0)
		)
		(min_thickness 0.25)
		(keepout
			(tracks not_allowed)
			(vias allowed)
			(pads allowed)
			(copperpour not_allowed)
			(footprints allowed)
		)
		(placement
			(enabled no)
			(sheetname "")
		)
		(fill yes
			(thermal_gap 0.5)
			(thermal_bridge_width 0.5)
			(island_removal_mode 0)
		)
		(polygon
			(pts
				(arc
					(start 314.083954 -147.079208)
					(mid 313.380374 -147.079208)
					(end 314.083954 -147.079208)
				)
			)
		)
	)
	(zone
		(layers "B.Cu" "In11.Cu" "In13.Cu" "In15.Cu")
		(hatch none 0.5)
		(connect_pads
			(clearance 0)
		)
		(min_thickness 0.25)
		(keepout
			(tracks not_allowed)
			(vias allowed)
			(pads allowed)
			(copperpour not_allowed)
			(footprints allowed)
		)
		(placement
			(enabled no)
			(sheetname "")
		)
		(fill yes
			(thermal_gap 0.5)
			(thermal_bridge_width 0.5)
			(island_removal_mode 0)
		)
		(polygon
			(pts
				(arc
					(start 268.286992 -101.120702)
					(mid 267.583412 -101.120702)
					(end 268.286992 -101.120702)
				)
			)
		)
	)
	(zone
		(layers "B.Cu" "In11.Cu" "In13.Cu" "In15.Cu")
		(hatch none 0.5)
		(connect_pads
			(clearance 0)
		)
		(min_thickness 0.25)
		(keepout
			(tracks not_allowed)
			(vias allowed)
			(pads allowed)
			(copperpour not_allowed)
			(footprints allowed)
		)
		(placement
			(enabled no)
			(sheetname "")
		)
		(fill yes
			(thermal_gap 0.5)
			(thermal_bridge_width 0.5)
			(island_removal_mode 0)
		)
		(polygon
			(pts
				(arc
					(start 411.126178 -280.699718)
					(mid 410.473398 -280.699718)
					(end 411.126178 -280.699718)
				)
			)
		)
	)
	(zone
		(layers "B.Cu" "In11.Cu" "In13.Cu" "In15.Cu")
		(hatch none 0.5)
		(connect_pads
			(clearance 0)
		)
		(min_thickness 0.25)
		(keepout
			(tracks not_allowed)
			(vias allowed)
			(pads allowed)
			(copperpour not_allowed)
			(footprints allowed)
		)
		(placement
			(enabled no)
			(sheetname "")
		)
		(fill yes
			(thermal_gap 0.5)
			(thermal_bridge_width 0.5)
			(island_removal_mode 0)
		)
		(polygon
			(pts
				(arc
					(start 309.276242 -286.399986)
					(mid 308.623462 -286.399986)
					(end 309.276242 -286.399986)
				)
			)
		)
	)
	(zone
		(layers "B.Cu" "In11.Cu" "In13.Cu" "In15.Cu")
		(hatch none 0.5)
		(connect_pads
			(clearance 0)
		)
		(min_thickness 0.25)
		(keepout
			(tracks not_allowed)
			(vias allowed)
			(pads allowed)
			(copperpour not_allowed)
			(footprints allowed)
		)
		(placement
			(enabled no)
			(sheetname "")
		)
		(fill yes
			(thermal_gap 0.5)
			(thermal_bridge_width 0.5)
			(island_removal_mode 0)
		)
		(polygon
			(pts
				(arc
					(start 188.426344 -279.749504)
					(mid 187.773564 -279.749504)
					(end 188.426344 -279.749504)
				)
			)
		)
	)
	(zone
		(layers "B.Cu" "In11.Cu" "In13.Cu" "In15.Cu")
		(hatch none 0.5)
		(connect_pads
			(clearance 0)
		)
		(min_thickness 0.25)
		(keepout
			(tracks not_allowed)
			(vias allowed)
			(pads allowed)
			(copperpour not_allowed)
			(footprints allowed)
		)
		(placement
			(enabled no)
			(sheetname "")
		)
		(fill yes
			(thermal_gap 0.5)
			(thermal_bridge_width 0.5)
			(island_removal_mode 0)
		)
		(polygon
			(pts
				(arc
					(start 84.52612 -131.712208)
					(mid 83.82254 -131.712208)
					(end 84.52612 -131.712208)
				)
			)
		)
	)
	(zone
		(layers "B.Cu" "In11.Cu" "In13.Cu" "In15.Cu")
		(hatch none 0.5)
		(connect_pads
			(clearance 0)
		)
		(min_thickness 0.25)
		(keepout
			(tracks not_allowed)
			(vias allowed)
			(pads allowed)
			(copperpour not_allowed)
			(footprints allowed)
		)
		(placement
			(enabled no)
			(sheetname "")
		)
		(fill yes
			(thermal_gap 0.5)
			(thermal_bridge_width 0.5)
			(island_removal_mode 0)
		)
		(polygon
			(pts
				(arc
					(start 78.02626 -282.599892)
					(mid 77.37348 -282.599892)
					(end 78.02626 -282.599892)
				)
			)
		)
	)
	(zone
		(layers "B.Cu" "In11.Cu" "In13.Cu" "In15.Cu")
		(hatch none 0.5)
		(connect_pads
			(clearance 0)
		)
		(min_thickness 0.25)
		(keepout
			(tracks not_allowed)
			(vias allowed)
			(pads allowed)
			(copperpour not_allowed)
			(footprints allowed)
		)
		(placement
			(enabled no)
			(sheetname "")
		)
		(fill yes
			(thermal_gap 0.5)
			(thermal_bridge_width 0.5)
			(island_removal_mode 0)
		)
		(polygon
			(pts
				(arc
					(start 35.47745 -131.297934)
					(mid 34.77387 -131.297934)
					(end 35.47745 -131.297934)
				)
			)
		)
	)
	(zone
		(layers "B.Cu" "In11.Cu" "In13.Cu" "In15.Cu")
		(hatch none 0.5)
		(connect_pads
			(clearance 0)
		)
		(min_thickness 0.25)
		(keepout
			(tracks not_allowed)
			(vias allowed)
			(pads allowed)
			(copperpour not_allowed)
			(footprints allowed)
		)
		(placement
			(enabled no)
			(sheetname "")
		)
		(fill yes
			(thermal_gap 0.5)
			(thermal_bridge_width 0.5)
			(island_removal_mode 0)
		)
		(polygon
			(pts
				(arc
					(start 72.28967 -397.790162)
					(mid 71.53021 -397.790162)
					(end 72.28967 -397.790162)
				)
			)
		)
	)
	(zone
		(layers "B.Cu" "In11.Cu" "In13.Cu" "In15.Cu")
		(hatch none 0.5)
		(connect_pads
			(clearance 0)
		)
		(min_thickness 0.25)
		(keepout
			(tracks not_allowed)
			(vias allowed)
			(pads allowed)
			(copperpour not_allowed)
			(footprints allowed)
		)
		(placement
			(enabled no)
			(sheetname "")
		)
		(fill yes
			(thermal_gap 0.5)
			(thermal_bridge_width 0.5)
			(island_removal_mode 0)
		)
		(polygon
			(pts
				(arc
					(start 383.77749 -131.297934)
					(mid 383.07391 -131.297934)
					(end 383.77749 -131.297934)
				)
			)
		)
	)
	(zone
		(layers "B.Cu" "In11.Cu" "In13.Cu" "In15.Cu")
		(hatch none 0.5)
		(connect_pads
			(clearance 0)
		)
		(min_thickness 0.25)
		(keepout
			(tracks not_allowed)
			(vias allowed)
			(pads allowed)
			(copperpour not_allowed)
			(footprints allowed)
		)
		(placement
			(enabled no)
			(sheetname "")
		)
		(fill yes
			(thermal_gap 0.5)
			(thermal_bridge_width 0.5)
			(island_removal_mode 0)
		)
		(polygon
			(pts
				(arc
					(start 430.184052 -130.769106)
					(mid 429.480472 -130.769106)
					(end 430.184052 -130.769106)
				)
			)
		)
	)
	(zone
		(layers "B.Cu" "In11.Cu" "In13.Cu" "In15.Cu")
		(hatch none 0.5)
		(connect_pads
			(clearance 0)
		)
		(min_thickness 0.25)
		(keepout
			(tracks not_allowed)
			(vias allowed)
			(pads allowed)
			(copperpour not_allowed)
			(footprints allowed)
		)
		(placement
			(enabled no)
			(sheetname "")
		)
		(fill yes
			(thermal_gap 0.5)
			(thermal_bridge_width 0.5)
			(island_removal_mode 0)
		)
		(polygon
			(pts
				(arc
					(start 340.66988 -374.390158)
					(mid 339.91042 -374.390158)
					(end 340.66988 -374.390158)
				)
			)
		)
	)
	(zone
		(layers "B.Cu" "In11.Cu" "In13.Cu" "In15.Cu")
		(hatch none 0.5)
		(connect_pads
			(clearance 0)
		)
		(min_thickness 0.25)
		(keepout
			(tracks not_allowed)
			(vias allowed)
			(pads allowed)
			(copperpour not_allowed)
			(footprints allowed)
		)
		(placement
			(enabled no)
			(sheetname "")
		)
		(fill yes
			(thermal_gap 0.5)
			(thermal_bridge_width 0.5)
			(island_removal_mode 0)
		)
		(polygon
			(pts
				(arc
					(start 310.226202 -288.299906)
					(mid 309.573422 -288.299906)
					(end 310.226202 -288.299906)
				)
			)
		)
	)
	(zone
		(layers "B.Cu" "In11.Cu" "In13.Cu" "In15.Cu")
		(hatch none 0.5)
		(connect_pads
			(clearance 0)
		)
		(min_thickness 0.25)
		(keepout
			(tracks not_allowed)
			(vias allowed)
			(pads allowed)
			(copperpour not_allowed)
			(footprints allowed)
		)
		(placement
			(enabled no)
			(sheetname "")
		)
		(fill yes
			(thermal_gap 0.5)
			(thermal_bridge_width 0.5)
			(island_removal_mode 0)
		)
		(polygon
			(pts
				(arc
					(start 432.82616 -148.02231)
					(mid 432.12258 -148.02231)
					(end 432.82616 -148.02231)
				)
			)
		)
	)
	(zone
		(layers "B.Cu" "In11.Cu" "In13.Cu" "In15.Cu")
		(hatch none 0.5)
		(connect_pads
			(clearance 0)
		)
		(min_thickness 0.25)
		(keepout
			(tracks not_allowed)
			(vias allowed)
			(pads allowed)
			(copperpour not_allowed)
			(footprints allowed)
		)
		(placement
			(enabled no)
			(sheetname "")
		)
		(fill yes
			(thermal_gap 0.5)
			(thermal_bridge_width 0.5)
			(island_removal_mode 0)
		)
		(polygon
			(pts
				(arc
					(start 404.767288 18.467324)
					(mid 404.063708 18.467324)
					(end 404.767288 18.467324)
				)
			)
		)
	)
	(zone
		(layers "B.Cu" "In11.Cu" "In13.Cu" "In15.Cu")
		(hatch none 0.5)
		(connect_pads
			(clearance 0)
		)
		(min_thickness 0.25)
		(keepout
			(tracks not_allowed)
			(vias allowed)
			(pads allowed)
			(copperpour not_allowed)
			(footprints allowed)
		)
		(placement
			(enabled no)
			(sheetname "")
		)
		(fill yes
			(thermal_gap 0.5)
			(thermal_bridge_width 0.5)
			(island_removal_mode 0)
		)
		(polygon
			(pts
				(arc
					(start 84.52612 -121.365772)
					(mid 83.82254 -121.365772)
					(end 84.52612 -121.365772)
				)
			)
		)
	)
	(zone
		(layers "B.Cu" "In11.Cu" "In13.Cu" "In15.Cu")
		(hatch none 0.5)
		(connect_pads
			(clearance 0)
		)
		(min_thickness 0.25)
		(keepout
			(tracks not_allowed)
			(vias allowed)
			(pads allowed)
			(copperpour not_allowed)
			(footprints allowed)
		)
		(placement
			(enabled no)
			(sheetname "")
		)
		(fill yes
			(thermal_gap 0.5)
			(thermal_bridge_width 0.5)
			(island_removal_mode 0)
		)
		(polygon
			(pts
				(arc
					(start 338.469732 -375.490232)
					(mid 337.710272 -375.490232)
					(end 338.469732 -375.490232)
				)
			)
		)
	)
	(zone
		(layers "B.Cu" "In11.Cu" "In13.Cu" "In15.Cu")
		(hatch none 0.5)
		(connect_pads
			(clearance 0)
		)
		(min_thickness 0.25)
		(keepout
			(tracks not_allowed)
			(vias allowed)
			(pads allowed)
			(copperpour not_allowed)
			(footprints allowed)
		)
		(placement
			(enabled no)
			(sheetname "")
		)
		(fill yes
			(thermal_gap 0.5)
			(thermal_bridge_width 0.5)
			(island_removal_mode 0)
		)
		(polygon
			(pts
				(arc
					(start 76.12634 -285.449772)
					(mid 75.47356 -285.449772)
					(end 76.12634 -285.449772)
				)
			)
		)
	)
	(zone
		(layers "B.Cu" "In11.Cu" "In13.Cu" "In15.Cu")
		(hatch none 0.5)
		(connect_pads
			(clearance 0)
		)
		(min_thickness 0.25)
		(keepout
			(tracks not_allowed)
			(vias allowed)
			(pads allowed)
			(copperpour not_allowed)
			(footprints allowed)
		)
		(placement
			(enabled no)
			(sheetname "")
		)
		(fill yes
			(thermal_gap 0.5)
			(thermal_bridge_width 0.5)
			(island_removal_mode 0)
		)
		(polygon
			(pts
				(arc
					(start 197.983856 -153.415746)
					(mid 197.280276 -153.415746)
					(end 197.983856 -153.415746)
				)
			)
		)
	)
	(zone
		(layers "B.Cu" "In11.Cu" "In13.Cu" "In15.Cu")
		(hatch none 0.5)
		(connect_pads
			(clearance 0)
		)
		(min_thickness 0.25)
		(keepout
			(tracks not_allowed)
			(vias allowed)
			(pads allowed)
			(copperpour not_allowed)
			(footprints allowed)
		)
		(placement
			(enabled no)
			(sheetname "")
		)
		(fill yes
			(thermal_gap 0.5)
			(thermal_bridge_width 0.5)
			(island_removal_mode 0)
		)
		(polygon
			(pts
				(arc
					(start 200.625964 -155.222194)
					(mid 199.922384 -155.222194)
					(end 200.625964 -155.222194)
				)
			)
		)
	)
	(zone
		(layers "B.Cu" "In11.Cu" "In13.Cu" "In15.Cu")
		(hatch none 0.5)
		(connect_pads
			(clearance 0)
		)
		(min_thickness 0.25)
		(keepout
			(tracks not_allowed)
			(vias allowed)
			(pads allowed)
			(copperpour not_allowed)
			(footprints allowed)
		)
		(placement
			(enabled no)
			(sheetname "")
		)
		(fill yes
			(thermal_gap 0.5)
			(thermal_bridge_width 0.5)
			(island_removal_mode 0)
		)
		(polygon
			(pts
				(arc
					(start 334.06969 -376.790204)
					(mid 333.31023 -376.790204)
					(end 334.06969 -376.790204)
				)
			)
		)
	)
	(zone
		(layers "B.Cu" "In11.Cu" "In13.Cu" "In15.Cu")
		(hatch none 0.5)
		(connect_pads
			(clearance 0)
		)
		(min_thickness 0.25)
		(keepout
			(tracks not_allowed)
			(vias allowed)
			(pads allowed)
			(copperpour not_allowed)
			(footprints allowed)
		)
		(placement
			(enabled no)
			(sheetname "")
		)
		(fill yes
			(thermal_gap 0.5)
			(thermal_bridge_width 0.5)
			(island_removal_mode 0)
		)
		(polygon
			(pts
				(arc
					(start 383.77749 -108.32084)
					(mid 383.07391 -108.32084)
					(end 383.77749 -108.32084)
				)
			)
		)
	)
	(zone
		(layers "B.Cu" "In11.Cu" "In13.Cu" "In15.Cu")
		(hatch none 0.5)
		(connect_pads
			(clearance 0)
		)
		(min_thickness 0.25)
		(keepout
			(tracks not_allowed)
			(vias allowed)
			(pads allowed)
			(copperpour not_allowed)
			(footprints allowed)
		)
		(placement
			(enabled no)
			(sheetname "")
		)
		(fill yes
			(thermal_gap 0.5)
			(thermal_bridge_width 0.5)
			(island_removal_mode 0)
		)
		(polygon
			(pts
				(arc
					(start 270.3195 -135.840724)
					(mid 269.61592 -135.840724)
					(end 270.3195 -135.840724)
				)
			)
		)
	)
	(zone
		(layers "B.Cu" "In11.Cu" "In13.Cu" "In15.Cu")
		(hatch none 0.5)
		(connect_pads
			(clearance 0)
		)
		(min_thickness 0.25)
		(keepout
			(tracks not_allowed)
			(vias allowed)
			(pads allowed)
			(copperpour not_allowed)
			(footprints allowed)
		)
		(placement
			(enabled no)
			(sheetname "")
		)
		(fill yes
			(thermal_gap 0.5)
			(thermal_bridge_width 0.5)
			(island_removal_mode 0)
		)
		(polygon
			(pts
				(arc
					(start 267.677392 -123.68784)
					(mid 266.973812 -123.68784)
					(end 267.677392 -123.68784)
				)
			)
		)
	)
	(zone
		(layers "B.Cu" "In11.Cu" "In13.Cu" "In15.Cu")
		(hatch none 0.5)
		(connect_pads
			(clearance 0)
		)
		(min_thickness 0.25)
		(keepout
			(tracks not_allowed)
			(vias allowed)
			(pads allowed)
			(copperpour not_allowed)
			(footprints allowed)
		)
		(placement
			(enabled no)
			(sheetname "")
		)
		(fill yes
			(thermal_gap 0.5)
			(thermal_bridge_width 0.5)
			(island_removal_mode 0)
		)
		(polygon
			(pts
				(arc
					(start 314.083954 -143.479266)
					(mid 313.380374 -143.479266)
					(end 314.083954 -143.479266)
				)
			)
		)
	)
	(zone
		(layers "B.Cu" "In11.Cu" "In13.Cu" "In15.Cu")
		(hatch none 0.5)
		(connect_pads
			(clearance 0)
		)
		(min_thickness 0.25)
		(keepout
			(tracks not_allowed)
			(vias allowed)
			(pads allowed)
			(copperpour not_allowed)
			(footprints allowed)
		)
		(placement
			(enabled no)
			(sheetname "")
		)
		(fill yes
			(thermal_gap 0.5)
			(thermal_bridge_width 0.5)
			(island_removal_mode 0)
		)
		(polygon
			(pts
				(arc
					(start 186.526424 -279.749504)
					(mid 185.873644 -279.749504)
					(end 186.526424 -279.749504)
				)
			)
		)
	)
	(zone
		(layers "B.Cu" "In11.Cu" "In13.Cu" "In15.Cu")
		(hatch none 0.5)
		(connect_pads
			(clearance 0)
		)
		(min_thickness 0.25)
		(keepout
			(tracks not_allowed)
			(vias allowed)
			(pads allowed)
			(copperpour not_allowed)
			(footprints allowed)
		)
		(placement
			(enabled no)
			(sheetname "")
		)
		(fill yes
			(thermal_gap 0.5)
			(thermal_bridge_width 0.5)
			(island_removal_mode 0)
		)
		(polygon
			(pts
				(arc
					(start 72.28967 -396.49019)
					(mid 71.53021 -396.49019)
					(end 72.28967 -396.49019)
				)
			)
		)
	)
	(zone
		(layers "B.Cu" "In11.Cu" "In13.Cu" "In15.Cu")
		(hatch none 0.5)
		(connect_pads
			(clearance 0)
		)
		(min_thickness 0.25)
		(keepout
			(tracks not_allowed)
			(vias allowed)
			(pads allowed)
			(copperpour not_allowed)
			(footprints allowed)
		)
		(placement
			(enabled no)
			(sheetname "")
		)
		(fill yes
			(thermal_gap 0.5)
			(thermal_bridge_width 0.5)
			(island_removal_mode 0)
		)
		(polygon
			(pts
				(arc
					(start 386.426202 -302.549814)
					(mid 385.773422 -302.549814)
					(end 386.426202 -302.549814)
				)
			)
		)
	)
	(zone
		(layers "B.Cu" "In11.Cu" "In13.Cu" "In15.Cu")
		(hatch none 0.5)
		(connect_pads
			(clearance 0)
		)
		(min_thickness 0.25)
		(keepout
			(tracks not_allowed)
			(vias allowed)
			(pads allowed)
			(copperpour not_allowed)
			(footprints allowed)
		)
		(placement
			(enabled no)
			(sheetname "")
		)
		(fill yes
			(thermal_gap 0.5)
			(thermal_bridge_width 0.5)
			(island_removal_mode 0)
		)
		(polygon
			(pts
				(arc
					(start 421.575992 -278.799798)
					(mid 420.923212 -278.799798)
					(end 421.575992 -278.799798)
				)
			)
		)
	)
	(zone
		(layers "B.Cu" "In11.Cu" "In13.Cu" "In15.Cu")
		(hatch none 0.5)
		(connect_pads
			(clearance 0)
		)
		(min_thickness 0.25)
		(keepout
			(tracks not_allowed)
			(vias allowed)
			(pads allowed)
			(copperpour not_allowed)
			(footprints allowed)
		)
		(placement
			(enabled no)
			(sheetname "")
		)
		(fill yes
			(thermal_gap 0.5)
			(thermal_bridge_width 0.5)
			(island_removal_mode 0)
		)
		(polygon
			(pts
				(arc
					(start 270.3195 -100.177854)
					(mid 269.61592 -100.177854)
					(end 270.3195 -100.177854)
				)
			)
		)
	)
	(zone
		(layers "B.Cu" "In11.Cu" "In13.Cu" "In15.Cu")
		(hatch none 0.5)
		(connect_pads
			(clearance 0)
		)
		(min_thickness 0.25)
		(keepout
			(tracks not_allowed)
			(vias allowed)
			(pads allowed)
			(copperpour not_allowed)
			(footprints allowed)
		)
		(placement
			(enabled no)
			(sheetname "")
		)
		(fill yes
			(thermal_gap 0.5)
			(thermal_bridge_width 0.5)
			(island_removal_mode 0)
		)
		(polygon
			(pts
				(arc
					(start 432.82616 -144.422114)
					(mid 432.12258 -144.422114)
					(end 432.82616 -144.422114)
				)
			)
		)
	)
	(zone
		(layers "B.Cu" "In11.Cu" "In13.Cu" "In15.Cu")
		(hatch none 0.5)
		(connect_pads
			(clearance 0)
		)
		(min_thickness 0.25)
		(keepout
			(tracks not_allowed)
			(vias allowed)
			(pads allowed)
			(copperpour not_allowed)
			(footprints allowed)
		)
		(placement
			(enabled no)
			(sheetname "")
		)
		(fill yes
			(thermal_gap 0.5)
			(thermal_bridge_width 0.5)
			(island_removal_mode 0)
		)
		(polygon
			(pts
				(arc
					(start 290.27628 -317.749936)
					(mid 289.6235 -317.749936)
					(end 290.27628 -317.749936)
				)
			)
		)
	)
	(zone
		(layers "B.Cu" "In11.Cu" "In13.Cu" "In15.Cu")
		(hatch none 0.5)
		(connect_pads
			(clearance 0)
		)
		(min_thickness 0.25)
		(keepout
			(tracks not_allowed)
			(vias allowed)
			(pads allowed)
			(copperpour not_allowed)
			(footprints allowed)
		)
		(placement
			(enabled no)
			(sheetname "")
		)
		(fill yes
			(thermal_gap 0.5)
			(thermal_bridge_width 0.5)
			(island_removal_mode 0)
		)
		(polygon
			(pts
				(arc
					(start 76.689712 -397.790162)
					(mid 75.930252 -397.790162)
					(end 76.689712 -397.790162)
				)
			)
		)
	)
	(zone
		(layers "B.Cu" "In11.Cu" "In13.Cu" "In15.Cu")
		(hatch none 0.5)
		(connect_pads
			(clearance 0)
		)
		(min_thickness 0.25)
		(keepout
			(tracks not_allowed)
			(vias allowed)
			(pads allowed)
			(copperpour not_allowed)
			(footprints allowed)
		)
		(placement
			(enabled no)
			(sheetname "")
		)
		(fill yes
			(thermal_gap 0.5)
			(thermal_bridge_width 0.5)
			(island_removal_mode 0)
		)
		(polygon
			(pts
				(arc
					(start 430.184052 -153.415746)
					(mid 429.480472 -153.415746)
					(end 430.184052 -153.415746)
				)
			)
		)
	)
	(zone
		(layers "B.Cu" "In11.Cu" "In13.Cu" "In15.Cu")
		(hatch none 0.5)
		(connect_pads
			(clearance 0)
		)
		(min_thickness 0.25)
		(keepout
			(tracks not_allowed)
			(vias allowed)
			(pads allowed)
			(copperpour not_allowed)
			(footprints allowed)
		)
		(placement
			(enabled no)
			(sheetname "")
		)
		(fill yes
			(thermal_gap 0.5)
			(thermal_bridge_width 0.5)
			(island_removal_mode 0)
		)
		(polygon
			(pts
				(arc
					(start 408.276044 -277.849838)
					(mid 407.623264 -277.849838)
					(end 408.276044 -277.849838)
				)
			)
		)
	)
	(zone
		(layers "B.Cu" "In11.Cu" "In13.Cu" "In15.Cu")
		(hatch none 0.5)
		(connect_pads
			(clearance 0)
		)
		(min_thickness 0.25)
		(keepout
			(tracks not_allowed)
			(vias allowed)
			(pads allowed)
			(copperpour not_allowed)
			(footprints allowed)
		)
		(placement
			(enabled no)
			(sheetname "")
		)
		(fill yes
			(thermal_gap 0.5)
			(thermal_bridge_width 0.5)
			(island_removal_mode 0)
		)
		(polygon
			(pts
				(arc
					(start 154.219402 -103.777796)
					(mid 153.515822 -103.777796)
					(end 154.219402 -103.777796)
				)
			)
		)
	)
	(zone
		(layers "B.Cu" "In11.Cu" "In13.Cu" "In15.Cu")
		(hatch none 0.5)
		(connect_pads
			(clearance 0)
		)
		(min_thickness 0.25)
		(keepout
			(tracks not_allowed)
			(vias allowed)
			(pads allowed)
			(copperpour not_allowed)
			(footprints allowed)
		)
		(placement
			(enabled no)
			(sheetname "")
		)
		(fill yes
			(thermal_gap 0.5)
			(thermal_bridge_width 0.5)
			(island_removal_mode 0)
		)
		(polygon
			(pts
				(arc
					(start 152.186894 -101.120702)
					(mid 151.483314 -101.120702)
					(end 152.186894 -101.120702)
				)
			)
		)
	)
	(zone
		(layers "B.Cu" "In11.Cu" "In13.Cu" "In15.Cu")
		(hatch none 0.5)
		(connect_pads
			(clearance 0)
		)
		(min_thickness 0.25)
		(keepout
			(tracks not_allowed)
			(vias allowed)
			(pads allowed)
			(copperpour not_allowed)
			(footprints allowed)
		)
		(placement
			(enabled no)
			(sheetname "")
		)
		(fill yes
			(thermal_gap 0.5)
			(thermal_bridge_width 0.5)
			(island_removal_mode 0)
		)
		(polygon
			(pts
				(arc
					(start 270.3195 -132.240782)
					(mid 269.61592 -132.240782)
					(end 270.3195 -132.240782)
				)
			)
		)
	)
	(zone
		(layers "B.Cu" "In11.Cu" "In13.Cu" "In15.Cu")
		(hatch none 0.5)
		(connect_pads
			(clearance 0)
		)
		(min_thickness 0.25)
		(keepout
			(tracks not_allowed)
			(vias allowed)
			(pads allowed)
			(copperpour not_allowed)
			(footprints allowed)
		)
		(placement
			(enabled no)
			(sheetname "")
		)
		(fill yes
			(thermal_gap 0.5)
			(thermal_bridge_width 0.5)
			(island_removal_mode 0)
		)
		(polygon
			(pts
				(arc
					(start 418.726366 -280.699718)
					(mid 418.073586 -280.699718)
					(end 418.726366 -280.699718)
				)
			)
		)
	)
	(zone
		(layers "B.Cu" "In11.Cu" "In13.Cu" "In15.Cu")
		(hatch none 0.5)
		(connect_pads
			(clearance 0)
		)
		(min_thickness 0.25)
		(keepout
			(tracks not_allowed)
			(vias allowed)
			(pads allowed)
			(copperpour not_allowed)
			(footprints allowed)
		)
		(placement
			(enabled no)
			(sheetname "")
		)
		(fill yes
			(thermal_gap 0.5)
			(thermal_bridge_width 0.5)
			(island_removal_mode 0)
		)
		(polygon
			(pts
				(arc
					(start 309.276242 -288.299906)
					(mid 308.623462 -288.299906)
					(end 309.276242 -288.299906)
				)
			)
		)
	)
	(zone
		(layers "B.Cu" "In11.Cu" "In13.Cu" "In15.Cu")
		(hatch none 0.5)
		(connect_pads
			(clearance 0)
		)
		(min_thickness 0.25)
		(keepout
			(tracks not_allowed)
			(vias allowed)
			(pads allowed)
			(copperpour not_allowed)
			(footprints allowed)
		)
		(placement
			(enabled no)
			(sheetname "")
		)
		(fill yes
			(thermal_gap 0.5)
			(thermal_bridge_width 0.5)
			(island_removal_mode 0)
		)
		(polygon
			(pts
				(arc
					(start 423.476166 -277.849838)
					(mid 422.823386 -277.849838)
					(end 423.476166 -277.849838)
				)
			)
		)
	)
	(zone
		(layers "B.Cu" "In11.Cu" "In13.Cu" "In15.Cu")
		(hatch none 0.5)
		(connect_pads
			(clearance 0)
		)
		(min_thickness 0.25)
		(keepout
			(tracks not_allowed)
			(vias allowed)
			(pads allowed)
			(copperpour not_allowed)
			(footprints allowed)
		)
		(placement
			(enabled no)
			(sheetname "")
		)
		(fill yes
			(thermal_gap 0.5)
			(thermal_bridge_width 0.5)
			(island_removal_mode 0)
		)
		(polygon
			(pts
				(arc
					(start 82.776314 -276.899878)
					(mid 82.123534 -276.899878)
					(end 82.776314 -276.899878)
				)
			)
		)
	)
	(zone
		(layers "B.Cu" "In11.Cu" "In13.Cu" "In15.Cu")
		(hatch none 0.5)
		(connect_pads
			(clearance 0)
		)
		(min_thickness 0.25)
		(keepout
			(tracks not_allowed)
			(vias allowed)
			(pads allowed)
			(copperpour not_allowed)
			(footprints allowed)
		)
		(placement
			(enabled no)
			(sheetname "")
		)
		(fill yes
			(thermal_gap 0.5)
			(thermal_bridge_width 0.5)
			(island_removal_mode 0)
		)
		(polygon
			(pts
				(arc
					(start 180.82641 -279.749504)
					(mid 180.17363 -279.749504)
					(end 180.82641 -279.749504)
				)
			)
		)
	)
	(zone
		(layers "B.Cu" "In11.Cu" "In13.Cu" "In15.Cu")
		(hatch none 0.5)
		(connect_pads
			(clearance 0)
		)
		(min_thickness 0.25)
		(keepout
			(tracks not_allowed)
			(vias allowed)
			(pads allowed)
			(copperpour not_allowed)
			(footprints allowed)
		)
		(placement
			(enabled no)
			(sheetname "")
		)
		(fill yes
			(thermal_gap 0.5)
			(thermal_bridge_width 0.5)
			(island_removal_mode 0)
		)
		(polygon
			(pts
				(arc
					(start 267.677392 -119.224298)
					(mid 266.973812 -119.224298)
					(end 267.677392 -119.224298)
				)
			)
		)
	)
	(zone
		(layers "B.Cu" "In11.Cu" "In13.Cu" "In15.Cu")
		(hatch none 0.5)
		(connect_pads
			(clearance 0)
		)
		(min_thickness 0.25)
		(keepout
			(tracks not_allowed)
			(vias allowed)
			(pads allowed)
			(copperpour not_allowed)
			(footprints allowed)
		)
		(placement
			(enabled no)
			(sheetname "")
		)
		(fill yes
			(thermal_gap 0.5)
			(thermal_bridge_width 0.5)
			(island_removal_mode 0)
		)
		(polygon
			(pts
				(arc
					(start 193.176398 -286.399986)
					(mid 192.523618 -286.399986)
					(end 193.176398 -286.399986)
				)
			)
		)
	)
	(zone
		(layers "B.Cu" "In11.Cu" "In13.Cu" "In15.Cu")
		(hatch none 0.5)
		(connect_pads
			(clearance 0)
		)
		(min_thickness 0.25)
		(keepout
			(tracks not_allowed)
			(vias allowed)
			(pads allowed)
			(copperpour not_allowed)
			(footprints allowed)
		)
		(placement
			(enabled no)
			(sheetname "")
		)
		(fill yes
			(thermal_gap 0.5)
			(thermal_bridge_width 0.5)
			(island_removal_mode 0)
		)
		(polygon
			(pts
				(arc
					(start 68.526152 -280.699718)
					(mid 67.873372 -280.699718)
					(end 68.526152 -280.699718)
				)
			)
		)
	)
	(zone
		(layers "B.Cu" "In11.Cu" "In13.Cu" "In15.Cu")
		(hatch none 0.5)
		(connect_pads
			(clearance 0)
		)
		(min_thickness 0.25)
		(keepout
			(tracks not_allowed)
			(vias allowed)
			(pads allowed)
			(copperpour not_allowed)
			(footprints allowed)
		)
		(placement
			(enabled no)
			(sheetname "")
		)
		(fill yes
			(thermal_gap 0.5)
			(thermal_bridge_width 0.5)
			(island_removal_mode 0)
		)
		(polygon
			(pts
				(arc
					(start 63.776352 -317.749936)
					(mid 63.123572 -317.749936)
					(end 63.776352 -317.749936)
				)
			)
		)
	)
	(zone
		(layers "B.Cu" "In11.Cu" "In13.Cu" "In15.Cu")
		(hatch none 0.5)
		(connect_pads
			(clearance 0)
		)
		(min_thickness 0.25)
		(keepout
			(tracks not_allowed)
			(vias allowed)
			(pads allowed)
			(copperpour not_allowed)
			(footprints allowed)
		)
		(placement
			(enabled no)
			(sheetname "")
		)
		(fill yes
			(thermal_gap 0.5)
			(thermal_bridge_width 0.5)
			(island_removal_mode 0)
		)
		(polygon
			(pts
				(arc
					(start 314.083954 -134.369302)
					(mid 313.380374 -134.369302)
					(end 314.083954 -134.369302)
				)
			)
		)
	)
	(zone
		(layers "B.Cu" "In11.Cu" "In13.Cu" "In15.Cu")
		(hatch none 0.5)
		(connect_pads
			(clearance 0)
		)
		(min_thickness 0.25)
		(keepout
			(tracks not_allowed)
			(vias allowed)
			(pads allowed)
			(copperpour not_allowed)
			(footprints allowed)
		)
		(placement
			(enabled no)
			(sheetname "")
		)
		(fill yes
			(thermal_gap 0.5)
			(thermal_bridge_width 0.5)
			(island_removal_mode 0)
		)
		(polygon
			(pts
				(arc
					(start 295.976294 -317.749936)
					(mid 295.323514 -317.749936)
					(end 295.976294 -317.749936)
				)
			)
		)
	)
	(zone
		(layers "B.Cu" "In11.Cu" "In13.Cu" "In15.Cu")
		(hatch none 0.5)
		(connect_pads
			(clearance 0)
		)
		(min_thickness 0.25)
		(keepout
			(tracks not_allowed)
			(vias allowed)
			(pads allowed)
			(copperpour not_allowed)
			(footprints allowed)
		)
		(placement
			(enabled no)
			(sheetname "")
		)
		(fill yes
			(thermal_gap 0.5)
			(thermal_bridge_width 0.5)
			(island_removal_mode 0)
		)
		(polygon
			(pts
				(arc
					(start 162.489642 -383.290064)
					(mid 161.730182 -383.290064)
					(end 162.489642 -383.290064)
				)
			)
		)
	)
	(zone
		(layers "B.Cu" "In11.Cu" "In13.Cu" "In15.Cu")
		(hatch none 0.5)
		(connect_pads
			(clearance 0)
		)
		(min_thickness 0.25)
		(keepout
			(tracks not_allowed)
			(vias allowed)
			(pads allowed)
			(copperpour not_allowed)
			(footprints allowed)
		)
		(placement
			(enabled no)
			(sheetname "")
		)
		(fill yes
			(thermal_gap 0.5)
			(thermal_bridge_width 0.5)
			(island_removal_mode 0)
		)
		(polygon
			(pts
				(arc
					(start 388.326376 -301.599854)
					(mid 387.673596 -301.599854)
					(end 388.326376 -301.599854)
				)
			)
		)
	)
	(zone
		(layers "B.Cu" "In11.Cu" "In13.Cu" "In15.Cu")
		(hatch none 0.5)
		(connect_pads
			(clearance 0)
		)
		(min_thickness 0.25)
		(keepout
			(tracks not_allowed)
			(vias allowed)
			(pads allowed)
			(copperpour not_allowed)
			(footprints allowed)
		)
		(placement
			(enabled no)
			(sheetname "")
		)
		(fill yes
			(thermal_gap 0.5)
			(thermal_bridge_width 0.5)
			(island_removal_mode 0)
		)
		(polygon
			(pts
				(arc
					(start 430.869598 -410.589984)
					(mid 430.110138 -410.589984)
					(end 430.869598 -410.589984)
				)
			)
		)
	)
	(zone
		(layers "B.Cu" "In11.Cu" "In13.Cu" "In15.Cu")
		(hatch none 0.5)
		(connect_pads
			(clearance 0)
		)
		(min_thickness 0.25)
		(keepout
			(tracks not_allowed)
			(vias allowed)
			(pads allowed)
			(copperpour not_allowed)
			(footprints allowed)
		)
		(placement
			(enabled no)
			(sheetname "")
		)
		(fill yes
			(thermal_gap 0.5)
			(thermal_bridge_width 0.5)
			(island_removal_mode 0)
		)
		(polygon
			(pts
				(arc
					(start 78.02626 -280.699718)
					(mid 77.37348 -280.699718)
					(end 78.02626 -280.699718)
				)
			)
		)
	)
	(zone
		(layers "B.Cu" "In11.Cu" "In13.Cu" "In15.Cu")
		(hatch none 0.5)
		(connect_pads
			(clearance 0)
		)
		(min_thickness 0.25)
		(keepout
			(tracks not_allowed)
			(vias allowed)
			(pads allowed)
			(copperpour not_allowed)
			(footprints allowed)
		)
		(placement
			(enabled no)
			(sheetname "")
		)
		(fill yes
			(thermal_gap 0.5)
			(thermal_bridge_width 0.5)
			(island_removal_mode 0)
		)
		(polygon
			(pts
				(arc
					(start 424.42638 -279.749504)
					(mid 423.7736 -279.749504)
					(end 424.42638 -279.749504)
				)
			)
		)
	)
	(zone
		(layers "B.Cu" "In11.Cu" "In13.Cu" "In15.Cu")
		(hatch none 0.5)
		(connect_pads
			(clearance 0)
		)
		(min_thickness 0.25)
		(keepout
			(tracks not_allowed)
			(vias allowed)
			(pads allowed)
			(copperpour not_allowed)
			(footprints allowed)
		)
		(placement
			(enabled no)
			(sheetname "")
		)
		(fill yes
			(thermal_gap 0.5)
			(thermal_bridge_width 0.5)
			(island_removal_mode 0)
		)
		(polygon
			(pts
				(arc
					(start 162.489642 -384.590036)
					(mid 161.730182 -384.590036)
					(end 162.489642 -384.590036)
				)
			)
		)
	)
	(zone
		(layers "B.Cu" "In11.Cu" "In13.Cu" "In15.Cu")
		(hatch none 0.5)
		(connect_pads
			(clearance 0)
		)
		(min_thickness 0.25)
		(keepout
			(tracks not_allowed)
			(vias allowed)
			(pads allowed)
			(copperpour not_allowed)
			(footprints allowed)
		)
		(placement
			(enabled no)
			(sheetname "")
		)
		(fill yes
			(thermal_gap 0.5)
			(thermal_bridge_width 0.5)
			(island_removal_mode 0)
		)
		(polygon
			(pts
				(arc
					(start 385.476242 -302.549814)
					(mid 384.823462 -302.549814)
					(end 385.476242 -302.549814)
				)
			)
		)
	)
	(zone
		(layers "B.Cu" "In11.Cu" "In13.Cu" "In15.Cu")
		(hatch none 0.5)
		(connect_pads
			(clearance 0)
		)
		(min_thickness 0.25)
		(keepout
			(tracks not_allowed)
			(vias allowed)
			(pads allowed)
			(copperpour not_allowed)
			(footprints allowed)
		)
		(placement
			(enabled no)
			(sheetname "")
		)
		(fill yes
			(thermal_gap 0.5)
			(thermal_bridge_width 0.5)
			(island_removal_mode 0)
		)
		(polygon
			(pts
				(arc
					(start 81.884012 -153.415746)
					(mid 81.180432 -153.415746)
					(end 81.884012 -153.415746)
				)
			)
		)
	)
	(zone
		(layers "B.Cu" "In11.Cu" "In13.Cu" "In15.Cu")
		(hatch none 0.5)
		(connect_pads
			(clearance 0)
		)
		(min_thickness 0.25)
		(keepout
			(tracks not_allowed)
			(vias allowed)
			(pads allowed)
			(copperpour not_allowed)
			(footprints allowed)
		)
		(placement
			(enabled no)
			(sheetname "")
		)
		(fill yes
			(thermal_gap 0.5)
			(thermal_bridge_width 0.5)
			(island_removal_mode 0)
		)
		(polygon
			(pts
				(arc
					(start 314.083954 -118.695724)
					(mid 313.380374 -118.695724)
					(end 314.083954 -118.695724)
				)
			)
		)
	)
	(zone
		(layers "B.Cu" "In11.Cu" "In13.Cu" "In15.Cu")
		(hatch none 0.5)
		(connect_pads
			(clearance 0)
		)
		(min_thickness 0.25)
		(keepout
			(tracks not_allowed)
			(vias allowed)
			(pads allowed)
			(copperpour not_allowed)
			(footprints allowed)
		)
		(placement
			(enabled no)
			(sheetname "")
		)
		(fill yes
			(thermal_gap 0.5)
			(thermal_bridge_width 0.5)
			(island_removal_mode 0)
		)
		(polygon
			(pts
				(arc
					(start 441.39866 17.596612)
					(mid 440.69508 17.596612)
					(end 441.39866 17.596612)
				)
			)
		)
	)
	(zone
		(layers "B.Cu" "In11.Cu" "In13.Cu" "In15.Cu")
		(hatch none 0.5)
		(connect_pads
			(clearance 0)
		)
		(min_thickness 0.25)
		(keepout
			(tracks not_allowed)
			(vias allowed)
			(pads allowed)
			(copperpour not_allowed)
			(footprints allowed)
		)
		(placement
			(enabled no)
			(sheetname "")
		)
		(fill yes
			(thermal_gap 0.5)
			(thermal_bridge_width 0.5)
			(island_removal_mode 0)
		)
		(polygon
			(pts
				(arc
					(start 76.12634 -279.749504)
					(mid 75.47356 -279.749504)
					(end 76.12634 -279.749504)
				)
			)
		)
	)
	(zone
		(layers "B.Cu" "In11.Cu" "In13.Cu" "In15.Cu")
		(hatch none 0.5)
		(connect_pads
			(clearance 0)
		)
		(min_thickness 0.25)
		(keepout
			(tracks not_allowed)
			(vias allowed)
			(pads allowed)
			(copperpour not_allowed)
			(footprints allowed)
		)
		(placement
			(enabled no)
			(sheetname "")
		)
		(fill yes
			(thermal_gap 0.5)
			(thermal_bridge_width 0.5)
			(island_removal_mode 0)
		)
		(polygon
			(pts
				(arc
					(start 387.376416 -303.499774)
					(mid 386.723636 -303.499774)
					(end 387.376416 -303.499774)
				)
			)
		)
	)
	(zone
		(layers "B.Cu" "In11.Cu" "In13.Cu" "In15.Cu")
		(hatch none 0.5)
		(connect_pads
			(clearance 0)
		)
		(min_thickness 0.25)
		(keepout
			(tracks not_allowed)
			(vias allowed)
			(pads allowed)
			(copperpour not_allowed)
			(footprints allowed)
		)
		(placement
			(enabled no)
			(sheetname "")
		)
		(fill yes
			(thermal_gap 0.5)
			(thermal_bridge_width 0.5)
			(island_removal_mode 0)
		)
		(polygon
			(pts
				(arc
					(start 419.676072 -278.799798)
					(mid 419.023292 -278.799798)
					(end 419.676072 -278.799798)
				)
			)
		)
	)
	(zone
		(layers "B.Cu" "In11.Cu" "In13.Cu" "In15.Cu")
		(hatch none 0.5)
		(connect_pads
			(clearance 0)
		)
		(min_thickness 0.25)
		(keepout
			(tracks not_allowed)
			(vias allowed)
			(pads allowed)
			(copperpour not_allowed)
			(footprints allowed)
		)
		(placement
			(enabled no)
			(sheetname "")
		)
		(fill yes
			(thermal_gap 0.5)
			(thermal_bridge_width 0.5)
			(island_removal_mode 0)
		)
		(polygon
			(pts
				(arc
					(start 76.12634 -280.699718)
					(mid 75.47356 -280.699718)
					(end 76.12634 -280.699718)
				)
			)
		)
	)
	(zone
		(layers "B.Cu" "In11.Cu" "In13.Cu" "In15.Cu")
		(hatch none 0.5)
		(connect_pads
			(clearance 0)
		)
		(min_thickness 0.25)
		(keepout
			(tracks not_allowed)
			(vias allowed)
			(pads allowed)
			(copperpour not_allowed)
			(footprints allowed)
		)
		(placement
			(enabled no)
			(sheetname "")
		)
		(fill yes
			(thermal_gap 0.5)
			(thermal_bridge_width 0.5)
			(island_removal_mode 0)
		)
		(polygon
			(pts
				(arc
					(start 267.677392 -111.920782)
					(mid 266.973812 -111.920782)
					(end 267.677392 -111.920782)
				)
			)
		)
	)
	(zone
		(layers "B.Cu" "In11.Cu" "In13.Cu" "In15.Cu")
		(hatch none 0.5)
		(connect_pads
			(clearance 0)
		)
		(min_thickness 0.25)
		(keepout
			(tracks not_allowed)
			(vias allowed)
			(pads allowed)
			(copperpour not_allowed)
			(footprints allowed)
		)
		(placement
			(enabled no)
			(sheetname "")
		)
		(fill yes
			(thermal_gap 0.5)
			(thermal_bridge_width 0.5)
			(island_removal_mode 0)
		)
		(polygon
			(pts
				(arc
					(start 78.889606 -375.490232)
					(mid 78.130146 -375.490232)
					(end 78.889606 -375.490232)
				)
			)
		)
	)
	(zone
		(layers "B.Cu" "In11.Cu" "In13.Cu" "In15.Cu")
		(hatch none 0.5)
		(connect_pads
			(clearance 0)
		)
		(min_thickness 0.25)
		(keepout
			(tracks not_allowed)
			(vias allowed)
			(pads allowed)
			(copperpour not_allowed)
			(footprints allowed)
		)
		(placement
			(enabled no)
			(sheetname "")
		)
		(fill yes
			(thermal_gap 0.5)
			(thermal_bridge_width 0.5)
			(island_removal_mode 0)
		)
		(polygon
			(pts
				(arc
					(start 291.22624 -315.849762)
					(mid 290.57346 -315.849762)
					(end 291.22624 -315.849762)
				)
			)
		)
	)
	(zone
		(layers "B.Cu" "In11.Cu" "In13.Cu" "In15.Cu")
		(hatch none 0.5)
		(connect_pads
			(clearance 0)
		)
		(min_thickness 0.25)
		(keepout
			(tracks not_allowed)
			(vias allowed)
			(pads allowed)
			(copperpour not_allowed)
			(footprints allowed)
		)
		(placement
			(enabled no)
			(sheetname "")
		)
		(fill yes
			(thermal_gap 0.5)
			(thermal_bridge_width 0.5)
			(island_removal_mode 0)
		)
		(polygon
			(pts
				(arc
					(start 196.976238 -278.799798)
					(mid 196.323458 -278.799798)
					(end 196.976238 -278.799798)
				)
			)
		)
	)
	(zone
		(layers "B.Cu" "In11.Cu" "In13.Cu" "In15.Cu")
		(hatch none 0.5)
		(connect_pads
			(clearance 0)
		)
		(min_thickness 0.25)
		(keepout
			(tracks not_allowed)
			(vias allowed)
			(pads allowed)
			(copperpour not_allowed)
			(footprints allowed)
		)
		(placement
			(enabled no)
			(sheetname "")
		)
		(fill yes
			(thermal_gap 0.5)
			(thermal_bridge_width 0.5)
			(island_removal_mode 0)
		)
		(polygon
			(pts
				(arc
					(start 196.026278 -280.699718)
					(mid 195.373498 -280.699718)
					(end 196.026278 -280.699718)
				)
			)
		)
	)
	(zone
		(layers "B.Cu" "In11.Cu" "In13.Cu" "In15.Cu")
		(hatch none 0.5)
		(connect_pads
			(clearance 0)
		)
		(min_thickness 0.25)
		(keepout
			(tracks not_allowed)
			(vias allowed)
			(pads allowed)
			(copperpour not_allowed)
			(footprints allowed)
		)
		(placement
			(enabled no)
			(sheetname "")
		)
		(fill yes
			(thermal_gap 0.5)
			(thermal_bridge_width 0.5)
			(island_removal_mode 0)
		)
		(polygon
			(pts
				(arc
					(start 192.226438 -283.549852)
					(mid 191.573658 -283.549852)
					(end 192.226438 -283.549852)
				)
			)
		)
	)
	(zone
		(layers "B.Cu" "In11.Cu" "In13.Cu" "In15.Cu")
		(hatch none 0.5)
		(connect_pads
			(clearance 0)
		)
		(min_thickness 0.25)
		(keepout
			(tracks not_allowed)
			(vias allowed)
			(pads allowed)
			(copperpour not_allowed)
			(footprints allowed)
		)
		(placement
			(enabled no)
			(sheetname "")
		)
		(fill yes
			(thermal_gap 0.5)
			(thermal_bridge_width 0.5)
			(island_removal_mode 0)
		)
		(polygon
			(pts
				(arc
					(start 338.469732 -376.790204)
					(mid 337.710272 -376.790204)
					(end 338.469732 -376.790204)
				)
			)
		)
	)
	(zone
		(layers "B.Cu" "In11.Cu" "In13.Cu" "In15.Cu")
		(hatch none 0.5)
		(connect_pads
			(clearance 0)
		)
		(min_thickness 0.25)
		(keepout
			(tracks not_allowed)
			(vias allowed)
			(pads allowed)
			(copperpour not_allowed)
			(footprints allowed)
		)
		(placement
			(enabled no)
			(sheetname "")
		)
		(fill yes
			(thermal_gap 0.5)
			(thermal_bridge_width 0.5)
			(island_removal_mode 0)
		)
		(polygon
			(pts
				(arc
					(start 295.02608 -315.849762)
					(mid 294.3733 -315.849762)
					(end 295.02608 -315.849762)
				)
			)
		)
	)
	(zone
		(layers "B.Cu" "In11.Cu" "In13.Cu" "In15.Cu")
		(hatch none 0.5)
		(connect_pads
			(clearance 0)
		)
		(min_thickness 0.25)
		(keepout
			(tracks not_allowed)
			(vias allowed)
			(pads allowed)
			(copperpour not_allowed)
			(footprints allowed)
		)
		(placement
			(enabled no)
			(sheetname "")
		)
		(fill yes
			(thermal_gap 0.5)
			(thermal_bridge_width 0.5)
			(island_removal_mode 0)
		)
		(polygon
			(pts
				(arc
					(start 345.069668 -397.790162)
					(mid 344.310208 -397.790162)
					(end 345.069668 -397.790162)
				)
			)
		)
	)
	(zone
		(layers "B.Cu" "In11.Cu" "In13.Cu" "In15.Cu")
		(hatch none 0.5)
		(connect_pads
			(clearance 0)
		)
		(min_thickness 0.25)
		(keepout
			(tracks not_allowed)
			(vias allowed)
			(pads allowed)
			(copperpour not_allowed)
			(footprints allowed)
		)
		(placement
			(enabled no)
			(sheetname "")
		)
		(fill yes
			(thermal_gap 0.5)
			(thermal_bridge_width 0.5)
			(island_removal_mode 0)
		)
		(polygon
			(pts
				(arc
					(start 316.726062 -148.02231)
					(mid 316.022482 -148.02231)
					(end 316.726062 -148.02231)
				)
			)
		)
	)
	(zone
		(layers "B.Cu" "In11.Cu" "In13.Cu" "In15.Cu")
		(hatch none 0.5)
		(connect_pads
			(clearance 0)
		)
		(min_thickness 0.25)
		(keepout
			(tracks not_allowed)
			(vias allowed)
			(pads allowed)
			(copperpour not_allowed)
			(footprints allowed)
		)
		(placement
			(enabled no)
			(sheetname "")
		)
		(fill yes
			(thermal_gap 0.5)
			(thermal_bridge_width 0.5)
			(island_removal_mode 0)
		)
		(polygon
			(pts
				(arc
					(start 151.577294 -134.034276)
					(mid 150.873714 -134.034276)
					(end 151.577294 -134.034276)
				)
			)
		)
	)
	(zone
		(layers "B.Cu" "In11.Cu" "In13.Cu" "In15.Cu")
		(hatch none 0.5)
		(connect_pads
			(clearance 0)
		)
		(min_thickness 0.25)
		(keepout
			(tracks not_allowed)
			(vias allowed)
			(pads allowed)
			(copperpour not_allowed)
			(footprints allowed)
		)
		(placement
			(enabled no)
			(sheetname "")
		)
		(fill yes
			(thermal_gap 0.5)
			(thermal_bridge_width 0.5)
			(island_removal_mode 0)
		)
		(polygon
			(pts
				(arc
					(start 154.219402 -124.630942)
					(mid 153.515822 -124.630942)
					(end 154.219402 -124.630942)
				)
			)
		)
	)
	(zone
		(layers "B.Cu" "In11.Cu" "In13.Cu" "In15.Cu")
		(hatch none 0.5)
		(connect_pads
			(clearance 0)
		)
		(min_thickness 0.25)
		(keepout
			(tracks not_allowed)
			(vias allowed)
			(pads allowed)
			(copperpour not_allowed)
			(footprints allowed)
		)
		(placement
			(enabled no)
			(sheetname "")
		)
		(fill yes
			(thermal_gap 0.5)
			(thermal_bridge_width 0.5)
			(island_removal_mode 0)
		)
		(polygon
			(pts
				(arc
					(start 384.38709 -101.120702)
					(mid 383.68351 -101.120702)
					(end 384.38709 -101.120702)
				)
			)
		)
	)
	(zone
		(layers "B.Cu" "In11.Cu" "In13.Cu" "In15.Cu")
		(hatch none 0.5)
		(connect_pads
			(clearance 0)
		)
		(min_thickness 0.25)
		(keepout
			(tracks not_allowed)
			(vias allowed)
			(pads allowed)
			(copperpour not_allowed)
			(footprints allowed)
		)
		(placement
			(enabled no)
			(sheetname "")
		)
		(fill yes
			(thermal_gap 0.5)
			(thermal_bridge_width 0.5)
			(island_removal_mode 0)
		)
		(polygon
			(pts
				(arc
					(start 316.726062 -131.712208)
					(mid 316.022482 -131.712208)
					(end 316.726062 -131.712208)
				)
			)
		)
	)
	(zone
		(layers "B.Cu" "In11.Cu" "In13.Cu" "In15.Cu")
		(hatch none 0.5)
		(connect_pads
			(clearance 0)
		)
		(min_thickness 0.25)
		(keepout
			(tracks not_allowed)
			(vias allowed)
			(pads allowed)
			(copperpour not_allowed)
			(footprints allowed)
		)
		(placement
			(enabled no)
			(sheetname "")
		)
		(fill yes
			(thermal_gap 0.5)
			(thermal_bridge_width 0.5)
			(island_removal_mode 0)
		)
		(polygon
			(pts
				(arc
					(start 81.884012 -149.81555)
					(mid 81.180432 -149.81555)
					(end 81.884012 -149.81555)
				)
			)
		)
	)
	(zone
		(layers "B.Cu" "In11.Cu" "In13.Cu" "In15.Cu")
		(hatch none 0.5)
		(connect_pads
			(clearance 0)
		)
		(min_thickness 0.25)
		(keepout
			(tracks not_allowed)
			(vias allowed)
			(pads allowed)
			(copperpour not_allowed)
			(footprints allowed)
		)
		(placement
			(enabled no)
			(sheetname "")
		)
		(fill yes
			(thermal_gap 0.5)
			(thermal_bridge_width 0.5)
			(island_removal_mode 0)
		)
		(polygon
			(pts
				(arc
					(start 430.184052 -149.81555)
					(mid 429.480472 -149.81555)
					(end 430.184052 -149.81555)
				)
			)
		)
	)
	(zone
		(layers "B.Cu" "In11.Cu" "In13.Cu" "In15.Cu")
		(hatch none 0.5)
		(connect_pads
			(clearance 0)
		)
		(min_thickness 0.25)
		(keepout
			(tracks not_allowed)
			(vias allowed)
			(pads allowed)
			(copperpour not_allowed)
			(footprints allowed)
		)
		(placement
			(enabled no)
			(sheetname "")
		)
		(fill yes
			(thermal_gap 0.5)
			(thermal_bridge_width 0.5)
			(island_removal_mode 0)
		)
		(polygon
			(pts
				(arc
					(start 78.889606 -398.890236)
					(mid 78.130146 -398.890236)
					(end 78.889606 -398.890236)
				)
			)
		)
	)
	(zone
		(layers "B.Cu" "In11.Cu" "In13.Cu" "In15.Cu")
		(hatch none 0.5)
		(connect_pads
			(clearance 0)
		)
		(min_thickness 0.25)
		(keepout
			(tracks not_allowed)
			(vias allowed)
			(pads allowed)
			(copperpour not_allowed)
			(footprints allowed)
		)
		(placement
			(enabled no)
			(sheetname "")
		)
		(fill yes
			(thermal_gap 0.5)
			(thermal_bridge_width 0.5)
			(island_removal_mode 0)
		)
		(polygon
			(pts
				(arc
					(start 422.069514 -410.589984)
					(mid 421.310054 -410.589984)
					(end 422.069514 -410.589984)
				)
			)
		)
	)
	(zone
		(layers "B.Cu" "In11.Cu" "In13.Cu" "In15.Cu")
		(hatch none 0.5)
		(connect_pads
			(clearance 0)
		)
		(min_thickness 0.25)
		(keepout
			(tracks not_allowed)
			(vias allowed)
			(pads allowed)
			(copperpour not_allowed)
			(footprints allowed)
		)
		(placement
			(enabled no)
			(sheetname "")
		)
		(fill yes
			(thermal_gap 0.5)
			(thermal_bridge_width 0.5)
			(island_removal_mode 0)
		)
		(polygon
			(pts
				(arc
					(start 156.126434 -315.849762)
					(mid 155.473654 -315.849762)
					(end 156.126434 -315.849762)
				)
			)
		)
	)
	(zone
		(layers "B.Cu" "In11.Cu" "In13.Cu" "In15.Cu")
		(hatch none 0.5)
		(connect_pads
			(clearance 0)
		)
		(min_thickness 0.25)
		(keepout
			(tracks not_allowed)
			(vias allowed)
			(pads allowed)
			(copperpour not_allowed)
			(footprints allowed)
		)
		(placement
			(enabled no)
			(sheetname "")
		)
		(fill yes
			(thermal_gap 0.5)
			(thermal_bridge_width 0.5)
			(island_removal_mode 0)
		)
		(polygon
			(pts
				(arc
					(start 139.840462 -198.5264)
					(mid 139.136882 -198.5264)
					(end 139.840462 -198.5264)
				)
			)
		)
	)
	(zone
		(layers "B.Cu" "In11.Cu" "In13.Cu" "In15.Cu")
		(hatch none 0.5)
		(connect_pads
			(clearance 0)
		)
		(min_thickness 0.25)
		(keepout
			(tracks not_allowed)
			(vias allowed)
			(pads allowed)
			(copperpour not_allowed)
			(footprints allowed)
		)
		(placement
			(enabled no)
			(sheetname "")
		)
		(fill yes
			(thermal_gap 0.5)
			(thermal_bridge_width 0.5)
			(island_removal_mode 0)
		)
		(polygon
			(pts
				(arc
					(start 158.026354 -316.799722)
					(mid 157.373574 -316.799722)
					(end 158.026354 -316.799722)
				)
			)
		)
	)
	(zone
		(layers "B.Cu" "In11.Cu" "In13.Cu" "In15.Cu")
		(hatch none 0.5)
		(connect_pads
			(clearance 0)
		)
		(min_thickness 0.25)
		(keepout
			(tracks not_allowed)
			(vias allowed)
			(pads allowed)
			(copperpour not_allowed)
			(footprints allowed)
		)
		(placement
			(enabled no)
			(sheetname "")
		)
		(fill yes
			(thermal_gap 0.5)
			(thermal_bridge_width 0.5)
			(island_removal_mode 0)
		)
		(polygon
			(pts
				(arc
					(start 316.726062 -132.575808)
					(mid 316.022482 -132.575808)
					(end 316.726062 -132.575808)
				)
			)
		)
	)
	(zone
		(layers "B.Cu" "In11.Cu" "In13.Cu" "In15.Cu")
		(hatch none 0.5)
		(connect_pads
			(clearance 0)
		)
		(min_thickness 0.25)
		(keepout
			(tracks not_allowed)
			(vias allowed)
			(pads allowed)
			(copperpour not_allowed)
			(footprints allowed)
		)
		(placement
			(enabled no)
			(sheetname "")
		)
		(fill yes
			(thermal_gap 0.5)
			(thermal_bridge_width 0.5)
			(island_removal_mode 0)
		)
		(polygon
			(pts
				(arc
					(start 288.376106 -318.699896)
					(mid 287.723326 -318.699896)
					(end 288.376106 -318.699896)
				)
			)
		)
	)
	(zone
		(layers "B.Cu" "In11.Cu" "In13.Cu" "In15.Cu")
		(hatch none 0.5)
		(connect_pads
			(clearance 0)
		)
		(min_thickness 0.25)
		(keepout
			(tracks not_allowed)
			(vias allowed)
			(pads allowed)
			(copperpour not_allowed)
			(footprints allowed)
		)
		(placement
			(enabled no)
			(sheetname "")
		)
		(fill yes
			(thermal_gap 0.5)
			(thermal_bridge_width 0.5)
			(island_removal_mode 0)
		)
		(polygon
			(pts
				(arc
					(start 81.089754 -374.390158)
					(mid 80.330294 -374.390158)
					(end 81.089754 -374.390158)
				)
			)
		)
	)
	(zone
		(layers "B.Cu" "In11.Cu" "In13.Cu" "In15.Cu")
		(hatch none 0.5)
		(connect_pads
			(clearance 0)
		)
		(min_thickness 0.25)
		(keepout
			(tracks not_allowed)
			(vias allowed)
			(pads allowed)
			(copperpour not_allowed)
			(footprints allowed)
		)
		(placement
			(enabled no)
			(sheetname "")
		)
		(fill yes
			(thermal_gap 0.5)
			(thermal_bridge_width 0.5)
			(island_removal_mode 0)
		)
		(polygon
			(pts
				(arc
					(start 292.1762 -317.749936)
					(mid 291.52342 -317.749936)
					(end 292.1762 -317.749936)
				)
			)
		)
	)
	(zone
		(layers "B.Cu" "In11.Cu" "In13.Cu" "In15.Cu")
		(hatch none 0.5)
		(connect_pads
			(clearance 0)
		)
		(min_thickness 0.25)
		(keepout
			(tracks not_allowed)
			(vias allowed)
			(pads allowed)
			(copperpour not_allowed)
			(footprints allowed)
		)
		(placement
			(enabled no)
			(sheetname "")
		)
		(fill yes
			(thermal_gap 0.5)
			(thermal_bridge_width 0.5)
			(island_removal_mode 0)
		)
		(polygon
			(pts
				(arc
					(start 314.083954 -150.67915)
					(mid 313.380374 -150.67915)
					(end 314.083954 -150.67915)
				)
			)
		)
	)
	(zone
		(layers "B.Cu" "In11.Cu" "In13.Cu" "In15.Cu")
		(hatch none 0.5)
		(connect_pads
			(clearance 0)
		)
		(min_thickness 0.25)
		(keepout
			(tracks not_allowed)
			(vias allowed)
			(pads allowed)
			(copperpour not_allowed)
			(footprints allowed)
		)
		(placement
			(enabled no)
			(sheetname "")
		)
		(fill yes
			(thermal_gap 0.5)
			(thermal_bridge_width 0.5)
			(island_removal_mode 0)
		)
		(polygon
			(pts
				(arc
					(start 35.47745 -120.087898)
					(mid 34.77387 -120.087898)
					(end 35.47745 -120.087898)
				)
			)
		)
	)
	(zone
		(layers "B.Cu" "In11.Cu" "In13.Cu" "In15.Cu")
		(hatch none 0.5)
		(connect_pads
			(clearance 0)
		)
		(min_thickness 0.25)
		(keepout
			(tracks not_allowed)
			(vias allowed)
			(pads allowed)
			(copperpour not_allowed)
			(footprints allowed)
		)
		(placement
			(enabled no)
			(sheetname "")
		)
		(fill yes
			(thermal_gap 0.5)
			(thermal_bridge_width 0.5)
			(island_removal_mode 0)
		)
		(polygon
			(pts
				(arc
					(start 314.083954 -149.81555)
					(mid 313.380374 -149.81555)
					(end 314.083954 -149.81555)
				)
			)
		)
	)
	(zone
		(layers "B.Cu" "In11.Cu" "In13.Cu" "In15.Cu")
		(hatch none 0.5)
		(connect_pads
			(clearance 0)
		)
		(min_thickness 0.25)
		(keepout
			(tracks not_allowed)
			(vias allowed)
			(pads allowed)
			(copperpour not_allowed)
			(footprints allowed)
		)
		(placement
			(enabled no)
			(sheetname "")
		)
		(fill yes
			(thermal_gap 0.5)
			(thermal_bridge_width 0.5)
			(island_removal_mode 0)
		)
		(polygon
			(pts
				(arc
					(start 154.22626 -308.249828)
					(mid 153.57348 -308.249828)
					(end 154.22626 -308.249828)
				)
			)
		)
	)
	(zone
		(layers "B.Cu" "In11.Cu" "In13.Cu" "In15.Cu")
		(hatch none 0.5)
		(connect_pads
			(clearance 0)
		)
		(min_thickness 0.25)
		(keepout
			(tracks not_allowed)
			(vias allowed)
			(pads allowed)
			(copperpour not_allowed)
			(footprints allowed)
		)
		(placement
			(enabled no)
			(sheetname "")
		)
		(fill yes
			(thermal_gap 0.5)
			(thermal_bridge_width 0.5)
			(island_removal_mode 0)
		)
		(polygon
			(pts
				(arc
					(start 85.489542 -374.390158)
					(mid 84.730082 -374.390158)
					(end 85.489542 -374.390158)
				)
			)
		)
	)
	(zone
		(layers "B.Cu" "In11.Cu" "In13.Cu" "In15.Cu")
		(hatch none 0.5)
		(connect_pads
			(clearance 0)
		)
		(min_thickness 0.25)
		(keepout
			(tracks not_allowed)
			(vias allowed)
			(pads allowed)
			(copperpour not_allowed)
			(footprints allowed)
		)
		(placement
			(enabled no)
			(sheetname "")
		)
		(fill yes
			(thermal_gap 0.5)
			(thermal_bridge_width 0.5)
			(island_removal_mode 0)
		)
		(polygon
			(pts
				(arc
					(start 296.926254 -279.749504)
					(mid 296.273474 -279.749504)
					(end 296.926254 -279.749504)
				)
			)
		)
	)
	(zone
		(layers "B.Cu" "In11.Cu" "In13.Cu" "In15.Cu")
		(hatch none 0.5)
		(connect_pads
			(clearance 0)
		)
		(min_thickness 0.25)
		(keepout
			(tracks not_allowed)
			(vias allowed)
			(pads allowed)
			(copperpour not_allowed)
			(footprints allowed)
		)
		(placement
			(enabled no)
			(sheetname "")
		)
		(fill yes
			(thermal_gap 0.5)
			(thermal_bridge_width 0.5)
			(island_removal_mode 0)
		)
		(polygon
			(pts
				(arc
					(start 430.126394 -279.749758)
					(mid 429.473614 -279.749758)
					(end 430.126394 -279.749758)
				)
			)
		)
	)
	(zone
		(layers "B.Cu" "In11.Cu" "In13.Cu" "In15.Cu")
		(hatch none 0.5)
		(connect_pads
			(clearance 0)
		)
		(min_thickness 0.25)
		(keepout
			(tracks not_allowed)
			(vias allowed)
			(pads allowed)
			(copperpour not_allowed)
			(footprints allowed)
		)
		(placement
			(enabled no)
			(sheetname "")
		)
		(fill yes
			(thermal_gap 0.5)
			(thermal_bridge_width 0.5)
			(island_removal_mode 0)
		)
		(polygon
			(pts
				(arc
					(start 64.726312 -279.749504)
					(mid 64.073532 -279.749504)
					(end 64.726312 -279.749504)
				)
			)
		)
	)
	(zone
		(layers "B.Cu" "In11.Cu" "In13.Cu" "In15.Cu")
		(hatch none 0.5)
		(connect_pads
			(clearance 0)
		)
		(min_thickness 0.25)
		(keepout
			(tracks not_allowed)
			(vias allowed)
			(pads allowed)
			(copperpour not_allowed)
			(footprints allowed)
		)
		(placement
			(enabled no)
			(sheetname "")
		)
		(fill yes
			(thermal_gap 0.5)
			(thermal_bridge_width 0.5)
			(island_removal_mode 0)
		)
		(polygon
			(pts
				(arc
					(start 155.176474 -318.699896)
					(mid 154.523694 -318.699896)
					(end 155.176474 -318.699896)
				)
			)
		)
	)
	(zone
		(layers "B.Cu" "In11.Cu" "In13.Cu" "In15.Cu")
		(hatch none 0.5)
		(connect_pads
			(clearance 0)
		)
		(min_thickness 0.25)
		(keepout
			(tracks not_allowed)
			(vias allowed)
			(pads allowed)
			(copperpour not_allowed)
			(footprints allowed)
		)
		(placement
			(enabled no)
			(sheetname "")
		)
		(fill yes
			(thermal_gap 0.5)
			(thermal_bridge_width 0.5)
			(island_removal_mode 0)
		)
		(polygon
			(pts
				(arc
					(start 334.06969 -375.490232)
					(mid 333.31023 -375.490232)
					(end 334.06969 -375.490232)
				)
			)
		)
	)
	(zone
		(layers "B.Cu" "In11.Cu" "In13.Cu" "In15.Cu")
		(hatch none 0.5)
		(connect_pads
			(clearance 0)
		)
		(min_thickness 0.25)
		(keepout
			(tracks not_allowed)
			(vias allowed)
			(pads allowed)
			(copperpour not_allowed)
			(footprints allowed)
		)
		(placement
			(enabled no)
			(sheetname "")
		)
		(fill yes
			(thermal_gap 0.5)
			(thermal_bridge_width 0.5)
			(island_removal_mode 0)
		)
		(polygon
			(pts
				(arc
					(start 181.776116 -277.849838)
					(mid 181.123336 -277.849838)
					(end 181.776116 -277.849838)
				)
			)
		)
	)
	(zone
		(layers "B.Cu" "In11.Cu" "In13.Cu" "In15.Cu")
		(hatch none 0.5)
		(connect_pads
			(clearance 0)
		)
		(min_thickness 0.25)
		(keepout
			(tracks not_allowed)
			(vias allowed)
			(pads allowed)
			(copperpour not_allowed)
			(footprints allowed)
		)
		(placement
			(enabled no)
			(sheetname "")
		)
		(fill yes
			(thermal_gap 0.5)
			(thermal_bridge_width 0.5)
			(island_removal_mode 0)
		)
		(polygon
			(pts
				(arc
					(start 390.226296 -315.849762)
					(mid 389.573516 -315.849762)
					(end 390.226296 -315.849762)
				)
			)
		)
	)
	(zone
		(layers "B.Cu" "In11.Cu" "In13.Cu" "In15.Cu")
		(hatch none 0.5)
		(connect_pads
			(clearance 0)
		)
		(min_thickness 0.25)
		(keepout
			(tracks not_allowed)
			(vias allowed)
			(pads allowed)
			(copperpour not_allowed)
			(footprints allowed)
		)
		(placement
			(enabled no)
			(sheetname "")
		)
		(fill yes
			(thermal_gap 0.5)
			(thermal_bridge_width 0.5)
			(island_removal_mode 0)
		)
		(polygon
			(pts
				(arc
					(start 387.376416 -301.599854)
					(mid 386.723636 -301.599854)
					(end 387.376416 -301.599854)
				)
			)
		)
	)
	(zone
		(layers "B.Cu" "In11.Cu" "In13.Cu" "In15.Cu")
		(hatch none 0.5)
		(connect_pads
			(clearance 0)
		)
		(min_thickness 0.25)
		(keepout
			(tracks not_allowed)
			(vias allowed)
			(pads allowed)
			(copperpour not_allowed)
			(footprints allowed)
		)
		(placement
			(enabled no)
			(sheetname "")
		)
		(fill yes
			(thermal_gap 0.5)
			(thermal_bridge_width 0.5)
			(island_removal_mode 0)
		)
		(polygon
			(pts
				(arc
					(start 194.126358 -279.749504)
					(mid 193.473578 -279.749504)
					(end 194.126358 -279.749504)
				)
			)
		)
	)
	(zone
		(layers "B.Cu" "In11.Cu" "In13.Cu" "In15.Cu")
		(hatch none 0.5)
		(connect_pads
			(clearance 0)
		)
		(min_thickness 0.25)
		(keepout
			(tracks not_allowed)
			(vias allowed)
			(pads allowed)
			(copperpour not_allowed)
			(footprints allowed)
		)
		(placement
			(enabled no)
			(sheetname "")
		)
		(fill yes
			(thermal_gap 0.5)
			(thermal_bridge_width 0.5)
			(island_removal_mode 0)
		)
		(polygon
			(pts
				(arc
					(start 194.126358 -280.699718)
					(mid 193.473578 -280.699718)
					(end 194.126358 -280.699718)
				)
			)
		)
	)
	(zone
		(layers "B.Cu" "In11.Cu" "In13.Cu" "In15.Cu")
		(hatch none 0.5)
		(connect_pads
			(clearance 0)
		)
		(min_thickness 0.25)
		(keepout
			(tracks not_allowed)
			(vias allowed)
			(pads allowed)
			(copperpour not_allowed)
			(footprints allowed)
		)
		(placement
			(enabled no)
			(sheetname "")
		)
		(fill yes
			(thermal_gap 0.5)
			(thermal_bridge_width 0.5)
			(island_removal_mode 0)
		)
		(polygon
			(pts
				(arc
					(start 166.889684 -410.589984)
					(mid 166.130224 -410.589984)
					(end 166.889684 -410.589984)
				)
			)
		)
	)
	(zone
		(layers "B.Cu" "In11.Cu" "In13.Cu" "In15.Cu")
		(hatch none 0.5)
		(connect_pads
			(clearance 0)
		)
		(min_thickness 0.25)
		(keepout
			(tracks not_allowed)
			(vias allowed)
			(pads allowed)
			(copperpour not_allowed)
			(footprints allowed)
		)
		(placement
			(enabled no)
			(sheetname "")
		)
		(fill yes
			(thermal_gap 0.5)
			(thermal_bridge_width 0.5)
			(island_removal_mode 0)
		)
		(polygon
			(pts
				(arc
					(start 383.77749 -130.434334)
					(mid 383.07391 -130.434334)
					(end 383.77749 -130.434334)
				)
			)
		)
	)
	(zone
		(layers "B.Cu" "In11.Cu" "In13.Cu" "In15.Cu")
		(hatch none 0.5)
		(connect_pads
			(clearance 0)
		)
		(min_thickness 0.25)
		(keepout
			(tracks not_allowed)
			(vias allowed)
			(pads allowed)
			(copperpour not_allowed)
			(footprints allowed)
		)
		(placement
			(enabled no)
			(sheetname "")
		)
		(fill yes
			(thermal_gap 0.5)
			(thermal_bridge_width 0.5)
			(island_removal_mode 0)
		)
		(polygon
			(pts
				(arc
					(start 153.2763 -306.349908)
					(mid 152.62352 -306.349908)
					(end 153.2763 -306.349908)
				)
			)
		)
	)
	(zone
		(layers "B.Cu" "In11.Cu" "In13.Cu" "In15.Cu")
		(hatch none 0.5)
		(connect_pads
			(clearance 0)
		)
		(min_thickness 0.25)
		(keepout
			(tracks not_allowed)
			(vias allowed)
			(pads allowed)
			(copperpour not_allowed)
			(footprints allowed)
		)
		(placement
			(enabled no)
			(sheetname "")
		)
		(fill yes
			(thermal_gap 0.5)
			(thermal_bridge_width 0.5)
			(island_removal_mode 0)
		)
		(polygon
			(pts
				(arc
					(start 425.376086 -278.799798)
					(mid 424.723306 -278.799798)
					(end 425.376086 -278.799798)
				)
			)
		)
	)
	(zone
		(layers "B.Cu" "In11.Cu" "In13.Cu" "In15.Cu")
		(hatch none 0.5)
		(connect_pads
			(clearance 0)
		)
		(min_thickness 0.25)
		(keepout
			(tracks not_allowed)
			(vias allowed)
			(pads allowed)
			(copperpour not_allowed)
			(footprints allowed)
		)
		(placement
			(enabled no)
			(sheetname "")
		)
		(fill yes
			(thermal_gap 0.5)
			(thermal_bridge_width 0.5)
			(island_removal_mode 0)
		)
		(polygon
			(pts
				(arc
					(start 345.069668 -396.49019)
					(mid 344.310208 -396.49019)
					(end 345.069668 -396.49019)
				)
			)
		)
	)
	(zone
		(layers "B.Cu" "In11.Cu" "In13.Cu" "In15.Cu")
		(hatch none 0.5)
		(connect_pads
			(clearance 0)
		)
		(min_thickness 0.25)
		(keepout
			(tracks not_allowed)
			(vias allowed)
			(pads allowed)
			(copperpour not_allowed)
			(footprints allowed)
		)
		(placement
			(enabled no)
			(sheetname "")
		)
		(fill yes
			(thermal_gap 0.5)
			(thermal_bridge_width 0.5)
			(island_removal_mode 0)
		)
		(polygon
			(pts
				(arc
					(start 383.77749 -111.920782)
					(mid 383.07391 -111.920782)
					(end 383.77749 -111.920782)
				)
			)
		)
	)
	(zone
		(layers "B.Cu" "In11.Cu" "In13.Cu" "In15.Cu")
		(hatch none 0.5)
		(connect_pads
			(clearance 0)
		)
		(min_thickness 0.25)
		(keepout
			(tracks not_allowed)
			(vias allowed)
			(pads allowed)
			(copperpour not_allowed)
			(footprints allowed)
		)
		(placement
			(enabled no)
			(sheetname "")
		)
		(fill yes
			(thermal_gap 0.5)
			(thermal_bridge_width 0.5)
			(island_removal_mode 0)
		)
		(polygon
			(pts
				(arc
					(start 65.676272 -318.699896)
					(mid 65.023492 -318.699896)
					(end 65.676272 -318.699896)
				)
			)
		)
	)
	(zone
		(layers "B.Cu" "In11.Cu" "In13.Cu" "In15.Cu")
		(hatch none 0.5)
		(connect_pads
			(clearance 0)
		)
		(min_thickness 0.25)
		(keepout
			(tracks not_allowed)
			(vias allowed)
			(pads allowed)
			(copperpour not_allowed)
			(footprints allowed)
		)
		(placement
			(enabled no)
			(sheetname "")
		)
		(fill yes
			(thermal_gap 0.5)
			(thermal_bridge_width 0.5)
			(island_removal_mode 0)
		)
		(polygon
			(pts
				(arc
					(start 197.926452 -276.899878)
					(mid 197.273672 -276.899878)
					(end 197.926452 -276.899878)
				)
			)
		)
	)
	(zone
		(layers "B.Cu" "In11.Cu" "In13.Cu" "In15.Cu")
		(hatch none 0.5)
		(connect_pads
			(clearance 0)
		)
		(min_thickness 0.25)
		(keepout
			(tracks not_allowed)
			(vias allowed)
			(pads allowed)
			(copperpour not_allowed)
			(footprints allowed)
		)
		(placement
			(enabled no)
			(sheetname "")
		)
		(fill yes
			(thermal_gap 0.5)
			(thermal_bridge_width 0.5)
			(island_removal_mode 0)
		)
		(polygon
			(pts
				(arc
					(start 430.869598 -384.590036)
					(mid 430.110138 -384.590036)
					(end 430.869598 -384.590036)
				)
			)
		)
	)
	(zone
		(layers "B.Cu" "In11.Cu" "In13.Cu" "In15.Cu")
		(hatch none 0.5)
		(connect_pads
			(clearance 0)
		)
		(min_thickness 0.25)
		(keepout
			(tracks not_allowed)
			(vias allowed)
			(pads allowed)
			(copperpour not_allowed)
			(footprints allowed)
		)
		(placement
			(enabled no)
			(sheetname "")
		)
		(fill yes
			(thermal_gap 0.5)
			(thermal_bridge_width 0.5)
			(island_removal_mode 0)
		)
		(polygon
			(pts
				(arc
					(start 160.289748 -408.190192)
					(mid 159.530288 -408.190192)
					(end 160.289748 -408.190192)
				)
			)
		)
	)
	(zone
		(layers "B.Cu" "In11.Cu" "In13.Cu" "In15.Cu")
		(hatch none 0.5)
		(connect_pads
			(clearance 0)
		)
		(min_thickness 0.25)
		(keepout
			(tracks not_allowed)
			(vias allowed)
			(pads allowed)
			(copperpour not_allowed)
			(footprints allowed)
		)
		(placement
			(enabled no)
			(sheetname "")
		)
		(fill yes
			(thermal_gap 0.5)
			(thermal_bridge_width 0.5)
			(island_removal_mode 0)
		)
		(polygon
			(pts
				(arc
					(start 38.119558 -135.840724)
					(mid 37.415978 -135.840724)
					(end 38.119558 -135.840724)
				)
			)
		)
	)
	(zone
		(layers "B.Cu" "In11.Cu" "In13.Cu" "In15.Cu")
		(hatch none 0.5)
		(connect_pads
			(clearance 0)
		)
		(min_thickness 0.25)
		(keepout
			(tracks not_allowed)
			(vias allowed)
			(pads allowed)
			(copperpour not_allowed)
			(footprints allowed)
		)
		(placement
			(enabled no)
			(sheetname "")
		)
		(fill yes
			(thermal_gap 0.5)
			(thermal_bridge_width 0.5)
			(island_removal_mode 0)
		)
		(polygon
			(pts
				(arc
					(start 195.076064 -277.849838)
					(mid 194.423284 -277.849838)
					(end 195.076064 -277.849838)
				)
			)
		)
	)
	(zone
		(layers "B.Cu" "In11.Cu" "In13.Cu" "In15.Cu")
		(hatch none 0.5)
		(connect_pads
			(clearance 0)
		)
		(min_thickness 0.25)
		(keepout
			(tracks not_allowed)
			(vias allowed)
			(pads allowed)
			(copperpour not_allowed)
			(footprints allowed)
		)
		(placement
			(enabled no)
			(sheetname "")
		)
		(fill yes
			(thermal_gap 0.5)
			(thermal_bridge_width 0.5)
			(island_removal_mode 0)
		)
		(polygon
			(pts
				(arc
					(start 164.68979 -408.190192)
					(mid 163.93033 -408.190192)
					(end 164.68979 -408.190192)
				)
			)
		)
	)
	(zone
		(layers "B.Cu" "In11.Cu" "In13.Cu" "In15.Cu")
		(hatch none 0.5)
		(connect_pads
			(clearance 0)
		)
		(min_thickness 0.25)
		(keepout
			(tracks not_allowed)
			(vias allowed)
			(pads allowed)
			(copperpour not_allowed)
			(footprints allowed)
		)
		(placement
			(enabled no)
			(sheetname "")
		)
		(fill yes
			(thermal_gap 0.5)
			(thermal_bridge_width 0.5)
			(island_removal_mode 0)
		)
		(polygon
			(pts
				(arc
					(start 433.069492 -382.18999)
					(mid 432.310032 -382.18999)
					(end 433.069492 -382.18999)
				)
			)
		)
	)
	(zone
		(layers "B.Cu" "In11.Cu" "In13.Cu" "In15.Cu")
		(hatch none 0.5)
		(connect_pads
			(clearance 0)
		)
		(min_thickness 0.25)
		(keepout
			(tracks not_allowed)
			(vias allowed)
			(pads allowed)
			(copperpour not_allowed)
			(footprints allowed)
		)
		(placement
			(enabled no)
			(sheetname "")
		)
		(fill yes
			(thermal_gap 0.5)
			(thermal_bridge_width 0.5)
			(island_removal_mode 0)
		)
		(polygon
			(pts
				(arc
					(start 73.275952 -277.849838)
					(mid 72.623172 -277.849838)
					(end 73.275952 -277.849838)
				)
			)
		)
	)
	(zone
		(layers "B.Cu" "In11.Cu" "In13.Cu" "In15.Cu")
		(hatch none 0.5)
		(connect_pads
			(clearance 0)
		)
		(min_thickness 0.25)
		(keepout
			(tracks not_allowed)
			(vias allowed)
			(pads allowed)
			(copperpour not_allowed)
			(footprints allowed)
		)
		(placement
			(enabled no)
			(sheetname "")
		)
		(fill yes
			(thermal_gap 0.5)
			(thermal_bridge_width 0.5)
			(island_removal_mode 0)
		)
		(polygon
			(pts
				(arc
					(start 72.326246 -280.699718)
					(mid 71.673466 -280.699718)
					(end 72.326246 -280.699718)
				)
			)
		)
	)
	(zone
		(layers "B.Cu" "In11.Cu" "In13.Cu" "In15.Cu")
		(hatch none 0.5)
		(connect_pads
			(clearance 0)
		)
		(min_thickness 0.25)
		(keepout
			(tracks not_allowed)
			(vias allowed)
			(pads allowed)
			(copperpour not_allowed)
			(footprints allowed)
		)
		(placement
			(enabled no)
			(sheetname "")
		)
		(fill yes
			(thermal_gap 0.5)
			(thermal_bridge_width 0.5)
			(island_removal_mode 0)
		)
		(polygon
			(pts
				(arc
					(start 386.419598 -135.840724)
					(mid 385.716018 -135.840724)
					(end 386.419598 -135.840724)
				)
			)
		)
	)
	(zone
		(layers "B.Cu" "In11.Cu" "In13.Cu" "In15.Cu")
		(hatch none 0.5)
		(connect_pads
			(clearance 0)
		)
		(min_thickness 0.25)
		(keepout
			(tracks not_allowed)
			(vias allowed)
			(pads allowed)
			(copperpour not_allowed)
			(footprints allowed)
		)
		(placement
			(enabled no)
			(sheetname "")
		)
		(fill yes
			(thermal_gap 0.5)
			(thermal_bridge_width 0.5)
			(island_removal_mode 0)
		)
		(polygon
			(pts
				(arc
					(start 193.176398 -282.599892)
					(mid 192.523618 -282.599892)
					(end 193.176398 -282.599892)
				)
			)
		)
	)
	(zone
		(layers "B.Cu" "In11.Cu" "In13.Cu" "In15.Cu")
		(hatch none 0.5)
		(connect_pads
			(clearance 0)
		)
		(min_thickness 0.25)
		(keepout
			(tracks not_allowed)
			(vias allowed)
			(pads allowed)
			(copperpour not_allowed)
			(footprints allowed)
		)
		(placement
			(enabled no)
			(sheetname "")
		)
		(fill yes
			(thermal_gap 0.5)
			(thermal_bridge_width 0.5)
			(island_removal_mode 0)
		)
		(polygon
			(pts
				(arc
					(start 383.77749 -122.82424)
					(mid 383.07391 -122.82424)
					(end 383.77749 -122.82424)
				)
			)
		)
	)
	(zone
		(layers "B.Cu" "In11.Cu" "In13.Cu" "In15.Cu")
		(hatch none 0.5)
		(connect_pads
			(clearance 0)
		)
		(min_thickness 0.25)
		(keepout
			(tracks not_allowed)
			(vias allowed)
			(pads allowed)
			(copperpour not_allowed)
			(footprints allowed)
		)
		(placement
			(enabled no)
			(sheetname "")
		)
		(fill yes
			(thermal_gap 0.5)
			(thermal_bridge_width 0.5)
			(island_removal_mode 0)
		)
		(polygon
			(pts
				(arc
					(start 75.176126 -277.849838)
					(mid 74.523346 -277.849838)
					(end 75.176126 -277.849838)
				)
			)
		)
	)
	(zone
		(layers "B.Cu" "In11.Cu" "In13.Cu" "In15.Cu")
		(hatch none 0.5)
		(connect_pads
			(clearance 0)
		)
		(min_thickness 0.25)
		(keepout
			(tracks not_allowed)
			(vias allowed)
			(pads allowed)
			(copperpour not_allowed)
			(footprints allowed)
		)
		(placement
			(enabled no)
			(sheetname "")
		)
		(fill yes
			(thermal_gap 0.5)
			(thermal_bridge_width 0.5)
			(island_removal_mode 0)
		)
		(polygon
			(pts
				(arc
					(start 347.269816 -398.890236)
					(mid 346.510356 -398.890236)
					(end 347.269816 -398.890236)
				)
			)
		)
	)
	(zone
		(layers "B.Cu" "In11.Cu" "In13.Cu" "In15.Cu")
		(hatch none 0.5)
		(connect_pads
			(clearance 0)
		)
		(min_thickness 0.25)
		(keepout
			(tracks not_allowed)
			(vias allowed)
			(pads allowed)
			(copperpour not_allowed)
			(footprints allowed)
		)
		(placement
			(enabled no)
			(sheetname "")
		)
		(fill yes
			(thermal_gap 0.5)
			(thermal_bridge_width 0.5)
			(island_removal_mode 0)
		)
		(polygon
			(pts
				(arc
					(start 386.419598 -106.514138)
					(mid 385.716018 -106.514138)
					(end 386.419598 -106.514138)
				)
			)
		)
	)
	(zone
		(layers "B.Cu" "In11.Cu" "In13.Cu" "In15.Cu")
		(hatch none 0.5)
		(connect_pads
			(clearance 0)
		)
		(min_thickness 0.25)
		(keepout
			(tracks not_allowed)
			(vias allowed)
			(pads allowed)
			(copperpour not_allowed)
			(footprints allowed)
		)
		(placement
			(enabled no)
			(sheetname "")
		)
		(fill yes
			(thermal_gap 0.5)
			(thermal_bridge_width 0.5)
			(island_removal_mode 0)
		)
		(polygon
			(pts
				(arc
					(start 387.376416 -317.749936)
					(mid 386.723636 -317.749936)
					(end 387.376416 -317.749936)
				)
			)
		)
	)
	(zone
		(layers "B.Cu" "In11.Cu" "In13.Cu" "In15.Cu")
		(hatch none 0.5)
		(connect_pads
			(clearance 0)
		)
		(min_thickness 0.25)
		(keepout
			(tracks not_allowed)
			(vias allowed)
			(pads allowed)
			(copperpour not_allowed)
			(footprints allowed)
		)
		(placement
			(enabled no)
			(sheetname "")
		)
		(fill yes
			(thermal_gap 0.5)
			(thermal_bridge_width 0.5)
			(island_removal_mode 0)
		)
		(polygon
			(pts
				(arc
					(start 428.669704 -409.490164)
					(mid 427.910244 -409.490164)
					(end 428.669704 -409.490164)
				)
			)
		)
	)
	(zone
		(layers "B.Cu" "In11.Cu" "In13.Cu" "In15.Cu")
		(hatch none 0.5)
		(connect_pads
			(clearance 0)
		)
		(min_thickness 0.25)
		(keepout
			(tracks not_allowed)
			(vias allowed)
			(pads allowed)
			(copperpour not_allowed)
			(footprints allowed)
		)
		(placement
			(enabled no)
			(sheetname "")
		)
		(fill yes
			(thermal_gap 0.5)
			(thermal_bridge_width 0.5)
			(island_removal_mode 0)
		)
		(polygon
			(pts
				(arc
					(start 154.22626 -306.349908)
					(mid 153.57348 -306.349908)
					(end 154.22626 -306.349908)
				)
			)
		)
	)
	(zone
		(layers "B.Cu" "In11.Cu" "In13.Cu" "In15.Cu")
		(hatch none 0.5)
		(connect_pads
			(clearance 0)
		)
		(min_thickness 0.25)
		(keepout
			(tracks not_allowed)
			(vias allowed)
			(pads allowed)
			(copperpour not_allowed)
			(footprints allowed)
		)
		(placement
			(enabled no)
			(sheetname "")
		)
		(fill yes
			(thermal_gap 0.5)
			(thermal_bridge_width 0.5)
			(island_removal_mode 0)
		)
		(polygon
			(pts
				(arc
					(start 55.226204 -315.849762)
					(mid 54.573424 -315.849762)
					(end 55.226204 -315.849762)
				)
			)
		)
	)
	(zone
		(layers "B.Cu" "In11.Cu" "In13.Cu" "In15.Cu")
		(hatch none 0.5)
		(connect_pads
			(clearance 0)
		)
		(min_thickness 0.25)
		(keepout
			(tracks not_allowed)
			(vias allowed)
			(pads allowed)
			(copperpour not_allowed)
			(footprints allowed)
		)
		(placement
			(enabled no)
			(sheetname "")
		)
		(fill yes
			(thermal_gap 0.5)
			(thermal_bridge_width 0.5)
			(island_removal_mode 0)
		)
		(polygon
			(pts
				(arc
					(start 74.226166 -279.749504)
					(mid 73.573386 -279.749504)
					(end 74.226166 -279.749504)
				)
			)
		)
	)
	(zone
		(layers "B.Cu" "In11.Cu" "In13.Cu" "In15.Cu")
		(hatch none 0.5)
		(connect_pads
			(clearance 0)
		)
		(min_thickness 0.25)
		(keepout
			(tracks not_allowed)
			(vias allowed)
			(pads allowed)
			(copperpour not_allowed)
			(footprints allowed)
		)
		(placement
			(enabled no)
			(sheetname "")
		)
		(fill yes
			(thermal_gap 0.5)
			(thermal_bridge_width 0.5)
			(island_removal_mode 0)
		)
		(polygon
			(pts
				(arc
					(start 78.02626 -288.299906)
					(mid 77.37348 -288.299906)
					(end 78.02626 -288.299906)
				)
			)
		)
	)
	(zone
		(layers "B.Cu" "In11.Cu" "In13.Cu" "In15.Cu")
		(hatch none 0.5)
		(connect_pads
			(clearance 0)
		)
		(min_thickness 0.25)
		(keepout
			(tracks not_allowed)
			(vias allowed)
			(pads allowed)
			(copperpour not_allowed)
			(footprints allowed)
		)
		(placement
			(enabled no)
			(sheetname "")
		)
		(fill yes
			(thermal_gap 0.5)
			(thermal_bridge_width 0.5)
			(island_removal_mode 0)
		)
		(polygon
			(pts
				(arc
					(start 35.47745 -122.82424)
					(mid 34.77387 -122.82424)
					(end 35.47745 -122.82424)
				)
			)
		)
	)
	(zone
		(layers "B.Cu" "In11.Cu" "In13.Cu" "In15.Cu")
		(hatch none 0.5)
		(connect_pads
			(clearance 0)
		)
		(min_thickness 0.25)
		(keepout
			(tracks not_allowed)
			(vias allowed)
			(pads allowed)
			(copperpour not_allowed)
			(footprints allowed)
		)
		(placement
			(enabled no)
			(sheetname "")
		)
		(fill yes
			(thermal_gap 0.5)
			(thermal_bridge_width 0.5)
			(island_removal_mode 0)
		)
		(polygon
			(pts
				(arc
					(start 342.869774 -376.790204)
					(mid 342.110314 -376.790204)
					(end 342.869774 -376.790204)
				)
			)
		)
	)
	(zone
		(layers "B.Cu" "In11.Cu" "In13.Cu" "In15.Cu")
		(hatch none 0.5)
		(connect_pads
			(clearance 0)
		)
		(min_thickness 0.25)
		(keepout
			(tracks not_allowed)
			(vias allowed)
			(pads allowed)
			(copperpour not_allowed)
			(footprints allowed)
		)
		(placement
			(enabled no)
			(sheetname "")
		)
		(fill yes
			(thermal_gap 0.5)
			(thermal_bridge_width 0.5)
			(island_removal_mode 0)
		)
		(polygon
			(pts
				(arc
					(start 60.926218 -316.799722)
					(mid 60.273438 -316.799722)
					(end 60.926218 -316.799722)
				)
			)
		)
	)
	(zone
		(layers "B.Cu" "In11.Cu" "In13.Cu" "In15.Cu")
		(hatch none 0.5)
		(connect_pads
			(clearance 0)
		)
		(min_thickness 0.25)
		(keepout
			(tracks not_allowed)
			(vias allowed)
			(pads allowed)
			(copperpour not_allowed)
			(footprints allowed)
		)
		(placement
			(enabled no)
			(sheetname "")
		)
		(fill yes
			(thermal_gap 0.5)
			(thermal_bridge_width 0.5)
			(island_removal_mode 0)
		)
		(polygon
			(pts
				(arc
					(start 75.176126 -283.549852)
					(mid 74.523346 -283.549852)
					(end 75.176126 -283.549852)
				)
			)
		)
	)
	(zone
		(layers "B.Cu" "In11.Cu" "In13.Cu" "In15.Cu")
		(hatch none 0.5)
		(connect_pads
			(clearance 0)
		)
		(min_thickness 0.25)
		(keepout
			(tracks not_allowed)
			(vias allowed)
			(pads allowed)
			(copperpour not_allowed)
			(footprints allowed)
		)
		(placement
			(enabled no)
			(sheetname "")
		)
		(fill yes
			(thermal_gap 0.5)
			(thermal_bridge_width 0.5)
			(island_removal_mode 0)
		)
		(polygon
			(pts
				(arc
					(start 35.47745 -134.897876)
					(mid 34.77387 -134.897876)
					(end 35.47745 -134.897876)
				)
			)
		)
	)
	(zone
		(layers "B.Cu" "In11.Cu" "In13.Cu" "In15.Cu")
		(hatch none 0.5)
		(connect_pads
			(clearance 0)
		)
		(min_thickness 0.25)
		(keepout
			(tracks not_allowed)
			(vias allowed)
			(pads allowed)
			(copperpour not_allowed)
			(footprints allowed)
		)
		(placement
			(enabled no)
			(sheetname "")
		)
		(fill yes
			(thermal_gap 0.5)
			(thermal_bridge_width 0.5)
			(island_removal_mode 0)
		)
		(polygon
			(pts
				(arc
					(start 310.226202 -282.599892)
					(mid 309.573422 -282.599892)
					(end 310.226202 -282.599892)
				)
			)
		)
	)
	(zone
		(layers "B.Cu" "In11.Cu" "In13.Cu" "In15.Cu")
		(hatch none 0.5)
		(connect_pads
			(clearance 0)
		)
		(min_thickness 0.25)
		(keepout
			(tracks not_allowed)
			(vias allowed)
			(pads allowed)
			(copperpour not_allowed)
			(footprints allowed)
		)
		(placement
			(enabled no)
			(sheetname "")
		)
		(fill yes
			(thermal_gap 0.5)
			(thermal_bridge_width 0.5)
			(island_removal_mode 0)
		)
		(polygon
			(pts
				(arc
					(start 64.726312 -316.799722)
					(mid 64.073532 -316.799722)
					(end 64.726312 -316.799722)
				)
			)
		)
	)
	(zone
		(layers "B.Cu" "In11.Cu" "In13.Cu" "In15.Cu")
		(hatch none 0.5)
		(connect_pads
			(clearance 0)
		)
		(min_thickness 0.25)
		(keepout
			(tracks not_allowed)
			(vias allowed)
			(pads allowed)
			(copperpour not_allowed)
			(footprints allowed)
		)
		(placement
			(enabled no)
			(sheetname "")
		)
		(fill yes
			(thermal_gap 0.5)
			(thermal_bridge_width 0.5)
			(island_removal_mode 0)
		)
		(polygon
			(pts
				(arc
					(start 292.1762 -318.699896)
					(mid 291.52342 -318.699896)
					(end 292.1762 -318.699896)
				)
			)
		)
	)
	(zone
		(layers "B.Cu" "In11.Cu" "In13.Cu" "In15.Cu")
		(hatch none 0.5)
		(connect_pads
			(clearance 0)
		)
		(min_thickness 0.25)
		(keepout
			(tracks not_allowed)
			(vias allowed)
			(pads allowed)
			(copperpour not_allowed)
			(footprints allowed)
		)
		(placement
			(enabled no)
			(sheetname "")
		)
		(fill yes
			(thermal_gap 0.5)
			(thermal_bridge_width 0.5)
			(island_removal_mode 0)
		)
		(polygon
			(pts
				(arc
					(start 186.526424 -280.699718)
					(mid 185.873644 -280.699718)
					(end 186.526424 -280.699718)
				)
			)
		)
	)
	(zone
		(layers "B.Cu" "In11.Cu" "In13.Cu" "In15.Cu")
		(hatch none 0.5)
		(connect_pads
			(clearance 0)
		)
		(min_thickness 0.25)
		(keepout
			(tracks not_allowed)
			(vias allowed)
			(pads allowed)
			(copperpour not_allowed)
			(footprints allowed)
		)
		(placement
			(enabled no)
			(sheetname "")
		)
		(fill yes
			(thermal_gap 0.5)
			(thermal_bridge_width 0.5)
			(island_removal_mode 0)
		)
		(polygon
			(pts
				(arc
					(start 294.07612 -317.749936)
					(mid 293.42334 -317.749936)
					(end 294.07612 -317.749936)
				)
			)
		)
	)
	(zone
		(layers "B.Cu" "In11.Cu" "In13.Cu" "In15.Cu")
		(hatch none 0.5)
		(connect_pads
			(clearance 0)
		)
		(min_thickness 0.25)
		(keepout
			(tracks not_allowed)
			(vias allowed)
			(pads allowed)
			(copperpour not_allowed)
			(footprints allowed)
		)
		(placement
			(enabled no)
			(sheetname "")
		)
		(fill yes
			(thermal_gap 0.5)
			(thermal_bridge_width 0.5)
			(island_removal_mode 0)
		)
		(polygon
			(pts
				(arc
					(start 74.489564 -397.59001)
					(mid 73.730104 -397.59001)
					(end 74.489564 -397.59001)
				)
			)
		)
	)
	(zone
		(layers "B.Cu" "In11.Cu" "In13.Cu" "In15.Cu")
		(hatch none 0.5)
		(connect_pads
			(clearance 0)
		)
		(min_thickness 0.25)
		(keepout
			(tracks not_allowed)
			(vias allowed)
			(pads allowed)
			(copperpour not_allowed)
			(footprints allowed)
		)
		(placement
			(enabled no)
			(sheetname "")
		)
		(fill yes
			(thermal_gap 0.5)
			(thermal_bridge_width 0.5)
			(island_removal_mode 0)
		)
		(polygon
			(pts
				(arc
					(start 197.983856 -142.615666)
					(mid 197.280276 -142.615666)
					(end 197.983856 -142.615666)
				)
			)
		)
	)
	(zone
		(layers "B.Cu" "In11.Cu" "In13.Cu" "In15.Cu")
		(hatch none 0.5)
		(connect_pads
			(clearance 0)
		)
		(min_thickness 0.25)
		(keepout
			(tracks not_allowed)
			(vias allowed)
			(pads allowed)
			(copperpour not_allowed)
			(footprints allowed)
		)
		(placement
			(enabled no)
			(sheetname "")
		)
		(fill yes
			(thermal_gap 0.5)
			(thermal_bridge_width 0.5)
			(island_removal_mode 0)
		)
		(polygon
			(pts
				(arc
					(start 81.089754 -397.790162)
					(mid 80.330294 -397.790162)
					(end 81.089754 -397.790162)
				)
			)
		)
	)
	(zone
		(layers "B.Cu" "In11.Cu" "In13.Cu" "In15.Cu")
		(hatch none 0.5)
		(connect_pads
			(clearance 0)
		)
		(min_thickness 0.25)
		(keepout
			(tracks not_allowed)
			(vias allowed)
			(pads allowed)
			(copperpour not_allowed)
			(footprints allowed)
		)
		(placement
			(enabled no)
			(sheetname "")
		)
		(fill yes
			(thermal_gap 0.5)
			(thermal_bridge_width 0.5)
			(island_removal_mode 0)
		)
		(polygon
			(pts
				(arc
					(start 342.869774 -398.890236)
					(mid 342.110314 -398.890236)
					(end 342.869774 -398.890236)
				)
			)
		)
	)
	(zone
		(layers "B.Cu" "In11.Cu" "In13.Cu" "In15.Cu")
		(hatch none 0.5)
		(connect_pads
			(clearance 0)
		)
		(min_thickness 0.25)
		(keepout
			(tracks not_allowed)
			(vias allowed)
			(pads allowed)
			(copperpour not_allowed)
			(footprints allowed)
		)
		(placement
			(enabled no)
			(sheetname "")
		)
		(fill yes
			(thermal_gap 0.5)
			(thermal_bridge_width 0.5)
			(island_removal_mode 0)
		)
		(polygon
			(pts
				(arc
					(start 338.469732 -398.890236)
					(mid 337.710272 -398.890236)
					(end 338.469732 -398.890236)
				)
			)
		)
	)
	(zone
		(layers "B.Cu" "In11.Cu" "In13.Cu" "In15.Cu")
		(hatch none 0.5)
		(connect_pads
			(clearance 0)
		)
		(min_thickness 0.25)
		(keepout
			(tracks not_allowed)
			(vias allowed)
			(pads allowed)
			(copperpour not_allowed)
			(footprints allowed)
		)
		(placement
			(enabled no)
			(sheetname "")
		)
		(fill yes
			(thermal_gap 0.5)
			(thermal_bridge_width 0.5)
			(island_removal_mode 0)
		)
		(polygon
			(pts
				(arc
					(start 200.625964 -151.622252)
					(mid 199.922384 -151.622252)
					(end 200.625964 -151.622252)
				)
			)
		)
	)
	(zone
		(layers "B.Cu" "In11.Cu" "In13.Cu" "In15.Cu")
		(hatch none 0.5)
		(connect_pads
			(clearance 0)
		)
		(min_thickness 0.25)
		(keepout
			(tracks not_allowed)
			(vias allowed)
			(pads allowed)
			(copperpour not_allowed)
			(footprints allowed)
		)
		(placement
			(enabled no)
			(sheetname "")
		)
		(fill yes
			(thermal_gap 0.5)
			(thermal_bridge_width 0.5)
			(island_removal_mode 0)
		)
		(polygon
			(pts
				(arc
					(start 169.089832 -382.18999)
					(mid 168.330372 -382.18999)
					(end 169.089832 -382.18999)
				)
			)
		)
	)
	(zone
		(layers "B.Cu" "In11.Cu" "In13.Cu" "In15.Cu")
		(hatch none 0.5)
		(connect_pads
			(clearance 0)
		)
		(min_thickness 0.25)
		(keepout
			(tracks not_allowed)
			(vias allowed)
			(pads allowed)
			(copperpour not_allowed)
			(footprints allowed)
		)
		(placement
			(enabled no)
			(sheetname "")
		)
		(fill yes
			(thermal_gap 0.5)
			(thermal_bridge_width 0.5)
			(island_removal_mode 0)
		)
		(polygon
			(pts
				(arc
					(start 457.999084 8.607552)
					(mid 457.295504 8.607552)
					(end 457.999084 8.607552)
				)
			)
		)
	)
	(zone
		(layers "B.Cu" "In11.Cu" "In13.Cu" "In15.Cu")
		(hatch none 0.5)
		(connect_pads
			(clearance 0)
		)
		(min_thickness 0.25)
		(keepout
			(tracks not_allowed)
			(vias allowed)
			(pads allowed)
			(copperpour not_allowed)
			(footprints allowed)
		)
		(placement
			(enabled no)
			(sheetname "")
		)
		(fill yes
			(thermal_gap 0.5)
			(thermal_bridge_width 0.5)
			(island_removal_mode 0)
		)
		(polygon
			(pts
				(arc
					(start 151.577294 -108.32084)
					(mid 150.873714 -108.32084)
					(end 151.577294 -108.32084)
				)
			)
		)
	)
	(zone
		(layers "B.Cu" "In11.Cu" "In13.Cu" "In15.Cu")
		(hatch none 0.5)
		(connect_pads
			(clearance 0)
		)
		(min_thickness 0.25)
		(keepout
			(tracks not_allowed)
			(vias allowed)
			(pads allowed)
			(copperpour not_allowed)
			(footprints allowed)
		)
		(placement
			(enabled no)
			(sheetname "")
		)
		(fill yes
			(thermal_gap 0.5)
			(thermal_bridge_width 0.5)
			(island_removal_mode 0)
		)
		(polygon
			(pts
				(arc
					(start 383.77749 -134.034276)
					(mid 383.07391 -134.034276)
					(end 383.77749 -134.034276)
				)
			)
		)
	)
	(zone
		(layers "B.Cu" "In11.Cu" "In13.Cu" "In15.Cu")
		(hatch none 0.5)
		(connect_pads
			(clearance 0)
		)
		(min_thickness 0.25)
		(keepout
			(tracks not_allowed)
			(vias allowed)
			(pads allowed)
			(copperpour not_allowed)
			(footprints allowed)
		)
		(placement
			(enabled no)
			(sheetname "")
		)
		(fill yes
			(thermal_gap 0.5)
			(thermal_bridge_width 0.5)
			(island_removal_mode 0)
		)
		(polygon
			(pts
				(arc
					(start 340.66988 -397.790162)
					(mid 339.91042 -397.790162)
					(end 340.66988 -397.790162)
				)
			)
		)
	)
	(zone
		(layers "B.Cu" "In11.Cu" "In13.Cu" "In15.Cu")
		(hatch none 0.5)
		(connect_pads
			(clearance 0)
		)
		(min_thickness 0.25)
		(keepout
			(tracks not_allowed)
			(vias allowed)
			(pads allowed)
			(copperpour not_allowed)
			(footprints allowed)
		)
		(placement
			(enabled no)
			(sheetname "")
		)
		(fill yes
			(thermal_gap 0.5)
			(thermal_bridge_width 0.5)
			(island_removal_mode 0)
		)
		(polygon
			(pts
				(arc
					(start 430.184052 -129.905506)
					(mid 429.480472 -129.905506)
					(end 430.184052 -129.905506)
				)
			)
		)
	)
	(zone
		(layers "B.Cu" "In11.Cu" "In13.Cu" "In15.Cu")
		(hatch none 0.5)
		(connect_pads
			(clearance 0)
		)
		(min_thickness 0.25)
		(keepout
			(tracks not_allowed)
			(vias allowed)
			(pads allowed)
			(copperpour not_allowed)
			(footprints allowed)
		)
		(placement
			(enabled no)
			(sheetname "")
		)
		(fill yes
			(thermal_gap 0.5)
			(thermal_bridge_width 0.5)
			(island_removal_mode 0)
		)
		(polygon
			(pts
				(arc
					(start 177.026316 -279.749504)
					(mid 176.373536 -279.749504)
					(end 177.026316 -279.749504)
				)
			)
		)
	)
	(zone
		(layers "B.Cu" "In11.Cu" "In13.Cu" "In15.Cu")
		(hatch none 0.5)
		(connect_pads
			(clearance 0)
		)
		(min_thickness 0.25)
		(keepout
			(tracks not_allowed)
			(vias allowed)
			(pads allowed)
			(copperpour not_allowed)
			(footprints allowed)
		)
		(placement
			(enabled no)
			(sheetname "")
		)
		(fill yes
			(thermal_gap 0.5)
			(thermal_bridge_width 0.5)
			(island_removal_mode 0)
		)
		(polygon
			(pts
				(arc
					(start 430.869598 -409.290012)
					(mid 430.110138 -409.290012)
					(end 430.869598 -409.290012)
				)
			)
		)
	)
	(zone
		(layers "B.Cu" "In11.Cu" "In13.Cu" "In15.Cu")
		(hatch none 0.5)
		(connect_pads
			(clearance 0)
		)
		(min_thickness 0.25)
		(keepout
			(tracks not_allowed)
			(vias allowed)
			(pads allowed)
			(copperpour not_allowed)
			(footprints allowed)
		)
		(placement
			(enabled no)
			(sheetname "")
		)
		(fill yes
			(thermal_gap 0.5)
			(thermal_bridge_width 0.5)
			(island_removal_mode 0)
		)
		(polygon
			(pts
				(arc
					(start 299.77588 -278.799798)
					(mid 299.1231 -278.799798)
					(end 299.77588 -278.799798)
				)
			)
		)
	)
	(zone
		(layers "B.Cu" "In11.Cu" "In13.Cu" "In15.Cu")
		(hatch none 0.5)
		(connect_pads
			(clearance 0)
		)
		(min_thickness 0.25)
		(keepout
			(tracks not_allowed)
			(vias allowed)
			(pads allowed)
			(copperpour not_allowed)
			(footprints allowed)
		)
		(placement
			(enabled no)
			(sheetname "")
		)
		(fill yes
			(thermal_gap 0.5)
			(thermal_bridge_width 0.5)
			(island_removal_mode 0)
		)
		(polygon
			(pts
				(arc
					(start 430.184052 -142.615666)
					(mid 429.480472 -142.615666)
					(end 430.184052 -142.615666)
				)
			)
		)
	)
	(zone
		(layers "B.Cu" "In11.Cu" "In13.Cu" "In15.Cu")
		(hatch none 0.5)
		(connect_pads
			(clearance 0)
		)
		(min_thickness 0.25)
		(keepout
			(tracks not_allowed)
			(vias allowed)
			(pads allowed)
			(copperpour not_allowed)
			(footprints allowed)
		)
		(placement
			(enabled no)
			(sheetname "")
		)
		(fill yes
			(thermal_gap 0.5)
			(thermal_bridge_width 0.5)
			(island_removal_mode 0)
		)
		(polygon
			(pts
				(arc
					(start 347.269816 -376.790204)
					(mid 346.510356 -376.790204)
					(end 347.269816 -376.790204)
				)
			)
		)
	)
	(zone
		(layers "B.Cu" "In11.Cu" "In13.Cu" "In15.Cu")
		(hatch none 0.5)
		(connect_pads
			(clearance 0)
		)
		(min_thickness 0.25)
		(keepout
			(tracks not_allowed)
			(vias allowed)
			(pads allowed)
			(copperpour not_allowed)
			(footprints allowed)
		)
		(placement
			(enabled no)
			(sheetname "")
		)
		(fill yes
			(thermal_gap 0.5)
			(thermal_bridge_width 0.5)
			(island_removal_mode 0)
		)
		(polygon
			(pts
				(arc
					(start 296.926254 -316.799722)
					(mid 296.273474 -316.799722)
					(end 296.926254 -316.799722)
				)
			)
		)
	)
	(zone
		(layers "B.Cu" "In11.Cu" "In13.Cu" "In15.Cu")
		(hatch none 0.5)
		(connect_pads
			(clearance 0)
		)
		(min_thickness 0.25)
		(keepout
			(tracks not_allowed)
			(vias allowed)
			(pads allowed)
			(copperpour not_allowed)
			(footprints allowed)
		)
		(placement
			(enabled no)
			(sheetname "")
		)
		(fill yes
			(thermal_gap 0.5)
			(thermal_bridge_width 0.5)
			(island_removal_mode 0)
		)
		(polygon
			(pts
				(arc
					(start 162.489642 -409.290012)
					(mid 161.730182 -409.290012)
					(end 162.489642 -409.290012)
				)
			)
		)
	)
	(zone
		(layers "B.Cu" "In11.Cu" "In13.Cu" "In15.Cu")
		(hatch none 0.5)
		(connect_pads
			(clearance 0)
		)
		(min_thickness 0.25)
		(keepout
			(tracks not_allowed)
			(vias allowed)
			(pads allowed)
			(copperpour not_allowed)
			(footprints allowed)
		)
		(placement
			(enabled no)
			(sheetname "")
		)
		(fill yes
			(thermal_gap 0.5)
			(thermal_bridge_width 0.5)
			(island_removal_mode 0)
		)
		(polygon
			(pts
				(arc
					(start 316.726062 -136.17575)
					(mid 316.022482 -136.17575)
					(end 316.726062 -136.17575)
				)
			)
		)
	)
	(zone
		(layers "B.Cu" "In11.Cu" "In13.Cu" "In15.Cu")
		(hatch none 0.5)
		(connect_pads
			(clearance 0)
		)
		(min_thickness 0.25)
		(keepout
			(tracks not_allowed)
			(vias allowed)
			(pads allowed)
			(copperpour not_allowed)
			(footprints allowed)
		)
		(placement
			(enabled no)
			(sheetname "")
		)
		(fill yes
			(thermal_gap 0.5)
			(thermal_bridge_width 0.5)
			(island_removal_mode 0)
		)
		(polygon
			(pts
				(arc
					(start 77.076046 -277.849838)
					(mid 76.423266 -277.849838)
					(end 77.076046 -277.849838)
				)
			)
		)
	)
	(zone
		(layers "B.Cu" "In11.Cu" "In13.Cu" "In15.Cu")
		(hatch none 0.5)
		(connect_pads
			(clearance 0)
		)
		(min_thickness 0.25)
		(keepout
			(tracks not_allowed)
			(vias allowed)
			(pads allowed)
			(copperpour not_allowed)
			(footprints allowed)
		)
		(placement
			(enabled no)
			(sheetname "")
		)
		(fill yes
			(thermal_gap 0.5)
			(thermal_bridge_width 0.5)
			(island_removal_mode 0)
		)
		(polygon
			(pts
				(arc
					(start 238.941864 -82.307176)
					(mid 238.238284 -82.307176)
					(end 238.941864 -82.307176)
				)
			)
		)
	)
	(zone
		(layers "B.Cu" "In11.Cu" "In13.Cu" "In15.Cu")
		(hatch none 0.5)
		(connect_pads
			(clearance 0)
		)
		(min_thickness 0.25)
		(keepout
			(tracks not_allowed)
			(vias allowed)
			(pads allowed)
			(copperpour not_allowed)
			(footprints allowed)
		)
		(placement
			(enabled no)
			(sheetname "")
		)
		(fill yes
			(thermal_gap 0.5)
			(thermal_bridge_width 0.5)
			(island_removal_mode 0)
		)
		(polygon
			(pts
				(arc
					(start 84.52612 -136.17575)
					(mid 83.82254 -136.17575)
					(end 84.52612 -136.17575)
				)
			)
		)
	)
	(zone
		(layers "B.Cu" "In11.Cu" "In13.Cu" "In15.Cu")
		(hatch none 0.5)
		(connect_pads
			(clearance 0)
		)
		(min_thickness 0.25)
		(keepout
			(tracks not_allowed)
			(vias allowed)
			(pads allowed)
			(copperpour not_allowed)
			(footprints allowed)
		)
		(placement
			(enabled no)
			(sheetname "")
		)
		(fill yes
			(thermal_gap 0.5)
			(thermal_bridge_width 0.5)
			(island_removal_mode 0)
		)
		(polygon
			(pts
				(arc
					(start 435.26964 -410.589984)
					(mid 434.51018 -410.589984)
					(end 435.26964 -410.589984)
				)
			)
		)
	)
	(zone
		(layers "B.Cu" "In11.Cu" "In13.Cu" "In15.Cu")
		(hatch none 0.5)
		(connect_pads
			(clearance 0)
		)
		(min_thickness 0.25)
		(keepout
			(tracks not_allowed)
			(vias allowed)
			(pads allowed)
			(copperpour not_allowed)
			(footprints allowed)
		)
		(placement
			(enabled no)
			(sheetname "")
		)
		(fill yes
			(thermal_gap 0.5)
			(thermal_bridge_width 0.5)
			(island_removal_mode 0)
		)
		(polygon
			(pts
				(arc
					(start 427.276006 -277.849838)
					(mid 426.623226 -277.849838)
					(end 427.276006 -277.849838)
				)
			)
		)
	)
	(zone
		(layers "B.Cu" "In11.Cu" "In13.Cu" "In15.Cu")
		(hatch none 0.5)
		(connect_pads
			(clearance 0)
		)
		(min_thickness 0.25)
		(keepout
			(tracks not_allowed)
			(vias allowed)
			(pads allowed)
			(copperpour not_allowed)
			(footprints allowed)
		)
		(placement
			(enabled no)
			(sheetname "")
		)
		(fill yes
			(thermal_gap 0.5)
			(thermal_bridge_width 0.5)
			(island_removal_mode 0)
		)
		(polygon
			(pts
				(arc
					(start 270.3195 -110.977934)
					(mid 269.61592 -110.977934)
					(end 270.3195 -110.977934)
				)
			)
		)
	)
	(zone
		(layers "B.Cu" "In11.Cu" "In13.Cu" "In15.Cu")
		(hatch none 0.5)
		(connect_pads
			(clearance 0)
		)
		(min_thickness 0.25)
		(keepout
			(tracks not_allowed)
			(vias allowed)
			(pads allowed)
			(copperpour not_allowed)
			(footprints allowed)
		)
		(placement
			(enabled no)
			(sheetname "")
		)
		(fill yes
			(thermal_gap 0.5)
			(thermal_bridge_width 0.5)
			(island_removal_mode 0)
		)
		(polygon
			(pts
				(arc
					(start 417.776152 -277.849838)
					(mid 417.123372 -277.849838)
					(end 417.776152 -277.849838)
				)
			)
		)
	)
	(zone
		(layers "B.Cu" "In11.Cu" "In13.Cu" "In15.Cu")
		(hatch none 0.5)
		(connect_pads
			(clearance 0)
		)
		(min_thickness 0.25)
		(keepout
			(tracks not_allowed)
			(vias allowed)
			(pads allowed)
			(copperpour not_allowed)
			(footprints allowed)
		)
		(placement
			(enabled no)
			(sheetname "")
		)
		(fill yes
			(thermal_gap 0.5)
			(thermal_bridge_width 0.5)
			(island_removal_mode 0)
		)
		(polygon
			(pts
				(arc
					(start 177.026316 -280.699718)
					(mid 176.373536 -280.699718)
					(end 177.026316 -280.699718)
				)
			)
		)
	)
	(zone
		(layers "B.Cu" "In11.Cu" "In13.Cu" "In15.Cu")
		(hatch none 0.5)
		(connect_pads
			(clearance 0)
		)
		(min_thickness 0.25)
		(keepout
			(tracks not_allowed)
			(vias allowed)
			(pads allowed)
			(copperpour not_allowed)
			(footprints allowed)
		)
		(placement
			(enabled no)
			(sheetname "")
		)
		(fill yes
			(thermal_gap 0.5)
			(thermal_bridge_width 0.5)
			(island_removal_mode 0)
		)
		(polygon
			(pts
				(arc
					(start 81.884012 -130.769106)
					(mid 81.180432 -130.769106)
					(end 81.884012 -130.769106)
				)
			)
		)
	)
	(zone
		(layers "B.Cu" "In11.Cu" "In13.Cu" "In15.Cu")
		(hatch none 0.5)
		(connect_pads
			(clearance 0)
		)
		(min_thickness 0.25)
		(keepout
			(tracks not_allowed)
			(vias allowed)
			(pads allowed)
			(copperpour not_allowed)
			(footprints allowed)
		)
		(placement
			(enabled no)
			(sheetname "")
		)
		(fill yes
			(thermal_gap 0.5)
			(thermal_bridge_width 0.5)
			(island_removal_mode 0)
		)
		(polygon
			(pts
				(arc
					(start 35.47745 -119.224298)
					(mid 34.77387 -119.224298)
					(end 35.47745 -119.224298)
				)
			)
		)
	)
	(zone
		(layers "B.Cu" "In11.Cu" "In13.Cu" "In15.Cu")
		(hatch none 0.5)
		(connect_pads
			(clearance 0)
		)
		(min_thickness 0.25)
		(keepout
			(tracks not_allowed)
			(vias allowed)
			(pads allowed)
			(copperpour not_allowed)
			(footprints allowed)
		)
		(placement
			(enabled no)
			(sheetname "")
		)
		(fill yes
			(thermal_gap 0.5)
			(thermal_bridge_width 0.5)
			(island_removal_mode 0)
		)
		(polygon
			(pts
				(arc
					(start 419.676072 -277.849838)
					(mid 419.023292 -277.849838)
					(end 419.676072 -277.849838)
				)
			)
		)
	)
	(zone
		(layers "B.Cu" "In11.Cu" "In13.Cu" "In15.Cu")
		(hatch none 0.5)
		(connect_pads
			(clearance 0)
		)
		(min_thickness 0.25)
		(keepout
			(tracks not_allowed)
			(vias allowed)
			(pads allowed)
			(copperpour not_allowed)
			(footprints allowed)
		)
		(placement
			(enabled no)
			(sheetname "")
		)
		(fill yes
			(thermal_gap 0.5)
			(thermal_bridge_width 0.5)
			(island_removal_mode 0)
		)
		(polygon
			(pts
				(arc
					(start 457.999084 7.743952)
					(mid 457.295504 7.743952)
					(end 457.999084 7.743952)
				)
			)
		)
	)
	(zone
		(layers "B.Cu" "In11.Cu" "In13.Cu" "In15.Cu")
		(hatch none 0.5)
		(connect_pads
			(clearance 0)
		)
		(min_thickness 0.25)
		(keepout
			(tracks not_allowed)
			(vias allowed)
			(pads allowed)
			(copperpour not_allowed)
			(footprints allowed)
		)
		(placement
			(enabled no)
			(sheetname "")
		)
		(fill yes
			(thermal_gap 0.5)
			(thermal_bridge_width 0.5)
			(island_removal_mode 0)
		)
		(polygon
			(pts
				(arc
					(start 173.48962 -409.490164)
					(mid 172.73016 -409.490164)
					(end 173.48962 -409.490164)
				)
			)
		)
	)
	(zone
		(layers "B.Cu" "In11.Cu" "In13.Cu" "In15.Cu")
		(hatch none 0.5)
		(connect_pads
			(clearance 0)
		)
		(min_thickness 0.25)
		(keepout
			(tracks not_allowed)
			(vias allowed)
			(pads allowed)
			(copperpour not_allowed)
			(footprints allowed)
		)
		(placement
			(enabled no)
			(sheetname "")
		)
		(fill yes
			(thermal_gap 0.5)
			(thermal_bridge_width 0.5)
			(island_removal_mode 0)
		)
		(polygon
			(pts
				(arc
					(start 270.3195 -133.104382)
					(mid 269.61592 -133.104382)
					(end 270.3195 -133.104382)
				)
			)
		)
	)
	(zone
		(layers "B.Cu" "In11.Cu" "In13.Cu" "In15.Cu")
		(hatch none 0.5)
		(connect_pads
			(clearance 0)
		)
		(min_thickness 0.25)
		(keepout
			(tracks not_allowed)
			(vias allowed)
			(pads allowed)
			(copperpour not_allowed)
			(footprints allowed)
		)
		(placement
			(enabled no)
			(sheetname "")
		)
		(fill yes
			(thermal_gap 0.5)
			(thermal_bridge_width 0.5)
			(island_removal_mode 0)
		)
		(polygon
			(pts
				(arc
					(start 383.77749 -105.584498)
					(mid 383.07391 -105.584498)
					(end 383.77749 -105.584498)
				)
			)
		)
	)
	(zone
		(layers "B.Cu" "In11.Cu" "In13.Cu" "In15.Cu")
		(hatch none 0.5)
		(connect_pads
			(clearance 0)
		)
		(min_thickness 0.25)
		(keepout
			(tracks not_allowed)
			(vias allowed)
			(pads allowed)
			(copperpour not_allowed)
			(footprints allowed)
		)
		(placement
			(enabled no)
			(sheetname "")
		)
		(fill yes
			(thermal_gap 0.5)
			(thermal_bridge_width 0.5)
			(island_removal_mode 0)
		)
		(polygon
			(pts
				(arc
					(start 316.726062 -156.085794)
					(mid 316.022482 -156.085794)
					(end 316.726062 -156.085794)
				)
			)
		)
	)
	(zone
		(layers "B.Cu" "In11.Cu" "In13.Cu" "In15.Cu")
		(hatch none 0.5)
		(connect_pads
			(clearance 0)
		)
		(min_thickness 0.25)
		(keepout
			(tracks not_allowed)
			(vias allowed)
			(pads allowed)
			(copperpour not_allowed)
			(footprints allowed)
		)
		(placement
			(enabled no)
			(sheetname "")
		)
		(fill yes
			(thermal_gap 0.5)
			(thermal_bridge_width 0.5)
			(island_removal_mode 0)
		)
		(polygon
			(pts
				(arc
					(start 307.376068 -283.549852)
					(mid 306.723288 -283.549852)
					(end 307.376068 -283.549852)
				)
			)
		)
	)
	(zone
		(layers "B.Cu" "In11.Cu" "In13.Cu" "In15.Cu")
		(hatch none 0.5)
		(connect_pads
			(clearance 0)
		)
		(min_thickness 0.25)
		(keepout
			(tracks not_allowed)
			(vias allowed)
			(pads allowed)
			(copperpour not_allowed)
			(footprints allowed)
		)
		(placement
			(enabled no)
			(sheetname "")
		)
		(fill yes
			(thermal_gap 0.5)
			(thermal_bridge_width 0.5)
			(island_removal_mode 0)
		)
		(polygon
			(pts
				(arc
					(start 198.876412 -279.749758)
					(mid 198.223632 -279.749758)
					(end 198.876412 -279.749758)
				)
			)
		)
	)
	(zone
		(layers "B.Cu" "In11.Cu" "In13.Cu" "In15.Cu")
		(hatch none 0.5)
		(connect_pads
			(clearance 0)
		)
		(min_thickness 0.25)
		(keepout
			(tracks not_allowed)
			(vias allowed)
			(pads allowed)
			(copperpour not_allowed)
			(footprints allowed)
		)
		(placement
			(enabled no)
			(sheetname "")
		)
		(fill yes
			(thermal_gap 0.5)
			(thermal_bridge_width 0.5)
			(island_removal_mode 0)
		)
		(polygon
			(pts
				(arc
					(start 69.476112 -277.849838)
					(mid 68.823332 -277.849838)
					(end 69.476112 -277.849838)
				)
			)
		)
	)
	(zone
		(layers "B.Cu" "In11.Cu" "In13.Cu" "In15.Cu")
		(hatch none 0.5)
		(connect_pads
			(clearance 0)
		)
		(min_thickness 0.25)
		(keepout
			(tracks not_allowed)
			(vias allowed)
			(pads allowed)
			(copperpour not_allowed)
			(footprints allowed)
		)
		(placement
			(enabled no)
			(sheetname "")
		)
		(fill yes
			(thermal_gap 0.5)
			(thermal_bridge_width 0.5)
			(island_removal_mode 0)
		)
		(polygon
			(pts
				(arc
					(start 422.526206 -280.699718)
					(mid 421.873426 -280.699718)
					(end 422.526206 -280.699718)
				)
			)
		)
	)
	(zone
		(layers "B.Cu" "In11.Cu" "In13.Cu" "In15.Cu")
		(hatch none 0.5)
		(connect_pads
			(clearance 0)
		)
		(min_thickness 0.25)
		(keepout
			(tracks not_allowed)
			(vias allowed)
			(pads allowed)
			(copperpour not_allowed)
			(footprints allowed)
		)
		(placement
			(enabled no)
			(sheetname "")
		)
		(fill yes
			(thermal_gap 0.5)
			(thermal_bridge_width 0.5)
			(island_removal_mode 0)
		)
		(polygon
			(pts
				(arc
					(start 385.476242 -308.249828)
					(mid 384.823462 -308.249828)
					(end 385.476242 -308.249828)
				)
			)
		)
	)
	(zone
		(layers "B.Cu" "In11.Cu" "In13.Cu" "In15.Cu")
		(hatch none 0.5)
		(connect_pads
			(clearance 0)
		)
		(min_thickness 0.25)
		(keepout
			(tracks not_allowed)
			(vias allowed)
			(pads allowed)
			(copperpour not_allowed)
			(footprints allowed)
		)
		(placement
			(enabled no)
			(sheetname "")
		)
		(fill yes
			(thermal_gap 0.5)
			(thermal_bridge_width 0.5)
			(island_removal_mode 0)
		)
		(polygon
			(pts
				(arc
					(start 307.376068 -287.349946)
					(mid 306.723288 -287.349946)
					(end 307.376068 -287.349946)
				)
			)
		)
	)
	(zone
		(layers "B.Cu" "In11.Cu" "In13.Cu" "In15.Cu")
		(hatch none 0.5)
		(connect_pads
			(clearance 0)
		)
		(min_thickness 0.25)
		(keepout
			(tracks not_allowed)
			(vias allowed)
			(pads allowed)
			(copperpour not_allowed)
			(footprints allowed)
		)
		(placement
			(enabled no)
			(sheetname "")
		)
		(fill yes
			(thermal_gap 0.5)
			(thermal_bridge_width 0.5)
			(island_removal_mode 0)
		)
		(polygon
			(pts
				(arc
					(start 197.983856 -146.215608)
					(mid 197.280276 -146.215608)
					(end 197.983856 -146.215608)
				)
			)
		)
	)
	(zone
		(layers "B.Cu" "In11.Cu" "In13.Cu" "In15.Cu")
		(hatch none 0.5)
		(connect_pads
			(clearance 0)
		)
		(min_thickness 0.25)
		(keepout
			(tracks not_allowed)
			(vias allowed)
			(pads allowed)
			(copperpour not_allowed)
			(footprints allowed)
		)
		(placement
			(enabled no)
			(sheetname "")
		)
		(fill yes
			(thermal_gap 0.5)
			(thermal_bridge_width 0.5)
			(island_removal_mode 0)
		)
		(polygon
			(pts
				(arc
					(start 239.805464 -82.307176)
					(mid 239.101884 -82.307176)
					(end 239.805464 -82.307176)
				)
			)
		)
	)
	(zone
		(layers "B.Cu" "In11.Cu" "In13.Cu" "In15.Cu")
		(hatch none 0.5)
		(connect_pads
			(clearance 0)
		)
		(min_thickness 0.25)
		(keepout
			(tracks not_allowed)
			(vias allowed)
			(pads allowed)
			(copperpour not_allowed)
			(footprints allowed)
		)
		(placement
			(enabled no)
			(sheetname "")
		)
		(fill yes
			(thermal_gap 0.5)
			(thermal_bridge_width 0.5)
			(island_removal_mode 0)
		)
		(polygon
			(pts
				(arc
					(start 303.575974 -277.849838)
					(mid 302.923194 -277.849838)
					(end 303.575974 -277.849838)
				)
			)
		)
	)
	(zone
		(layers "B.Cu" "In11.Cu" "In13.Cu" "In15.Cu")
		(hatch none 0.5)
		(connect_pads
			(clearance 0)
		)
		(min_thickness 0.25)
		(keepout
			(tracks not_allowed)
			(vias allowed)
			(pads allowed)
			(copperpour not_allowed)
			(footprints allowed)
		)
		(placement
			(enabled no)
			(sheetname "")
		)
		(fill yes
			(thermal_gap 0.5)
			(thermal_bridge_width 0.5)
			(island_removal_mode 0)
		)
		(polygon
			(pts
				(arc
					(start 77.0763 -286.399986)
					(mid 76.42352 -286.399986)
					(end 77.0763 -286.399986)
				)
			)
		)
	)
	(zone
		(layers "B.Cu" "In11.Cu" "In13.Cu" "In15.Cu")
		(hatch none 0.5)
		(connect_pads
			(clearance 0)
		)
		(min_thickness 0.25)
		(keepout
			(tracks not_allowed)
			(vias allowed)
			(pads allowed)
			(copperpour not_allowed)
			(footprints allowed)
		)
		(placement
			(enabled no)
			(sheetname "")
		)
		(fill yes
			(thermal_gap 0.5)
			(thermal_bridge_width 0.5)
			(island_removal_mode 0)
		)
		(polygon
			(pts
				(arc
					(start 336.269838 -396.49019)
					(mid 335.510378 -396.49019)
					(end 336.269838 -396.49019)
				)
			)
		)
	)
	(zone
		(layers "B.Cu" "In11.Cu" "In13.Cu" "In15.Cu")
		(hatch none 0.5)
		(connect_pads
			(clearance 0)
		)
		(min_thickness 0.25)
		(keepout
			(tracks not_allowed)
			(vias allowed)
			(pads allowed)
			(copperpour not_allowed)
			(footprints allowed)
		)
		(placement
			(enabled no)
			(sheetname "")
		)
		(fill yes
			(thermal_gap 0.5)
			(thermal_bridge_width 0.5)
			(island_removal_mode 0)
		)
		(polygon
			(pts
				(arc
					(start 183.676036 -278.799798)
					(mid 183.023256 -278.799798)
					(end 183.676036 -278.799798)
				)
			)
		)
	)
	(zone
		(layers "B.Cu" "In11.Cu" "In13.Cu" "In15.Cu")
		(hatch none 0.5)
		(connect_pads
			(clearance 0)
		)
		(min_thickness 0.25)
		(keepout
			(tracks not_allowed)
			(vias allowed)
			(pads allowed)
			(copperpour not_allowed)
			(footprints allowed)
		)
		(placement
			(enabled no)
			(sheetname "")
		)
		(fill yes
			(thermal_gap 0.5)
			(thermal_bridge_width 0.5)
			(island_removal_mode 0)
		)
		(polygon
			(pts
				(arc
					(start 151.577294 -131.297934)
					(mid 150.873714 -131.297934)
					(end 151.577294 -131.297934)
				)
			)
		)
	)
	(zone
		(layers "B.Cu" "In11.Cu" "In13.Cu" "In15.Cu")
		(hatch none 0.5)
		(connect_pads
			(clearance 0)
		)
		(min_thickness 0.25)
		(keepout
			(tracks not_allowed)
			(vias allowed)
			(pads allowed)
			(copperpour not_allowed)
			(footprints allowed)
		)
		(placement
			(enabled no)
			(sheetname "")
		)
		(fill yes
			(thermal_gap 0.5)
			(thermal_bridge_width 0.5)
			(island_removal_mode 0)
		)
		(polygon
			(pts
				(arc
					(start 151.577294 -119.224298)
					(mid 150.873714 -119.224298)
					(end 151.577294 -119.224298)
				)
			)
		)
	)
	(zone
		(layers "B.Cu" "In11.Cu" "In13.Cu" "In15.Cu")
		(hatch none 0.5)
		(connect_pads
			(clearance 0)
		)
		(min_thickness 0.25)
		(keepout
			(tracks not_allowed)
			(vias allowed)
			(pads allowed)
			(copperpour not_allowed)
			(footprints allowed)
		)
		(placement
			(enabled no)
			(sheetname "")
		)
		(fill yes
			(thermal_gap 0.5)
			(thermal_bridge_width 0.5)
			(island_removal_mode 0)
		)
		(polygon
			(pts
				(arc
					(start 304.526188 -280.699718)
					(mid 303.873408 -280.699718)
					(end 304.526188 -280.699718)
				)
			)
		)
	)
	(zone
		(layers "B.Cu" "In11.Cu" "In13.Cu" "In15.Cu")
		(hatch none 0.5)
		(connect_pads
			(clearance 0)
		)
		(min_thickness 0.25)
		(keepout
			(tracks not_allowed)
			(vias allowed)
			(pads allowed)
			(copperpour not_allowed)
			(footprints allowed)
		)
		(placement
			(enabled no)
			(sheetname "")
		)
		(fill yes
			(thermal_gap 0.5)
			(thermal_bridge_width 0.5)
			(island_removal_mode 0)
		)
		(polygon
			(pts
				(arc
					(start 383.77749 -109.18444)
					(mid 383.07391 -109.18444)
					(end 383.77749 -109.18444)
				)
			)
		)
	)
	(zone
		(layers "B.Cu" "In11.Cu" "In13.Cu" "In15.Cu")
		(hatch none 0.5)
		(connect_pads
			(clearance 0)
		)
		(min_thickness 0.25)
		(keepout
			(tracks not_allowed)
			(vias allowed)
			(pads allowed)
			(copperpour not_allowed)
			(footprints allowed)
		)
		(placement
			(enabled no)
			(sheetname "")
		)
		(fill yes
			(thermal_gap 0.5)
			(thermal_bridge_width 0.5)
			(island_removal_mode 0)
		)
		(polygon
			(pts
				(arc
					(start 62.826138 -280.699718)
					(mid 62.173358 -280.699718)
					(end 62.826138 -280.699718)
				)
			)
		)
	)
	(zone
		(layers "B.Cu" "In11.Cu" "In13.Cu" "In15.Cu")
		(hatch none 0.5)
		(connect_pads
			(clearance 0)
		)
		(min_thickness 0.25)
		(keepout
			(tracks not_allowed)
			(vias allowed)
			(pads allowed)
			(copperpour not_allowed)
			(footprints allowed)
		)
		(placement
			(enabled no)
			(sheetname "")
		)
		(fill yes
			(thermal_gap 0.5)
			(thermal_bridge_width 0.5)
			(island_removal_mode 0)
		)
		(polygon
			(pts
				(arc
					(start 270.3195 -99.314254)
					(mid 269.61592 -99.314254)
					(end 270.3195 -99.314254)
				)
			)
		)
	)
	(zone
		(layers "B.Cu" "In11.Cu" "In13.Cu" "In15.Cu")
		(hatch none 0.5)
		(connect_pads
			(clearance 0)
		)
		(min_thickness 0.25)
		(keepout
			(tracks not_allowed)
			(vias allowed)
			(pads allowed)
			(copperpour not_allowed)
			(footprints allowed)
		)
		(placement
			(enabled no)
			(sheetname "")
		)
		(fill yes
			(thermal_gap 0.5)
			(thermal_bridge_width 0.5)
			(island_removal_mode 0)
		)
		(polygon
			(pts
				(arc
					(start 345.069668 -374.390158)
					(mid 344.310208 -374.390158)
					(end 345.069668 -374.390158)
				)
			)
		)
	)
	(zone
		(layers "B.Cu" "In11.Cu" "In13.Cu" "In15.Cu")
		(hatch none 0.5)
		(connect_pads
			(clearance 0)
		)
		(min_thickness 0.25)
		(keepout
			(tracks not_allowed)
			(vias allowed)
			(pads allowed)
			(copperpour not_allowed)
			(footprints allowed)
		)
		(placement
			(enabled no)
			(sheetname "")
		)
		(fill yes
			(thermal_gap 0.5)
			(thermal_bridge_width 0.5)
			(island_removal_mode 0)
		)
		(polygon
			(pts
				(arc
					(start 425.37634 -288.299906)
					(mid 424.72356 -288.299906)
					(end 425.37634 -288.299906)
				)
			)
		)
	)
	(zone
		(layers "B.Cu" "In11.Cu" "In13.Cu" "In15.Cu")
		(hatch none 0.5)
		(connect_pads
			(clearance 0)
		)
		(min_thickness 0.25)
		(keepout
			(tracks not_allowed)
			(vias allowed)
			(pads allowed)
			(copperpour not_allowed)
			(footprints allowed)
		)
		(placement
			(enabled no)
			(sheetname "")
		)
		(fill yes
			(thermal_gap 0.5)
			(thermal_bridge_width 0.5)
			(island_removal_mode 0)
		)
		(polygon
			(pts
				(arc
					(start 38.119558 -99.314254)
					(mid 37.415978 -99.314254)
					(end 38.119558 -99.314254)
				)
			)
		)
	)
	(zone
		(layers "B.Cu" "In11.Cu" "In13.Cu" "In15.Cu")
		(hatch none 0.5)
		(connect_pads
			(clearance 0)
		)
		(min_thickness 0.25)
		(keepout
			(tracks not_allowed)
			(vias allowed)
			(pads allowed)
			(copperpour not_allowed)
			(footprints allowed)
		)
		(placement
			(enabled no)
			(sheetname "")
		)
		(fill yes
			(thermal_gap 0.5)
			(thermal_bridge_width 0.5)
			(island_removal_mode 0)
		)
		(polygon
			(pts
				(arc
					(start 78.02626 -279.749504)
					(mid 77.37348 -279.749504)
					(end 78.02626 -279.749504)
				)
			)
		)
	)
	(zone
		(layers "B.Cu" "In11.Cu" "In13.Cu" "In15.Cu")
		(hatch none 0.5)
		(connect_pads
			(clearance 0)
		)
		(min_thickness 0.25)
		(keepout
			(tracks not_allowed)
			(vias allowed)
			(pads allowed)
			(copperpour not_allowed)
			(footprints allowed)
		)
		(placement
			(enabled no)
			(sheetname "")
		)
		(fill yes
			(thermal_gap 0.5)
			(thermal_bridge_width 0.5)
			(island_removal_mode 0)
		)
		(polygon
			(pts
				(arc
					(start 309.275988 -278.799798)
					(mid 308.623208 -278.799798)
					(end 309.275988 -278.799798)
				)
			)
		)
	)
	(zone
		(layers "B.Cu" "In11.Cu" "In13.Cu" "In15.Cu")
		(hatch none 0.5)
		(connect_pads
			(clearance 0)
		)
		(min_thickness 0.25)
		(keepout
			(tracks not_allowed)
			(vias allowed)
			(pads allowed)
			(copperpour not_allowed)
			(footprints allowed)
		)
		(placement
			(enabled no)
			(sheetname "")
		)
		(fill yes
			(thermal_gap 0.5)
			(thermal_bridge_width 0.5)
			(island_removal_mode 0)
		)
		(polygon
			(pts
				(arc
					(start 183.676036 -277.849838)
					(mid 183.023256 -277.849838)
					(end 183.676036 -277.849838)
				)
			)
		)
	)
	(zone
		(layers "B.Cu" "In11.Cu" "In13.Cu" "In15.Cu")
		(hatch none 0.5)
		(connect_pads
			(clearance 0)
		)
		(min_thickness 0.25)
		(keepout
			(tracks not_allowed)
			(vias allowed)
			(pads allowed)
			(copperpour not_allowed)
			(footprints allowed)
		)
		(placement
			(enabled no)
			(sheetname "")
		)
		(fill yes
			(thermal_gap 0.5)
			(thermal_bridge_width 0.5)
			(island_removal_mode 0)
		)
		(polygon
			(pts
				(arc
					(start 197.983856 -130.769106)
					(mid 197.280276 -130.769106)
					(end 197.983856 -130.769106)
				)
			)
		)
	)
	(zone
		(layers "B.Cu" "In11.Cu" "In13.Cu" "In15.Cu")
		(hatch none 0.5)
		(connect_pads
			(clearance 0)
		)
		(min_thickness 0.25)
		(keepout
			(tracks not_allowed)
			(vias allowed)
			(pads allowed)
			(copperpour not_allowed)
			(footprints allowed)
		)
		(placement
			(enabled no)
			(sheetname "")
		)
		(fill yes
			(thermal_gap 0.5)
			(thermal_bridge_width 0.5)
			(island_removal_mode 0)
		)
		(polygon
			(pts
				(arc
					(start 331.869796 -396.49019)
					(mid 331.110336 -396.49019)
					(end 331.869796 -396.49019)
				)
			)
		)
	)
	(zone
		(layers "B.Cu" "In11.Cu" "In13.Cu" "In15.Cu")
		(hatch none 0.5)
		(connect_pads
			(clearance 0)
		)
		(min_thickness 0.25)
		(keepout
			(tracks not_allowed)
			(vias allowed)
			(pads allowed)
			(copperpour not_allowed)
			(footprints allowed)
		)
		(placement
			(enabled no)
			(sheetname "")
		)
		(fill yes
			(thermal_gap 0.5)
			(thermal_bridge_width 0.5)
			(island_removal_mode 0)
		)
		(polygon
			(pts
				(arc
					(start 314.976256 -276.899878)
					(mid 314.323476 -276.899878)
					(end 314.976256 -276.899878)
				)
			)
		)
	)
	(zone
		(layers "B.Cu" "In11.Cu" "In13.Cu" "In15.Cu")
		(hatch none 0.5)
		(connect_pads
			(clearance 0)
		)
		(min_thickness 0.25)
		(keepout
			(tracks not_allowed)
			(vias allowed)
			(pads allowed)
			(copperpour not_allowed)
			(footprints allowed)
		)
		(placement
			(enabled no)
			(sheetname "")
		)
		(fill yes
			(thermal_gap 0.5)
			(thermal_bridge_width 0.5)
			(island_removal_mode 0)
		)
		(polygon
			(pts
				(arc
					(start 435.26964 -384.590036)
					(mid 434.51018 -384.590036)
					(end 435.26964 -384.590036)
				)
			)
		)
	)
	(zone
		(layers "B.Cu" "In11.Cu" "In13.Cu" "In15.Cu")
		(hatch none 0.5)
		(connect_pads
			(clearance 0)
		)
		(min_thickness 0.25)
		(keepout
			(tracks not_allowed)
			(vias allowed)
			(pads allowed)
			(copperpour not_allowed)
			(footprints allowed)
		)
		(placement
			(enabled no)
			(sheetname "")
		)
		(fill yes
			(thermal_gap 0.5)
			(thermal_bridge_width 0.5)
			(island_removal_mode 0)
		)
		(polygon
			(pts
				(arc
					(start 386.426202 -316.799722)
					(mid 385.773422 -316.799722)
					(end 386.426202 -316.799722)
				)
			)
		)
	)
	(zone
		(layers "B.Cu" "In11.Cu" "In13.Cu" "In15.Cu")
		(hatch none 0.5)
		(connect_pads
			(clearance 0)
		)
		(min_thickness 0.25)
		(keepout
			(tracks not_allowed)
			(vias allowed)
			(pads allowed)
			(copperpour not_allowed)
			(footprints allowed)
		)
		(placement
			(enabled no)
			(sheetname "")
		)
		(fill yes
			(thermal_gap 0.5)
			(thermal_bridge_width 0.5)
			(island_removal_mode 0)
		)
		(polygon
			(pts
				(arc
					(start 383.77749 -112.784382)
					(mid 383.07391 -112.784382)
					(end 383.77749 -112.784382)
				)
			)
		)
	)
	(zone
		(layers "B.Cu" "In11.Cu" "In13.Cu" "In15.Cu")
		(hatch none 0.5)
		(connect_pads
			(clearance 0)
		)
		(min_thickness 0.25)
		(keepout
			(tracks not_allowed)
			(vias allowed)
			(pads allowed)
			(copperpour not_allowed)
			(footprints allowed)
		)
		(placement
			(enabled no)
			(sheetname "")
		)
		(fill yes
			(thermal_gap 0.5)
			(thermal_bridge_width 0.5)
			(island_removal_mode 0)
		)
		(polygon
			(pts
				(arc
					(start 286.476186 -317.749936)
					(mid 285.823406 -317.749936)
					(end 286.476186 -317.749936)
				)
			)
		)
	)
	(zone
		(layers "B.Cu" "In11.Cu" "In13.Cu" "In15.Cu")
		(hatch none 0.5)
		(connect_pads
			(clearance 0)
		)
		(min_thickness 0.25)
		(keepout
			(tracks not_allowed)
			(vias allowed)
			(pads allowed)
			(copperpour not_allowed)
			(footprints allowed)
		)
		(placement
			(enabled no)
			(sheetname "")
		)
		(fill yes
			(thermal_gap 0.5)
			(thermal_bridge_width 0.5)
			(island_removal_mode 0)
		)
		(polygon
			(pts
				(arc
					(start 313.076082 -278.799798)
					(mid 312.423302 -278.799798)
					(end 313.076082 -278.799798)
				)
			)
		)
	)
	(zone
		(layers "B.Cu" "In11.Cu" "In13.Cu" "In15.Cu")
		(hatch none 0.5)
		(connect_pads
			(clearance 0)
		)
		(min_thickness 0.25)
		(keepout
			(tracks not_allowed)
			(vias allowed)
			(pads allowed)
			(copperpour not_allowed)
			(footprints allowed)
		)
		(placement
			(enabled no)
			(sheetname "")
		)
		(fill yes
			(thermal_gap 0.5)
			(thermal_bridge_width 0.5)
			(island_removal_mode 0)
		)
		(polygon
			(pts
				(arc
					(start 38.119558 -125.494542)
					(mid 37.415978 -125.494542)
					(end 38.119558 -125.494542)
				)
			)
		)
	)
	(zone
		(layers "B.Cu" "In11.Cu" "In13.Cu" "In15.Cu")
		(hatch none 0.5)
		(connect_pads
			(clearance 0)
		)
		(min_thickness 0.25)
		(keepout
			(tracks not_allowed)
			(vias allowed)
			(pads allowed)
			(copperpour not_allowed)
			(footprints allowed)
		)
		(placement
			(enabled no)
			(sheetname "")
		)
		(fill yes
			(thermal_gap 0.5)
			(thermal_bridge_width 0.5)
			(island_removal_mode 0)
		)
		(polygon
			(pts
				(arc
					(start 414.926272 -279.749504)
					(mid 414.273492 -279.749504)
					(end 414.926272 -279.749504)
				)
			)
		)
	)
	(zone
		(layers "B.Cu" "In11.Cu" "In13.Cu" "In15.Cu")
		(hatch none 0.5)
		(connect_pads
			(clearance 0)
		)
		(min_thickness 0.25)
		(keepout
			(tracks not_allowed)
			(vias allowed)
			(pads allowed)
			(copperpour not_allowed)
			(footprints allowed)
		)
		(placement
			(enabled no)
			(sheetname "")
		)
		(fill yes
			(thermal_gap 0.5)
			(thermal_bridge_width 0.5)
			(island_removal_mode 0)
		)
		(polygon
			(pts
				(arc
					(start 154.219402 -102.914196)
					(mid 153.515822 -102.914196)
					(end 154.219402 -102.914196)
				)
			)
		)
	)
	(zone
		(layers "B.Cu" "In11.Cu" "In13.Cu" "In15.Cu")
		(hatch none 0.5)
		(connect_pads
			(clearance 0)
		)
		(min_thickness 0.25)
		(keepout
			(tracks not_allowed)
			(vias allowed)
			(pads allowed)
			(copperpour not_allowed)
			(footprints allowed)
		)
		(placement
			(enabled no)
			(sheetname "")
		)
		(fill yes
			(thermal_gap 0.5)
			(thermal_bridge_width 0.5)
			(island_removal_mode 0)
		)
		(polygon
			(pts
				(arc
					(start 155.176474 -307.299868)
					(mid 154.523694 -307.299868)
					(end 155.176474 -307.299868)
				)
			)
		)
	)
	(zone
		(layers "B.Cu" "In11.Cu" "In13.Cu" "In15.Cu")
		(hatch none 0.5)
		(connect_pads
			(clearance 0)
		)
		(min_thickness 0.25)
		(keepout
			(tracks not_allowed)
			(vias allowed)
			(pads allowed)
			(copperpour not_allowed)
			(footprints allowed)
		)
		(placement
			(enabled no)
			(sheetname "")
		)
		(fill yes
			(thermal_gap 0.5)
			(thermal_bridge_width 0.5)
			(island_removal_mode 0)
		)
		(polygon
			(pts
				(arc
					(start 35.47745 -112.784382)
					(mid 34.77387 -112.784382)
					(end 35.47745 -112.784382)
				)
			)
		)
	)
	(zone
		(layers "B.Cu" "In11.Cu" "In13.Cu" "In15.Cu")
		(hatch none 0.5)
		(connect_pads
			(clearance 0)
		)
		(min_thickness 0.25)
		(keepout
			(tracks not_allowed)
			(vias allowed)
			(pads allowed)
			(copperpour not_allowed)
			(footprints allowed)
		)
		(placement
			(enabled no)
			(sheetname "")
		)
		(fill yes
			(thermal_gap 0.5)
			(thermal_bridge_width 0.5)
			(island_removal_mode 0)
		)
		(polygon
			(pts
				(arc
					(start 84.52612 -155.222194)
					(mid 83.82254 -155.222194)
					(end 84.52612 -155.222194)
				)
			)
		)
	)
	(zone
		(layers "B.Cu" "In11.Cu" "In13.Cu" "In15.Cu")
		(hatch none 0.5)
		(connect_pads
			(clearance 0)
		)
		(min_thickness 0.25)
		(keepout
			(tracks not_allowed)
			(vias allowed)
			(pads allowed)
			(copperpour not_allowed)
			(footprints allowed)
		)
		(placement
			(enabled no)
			(sheetname "")
		)
		(fill yes
			(thermal_gap 0.5)
			(thermal_bridge_width 0.5)
			(island_removal_mode 0)
		)
		(polygon
			(pts
				(arc
					(start 431.076354 -279.749758)
					(mid 430.423574 -279.749758)
					(end 431.076354 -279.749758)
				)
			)
		)
	)
	(zone
		(layers "B.Cu" "In11.Cu" "In13.Cu" "In15.Cu")
		(hatch none 0.5)
		(connect_pads
			(clearance 0)
		)
		(min_thickness 0.25)
		(keepout
			(tracks not_allowed)
			(vias allowed)
			(pads allowed)
			(copperpour not_allowed)
			(footprints allowed)
		)
		(placement
			(enabled no)
			(sheetname "")
		)
		(fill yes
			(thermal_gap 0.5)
			(thermal_bridge_width 0.5)
			(island_removal_mode 0)
		)
		(polygon
			(pts
				(arc
					(start 239.79759 -87.976202)
					(mid 239.09401 -87.976202)
					(end 239.79759 -87.976202)
				)
			)
		)
	)
	(zone
		(layers "B.Cu" "In11.Cu" "In13.Cu" "In15.Cu")
		(hatch none 0.5)
		(connect_pads
			(clearance 0)
		)
		(min_thickness 0.25)
		(keepout
			(tracks not_allowed)
			(vias allowed)
			(pads allowed)
			(copperpour not_allowed)
			(footprints allowed)
		)
		(placement
			(enabled no)
			(sheetname "")
		)
		(fill yes
			(thermal_gap 0.5)
			(thermal_bridge_width 0.5)
			(island_removal_mode 0)
		)
		(polygon
			(pts
				(arc
					(start 383.77749 -123.68784)
					(mid 383.07391 -123.68784)
					(end 383.77749 -123.68784)
				)
			)
		)
	)
	(zone
		(layers "B.Cu" "In11.Cu" "In13.Cu" "In15.Cu")
		(hatch none 0.5)
		(connect_pads
			(clearance 0)
		)
		(min_thickness 0.25)
		(keepout
			(tracks not_allowed)
			(vias allowed)
			(pads allowed)
			(copperpour not_allowed)
			(footprints allowed)
		)
		(placement
			(enabled no)
			(sheetname "")
		)
		(fill yes
			(thermal_gap 0.5)
			(thermal_bridge_width 0.5)
			(island_removal_mode 0)
		)
		(polygon
			(pts
				(arc
					(start 156.126434 -316.799722)
					(mid 155.473654 -316.799722)
					(end 156.126434 -316.799722)
				)
			)
		)
	)
	(zone
		(layers "B.Cu" "In11.Cu" "In13.Cu" "In15.Cu")
		(hatch none 0.5)
		(connect_pads
			(clearance 0)
		)
		(min_thickness 0.25)
		(keepout
			(tracks not_allowed)
			(vias allowed)
			(pads allowed)
			(copperpour not_allowed)
			(footprints allowed)
		)
		(placement
			(enabled no)
			(sheetname "")
		)
		(fill yes
			(thermal_gap 0.5)
			(thermal_bridge_width 0.5)
			(island_removal_mode 0)
		)
		(polygon
			(pts
				(arc
					(start 270.3195 -107.377738)
					(mid 269.61592 -107.377738)
					(end 270.3195 -107.377738)
				)
			)
		)
	)
	(zone
		(layers "B.Cu" "In11.Cu" "In13.Cu" "In15.Cu")
		(hatch none 0.5)
		(connect_pads
			(clearance 0)
		)
		(min_thickness 0.25)
		(keepout
			(tracks not_allowed)
			(vias allowed)
			(pads allowed)
			(copperpour not_allowed)
			(footprints allowed)
		)
		(placement
			(enabled no)
			(sheetname "")
		)
		(fill yes
			(thermal_gap 0.5)
			(thermal_bridge_width 0.5)
			(island_removal_mode 0)
		)
		(polygon
			(pts
				(arc
					(start 415.875978 -277.849838)
					(mid 415.223198 -277.849838)
					(end 415.875978 -277.849838)
				)
			)
		)
	)
	(zone
		(layers "B.Cu" "In11.Cu" "In13.Cu" "In15.Cu")
		(hatch none 0.5)
		(connect_pads
			(clearance 0)
		)
		(min_thickness 0.25)
		(keepout
			(tracks not_allowed)
			(vias allowed)
			(pads allowed)
			(copperpour not_allowed)
			(footprints allowed)
		)
		(placement
			(enabled no)
			(sheetname "")
		)
		(fill yes
			(thermal_gap 0.5)
			(thermal_bridge_width 0.5)
			(island_removal_mode 0)
		)
		(polygon
			(pts
				(arc
					(start 81.884012 -154.279346)
					(mid 81.180432 -154.279346)
					(end 81.884012 -154.279346)
				)
			)
		)
	)
	(zone
		(layers "B.Cu" "In11.Cu" "In13.Cu" "In15.Cu")
		(hatch none 0.5)
		(connect_pads
			(clearance 0)
		)
		(min_thickness 0.25)
		(keepout
			(tracks not_allowed)
			(vias allowed)
			(pads allowed)
			(copperpour not_allowed)
			(footprints allowed)
		)
		(placement
			(enabled no)
			(sheetname "")
		)
		(fill yes
			(thermal_gap 0.5)
			(thermal_bridge_width 0.5)
			(island_removal_mode 0)
		)
		(polygon
			(pts
				(arc
					(start 314.083954 -146.215608)
					(mid 313.380374 -146.215608)
					(end 314.083954 -146.215608)
				)
			)
		)
	)
	(zone
		(layers "B.Cu" "In11.Cu" "In13.Cu" "In15.Cu")
		(hatch none 0.5)
		(connect_pads
			(clearance 0)
		)
		(min_thickness 0.25)
		(keepout
			(tracks not_allowed)
			(vias allowed)
			(pads allowed)
			(copperpour not_allowed)
			(footprints allowed)
		)
		(placement
			(enabled no)
			(sheetname "")
		)
		(fill yes
			(thermal_gap 0.5)
			(thermal_bridge_width 0.5)
			(island_removal_mode 0)
		)
		(polygon
			(pts
				(arc
					(start 60.926218 -279.749504)
					(mid 60.273438 -279.749504)
					(end 60.926218 -279.749504)
				)
			)
		)
	)
	(zone
		(layers "B.Cu" "In11.Cu" "In13.Cu" "In15.Cu")
		(hatch none 0.5)
		(connect_pads
			(clearance 0)
		)
		(min_thickness 0.25)
		(keepout
			(tracks not_allowed)
			(vias allowed)
			(pads allowed)
			(copperpour not_allowed)
			(footprints allowed)
		)
		(placement
			(enabled no)
			(sheetname "")
		)
		(fill yes
			(thermal_gap 0.5)
			(thermal_bridge_width 0.5)
			(island_removal_mode 0)
		)
		(polygon
			(pts
				(arc
					(start 194.126358 -284.499812)
					(mid 193.473578 -284.499812)
					(end 194.126358 -284.499812)
				)
			)
		)
	)
	(zone
		(layers "B.Cu" "In11.Cu" "In13.Cu" "In15.Cu")
		(hatch none 0.5)
		(connect_pads
			(clearance 0)
		)
		(min_thickness 0.25)
		(keepout
			(tracks not_allowed)
			(vias allowed)
			(pads allowed)
			(copperpour not_allowed)
			(footprints allowed)
		)
		(placement
			(enabled no)
			(sheetname "")
		)
		(fill yes
			(thermal_gap 0.5)
			(thermal_bridge_width 0.5)
			(island_removal_mode 0)
		)
		(polygon
			(pts
				(arc
					(start 62.826138 -279.749504)
					(mid 62.173358 -279.749504)
					(end 62.826138 -279.749504)
				)
			)
		)
	)
	(zone
		(layers "B.Cu" "In11.Cu" "In13.Cu" "In15.Cu")
		(hatch none 0.5)
		(connect_pads
			(clearance 0)
		)
		(min_thickness 0.25)
		(keepout
			(tracks not_allowed)
			(vias allowed)
			(pads allowed)
			(copperpour not_allowed)
			(footprints allowed)
		)
		(placement
			(enabled no)
			(sheetname "")
		)
		(fill yes
			(thermal_gap 0.5)
			(thermal_bridge_width 0.5)
			(island_removal_mode 0)
		)
		(polygon
			(pts
				(arc
					(start 197.926452 -279.749758)
					(mid 197.273672 -279.749758)
					(end 197.926452 -279.749758)
				)
			)
		)
	)
	(zone
		(layers "B.Cu" "In11.Cu" "In13.Cu" "In15.Cu")
		(hatch none 0.5)
		(connect_pads
			(clearance 0)
		)
		(min_thickness 0.25)
		(keepout
			(tracks not_allowed)
			(vias allowed)
			(pads allowed)
			(copperpour not_allowed)
			(footprints allowed)
		)
		(placement
			(enabled no)
			(sheetname "")
		)
		(fill yes
			(thermal_gap 0.5)
			(thermal_bridge_width 0.5)
			(island_removal_mode 0)
		)
		(polygon
			(pts
				(arc
					(start 289.32632 -316.799722)
					(mid 288.67354 -316.799722)
					(end 289.32632 -316.799722)
				)
			)
		)
	)
	(zone
		(layers "B.Cu" "In11.Cu" "In13.Cu" "In15.Cu")
		(hatch none 0.5)
		(connect_pads
			(clearance 0)
		)
		(min_thickness 0.25)
		(keepout
			(tracks not_allowed)
			(vias allowed)
			(pads allowed)
			(copperpour not_allowed)
			(footprints allowed)
		)
		(placement
			(enabled no)
			(sheetname "")
		)
		(fill yes
			(thermal_gap 0.5)
			(thermal_bridge_width 0.5)
			(island_removal_mode 0)
		)
		(polygon
			(pts
				(arc
					(start 345.069668 -375.69013)
					(mid 344.310208 -375.69013)
					(end 345.069668 -375.69013)
				)
			)
		)
	)
	(zone
		(layers "B.Cu" "In11.Cu" "In13.Cu" "In15.Cu")
		(hatch none 0.5)
		(connect_pads
			(clearance 0)
		)
		(min_thickness 0.25)
		(keepout
			(tracks not_allowed)
			(vias allowed)
			(pads allowed)
			(copperpour not_allowed)
			(footprints allowed)
		)
		(placement
			(enabled no)
			(sheetname "")
		)
		(fill yes
			(thermal_gap 0.5)
			(thermal_bridge_width 0.5)
			(island_removal_mode 0)
		)
		(polygon
			(pts
				(arc
					(start 151.577294 -134.897876)
					(mid 150.873714 -134.897876)
					(end 151.577294 -134.897876)
				)
			)
		)
	)
	(zone
		(layers "B.Cu" "In11.Cu" "In13.Cu" "In15.Cu")
		(hatch none 0.5)
		(connect_pads
			(clearance 0)
		)
		(min_thickness 0.25)
		(keepout
			(tracks not_allowed)
			(vias allowed)
			(pads allowed)
			(copperpour not_allowed)
			(footprints allowed)
		)
		(placement
			(enabled no)
			(sheetname "")
		)
		(fill yes
			(thermal_gap 0.5)
			(thermal_bridge_width 0.5)
			(island_removal_mode 0)
		)
		(polygon
			(pts
				(arc
					(start 84.52612 -151.622252)
					(mid 83.82254 -151.622252)
					(end 84.52612 -151.622252)
				)
			)
		)
	)
	(zone
		(layers "B.Cu" "In11.Cu" "In13.Cu" "In15.Cu")
		(hatch none 0.5)
		(connect_pads
			(clearance 0)
		)
		(min_thickness 0.25)
		(keepout
			(tracks not_allowed)
			(vias allowed)
			(pads allowed)
			(copperpour not_allowed)
			(footprints allowed)
		)
		(placement
			(enabled no)
			(sheetname "")
		)
		(fill yes
			(thermal_gap 0.5)
			(thermal_bridge_width 0.5)
			(island_removal_mode 0)
		)
		(polygon
			(pts
				(arc
					(start 432.82616 -124.102114)
					(mid 432.12258 -124.102114)
					(end 432.82616 -124.102114)
				)
			)
		)
	)
	(zone
		(layers "B.Cu" "In11.Cu" "In13.Cu" "In15.Cu")
		(hatch none 0.5)
		(connect_pads
			(clearance 0)
		)
		(min_thickness 0.25)
		(keepout
			(tracks not_allowed)
			(vias allowed)
			(pads allowed)
			(copperpour not_allowed)
			(footprints allowed)
		)
		(placement
			(enabled no)
			(sheetname "")
		)
		(fill yes
			(thermal_gap 0.5)
			(thermal_bridge_width 0.5)
			(island_removal_mode 0)
		)
		(polygon
			(pts
				(arc
					(start 77.076046 -278.799798)
					(mid 76.423266 -278.799798)
					(end 77.076046 -278.799798)
				)
			)
		)
	)
	(zone
		(layers "B.Cu" "In11.Cu" "In13.Cu" "In15.Cu")
		(hatch none 0.5)
		(connect_pads
			(clearance 0)
		)
		(min_thickness 0.25)
		(keepout
			(tracks not_allowed)
			(vias allowed)
			(pads allowed)
			(copperpour not_allowed)
			(footprints allowed)
		)
		(placement
			(enabled no)
			(sheetname "")
		)
		(fill yes
			(thermal_gap 0.5)
			(thermal_bridge_width 0.5)
			(island_removal_mode 0)
		)
		(polygon
			(pts
				(arc
					(start 430.184052 -122.295666)
					(mid 429.480472 -122.295666)
					(end 430.184052 -122.295666)
				)
			)
		)
	)
	(zone
		(layers "B.Cu" "In11.Cu" "In13.Cu" "In15.Cu")
		(hatch none 0.5)
		(connect_pads
			(clearance 0)
		)
		(min_thickness 0.25)
		(keepout
			(tracks not_allowed)
			(vias allowed)
			(pads allowed)
			(copperpour not_allowed)
			(footprints allowed)
		)
		(placement
			(enabled no)
			(sheetname "")
		)
		(fill yes
			(thermal_gap 0.5)
			(thermal_bridge_width 0.5)
			(island_removal_mode 0)
		)
		(polygon
			(pts
				(arc
					(start 192.226438 -285.449772)
					(mid 191.573658 -285.449772)
					(end 192.226438 -285.449772)
				)
			)
		)
	)
	(zone
		(layers "B.Cu" "In11.Cu" "In13.Cu" "In15.Cu")
		(hatch none 0.5)
		(connect_pads
			(clearance 0)
		)
		(min_thickness 0.25)
		(keepout
			(tracks not_allowed)
			(vias allowed)
			(pads allowed)
			(copperpour not_allowed)
			(footprints allowed)
		)
		(placement
			(enabled no)
			(sheetname "")
		)
		(fill yes
			(thermal_gap 0.5)
			(thermal_bridge_width 0.5)
			(island_removal_mode 0)
		)
		(polygon
			(pts
				(arc
					(start 80.87614 -277.849838)
					(mid 80.22336 -277.849838)
					(end 80.87614 -277.849838)
				)
			)
		)
	)
	(zone
		(layers "B.Cu" "In11.Cu" "In13.Cu" "In15.Cu")
		(hatch none 0.5)
		(connect_pads
			(clearance 0)
		)
		(min_thickness 0.25)
		(keepout
			(tracks not_allowed)
			(vias allowed)
			(pads allowed)
			(copperpour not_allowed)
			(footprints allowed)
		)
		(placement
			(enabled no)
			(sheetname "")
		)
		(fill yes
			(thermal_gap 0.5)
			(thermal_bridge_width 0.5)
			(island_removal_mode 0)
		)
		(polygon
			(pts
				(arc
					(start 84.52612 -124.965714)
					(mid 83.82254 -124.965714)
					(end 84.52612 -124.965714)
				)
			)
		)
	)
	(zone
		(layers "B.Cu" "In11.Cu" "In13.Cu" "In15.Cu")
		(hatch none 0.5)
		(connect_pads
			(clearance 0)
		)
		(min_thickness 0.25)
		(keepout
			(tracks not_allowed)
			(vias allowed)
			(pads allowed)
			(copperpour not_allowed)
			(footprints allowed)
		)
		(placement
			(enabled no)
			(sheetname "")
		)
		(fill yes
			(thermal_gap 0.5)
			(thermal_bridge_width 0.5)
			(island_removal_mode 0)
		)
		(polygon
			(pts
				(arc
					(start 81.089754 -375.69013)
					(mid 80.330294 -375.69013)
					(end 81.089754 -375.69013)
				)
			)
		)
	)
	(zone
		(layers "B.Cu" "In11.Cu" "In13.Cu" "In15.Cu")
		(hatch none 0.5)
		(connect_pads
			(clearance 0)
		)
		(min_thickness 0.25)
		(keepout
			(tracks not_allowed)
			(vias allowed)
			(pads allowed)
			(copperpour not_allowed)
			(footprints allowed)
		)
		(placement
			(enabled no)
			(sheetname "")
		)
		(fill yes
			(thermal_gap 0.5)
			(thermal_bridge_width 0.5)
			(island_removal_mode 0)
		)
		(polygon
			(pts
				(arc
					(start 314.083954 -133.505702)
					(mid 313.380374 -133.505702)
					(end 314.083954 -133.505702)
				)
			)
		)
	)
	(zone
		(layers "B.Cu" "In11.Cu" "In13.Cu" "In15.Cu")
		(hatch none 0.5)
		(connect_pads
			(clearance 0)
		)
		(min_thickness 0.25)
		(keepout
			(tracks not_allowed)
			(vias allowed)
			(pads allowed)
			(copperpour not_allowed)
			(footprints allowed)
		)
		(placement
			(enabled no)
			(sheetname "")
		)
		(fill yes
			(thermal_gap 0.5)
			(thermal_bridge_width 0.5)
			(island_removal_mode 0)
		)
		(polygon
			(pts
				(arc
					(start 179.876196 -278.799798)
					(mid 179.223416 -278.799798)
					(end 179.876196 -278.799798)
				)
			)
		)
	)
	(zone
		(layers "B.Cu" "In11.Cu" "In13.Cu" "In15.Cu")
		(hatch none 0.5)
		(connect_pads
			(clearance 0)
		)
		(min_thickness 0.25)
		(keepout
			(tracks not_allowed)
			(vias allowed)
			(pads allowed)
			(copperpour not_allowed)
			(footprints allowed)
		)
		(placement
			(enabled no)
			(sheetname "")
		)
		(fill yes
			(thermal_gap 0.5)
			(thermal_bridge_width 0.5)
			(island_removal_mode 0)
		)
		(polygon
			(pts
				(arc
					(start 194.126358 -282.599892)
					(mid 193.473578 -282.599892)
					(end 194.126358 -282.599892)
				)
			)
		)
	)
	(zone
		(layers "B.Cu" "In11.Cu" "In13.Cu" "In15.Cu")
		(hatch none 0.5)
		(connect_pads
			(clearance 0)
		)
		(min_thickness 0.25)
		(keepout
			(tracks not_allowed)
			(vias allowed)
			(pads allowed)
			(copperpour not_allowed)
			(footprints allowed)
		)
		(placement
			(enabled no)
			(sheetname "")
		)
		(fill yes
			(thermal_gap 0.5)
			(thermal_bridge_width 0.5)
			(island_removal_mode 0)
		)
		(polygon
			(pts
				(arc
					(start 294.075866 -278.799798)
					(mid 293.423086 -278.799798)
					(end 294.075866 -278.799798)
				)
			)
		)
	)
	(zone
		(layers "B.Cu" "In11.Cu" "In13.Cu" "In15.Cu")
		(hatch none 0.5)
		(connect_pads
			(clearance 0)
		)
		(min_thickness 0.25)
		(keepout
			(tracks not_allowed)
			(vias allowed)
			(pads allowed)
			(copperpour not_allowed)
			(footprints allowed)
		)
		(placement
			(enabled no)
			(sheetname "")
		)
		(fill yes
			(thermal_gap 0.5)
			(thermal_bridge_width 0.5)
			(island_removal_mode 0)
		)
		(polygon
			(pts
				(arc
					(start 79.92618 -280.699718)
					(mid 79.2734 -280.699718)
					(end 79.92618 -280.699718)
				)
			)
		)
	)
	(zone
		(layers "B.Cu" "In11.Cu" "In13.Cu" "In15.Cu")
		(hatch none 0.5)
		(connect_pads
			(clearance 0)
		)
		(min_thickness 0.25)
		(keepout
			(tracks not_allowed)
			(vias allowed)
			(pads allowed)
			(copperpour not_allowed)
			(footprints allowed)
		)
		(placement
			(enabled no)
			(sheetname "")
		)
		(fill yes
			(thermal_gap 0.5)
			(thermal_bridge_width 0.5)
			(island_removal_mode 0)
		)
		(polygon
			(pts
				(arc
					(start 36.08705 -101.120702)
					(mid 35.38347 -101.120702)
					(end 36.08705 -101.120702)
				)
			)
		)
	)
	(zone
		(layers "B.Cu" "In11.Cu" "In13.Cu" "In15.Cu")
		(hatch none 0.5)
		(connect_pads
			(clearance 0)
		)
		(min_thickness 0.25)
		(keepout
			(tracks not_allowed)
			(vias allowed)
			(pads allowed)
			(copperpour not_allowed)
			(footprints allowed)
		)
		(placement
			(enabled no)
			(sheetname "")
		)
		(fill yes
			(thermal_gap 0.5)
			(thermal_bridge_width 0.5)
			(island_removal_mode 0)
		)
		(polygon
			(pts
				(arc
					(start 388.326376 -307.299868)
					(mid 387.673596 -307.299868)
					(end 388.326376 -307.299868)
				)
			)
		)
	)
	(zone
		(layers "B.Cu" "In11.Cu" "In13.Cu" "In15.Cu")
		(hatch none 0.5)
		(connect_pads
			(clearance 0)
		)
		(min_thickness 0.25)
		(keepout
			(tracks not_allowed)
			(vias allowed)
			(pads allowed)
			(copperpour not_allowed)
			(footprints allowed)
		)
		(placement
			(enabled no)
			(sheetname "")
		)
		(fill yes
			(thermal_gap 0.5)
			(thermal_bridge_width 0.5)
			(island_removal_mode 0)
		)
		(polygon
			(pts
				(arc
					(start 84.52612 -124.102114)
					(mid 83.82254 -124.102114)
					(end 84.52612 -124.102114)
				)
			)
		)
	)
	(zone
		(layers "B.Cu" "In11.Cu" "In13.Cu" "In15.Cu")
		(hatch none 0.5)
		(connect_pads
			(clearance 0)
		)
		(min_thickness 0.25)
		(keepout
			(tracks not_allowed)
			(vias allowed)
			(pads allowed)
			(copperpour not_allowed)
			(footprints allowed)
		)
		(placement
			(enabled no)
			(sheetname "")
		)
		(fill yes
			(thermal_gap 0.5)
			(thermal_bridge_width 0.5)
			(island_removal_mode 0)
		)
		(polygon
			(pts
				(arc
					(start 428.22622 -279.749758)
					(mid 427.57344 -279.749758)
					(end 428.22622 -279.749758)
				)
			)
		)
	)
	(zone
		(layers "B.Cu" "In11.Cu" "In13.Cu" "In15.Cu")
		(hatch none 0.5)
		(connect_pads
			(clearance 0)
		)
		(min_thickness 0.25)
		(keepout
			(tracks not_allowed)
			(vias allowed)
			(pads allowed)
			(copperpour not_allowed)
			(footprints allowed)
		)
		(placement
			(enabled no)
			(sheetname "")
		)
		(fill yes
			(thermal_gap 0.5)
			(thermal_bridge_width 0.5)
			(island_removal_mode 0)
		)
		(polygon
			(pts
				(arc
					(start 166.889684 -409.290012)
					(mid 166.130224 -409.290012)
					(end 166.889684 -409.290012)
				)
			)
		)
	)
	(zone
		(layers "B.Cu" "In11.Cu" "In13.Cu" "In15.Cu")
		(hatch none 0.5)
		(connect_pads
			(clearance 0)
		)
		(min_thickness 0.25)
		(keepout
			(tracks not_allowed)
			(vias allowed)
			(pads allowed)
			(copperpour not_allowed)
			(footprints allowed)
		)
		(placement
			(enabled no)
			(sheetname "")
		)
		(fill yes
			(thermal_gap 0.5)
			(thermal_bridge_width 0.5)
			(island_removal_mode 0)
		)
		(polygon
			(pts
				(arc
					(start 430.184052 -143.479266)
					(mid 429.480472 -143.479266)
					(end 430.184052 -143.479266)
				)
			)
		)
	)
	(zone
		(layers "B.Cu" "In11.Cu" "In13.Cu" "In15.Cu")
		(hatch none 0.5)
		(connect_pads
			(clearance 0)
		)
		(min_thickness 0.25)
		(keepout
			(tracks not_allowed)
			(vias allowed)
			(pads allowed)
			(copperpour not_allowed)
			(footprints allowed)
		)
		(placement
			(enabled no)
			(sheetname "")
		)
		(fill yes
			(thermal_gap 0.5)
			(thermal_bridge_width 0.5)
			(island_removal_mode 0)
		)
		(polygon
			(pts
				(arc
					(start 192.226438 -287.349946)
					(mid 191.573658 -287.349946)
					(end 192.226438 -287.349946)
				)
			)
		)
	)
	(zone
		(layers "B.Cu" "In11.Cu" "In13.Cu" "In15.Cu")
		(hatch none 0.5)
		(connect_pads
			(clearance 0)
		)
		(min_thickness 0.25)
		(keepout
			(tracks not_allowed)
			(vias allowed)
			(pads allowed)
			(copperpour not_allowed)
			(footprints allowed)
		)
		(placement
			(enabled no)
			(sheetname "")
		)
		(fill yes
			(thermal_gap 0.5)
			(thermal_bridge_width 0.5)
			(island_removal_mode 0)
		)
		(polygon
			(pts
				(arc
					(start 74.489564 -375.490232)
					(mid 73.730104 -375.490232)
					(end 74.489564 -375.490232)
				)
			)
		)
	)
	(zone
		(layers "B.Cu" "In11.Cu" "In13.Cu" "In15.Cu")
		(hatch none 0.5)
		(connect_pads
			(clearance 0)
		)
		(min_thickness 0.25)
		(keepout
			(tracks not_allowed)
			(vias allowed)
			(pads allowed)
			(copperpour not_allowed)
			(footprints allowed)
		)
		(placement
			(enabled no)
			(sheetname "")
		)
		(fill yes
			(thermal_gap 0.5)
			(thermal_bridge_width 0.5)
			(island_removal_mode 0)
		)
		(polygon
			(pts
				(arc
					(start 413.976058 -277.849838)
					(mid 413.323278 -277.849838)
					(end 413.976058 -277.849838)
				)
			)
		)
	)
	(zone
		(layers "B.Cu" "In11.Cu" "In13.Cu" "In15.Cu")
		(hatch none 0.5)
		(connect_pads
			(clearance 0)
		)
		(min_thickness 0.25)
		(keepout
			(tracks not_allowed)
			(vias allowed)
			(pads allowed)
			(copperpour not_allowed)
			(footprints allowed)
		)
		(placement
			(enabled no)
			(sheetname "")
		)
		(fill yes
			(thermal_gap 0.5)
			(thermal_bridge_width 0.5)
			(island_removal_mode 0)
		)
		(polygon
			(pts
				(arc
					(start 402.227288 7.718044)
					(mid 401.523708 7.718044)
					(end 402.227288 7.718044)
				)
			)
		)
	)
	(zone
		(layers "B.Cu" "In11.Cu" "In13.Cu" "In15.Cu")
		(hatch none 0.5)
		(connect_pads
			(clearance 0)
		)
		(min_thickness 0.25)
		(keepout
			(tracks not_allowed)
			(vias allowed)
			(pads allowed)
			(copperpour not_allowed)
			(footprints allowed)
		)
		(placement
			(enabled no)
			(sheetname "")
		)
		(fill yes
			(thermal_gap 0.5)
			(thermal_bridge_width 0.5)
			(island_removal_mode 0)
		)
		(polygon
			(pts
				(arc
					(start 138.976862 -198.5264)
					(mid 138.273282 -198.5264)
					(end 138.976862 -198.5264)
				)
			)
		)
	)
	(zone
		(layers "B.Cu" "In11.Cu" "In13.Cu" "In15.Cu")
		(hatch none 0.5)
		(connect_pads
			(clearance 0)
		)
		(min_thickness 0.25)
		(keepout
			(tracks not_allowed)
			(vias allowed)
			(pads allowed)
			(copperpour not_allowed)
			(footprints allowed)
		)
		(placement
			(enabled no)
			(sheetname "")
		)
		(fill yes
			(thermal_gap 0.5)
			(thermal_bridge_width 0.5)
			(island_removal_mode 0)
		)
		(polygon
			(pts
				(arc
					(start 422.069514 -383.290064)
					(mid 421.310054 -383.290064)
					(end 422.069514 -383.290064)
				)
			)
		)
	)
	(zone
		(layers "B.Cu" "In11.Cu" "In13.Cu" "In15.Cu")
		(hatch none 0.5)
		(connect_pads
			(clearance 0)
		)
		(min_thickness 0.25)
		(keepout
			(tracks not_allowed)
			(vias allowed)
			(pads allowed)
			(copperpour not_allowed)
			(footprints allowed)
		)
		(placement
			(enabled no)
			(sheetname "")
		)
		(fill yes
			(thermal_gap 0.5)
			(thermal_bridge_width 0.5)
			(island_removal_mode 0)
		)
		(polygon
			(pts
				(arc
					(start 270.3195 -136.704324)
					(mid 269.61592 -136.704324)
					(end 270.3195 -136.704324)
				)
			)
		)
	)
	(zone
		(layers "B.Cu" "In11.Cu" "In13.Cu" "In15.Cu")
		(hatch none 0.5)
		(connect_pads
			(clearance 0)
		)
		(min_thickness 0.25)
		(keepout
			(tracks not_allowed)
			(vias allowed)
			(pads allowed)
			(copperpour not_allowed)
			(footprints allowed)
		)
		(placement
			(enabled no)
			(sheetname "")
		)
		(fill yes
			(thermal_gap 0.5)
			(thermal_bridge_width 0.5)
			(island_removal_mode 0)
		)
		(polygon
			(pts
				(arc
					(start 268.286992 -101.984302)
					(mid 267.583412 -101.984302)
					(end 268.286992 -101.984302)
				)
			)
		)
	)
	(zone
		(layers "B.Cu" "In11.Cu" "In13.Cu" "In15.Cu")
		(hatch none 0.5)
		(connect_pads
			(clearance 0)
		)
		(min_thickness 0.25)
		(keepout
			(tracks not_allowed)
			(vias allowed)
			(pads allowed)
			(copperpour not_allowed)
			(footprints allowed)
		)
		(placement
			(enabled no)
			(sheetname "")
		)
		(fill yes
			(thermal_gap 0.5)
			(thermal_bridge_width 0.5)
			(island_removal_mode 0)
		)
		(polygon
			(pts
				(arc
					(start 331.869796 -397.790162)
					(mid 331.110336 -397.790162)
					(end 331.869796 -397.790162)
				)
			)
		)
	)
	(zone
		(layers "B.Cu" "In11.Cu" "In13.Cu" "In15.Cu")
		(hatch none 0.5)
		(connect_pads
			(clearance 0)
		)
		(min_thickness 0.25)
		(keepout
			(tracks not_allowed)
			(vias allowed)
			(pads allowed)
			(copperpour not_allowed)
			(footprints allowed)
		)
		(placement
			(enabled no)
			(sheetname "")
		)
		(fill yes
			(thermal_gap 0.5)
			(thermal_bridge_width 0.5)
			(island_removal_mode 0)
		)
		(polygon
			(pts
				(arc
					(start 383.77749 -120.087898)
					(mid 383.07391 -120.087898)
					(end 383.77749 -120.087898)
				)
			)
		)
	)
	(zone
		(layers "B.Cu" "In11.Cu" "In13.Cu" "In15.Cu")
		(hatch none 0.5)
		(connect_pads
			(clearance 0)
		)
		(min_thickness 0.25)
		(keepout
			(tracks not_allowed)
			(vias allowed)
			(pads allowed)
			(copperpour not_allowed)
			(footprints allowed)
		)
		(placement
			(enabled no)
			(sheetname "")
		)
		(fill yes
			(thermal_gap 0.5)
			(thermal_bridge_width 0.5)
			(island_removal_mode 0)
		)
		(polygon
			(pts
				(arc
					(start 311.175908 -277.849838)
					(mid 310.523128 -277.849838)
					(end 311.175908 -277.849838)
				)
			)
		)
	)
	(zone
		(layers "B.Cu" "In11.Cu" "In13.Cu" "In15.Cu")
		(hatch none 0.5)
		(connect_pads
			(clearance 0)
		)
		(min_thickness 0.25)
		(keepout
			(tracks not_allowed)
			(vias allowed)
			(pads allowed)
			(copperpour not_allowed)
			(footprints allowed)
		)
		(placement
			(enabled no)
			(sheetname "")
		)
		(fill yes
			(thermal_gap 0.5)
			(thermal_bridge_width 0.5)
			(island_removal_mode 0)
		)
		(polygon
			(pts
				(arc
					(start 76.12634 -283.549852)
					(mid 75.47356 -283.549852)
					(end 76.12634 -283.549852)
				)
			)
		)
	)
	(zone
		(layers "B.Cu" "In11.Cu" "In13.Cu" "In15.Cu")
		(hatch none 0.5)
		(connect_pads
			(clearance 0)
		)
		(min_thickness 0.25)
		(keepout
			(tracks not_allowed)
			(vias allowed)
			(pads allowed)
			(copperpour not_allowed)
			(footprints allowed)
		)
		(placement
			(enabled no)
			(sheetname "")
		)
		(fill yes
			(thermal_gap 0.5)
			(thermal_bridge_width 0.5)
			(island_removal_mode 0)
		)
		(polygon
			(pts
				(arc
					(start 389.276336 -318.699896)
					(mid 388.623556 -318.699896)
					(end 389.276336 -318.699896)
				)
			)
		)
	)
	(zone
		(layers "B.Cu" "In11.Cu" "In13.Cu" "In15.Cu")
		(hatch none 0.5)
		(connect_pads
			(clearance 0)
		)
		(min_thickness 0.25)
		(keepout
			(tracks not_allowed)
			(vias allowed)
			(pads allowed)
			(copperpour not_allowed)
			(footprints allowed)
		)
		(placement
			(enabled no)
			(sheetname "")
		)
		(fill yes
			(thermal_gap 0.5)
			(thermal_bridge_width 0.5)
			(island_removal_mode 0)
		)
		(polygon
			(pts
				(arc
					(start 308.326282 -280.699718)
					(mid 307.673502 -280.699718)
					(end 308.326282 -280.699718)
				)
			)
		)
	)
	(zone
		(layers "B.Cu" "In11.Cu" "In13.Cu" "In15.Cu")
		(hatch none 0.5)
		(connect_pads
			(clearance 0)
		)
		(min_thickness 0.25)
		(keepout
			(tracks not_allowed)
			(vias allowed)
			(pads allowed)
			(copperpour not_allowed)
			(footprints allowed)
		)
		(placement
			(enabled no)
			(sheetname "")
		)
		(fill yes
			(thermal_gap 0.5)
			(thermal_bridge_width 0.5)
			(island_removal_mode 0)
		)
		(polygon
			(pts
				(arc
					(start 81.884012 -147.079208)
					(mid 81.180432 -147.079208)
					(end 81.884012 -147.079208)
				)
			)
		)
	)
	(zone
		(layers "B.Cu" "In11.Cu" "In13.Cu" "In15.Cu")
		(hatch none 0.5)
		(connect_pads
			(clearance 0)
		)
		(min_thickness 0.25)
		(keepout
			(tracks not_allowed)
			(vias allowed)
			(pads allowed)
			(copperpour not_allowed)
			(footprints allowed)
		)
		(placement
			(enabled no)
			(sheetname "")
		)
		(fill yes
			(thermal_gap 0.5)
			(thermal_bridge_width 0.5)
			(island_removal_mode 0)
		)
		(polygon
			(pts
				(arc
					(start 81.089754 -396.49019)
					(mid 80.330294 -396.49019)
					(end 81.089754 -396.49019)
				)
			)
		)
	)
	(zone
		(layers "B.Cu" "In11.Cu" "In13.Cu" "In15.Cu")
		(hatch none 0.5)
		(connect_pads
			(clearance 0)
		)
		(min_thickness 0.25)
		(keepout
			(tracks not_allowed)
			(vias allowed)
			(pads allowed)
			(copperpour not_allowed)
			(footprints allowed)
		)
		(placement
			(enabled no)
			(sheetname "")
		)
		(fill yes
			(thermal_gap 0.5)
			(thermal_bridge_width 0.5)
			(island_removal_mode 0)
		)
		(polygon
			(pts
				(arc
					(start 270.3195 -124.630942)
					(mid 269.61592 -124.630942)
					(end 270.3195 -124.630942)
				)
			)
		)
	)
	(zone
		(layers "B.Cu" "In11.Cu" "In13.Cu" "In15.Cu")
		(hatch none 0.5)
		(connect_pads
			(clearance 0)
		)
		(min_thickness 0.25)
		(keepout
			(tracks not_allowed)
			(vias allowed)
			(pads allowed)
			(copperpour not_allowed)
			(footprints allowed)
		)
		(placement
			(enabled no)
			(sheetname "")
		)
		(fill yes
			(thermal_gap 0.5)
			(thermal_bridge_width 0.5)
			(island_removal_mode 0)
		)
		(polygon
			(pts
				(arc
					(start 84.52612 -156.085794)
					(mid 83.82254 -156.085794)
					(end 84.52612 -156.085794)
				)
			)
		)
	)
	(zone
		(layers "B.Cu" "In11.Cu" "In13.Cu" "In15.Cu")
		(hatch none 0.5)
		(connect_pads
			(clearance 0)
		)
		(min_thickness 0.25)
		(keepout
			(tracks not_allowed)
			(vias allowed)
			(pads allowed)
			(copperpour not_allowed)
			(footprints allowed)
		)
		(placement
			(enabled no)
			(sheetname "")
		)
		(fill yes
			(thermal_gap 0.5)
			(thermal_bridge_width 0.5)
			(island_removal_mode 0)
		)
		(polygon
			(pts
				(arc
					(start 67.575938 -278.799798)
					(mid 66.923158 -278.799798)
					(end 67.575938 -278.799798)
				)
			)
		)
	)
	(zone
		(layers "B.Cu" "In11.Cu" "In13.Cu" "In15.Cu")
		(hatch none 0.5)
		(connect_pads
			(clearance 0)
		)
		(min_thickness 0.25)
		(keepout
			(tracks not_allowed)
			(vias allowed)
			(pads allowed)
			(copperpour not_allowed)
			(footprints allowed)
		)
		(placement
			(enabled no)
			(sheetname "")
		)
		(fill yes
			(thermal_gap 0.5)
			(thermal_bridge_width 0.5)
			(island_removal_mode 0)
		)
		(polygon
			(pts
				(arc
					(start 386.426202 -310.149748)
					(mid 385.773422 -310.149748)
					(end 386.426202 -310.149748)
				)
			)
		)
	)
	(zone
		(layers "B.Cu" "In11.Cu" "In13.Cu" "In15.Cu")
		(hatch none 0.5)
		(connect_pads
			(clearance 0)
		)
		(min_thickness 0.25)
		(keepout
			(tracks not_allowed)
			(vias allowed)
			(pads allowed)
			(copperpour not_allowed)
			(footprints allowed)
		)
		(placement
			(enabled no)
			(sheetname "")
		)
		(fill yes
			(thermal_gap 0.5)
			(thermal_bridge_width 0.5)
			(island_removal_mode 0)
		)
		(polygon
			(pts
				(arc
					(start 155.176474 -305.399948)
					(mid 154.523694 -305.399948)
					(end 155.176474 -305.399948)
				)
			)
		)
	)
	(zone
		(layers "B.Cu" "In11.Cu" "In13.Cu" "In15.Cu")
		(hatch none 0.5)
		(connect_pads
			(clearance 0)
		)
		(min_thickness 0.25)
		(keepout
			(tracks not_allowed)
			(vias allowed)
			(pads allowed)
			(copperpour not_allowed)
			(footprints allowed)
		)
		(placement
			(enabled no)
			(sheetname "")
		)
		(fill yes
			(thermal_gap 0.5)
			(thermal_bridge_width 0.5)
			(island_removal_mode 0)
		)
		(polygon
			(pts
				(arc
					(start 160.289748 -382.18999)
					(mid 159.530288 -382.18999)
					(end 160.289748 -382.18999)
				)
			)
		)
	)
	(zone
		(layers "B.Cu" "In11.Cu" "In13.Cu" "In15.Cu")
		(hatch none 0.5)
		(connect_pads
			(clearance 0)
		)
		(min_thickness 0.25)
		(keepout
			(tracks not_allowed)
			(vias allowed)
			(pads allowed)
			(copperpour not_allowed)
			(footprints allowed)
		)
		(placement
			(enabled no)
			(sheetname "")
		)
		(fill yes
			(thermal_gap 0.5)
			(thermal_bridge_width 0.5)
			(island_removal_mode 0)
		)
		(polygon
			(pts
				(arc
					(start 78.975966 -277.849838)
					(mid 78.323186 -277.849838)
					(end 78.975966 -277.849838)
				)
			)
		)
	)
	(zone
		(layers "B.Cu" "In11.Cu" "In13.Cu" "In15.Cu")
		(hatch none 0.5)
		(connect_pads
			(clearance 0)
		)
		(min_thickness 0.25)
		(keepout
			(tracks not_allowed)
			(vias allowed)
			(pads allowed)
			(copperpour not_allowed)
			(footprints allowed)
		)
		(placement
			(enabled no)
			(sheetname "")
		)
		(fill yes
			(thermal_gap 0.5)
			(thermal_bridge_width 0.5)
			(island_removal_mode 0)
		)
		(polygon
			(pts
				(arc
					(start 416.826192 -280.699718)
					(mid 416.173412 -280.699718)
					(end 416.826192 -280.699718)
				)
			)
		)
	)
	(zone
		(layers "B.Cu" "In11.Cu" "In13.Cu" "In15.Cu")
		(hatch none 0.5)
		(connect_pads
			(clearance 0)
		)
		(min_thickness 0.25)
		(keepout
			(tracks not_allowed)
			(vias allowed)
			(pads allowed)
			(copperpour not_allowed)
			(footprints allowed)
		)
		(placement
			(enabled no)
			(sheetname "")
		)
		(fill yes
			(thermal_gap 0.5)
			(thermal_bridge_width 0.5)
			(island_removal_mode 0)
		)
		(polygon
			(pts
				(arc
					(start 187.47613 -278.799798)
					(mid 186.82335 -278.799798)
					(end 187.47613 -278.799798)
				)
			)
		)
	)
	(zone
		(layers "B.Cu" "In11.Cu" "In13.Cu" "In15.Cu")
		(hatch none 0.5)
		(connect_pads
			(clearance 0)
		)
		(min_thickness 0.25)
		(keepout
			(tracks not_allowed)
			(vias allowed)
			(pads allowed)
			(copperpour not_allowed)
			(footprints allowed)
		)
		(placement
			(enabled no)
			(sheetname "")
		)
		(fill yes
			(thermal_gap 0.5)
			(thermal_bridge_width 0.5)
			(island_removal_mode 0)
		)
		(polygon
			(pts
				(arc
					(start 302.626268 -279.749504)
					(mid 301.973488 -279.749504)
					(end 302.626268 -279.749504)
				)
			)
		)
	)
	(zone
		(layers "B.Cu" "In11.Cu" "In13.Cu" "In15.Cu")
		(hatch none 0.5)
		(connect_pads
			(clearance 0)
		)
		(min_thickness 0.25)
		(keepout
			(tracks not_allowed)
			(vias allowed)
			(pads allowed)
			(copperpour not_allowed)
			(footprints allowed)
		)
		(placement
			(enabled no)
			(sheetname "")
		)
		(fill yes
			(thermal_gap 0.5)
			(thermal_bridge_width 0.5)
			(island_removal_mode 0)
		)
		(polygon
			(pts
				(arc
					(start 383.77749 -134.897876)
					(mid 383.07391 -134.897876)
					(end 383.77749 -134.897876)
				)
			)
		)
	)
	(zone
		(layers "B.Cu" "In11.Cu" "In13.Cu" "In15.Cu")
		(hatch none 0.5)
		(connect_pads
			(clearance 0)
		)
		(min_thickness 0.25)
		(keepout
			(tracks not_allowed)
			(vias allowed)
			(pads allowed)
			(copperpour not_allowed)
			(footprints allowed)
		)
		(placement
			(enabled no)
			(sheetname "")
		)
		(fill yes
			(thermal_gap 0.5)
			(thermal_bridge_width 0.5)
			(island_removal_mode 0)
		)
		(polygon
			(pts
				(arc
					(start 81.884012 -133.505702)
					(mid 81.180432 -133.505702)
					(end 81.884012 -133.505702)
				)
			)
		)
	)
	(zone
		(layers "B.Cu" "In11.Cu" "In13.Cu" "In15.Cu")
		(hatch none 0.5)
		(connect_pads
			(clearance 0)
		)
		(min_thickness 0.25)
		(keepout
			(tracks not_allowed)
			(vias allowed)
			(pads allowed)
			(copperpour not_allowed)
			(footprints allowed)
		)
		(placement
			(enabled no)
			(sheetname "")
		)
		(fill yes
			(thermal_gap 0.5)
			(thermal_bridge_width 0.5)
			(island_removal_mode 0)
		)
		(polygon
			(pts
				(arc
					(start 388.326376 -315.849762)
					(mid 387.673596 -315.849762)
					(end 388.326376 -315.849762)
				)
			)
		)
	)
	(zone
		(layers "B.Cu" "In11.Cu" "In13.Cu" "In15.Cu")
		(hatch none 0.5)
		(connect_pads
			(clearance 0)
		)
		(min_thickness 0.25)
		(keepout
			(tracks not_allowed)
			(vias allowed)
			(pads allowed)
			(copperpour not_allowed)
			(footprints allowed)
		)
		(placement
			(enabled no)
			(sheetname "")
		)
		(fill yes
			(thermal_gap 0.5)
			(thermal_bridge_width 0.5)
			(island_removal_mode 0)
		)
		(polygon
			(pts
				(arc
					(start 65.676018 -277.849838)
					(mid 65.023238 -277.849838)
					(end 65.676018 -277.849838)
				)
			)
		)
	)
	(zone
		(layers "B.Cu" "In11.Cu" "In13.Cu" "In15.Cu")
		(hatch none 0.5)
		(connect_pads
			(clearance 0)
		)
		(min_thickness 0.25)
		(keepout
			(tracks not_allowed)
			(vias allowed)
			(pads allowed)
			(copperpour not_allowed)
			(footprints allowed)
		)
		(placement
			(enabled no)
			(sheetname "")
		)
		(fill yes
			(thermal_gap 0.5)
			(thermal_bridge_width 0.5)
			(island_removal_mode 0)
		)
		(polygon
			(pts
				(arc
					(start 81.826354 -279.749758)
					(mid 81.173574 -279.749758)
					(end 81.826354 -279.749758)
				)
			)
		)
	)
	(zone
		(layers "B.Cu" "In11.Cu" "In13.Cu" "In15.Cu")
		(hatch none 0.5)
		(connect_pads
			(clearance 0)
		)
		(min_thickness 0.25)
		(keepout
			(tracks not_allowed)
			(vias allowed)
			(pads allowed)
			(copperpour not_allowed)
			(footprints allowed)
		)
		(placement
			(enabled no)
			(sheetname "")
		)
		(fill yes
			(thermal_gap 0.5)
			(thermal_bridge_width 0.5)
			(island_removal_mode 0)
		)
		(polygon
			(pts
				(arc
					(start 386.419598 -132.240782)
					(mid 385.716018 -132.240782)
					(end 386.419598 -132.240782)
				)
			)
		)
	)
	(zone
		(layers "B.Cu" "In11.Cu" "In13.Cu" "In15.Cu")
		(hatch none 0.5)
		(connect_pads
			(clearance 0)
		)
		(min_thickness 0.25)
		(keepout
			(tracks not_allowed)
			(vias allowed)
			(pads allowed)
			(copperpour not_allowed)
			(footprints allowed)
		)
		(placement
			(enabled no)
			(sheetname "")
		)
		(fill yes
			(thermal_gap 0.5)
			(thermal_bridge_width 0.5)
			(island_removal_mode 0)
		)
		(polygon
			(pts
				(arc
					(start 404.767288 17.603724)
					(mid 404.063708 17.603724)
					(end 404.767288 17.603724)
				)
			)
		)
	)
	(zone
		(layers "B.Cu" "In11.Cu" "In13.Cu" "In15.Cu")
		(hatch none 0.5)
		(connect_pads
			(clearance 0)
		)
		(min_thickness 0.25)
		(keepout
			(tracks not_allowed)
			(vias allowed)
			(pads allowed)
			(copperpour not_allowed)
			(footprints allowed)
		)
		(placement
			(enabled no)
			(sheetname "")
		)
		(fill yes
			(thermal_gap 0.5)
			(thermal_bridge_width 0.5)
			(island_removal_mode 0)
		)
		(polygon
			(pts
				(arc
					(start 151.577294 -123.68784)
					(mid 150.873714 -123.68784)
					(end 151.577294 -123.68784)
				)
			)
		)
	)
	(zone
		(layers "B.Cu" "In11.Cu" "In13.Cu" "In15.Cu")
		(hatch none 0.5)
		(connect_pads
			(clearance 0)
		)
		(min_thickness 0.25)
		(keepout
			(tracks not_allowed)
			(vias allowed)
			(pads allowed)
			(copperpour not_allowed)
			(footprints allowed)
		)
		(placement
			(enabled no)
			(sheetname "")
		)
		(fill yes
			(thermal_gap 0.5)
			(thermal_bridge_width 0.5)
			(island_removal_mode 0)
		)
		(polygon
			(pts
				(arc
					(start 38.119558 -133.104382)
					(mid 37.415978 -133.104382)
					(end 38.119558 -133.104382)
				)
			)
		)
	)
	(zone
		(layers "B.Cu" "In11.Cu" "In13.Cu" "In15.Cu")
		(hatch none 0.5)
		(connect_pads
			(clearance 0)
		)
		(min_thickness 0.25)
		(keepout
			(tracks not_allowed)
			(vias allowed)
			(pads allowed)
			(copperpour not_allowed)
			(footprints allowed)
		)
		(placement
			(enabled no)
			(sheetname "")
		)
		(fill yes
			(thermal_gap 0.5)
			(thermal_bridge_width 0.5)
			(island_removal_mode 0)
		)
		(polygon
			(pts
				(arc
					(start 301.676054 -278.799798)
					(mid 301.023274 -278.799798)
					(end 301.676054 -278.799798)
				)
			)
		)
	)
	(zone
		(layers "B.Cu" "In11.Cu" "In13.Cu" "In15.Cu")
		(hatch none 0.5)
		(connect_pads
			(clearance 0)
		)
		(min_thickness 0.25)
		(keepout
			(tracks not_allowed)
			(vias allowed)
			(pads allowed)
			(copperpour not_allowed)
			(footprints allowed)
		)
		(placement
			(enabled no)
			(sheetname "")
		)
		(fill yes
			(thermal_gap 0.5)
			(thermal_bridge_width 0.5)
			(island_removal_mode 0)
		)
		(polygon
			(pts
				(arc
					(start 386.419598 -133.104382)
					(mid 385.716018 -133.104382)
					(end 386.419598 -133.104382)
				)
			)
		)
	)
	(zone
		(layers "B.Cu" "In11.Cu" "In13.Cu" "In15.Cu")
		(hatch none 0.5)
		(connect_pads
			(clearance 0)
		)
		(min_thickness 0.25)
		(keepout
			(tracks not_allowed)
			(vias allowed)
			(pads allowed)
			(copperpour not_allowed)
			(footprints allowed)
		)
		(placement
			(enabled no)
			(sheetname "")
		)
		(fill yes
			(thermal_gap 0.5)
			(thermal_bridge_width 0.5)
			(island_removal_mode 0)
		)
		(polygon
			(pts
				(arc
					(start 177.976022 -278.799798)
					(mid 177.323242 -278.799798)
					(end 177.976022 -278.799798)
				)
			)
		)
	)
	(zone
		(layers "B.Cu" "In11.Cu" "In13.Cu" "In15.Cu")
		(hatch none 0.5)
		(connect_pads
			(clearance 0)
		)
		(min_thickness 0.25)
		(keepout
			(tracks not_allowed)
			(vias allowed)
			(pads allowed)
			(copperpour not_allowed)
			(footprints allowed)
		)
		(placement
			(enabled no)
			(sheetname "")
		)
		(fill yes
			(thermal_gap 0.5)
			(thermal_bridge_width 0.5)
			(island_removal_mode 0)
		)
		(polygon
			(pts
				(arc
					(start 301.676054 -277.849838)
					(mid 301.023274 -277.849838)
					(end 301.676054 -277.849838)
				)
			)
		)
	)
	(zone
		(layers "B.Cu" "In11.Cu" "In13.Cu" "In15.Cu")
		(hatch none 0.5)
		(connect_pads
			(clearance 0)
		)
		(min_thickness 0.25)
		(keepout
			(tracks not_allowed)
			(vias allowed)
			(pads allowed)
			(copperpour not_allowed)
			(footprints allowed)
		)
		(placement
			(enabled no)
			(sheetname "")
		)
		(fill yes
			(thermal_gap 0.5)
			(thermal_bridge_width 0.5)
			(island_removal_mode 0)
		)
		(polygon
			(pts
				(arc
					(start 57.126378 -316.799722)
					(mid 56.473598 -316.799722)
					(end 57.126378 -316.799722)
				)
			)
		)
	)
	(zone
		(layers "B.Cu" "In11.Cu" "In13.Cu" "In15.Cu")
		(hatch none 0.5)
		(connect_pads
			(clearance 0)
		)
		(min_thickness 0.25)
		(keepout
			(tracks not_allowed)
			(vias allowed)
			(pads allowed)
			(copperpour not_allowed)
			(footprints allowed)
		)
		(placement
			(enabled no)
			(sheetname "")
		)
		(fill yes
			(thermal_gap 0.5)
			(thermal_bridge_width 0.5)
			(island_removal_mode 0)
		)
		(polygon
			(pts
				(arc
					(start 424.42638 -280.699718)
					(mid 423.7736 -280.699718)
					(end 424.42638 -280.699718)
				)
			)
		)
	)
	(zone
		(layers "B.Cu" "In11.Cu" "In13.Cu" "In15.Cu")
		(hatch none 0.5)
		(connect_pads
			(clearance 0)
		)
		(min_thickness 0.25)
		(keepout
			(tracks not_allowed)
			(vias allowed)
			(pads allowed)
			(copperpour not_allowed)
			(footprints allowed)
		)
		(placement
			(enabled no)
			(sheetname "")
		)
		(fill yes
			(thermal_gap 0.5)
			(thermal_bridge_width 0.5)
			(island_removal_mode 0)
		)
		(polygon
			(pts
				(arc
					(start 292.175946 -277.849838)
					(mid 291.523166 -277.849838)
					(end 292.175946 -277.849838)
				)
			)
		)
	)
	(zone
		(layers "B.Cu" "In11.Cu" "In13.Cu" "In15.Cu")
		(hatch none 0.5)
		(connect_pads
			(clearance 0)
		)
		(min_thickness 0.25)
		(keepout
			(tracks not_allowed)
			(vias allowed)
			(pads allowed)
			(copperpour not_allowed)
			(footprints allowed)
		)
		(placement
			(enabled no)
			(sheetname "")
		)
		(fill yes
			(thermal_gap 0.5)
			(thermal_bridge_width 0.5)
			(island_removal_mode 0)
		)
		(polygon
			(pts
				(arc
					(start 316.726062 -124.965714)
					(mid 316.022482 -124.965714)
					(end 316.726062 -124.965714)
				)
			)
		)
	)
	(zone
		(layers "B.Cu" "In11.Cu" "In13.Cu" "In15.Cu")
		(hatch none 0.5)
		(connect_pads
			(clearance 0)
		)
		(min_thickness 0.25)
		(keepout
			(tracks not_allowed)
			(vias allowed)
			(pads allowed)
			(copperpour not_allowed)
			(footprints allowed)
		)
		(placement
			(enabled no)
			(sheetname "")
		)
		(fill yes
			(thermal_gap 0.5)
			(thermal_bridge_width 0.5)
			(island_removal_mode 0)
		)
		(polygon
			(pts
				(arc
					(start 55.226204 -316.799722)
					(mid 54.573424 -316.799722)
					(end 55.226204 -316.799722)
				)
			)
		)
	)
	(zone
		(layers "B.Cu" "In11.Cu" "In13.Cu" "In15.Cu")
		(hatch none 0.5)
		(connect_pads
			(clearance 0)
		)
		(min_thickness 0.25)
		(keepout
			(tracks not_allowed)
			(vias allowed)
			(pads allowed)
			(copperpour not_allowed)
			(footprints allowed)
		)
		(placement
			(enabled no)
			(sheetname "")
		)
		(fill yes
			(thermal_gap 0.5)
			(thermal_bridge_width 0.5)
			(island_removal_mode 0)
		)
		(polygon
			(pts
				(arc
					(start 53.326284 -316.799722)
					(mid 52.673504 -316.799722)
					(end 53.326284 -316.799722)
				)
			)
		)
	)
	(zone
		(layers "B.Cu" "In11.Cu" "In13.Cu" "In15.Cu")
		(hatch none 0.5)
		(connect_pads
			(clearance 0)
		)
		(min_thickness 0.25)
		(keepout
			(tracks not_allowed)
			(vias allowed)
			(pads allowed)
			(copperpour not_allowed)
			(footprints allowed)
		)
		(placement
			(enabled no)
			(sheetname "")
		)
		(fill yes
			(thermal_gap 0.5)
			(thermal_bridge_width 0.5)
			(island_removal_mode 0)
		)
		(polygon
			(pts
				(arc
					(start 153.2763 -310.149748)
					(mid 152.62352 -310.149748)
					(end 153.2763 -310.149748)
				)
			)
		)
	)
	(zone
		(layers "B.Cu" "In11.Cu" "In13.Cu" "In15.Cu")
		(hatch none 0.5)
		(connect_pads
			(clearance 0)
		)
		(min_thickness 0.25)
		(keepout
			(tracks not_allowed)
			(vias allowed)
			(pads allowed)
			(copperpour not_allowed)
			(footprints allowed)
		)
		(placement
			(enabled no)
			(sheetname "")
		)
		(fill yes
			(thermal_gap 0.5)
			(thermal_bridge_width 0.5)
			(island_removal_mode 0)
		)
		(polygon
			(pts
				(arc
					(start 338.469732 -397.59001)
					(mid 337.710272 -397.59001)
					(end 338.469732 -397.59001)
				)
			)
		)
	)
	(zone
		(layers "B.Cu" "In11.Cu" "In13.Cu" "In15.Cu")
		(hatch none 0.5)
		(connect_pads
			(clearance 0)
		)
		(min_thickness 0.25)
		(keepout
			(tracks not_allowed)
			(vias allowed)
			(pads allowed)
			(copperpour not_allowed)
			(footprints allowed)
		)
		(placement
			(enabled no)
			(sheetname "")
		)
		(fill yes
			(thermal_gap 0.5)
			(thermal_bridge_width 0.5)
			(island_removal_mode 0)
		)
		(polygon
			(pts
				(arc
					(start 314.026296 -276.899878)
					(mid 313.373516 -276.899878)
					(end 314.026296 -276.899878)
				)
			)
		)
	)
	(zone
		(layers "B.Cu" "In11.Cu" "In13.Cu" "In15.Cu")
		(hatch none 0.5)
		(connect_pads
			(clearance 0)
		)
		(min_thickness 0.25)
		(keepout
			(tracks not_allowed)
			(vias allowed)
			(pads allowed)
			(copperpour not_allowed)
			(footprints allowed)
		)
		(placement
			(enabled no)
			(sheetname "")
		)
		(fill yes
			(thermal_gap 0.5)
			(thermal_bridge_width 0.5)
			(island_removal_mode 0)
		)
		(polygon
			(pts
				(arc
					(start 182.72633 -280.699718)
					(mid 182.07355 -280.699718)
					(end 182.72633 -280.699718)
				)
			)
		)
	)
	(zone
		(layers "B.Cu" "In11.Cu" "In13.Cu" "In15.Cu")
		(hatch none 0.5)
		(connect_pads
			(clearance 0)
		)
		(min_thickness 0.25)
		(keepout
			(tracks not_allowed)
			(vias allowed)
			(pads allowed)
			(copperpour not_allowed)
			(footprints allowed)
		)
		(placement
			(enabled no)
			(sheetname "")
		)
		(fill yes
			(thermal_gap 0.5)
			(thermal_bridge_width 0.5)
			(island_removal_mode 0)
		)
		(polygon
			(pts
				(arc
					(start 410.175964 -278.799798)
					(mid 409.523184 -278.799798)
					(end 410.175964 -278.799798)
				)
			)
		)
	)
	(zone
		(layers "B.Cu" "In11.Cu" "In13.Cu" "In15.Cu")
		(hatch none 0.5)
		(connect_pads
			(clearance 0)
		)
		(min_thickness 0.25)
		(keepout
			(tracks not_allowed)
			(vias allowed)
			(pads allowed)
			(copperpour not_allowed)
			(footprints allowed)
		)
		(placement
			(enabled no)
			(sheetname "")
		)
		(fill yes
			(thermal_gap 0.5)
			(thermal_bridge_width 0.5)
			(island_removal_mode 0)
		)
		(polygon
			(pts
				(arc
					(start 154.22626 -310.149748)
					(mid 153.57348 -310.149748)
					(end 154.22626 -310.149748)
				)
			)
		)
	)
	(zone
		(layers "B.Cu" "In11.Cu" "In13.Cu" "In15.Cu")
		(hatch none 0.5)
		(connect_pads
			(clearance 0)
		)
		(min_thickness 0.25)
		(keepout
			(tracks not_allowed)
			(vias allowed)
			(pads allowed)
			(copperpour not_allowed)
			(footprints allowed)
		)
		(placement
			(enabled no)
			(sheetname "")
		)
		(fill yes
			(thermal_gap 0.5)
			(thermal_bridge_width 0.5)
			(island_removal_mode 0)
		)
		(polygon
			(pts
				(arc
					(start 285.526226 -315.849762)
					(mid 284.873446 -315.849762)
					(end 285.526226 -315.849762)
				)
			)
		)
	)
	(zone
		(layers "B.Cu" "In11.Cu" "In13.Cu" "In15.Cu")
		(hatch none 0.5)
		(connect_pads
			(clearance 0)
		)
		(min_thickness 0.25)
		(keepout
			(tracks not_allowed)
			(vias allowed)
			(pads allowed)
			(copperpour not_allowed)
			(footprints allowed)
		)
		(placement
			(enabled no)
			(sheetname "")
		)
		(fill yes
			(thermal_gap 0.5)
			(thermal_bridge_width 0.5)
			(island_removal_mode 0)
		)
		(polygon
			(pts
				(arc
					(start 336.269838 -374.390158)
					(mid 335.510378 -374.390158)
					(end 336.269838 -374.390158)
				)
			)
		)
	)
	(zone
		(layers "B.Cu" "In11.Cu" "In13.Cu" "In15.Cu")
		(hatch none 0.5)
		(connect_pads
			(clearance 0)
		)
		(min_thickness 0.25)
		(keepout
			(tracks not_allowed)
			(vias allowed)
			(pads allowed)
			(copperpour not_allowed)
			(footprints allowed)
		)
		(placement
			(enabled no)
			(sheetname "")
		)
		(fill yes
			(thermal_gap 0.5)
			(thermal_bridge_width 0.5)
			(island_removal_mode 0)
		)
		(polygon
			(pts
				(arc
					(start 74.226166 -280.699718)
					(mid 73.573386 -280.699718)
					(end 74.226166 -280.699718)
				)
			)
		)
	)
	(zone
		(layers "B.Cu" "In11.Cu" "In13.Cu" "In15.Cu")
		(hatch none 0.5)
		(connect_pads
			(clearance 0)
		)
		(min_thickness 0.25)
		(keepout
			(tracks not_allowed)
			(vias allowed)
			(pads allowed)
			(copperpour not_allowed)
			(footprints allowed)
		)
		(placement
			(enabled no)
			(sheetname "")
		)
		(fill yes
			(thermal_gap 0.5)
			(thermal_bridge_width 0.5)
			(island_removal_mode 0)
		)
		(polygon
			(pts
				(arc
					(start 200.625964 -124.965714)
					(mid 199.922384 -124.965714)
					(end 200.625964 -124.965714)
				)
			)
		)
	)
	(zone
		(layers "B.Cu" "In11.Cu" "In13.Cu" "In15.Cu")
		(hatch none 0.5)
		(connect_pads
			(clearance 0)
		)
		(min_thickness 0.25)
		(keepout
			(tracks not_allowed)
			(vias allowed)
			(pads allowed)
			(copperpour not_allowed)
			(footprints allowed)
		)
		(placement
			(enabled no)
			(sheetname "")
		)
		(fill yes
			(thermal_gap 0.5)
			(thermal_bridge_width 0.5)
			(island_removal_mode 0)
		)
		(polygon
			(pts
				(arc
					(start 154.219402 -110.977934)
					(mid 153.515822 -110.977934)
					(end 154.219402 -110.977934)
				)
			)
		)
	)
	(zone
		(layers "B.Cu" "In11.Cu" "In13.Cu" "In15.Cu")
		(hatch none 0.5)
		(connect_pads
			(clearance 0)
		)
		(min_thickness 0.25)
		(keepout
			(tracks not_allowed)
			(vias allowed)
			(pads allowed)
			(copperpour not_allowed)
			(footprints allowed)
		)
		(placement
			(enabled no)
			(sheetname "")
		)
		(fill yes
			(thermal_gap 0.5)
			(thermal_bridge_width 0.5)
			(island_removal_mode 0)
		)
		(polygon
			(pts
				(arc
					(start 386.419598 -125.494542)
					(mid 385.716018 -125.494542)
					(end 386.419598 -125.494542)
				)
			)
		)
	)
	(zone
		(layers "B.Cu" "In11.Cu" "In13.Cu" "In15.Cu")
		(hatch none 0.5)
		(connect_pads
			(clearance 0)
		)
		(min_thickness 0.25)
		(keepout
			(tracks not_allowed)
			(vias allowed)
			(pads allowed)
			(copperpour not_allowed)
			(footprints allowed)
		)
		(placement
			(enabled no)
			(sheetname "")
		)
		(fill yes
			(thermal_gap 0.5)
			(thermal_bridge_width 0.5)
			(island_removal_mode 0)
		)
		(polygon
			(pts
				(arc
					(start 154.219402 -106.514138)
					(mid 153.515822 -106.514138)
					(end 154.219402 -106.514138)
				)
			)
		)
	)
	(zone
		(layers "B.Cu" "In11.Cu" "In13.Cu" "In15.Cu")
		(hatch none 0.5)
		(connect_pads
			(clearance 0)
		)
		(min_thickness 0.25)
		(keepout
			(tracks not_allowed)
			(vias allowed)
			(pads allowed)
			(copperpour not_allowed)
			(footprints allowed)
		)
		(placement
			(enabled no)
			(sheetname "")
		)
		(fill yes
			(thermal_gap 0.5)
			(thermal_bridge_width 0.5)
			(island_removal_mode 0)
		)
		(polygon
			(pts
				(arc
					(start 387.376416 -307.299868)
					(mid 386.723636 -307.299868)
					(end 387.376416 -307.299868)
				)
			)
		)
	)
	(zone
		(layers "B.Cu" "In11.Cu" "In13.Cu" "In15.Cu")
		(hatch none 0.5)
		(connect_pads
			(clearance 0)
		)
		(min_thickness 0.25)
		(keepout
			(tracks not_allowed)
			(vias allowed)
			(pads allowed)
			(copperpour not_allowed)
			(footprints allowed)
		)
		(placement
			(enabled no)
			(sheetname "")
		)
		(fill yes
			(thermal_gap 0.5)
			(thermal_bridge_width 0.5)
			(island_removal_mode 0)
		)
		(polygon
			(pts
				(arc
					(start 424.269662 -382.18999)
					(mid 423.510202 -382.18999)
					(end 424.269662 -382.18999)
				)
			)
		)
	)
	(zone
		(layers "B.Cu" "In11.Cu" "In13.Cu" "In15.Cu")
		(hatch none 0.5)
		(connect_pads
			(clearance 0)
		)
		(min_thickness 0.25)
		(keepout
			(tracks not_allowed)
			(vias allowed)
			(pads allowed)
			(copperpour not_allowed)
			(footprints allowed)
		)
		(placement
			(enabled no)
			(sheetname "")
		)
		(fill yes
			(thermal_gap 0.5)
			(thermal_bridge_width 0.5)
			(island_removal_mode 0)
		)
		(polygon
			(pts
				(arc
					(start 386.419598 -103.777796)
					(mid 385.716018 -103.777796)
					(end 386.419598 -103.777796)
				)
			)
		)
	)
	(zone
		(layers "B.Cu" "In11.Cu" "In13.Cu" "In15.Cu")
		(hatch none 0.5)
		(connect_pads
			(clearance 0)
		)
		(min_thickness 0.25)
		(keepout
			(tracks not_allowed)
			(vias allowed)
			(pads allowed)
			(copperpour not_allowed)
			(footprints allowed)
		)
		(placement
			(enabled no)
			(sheetname "")
		)
		(fill yes
			(thermal_gap 0.5)
			(thermal_bridge_width 0.5)
			(island_removal_mode 0)
		)
		(polygon
			(pts
				(arc
					(start 81.884012 -119.559324)
					(mid 81.180432 -119.559324)
					(end 81.884012 -119.559324)
				)
			)
		)
	)
	(zone
		(layers "B.Cu" "In11.Cu" "In13.Cu" "In15.Cu")
		(hatch none 0.5)
		(connect_pads
			(clearance 0)
		)
		(min_thickness 0.25)
		(keepout
			(tracks not_allowed)
			(vias allowed)
			(pads allowed)
			(copperpour not_allowed)
			(footprints allowed)
		)
		(placement
			(enabled no)
			(sheetname "")
		)
		(fill yes
			(thermal_gap 0.5)
			(thermal_bridge_width 0.5)
			(island_removal_mode 0)
		)
		(polygon
			(pts
				(arc
					(start 432.82616 -152.485852)
					(mid 432.12258 -152.485852)
					(end 432.82616 -152.485852)
				)
			)
		)
	)
	(zone
		(layers "B.Cu" "In11.Cu" "In13.Cu" "In15.Cu")
		(hatch none 0.5)
		(connect_pads
			(clearance 0)
		)
		(min_thickness 0.25)
		(keepout
			(tracks not_allowed)
			(vias allowed)
			(pads allowed)
			(copperpour not_allowed)
			(footprints allowed)
		)
		(placement
			(enabled no)
			(sheetname "")
		)
		(fill yes
			(thermal_gap 0.5)
			(thermal_bridge_width 0.5)
			(island_removal_mode 0)
		)
		(polygon
			(pts
				(arc
					(start 83.289648 -398.890236)
					(mid 82.530188 -398.890236)
					(end 83.289648 -398.890236)
				)
			)
		)
	)
	(zone
		(layers "B.Cu" "In11.Cu" "In13.Cu" "In15.Cu")
		(hatch none 0.5)
		(connect_pads
			(clearance 0)
		)
		(min_thickness 0.25)
		(keepout
			(tracks not_allowed)
			(vias allowed)
			(pads allowed)
			(copperpour not_allowed)
			(footprints allowed)
		)
		(placement
			(enabled no)
			(sheetname "")
		)
		(fill yes
			(thermal_gap 0.5)
			(thermal_bridge_width 0.5)
			(island_removal_mode 0)
		)
		(polygon
			(pts
				(arc
					(start 197.983856 -123.159266)
					(mid 197.280276 -123.159266)
					(end 197.983856 -123.159266)
				)
			)
		)
	)
	(zone
		(layers "B.Cu" "In13.Cu" "In15.Cu")
		(hatch none 0.5)
		(connect_pads
			(clearance 0)
		)
		(min_thickness 0.25)
		(keepout
			(tracks not_allowed)
			(vias allowed)
			(pads allowed)
			(copperpour not_allowed)
			(footprints allowed)
		)
		(placement
			(enabled no)
			(sheetname "")
		)
		(fill yes
			(thermal_gap 0.5)
			(thermal_bridge_width 0.5)
			(island_removal_mode 0)
		)
		(polygon
			(pts
				(arc
					(start 422.082722 -354.732082)
					(mid 421.379142 -354.732082)
					(end 422.082722 -354.732082)
				)
			)
		)
	)
	(zone
		(layers "B.Cu" "In13.Cu" "In15.Cu")
		(hatch none 0.5)
		(connect_pads
			(clearance 0)
		)
		(min_thickness 0.25)
		(keepout
			(tracks not_allowed)
			(vias allowed)
			(pads allowed)
			(copperpour not_allowed)
			(footprints allowed)
		)
		(placement
			(enabled no)
			(sheetname "")
		)
		(fill yes
			(thermal_gap 0.5)
			(thermal_bridge_width 0.5)
			(island_removal_mode 0)
		)
		(polygon
			(pts
				(arc
					(start 424.269662 -375.69013)
					(mid 423.510202 -375.69013)
					(end 424.269662 -375.69013)
				)
			)
		)
	)
	(zone
		(layers "B.Cu" "In13.Cu" "In15.Cu")
		(hatch none 0.5)
		(connect_pads
			(clearance 0)
		)
		(min_thickness 0.25)
		(keepout
			(tracks not_allowed)
			(vias allowed)
			(pads allowed)
			(copperpour not_allowed)
			(footprints allowed)
		)
		(placement
			(enabled no)
			(sheetname "")
		)
		(fill yes
			(thermal_gap 0.5)
			(thermal_bridge_width 0.5)
			(island_removal_mode 0)
		)
		(polygon
			(pts
				(arc
					(start 426.469556 -401.49018)
					(mid 425.710096 -401.49018)
					(end 426.469556 -401.49018)
				)
			)
		)
	)
	(zone
		(layers "B.Cu" "In13.Cu" "In15.Cu")
		(hatch none 0.5)
		(connect_pads
			(clearance 0)
		)
		(min_thickness 0.25)
		(keepout
			(tracks not_allowed)
			(vias allowed)
			(pads allowed)
			(copperpour not_allowed)
			(footprints allowed)
		)
		(placement
			(enabled no)
			(sheetname "")
		)
		(fill yes
			(thermal_gap 0.5)
			(thermal_bridge_width 0.5)
			(island_removal_mode 0)
		)
		(polygon
			(pts
				(arc
					(start 100.299012 -30.92069)
					(mid 99.595432 -30.92069)
					(end 100.299012 -30.92069)
				)
			)
		)
	)
	(zone
		(layers "B.Cu" "In13.Cu" "In15.Cu")
		(hatch none 0.5)
		(connect_pads
			(clearance 0)
		)
		(min_thickness 0.25)
		(keepout
			(tracks not_allowed)
			(vias allowed)
			(pads allowed)
			(copperpour not_allowed)
			(footprints allowed)
		)
		(placement
			(enabled no)
			(sheetname "")
		)
		(fill yes
			(thermal_gap 0.5)
			(thermal_bridge_width 0.5)
			(island_removal_mode 0)
		)
		(polygon
			(pts
				(arc
					(start 251.857002 -32.714184)
					(mid 251.153422 -32.714184)
					(end 251.857002 -32.714184)
				)
			)
		)
	)
	(zone
		(layers "B.Cu" "In13.Cu" "In15.Cu")
		(hatch none 0.5)
		(connect_pads
			(clearance 0)
		)
		(min_thickness 0.25)
		(keepout
			(tracks not_allowed)
			(vias allowed)
			(pads allowed)
			(copperpour not_allowed)
			(footprints allowed)
		)
		(placement
			(enabled no)
			(sheetname "")
		)
		(fill yes
			(thermal_gap 0.5)
			(thermal_bridge_width 0.5)
			(island_removal_mode 0)
		)
		(polygon
			(pts
				(arc
					(start 303.856898 -31.850584)
					(mid 303.153318 -31.850584)
					(end 303.856898 -31.850584)
				)
			)
		)
	)
	(zone
		(layers "B.Cu" "In13.Cu" "In15.Cu")
		(hatch none 0.5)
		(connect_pads
			(clearance 0)
		)
		(min_thickness 0.25)
		(keepout
			(tracks not_allowed)
			(vias allowed)
			(pads allowed)
			(copperpour not_allowed)
			(footprints allowed)
		)
		(placement
			(enabled no)
			(sheetname "")
		)
		(fill yes
			(thermal_gap 0.5)
			(thermal_bridge_width 0.5)
			(island_removal_mode 0)
		)
		(polygon
			(pts
				(arc
					(start 160.876234 -302.549814)
					(mid 160.223454 -302.549814)
					(end 160.876234 -302.549814)
				)
			)
		)
	)
	(zone
		(layers "B.Cu" "In13.Cu" "In15.Cu")
		(hatch none 0.5)
		(connect_pads
			(clearance 0)
		)
		(min_thickness 0.25)
		(keepout
			(tracks not_allowed)
			(vias allowed)
			(pads allowed)
			(copperpour not_allowed)
			(footprints allowed)
		)
		(placement
			(enabled no)
			(sheetname "")
		)
		(fill yes
			(thermal_gap 0.5)
			(thermal_bridge_width 0.5)
			(island_removal_mode 0)
		)
		(polygon
			(pts
				(arc
					(start 159.926274 -306.349908)
					(mid 159.273494 -306.349908)
					(end 159.926274 -306.349908)
				)
			)
		)
	)
	(zone
		(layers "B.Cu" "In13.Cu" "In15.Cu")
		(hatch none 0.5)
		(connect_pads
			(clearance 0)
		)
		(min_thickness 0.25)
		(keepout
			(tracks not_allowed)
			(vias allowed)
			(pads allowed)
			(copperpour not_allowed)
			(footprints allowed)
		)
		(placement
			(enabled no)
			(sheetname "")
		)
		(fill yes
			(thermal_gap 0.5)
			(thermal_bridge_width 0.5)
			(island_removal_mode 0)
		)
		(polygon
			(pts
				(arc
					(start 285.526226 -279.749504)
					(mid 284.873446 -279.749504)
					(end 285.526226 -279.749504)
				)
			)
		)
	)
	(zone
		(layers "B.Cu" "In13.Cu" "In15.Cu")
		(hatch none 0.5)
		(connect_pads
			(clearance 0)
		)
		(min_thickness 0.25)
		(keepout
			(tracks not_allowed)
			(vias allowed)
			(pads allowed)
			(copperpour not_allowed)
			(footprints allowed)
		)
		(placement
			(enabled no)
			(sheetname "")
		)
		(fill yes
			(thermal_gap 0.5)
			(thermal_bridge_width 0.5)
			(island_removal_mode 0)
		)
		(polygon
			(pts
				(arc
					(start 422.082722 -345.465146)
					(mid 421.379142 -345.465146)
					(end 422.082722 -345.465146)
				)
			)
		)
	)
	(zone
		(layers "B.Cu" "In13.Cu" "In15.Cu")
		(hatch none 0.5)
		(connect_pads
			(clearance 0)
		)
		(min_thickness 0.25)
		(keepout
			(tracks not_allowed)
			(vias allowed)
			(pads allowed)
			(copperpour not_allowed)
			(footprints allowed)
		)
		(placement
			(enabled no)
			(sheetname "")
		)
		(fill yes
			(thermal_gap 0.5)
			(thermal_bridge_width 0.5)
			(island_removal_mode 0)
		)
		(polygon
			(pts
				(arc
					(start 284.576266 -277.849838)
					(mid 283.923486 -277.849838)
					(end 284.576266 -277.849838)
				)
			)
		)
	)
	(zone
		(layers "B.Cu" "In13.Cu" "In15.Cu")
		(hatch none 0.5)
		(connect_pads
			(clearance 0)
		)
		(min_thickness 0.25)
		(keepout
			(tracks not_allowed)
			(vias allowed)
			(pads allowed)
			(copperpour not_allowed)
			(footprints allowed)
		)
		(placement
			(enabled no)
			(sheetname "")
		)
		(fill yes
			(thermal_gap 0.5)
			(thermal_bridge_width 0.5)
			(island_removal_mode 0)
		)
		(polygon
			(pts
				(arc
					(start 275.330412 -345.465146)
					(mid 274.626832 -345.465146)
					(end 275.330412 -345.465146)
				)
			)
		)
	)
	(zone
		(layers "B.Cu" "In13.Cu" "In15.Cu")
		(hatch none 0.5)
		(connect_pads
			(clearance 0)
		)
		(min_thickness 0.25)
		(keepout
			(tracks not_allowed)
			(vias allowed)
			(pads allowed)
			(copperpour not_allowed)
			(footprints allowed)
		)
		(placement
			(enabled no)
			(sheetname "")
		)
		(fill yes
			(thermal_gap 0.5)
			(thermal_bridge_width 0.5)
			(island_removal_mode 0)
		)
		(polygon
			(pts
				(arc
					(start 158.976314 -307.299868)
					(mid 158.323534 -307.299868)
					(end 158.976314 -307.299868)
				)
			)
		)
	)
	(zone
		(layers "B.Cu" "In13.Cu" "In15.Cu")
		(hatch none 0.5)
		(connect_pads
			(clearance 0)
		)
		(min_thickness 0.25)
		(keepout
			(tracks not_allowed)
			(vias allowed)
			(pads allowed)
			(copperpour not_allowed)
			(footprints allowed)
		)
		(placement
			(enabled no)
			(sheetname "")
		)
		(fill yes
			(thermal_gap 0.5)
			(thermal_bridge_width 0.5)
			(island_removal_mode 0)
		)
		(polygon
			(pts
				(arc
					(start 158.976314 -313.949842)
					(mid 158.323534 -313.949842)
					(end 158.976314 -313.949842)
				)
			)
		)
	)
	(zone
		(layers "B.Cu" "In13.Cu" "In15.Cu")
		(hatch none 0.5)
		(connect_pads
			(clearance 0)
		)
		(min_thickness 0.25)
		(keepout
			(tracks not_allowed)
			(vias allowed)
			(pads allowed)
			(copperpour not_allowed)
			(footprints allowed)
		)
		(placement
			(enabled no)
			(sheetname "")
		)
		(fill yes
			(thermal_gap 0.5)
			(thermal_bridge_width 0.5)
			(island_removal_mode 0)
		)
		(polygon
			(pts
				(arc
					(start 426.055282 -351.611438)
					(mid 425.351702 -351.611438)
					(end 426.055282 -351.611438)
				)
			)
		)
	)
	(zone
		(layers "B.Cu" "In13.Cu" "In15.Cu")
		(hatch none 0.5)
		(connect_pads
			(clearance 0)
		)
		(min_thickness 0.25)
		(keepout
			(tracks not_allowed)
			(vias allowed)
			(pads allowed)
			(copperpour not_allowed)
			(footprints allowed)
		)
		(placement
			(enabled no)
			(sheetname "")
		)
		(fill yes
			(thermal_gap 0.5)
			(thermal_bridge_width 0.5)
			(island_removal_mode 0)
		)
		(polygon
			(pts
				(arc
					(start 57.126124 -280.699718)
					(mid 56.473344 -280.699718)
					(end 57.126124 -280.699718)
				)
			)
		)
	)
	(zone
		(layers "B.Cu" "In13.Cu" "In15.Cu")
		(hatch none 0.5)
		(connect_pads
			(clearance 0)
		)
		(min_thickness 0.25)
		(keepout
			(tracks not_allowed)
			(vias allowed)
			(pads allowed)
			(copperpour not_allowed)
			(footprints allowed)
		)
		(placement
			(enabled no)
			(sheetname "")
		)
		(fill yes
			(thermal_gap 0.5)
			(thermal_bridge_width 0.5)
			(island_removal_mode 0)
		)
		(polygon
			(pts
				(arc
					(start 22.793198 -351.611438)
					(mid 22.089618 -351.611438)
					(end 22.793198 -351.611438)
				)
			)
		)
	)
	(zone
		(layers "B.Cu" "In13.Cu" "In15.Cu")
		(hatch none 0.5)
		(connect_pads
			(clearance 0)
		)
		(min_thickness 0.25)
		(keepout
			(tracks not_allowed)
			(vias allowed)
			(pads allowed)
			(copperpour not_allowed)
			(footprints allowed)
		)
		(placement
			(enabled no)
			(sheetname "")
		)
		(fill yes
			(thermal_gap 0.5)
			(thermal_bridge_width 0.5)
			(island_removal_mode 0)
		)
		(polygon
			(pts
				(arc
					(start 37.089842 -397.790162)
					(mid 36.330382 -397.790162)
					(end 37.089842 -397.790162)
				)
			)
		)
	)
	(zone
		(layers "B.Cu" "In13.Cu" "In15.Cu")
		(hatch none 0.5)
		(connect_pads
			(clearance 0)
		)
		(min_thickness 0.25)
		(keepout
			(tracks not_allowed)
			(vias allowed)
			(pads allowed)
			(copperpour not_allowed)
			(footprints allowed)
		)
		(placement
			(enabled no)
			(sheetname "")
		)
		(fill yes
			(thermal_gap 0.5)
			(thermal_bridge_width 0.5)
			(island_removal_mode 0)
		)
		(polygon
			(pts
				(arc
					(start 161.826448 -279.749504)
					(mid 161.173668 -279.749504)
					(end 161.826448 -279.749504)
				)
			)
		)
	)
	(zone
		(layers "B.Cu" "In13.Cu" "In15.Cu")
		(hatch none 0.5)
		(connect_pads
			(clearance 0)
		)
		(min_thickness 0.25)
		(keepout
			(tracks not_allowed)
			(vias allowed)
			(pads allowed)
			(copperpour not_allowed)
			(footprints allowed)
		)
		(placement
			(enabled no)
			(sheetname "")
		)
		(fill yes
			(thermal_gap 0.5)
			(thermal_bridge_width 0.5)
			(island_removal_mode 0)
		)
		(polygon
			(pts
				(arc
					(start 415.864802 -345.465146)
					(mid 415.161222 -345.465146)
					(end 415.864802 -345.465146)
				)
			)
		)
	)
	(zone
		(layers "B.Cu" "In13.Cu" "In15.Cu")
		(hatch none 0.5)
		(connect_pads
			(clearance 0)
		)
		(min_thickness 0.25)
		(keepout
			(tracks not_allowed)
			(vias allowed)
			(pads allowed)
			(copperpour not_allowed)
			(footprints allowed)
		)
		(placement
			(enabled no)
			(sheetname "")
		)
		(fill yes
			(thermal_gap 0.5)
			(thermal_bridge_width 0.5)
			(island_removal_mode 0)
		)
		(polygon
			(pts
				(arc
					(start 39.201598 -342.439498)
					(mid 38.498018 -342.439498)
					(end 39.201598 -342.439498)
				)
			)
		)
	)
	(zone
		(layers "B.Cu" "In13.Cu" "In15.Cu")
		(hatch none 0.5)
		(connect_pads
			(clearance 0)
		)
		(min_thickness 0.25)
		(keepout
			(tracks not_allowed)
			(vias allowed)
			(pads allowed)
			(copperpour not_allowed)
			(footprints allowed)
		)
		(placement
			(enabled no)
			(sheetname "")
		)
		(fill yes
			(thermal_gap 0.5)
			(thermal_bridge_width 0.5)
			(island_removal_mode 0)
		)
		(polygon
			(pts
				(arc
					(start 292.269672 -396.49019)
					(mid 291.510212 -396.49019)
					(end 292.269672 -396.49019)
				)
			)
		)
	)
	(zone
		(layers "B.Cu" "In13.Cu" "In15.Cu")
		(hatch none 0.5)
		(connect_pads
			(clearance 0)
		)
		(min_thickness 0.25)
		(keepout
			(tracks not_allowed)
			(vias allowed)
			(pads allowed)
			(copperpour not_allowed)
			(footprints allowed)
		)
		(placement
			(enabled no)
			(sheetname "")
		)
		(fill yes
			(thermal_gap 0.5)
			(thermal_bridge_width 0.5)
			(island_removal_mode 0)
		)
		(polygon
			(pts
				(arc
					(start 59.026298 -280.699718)
					(mid 58.373518 -280.699718)
					(end 59.026298 -280.699718)
				)
			)
		)
	)
	(zone
		(layers "B.Cu" "In13.Cu" "In15.Cu")
		(hatch none 0.5)
		(connect_pads
			(clearance 0)
		)
		(min_thickness 0.25)
		(keepout
			(tracks not_allowed)
			(vias allowed)
			(pads allowed)
			(copperpour not_allowed)
			(footprints allowed)
		)
		(placement
			(enabled no)
			(sheetname "")
		)
		(fill yes
			(thermal_gap 0.5)
			(thermal_bridge_width 0.5)
			(island_removal_mode 0)
		)
		(polygon
			(pts
				(arc
					(start 161.757106 -31.850584)
					(mid 161.053526 -31.850584)
					(end 161.757106 -31.850584)
				)
			)
		)
	)
	(zone
		(layers "B.Cu" "In13.Cu" "In15.Cu")
		(hatch none 0.5)
		(connect_pads
			(clearance 0)
		)
		(min_thickness 0.25)
		(keepout
			(tracks not_allowed)
			(vias allowed)
			(pads allowed)
			(copperpour not_allowed)
			(footprints allowed)
		)
		(placement
			(enabled no)
			(sheetname "")
		)
		(fill yes
			(thermal_gap 0.5)
			(thermal_bridge_width 0.5)
			(island_removal_mode 0)
		)
		(polygon
			(pts
				(arc
					(start 287.86963 -370.489988)
					(mid 287.11017 -370.489988)
					(end 287.86963 -370.489988)
				)
			)
		)
	)
	(zone
		(layers "B.Cu" "In13.Cu" "In15.Cu")
		(hatch none 0.5)
		(connect_pads
			(clearance 0)
		)
		(min_thickness 0.25)
		(keepout
			(tracks not_allowed)
			(vias allowed)
			(pads allowed)
			(copperpour not_allowed)
			(footprints allowed)
		)
		(placement
			(enabled no)
			(sheetname "")
		)
		(fill yes
			(thermal_gap 0.5)
			(thermal_bridge_width 0.5)
			(island_removal_mode 0)
		)
		(polygon
			(pts
				(arc
					(start 51.637438 -345.465146)
					(mid 50.933858 -345.465146)
					(end 51.637438 -345.465146)
				)
			)
		)
	)
	(zone
		(layers "B.Cu" "In13.Cu" "In15.Cu")
		(hatch none 0.5)
		(connect_pads
			(clearance 0)
		)
		(min_thickness 0.25)
		(keepout
			(tracks not_allowed)
			(vias allowed)
			(pads allowed)
			(copperpour not_allowed)
			(footprints allowed)
		)
		(placement
			(enabled no)
			(sheetname "")
		)
		(fill yes
			(thermal_gap 0.5)
			(thermal_bridge_width 0.5)
			(island_removal_mode 0)
		)
		(polygon
			(pts
				(arc
					(start 294.469566 -371.590062)
					(mid 293.710106 -371.590062)
					(end 294.469566 -371.590062)
				)
			)
		)
	)
	(zone
		(layers "B.Cu" "In13.Cu" "In15.Cu")
		(hatch none 0.5)
		(connect_pads
			(clearance 0)
		)
		(min_thickness 0.25)
		(keepout
			(tracks not_allowed)
			(vias allowed)
			(pads allowed)
			(copperpour not_allowed)
			(footprints allowed)
		)
		(placement
			(enabled no)
			(sheetname "")
		)
		(fill yes
			(thermal_gap 0.5)
			(thermal_bridge_width 0.5)
			(island_removal_mode 0)
		)
		(polygon
			(pts
				(arc
					(start 394.97635 -278.799798)
					(mid 394.32357 -278.799798)
					(end 394.97635 -278.799798)
				)
			)
		)
	)
	(zone
		(layers "B.Cu" "In13.Cu" "In15.Cu")
		(hatch none 0.5)
		(connect_pads
			(clearance 0)
		)
		(min_thickness 0.25)
		(keepout
			(tracks not_allowed)
			(vias allowed)
			(pads allowed)
			(copperpour not_allowed)
			(footprints allowed)
		)
		(placement
			(enabled no)
			(sheetname "")
		)
		(fill yes
			(thermal_gap 0.5)
			(thermal_bridge_width 0.5)
			(island_removal_mode 0)
		)
		(polygon
			(pts
				(arc
					(start 306.426108 -311.099962)
					(mid 305.773328 -311.099962)
					(end 306.426108 -311.099962)
				)
			)
		)
	)
	(zone
		(layers "B.Cu" "In13.Cu" "In15.Cu")
		(hatch none 0.5)
		(connect_pads
			(clearance 0)
		)
		(min_thickness 0.25)
		(keepout
			(tracks not_allowed)
			(vias allowed)
			(pads allowed)
			(copperpour not_allowed)
			(footprints allowed)
		)
		(placement
			(enabled no)
			(sheetname "")
		)
		(fill yes
			(thermal_gap 0.5)
			(thermal_bridge_width 0.5)
			(island_removal_mode 0)
		)
		(polygon
			(pts
				(arc
					(start 422.069514 -376.790204)
					(mid 421.310054 -376.790204)
					(end 422.069514 -376.790204)
				)
			)
		)
	)
	(zone
		(layers "B.Cu" "In13.Cu" "In15.Cu")
		(hatch none 0.5)
		(connect_pads
			(clearance 0)
		)
		(min_thickness 0.25)
		(keepout
			(tracks not_allowed)
			(vias allowed)
			(pads allowed)
			(copperpour not_allowed)
			(footprints allowed)
		)
		(placement
			(enabled no)
			(sheetname "")
		)
		(fill yes
			(thermal_gap 0.5)
			(thermal_bridge_width 0.5)
			(island_removal_mode 0)
		)
		(polygon
			(pts
				(arc
					(start 20.547838 -345.465146)
					(mid 19.844258 -345.465146)
					(end 20.547838 -345.465146)
				)
			)
		)
	)
	(zone
		(layers "B.Cu" "In13.Cu" "In15.Cu")
		(hatch none 0.5)
		(connect_pads
			(clearance 0)
		)
		(min_thickness 0.25)
		(keepout
			(tracks not_allowed)
			(vias allowed)
			(pads allowed)
			(copperpour not_allowed)
			(footprints allowed)
		)
		(placement
			(enabled no)
			(sheetname "")
		)
		(fill yes
			(thermal_gap 0.5)
			(thermal_bridge_width 0.5)
			(island_removal_mode 0)
		)
		(polygon
			(pts
				(arc
					(start 48.299116 -34.520886)
					(mid 47.595536 -34.520886)
					(end 48.299116 -34.520886)
				)
			)
		)
	)
	(zone
		(layers "B.Cu" "In13.Cu" "In15.Cu")
		(hatch none 0.5)
		(connect_pads
			(clearance 0)
		)
		(min_thickness 0.25)
		(keepout
			(tracks not_allowed)
			(vias allowed)
			(pads allowed)
			(copperpour not_allowed)
			(footprints allowed)
		)
		(placement
			(enabled no)
			(sheetname "")
		)
		(fill yes
			(thermal_gap 0.5)
			(thermal_bridge_width 0.5)
			(island_removal_mode 0)
		)
		(polygon
			(pts
				(arc
					(start 187.757054 -31.850584)
					(mid 187.053474 -31.850584)
					(end 187.757054 -31.850584)
				)
			)
		)
	)
	(zone
		(layers "B.Cu" "In13.Cu" "In15.Cu")
		(hatch none 0.5)
		(connect_pads
			(clearance 0)
		)
		(min_thickness 0.25)
		(keepout
			(tracks not_allowed)
			(vias allowed)
			(pads allowed)
			(copperpour not_allowed)
			(footprints allowed)
		)
		(placement
			(enabled no)
			(sheetname "")
		)
		(fill yes
			(thermal_gap 0.5)
			(thermal_bridge_width 0.5)
			(island_removal_mode 0)
		)
		(polygon
			(pts
				(arc
					(start 174.973742 -354.732082)
					(mid 174.270162 -354.732082)
					(end 174.973742 -354.732082)
				)
			)
		)
	)
	(zone
		(layers "B.Cu" "In13.Cu" "In15.Cu")
		(hatch none 0.5)
		(connect_pads
			(clearance 0)
		)
		(min_thickness 0.25)
		(keepout
			(tracks not_allowed)
			(vias allowed)
			(pads allowed)
			(copperpour not_allowed)
			(footprints allowed)
		)
		(placement
			(enabled no)
			(sheetname "")
		)
		(fill yes
			(thermal_gap 0.5)
			(thermal_bridge_width 0.5)
			(island_removal_mode 0)
		)
		(polygon
			(pts
				(arc
					(start 405.426164 -279.749504)
					(mid 404.773384 -279.749504)
					(end 405.426164 -279.749504)
				)
			)
		)
	)
	(zone
		(layers "B.Cu" "In13.Cu" "In15.Cu")
		(hatch none 0.5)
		(connect_pads
			(clearance 0)
		)
		(min_thickness 0.25)
		(keepout
			(tracks not_allowed)
			(vias allowed)
			(pads allowed)
			(copperpour not_allowed)
			(footprints allowed)
		)
		(placement
			(enabled no)
			(sheetname "")
		)
		(fill yes
			(thermal_gap 0.5)
			(thermal_bridge_width 0.5)
			(island_removal_mode 0)
		)
		(polygon
			(pts
				(arc
					(start 422.082722 -357.75773)
					(mid 421.379142 -357.75773)
					(end 422.082722 -357.75773)
				)
			)
		)
	)
	(zone
		(layers "B.Cu" "In13.Cu" "In15.Cu")
		(hatch none 0.5)
		(connect_pads
			(clearance 0)
		)
		(min_thickness 0.25)
		(keepout
			(tracks not_allowed)
			(vias allowed)
			(pads allowed)
			(copperpour not_allowed)
			(footprints allowed)
		)
		(placement
			(enabled no)
			(sheetname "")
		)
		(fill yes
			(thermal_gap 0.5)
			(thermal_bridge_width 0.5)
			(island_removal_mode 0)
		)
		(polygon
			(pts
				(arc
					(start 164.68979 -400.390106)
					(mid 163.93033 -400.390106)
					(end 164.68979 -400.390106)
				)
			)
		)
	)
	(zone
		(layers "B.Cu" "In13.Cu" "In15.Cu")
		(hatch none 0.5)
		(connect_pads
			(clearance 0)
		)
		(min_thickness 0.25)
		(keepout
			(tracks not_allowed)
			(vias allowed)
			(pads allowed)
			(copperpour not_allowed)
			(footprints allowed)
		)
		(placement
			(enabled no)
			(sheetname "")
		)
		(fill yes
			(thermal_gap 0.5)
			(thermal_bridge_width 0.5)
			(island_removal_mode 0)
		)
		(polygon
			(pts
				(arc
					(start 290.069524 -398.890236)
					(mid 289.310064 -398.890236)
					(end 290.069524 -398.890236)
				)
			)
		)
	)
	(zone
		(layers "B.Cu" "In13.Cu" "In15.Cu")
		(hatch none 0.5)
		(connect_pads
			(clearance 0)
		)
		(min_thickness 0.25)
		(keepout
			(tracks not_allowed)
			(vias allowed)
			(pads allowed)
			(copperpour not_allowed)
			(footprints allowed)
		)
		(placement
			(enabled no)
			(sheetname "")
		)
		(fill yes
			(thermal_gap 0.5)
			(thermal_bridge_width 0.5)
			(island_removal_mode 0)
		)
		(polygon
			(pts
				(arc
					(start 51.426364 -279.749504)
					(mid 50.773584 -279.749504)
					(end 51.426364 -279.749504)
				)
			)
		)
	)
	(zone
		(layers "B.Cu" "In13.Cu" "In15.Cu")
		(hatch none 0.5)
		(connect_pads
			(clearance 0)
		)
		(min_thickness 0.25)
		(keepout
			(tracks not_allowed)
			(vias allowed)
			(pads allowed)
			(copperpour not_allowed)
			(footprints allowed)
		)
		(placement
			(enabled no)
			(sheetname "")
		)
		(fill yes
			(thermal_gap 0.5)
			(thermal_bridge_width 0.5)
			(island_removal_mode 0)
		)
		(polygon
			(pts
				(arc
					(start 422.946322 -345.465146)
					(mid 422.242742 -345.465146)
					(end 422.946322 -345.465146)
				)
			)
		)
	)
	(zone
		(layers "B.Cu" "In13.Cu" "In15.Cu")
		(hatch none 0.5)
		(connect_pads
			(clearance 0)
		)
		(min_thickness 0.25)
		(keepout
			(tracks not_allowed)
			(vias allowed)
			(pads allowed)
			(copperpour not_allowed)
			(footprints allowed)
		)
		(placement
			(enabled no)
			(sheetname "")
		)
		(fill yes
			(thermal_gap 0.5)
			(thermal_bridge_width 0.5)
			(island_removal_mode 0)
		)
		(polygon
			(pts
				(arc
					(start 413.619442 -348.58579)
					(mid 412.915862 -348.58579)
					(end 413.619442 -348.58579)
				)
			)
		)
	)
	(zone
		(layers "B.Cu" "In13.Cu" "In15.Cu")
		(hatch none 0.5)
		(connect_pads
			(clearance 0)
		)
		(min_thickness 0.25)
		(keepout
			(tracks not_allowed)
			(vias allowed)
			(pads allowed)
			(copperpour not_allowed)
			(footprints allowed)
		)
		(placement
			(enabled no)
			(sheetname "")
		)
		(fill yes
			(thermal_gap 0.5)
			(thermal_bridge_width 0.5)
			(island_removal_mode 0)
		)
		(polygon
			(pts
				(arc
					(start 75.17638 -312.999882)
					(mid 74.5236 -312.999882)
					(end 75.17638 -312.999882)
				)
			)
		)
	)
	(zone
		(layers "B.Cu" "In13.Cu" "In15.Cu")
		(hatch none 0.5)
		(connect_pads
			(clearance 0)
		)
		(min_thickness 0.25)
		(keepout
			(tracks not_allowed)
			(vias allowed)
			(pads allowed)
			(copperpour not_allowed)
			(footprints allowed)
		)
		(placement
			(enabled no)
			(sheetname "")
		)
		(fill yes
			(thermal_gap 0.5)
			(thermal_bridge_width 0.5)
			(island_removal_mode 0)
		)
		(polygon
			(pts
				(arc
					(start 26.765758 -354.732082)
					(mid 26.062178 -354.732082)
					(end 26.765758 -354.732082)
				)
			)
		)
	)
	(zone
		(layers "B.Cu" "In13.Cu" "In15.Cu")
		(hatch none 0.5)
		(connect_pads
			(clearance 0)
		)
		(min_thickness 0.25)
		(keepout
			(tracks not_allowed)
			(vias allowed)
			(pads allowed)
			(copperpour not_allowed)
			(footprints allowed)
		)
		(placement
			(enabled no)
			(sheetname "")
		)
		(fill yes
			(thermal_gap 0.5)
			(thermal_bridge_width 0.5)
			(island_removal_mode 0)
		)
		(polygon
			(pts
				(arc
					(start 160.876234 -304.449734)
					(mid 160.223454 -304.449734)
					(end 160.876234 -304.449734)
				)
			)
		)
	)
	(zone
		(layers "B.Cu" "In13.Cu" "In15.Cu")
		(hatch none 0.5)
		(connect_pads
			(clearance 0)
		)
		(min_thickness 0.25)
		(keepout
			(tracks not_allowed)
			(vias allowed)
			(pads allowed)
			(copperpour not_allowed)
			(footprints allowed)
		)
		(placement
			(enabled no)
			(sheetname "")
		)
		(fill yes
			(thermal_gap 0.5)
			(thermal_bridge_width 0.5)
			(island_removal_mode 0)
		)
		(polygon
			(pts
				(arc
					(start 175.689768 -402.790152)
					(mid 174.930308 -402.790152)
					(end 175.689768 -402.790152)
				)
			)
		)
	)
	(zone
		(layers "B.Cu" "In13.Cu" "In15.Cu")
		(hatch none 0.5)
		(connect_pads
			(clearance 0)
		)
		(min_thickness 0.25)
		(keepout
			(tracks not_allowed)
			(vias allowed)
			(pads allowed)
			(copperpour not_allowed)
			(footprints allowed)
		)
		(placement
			(enabled no)
			(sheetname "")
		)
		(fill yes
			(thermal_gap 0.5)
			(thermal_bridge_width 0.5)
			(island_removal_mode 0)
		)
		(polygon
			(pts
				(arc
					(start 76.12634 -308.249828)
					(mid 75.47356 -308.249828)
					(end 76.12634 -308.249828)
				)
			)
		)
	)
	(zone
		(layers "B.Cu" "In13.Cu" "In15.Cu")
		(hatch none 0.5)
		(connect_pads
			(clearance 0)
		)
		(min_thickness 0.25)
		(keepout
			(tracks not_allowed)
			(vias allowed)
			(pads allowed)
			(copperpour not_allowed)
			(footprints allowed)
		)
		(placement
			(enabled no)
			(sheetname "")
		)
		(fill yes
			(thermal_gap 0.5)
			(thermal_bridge_width 0.5)
			(island_removal_mode 0)
		)
		(polygon
			(pts
				(arc
					(start 424.269662 -374.390158)
					(mid 423.510202 -374.390158)
					(end 424.269662 -374.390158)
				)
			)
		)
	)
	(zone
		(layers "B.Cu" "In13.Cu" "In15.Cu")
		(hatch none 0.5)
		(connect_pads
			(clearance 0)
		)
		(min_thickness 0.25)
		(keepout
			(tracks not_allowed)
			(vias allowed)
			(pads allowed)
			(copperpour not_allowed)
			(footprints allowed)
		)
		(placement
			(enabled no)
			(sheetname "")
		)
		(fill yes
			(thermal_gap 0.5)
			(thermal_bridge_width 0.5)
			(island_removal_mode 0)
		)
		(polygon
			(pts
				(arc
					(start 168.755822 -345.465146)
					(mid 168.052242 -345.465146)
					(end 168.755822 -345.465146)
				)
			)
		)
	)
	(zone
		(layers "B.Cu" "In13.Cu" "In15.Cu")
		(hatch none 0.5)
		(connect_pads
			(clearance 0)
		)
		(min_thickness 0.25)
		(keepout
			(tracks not_allowed)
			(vias allowed)
			(pads allowed)
			(copperpour not_allowed)
			(footprints allowed)
		)
		(placement
			(enabled no)
			(sheetname "")
		)
		(fill yes
			(thermal_gap 0.5)
			(thermal_bridge_width 0.5)
			(island_removal_mode 0)
		)
		(polygon
			(pts
				(arc
					(start 42.310558 -351.611438)
					(mid 41.606978 -351.611438)
					(end 42.310558 -351.611438)
				)
			)
		)
	)
	(zone
		(layers "B.Cu" "In13.Cu" "In15.Cu")
		(hatch none 0.5)
		(connect_pads
			(clearance 0)
		)
		(min_thickness 0.25)
		(keepout
			(tracks not_allowed)
			(vias allowed)
			(pads allowed)
			(copperpour not_allowed)
			(footprints allowed)
		)
		(placement
			(enabled no)
			(sheetname "")
		)
		(fill yes
			(thermal_gap 0.5)
			(thermal_bridge_width 0.5)
			(island_removal_mode 0)
		)
		(polygon
			(pts
				(arc
					(start 288.376106 -278.799798)
					(mid 287.723326 -278.799798)
					(end 288.376106 -278.799798)
				)
			)
		)
	)
	(zone
		(layers "B.Cu" "In13.Cu" "In15.Cu")
		(hatch none 0.5)
		(connect_pads
			(clearance 0)
		)
		(min_thickness 0.25)
		(keepout
			(tracks not_allowed)
			(vias allowed)
			(pads allowed)
			(copperpour not_allowed)
			(footprints allowed)
		)
		(placement
			(enabled no)
			(sheetname "")
		)
		(fill yes
			(thermal_gap 0.5)
			(thermal_bridge_width 0.5)
			(island_removal_mode 0)
		)
		(polygon
			(pts
				(arc
					(start 166.889684 -402.790152)
					(mid 166.130224 -402.790152)
					(end 166.889684 -402.790152)
				)
			)
		)
	)
	(zone
		(layers "B.Cu" "In13.Cu" "In15.Cu")
		(hatch none 0.5)
		(connect_pads
			(clearance 0)
		)
		(min_thickness 0.25)
		(keepout
			(tracks not_allowed)
			(vias allowed)
			(pads allowed)
			(copperpour not_allowed)
			(footprints allowed)
		)
		(placement
			(enabled no)
			(sheetname "")
		)
		(fill yes
			(thermal_gap 0.5)
			(thermal_bridge_width 0.5)
			(island_removal_mode 0)
		)
		(polygon
			(pts
				(arc
					(start 39.201598 -357.75773)
					(mid 38.498018 -357.75773)
					(end 39.201598 -357.75773)
				)
			)
		)
	)
	(zone
		(layers "B.Cu" "In13.Cu" "In15.Cu")
		(hatch none 0.5)
		(connect_pads
			(clearance 0)
		)
		(min_thickness 0.25)
		(keepout
			(tracks not_allowed)
			(vias allowed)
			(pads allowed)
			(copperpour not_allowed)
			(footprints allowed)
		)
		(placement
			(enabled no)
			(sheetname "")
		)
		(fill yes
			(thermal_gap 0.5)
			(thermal_bridge_width 0.5)
			(island_removal_mode 0)
		)
		(polygon
			(pts
				(arc
					(start 445.956944 -28.250642)
					(mid 445.253364 -28.250642)
					(end 445.956944 -28.250642)
				)
			)
		)
	)
	(zone
		(layers "B.Cu" "In13.Cu" "In15.Cu")
		(hatch none 0.5)
		(connect_pads
			(clearance 0)
		)
		(min_thickness 0.25)
		(keepout
			(tracks not_allowed)
			(vias allowed)
			(pads allowed)
			(copperpour not_allowed)
			(footprints allowed)
		)
		(placement
			(enabled no)
			(sheetname "")
		)
		(fill yes
			(thermal_gap 0.5)
			(thermal_bridge_width 0.5)
			(island_removal_mode 0)
		)
		(polygon
			(pts
				(arc
					(start 71.656956 -32.714184)
					(mid 70.953376 -32.714184)
					(end 71.656956 -32.714184)
				)
			)
		)
	)
	(zone
		(layers "B.Cu" "In13.Cu" "In15.Cu")
		(hatch none 0.5)
		(connect_pads
			(clearance 0)
		)
		(min_thickness 0.25)
		(keepout
			(tracks not_allowed)
			(vias allowed)
			(pads allowed)
			(copperpour not_allowed)
			(footprints allowed)
		)
		(placement
			(enabled no)
			(sheetname "")
		)
		(fill yes
			(thermal_gap 0.5)
			(thermal_bridge_width 0.5)
			(island_removal_mode 0)
		)
		(polygon
			(pts
				(arc
					(start 306.499006 -30.92069)
					(mid 305.795426 -30.92069)
					(end 306.499006 -30.92069)
				)
			)
		)
	)
	(zone
		(layers "B.Cu" "In13.Cu" "In15.Cu")
		(hatch none 0.5)
		(connect_pads
			(clearance 0)
		)
		(min_thickness 0.25)
		(keepout
			(tracks not_allowed)
			(vias allowed)
			(pads allowed)
			(copperpour not_allowed)
			(footprints allowed)
		)
		(placement
			(enabled no)
			(sheetname "")
		)
		(fill yes
			(thermal_gap 0.5)
			(thermal_bridge_width 0.5)
			(island_removal_mode 0)
		)
		(polygon
			(pts
				(arc
					(start 388.326376 -312.049922)
					(mid 387.673596 -312.049922)
					(end 388.326376 -312.049922)
				)
			)
		)
	)
	(zone
		(layers "B.Cu" "In13.Cu" "In15.Cu")
		(hatch none 0.5)
		(connect_pads
			(clearance 0)
		)
		(min_thickness 0.25)
		(keepout
			(tracks not_allowed)
			(vias allowed)
			(pads allowed)
			(copperpour not_allowed)
			(footprints allowed)
		)
		(placement
			(enabled no)
			(sheetname "")
		)
		(fill yes
			(thermal_gap 0.5)
			(thermal_bridge_width 0.5)
			(island_removal_mode 0)
		)
		(polygon
			(pts
				(arc
					(start 433.069492 -374.390158)
					(mid 432.310032 -374.390158)
					(end 433.069492 -374.390158)
				)
			)
		)
	)
	(zone
		(layers "B.Cu" "In13.Cu" "In15.Cu")
		(hatch none 0.5)
		(connect_pads
			(clearance 0)
		)
		(min_thickness 0.25)
		(keepout
			(tracks not_allowed)
			(vias allowed)
			(pads allowed)
			(copperpour not_allowed)
			(footprints allowed)
		)
		(placement
			(enabled no)
			(sheetname "")
		)
		(fill yes
			(thermal_gap 0.5)
			(thermal_bridge_width 0.5)
			(island_removal_mode 0)
		)
		(polygon
			(pts
				(arc
					(start 290.011612 -348.58579)
					(mid 289.308032 -348.58579)
					(end 290.011612 -348.58579)
				)
			)
		)
	)
	(zone
		(layers "B.Cu" "In13.Cu" "In15.Cu")
		(hatch none 0.5)
		(connect_pads
			(clearance 0)
		)
		(min_thickness 0.25)
		(keepout
			(tracks not_allowed)
			(vias allowed)
			(pads allowed)
			(copperpour not_allowed)
			(footprints allowed)
		)
		(placement
			(enabled no)
			(sheetname "")
		)
		(fill yes
			(thermal_gap 0.5)
			(thermal_bridge_width 0.5)
			(island_removal_mode 0)
		)
		(polygon
			(pts
				(arc
					(start 409.646882 -342.439498)
					(mid 408.943302 -342.439498)
					(end 409.646882 -342.439498)
				)
			)
		)
	)
	(zone
		(layers "B.Cu" "In13.Cu" "In15.Cu")
		(hatch none 0.5)
		(connect_pads
			(clearance 0)
		)
		(min_thickness 0.25)
		(keepout
			(tracks not_allowed)
			(vias allowed)
			(pads allowed)
			(copperpour not_allowed)
			(footprints allowed)
		)
		(placement
			(enabled no)
			(sheetname "")
		)
		(fill yes
			(thermal_gap 0.5)
			(thermal_bridge_width 0.5)
			(island_removal_mode 0)
		)
		(polygon
			(pts
				(arc
					(start 156.126434 -311.099962)
					(mid 155.473654 -311.099962)
					(end 156.126434 -311.099962)
				)
			)
		)
	)
	(zone
		(layers "B.Cu" "In13.Cu" "In15.Cu")
		(hatch none 0.5)
		(connect_pads
			(clearance 0)
		)
		(min_thickness 0.25)
		(keepout
			(tracks not_allowed)
			(vias allowed)
			(pads allowed)
			(copperpour not_allowed)
			(footprints allowed)
		)
		(placement
			(enabled no)
			(sheetname "")
		)
		(fill yes
			(thermal_gap 0.5)
			(thermal_bridge_width 0.5)
			(island_removal_mode 0)
		)
		(polygon
			(pts
				(arc
					(start 430.869598 -375.490232)
					(mid 430.110138 -375.490232)
					(end 430.869598 -375.490232)
				)
			)
		)
	)
	(zone
		(layers "B.Cu" "In13.Cu" "In15.Cu")
		(hatch none 0.5)
		(connect_pads
			(clearance 0)
		)
		(min_thickness 0.25)
		(keepout
			(tracks not_allowed)
			(vias allowed)
			(pads allowed)
			(copperpour not_allowed)
			(footprints allowed)
		)
		(placement
			(enabled no)
			(sheetname "")
		)
		(fill yes
			(thermal_gap 0.5)
			(thermal_bridge_width 0.5)
			(island_removal_mode 0)
		)
		(polygon
			(pts
				(arc
					(start 281.548332 -345.465146)
					(mid 280.844752 -345.465146)
					(end 281.548332 -345.465146)
				)
			)
		)
	)
	(zone
		(layers "B.Cu" "In13.Cu" "In15.Cu")
		(hatch none 0.5)
		(connect_pads
			(clearance 0)
		)
		(min_thickness 0.25)
		(keepout
			(tracks not_allowed)
			(vias allowed)
			(pads allowed)
			(copperpour not_allowed)
			(footprints allowed)
		)
		(placement
			(enabled no)
			(sheetname "")
		)
		(fill yes
			(thermal_gap 0.5)
			(thermal_bridge_width 0.5)
			(island_removal_mode 0)
		)
		(polygon
			(pts
				(arc
					(start 48.299116 -30.05709)
					(mid 47.595536 -30.05709)
					(end 48.299116 -30.05709)
				)
			)
		)
	)
	(zone
		(layers "B.Cu" "In13.Cu" "In15.Cu")
		(hatch none 0.5)
		(connect_pads
			(clearance 0)
		)
		(min_thickness 0.25)
		(keepout
			(tracks not_allowed)
			(vias allowed)
			(pads allowed)
			(copperpour not_allowed)
			(footprints allowed)
		)
		(placement
			(enabled no)
			(sheetname "")
		)
		(fill yes
			(thermal_gap 0.5)
			(thermal_bridge_width 0.5)
			(island_removal_mode 0)
		)
		(polygon
			(pts
				(arc
					(start 19.684238 -342.439498)
					(mid 18.980658 -342.439498)
					(end 19.684238 -342.439498)
				)
			)
		)
	)
	(zone
		(layers "B.Cu" "In13.Cu" "In15.Cu")
		(hatch none 0.5)
		(connect_pads
			(clearance 0)
		)
		(min_thickness 0.25)
		(keepout
			(tracks not_allowed)
			(vias allowed)
			(pads allowed)
			(copperpour not_allowed)
			(footprints allowed)
		)
		(placement
			(enabled no)
			(sheetname "")
		)
		(fill yes
			(thermal_gap 0.5)
			(thermal_bridge_width 0.5)
			(island_removal_mode 0)
		)
		(polygon
			(pts
				(arc
					(start 390.226296 -311.099962)
					(mid 389.573516 -311.099962)
					(end 390.226296 -311.099962)
				)
			)
		)
	)
	(zone
		(layers "B.Cu" "In13.Cu" "In15.Cu")
		(hatch none 0.5)
		(connect_pads
			(clearance 0)
		)
		(min_thickness 0.25)
		(keepout
			(tracks not_allowed)
			(vias allowed)
			(pads allowed)
			(copperpour not_allowed)
			(footprints allowed)
		)
		(placement
			(enabled no)
			(sheetname "")
		)
		(fill yes
			(thermal_gap 0.5)
			(thermal_bridge_width 0.5)
			(island_removal_mode 0)
		)
		(polygon
			(pts
				(arc
					(start 32.983678 -357.75773)
					(mid 32.280098 -357.75773)
					(end 32.983678 -357.75773)
				)
			)
		)
	)
	(zone
		(layers "B.Cu" "In13.Cu" "In15.Cu")
		(hatch none 0.5)
		(connect_pads
			(clearance 0)
		)
		(min_thickness 0.25)
		(keepout
			(tracks not_allowed)
			(vias allowed)
			(pads allowed)
			(copperpour not_allowed)
			(footprints allowed)
		)
		(placement
			(enabled no)
			(sheetname "")
		)
		(fill yes
			(thermal_gap 0.5)
			(thermal_bridge_width 0.5)
			(island_removal_mode 0)
		)
		(polygon
			(pts
				(arc
					(start 138.399266 -33.657286)
					(mid 137.695686 -33.657286)
					(end 138.399266 -33.657286)
				)
			)
		)
	)
	(zone
		(layers "B.Cu" "In13.Cu" "In15.Cu")
		(hatch none 0.5)
		(connect_pads
			(clearance 0)
		)
		(min_thickness 0.25)
		(keepout
			(tracks not_allowed)
			(vias allowed)
			(pads allowed)
			(copperpour not_allowed)
			(footprints allowed)
		)
		(placement
			(enabled no)
			(sheetname "")
		)
		(fill yes
			(thermal_gap 0.5)
			(thermal_bridge_width 0.5)
			(island_removal_mode 0)
		)
		(polygon
			(pts
				(arc
					(start 308.326282 -312.049922)
					(mid 307.673502 -312.049922)
					(end 308.326282 -312.049922)
				)
			)
		)
	)
	(zone
		(layers "B.Cu" "In13.Cu" "In15.Cu")
		(hatch none 0.5)
		(connect_pads
			(clearance 0)
		)
		(min_thickness 0.25)
		(keepout
			(tracks not_allowed)
			(vias allowed)
			(pads allowed)
			(copperpour not_allowed)
			(footprints allowed)
		)
		(placement
			(enabled no)
			(sheetname "")
		)
		(fill yes
			(thermal_gap 0.5)
			(thermal_bridge_width 0.5)
			(island_removal_mode 0)
		)
		(polygon
			(pts
				(arc
					(start 308.326282 -304.449734)
					(mid 307.673502 -304.449734)
					(end 308.326282 -304.449734)
				)
			)
		)
	)
	(zone
		(layers "B.Cu" "In13.Cu" "In15.Cu")
		(hatch none 0.5)
		(connect_pads
			(clearance 0)
		)
		(min_thickness 0.25)
		(keepout
			(tracks not_allowed)
			(vias allowed)
			(pads allowed)
			(copperpour not_allowed)
			(footprints allowed)
		)
		(placement
			(enabled no)
			(sheetname "")
		)
		(fill yes
			(thermal_gap 0.5)
			(thermal_bridge_width 0.5)
			(island_removal_mode 0)
		)
		(polygon
			(pts
				(arc
					(start 268.248892 -342.439498)
					(mid 267.545312 -342.439498)
					(end 268.248892 -342.439498)
				)
			)
		)
	)
	(zone
		(layers "B.Cu" "In13.Cu" "In15.Cu")
		(hatch none 0.5)
		(connect_pads
			(clearance 0)
		)
		(min_thickness 0.25)
		(keepout
			(tracks not_allowed)
			(vias allowed)
			(pads allowed)
			(copperpour not_allowed)
			(footprints allowed)
		)
		(placement
			(enabled no)
			(sheetname "")
		)
		(fill yes
			(thermal_gap 0.5)
			(thermal_bridge_width 0.5)
			(island_removal_mode 0)
		)
		(polygon
			(pts
				(arc
					(start 299.338492 -345.465146)
					(mid 298.634912 -345.465146)
					(end 299.338492 -345.465146)
				)
			)
		)
	)
	(zone
		(layers "B.Cu" "In13.Cu" "In15.Cu")
		(hatch none 0.5)
		(connect_pads
			(clearance 0)
		)
		(min_thickness 0.25)
		(keepout
			(tracks not_allowed)
			(vias allowed)
			(pads allowed)
			(copperpour not_allowed)
			(footprints allowed)
		)
		(placement
			(enabled no)
			(sheetname "")
		)
		(fill yes
			(thermal_gap 0.5)
			(thermal_bridge_width 0.5)
			(island_removal_mode 0)
		)
		(polygon
			(pts
				(arc
					(start 422.069514 -401.49018)
					(mid 421.310054 -401.49018)
					(end 422.069514 -401.49018)
				)
			)
		)
	)
	(zone
		(layers "B.Cu" "In13.Cu" "In15.Cu")
		(hatch none 0.5)
		(connect_pads
			(clearance 0)
		)
		(min_thickness 0.25)
		(keepout
			(tracks not_allowed)
			(vias allowed)
			(pads allowed)
			(copperpour not_allowed)
			(footprints allowed)
		)
		(placement
			(enabled no)
			(sheetname "")
		)
		(fill yes
			(thermal_gap 0.5)
			(thermal_bridge_width 0.5)
			(island_removal_mode 0)
		)
		(polygon
			(pts
				(arc
					(start 289.326066 -280.699718)
					(mid 288.673286 -280.699718)
					(end 289.326066 -280.699718)
				)
			)
		)
	)
	(zone
		(layers "B.Cu" "In13.Cu" "In15.Cu")
		(hatch none 0.5)
		(connect_pads
			(clearance 0)
		)
		(min_thickness 0.25)
		(keepout
			(tracks not_allowed)
			(vias allowed)
			(pads allowed)
			(copperpour not_allowed)
			(footprints allowed)
		)
		(placement
			(enabled no)
			(sheetname "")
		)
		(fill yes
			(thermal_gap 0.5)
			(thermal_bridge_width 0.5)
			(island_removal_mode 0)
		)
		(polygon
			(pts
				(arc
					(start 32.120078 -342.439498)
					(mid 31.416498 -342.439498)
					(end 32.120078 -342.439498)
				)
			)
		)
	)
	(zone
		(layers "B.Cu" "In13.Cu" "In15.Cu")
		(hatch none 0.5)
		(connect_pads
			(clearance 0)
		)
		(min_thickness 0.25)
		(keepout
			(tracks not_allowed)
			(vias allowed)
			(pads allowed)
			(copperpour not_allowed)
			(footprints allowed)
		)
		(placement
			(enabled no)
			(sheetname "")
		)
		(fill yes
			(thermal_gap 0.5)
			(thermal_bridge_width 0.5)
			(island_removal_mode 0)
		)
		(polygon
			(pts
				(arc
					(start 275.330412 -354.732082)
					(mid 274.626832 -354.732082)
					(end 275.330412 -354.732082)
				)
			)
		)
	)
	(zone
		(layers "B.Cu" "In13.Cu" "In15.Cu")
		(hatch none 0.5)
		(connect_pads
			(clearance 0)
		)
		(min_thickness 0.25)
		(keepout
			(tracks not_allowed)
			(vias allowed)
			(pads allowed)
			(copperpour not_allowed)
			(footprints allowed)
		)
		(placement
			(enabled no)
			(sheetname "")
		)
		(fill yes
			(thermal_gap 0.5)
			(thermal_bridge_width 0.5)
			(island_removal_mode 0)
		)
		(polygon
			(pts
				(arc
					(start 310.226202 -309.199788)
					(mid 309.573422 -309.199788)
					(end 310.226202 -309.199788)
				)
			)
		)
	)
	(zone
		(layers "B.Cu" "In13.Cu" "In15.Cu")
		(hatch none 0.5)
		(connect_pads
			(clearance 0)
		)
		(min_thickness 0.25)
		(keepout
			(tracks not_allowed)
			(vias allowed)
			(pads allowed)
			(copperpour not_allowed)
			(footprints allowed)
		)
		(placement
			(enabled no)
			(sheetname "")
		)
		(fill yes
			(thermal_gap 0.5)
			(thermal_bridge_width 0.5)
			(island_removal_mode 0)
		)
		(polygon
			(pts
				(arc
					(start 277.575772 -348.58579)
					(mid 276.872192 -348.58579)
					(end 277.575772 -348.58579)
				)
			)
		)
	)
	(zone
		(layers "B.Cu" "In13.Cu" "In15.Cu")
		(hatch none 0.5)
		(connect_pads
			(clearance 0)
		)
		(min_thickness 0.25)
		(keepout
			(tracks not_allowed)
			(vias allowed)
			(pads allowed)
			(copperpour not_allowed)
			(footprints allowed)
		)
		(placement
			(enabled no)
			(sheetname "")
		)
		(fill yes
			(thermal_gap 0.5)
			(thermal_bridge_width 0.5)
			(island_removal_mode 0)
		)
		(polygon
			(pts
				(arc
					(start 34.889694 -397.59001)
					(mid 34.130234 -397.59001)
					(end 34.889694 -397.59001)
				)
			)
		)
	)
	(zone
		(layers "B.Cu" "In13.Cu" "In15.Cu")
		(hatch none 0.5)
		(connect_pads
			(clearance 0)
		)
		(min_thickness 0.25)
		(keepout
			(tracks not_allowed)
			(vias allowed)
			(pads allowed)
			(copperpour not_allowed)
			(footprints allowed)
		)
		(placement
			(enabled no)
			(sheetname "")
		)
		(fill yes
			(thermal_gap 0.5)
			(thermal_bridge_width 0.5)
			(island_removal_mode 0)
		)
		(polygon
			(pts
				(arc
					(start 159.926274 -302.549814)
					(mid 159.273494 -302.549814)
					(end 159.926274 -302.549814)
				)
			)
		)
	)
	(zone
		(layers "B.Cu" "In13.Cu" "In15.Cu")
		(hatch none 0.5)
		(connect_pads
			(clearance 0)
		)
		(min_thickness 0.25)
		(keepout
			(tracks not_allowed)
			(vias allowed)
			(pads allowed)
			(copperpour not_allowed)
			(footprints allowed)
		)
		(placement
			(enabled no)
			(sheetname "")
		)
		(fill yes
			(thermal_gap 0.5)
			(thermal_bridge_width 0.5)
			(island_removal_mode 0)
		)
		(polygon
			(pts
				(arc
					(start 277.85695 -31.850584)
					(mid 277.15337 -31.850584)
					(end 277.85695 -31.850584)
				)
			)
		)
	)
	(zone
		(layers "B.Cu" "In13.Cu" "In15.Cu")
		(hatch none 0.5)
		(connect_pads
			(clearance 0)
		)
		(min_thickness 0.25)
		(keepout
			(tracks not_allowed)
			(vias allowed)
			(pads allowed)
			(copperpour not_allowed)
			(footprints allowed)
		)
		(placement
			(enabled no)
			(sheetname "")
		)
		(fill yes
			(thermal_gap 0.5)
			(thermal_bridge_width 0.5)
			(island_removal_mode 0)
		)
		(polygon
			(pts
				(arc
					(start 419.956996 -28.250642)
					(mid 419.253416 -28.250642)
					(end 419.956996 -28.250642)
				)
			)
		)
	)
	(zone
		(layers "B.Cu" "In13.Cu" "In15.Cu")
		(hatch none 0.5)
		(connect_pads
			(clearance 0)
		)
		(min_thickness 0.25)
		(keepout
			(tracks not_allowed)
			(vias allowed)
			(pads allowed)
			(copperpour not_allowed)
			(footprints allowed)
		)
		(placement
			(enabled no)
			(sheetname "")
		)
		(fill yes
			(thermal_gap 0.5)
			(thermal_bridge_width 0.5)
			(island_removal_mode 0)
		)
		(polygon
			(pts
				(arc
					(start 32.120078 -357.75773)
					(mid 31.416498 -357.75773)
					(end 32.120078 -357.75773)
				)
			)
		)
	)
	(zone
		(layers "B.Cu" "In13.Cu" "In15.Cu")
		(hatch none 0.5)
		(connect_pads
			(clearance 0)
		)
		(min_thickness 0.25)
		(keepout
			(tracks not_allowed)
			(vias allowed)
			(pads allowed)
			(copperpour not_allowed)
			(footprints allowed)
		)
		(placement
			(enabled no)
			(sheetname "")
		)
		(fill yes
			(thermal_gap 0.5)
			(thermal_bridge_width 0.5)
			(island_removal_mode 0)
		)
		(polygon
			(pts
				(arc
					(start 213.757002 -32.714184)
					(mid 213.053422 -32.714184)
					(end 213.757002 -32.714184)
				)
			)
		)
	)
	(zone
		(layers "B.Cu" "In13.Cu" "In15.Cu")
		(hatch none 0.5)
		(connect_pads
			(clearance 0)
		)
		(min_thickness 0.25)
		(keepout
			(tracks not_allowed)
			(vias allowed)
			(pads allowed)
			(copperpour not_allowed)
			(footprints allowed)
		)
		(placement
			(enabled no)
			(sheetname "")
		)
		(fill yes
			(thermal_gap 0.5)
			(thermal_bridge_width 0.5)
			(island_removal_mode 0)
		)
		(polygon
			(pts
				(arc
					(start 48.57623 -278.799798)
					(mid 47.92345 -278.799798)
					(end 48.57623 -278.799798)
				)
			)
		)
	)
	(zone
		(layers "B.Cu" "In13.Cu" "In15.Cu")
		(hatch none 0.5)
		(connect_pads
			(clearance 0)
		)
		(min_thickness 0.25)
		(keepout
			(tracks not_allowed)
			(vias allowed)
			(pads allowed)
			(copperpour not_allowed)
			(footprints allowed)
		)
		(placement
			(enabled no)
			(sheetname "")
		)
		(fill yes
			(thermal_gap 0.5)
			(thermal_bridge_width 0.5)
			(island_removal_mode 0)
		)
		(polygon
			(pts
				(arc
					(start 435.26964 -402.790152)
					(mid 434.51018 -402.790152)
					(end 435.26964 -402.790152)
				)
			)
		)
	)
	(zone
		(layers "B.Cu" "In13.Cu" "In15.Cu")
		(hatch none 0.5)
		(connect_pads
			(clearance 0)
		)
		(min_thickness 0.25)
		(keepout
			(tracks not_allowed)
			(vias allowed)
			(pads allowed)
			(copperpour not_allowed)
			(footprints allowed)
		)
		(placement
			(enabled no)
			(sheetname "")
		)
		(fill yes
			(thermal_gap 0.5)
			(thermal_bridge_width 0.5)
			(island_removal_mode 0)
		)
		(polygon
			(pts
				(arc
					(start 158.026354 -311.099962)
					(mid 157.373574 -311.099962)
					(end 158.026354 -311.099962)
				)
			)
		)
	)
	(zone
		(layers "B.Cu" "In13.Cu" "In15.Cu")
		(hatch none 0.5)
		(connect_pads
			(clearance 0)
		)
		(min_thickness 0.25)
		(keepout
			(tracks not_allowed)
			(vias allowed)
			(pads allowed)
			(copperpour not_allowed)
			(footprints allowed)
		)
		(placement
			(enabled no)
			(sheetname "")
		)
		(fill yes
			(thermal_gap 0.5)
			(thermal_bridge_width 0.5)
			(island_removal_mode 0)
		)
		(polygon
			(pts
				(arc
					(start 158.026354 -303.499774)
					(mid 157.373574 -303.499774)
					(end 158.026354 -303.499774)
				)
			)
		)
	)
	(zone
		(layers "B.Cu" "In13.Cu" "In15.Cu")
		(hatch none 0.5)
		(connect_pads
			(clearance 0)
		)
		(min_thickness 0.25)
		(keepout
			(tracks not_allowed)
			(vias allowed)
			(pads allowed)
			(copperpour not_allowed)
			(footprints allowed)
		)
		(placement
			(enabled no)
			(sheetname "")
		)
		(fill yes
			(thermal_gap 0.5)
			(thermal_bridge_width 0.5)
			(island_removal_mode 0)
		)
		(polygon
			(pts
				(arc
					(start 390.226296 -301.599854)
					(mid 389.573516 -301.599854)
					(end 390.226296 -301.599854)
				)
			)
		)
	)
	(zone
		(layers "B.Cu" "In13.Cu" "In15.Cu")
		(hatch none 0.5)
		(connect_pads
			(clearance 0)
		)
		(min_thickness 0.25)
		(keepout
			(tracks not_allowed)
			(vias allowed)
			(pads allowed)
			(copperpour not_allowed)
			(footprints allowed)
		)
		(placement
			(enabled no)
			(sheetname "")
		)
		(fill yes
			(thermal_gap 0.5)
			(thermal_bridge_width 0.5)
			(island_removal_mode 0)
		)
		(polygon
			(pts
				(arc
					(start 187.409582 -342.439498)
					(mid 186.706002 -342.439498)
					(end 187.409582 -342.439498)
				)
			)
		)
	)
	(zone
		(layers "B.Cu" "In13.Cu" "In15.Cu")
		(hatch none 0.5)
		(connect_pads
			(clearance 0)
		)
		(min_thickness 0.25)
		(keepout
			(tracks not_allowed)
			(vias allowed)
			(pads allowed)
			(copperpour not_allowed)
			(footprints allowed)
		)
		(placement
			(enabled no)
			(sheetname "")
		)
		(fill yes
			(thermal_gap 0.5)
			(thermal_bridge_width 0.5)
			(island_removal_mode 0)
		)
		(polygon
			(pts
				(arc
					(start 422.082722 -342.439498)
					(mid 421.379142 -342.439498)
					(end 422.082722 -342.439498)
				)
			)
		)
	)
	(zone
		(layers "B.Cu" "In13.Cu" "In15.Cu")
		(hatch none 0.5)
		(connect_pads
			(clearance 0)
		)
		(min_thickness 0.25)
		(keepout
			(tracks not_allowed)
			(vias allowed)
			(pads allowed)
			(copperpour not_allowed)
			(footprints allowed)
		)
		(placement
			(enabled no)
			(sheetname "")
		)
		(fill yes
			(thermal_gap 0.5)
			(thermal_bridge_width 0.5)
			(island_removal_mode 0)
		)
		(polygon
			(pts
				(arc
					(start 287.86963 -397.790162)
					(mid 287.11017 -397.790162)
					(end 287.86963 -397.790162)
				)
			)
		)
	)
	(zone
		(layers "B.Cu" "In13.Cu" "In15.Cu")
		(hatch none 0.5)
		(connect_pads
			(clearance 0)
		)
		(min_thickness 0.25)
		(keepout
			(tracks not_allowed)
			(vias allowed)
			(pads allowed)
			(copperpour not_allowed)
			(footprints allowed)
		)
		(placement
			(enabled no)
			(sheetname "")
		)
		(fill yes
			(thermal_gap 0.5)
			(thermal_bridge_width 0.5)
			(island_removal_mode 0)
		)
		(polygon
			(pts
				(arc
					(start 20.547838 -342.439498)
					(mid 19.844258 -342.439498)
					(end 20.547838 -342.439498)
				)
			)
		)
	)
	(zone
		(layers "B.Cu" "In13.Cu" "In15.Cu")
		(hatch none 0.5)
		(connect_pads
			(clearance 0)
		)
		(min_thickness 0.25)
		(keepout
			(tracks not_allowed)
			(vias allowed)
			(pads allowed)
			(copperpour not_allowed)
			(footprints allowed)
		)
		(placement
			(enabled no)
			(sheetname "")
		)
		(fill yes
			(thermal_gap 0.5)
			(thermal_bridge_width 0.5)
			(island_removal_mode 0)
		)
		(polygon
			(pts
				(arc
					(start 79.92618 -312.049922)
					(mid 79.2734 -312.049922)
					(end 79.92618 -312.049922)
				)
			)
		)
	)
	(zone
		(layers "B.Cu" "In13.Cu" "In15.Cu")
		(hatch none 0.5)
		(connect_pads
			(clearance 0)
		)
		(min_thickness 0.25)
		(keepout
			(tracks not_allowed)
			(vias allowed)
			(pads allowed)
			(copperpour not_allowed)
			(footprints allowed)
		)
		(placement
			(enabled no)
			(sheetname "")
		)
		(fill yes
			(thermal_gap 0.5)
			(thermal_bridge_width 0.5)
			(island_removal_mode 0)
		)
		(polygon
			(pts
				(arc
					(start 392.126216 -308.249828)
					(mid 391.473436 -308.249828)
					(end 392.126216 -308.249828)
				)
			)
		)
	)
	(zone
		(layers "B.Cu" "In13.Cu" "In15.Cu")
		(hatch none 0.5)
		(connect_pads
			(clearance 0)
		)
		(min_thickness 0.25)
		(keepout
			(tracks not_allowed)
			(vias allowed)
			(pads allowed)
			(copperpour not_allowed)
			(footprints allowed)
		)
		(placement
			(enabled no)
			(sheetname "")
		)
		(fill yes
			(thermal_gap 0.5)
			(thermal_bridge_width 0.5)
			(island_removal_mode 0)
		)
		(polygon
			(pts
				(arc
					(start 71.656956 -29.114242)
					(mid 70.953376 -29.114242)
					(end 71.656956 -29.114242)
				)
			)
		)
	)
	(zone
		(layers "B.Cu" "In13.Cu" "In15.Cu")
		(hatch none 0.5)
		(connect_pads
			(clearance 0)
		)
		(min_thickness 0.25)
		(keepout
			(tracks not_allowed)
			(vias allowed)
			(pads allowed)
			(copperpour not_allowed)
			(footprints allowed)
		)
		(placement
			(enabled no)
			(sheetname "")
		)
		(fill yes
			(thermal_gap 0.5)
			(thermal_bridge_width 0.5)
			(island_removal_mode 0)
		)
		(polygon
			(pts
				(arc
					(start 385.476242 -314.899802)
					(mid 384.823462 -314.899802)
					(end 385.476242 -314.899802)
				)
			)
		)
	)
	(zone
		(layers "B.Cu" "In13.Cu" "In15.Cu")
		(hatch none 0.5)
		(connect_pads
			(clearance 0)
		)
		(min_thickness 0.25)
		(keepout
			(tracks not_allowed)
			(vias allowed)
			(pads allowed)
			(copperpour not_allowed)
			(footprints allowed)
		)
		(placement
			(enabled no)
			(sheetname "")
		)
		(fill yes
			(thermal_gap 0.5)
			(thermal_bridge_width 0.5)
			(island_removal_mode 0)
		)
		(polygon
			(pts
				(arc
					(start 287.86963 -371.790214)
					(mid 287.11017 -371.790214)
					(end 287.86963 -371.790214)
				)
			)
		)
	)
	(zone
		(layers "B.Cu" "In13.Cu" "In15.Cu")
		(hatch none 0.5)
		(connect_pads
			(clearance 0)
		)
		(min_thickness 0.25)
		(keepout
			(tracks not_allowed)
			(vias allowed)
			(pads allowed)
			(copperpour not_allowed)
			(footprints allowed)
		)
		(placement
			(enabled no)
			(sheetname "")
		)
		(fill yes
			(thermal_gap 0.5)
			(thermal_bridge_width 0.5)
			(island_removal_mode 0)
		)
		(polygon
			(pts
				(arc
					(start 170.376342 -278.799798)
					(mid 169.723562 -278.799798)
					(end 170.376342 -278.799798)
				)
			)
		)
	)
	(zone
		(layers "B.Cu" "In13.Cu" "In15.Cu")
		(hatch none 0.5)
		(connect_pads
			(clearance 0)
		)
		(min_thickness 0.25)
		(keepout
			(tracks not_allowed)
			(vias allowed)
			(pads allowed)
			(copperpour not_allowed)
			(footprints allowed)
		)
		(placement
			(enabled no)
			(sheetname "")
		)
		(fill yes
			(thermal_gap 0.5)
			(thermal_bridge_width 0.5)
			(island_removal_mode 0)
		)
		(polygon
			(pts
				(arc
					(start 100.299012 -34.520886)
					(mid 99.595432 -34.520886)
					(end 100.299012 -34.520886)
				)
			)
		)
	)
	(zone
		(layers "B.Cu" "In13.Cu" "In15.Cu")
		(hatch none 0.5)
		(connect_pads
			(clearance 0)
		)
		(min_thickness 0.25)
		(keepout
			(tracks not_allowed)
			(vias allowed)
			(pads allowed)
			(copperpour not_allowed)
			(footprints allowed)
		)
		(placement
			(enabled no)
			(sheetname "")
		)
		(fill yes
			(thermal_gap 0.5)
			(thermal_bridge_width 0.5)
			(island_removal_mode 0)
		)
		(polygon
			(pts
				(arc
					(start 437.627522 -348.58579)
					(mid 436.923942 -348.58579)
					(end 437.627522 -348.58579)
				)
			)
		)
	)
	(zone
		(layers "B.Cu" "In13.Cu" "In15.Cu")
		(hatch none 0.5)
		(connect_pads
			(clearance 0)
		)
		(min_thickness 0.25)
		(keepout
			(tracks not_allowed)
			(vias allowed)
			(pads allowed)
			(copperpour not_allowed)
			(footprints allowed)
		)
		(placement
			(enabled no)
			(sheetname "")
		)
		(fill yes
			(thermal_gap 0.5)
			(thermal_bridge_width 0.5)
			(island_removal_mode 0)
		)
		(polygon
			(pts
				(arc
					(start 306.499006 -30.05709)
					(mid 305.795426 -30.05709)
					(end 306.499006 -30.05709)
				)
			)
		)
	)
	(zone
		(layers "B.Cu" "In13.Cu" "In15.Cu")
		(hatch none 0.5)
		(connect_pads
			(clearance 0)
		)
		(min_thickness 0.25)
		(keepout
			(tracks not_allowed)
			(vias allowed)
			(pads allowed)
			(copperpour not_allowed)
			(footprints allowed)
		)
		(placement
			(enabled no)
			(sheetname "")
		)
		(fill yes
			(thermal_gap 0.5)
			(thermal_bridge_width 0.5)
			(island_removal_mode 0)
		)
		(polygon
			(pts
				(arc
					(start 37.089842 -370.489988)
					(mid 36.330382 -370.489988)
					(end 37.089842 -370.489988)
				)
			)
		)
	)
	(zone
		(layers "B.Cu" "In13.Cu" "In15.Cu")
		(hatch none 0.5)
		(connect_pads
			(clearance 0)
		)
		(min_thickness 0.25)
		(keepout
			(tracks not_allowed)
			(vias allowed)
			(pads allowed)
			(copperpour not_allowed)
			(footprints allowed)
		)
		(placement
			(enabled no)
			(sheetname "")
		)
		(fill yes
			(thermal_gap 0.5)
			(thermal_bridge_width 0.5)
			(island_removal_mode 0)
		)
		(polygon
			(pts
				(arc
					(start 184.300622 -348.58579)
					(mid 183.597042 -348.58579)
					(end 184.300622 -348.58579)
				)
			)
		)
	)
	(zone
		(layers "B.Cu" "In13.Cu" "In15.Cu")
		(hatch none 0.5)
		(connect_pads
			(clearance 0)
		)
		(min_thickness 0.25)
		(keepout
			(tracks not_allowed)
			(vias allowed)
			(pads allowed)
			(copperpour not_allowed)
			(footprints allowed)
		)
		(placement
			(enabled no)
			(sheetname "")
		)
		(fill yes
			(thermal_gap 0.5)
			(thermal_bridge_width 0.5)
			(island_removal_mode 0)
		)
		(polygon
			(pts
				(arc
					(start 45.657008 -32.714184)
					(mid 44.953428 -32.714184)
					(end 45.657008 -32.714184)
				)
			)
		)
	)
	(zone
		(layers "B.Cu" "In13.Cu" "In15.Cu")
		(hatch none 0.5)
		(connect_pads
			(clearance 0)
		)
		(min_thickness 0.25)
		(keepout
			(tracks not_allowed)
			(vias allowed)
			(pads allowed)
			(copperpour not_allowed)
			(footprints allowed)
		)
		(placement
			(enabled no)
			(sheetname "")
		)
		(fill yes
			(thermal_gap 0.5)
			(thermal_bridge_width 0.5)
			(island_removal_mode 0)
		)
		(polygon
			(pts
				(arc
					(start 165.626288 -280.699718)
					(mid 164.973508 -280.699718)
					(end 165.626288 -280.699718)
				)
			)
		)
	)
	(zone
		(layers "B.Cu" "In13.Cu" "In15.Cu")
		(hatch none 0.5)
		(connect_pads
			(clearance 0)
		)
		(min_thickness 0.25)
		(keepout
			(tracks not_allowed)
			(vias allowed)
			(pads allowed)
			(copperpour not_allowed)
			(footprints allowed)
		)
		(placement
			(enabled no)
			(sheetname "")
		)
		(fill yes
			(thermal_gap 0.5)
			(thermal_bridge_width 0.5)
			(island_removal_mode 0)
		)
		(polygon
			(pts
				(arc
					(start 162.537902 -357.75773)
					(mid 161.834322 -357.75773)
					(end 162.537902 -357.75773)
				)
			)
		)
	)
	(zone
		(layers "B.Cu" "In13.Cu" "In15.Cu")
		(hatch none 0.5)
		(connect_pads
			(clearance 0)
		)
		(min_thickness 0.25)
		(keepout
			(tracks not_allowed)
			(vias allowed)
			(pads allowed)
			(copperpour not_allowed)
			(footprints allowed)
		)
		(placement
			(enabled no)
			(sheetname "")
		)
		(fill yes
			(thermal_gap 0.5)
			(thermal_bridge_width 0.5)
			(island_removal_mode 0)
		)
		(polygon
			(pts
				(arc
					(start 274.466812 -354.732082)
					(mid 273.763232 -354.732082)
					(end 274.466812 -354.732082)
				)
			)
		)
	)
	(zone
		(layers "B.Cu" "In13.Cu" "In15.Cu")
		(hatch none 0.5)
		(connect_pads
			(clearance 0)
		)
		(min_thickness 0.25)
		(keepout
			(tracks not_allowed)
			(vias allowed)
			(pads allowed)
			(copperpour not_allowed)
			(footprints allowed)
		)
		(placement
			(enabled no)
			(sheetname "")
		)
		(fill yes
			(thermal_gap 0.5)
			(thermal_bridge_width 0.5)
			(island_removal_mode 0)
		)
		(polygon
			(pts
				(arc
					(start 293.984172 -357.75773)
					(mid 293.280592 -357.75773)
					(end 293.984172 -357.75773)
				)
			)
		)
	)
	(zone
		(layers "B.Cu" "In13.Cu" "In15.Cu")
		(hatch none 0.5)
		(connect_pads
			(clearance 0)
		)
		(min_thickness 0.25)
		(keepout
			(tracks not_allowed)
			(vias allowed)
			(pads allowed)
			(copperpour not_allowed)
			(footprints allowed)
		)
		(placement
			(enabled no)
			(sheetname "")
		)
		(fill yes
			(thermal_gap 0.5)
			(thermal_bridge_width 0.5)
			(island_removal_mode 0)
		)
		(polygon
			(pts
				(arc
					(start 306.499006 -33.657286)
					(mid 305.795426 -33.657286)
					(end 306.499006 -33.657286)
				)
			)
		)
	)
	(zone
		(layers "B.Cu" "In13.Cu" "In15.Cu")
		(hatch none 0.5)
		(connect_pads
			(clearance 0)
		)
		(min_thickness 0.25)
		(keepout
			(tracks not_allowed)
			(vias allowed)
			(pads allowed)
			(copperpour not_allowed)
			(footprints allowed)
		)
		(placement
			(enabled no)
			(sheetname "")
		)
		(fill yes
			(thermal_gap 0.5)
			(thermal_bridge_width 0.5)
			(island_removal_mode 0)
		)
		(polygon
			(pts
				(arc
					(start 163.401502 -354.732082)
					(mid 162.697922 -354.732082)
					(end 163.401502 -354.732082)
				)
			)
		)
	)
	(zone
		(layers "B.Cu" "In13.Cu" "In15.Cu")
		(hatch none 0.5)
		(connect_pads
			(clearance 0)
		)
		(min_thickness 0.25)
		(keepout
			(tracks not_allowed)
			(vias allowed)
			(pads allowed)
			(copperpour not_allowed)
			(footprints allowed)
		)
		(placement
			(enabled no)
			(sheetname "")
		)
		(fill yes
			(thermal_gap 0.5)
			(thermal_bridge_width 0.5)
			(island_removal_mode 0)
		)
		(polygon
			(pts
				(arc
					(start 434.518562 -342.439498)
					(mid 433.814982 -342.439498)
					(end 434.518562 -342.439498)
				)
			)
		)
	)
	(zone
		(layers "B.Cu" "In13.Cu" "In15.Cu")
		(hatch none 0.5)
		(connect_pads
			(clearance 0)
		)
		(min_thickness 0.25)
		(keepout
			(tracks not_allowed)
			(vias allowed)
			(pads allowed)
			(copperpour not_allowed)
			(footprints allowed)
		)
		(placement
			(enabled no)
			(sheetname "")
		)
		(fill yes
			(thermal_gap 0.5)
			(thermal_bridge_width 0.5)
			(island_removal_mode 0)
		)
		(polygon
			(pts
				(arc
					(start 53.326284 -280.699718)
					(mid 52.673504 -280.699718)
					(end 53.326284 -280.699718)
				)
			)
		)
	)
	(zone
		(layers "B.Cu" "In13.Cu" "In15.Cu")
		(hatch none 0.5)
		(connect_pads
			(clearance 0)
		)
		(min_thickness 0.25)
		(keepout
			(tracks not_allowed)
			(vias allowed)
			(pads allowed)
			(copperpour not_allowed)
			(footprints allowed)
		)
		(placement
			(enabled no)
			(sheetname "")
		)
		(fill yes
			(thermal_gap 0.5)
			(thermal_bridge_width 0.5)
			(island_removal_mode 0)
		)
		(polygon
			(pts
				(arc
					(start 50.47615 -278.799798)
					(mid 49.82337 -278.799798)
					(end 50.47615 -278.799798)
				)
			)
		)
	)
	(zone
		(layers "B.Cu" "In13.Cu" "In15.Cu")
		(hatch none 0.5)
		(connect_pads
			(clearance 0)
		)
		(min_thickness 0.25)
		(keepout
			(tracks not_allowed)
			(vias allowed)
			(pads allowed)
			(copperpour not_allowed)
			(footprints allowed)
		)
		(placement
			(enabled no)
			(sheetname "")
		)
		(fill yes
			(thermal_gap 0.5)
			(thermal_bridge_width 0.5)
			(island_removal_mode 0)
		)
		(polygon
			(pts
				(arc
					(start 314.026296 -312.049922)
					(mid 313.373516 -312.049922)
					(end 314.026296 -312.049922)
				)
			)
		)
	)
	(zone
		(layers "B.Cu" "In13.Cu" "In15.Cu")
		(hatch none 0.5)
		(connect_pads
			(clearance 0)
		)
		(min_thickness 0.25)
		(keepout
			(tracks not_allowed)
			(vias allowed)
			(pads allowed)
			(copperpour not_allowed)
			(footprints allowed)
		)
		(placement
			(enabled no)
			(sheetname "")
		)
		(fill yes
			(thermal_gap 0.5)
			(thermal_bridge_width 0.5)
			(island_removal_mode 0)
		)
		(polygon
			(pts
				(arc
					(start 54.276244 -277.849838)
					(mid 53.623464 -277.849838)
					(end 54.276244 -277.849838)
				)
			)
		)
	)
	(zone
		(layers "B.Cu" "In13.Cu" "In15.Cu")
		(hatch none 0.5)
		(connect_pads
			(clearance 0)
		)
		(min_thickness 0.25)
		(keepout
			(tracks not_allowed)
			(vias allowed)
			(pads allowed)
			(copperpour not_allowed)
			(footprints allowed)
		)
		(placement
			(enabled no)
			(sheetname "")
		)
		(fill yes
			(thermal_gap 0.5)
			(thermal_bridge_width 0.5)
			(island_removal_mode 0)
		)
		(polygon
			(pts
				(arc
					(start 190.399162 -30.05709)
					(mid 189.695582 -30.05709)
					(end 190.399162 -30.05709)
				)
			)
		)
	)
	(zone
		(layers "B.Cu" "In13.Cu" "In15.Cu")
		(hatch none 0.5)
		(connect_pads
			(clearance 0)
		)
		(min_thickness 0.25)
		(keepout
			(tracks not_allowed)
			(vias allowed)
			(pads allowed)
			(copperpour not_allowed)
			(footprints allowed)
		)
		(placement
			(enabled no)
			(sheetname "")
		)
		(fill yes
			(thermal_gap 0.5)
			(thermal_bridge_width 0.5)
			(island_removal_mode 0)
		)
		(polygon
			(pts
				(arc
					(start 213.757002 -29.114242)
					(mid 213.053422 -29.114242)
					(end 213.757002 -29.114242)
				)
			)
		)
	)
	(zone
		(layers "B.Cu" "In13.Cu" "In15.Cu")
		(hatch none 0.5)
		(connect_pads
			(clearance 0)
		)
		(min_thickness 0.25)
		(keepout
			(tracks not_allowed)
			(vias allowed)
			(pads allowed)
			(copperpour not_allowed)
			(footprints allowed)
		)
		(placement
			(enabled no)
			(sheetname "")
		)
		(fill yes
			(thermal_gap 0.5)
			(thermal_bridge_width 0.5)
			(island_removal_mode 0)
		)
		(polygon
			(pts
				(arc
					(start 312.126122 -312.049922)
					(mid 311.473342 -312.049922)
					(end 312.126122 -312.049922)
				)
			)
		)
	)
	(zone
		(layers "B.Cu" "In13.Cu" "In15.Cu")
		(hatch none 0.5)
		(connect_pads
			(clearance 0)
		)
		(min_thickness 0.25)
		(keepout
			(tracks not_allowed)
			(vias allowed)
			(pads allowed)
			(copperpour not_allowed)
			(footprints allowed)
		)
		(placement
			(enabled no)
			(sheetname "")
		)
		(fill yes
			(thermal_gap 0.5)
			(thermal_bridge_width 0.5)
			(island_removal_mode 0)
		)
		(polygon
			(pts
				(arc
					(start 448.599052 -33.657286)
					(mid 447.895472 -33.657286)
					(end 448.599052 -33.657286)
				)
			)
		)
	)
	(zone
		(layers "B.Cu" "In13.Cu" "In15.Cu")
		(hatch none 0.5)
		(connect_pads
			(clearance 0)
		)
		(min_thickness 0.25)
		(keepout
			(tracks not_allowed)
			(vias allowed)
			(pads allowed)
			(copperpour not_allowed)
			(footprints allowed)
		)
		(placement
			(enabled no)
			(sheetname "")
		)
		(fill yes
			(thermal_gap 0.5)
			(thermal_bridge_width 0.5)
			(island_removal_mode 0)
		)
		(polygon
			(pts
				(arc
					(start 280.499058 -34.520886)
					(mid 279.795478 -34.520886)
					(end 280.499058 -34.520886)
				)
			)
		)
	)
	(zone
		(layers "B.Cu" "In13.Cu" "In15.Cu")
		(hatch none 0.5)
		(connect_pads
			(clearance 0)
		)
		(min_thickness 0.25)
		(keepout
			(tracks not_allowed)
			(vias allowed)
			(pads allowed)
			(copperpour not_allowed)
			(footprints allowed)
		)
		(placement
			(enabled no)
			(sheetname "")
		)
		(fill yes
			(thermal_gap 0.5)
			(thermal_bridge_width 0.5)
			(island_removal_mode 0)
		)
		(polygon
			(pts
				(arc
					(start 28.289758 -396.49019)
					(mid 27.530298 -396.49019)
					(end 28.289758 -396.49019)
				)
			)
		)
	)
	(zone
		(layers "B.Cu" "In13.Cu" "In15.Cu")
		(hatch none 0.5)
		(connect_pads
			(clearance 0)
		)
		(min_thickness 0.25)
		(keepout
			(tracks not_allowed)
			(vias allowed)
			(pads allowed)
			(copperpour not_allowed)
			(footprints allowed)
		)
		(placement
			(enabled no)
			(sheetname "")
		)
		(fill yes
			(thermal_gap 0.5)
			(thermal_bridge_width 0.5)
			(island_removal_mode 0)
		)
		(polygon
			(pts
				(arc
					(start 78.97622 -313.949842)
					(mid 78.32344 -313.949842)
					(end 78.97622 -313.949842)
				)
			)
		)
	)
	(zone
		(layers "B.Cu" "In13.Cu" "In15.Cu")
		(hatch none 0.5)
		(connect_pads
			(clearance 0)
		)
		(min_thickness 0.25)
		(keepout
			(tracks not_allowed)
			(vias allowed)
			(pads allowed)
			(copperpour not_allowed)
			(footprints allowed)
		)
		(placement
			(enabled no)
			(sheetname "")
		)
		(fill yes
			(thermal_gap 0.5)
			(thermal_bridge_width 0.5)
			(island_removal_mode 0)
		)
		(polygon
			(pts
				(arc
					(start 185.164222 -348.58579)
					(mid 184.460642 -348.58579)
					(end 185.164222 -348.58579)
				)
			)
		)
	)
	(zone
		(layers "B.Cu" "In13.Cu" "In15.Cu")
		(hatch none 0.5)
		(connect_pads
			(clearance 0)
		)
		(min_thickness 0.25)
		(keepout
			(tracks not_allowed)
			(vias allowed)
			(pads allowed)
			(copperpour not_allowed)
			(footprints allowed)
		)
		(placement
			(enabled no)
			(sheetname "")
		)
		(fill yes
			(thermal_gap 0.5)
			(thermal_bridge_width 0.5)
			(island_removal_mode 0)
		)
		(polygon
			(pts
				(arc
					(start 413.619442 -351.611438)
					(mid 412.915862 -351.611438)
					(end 413.619442 -351.611438)
				)
			)
		)
	)
	(zone
		(layers "B.Cu" "In13.Cu" "In15.Cu")
		(hatch none 0.5)
		(connect_pads
			(clearance 0)
		)
		(min_thickness 0.25)
		(keepout
			(tracks not_allowed)
			(vias allowed)
			(pads allowed)
			(copperpour not_allowed)
			(footprints allowed)
		)
		(placement
			(enabled no)
			(sheetname "")
		)
		(fill yes
			(thermal_gap 0.5)
			(thermal_bridge_width 0.5)
			(island_removal_mode 0)
		)
		(polygon
			(pts
				(arc
					(start 51.426364 -280.699718)
					(mid 50.773584 -280.699718)
					(end 51.426364 -280.699718)
				)
			)
		)
	)
	(zone
		(layers "B.Cu" "In13.Cu" "In15.Cu")
		(hatch none 0.5)
		(connect_pads
			(clearance 0)
		)
		(min_thickness 0.25)
		(keepout
			(tracks not_allowed)
			(vias allowed)
			(pads allowed)
			(copperpour not_allowed)
			(footprints allowed)
		)
		(placement
			(enabled no)
			(sheetname "")
		)
		(fill yes
			(thermal_gap 0.5)
			(thermal_bridge_width 0.5)
			(island_removal_mode 0)
		)
		(polygon
			(pts
				(arc
					(start 435.382162 -342.439498)
					(mid 434.678582 -342.439498)
					(end 435.382162 -342.439498)
				)
			)
		)
	)
	(zone
		(layers "B.Cu" "In13.Cu" "In15.Cu")
		(hatch none 0.5)
		(connect_pads
			(clearance 0)
		)
		(min_thickness 0.25)
		(keepout
			(tracks not_allowed)
			(vias allowed)
			(pads allowed)
			(copperpour not_allowed)
			(footprints allowed)
		)
		(placement
			(enabled no)
			(sheetname "")
		)
		(fill yes
			(thermal_gap 0.5)
			(thermal_bridge_width 0.5)
			(island_removal_mode 0)
		)
		(polygon
			(pts
				(arc
					(start 310.226202 -305.399948)
					(mid 309.573422 -305.399948)
					(end 310.226202 -305.399948)
				)
			)
		)
	)
	(zone
		(layers "B.Cu" "In13.Cu" "In15.Cu")
		(hatch none 0.5)
		(connect_pads
			(clearance 0)
		)
		(min_thickness 0.25)
		(keepout
			(tracks not_allowed)
			(vias allowed)
			(pads allowed)
			(copperpour not_allowed)
			(footprints allowed)
		)
		(placement
			(enabled no)
			(sheetname "")
		)
		(fill yes
			(thermal_gap 0.5)
			(thermal_bridge_width 0.5)
			(island_removal_mode 0)
		)
		(polygon
			(pts
				(arc
					(start 301.069502 -371.790214)
					(mid 300.310042 -371.790214)
					(end 301.069502 -371.790214)
				)
			)
		)
	)
	(zone
		(layers "B.Cu" "In13.Cu" "In15.Cu")
		(hatch none 0.5)
		(connect_pads
			(clearance 0)
		)
		(min_thickness 0.25)
		(keepout
			(tracks not_allowed)
			(vias allowed)
			(pads allowed)
			(copperpour not_allowed)
			(footprints allowed)
		)
		(placement
			(enabled no)
			(sheetname "")
		)
		(fill yes
			(thermal_gap 0.5)
			(thermal_bridge_width 0.5)
			(island_removal_mode 0)
		)
		(polygon
			(pts
				(arc
					(start 396.599156 -34.520886)
					(mid 395.895576 -34.520886)
					(end 396.599156 -34.520886)
				)
			)
		)
	)
	(zone
		(layers "B.Cu" "In13.Cu" "In15.Cu")
		(hatch none 0.5)
		(connect_pads
			(clearance 0)
		)
		(min_thickness 0.25)
		(keepout
			(tracks not_allowed)
			(vias allowed)
			(pads allowed)
			(copperpour not_allowed)
			(footprints allowed)
		)
		(placement
			(enabled no)
			(sheetname "")
		)
		(fill yes
			(thermal_gap 0.5)
			(thermal_bridge_width 0.5)
			(island_removal_mode 0)
		)
		(polygon
			(pts
				(arc
					(start 51.637438 -342.439498)
					(mid 50.933858 -342.439498)
					(end 51.637438 -342.439498)
				)
			)
		)
	)
	(zone
		(layers "B.Cu" "In13.Cu" "In15.Cu")
		(hatch none 0.5)
		(connect_pads
			(clearance 0)
		)
		(min_thickness 0.25)
		(keepout
			(tracks not_allowed)
			(vias allowed)
			(pads allowed)
			(copperpour not_allowed)
			(footprints allowed)
		)
		(placement
			(enabled no)
			(sheetname "")
		)
		(fill yes
			(thermal_gap 0.5)
			(thermal_bridge_width 0.5)
			(island_removal_mode 0)
		)
		(polygon
			(pts
				(arc
					(start 174.973742 -357.75773)
					(mid 174.270162 -357.75773)
					(end 174.973742 -357.75773)
				)
			)
		)
	)
	(zone
		(layers "B.Cu" "In13.Cu" "In15.Cu")
		(hatch none 0.5)
		(connect_pads
			(clearance 0)
		)
		(min_thickness 0.25)
		(keepout
			(tracks not_allowed)
			(vias allowed)
			(pads allowed)
			(copperpour not_allowed)
			(footprints allowed)
		)
		(placement
			(enabled no)
			(sheetname "")
		)
		(fill yes
			(thermal_gap 0.5)
			(thermal_bridge_width 0.5)
			(island_removal_mode 0)
		)
		(polygon
			(pts
				(arc
					(start 403.526244 -280.699718)
					(mid 402.873464 -280.699718)
					(end 403.526244 -280.699718)
				)
			)
		)
	)
	(zone
		(layers "B.Cu" "In13.Cu" "In15.Cu")
		(hatch none 0.5)
		(connect_pads
			(clearance 0)
		)
		(min_thickness 0.25)
		(keepout
			(tracks not_allowed)
			(vias allowed)
			(pads allowed)
			(copperpour not_allowed)
			(footprints allowed)
		)
		(placement
			(enabled no)
			(sheetname "")
		)
		(fill yes
			(thermal_gap 0.5)
			(thermal_bridge_width 0.5)
			(island_removal_mode 0)
		)
		(polygon
			(pts
				(arc
					(start 329.856846 -32.714184)
					(mid 329.153266 -32.714184)
					(end 329.856846 -32.714184)
				)
			)
		)
	)
	(zone
		(layers "B.Cu" "In13.Cu" "In15.Cu")
		(hatch none 0.5)
		(connect_pads
			(clearance 0)
		)
		(min_thickness 0.25)
		(keepout
			(tracks not_allowed)
			(vias allowed)
			(pads allowed)
			(copperpour not_allowed)
			(footprints allowed)
		)
		(placement
			(enabled no)
			(sheetname "")
		)
		(fill yes
			(thermal_gap 0.5)
			(thermal_bridge_width 0.5)
			(island_removal_mode 0)
		)
		(polygon
			(pts
				(arc
					(start 39.289736 -398.890236)
					(mid 38.530276 -398.890236)
					(end 39.289736 -398.890236)
				)
			)
		)
	)
	(zone
		(layers "B.Cu" "In13.Cu" "In15.Cu")
		(hatch none 0.5)
		(connect_pads
			(clearance 0)
		)
		(min_thickness 0.25)
		(keepout
			(tracks not_allowed)
			(vias allowed)
			(pads allowed)
			(copperpour not_allowed)
			(footprints allowed)
		)
		(placement
			(enabled no)
			(sheetname "")
		)
		(fill yes
			(thermal_gap 0.5)
			(thermal_bridge_width 0.5)
			(island_removal_mode 0)
		)
		(polygon
			(pts
				(arc
					(start 216.39911 -33.657286)
					(mid 215.69553 -33.657286)
					(end 216.39911 -33.657286)
				)
			)
		)
	)
	(zone
		(layers "B.Cu" "In13.Cu" "In15.Cu")
		(hatch none 0.5)
		(connect_pads
			(clearance 0)
		)
		(min_thickness 0.25)
		(keepout
			(tracks not_allowed)
			(vias allowed)
			(pads allowed)
			(copperpour not_allowed)
			(footprints allowed)
		)
		(placement
			(enabled no)
			(sheetname "")
		)
		(fill yes
			(thermal_gap 0.5)
			(thermal_bridge_width 0.5)
			(island_removal_mode 0)
		)
		(polygon
			(pts
				(arc
					(start 419.956996 -32.714184)
					(mid 419.253416 -32.714184)
					(end 419.956996 -32.714184)
				)
			)
		)
	)
	(zone
		(layers "B.Cu" "In13.Cu" "In15.Cu")
		(hatch none 0.5)
		(connect_pads
			(clearance 0)
		)
		(min_thickness 0.25)
		(keepout
			(tracks not_allowed)
			(vias allowed)
			(pads allowed)
			(copperpour not_allowed)
			(footprints allowed)
		)
		(placement
			(enabled no)
			(sheetname "")
		)
		(fill yes
			(thermal_gap 0.5)
			(thermal_bridge_width 0.5)
			(island_removal_mode 0)
		)
		(polygon
			(pts
				(arc
					(start 182.055262 -354.732082)
					(mid 181.351682 -354.732082)
					(end 182.055262 -354.732082)
				)
			)
		)
	)
	(zone
		(layers "B.Cu" "In13.Cu" "In15.Cu")
		(hatch none 0.5)
		(connect_pads
			(clearance 0)
		)
		(min_thickness 0.25)
		(keepout
			(tracks not_allowed)
			(vias allowed)
			(pads allowed)
			(copperpour not_allowed)
			(footprints allowed)
		)
		(placement
			(enabled no)
			(sheetname "")
		)
		(fill yes
			(thermal_gap 0.5)
			(thermal_bridge_width 0.5)
			(island_removal_mode 0)
		)
		(polygon
			(pts
				(arc
					(start 76.12634 -304.449734)
					(mid 75.47356 -304.449734)
					(end 76.12634 -304.449734)
				)
			)
		)
	)
	(zone
		(layers "B.Cu" "In13.Cu" "In15.Cu")
		(hatch none 0.5)
		(connect_pads
			(clearance 0)
		)
		(min_thickness 0.25)
		(keepout
			(tracks not_allowed)
			(vias allowed)
			(pads allowed)
			(copperpour not_allowed)
			(footprints allowed)
		)
		(placement
			(enabled no)
			(sheetname "")
		)
		(fill yes
			(thermal_gap 0.5)
			(thermal_bridge_width 0.5)
			(island_removal_mode 0)
		)
		(polygon
			(pts
				(arc
					(start 313.076082 -312.999882)
					(mid 312.423302 -312.999882)
					(end 313.076082 -312.999882)
				)
			)
		)
	)
	(zone
		(layers "B.Cu" "In13.Cu" "In15.Cu")
		(hatch none 0.5)
		(connect_pads
			(clearance 0)
		)
		(min_thickness 0.25)
		(keepout
			(tracks not_allowed)
			(vias allowed)
			(pads allowed)
			(copperpour not_allowed)
			(footprints allowed)
		)
		(placement
			(enabled no)
			(sheetname "")
		)
		(fill yes
			(thermal_gap 0.5)
			(thermal_bridge_width 0.5)
			(island_removal_mode 0)
		)
		(polygon
			(pts
				(arc
					(start 19.65706 -31.850584)
					(mid 18.95348 -31.850584)
					(end 19.65706 -31.850584)
				)
			)
		)
	)
	(zone
		(layers "B.Cu" "In13.Cu" "In15.Cu")
		(hatch none 0.5)
		(connect_pads
			(clearance 0)
		)
		(min_thickness 0.25)
		(keepout
			(tracks not_allowed)
			(vias allowed)
			(pads allowed)
			(copperpour not_allowed)
			(footprints allowed)
		)
		(placement
			(enabled no)
			(sheetname "")
		)
		(fill yes
			(thermal_gap 0.5)
			(thermal_bridge_width 0.5)
			(island_removal_mode 0)
		)
		(polygon
			(pts
				(arc
					(start 428.669704 -375.69013)
					(mid 427.910244 -375.69013)
					(end 428.669704 -375.69013)
				)
			)
		)
	)
	(zone
		(layers "B.Cu" "In13.Cu" "In15.Cu")
		(hatch none 0.5)
		(connect_pads
			(clearance 0)
		)
		(min_thickness 0.25)
		(keepout
			(tracks not_allowed)
			(vias allowed)
			(pads allowed)
			(copperpour not_allowed)
			(footprints allowed)
		)
		(placement
			(enabled no)
			(sheetname "")
		)
		(fill yes
			(thermal_gap 0.5)
			(thermal_bridge_width 0.5)
			(island_removal_mode 0)
		)
		(polygon
			(pts
				(arc
					(start 167.526462 -280.699718)
					(mid 166.873682 -280.699718)
					(end 167.526462 -280.699718)
				)
			)
		)
	)
	(zone
		(layers "B.Cu" "In13.Cu" "In15.Cu")
		(hatch none 0.5)
		(connect_pads
			(clearance 0)
		)
		(min_thickness 0.25)
		(keepout
			(tracks not_allowed)
			(vias allowed)
			(pads allowed)
			(copperpour not_allowed)
			(footprints allowed)
		)
		(placement
			(enabled no)
			(sheetname "")
		)
		(fill yes
			(thermal_gap 0.5)
			(thermal_bridge_width 0.5)
			(island_removal_mode 0)
		)
		(polygon
			(pts
				(arc
					(start 45.419518 -345.465146)
					(mid 44.715938 -345.465146)
					(end 45.419518 -345.465146)
				)
			)
		)
	)
	(zone
		(layers "B.Cu" "In13.Cu" "In15.Cu")
		(hatch none 0.5)
		(connect_pads
			(clearance 0)
		)
		(min_thickness 0.25)
		(keepout
			(tracks not_allowed)
			(vias allowed)
			(pads allowed)
			(copperpour not_allowed)
			(footprints allowed)
		)
		(placement
			(enabled no)
			(sheetname "")
		)
		(fill yes
			(thermal_gap 0.5)
			(thermal_bridge_width 0.5)
			(island_removal_mode 0)
		)
		(polygon
			(pts
				(arc
					(start 32.6898 -396.49019)
					(mid 31.93034 -396.49019)
					(end 32.6898 -396.49019)
				)
			)
		)
	)
	(zone
		(layers "B.Cu" "In13.Cu" "In15.Cu")
		(hatch none 0.5)
		(connect_pads
			(clearance 0)
		)
		(min_thickness 0.25)
		(keepout
			(tracks not_allowed)
			(vias allowed)
			(pads allowed)
			(copperpour not_allowed)
			(footprints allowed)
		)
		(placement
			(enabled no)
			(sheetname "")
		)
		(fill yes
			(thermal_gap 0.5)
			(thermal_bridge_width 0.5)
			(island_removal_mode 0)
		)
		(polygon
			(pts
				(arc
					(start 435.382162 -357.75773)
					(mid 434.678582 -357.75773)
					(end 435.382162 -357.75773)
				)
			)
		)
	)
	(zone
		(layers "B.Cu" "In13.Cu" "In15.Cu")
		(hatch none 0.5)
		(connect_pads
			(clearance 0)
		)
		(min_thickness 0.25)
		(keepout
			(tracks not_allowed)
			(vias allowed)
			(pads allowed)
			(copperpour not_allowed)
			(footprints allowed)
		)
		(placement
			(enabled no)
			(sheetname "")
		)
		(fill yes
			(thermal_gap 0.5)
			(thermal_bridge_width 0.5)
			(island_removal_mode 0)
		)
		(polygon
			(pts
				(arc
					(start 166.889684 -401.49018)
					(mid 166.130224 -401.49018)
					(end 166.889684 -401.49018)
				)
			)
		)
	)
	(zone
		(layers "B.Cu" "In13.Cu" "In15.Cu")
		(hatch none 0.5)
		(connect_pads
			(clearance 0)
		)
		(min_thickness 0.25)
		(keepout
			(tracks not_allowed)
			(vias allowed)
			(pads allowed)
			(copperpour not_allowed)
			(footprints allowed)
		)
		(placement
			(enabled no)
			(sheetname "")
		)
		(fill yes
			(thermal_gap 0.5)
			(thermal_bridge_width 0.5)
			(island_removal_mode 0)
		)
		(polygon
			(pts
				(arc
					(start 188.273182 -342.439498)
					(mid 187.569602 -342.439498)
					(end 188.273182 -342.439498)
				)
			)
		)
	)
	(zone
		(layers "B.Cu" "In13.Cu" "In15.Cu")
		(hatch none 0.5)
		(connect_pads
			(clearance 0)
		)
		(min_thickness 0.25)
		(keepout
			(tracks not_allowed)
			(vias allowed)
			(pads allowed)
			(copperpour not_allowed)
			(footprints allowed)
		)
		(placement
			(enabled no)
			(sheetname "")
		)
		(fill yes
			(thermal_gap 0.5)
			(thermal_bridge_width 0.5)
			(island_removal_mode 0)
		)
		(polygon
			(pts
				(arc
					(start 396.87627 -277.849838)
					(mid 396.22349 -277.849838)
					(end 396.87627 -277.849838)
				)
			)
		)
	)
	(zone
		(layers "B.Cu" "In13.Cu" "In15.Cu")
		(hatch none 0.5)
		(connect_pads
			(clearance 0)
		)
		(min_thickness 0.25)
		(keepout
			(tracks not_allowed)
			(vias allowed)
			(pads allowed)
			(copperpour not_allowed)
			(footprints allowed)
		)
		(placement
			(enabled no)
			(sheetname "")
		)
		(fill yes
			(thermal_gap 0.5)
			(thermal_bridge_width 0.5)
			(island_removal_mode 0)
		)
		(polygon
			(pts
				(arc
					(start 431.409602 -348.58579)
					(mid 430.706022 -348.58579)
					(end 431.409602 -348.58579)
				)
			)
		)
	)
	(zone
		(layers "B.Cu" "In13.Cu" "In15.Cu")
		(hatch none 0.5)
		(connect_pads
			(clearance 0)
		)
		(min_thickness 0.25)
		(keepout
			(tracks not_allowed)
			(vias allowed)
			(pads allowed)
			(copperpour not_allowed)
			(footprints allowed)
		)
		(placement
			(enabled no)
			(sheetname "")
		)
		(fill yes
			(thermal_gap 0.5)
			(thermal_bridge_width 0.5)
			(island_removal_mode 0)
		)
		(polygon
			(pts
				(arc
					(start 283.626306 -279.749504)
					(mid 282.973526 -279.749504)
					(end 283.626306 -279.749504)
				)
			)
		)
	)
	(zone
		(layers "B.Cu" "In13.Cu" "In15.Cu")
		(hatch none 0.5)
		(connect_pads
			(clearance 0)
		)
		(min_thickness 0.25)
		(keepout
			(tracks not_allowed)
			(vias allowed)
			(pads allowed)
			(copperpour not_allowed)
			(footprints allowed)
		)
		(placement
			(enabled no)
			(sheetname "")
		)
		(fill yes
			(thermal_gap 0.5)
			(thermal_bridge_width 0.5)
			(island_removal_mode 0)
		)
		(polygon
			(pts
				(arc
					(start 296.669714 -371.790214)
					(mid 295.910254 -371.790214)
					(end 296.669714 -371.790214)
				)
			)
		)
	)
	(zone
		(layers "B.Cu" "In13.Cu" "In15.Cu")
		(hatch none 0.5)
		(connect_pads
			(clearance 0)
		)
		(min_thickness 0.25)
		(keepout
			(tracks not_allowed)
			(vias allowed)
			(pads allowed)
			(copperpour not_allowed)
			(footprints allowed)
		)
		(placement
			(enabled no)
			(sheetname "")
		)
		(fill yes
			(thermal_gap 0.5)
			(thermal_bridge_width 0.5)
			(island_removal_mode 0)
		)
		(polygon
			(pts
				(arc
					(start 164.68979 -401.690078)
					(mid 163.93033 -401.690078)
					(end 164.68979 -401.690078)
				)
			)
		)
	)
	(zone
		(layers "B.Cu" "In13.Cu" "In15.Cu")
		(hatch none 0.5)
		(connect_pads
			(clearance 0)
		)
		(min_thickness 0.25)
		(keepout
			(tracks not_allowed)
			(vias allowed)
			(pads allowed)
			(copperpour not_allowed)
			(footprints allowed)
		)
		(placement
			(enabled no)
			(sheetname "")
		)
		(fill yes
			(thermal_gap 0.5)
			(thermal_bridge_width 0.5)
			(island_removal_mode 0)
		)
		(polygon
			(pts
				(arc
					(start 38.337998 -354.732082)
					(mid 37.634418 -354.732082)
					(end 38.337998 -354.732082)
				)
			)
		)
	)
	(zone
		(layers "B.Cu" "In13.Cu" "In15.Cu")
		(hatch none 0.5)
		(connect_pads
			(clearance 0)
		)
		(min_thickness 0.25)
		(keepout
			(tracks not_allowed)
			(vias allowed)
			(pads allowed)
			(copperpour not_allowed)
			(footprints allowed)
		)
		(placement
			(enabled no)
			(sheetname "")
		)
		(fill yes
			(thermal_gap 0.5)
			(thermal_bridge_width 0.5)
			(island_removal_mode 0)
		)
		(polygon
			(pts
				(arc
					(start 77.0763 -309.199788)
					(mid 76.42352 -309.199788)
					(end 77.0763 -309.199788)
				)
			)
		)
	)
	(zone
		(layers "B.Cu" "In13.Cu" "In15.Cu")
		(hatch none 0.5)
		(connect_pads
			(clearance 0)
		)
		(min_thickness 0.25)
		(keepout
			(tracks not_allowed)
			(vias allowed)
			(pads allowed)
			(copperpour not_allowed)
			(footprints allowed)
		)
		(placement
			(enabled no)
			(sheetname "")
		)
		(fill yes
			(thermal_gap 0.5)
			(thermal_bridge_width 0.5)
			(island_removal_mode 0)
		)
		(polygon
			(pts
				(arc
					(start 76.12634 -306.349908)
					(mid 75.47356 -306.349908)
					(end 76.12634 -306.349908)
				)
			)
		)
	)
	(zone
		(layers "B.Cu" "In13.Cu" "In15.Cu")
		(hatch none 0.5)
		(connect_pads
			(clearance 0)
		)
		(min_thickness 0.25)
		(keepout
			(tracks not_allowed)
			(vias allowed)
			(pads allowed)
			(copperpour not_allowed)
			(footprints allowed)
		)
		(placement
			(enabled no)
			(sheetname "")
		)
		(fill yes
			(thermal_gap 0.5)
			(thermal_bridge_width 0.5)
			(island_removal_mode 0)
		)
		(polygon
			(pts
				(arc
					(start 169.619422 -354.732082)
					(mid 168.915842 -354.732082)
					(end 169.619422 -354.732082)
				)
			)
		)
	)
	(zone
		(layers "B.Cu" "In13.Cu" "In15.Cu")
		(hatch none 0.5)
		(connect_pads
			(clearance 0)
		)
		(min_thickness 0.25)
		(keepout
			(tracks not_allowed)
			(vias allowed)
			(pads allowed)
			(copperpour not_allowed)
			(footprints allowed)
		)
		(placement
			(enabled no)
			(sheetname "")
		)
		(fill yes
			(thermal_gap 0.5)
			(thermal_bridge_width 0.5)
			(island_removal_mode 0)
		)
		(polygon
			(pts
				(arc
					(start 49.52619 -279.749504)
					(mid 48.87341 -279.749504)
					(end 49.52619 -279.749504)
				)
			)
		)
	)
	(zone
		(layers "B.Cu" "In13.Cu" "In15.Cu")
		(hatch none 0.5)
		(connect_pads
			(clearance 0)
		)
		(min_thickness 0.25)
		(keepout
			(tracks not_allowed)
			(vias allowed)
			(pads allowed)
			(copperpour not_allowed)
			(footprints allowed)
		)
		(placement
			(enabled no)
			(sheetname "")
		)
		(fill yes
			(thermal_gap 0.5)
			(thermal_bridge_width 0.5)
			(island_removal_mode 0)
		)
		(polygon
			(pts
				(arc
					(start 251.857002 -28.250642)
					(mid 251.153422 -28.250642)
					(end 251.857002 -28.250642)
				)
			)
		)
	)
	(zone
		(layers "B.Cu" "In13.Cu" "In15.Cu")
		(hatch none 0.5)
		(connect_pads
			(clearance 0)
		)
		(min_thickness 0.25)
		(keepout
			(tracks not_allowed)
			(vias allowed)
			(pads allowed)
			(copperpour not_allowed)
			(footprints allowed)
		)
		(placement
			(enabled no)
			(sheetname "")
		)
		(fill yes
			(thermal_gap 0.5)
			(thermal_bridge_width 0.5)
			(island_removal_mode 0)
		)
		(polygon
			(pts
				(arc
					(start 50.773838 -354.732082)
					(mid 50.070258 -354.732082)
					(end 50.773838 -354.732082)
				)
			)
		)
	)
	(zone
		(layers "B.Cu" "In13.Cu" "In15.Cu")
		(hatch none 0.5)
		(connect_pads
			(clearance 0)
		)
		(min_thickness 0.25)
		(keepout
			(tracks not_allowed)
			(vias allowed)
			(pads allowed)
			(copperpour not_allowed)
			(footprints allowed)
		)
		(placement
			(enabled no)
			(sheetname "")
		)
		(fill yes
			(thermal_gap 0.5)
			(thermal_bridge_width 0.5)
			(island_removal_mode 0)
		)
		(polygon
			(pts
				(arc
					(start 410.510482 -345.465146)
					(mid 409.806902 -345.465146)
					(end 410.510482 -345.465146)
				)
			)
		)
	)
	(zone
		(layers "B.Cu" "In13.Cu" "In15.Cu")
		(hatch none 0.5)
		(connect_pads
			(clearance 0)
		)
		(min_thickness 0.25)
		(keepout
			(tracks not_allowed)
			(vias allowed)
			(pads allowed)
			(copperpour not_allowed)
			(footprints allowed)
		)
		(placement
			(enabled no)
			(sheetname "")
		)
		(fill yes
			(thermal_gap 0.5)
			(thermal_bridge_width 0.5)
			(island_removal_mode 0)
		)
		(polygon
			(pts
				(arc
					(start 41.446958 -348.58579)
					(mid 40.743378 -348.58579)
					(end 41.446958 -348.58579)
				)
			)
		)
	)
	(zone
		(layers "B.Cu" "In13.Cu" "In15.Cu")
		(hatch none 0.5)
		(connect_pads
			(clearance 0)
		)
		(min_thickness 0.25)
		(keepout
			(tracks not_allowed)
			(vias allowed)
			(pads allowed)
			(copperpour not_allowed)
			(footprints allowed)
		)
		(placement
			(enabled no)
			(sheetname "")
		)
		(fill yes
			(thermal_gap 0.5)
			(thermal_bridge_width 0.5)
			(island_removal_mode 0)
		)
		(polygon
			(pts
				(arc
					(start 269.112492 -342.439498)
					(mid 268.408912 -342.439498)
					(end 269.112492 -342.439498)
				)
			)
		)
	)
	(zone
		(layers "B.Cu" "In13.Cu" "In15.Cu")
		(hatch none 0.5)
		(connect_pads
			(clearance 0)
		)
		(min_thickness 0.25)
		(keepout
			(tracks not_allowed)
			(vias allowed)
			(pads allowed)
			(copperpour not_allowed)
			(footprints allowed)
		)
		(placement
			(enabled no)
			(sheetname "")
		)
		(fill yes
			(thermal_gap 0.5)
			(thermal_bridge_width 0.5)
			(island_removal_mode 0)
		)
		(polygon
			(pts
				(arc
					(start 424.269662 -400.390106)
					(mid 423.510202 -400.390106)
					(end 424.269662 -400.390106)
				)
			)
		)
	)
	(zone
		(layers "B.Cu" "In13.Cu" "In15.Cu")
		(hatch none 0.5)
		(connect_pads
			(clearance 0)
		)
		(min_thickness 0.25)
		(keepout
			(tracks not_allowed)
			(vias allowed)
			(pads allowed)
			(copperpour not_allowed)
			(footprints allowed)
		)
		(placement
			(enabled no)
			(sheetname "")
		)
		(fill yes
			(thermal_gap 0.5)
			(thermal_bridge_width 0.5)
			(island_removal_mode 0)
		)
		(polygon
			(pts
				(arc
					(start 440.736482 -342.439498)
					(mid 440.032902 -342.439498)
					(end 440.736482 -342.439498)
				)
			)
		)
	)
	(zone
		(layers "B.Cu" "In13.Cu" "In15.Cu")
		(hatch none 0.5)
		(connect_pads
			(clearance 0)
		)
		(min_thickness 0.25)
		(keepout
			(tracks not_allowed)
			(vias allowed)
			(pads allowed)
			(copperpour not_allowed)
			(footprints allowed)
		)
		(placement
			(enabled no)
			(sheetname "")
		)
		(fill yes
			(thermal_gap 0.5)
			(thermal_bridge_width 0.5)
			(island_removal_mode 0)
		)
		(polygon
			(pts
				(arc
					(start 287.766252 -345.465146)
					(mid 287.062672 -345.465146)
					(end 287.766252 -345.465146)
				)
			)
		)
	)
	(zone
		(layers "B.Cu" "In13.Cu" "In15.Cu")
		(hatch none 0.5)
		(connect_pads
			(clearance 0)
		)
		(min_thickness 0.25)
		(keepout
			(tracks not_allowed)
			(vias allowed)
			(pads allowed)
			(copperpour not_allowed)
			(footprints allowed)
		)
		(placement
			(enabled no)
			(sheetname "")
		)
		(fill yes
			(thermal_gap 0.5)
			(thermal_bridge_width 0.5)
			(island_removal_mode 0)
		)
		(polygon
			(pts
				(arc
					(start 391.176256 -307.299868)
					(mid 390.523476 -307.299868)
					(end 391.176256 -307.299868)
				)
			)
		)
	)
	(zone
		(layers "B.Cu" "In13.Cu" "In15.Cu")
		(hatch none 0.5)
		(connect_pads
			(clearance 0)
		)
		(min_thickness 0.25)
		(keepout
			(tracks not_allowed)
			(vias allowed)
			(pads allowed)
			(copperpour not_allowed)
			(footprints allowed)
		)
		(placement
			(enabled no)
			(sheetname "")
		)
		(fill yes
			(thermal_gap 0.5)
			(thermal_bridge_width 0.5)
			(island_removal_mode 0)
		)
		(polygon
			(pts
				(arc
					(start 43.689778 -397.59001)
					(mid 42.930318 -397.59001)
					(end 43.689778 -397.59001)
				)
			)
		)
	)
	(zone
		(layers "B.Cu" "In13.Cu" "In15.Cu")
		(hatch none 0.5)
		(connect_pads
			(clearance 0)
		)
		(min_thickness 0.25)
		(keepout
			(tracks not_allowed)
			(vias allowed)
			(pads allowed)
			(copperpour not_allowed)
			(footprints allowed)
		)
		(placement
			(enabled no)
			(sheetname "")
		)
		(fill yes
			(thermal_gap 0.5)
			(thermal_bridge_width 0.5)
			(island_removal_mode 0)
		)
		(polygon
			(pts
				(arc
					(start 213.757002 -31.850584)
					(mid 213.053422 -31.850584)
					(end 213.757002 -31.850584)
				)
			)
		)
	)
	(zone
		(layers "B.Cu" "In13.Cu" "In15.Cu")
		(hatch none 0.5)
		(connect_pads
			(clearance 0)
		)
		(min_thickness 0.25)
		(keepout
			(tracks not_allowed)
			(vias allowed)
			(pads allowed)
			(copperpour not_allowed)
			(footprints allowed)
		)
		(placement
			(enabled no)
			(sheetname "")
		)
		(fill yes
			(thermal_gap 0.5)
			(thermal_bridge_width 0.5)
			(island_removal_mode 0)
		)
		(polygon
			(pts
				(arc
					(start 293.120572 -354.732082)
					(mid 292.416992 -354.732082)
					(end 293.120572 -354.732082)
				)
			)
		)
	)
	(zone
		(layers "B.Cu" "In13.Cu" "In15.Cu")
		(hatch none 0.5)
		(connect_pads
			(clearance 0)
		)
		(min_thickness 0.25)
		(keepout
			(tracks not_allowed)
			(vias allowed)
			(pads allowed)
			(copperpour not_allowed)
			(footprints allowed)
		)
		(placement
			(enabled no)
			(sheetname "")
		)
		(fill yes
			(thermal_gap 0.5)
			(thermal_bridge_width 0.5)
			(island_removal_mode 0)
		)
		(polygon
			(pts
				(arc
					(start 216.39911 -30.05709)
					(mid 215.69553 -30.05709)
					(end 216.39911 -30.05709)
				)
			)
		)
	)
	(zone
		(layers "B.Cu" "In13.Cu" "In15.Cu")
		(hatch none 0.5)
		(connect_pads
			(clearance 0)
		)
		(min_thickness 0.25)
		(keepout
			(tracks not_allowed)
			(vias allowed)
			(pads allowed)
			(copperpour not_allowed)
			(footprints allowed)
		)
		(placement
			(enabled no)
			(sheetname "")
		)
		(fill yes
			(thermal_gap 0.5)
			(thermal_bridge_width 0.5)
			(island_removal_mode 0)
		)
		(polygon
			(pts
				(arc
					(start 76.12634 -311.099962)
					(mid 75.47356 -311.099962)
					(end 76.12634 -311.099962)
				)
			)
		)
	)
	(zone
		(layers "B.Cu" "In13.Cu" "In15.Cu")
		(hatch none 0.5)
		(connect_pads
			(clearance 0)
		)
		(min_thickness 0.25)
		(keepout
			(tracks not_allowed)
			(vias allowed)
			(pads allowed)
			(copperpour not_allowed)
			(footprints allowed)
		)
		(placement
			(enabled no)
			(sheetname "")
		)
		(fill yes
			(thermal_gap 0.5)
			(thermal_bridge_width 0.5)
			(island_removal_mode 0)
		)
		(polygon
			(pts
				(arc
					(start 193.627502 -345.465146)
					(mid 192.923922 -345.465146)
					(end 193.627502 -345.465146)
				)
			)
		)
	)
	(zone
		(layers "B.Cu" "In13.Cu" "In15.Cu")
		(hatch none 0.5)
		(connect_pads
			(clearance 0)
		)
		(min_thickness 0.25)
		(keepout
			(tracks not_allowed)
			(vias allowed)
			(pads allowed)
			(copperpour not_allowed)
			(footprints allowed)
		)
		(placement
			(enabled no)
			(sheetname "")
		)
		(fill yes
			(thermal_gap 0.5)
			(thermal_bridge_width 0.5)
			(island_removal_mode 0)
		)
		(polygon
			(pts
				(arc
					(start 281.548332 -342.439498)
					(mid 280.844752 -342.439498)
					(end 281.548332 -342.439498)
				)
			)
		)
	)
	(zone
		(layers "B.Cu" "In13.Cu" "In15.Cu")
		(hatch none 0.5)
		(connect_pads
			(clearance 0)
		)
		(min_thickness 0.25)
		(keepout
			(tracks not_allowed)
			(vias allowed)
			(pads allowed)
			(copperpour not_allowed)
			(footprints allowed)
		)
		(placement
			(enabled no)
			(sheetname "")
		)
		(fill yes
			(thermal_gap 0.5)
			(thermal_bridge_width 0.5)
			(island_removal_mode 0)
		)
		(polygon
			(pts
				(arc
					(start 32.983678 -342.439498)
					(mid 32.280098 -342.439498)
					(end 32.983678 -342.439498)
				)
			)
		)
	)
	(zone
		(layers "B.Cu" "In13.Cu" "In15.Cu")
		(hatch none 0.5)
		(connect_pads
			(clearance 0)
		)
		(min_thickness 0.25)
		(keepout
			(tracks not_allowed)
			(vias allowed)
			(pads allowed)
			(copperpour not_allowed)
			(footprints allowed)
		)
		(placement
			(enabled no)
			(sheetname "")
		)
		(fill yes
			(thermal_gap 0.5)
			(thermal_bridge_width 0.5)
			(island_removal_mode 0)
		)
		(polygon
			(pts
				(arc
					(start 424.269662 -401.690078)
					(mid 423.510202 -401.690078)
					(end 424.269662 -401.690078)
				)
			)
		)
	)
	(zone
		(layers "B.Cu" "In13.Cu" "In15.Cu")
		(hatch none 0.5)
		(connect_pads
			(clearance 0)
		)
		(min_thickness 0.25)
		(keepout
			(tracks not_allowed)
			(vias allowed)
			(pads allowed)
			(copperpour not_allowed)
			(footprints allowed)
		)
		(placement
			(enabled no)
			(sheetname "")
		)
		(fill yes
			(thermal_gap 0.5)
			(thermal_bridge_width 0.5)
			(island_removal_mode 0)
		)
		(polygon
			(pts
				(arc
					(start 440.736482 -354.732082)
					(mid 440.032902 -354.732082)
					(end 440.736482 -354.732082)
				)
			)
		)
	)
	(zone
		(layers "B.Cu" "In13.Cu" "In15.Cu")
		(hatch none 0.5)
		(connect_pads
			(clearance 0)
		)
		(min_thickness 0.25)
		(keepout
			(tracks not_allowed)
			(vias allowed)
			(pads allowed)
			(copperpour not_allowed)
			(footprints allowed)
		)
		(placement
			(enabled no)
			(sheetname "")
		)
		(fill yes
			(thermal_gap 0.5)
			(thermal_bridge_width 0.5)
			(island_removal_mode 0)
		)
		(polygon
			(pts
				(arc
					(start 28.289758 -370.489988)
					(mid 27.530298 -370.489988)
					(end 28.289758 -370.489988)
				)
			)
		)
	)
	(zone
		(layers "B.Cu" "In13.Cu" "In15.Cu")
		(hatch none 0.5)
		(connect_pads
			(clearance 0)
		)
		(min_thickness 0.25)
		(keepout
			(tracks not_allowed)
			(vias allowed)
			(pads allowed)
			(copperpour not_allowed)
			(footprints allowed)
		)
		(placement
			(enabled no)
			(sheetname "")
		)
		(fill yes
			(thermal_gap 0.5)
			(thermal_bridge_width 0.5)
			(island_removal_mode 0)
		)
		(polygon
			(pts
				(arc
					(start 272.221452 -351.611438)
					(mid 271.517872 -351.611438)
					(end 272.221452 -351.611438)
				)
			)
		)
	)
	(zone
		(layers "B.Cu" "In13.Cu" "In15.Cu")
		(hatch none 0.5)
		(connect_pads
			(clearance 0)
		)
		(min_thickness 0.25)
		(keepout
			(tracks not_allowed)
			(vias allowed)
			(pads allowed)
			(copperpour not_allowed)
			(footprints allowed)
		)
		(placement
			(enabled no)
			(sheetname "")
		)
		(fill yes
			(thermal_gap 0.5)
			(thermal_bridge_width 0.5)
			(island_removal_mode 0)
		)
		(polygon
			(pts
				(arc
					(start 50.47615 -277.849838)
					(mid 49.82337 -277.849838)
					(end 50.47615 -277.849838)
				)
			)
		)
	)
	(zone
		(layers "B.Cu" "In13.Cu" "In15.Cu")
		(hatch none 0.5)
		(connect_pads
			(clearance 0)
		)
		(min_thickness 0.25)
		(keepout
			(tracks not_allowed)
			(vias allowed)
			(pads allowed)
			(copperpour not_allowed)
			(footprints allowed)
		)
		(placement
			(enabled no)
			(sheetname "")
		)
		(fill yes
			(thermal_gap 0.5)
			(thermal_bridge_width 0.5)
			(island_removal_mode 0)
		)
		(polygon
			(pts
				(arc
					(start 391.176256 -301.599854)
					(mid 390.523476 -301.599854)
					(end 391.176256 -301.599854)
				)
			)
		)
	)
	(zone
		(layers "B.Cu" "In13.Cu" "In15.Cu")
		(hatch none 0.5)
		(connect_pads
			(clearance 0)
		)
		(min_thickness 0.25)
		(keepout
			(tracks not_allowed)
			(vias allowed)
			(pads allowed)
			(copperpour not_allowed)
			(footprints allowed)
		)
		(placement
			(enabled no)
			(sheetname "")
		)
		(fill yes
			(thermal_gap 0.5)
			(thermal_bridge_width 0.5)
			(island_removal_mode 0)
		)
		(polygon
			(pts
				(arc
					(start 332.498954 -30.05709)
					(mid 331.795374 -30.05709)
					(end 332.498954 -30.05709)
				)
			)
		)
	)
	(zone
		(layers "B.Cu" "In13.Cu" "In15.Cu")
		(hatch none 0.5)
		(connect_pads
			(clearance 0)
		)
		(min_thickness 0.25)
		(keepout
			(tracks not_allowed)
			(vias allowed)
			(pads allowed)
			(copperpour not_allowed)
			(footprints allowed)
		)
		(placement
			(enabled no)
			(sheetname "")
		)
		(fill yes
			(thermal_gap 0.5)
			(thermal_bridge_width 0.5)
			(island_removal_mode 0)
		)
		(polygon
			(pts
				(arc
					(start 25.902158 -357.75773)
					(mid 25.198578 -357.75773)
					(end 25.902158 -357.75773)
				)
			)
		)
	)
	(zone
		(layers "B.Cu" "In13.Cu" "In15.Cu")
		(hatch none 0.5)
		(connect_pads
			(clearance 0)
		)
		(min_thickness 0.25)
		(keepout
			(tracks not_allowed)
			(vias allowed)
			(pads allowed)
			(copperpour not_allowed)
			(footprints allowed)
		)
		(placement
			(enabled no)
			(sheetname "")
		)
		(fill yes
			(thermal_gap 0.5)
			(thermal_bridge_width 0.5)
			(island_removal_mode 0)
		)
		(polygon
			(pts
				(arc
					(start 155.176474 -313.949842)
					(mid 154.523694 -313.949842)
					(end 155.176474 -313.949842)
				)
			)
		)
	)
	(zone
		(layers "B.Cu" "In13.Cu" "In15.Cu")
		(hatch none 0.5)
		(connect_pads
			(clearance 0)
		)
		(min_thickness 0.25)
		(keepout
			(tracks not_allowed)
			(vias allowed)
			(pads allowed)
			(copperpour not_allowed)
			(footprints allowed)
		)
		(placement
			(enabled no)
			(sheetname "")
		)
		(fill yes
			(thermal_gap 0.5)
			(thermal_bridge_width 0.5)
			(island_removal_mode 0)
		)
		(polygon
			(pts
				(arc
					(start 419.86962 -400.390106)
					(mid 419.11016 -400.390106)
					(end 419.86962 -400.390106)
				)
			)
		)
	)
	(zone
		(layers "B.Cu" "In13.Cu" "In15.Cu")
		(hatch none 0.5)
		(connect_pads
			(clearance 0)
		)
		(min_thickness 0.25)
		(keepout
			(tracks not_allowed)
			(vias allowed)
			(pads allowed)
			(copperpour not_allowed)
			(footprints allowed)
		)
		(placement
			(enabled no)
			(sheetname "")
		)
		(fill yes
			(thermal_gap 0.5)
			(thermal_bridge_width 0.5)
			(island_removal_mode 0)
		)
		(polygon
			(pts
				(arc
					(start 39.289736 -372.890034)
					(mid 38.530276 -372.890034)
					(end 39.289736 -372.890034)
				)
			)
		)
	)
	(zone
		(layers "B.Cu" "In13.Cu" "In15.Cu")
		(hatch none 0.5)
		(connect_pads
			(clearance 0)
		)
		(min_thickness 0.25)
		(keepout
			(tracks not_allowed)
			(vias allowed)
			(pads allowed)
			(copperpour not_allowed)
			(footprints allowed)
		)
		(placement
			(enabled no)
			(sheetname "")
		)
		(fill yes
			(thermal_gap 0.5)
			(thermal_bridge_width 0.5)
			(island_removal_mode 0)
		)
		(polygon
			(pts
				(arc
					(start 329.856846 -29.114242)
					(mid 329.153266 -29.114242)
					(end 329.856846 -29.114242)
				)
			)
		)
	)
	(zone
		(layers "B.Cu" "In13.Cu" "In15.Cu")
		(hatch none 0.5)
		(connect_pads
			(clearance 0)
		)
		(min_thickness 0.25)
		(keepout
			(tracks not_allowed)
			(vias allowed)
			(pads allowed)
			(copperpour not_allowed)
			(footprints allowed)
		)
		(placement
			(enabled no)
			(sheetname "")
		)
		(fill yes
			(thermal_gap 0.5)
			(thermal_bridge_width 0.5)
			(island_removal_mode 0)
		)
		(polygon
			(pts
				(arc
					(start 298.869608 -398.890236)
					(mid 298.110148 -398.890236)
					(end 298.869608 -398.890236)
				)
			)
		)
	)
	(zone
		(layers "B.Cu" "In13.Cu" "In15.Cu")
		(hatch none 0.5)
		(connect_pads
			(clearance 0)
		)
		(min_thickness 0.25)
		(keepout
			(tracks not_allowed)
			(vias allowed)
			(pads allowed)
			(copperpour not_allowed)
			(footprints allowed)
		)
		(placement
			(enabled no)
			(sheetname "")
		)
		(fill yes
			(thermal_gap 0.5)
			(thermal_bridge_width 0.5)
			(island_removal_mode 0)
		)
		(polygon
			(pts
				(arc
					(start 171.864782 -351.611438)
					(mid 171.161202 -351.611438)
					(end 171.864782 -351.611438)
				)
			)
		)
	)
	(zone
		(layers "B.Cu" "In13.Cu" "In15.Cu")
		(hatch none 0.5)
		(connect_pads
			(clearance 0)
		)
		(min_thickness 0.25)
		(keepout
			(tracks not_allowed)
			(vias allowed)
			(pads allowed)
			(copperpour not_allowed)
			(footprints allowed)
		)
		(placement
			(enabled no)
			(sheetname "")
		)
		(fill yes
			(thermal_gap 0.5)
			(thermal_bridge_width 0.5)
			(island_removal_mode 0)
		)
		(polygon
			(pts
				(arc
					(start 166.576248 -278.799798)
					(mid 165.923468 -278.799798)
					(end 166.576248 -278.799798)
				)
			)
		)
	)
	(zone
		(layers "B.Cu" "In13.Cu" "In15.Cu")
		(hatch none 0.5)
		(connect_pads
			(clearance 0)
		)
		(min_thickness 0.25)
		(keepout
			(tracks not_allowed)
			(vias allowed)
			(pads allowed)
			(copperpour not_allowed)
			(footprints allowed)
		)
		(placement
			(enabled no)
			(sheetname "")
		)
		(fill yes
			(thermal_gap 0.5)
			(thermal_bridge_width 0.5)
			(island_removal_mode 0)
		)
		(polygon
			(pts
				(arc
					(start 81.826354 -312.049922)
					(mid 81.173574 -312.049922)
					(end 81.826354 -312.049922)
				)
			)
		)
	)
	(zone
		(layers "B.Cu" "In13.Cu" "In15.Cu")
		(hatch none 0.5)
		(connect_pads
			(clearance 0)
		)
		(min_thickness 0.25)
		(keepout
			(tracks not_allowed)
			(vias allowed)
			(pads allowed)
			(copperpour not_allowed)
			(footprints allowed)
		)
		(placement
			(enabled no)
			(sheetname "")
		)
		(fill yes
			(thermal_gap 0.5)
			(thermal_bridge_width 0.5)
			(island_removal_mode 0)
		)
		(polygon
			(pts
				(arc
					(start 173.48962 -375.69013)
					(mid 172.73016 -375.69013)
					(end 173.48962 -375.69013)
				)
			)
		)
	)
	(zone
		(layers "B.Cu" "In13.Cu" "In15.Cu")
		(hatch none 0.5)
		(connect_pads
			(clearance 0)
		)
		(min_thickness 0.25)
		(keepout
			(tracks not_allowed)
			(vias allowed)
			(pads allowed)
			(copperpour not_allowed)
			(footprints allowed)
		)
		(placement
			(enabled no)
			(sheetname "")
		)
		(fill yes
			(thermal_gap 0.5)
			(thermal_bridge_width 0.5)
			(island_removal_mode 0)
		)
		(polygon
			(pts
				(arc
					(start 44.776136 -277.849838)
					(mid 44.123356 -277.849838)
					(end 44.776136 -277.849838)
				)
			)
		)
	)
	(zone
		(layers "B.Cu" "In13.Cu" "In15.Cu")
		(hatch none 0.5)
		(connect_pads
			(clearance 0)
		)
		(min_thickness 0.25)
		(keepout
			(tracks not_allowed)
			(vias allowed)
			(pads allowed)
			(copperpour not_allowed)
			(footprints allowed)
		)
		(placement
			(enabled no)
			(sheetname "")
		)
		(fill yes
			(thermal_gap 0.5)
			(thermal_bridge_width 0.5)
			(island_removal_mode 0)
		)
		(polygon
			(pts
				(arc
					(start 307.376322 -313.949842)
					(mid 306.723542 -313.949842)
					(end 307.376322 -313.949842)
				)
			)
		)
	)
	(zone
		(layers "B.Cu" "In13.Cu" "In15.Cu")
		(hatch none 0.5)
		(connect_pads
			(clearance 0)
		)
		(min_thickness 0.25)
		(keepout
			(tracks not_allowed)
			(vias allowed)
			(pads allowed)
			(copperpour not_allowed)
			(footprints allowed)
		)
		(placement
			(enabled no)
			(sheetname "")
		)
		(fill yes
			(thermal_gap 0.5)
			(thermal_bridge_width 0.5)
			(island_removal_mode 0)
		)
		(polygon
			(pts
				(arc
					(start 310.226202 -312.049922)
					(mid 309.573422 -312.049922)
					(end 310.226202 -312.049922)
				)
			)
		)
	)
	(zone
		(layers "B.Cu" "In13.Cu" "In15.Cu")
		(hatch none 0.5)
		(connect_pads
			(clearance 0)
		)
		(min_thickness 0.25)
		(keepout
			(tracks not_allowed)
			(vias allowed)
			(pads allowed)
			(copperpour not_allowed)
			(footprints allowed)
		)
		(placement
			(enabled no)
			(sheetname "")
		)
		(fill yes
			(thermal_gap 0.5)
			(thermal_bridge_width 0.5)
			(island_removal_mode 0)
		)
		(polygon
			(pts
				(arc
					(start 168.476422 -278.799798)
					(mid 167.823642 -278.799798)
					(end 168.476422 -278.799798)
				)
			)
		)
	)
	(zone
		(layers "B.Cu" "In13.Cu" "In15.Cu")
		(hatch none 0.5)
		(connect_pads
			(clearance 0)
		)
		(min_thickness 0.25)
		(keepout
			(tracks not_allowed)
			(vias allowed)
			(pads allowed)
			(copperpour not_allowed)
			(footprints allowed)
		)
		(placement
			(enabled no)
			(sheetname "")
		)
		(fill yes
			(thermal_gap 0.5)
			(thermal_bridge_width 0.5)
			(island_removal_mode 0)
		)
		(polygon
			(pts
				(arc
					(start 74.299064 -34.520886)
					(mid 73.595484 -34.520886)
					(end 74.299064 -34.520886)
				)
			)
		)
	)
	(zone
		(layers "B.Cu" "In13.Cu" "In15.Cu")
		(hatch none 0.5)
		(connect_pads
			(clearance 0)
		)
		(min_thickness 0.25)
		(keepout
			(tracks not_allowed)
			(vias allowed)
			(pads allowed)
			(copperpour not_allowed)
			(footprints allowed)
		)
		(placement
			(enabled no)
			(sheetname "")
		)
		(fill yes
			(thermal_gap 0.5)
			(thermal_bridge_width 0.5)
			(island_removal_mode 0)
		)
		(polygon
			(pts
				(arc
					(start 390.226296 -312.049922)
					(mid 389.573516 -312.049922)
					(end 390.226296 -312.049922)
				)
			)
		)
	)
	(zone
		(layers "B.Cu" "In13.Cu" "In15.Cu")
		(hatch none 0.5)
		(connect_pads
			(clearance 0)
		)
		(min_thickness 0.25)
		(keepout
			(tracks not_allowed)
			(vias allowed)
			(pads allowed)
			(copperpour not_allowed)
			(footprints allowed)
		)
		(placement
			(enabled no)
			(sheetname "")
		)
		(fill yes
			(thermal_gap 0.5)
			(thermal_bridge_width 0.5)
			(island_removal_mode 0)
		)
		(polygon
			(pts
				(arc
					(start 415.864802 -357.75773)
					(mid 415.161222 -357.75773)
					(end 415.864802 -357.75773)
				)
			)
		)
	)
	(zone
		(layers "B.Cu" "In13.Cu" "In15.Cu")
		(hatch none 0.5)
		(connect_pads
			(clearance 0)
		)
		(min_thickness 0.25)
		(keepout
			(tracks not_allowed)
			(vias allowed)
			(pads allowed)
			(copperpour not_allowed)
			(footprints allowed)
		)
		(placement
			(enabled no)
			(sheetname "")
		)
		(fill yes
			(thermal_gap 0.5)
			(thermal_bridge_width 0.5)
			(island_removal_mode 0)
		)
		(polygon
			(pts
				(arc
					(start 287.86963 -396.49019)
					(mid 287.11017 -396.49019)
					(end 287.86963 -396.49019)
				)
			)
		)
	)
	(zone
		(layers "B.Cu" "In13.Cu" "In15.Cu")
		(hatch none 0.5)
		(connect_pads
			(clearance 0)
		)
		(min_thickness 0.25)
		(keepout
			(tracks not_allowed)
			(vias allowed)
			(pads allowed)
			(copperpour not_allowed)
			(footprints allowed)
		)
		(placement
			(enabled no)
			(sheetname "")
		)
		(fill yes
			(thermal_gap 0.5)
			(thermal_bridge_width 0.5)
			(island_removal_mode 0)
		)
		(polygon
			(pts
				(arc
					(start 332.498954 -30.92069)
					(mid 331.795374 -30.92069)
					(end 332.498954 -30.92069)
				)
			)
		)
	)
	(zone
		(layers "B.Cu" "In13.Cu" "In15.Cu")
		(hatch none 0.5)
		(connect_pads
			(clearance 0)
		)
		(min_thickness 0.25)
		(keepout
			(tracks not_allowed)
			(vias allowed)
			(pads allowed)
			(copperpour not_allowed)
			(footprints allowed)
		)
		(placement
			(enabled no)
			(sheetname "")
		)
		(fill yes
			(thermal_gap 0.5)
			(thermal_bridge_width 0.5)
			(island_removal_mode 0)
		)
		(polygon
			(pts
				(arc
					(start 290.011612 -351.611438)
					(mid 289.308032 -351.611438)
					(end 290.011612 -351.611438)
				)
			)
		)
	)
	(zone
		(layers "B.Cu" "In13.Cu" "In15.Cu")
		(hatch none 0.5)
		(connect_pads
			(clearance 0)
		)
		(min_thickness 0.25)
		(keepout
			(tracks not_allowed)
			(vias allowed)
			(pads allowed)
			(copperpour not_allowed)
			(footprints allowed)
		)
		(placement
			(enabled no)
			(sheetname "")
		)
		(fill yes
			(thermal_gap 0.5)
			(thermal_bridge_width 0.5)
			(island_removal_mode 0)
		)
		(polygon
			(pts
				(arc
					(start 418.973762 -348.58579)
					(mid 418.270182 -348.58579)
					(end 418.973762 -348.58579)
				)
			)
		)
	)
	(zone
		(layers "B.Cu" "In13.Cu" "In15.Cu")
		(hatch none 0.5)
		(connect_pads
			(clearance 0)
		)
		(min_thickness 0.25)
		(keepout
			(tracks not_allowed)
			(vias allowed)
			(pads allowed)
			(copperpour not_allowed)
			(footprints allowed)
		)
		(placement
			(enabled no)
			(sheetname "")
		)
		(fill yes
			(thermal_gap 0.5)
			(thermal_bridge_width 0.5)
			(island_removal_mode 0)
		)
		(polygon
			(pts
				(arc
					(start 329.856846 -28.250642)
					(mid 329.153266 -28.250642)
					(end 329.856846 -28.250642)
				)
			)
		)
	)
	(zone
		(layers "B.Cu" "In13.Cu" "In15.Cu")
		(hatch none 0.5)
		(connect_pads
			(clearance 0)
		)
		(min_thickness 0.25)
		(keepout
			(tracks not_allowed)
			(vias allowed)
			(pads allowed)
			(copperpour not_allowed)
			(footprints allowed)
		)
		(placement
			(enabled no)
			(sheetname "")
		)
		(fill yes
			(thermal_gap 0.5)
			(thermal_bridge_width 0.5)
			(island_removal_mode 0)
		)
		(polygon
			(pts
				(arc
					(start 43.689778 -371.590062)
					(mid 42.930318 -371.590062)
					(end 43.689778 -371.590062)
				)
			)
		)
	)
	(zone
		(layers "B.Cu" "In13.Cu" "In15.Cu")
		(hatch none 0.5)
		(connect_pads
			(clearance 0)
		)
		(min_thickness 0.25)
		(keepout
			(tracks not_allowed)
			(vias allowed)
			(pads allowed)
			(copperpour not_allowed)
			(footprints allowed)
		)
		(placement
			(enabled no)
			(sheetname "")
		)
		(fill yes
			(thermal_gap 0.5)
			(thermal_bridge_width 0.5)
			(island_removal_mode 0)
		)
		(polygon
			(pts
				(arc
					(start 162.776408 -277.849838)
					(mid 162.123628 -277.849838)
					(end 162.776408 -277.849838)
				)
			)
		)
	)
	(zone
		(layers "B.Cu" "In13.Cu" "In15.Cu")
		(hatch none 0.5)
		(connect_pads
			(clearance 0)
		)
		(min_thickness 0.25)
		(keepout
			(tracks not_allowed)
			(vias allowed)
			(pads allowed)
			(copperpour not_allowed)
			(footprints allowed)
		)
		(placement
			(enabled no)
			(sheetname "")
		)
		(fill yes
			(thermal_gap 0.5)
			(thermal_bridge_width 0.5)
			(island_removal_mode 0)
		)
		(polygon
			(pts
				(arc
					(start 78.02626 -305.399948)
					(mid 77.37348 -305.399948)
					(end 78.02626 -305.399948)
				)
			)
		)
	)
	(zone
		(layers "B.Cu" "In13.Cu" "In15.Cu")
		(hatch none 0.5)
		(connect_pads
			(clearance 0)
		)
		(min_thickness 0.25)
		(keepout
			(tracks not_allowed)
			(vias allowed)
			(pads allowed)
			(copperpour not_allowed)
			(footprints allowed)
		)
		(placement
			(enabled no)
			(sheetname "")
		)
		(fill yes
			(thermal_gap 0.5)
			(thermal_bridge_width 0.5)
			(island_removal_mode 0)
		)
		(polygon
			(pts
				(arc
					(start 173.226222 -280.699718)
					(mid 172.573442 -280.699718)
					(end 173.226222 -280.699718)
				)
			)
		)
	)
	(zone
		(layers "B.Cu" "In13.Cu" "In15.Cu")
		(hatch none 0.5)
		(connect_pads
			(clearance 0)
		)
		(min_thickness 0.25)
		(keepout
			(tracks not_allowed)
			(vias allowed)
			(pads allowed)
			(copperpour not_allowed)
			(footprints allowed)
		)
		(placement
			(enabled no)
			(sheetname "")
		)
		(fill yes
			(thermal_gap 0.5)
			(thermal_bridge_width 0.5)
			(island_removal_mode 0)
		)
		(polygon
			(pts
				(arc
					(start 422.946322 -342.439498)
					(mid 422.242742 -342.439498)
					(end 422.946322 -342.439498)
				)
			)
		)
	)
	(zone
		(layers "B.Cu" "In13.Cu" "In15.Cu")
		(hatch none 0.5)
		(connect_pads
			(clearance 0)
		)
		(min_thickness 0.25)
		(keepout
			(tracks not_allowed)
			(vias allowed)
			(pads allowed)
			(copperpour not_allowed)
			(footprints allowed)
		)
		(placement
			(enabled no)
			(sheetname "")
		)
		(fill yes
			(thermal_gap 0.5)
			(thermal_bridge_width 0.5)
			(island_removal_mode 0)
		)
		(polygon
			(pts
				(arc
					(start 165.626288 -279.749504)
					(mid 164.973508 -279.749504)
					(end 165.626288 -279.749504)
				)
			)
		)
	)
	(zone
		(layers "B.Cu" "In13.Cu" "In15.Cu")
		(hatch none 0.5)
		(connect_pads
			(clearance 0)
		)
		(min_thickness 0.25)
		(keepout
			(tracks not_allowed)
			(vias allowed)
			(pads allowed)
			(copperpour not_allowed)
			(footprints allowed)
		)
		(placement
			(enabled no)
			(sheetname "")
		)
		(fill yes
			(thermal_gap 0.5)
			(thermal_bridge_width 0.5)
			(island_removal_mode 0)
		)
		(polygon
			(pts
				(arc
					(start 418.973762 -351.611438)
					(mid 418.270182 -351.611438)
					(end 418.973762 -351.611438)
				)
			)
		)
	)
	(zone
		(layers "B.Cu" "In13.Cu" "In15.Cu")
		(hatch none 0.5)
		(connect_pads
			(clearance 0)
		)
		(min_thickness 0.25)
		(keepout
			(tracks not_allowed)
			(vias allowed)
			(pads allowed)
			(copperpour not_allowed)
			(footprints allowed)
		)
		(placement
			(enabled no)
			(sheetname "")
		)
		(fill yes
			(thermal_gap 0.5)
			(thermal_bridge_width 0.5)
			(island_removal_mode 0)
		)
		(polygon
			(pts
				(arc
					(start 445.956944 -31.850584)
					(mid 445.253364 -31.850584)
					(end 445.956944 -31.850584)
				)
			)
		)
	)
	(zone
		(layers "B.Cu" "In13.Cu" "In15.Cu")
		(hatch none 0.5)
		(connect_pads
			(clearance 0)
		)
		(min_thickness 0.25)
		(keepout
			(tracks not_allowed)
			(vias allowed)
			(pads allowed)
			(copperpour not_allowed)
			(footprints allowed)
		)
		(placement
			(enabled no)
			(sheetname "")
		)
		(fill yes
			(thermal_gap 0.5)
			(thermal_bridge_width 0.5)
			(island_removal_mode 0)
		)
		(polygon
			(pts
				(arc
					(start 314.976256 -312.049922)
					(mid 314.323476 -312.049922)
					(end 314.976256 -312.049922)
				)
			)
		)
	)
	(zone
		(layers "B.Cu" "In13.Cu" "In15.Cu")
		(hatch none 0.5)
		(connect_pads
			(clearance 0)
		)
		(min_thickness 0.25)
		(keepout
			(tracks not_allowed)
			(vias allowed)
			(pads allowed)
			(copperpour not_allowed)
			(footprints allowed)
		)
		(placement
			(enabled no)
			(sheetname "")
		)
		(fill yes
			(thermal_gap 0.5)
			(thermal_bridge_width 0.5)
			(island_removal_mode 0)
		)
		(polygon
			(pts
				(arc
					(start 254.49911 -30.92069)
					(mid 253.79553 -30.92069)
					(end 254.49911 -30.92069)
				)
			)
		)
	)
	(zone
		(layers "B.Cu" "In13.Cu" "In15.Cu")
		(hatch none 0.5)
		(connect_pads
			(clearance 0)
		)
		(min_thickness 0.25)
		(keepout
			(tracks not_allowed)
			(vias allowed)
			(pads allowed)
			(copperpour not_allowed)
			(footprints allowed)
		)
		(placement
			(enabled no)
			(sheetname "")
		)
		(fill yes
			(thermal_gap 0.5)
			(thermal_bridge_width 0.5)
			(island_removal_mode 0)
		)
		(polygon
			(pts
				(arc
					(start 22.793198 -348.58579)
					(mid 22.089618 -348.58579)
					(end 22.793198 -348.58579)
				)
			)
		)
	)
	(zone
		(layers "B.Cu" "In13.Cu" "In15.Cu")
		(hatch none 0.5)
		(connect_pads
			(clearance 0)
		)
		(min_thickness 0.25)
		(keepout
			(tracks not_allowed)
			(vias allowed)
			(pads allowed)
			(copperpour not_allowed)
			(footprints allowed)
		)
		(placement
			(enabled no)
			(sheetname "")
		)
		(fill yes
			(thermal_gap 0.5)
			(thermal_bridge_width 0.5)
			(island_removal_mode 0)
		)
		(polygon
			(pts
				(arc
					(start 92.089732 -405.390096)
					(mid 91.330272 -405.390096)
					(end 92.089732 -405.390096)
				)
			)
		)
	)
	(zone
		(layers "B.Cu" "In13.Cu" "In15.Cu")
		(hatch none 0.5)
		(connect_pads
			(clearance 0)
		)
		(min_thickness 0.25)
		(keepout
			(tracks not_allowed)
			(vias allowed)
			(pads allowed)
			(copperpour not_allowed)
			(footprints allowed)
		)
		(placement
			(enabled no)
			(sheetname "")
		)
		(fill yes
			(thermal_gap 0.5)
			(thermal_bridge_width 0.5)
			(island_removal_mode 0)
		)
		(polygon
			(pts
				(arc
					(start 166.889684 -375.490232)
					(mid 166.130224 -375.490232)
					(end 166.889684 -375.490232)
				)
			)
		)
	)
	(zone
		(layers "B.Cu" "In13.Cu" "In15.Cu")
		(hatch none 0.5)
		(connect_pads
			(clearance 0)
		)
		(min_thickness 0.25)
		(keepout
			(tracks not_allowed)
			(vias allowed)
			(pads allowed)
			(copperpour not_allowed)
			(footprints allowed)
		)
		(placement
			(enabled no)
			(sheetname "")
		)
		(fill yes
			(thermal_gap 0.5)
			(thermal_bridge_width 0.5)
			(island_removal_mode 0)
		)
		(polygon
			(pts
				(arc
					(start 35.229038 -348.58579)
					(mid 34.525458 -348.58579)
					(end 35.229038 -348.58579)
				)
			)
		)
	)
	(zone
		(layers "B.Cu" "In13.Cu" "In15.Cu")
		(hatch none 0.5)
		(connect_pads
			(clearance 0)
		)
		(min_thickness 0.25)
		(keepout
			(tracks not_allowed)
			(vias allowed)
			(pads allowed)
			(copperpour not_allowed)
			(footprints allowed)
		)
		(placement
			(enabled no)
			(sheetname "")
		)
		(fill yes
			(thermal_gap 0.5)
			(thermal_bridge_width 0.5)
			(island_removal_mode 0)
		)
		(polygon
			(pts
				(arc
					(start 158.976314 -312.999882)
					(mid 158.323534 -312.999882)
					(end 158.976314 -312.999882)
				)
			)
		)
	)
	(zone
		(layers "B.Cu" "In13.Cu" "In15.Cu")
		(hatch none 0.5)
		(connect_pads
			(clearance 0)
		)
		(min_thickness 0.25)
		(keepout
			(tracks not_allowed)
			(vias allowed)
			(pads allowed)
			(copperpour not_allowed)
			(footprints allowed)
		)
		(placement
			(enabled no)
			(sheetname "")
		)
		(fill yes
			(thermal_gap 0.5)
			(thermal_bridge_width 0.5)
			(island_removal_mode 0)
		)
		(polygon
			(pts
				(arc
					(start 166.576248 -277.849838)
					(mid 165.923468 -277.849838)
					(end 166.576248 -277.849838)
				)
			)
		)
	)
	(zone
		(layers "B.Cu" "In13.Cu" "In15.Cu")
		(hatch none 0.5)
		(connect_pads
			(clearance 0)
		)
		(min_thickness 0.25)
		(keepout
			(tracks not_allowed)
			(vias allowed)
			(pads allowed)
			(copperpour not_allowed)
			(footprints allowed)
		)
		(placement
			(enabled no)
			(sheetname "")
		)
		(fill yes
			(thermal_gap 0.5)
			(thermal_bridge_width 0.5)
			(island_removal_mode 0)
		)
		(polygon
			(pts
				(arc
					(start 169.089832 -401.690078)
					(mid 168.330372 -401.690078)
					(end 169.089832 -401.690078)
				)
			)
		)
	)
	(zone
		(layers "B.Cu" "In13.Cu" "In15.Cu")
		(hatch none 0.5)
		(connect_pads
			(clearance 0)
		)
		(min_thickness 0.25)
		(keepout
			(tracks not_allowed)
			(vias allowed)
			(pads allowed)
			(copperpour not_allowed)
			(footprints allowed)
		)
		(placement
			(enabled no)
			(sheetname "")
		)
		(fill yes
			(thermal_gap 0.5)
			(thermal_bridge_width 0.5)
			(island_removal_mode 0)
		)
		(polygon
			(pts
				(arc
					(start 51.637438 -354.732082)
					(mid 50.933858 -354.732082)
					(end 51.637438 -354.732082)
				)
			)
		)
	)
	(zone
		(layers "B.Cu" "In13.Cu" "In15.Cu")
		(hatch none 0.5)
		(connect_pads
			(clearance 0)
		)
		(min_thickness 0.25)
		(keepout
			(tracks not_allowed)
			(vias allowed)
			(pads allowed)
			(copperpour not_allowed)
			(footprints allowed)
		)
		(placement
			(enabled no)
			(sheetname "")
		)
		(fill yes
			(thermal_gap 0.5)
			(thermal_bridge_width 0.5)
			(island_removal_mode 0)
		)
		(polygon
			(pts
				(arc
					(start 50.773838 -357.75773)
					(mid 50.070258 -357.75773)
					(end 50.773838 -357.75773)
				)
			)
		)
	)
	(zone
		(layers "B.Cu" "In13.Cu" "In15.Cu")
		(hatch none 0.5)
		(connect_pads
			(clearance 0)
		)
		(min_thickness 0.25)
		(keepout
			(tracks not_allowed)
			(vias allowed)
			(pads allowed)
			(copperpour not_allowed)
			(footprints allowed)
		)
		(placement
			(enabled no)
			(sheetname "")
		)
		(fill yes
			(thermal_gap 0.5)
			(thermal_bridge_width 0.5)
			(island_removal_mode 0)
		)
		(polygon
			(pts
				(arc
					(start 216.39911 -30.92069)
					(mid 215.69553 -30.92069)
					(end 216.39911 -30.92069)
				)
			)
		)
	)
	(zone
		(layers "B.Cu" "In13.Cu" "In15.Cu")
		(hatch none 0.5)
		(connect_pads
			(clearance 0)
		)
		(min_thickness 0.25)
		(keepout
			(tracks not_allowed)
			(vias allowed)
			(pads allowed)
			(copperpour not_allowed)
			(footprints allowed)
		)
		(placement
			(enabled no)
			(sheetname "")
		)
		(fill yes
			(thermal_gap 0.5)
			(thermal_bridge_width 0.5)
			(island_removal_mode 0)
		)
		(polygon
			(pts
				(arc
					(start 300.202092 -357.75773)
					(mid 299.498512 -357.75773)
					(end 300.202092 -357.75773)
				)
			)
		)
	)
	(zone
		(layers "B.Cu" "In13.Cu" "In15.Cu")
		(hatch none 0.5)
		(connect_pads
			(clearance 0)
		)
		(min_thickness 0.25)
		(keepout
			(tracks not_allowed)
			(vias allowed)
			(pads allowed)
			(copperpour not_allowed)
			(footprints allowed)
		)
		(placement
			(enabled no)
			(sheetname "")
		)
		(fill yes
			(thermal_gap 0.5)
			(thermal_bridge_width 0.5)
			(island_removal_mode 0)
		)
		(polygon
			(pts
				(arc
					(start 161.757106 -29.114242)
					(mid 161.053526 -29.114242)
					(end 161.757106 -29.114242)
				)
			)
		)
	)
	(zone
		(layers "B.Cu" "In13.Cu" "In15.Cu")
		(hatch none 0.5)
		(connect_pads
			(clearance 0)
		)
		(min_thickness 0.25)
		(keepout
			(tracks not_allowed)
			(vias allowed)
			(pads allowed)
			(copperpour not_allowed)
			(footprints allowed)
		)
		(placement
			(enabled no)
			(sheetname "")
		)
		(fill yes
			(thermal_gap 0.5)
			(thermal_bridge_width 0.5)
			(island_removal_mode 0)
		)
		(polygon
			(pts
				(arc
					(start 329.856846 -31.850584)
					(mid 329.153266 -31.850584)
					(end 329.856846 -31.850584)
				)
			)
		)
	)
	(zone
		(layers "B.Cu" "In13.Cu" "In15.Cu")
		(hatch none 0.5)
		(connect_pads
			(clearance 0)
		)
		(min_thickness 0.25)
		(keepout
			(tracks not_allowed)
			(vias allowed)
			(pads allowed)
			(copperpour not_allowed)
			(footprints allowed)
		)
		(placement
			(enabled no)
			(sheetname "")
		)
		(fill yes
			(thermal_gap 0.5)
			(thermal_bridge_width 0.5)
			(island_removal_mode 0)
		)
		(polygon
			(pts
				(arc
					(start 174.973742 -345.465146)
					(mid 174.270162 -345.465146)
					(end 174.973742 -345.465146)
				)
			)
		)
	)
	(zone
		(layers "B.Cu" "In13.Cu" "In15.Cu")
		(hatch none 0.5)
		(connect_pads
			(clearance 0)
		)
		(min_thickness 0.25)
		(keepout
			(tracks not_allowed)
			(vias allowed)
			(pads allowed)
			(copperpour not_allowed)
			(footprints allowed)
		)
		(placement
			(enabled no)
			(sheetname "")
		)
		(fill yes
			(thermal_gap 0.5)
			(thermal_bridge_width 0.5)
			(island_removal_mode 0)
		)
		(polygon
			(pts
				(arc
					(start 39.201598 -345.465146)
					(mid 38.498018 -345.465146)
					(end 39.201598 -345.465146)
				)
			)
		)
	)
	(zone
		(layers "B.Cu" "In13.Cu" "In15.Cu")
		(hatch none 0.5)
		(connect_pads
			(clearance 0)
		)
		(min_thickness 0.25)
		(keepout
			(tracks not_allowed)
			(vias allowed)
			(pads allowed)
			(copperpour not_allowed)
			(footprints allowed)
		)
		(placement
			(enabled no)
			(sheetname "")
		)
		(fill yes
			(thermal_gap 0.5)
			(thermal_bridge_width 0.5)
			(island_removal_mode 0)
		)
		(polygon
			(pts
				(arc
					(start 75.17638 -306.349908)
					(mid 74.5236 -306.349908)
					(end 75.17638 -306.349908)
				)
			)
		)
	)
	(zone
		(layers "B.Cu" "In13.Cu" "In15.Cu")
		(hatch none 0.5)
		(connect_pads
			(clearance 0)
		)
		(min_thickness 0.25)
		(keepout
			(tracks not_allowed)
			(vias allowed)
			(pads allowed)
			(copperpour not_allowed)
			(footprints allowed)
		)
		(placement
			(enabled no)
			(sheetname "")
		)
		(fill yes
			(thermal_gap 0.5)
			(thermal_bridge_width 0.5)
			(island_removal_mode 0)
		)
		(polygon
			(pts
				(arc
					(start 168.476422 -277.849838)
					(mid 167.823642 -277.849838)
					(end 168.476422 -277.849838)
				)
			)
		)
	)
	(zone
		(layers "B.Cu" "In13.Cu" "In15.Cu")
		(hatch none 0.5)
		(connect_pads
			(clearance 0)
		)
		(min_thickness 0.25)
		(keepout
			(tracks not_allowed)
			(vias allowed)
			(pads allowed)
			(copperpour not_allowed)
			(footprints allowed)
		)
		(placement
			(enabled no)
			(sheetname "")
		)
		(fill yes
			(thermal_gap 0.5)
			(thermal_bridge_width 0.5)
			(island_removal_mode 0)
		)
		(polygon
			(pts
				(arc
					(start 390.226296 -309.199788)
					(mid 389.573516 -309.199788)
					(end 390.226296 -309.199788)
				)
			)
		)
	)
	(zone
		(layers "B.Cu" "In13.Cu" "In15.Cu")
		(hatch none 0.5)
		(connect_pads
			(clearance 0)
		)
		(min_thickness 0.25)
		(keepout
			(tracks not_allowed)
			(vias allowed)
			(pads allowed)
			(copperpour not_allowed)
			(footprints allowed)
		)
		(placement
			(enabled no)
			(sheetname "")
		)
		(fill yes
			(thermal_gap 0.5)
			(thermal_bridge_width 0.5)
			(island_removal_mode 0)
		)
		(polygon
			(pts
				(arc
					(start 435.382162 -354.732082)
					(mid 434.678582 -354.732082)
					(end 435.382162 -354.732082)
				)
			)
		)
	)
	(zone
		(layers "B.Cu" "In13.Cu" "In15.Cu")
		(hatch none 0.5)
		(connect_pads
			(clearance 0)
		)
		(min_thickness 0.25)
		(keepout
			(tracks not_allowed)
			(vias allowed)
			(pads allowed)
			(copperpour not_allowed)
			(footprints allowed)
		)
		(placement
			(enabled no)
			(sheetname "")
		)
		(fill yes
			(thermal_gap 0.5)
			(thermal_bridge_width 0.5)
			(island_removal_mode 0)
		)
		(polygon
			(pts
				(arc
					(start 173.48962 -374.390158)
					(mid 172.73016 -374.390158)
					(end 173.48962 -374.390158)
				)
			)
		)
	)
	(zone
		(layers "B.Cu" "In13.Cu" "In15.Cu")
		(hatch none 0.5)
		(connect_pads
			(clearance 0)
		)
		(min_thickness 0.25)
		(keepout
			(tracks not_allowed)
			(vias allowed)
			(pads allowed)
			(copperpour not_allowed)
			(footprints allowed)
		)
		(placement
			(enabled no)
			(sheetname "")
		)
		(fill yes
			(thermal_gap 0.5)
			(thermal_bridge_width 0.5)
			(island_removal_mode 0)
		)
		(polygon
			(pts
				(arc
					(start 22.299168 -30.05709)
					(mid 21.595588 -30.05709)
					(end 22.299168 -30.05709)
				)
			)
		)
	)
	(zone
		(layers "B.Cu" "In13.Cu" "In15.Cu")
		(hatch none 0.5)
		(connect_pads
			(clearance 0)
		)
		(min_thickness 0.25)
		(keepout
			(tracks not_allowed)
			(vias allowed)
			(pads allowed)
			(copperpour not_allowed)
			(footprints allowed)
		)
		(placement
			(enabled no)
			(sheetname "")
		)
		(fill yes
			(thermal_gap 0.5)
			(thermal_bridge_width 0.5)
			(island_removal_mode 0)
		)
		(polygon
			(pts
				(arc
					(start 41.48963 -370.489988)
					(mid 40.73017 -370.489988)
					(end 41.48963 -370.489988)
				)
			)
		)
	)
	(zone
		(layers "B.Cu" "In13.Cu" "In15.Cu")
		(hatch none 0.5)
		(connect_pads
			(clearance 0)
		)
		(min_thickness 0.25)
		(keepout
			(tracks not_allowed)
			(vias allowed)
			(pads allowed)
			(copperpour not_allowed)
			(footprints allowed)
		)
		(placement
			(enabled no)
			(sheetname "")
		)
		(fill yes
			(thermal_gap 0.5)
			(thermal_bridge_width 0.5)
			(island_removal_mode 0)
		)
		(polygon
			(pts
				(arc
					(start 97.656904 -28.250642)
					(mid 96.953324 -28.250642)
					(end 97.656904 -28.250642)
				)
			)
		)
	)
	(zone
		(layers "B.Cu" "In13.Cu" "In15.Cu")
		(hatch none 0.5)
		(connect_pads
			(clearance 0)
		)
		(min_thickness 0.25)
		(keepout
			(tracks not_allowed)
			(vias allowed)
			(pads allowed)
			(copperpour not_allowed)
			(footprints allowed)
		)
		(placement
			(enabled no)
			(sheetname "")
		)
		(fill yes
			(thermal_gap 0.5)
			(thermal_bridge_width 0.5)
			(island_removal_mode 0)
		)
		(polygon
			(pts
				(arc
					(start 275.330412 -342.439498)
					(mid 274.626832 -342.439498)
					(end 275.330412 -342.439498)
				)
			)
		)
	)
	(zone
		(layers "B.Cu" "In13.Cu" "In15.Cu")
		(hatch none 0.5)
		(connect_pads
			(clearance 0)
		)
		(min_thickness 0.25)
		(keepout
			(tracks not_allowed)
			(vias allowed)
			(pads allowed)
			(copperpour not_allowed)
			(footprints allowed)
		)
		(placement
			(enabled no)
			(sheetname "")
		)
		(fill yes
			(thermal_gap 0.5)
			(thermal_bridge_width 0.5)
			(island_removal_mode 0)
		)
		(polygon
			(pts
				(arc
					(start 172.728382 -351.611438)
					(mid 172.024802 -351.611438)
					(end 172.728382 -351.611438)
				)
			)
		)
	)
	(zone
		(layers "B.Cu" "In13.Cu" "In15.Cu")
		(hatch none 0.5)
		(connect_pads
			(clearance 0)
		)
		(min_thickness 0.25)
		(keepout
			(tracks not_allowed)
			(vias allowed)
			(pads allowed)
			(copperpour not_allowed)
			(footprints allowed)
		)
		(placement
			(enabled no)
			(sheetname "")
		)
		(fill yes
			(thermal_gap 0.5)
			(thermal_bridge_width 0.5)
			(island_removal_mode 0)
		)
		(polygon
			(pts
				(arc
					(start 405.426164 -280.699718)
					(mid 404.773384 -280.699718)
					(end 405.426164 -280.699718)
				)
			)
		)
	)
	(zone
		(layers "B.Cu" "In13.Cu" "In15.Cu")
		(hatch none 0.5)
		(connect_pads
			(clearance 0)
		)
		(min_thickness 0.25)
		(keepout
			(tracks not_allowed)
			(vias allowed)
			(pads allowed)
			(copperpour not_allowed)
			(footprints allowed)
		)
		(placement
			(enabled no)
			(sheetname "")
		)
		(fill yes
			(thermal_gap 0.5)
			(thermal_bridge_width 0.5)
			(island_removal_mode 0)
		)
		(polygon
			(pts
				(arc
					(start 160.289748 -401.690078)
					(mid 159.530288 -401.690078)
					(end 160.289748 -401.690078)
				)
			)
		)
	)
	(zone
		(layers "B.Cu" "In13.Cu" "In15.Cu")
		(hatch none 0.5)
		(connect_pads
			(clearance 0)
		)
		(min_thickness 0.25)
		(keepout
			(tracks not_allowed)
			(vias allowed)
			(pads allowed)
			(copperpour not_allowed)
			(footprints allowed)
		)
		(placement
			(enabled no)
			(sheetname "")
		)
		(fill yes
			(thermal_gap 0.5)
			(thermal_bridge_width 0.5)
			(island_removal_mode 0)
		)
		(polygon
			(pts
				(arc
					(start 290.069524 -372.890034)
					(mid 289.310064 -372.890034)
					(end 290.069524 -372.890034)
				)
			)
		)
	)
	(zone
		(layers "B.Cu" "In13.Cu" "In15.Cu")
		(hatch none 0.5)
		(connect_pads
			(clearance 0)
		)
		(min_thickness 0.25)
		(keepout
			(tracks not_allowed)
			(vias allowed)
			(pads allowed)
			(copperpour not_allowed)
			(footprints allowed)
		)
		(placement
			(enabled no)
			(sheetname "")
		)
		(fill yes
			(thermal_gap 0.5)
			(thermal_bridge_width 0.5)
			(island_removal_mode 0)
		)
		(polygon
			(pts
				(arc
					(start 92.089732 -406.690068)
					(mid 91.330272 -406.690068)
					(end 92.089732 -406.690068)
				)
			)
		)
	)
	(zone
		(layers "B.Cu" "In13.Cu" "In15.Cu")
		(hatch none 0.5)
		(connect_pads
			(clearance 0)
		)
		(min_thickness 0.25)
		(keepout
			(tracks not_allowed)
			(vias allowed)
			(pads allowed)
			(copperpour not_allowed)
			(footprints allowed)
		)
		(placement
			(enabled no)
			(sheetname "")
		)
		(fill yes
			(thermal_gap 0.5)
			(thermal_bridge_width 0.5)
			(island_removal_mode 0)
		)
		(polygon
			(pts
				(arc
					(start 410.510482 -342.439498)
					(mid 409.806902 -342.439498)
					(end 410.510482 -342.439498)
				)
			)
		)
	)
	(zone
		(layers "B.Cu" "In13.Cu" "In15.Cu")
		(hatch none 0.5)
		(connect_pads
			(clearance 0)
		)
		(min_thickness 0.25)
		(keepout
			(tracks not_allowed)
			(vias allowed)
			(pads allowed)
			(copperpour not_allowed)
			(footprints allowed)
		)
		(placement
			(enabled no)
			(sheetname "")
		)
		(fill yes
			(thermal_gap 0.5)
			(thermal_bridge_width 0.5)
			(island_removal_mode 0)
		)
		(polygon
			(pts
				(arc
					(start 32.983678 -354.732082)
					(mid 32.280098 -354.732082)
					(end 32.983678 -354.732082)
				)
			)
		)
	)
	(zone
		(layers "B.Cu" "In13.Cu" "In15.Cu")
		(hatch none 0.5)
		(connect_pads
			(clearance 0)
		)
		(min_thickness 0.25)
		(keepout
			(tracks not_allowed)
			(vias allowed)
			(pads allowed)
			(copperpour not_allowed)
			(footprints allowed)
		)
		(placement
			(enabled no)
			(sheetname "")
		)
		(fill yes
			(thermal_gap 0.5)
			(thermal_bridge_width 0.5)
			(island_removal_mode 0)
		)
		(polygon
			(pts
				(arc
					(start 169.426382 -279.749504)
					(mid 168.773602 -279.749504)
					(end 169.426382 -279.749504)
				)
			)
		)
	)
	(zone
		(layers "B.Cu" "In13.Cu" "In15.Cu")
		(hatch none 0.5)
		(connect_pads
			(clearance 0)
		)
		(min_thickness 0.25)
		(keepout
			(tracks not_allowed)
			(vias allowed)
			(pads allowed)
			(copperpour not_allowed)
			(footprints allowed)
		)
		(placement
			(enabled no)
			(sheetname "")
		)
		(fill yes
			(thermal_gap 0.5)
			(thermal_bridge_width 0.5)
			(island_removal_mode 0)
		)
		(polygon
			(pts
				(arc
					(start 158.026354 -301.599854)
					(mid 157.373574 -301.599854)
					(end 158.026354 -301.599854)
				)
			)
		)
	)
	(zone
		(layers "B.Cu" "In13.Cu" "In15.Cu")
		(hatch none 0.5)
		(connect_pads
			(clearance 0)
		)
		(min_thickness 0.25)
		(keepout
			(tracks not_allowed)
			(vias allowed)
			(pads allowed)
			(copperpour not_allowed)
			(footprints allowed)
		)
		(placement
			(enabled no)
			(sheetname "")
		)
		(fill yes
			(thermal_gap 0.5)
			(thermal_bridge_width 0.5)
			(island_removal_mode 0)
		)
		(polygon
			(pts
				(arc
					(start 293.984172 -345.465146)
					(mid 293.280592 -345.465146)
					(end 293.984172 -345.465146)
				)
			)
		)
	)
	(zone
		(layers "B.Cu" "In13.Cu" "In15.Cu")
		(hatch none 0.5)
		(connect_pads
			(clearance 0)
		)
		(min_thickness 0.25)
		(keepout
			(tracks not_allowed)
			(vias allowed)
			(pads allowed)
			(copperpour not_allowed)
			(footprints allowed)
		)
		(placement
			(enabled no)
			(sheetname "")
		)
		(fill yes
			(thermal_gap 0.5)
			(thermal_bridge_width 0.5)
			(island_removal_mode 0)
		)
		(polygon
			(pts
				(arc
					(start 188.273182 -357.733854)
					(mid 187.569602 -357.733854)
					(end 188.273182 -357.733854)
				)
			)
		)
	)
	(zone
		(layers "B.Cu" "In13.Cu" "In15.Cu")
		(hatch none 0.5)
		(connect_pads
			(clearance 0)
		)
		(min_thickness 0.25)
		(keepout
			(tracks not_allowed)
			(vias allowed)
			(pads allowed)
			(copperpour not_allowed)
			(footprints allowed)
		)
		(placement
			(enabled no)
			(sheetname "")
		)
		(fill yes
			(thermal_gap 0.5)
			(thermal_bridge_width 0.5)
			(island_removal_mode 0)
		)
		(polygon
			(pts
				(arc
					(start 428.300642 -342.439498)
					(mid 427.597062 -342.439498)
					(end 428.300642 -342.439498)
				)
			)
		)
	)
	(zone
		(layers "B.Cu" "In13.Cu" "In15.Cu")
		(hatch none 0.5)
		(connect_pads
			(clearance 0)
		)
		(min_thickness 0.25)
		(keepout
			(tracks not_allowed)
			(vias allowed)
			(pads allowed)
			(copperpour not_allowed)
			(footprints allowed)
		)
		(placement
			(enabled no)
			(sheetname "")
		)
		(fill yes
			(thermal_gap 0.5)
			(thermal_bridge_width 0.5)
			(island_removal_mode 0)
		)
		(polygon
			(pts
				(arc
					(start 281.726132 -279.749504)
					(mid 281.073352 -279.749504)
					(end 281.726132 -279.749504)
				)
			)
		)
	)
	(zone
		(layers "B.Cu" "In13.Cu" "In15.Cu")
		(hatch none 0.5)
		(connect_pads
			(clearance 0)
		)
		(min_thickness 0.25)
		(keepout
			(tracks not_allowed)
			(vias allowed)
			(pads allowed)
			(copperpour not_allowed)
			(footprints allowed)
		)
		(placement
			(enabled no)
			(sheetname "")
		)
		(fill yes
			(thermal_gap 0.5)
			(thermal_bridge_width 0.5)
			(island_removal_mode 0)
		)
		(polygon
			(pts
				(arc
					(start 393.076176 -308.249828)
					(mid 392.423396 -308.249828)
					(end 393.076176 -308.249828)
				)
			)
		)
	)
	(zone
		(layers "B.Cu" "In13.Cu" "In15.Cu")
		(hatch none 0.5)
		(connect_pads
			(clearance 0)
		)
		(min_thickness 0.25)
		(keepout
			(tracks not_allowed)
			(vias allowed)
			(pads allowed)
			(copperpour not_allowed)
			(footprints allowed)
		)
		(placement
			(enabled no)
			(sheetname "")
		)
		(fill yes
			(thermal_gap 0.5)
			(thermal_bridge_width 0.5)
			(island_removal_mode 0)
		)
		(polygon
			(pts
				(arc
					(start 168.755822 -354.732082)
					(mid 168.052242 -354.732082)
					(end 168.755822 -354.732082)
				)
			)
		)
	)
	(zone
		(layers "B.Cu" "In13.Cu" "In15.Cu")
		(hatch none 0.5)
		(connect_pads
			(clearance 0)
		)
		(min_thickness 0.25)
		(keepout
			(tracks not_allowed)
			(vias allowed)
			(pads allowed)
			(copperpour not_allowed)
			(footprints allowed)
		)
		(placement
			(enabled no)
			(sheetname "")
		)
		(fill yes
			(thermal_gap 0.5)
			(thermal_bridge_width 0.5)
			(island_removal_mode 0)
		)
		(polygon
			(pts
				(arc
					(start 158.026354 -309.199788)
					(mid 157.373574 -309.199788)
					(end 158.026354 -309.199788)
				)
			)
		)
	)
	(zone
		(layers "B.Cu" "In13.Cu" "In15.Cu")
		(hatch none 0.5)
		(connect_pads
			(clearance 0)
		)
		(min_thickness 0.25)
		(keepout
			(tracks not_allowed)
			(vias allowed)
			(pads allowed)
			(copperpour not_allowed)
			(footprints allowed)
		)
		(placement
			(enabled no)
			(sheetname "")
		)
		(fill yes
			(thermal_gap 0.5)
			(thermal_bridge_width 0.5)
			(island_removal_mode 0)
		)
		(polygon
			(pts
				(arc
					(start 399.726404 -279.749504)
					(mid 399.073624 -279.749504)
					(end 399.726404 -279.749504)
				)
			)
		)
	)
	(zone
		(layers "B.Cu" "In13.Cu" "In15.Cu")
		(hatch none 0.5)
		(connect_pads
			(clearance 0)
		)
		(min_thickness 0.25)
		(keepout
			(tracks not_allowed)
			(vias allowed)
			(pads allowed)
			(copperpour not_allowed)
			(footprints allowed)
		)
		(placement
			(enabled no)
			(sheetname "")
		)
		(fill yes
			(thermal_gap 0.5)
			(thermal_bridge_width 0.5)
			(island_removal_mode 0)
		)
		(polygon
			(pts
				(arc
					(start 157.076394 -312.999882)
					(mid 156.423614 -312.999882)
					(end 157.076394 -312.999882)
				)
			)
		)
	)
	(zone
		(layers "B.Cu" "In13.Cu" "In15.Cu")
		(hatch none 0.5)
		(connect_pads
			(clearance 0)
		)
		(min_thickness 0.25)
		(keepout
			(tracks not_allowed)
			(vias allowed)
			(pads allowed)
			(copperpour not_allowed)
			(footprints allowed)
		)
		(placement
			(enabled no)
			(sheetname "")
		)
		(fill yes
			(thermal_gap 0.5)
			(thermal_bridge_width 0.5)
			(island_removal_mode 0)
		)
		(polygon
			(pts
				(arc
					(start 301.069502 -396.49019)
					(mid 300.310042 -396.49019)
					(end 301.069502 -396.49019)
				)
			)
		)
	)
	(zone
		(layers "B.Cu" "In13.Cu" "In15.Cu")
		(hatch none 0.5)
		(connect_pads
			(clearance 0)
		)
		(min_thickness 0.25)
		(keepout
			(tracks not_allowed)
			(vias allowed)
			(pads allowed)
			(copperpour not_allowed)
			(footprints allowed)
		)
		(placement
			(enabled no)
			(sheetname "")
		)
		(fill yes
			(thermal_gap 0.5)
			(thermal_bridge_width 0.5)
			(island_removal_mode 0)
		)
		(polygon
			(pts
				(arc
					(start 170.376342 -277.849838)
					(mid 169.723562 -277.849838)
					(end 170.376342 -277.849838)
				)
			)
		)
	)
	(zone
		(layers "B.Cu" "In13.Cu" "In15.Cu")
		(hatch none 0.5)
		(connect_pads
			(clearance 0)
		)
		(min_thickness 0.25)
		(keepout
			(tracks not_allowed)
			(vias allowed)
			(pads allowed)
			(copperpour not_allowed)
			(footprints allowed)
		)
		(placement
			(enabled no)
			(sheetname "")
		)
		(fill yes
			(thermal_gap 0.5)
			(thermal_bridge_width 0.5)
			(island_removal_mode 0)
		)
		(polygon
			(pts
				(arc
					(start 160.292542 -357.75773)
					(mid 159.588962 -357.75773)
					(end 160.292542 -357.75773)
				)
			)
		)
	)
	(zone
		(layers "B.Cu" "In13.Cu" "In15.Cu")
		(hatch none 0.5)
		(connect_pads
			(clearance 0)
		)
		(min_thickness 0.25)
		(keepout
			(tracks not_allowed)
			(vias allowed)
			(pads allowed)
			(copperpour not_allowed)
			(footprints allowed)
		)
		(placement
			(enabled no)
			(sheetname "")
		)
		(fill yes
			(thermal_gap 0.5)
			(thermal_bridge_width 0.5)
			(island_removal_mode 0)
		)
		(polygon
			(pts
				(arc
					(start 419.86962 -374.390158)
					(mid 419.11016 -374.390158)
					(end 419.86962 -374.390158)
				)
			)
		)
	)
	(zone
		(layers "B.Cu" "In13.Cu" "In15.Cu")
		(hatch none 0.5)
		(connect_pads
			(clearance 0)
		)
		(min_thickness 0.25)
		(keepout
			(tracks not_allowed)
			(vias allowed)
			(pads allowed)
			(copperpour not_allowed)
			(footprints allowed)
		)
		(placement
			(enabled no)
			(sheetname "")
		)
		(fill yes
			(thermal_gap 0.5)
			(thermal_bridge_width 0.5)
			(island_removal_mode 0)
		)
		(polygon
			(pts
				(arc
					(start 162.489642 -402.790152)
					(mid 161.730182 -402.790152)
					(end 162.489642 -402.790152)
				)
			)
		)
	)
	(zone
		(layers "B.Cu" "In13.Cu" "In15.Cu")
		(hatch none 0.5)
		(connect_pads
			(clearance 0)
		)
		(min_thickness 0.25)
		(keepout
			(tracks not_allowed)
			(vias allowed)
			(pads allowed)
			(copperpour not_allowed)
			(footprints allowed)
		)
		(placement
			(enabled no)
			(sheetname "")
		)
		(fill yes
			(thermal_gap 0.5)
			(thermal_bridge_width 0.5)
			(island_removal_mode 0)
		)
		(polygon
			(pts
				(arc
					(start 391.176256 -305.399948)
					(mid 390.523476 -305.399948)
					(end 391.176256 -305.399948)
				)
			)
		)
	)
	(zone
		(layers "B.Cu" "In13.Cu" "In15.Cu")
		(hatch none 0.5)
		(connect_pads
			(clearance 0)
		)
		(min_thickness 0.25)
		(keepout
			(tracks not_allowed)
			(vias allowed)
			(pads allowed)
			(copperpour not_allowed)
			(footprints allowed)
		)
		(placement
			(enabled no)
			(sheetname "")
		)
		(fill yes
			(thermal_gap 0.5)
			(thermal_bridge_width 0.5)
			(island_removal_mode 0)
		)
		(polygon
			(pts
				(arc
					(start 29.011118 -348.58579)
					(mid 28.307538 -348.58579)
					(end 29.011118 -348.58579)
				)
			)
		)
	)
	(zone
		(layers "B.Cu" "In13.Cu" "In15.Cu")
		(hatch none 0.5)
		(connect_pads
			(clearance 0)
		)
		(min_thickness 0.25)
		(keepout
			(tracks not_allowed)
			(vias allowed)
			(pads allowed)
			(copperpour not_allowed)
			(footprints allowed)
		)
		(placement
			(enabled no)
			(sheetname "")
		)
		(fill yes
			(thermal_gap 0.5)
			(thermal_bridge_width 0.5)
			(island_removal_mode 0)
		)
		(polygon
			(pts
				(arc
					(start 428.669704 -374.390158)
					(mid 427.910244 -374.390158)
					(end 428.669704 -374.390158)
				)
			)
		)
	)
	(zone
		(layers "B.Cu" "In13.Cu" "In15.Cu")
		(hatch none 0.5)
		(connect_pads
			(clearance 0)
		)
		(min_thickness 0.25)
		(keepout
			(tracks not_allowed)
			(vias allowed)
			(pads allowed)
			(copperpour not_allowed)
			(footprints allowed)
		)
		(placement
			(enabled no)
			(sheetname "")
		)
		(fill yes
			(thermal_gap 0.5)
			(thermal_bridge_width 0.5)
			(island_removal_mode 0)
		)
		(polygon
			(pts
				(arc
					(start 158.976314 -301.599854)
					(mid 158.323534 -301.599854)
					(end 158.976314 -301.599854)
				)
			)
		)
	)
	(zone
		(layers "B.Cu" "In13.Cu" "In15.Cu")
		(hatch none 0.5)
		(connect_pads
			(clearance 0)
		)
		(min_thickness 0.25)
		(keepout
			(tracks not_allowed)
			(vias allowed)
			(pads allowed)
			(copperpour not_allowed)
			(footprints allowed)
		)
		(placement
			(enabled no)
			(sheetname "")
		)
		(fill yes
			(thermal_gap 0.5)
			(thermal_bridge_width 0.5)
			(island_removal_mode 0)
		)
		(polygon
			(pts
				(arc
					(start 213.757002 -28.250642)
					(mid 213.053422 -28.250642)
					(end 213.757002 -28.250642)
				)
			)
		)
	)
	(zone
		(layers "B.Cu" "In13.Cu" "In15.Cu")
		(hatch none 0.5)
		(connect_pads
			(clearance 0)
		)
		(min_thickness 0.25)
		(keepout
			(tracks not_allowed)
			(vias allowed)
			(pads allowed)
			(copperpour not_allowed)
			(footprints allowed)
		)
		(placement
			(enabled no)
			(sheetname "")
		)
		(fill yes
			(thermal_gap 0.5)
			(thermal_bridge_width 0.5)
			(island_removal_mode 0)
		)
		(polygon
			(pts
				(arc
					(start 36.092638 -351.611438)
					(mid 35.389058 -351.611438)
					(end 36.092638 -351.611438)
				)
			)
		)
	)
	(zone
		(layers "B.Cu" "In13.Cu" "In15.Cu")
		(hatch none 0.5)
		(connect_pads
			(clearance 0)
		)
		(min_thickness 0.25)
		(keepout
			(tracks not_allowed)
			(vias allowed)
			(pads allowed)
			(copperpour not_allowed)
			(footprints allowed)
		)
		(placement
			(enabled no)
			(sheetname "")
		)
		(fill yes
			(thermal_gap 0.5)
			(thermal_bridge_width 0.5)
			(island_removal_mode 0)
		)
		(polygon
			(pts
				(arc
					(start 294.469566 -372.890034)
					(mid 293.710106 -372.890034)
					(end 294.469566 -372.890034)
				)
			)
		)
	)
	(zone
		(layers "B.Cu" "In13.Cu" "In15.Cu")
		(hatch none 0.5)
		(connect_pads
			(clearance 0)
		)
		(min_thickness 0.25)
		(keepout
			(tracks not_allowed)
			(vias allowed)
			(pads allowed)
			(copperpour not_allowed)
			(footprints allowed)
		)
		(placement
			(enabled no)
			(sheetname "")
		)
		(fill yes
			(thermal_gap 0.5)
			(thermal_bridge_width 0.5)
			(island_removal_mode 0)
		)
		(polygon
			(pts
				(arc
					(start 396.599156 -33.657286)
					(mid 395.895576 -33.657286)
					(end 396.599156 -33.657286)
				)
			)
		)
	)
	(zone
		(layers "B.Cu" "In13.Cu" "In15.Cu")
		(hatch none 0.5)
		(connect_pads
			(clearance 0)
		)
		(min_thickness 0.25)
		(keepout
			(tracks not_allowed)
			(vias allowed)
			(pads allowed)
			(copperpour not_allowed)
			(footprints allowed)
		)
		(placement
			(enabled no)
			(sheetname "")
		)
		(fill yes
			(thermal_gap 0.5)
			(thermal_bridge_width 0.5)
			(island_removal_mode 0)
		)
		(polygon
			(pts
				(arc
					(start 81.826354 -314.899802)
					(mid 81.173574 -314.899802)
					(end 81.826354 -314.899802)
				)
			)
		)
	)
	(zone
		(layers "B.Cu" "In13.Cu" "In15.Cu")
		(hatch none 0.5)
		(connect_pads
			(clearance 0)
		)
		(min_thickness 0.25)
		(keepout
			(tracks not_allowed)
			(vias allowed)
			(pads allowed)
			(copperpour not_allowed)
			(footprints allowed)
		)
		(placement
			(enabled no)
			(sheetname "")
		)
		(fill yes
			(thermal_gap 0.5)
			(thermal_bridge_width 0.5)
			(island_removal_mode 0)
		)
		(polygon
			(pts
				(arc
					(start 416.728402 -354.732082)
					(mid 416.024822 -354.732082)
					(end 416.728402 -354.732082)
				)
			)
		)
	)
	(zone
		(layers "B.Cu" "In13.Cu" "In15.Cu")
		(hatch none 0.5)
		(connect_pads
			(clearance 0)
		)
		(min_thickness 0.25)
		(keepout
			(tracks not_allowed)
			(vias allowed)
			(pads allowed)
			(copperpour not_allowed)
			(footprints allowed)
		)
		(placement
			(enabled no)
			(sheetname "")
		)
		(fill yes
			(thermal_gap 0.5)
			(thermal_bridge_width 0.5)
			(island_removal_mode 0)
		)
		(polygon
			(pts
				(arc
					(start 280.684732 -342.439498)
					(mid 279.981152 -342.439498)
					(end 280.684732 -342.439498)
				)
			)
		)
	)
	(zone
		(layers "B.Cu" "In13.Cu" "In15.Cu")
		(hatch none 0.5)
		(connect_pads
			(clearance 0)
		)
		(min_thickness 0.25)
		(keepout
			(tracks not_allowed)
			(vias allowed)
			(pads allowed)
			(copperpour not_allowed)
			(footprints allowed)
		)
		(placement
			(enabled no)
			(sheetname "")
		)
		(fill yes
			(thermal_gap 0.5)
			(thermal_bridge_width 0.5)
			(island_removal_mode 0)
		)
		(polygon
			(pts
				(arc
					(start 277.926292 -280.699718)
					(mid 277.273512 -280.699718)
					(end 277.926292 -280.699718)
				)
			)
		)
	)
	(zone
		(layers "B.Cu" "In13.Cu" "In15.Cu")
		(hatch none 0.5)
		(connect_pads
			(clearance 0)
		)
		(min_thickness 0.25)
		(keepout
			(tracks not_allowed)
			(vias allowed)
			(pads allowed)
			(copperpour not_allowed)
			(footprints allowed)
		)
		(placement
			(enabled no)
			(sheetname "")
		)
		(fill yes
			(thermal_gap 0.5)
			(thermal_bridge_width 0.5)
			(island_removal_mode 0)
		)
		(polygon
			(pts
				(arc
					(start 172.276262 -278.799798)
					(mid 171.623482 -278.799798)
					(end 172.276262 -278.799798)
				)
			)
		)
	)
	(zone
		(layers "B.Cu" "In13.Cu" "In15.Cu")
		(hatch none 0.5)
		(connect_pads
			(clearance 0)
		)
		(min_thickness 0.25)
		(keepout
			(tracks not_allowed)
			(vias allowed)
			(pads allowed)
			(copperpour not_allowed)
			(footprints allowed)
		)
		(placement
			(enabled no)
			(sheetname "")
		)
		(fill yes
			(thermal_gap 0.5)
			(thermal_bridge_width 0.5)
			(island_removal_mode 0)
		)
		(polygon
			(pts
				(arc
					(start 391.176256 -309.199788)
					(mid 390.523476 -309.199788)
					(end 391.176256 -309.199788)
				)
			)
		)
	)
	(zone
		(layers "B.Cu" "In13.Cu" "In15.Cu")
		(hatch none 0.5)
		(connect_pads
			(clearance 0)
		)
		(min_thickness 0.25)
		(keepout
			(tracks not_allowed)
			(vias allowed)
			(pads allowed)
			(copperpour not_allowed)
			(footprints allowed)
		)
		(placement
			(enabled no)
			(sheetname "")
		)
		(fill yes
			(thermal_gap 0.5)
			(thermal_bridge_width 0.5)
			(island_removal_mode 0)
		)
		(polygon
			(pts
				(arc
					(start 422.069514 -402.790152)
					(mid 421.310054 -402.790152)
					(end 422.069514 -402.790152)
				)
			)
		)
	)
	(zone
		(layers "B.Cu" "In13.Cu" "In15.Cu")
		(hatch none 0.5)
		(connect_pads
			(clearance 0)
		)
		(min_thickness 0.25)
		(keepout
			(tracks not_allowed)
			(vias allowed)
			(pads allowed)
			(copperpour not_allowed)
			(footprints allowed)
		)
		(placement
			(enabled no)
			(sheetname "")
		)
		(fill yes
			(thermal_gap 0.5)
			(thermal_bridge_width 0.5)
			(island_removal_mode 0)
		)
		(polygon
			(pts
				(arc
					(start 419.86962 -401.690078)
					(mid 419.11016 -401.690078)
					(end 419.86962 -401.690078)
				)
			)
		)
	)
	(zone
		(layers "B.Cu" "In13.Cu" "In15.Cu")
		(hatch none 0.5)
		(connect_pads
			(clearance 0)
		)
		(min_thickness 0.25)
		(keepout
			(tracks not_allowed)
			(vias allowed)
			(pads allowed)
			(copperpour not_allowed)
			(footprints allowed)
		)
		(placement
			(enabled no)
			(sheetname "")
		)
		(fill yes
			(thermal_gap 0.5)
			(thermal_bridge_width 0.5)
			(island_removal_mode 0)
		)
		(polygon
			(pts
				(arc
					(start 254.49911 -33.657286)
					(mid 253.79553 -33.657286)
					(end 254.49911 -33.657286)
				)
			)
		)
	)
	(zone
		(layers "B.Cu" "In13.Cu" "In15.Cu")
		(hatch none 0.5)
		(connect_pads
			(clearance 0)
		)
		(min_thickness 0.25)
		(keepout
			(tracks not_allowed)
			(vias allowed)
			(pads allowed)
			(copperpour not_allowed)
			(footprints allowed)
		)
		(placement
			(enabled no)
			(sheetname "")
		)
		(fill yes
			(thermal_gap 0.5)
			(thermal_bridge_width 0.5)
			(island_removal_mode 0)
		)
		(polygon
			(pts
				(arc
					(start 32.6898 -371.790214)
					(mid 31.93034 -371.790214)
					(end 32.6898 -371.790214)
				)
			)
		)
	)
	(zone
		(layers "B.Cu" "In13.Cu" "In15.Cu")
		(hatch none 0.5)
		(connect_pads
			(clearance 0)
		)
		(min_thickness 0.25)
		(keepout
			(tracks not_allowed)
			(vias allowed)
			(pads allowed)
			(copperpour not_allowed)
			(footprints allowed)
		)
		(placement
			(enabled no)
			(sheetname "")
		)
		(fill yes
			(thermal_gap 0.5)
			(thermal_bridge_width 0.5)
			(island_removal_mode 0)
		)
		(polygon
			(pts
				(arc
					(start 30.489652 -372.890034)
					(mid 29.730192 -372.890034)
					(end 30.489652 -372.890034)
				)
			)
		)
	)
	(zone
		(layers "B.Cu" "In13.Cu" "In15.Cu")
		(hatch none 0.5)
		(connect_pads
			(clearance 0)
		)
		(min_thickness 0.25)
		(keepout
			(tracks not_allowed)
			(vias allowed)
			(pads allowed)
			(copperpour not_allowed)
			(footprints allowed)
		)
		(placement
			(enabled no)
			(sheetname "")
		)
		(fill yes
			(thermal_gap 0.5)
			(thermal_bridge_width 0.5)
			(island_removal_mode 0)
		)
		(polygon
			(pts
				(arc
					(start 157.076394 -313.949842)
					(mid 156.423614 -313.949842)
					(end 157.076394 -313.949842)
				)
			)
		)
	)
	(zone
		(layers "B.Cu" "In13.Cu" "In15.Cu")
		(hatch none 0.5)
		(connect_pads
			(clearance 0)
		)
		(min_thickness 0.25)
		(keepout
			(tracks not_allowed)
			(vias allowed)
			(pads allowed)
			(copperpour not_allowed)
			(footprints allowed)
		)
		(placement
			(enabled no)
			(sheetname "")
		)
		(fill yes
			(thermal_gap 0.5)
			(thermal_bridge_width 0.5)
			(island_removal_mode 0)
		)
		(polygon
			(pts
				(arc
					(start 308.326282 -311.099962)
					(mid 307.673502 -311.099962)
					(end 308.326282 -311.099962)
				)
			)
		)
	)
	(zone
		(layers "B.Cu" "In13.Cu" "In15.Cu")
		(hatch none 0.5)
		(connect_pads
			(clearance 0)
		)
		(min_thickness 0.25)
		(keepout
			(tracks not_allowed)
			(vias allowed)
			(pads allowed)
			(copperpour not_allowed)
			(footprints allowed)
		)
		(placement
			(enabled no)
			(sheetname "")
		)
		(fill yes
			(thermal_gap 0.5)
			(thermal_bridge_width 0.5)
			(island_removal_mode 0)
		)
		(polygon
			(pts
				(arc
					(start 367.9571 -28.250642)
					(mid 367.25352 -28.250642)
					(end 367.9571 -28.250642)
				)
			)
		)
	)
	(zone
		(layers "B.Cu" "In13.Cu" "In15.Cu")
		(hatch none 0.5)
		(connect_pads
			(clearance 0)
		)
		(min_thickness 0.25)
		(keepout
			(tracks not_allowed)
			(vias allowed)
			(pads allowed)
			(copperpour not_allowed)
			(footprints allowed)
		)
		(placement
			(enabled no)
			(sheetname "")
		)
		(fill yes
			(thermal_gap 0.5)
			(thermal_bridge_width 0.5)
			(island_removal_mode 0)
		)
		(polygon
			(pts
				(arc
					(start 274.466812 -342.439498)
					(mid 273.763232 -342.439498)
					(end 274.466812 -342.439498)
				)
			)
		)
	)
	(zone
		(layers "B.Cu" "In13.Cu" "In15.Cu")
		(hatch none 0.5)
		(connect_pads
			(clearance 0)
		)
		(min_thickness 0.25)
		(keepout
			(tracks not_allowed)
			(vias allowed)
			(pads allowed)
			(copperpour not_allowed)
			(footprints allowed)
		)
		(placement
			(enabled no)
			(sheetname "")
		)
		(fill yes
			(thermal_gap 0.5)
			(thermal_bridge_width 0.5)
			(island_removal_mode 0)
		)
		(polygon
			(pts
				(arc
					(start 432.273202 -348.58579)
					(mid 431.569622 -348.58579)
					(end 432.273202 -348.58579)
				)
			)
		)
	)
	(zone
		(layers "B.Cu" "In13.Cu" "In15.Cu")
		(hatch none 0.5)
		(connect_pads
			(clearance 0)
		)
		(min_thickness 0.25)
		(keepout
			(tracks not_allowed)
			(vias allowed)
			(pads allowed)
			(copperpour not_allowed)
			(footprints allowed)
		)
		(placement
			(enabled no)
			(sheetname "")
		)
		(fill yes
			(thermal_gap 0.5)
			(thermal_bridge_width 0.5)
			(island_removal_mode 0)
		)
		(polygon
			(pts
				(arc
					(start 190.399162 -33.657286)
					(mid 189.695582 -33.657286)
					(end 190.399162 -33.657286)
				)
			)
		)
	)
	(zone
		(layers "B.Cu" "In13.Cu" "In15.Cu")
		(hatch none 0.5)
		(connect_pads
			(clearance 0)
		)
		(min_thickness 0.25)
		(keepout
			(tracks not_allowed)
			(vias allowed)
			(pads allowed)
			(copperpour not_allowed)
			(footprints allowed)
		)
		(placement
			(enabled no)
			(sheetname "")
		)
		(fill yes
			(thermal_gap 0.5)
			(thermal_bridge_width 0.5)
			(island_removal_mode 0)
		)
		(polygon
			(pts
				(arc
					(start 92.089732 -409.290012)
					(mid 91.330272 -409.290012)
					(end 92.089732 -409.290012)
				)
			)
		)
	)
	(zone
		(layers "B.Cu" "In13.Cu" "In15.Cu")
		(hatch none 0.5)
		(connect_pads
			(clearance 0)
		)
		(min_thickness 0.25)
		(keepout
			(tracks not_allowed)
			(vias allowed)
			(pads allowed)
			(copperpour not_allowed)
			(footprints allowed)
		)
		(placement
			(enabled no)
			(sheetname "")
		)
		(fill yes
			(thermal_gap 0.5)
			(thermal_bridge_width 0.5)
			(island_removal_mode 0)
		)
		(polygon
			(pts
				(arc
					(start 370.599208 -34.520886)
					(mid 369.895628 -34.520886)
					(end 370.599208 -34.520886)
				)
			)
		)
	)
	(zone
		(layers "B.Cu" "In13.Cu" "In15.Cu")
		(hatch none 0.5)
		(connect_pads
			(clearance 0)
		)
		(min_thickness 0.25)
		(keepout
			(tracks not_allowed)
			(vias allowed)
			(pads allowed)
			(copperpour not_allowed)
			(footprints allowed)
		)
		(placement
			(enabled no)
			(sheetname "")
		)
		(fill yes
			(thermal_gap 0.5)
			(thermal_bridge_width 0.5)
			(island_removal_mode 0)
		)
		(polygon
			(pts
				(arc
					(start 166.889684 -376.790204)
					(mid 166.130224 -376.790204)
					(end 166.889684 -376.790204)
				)
			)
		)
	)
	(zone
		(layers "B.Cu" "In13.Cu" "In15.Cu")
		(hatch none 0.5)
		(connect_pads
			(clearance 0)
		)
		(min_thickness 0.25)
		(keepout
			(tracks not_allowed)
			(vias allowed)
			(pads allowed)
			(copperpour not_allowed)
			(footprints allowed)
		)
		(placement
			(enabled no)
			(sheetname "")
		)
		(fill yes
			(thermal_gap 0.5)
			(thermal_bridge_width 0.5)
			(island_removal_mode 0)
		)
		(polygon
			(pts
				(arc
					(start 428.300642 -354.732082)
					(mid 427.597062 -354.732082)
					(end 428.300642 -354.732082)
				)
			)
		)
	)
	(zone
		(layers "B.Cu" "In13.Cu" "In15.Cu")
		(hatch none 0.5)
		(connect_pads
			(clearance 0)
		)
		(min_thickness 0.25)
		(keepout
			(tracks not_allowed)
			(vias allowed)
			(pads allowed)
			(copperpour not_allowed)
			(footprints allowed)
		)
		(placement
			(enabled no)
			(sheetname "")
		)
		(fill yes
			(thermal_gap 0.5)
			(thermal_bridge_width 0.5)
			(island_removal_mode 0)
		)
		(polygon
			(pts
				(arc
					(start 75.17638 -313.949842)
					(mid 74.5236 -313.949842)
					(end 75.17638 -313.949842)
				)
			)
		)
	)
	(zone
		(layers "B.Cu" "In13.Cu" "In15.Cu")
		(hatch none 0.5)
		(connect_pads
			(clearance 0)
		)
		(min_thickness 0.25)
		(keepout
			(tracks not_allowed)
			(vias allowed)
			(pads allowed)
			(copperpour not_allowed)
			(footprints allowed)
		)
		(placement
			(enabled no)
			(sheetname "")
		)
		(fill yes
			(thermal_gap 0.5)
			(thermal_bridge_width 0.5)
			(island_removal_mode 0)
		)
		(polygon
			(pts
				(arc
					(start 429.164242 -354.732082)
					(mid 428.460662 -354.732082)
					(end 429.164242 -354.732082)
				)
			)
		)
	)
	(zone
		(layers "B.Cu" "In13.Cu" "In15.Cu")
		(hatch none 0.5)
		(connect_pads
			(clearance 0)
		)
		(min_thickness 0.25)
		(keepout
			(tracks not_allowed)
			(vias allowed)
			(pads allowed)
			(copperpour not_allowed)
			(footprints allowed)
		)
		(placement
			(enabled no)
			(sheetname "")
		)
		(fill yes
			(thermal_gap 0.5)
			(thermal_bridge_width 0.5)
			(island_removal_mode 0)
		)
		(polygon
			(pts
				(arc
					(start 426.055282 -348.58579)
					(mid 425.351702 -348.58579)
					(end 426.055282 -348.58579)
				)
			)
		)
	)
	(zone
		(layers "B.Cu" "In13.Cu" "In15.Cu")
		(hatch none 0.5)
		(connect_pads
			(clearance 0)
		)
		(min_thickness 0.25)
		(keepout
			(tracks not_allowed)
			(vias allowed)
			(pads allowed)
			(copperpour not_allowed)
			(footprints allowed)
		)
		(placement
			(enabled no)
			(sheetname "")
		)
		(fill yes
			(thermal_gap 0.5)
			(thermal_bridge_width 0.5)
			(island_removal_mode 0)
		)
		(polygon
			(pts
				(arc
					(start 422.599104 -33.657286)
					(mid 421.895524 -33.657286)
					(end 422.599104 -33.657286)
				)
			)
		)
	)
	(zone
		(layers "B.Cu" "In13.Cu" "In15.Cu")
		(hatch none 0.5)
		(connect_pads
			(clearance 0)
		)
		(min_thickness 0.25)
		(keepout
			(tracks not_allowed)
			(vias allowed)
			(pads allowed)
			(copperpour not_allowed)
			(footprints allowed)
		)
		(placement
			(enabled no)
			(sheetname "")
		)
		(fill yes
			(thermal_gap 0.5)
			(thermal_bridge_width 0.5)
			(island_removal_mode 0)
		)
		(polygon
			(pts
				(arc
					(start 402.576284 -278.799798)
					(mid 401.923504 -278.799798)
					(end 402.576284 -278.799798)
				)
			)
		)
	)
	(zone
		(layers "B.Cu" "In13.Cu" "In15.Cu")
		(hatch none 0.5)
		(connect_pads
			(clearance 0)
		)
		(min_thickness 0.25)
		(keepout
			(tracks not_allowed)
			(vias allowed)
			(pads allowed)
			(copperpour not_allowed)
			(footprints allowed)
		)
		(placement
			(enabled no)
			(sheetname "")
		)
		(fill yes
			(thermal_gap 0.5)
			(thermal_bridge_width 0.5)
			(island_removal_mode 0)
		)
		(polygon
			(pts
				(arc
					(start 167.526462 -279.749504)
					(mid 166.873682 -279.749504)
					(end 167.526462 -279.749504)
				)
			)
		)
	)
	(zone
		(layers "B.Cu" "In13.Cu" "In15.Cu")
		(hatch none 0.5)
		(connect_pads
			(clearance 0)
		)
		(min_thickness 0.25)
		(keepout
			(tracks not_allowed)
			(vias allowed)
			(pads allowed)
			(copperpour not_allowed)
			(footprints allowed)
		)
		(placement
			(enabled no)
			(sheetname "")
		)
		(fill yes
			(thermal_gap 0.5)
			(thermal_bridge_width 0.5)
			(island_removal_mode 0)
		)
		(polygon
			(pts
				(arc
					(start 277.85695 -29.114242)
					(mid 277.15337 -29.114242)
					(end 277.85695 -29.114242)
				)
			)
		)
	)
	(zone
		(layers "B.Cu" "In13.Cu" "In15.Cu")
		(hatch none 0.5)
		(connect_pads
			(clearance 0)
		)
		(min_thickness 0.25)
		(keepout
			(tracks not_allowed)
			(vias allowed)
			(pads allowed)
			(copperpour not_allowed)
			(footprints allowed)
		)
		(placement
			(enabled no)
			(sheetname "")
		)
		(fill yes
			(thermal_gap 0.5)
			(thermal_bridge_width 0.5)
			(island_removal_mode 0)
		)
		(polygon
			(pts
				(arc
					(start 278.876252 -277.849838)
					(mid 278.223472 -277.849838)
					(end 278.876252 -277.849838)
				)
			)
		)
	)
	(zone
		(layers "B.Cu" "In13.Cu" "In15.Cu")
		(hatch none 0.5)
		(connect_pads
			(clearance 0)
		)
		(min_thickness 0.25)
		(keepout
			(tracks not_allowed)
			(vias allowed)
			(pads allowed)
			(copperpour not_allowed)
			(footprints allowed)
		)
		(placement
			(enabled no)
			(sheetname "")
		)
		(fill yes
			(thermal_gap 0.5)
			(thermal_bridge_width 0.5)
			(island_removal_mode 0)
		)
		(polygon
			(pts
				(arc
					(start 74.226166 -311.099962)
					(mid 73.573386 -311.099962)
					(end 74.226166 -311.099962)
				)
			)
		)
	)
	(zone
		(layers "B.Cu" "In13.Cu" "In15.Cu")
		(hatch none 0.5)
		(connect_pads
			(clearance 0)
		)
		(min_thickness 0.25)
		(keepout
			(tracks not_allowed)
			(vias allowed)
			(pads allowed)
			(copperpour not_allowed)
			(footprints allowed)
		)
		(placement
			(enabled no)
			(sheetname "")
		)
		(fill yes
			(thermal_gap 0.5)
			(thermal_bridge_width 0.5)
			(island_removal_mode 0)
		)
		(polygon
			(pts
				(arc
					(start 433.069492 -401.690078)
					(mid 432.310032 -401.690078)
					(end 433.069492 -401.690078)
				)
			)
		)
	)
	(zone
		(layers "B.Cu" "In13.Cu" "In15.Cu")
		(hatch none 0.5)
		(connect_pads
			(clearance 0)
		)
		(min_thickness 0.25)
		(keepout
			(tracks not_allowed)
			(vias allowed)
			(pads allowed)
			(copperpour not_allowed)
			(footprints allowed)
		)
		(placement
			(enabled no)
			(sheetname "")
		)
		(fill yes
			(thermal_gap 0.5)
			(thermal_bridge_width 0.5)
			(island_removal_mode 0)
		)
		(polygon
			(pts
				(arc
					(start 155.176474 -312.999882)
					(mid 154.523694 -312.999882)
					(end 155.176474 -312.999882)
				)
			)
		)
	)
	(zone
		(layers "B.Cu" "In13.Cu" "In15.Cu")
		(hatch none 0.5)
		(connect_pads
			(clearance 0)
		)
		(min_thickness 0.25)
		(keepout
			(tracks not_allowed)
			(vias allowed)
			(pads allowed)
			(copperpour not_allowed)
			(footprints allowed)
		)
		(placement
			(enabled no)
			(sheetname "")
		)
		(fill yes
			(thermal_gap 0.5)
			(thermal_bridge_width 0.5)
			(island_removal_mode 0)
		)
		(polygon
			(pts
				(arc
					(start 78.97622 -312.999882)
					(mid 78.32344 -312.999882)
					(end 78.97622 -312.999882)
				)
			)
		)
	)
	(zone
		(layers "B.Cu" "In13.Cu" "In15.Cu")
		(hatch none 0.5)
		(connect_pads
			(clearance 0)
		)
		(min_thickness 0.25)
		(keepout
			(tracks not_allowed)
			(vias allowed)
			(pads allowed)
			(copperpour not_allowed)
			(footprints allowed)
		)
		(placement
			(enabled no)
			(sheetname "")
		)
		(fill yes
			(thermal_gap 0.5)
			(thermal_bridge_width 0.5)
			(island_removal_mode 0)
		)
		(polygon
			(pts
				(arc
					(start 309.276242 -313.949842)
					(mid 308.623462 -313.949842)
					(end 309.276242 -313.949842)
				)
			)
		)
	)
	(zone
		(layers "B.Cu" "In13.Cu" "In15.Cu")
		(hatch none 0.5)
		(connect_pads
			(clearance 0)
		)
		(min_thickness 0.25)
		(keepout
			(tracks not_allowed)
			(vias allowed)
			(pads allowed)
			(copperpour not_allowed)
			(footprints allowed)
		)
		(placement
			(enabled no)
			(sheetname "")
		)
		(fill yes
			(thermal_gap 0.5)
			(thermal_bridge_width 0.5)
			(island_removal_mode 0)
		)
		(polygon
			(pts
				(arc
					(start 299.338492 -357.75773)
					(mid 298.634912 -357.75773)
					(end 299.338492 -357.75773)
				)
			)
		)
	)
	(zone
		(layers "B.Cu" "In13.Cu" "In15.Cu")
		(hatch none 0.5)
		(connect_pads
			(clearance 0)
		)
		(min_thickness 0.25)
		(keepout
			(tracks not_allowed)
			(vias allowed)
			(pads allowed)
			(copperpour not_allowed)
			(footprints allowed)
		)
		(placement
			(enabled no)
			(sheetname "")
		)
		(fill yes
			(thermal_gap 0.5)
			(thermal_bridge_width 0.5)
			(island_removal_mode 0)
		)
		(polygon
			(pts
				(arc
					(start 165.646862 -348.58579)
					(mid 164.943282 -348.58579)
					(end 165.646862 -348.58579)
				)
			)
		)
	)
	(zone
		(layers "B.Cu" "In13.Cu" "In15.Cu")
		(hatch none 0.5)
		(connect_pads
			(clearance 0)
		)
		(min_thickness 0.25)
		(keepout
			(tracks not_allowed)
			(vias allowed)
			(pads allowed)
			(copperpour not_allowed)
			(footprints allowed)
		)
		(placement
			(enabled no)
			(sheetname "")
		)
		(fill yes
			(thermal_gap 0.5)
			(thermal_bridge_width 0.5)
			(island_removal_mode 0)
		)
		(polygon
			(pts
				(arc
					(start 32.983678 -345.465146)
					(mid 32.280098 -345.465146)
					(end 32.983678 -345.465146)
				)
			)
		)
	)
	(zone
		(layers "B.Cu" "In13.Cu" "In15.Cu")
		(hatch none 0.5)
		(connect_pads
			(clearance 0)
		)
		(min_thickness 0.25)
		(keepout
			(tracks not_allowed)
			(vias allowed)
			(pads allowed)
			(copperpour not_allowed)
			(footprints allowed)
		)
		(placement
			(enabled no)
			(sheetname "")
		)
		(fill yes
			(thermal_gap 0.5)
			(thermal_bridge_width 0.5)
			(island_removal_mode 0)
		)
		(polygon
			(pts
				(arc
					(start 303.856898 -29.114242)
					(mid 303.153318 -29.114242)
					(end 303.856898 -29.114242)
				)
			)
		)
	)
	(zone
		(layers "B.Cu" "In13.Cu" "In15.Cu")
		(hatch none 0.5)
		(connect_pads
			(clearance 0)
		)
		(min_thickness 0.25)
		(keepout
			(tracks not_allowed)
			(vias allowed)
			(pads allowed)
			(copperpour not_allowed)
			(footprints allowed)
		)
		(placement
			(enabled no)
			(sheetname "")
		)
		(fill yes
			(thermal_gap 0.5)
			(thermal_bridge_width 0.5)
			(island_removal_mode 0)
		)
		(polygon
			(pts
				(arc
					(start 310.226202 -311.099962)
					(mid 309.573422 -311.099962)
					(end 310.226202 -311.099962)
				)
			)
		)
	)
	(zone
		(layers "B.Cu" "In13.Cu" "In15.Cu")
		(hatch none 0.5)
		(connect_pads
			(clearance 0)
		)
		(min_thickness 0.25)
		(keepout
			(tracks not_allowed)
			(vias allowed)
			(pads allowed)
			(copperpour not_allowed)
			(footprints allowed)
		)
		(placement
			(enabled no)
			(sheetname "")
		)
		(fill yes
			(thermal_gap 0.5)
			(thermal_bridge_width 0.5)
			(island_removal_mode 0)
		)
		(polygon
			(pts
				(arc
					(start 441.600082 -357.75773)
					(mid 440.896502 -357.75773)
					(end 441.600082 -357.75773)
				)
			)
		)
	)
	(zone
		(layers "B.Cu" "In13.Cu" "In15.Cu")
		(hatch none 0.5)
		(connect_pads
			(clearance 0)
		)
		(min_thickness 0.25)
		(keepout
			(tracks not_allowed)
			(vias allowed)
			(pads allowed)
			(copperpour not_allowed)
			(footprints allowed)
		)
		(placement
			(enabled no)
			(sheetname "")
		)
		(fill yes
			(thermal_gap 0.5)
			(thermal_bridge_width 0.5)
			(island_removal_mode 0)
		)
		(polygon
			(pts
				(arc
					(start 296.669714 -397.790162)
					(mid 295.910254 -397.790162)
					(end 296.669714 -397.790162)
				)
			)
		)
	)
	(zone
		(layers "B.Cu" "In13.Cu" "In15.Cu")
		(hatch none 0.5)
		(connect_pads
			(clearance 0)
		)
		(min_thickness 0.25)
		(keepout
			(tracks not_allowed)
			(vias allowed)
			(pads allowed)
			(copperpour not_allowed)
			(footprints allowed)
		)
		(placement
			(enabled no)
			(sheetname "")
		)
		(fill yes
			(thermal_gap 0.5)
			(thermal_bridge_width 0.5)
			(island_removal_mode 0)
		)
		(polygon
			(pts
				(arc
					(start 388.326376 -311.099962)
					(mid 387.673596 -311.099962)
					(end 388.326376 -311.099962)
				)
			)
		)
	)
	(zone
		(layers "B.Cu" "In13.Cu" "In15.Cu")
		(hatch none 0.5)
		(connect_pads
			(clearance 0)
		)
		(min_thickness 0.25)
		(keepout
			(tracks not_allowed)
			(vias allowed)
			(pads allowed)
			(copperpour not_allowed)
			(footprints allowed)
		)
		(placement
			(enabled no)
			(sheetname "")
		)
		(fill yes
			(thermal_gap 0.5)
			(thermal_bridge_width 0.5)
			(island_removal_mode 0)
		)
		(polygon
			(pts
				(arc
					(start 80.87614 -313.949842)
					(mid 80.22336 -313.949842)
					(end 80.87614 -313.949842)
				)
			)
		)
	)
	(zone
		(layers "B.Cu" "In13.Cu" "In15.Cu")
		(hatch none 0.5)
		(connect_pads
			(clearance 0)
		)
		(min_thickness 0.25)
		(keepout
			(tracks not_allowed)
			(vias allowed)
			(pads allowed)
			(copperpour not_allowed)
			(footprints allowed)
		)
		(placement
			(enabled no)
			(sheetname "")
		)
		(fill yes
			(thermal_gap 0.5)
			(thermal_bridge_width 0.5)
			(island_removal_mode 0)
		)
		(polygon
			(pts
				(arc
					(start 74.299064 -30.92069)
					(mid 73.595484 -30.92069)
					(end 74.299064 -30.92069)
				)
			)
		)
	)
	(zone
		(layers "B.Cu" "In13.Cu" "In15.Cu")
		(hatch none 0.5)
		(connect_pads
			(clearance 0)
		)
		(min_thickness 0.25)
		(keepout
			(tracks not_allowed)
			(vias allowed)
			(pads allowed)
			(copperpour not_allowed)
			(footprints allowed)
		)
		(placement
			(enabled no)
			(sheetname "")
		)
		(fill yes
			(thermal_gap 0.5)
			(thermal_bridge_width 0.5)
			(island_removal_mode 0)
		)
		(polygon
			(pts
				(arc
					(start 169.089832 -374.390158)
					(mid 168.330372 -374.390158)
					(end 169.089832 -374.390158)
				)
			)
		)
	)
	(zone
		(layers "B.Cu" "In13.Cu" "In15.Cu")
		(hatch none 0.5)
		(connect_pads
			(clearance 0)
		)
		(min_thickness 0.25)
		(keepout
			(tracks not_allowed)
			(vias allowed)
			(pads allowed)
			(copperpour not_allowed)
			(footprints allowed)
		)
		(placement
			(enabled no)
			(sheetname "")
		)
		(fill yes
			(thermal_gap 0.5)
			(thermal_bridge_width 0.5)
			(island_removal_mode 0)
		)
		(polygon
			(pts
				(arc
					(start 187.409582 -354.708206)
					(mid 186.706002 -354.708206)
					(end 187.409582 -354.708206)
				)
			)
		)
	)
	(zone
		(layers "B.Cu" "In13.Cu" "In15.Cu")
		(hatch none 0.5)
		(connect_pads
			(clearance 0)
		)
		(min_thickness 0.25)
		(keepout
			(tracks not_allowed)
			(vias allowed)
			(pads allowed)
			(copperpour not_allowed)
			(footprints allowed)
		)
		(placement
			(enabled no)
			(sheetname "")
		)
		(fill yes
			(thermal_gap 0.5)
			(thermal_bridge_width 0.5)
			(island_removal_mode 0)
		)
		(polygon
			(pts
				(arc
					(start 275.330412 -357.75773)
					(mid 274.626832 -357.75773)
					(end 275.330412 -357.75773)
				)
			)
		)
	)
	(zone
		(layers "B.Cu" "In13.Cu" "In15.Cu")
		(hatch none 0.5)
		(connect_pads
			(clearance 0)
		)
		(min_thickness 0.25)
		(keepout
			(tracks not_allowed)
			(vias allowed)
			(pads allowed)
			(copperpour not_allowed)
			(footprints allowed)
		)
		(placement
			(enabled no)
			(sheetname "")
		)
		(fill yes
			(thermal_gap 0.5)
			(thermal_bridge_width 0.5)
			(island_removal_mode 0)
		)
		(polygon
			(pts
				(arc
					(start 37.089842 -396.49019)
					(mid 36.330382 -396.49019)
					(end 37.089842 -396.49019)
				)
			)
		)
	)
	(zone
		(layers "B.Cu" "In13.Cu" "In15.Cu")
		(hatch none 0.5)
		(connect_pads
			(clearance 0)
		)
		(min_thickness 0.25)
		(keepout
			(tracks not_allowed)
			(vias allowed)
			(pads allowed)
			(copperpour not_allowed)
			(footprints allowed)
		)
		(placement
			(enabled no)
			(sheetname "")
		)
		(fill yes
			(thermal_gap 0.5)
			(thermal_bridge_width 0.5)
			(island_removal_mode 0)
		)
		(polygon
			(pts
				(arc
					(start 309.276242 -307.299868)
					(mid 308.623462 -307.299868)
					(end 309.276242 -307.299868)
				)
			)
		)
	)
	(zone
		(layers "B.Cu" "In13.Cu" "In15.Cu")
		(hatch none 0.5)
		(connect_pads
			(clearance 0)
		)
		(min_thickness 0.25)
		(keepout
			(tracks not_allowed)
			(vias allowed)
			(pads allowed)
			(copperpour not_allowed)
			(footprints allowed)
		)
		(placement
			(enabled no)
			(sheetname "")
		)
		(fill yes
			(thermal_gap 0.5)
			(thermal_bridge_width 0.5)
			(island_removal_mode 0)
		)
		(polygon
			(pts
				(arc
					(start 48.08982 -410.589984)
					(mid 47.33036 -410.589984)
					(end 48.08982 -410.589984)
				)
			)
		)
	)
	(zone
		(layers "B.Cu" "In13.Cu" "In15.Cu")
		(hatch none 0.5)
		(connect_pads
			(clearance 0)
		)
		(min_thickness 0.25)
		(keepout
			(tracks not_allowed)
			(vias allowed)
			(pads allowed)
			(copperpour not_allowed)
			(footprints allowed)
		)
		(placement
			(enabled no)
			(sheetname "")
		)
		(fill yes
			(thermal_gap 0.5)
			(thermal_bridge_width 0.5)
			(island_removal_mode 0)
		)
		(polygon
			(pts
				(arc
					(start 74.226166 -312.049922)
					(mid 73.573386 -312.049922)
					(end 74.226166 -312.049922)
				)
			)
		)
	)
	(zone
		(layers "B.Cu" "In13.Cu" "In15.Cu")
		(hatch none 0.5)
		(connect_pads
			(clearance 0)
		)
		(min_thickness 0.25)
		(keepout
			(tracks not_allowed)
			(vias allowed)
			(pads allowed)
			(copperpour not_allowed)
			(footprints allowed)
		)
		(placement
			(enabled no)
			(sheetname "")
		)
		(fill yes
			(thermal_gap 0.5)
			(thermal_bridge_width 0.5)
			(island_removal_mode 0)
		)
		(polygon
			(pts
				(arc
					(start 187.409582 -345.465146)
					(mid 186.706002 -345.465146)
					(end 187.409582 -345.465146)
				)
			)
		)
	)
	(zone
		(layers "B.Cu" "In13.Cu" "In15.Cu")
		(hatch none 0.5)
		(connect_pads
			(clearance 0)
		)
		(min_thickness 0.25)
		(keepout
			(tracks not_allowed)
			(vias allowed)
			(pads allowed)
			(copperpour not_allowed)
			(footprints allowed)
		)
		(placement
			(enabled no)
			(sheetname "")
		)
		(fill yes
			(thermal_gap 0.5)
			(thermal_bridge_width 0.5)
			(island_removal_mode 0)
		)
		(polygon
			(pts
				(arc
					(start 77.0763 -305.399948)
					(mid 76.42352 -305.399948)
					(end 77.0763 -305.399948)
				)
			)
		)
	)
	(zone
		(layers "B.Cu" "In13.Cu" "In15.Cu")
		(hatch none 0.5)
		(connect_pads
			(clearance 0)
		)
		(min_thickness 0.25)
		(keepout
			(tracks not_allowed)
			(vias allowed)
			(pads allowed)
			(copperpour not_allowed)
			(footprints allowed)
		)
		(placement
			(enabled no)
			(sheetname "")
		)
		(fill yes
			(thermal_gap 0.5)
			(thermal_bridge_width 0.5)
			(island_removal_mode 0)
		)
		(polygon
			(pts
				(arc
					(start 32.6898 -397.790162)
					(mid 31.93034 -397.790162)
					(end 32.6898 -397.790162)
				)
			)
		)
	)
	(zone
		(layers "B.Cu" "In13.Cu" "In15.Cu")
		(hatch none 0.5)
		(connect_pads
			(clearance 0)
		)
		(min_thickness 0.25)
		(keepout
			(tracks not_allowed)
			(vias allowed)
			(pads allowed)
			(copperpour not_allowed)
			(footprints allowed)
		)
		(placement
			(enabled no)
			(sheetname "")
		)
		(fill yes
			(thermal_gap 0.5)
			(thermal_bridge_width 0.5)
			(island_removal_mode 0)
		)
		(polygon
			(pts
				(arc
					(start 290.27628 -278.799798)
					(mid 289.6235 -278.799798)
					(end 290.27628 -278.799798)
				)
			)
		)
	)
	(zone
		(layers "B.Cu" "In13.Cu" "In15.Cu")
		(hatch none 0.5)
		(connect_pads
			(clearance 0)
		)
		(min_thickness 0.25)
		(keepout
			(tracks not_allowed)
			(vias allowed)
			(pads allowed)
			(copperpour not_allowed)
			(footprints allowed)
		)
		(placement
			(enabled no)
			(sheetname "")
		)
		(fill yes
			(thermal_gap 0.5)
			(thermal_bridge_width 0.5)
			(island_removal_mode 0)
		)
		(polygon
			(pts
				(arc
					(start 23.656798 -351.611438)
					(mid 22.953218 -351.611438)
					(end 23.656798 -351.611438)
				)
			)
		)
	)
	(zone
		(layers "B.Cu" "In13.Cu" "In15.Cu")
		(hatch none 0.5)
		(connect_pads
			(clearance 0)
		)
		(min_thickness 0.25)
		(keepout
			(tracks not_allowed)
			(vias allowed)
			(pads allowed)
			(copperpour not_allowed)
			(footprints allowed)
		)
		(placement
			(enabled no)
			(sheetname "")
		)
		(fill yes
			(thermal_gap 0.5)
			(thermal_bridge_width 0.5)
			(island_removal_mode 0)
		)
		(polygon
			(pts
				(arc
					(start 37.089842 -371.790214)
					(mid 36.330382 -371.790214)
					(end 37.089842 -371.790214)
				)
			)
		)
	)
	(zone
		(layers "B.Cu" "In13.Cu" "In15.Cu")
		(hatch none 0.5)
		(connect_pads
			(clearance 0)
		)
		(min_thickness 0.25)
		(keepout
			(tracks not_allowed)
			(vias allowed)
			(pads allowed)
			(copperpour not_allowed)
			(footprints allowed)
		)
		(placement
			(enabled no)
			(sheetname "")
		)
		(fill yes
			(thermal_gap 0.5)
			(thermal_bridge_width 0.5)
			(island_removal_mode 0)
		)
		(polygon
			(pts
				(arc
					(start 50.773838 -345.465146)
					(mid 50.070258 -345.465146)
					(end 50.773838 -345.465146)
				)
			)
		)
	)
	(zone
		(layers "B.Cu" "In13.Cu" "In15.Cu")
		(hatch none 0.5)
		(connect_pads
			(clearance 0)
		)
		(min_thickness 0.25)
		(keepout
			(tracks not_allowed)
			(vias allowed)
			(pads allowed)
			(copperpour not_allowed)
			(footprints allowed)
		)
		(placement
			(enabled no)
			(sheetname "")
		)
		(fill yes
			(thermal_gap 0.5)
			(thermal_bridge_width 0.5)
			(island_removal_mode 0)
		)
		(polygon
			(pts
				(arc
					(start 79.92618 -311.099962)
					(mid 79.2734 -311.099962)
					(end 79.92618 -311.099962)
				)
			)
		)
	)
	(zone
		(layers "B.Cu" "In13.Cu" "In15.Cu")
		(hatch none 0.5)
		(connect_pads
			(clearance 0)
		)
		(min_thickness 0.25)
		(keepout
			(tracks not_allowed)
			(vias allowed)
			(pads allowed)
			(copperpour not_allowed)
			(footprints allowed)
		)
		(placement
			(enabled no)
			(sheetname "")
		)
		(fill yes
			(thermal_gap 0.5)
			(thermal_bridge_width 0.5)
			(island_removal_mode 0)
		)
		(polygon
			(pts
				(arc
					(start 306.426108 -312.049922)
					(mid 305.773328 -312.049922)
					(end 306.426108 -312.049922)
				)
			)
		)
	)
	(zone
		(layers "B.Cu" "In13.Cu" "In15.Cu")
		(hatch none 0.5)
		(connect_pads
			(clearance 0)
		)
		(min_thickness 0.25)
		(keepout
			(tracks not_allowed)
			(vias allowed)
			(pads allowed)
			(copperpour not_allowed)
			(footprints allowed)
		)
		(placement
			(enabled no)
			(sheetname "")
		)
		(fill yes
			(thermal_gap 0.5)
			(thermal_bridge_width 0.5)
			(island_removal_mode 0)
		)
		(polygon
			(pts
				(arc
					(start 190.518542 -348.58579)
					(mid 189.814962 -348.58579)
					(end 190.518542 -348.58579)
				)
			)
		)
	)
	(zone
		(layers "B.Cu" "In13.Cu" "In15.Cu")
		(hatch none 0.5)
		(connect_pads
			(clearance 0)
		)
		(min_thickness 0.25)
		(keepout
			(tracks not_allowed)
			(vias allowed)
			(pads allowed)
			(copperpour not_allowed)
			(footprints allowed)
		)
		(placement
			(enabled no)
			(sheetname "")
		)
		(fill yes
			(thermal_gap 0.5)
			(thermal_bridge_width 0.5)
			(island_removal_mode 0)
		)
		(polygon
			(pts
				(arc
					(start 45.419518 -342.439498)
					(mid 44.715938 -342.439498)
					(end 45.419518 -342.439498)
				)
			)
		)
	)
	(zone
		(layers "B.Cu" "In13.Cu" "In15.Cu")
		(hatch none 0.5)
		(connect_pads
			(clearance 0)
		)
		(min_thickness 0.25)
		(keepout
			(tracks not_allowed)
			(vias allowed)
			(pads allowed)
			(copperpour not_allowed)
			(footprints allowed)
		)
		(placement
			(enabled no)
			(sheetname "")
		)
		(fill yes
			(thermal_gap 0.5)
			(thermal_bridge_width 0.5)
			(island_removal_mode 0)
		)
		(polygon
			(pts
				(arc
					(start 280.684732 -357.75773)
					(mid 279.981152 -357.75773)
					(end 280.684732 -357.75773)
				)
			)
		)
	)
	(zone
		(layers "B.Cu" "In13.Cu" "In15.Cu")
		(hatch none 0.5)
		(connect_pads
			(clearance 0)
		)
		(min_thickness 0.25)
		(keepout
			(tracks not_allowed)
			(vias allowed)
			(pads allowed)
			(copperpour not_allowed)
			(footprints allowed)
		)
		(placement
			(enabled no)
			(sheetname "")
		)
		(fill yes
			(thermal_gap 0.5)
			(thermal_bridge_width 0.5)
			(island_removal_mode 0)
		)
		(polygon
			(pts
				(arc
					(start 415.864802 -342.439498)
					(mid 415.161222 -342.439498)
					(end 415.864802 -342.439498)
				)
			)
		)
	)
	(zone
		(layers "B.Cu" "In13.Cu" "In15.Cu")
		(hatch none 0.5)
		(connect_pads
			(clearance 0)
		)
		(min_thickness 0.25)
		(keepout
			(tracks not_allowed)
			(vias allowed)
			(pads allowed)
			(copperpour not_allowed)
			(footprints allowed)
		)
		(placement
			(enabled no)
			(sheetname "")
		)
		(fill yes
			(thermal_gap 0.5)
			(thermal_bridge_width 0.5)
			(island_removal_mode 0)
		)
		(polygon
			(pts
				(arc
					(start 412.755842 -348.58579)
					(mid 412.052262 -348.58579)
					(end 412.755842 -348.58579)
				)
			)
		)
	)
	(zone
		(layers "B.Cu" "In13.Cu" "In15.Cu")
		(hatch none 0.5)
		(connect_pads
			(clearance 0)
		)
		(min_thickness 0.25)
		(keepout
			(tracks not_allowed)
			(vias allowed)
			(pads allowed)
			(copperpour not_allowed)
			(footprints allowed)
		)
		(placement
			(enabled no)
			(sheetname "")
		)
		(fill yes
			(thermal_gap 0.5)
			(thermal_bridge_width 0.5)
			(island_removal_mode 0)
		)
		(polygon
			(pts
				(arc
					(start 277.575772 -351.611438)
					(mid 276.872192 -351.611438)
					(end 277.575772 -351.611438)
				)
			)
		)
	)
	(zone
		(layers "B.Cu" "In13.Cu" "In15.Cu")
		(hatch none 0.5)
		(connect_pads
			(clearance 0)
		)
		(min_thickness 0.25)
		(keepout
			(tracks not_allowed)
			(vias allowed)
			(pads allowed)
			(copperpour not_allowed)
			(footprints allowed)
		)
		(placement
			(enabled no)
			(sheetname "")
		)
		(fill yes
			(thermal_gap 0.5)
			(thermal_bridge_width 0.5)
			(island_removal_mode 0)
		)
		(polygon
			(pts
				(arc
					(start 174.176436 -277.849838)
					(mid 173.523656 -277.849838)
					(end 174.176436 -277.849838)
				)
			)
		)
	)
	(zone
		(layers "B.Cu" "In13.Cu" "In15.Cu")
		(hatch none 0.5)
		(connect_pads
			(clearance 0)
		)
		(min_thickness 0.25)
		(keepout
			(tracks not_allowed)
			(vias allowed)
			(pads allowed)
			(copperpour not_allowed)
			(footprints allowed)
		)
		(placement
			(enabled no)
			(sheetname "")
		)
		(fill yes
			(thermal_gap 0.5)
			(thermal_bridge_width 0.5)
			(island_removal_mode 0)
		)
		(polygon
			(pts
				(arc
					(start 396.599156 -30.05709)
					(mid 395.895576 -30.05709)
					(end 396.599156 -30.05709)
				)
			)
		)
	)
	(zone
		(layers "B.Cu" "In13.Cu" "In15.Cu")
		(hatch none 0.5)
		(connect_pads
			(clearance 0)
		)
		(min_thickness 0.25)
		(keepout
			(tracks not_allowed)
			(vias allowed)
			(pads allowed)
			(copperpour not_allowed)
			(footprints allowed)
		)
		(placement
			(enabled no)
			(sheetname "")
		)
		(fill yes
			(thermal_gap 0.5)
			(thermal_bridge_width 0.5)
			(island_removal_mode 0)
		)
		(polygon
			(pts
				(arc
					(start 301.069502 -370.489988)
					(mid 300.310042 -370.489988)
					(end 301.069502 -370.489988)
				)
			)
		)
	)
	(zone
		(layers "B.Cu" "In13.Cu" "In15.Cu")
		(hatch none 0.5)
		(connect_pads
			(clearance 0)
		)
		(min_thickness 0.25)
		(keepout
			(tracks not_allowed)
			(vias allowed)
			(pads allowed)
			(copperpour not_allowed)
			(footprints allowed)
		)
		(placement
			(enabled no)
			(sheetname "")
		)
		(fill yes
			(thermal_gap 0.5)
			(thermal_bridge_width 0.5)
			(island_removal_mode 0)
		)
		(polygon
			(pts
				(arc
					(start 32.120078 -345.465146)
					(mid 31.416498 -345.465146)
					(end 32.120078 -345.465146)
				)
			)
		)
	)
	(zone
		(layers "B.Cu" "In13.Cu" "In15.Cu")
		(hatch none 0.5)
		(connect_pads
			(clearance 0)
		)
		(min_thickness 0.25)
		(keepout
			(tracks not_allowed)
			(vias allowed)
			(pads allowed)
			(copperpour not_allowed)
			(footprints allowed)
		)
		(placement
			(enabled no)
			(sheetname "")
		)
		(fill yes
			(thermal_gap 0.5)
			(thermal_bridge_width 0.5)
			(island_removal_mode 0)
		)
		(polygon
			(pts
				(arc
					(start 163.726368 -280.699718)
					(mid 163.073588 -280.699718)
					(end 163.726368 -280.699718)
				)
			)
		)
	)
	(zone
		(layers "B.Cu" "In13.Cu" "In15.Cu")
		(hatch none 0.5)
		(connect_pads
			(clearance 0)
		)
		(min_thickness 0.25)
		(keepout
			(tracks not_allowed)
			(vias allowed)
			(pads allowed)
			(copperpour not_allowed)
			(footprints allowed)
		)
		(placement
			(enabled no)
			(sheetname "")
		)
		(fill yes
			(thermal_gap 0.5)
			(thermal_bridge_width 0.5)
			(island_removal_mode 0)
		)
		(polygon
			(pts
				(arc
					(start 386.426202 -312.049922)
					(mid 385.773422 -312.049922)
					(end 386.426202 -312.049922)
				)
			)
		)
	)
	(zone
		(layers "B.Cu" "In13.Cu" "In15.Cu")
		(hatch none 0.5)
		(connect_pads
			(clearance 0)
		)
		(min_thickness 0.25)
		(keepout
			(tracks not_allowed)
			(vias allowed)
			(pads allowed)
			(copperpour not_allowed)
			(footprints allowed)
		)
		(placement
			(enabled no)
			(sheetname "")
		)
		(fill yes
			(thermal_gap 0.5)
			(thermal_bridge_width 0.5)
			(island_removal_mode 0)
		)
		(polygon
			(pts
				(arc
					(start 169.619422 -357.75773)
					(mid 168.915842 -357.75773)
					(end 169.619422 -357.75773)
				)
			)
		)
	)
	(zone
		(layers "B.Cu" "In13.Cu" "In15.Cu")
		(hatch none 0.5)
		(connect_pads
			(clearance 0)
		)
		(min_thickness 0.25)
		(keepout
			(tracks not_allowed)
			(vias allowed)
			(pads allowed)
			(copperpour not_allowed)
			(footprints allowed)
		)
		(placement
			(enabled no)
			(sheetname "")
		)
		(fill yes
			(thermal_gap 0.5)
			(thermal_bridge_width 0.5)
			(island_removal_mode 0)
		)
		(polygon
			(pts
				(arc
					(start 286.902652 -357.75773)
					(mid 286.199072 -357.75773)
					(end 286.902652 -357.75773)
				)
			)
		)
	)
	(zone
		(layers "B.Cu" "In13.Cu" "In15.Cu")
		(hatch none 0.5)
		(connect_pads
			(clearance 0)
		)
		(min_thickness 0.25)
		(keepout
			(tracks not_allowed)
			(vias allowed)
			(pads allowed)
			(copperpour not_allowed)
			(footprints allowed)
		)
		(placement
			(enabled no)
			(sheetname "")
		)
		(fill yes
			(thermal_gap 0.5)
			(thermal_bridge_width 0.5)
			(island_removal_mode 0)
		)
		(polygon
			(pts
				(arc
					(start 271.357852 -351.611438)
					(mid 270.654272 -351.611438)
					(end 271.357852 -351.611438)
				)
			)
		)
	)
	(zone
		(layers "B.Cu" "In13.Cu" "In15.Cu")
		(hatch none 0.5)
		(connect_pads
			(clearance 0)
		)
		(min_thickness 0.25)
		(keepout
			(tracks not_allowed)
			(vias allowed)
			(pads allowed)
			(copperpour not_allowed)
			(footprints allowed)
		)
		(placement
			(enabled no)
			(sheetname "")
		)
		(fill yes
			(thermal_gap 0.5)
			(thermal_bridge_width 0.5)
			(island_removal_mode 0)
		)
		(polygon
			(pts
				(arc
					(start 22.299168 -33.657286)
					(mid 21.595588 -33.657286)
					(end 22.299168 -33.657286)
				)
			)
		)
	)
	(zone
		(layers "B.Cu" "In13.Cu" "In15.Cu")
		(hatch none 0.5)
		(connect_pads
			(clearance 0)
		)
		(min_thickness 0.25)
		(keepout
			(tracks not_allowed)
			(vias allowed)
			(pads allowed)
			(copperpour not_allowed)
			(footprints allowed)
		)
		(placement
			(enabled no)
			(sheetname "")
		)
		(fill yes
			(thermal_gap 0.5)
			(thermal_bridge_width 0.5)
			(island_removal_mode 0)
		)
		(polygon
			(pts
				(arc
					(start 22.299168 -30.92069)
					(mid 21.595588 -30.92069)
					(end 22.299168 -30.92069)
				)
			)
		)
	)
	(zone
		(layers "B.Cu" "In13.Cu" "In15.Cu")
		(hatch none 0.5)
		(connect_pads
			(clearance 0)
		)
		(min_thickness 0.25)
		(keepout
			(tracks not_allowed)
			(vias allowed)
			(pads allowed)
			(copperpour not_allowed)
			(footprints allowed)
		)
		(placement
			(enabled no)
			(sheetname "")
		)
		(fill yes
			(thermal_gap 0.5)
			(thermal_bridge_width 0.5)
			(island_removal_mode 0)
		)
		(polygon
			(pts
				(arc
					(start 26.765758 -345.465146)
					(mid 26.062178 -345.465146)
					(end 26.765758 -345.465146)
				)
			)
		)
	)
	(zone
		(layers "B.Cu" "In13.Cu" "In15.Cu")
		(hatch none 0.5)
		(connect_pads
			(clearance 0)
		)
		(min_thickness 0.25)
		(keepout
			(tracks not_allowed)
			(vias allowed)
			(pads allowed)
			(copperpour not_allowed)
			(footprints allowed)
		)
		(placement
			(enabled no)
			(sheetname "")
		)
		(fill yes
			(thermal_gap 0.5)
			(thermal_bridge_width 0.5)
			(island_removal_mode 0)
		)
		(polygon
			(pts
				(arc
					(start 386.426202 -314.899802)
					(mid 385.773422 -314.899802)
					(end 386.426202 -314.899802)
				)
			)
		)
	)
	(zone
		(layers "B.Cu" "In13.Cu" "In15.Cu")
		(hatch none 0.5)
		(connect_pads
			(clearance 0)
		)
		(min_thickness 0.25)
		(keepout
			(tracks not_allowed)
			(vias allowed)
			(pads allowed)
			(copperpour not_allowed)
			(footprints allowed)
		)
		(placement
			(enabled no)
			(sheetname "")
		)
		(fill yes
			(thermal_gap 0.5)
			(thermal_bridge_width 0.5)
			(island_removal_mode 0)
		)
		(polygon
			(pts
				(arc
					(start 390.226296 -303.499774)
					(mid 389.573516 -303.499774)
					(end 390.226296 -303.499774)
				)
			)
		)
	)
	(zone
		(layers "B.Cu" "In13.Cu" "In15.Cu")
		(hatch none 0.5)
		(connect_pads
			(clearance 0)
		)
		(min_thickness 0.25)
		(keepout
			(tracks not_allowed)
			(vias allowed)
			(pads allowed)
			(copperpour not_allowed)
			(footprints allowed)
		)
		(placement
			(enabled no)
			(sheetname "")
		)
		(fill yes
			(thermal_gap 0.5)
			(thermal_bridge_width 0.5)
			(island_removal_mode 0)
		)
		(polygon
			(pts
				(arc
					(start 434.518562 -357.75773)
					(mid 433.814982 -357.75773)
					(end 434.518562 -357.75773)
				)
			)
		)
	)
	(zone
		(layers "B.Cu" "In13.Cu" "In15.Cu")
		(hatch none 0.5)
		(connect_pads
			(clearance 0)
		)
		(min_thickness 0.25)
		(keepout
			(tracks not_allowed)
			(vias allowed)
			(pads allowed)
			(copperpour not_allowed)
			(footprints allowed)
		)
		(placement
			(enabled no)
			(sheetname "")
		)
		(fill yes
			(thermal_gap 0.5)
			(thermal_bridge_width 0.5)
			(island_removal_mode 0)
		)
		(polygon
			(pts
				(arc
					(start 54.276244 -278.799798)
					(mid 53.623464 -278.799798)
					(end 54.276244 -278.799798)
				)
			)
		)
	)
	(zone
		(layers "B.Cu" "In13.Cu" "In15.Cu")
		(hatch none 0.5)
		(connect_pads
			(clearance 0)
		)
		(min_thickness 0.25)
		(keepout
			(tracks not_allowed)
			(vias allowed)
			(pads allowed)
			(copperpour not_allowed)
			(footprints allowed)
		)
		(placement
			(enabled no)
			(sheetname "")
		)
		(fill yes
			(thermal_gap 0.5)
			(thermal_bridge_width 0.5)
			(island_removal_mode 0)
		)
		(polygon
			(pts
				(arc
					(start 440.736482 -345.465146)
					(mid 440.032902 -345.465146)
					(end 440.736482 -345.465146)
				)
			)
		)
	)
	(zone
		(layers "B.Cu" "In13.Cu" "In15.Cu")
		(hatch none 0.5)
		(connect_pads
			(clearance 0)
		)
		(min_thickness 0.25)
		(keepout
			(tracks not_allowed)
			(vias allowed)
			(pads allowed)
			(copperpour not_allowed)
			(footprints allowed)
		)
		(placement
			(enabled no)
			(sheetname "")
		)
		(fill yes
			(thermal_gap 0.5)
			(thermal_bridge_width 0.5)
			(island_removal_mode 0)
		)
		(polygon
			(pts
				(arc
					(start 428.669704 -401.690078)
					(mid 427.910244 -401.690078)
					(end 428.669704 -401.690078)
				)
			)
		)
	)
	(zone
		(layers "B.Cu" "In13.Cu" "In15.Cu")
		(hatch none 0.5)
		(connect_pads
			(clearance 0)
		)
		(min_thickness 0.25)
		(keepout
			(tracks not_allowed)
			(vias allowed)
			(pads allowed)
			(copperpour not_allowed)
			(footprints allowed)
		)
		(placement
			(enabled no)
			(sheetname "")
		)
		(fill yes
			(thermal_gap 0.5)
			(thermal_bridge_width 0.5)
			(island_removal_mode 0)
		)
		(polygon
			(pts
				(arc
					(start 29.011118 -351.611438)
					(mid 28.307538 -351.611438)
					(end 29.011118 -351.611438)
				)
			)
		)
	)
	(zone
		(layers "B.Cu" "In13.Cu" "In15.Cu")
		(hatch none 0.5)
		(connect_pads
			(clearance 0)
		)
		(min_thickness 0.25)
		(keepout
			(tracks not_allowed)
			(vias allowed)
			(pads allowed)
			(copperpour not_allowed)
			(footprints allowed)
		)
		(placement
			(enabled no)
			(sheetname "")
		)
		(fill yes
			(thermal_gap 0.5)
			(thermal_bridge_width 0.5)
			(island_removal_mode 0)
		)
		(polygon
			(pts
				(arc
					(start 92.089732 -410.589984)
					(mid 91.330272 -410.589984)
					(end 92.089732 -410.589984)
				)
			)
		)
	)
	(zone
		(layers "B.Cu" "In13.Cu" "In15.Cu")
		(hatch none 0.5)
		(connect_pads
			(clearance 0)
		)
		(min_thickness 0.25)
		(keepout
			(tracks not_allowed)
			(vias allowed)
			(pads allowed)
			(copperpour not_allowed)
			(footprints allowed)
		)
		(placement
			(enabled no)
			(sheetname "")
		)
		(fill yes
			(thermal_gap 0.5)
			(thermal_bridge_width 0.5)
			(island_removal_mode 0)
		)
		(polygon
			(pts
				(arc
					(start 154.22626 -312.049922)
					(mid 153.57348 -312.049922)
					(end 154.22626 -312.049922)
				)
			)
		)
	)
	(zone
		(layers "B.Cu" "In13.Cu" "In15.Cu")
		(hatch none 0.5)
		(connect_pads
			(clearance 0)
		)
		(min_thickness 0.25)
		(keepout
			(tracks not_allowed)
			(vias allowed)
			(pads allowed)
			(copperpour not_allowed)
			(footprints allowed)
		)
		(placement
			(enabled no)
			(sheetname "")
		)
		(fill yes
			(thermal_gap 0.5)
			(thermal_bridge_width 0.5)
			(island_removal_mode 0)
		)
		(polygon
			(pts
				(arc
					(start 77.0763 -313.949842)
					(mid 76.42352 -313.949842)
					(end 77.0763 -313.949842)
				)
			)
		)
	)
	(zone
		(layers "B.Cu" "In13.Cu" "In15.Cu")
		(hatch none 0.5)
		(connect_pads
			(clearance 0)
		)
		(min_thickness 0.25)
		(keepout
			(tracks not_allowed)
			(vias allowed)
			(pads allowed)
			(copperpour not_allowed)
			(footprints allowed)
		)
		(placement
			(enabled no)
			(sheetname "")
		)
		(fill yes
			(thermal_gap 0.5)
			(thermal_bridge_width 0.5)
			(island_removal_mode 0)
		)
		(polygon
			(pts
				(arc
					(start 173.226222 -279.749504)
					(mid 172.573442 -279.749504)
					(end 173.226222 -279.749504)
				)
			)
		)
	)
	(zone
		(layers "B.Cu" "In13.Cu" "In15.Cu")
		(hatch none 0.5)
		(connect_pads
			(clearance 0)
		)
		(min_thickness 0.25)
		(keepout
			(tracks not_allowed)
			(vias allowed)
			(pads allowed)
			(copperpour not_allowed)
			(footprints allowed)
		)
		(placement
			(enabled no)
			(sheetname "")
		)
		(fill yes
			(thermal_gap 0.5)
			(thermal_bridge_width 0.5)
			(island_removal_mode 0)
		)
		(polygon
			(pts
				(arc
					(start 308.326282 -308.249828)
					(mid 307.673502 -308.249828)
					(end 308.326282 -308.249828)
				)
			)
		)
	)
	(zone
		(layers "B.Cu" "In13.Cu" "In15.Cu")
		(hatch none 0.5)
		(connect_pads
			(clearance 0)
		)
		(min_thickness 0.25)
		(keepout
			(tracks not_allowed)
			(vias allowed)
			(pads allowed)
			(copperpour not_allowed)
			(footprints allowed)
		)
		(placement
			(enabled no)
			(sheetname "")
		)
		(fill yes
			(thermal_gap 0.5)
			(thermal_bridge_width 0.5)
			(island_removal_mode 0)
		)
		(polygon
			(pts
				(arc
					(start 303.26965 -371.590062)
					(mid 302.51019 -371.590062)
					(end 303.26965 -371.590062)
				)
			)
		)
	)
	(zone
		(layers "B.Cu" "In13.Cu" "In15.Cu")
		(hatch none 0.5)
		(connect_pads
			(clearance 0)
		)
		(min_thickness 0.25)
		(keepout
			(tracks not_allowed)
			(vias allowed)
			(pads allowed)
			(copperpour not_allowed)
			(footprints allowed)
		)
		(placement
			(enabled no)
			(sheetname "")
		)
		(fill yes
			(thermal_gap 0.5)
			(thermal_bridge_width 0.5)
			(island_removal_mode 0)
		)
		(polygon
			(pts
				(arc
					(start 292.269672 -370.489988)
					(mid 291.510212 -370.489988)
					(end 292.269672 -370.489988)
				)
			)
		)
	)
	(zone
		(layers "B.Cu" "In13.Cu" "In15.Cu")
		(hatch none 0.5)
		(connect_pads
			(clearance 0)
		)
		(min_thickness 0.25)
		(keepout
			(tracks not_allowed)
			(vias allowed)
			(pads allowed)
			(copperpour not_allowed)
			(footprints allowed)
		)
		(placement
			(enabled no)
			(sheetname "")
		)
		(fill yes
			(thermal_gap 0.5)
			(thermal_bridge_width 0.5)
			(island_removal_mode 0)
		)
		(polygon
			(pts
				(arc
					(start 280.776172 -278.799798)
					(mid 280.123392 -278.799798)
					(end 280.776172 -278.799798)
				)
			)
		)
	)
	(zone
		(layers "B.Cu" "In13.Cu" "In15.Cu")
		(hatch none 0.5)
		(connect_pads
			(clearance 0)
		)
		(min_thickness 0.25)
		(keepout
			(tracks not_allowed)
			(vias allowed)
			(pads allowed)
			(copperpour not_allowed)
			(footprints allowed)
		)
		(placement
			(enabled no)
			(sheetname "")
		)
		(fill yes
			(thermal_gap 0.5)
			(thermal_bridge_width 0.5)
			(island_removal_mode 0)
		)
		(polygon
			(pts
				(arc
					(start 135.757158 -28.250642)
					(mid 135.053578 -28.250642)
					(end 135.757158 -28.250642)
				)
			)
		)
	)
	(zone
		(layers "B.Cu" "In13.Cu" "In15.Cu")
		(hatch none 0.5)
		(connect_pads
			(clearance 0)
		)
		(min_thickness 0.25)
		(keepout
			(tracks not_allowed)
			(vias allowed)
			(pads allowed)
			(copperpour not_allowed)
			(footprints allowed)
		)
		(placement
			(enabled no)
			(sheetname "")
		)
		(fill yes
			(thermal_gap 0.5)
			(thermal_bridge_width 0.5)
			(island_removal_mode 0)
		)
		(polygon
			(pts
				(arc
					(start 44.555918 -342.439498)
					(mid 43.852338 -342.439498)
					(end 44.555918 -342.439498)
				)
			)
		)
	)
	(zone
		(layers "B.Cu" "In13.Cu" "In15.Cu")
		(hatch none 0.5)
		(connect_pads
			(clearance 0)
		)
		(min_thickness 0.25)
		(keepout
			(tracks not_allowed)
			(vias allowed)
			(pads allowed)
			(copperpour not_allowed)
			(footprints allowed)
		)
		(placement
			(enabled no)
			(sheetname "")
		)
		(fill yes
			(thermal_gap 0.5)
			(thermal_bridge_width 0.5)
			(island_removal_mode 0)
		)
		(polygon
			(pts
				(arc
					(start 55.226204 -280.699718)
					(mid 54.573424 -280.699718)
					(end 55.226204 -280.699718)
				)
			)
		)
	)
	(zone
		(layers "B.Cu" "In13.Cu" "In15.Cu")
		(hatch none 0.5)
		(connect_pads
			(clearance 0)
		)
		(min_thickness 0.25)
		(keepout
			(tracks not_allowed)
			(vias allowed)
			(pads allowed)
			(copperpour not_allowed)
			(footprints allowed)
		)
		(placement
			(enabled no)
			(sheetname "")
		)
		(fill yes
			(thermal_gap 0.5)
			(thermal_bridge_width 0.5)
			(island_removal_mode 0)
		)
		(polygon
			(pts
				(arc
					(start 281.726132 -280.699718)
					(mid 281.073352 -280.699718)
					(end 281.726132 -280.699718)
				)
			)
		)
	)
	(zone
		(layers "B.Cu" "In13.Cu" "In15.Cu")
		(hatch none 0.5)
		(connect_pads
			(clearance 0)
		)
		(min_thickness 0.25)
		(keepout
			(tracks not_allowed)
			(vias allowed)
			(pads allowed)
			(copperpour not_allowed)
			(footprints allowed)
		)
		(placement
			(enabled no)
			(sheetname "")
		)
		(fill yes
			(thermal_gap 0.5)
			(thermal_bridge_width 0.5)
			(island_removal_mode 0)
		)
		(polygon
			(pts
				(arc
					(start 278.876252 -278.799798)
					(mid 278.223472 -278.799798)
					(end 278.876252 -278.799798)
				)
			)
		)
	)
	(zone
		(layers "B.Cu" "In13.Cu" "In15.Cu")
		(hatch none 0.5)
		(connect_pads
			(clearance 0)
		)
		(min_thickness 0.25)
		(keepout
			(tracks not_allowed)
			(vias allowed)
			(pads allowed)
			(copperpour not_allowed)
			(footprints allowed)
		)
		(placement
			(enabled no)
			(sheetname "")
		)
		(fill yes
			(thermal_gap 0.5)
			(thermal_bridge_width 0.5)
			(island_removal_mode 0)
		)
		(polygon
			(pts
				(arc
					(start 44.555918 -345.465146)
					(mid 43.852338 -345.465146)
					(end 44.555918 -345.465146)
				)
			)
		)
	)
	(zone
		(layers "B.Cu" "In13.Cu" "In15.Cu")
		(hatch none 0.5)
		(connect_pads
			(clearance 0)
		)
		(min_thickness 0.25)
		(keepout
			(tracks not_allowed)
			(vias allowed)
			(pads allowed)
			(copperpour not_allowed)
			(footprints allowed)
		)
		(placement
			(enabled no)
			(sheetname "")
		)
		(fill yes
			(thermal_gap 0.5)
			(thermal_bridge_width 0.5)
			(island_removal_mode 0)
		)
		(polygon
			(pts
				(arc
					(start 47.62627 -279.749504)
					(mid 46.97349 -279.749504)
					(end 47.62627 -279.749504)
				)
			)
		)
	)
	(zone
		(layers "B.Cu" "In13.Cu" "In15.Cu")
		(hatch none 0.5)
		(connect_pads
			(clearance 0)
		)
		(min_thickness 0.25)
		(keepout
			(tracks not_allowed)
			(vias allowed)
			(pads allowed)
			(copperpour not_allowed)
			(footprints allowed)
		)
		(placement
			(enabled no)
			(sheetname "")
		)
		(fill yes
			(thermal_gap 0.5)
			(thermal_bridge_width 0.5)
			(island_removal_mode 0)
		)
		(polygon
			(pts
				(arc
					(start 396.87627 -278.799798)
					(mid 396.22349 -278.799798)
					(end 396.87627 -278.799798)
				)
			)
		)
	)
	(zone
		(layers "B.Cu" "In13.Cu" "In15.Cu")
		(hatch none 0.5)
		(connect_pads
			(clearance 0)
		)
		(min_thickness 0.25)
		(keepout
			(tracks not_allowed)
			(vias allowed)
			(pads allowed)
			(copperpour not_allowed)
			(footprints allowed)
		)
		(placement
			(enabled no)
			(sheetname "")
		)
		(fill yes
			(thermal_gap 0.5)
			(thermal_bridge_width 0.5)
			(island_removal_mode 0)
		)
		(polygon
			(pts
				(arc
					(start 39.201598 -354.732082)
					(mid 38.498018 -354.732082)
					(end 39.201598 -354.732082)
				)
			)
		)
	)
	(zone
		(layers "B.Cu" "In13.Cu" "In15.Cu")
		(hatch none 0.5)
		(connect_pads
			(clearance 0)
		)
		(min_thickness 0.25)
		(keepout
			(tracks not_allowed)
			(vias allowed)
			(pads allowed)
			(copperpour not_allowed)
			(footprints allowed)
		)
		(placement
			(enabled no)
			(sheetname "")
		)
		(fill yes
			(thermal_gap 0.5)
			(thermal_bridge_width 0.5)
			(island_removal_mode 0)
		)
		(polygon
			(pts
				(arc
					(start 306.499006 -34.520886)
					(mid 305.795426 -34.520886)
					(end 306.499006 -34.520886)
				)
			)
		)
	)
	(zone
		(layers "B.Cu" "In13.Cu" "In15.Cu")
		(hatch none 0.5)
		(connect_pads
			(clearance 0)
		)
		(min_thickness 0.25)
		(keepout
			(tracks not_allowed)
			(vias allowed)
			(pads allowed)
			(copperpour not_allowed)
			(footprints allowed)
		)
		(placement
			(enabled no)
			(sheetname "")
		)
		(fill yes
			(thermal_gap 0.5)
			(thermal_bridge_width 0.5)
			(island_removal_mode 0)
		)
		(polygon
			(pts
				(arc
					(start 160.289748 -375.69013)
					(mid 159.530288 -375.69013)
					(end 160.289748 -375.69013)
				)
			)
		)
	)
	(zone
		(layers "B.Cu" "In13.Cu" "In15.Cu")
		(hatch none 0.5)
		(connect_pads
			(clearance 0)
		)
		(min_thickness 0.25)
		(keepout
			(tracks not_allowed)
			(vias allowed)
			(pads allowed)
			(copperpour not_allowed)
			(footprints allowed)
		)
		(placement
			(enabled no)
			(sheetname "")
		)
		(fill yes
			(thermal_gap 0.5)
			(thermal_bridge_width 0.5)
			(island_removal_mode 0)
		)
		(polygon
			(pts
				(arc
					(start 38.337998 -357.75773)
					(mid 37.634418 -357.75773)
					(end 38.337998 -357.75773)
				)
			)
		)
	)
	(zone
		(layers "B.Cu" "In13.Cu" "In15.Cu")
		(hatch none 0.5)
		(connect_pads
			(clearance 0)
		)
		(min_thickness 0.25)
		(keepout
			(tracks not_allowed)
			(vias allowed)
			(pads allowed)
			(copperpour not_allowed)
			(footprints allowed)
		)
		(placement
			(enabled no)
			(sheetname "")
		)
		(fill yes
			(thermal_gap 0.5)
			(thermal_bridge_width 0.5)
			(island_removal_mode 0)
		)
		(polygon
			(pts
				(arc
					(start 38.337998 -342.439498)
					(mid 37.634418 -342.439498)
					(end 38.337998 -342.439498)
				)
			)
		)
	)
	(zone
		(layers "B.Cu" "In13.Cu" "In15.Cu")
		(hatch none 0.5)
		(connect_pads
			(clearance 0)
		)
		(min_thickness 0.25)
		(keepout
			(tracks not_allowed)
			(vias allowed)
			(pads allowed)
			(copperpour not_allowed)
			(footprints allowed)
		)
		(placement
			(enabled no)
			(sheetname "")
		)
		(fill yes
			(thermal_gap 0.5)
			(thermal_bridge_width 0.5)
			(island_removal_mode 0)
		)
		(polygon
			(pts
				(arc
					(start 181.191662 -342.439498)
					(mid 180.488082 -342.439498)
					(end 181.191662 -342.439498)
				)
			)
		)
	)
	(zone
		(layers "B.Cu" "In13.Cu" "In15.Cu")
		(hatch none 0.5)
		(connect_pads
			(clearance 0)
		)
		(min_thickness 0.25)
		(keepout
			(tracks not_allowed)
			(vias allowed)
			(pads allowed)
			(copperpour not_allowed)
			(footprints allowed)
		)
		(placement
			(enabled no)
			(sheetname "")
		)
		(fill yes
			(thermal_gap 0.5)
			(thermal_bridge_width 0.5)
			(island_removal_mode 0)
		)
		(polygon
			(pts
				(arc
					(start 78.02626 -307.299868)
					(mid 77.37348 -307.299868)
					(end 78.02626 -307.299868)
				)
			)
		)
	)
	(zone
		(layers "B.Cu" "In13.Cu" "In15.Cu")
		(hatch none 0.5)
		(connect_pads
			(clearance 0)
		)
		(min_thickness 0.25)
		(keepout
			(tracks not_allowed)
			(vias allowed)
			(pads allowed)
			(copperpour not_allowed)
			(footprints allowed)
		)
		(placement
			(enabled no)
			(sheetname "")
		)
		(fill yes
			(thermal_gap 0.5)
			(thermal_bridge_width 0.5)
			(island_removal_mode 0)
		)
		(polygon
			(pts
				(arc
					(start 29.874718 -351.611438)
					(mid 29.171138 -351.611438)
					(end 29.874718 -351.611438)
				)
			)
		)
	)
	(zone
		(layers "B.Cu" "In13.Cu" "In15.Cu")
		(hatch none 0.5)
		(connect_pads
			(clearance 0)
		)
		(min_thickness 0.25)
		(keepout
			(tracks not_allowed)
			(vias allowed)
			(pads allowed)
			(copperpour not_allowed)
			(footprints allowed)
		)
		(placement
			(enabled no)
			(sheetname "")
		)
		(fill yes
			(thermal_gap 0.5)
			(thermal_bridge_width 0.5)
			(island_removal_mode 0)
		)
		(polygon
			(pts
				(arc
					(start 425.191682 -348.58579)
					(mid 424.488102 -348.58579)
					(end 425.191682 -348.58579)
				)
			)
		)
	)
	(zone
		(layers "B.Cu" "In13.Cu" "In15.Cu")
		(hatch none 0.5)
		(connect_pads
			(clearance 0)
		)
		(min_thickness 0.25)
		(keepout
			(tracks not_allowed)
			(vias allowed)
			(pads allowed)
			(copperpour not_allowed)
			(footprints allowed)
		)
		(placement
			(enabled no)
			(sheetname "")
		)
		(fill yes
			(thermal_gap 0.5)
			(thermal_bridge_width 0.5)
			(island_removal_mode 0)
		)
		(polygon
			(pts
				(arc
					(start 392.126216 -304.449734)
					(mid 391.473436 -304.449734)
					(end 392.126216 -304.449734)
				)
			)
		)
	)
	(zone
		(layers "B.Cu" "In13.Cu" "In15.Cu")
		(hatch none 0.5)
		(connect_pads
			(clearance 0)
		)
		(min_thickness 0.25)
		(keepout
			(tracks not_allowed)
			(vias allowed)
			(pads allowed)
			(copperpour not_allowed)
			(footprints allowed)
		)
		(placement
			(enabled no)
			(sheetname "")
		)
		(fill yes
			(thermal_gap 0.5)
			(thermal_bridge_width 0.5)
			(island_removal_mode 0)
		)
		(polygon
			(pts
				(arc
					(start 172.728382 -348.58579)
					(mid 172.024802 -348.58579)
					(end 172.728382 -348.58579)
				)
			)
		)
	)
	(zone
		(layers "B.Cu" "In13.Cu" "In15.Cu")
		(hatch none 0.5)
		(connect_pads
			(clearance 0)
		)
		(min_thickness 0.25)
		(keepout
			(tracks not_allowed)
			(vias allowed)
			(pads allowed)
			(copperpour not_allowed)
			(footprints allowed)
		)
		(placement
			(enabled no)
			(sheetname "")
		)
		(fill yes
			(thermal_gap 0.5)
			(thermal_bridge_width 0.5)
			(island_removal_mode 0)
		)
		(polygon
			(pts
				(arc
					(start 175.689768 -401.49018)
					(mid 174.930308 -401.49018)
					(end 175.689768 -401.49018)
				)
			)
		)
	)
	(zone
		(layers "B.Cu" "In13.Cu" "In15.Cu")
		(hatch none 0.5)
		(connect_pads
			(clearance 0)
		)
		(min_thickness 0.25)
		(keepout
			(tracks not_allowed)
			(vias allowed)
			(pads allowed)
			(copperpour not_allowed)
			(footprints allowed)
		)
		(placement
			(enabled no)
			(sheetname "")
		)
		(fill yes
			(thermal_gap 0.5)
			(thermal_bridge_width 0.5)
			(island_removal_mode 0)
		)
		(polygon
			(pts
				(arc
					(start 254.49911 -30.05709)
					(mid 253.79553 -30.05709)
					(end 254.49911 -30.05709)
				)
			)
		)
	)
	(zone
		(layers "B.Cu" "In13.Cu" "In15.Cu")
		(hatch none 0.5)
		(connect_pads
			(clearance 0)
		)
		(min_thickness 0.25)
		(keepout
			(tracks not_allowed)
			(vias allowed)
			(pads allowed)
			(copperpour not_allowed)
			(footprints allowed)
		)
		(placement
			(enabled no)
			(sheetname "")
		)
		(fill yes
			(thermal_gap 0.5)
			(thermal_bridge_width 0.5)
			(island_removal_mode 0)
		)
		(polygon
			(pts
				(arc
					(start 426.469556 -375.490232)
					(mid 425.710096 -375.490232)
					(end 426.469556 -375.490232)
				)
			)
		)
	)
	(zone
		(layers "B.Cu" "In13.Cu" "In15.Cu")
		(hatch none 0.5)
		(connect_pads
			(clearance 0)
		)
		(min_thickness 0.25)
		(keepout
			(tracks not_allowed)
			(vias allowed)
			(pads allowed)
			(copperpour not_allowed)
			(footprints allowed)
		)
		(placement
			(enabled no)
			(sheetname "")
		)
		(fill yes
			(thermal_gap 0.5)
			(thermal_bridge_width 0.5)
			(island_removal_mode 0)
		)
		(polygon
			(pts
				(arc
					(start 393.957048 -29.114242)
					(mid 393.253468 -29.114242)
					(end 393.957048 -29.114242)
				)
			)
		)
	)
	(zone
		(layers "B.Cu" "In13.Cu" "In15.Cu")
		(hatch none 0.5)
		(connect_pads
			(clearance 0)
		)
		(min_thickness 0.25)
		(keepout
			(tracks not_allowed)
			(vias allowed)
			(pads allowed)
			(copperpour not_allowed)
			(footprints allowed)
		)
		(placement
			(enabled no)
			(sheetname "")
		)
		(fill yes
			(thermal_gap 0.5)
			(thermal_bridge_width 0.5)
			(island_removal_mode 0)
		)
		(polygon
			(pts
				(arc
					(start 284.657292 -351.611438)
					(mid 283.953712 -351.611438)
					(end 284.657292 -351.611438)
				)
			)
		)
	)
	(zone
		(layers "B.Cu" "In13.Cu" "In15.Cu")
		(hatch none 0.5)
		(connect_pads
			(clearance 0)
		)
		(min_thickness 0.25)
		(keepout
			(tracks not_allowed)
			(vias allowed)
			(pads allowed)
			(copperpour not_allowed)
			(footprints allowed)
		)
		(placement
			(enabled no)
			(sheetname "")
		)
		(fill yes
			(thermal_gap 0.5)
			(thermal_bridge_width 0.5)
			(island_removal_mode 0)
		)
		(polygon
			(pts
				(arc
					(start 178.946302 -351.611438)
					(mid 178.242722 -351.611438)
					(end 178.946302 -351.611438)
				)
			)
		)
	)
	(zone
		(layers "B.Cu" "In13.Cu" "In15.Cu")
		(hatch none 0.5)
		(connect_pads
			(clearance 0)
		)
		(min_thickness 0.25)
		(keepout
			(tracks not_allowed)
			(vias allowed)
			(pads allowed)
			(copperpour not_allowed)
			(footprints allowed)
		)
		(placement
			(enabled no)
			(sheetname "")
		)
		(fill yes
			(thermal_gap 0.5)
			(thermal_bridge_width 0.5)
			(island_removal_mode 0)
		)
		(polygon
			(pts
				(arc
					(start 71.656956 -28.250642)
					(mid 70.953376 -28.250642)
					(end 71.656956 -28.250642)
				)
			)
		)
	)
	(zone
		(layers "B.Cu" "In13.Cu" "In15.Cu")
		(hatch none 0.5)
		(connect_pads
			(clearance 0)
		)
		(min_thickness 0.25)
		(keepout
			(tracks not_allowed)
			(vias allowed)
			(pads allowed)
			(copperpour not_allowed)
			(footprints allowed)
		)
		(placement
			(enabled no)
			(sheetname "")
		)
		(fill yes
			(thermal_gap 0.5)
			(thermal_bridge_width 0.5)
			(island_removal_mode 0)
		)
		(polygon
			(pts
				(arc
					(start 292.269672 -397.790162)
					(mid 291.510212 -397.790162)
					(end 292.269672 -397.790162)
				)
			)
		)
	)
	(zone
		(layers "B.Cu" "In13.Cu" "In15.Cu")
		(hatch none 0.5)
		(connect_pads
			(clearance 0)
		)
		(min_thickness 0.25)
		(keepout
			(tracks not_allowed)
			(vias allowed)
			(pads allowed)
			(copperpour not_allowed)
			(footprints allowed)
		)
		(placement
			(enabled no)
			(sheetname "")
		)
		(fill yes
			(thermal_gap 0.5)
			(thermal_bridge_width 0.5)
			(island_removal_mode 0)
		)
		(polygon
			(pts
				(arc
					(start 97.656904 -31.850584)
					(mid 96.953324 -31.850584)
					(end 97.656904 -31.850584)
				)
			)
		)
	)
	(zone
		(layers "B.Cu" "In13.Cu" "In15.Cu")
		(hatch none 0.5)
		(connect_pads
			(clearance 0)
		)
		(min_thickness 0.25)
		(keepout
			(tracks not_allowed)
			(vias allowed)
			(pads allowed)
			(copperpour not_allowed)
			(footprints allowed)
		)
		(placement
			(enabled no)
			(sheetname "")
		)
		(fill yes
			(thermal_gap 0.5)
			(thermal_bridge_width 0.5)
			(island_removal_mode 0)
		)
		(polygon
			(pts
				(arc
					(start 25.902158 -342.439498)
					(mid 25.198578 -342.439498)
					(end 25.902158 -342.439498)
				)
			)
		)
	)
	(zone
		(layers "B.Cu" "In13.Cu" "In15.Cu")
		(hatch none 0.5)
		(connect_pads
			(clearance 0)
		)
		(min_thickness 0.25)
		(keepout
			(tracks not_allowed)
			(vias allowed)
			(pads allowed)
			(copperpour not_allowed)
			(footprints allowed)
		)
		(placement
			(enabled no)
			(sheetname "")
		)
		(fill yes
			(thermal_gap 0.5)
			(thermal_bridge_width 0.5)
			(island_removal_mode 0)
		)
		(polygon
			(pts
				(arc
					(start 422.946322 -357.75773)
					(mid 422.242742 -357.75773)
					(end 422.946322 -357.75773)
				)
			)
		)
	)
	(zone
		(layers "B.Cu" "In13.Cu" "In15.Cu")
		(hatch none 0.5)
		(connect_pads
			(clearance 0)
		)
		(min_thickness 0.25)
		(keepout
			(tracks not_allowed)
			(vias allowed)
			(pads allowed)
			(copperpour not_allowed)
			(footprints allowed)
		)
		(placement
			(enabled no)
			(sheetname "")
		)
		(fill yes
			(thermal_gap 0.5)
			(thermal_bridge_width 0.5)
			(island_removal_mode 0)
		)
		(polygon
			(pts
				(arc
					(start 138.399266 -30.05709)
					(mid 137.695686 -30.05709)
					(end 138.399266 -30.05709)
				)
			)
		)
	)
	(zone
		(layers "B.Cu" "In13.Cu" "In15.Cu")
		(hatch none 0.5)
		(connect_pads
			(clearance 0)
		)
		(min_thickness 0.25)
		(keepout
			(tracks not_allowed)
			(vias allowed)
			(pads allowed)
			(copperpour not_allowed)
			(footprints allowed)
		)
		(placement
			(enabled no)
			(sheetname "")
		)
		(fill yes
			(thermal_gap 0.5)
			(thermal_bridge_width 0.5)
			(island_removal_mode 0)
		)
		(polygon
			(pts
				(arc
					(start 100.299012 -33.657286)
					(mid 99.595432 -33.657286)
					(end 100.299012 -33.657286)
				)
			)
		)
	)
	(zone
		(layers "B.Cu" "In13.Cu" "In15.Cu")
		(hatch none 0.5)
		(connect_pads
			(clearance 0)
		)
		(min_thickness 0.25)
		(keepout
			(tracks not_allowed)
			(vias allowed)
			(pads allowed)
			(copperpour not_allowed)
			(footprints allowed)
		)
		(placement
			(enabled no)
			(sheetname "")
		)
		(fill yes
			(thermal_gap 0.5)
			(thermal_bridge_width 0.5)
			(island_removal_mode 0)
		)
		(polygon
			(pts
				(arc
					(start 187.409582 -357.733854)
					(mid 186.706002 -357.733854)
					(end 187.409582 -357.733854)
				)
			)
		)
	)
	(zone
		(layers "B.Cu" "In13.Cu" "In15.Cu")
		(hatch none 0.5)
		(connect_pads
			(clearance 0)
		)
		(min_thickness 0.25)
		(keepout
			(tracks not_allowed)
			(vias allowed)
			(pads allowed)
			(copperpour not_allowed)
			(footprints allowed)
		)
		(placement
			(enabled no)
			(sheetname "")
		)
		(fill yes
			(thermal_gap 0.5)
			(thermal_bridge_width 0.5)
			(island_removal_mode 0)
		)
		(polygon
			(pts
				(arc
					(start 419.956996 -29.114242)
					(mid 419.253416 -29.114242)
					(end 419.956996 -29.114242)
				)
			)
		)
	)
	(zone
		(layers "B.Cu" "In13.Cu" "In15.Cu")
		(hatch none 0.5)
		(connect_pads
			(clearance 0)
		)
		(min_thickness 0.25)
		(keepout
			(tracks not_allowed)
			(vias allowed)
			(pads allowed)
			(copperpour not_allowed)
			(footprints allowed)
		)
		(placement
			(enabled no)
			(sheetname "")
		)
		(fill yes
			(thermal_gap 0.5)
			(thermal_bridge_width 0.5)
			(island_removal_mode 0)
		)
		(polygon
			(pts
				(arc
					(start 269.112492 -345.465146)
					(mid 268.408912 -345.465146)
					(end 269.112492 -345.465146)
				)
			)
		)
	)
	(zone
		(layers "B.Cu" "In13.Cu" "In15.Cu")
		(hatch none 0.5)
		(connect_pads
			(clearance 0)
		)
		(min_thickness 0.25)
		(keepout
			(tracks not_allowed)
			(vias allowed)
			(pads allowed)
			(copperpour not_allowed)
			(footprints allowed)
		)
		(placement
			(enabled no)
			(sheetname "")
		)
		(fill yes
			(thermal_gap 0.5)
			(thermal_bridge_width 0.5)
			(island_removal_mode 0)
		)
		(polygon
			(pts
				(arc
					(start 313.076082 -313.949842)
					(mid 312.423302 -313.949842)
					(end 313.076082 -313.949842)
				)
			)
		)
	)
	(zone
		(layers "B.Cu" "In13.Cu" "In15.Cu")
		(hatch none 0.5)
		(connect_pads
			(clearance 0)
		)
		(min_thickness 0.25)
		(keepout
			(tracks not_allowed)
			(vias allowed)
			(pads allowed)
			(copperpour not_allowed)
			(footprints allowed)
		)
		(placement
			(enabled no)
			(sheetname "")
		)
		(fill yes
			(thermal_gap 0.5)
			(thermal_bridge_width 0.5)
			(island_removal_mode 0)
		)
		(polygon
			(pts
				(arc
					(start 48.299116 -33.657286)
					(mid 47.595536 -33.657286)
					(end 48.299116 -33.657286)
				)
			)
		)
	)
	(zone
		(layers "B.Cu" "In13.Cu" "In15.Cu")
		(hatch none 0.5)
		(connect_pads
			(clearance 0)
		)
		(min_thickness 0.25)
		(keepout
			(tracks not_allowed)
			(vias allowed)
			(pads allowed)
			(copperpour not_allowed)
			(footprints allowed)
		)
		(placement
			(enabled no)
			(sheetname "")
		)
		(fill yes
			(thermal_gap 0.5)
			(thermal_bridge_width 0.5)
			(island_removal_mode 0)
		)
		(polygon
			(pts
				(arc
					(start 389.276336 -312.999882)
					(mid 388.623556 -312.999882)
					(end 389.276336 -312.999882)
				)
			)
		)
	)
	(zone
		(layers "B.Cu" "In13.Cu" "In15.Cu")
		(hatch none 0.5)
		(connect_pads
			(clearance 0)
		)
		(min_thickness 0.25)
		(keepout
			(tracks not_allowed)
			(vias allowed)
			(pads allowed)
			(copperpour not_allowed)
			(footprints allowed)
		)
		(placement
			(enabled no)
			(sheetname "")
		)
		(fill yes
			(thermal_gap 0.5)
			(thermal_bridge_width 0.5)
			(island_removal_mode 0)
		)
		(polygon
			(pts
				(arc
					(start 391.176256 -303.499774)
					(mid 390.523476 -303.499774)
					(end 391.176256 -303.499774)
				)
			)
		)
	)
	(zone
		(layers "B.Cu" "In13.Cu" "In15.Cu")
		(hatch none 0.5)
		(connect_pads
			(clearance 0)
		)
		(min_thickness 0.25)
		(keepout
			(tracks not_allowed)
			(vias allowed)
			(pads allowed)
			(copperpour not_allowed)
			(footprints allowed)
		)
		(placement
			(enabled no)
			(sheetname "")
		)
		(fill yes
			(thermal_gap 0.5)
			(thermal_bridge_width 0.5)
			(island_removal_mode 0)
		)
		(polygon
			(pts
				(arc
					(start 282.676092 -277.849838)
					(mid 282.023312 -277.849838)
					(end 282.676092 -277.849838)
				)
			)
		)
	)
	(zone
		(layers "B.Cu" "In13.Cu" "In15.Cu")
		(hatch none 0.5)
		(connect_pads
			(clearance 0)
		)
		(min_thickness 0.25)
		(keepout
			(tracks not_allowed)
			(vias allowed)
			(pads allowed)
			(copperpour not_allowed)
			(footprints allowed)
		)
		(placement
			(enabled no)
			(sheetname "")
		)
		(fill yes
			(thermal_gap 0.5)
			(thermal_bridge_width 0.5)
			(island_removal_mode 0)
		)
		(polygon
			(pts
				(arc
					(start 173.48962 -400.390106)
					(mid 172.73016 -400.390106)
					(end 173.48962 -400.390106)
				)
			)
		)
	)
	(zone
		(layers "B.Cu" "In13.Cu" "In15.Cu")
		(hatch none 0.5)
		(connect_pads
			(clearance 0)
		)
		(min_thickness 0.25)
		(keepout
			(tracks not_allowed)
			(vias allowed)
			(pads allowed)
			(copperpour not_allowed)
			(footprints allowed)
		)
		(placement
			(enabled no)
			(sheetname "")
		)
		(fill yes
			(thermal_gap 0.5)
			(thermal_bridge_width 0.5)
			(island_removal_mode 0)
		)
		(polygon
			(pts
				(arc
					(start 422.069514 -375.490232)
					(mid 421.310054 -375.490232)
					(end 422.069514 -375.490232)
				)
			)
		)
	)
	(zone
		(layers "B.Cu" "In13.Cu" "In15.Cu")
		(hatch none 0.5)
		(connect_pads
			(clearance 0)
		)
		(min_thickness 0.25)
		(keepout
			(tracks not_allowed)
			(vias allowed)
			(pads allowed)
			(copperpour not_allowed)
			(footprints allowed)
		)
		(placement
			(enabled no)
			(sheetname "")
		)
		(fill yes
			(thermal_gap 0.5)
			(thermal_bridge_width 0.5)
			(island_removal_mode 0)
		)
		(polygon
			(pts
				(arc
					(start 293.984172 -354.732082)
					(mid 293.280592 -354.732082)
					(end 293.984172 -354.732082)
				)
			)
		)
	)
	(zone
		(layers "B.Cu" "In13.Cu" "In15.Cu")
		(hatch none 0.5)
		(connect_pads
			(clearance 0)
		)
		(min_thickness 0.25)
		(keepout
			(tracks not_allowed)
			(vias allowed)
			(pads allowed)
			(copperpour not_allowed)
			(footprints allowed)
		)
		(placement
			(enabled no)
			(sheetname "")
		)
		(fill yes
			(thermal_gap 0.5)
			(thermal_bridge_width 0.5)
			(island_removal_mode 0)
		)
		(polygon
			(pts
				(arc
					(start 428.300642 -357.75773)
					(mid 427.597062 -357.75773)
					(end 428.300642 -357.75773)
				)
			)
		)
	)
	(zone
		(layers "B.Cu" "In13.Cu" "In15.Cu")
		(hatch none 0.5)
		(connect_pads
			(clearance 0)
		)
		(min_thickness 0.25)
		(keepout
			(tracks not_allowed)
			(vias allowed)
			(pads allowed)
			(copperpour not_allowed)
			(footprints allowed)
		)
		(placement
			(enabled no)
			(sheetname "")
		)
		(fill yes
			(thermal_gap 0.5)
			(thermal_bridge_width 0.5)
			(island_removal_mode 0)
		)
		(polygon
			(pts
				(arc
					(start 394.02639 -280.699718)
					(mid 393.37361 -280.699718)
					(end 394.02639 -280.699718)
				)
			)
		)
	)
	(zone
		(layers "B.Cu" "In13.Cu" "In15.Cu")
		(hatch none 0.5)
		(connect_pads
			(clearance 0)
		)
		(min_thickness 0.25)
		(keepout
			(tracks not_allowed)
			(vias allowed)
			(pads allowed)
			(copperpour not_allowed)
			(footprints allowed)
		)
		(placement
			(enabled no)
			(sheetname "")
		)
		(fill yes
			(thermal_gap 0.5)
			(thermal_bridge_width 0.5)
			(island_removal_mode 0)
		)
		(polygon
			(pts
				(arc
					(start 434.518562 -354.732082)
					(mid 433.814982 -354.732082)
					(end 434.518562 -354.732082)
				)
			)
		)
	)
	(zone
		(layers "B.Cu" "In13.Cu" "In15.Cu")
		(hatch none 0.5)
		(connect_pads
			(clearance 0)
		)
		(min_thickness 0.25)
		(keepout
			(tracks not_allowed)
			(vias allowed)
			(pads allowed)
			(copperpour not_allowed)
			(footprints allowed)
		)
		(placement
			(enabled no)
			(sheetname "")
		)
		(fill yes
			(thermal_gap 0.5)
			(thermal_bridge_width 0.5)
			(island_removal_mode 0)
		)
		(polygon
			(pts
				(arc
					(start 287.766252 -357.75773)
					(mid 287.062672 -357.75773)
					(end 287.766252 -357.75773)
				)
			)
		)
	)
	(zone
		(layers "B.Cu" "In13.Cu" "In15.Cu")
		(hatch none 0.5)
		(connect_pads
			(clearance 0)
		)
		(min_thickness 0.25)
		(keepout
			(tracks not_allowed)
			(vias allowed)
			(pads allowed)
			(copperpour not_allowed)
			(footprints allowed)
		)
		(placement
			(enabled no)
			(sheetname "")
		)
		(fill yes
			(thermal_gap 0.5)
			(thermal_bridge_width 0.5)
			(island_removal_mode 0)
		)
		(polygon
			(pts
				(arc
					(start 174.176436 -278.799798)
					(mid 173.523656 -278.799798)
					(end 174.176436 -278.799798)
				)
			)
		)
	)
	(zone
		(layers "B.Cu" "In13.Cu" "In15.Cu")
		(hatch none 0.5)
		(connect_pads
			(clearance 0)
		)
		(min_thickness 0.25)
		(keepout
			(tracks not_allowed)
			(vias allowed)
			(pads allowed)
			(copperpour not_allowed)
			(footprints allowed)
		)
		(placement
			(enabled no)
			(sheetname "")
		)
		(fill yes
			(thermal_gap 0.5)
			(thermal_bridge_width 0.5)
			(island_removal_mode 0)
		)
		(polygon
			(pts
				(arc
					(start 78.02626 -312.049922)
					(mid 77.37348 -312.049922)
					(end 78.02626 -312.049922)
				)
			)
		)
	)
	(zone
		(layers "B.Cu" "In13.Cu" "In15.Cu")
		(hatch none 0.5)
		(connect_pads
			(clearance 0)
		)
		(min_thickness 0.25)
		(keepout
			(tracks not_allowed)
			(vias allowed)
			(pads allowed)
			(copperpour not_allowed)
			(footprints allowed)
		)
		(placement
			(enabled no)
			(sheetname "")
		)
		(fill yes
			(thermal_gap 0.5)
			(thermal_bridge_width 0.5)
			(island_removal_mode 0)
		)
		(polygon
			(pts
				(arc
					(start 290.069524 -371.590062)
					(mid 289.310064 -371.590062)
					(end 290.069524 -371.590062)
				)
			)
		)
	)
	(zone
		(layers "B.Cu" "In13.Cu" "In15.Cu")
		(hatch none 0.5)
		(connect_pads
			(clearance 0)
		)
		(min_thickness 0.25)
		(keepout
			(tracks not_allowed)
			(vias allowed)
			(pads allowed)
			(copperpour not_allowed)
			(footprints allowed)
		)
		(placement
			(enabled no)
			(sheetname "")
		)
		(fill yes
			(thermal_gap 0.5)
			(thermal_bridge_width 0.5)
			(island_removal_mode 0)
		)
		(polygon
			(pts
				(arc
					(start 399.726404 -280.699718)
					(mid 399.073624 -280.699718)
					(end 399.726404 -280.699718)
				)
			)
		)
	)
	(zone
		(layers "B.Cu" "In13.Cu" "In15.Cu")
		(hatch none 0.5)
		(connect_pads
			(clearance 0)
		)
		(min_thickness 0.25)
		(keepout
			(tracks not_allowed)
			(vias allowed)
			(pads allowed)
			(copperpour not_allowed)
			(footprints allowed)
		)
		(placement
			(enabled no)
			(sheetname "")
		)
		(fill yes
			(thermal_gap 0.5)
			(thermal_bridge_width 0.5)
			(island_removal_mode 0)
		)
		(polygon
			(pts
				(arc
					(start 173.48962 -401.690078)
					(mid 172.73016 -401.690078)
					(end 173.48962 -401.690078)
				)
			)
		)
	)
	(zone
		(layers "B.Cu" "In13.Cu" "In15.Cu")
		(hatch none 0.5)
		(connect_pads
			(clearance 0)
		)
		(min_thickness 0.25)
		(keepout
			(tracks not_allowed)
			(vias allowed)
			(pads allowed)
			(copperpour not_allowed)
			(footprints allowed)
		)
		(placement
			(enabled no)
			(sheetname "")
		)
		(fill yes
			(thermal_gap 0.5)
			(thermal_bridge_width 0.5)
			(island_removal_mode 0)
		)
		(polygon
			(pts
				(arc
					(start 281.548332 -357.75773)
					(mid 280.844752 -357.75773)
					(end 281.548332 -357.75773)
				)
			)
		)
	)
	(zone
		(layers "B.Cu" "In13.Cu" "In15.Cu")
		(hatch none 0.5)
		(connect_pads
			(clearance 0)
		)
		(min_thickness 0.25)
		(keepout
			(tracks not_allowed)
			(vias allowed)
			(pads allowed)
			(copperpour not_allowed)
			(footprints allowed)
		)
		(placement
			(enabled no)
			(sheetname "")
		)
		(fill yes
			(thermal_gap 0.5)
			(thermal_bridge_width 0.5)
			(island_removal_mode 0)
		)
		(polygon
			(pts
				(arc
					(start 45.657008 -29.114242)
					(mid 44.953428 -29.114242)
					(end 45.657008 -29.114242)
				)
			)
		)
	)
	(zone
		(layers "B.Cu" "In13.Cu" "In15.Cu")
		(hatch none 0.5)
		(connect_pads
			(clearance 0)
		)
		(min_thickness 0.25)
		(keepout
			(tracks not_allowed)
			(vias allowed)
			(pads allowed)
			(copperpour not_allowed)
			(footprints allowed)
		)
		(placement
			(enabled no)
			(sheetname "")
		)
		(fill yes
			(thermal_gap 0.5)
			(thermal_bridge_width 0.5)
			(island_removal_mode 0)
		)
		(polygon
			(pts
				(arc
					(start 278.439372 -348.58579)
					(mid 277.735792 -348.58579)
					(end 278.439372 -348.58579)
				)
			)
		)
	)
	(zone
		(layers "B.Cu" "In13.Cu" "In15.Cu")
		(hatch none 0.5)
		(connect_pads
			(clearance 0)
		)
		(min_thickness 0.25)
		(keepout
			(tracks not_allowed)
			(vias allowed)
			(pads allowed)
			(copperpour not_allowed)
			(footprints allowed)
		)
		(placement
			(enabled no)
			(sheetname "")
		)
		(fill yes
			(thermal_gap 0.5)
			(thermal_bridge_width 0.5)
			(island_removal_mode 0)
		)
		(polygon
			(pts
				(arc
					(start 43.689778 -398.890236)
					(mid 42.930318 -398.890236)
					(end 43.689778 -398.890236)
				)
			)
		)
	)
	(zone
		(layers "B.Cu" "In13.Cu" "In15.Cu")
		(hatch none 0.5)
		(connect_pads
			(clearance 0)
		)
		(min_thickness 0.25)
		(keepout
			(tracks not_allowed)
			(vias allowed)
			(pads allowed)
			(copperpour not_allowed)
			(footprints allowed)
		)
		(placement
			(enabled no)
			(sheetname "")
		)
		(fill yes
			(thermal_gap 0.5)
			(thermal_bridge_width 0.5)
			(island_removal_mode 0)
		)
		(polygon
			(pts
				(arc
					(start 400.676364 -277.849838)
					(mid 400.023584 -277.849838)
					(end 400.676364 -277.849838)
				)
			)
		)
	)
	(zone
		(layers "B.Cu" "In13.Cu" "In15.Cu")
		(hatch none 0.5)
		(connect_pads
			(clearance 0)
		)
		(min_thickness 0.25)
		(keepout
			(tracks not_allowed)
			(vias allowed)
			(pads allowed)
			(copperpour not_allowed)
			(footprints allowed)
		)
		(placement
			(enabled no)
			(sheetname "")
		)
		(fill yes
			(thermal_gap 0.5)
			(thermal_bridge_width 0.5)
			(island_removal_mode 0)
		)
		(polygon
			(pts
				(arc
					(start 159.428942 -354.732082)
					(mid 158.725362 -354.732082)
					(end 159.428942 -354.732082)
				)
			)
		)
	)
	(zone
		(layers "B.Cu" "In13.Cu" "In15.Cu")
		(hatch none 0.5)
		(connect_pads
			(clearance 0)
		)
		(min_thickness 0.25)
		(keepout
			(tracks not_allowed)
			(vias allowed)
			(pads allowed)
			(copperpour not_allowed)
			(footprints allowed)
		)
		(placement
			(enabled no)
			(sheetname "")
		)
		(fill yes
			(thermal_gap 0.5)
			(thermal_bridge_width 0.5)
			(island_removal_mode 0)
		)
		(polygon
			(pts
				(arc
					(start 164.399214 -30.05709)
					(mid 163.695634 -30.05709)
					(end 164.399214 -30.05709)
				)
			)
		)
	)
	(zone
		(layers "B.Cu" "In13.Cu" "In15.Cu")
		(hatch none 0.5)
		(connect_pads
			(clearance 0)
		)
		(min_thickness 0.25)
		(keepout
			(tracks not_allowed)
			(vias allowed)
			(pads allowed)
			(copperpour not_allowed)
			(footprints allowed)
		)
		(placement
			(enabled no)
			(sheetname "")
		)
		(fill yes
			(thermal_gap 0.5)
			(thermal_bridge_width 0.5)
			(island_removal_mode 0)
		)
		(polygon
			(pts
				(arc
					(start 164.399214 -33.657286)
					(mid 163.695634 -33.657286)
					(end 164.399214 -33.657286)
				)
			)
		)
	)
	(zone
		(layers "B.Cu" "In13.Cu" "In15.Cu")
		(hatch none 0.5)
		(connect_pads
			(clearance 0)
		)
		(min_thickness 0.25)
		(keepout
			(tracks not_allowed)
			(vias allowed)
			(pads allowed)
			(copperpour not_allowed)
			(footprints allowed)
		)
		(placement
			(enabled no)
			(sheetname "")
		)
		(fill yes
			(thermal_gap 0.5)
			(thermal_bridge_width 0.5)
			(island_removal_mode 0)
		)
		(polygon
			(pts
				(arc
					(start 393.957048 -31.850584)
					(mid 393.253468 -31.850584)
					(end 393.957048 -31.850584)
				)
			)
		)
	)
	(zone
		(layers "B.Cu" "In13.Cu" "In15.Cu")
		(hatch none 0.5)
		(connect_pads
			(clearance 0)
		)
		(min_thickness 0.25)
		(keepout
			(tracks not_allowed)
			(vias allowed)
			(pads allowed)
			(copperpour not_allowed)
			(footprints allowed)
		)
		(placement
			(enabled no)
			(sheetname "")
		)
		(fill yes
			(thermal_gap 0.5)
			(thermal_bridge_width 0.5)
			(island_removal_mode 0)
		)
		(polygon
			(pts
				(arc
					(start 164.676328 -278.799798)
					(mid 164.023548 -278.799798)
					(end 164.676328 -278.799798)
				)
			)
		)
	)
	(zone
		(layers "B.Cu" "In13.Cu" "In15.Cu")
		(hatch none 0.5)
		(connect_pads
			(clearance 0)
		)
		(min_thickness 0.25)
		(keepout
			(tracks not_allowed)
			(vias allowed)
			(pads allowed)
			(copperpour not_allowed)
			(footprints allowed)
		)
		(placement
			(enabled no)
			(sheetname "")
		)
		(fill yes
			(thermal_gap 0.5)
			(thermal_bridge_width 0.5)
			(island_removal_mode 0)
		)
		(polygon
			(pts
				(arc
					(start 193.627502 -342.439498)
					(mid 192.923922 -342.439498)
					(end 193.627502 -342.439498)
				)
			)
		)
	)
	(zone
		(layers "B.Cu" "In13.Cu" "In15.Cu")
		(hatch none 0.5)
		(connect_pads
			(clearance 0)
		)
		(min_thickness 0.25)
		(keepout
			(tracks not_allowed)
			(vias allowed)
			(pads allowed)
			(copperpour not_allowed)
			(footprints allowed)
		)
		(placement
			(enabled no)
			(sheetname "")
		)
		(fill yes
			(thermal_gap 0.5)
			(thermal_bridge_width 0.5)
			(island_removal_mode 0)
		)
		(polygon
			(pts
				(arc
					(start 298.869608 -372.890034)
					(mid 298.110148 -372.890034)
					(end 298.869608 -372.890034)
				)
			)
		)
	)
	(zone
		(layers "B.Cu" "In13.Cu" "In15.Cu")
		(hatch none 0.5)
		(connect_pads
			(clearance 0)
		)
		(min_thickness 0.25)
		(keepout
			(tracks not_allowed)
			(vias allowed)
			(pads allowed)
			(copperpour not_allowed)
			(footprints allowed)
		)
		(placement
			(enabled no)
			(sheetname "")
		)
		(fill yes
			(thermal_gap 0.5)
			(thermal_bridge_width 0.5)
			(island_removal_mode 0)
		)
		(polygon
			(pts
				(arc
					(start 406.376378 -278.799798)
					(mid 405.723598 -278.799798)
					(end 406.376378 -278.799798)
				)
			)
		)
	)
	(zone
		(layers "B.Cu" "In13.Cu" "In15.Cu")
		(hatch none 0.5)
		(connect_pads
			(clearance 0)
		)
		(min_thickness 0.25)
		(keepout
			(tracks not_allowed)
			(vias allowed)
			(pads allowed)
			(copperpour not_allowed)
			(footprints allowed)
		)
		(placement
			(enabled no)
			(sheetname "")
		)
		(fill yes
			(thermal_gap 0.5)
			(thermal_bridge_width 0.5)
			(island_removal_mode 0)
		)
		(polygon
			(pts
				(arc
					(start 35.229038 -351.611438)
					(mid 34.525458 -351.611438)
					(end 35.229038 -351.611438)
				)
			)
		)
	)
	(zone
		(layers "B.Cu" "In13.Cu" "In15.Cu")
		(hatch none 0.5)
		(connect_pads
			(clearance 0)
		)
		(min_thickness 0.25)
		(keepout
			(tracks not_allowed)
			(vias allowed)
			(pads allowed)
			(copperpour not_allowed)
			(footprints allowed)
		)
		(placement
			(enabled no)
			(sheetname "")
		)
		(fill yes
			(thermal_gap 0.5)
			(thermal_bridge_width 0.5)
			(island_removal_mode 0)
		)
		(polygon
			(pts
				(arc
					(start 135.757158 -31.850584)
					(mid 135.053578 -31.850584)
					(end 135.757158 -31.850584)
				)
			)
		)
	)
	(zone
		(layers "B.Cu" "In13.Cu" "In15.Cu")
		(hatch none 0.5)
		(connect_pads
			(clearance 0)
		)
		(min_thickness 0.25)
		(keepout
			(tracks not_allowed)
			(vias allowed)
			(pads allowed)
			(copperpour not_allowed)
			(footprints allowed)
		)
		(placement
			(enabled no)
			(sheetname "")
		)
		(fill yes
			(thermal_gap 0.5)
			(thermal_bridge_width 0.5)
			(island_removal_mode 0)
		)
		(polygon
			(pts
				(arc
					(start 181.191662 -354.732082)
					(mid 180.488082 -354.732082)
					(end 181.191662 -354.732082)
				)
			)
		)
	)
	(zone
		(layers "B.Cu" "In13.Cu" "In15.Cu")
		(hatch none 0.5)
		(connect_pads
			(clearance 0)
		)
		(min_thickness 0.25)
		(keepout
			(tracks not_allowed)
			(vias allowed)
			(pads allowed)
			(copperpour not_allowed)
			(footprints allowed)
		)
		(placement
			(enabled no)
			(sheetname "")
		)
		(fill yes
			(thermal_gap 0.5)
			(thermal_bridge_width 0.5)
			(island_removal_mode 0)
		)
		(polygon
			(pts
				(arc
					(start 159.428942 -357.75773)
					(mid 158.725362 -357.75773)
					(end 159.428942 -357.75773)
				)
			)
		)
	)
	(zone
		(layers "B.Cu" "In13.Cu" "In15.Cu")
		(hatch none 0.5)
		(connect_pads
			(clearance 0)
		)
		(min_thickness 0.25)
		(keepout
			(tracks not_allowed)
			(vias allowed)
			(pads allowed)
			(copperpour not_allowed)
			(footprints allowed)
		)
		(placement
			(enabled no)
			(sheetname "")
		)
		(fill yes
			(thermal_gap 0.5)
			(thermal_bridge_width 0.5)
			(island_removal_mode 0)
		)
		(polygon
			(pts
				(arc
					(start 153.2763 -314.899802)
					(mid 152.62352 -314.899802)
					(end 153.2763 -314.899802)
				)
			)
		)
	)
	(zone
		(layers "B.Cu" "In13.Cu" "In15.Cu")
		(hatch none 0.5)
		(connect_pads
			(clearance 0)
		)
		(min_thickness 0.25)
		(keepout
			(tracks not_allowed)
			(vias allowed)
			(pads allowed)
			(copperpour not_allowed)
			(footprints allowed)
		)
		(placement
			(enabled no)
			(sheetname "")
		)
		(fill yes
			(thermal_gap 0.5)
			(thermal_bridge_width 0.5)
			(island_removal_mode 0)
		)
		(polygon
			(pts
				(arc
					(start 158.976314 -303.499774)
					(mid 158.323534 -303.499774)
					(end 158.976314 -303.499774)
				)
			)
		)
	)
	(zone
		(layers "B.Cu" "In13.Cu" "In15.Cu")
		(hatch none 0.5)
		(connect_pads
			(clearance 0)
		)
		(min_thickness 0.25)
		(keepout
			(tracks not_allowed)
			(vias allowed)
			(pads allowed)
			(copperpour not_allowed)
			(footprints allowed)
		)
		(placement
			(enabled no)
			(sheetname "")
		)
		(fill yes
			(thermal_gap 0.5)
			(thermal_bridge_width 0.5)
			(island_removal_mode 0)
		)
		(polygon
			(pts
				(arc
					(start 294.469566 -398.890236)
					(mid 293.710106 -398.890236)
					(end 294.469566 -398.890236)
				)
			)
		)
	)
	(zone
		(layers "B.Cu" "In13.Cu" "In15.Cu")
		(hatch none 0.5)
		(connect_pads
			(clearance 0)
		)
		(min_thickness 0.25)
		(keepout
			(tracks not_allowed)
			(vias allowed)
			(pads allowed)
			(copperpour not_allowed)
			(footprints allowed)
		)
		(placement
			(enabled no)
			(sheetname "")
		)
		(fill yes
			(thermal_gap 0.5)
			(thermal_bridge_width 0.5)
			(island_removal_mode 0)
		)
		(polygon
			(pts
				(arc
					(start 48.528478 -351.611438)
					(mid 47.824898 -351.611438)
					(end 48.528478 -351.611438)
				)
			)
		)
	)
	(zone
		(layers "B.Cu" "In13.Cu" "In15.Cu")
		(hatch none 0.5)
		(connect_pads
			(clearance 0)
		)
		(min_thickness 0.25)
		(keepout
			(tracks not_allowed)
			(vias allowed)
			(pads allowed)
			(copperpour not_allowed)
			(footprints allowed)
		)
		(placement
			(enabled no)
			(sheetname "")
		)
		(fill yes
			(thermal_gap 0.5)
			(thermal_bridge_width 0.5)
			(island_removal_mode 0)
		)
		(polygon
			(pts
				(arc
					(start 290.27628 -277.849838)
					(mid 289.6235 -277.849838)
					(end 290.27628 -277.849838)
				)
			)
		)
	)
	(zone
		(layers "B.Cu" "In13.Cu" "In15.Cu")
		(hatch none 0.5)
		(connect_pads
			(clearance 0)
		)
		(min_thickness 0.25)
		(keepout
			(tracks not_allowed)
			(vias allowed)
			(pads allowed)
			(copperpour not_allowed)
			(footprints allowed)
		)
		(placement
			(enabled no)
			(sheetname "")
		)
		(fill yes
			(thermal_gap 0.5)
			(thermal_bridge_width 0.5)
			(island_removal_mode 0)
		)
		(polygon
			(pts
				(arc
					(start 303.856898 -28.250642)
					(mid 303.153318 -28.250642)
					(end 303.856898 -28.250642)
				)
			)
		)
	)
	(zone
		(layers "B.Cu" "In13.Cu" "In15.Cu")
		(hatch none 0.5)
		(connect_pads
			(clearance 0)
		)
		(min_thickness 0.25)
		(keepout
			(tracks not_allowed)
			(vias allowed)
			(pads allowed)
			(copperpour not_allowed)
			(footprints allowed)
		)
		(placement
			(enabled no)
			(sheetname "")
		)
		(fill yes
			(thermal_gap 0.5)
			(thermal_bridge_width 0.5)
			(island_removal_mode 0)
		)
		(polygon
			(pts
				(arc
					(start 52.376324 -277.849838)
					(mid 51.723544 -277.849838)
					(end 52.376324 -277.849838)
				)
			)
		)
	)
	(zone
		(layers "B.Cu" "In13.Cu" "In15.Cu")
		(hatch none 0.5)
		(connect_pads
			(clearance 0)
		)
		(min_thickness 0.25)
		(keepout
			(tracks not_allowed)
			(vias allowed)
			(pads allowed)
			(copperpour not_allowed)
			(footprints allowed)
		)
		(placement
			(enabled no)
			(sheetname "")
		)
		(fill yes
			(thermal_gap 0.5)
			(thermal_bridge_width 0.5)
			(island_removal_mode 0)
		)
		(polygon
			(pts
				(arc
					(start 296.669714 -370.489988)
					(mid 295.910254 -370.489988)
					(end 296.669714 -370.489988)
				)
			)
		)
	)
	(zone
		(layers "B.Cu" "In13.Cu" "In15.Cu")
		(hatch none 0.5)
		(connect_pads
			(clearance 0)
		)
		(min_thickness 0.25)
		(keepout
			(tracks not_allowed)
			(vias allowed)
			(pads allowed)
			(copperpour not_allowed)
			(footprints allowed)
		)
		(placement
			(enabled no)
			(sheetname "")
		)
		(fill yes
			(thermal_gap 0.5)
			(thermal_bridge_width 0.5)
			(island_removal_mode 0)
		)
		(polygon
			(pts
				(arc
					(start 441.600082 -342.439498)
					(mid 440.896502 -342.439498)
					(end 441.600082 -342.439498)
				)
			)
		)
	)
	(zone
		(layers "B.Cu" "In13.Cu" "In15.Cu")
		(hatch none 0.5)
		(connect_pads
			(clearance 0)
		)
		(min_thickness 0.25)
		(keepout
			(tracks not_allowed)
			(vias allowed)
			(pads allowed)
			(copperpour not_allowed)
			(footprints allowed)
		)
		(placement
			(enabled no)
			(sheetname "")
		)
		(fill yes
			(thermal_gap 0.5)
			(thermal_bridge_width 0.5)
			(island_removal_mode 0)
		)
		(polygon
			(pts
				(arc
					(start 277.85695 -28.250642)
					(mid 277.15337 -28.250642)
					(end 277.85695 -28.250642)
				)
			)
		)
	)
	(zone
		(layers "B.Cu" "In13.Cu" "In15.Cu")
		(hatch none 0.5)
		(connect_pads
			(clearance 0)
		)
		(min_thickness 0.25)
		(keepout
			(tracks not_allowed)
			(vias allowed)
			(pads allowed)
			(copperpour not_allowed)
			(footprints allowed)
		)
		(placement
			(enabled no)
			(sheetname "")
		)
		(fill yes
			(thermal_gap 0.5)
			(thermal_bridge_width 0.5)
			(island_removal_mode 0)
		)
		(polygon
			(pts
				(arc
					(start 175.126396 -279.749504)
					(mid 174.473616 -279.749504)
					(end 175.126396 -279.749504)
				)
			)
		)
	)
	(zone
		(layers "B.Cu" "In13.Cu" "In15.Cu")
		(hatch none 0.5)
		(connect_pads
			(clearance 0)
		)
		(min_thickness 0.25)
		(keepout
			(tracks not_allowed)
			(vias allowed)
			(pads allowed)
			(copperpour not_allowed)
			(footprints allowed)
		)
		(placement
			(enabled no)
			(sheetname "")
		)
		(fill yes
			(thermal_gap 0.5)
			(thermal_bridge_width 0.5)
			(island_removal_mode 0)
		)
		(polygon
			(pts
				(arc
					(start 45.72635 -279.749504)
					(mid 45.07357 -279.749504)
					(end 45.72635 -279.749504)
				)
			)
		)
	)
	(zone
		(layers "B.Cu" "In13.Cu" "In15.Cu")
		(hatch none 0.5)
		(connect_pads
			(clearance 0)
		)
		(min_thickness 0.25)
		(keepout
			(tracks not_allowed)
			(vias allowed)
			(pads allowed)
			(copperpour not_allowed)
			(footprints allowed)
		)
		(placement
			(enabled no)
			(sheetname "")
		)
		(fill yes
			(thermal_gap 0.5)
			(thermal_bridge_width 0.5)
			(island_removal_mode 0)
		)
		(polygon
			(pts
				(arc
					(start 283.793692 -351.611438)
					(mid 283.090112 -351.611438)
					(end 283.793692 -351.611438)
				)
			)
		)
	)
	(zone
		(layers "B.Cu" "In13.Cu" "In15.Cu")
		(hatch none 0.5)
		(connect_pads
			(clearance 0)
		)
		(min_thickness 0.25)
		(keepout
			(tracks not_allowed)
			(vias allowed)
			(pads allowed)
			(copperpour not_allowed)
			(footprints allowed)
		)
		(placement
			(enabled no)
			(sheetname "")
		)
		(fill yes
			(thermal_gap 0.5)
			(thermal_bridge_width 0.5)
			(island_removal_mode 0)
		)
		(polygon
			(pts
				(arc
					(start 294.469566 -397.59001)
					(mid 293.710106 -397.59001)
					(end 294.469566 -397.59001)
				)
			)
		)
	)
	(zone
		(layers "B.Cu" "In13.Cu" "In15.Cu")
		(hatch none 0.5)
		(connect_pads
			(clearance 0)
		)
		(min_thickness 0.25)
		(keepout
			(tracks not_allowed)
			(vias allowed)
			(pads allowed)
			(copperpour not_allowed)
			(footprints allowed)
		)
		(placement
			(enabled no)
			(sheetname "")
		)
		(fill yes
			(thermal_gap 0.5)
			(thermal_bridge_width 0.5)
			(island_removal_mode 0)
		)
		(polygon
			(pts
				(arc
					(start 159.926274 -304.449734)
					(mid 159.273494 -304.449734)
					(end 159.926274 -304.449734)
				)
			)
		)
	)
	(zone
		(layers "B.Cu" "In13.Cu" "In15.Cu")
		(hatch none 0.5)
		(connect_pads
			(clearance 0)
		)
		(min_thickness 0.25)
		(keepout
			(tracks not_allowed)
			(vias allowed)
			(pads allowed)
			(copperpour not_allowed)
			(footprints allowed)
		)
		(placement
			(enabled no)
			(sheetname "")
		)
		(fill yes
			(thermal_gap 0.5)
			(thermal_bridge_width 0.5)
			(island_removal_mode 0)
		)
		(polygon
			(pts
				(arc
					(start 280.776172 -277.849838)
					(mid 280.123392 -277.849838)
					(end 280.776172 -277.849838)
				)
			)
		)
	)
	(zone
		(layers "B.Cu" "In13.Cu" "In15.Cu")
		(hatch none 0.5)
		(connect_pads
			(clearance 0)
		)
		(min_thickness 0.25)
		(keepout
			(tracks not_allowed)
			(vias allowed)
			(pads allowed)
			(copperpour not_allowed)
			(footprints allowed)
		)
		(placement
			(enabled no)
			(sheetname "")
		)
		(fill yes
			(thermal_gap 0.5)
			(thermal_bridge_width 0.5)
			(island_removal_mode 0)
		)
		(polygon
			(pts
				(arc
					(start 279.826212 -279.749504)
					(mid 279.173432 -279.749504)
					(end 279.826212 -279.749504)
				)
			)
		)
	)
	(zone
		(layers "B.Cu" "In13.Cu" "In15.Cu")
		(hatch none 0.5)
		(connect_pads
			(clearance 0)
		)
		(min_thickness 0.25)
		(keepout
			(tracks not_allowed)
			(vias allowed)
			(pads allowed)
			(copperpour not_allowed)
			(footprints allowed)
		)
		(placement
			(enabled no)
			(sheetname "")
		)
		(fill yes
			(thermal_gap 0.5)
			(thermal_bridge_width 0.5)
			(island_removal_mode 0)
		)
		(polygon
			(pts
				(arc
					(start 422.599104 -30.92069)
					(mid 421.895524 -30.92069)
					(end 422.599104 -30.92069)
				)
			)
		)
	)
	(zone
		(layers "B.Cu" "In13.Cu" "In15.Cu")
		(hatch none 0.5)
		(connect_pads
			(clearance 0)
		)
		(min_thickness 0.25)
		(keepout
			(tracks not_allowed)
			(vias allowed)
			(pads allowed)
			(copperpour not_allowed)
			(footprints allowed)
		)
		(placement
			(enabled no)
			(sheetname "")
		)
		(fill yes
			(thermal_gap 0.5)
			(thermal_bridge_width 0.5)
			(island_removal_mode 0)
		)
		(polygon
			(pts
				(arc
					(start 298.869608 -397.59001)
					(mid 298.110148 -397.59001)
					(end 298.869608 -397.59001)
				)
			)
		)
	)
	(zone
		(layers "B.Cu" "In13.Cu" "In15.Cu")
		(hatch none 0.5)
		(connect_pads
			(clearance 0)
		)
		(min_thickness 0.25)
		(keepout
			(tracks not_allowed)
			(vias allowed)
			(pads allowed)
			(copperpour not_allowed)
			(footprints allowed)
		)
		(placement
			(enabled no)
			(sheetname "")
		)
		(fill yes
			(thermal_gap 0.5)
			(thermal_bridge_width 0.5)
			(island_removal_mode 0)
		)
		(polygon
			(pts
				(arc
					(start 171.326302 -280.699718)
					(mid 170.673522 -280.699718)
					(end 171.326302 -280.699718)
				)
			)
		)
	)
	(zone
		(layers "B.Cu" "In13.Cu" "In15.Cu")
		(hatch none 0.5)
		(connect_pads
			(clearance 0)
		)
		(min_thickness 0.25)
		(keepout
			(tracks not_allowed)
			(vias allowed)
			(pads allowed)
			(copperpour not_allowed)
			(footprints allowed)
		)
		(placement
			(enabled no)
			(sheetname "")
		)
		(fill yes
			(thermal_gap 0.5)
			(thermal_bridge_width 0.5)
			(island_removal_mode 0)
		)
		(polygon
			(pts
				(arc
					(start 160.292542 -354.732082)
					(mid 159.588962 -354.732082)
					(end 160.292542 -354.732082)
				)
			)
		)
	)
	(zone
		(layers "B.Cu" "In13.Cu" "In15.Cu")
		(hatch none 0.5)
		(connect_pads
			(clearance 0)
		)
		(min_thickness 0.25)
		(keepout
			(tracks not_allowed)
			(vias allowed)
			(pads allowed)
			(copperpour not_allowed)
			(footprints allowed)
		)
		(placement
			(enabled no)
			(sheetname "")
		)
		(fill yes
			(thermal_gap 0.5)
			(thermal_bridge_width 0.5)
			(island_removal_mode 0)
		)
		(polygon
			(pts
				(arc
					(start 48.08982 -405.390096)
					(mid 47.33036 -405.390096)
					(end 48.08982 -405.390096)
				)
			)
		)
	)
	(zone
		(layers "B.Cu" "In13.Cu" "In15.Cu")
		(hatch none 0.5)
		(connect_pads
			(clearance 0)
		)
		(min_thickness 0.25)
		(keepout
			(tracks not_allowed)
			(vias allowed)
			(pads allowed)
			(copperpour not_allowed)
			(footprints allowed)
		)
		(placement
			(enabled no)
			(sheetname "")
		)
		(fill yes
			(thermal_gap 0.5)
			(thermal_bridge_width 0.5)
			(island_removal_mode 0)
		)
		(polygon
			(pts
				(arc
					(start 385.476242 -312.049922)
					(mid 384.823462 -312.049922)
					(end 385.476242 -312.049922)
				)
			)
		)
	)
	(zone
		(layers "B.Cu" "In13.Cu" "In15.Cu")
		(hatch none 0.5)
		(connect_pads
			(clearance 0)
		)
		(min_thickness 0.25)
		(keepout
			(tracks not_allowed)
			(vias allowed)
			(pads allowed)
			(copperpour not_allowed)
			(footprints allowed)
		)
		(placement
			(enabled no)
			(sheetname "")
		)
		(fill yes
			(thermal_gap 0.5)
			(thermal_bridge_width 0.5)
			(island_removal_mode 0)
		)
		(polygon
			(pts
				(arc
					(start 293.120572 -342.439498)
					(mid 292.416992 -342.439498)
					(end 293.120572 -342.439498)
				)
			)
		)
	)
	(zone
		(layers "B.Cu" "In13.Cu" "In15.Cu")
		(hatch none 0.5)
		(connect_pads
			(clearance 0)
		)
		(min_thickness 0.25)
		(keepout
			(tracks not_allowed)
			(vias allowed)
			(pads allowed)
			(copperpour not_allowed)
			(footprints allowed)
		)
		(placement
			(enabled no)
			(sheetname "")
		)
		(fill yes
			(thermal_gap 0.5)
			(thermal_bridge_width 0.5)
			(island_removal_mode 0)
		)
		(polygon
			(pts
				(arc
					(start 286.902652 -354.732082)
					(mid 286.199072 -354.732082)
					(end 286.902652 -354.732082)
				)
			)
		)
	)
	(zone
		(layers "B.Cu" "In13.Cu" "In15.Cu")
		(hatch none 0.5)
		(connect_pads
			(clearance 0)
		)
		(min_thickness 0.25)
		(keepout
			(tracks not_allowed)
			(vias allowed)
			(pads allowed)
			(copperpour not_allowed)
			(footprints allowed)
		)
		(placement
			(enabled no)
			(sheetname "")
		)
		(fill yes
			(thermal_gap 0.5)
			(thermal_bridge_width 0.5)
			(island_removal_mode 0)
		)
		(polygon
			(pts
				(arc
					(start 188.273182 -345.465146)
					(mid 187.569602 -345.465146)
					(end 188.273182 -345.465146)
				)
			)
		)
	)
	(zone
		(layers "B.Cu" "In13.Cu" "In15.Cu")
		(hatch none 0.5)
		(connect_pads
			(clearance 0)
		)
		(min_thickness 0.25)
		(keepout
			(tracks not_allowed)
			(vias allowed)
			(pads allowed)
			(copperpour not_allowed)
			(footprints allowed)
		)
		(placement
			(enabled no)
			(sheetname "")
		)
		(fill yes
			(thermal_gap 0.5)
			(thermal_bridge_width 0.5)
			(island_removal_mode 0)
		)
		(polygon
			(pts
				(arc
					(start 175.689768 -376.790204)
					(mid 174.930308 -376.790204)
					(end 175.689768 -376.790204)
				)
			)
		)
	)
	(zone
		(layers "B.Cu" "In13.Cu" "In15.Cu")
		(hatch none 0.5)
		(connect_pads
			(clearance 0)
		)
		(min_thickness 0.25)
		(keepout
			(tracks not_allowed)
			(vias allowed)
			(pads allowed)
			(copperpour not_allowed)
			(footprints allowed)
		)
		(placement
			(enabled no)
			(sheetname "")
		)
		(fill yes
			(thermal_gap 0.5)
			(thermal_bridge_width 0.5)
			(island_removal_mode 0)
		)
		(polygon
			(pts
				(arc
					(start 174.973742 -342.439498)
					(mid 174.270162 -342.439498)
					(end 174.973742 -342.439498)
				)
			)
		)
	)
	(zone
		(layers "B.Cu" "In13.Cu" "In15.Cu")
		(hatch none 0.5)
		(connect_pads
			(clearance 0)
		)
		(min_thickness 0.25)
		(keepout
			(tracks not_allowed)
			(vias allowed)
			(pads allowed)
			(copperpour not_allowed)
			(footprints allowed)
		)
		(placement
			(enabled no)
			(sheetname "")
		)
		(fill yes
			(thermal_gap 0.5)
			(thermal_bridge_width 0.5)
			(island_removal_mode 0)
		)
		(polygon
			(pts
				(arc
					(start 370.599208 -30.05709)
					(mid 369.895628 -30.05709)
					(end 370.599208 -30.05709)
				)
			)
		)
	)
	(zone
		(layers "B.Cu" "In13.Cu" "In15.Cu")
		(hatch none 0.5)
		(connect_pads
			(clearance 0)
		)
		(min_thickness 0.25)
		(keepout
			(tracks not_allowed)
			(vias allowed)
			(pads allowed)
			(copperpour not_allowed)
			(footprints allowed)
		)
		(placement
			(enabled no)
			(sheetname "")
		)
		(fill yes
			(thermal_gap 0.5)
			(thermal_bridge_width 0.5)
			(island_removal_mode 0)
		)
		(polygon
			(pts
				(arc
					(start 58.076338 -278.799798)
					(mid 57.423558 -278.799798)
					(end 58.076338 -278.799798)
				)
			)
		)
	)
	(zone
		(layers "B.Cu" "In13.Cu" "In15.Cu")
		(hatch none 0.5)
		(connect_pads
			(clearance 0)
		)
		(min_thickness 0.25)
		(keepout
			(tracks not_allowed)
			(vias allowed)
			(pads allowed)
			(copperpour not_allowed)
			(footprints allowed)
		)
		(placement
			(enabled no)
			(sheetname "")
		)
		(fill yes
			(thermal_gap 0.5)
			(thermal_bridge_width 0.5)
			(island_removal_mode 0)
		)
		(polygon
			(pts
				(arc
					(start 422.599104 -34.520886)
					(mid 421.895524 -34.520886)
					(end 422.599104 -34.520886)
				)
			)
		)
	)
	(zone
		(layers "B.Cu" "In13.Cu" "In15.Cu")
		(hatch none 0.5)
		(connect_pads
			(clearance 0)
		)
		(min_thickness 0.25)
		(keepout
			(tracks not_allowed)
			(vias allowed)
			(pads allowed)
			(copperpour not_allowed)
			(footprints allowed)
		)
		(placement
			(enabled no)
			(sheetname "")
		)
		(fill yes
			(thermal_gap 0.5)
			(thermal_bridge_width 0.5)
			(island_removal_mode 0)
		)
		(polygon
			(pts
				(arc
					(start 284.576266 -278.799798)
					(mid 283.923486 -278.799798)
					(end 284.576266 -278.799798)
				)
			)
		)
	)
	(zone
		(layers "B.Cu" "In13.Cu" "In15.Cu")
		(hatch none 0.5)
		(connect_pads
			(clearance 0)
		)
		(min_thickness 0.25)
		(keepout
			(tracks not_allowed)
			(vias allowed)
			(pads allowed)
			(copperpour not_allowed)
			(footprints allowed)
		)
		(placement
			(enabled no)
			(sheetname "")
		)
		(fill yes
			(thermal_gap 0.5)
			(thermal_bridge_width 0.5)
			(island_removal_mode 0)
		)
		(polygon
			(pts
				(arc
					(start 430.869598 -376.790204)
					(mid 430.110138 -376.790204)
					(end 430.869598 -376.790204)
				)
			)
		)
	)
	(zone
		(layers "B.Cu" "In13.Cu" "In15.Cu")
		(hatch none 0.5)
		(connect_pads
			(clearance 0)
		)
		(min_thickness 0.25)
		(keepout
			(tracks not_allowed)
			(vias allowed)
			(pads allowed)
			(copperpour not_allowed)
			(footprints allowed)
		)
		(placement
			(enabled no)
			(sheetname "")
		)
		(fill yes
			(thermal_gap 0.5)
			(thermal_bridge_width 0.5)
			(island_removal_mode 0)
		)
		(polygon
			(pts
				(arc
					(start 398.77619 -277.849838)
					(mid 398.12341 -277.849838)
					(end 398.77619 -277.849838)
				)
			)
		)
	)
	(zone
		(layers "B.Cu" "In13.Cu" "In15.Cu")
		(hatch none 0.5)
		(connect_pads
			(clearance 0)
		)
		(min_thickness 0.25)
		(keepout
			(tracks not_allowed)
			(vias allowed)
			(pads allowed)
			(copperpour not_allowed)
			(footprints allowed)
		)
		(placement
			(enabled no)
			(sheetname "")
		)
		(fill yes
			(thermal_gap 0.5)
			(thermal_bridge_width 0.5)
			(island_removal_mode 0)
		)
		(polygon
			(pts
				(arc
					(start 303.26965 -372.890034)
					(mid 302.51019 -372.890034)
					(end 303.26965 -372.890034)
				)
			)
		)
	)
	(zone
		(layers "B.Cu" "In13.Cu" "In15.Cu")
		(hatch none 0.5)
		(connect_pads
			(clearance 0)
		)
		(min_thickness 0.25)
		(keepout
			(tracks not_allowed)
			(vias allowed)
			(pads allowed)
			(copperpour not_allowed)
			(footprints allowed)
		)
		(placement
			(enabled no)
			(sheetname "")
		)
		(fill yes
			(thermal_gap 0.5)
			(thermal_bridge_width 0.5)
			(island_removal_mode 0)
		)
		(polygon
			(pts
				(arc
					(start 395.92631 -280.699718)
					(mid 395.27353 -280.699718)
					(end 395.92631 -280.699718)
				)
			)
		)
	)
	(zone
		(layers "B.Cu" "In13.Cu" "In15.Cu")
		(hatch none 0.5)
		(connect_pads
			(clearance 0)
		)
		(min_thickness 0.25)
		(keepout
			(tracks not_allowed)
			(vias allowed)
			(pads allowed)
			(copperpour not_allowed)
			(footprints allowed)
		)
		(placement
			(enabled no)
			(sheetname "")
		)
		(fill yes
			(thermal_gap 0.5)
			(thermal_bridge_width 0.5)
			(island_removal_mode 0)
		)
		(polygon
			(pts
				(arc
					(start 156.126434 -312.049922)
					(mid 155.473654 -312.049922)
					(end 156.126434 -312.049922)
				)
			)
		)
	)
	(zone
		(layers "B.Cu" "In13.Cu" "In15.Cu")
		(hatch none 0.5)
		(connect_pads
			(clearance 0)
		)
		(min_thickness 0.25)
		(keepout
			(tracks not_allowed)
			(vias allowed)
			(pads allowed)
			(copperpour not_allowed)
			(footprints allowed)
		)
		(placement
			(enabled no)
			(sheetname "")
		)
		(fill yes
			(thermal_gap 0.5)
			(thermal_bridge_width 0.5)
			(island_removal_mode 0)
		)
		(polygon
			(pts
				(arc
					(start 284.657292 -348.58579)
					(mid 283.953712 -348.58579)
					(end 284.657292 -348.58579)
				)
			)
		)
	)
	(zone
		(layers "B.Cu" "In13.Cu" "In15.Cu")
		(hatch none 0.5)
		(connect_pads
			(clearance 0)
		)
		(min_thickness 0.25)
		(keepout
			(tracks not_allowed)
			(vias allowed)
			(pads allowed)
			(copperpour not_allowed)
			(footprints allowed)
		)
		(placement
			(enabled no)
			(sheetname "")
		)
		(fill yes
			(thermal_gap 0.5)
			(thermal_bridge_width 0.5)
			(island_removal_mode 0)
		)
		(polygon
			(pts
				(arc
					(start 47.62627 -280.699718)
					(mid 46.97349 -280.699718)
					(end 47.62627 -280.699718)
				)
			)
		)
	)
	(zone
		(layers "B.Cu" "In13.Cu" "In15.Cu")
		(hatch none 0.5)
		(connect_pads
			(clearance 0)
		)
		(min_thickness 0.25)
		(keepout
			(tracks not_allowed)
			(vias allowed)
			(pads allowed)
			(copperpour not_allowed)
			(footprints allowed)
		)
		(placement
			(enabled no)
			(sheetname "")
		)
		(fill yes
			(thermal_gap 0.5)
			(thermal_bridge_width 0.5)
			(island_removal_mode 0)
		)
		(polygon
			(pts
				(arc
					(start 19.65706 -28.250642)
					(mid 18.95348 -28.250642)
					(end 19.65706 -28.250642)
				)
			)
		)
	)
	(zone
		(layers "B.Cu" "In13.Cu" "In15.Cu")
		(hatch none 0.5)
		(connect_pads
			(clearance 0)
		)
		(min_thickness 0.25)
		(keepout
			(tracks not_allowed)
			(vias allowed)
			(pads allowed)
			(copperpour not_allowed)
			(footprints allowed)
		)
		(placement
			(enabled no)
			(sheetname "")
		)
		(fill yes
			(thermal_gap 0.5)
			(thermal_bridge_width 0.5)
			(island_removal_mode 0)
		)
		(polygon
			(pts
				(arc
					(start 178.082702 -351.611438)
					(mid 177.379122 -351.611438)
					(end 178.082702 -351.611438)
				)
			)
		)
	)
	(zone
		(layers "B.Cu" "In13.Cu" "In15.Cu")
		(hatch none 0.5)
		(connect_pads
			(clearance 0)
		)
		(min_thickness 0.25)
		(keepout
			(tracks not_allowed)
			(vias allowed)
			(pads allowed)
			(copperpour not_allowed)
			(footprints allowed)
		)
		(placement
			(enabled no)
			(sheetname "")
		)
		(fill yes
			(thermal_gap 0.5)
			(thermal_bridge_width 0.5)
			(island_removal_mode 0)
		)
		(polygon
			(pts
				(arc
					(start 181.191662 -345.465146)
					(mid 180.488082 -345.465146)
					(end 181.191662 -345.465146)
				)
			)
		)
	)
	(zone
		(layers "B.Cu" "In13.Cu" "In15.Cu")
		(hatch none 0.5)
		(connect_pads
			(clearance 0)
		)
		(min_thickness 0.25)
		(keepout
			(tracks not_allowed)
			(vias allowed)
			(pads allowed)
			(copperpour not_allowed)
			(footprints allowed)
		)
		(placement
			(enabled no)
			(sheetname "")
		)
		(fill yes
			(thermal_gap 0.5)
			(thermal_bridge_width 0.5)
			(island_removal_mode 0)
		)
		(polygon
			(pts
				(arc
					(start 283.626306 -280.699718)
					(mid 282.973526 -280.699718)
					(end 283.626306 -280.699718)
				)
			)
		)
	)
	(zone
		(layers "B.Cu" "In13.Cu" "In15.Cu")
		(hatch none 0.5)
		(connect_pads
			(clearance 0)
		)
		(min_thickness 0.25)
		(keepout
			(tracks not_allowed)
			(vias allowed)
			(pads allowed)
			(copperpour not_allowed)
			(footprints allowed)
		)
		(placement
			(enabled no)
			(sheetname "")
		)
		(fill yes
			(thermal_gap 0.5)
			(thermal_bridge_width 0.5)
			(island_removal_mode 0)
		)
		(polygon
			(pts
				(arc
					(start 280.499058 -30.05709)
					(mid 279.795478 -30.05709)
					(end 280.499058 -30.05709)
				)
			)
		)
	)
	(zone
		(layers "B.Cu" "In13.Cu" "In15.Cu")
		(hatch none 0.5)
		(connect_pads
			(clearance 0)
		)
		(min_thickness 0.25)
		(keepout
			(tracks not_allowed)
			(vias allowed)
			(pads allowed)
			(copperpour not_allowed)
			(footprints allowed)
		)
		(placement
			(enabled no)
			(sheetname "")
		)
		(fill yes
			(thermal_gap 0.5)
			(thermal_bridge_width 0.5)
			(island_removal_mode 0)
		)
		(polygon
			(pts
				(arc
					(start 25.902158 -354.732082)
					(mid 25.198578 -354.732082)
					(end 25.902158 -354.732082)
				)
			)
		)
	)
	(zone
		(layers "B.Cu" "In13.Cu" "In15.Cu")
		(hatch none 0.5)
		(connect_pads
			(clearance 0)
		)
		(min_thickness 0.25)
		(keepout
			(tracks not_allowed)
			(vias allowed)
			(pads allowed)
			(copperpour not_allowed)
			(footprints allowed)
		)
		(placement
			(enabled no)
			(sheetname "")
		)
		(fill yes
			(thermal_gap 0.5)
			(thermal_bridge_width 0.5)
			(island_removal_mode 0)
		)
		(polygon
			(pts
				(arc
					(start 283.793692 -348.58579)
					(mid 283.090112 -348.58579)
					(end 283.793692 -348.58579)
				)
			)
		)
	)
	(zone
		(layers "B.Cu" "In13.Cu" "In15.Cu")
		(hatch none 0.5)
		(connect_pads
			(clearance 0)
		)
		(min_thickness 0.25)
		(keepout
			(tracks not_allowed)
			(vias allowed)
			(pads allowed)
			(copperpour not_allowed)
			(footprints allowed)
		)
		(placement
			(enabled no)
			(sheetname "")
		)
		(fill yes
			(thermal_gap 0.5)
			(thermal_bridge_width 0.5)
			(island_removal_mode 0)
		)
		(polygon
			(pts
				(arc
					(start 41.48963 -371.790214)
					(mid 40.73017 -371.790214)
					(end 41.48963 -371.790214)
				)
			)
		)
	)
	(zone
		(layers "B.Cu" "In13.Cu" "In15.Cu")
		(hatch none 0.5)
		(connect_pads
			(clearance 0)
		)
		(min_thickness 0.25)
		(keepout
			(tracks not_allowed)
			(vias allowed)
			(pads allowed)
			(copperpour not_allowed)
			(footprints allowed)
		)
		(placement
			(enabled no)
			(sheetname "")
		)
		(fill yes
			(thermal_gap 0.5)
			(thermal_bridge_width 0.5)
			(island_removal_mode 0)
		)
		(polygon
			(pts
				(arc
					(start 393.076176 -302.549814)
					(mid 392.423396 -302.549814)
					(end 393.076176 -302.549814)
				)
			)
		)
	)
	(zone
		(layers "B.Cu" "In13.Cu" "In15.Cu")
		(hatch none 0.5)
		(connect_pads
			(clearance 0)
		)
		(min_thickness 0.25)
		(keepout
			(tracks not_allowed)
			(vias allowed)
			(pads allowed)
			(copperpour not_allowed)
			(footprints allowed)
		)
		(placement
			(enabled no)
			(sheetname "")
		)
		(fill yes
			(thermal_gap 0.5)
			(thermal_bridge_width 0.5)
			(island_removal_mode 0)
		)
		(polygon
			(pts
				(arc
					(start 367.9571 -29.114242)
					(mid 367.25352 -29.114242)
					(end 367.9571 -29.114242)
				)
			)
		)
	)
	(zone
		(layers "B.Cu" "In13.Cu" "In15.Cu")
		(hatch none 0.5)
		(connect_pads
			(clearance 0)
		)
		(min_thickness 0.25)
		(keepout
			(tracks not_allowed)
			(vias allowed)
			(pads allowed)
			(copperpour not_allowed)
			(footprints allowed)
		)
		(placement
			(enabled no)
			(sheetname "")
		)
		(fill yes
			(thermal_gap 0.5)
			(thermal_bridge_width 0.5)
			(island_removal_mode 0)
		)
		(polygon
			(pts
				(arc
					(start 297.093132 -348.58579)
					(mid 296.389552 -348.58579)
					(end 297.093132 -348.58579)
				)
			)
		)
	)
	(zone
		(layers "B.Cu" "In13.Cu" "In15.Cu")
		(hatch none 0.5)
		(connect_pads
			(clearance 0)
		)
		(min_thickness 0.25)
		(keepout
			(tracks not_allowed)
			(vias allowed)
			(pads allowed)
			(copperpour not_allowed)
			(footprints allowed)
		)
		(placement
			(enabled no)
			(sheetname "")
		)
		(fill yes
			(thermal_gap 0.5)
			(thermal_bridge_width 0.5)
			(island_removal_mode 0)
		)
		(polygon
			(pts
				(arc
					(start 25.902158 -345.465146)
					(mid 25.198578 -345.465146)
					(end 25.902158 -345.465146)
				)
			)
		)
	)
	(zone
		(layers "B.Cu" "In13.Cu" "In15.Cu")
		(hatch none 0.5)
		(connect_pads
			(clearance 0)
		)
		(min_thickness 0.25)
		(keepout
			(tracks not_allowed)
			(vias allowed)
			(pads allowed)
			(copperpour not_allowed)
			(footprints allowed)
		)
		(placement
			(enabled no)
			(sheetname "")
		)
		(fill yes
			(thermal_gap 0.5)
			(thermal_bridge_width 0.5)
			(island_removal_mode 0)
		)
		(polygon
			(pts
				(arc
					(start 191.382142 -348.58579)
					(mid 190.678562 -348.58579)
					(end 191.382142 -348.58579)
				)
			)
		)
	)
	(zone
		(layers "B.Cu" "In13.Cu" "In15.Cu")
		(hatch none 0.5)
		(connect_pads
			(clearance 0)
		)
		(min_thickness 0.25)
		(keepout
			(tracks not_allowed)
			(vias allowed)
			(pads allowed)
			(copperpour not_allowed)
			(footprints allowed)
		)
		(placement
			(enabled no)
			(sheetname "")
		)
		(fill yes
			(thermal_gap 0.5)
			(thermal_bridge_width 0.5)
			(island_removal_mode 0)
		)
		(polygon
			(pts
				(arc
					(start 82.776314 -312.049922)
					(mid 82.123534 -312.049922)
					(end 82.776314 -312.049922)
				)
			)
		)
	)
	(zone
		(layers "B.Cu" "In13.Cu" "In15.Cu")
		(hatch none 0.5)
		(connect_pads
			(clearance 0)
		)
		(min_thickness 0.25)
		(keepout
			(tracks not_allowed)
			(vias allowed)
			(pads allowed)
			(copperpour not_allowed)
			(footprints allowed)
		)
		(placement
			(enabled no)
			(sheetname "")
		)
		(fill yes
			(thermal_gap 0.5)
			(thermal_bridge_width 0.5)
			(island_removal_mode 0)
		)
		(polygon
			(pts
				(arc
					(start 296.229532 -351.611438)
					(mid 295.525952 -351.611438)
					(end 296.229532 -351.611438)
				)
			)
		)
	)
	(zone
		(layers "B.Cu" "In13.Cu" "In15.Cu")
		(hatch none 0.5)
		(connect_pads
			(clearance 0)
		)
		(min_thickness 0.25)
		(keepout
			(tracks not_allowed)
			(vias allowed)
			(pads allowed)
			(copperpour not_allowed)
			(footprints allowed)
		)
		(placement
			(enabled no)
			(sheetname "")
		)
		(fill yes
			(thermal_gap 0.5)
			(thermal_bridge_width 0.5)
			(island_removal_mode 0)
		)
		(polygon
			(pts
				(arc
					(start 97.656904 -32.714184)
					(mid 96.953324 -32.714184)
					(end 97.656904 -32.714184)
				)
			)
		)
	)
	(zone
		(layers "B.Cu" "In13.Cu" "In15.Cu")
		(hatch none 0.5)
		(connect_pads
			(clearance 0)
		)
		(min_thickness 0.25)
		(keepout
			(tracks not_allowed)
			(vias allowed)
			(pads allowed)
			(copperpour not_allowed)
			(footprints allowed)
		)
		(placement
			(enabled no)
			(sheetname "")
		)
		(fill yes
			(thermal_gap 0.5)
			(thermal_bridge_width 0.5)
			(island_removal_mode 0)
		)
		(polygon
			(pts
				(arc
					(start 26.765758 -357.75773)
					(mid 26.062178 -357.75773)
					(end 26.765758 -357.75773)
				)
			)
		)
	)
	(zone
		(layers "B.Cu" "In13.Cu" "In15.Cu")
		(hatch none 0.5)
		(connect_pads
			(clearance 0)
		)
		(min_thickness 0.25)
		(keepout
			(tracks not_allowed)
			(vias allowed)
			(pads allowed)
			(copperpour not_allowed)
			(footprints allowed)
		)
		(placement
			(enabled no)
			(sheetname "")
		)
		(fill yes
			(thermal_gap 0.5)
			(thermal_bridge_width 0.5)
			(island_removal_mode 0)
		)
		(polygon
			(pts
				(arc
					(start 162.489642 -376.790204)
					(mid 161.730182 -376.790204)
					(end 162.489642 -376.790204)
				)
			)
		)
	)
	(zone
		(layers "B.Cu" "In13.Cu" "In15.Cu")
		(hatch none 0.5)
		(connect_pads
			(clearance 0)
		)
		(min_thickness 0.25)
		(keepout
			(tracks not_allowed)
			(vias allowed)
			(pads allowed)
			(copperpour not_allowed)
			(footprints allowed)
		)
		(placement
			(enabled no)
			(sheetname "")
		)
		(fill yes
			(thermal_gap 0.5)
			(thermal_bridge_width 0.5)
			(island_removal_mode 0)
		)
		(polygon
			(pts
				(arc
					(start 429.164242 -342.439498)
					(mid 428.460662 -342.439498)
					(end 429.164242 -342.439498)
				)
			)
		)
	)
	(zone
		(layers "B.Cu" "In13.Cu" "In15.Cu")
		(hatch none 0.5)
		(connect_pads
			(clearance 0)
		)
		(min_thickness 0.25)
		(keepout
			(tracks not_allowed)
			(vias allowed)
			(pads allowed)
			(copperpour not_allowed)
			(footprints allowed)
		)
		(placement
			(enabled no)
			(sheetname "")
		)
		(fill yes
			(thermal_gap 0.5)
			(thermal_bridge_width 0.5)
			(island_removal_mode 0)
		)
		(polygon
			(pts
				(arc
					(start 158.026354 -312.049922)
					(mid 157.373574 -312.049922)
					(end 158.026354 -312.049922)
				)
			)
		)
	)
	(zone
		(layers "B.Cu" "In13.Cu" "In15.Cu")
		(hatch none 0.5)
		(connect_pads
			(clearance 0)
		)
		(min_thickness 0.25)
		(keepout
			(tracks not_allowed)
			(vias allowed)
			(pads allowed)
			(copperpour not_allowed)
			(footprints allowed)
		)
		(placement
			(enabled no)
			(sheetname "")
		)
		(fill yes
			(thermal_gap 0.5)
			(thermal_bridge_width 0.5)
			(island_removal_mode 0)
		)
		(polygon
			(pts
				(arc
					(start 391.176256 -313.949842)
					(mid 390.523476 -313.949842)
					(end 391.176256 -313.949842)
				)
			)
		)
	)
	(zone
		(layers "B.Cu" "In13.Cu" "In15.Cu")
		(hatch none 0.5)
		(connect_pads
			(clearance 0)
		)
		(min_thickness 0.25)
		(keepout
			(tracks not_allowed)
			(vias allowed)
			(pads allowed)
			(copperpour not_allowed)
			(footprints allowed)
		)
		(placement
			(enabled no)
			(sheetname "")
		)
		(fill yes
			(thermal_gap 0.5)
			(thermal_bridge_width 0.5)
			(island_removal_mode 0)
		)
		(polygon
			(pts
				(arc
					(start 441.600082 -345.465146)
					(mid 440.896502 -345.465146)
					(end 441.600082 -345.465146)
				)
			)
		)
	)
	(zone
		(layers "B.Cu" "In13.Cu" "In15.Cu")
		(hatch none 0.5)
		(connect_pads
			(clearance 0)
		)
		(min_thickness 0.25)
		(keepout
			(tracks not_allowed)
			(vias allowed)
			(pads allowed)
			(copperpour not_allowed)
			(footprints allowed)
		)
		(placement
			(enabled no)
			(sheetname "")
		)
		(fill yes
			(thermal_gap 0.5)
			(thermal_bridge_width 0.5)
			(island_removal_mode 0)
		)
		(polygon
			(pts
				(arc
					(start 280.499058 -30.92069)
					(mid 279.795478 -30.92069)
					(end 280.499058 -30.92069)
				)
			)
		)
	)
	(zone
		(layers "B.Cu" "In13.Cu" "In15.Cu")
		(hatch none 0.5)
		(connect_pads
			(clearance 0)
		)
		(min_thickness 0.25)
		(keepout
			(tracks not_allowed)
			(vias allowed)
			(pads allowed)
			(copperpour not_allowed)
			(footprints allowed)
		)
		(placement
			(enabled no)
			(sheetname "")
		)
		(fill yes
			(thermal_gap 0.5)
			(thermal_bridge_width 0.5)
			(island_removal_mode 0)
		)
		(polygon
			(pts
				(arc
					(start 274.466812 -357.75773)
					(mid 273.763232 -357.75773)
					(end 274.466812 -357.75773)
				)
			)
		)
	)
	(zone
		(layers "B.Cu" "In13.Cu" "In15.Cu")
		(hatch none 0.5)
		(connect_pads
			(clearance 0)
		)
		(min_thickness 0.25)
		(keepout
			(tracks not_allowed)
			(vias allowed)
			(pads allowed)
			(copperpour not_allowed)
			(footprints allowed)
		)
		(placement
			(enabled no)
			(sheetname "")
		)
		(fill yes
			(thermal_gap 0.5)
			(thermal_bridge_width 0.5)
			(island_removal_mode 0)
		)
		(polygon
			(pts
				(arc
					(start 80.87614 -312.999882)
					(mid 80.22336 -312.999882)
					(end 80.87614 -312.999882)
				)
			)
		)
	)
	(zone
		(layers "B.Cu" "In13.Cu" "In15.Cu")
		(hatch none 0.5)
		(connect_pads
			(clearance 0)
		)
		(min_thickness 0.25)
		(keepout
			(tracks not_allowed)
			(vias allowed)
			(pads allowed)
			(copperpour not_allowed)
			(footprints allowed)
		)
		(placement
			(enabled no)
			(sheetname "")
		)
		(fill yes
			(thermal_gap 0.5)
			(thermal_bridge_width 0.5)
			(island_removal_mode 0)
		)
		(polygon
			(pts
				(arc
					(start 182.055262 -345.465146)
					(mid 181.351682 -345.465146)
					(end 182.055262 -345.465146)
				)
			)
		)
	)
	(zone
		(layers "B.Cu" "In13.Cu" "In15.Cu")
		(hatch none 0.5)
		(connect_pads
			(clearance 0)
		)
		(min_thickness 0.25)
		(keepout
			(tracks not_allowed)
			(vias allowed)
			(pads allowed)
			(copperpour not_allowed)
			(footprints allowed)
		)
		(placement
			(enabled no)
			(sheetname "")
		)
		(fill yes
			(thermal_gap 0.5)
			(thermal_bridge_width 0.5)
			(island_removal_mode 0)
		)
		(polygon
			(pts
				(arc
					(start 41.48963 -397.790162)
					(mid 40.73017 -397.790162)
					(end 41.48963 -397.790162)
				)
			)
		)
	)
	(zone
		(layers "B.Cu" "In13.Cu" "In15.Cu")
		(hatch none 0.5)
		(connect_pads
			(clearance 0)
		)
		(min_thickness 0.25)
		(keepout
			(tracks not_allowed)
			(vias allowed)
			(pads allowed)
			(copperpour not_allowed)
			(footprints allowed)
		)
		(placement
			(enabled no)
			(sheetname "")
		)
		(fill yes
			(thermal_gap 0.5)
			(thermal_bridge_width 0.5)
			(island_removal_mode 0)
		)
		(polygon
			(pts
				(arc
					(start 286.476186 -277.849838)
					(mid 285.823406 -277.849838)
					(end 286.476186 -277.849838)
				)
			)
		)
	)
	(zone
		(layers "B.Cu" "In13.Cu" "In15.Cu")
		(hatch none 0.5)
		(connect_pads
			(clearance 0)
		)
		(min_thickness 0.25)
		(keepout
			(tracks not_allowed)
			(vias allowed)
			(pads allowed)
			(copperpour not_allowed)
			(footprints allowed)
		)
		(placement
			(enabled no)
			(sheetname "")
		)
		(fill yes
			(thermal_gap 0.5)
			(thermal_bridge_width 0.5)
			(island_removal_mode 0)
		)
		(polygon
			(pts
				(arc
					(start 286.902652 -342.439498)
					(mid 286.199072 -342.439498)
					(end 286.902652 -342.439498)
				)
			)
		)
	)
	(zone
		(layers "B.Cu" "In13.Cu" "In15.Cu")
		(hatch none 0.5)
		(connect_pads
			(clearance 0)
		)
		(min_thickness 0.25)
		(keepout
			(tracks not_allowed)
			(vias allowed)
			(pads allowed)
			(copperpour not_allowed)
			(footprints allowed)
		)
		(placement
			(enabled no)
			(sheetname "")
		)
		(fill yes
			(thermal_gap 0.5)
			(thermal_bridge_width 0.5)
			(island_removal_mode 0)
		)
		(polygon
			(pts
				(arc
					(start 34.889694 -398.890236)
					(mid 34.130234 -398.890236)
					(end 34.889694 -398.890236)
				)
			)
		)
	)
	(zone
		(layers "B.Cu" "In13.Cu" "In15.Cu")
		(hatch none 0.5)
		(connect_pads
			(clearance 0)
		)
		(min_thickness 0.25)
		(keepout
			(tracks not_allowed)
			(vias allowed)
			(pads allowed)
			(copperpour not_allowed)
			(footprints allowed)
		)
		(placement
			(enabled no)
			(sheetname "")
		)
		(fill yes
			(thermal_gap 0.5)
			(thermal_bridge_width 0.5)
			(island_removal_mode 0)
		)
		(polygon
			(pts
				(arc
					(start 78.02626 -309.199788)
					(mid 77.37348 -309.199788)
					(end 78.02626 -309.199788)
				)
			)
		)
	)
	(zone
		(layers "B.Cu" "In13.Cu" "In15.Cu")
		(hatch none 0.5)
		(connect_pads
			(clearance 0)
		)
		(min_thickness 0.25)
		(keepout
			(tracks not_allowed)
			(vias allowed)
			(pads allowed)
			(copperpour not_allowed)
			(footprints allowed)
		)
		(placement
			(enabled no)
			(sheetname "")
		)
		(fill yes
			(thermal_gap 0.5)
			(thermal_bridge_width 0.5)
			(island_removal_mode 0)
		)
		(polygon
			(pts
				(arc
					(start 440.736482 -357.75773)
					(mid 440.032902 -357.75773)
					(end 440.736482 -357.75773)
				)
			)
		)
	)
	(zone
		(layers "B.Cu" "In13.Cu" "In15.Cu")
		(hatch none 0.5)
		(connect_pads
			(clearance 0)
		)
		(min_thickness 0.25)
		(keepout
			(tracks not_allowed)
			(vias allowed)
			(pads allowed)
			(copperpour not_allowed)
			(footprints allowed)
		)
		(placement
			(enabled no)
			(sheetname "")
		)
		(fill yes
			(thermal_gap 0.5)
			(thermal_bridge_width 0.5)
			(island_removal_mode 0)
		)
		(polygon
			(pts
				(arc
					(start 39.289736 -397.59001)
					(mid 38.530276 -397.59001)
					(end 39.289736 -397.59001)
				)
			)
		)
	)
	(zone
		(layers "B.Cu" "In13.Cu" "In15.Cu")
		(hatch none 0.5)
		(connect_pads
			(clearance 0)
		)
		(min_thickness 0.25)
		(keepout
			(tracks not_allowed)
			(vias allowed)
			(pads allowed)
			(copperpour not_allowed)
			(footprints allowed)
		)
		(placement
			(enabled no)
			(sheetname "")
		)
		(fill yes
			(thermal_gap 0.5)
			(thermal_bridge_width 0.5)
			(island_removal_mode 0)
		)
		(polygon
			(pts
				(arc
					(start 159.926274 -308.249828)
					(mid 159.273494 -308.249828)
					(end 159.926274 -308.249828)
				)
			)
		)
	)
	(zone
		(layers "B.Cu" "In13.Cu" "In15.Cu")
		(hatch none 0.5)
		(connect_pads
			(clearance 0)
		)
		(min_thickness 0.25)
		(keepout
			(tracks not_allowed)
			(vias allowed)
			(pads allowed)
			(copperpour not_allowed)
			(footprints allowed)
		)
		(placement
			(enabled no)
			(sheetname "")
		)
		(fill yes
			(thermal_gap 0.5)
			(thermal_bridge_width 0.5)
			(island_removal_mode 0)
		)
		(polygon
			(pts
				(arc
					(start 276.976078 -278.799798)
					(mid 276.323298 -278.799798)
					(end 276.976078 -278.799798)
				)
			)
		)
	)
	(zone
		(layers "B.Cu" "In13.Cu" "In15.Cu")
		(hatch none 0.5)
		(connect_pads
			(clearance 0)
		)
		(min_thickness 0.25)
		(keepout
			(tracks not_allowed)
			(vias allowed)
			(pads allowed)
			(copperpour not_allowed)
			(footprints allowed)
		)
		(placement
			(enabled no)
			(sheetname "")
		)
		(fill yes
			(thermal_gap 0.5)
			(thermal_bridge_width 0.5)
			(island_removal_mode 0)
		)
		(polygon
			(pts
				(arc
					(start 303.26965 -397.59001)
					(mid 302.51019 -397.59001)
					(end 303.26965 -397.59001)
				)
			)
		)
	)
	(zone
		(layers "B.Cu" "In13.Cu" "In15.Cu")
		(hatch none 0.5)
		(connect_pads
			(clearance 0)
		)
		(min_thickness 0.25)
		(keepout
			(tracks not_allowed)
			(vias allowed)
			(pads allowed)
			(copperpour not_allowed)
			(footprints allowed)
		)
		(placement
			(enabled no)
			(sheetname "")
		)
		(fill yes
			(thermal_gap 0.5)
			(thermal_bridge_width 0.5)
			(island_removal_mode 0)
		)
		(polygon
			(pts
				(arc
					(start 191.382142 -351.611438)
					(mid 190.678562 -351.611438)
					(end 191.382142 -351.611438)
				)
			)
		)
	)
	(zone
		(layers "B.Cu" "In13.Cu" "In15.Cu")
		(hatch none 0.5)
		(connect_pads
			(clearance 0)
		)
		(min_thickness 0.25)
		(keepout
			(tracks not_allowed)
			(vias allowed)
			(pads allowed)
			(copperpour not_allowed)
			(footprints allowed)
		)
		(placement
			(enabled no)
			(sheetname "")
		)
		(fill yes
			(thermal_gap 0.5)
			(thermal_bridge_width 0.5)
			(island_removal_mode 0)
		)
		(polygon
			(pts
				(arc
					(start 44.555918 -354.732082)
					(mid 43.852338 -354.732082)
					(end 44.555918 -354.732082)
				)
			)
		)
	)
	(zone
		(layers "B.Cu" "In13.Cu" "In15.Cu")
		(hatch none 0.5)
		(connect_pads
			(clearance 0)
		)
		(min_thickness 0.25)
		(keepout
			(tracks not_allowed)
			(vias allowed)
			(pads allowed)
			(copperpour not_allowed)
			(footprints allowed)
		)
		(placement
			(enabled no)
			(sheetname "")
		)
		(fill yes
			(thermal_gap 0.5)
			(thermal_bridge_width 0.5)
			(island_removal_mode 0)
		)
		(polygon
			(pts
				(arc
					(start 429.164242 -345.465146)
					(mid 428.460662 -345.465146)
					(end 429.164242 -345.465146)
				)
			)
		)
	)
	(zone
		(layers "B.Cu" "In13.Cu" "In15.Cu")
		(hatch none 0.5)
		(connect_pads
			(clearance 0)
		)
		(min_thickness 0.25)
		(keepout
			(tracks not_allowed)
			(vias allowed)
			(pads allowed)
			(copperpour not_allowed)
			(footprints allowed)
		)
		(placement
			(enabled no)
			(sheetname "")
		)
		(fill yes
			(thermal_gap 0.5)
			(thermal_bridge_width 0.5)
			(island_removal_mode 0)
		)
		(polygon
			(pts
				(arc
					(start 160.289748 -400.390106)
					(mid 159.530288 -400.390106)
					(end 160.289748 -400.390106)
				)
			)
		)
	)
	(zone
		(layers "B.Cu" "In13.Cu" "In15.Cu")
		(hatch none 0.5)
		(connect_pads
			(clearance 0)
		)
		(min_thickness 0.25)
		(keepout
			(tracks not_allowed)
			(vias allowed)
			(pads allowed)
			(copperpour not_allowed)
			(footprints allowed)
		)
		(placement
			(enabled no)
			(sheetname "")
		)
		(fill yes
			(thermal_gap 0.5)
			(thermal_bridge_width 0.5)
			(island_removal_mode 0)
		)
		(polygon
			(pts
				(arc
					(start 169.089832 -400.390106)
					(mid 168.330372 -400.390106)
					(end 169.089832 -400.390106)
				)
			)
		)
	)
	(zone
		(layers "B.Cu" "In13.Cu" "In15.Cu")
		(hatch none 0.5)
		(connect_pads
			(clearance 0)
		)
		(min_thickness 0.25)
		(keepout
			(tracks not_allowed)
			(vias allowed)
			(pads allowed)
			(copperpour not_allowed)
			(footprints allowed)
		)
		(placement
			(enabled no)
			(sheetname "")
		)
		(fill yes
			(thermal_gap 0.5)
			(thermal_bridge_width 0.5)
			(island_removal_mode 0)
		)
		(polygon
			(pts
				(arc
					(start 445.956944 -29.114242)
					(mid 445.253364 -29.114242)
					(end 445.956944 -29.114242)
				)
			)
		)
	)
	(zone
		(layers "B.Cu" "In13.Cu" "In15.Cu")
		(hatch none 0.5)
		(connect_pads
			(clearance 0)
		)
		(min_thickness 0.25)
		(keepout
			(tracks not_allowed)
			(vias allowed)
			(pads allowed)
			(copperpour not_allowed)
			(footprints allowed)
		)
		(placement
			(enabled no)
			(sheetname "")
		)
		(fill yes
			(thermal_gap 0.5)
			(thermal_bridge_width 0.5)
			(island_removal_mode 0)
		)
		(polygon
			(pts
				(arc
					(start 282.676092 -278.799798)
					(mid 282.023312 -278.799798)
					(end 282.676092 -278.799798)
				)
			)
		)
	)
	(zone
		(layers "B.Cu" "In13.Cu" "In15.Cu")
		(hatch none 0.5)
		(connect_pads
			(clearance 0)
		)
		(min_thickness 0.25)
		(keepout
			(tracks not_allowed)
			(vias allowed)
			(pads allowed)
			(copperpour not_allowed)
			(footprints allowed)
		)
		(placement
			(enabled no)
			(sheetname "")
		)
		(fill yes
			(thermal_gap 0.5)
			(thermal_bridge_width 0.5)
			(island_removal_mode 0)
		)
		(polygon
			(pts
				(arc
					(start 307.376322 -308.249828)
					(mid 306.723542 -308.249828)
					(end 307.376322 -308.249828)
				)
			)
		)
	)
	(zone
		(layers "B.Cu" "In13.Cu" "In15.Cu")
		(hatch none 0.5)
		(connect_pads
			(clearance 0)
		)
		(min_thickness 0.25)
		(keepout
			(tracks not_allowed)
			(vias allowed)
			(pads allowed)
			(copperpour not_allowed)
			(footprints allowed)
		)
		(placement
			(enabled no)
			(sheetname "")
		)
		(fill yes
			(thermal_gap 0.5)
			(thermal_bridge_width 0.5)
			(island_removal_mode 0)
		)
		(polygon
			(pts
				(arc
					(start 52.376324 -278.799798)
					(mid 51.723544 -278.799798)
					(end 52.376324 -278.799798)
				)
			)
		)
	)
	(zone
		(layers "B.Cu" "In13.Cu" "In15.Cu")
		(hatch none 0.5)
		(connect_pads
			(clearance 0)
		)
		(min_thickness 0.25)
		(keepout
			(tracks not_allowed)
			(vias allowed)
			(pads allowed)
			(copperpour not_allowed)
			(footprints allowed)
		)
		(placement
			(enabled no)
			(sheetname "")
		)
		(fill yes
			(thermal_gap 0.5)
			(thermal_bridge_width 0.5)
			(island_removal_mode 0)
		)
		(polygon
			(pts
				(arc
					(start 435.382162 -345.465146)
					(mid 434.678582 -345.465146)
					(end 435.382162 -345.465146)
				)
			)
		)
	)
	(zone
		(layers "B.Cu" "In13.Cu" "In15.Cu")
		(hatch none 0.5)
		(connect_pads
			(clearance 0)
		)
		(min_thickness 0.25)
		(keepout
			(tracks not_allowed)
			(vias allowed)
			(pads allowed)
			(copperpour not_allowed)
			(footprints allowed)
		)
		(placement
			(enabled no)
			(sheetname "")
		)
		(fill yes
			(thermal_gap 0.5)
			(thermal_bridge_width 0.5)
			(island_removal_mode 0)
		)
		(polygon
			(pts
				(arc
					(start 416.728402 -342.439498)
					(mid 416.024822 -342.439498)
					(end 416.728402 -342.439498)
				)
			)
		)
	)
	(zone
		(layers "B.Cu" "In13.Cu" "In15.Cu")
		(hatch none 0.5)
		(connect_pads
			(clearance 0)
		)
		(min_thickness 0.25)
		(keepout
			(tracks not_allowed)
			(vias allowed)
			(pads allowed)
			(copperpour not_allowed)
			(footprints allowed)
		)
		(placement
			(enabled no)
			(sheetname "")
		)
		(fill yes
			(thermal_gap 0.5)
			(thermal_bridge_width 0.5)
			(island_removal_mode 0)
		)
		(polygon
			(pts
				(arc
					(start 162.489642 -401.49018)
					(mid 161.730182 -401.49018)
					(end 162.489642 -401.49018)
				)
			)
		)
	)
	(zone
		(layers "B.Cu" "In13.Cu" "In15.Cu")
		(hatch none 0.5)
		(connect_pads
			(clearance 0)
		)
		(min_thickness 0.25)
		(keepout
			(tracks not_allowed)
			(vias allowed)
			(pads allowed)
			(copperpour not_allowed)
			(footprints allowed)
		)
		(placement
			(enabled no)
			(sheetname "")
		)
		(fill yes
			(thermal_gap 0.5)
			(thermal_bridge_width 0.5)
			(island_removal_mode 0)
		)
		(polygon
			(pts
				(arc
					(start 164.676328 -277.849838)
					(mid 164.023548 -277.849838)
					(end 164.676328 -277.849838)
				)
			)
		)
	)
	(zone
		(layers "B.Cu" "In13.Cu" "In15.Cu")
		(hatch none 0.5)
		(connect_pads
			(clearance 0)
		)
		(min_thickness 0.25)
		(keepout
			(tracks not_allowed)
			(vias allowed)
			(pads allowed)
			(copperpour not_allowed)
			(footprints allowed)
		)
		(placement
			(enabled no)
			(sheetname "")
		)
		(fill yes
			(thermal_gap 0.5)
			(thermal_bridge_width 0.5)
			(island_removal_mode 0)
		)
		(polygon
			(pts
				(arc
					(start 46.67631 -277.849838)
					(mid 46.02353 -277.849838)
					(end 46.67631 -277.849838)
				)
			)
		)
	)
	(zone
		(layers "B.Cu" "In13.Cu" "In15.Cu")
		(hatch none 0.5)
		(connect_pads
			(clearance 0)
		)
		(min_thickness 0.25)
		(keepout
			(tracks not_allowed)
			(vias allowed)
			(pads allowed)
			(copperpour not_allowed)
			(footprints allowed)
		)
		(placement
			(enabled no)
			(sheetname "")
		)
		(fill yes
			(thermal_gap 0.5)
			(thermal_bridge_width 0.5)
			(island_removal_mode 0)
		)
		(polygon
			(pts
				(arc
					(start 160.289748 -374.390158)
					(mid 159.530288 -374.390158)
					(end 160.289748 -374.390158)
				)
			)
		)
	)
	(zone
		(layers "B.Cu" "In13.Cu" "In15.Cu")
		(hatch none 0.5)
		(connect_pads
			(clearance 0)
		)
		(min_thickness 0.25)
		(keepout
			(tracks not_allowed)
			(vias allowed)
			(pads allowed)
			(copperpour not_allowed)
			(footprints allowed)
		)
		(placement
			(enabled no)
			(sheetname "")
		)
		(fill yes
			(thermal_gap 0.5)
			(thermal_bridge_width 0.5)
			(island_removal_mode 0)
		)
		(polygon
			(pts
				(arc
					(start 370.599208 -30.92069)
					(mid 369.895628 -30.92069)
					(end 370.599208 -30.92069)
				)
			)
		)
	)
	(zone
		(layers "B.Cu" "In13.Cu" "In15.Cu")
		(hatch none 0.5)
		(connect_pads
			(clearance 0)
		)
		(min_thickness 0.25)
		(keepout
			(tracks not_allowed)
			(vias allowed)
			(pads allowed)
			(copperpour not_allowed)
			(footprints allowed)
		)
		(placement
			(enabled no)
			(sheetname "")
		)
		(fill yes
			(thermal_gap 0.5)
			(thermal_bridge_width 0.5)
			(island_removal_mode 0)
		)
		(polygon
			(pts
				(arc
					(start 309.276242 -309.199788)
					(mid 308.623462 -309.199788)
					(end 309.276242 -309.199788)
				)
			)
		)
	)
	(zone
		(layers "B.Cu" "In13.Cu" "In15.Cu")
		(hatch none 0.5)
		(connect_pads
			(clearance 0)
		)
		(min_thickness 0.25)
		(keepout
			(tracks not_allowed)
			(vias allowed)
			(pads allowed)
			(copperpour not_allowed)
			(footprints allowed)
		)
		(placement
			(enabled no)
			(sheetname "")
		)
		(fill yes
			(thermal_gap 0.5)
			(thermal_bridge_width 0.5)
			(island_removal_mode 0)
		)
		(polygon
			(pts
				(arc
					(start 296.669714 -396.49019)
					(mid 295.910254 -396.49019)
					(end 296.669714 -396.49019)
				)
			)
		)
	)
	(zone
		(layers "B.Cu" "In13.Cu" "In15.Cu")
		(hatch none 0.5)
		(connect_pads
			(clearance 0)
		)
		(min_thickness 0.25)
		(keepout
			(tracks not_allowed)
			(vias allowed)
			(pads allowed)
			(copperpour not_allowed)
			(footprints allowed)
		)
		(placement
			(enabled no)
			(sheetname "")
		)
		(fill yes
			(thermal_gap 0.5)
			(thermal_bridge_width 0.5)
			(island_removal_mode 0)
		)
		(polygon
			(pts
				(arc
					(start 309.276242 -312.999882)
					(mid 308.623462 -312.999882)
					(end 309.276242 -312.999882)
				)
			)
		)
	)
	(zone
		(layers "B.Cu" "In13.Cu" "In15.Cu")
		(hatch none 0.5)
		(connect_pads
			(clearance 0)
		)
		(min_thickness 0.25)
		(keepout
			(tracks not_allowed)
			(vias allowed)
			(pads allowed)
			(copperpour not_allowed)
			(footprints allowed)
		)
		(placement
			(enabled no)
			(sheetname "")
		)
		(fill yes
			(thermal_gap 0.5)
			(thermal_bridge_width 0.5)
			(island_removal_mode 0)
		)
		(polygon
			(pts
				(arc
					(start 171.326302 -279.749504)
					(mid 170.673522 -279.749504)
					(end 171.326302 -279.749504)
				)
			)
		)
	)
	(zone
		(layers "B.Cu" "In13.Cu" "In15.Cu")
		(hatch none 0.5)
		(connect_pads
			(clearance 0)
		)
		(min_thickness 0.25)
		(keepout
			(tracks not_allowed)
			(vias allowed)
			(pads allowed)
			(copperpour not_allowed)
			(footprints allowed)
		)
		(placement
			(enabled no)
			(sheetname "")
		)
		(fill yes
			(thermal_gap 0.5)
			(thermal_bridge_width 0.5)
			(island_removal_mode 0)
		)
		(polygon
			(pts
				(arc
					(start 390.226296 -307.299868)
					(mid 389.573516 -307.299868)
					(end 390.226296 -307.299868)
				)
			)
		)
	)
	(zone
		(layers "B.Cu" "In13.Cu" "In15.Cu")
		(hatch none 0.5)
		(connect_pads
			(clearance 0)
		)
		(min_thickness 0.25)
		(keepout
			(tracks not_allowed)
			(vias allowed)
			(pads allowed)
			(copperpour not_allowed)
			(footprints allowed)
		)
		(placement
			(enabled no)
			(sheetname "")
		)
		(fill yes
			(thermal_gap 0.5)
			(thermal_bridge_width 0.5)
			(island_removal_mode 0)
		)
		(polygon
			(pts
				(arc
					(start 100.299012 -30.05709)
					(mid 99.595432 -30.05709)
					(end 100.299012 -30.05709)
				)
			)
		)
	)
	(zone
		(layers "B.Cu" "In13.Cu" "In15.Cu")
		(hatch none 0.5)
		(connect_pads
			(clearance 0)
		)
		(min_thickness 0.25)
		(keepout
			(tracks not_allowed)
			(vias allowed)
			(pads allowed)
			(copperpour not_allowed)
			(footprints allowed)
		)
		(placement
			(enabled no)
			(sheetname "")
		)
		(fill yes
			(thermal_gap 0.5)
			(thermal_bridge_width 0.5)
			(island_removal_mode 0)
		)
		(polygon
			(pts
				(arc
					(start 404.476204 -277.849838)
					(mid 403.823424 -277.849838)
					(end 404.476204 -277.849838)
				)
			)
		)
	)
	(zone
		(layers "B.Cu" "In13.Cu" "In15.Cu")
		(hatch none 0.5)
		(connect_pads
			(clearance 0)
		)
		(min_thickness 0.25)
		(keepout
			(tracks not_allowed)
			(vias allowed)
			(pads allowed)
			(copperpour not_allowed)
			(footprints allowed)
		)
		(placement
			(enabled no)
			(sheetname "")
		)
		(fill yes
			(thermal_gap 0.5)
			(thermal_bridge_width 0.5)
			(island_removal_mode 0)
		)
		(polygon
			(pts
				(arc
					(start 285.526226 -280.699718)
					(mid 284.873446 -280.699718)
					(end 285.526226 -280.699718)
				)
			)
		)
	)
	(zone
		(layers "B.Cu" "In13.Cu" "In15.Cu")
		(hatch none 0.5)
		(connect_pads
			(clearance 0)
		)
		(min_thickness 0.25)
		(keepout
			(tracks not_allowed)
			(vias allowed)
			(pads allowed)
			(copperpour not_allowed)
			(footprints allowed)
		)
		(placement
			(enabled no)
			(sheetname "")
		)
		(fill yes
			(thermal_gap 0.5)
			(thermal_bridge_width 0.5)
			(island_removal_mode 0)
		)
		(polygon
			(pts
				(arc
					(start 158.976314 -305.399948)
					(mid 158.323534 -305.399948)
					(end 158.976314 -305.399948)
				)
			)
		)
	)
	(zone
		(layers "B.Cu" "In13.Cu" "In15.Cu")
		(hatch none 0.5)
		(connect_pads
			(clearance 0)
		)
		(min_thickness 0.25)
		(keepout
			(tracks not_allowed)
			(vias allowed)
			(pads allowed)
			(copperpour not_allowed)
			(footprints allowed)
		)
		(placement
			(enabled no)
			(sheetname "")
		)
		(fill yes
			(thermal_gap 0.5)
			(thermal_bridge_width 0.5)
			(island_removal_mode 0)
		)
		(polygon
			(pts
				(arc
					(start 419.86962 -375.69013)
					(mid 419.11016 -375.69013)
					(end 419.86962 -375.69013)
				)
			)
		)
	)
	(zone
		(layers "B.Cu" "In13.Cu" "In15.Cu")
		(hatch none 0.5)
		(connect_pads
			(clearance 0)
		)
		(min_thickness 0.25)
		(keepout
			(tracks not_allowed)
			(vias allowed)
			(pads allowed)
			(copperpour not_allowed)
			(footprints allowed)
		)
		(placement
			(enabled no)
			(sheetname "")
		)
		(fill yes
			(thermal_gap 0.5)
			(thermal_bridge_width 0.5)
			(island_removal_mode 0)
		)
		(polygon
			(pts
				(arc
					(start 448.599052 -30.92069)
					(mid 447.895472 -30.92069)
					(end 448.599052 -30.92069)
				)
			)
		)
	)
	(zone
		(layers "B.Cu" "In13.Cu" "In15.Cu")
		(hatch none 0.5)
		(connect_pads
			(clearance 0)
		)
		(min_thickness 0.25)
		(keepout
			(tracks not_allowed)
			(vias allowed)
			(pads allowed)
			(copperpour not_allowed)
			(footprints allowed)
		)
		(placement
			(enabled no)
			(sheetname "")
		)
		(fill yes
			(thermal_gap 0.5)
			(thermal_bridge_width 0.5)
			(island_removal_mode 0)
		)
		(polygon
			(pts
				(arc
					(start 48.57623 -277.849838)
					(mid 47.92345 -277.849838)
					(end 48.57623 -277.849838)
				)
			)
		)
	)
	(zone
		(layers "B.Cu" "In13.Cu" "In15.Cu")
		(hatch none 0.5)
		(connect_pads
			(clearance 0)
		)
		(min_thickness 0.25)
		(keepout
			(tracks not_allowed)
			(vias allowed)
			(pads allowed)
			(copperpour not_allowed)
			(footprints allowed)
		)
		(placement
			(enabled no)
			(sheetname "")
		)
		(fill yes
			(thermal_gap 0.5)
			(thermal_bridge_width 0.5)
			(island_removal_mode 0)
		)
		(polygon
			(pts
				(arc
					(start 169.619422 -345.465146)
					(mid 168.915842 -345.465146)
					(end 169.619422 -345.465146)
				)
			)
		)
	)
	(zone
		(layers "B.Cu" "In13.Cu" "In15.Cu")
		(hatch none 0.5)
		(connect_pads
			(clearance 0)
		)
		(min_thickness 0.25)
		(keepout
			(tracks not_allowed)
			(vias allowed)
			(pads allowed)
			(copperpour not_allowed)
			(footprints allowed)
		)
		(placement
			(enabled no)
			(sheetname "")
		)
		(fill yes
			(thermal_gap 0.5)
			(thermal_bridge_width 0.5)
			(island_removal_mode 0)
		)
		(polygon
			(pts
				(arc
					(start 312.126122 -311.099962)
					(mid 311.473342 -311.099962)
					(end 312.126122 -311.099962)
				)
			)
		)
	)
	(zone
		(layers "B.Cu" "In13.Cu" "In15.Cu")
		(hatch none 0.5)
		(connect_pads
			(clearance 0)
		)
		(min_thickness 0.25)
		(keepout
			(tracks not_allowed)
			(vias allowed)
			(pads allowed)
			(copperpour not_allowed)
			(footprints allowed)
		)
		(placement
			(enabled no)
			(sheetname "")
		)
		(fill yes
			(thermal_gap 0.5)
			(thermal_bridge_width 0.5)
			(island_removal_mode 0)
		)
		(polygon
			(pts
				(arc
					(start 416.728402 -345.465146)
					(mid 416.024822 -345.465146)
					(end 416.728402 -345.465146)
				)
			)
		)
	)
	(zone
		(layers "B.Cu" "In13.Cu" "In15.Cu")
		(hatch none 0.5)
		(connect_pads
			(clearance 0)
		)
		(min_thickness 0.25)
		(keepout
			(tracks not_allowed)
			(vias allowed)
			(pads allowed)
			(copperpour not_allowed)
			(footprints allowed)
		)
		(placement
			(enabled no)
			(sheetname "")
		)
		(fill yes
			(thermal_gap 0.5)
			(thermal_bridge_width 0.5)
			(island_removal_mode 0)
		)
		(polygon
			(pts
				(arc
					(start 268.248892 -345.465146)
					(mid 267.545312 -345.465146)
					(end 268.248892 -345.465146)
				)
			)
		)
	)
	(zone
		(layers "B.Cu" "In13.Cu" "In15.Cu")
		(hatch none 0.5)
		(connect_pads
			(clearance 0)
		)
		(min_thickness 0.25)
		(keepout
			(tracks not_allowed)
			(vias allowed)
			(pads allowed)
			(copperpour not_allowed)
			(footprints allowed)
		)
		(placement
			(enabled no)
			(sheetname "")
		)
		(fill yes
			(thermal_gap 0.5)
			(thermal_bridge_width 0.5)
			(island_removal_mode 0)
		)
		(polygon
			(pts
				(arc
					(start 153.2763 -312.049922)
					(mid 152.62352 -312.049922)
					(end 153.2763 -312.049922)
				)
			)
		)
	)
	(zone
		(layers "B.Cu" "In13.Cu" "In15.Cu")
		(hatch none 0.5)
		(connect_pads
			(clearance 0)
		)
		(min_thickness 0.25)
		(keepout
			(tracks not_allowed)
			(vias allowed)
			(pads allowed)
			(copperpour not_allowed)
			(footprints allowed)
		)
		(placement
			(enabled no)
			(sheetname "")
		)
		(fill yes
			(thermal_gap 0.5)
			(thermal_bridge_width 0.5)
			(island_removal_mode 0)
		)
		(polygon
			(pts
				(arc
					(start 160.876234 -278.799798)
					(mid 160.223454 -278.799798)
					(end 160.876234 -278.799798)
				)
			)
		)
	)
	(zone
		(layers "B.Cu" "In13.Cu" "In15.Cu")
		(hatch none 0.5)
		(connect_pads
			(clearance 0)
		)
		(min_thickness 0.25)
		(keepout
			(tracks not_allowed)
			(vias allowed)
			(pads allowed)
			(copperpour not_allowed)
			(footprints allowed)
		)
		(placement
			(enabled no)
			(sheetname "")
		)
		(fill yes
			(thermal_gap 0.5)
			(thermal_bridge_width 0.5)
			(island_removal_mode 0)
		)
		(polygon
			(pts
				(arc
					(start 401.626324 -280.699718)
					(mid 400.973544 -280.699718)
					(end 401.626324 -280.699718)
				)
			)
		)
	)
	(zone
		(layers "B.Cu" "In13.Cu" "In15.Cu")
		(hatch none 0.5)
		(connect_pads
			(clearance 0)
		)
		(min_thickness 0.25)
		(keepout
			(tracks not_allowed)
			(vias allowed)
			(pads allowed)
			(copperpour not_allowed)
			(footprints allowed)
		)
		(placement
			(enabled no)
			(sheetname "")
		)
		(fill yes
			(thermal_gap 0.5)
			(thermal_bridge_width 0.5)
			(island_removal_mode 0)
		)
		(polygon
			(pts
				(arc
					(start 97.656904 -29.114242)
					(mid 96.953324 -29.114242)
					(end 97.656904 -29.114242)
				)
			)
		)
	)
	(zone
		(layers "B.Cu" "In13.Cu" "In15.Cu")
		(hatch none 0.5)
		(connect_pads
			(clearance 0)
		)
		(min_thickness 0.25)
		(keepout
			(tracks not_allowed)
			(vias allowed)
			(pads allowed)
			(copperpour not_allowed)
			(footprints allowed)
		)
		(placement
			(enabled no)
			(sheetname "")
		)
		(fill yes
			(thermal_gap 0.5)
			(thermal_bridge_width 0.5)
			(island_removal_mode 0)
		)
		(polygon
			(pts
				(arc
					(start 164.399214 -30.92069)
					(mid 163.695634 -30.92069)
					(end 164.399214 -30.92069)
				)
			)
		)
	)
	(zone
		(layers "B.Cu" "In13.Cu" "In15.Cu")
		(hatch none 0.5)
		(connect_pads
			(clearance 0)
		)
		(min_thickness 0.25)
		(keepout
			(tracks not_allowed)
			(vias allowed)
			(pads allowed)
			(copperpour not_allowed)
			(footprints allowed)
		)
		(placement
			(enabled no)
			(sheetname "")
		)
		(fill yes
			(thermal_gap 0.5)
			(thermal_bridge_width 0.5)
			(island_removal_mode 0)
		)
		(polygon
			(pts
				(arc
					(start 277.926292 -279.749504)
					(mid 277.273512 -279.749504)
					(end 277.926292 -279.749504)
				)
			)
		)
	)
	(zone
		(layers "B.Cu" "In13.Cu" "In15.Cu")
		(hatch none 0.5)
		(connect_pads
			(clearance 0)
		)
		(min_thickness 0.25)
		(keepout
			(tracks not_allowed)
			(vias allowed)
			(pads allowed)
			(copperpour not_allowed)
			(footprints allowed)
		)
		(placement
			(enabled no)
			(sheetname "")
		)
		(fill yes
			(thermal_gap 0.5)
			(thermal_bridge_width 0.5)
			(island_removal_mode 0)
		)
		(polygon
			(pts
				(arc
					(start 274.466812 -345.465146)
					(mid 273.763232 -345.465146)
					(end 274.466812 -345.465146)
				)
			)
		)
	)
	(zone
		(layers "B.Cu" "In13.Cu" "In15.Cu")
		(hatch none 0.5)
		(connect_pads
			(clearance 0)
		)
		(min_thickness 0.25)
		(keepout
			(tracks not_allowed)
			(vias allowed)
			(pads allowed)
			(copperpour not_allowed)
			(footprints allowed)
		)
		(placement
			(enabled no)
			(sheetname "")
		)
		(fill yes
			(thermal_gap 0.5)
			(thermal_bridge_width 0.5)
			(island_removal_mode 0)
		)
		(polygon
			(pts
				(arc
					(start 251.857002 -29.114242)
					(mid 251.153422 -29.114242)
					(end 251.857002 -29.114242)
				)
			)
		)
	)
	(zone
		(layers "B.Cu" "In13.Cu" "In15.Cu")
		(hatch none 0.5)
		(connect_pads
			(clearance 0)
		)
		(min_thickness 0.25)
		(keepout
			(tracks not_allowed)
			(vias allowed)
			(pads allowed)
			(copperpour not_allowed)
			(footprints allowed)
		)
		(placement
			(enabled no)
			(sheetname "")
		)
		(fill yes
			(thermal_gap 0.5)
			(thermal_bridge_width 0.5)
			(island_removal_mode 0)
		)
		(polygon
			(pts
				(arc
					(start 185.164222 -351.611438)
					(mid 184.460642 -351.611438)
					(end 185.164222 -351.611438)
				)
			)
		)
	)
	(zone
		(layers "B.Cu" "In13.Cu" "In15.Cu")
		(hatch none 0.5)
		(connect_pads
			(clearance 0)
		)
		(min_thickness 0.25)
		(keepout
			(tracks not_allowed)
			(vias allowed)
			(pads allowed)
			(copperpour not_allowed)
			(footprints allowed)
		)
		(placement
			(enabled no)
			(sheetname "")
		)
		(fill yes
			(thermal_gap 0.5)
			(thermal_bridge_width 0.5)
			(island_removal_mode 0)
		)
		(polygon
			(pts
				(arc
					(start 310.226202 -307.299868)
					(mid 309.573422 -307.299868)
					(end 310.226202 -307.299868)
				)
			)
		)
	)
	(zone
		(layers "B.Cu" "In13.Cu" "In15.Cu")
		(hatch none 0.5)
		(connect_pads
			(clearance 0)
		)
		(min_thickness 0.25)
		(keepout
			(tracks not_allowed)
			(vias allowed)
			(pads allowed)
			(copperpour not_allowed)
			(footprints allowed)
		)
		(placement
			(enabled no)
			(sheetname "")
		)
		(fill yes
			(thermal_gap 0.5)
			(thermal_bridge_width 0.5)
			(island_removal_mode 0)
		)
		(polygon
			(pts
				(arc
					(start 286.476186 -278.799798)
					(mid 285.823406 -278.799798)
					(end 286.476186 -278.799798)
				)
			)
		)
	)
	(zone
		(layers "B.Cu" "In13.Cu" "In15.Cu")
		(hatch none 0.5)
		(connect_pads
			(clearance 0)
		)
		(min_thickness 0.25)
		(keepout
			(tracks not_allowed)
			(vias allowed)
			(pads allowed)
			(copperpour not_allowed)
			(footprints allowed)
		)
		(placement
			(enabled no)
			(sheetname "")
		)
		(fill yes
			(thermal_gap 0.5)
			(thermal_bridge_width 0.5)
			(island_removal_mode 0)
		)
		(polygon
			(pts
				(arc
					(start 175.837342 -345.465146)
					(mid 175.133762 -345.465146)
					(end 175.837342 -345.465146)
				)
			)
		)
	)
	(zone
		(layers "B.Cu" "In13.Cu" "In15.Cu")
		(hatch none 0.5)
		(connect_pads
			(clearance 0)
		)
		(min_thickness 0.25)
		(keepout
			(tracks not_allowed)
			(vias allowed)
			(pads allowed)
			(copperpour not_allowed)
			(footprints allowed)
		)
		(placement
			(enabled no)
			(sheetname "")
		)
		(fill yes
			(thermal_gap 0.5)
			(thermal_bridge_width 0.5)
			(island_removal_mode 0)
		)
		(polygon
			(pts
				(arc
					(start 48.08982 -409.290012)
					(mid 47.33036 -409.290012)
					(end 48.08982 -409.290012)
				)
			)
		)
	)
	(zone
		(layers "B.Cu" "In13.Cu" "In15.Cu")
		(hatch none 0.5)
		(connect_pads
			(clearance 0)
		)
		(min_thickness 0.25)
		(keepout
			(tracks not_allowed)
			(vias allowed)
			(pads allowed)
			(copperpour not_allowed)
			(footprints allowed)
		)
		(placement
			(enabled no)
			(sheetname "")
		)
		(fill yes
			(thermal_gap 0.5)
			(thermal_bridge_width 0.5)
			(island_removal_mode 0)
		)
		(polygon
			(pts
				(arc
					(start 280.684732 -354.732082)
					(mid 279.981152 -354.732082)
					(end 280.684732 -354.732082)
				)
			)
		)
	)
	(zone
		(layers "B.Cu" "In13.Cu" "In15.Cu")
		(hatch none 0.5)
		(connect_pads
			(clearance 0)
		)
		(min_thickness 0.25)
		(keepout
			(tracks not_allowed)
			(vias allowed)
			(pads allowed)
			(copperpour not_allowed)
			(footprints allowed)
		)
		(placement
			(enabled no)
			(sheetname "")
		)
		(fill yes
			(thermal_gap 0.5)
			(thermal_bridge_width 0.5)
			(island_removal_mode 0)
		)
		(polygon
			(pts
				(arc
					(start 36.092638 -348.58579)
					(mid 35.389058 -348.58579)
					(end 36.092638 -348.58579)
				)
			)
		)
	)
	(zone
		(layers "B.Cu" "In13.Cu" "In15.Cu")
		(hatch none 0.5)
		(connect_pads
			(clearance 0)
		)
		(min_thickness 0.25)
		(keepout
			(tracks not_allowed)
			(vias allowed)
			(pads allowed)
			(copperpour not_allowed)
			(footprints allowed)
		)
		(placement
			(enabled no)
			(sheetname "")
		)
		(fill yes
			(thermal_gap 0.5)
			(thermal_bridge_width 0.5)
			(island_removal_mode 0)
		)
		(polygon
			(pts
				(arc
					(start 171.289726 -376.790204)
					(mid 170.530266 -376.790204)
					(end 171.289726 -376.790204)
				)
			)
		)
	)
	(zone
		(layers "B.Cu" "In13.Cu" "In15.Cu")
		(hatch none 0.5)
		(connect_pads
			(clearance 0)
		)
		(min_thickness 0.25)
		(keepout
			(tracks not_allowed)
			(vias allowed)
			(pads allowed)
			(copperpour not_allowed)
			(footprints allowed)
		)
		(placement
			(enabled no)
			(sheetname "")
		)
		(fill yes
			(thermal_gap 0.5)
			(thermal_bridge_width 0.5)
			(island_removal_mode 0)
		)
		(polygon
			(pts
				(arc
					(start 138.399266 -34.520886)
					(mid 137.695686 -34.520886)
					(end 138.399266 -34.520886)
				)
			)
		)
	)
	(zone
		(layers "B.Cu" "In13.Cu" "In15.Cu")
		(hatch none 0.5)
		(connect_pads
			(clearance 0)
		)
		(min_thickness 0.25)
		(keepout
			(tracks not_allowed)
			(vias allowed)
			(pads allowed)
			(copperpour not_allowed)
			(footprints allowed)
		)
		(placement
			(enabled no)
			(sheetname "")
		)
		(fill yes
			(thermal_gap 0.5)
			(thermal_bridge_width 0.5)
			(island_removal_mode 0)
		)
		(polygon
			(pts
				(arc
					(start 46.67631 -278.799798)
					(mid 46.02353 -278.799798)
					(end 46.67631 -278.799798)
				)
			)
		)
	)
	(zone
		(layers "B.Cu" "In13.Cu" "In15.Cu")
		(hatch none 0.5)
		(connect_pads
			(clearance 0)
		)
		(min_thickness 0.25)
		(keepout
			(tracks not_allowed)
			(vias allowed)
			(pads allowed)
			(copperpour not_allowed)
			(footprints allowed)
		)
		(placement
			(enabled no)
			(sheetname "")
		)
		(fill yes
			(thermal_gap 0.5)
			(thermal_bridge_width 0.5)
			(island_removal_mode 0)
		)
		(polygon
			(pts
				(arc
					(start 160.876234 -308.249828)
					(mid 160.223454 -308.249828)
					(end 160.876234 -308.249828)
				)
			)
		)
	)
	(zone
		(layers "B.Cu" "In13.Cu" "In15.Cu")
		(hatch none 0.5)
		(connect_pads
			(clearance 0)
		)
		(min_thickness 0.25)
		(keepout
			(tracks not_allowed)
			(vias allowed)
			(pads allowed)
			(copperpour not_allowed)
			(footprints allowed)
		)
		(placement
			(enabled no)
			(sheetname "")
		)
		(fill yes
			(thermal_gap 0.5)
			(thermal_bridge_width 0.5)
			(island_removal_mode 0)
		)
		(polygon
			(pts
				(arc
					(start 168.755822 -342.439498)
					(mid 168.052242 -342.439498)
					(end 168.755822 -342.439498)
				)
			)
		)
	)
	(zone
		(layers "B.Cu" "In13.Cu" "In15.Cu")
		(hatch none 0.5)
		(connect_pads
			(clearance 0)
		)
		(min_thickness 0.25)
		(keepout
			(tracks not_allowed)
			(vias allowed)
			(pads allowed)
			(copperpour not_allowed)
			(footprints allowed)
		)
		(placement
			(enabled no)
			(sheetname "")
		)
		(fill yes
			(thermal_gap 0.5)
			(thermal_bridge_width 0.5)
			(island_removal_mode 0)
		)
		(polygon
			(pts
				(arc
					(start 390.226296 -305.399948)
					(mid 389.573516 -305.399948)
					(end 390.226296 -305.399948)
				)
			)
		)
	)
	(zone
		(layers "B.Cu" "In13.Cu" "In15.Cu")
		(hatch none 0.5)
		(connect_pads
			(clearance 0)
		)
		(min_thickness 0.25)
		(keepout
			(tracks not_allowed)
			(vias allowed)
			(pads allowed)
			(copperpour not_allowed)
			(footprints allowed)
		)
		(placement
			(enabled no)
			(sheetname "")
		)
		(fill yes
			(thermal_gap 0.5)
			(thermal_bridge_width 0.5)
			(island_removal_mode 0)
		)
		(polygon
			(pts
				(arc
					(start 29.874718 -348.58579)
					(mid 29.171138 -348.58579)
					(end 29.874718 -348.58579)
				)
			)
		)
	)
	(zone
		(layers "B.Cu" "In13.Cu" "In15.Cu")
		(hatch none 0.5)
		(connect_pads
			(clearance 0)
		)
		(min_thickness 0.25)
		(keepout
			(tracks not_allowed)
			(vias allowed)
			(pads allowed)
			(copperpour not_allowed)
			(footprints allowed)
		)
		(placement
			(enabled no)
			(sheetname "")
		)
		(fill yes
			(thermal_gap 0.5)
			(thermal_bridge_width 0.5)
			(island_removal_mode 0)
		)
		(polygon
			(pts
				(arc
					(start 164.68979 -374.390158)
					(mid 163.93033 -374.390158)
					(end 164.68979 -374.390158)
				)
			)
		)
	)
	(zone
		(layers "B.Cu" "In13.Cu" "In15.Cu")
		(hatch none 0.5)
		(connect_pads
			(clearance 0)
		)
		(min_thickness 0.25)
		(keepout
			(tracks not_allowed)
			(vias allowed)
			(pads allowed)
			(copperpour not_allowed)
			(footprints allowed)
		)
		(placement
			(enabled no)
			(sheetname "")
		)
		(fill yes
			(thermal_gap 0.5)
			(thermal_bridge_width 0.5)
			(island_removal_mode 0)
		)
		(polygon
			(pts
				(arc
					(start 403.526244 -279.749504)
					(mid 402.873464 -279.749504)
					(end 403.526244 -279.749504)
				)
			)
		)
	)
	(zone
		(layers "B.Cu" "In13.Cu" "In15.Cu")
		(hatch none 0.5)
		(connect_pads
			(clearance 0)
		)
		(min_thickness 0.25)
		(keepout
			(tracks not_allowed)
			(vias allowed)
			(pads allowed)
			(copperpour not_allowed)
			(footprints allowed)
		)
		(placement
			(enabled no)
			(sheetname "")
		)
		(fill yes
			(thermal_gap 0.5)
			(thermal_bridge_width 0.5)
			(island_removal_mode 0)
		)
		(polygon
			(pts
				(arc
					(start 135.757158 -32.714184)
					(mid 135.053578 -32.714184)
					(end 135.757158 -32.714184)
				)
			)
		)
	)
	(zone
		(layers "B.Cu" "In13.Cu" "In15.Cu")
		(hatch none 0.5)
		(connect_pads
			(clearance 0)
		)
		(min_thickness 0.25)
		(keepout
			(tracks not_allowed)
			(vias allowed)
			(pads allowed)
			(copperpour not_allowed)
			(footprints allowed)
		)
		(placement
			(enabled no)
			(sheetname "")
		)
		(fill yes
			(thermal_gap 0.5)
			(thermal_bridge_width 0.5)
			(island_removal_mode 0)
		)
		(polygon
			(pts
				(arc
					(start 293.120572 -357.75773)
					(mid 292.416992 -357.75773)
					(end 293.120572 -357.75773)
				)
			)
		)
	)
	(zone
		(layers "B.Cu" "In13.Cu" "In15.Cu")
		(hatch none 0.5)
		(connect_pads
			(clearance 0)
		)
		(min_thickness 0.25)
		(keepout
			(tracks not_allowed)
			(vias allowed)
			(pads allowed)
			(copperpour not_allowed)
			(footprints allowed)
		)
		(placement
			(enabled no)
			(sheetname "")
		)
		(fill yes
			(thermal_gap 0.5)
			(thermal_bridge_width 0.5)
			(island_removal_mode 0)
		)
		(polygon
			(pts
				(arc
					(start 161.757106 -28.250642)
					(mid 161.053526 -28.250642)
					(end 161.757106 -28.250642)
				)
			)
		)
	)
	(zone
		(layers "B.Cu" "In13.Cu" "In15.Cu")
		(hatch none 0.5)
		(connect_pads
			(clearance 0)
		)
		(min_thickness 0.25)
		(keepout
			(tracks not_allowed)
			(vias allowed)
			(pads allowed)
			(copperpour not_allowed)
			(footprints allowed)
		)
		(placement
			(enabled no)
			(sheetname "")
		)
		(fill yes
			(thermal_gap 0.5)
			(thermal_bridge_width 0.5)
			(island_removal_mode 0)
		)
		(polygon
			(pts
				(arc
					(start 393.076176 -277.849838)
					(mid 392.423396 -277.849838)
					(end 393.076176 -277.849838)
				)
			)
		)
	)
	(zone
		(layers "B.Cu" "In13.Cu" "In15.Cu")
		(hatch none 0.5)
		(connect_pads
			(clearance 0)
		)
		(min_thickness 0.25)
		(keepout
			(tracks not_allowed)
			(vias allowed)
			(pads allowed)
			(copperpour not_allowed)
			(footprints allowed)
		)
		(placement
			(enabled no)
			(sheetname "")
		)
		(fill yes
			(thermal_gap 0.5)
			(thermal_bridge_width 0.5)
			(island_removal_mode 0)
		)
		(polygon
			(pts
				(arc
					(start 303.856898 -32.714184)
					(mid 303.153318 -32.714184)
					(end 303.856898 -32.714184)
				)
			)
		)
	)
	(zone
		(layers "B.Cu" "In13.Cu" "In15.Cu")
		(hatch none 0.5)
		(connect_pads
			(clearance 0)
		)
		(min_thickness 0.25)
		(keepout
			(tracks not_allowed)
			(vias allowed)
			(pads allowed)
			(copperpour not_allowed)
			(footprints allowed)
		)
		(placement
			(enabled no)
			(sheetname "")
		)
		(fill yes
			(thermal_gap 0.5)
			(thermal_bridge_width 0.5)
			(island_removal_mode 0)
		)
		(polygon
			(pts
				(arc
					(start 216.39911 -34.520886)
					(mid 215.69553 -34.520886)
					(end 216.39911 -34.520886)
				)
			)
		)
	)
	(zone
		(layers "B.Cu" "In13.Cu" "In15.Cu")
		(hatch none 0.5)
		(connect_pads
			(clearance 0)
		)
		(min_thickness 0.25)
		(keepout
			(tracks not_allowed)
			(vias allowed)
			(pads allowed)
			(copperpour not_allowed)
			(footprints allowed)
		)
		(placement
			(enabled no)
			(sheetname "")
		)
		(fill yes
			(thermal_gap 0.5)
			(thermal_bridge_width 0.5)
			(island_removal_mode 0)
		)
		(polygon
			(pts
				(arc
					(start 298.869608 -371.590062)
					(mid 298.110148 -371.590062)
					(end 298.869608 -371.590062)
				)
			)
		)
	)
	(zone
		(layers "B.Cu" "In13.Cu" "In15.Cu")
		(hatch none 0.5)
		(connect_pads
			(clearance 0)
		)
		(min_thickness 0.25)
		(keepout
			(tracks not_allowed)
			(vias allowed)
			(pads allowed)
			(copperpour not_allowed)
			(footprints allowed)
		)
		(placement
			(enabled no)
			(sheetname "")
		)
		(fill yes
			(thermal_gap 0.5)
			(thermal_bridge_width 0.5)
			(island_removal_mode 0)
		)
		(polygon
			(pts
				(arc
					(start 45.72635 -280.699718)
					(mid 45.07357 -280.699718)
					(end 45.72635 -280.699718)
				)
			)
		)
	)
	(zone
		(layers "B.Cu" "In13.Cu" "In15.Cu")
		(hatch none 0.5)
		(connect_pads
			(clearance 0)
		)
		(min_thickness 0.25)
		(keepout
			(tracks not_allowed)
			(vias allowed)
			(pads allowed)
			(copperpour not_allowed)
			(footprints allowed)
		)
		(placement
			(enabled no)
			(sheetname "")
		)
		(fill yes
			(thermal_gap 0.5)
			(thermal_bridge_width 0.5)
			(island_removal_mode 0)
		)
		(polygon
			(pts
				(arc
					(start 401.626324 -279.749504)
					(mid 400.973544 -279.749504)
					(end 401.626324 -279.749504)
				)
			)
		)
	)
	(zone
		(layers "B.Cu" "In13.Cu" "In15.Cu")
		(hatch none 0.5)
		(connect_pads
			(clearance 0)
		)
		(min_thickness 0.25)
		(keepout
			(tracks not_allowed)
			(vias allowed)
			(pads allowed)
			(copperpour not_allowed)
			(footprints allowed)
		)
		(placement
			(enabled no)
			(sheetname "")
		)
		(fill yes
			(thermal_gap 0.5)
			(thermal_bridge_width 0.5)
			(island_removal_mode 0)
		)
		(polygon
			(pts
				(arc
					(start 82.776314 -314.899802)
					(mid 82.123534 -314.899802)
					(end 82.776314 -314.899802)
				)
			)
		)
	)
	(zone
		(layers "B.Cu" "In13.Cu" "In15.Cu")
		(hatch none 0.5)
		(connect_pads
			(clearance 0)
		)
		(min_thickness 0.25)
		(keepout
			(tracks not_allowed)
			(vias allowed)
			(pads allowed)
			(copperpour not_allowed)
			(footprints allowed)
		)
		(placement
			(enabled no)
			(sheetname "")
		)
		(fill yes
			(thermal_gap 0.5)
			(thermal_bridge_width 0.5)
			(island_removal_mode 0)
		)
		(polygon
			(pts
				(arc
					(start 187.757054 -29.114242)
					(mid 187.053474 -29.114242)
					(end 187.757054 -29.114242)
				)
			)
		)
	)
	(zone
		(layers "B.Cu" "In13.Cu" "In15.Cu")
		(hatch none 0.5)
		(connect_pads
			(clearance 0)
		)
		(min_thickness 0.25)
		(keepout
			(tracks not_allowed)
			(vias allowed)
			(pads allowed)
			(copperpour not_allowed)
			(footprints allowed)
		)
		(placement
			(enabled no)
			(sheetname "")
		)
		(fill yes
			(thermal_gap 0.5)
			(thermal_bridge_width 0.5)
			(island_removal_mode 0)
		)
		(polygon
			(pts
				(arc
					(start 406.376378 -277.849838)
					(mid 405.723598 -277.849838)
					(end 406.376378 -277.849838)
				)
			)
		)
	)
	(zone
		(layers "B.Cu" "In13.Cu" "In15.Cu")
		(hatch none 0.5)
		(connect_pads
			(clearance 0)
		)
		(min_thickness 0.25)
		(keepout
			(tracks not_allowed)
			(vias allowed)
			(pads allowed)
			(copperpour not_allowed)
			(footprints allowed)
		)
		(placement
			(enabled no)
			(sheetname "")
		)
		(fill yes
			(thermal_gap 0.5)
			(thermal_bridge_width 0.5)
			(island_removal_mode 0)
		)
		(polygon
			(pts
				(arc
					(start 169.619422 -342.439498)
					(mid 168.915842 -342.439498)
					(end 169.619422 -342.439498)
				)
			)
		)
	)
	(zone
		(layers "B.Cu" "In13.Cu" "In15.Cu")
		(hatch none 0.5)
		(connect_pads
			(clearance 0)
		)
		(min_thickness 0.25)
		(keepout
			(tracks not_allowed)
			(vias allowed)
			(pads allowed)
			(copperpour not_allowed)
			(footprints allowed)
		)
		(placement
			(enabled no)
			(sheetname "")
		)
		(fill yes
			(thermal_gap 0.5)
			(thermal_bridge_width 0.5)
			(island_removal_mode 0)
		)
		(polygon
			(pts
				(arc
					(start 426.469556 -376.790204)
					(mid 425.710096 -376.790204)
					(end 426.469556 -376.790204)
				)
			)
		)
	)
	(zone
		(layers "B.Cu" "In13.Cu" "In15.Cu")
		(hatch none 0.5)
		(connect_pads
			(clearance 0)
		)
		(min_thickness 0.25)
		(keepout
			(tracks not_allowed)
			(vias allowed)
			(pads allowed)
			(copperpour not_allowed)
			(footprints allowed)
		)
		(placement
			(enabled no)
			(sheetname "")
		)
		(fill yes
			(thermal_gap 0.5)
			(thermal_bridge_width 0.5)
			(island_removal_mode 0)
		)
		(polygon
			(pts
				(arc
					(start 48.299116 -30.92069)
					(mid 47.595536 -30.92069)
					(end 48.299116 -30.92069)
				)
			)
		)
	)
	(zone
		(layers "B.Cu" "In13.Cu" "In15.Cu")
		(hatch none 0.5)
		(connect_pads
			(clearance 0)
		)
		(min_thickness 0.25)
		(keepout
			(tracks not_allowed)
			(vias allowed)
			(pads allowed)
			(copperpour not_allowed)
			(footprints allowed)
		)
		(placement
			(enabled no)
			(sheetname "")
		)
		(fill yes
			(thermal_gap 0.5)
			(thermal_bridge_width 0.5)
			(island_removal_mode 0)
		)
		(polygon
			(pts
				(arc
					(start 435.26964 -401.49018)
					(mid 434.51018 -401.49018)
					(end 435.26964 -401.49018)
				)
			)
		)
	)
	(zone
		(layers "B.Cu" "In13.Cu" "In15.Cu")
		(hatch none 0.5)
		(connect_pads
			(clearance 0)
		)
		(min_thickness 0.25)
		(keepout
			(tracks not_allowed)
			(vias allowed)
			(pads allowed)
			(copperpour not_allowed)
			(footprints allowed)
		)
		(placement
			(enabled no)
			(sheetname "")
		)
		(fill yes
			(thermal_gap 0.5)
			(thermal_bridge_width 0.5)
			(island_removal_mode 0)
		)
		(polygon
			(pts
				(arc
					(start 292.269672 -371.790214)
					(mid 291.510212 -371.790214)
					(end 292.269672 -371.790214)
				)
			)
		)
	)
	(zone
		(layers "B.Cu" "In13.Cu" "In15.Cu")
		(hatch none 0.5)
		(connect_pads
			(clearance 0)
		)
		(min_thickness 0.25)
		(keepout
			(tracks not_allowed)
			(vias allowed)
			(pads allowed)
			(copperpour not_allowed)
			(footprints allowed)
		)
		(placement
			(enabled no)
			(sheetname "")
		)
		(fill yes
			(thermal_gap 0.5)
			(thermal_bridge_width 0.5)
			(island_removal_mode 0)
		)
		(polygon
			(pts
				(arc
					(start 419.837362 -351.611438)
					(mid 419.133782 -351.611438)
					(end 419.837362 -351.611438)
				)
			)
		)
	)
	(zone
		(layers "B.Cu" "In13.Cu" "In15.Cu")
		(hatch none 0.5)
		(connect_pads
			(clearance 0)
		)
		(min_thickness 0.25)
		(keepout
			(tracks not_allowed)
			(vias allowed)
			(pads allowed)
			(copperpour not_allowed)
			(footprints allowed)
		)
		(placement
			(enabled no)
			(sheetname "")
		)
		(fill yes
			(thermal_gap 0.5)
			(thermal_bridge_width 0.5)
			(island_removal_mode 0)
		)
		(polygon
			(pts
				(arc
					(start 50.773838 -342.439498)
					(mid 50.070258 -342.439498)
					(end 50.773838 -342.439498)
				)
			)
		)
	)
	(zone
		(layers "B.Cu" "In13.Cu" "In15.Cu")
		(hatch none 0.5)
		(connect_pads
			(clearance 0)
		)
		(min_thickness 0.25)
		(keepout
			(tracks not_allowed)
			(vias allowed)
			(pads allowed)
			(copperpour not_allowed)
			(footprints allowed)
		)
		(placement
			(enabled no)
			(sheetname "")
		)
		(fill yes
			(thermal_gap 0.5)
			(thermal_bridge_width 0.5)
			(island_removal_mode 0)
		)
		(polygon
			(pts
				(arc
					(start 178.082702 -348.58579)
					(mid 177.379122 -348.58579)
					(end 178.082702 -348.58579)
				)
			)
		)
	)
	(zone
		(layers "B.Cu" "In13.Cu" "In15.Cu")
		(hatch none 0.5)
		(connect_pads
			(clearance 0)
		)
		(min_thickness 0.25)
		(keepout
			(tracks not_allowed)
			(vias allowed)
			(pads allowed)
			(copperpour not_allowed)
			(footprints allowed)
		)
		(placement
			(enabled no)
			(sheetname "")
		)
		(fill yes
			(thermal_gap 0.5)
			(thermal_bridge_width 0.5)
			(island_removal_mode 0)
		)
		(polygon
			(pts
				(arc
					(start 175.126396 -280.699718)
					(mid 174.473616 -280.699718)
					(end 175.126396 -280.699718)
				)
			)
		)
	)
	(zone
		(layers "B.Cu" "In13.Cu" "In15.Cu")
		(hatch none 0.5)
		(connect_pads
			(clearance 0)
		)
		(min_thickness 0.25)
		(keepout
			(tracks not_allowed)
			(vias allowed)
			(pads allowed)
			(copperpour not_allowed)
			(footprints allowed)
		)
		(placement
			(enabled no)
			(sheetname "")
		)
		(fill yes
			(thermal_gap 0.5)
			(thermal_bridge_width 0.5)
			(island_removal_mode 0)
		)
		(polygon
			(pts
				(arc
					(start 251.857002 -31.850584)
					(mid 251.153422 -31.850584)
					(end 251.857002 -31.850584)
				)
			)
		)
	)
	(zone
		(layers "B.Cu" "In13.Cu" "In15.Cu")
		(hatch none 0.5)
		(connect_pads
			(clearance 0)
		)
		(min_thickness 0.25)
		(keepout
			(tracks not_allowed)
			(vias allowed)
			(pads allowed)
			(copperpour not_allowed)
			(footprints allowed)
		)
		(placement
			(enabled no)
			(sheetname "")
		)
		(fill yes
			(thermal_gap 0.5)
			(thermal_bridge_width 0.5)
			(island_removal_mode 0)
		)
		(polygon
			(pts
				(arc
					(start 158.026354 -307.299868)
					(mid 157.373574 -307.299868)
					(end 158.026354 -307.299868)
				)
			)
		)
	)
	(zone
		(layers "B.Cu" "In13.Cu" "In15.Cu")
		(hatch none 0.5)
		(connect_pads
			(clearance 0)
		)
		(min_thickness 0.25)
		(keepout
			(tracks not_allowed)
			(vias allowed)
			(pads allowed)
			(copperpour not_allowed)
			(footprints allowed)
		)
		(placement
			(enabled no)
			(sheetname "")
		)
		(fill yes
			(thermal_gap 0.5)
			(thermal_bridge_width 0.5)
			(island_removal_mode 0)
		)
		(polygon
			(pts
				(arc
					(start 272.221452 -348.58579)
					(mid 271.517872 -348.58579)
					(end 272.221452 -348.58579)
				)
			)
		)
	)
	(zone
		(layers "B.Cu" "In13.Cu" "In15.Cu")
		(hatch none 0.5)
		(connect_pads
			(clearance 0)
		)
		(min_thickness 0.25)
		(keepout
			(tracks not_allowed)
			(vias allowed)
			(pads allowed)
			(copperpour not_allowed)
			(footprints allowed)
		)
		(placement
			(enabled no)
			(sheetname "")
		)
		(fill yes
			(thermal_gap 0.5)
			(thermal_bridge_width 0.5)
			(island_removal_mode 0)
		)
		(polygon
			(pts
				(arc
					(start 435.26964 -375.490232)
					(mid 434.51018 -375.490232)
					(end 435.26964 -375.490232)
				)
			)
		)
	)
	(zone
		(layers "B.Cu" "In13.Cu" "In15.Cu")
		(hatch none 0.5)
		(connect_pads
			(clearance 0)
		)
		(min_thickness 0.25)
		(keepout
			(tracks not_allowed)
			(vias allowed)
			(pads allowed)
			(copperpour not_allowed)
			(footprints allowed)
		)
		(placement
			(enabled no)
			(sheetname "")
		)
		(fill yes
			(thermal_gap 0.5)
			(thermal_bridge_width 0.5)
			(island_removal_mode 0)
		)
		(polygon
			(pts
				(arc
					(start 394.97635 -277.849838)
					(mid 394.32357 -277.849838)
					(end 394.97635 -277.849838)
				)
			)
		)
	)
	(zone
		(layers "B.Cu" "In13.Cu" "In15.Cu")
		(hatch none 0.5)
		(connect_pads
			(clearance 0)
		)
		(min_thickness 0.25)
		(keepout
			(tracks not_allowed)
			(vias allowed)
			(pads allowed)
			(copperpour not_allowed)
			(footprints allowed)
		)
		(placement
			(enabled no)
			(sheetname "")
		)
		(fill yes
			(thermal_gap 0.5)
			(thermal_bridge_width 0.5)
			(island_removal_mode 0)
		)
		(polygon
			(pts
				(arc
					(start 58.076338 -277.849838)
					(mid 57.423558 -277.849838)
					(end 58.076338 -277.849838)
				)
			)
		)
	)
	(zone
		(layers "B.Cu" "In13.Cu" "In15.Cu")
		(hatch none 0.5)
		(connect_pads
			(clearance 0)
		)
		(min_thickness 0.25)
		(keepout
			(tracks not_allowed)
			(vias allowed)
			(pads allowed)
			(copperpour not_allowed)
			(footprints allowed)
		)
		(placement
			(enabled no)
			(sheetname "")
		)
		(fill yes
			(thermal_gap 0.5)
			(thermal_bridge_width 0.5)
			(island_removal_mode 0)
		)
		(polygon
			(pts
				(arc
					(start 400.676364 -278.799798)
					(mid 400.023584 -278.799798)
					(end 400.676364 -278.799798)
				)
			)
		)
	)
	(zone
		(layers "B.Cu" "In13.Cu" "In15.Cu")
		(hatch none 0.5)
		(connect_pads
			(clearance 0)
		)
		(min_thickness 0.25)
		(keepout
			(tracks not_allowed)
			(vias allowed)
			(pads allowed)
			(copperpour not_allowed)
			(footprints allowed)
		)
		(placement
			(enabled no)
			(sheetname "")
		)
		(fill yes
			(thermal_gap 0.5)
			(thermal_bridge_width 0.5)
			(island_removal_mode 0)
		)
		(polygon
			(pts
				(arc
					(start 181.191662 -357.75773)
					(mid 180.488082 -357.75773)
					(end 181.191662 -357.75773)
				)
			)
		)
	)
	(zone
		(layers "B.Cu" "In13.Cu" "In15.Cu")
		(hatch none 0.5)
		(connect_pads
			(clearance 0)
		)
		(min_thickness 0.25)
		(keepout
			(tracks not_allowed)
			(vias allowed)
			(pads allowed)
			(copperpour not_allowed)
			(footprints allowed)
		)
		(placement
			(enabled no)
			(sheetname "")
		)
		(fill yes
			(thermal_gap 0.5)
			(thermal_bridge_width 0.5)
			(island_removal_mode 0)
		)
		(polygon
			(pts
				(arc
					(start 194.491102 -342.439498)
					(mid 193.787522 -342.439498)
					(end 194.491102 -342.439498)
				)
			)
		)
	)
	(zone
		(layers "B.Cu" "In13.Cu" "In15.Cu")
		(hatch none 0.5)
		(connect_pads
			(clearance 0)
		)
		(min_thickness 0.25)
		(keepout
			(tracks not_allowed)
			(vias allowed)
			(pads allowed)
			(copperpour not_allowed)
			(footprints allowed)
		)
		(placement
			(enabled no)
			(sheetname "")
		)
		(fill yes
			(thermal_gap 0.5)
			(thermal_bridge_width 0.5)
			(island_removal_mode 0)
		)
		(polygon
			(pts
				(arc
					(start 190.399162 -34.520886)
					(mid 189.695582 -34.520886)
					(end 190.399162 -34.520886)
				)
			)
		)
	)
	(zone
		(layers "B.Cu" "In13.Cu" "In15.Cu")
		(hatch none 0.5)
		(connect_pads
			(clearance 0)
		)
		(min_thickness 0.25)
		(keepout
			(tracks not_allowed)
			(vias allowed)
			(pads allowed)
			(copperpour not_allowed)
			(footprints allowed)
		)
		(placement
			(enabled no)
			(sheetname "")
		)
		(fill yes
			(thermal_gap 0.5)
			(thermal_bridge_width 0.5)
			(island_removal_mode 0)
		)
		(polygon
			(pts
				(arc
					(start 389.276336 -313.949842)
					(mid 388.623556 -313.949842)
					(end 389.276336 -313.949842)
				)
			)
		)
	)
	(zone
		(layers "B.Cu" "In13.Cu" "In15.Cu")
		(hatch none 0.5)
		(connect_pads
			(clearance 0)
		)
		(min_thickness 0.25)
		(keepout
			(tracks not_allowed)
			(vias allowed)
			(pads allowed)
			(copperpour not_allowed)
			(footprints allowed)
		)
		(placement
			(enabled no)
			(sheetname "")
		)
		(fill yes
			(thermal_gap 0.5)
			(thermal_bridge_width 0.5)
			(island_removal_mode 0)
		)
		(polygon
			(pts
				(arc
					(start 445.956944 -32.714184)
					(mid 445.253364 -32.714184)
					(end 445.956944 -32.714184)
				)
			)
		)
	)
	(zone
		(layers "B.Cu" "In13.Cu" "In15.Cu")
		(hatch none 0.5)
		(connect_pads
			(clearance 0)
		)
		(min_thickness 0.25)
		(keepout
			(tracks not_allowed)
			(vias allowed)
			(pads allowed)
			(copperpour not_allowed)
			(footprints allowed)
		)
		(placement
			(enabled no)
			(sheetname "")
		)
		(fill yes
			(thermal_gap 0.5)
			(thermal_bridge_width 0.5)
			(island_removal_mode 0)
		)
		(polygon
			(pts
				(arc
					(start 404.476204 -278.799798)
					(mid 403.823424 -278.799798)
					(end 404.476204 -278.799798)
				)
			)
		)
	)
	(zone
		(layers "B.Cu" "In13.Cu" "In15.Cu")
		(hatch none 0.5)
		(connect_pads
			(clearance 0)
		)
		(min_thickness 0.25)
		(keepout
			(tracks not_allowed)
			(vias allowed)
			(pads allowed)
			(copperpour not_allowed)
			(footprints allowed)
		)
		(placement
			(enabled no)
			(sheetname "")
		)
		(fill yes
			(thermal_gap 0.5)
			(thermal_bridge_width 0.5)
			(island_removal_mode 0)
		)
		(polygon
			(pts
				(arc
					(start 44.555918 -357.75773)
					(mid 43.852338 -357.75773)
					(end 44.555918 -357.75773)
				)
			)
		)
	)
	(zone
		(layers "B.Cu" "In13.Cu" "In15.Cu")
		(hatch none 0.5)
		(connect_pads
			(clearance 0)
		)
		(min_thickness 0.25)
		(keepout
			(tracks not_allowed)
			(vias allowed)
			(pads allowed)
			(copperpour not_allowed)
			(footprints allowed)
		)
		(placement
			(enabled no)
			(sheetname "")
		)
		(fill yes
			(thermal_gap 0.5)
			(thermal_bridge_width 0.5)
			(island_removal_mode 0)
		)
		(polygon
			(pts
				(arc
					(start 393.076176 -304.449734)
					(mid 392.423396 -304.449734)
					(end 393.076176 -304.449734)
				)
			)
		)
	)
	(zone
		(layers "B.Cu" "In13.Cu" "In15.Cu")
		(hatch none 0.5)
		(connect_pads
			(clearance 0)
		)
		(min_thickness 0.25)
		(keepout
			(tracks not_allowed)
			(vias allowed)
			(pads allowed)
			(copperpour not_allowed)
			(footprints allowed)
		)
		(placement
			(enabled no)
			(sheetname "")
		)
		(fill yes
			(thermal_gap 0.5)
			(thermal_bridge_width 0.5)
			(island_removal_mode 0)
		)
		(polygon
			(pts
				(arc
					(start 280.684732 -345.465146)
					(mid 279.981152 -345.465146)
					(end 280.684732 -345.465146)
				)
			)
		)
	)
	(zone
		(layers "B.Cu" "In13.Cu" "In15.Cu")
		(hatch none 0.5)
		(connect_pads
			(clearance 0)
		)
		(min_thickness 0.25)
		(keepout
			(tracks not_allowed)
			(vias allowed)
			(pads allowed)
			(copperpour not_allowed)
			(footprints allowed)
		)
		(placement
			(enabled no)
			(sheetname "")
		)
		(fill yes
			(thermal_gap 0.5)
			(thermal_bridge_width 0.5)
			(island_removal_mode 0)
		)
		(polygon
			(pts
				(arc
					(start 299.338492 -342.439498)
					(mid 298.634912 -342.439498)
					(end 299.338492 -342.439498)
				)
			)
		)
	)
	(zone
		(layers "B.Cu" "In13.Cu" "In15.Cu")
		(hatch none 0.5)
		(connect_pads
			(clearance 0)
		)
		(min_thickness 0.25)
		(keepout
			(tracks not_allowed)
			(vias allowed)
			(pads allowed)
			(copperpour not_allowed)
			(footprints allowed)
		)
		(placement
			(enabled no)
			(sheetname "")
		)
		(fill yes
			(thermal_gap 0.5)
			(thermal_bridge_width 0.5)
			(island_removal_mode 0)
		)
		(polygon
			(pts
				(arc
					(start 162.537902 -354.732082)
					(mid 161.834322 -354.732082)
					(end 162.537902 -354.732082)
				)
			)
		)
	)
	(zone
		(layers "B.Cu" "In13.Cu" "In15.Cu")
		(hatch none 0.5)
		(connect_pads
			(clearance 0)
		)
		(min_thickness 0.25)
		(keepout
			(tracks not_allowed)
			(vias allowed)
			(pads allowed)
			(copperpour not_allowed)
			(footprints allowed)
		)
		(placement
			(enabled no)
			(sheetname "")
		)
		(fill yes
			(thermal_gap 0.5)
			(thermal_bridge_width 0.5)
			(island_removal_mode 0)
		)
		(polygon
			(pts
				(arc
					(start 32.6898 -370.489988)
					(mid 31.93034 -370.489988)
					(end 32.6898 -370.489988)
				)
			)
		)
	)
	(zone
		(layers "B.Cu" "In13.Cu" "In15.Cu")
		(hatch none 0.5)
		(connect_pads
			(clearance 0)
		)
		(min_thickness 0.25)
		(keepout
			(tracks not_allowed)
			(vias allowed)
			(pads allowed)
			(copperpour not_allowed)
			(footprints allowed)
		)
		(placement
			(enabled no)
			(sheetname "")
		)
		(fill yes
			(thermal_gap 0.5)
			(thermal_bridge_width 0.5)
			(island_removal_mode 0)
		)
		(polygon
			(pts
				(arc
					(start 184.300622 -351.611438)
					(mid 183.597042 -351.611438)
					(end 184.300622 -351.611438)
				)
			)
		)
	)
	(zone
		(layers "B.Cu" "In13.Cu" "In15.Cu")
		(hatch none 0.5)
		(connect_pads
			(clearance 0)
		)
		(min_thickness 0.25)
		(keepout
			(tracks not_allowed)
			(vias allowed)
			(pads allowed)
			(copperpour not_allowed)
			(footprints allowed)
		)
		(placement
			(enabled no)
			(sheetname "")
		)
		(fill yes
			(thermal_gap 0.5)
			(thermal_bridge_width 0.5)
			(island_removal_mode 0)
		)
		(polygon
			(pts
				(arc
					(start 160.876234 -306.349908)
					(mid 160.223454 -306.349908)
					(end 160.876234 -306.349908)
				)
			)
		)
	)
	(zone
		(layers "B.Cu" "In13.Cu" "In15.Cu")
		(hatch none 0.5)
		(connect_pads
			(clearance 0)
		)
		(min_thickness 0.25)
		(keepout
			(tracks not_allowed)
			(vias allowed)
			(pads allowed)
			(copperpour not_allowed)
			(footprints allowed)
		)
		(placement
			(enabled no)
			(sheetname "")
		)
		(fill yes
			(thermal_gap 0.5)
			(thermal_bridge_width 0.5)
			(island_removal_mode 0)
		)
		(polygon
			(pts
				(arc
					(start 30.489652 -371.590062)
					(mid 29.730192 -371.590062)
					(end 30.489652 -371.590062)
				)
			)
		)
	)
	(zone
		(layers "B.Cu" "In13.Cu" "In15.Cu")
		(hatch none 0.5)
		(connect_pads
			(clearance 0)
		)
		(min_thickness 0.25)
		(keepout
			(tracks not_allowed)
			(vias allowed)
			(pads allowed)
			(copperpour not_allowed)
			(footprints allowed)
		)
		(placement
			(enabled no)
			(sheetname "")
		)
		(fill yes
			(thermal_gap 0.5)
			(thermal_bridge_width 0.5)
			(island_removal_mode 0)
		)
		(polygon
			(pts
				(arc
					(start 437.627522 -351.611438)
					(mid 436.923942 -351.611438)
					(end 437.627522 -351.611438)
				)
			)
		)
	)
	(zone
		(layers "B.Cu" "In13.Cu" "In15.Cu")
		(hatch none 0.5)
		(connect_pads
			(clearance 0)
		)
		(min_thickness 0.25)
		(keepout
			(tracks not_allowed)
			(vias allowed)
			(pads allowed)
			(copperpour not_allowed)
			(footprints allowed)
		)
		(placement
			(enabled no)
			(sheetname "")
		)
		(fill yes
			(thermal_gap 0.5)
			(thermal_bridge_width 0.5)
			(island_removal_mode 0)
		)
		(polygon
			(pts
				(arc
					(start 367.9571 -31.850584)
					(mid 367.25352 -31.850584)
					(end 367.9571 -31.850584)
				)
			)
		)
	)
	(zone
		(layers "B.Cu" "In13.Cu" "In15.Cu")
		(hatch none 0.5)
		(connect_pads
			(clearance 0)
		)
		(min_thickness 0.25)
		(keepout
			(tracks not_allowed)
			(vias allowed)
			(pads allowed)
			(copperpour not_allowed)
			(footprints allowed)
		)
		(placement
			(enabled no)
			(sheetname "")
		)
		(fill yes
			(thermal_gap 0.5)
			(thermal_bridge_width 0.5)
			(island_removal_mode 0)
		)
		(polygon
			(pts
				(arc
					(start 75.17638 -308.249828)
					(mid 74.5236 -308.249828)
					(end 75.17638 -308.249828)
				)
			)
		)
	)
	(zone
		(layers "B.Cu" "In13.Cu" "In15.Cu")
		(hatch none 0.5)
		(connect_pads
			(clearance 0)
		)
		(min_thickness 0.25)
		(keepout
			(tracks not_allowed)
			(vias allowed)
			(pads allowed)
			(copperpour not_allowed)
			(footprints allowed)
		)
		(placement
			(enabled no)
			(sheetname "")
		)
		(fill yes
			(thermal_gap 0.5)
			(thermal_bridge_width 0.5)
			(island_removal_mode 0)
		)
		(polygon
			(pts
				(arc
					(start 161.757106 -32.714184)
					(mid 161.053526 -32.714184)
					(end 161.757106 -32.714184)
				)
			)
		)
	)
	(zone
		(layers "B.Cu" "In13.Cu" "In15.Cu")
		(hatch none 0.5)
		(connect_pads
			(clearance 0)
		)
		(min_thickness 0.25)
		(keepout
			(tracks not_allowed)
			(vias allowed)
			(pads allowed)
			(copperpour not_allowed)
			(footprints allowed)
		)
		(placement
			(enabled no)
			(sheetname "")
		)
		(fill yes
			(thermal_gap 0.5)
			(thermal_bridge_width 0.5)
			(island_removal_mode 0)
		)
		(polygon
			(pts
				(arc
					(start 48.528478 -348.58579)
					(mid 47.824898 -348.58579)
					(end 48.528478 -348.58579)
				)
			)
		)
	)
	(zone
		(layers "B.Cu" "In13.Cu" "In15.Cu")
		(hatch none 0.5)
		(connect_pads
			(clearance 0)
		)
		(min_thickness 0.25)
		(keepout
			(tracks not_allowed)
			(vias allowed)
			(pads allowed)
			(copperpour not_allowed)
			(footprints allowed)
		)
		(placement
			(enabled no)
			(sheetname "")
		)
		(fill yes
			(thermal_gap 0.5)
			(thermal_bridge_width 0.5)
			(island_removal_mode 0)
		)
		(polygon
			(pts
				(arc
					(start 34.889694 -371.590062)
					(mid 34.130234 -371.590062)
					(end 34.889694 -371.590062)
				)
			)
		)
	)
	(zone
		(layers "B.Cu" "In13.Cu" "In15.Cu")
		(hatch none 0.5)
		(connect_pads
			(clearance 0)
		)
		(min_thickness 0.25)
		(keepout
			(tracks not_allowed)
			(vias allowed)
			(pads allowed)
			(copperpour not_allowed)
			(footprints allowed)
		)
		(placement
			(enabled no)
			(sheetname "")
		)
		(fill yes
			(thermal_gap 0.5)
			(thermal_bridge_width 0.5)
			(island_removal_mode 0)
		)
		(polygon
			(pts
				(arc
					(start 171.864782 -348.58579)
					(mid 171.161202 -348.58579)
					(end 171.864782 -348.58579)
				)
			)
		)
	)
	(zone
		(layers "B.Cu" "In13.Cu" "In15.Cu")
		(hatch none 0.5)
		(connect_pads
			(clearance 0)
		)
		(min_thickness 0.25)
		(keepout
			(tracks not_allowed)
			(vias allowed)
			(pads allowed)
			(copperpour not_allowed)
			(footprints allowed)
		)
		(placement
			(enabled no)
			(sheetname "")
		)
		(fill yes
			(thermal_gap 0.5)
			(thermal_bridge_width 0.5)
			(island_removal_mode 0)
		)
		(polygon
			(pts
				(arc
					(start 416.728402 -357.75773)
					(mid 416.024822 -357.75773)
					(end 416.728402 -357.75773)
				)
			)
		)
	)
	(zone
		(layers "B.Cu" "In13.Cu" "In15.Cu")
		(hatch none 0.5)
		(connect_pads
			(clearance 0)
		)
		(min_thickness 0.25)
		(keepout
			(tracks not_allowed)
			(vias allowed)
			(pads allowed)
			(copperpour not_allowed)
			(footprints allowed)
		)
		(placement
			(enabled no)
			(sheetname "")
		)
		(fill yes
			(thermal_gap 0.5)
			(thermal_bridge_width 0.5)
			(island_removal_mode 0)
		)
		(polygon
			(pts
				(arc
					(start 171.289726 -375.490232)
					(mid 170.530266 -375.490232)
					(end 171.289726 -375.490232)
				)
			)
		)
	)
	(zone
		(layers "B.Cu" "In13.Cu" "In15.Cu")
		(hatch none 0.5)
		(connect_pads
			(clearance 0)
		)
		(min_thickness 0.25)
		(keepout
			(tracks not_allowed)
			(vias allowed)
			(pads allowed)
			(copperpour not_allowed)
			(footprints allowed)
		)
		(placement
			(enabled no)
			(sheetname "")
		)
		(fill yes
			(thermal_gap 0.5)
			(thermal_bridge_width 0.5)
			(island_removal_mode 0)
		)
		(polygon
			(pts
				(arc
					(start 154.22626 -314.899802)
					(mid 153.57348 -314.899802)
					(end 154.22626 -314.899802)
				)
			)
		)
	)
	(zone
		(layers "B.Cu" "In13.Cu" "In15.Cu")
		(hatch none 0.5)
		(connect_pads
			(clearance 0)
		)
		(min_thickness 0.25)
		(keepout
			(tracks not_allowed)
			(vias allowed)
			(pads allowed)
			(copperpour not_allowed)
			(footprints allowed)
		)
		(placement
			(enabled no)
			(sheetname "")
		)
		(fill yes
			(thermal_gap 0.5)
			(thermal_bridge_width 0.5)
			(island_removal_mode 0)
		)
		(polygon
			(pts
				(arc
					(start 178.946302 -348.58579)
					(mid 178.242722 -348.58579)
					(end 178.946302 -348.58579)
				)
			)
		)
	)
	(zone
		(layers "B.Cu" "In13.Cu" "In15.Cu")
		(hatch none 0.5)
		(connect_pads
			(clearance 0)
		)
		(min_thickness 0.25)
		(keepout
			(tracks not_allowed)
			(vias allowed)
			(pads allowed)
			(copperpour not_allowed)
			(footprints allowed)
		)
		(placement
			(enabled no)
			(sheetname "")
		)
		(fill yes
			(thermal_gap 0.5)
			(thermal_bridge_width 0.5)
			(island_removal_mode 0)
		)
		(polygon
			(pts
				(arc
					(start 299.338492 -354.732082)
					(mid 298.634912 -354.732082)
					(end 299.338492 -354.732082)
				)
			)
		)
	)
	(zone
		(layers "B.Cu" "In13.Cu" "In15.Cu")
		(hatch none 0.5)
		(connect_pads
			(clearance 0)
		)
		(min_thickness 0.25)
		(keepout
			(tracks not_allowed)
			(vias allowed)
			(pads allowed)
			(copperpour not_allowed)
			(footprints allowed)
		)
		(placement
			(enabled no)
			(sheetname "")
		)
		(fill yes
			(thermal_gap 0.5)
			(thermal_bridge_width 0.5)
			(island_removal_mode 0)
		)
		(polygon
			(pts
				(arc
					(start 387.376416 -313.949842)
					(mid 386.723636 -313.949842)
					(end 387.376416 -313.949842)
				)
			)
		)
	)
	(zone
		(layers "B.Cu" "In13.Cu" "In15.Cu")
		(hatch none 0.5)
		(connect_pads
			(clearance 0)
		)
		(min_thickness 0.25)
		(keepout
			(tracks not_allowed)
			(vias allowed)
			(pads allowed)
			(copperpour not_allowed)
			(footprints allowed)
		)
		(placement
			(enabled no)
			(sheetname "")
		)
		(fill yes
			(thermal_gap 0.5)
			(thermal_bridge_width 0.5)
			(island_removal_mode 0)
		)
		(polygon
			(pts
				(arc
					(start 254.49911 -34.520886)
					(mid 253.79553 -34.520886)
					(end 254.49911 -34.520886)
				)
			)
		)
	)
	(zone
		(layers "B.Cu" "In13.Cu" "In15.Cu")
		(hatch none 0.5)
		(connect_pads
			(clearance 0)
		)
		(min_thickness 0.25)
		(keepout
			(tracks not_allowed)
			(vias allowed)
			(pads allowed)
			(copperpour not_allowed)
			(footprints allowed)
		)
		(placement
			(enabled no)
			(sheetname "")
		)
		(fill yes
			(thermal_gap 0.5)
			(thermal_bridge_width 0.5)
			(island_removal_mode 0)
		)
		(polygon
			(pts
				(arc
					(start 332.498954 -33.657286)
					(mid 331.795374 -33.657286)
					(end 332.498954 -33.657286)
				)
			)
		)
	)
	(zone
		(layers "B.Cu" "In13.Cu" "In15.Cu")
		(hatch none 0.5)
		(connect_pads
			(clearance 0)
		)
		(min_thickness 0.25)
		(keepout
			(tracks not_allowed)
			(vias allowed)
			(pads allowed)
			(copperpour not_allowed)
			(footprints allowed)
		)
		(placement
			(enabled no)
			(sheetname "")
		)
		(fill yes
			(thermal_gap 0.5)
			(thermal_bridge_width 0.5)
			(island_removal_mode 0)
		)
		(polygon
			(pts
				(arc
					(start 415.864802 -354.732082)
					(mid 415.161222 -354.732082)
					(end 415.864802 -354.732082)
				)
			)
		)
	)
	(zone
		(layers "B.Cu" "In13.Cu" "In15.Cu")
		(hatch none 0.5)
		(connect_pads
			(clearance 0)
		)
		(min_thickness 0.25)
		(keepout
			(tracks not_allowed)
			(vias allowed)
			(pads allowed)
			(copperpour not_allowed)
			(footprints allowed)
		)
		(placement
			(enabled no)
			(sheetname "")
		)
		(fill yes
			(thermal_gap 0.5)
			(thermal_bridge_width 0.5)
			(island_removal_mode 0)
		)
		(polygon
			(pts
				(arc
					(start 387.376416 -312.999882)
					(mid 386.723636 -312.999882)
					(end 387.376416 -312.999882)
				)
			)
		)
	)
	(zone
		(layers "B.Cu" "In13.Cu" "In15.Cu")
		(hatch none 0.5)
		(connect_pads
			(clearance 0)
		)
		(min_thickness 0.25)
		(keepout
			(tracks not_allowed)
			(vias allowed)
			(pads allowed)
			(copperpour not_allowed)
			(footprints allowed)
		)
		(placement
			(enabled no)
			(sheetname "")
		)
		(fill yes
			(thermal_gap 0.5)
			(thermal_bridge_width 0.5)
			(island_removal_mode 0)
		)
		(polygon
			(pts
				(arc
					(start 161.826448 -280.699718)
					(mid 161.173668 -280.699718)
					(end 161.826448 -280.699718)
				)
			)
		)
	)
	(zone
		(layers "B.Cu" "In13.Cu" "In15.Cu")
		(hatch none 0.5)
		(connect_pads
			(clearance 0)
		)
		(min_thickness 0.25)
		(keepout
			(tracks not_allowed)
			(vias allowed)
			(pads allowed)
			(copperpour not_allowed)
			(footprints allowed)
		)
		(placement
			(enabled no)
			(sheetname "")
		)
		(fill yes
			(thermal_gap 0.5)
			(thermal_bridge_width 0.5)
			(island_removal_mode 0)
		)
		(polygon
			(pts
				(arc
					(start 34.889694 -372.890034)
					(mid 34.130234 -372.890034)
					(end 34.889694 -372.890034)
				)
			)
		)
	)
	(zone
		(layers "B.Cu" "In13.Cu" "In15.Cu")
		(hatch none 0.5)
		(connect_pads
			(clearance 0)
		)
		(min_thickness 0.25)
		(keepout
			(tracks not_allowed)
			(vias allowed)
			(pads allowed)
			(copperpour not_allowed)
			(footprints allowed)
		)
		(placement
			(enabled no)
			(sheetname "")
		)
		(fill yes
			(thermal_gap 0.5)
			(thermal_bridge_width 0.5)
			(island_removal_mode 0)
		)
		(polygon
			(pts
				(arc
					(start 32.120078 -354.732082)
					(mid 31.416498 -354.732082)
					(end 32.120078 -354.732082)
				)
			)
		)
	)
	(zone
		(layers "B.Cu" "In13.Cu" "In15.Cu")
		(hatch none 0.5)
		(connect_pads
			(clearance 0)
		)
		(min_thickness 0.25)
		(keepout
			(tracks not_allowed)
			(vias allowed)
			(pads allowed)
			(copperpour not_allowed)
			(footprints allowed)
		)
		(placement
			(enabled no)
			(sheetname "")
		)
		(fill yes
			(thermal_gap 0.5)
			(thermal_bridge_width 0.5)
			(island_removal_mode 0)
		)
		(polygon
			(pts
				(arc
					(start 433.069492 -400.390106)
					(mid 432.310032 -400.390106)
					(end 433.069492 -400.390106)
				)
			)
		)
	)
	(zone
		(layers "B.Cu" "In13.Cu" "In15.Cu")
		(hatch none 0.5)
		(connect_pads
			(clearance 0)
		)
		(min_thickness 0.25)
		(keepout
			(tracks not_allowed)
			(vias allowed)
			(pads allowed)
			(copperpour not_allowed)
			(footprints allowed)
		)
		(placement
			(enabled no)
			(sheetname "")
		)
		(fill yes
			(thermal_gap 0.5)
			(thermal_bridge_width 0.5)
			(island_removal_mode 0)
		)
		(polygon
			(pts
				(arc
					(start 308.326282 -306.349908)
					(mid 307.673502 -306.349908)
					(end 308.326282 -306.349908)
				)
			)
		)
	)
	(zone
		(layers "B.Cu" "In13.Cu" "In15.Cu")
		(hatch none 0.5)
		(connect_pads
			(clearance 0)
		)
		(min_thickness 0.25)
		(keepout
			(tracks not_allowed)
			(vias allowed)
			(pads allowed)
			(copperpour not_allowed)
			(footprints allowed)
		)
		(placement
			(enabled no)
			(sheetname "")
		)
		(fill yes
			(thermal_gap 0.5)
			(thermal_bridge_width 0.5)
			(island_removal_mode 0)
		)
		(polygon
			(pts
				(arc
					(start 279.826212 -280.699718)
					(mid 279.173432 -280.699718)
					(end 279.826212 -280.699718)
				)
			)
		)
	)
	(zone
		(layers "B.Cu" "In13.Cu" "In15.Cu")
		(hatch none 0.5)
		(connect_pads
			(clearance 0)
		)
		(min_thickness 0.25)
		(keepout
			(tracks not_allowed)
			(vias allowed)
			(pads allowed)
			(copperpour not_allowed)
			(footprints allowed)
		)
		(placement
			(enabled no)
			(sheetname "")
		)
		(fill yes
			(thermal_gap 0.5)
			(thermal_bridge_width 0.5)
			(island_removal_mode 0)
		)
		(polygon
			(pts
				(arc
					(start 187.757054 -28.250642)
					(mid 187.053474 -28.250642)
					(end 187.757054 -28.250642)
				)
			)
		)
	)
	(zone
		(layers "B.Cu" "In13.Cu" "In15.Cu")
		(hatch none 0.5)
		(connect_pads
			(clearance 0)
		)
		(min_thickness 0.25)
		(keepout
			(tracks not_allowed)
			(vias allowed)
			(pads allowed)
			(copperpour not_allowed)
			(footprints allowed)
		)
		(placement
			(enabled no)
			(sheetname "")
		)
		(fill yes
			(thermal_gap 0.5)
			(thermal_bridge_width 0.5)
			(island_removal_mode 0)
		)
		(polygon
			(pts
				(arc
					(start 434.518562 -345.465146)
					(mid 433.814982 -345.465146)
					(end 434.518562 -345.465146)
				)
			)
		)
	)
	(zone
		(layers "B.Cu" "In13.Cu" "In15.Cu")
		(hatch none 0.5)
		(connect_pads
			(clearance 0)
		)
		(min_thickness 0.25)
		(keepout
			(tracks not_allowed)
			(vias allowed)
			(pads allowed)
			(copperpour not_allowed)
			(footprints allowed)
		)
		(placement
			(enabled no)
			(sheetname "")
		)
		(fill yes
			(thermal_gap 0.5)
			(thermal_bridge_width 0.5)
			(island_removal_mode 0)
		)
		(polygon
			(pts
				(arc
					(start 45.657008 -31.850584)
					(mid 44.953428 -31.850584)
					(end 45.657008 -31.850584)
				)
			)
		)
	)
	(zone
		(layers "B.Cu" "In13.Cu" "In15.Cu")
		(hatch none 0.5)
		(connect_pads
			(clearance 0)
		)
		(min_thickness 0.25)
		(keepout
			(tracks not_allowed)
			(vias allowed)
			(pads allowed)
			(copperpour not_allowed)
			(footprints allowed)
		)
		(placement
			(enabled no)
			(sheetname "")
		)
		(fill yes
			(thermal_gap 0.5)
			(thermal_bridge_width 0.5)
			(island_removal_mode 0)
		)
		(polygon
			(pts
				(arc
					(start 45.419518 -354.732082)
					(mid 44.715938 -354.732082)
					(end 45.419518 -354.732082)
				)
			)
		)
	)
	(zone
		(layers "B.Cu" "In13.Cu" "In15.Cu")
		(hatch none 0.5)
		(connect_pads
			(clearance 0)
		)
		(min_thickness 0.25)
		(keepout
			(tracks not_allowed)
			(vias allowed)
			(pads allowed)
			(copperpour not_allowed)
			(footprints allowed)
		)
		(placement
			(enabled no)
			(sheetname "")
		)
		(fill yes
			(thermal_gap 0.5)
			(thermal_bridge_width 0.5)
			(island_removal_mode 0)
		)
		(polygon
			(pts
				(arc
					(start 291.22624 -279.749504)
					(mid 290.57346 -279.749504)
					(end 291.22624 -279.749504)
				)
			)
		)
	)
	(zone
		(layers "B.Cu" "In13.Cu" "In15.Cu")
		(hatch none 0.5)
		(connect_pads
			(clearance 0)
		)
		(min_thickness 0.25)
		(keepout
			(tracks not_allowed)
			(vias allowed)
			(pads allowed)
			(copperpour not_allowed)
			(footprints allowed)
		)
		(placement
			(enabled no)
			(sheetname "")
		)
		(fill yes
			(thermal_gap 0.5)
			(thermal_bridge_width 0.5)
			(island_removal_mode 0)
		)
		(polygon
			(pts
				(arc
					(start 395.92631 -279.749504)
					(mid 395.27353 -279.749504)
					(end 395.92631 -279.749504)
				)
			)
		)
	)
	(zone
		(layers "B.Cu" "In13.Cu" "In15.Cu")
		(hatch none 0.5)
		(connect_pads
			(clearance 0)
		)
		(min_thickness 0.25)
		(keepout
			(tracks not_allowed)
			(vias allowed)
			(pads allowed)
			(copperpour not_allowed)
			(footprints allowed)
		)
		(placement
			(enabled no)
			(sheetname "")
		)
		(fill yes
			(thermal_gap 0.5)
			(thermal_bridge_width 0.5)
			(island_removal_mode 0)
		)
		(polygon
			(pts
				(arc
					(start 309.276242 -305.399948)
					(mid 308.623462 -305.399948)
					(end 309.276242 -305.399948)
				)
			)
		)
	)
	(zone
		(layers "B.Cu" "In13.Cu" "In15.Cu")
		(hatch none 0.5)
		(connect_pads
			(clearance 0)
		)
		(min_thickness 0.25)
		(keepout
			(tracks not_allowed)
			(vias allowed)
			(pads allowed)
			(copperpour not_allowed)
			(footprints allowed)
		)
		(placement
			(enabled no)
			(sheetname "")
		)
		(fill yes
			(thermal_gap 0.5)
			(thermal_bridge_width 0.5)
			(island_removal_mode 0)
		)
		(polygon
			(pts
				(arc
					(start 77.0763 -312.999882)
					(mid 76.42352 -312.999882)
					(end 77.0763 -312.999882)
				)
			)
		)
	)
	(zone
		(layers "B.Cu" "In13.Cu" "In15.Cu")
		(hatch none 0.5)
		(connect_pads
			(clearance 0)
		)
		(min_thickness 0.25)
		(keepout
			(tracks not_allowed)
			(vias allowed)
			(pads allowed)
			(copperpour not_allowed)
			(footprints allowed)
		)
		(placement
			(enabled no)
			(sheetname "")
		)
		(fill yes
			(thermal_gap 0.5)
			(thermal_bridge_width 0.5)
			(island_removal_mode 0)
		)
		(polygon
			(pts
				(arc
					(start 45.657008 -28.250642)
					(mid 44.953428 -28.250642)
					(end 45.657008 -28.250642)
				)
			)
		)
	)
	(zone
		(layers "B.Cu" "In13.Cu" "In15.Cu")
		(hatch none 0.5)
		(connect_pads
			(clearance 0)
		)
		(min_thickness 0.25)
		(keepout
			(tracks not_allowed)
			(vias allowed)
			(pads allowed)
			(copperpour not_allowed)
			(footprints allowed)
		)
		(placement
			(enabled no)
			(sheetname "")
		)
		(fill yes
			(thermal_gap 0.5)
			(thermal_bridge_width 0.5)
			(island_removal_mode 0)
		)
		(polygon
			(pts
				(arc
					(start 182.055262 -342.439498)
					(mid 181.351682 -342.439498)
					(end 182.055262 -342.439498)
				)
			)
		)
	)
	(zone
		(layers "B.Cu" "In13.Cu" "In15.Cu")
		(hatch none 0.5)
		(connect_pads
			(clearance 0)
		)
		(min_thickness 0.25)
		(keepout
			(tracks not_allowed)
			(vias allowed)
			(pads allowed)
			(copperpour not_allowed)
			(footprints allowed)
		)
		(placement
			(enabled no)
			(sheetname "")
		)
		(fill yes
			(thermal_gap 0.5)
			(thermal_bridge_width 0.5)
			(island_removal_mode 0)
		)
		(polygon
			(pts
				(arc
					(start 172.276262 -277.849838)
					(mid 171.623482 -277.849838)
					(end 172.276262 -277.849838)
				)
			)
		)
	)
	(zone
		(layers "B.Cu" "In13.Cu" "In15.Cu")
		(hatch none 0.5)
		(connect_pads
			(clearance 0)
		)
		(min_thickness 0.25)
		(keepout
			(tracks not_allowed)
			(vias allowed)
			(pads allowed)
			(copperpour not_allowed)
			(footprints allowed)
		)
		(placement
			(enabled no)
			(sheetname "")
		)
		(fill yes
			(thermal_gap 0.5)
			(thermal_bridge_width 0.5)
			(island_removal_mode 0)
		)
		(polygon
			(pts
				(arc
					(start 26.765758 -342.439498)
					(mid 26.062178 -342.439498)
					(end 26.765758 -342.439498)
				)
			)
		)
	)
	(zone
		(layers "B.Cu" "In13.Cu" "In15.Cu")
		(hatch none 0.5)
		(connect_pads
			(clearance 0)
		)
		(min_thickness 0.25)
		(keepout
			(tracks not_allowed)
			(vias allowed)
			(pads allowed)
			(copperpour not_allowed)
			(footprints allowed)
		)
		(placement
			(enabled no)
			(sheetname "")
		)
		(fill yes
			(thermal_gap 0.5)
			(thermal_bridge_width 0.5)
			(island_removal_mode 0)
		)
		(polygon
			(pts
				(arc
					(start 190.399162 -30.92069)
					(mid 189.695582 -30.92069)
					(end 190.399162 -30.92069)
				)
			)
		)
	)
	(zone
		(layers "B.Cu" "In13.Cu" "In15.Cu")
		(hatch none 0.5)
		(connect_pads
			(clearance 0)
		)
		(min_thickness 0.25)
		(keepout
			(tracks not_allowed)
			(vias allowed)
			(pads allowed)
			(copperpour not_allowed)
			(footprints allowed)
		)
		(placement
			(enabled no)
			(sheetname "")
		)
		(fill yes
			(thermal_gap 0.5)
			(thermal_bridge_width 0.5)
			(island_removal_mode 0)
		)
		(polygon
			(pts
				(arc
					(start 19.684238 -345.465146)
					(mid 18.980658 -345.465146)
					(end 19.684238 -345.465146)
				)
			)
		)
	)
	(zone
		(layers "B.Cu" "In13.Cu" "In15.Cu")
		(hatch none 0.5)
		(connect_pads
			(clearance 0)
		)
		(min_thickness 0.25)
		(keepout
			(tracks not_allowed)
			(vias allowed)
			(pads allowed)
			(copperpour not_allowed)
			(footprints allowed)
		)
		(placement
			(enabled no)
			(sheetname "")
		)
		(fill yes
			(thermal_gap 0.5)
			(thermal_bridge_width 0.5)
			(island_removal_mode 0)
		)
		(polygon
			(pts
				(arc
					(start 53.326284 -279.749504)
					(mid 52.673504 -279.749504)
					(end 53.326284 -279.749504)
				)
			)
		)
	)
	(zone
		(layers "B.Cu" "In13.Cu" "In15.Cu")
		(hatch none 0.5)
		(connect_pads
			(clearance 0)
		)
		(min_thickness 0.25)
		(keepout
			(tracks not_allowed)
			(vias allowed)
			(pads allowed)
			(copperpour not_allowed)
			(footprints allowed)
		)
		(placement
			(enabled no)
			(sheetname "")
		)
		(fill yes
			(thermal_gap 0.5)
			(thermal_bridge_width 0.5)
			(island_removal_mode 0)
		)
		(polygon
			(pts
				(arc
					(start 175.837342 -357.75773)
					(mid 175.133762 -357.75773)
					(end 175.837342 -357.75773)
				)
			)
		)
	)
	(zone
		(layers "B.Cu" "In13.Cu" "In15.Cu")
		(hatch none 0.5)
		(connect_pads
			(clearance 0)
		)
		(min_thickness 0.25)
		(keepout
			(tracks not_allowed)
			(vias allowed)
			(pads allowed)
			(copperpour not_allowed)
			(footprints allowed)
		)
		(placement
			(enabled no)
			(sheetname "")
		)
		(fill yes
			(thermal_gap 0.5)
			(thermal_bridge_width 0.5)
			(island_removal_mode 0)
		)
		(polygon
			(pts
				(arc
					(start 435.26964 -376.790204)
					(mid 434.51018 -376.790204)
					(end 435.26964 -376.790204)
				)
			)
		)
	)
	(zone
		(layers "B.Cu" "In13.Cu" "In15.Cu")
		(hatch none 0.5)
		(connect_pads
			(clearance 0)
		)
		(min_thickness 0.25)
		(keepout
			(tracks not_allowed)
			(vias allowed)
			(pads allowed)
			(copperpour not_allowed)
			(footprints allowed)
		)
		(placement
			(enabled no)
			(sheetname "")
		)
		(fill yes
			(thermal_gap 0.5)
			(thermal_bridge_width 0.5)
			(island_removal_mode 0)
		)
		(polygon
			(pts
				(arc
					(start 397.82623 -280.699718)
					(mid 397.17345 -280.699718)
					(end 397.82623 -280.699718)
				)
			)
		)
	)
	(zone
		(layers "B.Cu" "In13.Cu" "In15.Cu")
		(hatch none 0.5)
		(connect_pads
			(clearance 0)
		)
		(min_thickness 0.25)
		(keepout
			(tracks not_allowed)
			(vias allowed)
			(pads allowed)
			(copperpour not_allowed)
			(footprints allowed)
		)
		(placement
			(enabled no)
			(sheetname "")
		)
		(fill yes
			(thermal_gap 0.5)
			(thermal_bridge_width 0.5)
			(island_removal_mode 0)
		)
		(polygon
			(pts
				(arc
					(start 78.02626 -311.099962)
					(mid 77.37348 -311.099962)
					(end 78.02626 -311.099962)
				)
			)
		)
	)
	(zone
		(layers "B.Cu" "In13.Cu" "In15.Cu")
		(hatch none 0.5)
		(connect_pads
			(clearance 0)
		)
		(min_thickness 0.25)
		(keepout
			(tracks not_allowed)
			(vias allowed)
			(pads allowed)
			(copperpour not_allowed)
			(footprints allowed)
		)
		(placement
			(enabled no)
			(sheetname "")
		)
		(fill yes
			(thermal_gap 0.5)
			(thermal_bridge_width 0.5)
			(island_removal_mode 0)
		)
		(polygon
			(pts
				(arc
					(start 135.757158 -29.114242)
					(mid 135.053578 -29.114242)
					(end 135.757158 -29.114242)
				)
			)
		)
	)
	(zone
		(layers "B.Cu" "In13.Cu" "In15.Cu")
		(hatch none 0.5)
		(connect_pads
			(clearance 0)
		)
		(min_thickness 0.25)
		(keepout
			(tracks not_allowed)
			(vias allowed)
			(pads allowed)
			(copperpour not_allowed)
			(footprints allowed)
		)
		(placement
			(enabled no)
			(sheetname "")
		)
		(fill yes
			(thermal_gap 0.5)
			(thermal_bridge_width 0.5)
			(island_removal_mode 0)
		)
		(polygon
			(pts
				(arc
					(start 432.273202 -351.611438)
					(mid 431.569622 -351.611438)
					(end 432.273202 -351.611438)
				)
			)
		)
	)
	(zone
		(layers "B.Cu" "In13.Cu" "In15.Cu")
		(hatch none 0.5)
		(connect_pads
			(clearance 0)
		)
		(min_thickness 0.25)
		(keepout
			(tracks not_allowed)
			(vias allowed)
			(pads allowed)
			(copperpour not_allowed)
			(footprints allowed)
		)
		(placement
			(enabled no)
			(sheetname "")
		)
		(fill yes
			(thermal_gap 0.5)
			(thermal_bridge_width 0.5)
			(island_removal_mode 0)
		)
		(polygon
			(pts
				(arc
					(start 41.48963 -396.49019)
					(mid 40.73017 -396.49019)
					(end 41.48963 -396.49019)
				)
			)
		)
	)
	(zone
		(layers "B.Cu" "In13.Cu" "In15.Cu")
		(hatch none 0.5)
		(connect_pads
			(clearance 0)
		)
		(min_thickness 0.25)
		(keepout
			(tracks not_allowed)
			(vias allowed)
			(pads allowed)
			(copperpour not_allowed)
			(footprints allowed)
		)
		(placement
			(enabled no)
			(sheetname "")
		)
		(fill yes
			(thermal_gap 0.5)
			(thermal_bridge_width 0.5)
			(island_removal_mode 0)
		)
		(polygon
			(pts
				(arc
					(start 41.446958 -351.611438)
					(mid 40.743378 -351.611438)
					(end 41.446958 -351.611438)
				)
			)
		)
	)
	(zone
		(layers "B.Cu" "In13.Cu" "In15.Cu")
		(hatch none 0.5)
		(connect_pads
			(clearance 0)
		)
		(min_thickness 0.25)
		(keepout
			(tracks not_allowed)
			(vias allowed)
			(pads allowed)
			(copperpour not_allowed)
			(footprints allowed)
		)
		(placement
			(enabled no)
			(sheetname "")
		)
		(fill yes
			(thermal_gap 0.5)
			(thermal_bridge_width 0.5)
			(island_removal_mode 0)
		)
		(polygon
			(pts
				(arc
					(start 164.399214 -34.520886)
					(mid 163.695634 -34.520886)
					(end 164.399214 -34.520886)
				)
			)
		)
	)
	(zone
		(layers "B.Cu" "In13.Cu" "In15.Cu")
		(hatch none 0.5)
		(connect_pads
			(clearance 0)
		)
		(min_thickness 0.25)
		(keepout
			(tracks not_allowed)
			(vias allowed)
			(pads allowed)
			(copperpour not_allowed)
			(footprints allowed)
		)
		(placement
			(enabled no)
			(sheetname "")
		)
		(fill yes
			(thermal_gap 0.5)
			(thermal_bridge_width 0.5)
			(island_removal_mode 0)
		)
		(polygon
			(pts
				(arc
					(start 166.510462 -351.611438)
					(mid 165.806882 -351.611438)
					(end 166.510462 -351.611438)
				)
			)
		)
	)
	(zone
		(layers "B.Cu" "In13.Cu" "In15.Cu")
		(hatch none 0.5)
		(connect_pads
			(clearance 0)
		)
		(min_thickness 0.25)
		(keepout
			(tracks not_allowed)
			(vias allowed)
			(pads allowed)
			(copperpour not_allowed)
			(footprints allowed)
		)
		(placement
			(enabled no)
			(sheetname "")
		)
		(fill yes
			(thermal_gap 0.5)
			(thermal_bridge_width 0.5)
			(island_removal_mode 0)
		)
		(polygon
			(pts
				(arc
					(start 160.876234 -277.849838)
					(mid 160.223454 -277.849838)
					(end 160.876234 -277.849838)
				)
			)
		)
	)
	(zone
		(layers "B.Cu" "In13.Cu" "In15.Cu")
		(hatch none 0.5)
		(connect_pads
			(clearance 0)
		)
		(min_thickness 0.25)
		(keepout
			(tracks not_allowed)
			(vias allowed)
			(pads allowed)
			(copperpour not_allowed)
			(footprints allowed)
		)
		(placement
			(enabled no)
			(sheetname "")
		)
		(fill yes
			(thermal_gap 0.5)
			(thermal_bridge_width 0.5)
			(island_removal_mode 0)
		)
		(polygon
			(pts
				(arc
					(start 300.202092 -342.439498)
					(mid 299.498512 -342.439498)
					(end 300.202092 -342.439498)
				)
			)
		)
	)
	(zone
		(layers "B.Cu" "In13.Cu" "In15.Cu")
		(hatch none 0.5)
		(connect_pads
			(clearance 0)
		)
		(min_thickness 0.25)
		(keepout
			(tracks not_allowed)
			(vias allowed)
			(pads allowed)
			(copperpour not_allowed)
			(footprints allowed)
		)
		(placement
			(enabled no)
			(sheetname "")
		)
		(fill yes
			(thermal_gap 0.5)
			(thermal_bridge_width 0.5)
			(island_removal_mode 0)
		)
		(polygon
			(pts
				(arc
					(start 165.646862 -351.611438)
					(mid 164.943282 -351.611438)
					(end 165.646862 -351.611438)
				)
			)
		)
	)
	(zone
		(layers "B.Cu" "In13.Cu" "In15.Cu")
		(hatch none 0.5)
		(connect_pads
			(clearance 0)
		)
		(min_thickness 0.25)
		(keepout
			(tracks not_allowed)
			(vias allowed)
			(pads allowed)
			(copperpour not_allowed)
			(footprints allowed)
		)
		(placement
			(enabled no)
			(sheetname "")
		)
		(fill yes
			(thermal_gap 0.5)
			(thermal_bridge_width 0.5)
			(island_removal_mode 0)
		)
		(polygon
			(pts
				(arc
					(start 278.439372 -351.611438)
					(mid 277.735792 -351.611438)
					(end 278.439372 -351.611438)
				)
			)
		)
	)
	(zone
		(layers "B.Cu" "In13.Cu" "In15.Cu")
		(hatch none 0.5)
		(connect_pads
			(clearance 0)
		)
		(min_thickness 0.25)
		(keepout
			(tracks not_allowed)
			(vias allowed)
			(pads allowed)
			(copperpour not_allowed)
			(footprints allowed)
		)
		(placement
			(enabled no)
			(sheetname "")
		)
		(fill yes
			(thermal_gap 0.5)
			(thermal_bridge_width 0.5)
			(island_removal_mode 0)
		)
		(polygon
			(pts
				(arc
					(start 307.376322 -304.449734)
					(mid 306.723542 -304.449734)
					(end 307.376322 -304.449734)
				)
			)
		)
	)
	(zone
		(layers "B.Cu" "In13.Cu" "In15.Cu")
		(hatch none 0.5)
		(connect_pads
			(clearance 0)
		)
		(min_thickness 0.25)
		(keepout
			(tracks not_allowed)
			(vias allowed)
			(pads allowed)
			(copperpour not_allowed)
			(footprints allowed)
		)
		(placement
			(enabled no)
			(sheetname "")
		)
		(fill yes
			(thermal_gap 0.5)
			(thermal_bridge_width 0.5)
			(island_removal_mode 0)
		)
		(polygon
			(pts
				(arc
					(start 23.656798 -348.58579)
					(mid 22.953218 -348.58579)
					(end 23.656798 -348.58579)
				)
			)
		)
	)
	(zone
		(layers "B.Cu" "In13.Cu" "In15.Cu")
		(hatch none 0.5)
		(connect_pads
			(clearance 0)
		)
		(min_thickness 0.25)
		(keepout
			(tracks not_allowed)
			(vias allowed)
			(pads allowed)
			(copperpour not_allowed)
			(footprints allowed)
		)
		(placement
			(enabled no)
			(sheetname "")
		)
		(fill yes
			(thermal_gap 0.5)
			(thermal_bridge_width 0.5)
			(island_removal_mode 0)
		)
		(polygon
			(pts
				(arc
					(start 194.491102 -345.465146)
					(mid 193.787522 -345.465146)
					(end 194.491102 -345.465146)
				)
			)
		)
	)
	(zone
		(layers "B.Cu" "In13.Cu" "In15.Cu")
		(hatch none 0.5)
		(connect_pads
			(clearance 0)
		)
		(min_thickness 0.25)
		(keepout
			(tracks not_allowed)
			(vias allowed)
			(pads allowed)
			(copperpour not_allowed)
			(footprints allowed)
		)
		(placement
			(enabled no)
			(sheetname "")
		)
		(fill yes
			(thermal_gap 0.5)
			(thermal_bridge_width 0.5)
			(island_removal_mode 0)
		)
		(polygon
			(pts
				(arc
					(start 166.510462 -348.58579)
					(mid 165.806882 -348.58579)
					(end 166.510462 -348.58579)
				)
			)
		)
	)
	(zone
		(layers "B.Cu" "In13.Cu" "In15.Cu")
		(hatch none 0.5)
		(connect_pads
			(clearance 0)
		)
		(min_thickness 0.25)
		(keepout
			(tracks not_allowed)
			(vias allowed)
			(pads allowed)
			(copperpour not_allowed)
			(footprints allowed)
		)
		(placement
			(enabled no)
			(sheetname "")
		)
		(fill yes
			(thermal_gap 0.5)
			(thermal_bridge_width 0.5)
			(island_removal_mode 0)
		)
		(polygon
			(pts
				(arc
					(start 441.600082 -354.732082)
					(mid 440.896502 -354.732082)
					(end 441.600082 -354.732082)
				)
			)
		)
	)
	(zone
		(layers "B.Cu" "In13.Cu" "In15.Cu")
		(hatch none 0.5)
		(connect_pads
			(clearance 0)
		)
		(min_thickness 0.25)
		(keepout
			(tracks not_allowed)
			(vias allowed)
			(pads allowed)
			(copperpour not_allowed)
			(footprints allowed)
		)
		(placement
			(enabled no)
			(sheetname "")
		)
		(fill yes
			(thermal_gap 0.5)
			(thermal_bridge_width 0.5)
			(island_removal_mode 0)
		)
		(polygon
			(pts
				(arc
					(start 419.956996 -31.850584)
					(mid 419.253416 -31.850584)
					(end 419.956996 -31.850584)
				)
			)
		)
	)
	(zone
		(layers "B.Cu" "In13.Cu" "In15.Cu")
		(hatch none 0.5)
		(connect_pads
			(clearance 0)
		)
		(min_thickness 0.25)
		(keepout
			(tracks not_allowed)
			(vias allowed)
			(pads allowed)
			(copperpour not_allowed)
			(footprints allowed)
		)
		(placement
			(enabled no)
			(sheetname "")
		)
		(fill yes
			(thermal_gap 0.5)
			(thermal_bridge_width 0.5)
			(island_removal_mode 0)
		)
		(polygon
			(pts
				(arc
					(start 293.984172 -342.439498)
					(mid 293.280592 -342.439498)
					(end 293.984172 -342.439498)
				)
			)
		)
	)
	(zone
		(layers "B.Cu" "In13.Cu" "In15.Cu")
		(hatch none 0.5)
		(connect_pads
			(clearance 0)
		)
		(min_thickness 0.25)
		(keepout
			(tracks not_allowed)
			(vias allowed)
			(pads allowed)
			(copperpour not_allowed)
			(footprints allowed)
		)
		(placement
			(enabled no)
			(sheetname "")
		)
		(fill yes
			(thermal_gap 0.5)
			(thermal_bridge_width 0.5)
			(island_removal_mode 0)
		)
		(polygon
			(pts
				(arc
					(start 370.599208 -33.657286)
					(mid 369.895628 -33.657286)
					(end 370.599208 -33.657286)
				)
			)
		)
	)
	(zone
		(layers "B.Cu" "In13.Cu" "In15.Cu")
		(hatch none 0.5)
		(connect_pads
			(clearance 0)
		)
		(min_thickness 0.25)
		(keepout
			(tracks not_allowed)
			(vias allowed)
			(pads allowed)
			(copperpour not_allowed)
			(footprints allowed)
		)
		(placement
			(enabled no)
			(sheetname "")
		)
		(fill yes
			(thermal_gap 0.5)
			(thermal_bridge_width 0.5)
			(island_removal_mode 0)
		)
		(polygon
			(pts
				(arc
					(start 448.599052 -30.05709)
					(mid 447.895472 -30.05709)
					(end 448.599052 -30.05709)
				)
			)
		)
	)
	(zone
		(layers "B.Cu" "In13.Cu" "In15.Cu")
		(hatch none 0.5)
		(connect_pads
			(clearance 0)
		)
		(min_thickness 0.25)
		(keepout
			(tracks not_allowed)
			(vias allowed)
			(pads allowed)
			(copperpour not_allowed)
			(footprints allowed)
		)
		(placement
			(enabled no)
			(sheetname "")
		)
		(fill yes
			(thermal_gap 0.5)
			(thermal_bridge_width 0.5)
			(island_removal_mode 0)
		)
		(polygon
			(pts
				(arc
					(start 300.202092 -345.465146)
					(mid 299.498512 -345.465146)
					(end 300.202092 -345.465146)
				)
			)
		)
	)
	(zone
		(layers "B.Cu" "In13.Cu" "In15.Cu")
		(hatch none 0.5)
		(connect_pads
			(clearance 0)
		)
		(min_thickness 0.25)
		(keepout
			(tracks not_allowed)
			(vias allowed)
			(pads allowed)
			(copperpour not_allowed)
			(footprints allowed)
		)
		(placement
			(enabled no)
			(sheetname "")
		)
		(fill yes
			(thermal_gap 0.5)
			(thermal_bridge_width 0.5)
			(island_removal_mode 0)
		)
		(polygon
			(pts
				(arc
					(start 393.957048 -32.714184)
					(mid 393.253468 -32.714184)
					(end 393.957048 -32.714184)
				)
			)
		)
	)
	(zone
		(layers "B.Cu" "In13.Cu" "In15.Cu")
		(hatch none 0.5)
		(connect_pads
			(clearance 0)
		)
		(min_thickness 0.25)
		(keepout
			(tracks not_allowed)
			(vias allowed)
			(pads allowed)
			(copperpour not_allowed)
			(footprints allowed)
		)
		(placement
			(enabled no)
			(sheetname "")
		)
		(fill yes
			(thermal_gap 0.5)
			(thermal_bridge_width 0.5)
			(island_removal_mode 0)
		)
		(polygon
			(pts
				(arc
					(start 39.289736 -371.590062)
					(mid 38.530276 -371.590062)
					(end 39.289736 -371.590062)
				)
			)
		)
	)
	(zone
		(layers "B.Cu" "In13.Cu" "In15.Cu")
		(hatch none 0.5)
		(connect_pads
			(clearance 0)
		)
		(min_thickness 0.25)
		(keepout
			(tracks not_allowed)
			(vias allowed)
			(pads allowed)
			(copperpour not_allowed)
			(footprints allowed)
		)
		(placement
			(enabled no)
			(sheetname "")
		)
		(fill yes
			(thermal_gap 0.5)
			(thermal_bridge_width 0.5)
			(island_removal_mode 0)
		)
		(polygon
			(pts
				(arc
					(start 301.069502 -397.790162)
					(mid 300.310042 -397.790162)
					(end 301.069502 -397.790162)
				)
			)
		)
	)
	(zone
		(layers "B.Cu" "In13.Cu" "In15.Cu")
		(hatch none 0.5)
		(connect_pads
			(clearance 0)
		)
		(min_thickness 0.25)
		(keepout
			(tracks not_allowed)
			(vias allowed)
			(pads allowed)
			(copperpour not_allowed)
			(footprints allowed)
		)
		(placement
			(enabled no)
			(sheetname "")
		)
		(fill yes
			(thermal_gap 0.5)
			(thermal_bridge_width 0.5)
			(island_removal_mode 0)
		)
		(polygon
			(pts
				(arc
					(start 290.875212 -351.611438)
					(mid 290.171632 -351.611438)
					(end 290.875212 -351.611438)
				)
			)
		)
	)
	(zone
		(layers "B.Cu" "In13.Cu" "In15.Cu")
		(hatch none 0.5)
		(connect_pads
			(clearance 0)
		)
		(min_thickness 0.25)
		(keepout
			(tracks not_allowed)
			(vias allowed)
			(pads allowed)
			(copperpour not_allowed)
			(footprints allowed)
		)
		(placement
			(enabled no)
			(sheetname "")
		)
		(fill yes
			(thermal_gap 0.5)
			(thermal_bridge_width 0.5)
			(island_removal_mode 0)
		)
		(polygon
			(pts
				(arc
					(start 392.126216 -306.349908)
					(mid 391.473436 -306.349908)
					(end 392.126216 -306.349908)
				)
			)
		)
	)
	(zone
		(layers "B.Cu" "In13.Cu" "In15.Cu")
		(hatch none 0.5)
		(connect_pads
			(clearance 0)
		)
		(min_thickness 0.25)
		(keepout
			(tracks not_allowed)
			(vias allowed)
			(pads allowed)
			(copperpour not_allowed)
			(footprints allowed)
		)
		(placement
			(enabled no)
			(sheetname "")
		)
		(fill yes
			(thermal_gap 0.5)
			(thermal_bridge_width 0.5)
			(island_removal_mode 0)
		)
		(polygon
			(pts
				(arc
					(start 289.326066 -279.749504)
					(mid 288.673286 -279.749504)
					(end 289.326066 -279.749504)
				)
			)
		)
	)
	(zone
		(layers "B.Cu" "In13.Cu" "In15.Cu")
		(hatch none 0.5)
		(connect_pads
			(clearance 0)
		)
		(min_thickness 0.25)
		(keepout
			(tracks not_allowed)
			(vias allowed)
			(pads allowed)
			(copperpour not_allowed)
			(footprints allowed)
		)
		(placement
			(enabled no)
			(sheetname "")
		)
		(fill yes
			(thermal_gap 0.5)
			(thermal_bridge_width 0.5)
			(island_removal_mode 0)
		)
		(polygon
			(pts
				(arc
					(start 175.689768 -375.490232)
					(mid 174.930308 -375.490232)
					(end 175.689768 -375.490232)
				)
			)
		)
	)
	(zone
		(layers "B.Cu" "In13.Cu" "In15.Cu")
		(hatch none 0.5)
		(connect_pads
			(clearance 0)
		)
		(min_thickness 0.25)
		(keepout
			(tracks not_allowed)
			(vias allowed)
			(pads allowed)
			(copperpour not_allowed)
			(footprints allowed)
		)
		(placement
			(enabled no)
			(sheetname "")
		)
		(fill yes
			(thermal_gap 0.5)
			(thermal_bridge_width 0.5)
			(island_removal_mode 0)
		)
		(polygon
			(pts
				(arc
					(start 430.869598 -401.49018)
					(mid 430.110138 -401.49018)
					(end 430.869598 -401.49018)
				)
			)
		)
	)
	(zone
		(layers "B.Cu" "In13.Cu" "In15.Cu")
		(hatch none 0.5)
		(connect_pads
			(clearance 0)
		)
		(min_thickness 0.25)
		(keepout
			(tracks not_allowed)
			(vias allowed)
			(pads allowed)
			(copperpour not_allowed)
			(footprints allowed)
		)
		(placement
			(enabled no)
			(sheetname "")
		)
		(fill yes
			(thermal_gap 0.5)
			(thermal_bridge_width 0.5)
			(island_removal_mode 0)
		)
		(polygon
			(pts
				(arc
					(start 175.837342 -354.732082)
					(mid 175.133762 -354.732082)
					(end 175.837342 -354.732082)
				)
			)
		)
	)
	(zone
		(layers "B.Cu" "In13.Cu" "In15.Cu")
		(hatch none 0.5)
		(connect_pads
			(clearance 0)
		)
		(min_thickness 0.25)
		(keepout
			(tracks not_allowed)
			(vias allowed)
			(pads allowed)
			(copperpour not_allowed)
			(footprints allowed)
		)
		(placement
			(enabled no)
			(sheetname "")
		)
		(fill yes
			(thermal_gap 0.5)
			(thermal_bridge_width 0.5)
			(island_removal_mode 0)
		)
		(polygon
			(pts
				(arc
					(start 44.776136 -278.799798)
					(mid 44.123356 -278.799798)
					(end 44.776136 -278.799798)
				)
			)
		)
	)
	(zone
		(layers "B.Cu" "In13.Cu" "In15.Cu")
		(hatch none 0.5)
		(connect_pads
			(clearance 0)
		)
		(min_thickness 0.25)
		(keepout
			(tracks not_allowed)
			(vias allowed)
			(pads allowed)
			(copperpour not_allowed)
			(footprints allowed)
		)
		(placement
			(enabled no)
			(sheetname "")
		)
		(fill yes
			(thermal_gap 0.5)
			(thermal_bridge_width 0.5)
			(island_removal_mode 0)
		)
		(polygon
			(pts
				(arc
					(start 164.68979 -375.69013)
					(mid 163.93033 -375.69013)
					(end 164.68979 -375.69013)
				)
			)
		)
	)
	(zone
		(layers "B.Cu" "In13.Cu" "In15.Cu")
		(hatch none 0.5)
		(connect_pads
			(clearance 0)
		)
		(min_thickness 0.25)
		(keepout
			(tracks not_allowed)
			(vias allowed)
			(pads allowed)
			(copperpour not_allowed)
			(footprints allowed)
		)
		(placement
			(enabled no)
			(sheetname "")
		)
		(fill yes
			(thermal_gap 0.5)
			(thermal_bridge_width 0.5)
			(island_removal_mode 0)
		)
		(polygon
			(pts
				(arc
					(start 428.300642 -345.465146)
					(mid 427.597062 -345.465146)
					(end 428.300642 -345.465146)
				)
			)
		)
	)
	(zone
		(layers "B.Cu" "In13.Cu" "In15.Cu")
		(hatch none 0.5)
		(connect_pads
			(clearance 0)
		)
		(min_thickness 0.25)
		(keepout
			(tracks not_allowed)
			(vias allowed)
			(pads allowed)
			(copperpour not_allowed)
			(footprints allowed)
		)
		(placement
			(enabled no)
			(sheetname "")
		)
		(fill yes
			(thermal_gap 0.5)
			(thermal_bridge_width 0.5)
			(island_removal_mode 0)
		)
		(polygon
			(pts
				(arc
					(start 163.726368 -279.749504)
					(mid 163.073588 -279.749504)
					(end 163.726368 -279.749504)
				)
			)
		)
	)
	(zone
		(layers "B.Cu" "In13.Cu" "In15.Cu")
		(hatch none 0.5)
		(connect_pads
			(clearance 0)
		)
		(min_thickness 0.25)
		(keepout
			(tracks not_allowed)
			(vias allowed)
			(pads allowed)
			(copperpour not_allowed)
			(footprints allowed)
		)
		(placement
			(enabled no)
			(sheetname "")
		)
		(fill yes
			(thermal_gap 0.5)
			(thermal_bridge_width 0.5)
			(island_removal_mode 0)
		)
		(polygon
			(pts
				(arc
					(start 171.289726 -402.790152)
					(mid 170.530266 -402.790152)
					(end 171.289726 -402.790152)
				)
			)
		)
	)
	(zone
		(layers "B.Cu" "In13.Cu" "In15.Cu")
		(hatch none 0.5)
		(connect_pads
			(clearance 0)
		)
		(min_thickness 0.25)
		(keepout
			(tracks not_allowed)
			(vias allowed)
			(pads allowed)
			(copperpour not_allowed)
			(footprints allowed)
		)
		(placement
			(enabled no)
			(sheetname "")
		)
		(fill yes
			(thermal_gap 0.5)
			(thermal_bridge_width 0.5)
			(island_removal_mode 0)
		)
		(polygon
			(pts
				(arc
					(start 28.289758 -371.790214)
					(mid 27.530298 -371.790214)
					(end 28.289758 -371.790214)
				)
			)
		)
	)
	(zone
		(layers "B.Cu" "In13.Cu" "In15.Cu")
		(hatch none 0.5)
		(connect_pads
			(clearance 0)
		)
		(min_thickness 0.25)
		(keepout
			(tracks not_allowed)
			(vias allowed)
			(pads allowed)
			(copperpour not_allowed)
			(footprints allowed)
		)
		(placement
			(enabled no)
			(sheetname "")
		)
		(fill yes
			(thermal_gap 0.5)
			(thermal_bridge_width 0.5)
			(island_removal_mode 0)
		)
		(polygon
			(pts
				(arc
					(start 419.837362 -348.58579)
					(mid 419.133782 -348.58579)
					(end 419.837362 -348.58579)
				)
			)
		)
	)
	(zone
		(layers "B.Cu" "In13.Cu" "In15.Cu")
		(hatch none 0.5)
		(connect_pads
			(clearance 0)
		)
		(min_thickness 0.25)
		(keepout
			(tracks not_allowed)
			(vias allowed)
			(pads allowed)
			(copperpour not_allowed)
			(footprints allowed)
		)
		(placement
			(enabled no)
			(sheetname "")
		)
		(fill yes
			(thermal_gap 0.5)
			(thermal_bridge_width 0.5)
			(island_removal_mode 0)
		)
		(polygon
			(pts
				(arc
					(start 188.273182 -354.708206)
					(mid 187.569602 -354.708206)
					(end 188.273182 -354.708206)
				)
			)
		)
	)
	(zone
		(layers "B.Cu" "In13.Cu" "In15.Cu")
		(hatch none 0.5)
		(connect_pads
			(clearance 0)
		)
		(min_thickness 0.25)
		(keepout
			(tracks not_allowed)
			(vias allowed)
			(pads allowed)
			(copperpour not_allowed)
			(footprints allowed)
		)
		(placement
			(enabled no)
			(sheetname "")
		)
		(fill yes
			(thermal_gap 0.5)
			(thermal_bridge_width 0.5)
			(island_removal_mode 0)
		)
		(polygon
			(pts
				(arc
					(start 307.376322 -312.999882)
					(mid 306.723542 -312.999882)
					(end 307.376322 -312.999882)
				)
			)
		)
	)
	(zone
		(layers "B.Cu" "In13.Cu" "In15.Cu")
		(hatch none 0.5)
		(connect_pads
			(clearance 0)
		)
		(min_thickness 0.25)
		(keepout
			(tracks not_allowed)
			(vias allowed)
			(pads allowed)
			(copperpour not_allowed)
			(footprints allowed)
		)
		(placement
			(enabled no)
			(sheetname "")
		)
		(fill yes
			(thermal_gap 0.5)
			(thermal_bridge_width 0.5)
			(island_removal_mode 0)
		)
		(polygon
			(pts
				(arc
					(start 38.337998 -345.465146)
					(mid 37.634418 -345.465146)
					(end 38.337998 -345.465146)
				)
			)
		)
	)
	(zone
		(layers "B.Cu" "In13.Cu" "In15.Cu")
		(hatch none 0.5)
		(connect_pads
			(clearance 0)
		)
		(min_thickness 0.25)
		(keepout
			(tracks not_allowed)
			(vias allowed)
			(pads allowed)
			(copperpour not_allowed)
			(footprints allowed)
		)
		(placement
			(enabled no)
			(sheetname "")
		)
		(fill yes
			(thermal_gap 0.5)
			(thermal_bridge_width 0.5)
			(island_removal_mode 0)
		)
		(polygon
			(pts
				(arc
					(start 402.576284 -277.849838)
					(mid 401.923504 -277.849838)
					(end 402.576284 -277.849838)
				)
			)
		)
	)
	(zone
		(layers "B.Cu" "In13.Cu" "In15.Cu")
		(hatch none 0.5)
		(connect_pads
			(clearance 0)
		)
		(min_thickness 0.25)
		(keepout
			(tracks not_allowed)
			(vias allowed)
			(pads allowed)
			(copperpour not_allowed)
			(footprints allowed)
		)
		(placement
			(enabled no)
			(sheetname "")
		)
		(fill yes
			(thermal_gap 0.5)
			(thermal_bridge_width 0.5)
			(island_removal_mode 0)
		)
		(polygon
			(pts
				(arc
					(start 175.837342 -342.439498)
					(mid 175.133762 -342.439498)
					(end 175.837342 -342.439498)
				)
			)
		)
	)
	(zone
		(layers "B.Cu" "In13.Cu" "In15.Cu")
		(hatch none 0.5)
		(connect_pads
			(clearance 0)
		)
		(min_thickness 0.25)
		(keepout
			(tracks not_allowed)
			(vias allowed)
			(pads allowed)
			(copperpour not_allowed)
			(footprints allowed)
		)
		(placement
			(enabled no)
			(sheetname "")
		)
		(fill yes
			(thermal_gap 0.5)
			(thermal_bridge_width 0.5)
			(island_removal_mode 0)
		)
		(polygon
			(pts
				(arc
					(start 428.669704 -400.390106)
					(mid 427.910244 -400.390106)
					(end 428.669704 -400.390106)
				)
			)
		)
	)
	(zone
		(layers "B.Cu" "In13.Cu" "In15.Cu")
		(hatch none 0.5)
		(connect_pads
			(clearance 0)
		)
		(min_thickness 0.25)
		(keepout
			(tracks not_allowed)
			(vias allowed)
			(pads allowed)
			(copperpour not_allowed)
			(footprints allowed)
		)
		(placement
			(enabled no)
			(sheetname "")
		)
		(fill yes
			(thermal_gap 0.5)
			(thermal_bridge_width 0.5)
			(island_removal_mode 0)
		)
		(polygon
			(pts
				(arc
					(start 171.289726 -401.49018)
					(mid 170.530266 -401.49018)
					(end 171.289726 -401.49018)
				)
			)
		)
	)
	(zone
		(layers "B.Cu" "In13.Cu" "In15.Cu")
		(hatch none 0.5)
		(connect_pads
			(clearance 0)
		)
		(min_thickness 0.25)
		(keepout
			(tracks not_allowed)
			(vias allowed)
			(pads allowed)
			(copperpour not_allowed)
			(footprints allowed)
		)
		(placement
			(enabled no)
			(sheetname "")
		)
		(fill yes
			(thermal_gap 0.5)
			(thermal_bridge_width 0.5)
			(island_removal_mode 0)
		)
		(polygon
			(pts
				(arc
					(start 169.426382 -280.699718)
					(mid 168.773602 -280.699718)
					(end 169.426382 -280.699718)
				)
			)
		)
	)
	(zone
		(layers "B.Cu" "In13.Cu" "In15.Cu")
		(hatch none 0.5)
		(connect_pads
			(clearance 0)
		)
		(min_thickness 0.25)
		(keepout
			(tracks not_allowed)
			(vias allowed)
			(pads allowed)
			(copperpour not_allowed)
			(footprints allowed)
		)
		(placement
			(enabled no)
			(sheetname "")
		)
		(fill yes
			(thermal_gap 0.5)
			(thermal_bridge_width 0.5)
			(island_removal_mode 0)
		)
		(polygon
			(pts
				(arc
					(start 314.976256 -314.899802)
					(mid 314.323476 -314.899802)
					(end 314.976256 -314.899802)
				)
			)
		)
	)
	(zone
		(layers "B.Cu" "In13.Cu" "In15.Cu")
		(hatch none 0.5)
		(connect_pads
			(clearance 0)
		)
		(min_thickness 0.25)
		(keepout
			(tracks not_allowed)
			(vias allowed)
			(pads allowed)
			(copperpour not_allowed)
			(footprints allowed)
		)
		(placement
			(enabled no)
			(sheetname "")
		)
		(fill yes
			(thermal_gap 0.5)
			(thermal_bridge_width 0.5)
			(island_removal_mode 0)
		)
		(polygon
			(pts
				(arc
					(start 74.299064 -33.657286)
					(mid 73.595484 -33.657286)
					(end 74.299064 -33.657286)
				)
			)
		)
	)
	(zone
		(layers "B.Cu" "In13.Cu" "In15.Cu")
		(hatch none 0.5)
		(connect_pads
			(clearance 0)
		)
		(min_thickness 0.25)
		(keepout
			(tracks not_allowed)
			(vias allowed)
			(pads allowed)
			(copperpour not_allowed)
			(footprints allowed)
		)
		(placement
			(enabled no)
			(sheetname "")
		)
		(fill yes
			(thermal_gap 0.5)
			(thermal_bridge_width 0.5)
			(island_removal_mode 0)
		)
		(polygon
			(pts
				(arc
					(start 75.17638 -304.449734)
					(mid 74.5236 -304.449734)
					(end 75.17638 -304.449734)
				)
			)
		)
	)
	(zone
		(layers "B.Cu" "In13.Cu" "In15.Cu")
		(hatch none 0.5)
		(connect_pads
			(clearance 0)
		)
		(min_thickness 0.25)
		(keepout
			(tracks not_allowed)
			(vias allowed)
			(pads allowed)
			(copperpour not_allowed)
			(footprints allowed)
		)
		(placement
			(enabled no)
			(sheetname "")
		)
		(fill yes
			(thermal_gap 0.5)
			(thermal_bridge_width 0.5)
			(island_removal_mode 0)
		)
		(polygon
			(pts
				(arc
					(start 433.069492 -375.69013)
					(mid 432.310032 -375.69013)
					(end 433.069492 -375.69013)
				)
			)
		)
	)
	(zone
		(layers "B.Cu" "In13.Cu" "In15.Cu")
		(hatch none 0.5)
		(connect_pads
			(clearance 0)
		)
		(min_thickness 0.25)
		(keepout
			(tracks not_allowed)
			(vias allowed)
			(pads allowed)
			(copperpour not_allowed)
			(footprints allowed)
		)
		(placement
			(enabled no)
			(sheetname "")
		)
		(fill yes
			(thermal_gap 0.5)
			(thermal_bridge_width 0.5)
			(island_removal_mode 0)
		)
		(polygon
			(pts
				(arc
					(start 19.65706 -29.114242)
					(mid 18.95348 -29.114242)
					(end 19.65706 -29.114242)
				)
			)
		)
	)
	(zone
		(layers "B.Cu" "In13.Cu" "In15.Cu")
		(hatch none 0.5)
		(connect_pads
			(clearance 0)
		)
		(min_thickness 0.25)
		(keepout
			(tracks not_allowed)
			(vias allowed)
			(pads allowed)
			(copperpour not_allowed)
			(footprints allowed)
		)
		(placement
			(enabled no)
			(sheetname "")
		)
		(fill yes
			(thermal_gap 0.5)
			(thermal_bridge_width 0.5)
			(island_removal_mode 0)
		)
		(polygon
			(pts
				(arc
					(start 57.126124 -279.749504)
					(mid 56.473344 -279.749504)
					(end 57.126124 -279.749504)
				)
			)
		)
	)
	(zone
		(layers "B.Cu" "In13.Cu" "In15.Cu")
		(hatch none 0.5)
		(connect_pads
			(clearance 0)
		)
		(min_thickness 0.25)
		(keepout
			(tracks not_allowed)
			(vias allowed)
			(pads allowed)
			(copperpour not_allowed)
			(footprints allowed)
		)
		(placement
			(enabled no)
			(sheetname "")
		)
		(fill yes
			(thermal_gap 0.5)
			(thermal_bridge_width 0.5)
			(island_removal_mode 0)
		)
		(polygon
			(pts
				(arc
					(start 280.499058 -33.657286)
					(mid 279.795478 -33.657286)
					(end 280.499058 -33.657286)
				)
			)
		)
	)
	(zone
		(layers "B.Cu" "In13.Cu" "In15.Cu")
		(hatch none 0.5)
		(connect_pads
			(clearance 0)
		)
		(min_thickness 0.25)
		(keepout
			(tracks not_allowed)
			(vias allowed)
			(pads allowed)
			(copperpour not_allowed)
			(footprints allowed)
		)
		(placement
			(enabled no)
			(sheetname "")
		)
		(fill yes
			(thermal_gap 0.5)
			(thermal_bridge_width 0.5)
			(island_removal_mode 0)
		)
		(polygon
			(pts
				(arc
					(start 393.076176 -306.349908)
					(mid 392.423396 -306.349908)
					(end 393.076176 -306.349908)
				)
			)
		)
	)
	(zone
		(layers "B.Cu" "In13.Cu" "In15.Cu")
		(hatch none 0.5)
		(connect_pads
			(clearance 0)
		)
		(min_thickness 0.25)
		(keepout
			(tracks not_allowed)
			(vias allowed)
			(pads allowed)
			(copperpour not_allowed)
			(footprints allowed)
		)
		(placement
			(enabled no)
			(sheetname "")
		)
		(fill yes
			(thermal_gap 0.5)
			(thermal_bridge_width 0.5)
			(island_removal_mode 0)
		)
		(polygon
			(pts
				(arc
					(start 190.518542 -351.611438)
					(mid 189.814962 -351.611438)
					(end 190.518542 -351.611438)
				)
			)
		)
	)
	(zone
		(layers "B.Cu" "In13.Cu" "In15.Cu")
		(hatch none 0.5)
		(connect_pads
			(clearance 0)
		)
		(min_thickness 0.25)
		(keepout
			(tracks not_allowed)
			(vias allowed)
			(pads allowed)
			(copperpour not_allowed)
			(footprints allowed)
		)
		(placement
			(enabled no)
			(sheetname "")
		)
		(fill yes
			(thermal_gap 0.5)
			(thermal_bridge_width 0.5)
			(island_removal_mode 0)
		)
		(polygon
			(pts
				(arc
					(start 138.399266 -30.92069)
					(mid 137.695686 -30.92069)
					(end 138.399266 -30.92069)
				)
			)
		)
	)
	(zone
		(layers "B.Cu" "In13.Cu" "In15.Cu")
		(hatch none 0.5)
		(connect_pads
			(clearance 0)
		)
		(min_thickness 0.25)
		(keepout
			(tracks not_allowed)
			(vias allowed)
			(pads allowed)
			(copperpour not_allowed)
			(footprints allowed)
		)
		(placement
			(enabled no)
			(sheetname "")
		)
		(fill yes
			(thermal_gap 0.5)
			(thermal_bridge_width 0.5)
			(island_removal_mode 0)
		)
		(polygon
			(pts
				(arc
					(start 332.498954 -34.520886)
					(mid 331.795374 -34.520886)
					(end 332.498954 -34.520886)
				)
			)
		)
	)
	(zone
		(layers "B.Cu" "In13.Cu" "In15.Cu")
		(hatch none 0.5)
		(connect_pads
			(clearance 0)
		)
		(min_thickness 0.25)
		(keepout
			(tracks not_allowed)
			(vias allowed)
			(pads allowed)
			(copperpour not_allowed)
			(footprints allowed)
		)
		(placement
			(enabled no)
			(sheetname "")
		)
		(fill yes
			(thermal_gap 0.5)
			(thermal_bridge_width 0.5)
			(island_removal_mode 0)
		)
		(polygon
			(pts
				(arc
					(start 162.489642 -375.490232)
					(mid 161.730182 -375.490232)
					(end 162.489642 -375.490232)
				)
			)
		)
	)
	(zone
		(layers "B.Cu" "In13.Cu" "In15.Cu")
		(hatch none 0.5)
		(connect_pads
			(clearance 0)
		)
		(min_thickness 0.25)
		(keepout
			(tracks not_allowed)
			(vias allowed)
			(pads allowed)
			(copperpour not_allowed)
			(footprints allowed)
		)
		(placement
			(enabled no)
			(sheetname "")
		)
		(fill yes
			(thermal_gap 0.5)
			(thermal_bridge_width 0.5)
			(island_removal_mode 0)
		)
		(polygon
			(pts
				(arc
					(start 392.126216 -302.549814)
					(mid 391.473436 -302.549814)
					(end 392.126216 -302.549814)
				)
			)
		)
	)
	(zone
		(layers "B.Cu" "In13.Cu" "In15.Cu")
		(hatch none 0.5)
		(connect_pads
			(clearance 0)
		)
		(min_thickness 0.25)
		(keepout
			(tracks not_allowed)
			(vias allowed)
			(pads allowed)
			(copperpour not_allowed)
			(footprints allowed)
		)
		(placement
			(enabled no)
			(sheetname "")
		)
		(fill yes
			(thermal_gap 0.5)
			(thermal_bridge_width 0.5)
			(island_removal_mode 0)
		)
		(polygon
			(pts
				(arc
					(start 438.491122 -348.58579)
					(mid 437.787542 -348.58579)
					(end 438.491122 -348.58579)
				)
			)
		)
	)
	(zone
		(layers "B.Cu" "In13.Cu" "In15.Cu")
		(hatch none 0.5)
		(connect_pads
			(clearance 0)
		)
		(min_thickness 0.25)
		(keepout
			(tracks not_allowed)
			(vias allowed)
			(pads allowed)
			(copperpour not_allowed)
			(footprints allowed)
		)
		(placement
			(enabled no)
			(sheetname "")
		)
		(fill yes
			(thermal_gap 0.5)
			(thermal_bridge_width 0.5)
			(island_removal_mode 0)
		)
		(polygon
			(pts
				(arc
					(start 56.176164 -278.799798)
					(mid 55.523384 -278.799798)
					(end 56.176164 -278.799798)
				)
			)
		)
	)
	(zone
		(layers "B.Cu" "In13.Cu" "In15.Cu")
		(hatch none 0.5)
		(connect_pads
			(clearance 0)
		)
		(min_thickness 0.25)
		(keepout
			(tracks not_allowed)
			(vias allowed)
			(pads allowed)
			(copperpour not_allowed)
			(footprints allowed)
		)
		(placement
			(enabled no)
			(sheetname "")
		)
		(fill yes
			(thermal_gap 0.5)
			(thermal_bridge_width 0.5)
			(island_removal_mode 0)
		)
		(polygon
			(pts
				(arc
					(start 56.176164 -277.849838)
					(mid 55.523384 -277.849838)
					(end 56.176164 -277.849838)
				)
			)
		)
	)
	(zone
		(layers "B.Cu" "In13.Cu" "In15.Cu")
		(hatch none 0.5)
		(connect_pads
			(clearance 0)
		)
		(min_thickness 0.25)
		(keepout
			(tracks not_allowed)
			(vias allowed)
			(pads allowed)
			(copperpour not_allowed)
			(footprints allowed)
		)
		(placement
			(enabled no)
			(sheetname "")
		)
		(fill yes
			(thermal_gap 0.5)
			(thermal_bridge_width 0.5)
			(island_removal_mode 0)
		)
		(polygon
			(pts
				(arc
					(start 311.176162 -313.949842)
					(mid 310.523382 -313.949842)
					(end 311.176162 -313.949842)
				)
			)
		)
	)
	(zone
		(layers "B.Cu" "In13.Cu" "In15.Cu")
		(hatch none 0.5)
		(connect_pads
			(clearance 0)
		)
		(min_thickness 0.25)
		(keepout
			(tracks not_allowed)
			(vias allowed)
			(pads allowed)
			(copperpour not_allowed)
			(footprints allowed)
		)
		(placement
			(enabled no)
			(sheetname "")
		)
		(fill yes
			(thermal_gap 0.5)
			(thermal_bridge_width 0.5)
			(island_removal_mode 0)
		)
		(polygon
			(pts
				(arc
					(start 74.299064 -30.05709)
					(mid 73.595484 -30.05709)
					(end 74.299064 -30.05709)
				)
			)
		)
	)
	(zone
		(layers "B.Cu" "In13.Cu" "In15.Cu")
		(hatch none 0.5)
		(connect_pads
			(clearance 0)
		)
		(min_thickness 0.25)
		(keepout
			(tracks not_allowed)
			(vias allowed)
			(pads allowed)
			(copperpour not_allowed)
			(footprints allowed)
		)
		(placement
			(enabled no)
			(sheetname "")
		)
		(fill yes
			(thermal_gap 0.5)
			(thermal_bridge_width 0.5)
			(island_removal_mode 0)
		)
		(polygon
			(pts
				(arc
					(start 300.202092 -354.732082)
					(mid 299.498512 -354.732082)
					(end 300.202092 -354.732082)
				)
			)
		)
	)
	(zone
		(layers "B.Cu" "In13.Cu" "In15.Cu")
		(hatch none 0.5)
		(connect_pads
			(clearance 0)
		)
		(min_thickness 0.25)
		(keepout
			(tracks not_allowed)
			(vias allowed)
			(pads allowed)
			(copperpour not_allowed)
			(footprints allowed)
		)
		(placement
			(enabled no)
			(sheetname "")
		)
		(fill yes
			(thermal_gap 0.5)
			(thermal_bridge_width 0.5)
			(island_removal_mode 0)
		)
		(polygon
			(pts
				(arc
					(start 168.755822 -357.75773)
					(mid 168.052242 -357.75773)
					(end 168.755822 -357.75773)
				)
			)
		)
	)
	(zone
		(layers "B.Cu" "In13.Cu" "In15.Cu")
		(hatch none 0.5)
		(connect_pads
			(clearance 0)
		)
		(min_thickness 0.25)
		(keepout
			(tracks not_allowed)
			(vias allowed)
			(pads allowed)
			(copperpour not_allowed)
			(footprints allowed)
		)
		(placement
			(enabled no)
			(sheetname "")
		)
		(fill yes
			(thermal_gap 0.5)
			(thermal_bridge_width 0.5)
			(island_removal_mode 0)
		)
		(polygon
			(pts
				(arc
					(start 51.637438 -357.75773)
					(mid 50.933858 -357.75773)
					(end 51.637438 -357.75773)
				)
			)
		)
	)
	(zone
		(layers "B.Cu" "In13.Cu" "In15.Cu")
		(hatch none 0.5)
		(connect_pads
			(clearance 0)
		)
		(min_thickness 0.25)
		(keepout
			(tracks not_allowed)
			(vias allowed)
			(pads allowed)
			(copperpour not_allowed)
			(footprints allowed)
		)
		(placement
			(enabled no)
			(sheetname "")
		)
		(fill yes
			(thermal_gap 0.5)
			(thermal_bridge_width 0.5)
			(island_removal_mode 0)
		)
		(polygon
			(pts
				(arc
					(start 426.469556 -402.790152)
					(mid 425.710096 -402.790152)
					(end 426.469556 -402.790152)
				)
			)
		)
	)
	(zone
		(layers "B.Cu" "In13.Cu" "In15.Cu")
		(hatch none 0.5)
		(connect_pads
			(clearance 0)
		)
		(min_thickness 0.25)
		(keepout
			(tracks not_allowed)
			(vias allowed)
			(pads allowed)
			(copperpour not_allowed)
			(footprints allowed)
		)
		(placement
			(enabled no)
			(sheetname "")
		)
		(fill yes
			(thermal_gap 0.5)
			(thermal_bridge_width 0.5)
			(island_removal_mode 0)
		)
		(polygon
			(pts
				(arc
					(start 277.85695 -32.714184)
					(mid 277.15337 -32.714184)
					(end 277.85695 -32.714184)
				)
			)
		)
	)
	(zone
		(layers "B.Cu" "In13.Cu" "In15.Cu")
		(hatch none 0.5)
		(connect_pads
			(clearance 0)
		)
		(min_thickness 0.25)
		(keepout
			(tracks not_allowed)
			(vias allowed)
			(pads allowed)
			(copperpour not_allowed)
			(footprints allowed)
		)
		(placement
			(enabled no)
			(sheetname "")
		)
		(fill yes
			(thermal_gap 0.5)
			(thermal_bridge_width 0.5)
			(island_removal_mode 0)
		)
		(polygon
			(pts
				(arc
					(start 47.664878 -351.611438)
					(mid 46.961298 -351.611438)
					(end 47.664878 -351.611438)
				)
			)
		)
	)
	(zone
		(layers "B.Cu" "In13.Cu" "In15.Cu")
		(hatch none 0.5)
		(connect_pads
			(clearance 0)
		)
		(min_thickness 0.25)
		(keepout
			(tracks not_allowed)
			(vias allowed)
			(pads allowed)
			(copperpour not_allowed)
			(footprints allowed)
		)
		(placement
			(enabled no)
			(sheetname "")
		)
		(fill yes
			(thermal_gap 0.5)
			(thermal_bridge_width 0.5)
			(island_removal_mode 0)
		)
		(polygon
			(pts
				(arc
					(start 45.419518 -357.75773)
					(mid 44.715938 -357.75773)
					(end 45.419518 -357.75773)
				)
			)
		)
	)
	(zone
		(layers "B.Cu" "In13.Cu" "In15.Cu")
		(hatch none 0.5)
		(connect_pads
			(clearance 0)
		)
		(min_thickness 0.25)
		(keepout
			(tracks not_allowed)
			(vias allowed)
			(pads allowed)
			(copperpour not_allowed)
			(footprints allowed)
		)
		(placement
			(enabled no)
			(sheetname "")
		)
		(fill yes
			(thermal_gap 0.5)
			(thermal_bridge_width 0.5)
			(island_removal_mode 0)
		)
		(polygon
			(pts
				(arc
					(start 367.9571 -32.714184)
					(mid 367.25352 -32.714184)
					(end 367.9571 -32.714184)
				)
			)
		)
	)
	(zone
		(layers "B.Cu" "In13.Cu" "In15.Cu")
		(hatch none 0.5)
		(connect_pads
			(clearance 0)
		)
		(min_thickness 0.25)
		(keepout
			(tracks not_allowed)
			(vias allowed)
			(pads allowed)
			(copperpour not_allowed)
			(footprints allowed)
		)
		(placement
			(enabled no)
			(sheetname "")
		)
		(fill yes
			(thermal_gap 0.5)
			(thermal_bridge_width 0.5)
			(island_removal_mode 0)
		)
		(polygon
			(pts
				(arc
					(start 55.226204 -279.749504)
					(mid 54.573424 -279.749504)
					(end 55.226204 -279.749504)
				)
			)
		)
	)
	(zone
		(layers "B.Cu" "In13.Cu" "In15.Cu")
		(hatch none 0.5)
		(connect_pads
			(clearance 0)
		)
		(min_thickness 0.25)
		(keepout
			(tracks not_allowed)
			(vias allowed)
			(pads allowed)
			(copperpour not_allowed)
			(footprints allowed)
		)
		(placement
			(enabled no)
			(sheetname "")
		)
		(fill yes
			(thermal_gap 0.5)
			(thermal_bridge_width 0.5)
			(island_removal_mode 0)
		)
		(polygon
			(pts
				(arc
					(start 407.326338 -280.699718)
					(mid 406.673558 -280.699718)
					(end 407.326338 -280.699718)
				)
			)
		)
	)
	(zone
		(layers "B.Cu" "In13.Cu" "In15.Cu")
		(hatch none 0.5)
		(connect_pads
			(clearance 0)
		)
		(min_thickness 0.25)
		(keepout
			(tracks not_allowed)
			(vias allowed)
			(pads allowed)
			(copperpour not_allowed)
			(footprints allowed)
		)
		(placement
			(enabled no)
			(sheetname "")
		)
		(fill yes
			(thermal_gap 0.5)
			(thermal_bridge_width 0.5)
			(island_removal_mode 0)
		)
		(polygon
			(pts
				(arc
					(start 182.055262 -357.75773)
					(mid 181.351682 -357.75773)
					(end 182.055262 -357.75773)
				)
			)
		)
	)
	(zone
		(layers "B.Cu" "In13.Cu" "In15.Cu")
		(hatch none 0.5)
		(connect_pads
			(clearance 0)
		)
		(min_thickness 0.25)
		(keepout
			(tracks not_allowed)
			(vias allowed)
			(pads allowed)
			(copperpour not_allowed)
			(footprints allowed)
		)
		(placement
			(enabled no)
			(sheetname "")
		)
		(fill yes
			(thermal_gap 0.5)
			(thermal_bridge_width 0.5)
			(island_removal_mode 0)
		)
		(polygon
			(pts
				(arc
					(start 290.875212 -348.58579)
					(mid 290.171632 -348.58579)
					(end 290.875212 -348.58579)
				)
			)
		)
	)
	(zone
		(layers "B.Cu" "In13.Cu" "In15.Cu")
		(hatch none 0.5)
		(connect_pads
			(clearance 0)
		)
		(min_thickness 0.25)
		(keepout
			(tracks not_allowed)
			(vias allowed)
			(pads allowed)
			(copperpour not_allowed)
			(footprints allowed)
		)
		(placement
			(enabled no)
			(sheetname "")
		)
		(fill yes
			(thermal_gap 0.5)
			(thermal_bridge_width 0.5)
			(island_removal_mode 0)
		)
		(polygon
			(pts
				(arc
					(start 314.026296 -314.899802)
					(mid 313.373516 -314.899802)
					(end 314.026296 -314.899802)
				)
			)
		)
	)
	(zone
		(layers "B.Cu" "In13.Cu" "In15.Cu")
		(hatch none 0.5)
		(connect_pads
			(clearance 0)
		)
		(min_thickness 0.25)
		(keepout
			(tracks not_allowed)
			(vias allowed)
			(pads allowed)
			(copperpour not_allowed)
			(footprints allowed)
		)
		(placement
			(enabled no)
			(sheetname "")
		)
		(fill yes
			(thermal_gap 0.5)
			(thermal_bridge_width 0.5)
			(island_removal_mode 0)
		)
		(polygon
			(pts
				(arc
					(start 397.82623 -279.749504)
					(mid 397.17345 -279.749504)
					(end 397.82623 -279.749504)
				)
			)
		)
	)
	(zone
		(layers "B.Cu" "In13.Cu" "In15.Cu")
		(hatch none 0.5)
		(connect_pads
			(clearance 0)
		)
		(min_thickness 0.25)
		(keepout
			(tracks not_allowed)
			(vias allowed)
			(pads allowed)
			(copperpour not_allowed)
			(footprints allowed)
		)
		(placement
			(enabled no)
			(sheetname "")
		)
		(fill yes
			(thermal_gap 0.5)
			(thermal_bridge_width 0.5)
			(island_removal_mode 0)
		)
		(polygon
			(pts
				(arc
					(start 296.229532 -348.58579)
					(mid 295.525952 -348.58579)
					(end 296.229532 -348.58579)
				)
			)
		)
	)
	(zone
		(layers "B.Cu" "In13.Cu" "In15.Cu")
		(hatch none 0.5)
		(connect_pads
			(clearance 0)
		)
		(min_thickness 0.25)
		(keepout
			(tracks not_allowed)
			(vias allowed)
			(pads allowed)
			(copperpour not_allowed)
			(footprints allowed)
		)
		(placement
			(enabled no)
			(sheetname "")
		)
		(fill yes
			(thermal_gap 0.5)
			(thermal_bridge_width 0.5)
			(island_removal_mode 0)
		)
		(polygon
			(pts
				(arc
					(start 293.120572 -345.465146)
					(mid 292.416992 -345.465146)
					(end 293.120572 -345.465146)
				)
			)
		)
	)
	(zone
		(layers "B.Cu" "In13.Cu" "In15.Cu")
		(hatch none 0.5)
		(connect_pads
			(clearance 0)
		)
		(min_thickness 0.25)
		(keepout
			(tracks not_allowed)
			(vias allowed)
			(pads allowed)
			(copperpour not_allowed)
			(footprints allowed)
		)
		(placement
			(enabled no)
			(sheetname "")
		)
		(fill yes
			(thermal_gap 0.5)
			(thermal_bridge_width 0.5)
			(island_removal_mode 0)
		)
		(polygon
			(pts
				(arc
					(start 59.026298 -279.749504)
					(mid 58.373518 -279.749504)
					(end 59.026298 -279.749504)
				)
			)
		)
	)
	(zone
		(layers "B.Cu" "In13.Cu" "In15.Cu")
		(hatch none 0.5)
		(connect_pads
			(clearance 0)
		)
		(min_thickness 0.25)
		(keepout
			(tracks not_allowed)
			(vias allowed)
			(pads allowed)
			(copperpour not_allowed)
			(footprints allowed)
		)
		(placement
			(enabled no)
			(sheetname "")
		)
		(fill yes
			(thermal_gap 0.5)
			(thermal_bridge_width 0.5)
			(island_removal_mode 0)
		)
		(polygon
			(pts
				(arc
					(start 19.65706 -32.714184)
					(mid 18.95348 -32.714184)
					(end 19.65706 -32.714184)
				)
			)
		)
	)
	(zone
		(layers "B.Cu" "In13.Cu" "In15.Cu")
		(hatch none 0.5)
		(connect_pads
			(clearance 0)
		)
		(min_thickness 0.25)
		(keepout
			(tracks not_allowed)
			(vias allowed)
			(pads allowed)
			(copperpour not_allowed)
			(footprints allowed)
		)
		(placement
			(enabled no)
			(sheetname "")
		)
		(fill yes
			(thermal_gap 0.5)
			(thermal_bridge_width 0.5)
			(island_removal_mode 0)
		)
		(polygon
			(pts
				(arc
					(start 30.489652 -397.59001)
					(mid 29.730192 -397.59001)
					(end 30.489652 -397.59001)
				)
			)
		)
	)
	(zone
		(layers "B.Cu" "In13.Cu" "In15.Cu")
		(hatch none 0.5)
		(connect_pads
			(clearance 0)
		)
		(min_thickness 0.25)
		(keepout
			(tracks not_allowed)
			(vias allowed)
			(pads allowed)
			(copperpour not_allowed)
			(footprints allowed)
		)
		(placement
			(enabled no)
			(sheetname "")
		)
		(fill yes
			(thermal_gap 0.5)
			(thermal_bridge_width 0.5)
			(island_removal_mode 0)
		)
		(polygon
			(pts
				(arc
					(start 287.766252 -354.732082)
					(mid 287.062672 -354.732082)
					(end 287.766252 -354.732082)
				)
			)
		)
	)
	(zone
		(layers "B.Cu" "In13.Cu" "In15.Cu")
		(hatch none 0.5)
		(connect_pads
			(clearance 0)
		)
		(min_thickness 0.25)
		(keepout
			(tracks not_allowed)
			(vias allowed)
			(pads allowed)
			(copperpour not_allowed)
			(footprints allowed)
		)
		(placement
			(enabled no)
			(sheetname "")
		)
		(fill yes
			(thermal_gap 0.5)
			(thermal_bridge_width 0.5)
			(island_removal_mode 0)
		)
		(polygon
			(pts
				(arc
					(start 158.976314 -309.199788)
					(mid 158.323534 -309.199788)
					(end 158.976314 -309.199788)
				)
			)
		)
	)
	(zone
		(layers "B.Cu" "In13.Cu" "In15.Cu")
		(hatch none 0.5)
		(connect_pads
			(clearance 0)
		)
		(min_thickness 0.25)
		(keepout
			(tracks not_allowed)
			(vias allowed)
			(pads allowed)
			(copperpour not_allowed)
			(footprints allowed)
		)
		(placement
			(enabled no)
			(sheetname "")
		)
		(fill yes
			(thermal_gap 0.5)
			(thermal_bridge_width 0.5)
			(island_removal_mode 0)
		)
		(polygon
			(pts
				(arc
					(start 43.689778 -372.890034)
					(mid 42.930318 -372.890034)
					(end 43.689778 -372.890034)
				)
			)
		)
	)
	(zone
		(layers "B.Cu" "In13.Cu" "In15.Cu")
		(hatch none 0.5)
		(connect_pads
			(clearance 0)
		)
		(min_thickness 0.25)
		(keepout
			(tracks not_allowed)
			(vias allowed)
			(pads allowed)
			(copperpour not_allowed)
			(footprints allowed)
		)
		(placement
			(enabled no)
			(sheetname "")
		)
		(fill yes
			(thermal_gap 0.5)
			(thermal_bridge_width 0.5)
			(island_removal_mode 0)
		)
		(polygon
			(pts
				(arc
					(start 288.376106 -277.849838)
					(mid 287.723326 -277.849838)
					(end 288.376106 -277.849838)
				)
			)
		)
	)
	(zone
		(layers "B.Cu" "In13.Cu" "In15.Cu")
		(hatch none 0.5)
		(connect_pads
			(clearance 0)
		)
		(min_thickness 0.25)
		(keepout
			(tracks not_allowed)
			(vias allowed)
			(pads allowed)
			(copperpour not_allowed)
			(footprints allowed)
		)
		(placement
			(enabled no)
			(sheetname "")
		)
		(fill yes
			(thermal_gap 0.5)
			(thermal_bridge_width 0.5)
			(island_removal_mode 0)
		)
		(polygon
			(pts
				(arc
					(start 448.599052 -34.520886)
					(mid 447.895472 -34.520886)
					(end 448.599052 -34.520886)
				)
			)
		)
	)
	(zone
		(layers "B.Cu" "In13.Cu" "In15.Cu")
		(hatch none 0.5)
		(connect_pads
			(clearance 0)
		)
		(min_thickness 0.25)
		(keepout
			(tracks not_allowed)
			(vias allowed)
			(pads allowed)
			(copperpour not_allowed)
			(footprints allowed)
		)
		(placement
			(enabled no)
			(sheetname "")
		)
		(fill yes
			(thermal_gap 0.5)
			(thermal_bridge_width 0.5)
			(island_removal_mode 0)
		)
		(polygon
			(pts
				(arc
					(start 287.426146 -280.699718)
					(mid 286.773366 -280.699718)
					(end 287.426146 -280.699718)
				)
			)
		)
	)
	(zone
		(layers "B.Cu" "In13.Cu" "In15.Cu")
		(hatch none 0.5)
		(connect_pads
			(clearance 0)
		)
		(min_thickness 0.25)
		(keepout
			(tracks not_allowed)
			(vias allowed)
			(pads allowed)
			(copperpour not_allowed)
			(footprints allowed)
		)
		(placement
			(enabled no)
			(sheetname "")
		)
		(fill yes
			(thermal_gap 0.5)
			(thermal_bridge_width 0.5)
			(island_removal_mode 0)
		)
		(polygon
			(pts
				(arc
					(start 22.299168 -34.520886)
					(mid 21.595588 -34.520886)
					(end 22.299168 -34.520886)
				)
			)
		)
	)
	(zone
		(layers "B.Cu" "In13.Cu" "In15.Cu")
		(hatch none 0.5)
		(connect_pads
			(clearance 0)
		)
		(min_thickness 0.25)
		(keepout
			(tracks not_allowed)
			(vias allowed)
			(pads allowed)
			(copperpour not_allowed)
			(footprints allowed)
		)
		(placement
			(enabled no)
			(sheetname "")
		)
		(fill yes
			(thermal_gap 0.5)
			(thermal_bridge_width 0.5)
			(island_removal_mode 0)
		)
		(polygon
			(pts
				(arc
					(start 438.491122 -351.611438)
					(mid 437.787542 -351.611438)
					(end 438.491122 -351.611438)
				)
			)
		)
	)
	(zone
		(layers "B.Cu" "In13.Cu" "In15.Cu")
		(hatch none 0.5)
		(connect_pads
			(clearance 0)
		)
		(min_thickness 0.25)
		(keepout
			(tracks not_allowed)
			(vias allowed)
			(pads allowed)
			(copperpour not_allowed)
			(footprints allowed)
		)
		(placement
			(enabled no)
			(sheetname "")
		)
		(fill yes
			(thermal_gap 0.5)
			(thermal_bridge_width 0.5)
			(island_removal_mode 0)
		)
		(polygon
			(pts
				(arc
					(start 398.77619 -278.799798)
					(mid 398.12341 -278.799798)
					(end 398.77619 -278.799798)
				)
			)
		)
	)
	(zone
		(layers "B.Cu" "In13.Cu" "In15.Cu")
		(hatch none 0.5)
		(connect_pads
			(clearance 0)
		)
		(min_thickness 0.25)
		(keepout
			(tracks not_allowed)
			(vias allowed)
			(pads allowed)
			(copperpour not_allowed)
			(footprints allowed)
		)
		(placement
			(enabled no)
			(sheetname "")
		)
		(fill yes
			(thermal_gap 0.5)
			(thermal_bridge_width 0.5)
			(island_removal_mode 0)
		)
		(polygon
			(pts
				(arc
					(start 297.093132 -351.611438)
					(mid 296.389552 -351.611438)
					(end 297.093132 -351.611438)
				)
			)
		)
	)
	(zone
		(layers "B.Cu" "In13.Cu" "In15.Cu")
		(hatch none 0.5)
		(connect_pads
			(clearance 0)
		)
		(min_thickness 0.25)
		(keepout
			(tracks not_allowed)
			(vias allowed)
			(pads allowed)
			(copperpour not_allowed)
			(footprints allowed)
		)
		(placement
			(enabled no)
			(sheetname "")
		)
		(fill yes
			(thermal_gap 0.5)
			(thermal_bridge_width 0.5)
			(island_removal_mode 0)
		)
		(polygon
			(pts
				(arc
					(start 287.426146 -279.749504)
					(mid 286.773366 -279.749504)
					(end 287.426146 -279.749504)
				)
			)
		)
	)
	(zone
		(layers "B.Cu" "In13.Cu" "In15.Cu")
		(hatch none 0.5)
		(connect_pads
			(clearance 0)
		)
		(min_thickness 0.25)
		(keepout
			(tracks not_allowed)
			(vias allowed)
			(pads allowed)
			(copperpour not_allowed)
			(footprints allowed)
		)
		(placement
			(enabled no)
			(sheetname "")
		)
		(fill yes
			(thermal_gap 0.5)
			(thermal_bridge_width 0.5)
			(island_removal_mode 0)
		)
		(polygon
			(pts
				(arc
					(start 71.656956 -31.850584)
					(mid 70.953376 -31.850584)
					(end 71.656956 -31.850584)
				)
			)
		)
	)
	(zone
		(layers "B.Cu" "In13.Cu" "In15.Cu")
		(hatch none 0.5)
		(connect_pads
			(clearance 0)
		)
		(min_thickness 0.25)
		(keepout
			(tracks not_allowed)
			(vias allowed)
			(pads allowed)
			(copperpour not_allowed)
			(footprints allowed)
		)
		(placement
			(enabled no)
			(sheetname "")
		)
		(fill yes
			(thermal_gap 0.5)
			(thermal_bridge_width 0.5)
			(island_removal_mode 0)
		)
		(polygon
			(pts
				(arc
					(start 429.164242 -357.75773)
					(mid 428.460662 -357.75773)
					(end 429.164242 -357.75773)
				)
			)
		)
	)
	(zone
		(layers "B.Cu" "In13.Cu" "In15.Cu")
		(hatch none 0.5)
		(connect_pads
			(clearance 0)
		)
		(min_thickness 0.25)
		(keepout
			(tracks not_allowed)
			(vias allowed)
			(pads allowed)
			(copperpour not_allowed)
			(footprints allowed)
		)
		(placement
			(enabled no)
			(sheetname "")
		)
		(fill yes
			(thermal_gap 0.5)
			(thermal_bridge_width 0.5)
			(island_removal_mode 0)
		)
		(polygon
			(pts
				(arc
					(start 407.326338 -279.749504)
					(mid 406.673558 -279.749504)
					(end 407.326338 -279.749504)
				)
			)
		)
	)
	(zone
		(layers "B.Cu" "In13.Cu" "In15.Cu")
		(hatch none 0.5)
		(connect_pads
			(clearance 0)
		)
		(min_thickness 0.25)
		(keepout
			(tracks not_allowed)
			(vias allowed)
			(pads allowed)
			(copperpour not_allowed)
			(footprints allowed)
		)
		(placement
			(enabled no)
			(sheetname "")
		)
		(fill yes
			(thermal_gap 0.5)
			(thermal_bridge_width 0.5)
			(island_removal_mode 0)
		)
		(polygon
			(pts
				(arc
					(start 76.12634 -312.049922)
					(mid 75.47356 -312.049922)
					(end 76.12634 -312.049922)
				)
			)
		)
	)
	(zone
		(layers "B.Cu" "In13.Cu" "In15.Cu")
		(hatch none 0.5)
		(connect_pads
			(clearance 0)
		)
		(min_thickness 0.25)
		(keepout
			(tracks not_allowed)
			(vias allowed)
			(pads allowed)
			(copperpour not_allowed)
			(footprints allowed)
		)
		(placement
			(enabled no)
			(sheetname "")
		)
		(fill yes
			(thermal_gap 0.5)
			(thermal_bridge_width 0.5)
			(island_removal_mode 0)
		)
		(polygon
			(pts
				(arc
					(start 307.376322 -306.349908)
					(mid 306.723542 -306.349908)
					(end 307.376322 -306.349908)
				)
			)
		)
	)
	(zone
		(layers "B.Cu" "In13.Cu" "In15.Cu")
		(hatch none 0.5)
		(connect_pads
			(clearance 0)
		)
		(min_thickness 0.25)
		(keepout
			(tracks not_allowed)
			(vias allowed)
			(pads allowed)
			(copperpour not_allowed)
			(footprints allowed)
		)
		(placement
			(enabled no)
			(sheetname "")
		)
		(fill yes
			(thermal_gap 0.5)
			(thermal_bridge_width 0.5)
			(island_removal_mode 0)
		)
		(polygon
			(pts
				(arc
					(start 287.766252 -342.439498)
					(mid 287.062672 -342.439498)
					(end 287.766252 -342.439498)
				)
			)
		)
	)
	(zone
		(layers "B.Cu" "In13.Cu" "In15.Cu")
		(hatch none 0.5)
		(connect_pads
			(clearance 0)
		)
		(min_thickness 0.25)
		(keepout
			(tracks not_allowed)
			(vias allowed)
			(pads allowed)
			(copperpour not_allowed)
			(footprints allowed)
		)
		(placement
			(enabled no)
			(sheetname "")
		)
		(fill yes
			(thermal_gap 0.5)
			(thermal_bridge_width 0.5)
			(island_removal_mode 0)
		)
		(polygon
			(pts
				(arc
					(start 42.310558 -348.58579)
					(mid 41.606978 -348.58579)
					(end 42.310558 -348.58579)
				)
			)
		)
	)
	(zone
		(layers "B.Cu" "In13.Cu" "In15.Cu")
		(hatch none 0.5)
		(connect_pads
			(clearance 0)
		)
		(min_thickness 0.25)
		(keepout
			(tracks not_allowed)
			(vias allowed)
			(pads allowed)
			(copperpour not_allowed)
			(footprints allowed)
		)
		(placement
			(enabled no)
			(sheetname "")
		)
		(fill yes
			(thermal_gap 0.5)
			(thermal_bridge_width 0.5)
			(island_removal_mode 0)
		)
		(polygon
			(pts
				(arc
					(start 394.02639 -279.749504)
					(mid 393.37361 -279.749504)
					(end 394.02639 -279.749504)
				)
			)
		)
	)
	(zone
		(layers "B.Cu" "In13.Cu" "In15.Cu")
		(hatch none 0.5)
		(connect_pads
			(clearance 0)
		)
		(min_thickness 0.25)
		(keepout
			(tracks not_allowed)
			(vias allowed)
			(pads allowed)
			(copperpour not_allowed)
			(footprints allowed)
		)
		(placement
			(enabled no)
			(sheetname "")
		)
		(fill yes
			(thermal_gap 0.5)
			(thermal_bridge_width 0.5)
			(island_removal_mode 0)
		)
		(polygon
			(pts
				(arc
					(start 276.976078 -277.849838)
					(mid 276.323298 -277.849838)
					(end 276.976078 -277.849838)
				)
			)
		)
	)
	(zone
		(layers "B.Cu" "In13.Cu" "In15.Cu")
		(hatch none 0.5)
		(connect_pads
			(clearance 0)
		)
		(min_thickness 0.25)
		(keepout
			(tracks not_allowed)
			(vias allowed)
			(pads allowed)
			(copperpour not_allowed)
			(footprints allowed)
		)
		(placement
			(enabled no)
			(sheetname "")
		)
		(fill yes
			(thermal_gap 0.5)
			(thermal_bridge_width 0.5)
			(island_removal_mode 0)
		)
		(polygon
			(pts
				(arc
					(start 291.22624 -280.699718)
					(mid 290.57346 -280.699718)
					(end 291.22624 -280.699718)
				)
			)
		)
	)
	(zone
		(layers "B.Cu" "In13.Cu" "In15.Cu")
		(hatch none 0.5)
		(connect_pads
			(clearance 0)
		)
		(min_thickness 0.25)
		(keepout
			(tracks not_allowed)
			(vias allowed)
			(pads allowed)
			(copperpour not_allowed)
			(footprints allowed)
		)
		(placement
			(enabled no)
			(sheetname "")
		)
		(fill yes
			(thermal_gap 0.5)
			(thermal_bridge_width 0.5)
			(island_removal_mode 0)
		)
		(polygon
			(pts
				(arc
					(start 187.757054 -32.714184)
					(mid 187.053474 -32.714184)
					(end 187.757054 -32.714184)
				)
			)
		)
	)
	(zone
		(layers "B.Cu" "In13.Cu" "In15.Cu")
		(hatch none 0.5)
		(connect_pads
			(clearance 0)
		)
		(min_thickness 0.25)
		(keepout
			(tracks not_allowed)
			(vias allowed)
			(pads allowed)
			(copperpour not_allowed)
			(footprints allowed)
		)
		(placement
			(enabled no)
			(sheetname "")
		)
		(fill yes
			(thermal_gap 0.5)
			(thermal_bridge_width 0.5)
			(island_removal_mode 0)
		)
		(polygon
			(pts
				(arc
					(start 409.646882 -345.465146)
					(mid 408.943302 -345.465146)
					(end 409.646882 -345.465146)
				)
			)
		)
	)
	(zone
		(layers "B.Cu" "In13.Cu" "In15.Cu")
		(hatch none 0.5)
		(connect_pads
			(clearance 0)
		)
		(min_thickness 0.25)
		(keepout
			(tracks not_allowed)
			(vias allowed)
			(pads allowed)
			(copperpour not_allowed)
			(footprints allowed)
		)
		(placement
			(enabled no)
			(sheetname "")
		)
		(fill yes
			(thermal_gap 0.5)
			(thermal_bridge_width 0.5)
			(island_removal_mode 0)
		)
		(polygon
			(pts
				(arc
					(start 290.069524 -397.59001)
					(mid 289.310064 -397.59001)
					(end 290.069524 -397.59001)
				)
			)
		)
	)
	(zone
		(layers "B.Cu" "In13.Cu" "In15.Cu")
		(hatch none 0.5)
		(connect_pads
			(clearance 0)
		)
		(min_thickness 0.25)
		(keepout
			(tracks not_allowed)
			(vias allowed)
			(pads allowed)
			(copperpour not_allowed)
			(footprints allowed)
		)
		(placement
			(enabled no)
			(sheetname "")
		)
		(fill yes
			(thermal_gap 0.5)
			(thermal_bridge_width 0.5)
			(island_removal_mode 0)
		)
		(polygon
			(pts
				(arc
					(start 393.957048 -28.250642)
					(mid 393.253468 -28.250642)
					(end 393.957048 -28.250642)
				)
			)
		)
	)
	(zone
		(layers "B.Cu" "In13.Cu" "In15.Cu")
		(hatch none 0.5)
		(connect_pads
			(clearance 0)
		)
		(min_thickness 0.25)
		(keepout
			(tracks not_allowed)
			(vias allowed)
			(pads allowed)
			(copperpour not_allowed)
			(footprints allowed)
		)
		(placement
			(enabled no)
			(sheetname "")
		)
		(fill yes
			(thermal_gap 0.5)
			(thermal_bridge_width 0.5)
			(island_removal_mode 0)
		)
		(polygon
			(pts
				(arc
					(start 169.089832 -375.69013)
					(mid 168.330372 -375.69013)
					(end 169.089832 -375.69013)
				)
			)
		)
	)
	(zone
		(layers "B.Cu" "In13.Cu" "In15.Cu")
		(hatch none 0.5)
		(connect_pads
			(clearance 0)
		)
		(min_thickness 0.25)
		(keepout
			(tracks not_allowed)
			(vias allowed)
			(pads allowed)
			(copperpour not_allowed)
			(footprints allowed)
		)
		(placement
			(enabled no)
			(sheetname "")
		)
		(fill yes
			(thermal_gap 0.5)
			(thermal_bridge_width 0.5)
			(island_removal_mode 0)
		)
		(polygon
			(pts
				(arc
					(start 303.26965 -398.890236)
					(mid 302.51019 -398.890236)
					(end 303.26965 -398.890236)
				)
			)
		)
	)
	(zone
		(layers "B.Cu" "In13.Cu" "In15.Cu")
		(hatch none 0.5)
		(connect_pads
			(clearance 0)
		)
		(min_thickness 0.25)
		(keepout
			(tracks not_allowed)
			(vias allowed)
			(pads allowed)
			(copperpour not_allowed)
			(footprints allowed)
		)
		(placement
			(enabled no)
			(sheetname "")
		)
		(fill yes
			(thermal_gap 0.5)
			(thermal_bridge_width 0.5)
			(island_removal_mode 0)
		)
		(polygon
			(pts
				(arc
					(start 77.0763 -307.299868)
					(mid 76.42352 -307.299868)
					(end 77.0763 -307.299868)
				)
			)
		)
	)
	(zone
		(layers "B.Cu" "In13.Cu" "In15.Cu")
		(hatch none 0.5)
		(connect_pads
			(clearance 0)
		)
		(min_thickness 0.25)
		(keepout
			(tracks not_allowed)
			(vias allowed)
			(pads allowed)
			(copperpour not_allowed)
			(footprints allowed)
		)
		(placement
			(enabled no)
			(sheetname "")
		)
		(fill yes
			(thermal_gap 0.5)
			(thermal_bridge_width 0.5)
			(island_removal_mode 0)
		)
		(polygon
			(pts
				(arc
					(start 425.191682 -351.611438)
					(mid 424.488102 -351.611438)
					(end 425.191682 -351.611438)
				)
			)
		)
	)
	(zone
		(layers "B.Cu" "In13.Cu" "In15.Cu")
		(hatch none 0.5)
		(connect_pads
			(clearance 0)
		)
		(min_thickness 0.25)
		(keepout
			(tracks not_allowed)
			(vias allowed)
			(pads allowed)
			(copperpour not_allowed)
			(footprints allowed)
		)
		(placement
			(enabled no)
			(sheetname "")
		)
		(fill yes
			(thermal_gap 0.5)
			(thermal_bridge_width 0.5)
			(island_removal_mode 0)
		)
		(polygon
			(pts
				(arc
					(start 412.755842 -351.611438)
					(mid 412.052262 -351.611438)
					(end 412.755842 -351.611438)
				)
			)
		)
	)
	(zone
		(layers "B.Cu" "In13.Cu" "In15.Cu")
		(hatch none 0.5)
		(connect_pads
			(clearance 0)
		)
		(min_thickness 0.25)
		(keepout
			(tracks not_allowed)
			(vias allowed)
			(pads allowed)
			(copperpour not_allowed)
			(footprints allowed)
		)
		(placement
			(enabled no)
			(sheetname "")
		)
		(fill yes
			(thermal_gap 0.5)
			(thermal_bridge_width 0.5)
			(island_removal_mode 0)
		)
		(polygon
			(pts
				(arc
					(start 391.176256 -312.999882)
					(mid 390.523476 -312.999882)
					(end 391.176256 -312.999882)
				)
			)
		)
	)
	(zone
		(layers "B.Cu" "In13.Cu" "In15.Cu")
		(hatch none 0.5)
		(connect_pads
			(clearance 0)
		)
		(min_thickness 0.25)
		(keepout
			(tracks not_allowed)
			(vias allowed)
			(pads allowed)
			(copperpour not_allowed)
			(footprints allowed)
		)
		(placement
			(enabled no)
			(sheetname "")
		)
		(fill yes
			(thermal_gap 0.5)
			(thermal_bridge_width 0.5)
			(island_removal_mode 0)
		)
		(polygon
			(pts
				(arc
					(start 30.489652 -398.890236)
					(mid 29.730192 -398.890236)
					(end 30.489652 -398.890236)
				)
			)
		)
	)
	(zone
		(layers "B.Cu" "In13.Cu" "In15.Cu")
		(hatch none 0.5)
		(connect_pads
			(clearance 0)
		)
		(min_thickness 0.25)
		(keepout
			(tracks not_allowed)
			(vias allowed)
			(pads allowed)
			(copperpour not_allowed)
			(footprints allowed)
		)
		(placement
			(enabled no)
			(sheetname "")
		)
		(fill yes
			(thermal_gap 0.5)
			(thermal_bridge_width 0.5)
			(island_removal_mode 0)
		)
		(polygon
			(pts
				(arc
					(start 49.52619 -280.699718)
					(mid 48.87341 -280.699718)
					(end 49.52619 -280.699718)
				)
			)
		)
	)
	(zone
		(layers "B.Cu" "In13.Cu" "In15.Cu")
		(hatch none 0.5)
		(connect_pads
			(clearance 0)
		)
		(min_thickness 0.25)
		(keepout
			(tracks not_allowed)
			(vias allowed)
			(pads allowed)
			(copperpour not_allowed)
			(footprints allowed)
		)
		(placement
			(enabled no)
			(sheetname "")
		)
		(fill yes
			(thermal_gap 0.5)
			(thermal_bridge_width 0.5)
			(island_removal_mode 0)
		)
		(polygon
			(pts
				(arc
					(start 286.902652 -345.465146)
					(mid 286.199072 -345.465146)
					(end 286.902652 -345.465146)
				)
			)
		)
	)
	(zone
		(layers "B.Cu" "In13.Cu" "In15.Cu")
		(hatch none 0.5)
		(connect_pads
			(clearance 0)
		)
		(min_thickness 0.25)
		(keepout
			(tracks not_allowed)
			(vias allowed)
			(pads allowed)
			(copperpour not_allowed)
			(footprints allowed)
		)
		(placement
			(enabled no)
			(sheetname "")
		)
		(fill yes
			(thermal_gap 0.5)
			(thermal_bridge_width 0.5)
			(island_removal_mode 0)
		)
		(polygon
			(pts
				(arc
					(start 48.08982 -406.690068)
					(mid 47.33036 -406.690068)
					(end 48.08982 -406.690068)
				)
			)
		)
	)
	(zone
		(layers "B.Cu" "In13.Cu" "In15.Cu")
		(hatch none 0.5)
		(connect_pads
			(clearance 0)
		)
		(min_thickness 0.25)
		(keepout
			(tracks not_allowed)
			(vias allowed)
			(pads allowed)
			(copperpour not_allowed)
			(footprints allowed)
		)
		(placement
			(enabled no)
			(sheetname "")
		)
		(fill yes
			(thermal_gap 0.5)
			(thermal_bridge_width 0.5)
			(island_removal_mode 0)
		)
		(polygon
			(pts
				(arc
					(start 271.357852 -348.58579)
					(mid 270.654272 -348.58579)
					(end 271.357852 -348.58579)
				)
			)
		)
	)
	(zone
		(layers "B.Cu" "In13.Cu" "In15.Cu")
		(hatch none 0.5)
		(connect_pads
			(clearance 0)
		)
		(min_thickness 0.25)
		(keepout
			(tracks not_allowed)
			(vias allowed)
			(pads allowed)
			(copperpour not_allowed)
			(footprints allowed)
		)
		(placement
			(enabled no)
			(sheetname "")
		)
		(fill yes
			(thermal_gap 0.5)
			(thermal_bridge_width 0.5)
			(island_removal_mode 0)
		)
		(polygon
			(pts
				(arc
					(start 163.401502 -357.75773)
					(mid 162.697922 -357.75773)
					(end 163.401502 -357.75773)
				)
			)
		)
	)
	(zone
		(layers "B.Cu" "In13.Cu" "In15.Cu")
		(hatch none 0.5)
		(connect_pads
			(clearance 0)
		)
		(min_thickness 0.25)
		(keepout
			(tracks not_allowed)
			(vias allowed)
			(pads allowed)
			(copperpour not_allowed)
			(footprints allowed)
		)
		(placement
			(enabled no)
			(sheetname "")
		)
		(fill yes
			(thermal_gap 0.5)
			(thermal_bridge_width 0.5)
			(island_removal_mode 0)
		)
		(polygon
			(pts
				(arc
					(start 162.776408 -278.799798)
					(mid 162.123628 -278.799798)
					(end 162.776408 -278.799798)
				)
			)
		)
	)
	(zone
		(layers "B.Cu" "In13.Cu" "In15.Cu")
		(hatch none 0.5)
		(connect_pads
			(clearance 0)
		)
		(min_thickness 0.25)
		(keepout
			(tracks not_allowed)
			(vias allowed)
			(pads allowed)
			(copperpour not_allowed)
			(footprints allowed)
		)
		(placement
			(enabled no)
			(sheetname "")
		)
		(fill yes
			(thermal_gap 0.5)
			(thermal_bridge_width 0.5)
			(island_removal_mode 0)
		)
		(polygon
			(pts
				(arc
					(start 396.599156 -30.92069)
					(mid 395.895576 -30.92069)
					(end 396.599156 -30.92069)
				)
			)
		)
	)
	(zone
		(layers "B.Cu" "In13.Cu" "In15.Cu")
		(hatch none 0.5)
		(connect_pads
			(clearance 0)
		)
		(min_thickness 0.25)
		(keepout
			(tracks not_allowed)
			(vias allowed)
			(pads allowed)
			(copperpour not_allowed)
			(footprints allowed)
		)
		(placement
			(enabled no)
			(sheetname "")
		)
		(fill yes
			(thermal_gap 0.5)
			(thermal_bridge_width 0.5)
			(island_removal_mode 0)
		)
		(polygon
			(pts
				(arc
					(start 47.664878 -348.58579)
					(mid 46.961298 -348.58579)
					(end 47.664878 -348.58579)
				)
			)
		)
	)
	(zone
		(layers "B.Cu" "In13.Cu" "In15.Cu")
		(hatch none 0.5)
		(connect_pads
			(clearance 0)
		)
		(min_thickness 0.25)
		(keepout
			(tracks not_allowed)
			(vias allowed)
			(pads allowed)
			(copperpour not_allowed)
			(footprints allowed)
		)
		(placement
			(enabled no)
			(sheetname "")
		)
		(fill yes
			(thermal_gap 0.5)
			(thermal_bridge_width 0.5)
			(island_removal_mode 0)
		)
		(polygon
			(pts
				(arc
					(start 430.869598 -402.790152)
					(mid 430.110138 -402.790152)
					(end 430.869598 -402.790152)
				)
			)
		)
	)
	(zone
		(layers "B.Cu" "In13.Cu" "In15.Cu")
		(hatch none 0.5)
		(connect_pads
			(clearance 0)
		)
		(min_thickness 0.25)
		(keepout
			(tracks not_allowed)
			(vias allowed)
			(pads allowed)
			(copperpour not_allowed)
			(footprints allowed)
		)
		(placement
			(enabled no)
			(sheetname "")
		)
		(fill yes
			(thermal_gap 0.5)
			(thermal_bridge_width 0.5)
			(island_removal_mode 0)
		)
		(polygon
			(pts
				(arc
					(start 311.176162 -312.999882)
					(mid 310.523382 -312.999882)
					(end 311.176162 -312.999882)
				)
			)
		)
	)
	(zone
		(layers "B.Cu" "In13.Cu" "In15.Cu")
		(hatch none 0.5)
		(connect_pads
			(clearance 0)
		)
		(min_thickness 0.25)
		(keepout
			(tracks not_allowed)
			(vias allowed)
			(pads allowed)
			(copperpour not_allowed)
			(footprints allowed)
		)
		(placement
			(enabled no)
			(sheetname "")
		)
		(fill yes
			(thermal_gap 0.5)
			(thermal_bridge_width 0.5)
			(island_removal_mode 0)
		)
		(polygon
			(pts
				(arc
					(start 393.076176 -278.799798)
					(mid 392.423396 -278.799798)
					(end 393.076176 -278.799798)
				)
			)
		)
	)
	(zone
		(layers "B.Cu" "In13.Cu" "In15.Cu")
		(hatch none 0.5)
		(connect_pads
			(clearance 0)
		)
		(min_thickness 0.25)
		(keepout
			(tracks not_allowed)
			(vias allowed)
			(pads allowed)
			(copperpour not_allowed)
			(footprints allowed)
		)
		(placement
			(enabled no)
			(sheetname "")
		)
		(fill yes
			(thermal_gap 0.5)
			(thermal_bridge_width 0.5)
			(island_removal_mode 0)
		)
		(polygon
			(pts
				(arc
					(start 431.409602 -351.611438)
					(mid 430.706022 -351.611438)
					(end 431.409602 -351.611438)
				)
			)
		)
	)
	(zone
		(layers "B.Cu" "In13.Cu" "In15.Cu")
		(hatch none 0.5)
		(connect_pads
			(clearance 0)
		)
		(min_thickness 0.25)
		(keepout
			(tracks not_allowed)
			(vias allowed)
			(pads allowed)
			(copperpour not_allowed)
			(footprints allowed)
		)
		(placement
			(enabled no)
			(sheetname "")
		)
		(fill yes
			(thermal_gap 0.5)
			(thermal_bridge_width 0.5)
			(island_removal_mode 0)
		)
		(polygon
			(pts
				(arc
					(start 28.289758 -397.790162)
					(mid 27.530298 -397.790162)
					(end 28.289758 -397.790162)
				)
			)
		)
	)
	(zone
		(layers "B.Cu" "In13.Cu" "In15.Cu")
		(hatch none 0.5)
		(connect_pads
			(clearance 0)
		)
		(min_thickness 0.25)
		(keepout
			(tracks not_allowed)
			(vias allowed)
			(pads allowed)
			(copperpour not_allowed)
			(footprints allowed)
		)
		(placement
			(enabled no)
			(sheetname "")
		)
		(fill yes
			(thermal_gap 0.5)
			(thermal_bridge_width 0.5)
			(island_removal_mode 0)
		)
		(polygon
			(pts
				(arc
					(start 422.599104 -30.05709)
					(mid 421.895524 -30.05709)
					(end 422.599104 -30.05709)
				)
			)
		)
	)
	(zone
		(layers "B.Cu" "In13.Cu" "In15.Cu")
		(hatch none 0.5)
		(connect_pads
			(clearance 0)
		)
		(min_thickness 0.25)
		(keepout
			(tracks not_allowed)
			(vias allowed)
			(pads allowed)
			(copperpour not_allowed)
			(footprints allowed)
		)
		(placement
			(enabled no)
			(sheetname "")
		)
		(fill yes
			(thermal_gap 0.5)
			(thermal_bridge_width 0.5)
			(island_removal_mode 0)
		)
		(polygon
			(pts
				(arc
					(start 158.026354 -305.399948)
					(mid 157.373574 -305.399948)
					(end 158.026354 -305.399948)
				)
			)
		)
	)
	(zone
		(layers "B.Cu" "In13.Cu" "In15.Cu")
		(hatch none 0.5)
		(connect_pads
			(clearance 0)
		)
		(min_thickness 0.25)
		(keepout
			(tracks not_allowed)
			(vias allowed)
			(pads allowed)
			(copperpour not_allowed)
			(footprints allowed)
		)
		(placement
			(enabled no)
			(sheetname "")
		)
		(fill yes
			(thermal_gap 0.5)
			(thermal_bridge_width 0.5)
			(island_removal_mode 0)
		)
		(polygon
			(pts
				(arc
					(start 422.946322 -354.732082)
					(mid 422.242742 -354.732082)
					(end 422.946322 -354.732082)
				)
			)
		)
	)
	(zone
		(layers "B.Cu" "In13.Cu" "In15.Cu")
		(hatch none 0.5)
		(connect_pads
			(clearance 0)
		)
		(min_thickness 0.25)
		(keepout
			(tracks not_allowed)
			(vias allowed)
			(pads allowed)
			(copperpour not_allowed)
			(footprints allowed)
		)
		(placement
			(enabled no)
			(sheetname "")
		)
		(fill yes
			(thermal_gap 0.5)
			(thermal_bridge_width 0.5)
			(island_removal_mode 0)
		)
		(polygon
			(pts
				(arc
					(start 281.548332 -354.732082)
					(mid 280.844752 -354.732082)
					(end 281.548332 -354.732082)
				)
			)
		)
	)
	(zone
		(layers "B.Cu" "In15.Cu")
		(hatch none 0.5)
		(connect_pads
			(clearance 0)
		)
		(min_thickness 0.25)
		(keepout
			(tracks not_allowed)
			(vias allowed)
			(pads allowed)
			(copperpour not_allowed)
			(footprints allowed)
		)
		(placement
			(enabled no)
			(sheetname "")
		)
		(fill yes
			(thermal_gap 0.5)
			(thermal_bridge_width 0.5)
			(island_removal_mode 0)
		)
		(polygon
			(pts
				(arc
					(start 53.326284 -312.049922)
					(mid 52.673504 -312.049922)
					(end 53.326284 -312.049922)
				)
			)
		)
	)
	(zone
		(layers "B.Cu" "In15.Cu")
		(hatch none 0.5)
		(connect_pads
			(clearance 0)
		)
		(min_thickness 0.25)
		(keepout
			(tracks not_allowed)
			(vias allowed)
			(pads allowed)
			(copperpour not_allowed)
			(footprints allowed)
		)
		(placement
			(enabled no)
			(sheetname "")
		)
		(fill yes
			(thermal_gap 0.5)
			(thermal_bridge_width 0.5)
			(island_removal_mode 0)
		)
		(polygon
			(pts
				(arc
					(start 377.75769 -345.465146)
					(mid 377.05411 -345.465146)
					(end 377.75769 -345.465146)
				)
			)
		)
	)
	(zone
		(layers "B.Cu" "In15.Cu")
		(hatch none 0.5)
		(connect_pads
			(clearance 0)
		)
		(min_thickness 0.25)
		(keepout
			(tracks not_allowed)
			(vias allowed)
			(pads allowed)
			(copperpour not_allowed)
			(footprints allowed)
		)
		(placement
			(enabled no)
			(sheetname "")
		)
		(fill yes
			(thermal_gap 0.5)
			(thermal_bridge_width 0.5)
			(island_removal_mode 0)
		)
		(polygon
			(pts
				(arc
					(start 85.489542 -383.490216)
					(mid 84.730082 -383.490216)
					(end 85.489542 -383.490216)
				)
			)
		)
	)
	(zone
		(layers "B.Cu" "In15.Cu")
		(hatch none 0.5)
		(connect_pads
			(clearance 0)
		)
		(min_thickness 0.25)
		(keepout
			(tracks not_allowed)
			(vias allowed)
			(pads allowed)
			(copperpour not_allowed)
			(footprints allowed)
		)
		(placement
			(enabled no)
			(sheetname "")
		)
		(fill yes
			(thermal_gap 0.5)
			(thermal_bridge_width 0.5)
			(island_removal_mode 0)
		)
		(polygon
			(pts
				(arc
					(start 396.87627 -312.999882)
					(mid 396.22349 -312.999882)
					(end 396.87627 -312.999882)
				)
			)
		)
	)
	(zone
		(layers "B.Cu" "In15.Cu")
		(hatch none 0.5)
		(connect_pads
			(clearance 0)
		)
		(min_thickness 0.25)
		(keepout
			(tracks not_allowed)
			(vias allowed)
			(pads allowed)
			(copperpour not_allowed)
			(footprints allowed)
		)
		(placement
			(enabled no)
			(sheetname "")
		)
		(fill yes
			(thermal_gap 0.5)
			(thermal_bridge_width 0.5)
			(island_removal_mode 0)
		)
		(polygon
			(pts
				(arc
					(start 72.28967 -408.190192)
					(mid 71.53021 -408.190192)
					(end 72.28967 -408.190192)
				)
			)
		)
	)
	(zone
		(layers "B.Cu" "In15.Cu")
		(hatch none 0.5)
		(connect_pads
			(clearance 0)
		)
		(min_thickness 0.25)
		(keepout
			(tracks not_allowed)
			(vias allowed)
			(pads allowed)
			(copperpour not_allowed)
			(footprints allowed)
		)
		(placement
			(enabled no)
			(sheetname "")
		)
		(fill yes
			(thermal_gap 0.5)
			(thermal_bridge_width 0.5)
			(island_removal_mode 0)
		)
		(polygon
			(pts
				(arc
					(start 276.976078 -313.949842)
					(mid 276.323298 -313.949842)
					(end 276.976078 -313.949842)
				)
			)
		)
	)
	(zone
		(layers "B.Cu" "In15.Cu")
		(hatch none 0.5)
		(connect_pads
			(clearance 0)
		)
		(min_thickness 0.25)
		(keepout
			(tracks not_allowed)
			(vias allowed)
			(pads allowed)
			(copperpour not_allowed)
			(footprints allowed)
		)
		(placement
			(enabled no)
			(sheetname "")
		)
		(fill yes
			(thermal_gap 0.5)
			(thermal_bridge_width 0.5)
			(island_removal_mode 0)
		)
		(polygon
			(pts
				(arc
					(start 52.376324 -312.999882)
					(mid 51.723544 -312.999882)
					(end 52.376324 -312.999882)
				)
			)
		)
	)
	(zone
		(layers "B.Cu" "In15.Cu")
		(hatch none 0.5)
		(connect_pads
			(clearance 0)
		)
		(min_thickness 0.25)
		(keepout
			(tracks not_allowed)
			(vias allowed)
			(pads allowed)
			(copperpour not_allowed)
			(footprints allowed)
		)
		(placement
			(enabled no)
			(sheetname "")
		)
		(fill yes
			(thermal_gap 0.5)
			(thermal_bridge_width 0.5)
			(island_removal_mode 0)
		)
		(polygon
			(pts
				(arc
					(start 93.677232 -357.75773)
					(mid 92.973652 -357.75773)
					(end 93.677232 -357.75773)
				)
			)
		)
	)
	(zone
		(layers "B.Cu" "In15.Cu")
		(hatch none 0.5)
		(connect_pads
			(clearance 0)
		)
		(min_thickness 0.25)
		(keepout
			(tracks not_allowed)
			(vias allowed)
			(pads allowed)
			(copperpour not_allowed)
			(footprints allowed)
		)
		(placement
			(enabled no)
			(sheetname "")
		)
		(fill yes
			(thermal_gap 0.5)
			(thermal_bridge_width 0.5)
			(island_removal_mode 0)
		)
		(polygon
			(pts
				(arc
					(start 386.869686 -410.589984)
					(mid 386.110226 -410.589984)
					(end 386.869686 -410.589984)
				)
			)
		)
	)
	(zone
		(layers "B.Cu" "In15.Cu")
		(hatch none 0.5)
		(connect_pads
			(clearance 0)
		)
		(min_thickness 0.25)
		(keepout
			(tracks not_allowed)
			(vias allowed)
			(pads allowed)
			(copperpour not_allowed)
			(footprints allowed)
		)
		(placement
			(enabled no)
			(sheetname "")
		)
		(fill yes
			(thermal_gap 0.5)
			(thermal_bridge_width 0.5)
			(island_removal_mode 0)
		)
		(polygon
			(pts
				(arc
					(start 340.835234 -348.58579)
					(mid 340.131654 -348.58579)
					(end 340.835234 -348.58579)
				)
			)
		)
	)
	(zone
		(layers "B.Cu" "In15.Cu")
		(hatch none 0.5)
		(connect_pads
			(clearance 0)
		)
		(min_thickness 0.25)
		(keepout
			(tracks not_allowed)
			(vias allowed)
			(pads allowed)
			(copperpour not_allowed)
			(footprints allowed)
		)
		(placement
			(enabled no)
			(sheetname "")
		)
		(fill yes
			(thermal_gap 0.5)
			(thermal_bridge_width 0.5)
			(island_removal_mode 0)
		)
		(polygon
			(pts
				(arc
					(start 74.489564 -410.589984)
					(mid 73.730104 -410.589984)
					(end 74.489564 -410.589984)
				)
			)
		)
	)
	(zone
		(layers "B.Cu" "In15.Cu")
		(hatch none 0.5)
		(connect_pads
			(clearance 0)
		)
		(min_thickness 0.25)
		(keepout
			(tracks not_allowed)
			(vias allowed)
			(pads allowed)
			(copperpour not_allowed)
			(footprints allowed)
		)
		(placement
			(enabled no)
			(sheetname "")
		)
		(fill yes
			(thermal_gap 0.5)
			(thermal_bridge_width 0.5)
			(island_removal_mode 0)
		)
		(polygon
			(pts
				(arc
					(start 75.023472 -345.465146)
					(mid 74.319892 -345.465146)
					(end 75.023472 -345.465146)
				)
			)
		)
	)
	(zone
		(layers "B.Cu" "In15.Cu")
		(hatch none 0.5)
		(connect_pads
			(clearance 0)
		)
		(min_thickness 0.25)
		(keepout
			(tracks not_allowed)
			(vias allowed)
			(pads allowed)
			(copperpour not_allowed)
			(footprints allowed)
		)
		(placement
			(enabled no)
			(sheetname "")
		)
		(fill yes
			(thermal_gap 0.5)
			(thermal_bridge_width 0.5)
			(island_removal_mode 0)
		)
		(polygon
			(pts
				(arc
					(start 323.045074 -351.611438)
					(mid 322.341494 -351.611438)
					(end 323.045074 -351.611438)
				)
			)
		)
	)
	(zone
		(layers "B.Cu" "In15.Cu")
		(hatch none 0.5)
		(connect_pads
			(clearance 0)
		)
		(min_thickness 0.25)
		(keepout
			(tracks not_allowed)
			(vias allowed)
			(pads allowed)
			(copperpour not_allowed)
			(footprints allowed)
		)
		(placement
			(enabled no)
			(sheetname "")
		)
		(fill yes
			(thermal_gap 0.5)
			(thermal_bridge_width 0.5)
			(island_removal_mode 0)
		)
		(polygon
			(pts
				(arc
					(start 396.41145 -357.75773)
					(mid 395.70787 -357.75773)
					(end 396.41145 -357.75773)
				)
			)
		)
	)
	(zone
		(layers "B.Cu" "In15.Cu")
		(hatch none 0.5)
		(connect_pads
			(clearance 0)
		)
		(min_thickness 0.25)
		(keepout
			(tracks not_allowed)
			(vias allowed)
			(pads allowed)
			(copperpour not_allowed)
			(footprints allowed)
		)
		(placement
			(enabled no)
			(sheetname "")
		)
		(fill yes
			(thermal_gap 0.5)
			(thermal_bridge_width 0.5)
			(island_removal_mode 0)
		)
		(polygon
			(pts
				(arc
					(start 418.726366 -312.049922)
					(mid 418.073586 -312.049922)
					(end 418.726366 -312.049922)
				)
			)
		)
	)
	(zone
		(layers "B.Cu" "In15.Cu")
		(hatch none 0.5)
		(connect_pads
			(clearance 0)
		)
		(min_thickness 0.25)
		(keepout
			(tracks not_allowed)
			(vias allowed)
			(pads allowed)
			(copperpour not_allowed)
			(footprints allowed)
		)
		(placement
			(enabled no)
			(sheetname "")
		)
		(fill yes
			(thermal_gap 0.5)
			(thermal_bridge_width 0.5)
			(island_removal_mode 0)
		)
		(polygon
			(pts
				(arc
					(start 334.06969 -409.290012)
					(mid 333.31023 -409.290012)
					(end 334.06969 -409.290012)
				)
			)
		)
	)
	(zone
		(layers "B.Cu" "In15.Cu")
		(hatch none 0.5)
		(connect_pads
			(clearance 0)
		)
		(min_thickness 0.25)
		(keepout
			(tracks not_allowed)
			(vias allowed)
			(pads allowed)
			(copperpour not_allowed)
			(footprints allowed)
		)
		(placement
			(enabled no)
			(sheetname "")
		)
		(fill yes
			(thermal_gap 0.5)
			(thermal_bridge_width 0.5)
			(island_removal_mode 0)
		)
		(polygon
			(pts
				(arc
					(start 378.62129 -357.75773)
					(mid 377.91771 -357.75773)
					(end 378.62129 -357.75773)
				)
			)
		)
	)
	(zone
		(layers "B.Cu" "In15.Cu")
		(hatch none 0.5)
		(connect_pads
			(clearance 0)
		)
		(min_thickness 0.25)
		(keepout
			(tracks not_allowed)
			(vias allowed)
			(pads allowed)
			(copperpour not_allowed)
			(footprints allowed)
		)
		(placement
			(enabled no)
			(sheetname "")
		)
		(fill yes
			(thermal_gap 0.5)
			(thermal_bridge_width 0.5)
			(island_removal_mode 0)
		)
		(polygon
			(pts
				(arc
					(start 137.085578 -342.439498)
					(mid 136.381998 -342.439498)
					(end 137.085578 -342.439498)
				)
			)
		)
	)
	(zone
		(layers "B.Cu" "In15.Cu")
		(hatch none 0.5)
		(connect_pads
			(clearance 0)
		)
		(min_thickness 0.25)
		(keepout
			(tracks not_allowed)
			(vias allowed)
			(pads allowed)
			(copperpour not_allowed)
			(footprints allowed)
		)
		(placement
			(enabled no)
			(sheetname "")
		)
		(fill yes
			(thermal_gap 0.5)
			(thermal_bridge_width 0.5)
			(island_removal_mode 0)
		)
		(polygon
			(pts
				(arc
					(start 279.826212 -311.099962)
					(mid 279.173432 -311.099962)
					(end 279.826212 -311.099962)
				)
			)
		)
	)
	(zone
		(layers "B.Cu" "In15.Cu")
		(hatch none 0.5)
		(connect_pads
			(clearance 0)
		)
		(min_thickness 0.25)
		(keepout
			(tracks not_allowed)
			(vias allowed)
			(pads allowed)
			(copperpour not_allowed)
			(footprints allowed)
		)
		(placement
			(enabled no)
			(sheetname "")
		)
		(fill yes
			(thermal_gap 0.5)
			(thermal_bridge_width 0.5)
			(island_removal_mode 0)
		)
		(polygon
			(pts
				(arc
					(start 87.459312 -342.439498)
					(mid 86.755732 -342.439498)
					(end 87.459312 -342.439498)
				)
			)
		)
	)
	(zone
		(layers "B.Cu" "In15.Cu")
		(hatch none 0.5)
		(connect_pads
			(clearance 0)
		)
		(min_thickness 0.25)
		(keepout
			(tracks not_allowed)
			(vias allowed)
			(pads allowed)
			(copperpour not_allowed)
			(footprints allowed)
		)
		(placement
			(enabled no)
			(sheetname "")
		)
		(fill yes
			(thermal_gap 0.5)
			(thermal_bridge_width 0.5)
			(island_removal_mode 0)
		)
		(polygon
			(pts
				(arc
					(start 394.16609 -348.58579)
					(mid 393.46251 -348.58579)
					(end 394.16609 -348.58579)
				)
			)
		)
	)
	(zone
		(layers "B.Cu" "In15.Cu")
		(hatch none 0.5)
		(connect_pads
			(clearance 0)
		)
		(min_thickness 0.25)
		(keepout
			(tracks not_allowed)
			(vias allowed)
			(pads allowed)
			(copperpour not_allowed)
			(footprints allowed)
		)
		(placement
			(enabled no)
			(sheetname "")
		)
		(fill yes
			(thermal_gap 0.5)
			(thermal_bridge_width 0.5)
			(island_removal_mode 0)
		)
		(polygon
			(pts
				(arc
					(start 183.67629 -313.949842)
					(mid 183.02351 -313.949842)
					(end 183.67629 -313.949842)
				)
			)
		)
	)
	(zone
		(layers "B.Cu" "In15.Cu")
		(hatch none 0.5)
		(connect_pads
			(clearance 0)
		)
		(min_thickness 0.25)
		(keepout
			(tracks not_allowed)
			(vias allowed)
			(pads allowed)
			(copperpour not_allowed)
			(footprints allowed)
		)
		(placement
			(enabled no)
			(sheetname "")
		)
		(fill yes
			(thermal_gap 0.5)
			(thermal_bridge_width 0.5)
			(island_removal_mode 0)
		)
		(polygon
			(pts
				(arc
					(start 160.876234 -313.949842)
					(mid 160.223454 -313.949842)
					(end 160.876234 -313.949842)
				)
			)
		)
	)
	(zone
		(layers "B.Cu" "In15.Cu")
		(hatch none 0.5)
		(connect_pads
			(clearance 0)
		)
		(min_thickness 0.25)
		(keepout
			(tracks not_allowed)
			(vias allowed)
			(pads allowed)
			(copperpour not_allowed)
			(footprints allowed)
		)
		(placement
			(enabled no)
			(sheetname "")
		)
		(fill yes
			(thermal_gap 0.5)
			(thermal_bridge_width 0.5)
			(island_removal_mode 0)
		)
		(polygon
			(pts
				(arc
					(start 140.194538 -348.58579)
					(mid 139.490958 -348.58579)
					(end 140.194538 -348.58579)
				)
			)
		)
	)
	(zone
		(layers "B.Cu" "In15.Cu")
		(hatch none 0.5)
		(connect_pads
			(clearance 0)
		)
		(min_thickness 0.25)
		(keepout
			(tracks not_allowed)
			(vias allowed)
			(pads allowed)
			(copperpour not_allowed)
			(footprints allowed)
		)
		(placement
			(enabled no)
			(sheetname "")
		)
		(fill yes
			(thermal_gap 0.5)
			(thermal_bridge_width 0.5)
			(island_removal_mode 0)
		)
		(polygon
			(pts
				(arc
					(start 125.513338 -357.75773)
					(mid 124.809758 -357.75773)
					(end 125.513338 -357.75773)
				)
			)
		)
	)
	(zone
		(layers "B.Cu" "In15.Cu")
		(hatch none 0.5)
		(connect_pads
			(clearance 0)
		)
		(min_thickness 0.25)
		(keepout
			(tracks not_allowed)
			(vias allowed)
			(pads allowed)
			(copperpour not_allowed)
			(footprints allowed)
		)
		(placement
			(enabled no)
			(sheetname "")
		)
		(fill yes
			(thermal_gap 0.5)
			(thermal_bridge_width 0.5)
			(island_removal_mode 0)
		)
		(polygon
			(pts
				(arc
					(start 391.269728 -409.290012)
					(mid 390.510268 -409.290012)
					(end 391.269728 -409.290012)
				)
			)
		)
	)
	(zone
		(layers "B.Cu" "In15.Cu")
		(hatch none 0.5)
		(connect_pads
			(clearance 0)
		)
		(min_thickness 0.25)
		(keepout
			(tracks not_allowed)
			(vias allowed)
			(pads allowed)
			(copperpour not_allowed)
			(footprints allowed)
		)
		(placement
			(enabled no)
			(sheetname "")
		)
		(fill yes
			(thermal_gap 0.5)
			(thermal_bridge_width 0.5)
			(island_removal_mode 0)
		)
		(polygon
			(pts
				(arc
					(start 378.069602 -409.290012)
					(mid 377.310142 -409.290012)
					(end 378.069602 -409.290012)
				)
			)
		)
	)
	(zone
		(layers "B.Cu" "In15.Cu")
		(hatch none 0.5)
		(connect_pads
			(clearance 0)
		)
		(min_thickness 0.25)
		(keepout
			(tracks not_allowed)
			(vias allowed)
			(pads allowed)
			(copperpour not_allowed)
			(footprints allowed)
		)
		(placement
			(enabled no)
			(sheetname "")
		)
		(fill yes
			(thermal_gap 0.5)
			(thermal_bridge_width 0.5)
			(island_removal_mode 0)
		)
		(polygon
			(pts
				(arc
					(start 58.073036 -371.310662)
					(mid 57.369456 -371.310662)
					(end 58.073036 -371.310662)
				)
			)
		)
	)
	(zone
		(layers "B.Cu" "In15.Cu")
		(hatch none 0.5)
		(connect_pads
			(clearance 0)
		)
		(min_thickness 0.25)
		(keepout
			(tracks not_allowed)
			(vias allowed)
			(pads allowed)
			(copperpour not_allowed)
			(footprints allowed)
		)
		(placement
			(enabled no)
			(sheetname "")
		)
		(fill yes
			(thermal_gap 0.5)
			(thermal_bridge_width 0.5)
			(island_removal_mode 0)
		)
		(polygon
			(pts
				(arc
					(start 287.426146 -311.099962)
					(mid 286.773366 -311.099962)
					(end 287.426146 -311.099962)
				)
			)
		)
	)
	(zone
		(layers "B.Cu" "In15.Cu")
		(hatch none 0.5)
		(connect_pads
			(clearance 0)
		)
		(min_thickness 0.25)
		(keepout
			(tracks not_allowed)
			(vias allowed)
			(pads allowed)
			(copperpour not_allowed)
			(footprints allowed)
		)
		(placement
			(enabled no)
			(sheetname "")
		)
		(fill yes
			(thermal_gap 0.5)
			(thermal_bridge_width 0.5)
			(island_removal_mode 0)
		)
		(polygon
			(pts
				(arc
					(start 78.889606 -409.290012)
					(mid 78.130146 -409.290012)
					(end 78.889606 -409.290012)
				)
			)
		)
	)
	(zone
		(layers "B.Cu" "In15.Cu")
		(hatch none 0.5)
		(connect_pads
			(clearance 0)
		)
		(min_thickness 0.25)
		(keepout
			(tracks not_allowed)
			(vias allowed)
			(pads allowed)
			(copperpour not_allowed)
			(footprints allowed)
		)
		(placement
			(enabled no)
			(sheetname "")
		)
		(fill yes
			(thermal_gap 0.5)
			(thermal_bridge_width 0.5)
			(island_removal_mode 0)
		)
		(polygon
			(pts
				(arc
					(start 383.97561 -345.465146)
					(mid 383.27203 -345.465146)
					(end 383.97561 -345.465146)
				)
			)
		)
	)
	(zone
		(layers "B.Cu" "In15.Cu")
		(hatch none 0.5)
		(connect_pads
			(clearance 0)
		)
		(min_thickness 0.25)
		(keepout
			(tracks not_allowed)
			(vias allowed)
			(pads allowed)
			(copperpour not_allowed)
			(footprints allowed)
		)
		(placement
			(enabled no)
			(sheetname "")
		)
		(fill yes
			(thermal_gap 0.5)
			(thermal_bridge_width 0.5)
			(island_removal_mode 0)
		)
		(polygon
			(pts
				(arc
					(start 395.92631 -311.099962)
					(mid 395.27353 -311.099962)
					(end 395.92631 -311.099962)
				)
			)
		)
	)
	(zone
		(layers "B.Cu" "In15.Cu")
		(hatch none 0.5)
		(connect_pads
			(clearance 0)
		)
		(min_thickness 0.25)
		(keepout
			(tracks not_allowed)
			(vias allowed)
			(pads allowed)
			(copperpour not_allowed)
			(footprints allowed)
		)
		(placement
			(enabled no)
			(sheetname "")
		)
		(fill yes
			(thermal_gap 0.5)
			(thermal_bridge_width 0.5)
			(island_removal_mode 0)
		)
		(polygon
			(pts
				(arc
					(start 336.269838 -409.490164)
					(mid 335.510378 -409.490164)
					(end 336.269838 -409.490164)
				)
			)
		)
	)
	(zone
		(layers "B.Cu" "In15.Cu")
		(hatch none 0.5)
		(connect_pads
			(clearance 0)
		)
		(min_thickness 0.25)
		(keepout
			(tracks not_allowed)
			(vias allowed)
			(pads allowed)
			(copperpour not_allowed)
			(footprints allowed)
		)
		(placement
			(enabled no)
			(sheetname "")
		)
		(fill yes
			(thermal_gap 0.5)
			(thermal_bridge_width 0.5)
			(island_removal_mode 0)
		)
		(polygon
			(pts
				(arc
					(start 396.41145 -345.465146)
					(mid 395.70787 -345.465146)
					(end 396.41145 -345.465146)
				)
			)
		)
	)
	(zone
		(layers "B.Cu" "In15.Cu")
		(hatch none 0.5)
		(connect_pads
			(clearance 0)
		)
		(min_thickness 0.25)
		(keepout
			(tracks not_allowed)
			(vias allowed)
			(pads allowed)
			(copperpour not_allowed)
			(footprints allowed)
		)
		(placement
			(enabled no)
			(sheetname "")
		)
		(fill yes
			(thermal_gap 0.5)
			(thermal_bridge_width 0.5)
			(island_removal_mode 0)
		)
		(polygon
			(pts
				(arc
					(start 336.269838 -382.18999)
					(mid 335.510378 -382.18999)
					(end 336.269838 -382.18999)
				)
			)
		)
	)
	(zone
		(layers "B.Cu" "In15.Cu")
		(hatch none 0.5)
		(connect_pads
			(clearance 0)
		)
		(min_thickness 0.25)
		(keepout
			(tracks not_allowed)
			(vias allowed)
			(pads allowed)
			(copperpour not_allowed)
			(footprints allowed)
		)
		(placement
			(enabled no)
			(sheetname "")
		)
		(fill yes
			(thermal_gap 0.5)
			(thermal_bridge_width 0.5)
			(island_removal_mode 0)
		)
		(polygon
			(pts
				(arc
					(start 186.526424 -312.049922)
					(mid 185.873644 -312.049922)
					(end 186.526424 -312.049922)
				)
			)
		)
	)
	(zone
		(layers "B.Cu" "In15.Cu")
		(hatch none 0.5)
		(connect_pads
			(clearance 0)
		)
		(min_thickness 0.25)
		(keepout
			(tracks not_allowed)
			(vias allowed)
			(pads allowed)
			(copperpour not_allowed)
			(footprints allowed)
		)
		(placement
			(enabled no)
			(sheetname "")
		)
		(fill yes
			(thermal_gap 0.5)
			(thermal_bridge_width 0.5)
			(island_removal_mode 0)
		)
		(polygon
			(pts
				(arc
					(start 81.241392 -357.75773)
					(mid 80.537812 -357.75773)
					(end 81.241392 -357.75773)
				)
			)
		)
	)
	(zone
		(layers "B.Cu" "In15.Cu")
		(hatch none 0.5)
		(connect_pads
			(clearance 0)
		)
		(min_thickness 0.25)
		(keepout
			(tracks not_allowed)
			(vias allowed)
			(pads allowed)
			(copperpour not_allowed)
			(footprints allowed)
		)
		(placement
			(enabled no)
			(sheetname "")
		)
		(fill yes
			(thermal_gap 0.5)
			(thermal_bridge_width 0.5)
			(island_removal_mode 0)
		)
		(polygon
			(pts
				(arc
					(start 125.08992 -379.590046)
					(mid 124.33046 -379.590046)
					(end 125.08992 -379.590046)
				)
			)
		)
	)
	(zone
		(layers "B.Cu" "In15.Cu")
		(hatch none 0.5)
		(connect_pads
			(clearance 0)
		)
		(min_thickness 0.25)
		(keepout
			(tracks not_allowed)
			(vias allowed)
			(pads allowed)
			(copperpour not_allowed)
			(footprints allowed)
		)
		(placement
			(enabled no)
			(sheetname "")
		)
		(fill yes
			(thermal_gap 0.5)
			(thermal_bridge_width 0.5)
			(island_removal_mode 0)
		)
		(polygon
			(pts
				(arc
					(start 332.371954 -342.439498)
					(mid 331.668374 -342.439498)
					(end 332.371954 -342.439498)
				)
			)
		)
	)
	(zone
		(layers "B.Cu" "In15.Cu")
		(hatch none 0.5)
		(connect_pads
			(clearance 0)
		)
		(min_thickness 0.25)
		(keepout
			(tracks not_allowed)
			(vias allowed)
			(pads allowed)
			(copperpour not_allowed)
			(footprints allowed)
		)
		(placement
			(enabled no)
			(sheetname "")
		)
		(fill yes
			(thermal_gap 0.5)
			(thermal_bridge_width 0.5)
			(island_removal_mode 0)
		)
		(polygon
			(pts
				(arc
					(start 143.303498 -345.465146)
					(mid 142.599918 -345.465146)
					(end 143.303498 -345.465146)
				)
			)
		)
	)
	(zone
		(layers "B.Cu" "In15.Cu")
		(hatch none 0.5)
		(connect_pads
			(clearance 0)
		)
		(min_thickness 0.25)
		(keepout
			(tracks not_allowed)
			(vias allowed)
			(pads allowed)
			(copperpour not_allowed)
			(footprints allowed)
		)
		(placement
			(enabled no)
			(sheetname "")
		)
		(fill yes
			(thermal_gap 0.5)
			(thermal_bridge_width 0.5)
			(island_removal_mode 0)
		)
		(polygon
			(pts
				(arc
					(start 44.776136 -313.949842)
					(mid 44.123356 -313.949842)
					(end 44.776136 -313.949842)
				)
			)
		)
	)
	(zone
		(layers "B.Cu" "In15.Cu")
		(hatch none 0.5)
		(connect_pads
			(clearance 0)
		)
		(min_thickness 0.25)
		(keepout
			(tracks not_allowed)
			(vias allowed)
			(pads allowed)
			(copperpour not_allowed)
			(footprints allowed)
		)
		(placement
			(enabled no)
			(sheetname "")
		)
		(fill yes
			(thermal_gap 0.5)
			(thermal_bridge_width 0.5)
			(island_removal_mode 0)
		)
		(polygon
			(pts
				(arc
					(start 290.27628 -312.999882)
					(mid 289.6235 -312.999882)
					(end 290.27628 -312.999882)
				)
			)
		)
	)
	(zone
		(layers "B.Cu" "In15.Cu")
		(hatch none 0.5)
		(connect_pads
			(clearance 0)
		)
		(min_thickness 0.25)
		(keepout
			(tracks not_allowed)
			(vias allowed)
			(pads allowed)
			(copperpour not_allowed)
			(footprints allowed)
		)
		(placement
			(enabled no)
			(sheetname "")
		)
		(fill yes
			(thermal_gap 0.5)
			(thermal_bridge_width 0.5)
			(island_removal_mode 0)
		)
		(polygon
			(pts
				(arc
					(start 343.944194 -354.732082)
					(mid 343.240614 -354.732082)
					(end 343.944194 -354.732082)
				)
			)
		)
	)
	(zone
		(layers "B.Cu" "In15.Cu")
		(hatch none 0.5)
		(connect_pads
			(clearance 0)
		)
		(min_thickness 0.25)
		(keepout
			(tracks not_allowed)
			(vias allowed)
			(pads allowed)
			(copperpour not_allowed)
			(footprints allowed)
		)
		(placement
			(enabled no)
			(sheetname "")
		)
		(fill yes
			(thermal_gap 0.5)
			(thermal_bridge_width 0.5)
			(island_removal_mode 0)
		)
		(polygon
			(pts
				(arc
					(start 343.944194 -342.439498)
					(mid 343.240614 -342.439498)
					(end 343.944194 -342.439498)
				)
			)
		)
	)
	(zone
		(layers "B.Cu" "In15.Cu")
		(hatch none 0.5)
		(connect_pads
			(clearance 0)
		)
		(min_thickness 0.25)
		(keepout
			(tracks not_allowed)
			(vias allowed)
			(pads allowed)
			(copperpour not_allowed)
			(footprints allowed)
		)
		(placement
			(enabled no)
			(sheetname "")
		)
		(fill yes
			(thermal_gap 0.5)
			(thermal_bridge_width 0.5)
			(island_removal_mode 0)
		)
		(polygon
			(pts
				(arc
					(start 55.226204 -312.049922)
					(mid 54.573424 -312.049922)
					(end 55.226204 -312.049922)
				)
			)
		)
	)
	(zone
		(layers "B.Cu" "In15.Cu")
		(hatch none 0.5)
		(connect_pads
			(clearance 0)
		)
		(min_thickness 0.25)
		(keepout
			(tracks not_allowed)
			(vias allowed)
			(pads allowed)
			(copperpour not_allowed)
			(footprints allowed)
		)
		(placement
			(enabled no)
			(sheetname "")
		)
		(fill yes
			(thermal_gap 0.5)
			(thermal_bridge_width 0.5)
			(island_removal_mode 0)
		)
		(polygon
			(pts
				(arc
					(start 375.51233 -351.611438)
					(mid 374.80875 -351.611438)
					(end 375.51233 -351.611438)
				)
			)
		)
	)
	(zone
		(layers "B.Cu" "In15.Cu")
		(hatch none 0.5)
		(connect_pads
			(clearance 0)
		)
		(min_thickness 0.25)
		(keepout
			(tracks not_allowed)
			(vias allowed)
			(pads allowed)
			(copperpour not_allowed)
			(footprints allowed)
		)
		(placement
			(enabled no)
			(sheetname "")
		)
		(fill yes
			(thermal_gap 0.5)
			(thermal_bridge_width 0.5)
			(island_removal_mode 0)
		)
		(polygon
			(pts
				(arc
					(start 115.322858 -348.58579)
					(mid 114.619278 -348.58579)
					(end 115.322858 -348.58579)
				)
			)
		)
	)
	(zone
		(layers "B.Cu" "In15.Cu")
		(hatch none 0.5)
		(connect_pads
			(clearance 0)
		)
		(min_thickness 0.25)
		(keepout
			(tracks not_allowed)
			(vias allowed)
			(pads allowed)
			(copperpour not_allowed)
			(footprints allowed)
		)
		(placement
			(enabled no)
			(sheetname "")
		)
		(fill yes
			(thermal_gap 0.5)
			(thermal_bridge_width 0.5)
			(island_removal_mode 0)
		)
		(polygon
			(pts
				(arc
					(start 182.72633 -311.099962)
					(mid 182.07355 -311.099962)
					(end 182.72633 -311.099962)
				)
			)
		)
	)
	(zone
		(layers "B.Cu" "In15.Cu")
		(hatch none 0.5)
		(connect_pads
			(clearance 0)
		)
		(min_thickness 0.25)
		(keepout
			(tracks not_allowed)
			(vias allowed)
			(pads allowed)
			(copperpour not_allowed)
			(footprints allowed)
		)
		(placement
			(enabled no)
			(sheetname "")
		)
		(fill yes
			(thermal_gap 0.5)
			(thermal_bridge_width 0.5)
			(island_removal_mode 0)
		)
		(polygon
			(pts
				(arc
					(start 326.154034 -342.439498)
					(mid 325.450454 -342.439498)
					(end 326.154034 -342.439498)
				)
			)
		)
	)
	(zone
		(layers "B.Cu" "In15.Cu")
		(hatch none 0.5)
		(connect_pads
			(clearance 0)
		)
		(min_thickness 0.25)
		(keepout
			(tracks not_allowed)
			(vias allowed)
			(pads allowed)
			(copperpour not_allowed)
			(footprints allowed)
		)
		(placement
			(enabled no)
			(sheetname "")
		)
		(fill yes
			(thermal_gap 0.5)
			(thermal_bridge_width 0.5)
			(island_removal_mode 0)
		)
		(polygon
			(pts
				(arc
					(start 282.676092 -312.999882)
					(mid 282.023312 -312.999882)
					(end 282.676092 -312.999882)
				)
			)
		)
	)
	(zone
		(layers "B.Cu" "In15.Cu")
		(hatch none 0.5)
		(connect_pads
			(clearance 0)
		)
		(min_thickness 0.25)
		(keepout
			(tracks not_allowed)
			(vias allowed)
			(pads allowed)
			(copperpour not_allowed)
			(footprints allowed)
		)
		(placement
			(enabled no)
			(sheetname "")
		)
		(fill yes
			(thermal_gap 0.5)
			(thermal_bridge_width 0.5)
			(island_removal_mode 0)
		)
		(polygon
			(pts
				(arc
					(start 51.426364 -312.049922)
					(mid 50.773584 -312.049922)
					(end 51.426364 -312.049922)
				)
			)
		)
	)
	(zone
		(layers "B.Cu" "In15.Cu")
		(hatch none 0.5)
		(connect_pads
			(clearance 0)
		)
		(min_thickness 0.25)
		(keepout
			(tracks not_allowed)
			(vias allowed)
			(pads allowed)
			(copperpour not_allowed)
			(footprints allowed)
		)
		(placement
			(enabled no)
			(sheetname "")
		)
		(fill yes
			(thermal_gap 0.5)
			(thermal_bridge_width 0.5)
			(island_removal_mode 0)
		)
		(polygon
			(pts
				(arc
					(start 125.513338 -342.439498)
					(mid 124.809758 -342.439498)
					(end 125.513338 -342.439498)
				)
			)
		)
	)
	(zone
		(layers "B.Cu" "In15.Cu")
		(hatch none 0.5)
		(connect_pads
			(clearance 0)
		)
		(min_thickness 0.25)
		(keepout
			(tracks not_allowed)
			(vias allowed)
			(pads allowed)
			(copperpour not_allowed)
			(footprints allowed)
		)
		(placement
			(enabled no)
			(sheetname "")
		)
		(fill yes
			(thermal_gap 0.5)
			(thermal_bridge_width 0.5)
			(island_removal_mode 0)
		)
		(polygon
			(pts
				(arc
					(start 45.72635 -312.049922)
					(mid 45.07357 -312.049922)
					(end 45.72635 -312.049922)
				)
			)
		)
	)
	(zone
		(layers "B.Cu" "In15.Cu")
		(hatch none 0.5)
		(connect_pads
			(clearance 0)
		)
		(min_thickness 0.25)
		(keepout
			(tracks not_allowed)
			(vias allowed)
			(pads allowed)
			(copperpour not_allowed)
			(footprints allowed)
		)
		(placement
			(enabled no)
			(sheetname "")
		)
		(fill yes
			(thermal_gap 0.5)
			(thermal_bridge_width 0.5)
			(island_removal_mode 0)
		)
		(polygon
			(pts
				(arc
					(start 112.213898 -342.439498)
					(mid 111.510318 -342.439498)
					(end 112.213898 -342.439498)
				)
			)
		)
	)
	(zone
		(layers "B.Cu" "In15.Cu")
		(hatch none 0.5)
		(connect_pads
			(clearance 0)
		)
		(min_thickness 0.25)
		(keepout
			(tracks not_allowed)
			(vias allowed)
			(pads allowed)
			(copperpour not_allowed)
			(footprints allowed)
		)
		(placement
			(enabled no)
			(sheetname "")
		)
		(fill yes
			(thermal_gap 0.5)
			(thermal_bridge_width 0.5)
			(island_removal_mode 0)
		)
		(polygon
			(pts
				(arc
					(start 89.704672 -351.611438)
					(mid 89.001092 -351.611438)
					(end 89.704672 -351.611438)
				)
			)
		)
	)
	(zone
		(layers "B.Cu" "In15.Cu")
		(hatch none 0.5)
		(connect_pads
			(clearance 0)
		)
		(min_thickness 0.25)
		(keepout
			(tracks not_allowed)
			(vias allowed)
			(pads allowed)
			(copperpour not_allowed)
			(footprints allowed)
		)
		(placement
			(enabled no)
			(sheetname "")
		)
		(fill yes
			(thermal_gap 0.5)
			(thermal_bridge_width 0.5)
			(island_removal_mode 0)
		)
		(polygon
			(pts
				(arc
					(start 384.83921 -354.732082)
					(mid 384.13563 -354.732082)
					(end 384.83921 -354.732082)
				)
			)
		)
	)
	(zone
		(layers "B.Cu" "In15.Cu")
		(hatch none 0.5)
		(connect_pads
			(clearance 0)
		)
		(min_thickness 0.25)
		(keepout
			(tracks not_allowed)
			(vias allowed)
			(pads allowed)
			(copperpour not_allowed)
			(footprints allowed)
		)
		(placement
			(enabled no)
			(sheetname "")
		)
		(fill yes
			(thermal_gap 0.5)
			(thermal_bridge_width 0.5)
			(island_removal_mode 0)
		)
		(polygon
			(pts
				(arc
					(start 160.876234 -312.999882)
					(mid 160.223454 -312.999882)
					(end 160.876234 -312.999882)
				)
			)
		)
	)
	(zone
		(layers "B.Cu" "In15.Cu")
		(hatch none 0.5)
		(connect_pads
			(clearance 0)
		)
		(min_thickness 0.25)
		(keepout
			(tracks not_allowed)
			(vias allowed)
			(pads allowed)
			(copperpour not_allowed)
			(footprints allowed)
		)
		(placement
			(enabled no)
			(sheetname "")
		)
		(fill yes
			(thermal_gap 0.5)
			(thermal_bridge_width 0.5)
			(island_removal_mode 0)
		)
		(polygon
			(pts
				(arc
					(start 387.08457 -351.611438)
					(mid 386.38099 -351.611438)
					(end 387.08457 -351.611438)
				)
			)
		)
	)
	(zone
		(layers "B.Cu" "In15.Cu")
		(hatch none 0.5)
		(connect_pads
			(clearance 0)
		)
		(min_thickness 0.25)
		(keepout
			(tracks not_allowed)
			(vias allowed)
			(pads allowed)
			(copperpour not_allowed)
			(footprints allowed)
		)
		(placement
			(enabled no)
			(sheetname "")
		)
		(fill yes
			(thermal_gap 0.5)
			(thermal_bridge_width 0.5)
			(island_removal_mode 0)
		)
		(polygon
			(pts
				(arc
					(start 47.62627 -311.099962)
					(mid 46.97349 -311.099962)
					(end 47.62627 -311.099962)
				)
			)
		)
	)
	(zone
		(layers "B.Cu" "In15.Cu")
		(hatch none 0.5)
		(connect_pads
			(clearance 0)
		)
		(min_thickness 0.25)
		(keepout
			(tracks not_allowed)
			(vias allowed)
			(pads allowed)
			(copperpour not_allowed)
			(footprints allowed)
		)
		(placement
			(enabled no)
			(sheetname "")
		)
		(fill yes
			(thermal_gap 0.5)
			(thermal_bridge_width 0.5)
			(island_removal_mode 0)
		)
		(polygon
			(pts
				(arc
					(start 400.38401 -348.58579)
					(mid 399.68043 -348.58579)
					(end 400.38401 -348.58579)
				)
			)
		)
	)
	(zone
		(layers "B.Cu" "In15.Cu")
		(hatch none 0.5)
		(connect_pads
			(clearance 0)
		)
		(min_thickness 0.25)
		(keepout
			(tracks not_allowed)
			(vias allowed)
			(pads allowed)
			(copperpour not_allowed)
			(footprints allowed)
		)
		(placement
			(enabled no)
			(sheetname "")
		)
		(fill yes
			(thermal_gap 0.5)
			(thermal_bridge_width 0.5)
			(island_removal_mode 0)
		)
		(polygon
			(pts
				(arc
					(start 392.126216 -312.049922)
					(mid 391.473436 -312.049922)
					(end 392.126216 -312.049922)
				)
			)
		)
	)
	(zone
		(layers "B.Cu" "In15.Cu")
		(hatch none 0.5)
		(connect_pads
			(clearance 0)
		)
		(min_thickness 0.25)
		(keepout
			(tracks not_allowed)
			(vias allowed)
			(pads allowed)
			(copperpour not_allowed)
			(footprints allowed)
		)
		(placement
			(enabled no)
			(sheetname "")
		)
		(fill yes
			(thermal_gap 0.5)
			(thermal_bridge_width 0.5)
			(island_removal_mode 0)
		)
		(polygon
			(pts
				(arc
					(start 391.269728 -380.69012)
					(mid 390.510268 -380.69012)
					(end 391.269728 -380.69012)
				)
			)
		)
	)
	(zone
		(layers "B.Cu" "In15.Cu")
		(hatch none 0.5)
		(connect_pads
			(clearance 0)
		)
		(min_thickness 0.25)
		(keepout
			(tracks not_allowed)
			(vias allowed)
			(pads allowed)
			(copperpour not_allowed)
			(footprints allowed)
		)
		(placement
			(enabled no)
			(sheetname "")
		)
		(fill yes
			(thermal_gap 0.5)
			(thermal_bridge_width 0.5)
			(island_removal_mode 0)
		)
		(polygon
			(pts
				(arc
					(start 80.377792 -357.75773)
					(mid 79.674212 -357.75773)
					(end 80.377792 -357.75773)
				)
			)
		)
	)
	(zone
		(layers "B.Cu" "In15.Cu")
		(hatch none 0.5)
		(connect_pads
			(clearance 0)
		)
		(min_thickness 0.25)
		(keepout
			(tracks not_allowed)
			(vias allowed)
			(pads allowed)
			(copperpour not_allowed)
			(footprints allowed)
		)
		(placement
			(enabled no)
			(sheetname "")
		)
		(fill yes
			(thermal_gap 0.5)
			(thermal_bridge_width 0.5)
			(island_removal_mode 0)
		)
		(polygon
			(pts
				(arc
					(start 77.268832 -348.58579)
					(mid 76.565252 -348.58579)
					(end 77.268832 -348.58579)
				)
			)
		)
	)
	(zone
		(layers "B.Cu" "In15.Cu")
		(hatch none 0.5)
		(connect_pads
			(clearance 0)
		)
		(min_thickness 0.25)
		(keepout
			(tracks not_allowed)
			(vias allowed)
			(pads allowed)
			(copperpour not_allowed)
			(footprints allowed)
		)
		(placement
			(enabled no)
			(sheetname "")
		)
		(fill yes
			(thermal_gap 0.5)
			(thermal_bridge_width 0.5)
			(island_removal_mode 0)
		)
		(polygon
			(pts
				(arc
					(start 394.97635 -313.949842)
					(mid 394.32357 -313.949842)
					(end 394.97635 -313.949842)
				)
			)
		)
	)
	(zone
		(layers "B.Cu" "In15.Cu")
		(hatch none 0.5)
		(connect_pads
			(clearance 0)
		)
		(min_thickness 0.25)
		(keepout
			(tracks not_allowed)
			(vias allowed)
			(pads allowed)
			(copperpour not_allowed)
			(footprints allowed)
		)
		(placement
			(enabled no)
			(sheetname "")
		)
		(fill yes
			(thermal_gap 0.5)
			(thermal_bridge_width 0.5)
			(island_removal_mode 0)
		)
		(polygon
			(pts
				(arc
					(start 43.826176 -312.049922)
					(mid 43.173396 -312.049922)
					(end 43.826176 -312.049922)
				)
			)
		)
	)
	(zone
		(layers "B.Cu" "In15.Cu")
		(hatch none 0.5)
		(connect_pads
			(clearance 0)
		)
		(min_thickness 0.25)
		(keepout
			(tracks not_allowed)
			(vias allowed)
			(pads allowed)
			(copperpour not_allowed)
			(footprints allowed)
		)
		(placement
			(enabled no)
			(sheetname "")
		)
		(fill yes
			(thermal_gap 0.5)
			(thermal_bridge_width 0.5)
			(island_removal_mode 0)
		)
		(polygon
			(pts
				(arc
					(start 58.073036 -370.447062)
					(mid 57.369456 -370.447062)
					(end 58.073036 -370.447062)
				)
			)
		)
	)
	(zone
		(layers "B.Cu" "In15.Cu")
		(hatch none 0.5)
		(connect_pads
			(clearance 0)
		)
		(min_thickness 0.25)
		(keepout
			(tracks not_allowed)
			(vias allowed)
			(pads allowed)
			(copperpour not_allowed)
			(footprints allowed)
		)
		(placement
			(enabled no)
			(sheetname "")
		)
		(fill yes
			(thermal_gap 0.5)
			(thermal_bridge_width 0.5)
			(island_removal_mode 0)
		)
		(polygon
			(pts
				(arc
					(start 319.072514 -342.439498)
					(mid 318.368934 -342.439498)
					(end 319.072514 -342.439498)
				)
			)
		)
	)
	(zone
		(layers "B.Cu" "In15.Cu")
		(hatch none 0.5)
		(connect_pads
			(clearance 0)
		)
		(min_thickness 0.25)
		(keepout
			(tracks not_allowed)
			(vias allowed)
			(pads allowed)
			(copperpour not_allowed)
			(footprints allowed)
		)
		(placement
			(enabled no)
			(sheetname "")
		)
		(fill yes
			(thermal_gap 0.5)
			(thermal_bridge_width 0.5)
			(island_removal_mode 0)
		)
		(polygon
			(pts
				(arc
					(start 74.159872 -345.465146)
					(mid 73.456292 -345.465146)
					(end 74.159872 -345.465146)
				)
			)
		)
	)
	(zone
		(layers "B.Cu" "In15.Cu")
		(hatch none 0.5)
		(connect_pads
			(clearance 0)
		)
		(min_thickness 0.25)
		(keepout
			(tracks not_allowed)
			(vias allowed)
			(pads allowed)
			(copperpour not_allowed)
			(footprints allowed)
		)
		(placement
			(enabled no)
			(sheetname "")
		)
		(fill yes
			(thermal_gap 0.5)
			(thermal_bridge_width 0.5)
			(island_removal_mode 0)
		)
		(polygon
			(pts
				(arc
					(start 124.649738 -342.439498)
					(mid 123.946158 -342.439498)
					(end 124.649738 -342.439498)
				)
			)
		)
	)
	(zone
		(layers "B.Cu" "In15.Cu")
		(hatch none 0.5)
		(connect_pads
			(clearance 0)
		)
		(min_thickness 0.25)
		(keepout
			(tracks not_allowed)
			(vias allowed)
			(pads allowed)
			(copperpour not_allowed)
			(footprints allowed)
		)
		(placement
			(enabled no)
			(sheetname "")
		)
		(fill yes
			(thermal_gap 0.5)
			(thermal_bridge_width 0.5)
			(island_removal_mode 0)
		)
		(polygon
			(pts
				(arc
					(start 344.807794 -342.439498)
					(mid 344.104214 -342.439498)
					(end 344.807794 -342.439498)
				)
			)
		)
	)
	(zone
		(layers "B.Cu" "In15.Cu")
		(hatch none 0.5)
		(connect_pads
			(clearance 0)
		)
		(min_thickness 0.25)
		(keepout
			(tracks not_allowed)
			(vias allowed)
			(pads allowed)
			(copperpour not_allowed)
			(footprints allowed)
		)
		(placement
			(enabled no)
			(sheetname "")
		)
		(fill yes
			(thermal_gap 0.5)
			(thermal_bridge_width 0.5)
			(island_removal_mode 0)
		)
		(polygon
			(pts
				(arc
					(start 74.159872 -357.75773)
					(mid 73.456292 -357.75773)
					(end 74.159872 -357.75773)
				)
			)
		)
	)
	(zone
		(layers "B.Cu" "In15.Cu")
		(hatch none 0.5)
		(connect_pads
			(clearance 0)
		)
		(min_thickness 0.25)
		(keepout
			(tracks not_allowed)
			(vias allowed)
			(pads allowed)
			(copperpour not_allowed)
			(footprints allowed)
		)
		(placement
			(enabled no)
			(sheetname "")
		)
		(fill yes
			(thermal_gap 0.5)
			(thermal_bridge_width 0.5)
			(island_removal_mode 0)
		)
		(polygon
			(pts
				(arc
					(start 116.186458 -351.611438)
					(mid 115.482878 -351.611438)
					(end 116.186458 -351.611438)
				)
			)
		)
	)
	(zone
		(layers "B.Cu" "In15.Cu")
		(hatch none 0.5)
		(connect_pads
			(clearance 0)
		)
		(min_thickness 0.25)
		(keepout
			(tracks not_allowed)
			(vias allowed)
			(pads allowed)
			(copperpour not_allowed)
			(footprints allowed)
		)
		(placement
			(enabled no)
			(sheetname "")
		)
		(fill yes
			(thermal_gap 0.5)
			(thermal_bridge_width 0.5)
			(island_removal_mode 0)
		)
		(polygon
			(pts
				(arc
					(start 188.426344 -311.099962)
					(mid 187.773564 -311.099962)
					(end 188.426344 -311.099962)
				)
			)
		)
	)
	(zone
		(layers "B.Cu" "In15.Cu")
		(hatch none 0.5)
		(connect_pads
			(clearance 0)
		)
		(min_thickness 0.25)
		(keepout
			(tracks not_allowed)
			(vias allowed)
			(pads allowed)
			(copperpour not_allowed)
			(footprints allowed)
		)
		(placement
			(enabled no)
			(sheetname "")
		)
		(fill yes
			(thermal_gap 0.5)
			(thermal_bridge_width 0.5)
			(island_removal_mode 0)
		)
		(polygon
			(pts
				(arc
					(start 137.949178 -345.465146)
					(mid 137.245598 -345.465146)
					(end 137.949178 -345.465146)
				)
			)
		)
	)
	(zone
		(layers "B.Cu" "In15.Cu")
		(hatch none 0.5)
		(connect_pads
			(clearance 0)
		)
		(min_thickness 0.25)
		(keepout
			(tracks not_allowed)
			(vias allowed)
			(pads allowed)
			(copperpour not_allowed)
			(footprints allowed)
		)
		(placement
			(enabled no)
			(sheetname "")
		)
		(fill yes
			(thermal_gap 0.5)
			(thermal_bridge_width 0.5)
			(island_removal_mode 0)
		)
		(polygon
			(pts
				(arc
					(start 347.269816 -383.290064)
					(mid 346.510356 -383.290064)
					(end 347.269816 -383.290064)
				)
			)
		)
	)
	(zone
		(layers "B.Cu" "In15.Cu")
		(hatch none 0.5)
		(connect_pads
			(clearance 0)
		)
		(min_thickness 0.25)
		(keepout
			(tracks not_allowed)
			(vias allowed)
			(pads allowed)
			(copperpour not_allowed)
			(footprints allowed)
		)
		(placement
			(enabled no)
			(sheetname "")
		)
		(fill yes
			(thermal_gap 0.5)
			(thermal_bridge_width 0.5)
			(island_removal_mode 0)
		)
		(polygon
			(pts
				(arc
					(start 76.689712 -383.490216)
					(mid 75.930252 -383.490216)
					(end 76.689712 -383.490216)
				)
			)
		)
	)
	(zone
		(layers "B.Cu" "In15.Cu")
		(hatch none 0.5)
		(connect_pads
			(clearance 0)
		)
		(min_thickness 0.25)
		(keepout
			(tracks not_allowed)
			(vias allowed)
			(pads allowed)
			(copperpour not_allowed)
			(footprints allowed)
		)
		(placement
			(enabled no)
			(sheetname "")
		)
		(fill yes
			(thermal_gap 0.5)
			(thermal_bridge_width 0.5)
			(island_removal_mode 0)
		)
		(polygon
			(pts
				(arc
					(start 131.689856 -379.390148)
					(mid 130.930396 -379.390148)
					(end 131.689856 -379.390148)
				)
			)
		)
	)
	(zone
		(layers "B.Cu" "In15.Cu")
		(hatch none 0.5)
		(connect_pads
			(clearance 0)
		)
		(min_thickness 0.25)
		(keepout
			(tracks not_allowed)
			(vias allowed)
			(pads allowed)
			(copperpour not_allowed)
			(footprints allowed)
		)
		(placement
			(enabled no)
			(sheetname "")
		)
		(fill yes
			(thermal_gap 0.5)
			(thermal_bridge_width 0.5)
			(island_removal_mode 0)
		)
		(polygon
			(pts
				(arc
					(start 74.489564 -384.590036)
					(mid 73.730104 -384.590036)
					(end 74.489564 -384.590036)
				)
			)
		)
	)
	(zone
		(layers "B.Cu" "In15.Cu")
		(hatch none 0.5)
		(connect_pads
			(clearance 0)
		)
		(min_thickness 0.25)
		(keepout
			(tracks not_allowed)
			(vias allowed)
			(pads allowed)
			(copperpour not_allowed)
			(footprints allowed)
		)
		(placement
			(enabled no)
			(sheetname "")
		)
		(fill yes
			(thermal_gap 0.5)
			(thermal_bridge_width 0.5)
			(island_removal_mode 0)
		)
		(polygon
			(pts
				(arc
					(start 185.576464 -312.999882)
					(mid 184.923684 -312.999882)
					(end 185.576464 -312.999882)
				)
			)
		)
	)
	(zone
		(layers "B.Cu" "In15.Cu")
		(hatch none 0.5)
		(connect_pads
			(clearance 0)
		)
		(min_thickness 0.25)
		(keepout
			(tracks not_allowed)
			(vias allowed)
			(pads allowed)
			(copperpour not_allowed)
			(footprints allowed)
		)
		(placement
			(enabled no)
			(sheetname "")
		)
		(fill yes
			(thermal_gap 0.5)
			(thermal_bridge_width 0.5)
			(island_removal_mode 0)
		)
		(polygon
			(pts
				(arc
					(start 122.404378 -348.58579)
					(mid 121.700798 -348.58579)
					(end 122.404378 -348.58579)
				)
			)
		)
	)
	(zone
		(layers "B.Cu" "In15.Cu")
		(hatch none 0.5)
		(connect_pads
			(clearance 0)
		)
		(min_thickness 0.25)
		(keepout
			(tracks not_allowed)
			(vias allowed)
			(pads allowed)
			(copperpour not_allowed)
			(footprints allowed)
		)
		(placement
			(enabled no)
			(sheetname "")
		)
		(fill yes
			(thermal_gap 0.5)
			(thermal_bridge_width 0.5)
			(island_removal_mode 0)
		)
		(polygon
			(pts
				(arc
					(start 322.181474 -348.58579)
					(mid 321.477894 -348.58579)
					(end 322.181474 -348.58579)
				)
			)
		)
	)
	(zone
		(layers "B.Cu" "In15.Cu")
		(hatch none 0.5)
		(connect_pads
			(clearance 0)
		)
		(min_thickness 0.25)
		(keepout
			(tracks not_allowed)
			(vias allowed)
			(pads allowed)
			(copperpour not_allowed)
			(footprints allowed)
		)
		(placement
			(enabled no)
			(sheetname "")
		)
		(fill yes
			(thermal_gap 0.5)
			(thermal_bridge_width 0.5)
			(island_removal_mode 0)
		)
		(polygon
			(pts
				(arc
					(start 402.62937 -354.732082)
					(mid 401.92579 -354.732082)
					(end 402.62937 -354.732082)
				)
			)
		)
	)
	(zone
		(layers "B.Cu" "In15.Cu")
		(hatch none 0.5)
		(connect_pads
			(clearance 0)
		)
		(min_thickness 0.25)
		(keepout
			(tracks not_allowed)
			(vias allowed)
			(pads allowed)
			(copperpour not_allowed)
			(footprints allowed)
		)
		(placement
			(enabled no)
			(sheetname "")
		)
		(fill yes
			(thermal_gap 0.5)
			(thermal_bridge_width 0.5)
			(island_removal_mode 0)
		)
		(polygon
			(pts
				(arc
					(start 130.867658 -342.439498)
					(mid 130.164078 -342.439498)
					(end 130.867658 -342.439498)
				)
			)
		)
	)
	(zone
		(layers "B.Cu" "In15.Cu")
		(hatch none 0.5)
		(connect_pads
			(clearance 0)
		)
		(min_thickness 0.25)
		(keepout
			(tracks not_allowed)
			(vias allowed)
			(pads allowed)
			(copperpour not_allowed)
			(footprints allowed)
		)
		(placement
			(enabled no)
			(sheetname "")
		)
		(fill yes
			(thermal_gap 0.5)
			(thermal_bridge_width 0.5)
			(island_removal_mode 0)
		)
		(polygon
			(pts
				(arc
					(start 125.513338 -354.732082)
					(mid 124.809758 -354.732082)
					(end 125.513338 -354.732082)
				)
			)
		)
	)
	(zone
		(layers "B.Cu" "In15.Cu")
		(hatch none 0.5)
		(connect_pads
			(clearance 0)
		)
		(min_thickness 0.25)
		(keepout
			(tracks not_allowed)
			(vias allowed)
			(pads allowed)
			(copperpour not_allowed)
			(footprints allowed)
		)
		(placement
			(enabled no)
			(sheetname "")
		)
		(fill yes
			(thermal_gap 0.5)
			(thermal_bridge_width 0.5)
			(island_removal_mode 0)
		)
		(polygon
			(pts
				(arc
					(start 340.66988 -383.490216)
					(mid 339.91042 -383.490216)
					(end 340.66988 -383.490216)
				)
			)
		)
	)
	(zone
		(layers "B.Cu" "In15.Cu")
		(hatch none 0.5)
		(connect_pads
			(clearance 0)
		)
		(min_thickness 0.25)
		(keepout
			(tracks not_allowed)
			(vias allowed)
			(pads allowed)
			(copperpour not_allowed)
			(footprints allowed)
		)
		(placement
			(enabled no)
			(sheetname "")
		)
		(fill yes
			(thermal_gap 0.5)
			(thermal_bridge_width 0.5)
			(island_removal_mode 0)
		)
		(polygon
			(pts
				(arc
					(start 396.41145 -342.439498)
					(mid 395.70787 -342.439498)
					(end 396.41145 -342.439498)
				)
			)
		)
	)
	(zone
		(layers "B.Cu" "In15.Cu")
		(hatch none 0.5)
		(connect_pads
			(clearance 0)
		)
		(min_thickness 0.25)
		(keepout
			(tracks not_allowed)
			(vias allowed)
			(pads allowed)
			(copperpour not_allowed)
			(footprints allowed)
		)
		(placement
			(enabled no)
			(sheetname "")
		)
		(fill yes
			(thermal_gap 0.5)
			(thermal_bridge_width 0.5)
			(island_removal_mode 0)
		)
		(polygon
			(pts
				(arc
					(start 289.32632 -312.049922)
					(mid 288.67354 -312.049922)
					(end 289.32632 -312.049922)
				)
			)
		)
	)
	(zone
		(layers "B.Cu" "In15.Cu")
		(hatch none 0.5)
		(connect_pads
			(clearance 0)
		)
		(min_thickness 0.25)
		(keepout
			(tracks not_allowed)
			(vias allowed)
			(pads allowed)
			(copperpour not_allowed)
			(footprints allowed)
		)
		(placement
			(enabled no)
			(sheetname "")
		)
		(fill yes
			(thermal_gap 0.5)
			(thermal_bridge_width 0.5)
			(island_removal_mode 0)
		)
		(polygon
			(pts
				(arc
					(start 415.876232 -312.999882)
					(mid 415.223452 -312.999882)
					(end 415.876232 -312.999882)
				)
			)
		)
	)
	(zone
		(layers "B.Cu" "In15.Cu")
		(hatch none 0.5)
		(connect_pads
			(clearance 0)
		)
		(min_thickness 0.25)
		(keepout
			(tracks not_allowed)
			(vias allowed)
			(pads allowed)
			(copperpour not_allowed)
			(footprints allowed)
		)
		(placement
			(enabled no)
			(sheetname "")
		)
		(fill yes
			(thermal_gap 0.5)
			(thermal_bridge_width 0.5)
			(island_removal_mode 0)
		)
		(polygon
			(pts
				(arc
					(start 116.289836 -409.490164)
					(mid 115.530376 -409.490164)
					(end 116.289836 -409.490164)
				)
			)
		)
	)
	(zone
		(layers "B.Cu" "In15.Cu")
		(hatch none 0.5)
		(connect_pads
			(clearance 0)
		)
		(min_thickness 0.25)
		(keepout
			(tracks not_allowed)
			(vias allowed)
			(pads allowed)
			(copperpour not_allowed)
			(footprints allowed)
		)
		(placement
			(enabled no)
			(sheetname "")
		)
		(fill yes
			(thermal_gap 0.5)
			(thermal_bridge_width 0.5)
			(island_removal_mode 0)
		)
		(polygon
			(pts
				(arc
					(start 83.486752 -348.58579)
					(mid 82.783172 -348.58579)
					(end 83.486752 -348.58579)
				)
			)
		)
	)
	(zone
		(layers "B.Cu" "In15.Cu")
		(hatch none 0.5)
		(connect_pads
			(clearance 0)
		)
		(min_thickness 0.25)
		(keepout
			(tracks not_allowed)
			(vias allowed)
			(pads allowed)
			(copperpour not_allowed)
			(footprints allowed)
		)
		(placement
			(enabled no)
			(sheetname "")
		)
		(fill yes
			(thermal_gap 0.5)
			(thermal_bridge_width 0.5)
			(island_removal_mode 0)
		)
		(polygon
			(pts
				(arc
					(start 340.66988 -408.190192)
					(mid 339.91042 -408.190192)
					(end 340.66988 -408.190192)
				)
			)
		)
	)
	(zone
		(layers "B.Cu" "In15.Cu")
		(hatch none 0.5)
		(connect_pads
			(clearance 0)
		)
		(min_thickness 0.25)
		(keepout
			(tracks not_allowed)
			(vias allowed)
			(pads allowed)
			(copperpour not_allowed)
			(footprints allowed)
		)
		(placement
			(enabled no)
			(sheetname "")
		)
		(fill yes
			(thermal_gap 0.5)
			(thermal_bridge_width 0.5)
			(island_removal_mode 0)
		)
		(polygon
			(pts
				(arc
					(start 280.776172 -312.999882)
					(mid 280.123392 -312.999882)
					(end 280.776172 -312.999882)
				)
			)
		)
	)
	(zone
		(layers "B.Cu" "In15.Cu")
		(hatch none 0.5)
		(connect_pads
			(clearance 0)
		)
		(min_thickness 0.25)
		(keepout
			(tracks not_allowed)
			(vias allowed)
			(pads allowed)
			(copperpour not_allowed)
			(footprints allowed)
		)
		(placement
			(enabled no)
			(sheetname "")
		)
		(fill yes
			(thermal_gap 0.5)
			(thermal_bridge_width 0.5)
			(island_removal_mode 0)
		)
		(polygon
			(pts
				(arc
					(start 377.75769 -357.75773)
					(mid 377.05411 -357.75773)
					(end 377.75769 -357.75773)
				)
			)
		)
	)
	(zone
		(layers "B.Cu" "In15.Cu")
		(hatch none 0.5)
		(connect_pads
			(clearance 0)
		)
		(min_thickness 0.25)
		(keepout
			(tracks not_allowed)
			(vias allowed)
			(pads allowed)
			(copperpour not_allowed)
			(footprints allowed)
		)
		(placement
			(enabled no)
			(sheetname "")
		)
		(fill yes
			(thermal_gap 0.5)
			(thermal_bridge_width 0.5)
			(island_removal_mode 0)
		)
		(polygon
			(pts
				(arc
					(start 419.676326 -313.949842)
					(mid 419.023546 -313.949842)
					(end 419.676326 -313.949842)
				)
			)
		)
	)
	(zone
		(layers "B.Cu" "In15.Cu")
		(hatch none 0.5)
		(connect_pads
			(clearance 0)
		)
		(min_thickness 0.25)
		(keepout
			(tracks not_allowed)
			(vias allowed)
			(pads allowed)
			(copperpour not_allowed)
			(footprints allowed)
		)
		(placement
			(enabled no)
			(sheetname "")
		)
		(fill yes
			(thermal_gap 0.5)
			(thermal_bridge_width 0.5)
			(island_removal_mode 0)
		)
		(polygon
			(pts
				(arc
					(start 87.459312 -345.465146)
					(mid 86.755732 -345.465146)
					(end 87.459312 -345.465146)
				)
			)
		)
	)
	(zone
		(layers "B.Cu" "In15.Cu")
		(hatch none 0.5)
		(connect_pads
			(clearance 0)
		)
		(min_thickness 0.25)
		(keepout
			(tracks not_allowed)
			(vias allowed)
			(pads allowed)
			(copperpour not_allowed)
			(footprints allowed)
		)
		(placement
			(enabled no)
			(sheetname "")
		)
		(fill yes
			(thermal_gap 0.5)
			(thermal_bridge_width 0.5)
			(island_removal_mode 0)
		)
		(polygon
			(pts
				(arc
					(start 319.072514 -354.732082)
					(mid 318.368934 -354.732082)
					(end 319.072514 -354.732082)
				)
			)
		)
	)
	(zone
		(layers "B.Cu" "In15.Cu")
		(hatch none 0.5)
		(connect_pads
			(clearance 0)
		)
		(min_thickness 0.25)
		(keepout
			(tracks not_allowed)
			(vias allowed)
			(pads allowed)
			(copperpour not_allowed)
			(footprints allowed)
		)
		(placement
			(enabled no)
			(sheetname "")
		)
		(fill yes
			(thermal_gap 0.5)
			(thermal_bridge_width 0.5)
			(island_removal_mode 0)
		)
		(polygon
			(pts
				(arc
					(start 378.069602 -380.69012)
					(mid 377.310142 -380.69012)
					(end 378.069602 -380.69012)
				)
			)
		)
	)
	(zone
		(layers "B.Cu" "In15.Cu")
		(hatch none 0.5)
		(connect_pads
			(clearance 0)
		)
		(min_thickness 0.25)
		(keepout
			(tracks not_allowed)
			(vias allowed)
			(pads allowed)
			(copperpour not_allowed)
			(footprints allowed)
		)
		(placement
			(enabled no)
			(sheetname "")
		)
		(fill yes
			(thermal_gap 0.5)
			(thermal_bridge_width 0.5)
			(island_removal_mode 0)
		)
		(polygon
			(pts
				(arc
					(start 118.431818 -354.732082)
					(mid 117.728238 -354.732082)
					(end 118.431818 -354.732082)
				)
			)
		)
	)
	(zone
		(layers "B.Cu" "In15.Cu")
		(hatch none 0.5)
		(connect_pads
			(clearance 0)
		)
		(min_thickness 0.25)
		(keepout
			(tracks not_allowed)
			(vias allowed)
			(pads allowed)
			(copperpour not_allowed)
			(footprints allowed)
		)
		(placement
			(enabled no)
			(sheetname "")
		)
		(fill yes
			(thermal_gap 0.5)
			(thermal_bridge_width 0.5)
			(island_removal_mode 0)
		)
		(polygon
			(pts
				(arc
					(start 137.085578 -354.732082)
					(mid 136.381998 -354.732082)
					(end 137.085578 -354.732082)
				)
			)
		)
	)
	(zone
		(layers "B.Cu" "In15.Cu")
		(hatch none 0.5)
		(connect_pads
			(clearance 0)
		)
		(min_thickness 0.25)
		(keepout
			(tracks not_allowed)
			(vias allowed)
			(pads allowed)
			(copperpour not_allowed)
			(footprints allowed)
		)
		(placement
			(enabled no)
			(sheetname "")
		)
		(fill yes
			(thermal_gap 0.5)
			(thermal_bridge_width 0.5)
			(island_removal_mode 0)
		)
		(polygon
			(pts
				(arc
					(start 375.869708 -408.190192)
					(mid 375.110248 -408.190192)
					(end 375.869708 -408.190192)
				)
			)
		)
	)
	(zone
		(layers "B.Cu" "In15.Cu")
		(hatch none 0.5)
		(connect_pads
			(clearance 0)
		)
		(min_thickness 0.25)
		(keepout
			(tracks not_allowed)
			(vias allowed)
			(pads allowed)
			(copperpour not_allowed)
			(footprints allowed)
		)
		(placement
			(enabled no)
			(sheetname "")
		)
		(fill yes
			(thermal_gap 0.5)
			(thermal_bridge_width 0.5)
			(island_removal_mode 0)
		)
		(polygon
			(pts
				(arc
					(start 127.289814 -379.390148)
					(mid 126.530354 -379.390148)
					(end 127.289814 -379.390148)
				)
			)
		)
	)
	(zone
		(layers "B.Cu" "In15.Cu")
		(hatch none 0.5)
		(connect_pads
			(clearance 0)
		)
		(min_thickness 0.25)
		(keepout
			(tracks not_allowed)
			(vias allowed)
			(pads allowed)
			(copperpour not_allowed)
			(footprints allowed)
		)
		(placement
			(enabled no)
			(sheetname "")
		)
		(fill yes
			(thermal_gap 0.5)
			(thermal_bridge_width 0.5)
			(island_removal_mode 0)
		)
		(polygon
			(pts
				(arc
					(start 341.698834 -348.58579)
					(mid 340.995254 -348.58579)
					(end 341.698834 -348.58579)
				)
			)
		)
	)
	(zone
		(layers "B.Cu" "In15.Cu")
		(hatch none 0.5)
		(connect_pads
			(clearance 0)
		)
		(min_thickness 0.25)
		(keepout
			(tracks not_allowed)
			(vias allowed)
			(pads allowed)
			(copperpour not_allowed)
			(footprints allowed)
		)
		(placement
			(enabled no)
			(sheetname "")
		)
		(fill yes
			(thermal_gap 0.5)
			(thermal_bridge_width 0.5)
			(island_removal_mode 0)
		)
		(polygon
			(pts
				(arc
					(start 184.62625 -311.099962)
					(mid 183.97347 -311.099962)
					(end 184.62625 -311.099962)
				)
			)
		)
	)
	(zone
		(layers "B.Cu" "In15.Cu")
		(hatch none 0.5)
		(connect_pads
			(clearance 0)
		)
		(min_thickness 0.25)
		(keepout
			(tracks not_allowed)
			(vias allowed)
			(pads allowed)
			(copperpour not_allowed)
			(footprints allowed)
		)
		(placement
			(enabled no)
			(sheetname "")
		)
		(fill yes
			(thermal_gap 0.5)
			(thermal_bridge_width 0.5)
			(island_removal_mode 0)
		)
		(polygon
			(pts
				(arc
					(start 83.289648 -383.290064)
					(mid 82.530188 -383.290064)
					(end 83.289648 -383.290064)
				)
			)
		)
	)
	(zone
		(layers "B.Cu" "In15.Cu")
		(hatch none 0.5)
		(connect_pads
			(clearance 0)
		)
		(min_thickness 0.25)
		(keepout
			(tracks not_allowed)
			(vias allowed)
			(pads allowed)
			(copperpour not_allowed)
			(footprints allowed)
		)
		(placement
			(enabled no)
			(sheetname "")
		)
		(fill yes
			(thermal_gap 0.5)
			(thermal_bridge_width 0.5)
			(island_removal_mode 0)
		)
		(polygon
			(pts
				(arc
					(start 387.08457 -348.58579)
					(mid 386.38099 -348.58579)
					(end 387.08457 -348.58579)
				)
			)
		)
	)
	(zone
		(layers "B.Cu" "In15.Cu")
		(hatch none 0.5)
		(connect_pads
			(clearance 0)
		)
		(min_thickness 0.25)
		(keepout
			(tracks not_allowed)
			(vias allowed)
			(pads allowed)
			(copperpour not_allowed)
			(footprints allowed)
		)
		(placement
			(enabled no)
			(sheetname "")
		)
		(fill yes
			(thermal_gap 0.5)
			(thermal_bridge_width 0.5)
			(island_removal_mode 0)
		)
		(polygon
			(pts
				(arc
					(start 58.076338 -312.999882)
					(mid 57.423558 -312.999882)
					(end 58.076338 -312.999882)
				)
			)
		)
	)
	(zone
		(layers "B.Cu" "In15.Cu")
		(hatch none 0.5)
		(connect_pads
			(clearance 0)
		)
		(min_thickness 0.25)
		(keepout
			(tracks not_allowed)
			(vias allowed)
			(pads allowed)
			(copperpour not_allowed)
			(footprints allowed)
		)
		(placement
			(enabled no)
			(sheetname "")
		)
		(fill yes
			(thermal_gap 0.5)
			(thermal_bridge_width 0.5)
			(island_removal_mode 0)
		)
		(polygon
			(pts
				(arc
					(start 276.976078 -312.999882)
					(mid 276.323298 -312.999882)
					(end 276.976078 -312.999882)
				)
			)
		)
	)
	(zone
		(layers "B.Cu" "In15.Cu")
		(hatch none 0.5)
		(connect_pads
			(clearance 0)
		)
		(min_thickness 0.25)
		(keepout
			(tracks not_allowed)
			(vias allowed)
			(pads allowed)
			(copperpour not_allowed)
			(footprints allowed)
		)
		(placement
			(enabled no)
			(sheetname "")
		)
		(fill yes
			(thermal_gap 0.5)
			(thermal_bridge_width 0.5)
			(island_removal_mode 0)
		)
		(polygon
			(pts
				(arc
					(start 50.47615 -312.999882)
					(mid 49.82337 -312.999882)
					(end 50.47615 -312.999882)
				)
			)
		)
	)
	(zone
		(layers "B.Cu" "In15.Cu")
		(hatch none 0.5)
		(connect_pads
			(clearance 0)
		)
		(min_thickness 0.25)
		(keepout
			(tracks not_allowed)
			(vias allowed)
			(pads allowed)
			(copperpour not_allowed)
			(footprints allowed)
		)
		(placement
			(enabled no)
			(sheetname "")
		)
		(fill yes
			(thermal_gap 0.5)
			(thermal_bridge_width 0.5)
			(island_removal_mode 0)
		)
		(polygon
			(pts
				(arc
					(start 78.132432 -348.58579)
					(mid 77.428852 -348.58579)
					(end 78.132432 -348.58579)
				)
			)
		)
	)
	(zone
		(layers "B.Cu" "In15.Cu")
		(hatch none 0.5)
		(connect_pads
			(clearance 0)
		)
		(min_thickness 0.25)
		(keepout
			(tracks not_allowed)
			(vias allowed)
			(pads allowed)
			(copperpour not_allowed)
			(footprints allowed)
		)
		(placement
			(enabled no)
			(sheetname "")
		)
		(fill yes
			(thermal_gap 0.5)
			(thermal_bridge_width 0.5)
			(island_removal_mode 0)
		)
		(polygon
			(pts
				(arc
					(start 113.077498 -342.439498)
					(mid 112.373918 -342.439498)
					(end 113.077498 -342.439498)
				)
			)
		)
	)
	(zone
		(layers "B.Cu" "In15.Cu")
		(hatch none 0.5)
		(connect_pads
			(clearance 0)
		)
		(min_thickness 0.25)
		(keepout
			(tracks not_allowed)
			(vias allowed)
			(pads allowed)
			(copperpour not_allowed)
			(footprints allowed)
		)
		(placement
			(enabled no)
			(sheetname "")
		)
		(fill yes
			(thermal_gap 0.5)
			(thermal_bridge_width 0.5)
			(island_removal_mode 0)
		)
		(polygon
			(pts
				(arc
					(start 52.376324 -313.949842)
					(mid 51.723544 -313.949842)
					(end 52.376324 -313.949842)
				)
			)
		)
	)
	(zone
		(layers "B.Cu" "In15.Cu")
		(hatch none 0.5)
		(connect_pads
			(clearance 0)
		)
		(min_thickness 0.25)
		(keepout
			(tracks not_allowed)
			(vias allowed)
			(pads allowed)
			(copperpour not_allowed)
			(footprints allowed)
		)
		(placement
			(enabled no)
			(sheetname "")
		)
		(fill yes
			(thermal_gap 0.5)
			(thermal_bridge_width 0.5)
			(island_removal_mode 0)
		)
		(polygon
			(pts
				(arc
					(start 276.026118 -311.099962)
					(mid 275.373338 -311.099962)
					(end 276.026118 -311.099962)
				)
			)
		)
	)
	(zone
		(layers "B.Cu" "In15.Cu")
		(hatch none 0.5)
		(connect_pads
			(clearance 0)
		)
		(min_thickness 0.25)
		(keepout
			(tracks not_allowed)
			(vias allowed)
			(pads allowed)
			(copperpour not_allowed)
			(footprints allowed)
		)
		(placement
			(enabled no)
			(sheetname "")
		)
		(fill yes
			(thermal_gap 0.5)
			(thermal_bridge_width 0.5)
			(island_removal_mode 0)
		)
		(polygon
			(pts
				(arc
					(start 118.48973 -380.69012)
					(mid 117.73027 -380.69012)
					(end 118.48973 -380.69012)
				)
			)
		)
	)
	(zone
		(layers "B.Cu" "In15.Cu")
		(hatch none 0.5)
		(connect_pads
			(clearance 0)
		)
		(min_thickness 0.25)
		(keepout
			(tracks not_allowed)
			(vias allowed)
			(pads allowed)
			(copperpour not_allowed)
			(footprints allowed)
		)
		(placement
			(enabled no)
			(sheetname "")
		)
		(fill yes
			(thermal_gap 0.5)
			(thermal_bridge_width 0.5)
			(island_removal_mode 0)
		)
		(polygon
			(pts
				(arc
					(start 380.26975 -379.590046)
					(mid 379.51029 -379.590046)
					(end 380.26975 -379.590046)
				)
			)
		)
	)
	(zone
		(layers "B.Cu" "In15.Cu")
		(hatch none 0.5)
		(connect_pads
			(clearance 0)
		)
		(min_thickness 0.25)
		(keepout
			(tracks not_allowed)
			(vias allowed)
			(pads allowed)
			(copperpour not_allowed)
			(footprints allowed)
		)
		(placement
			(enabled no)
			(sheetname "")
		)
		(fill yes
			(thermal_gap 0.5)
			(thermal_bridge_width 0.5)
			(island_removal_mode 0)
		)
		(polygon
			(pts
				(arc
					(start 384.83921 -345.465146)
					(mid 384.13563 -345.465146)
					(end 384.83921 -345.465146)
				)
			)
		)
	)
	(zone
		(layers "B.Cu" "In15.Cu")
		(hatch none 0.5)
		(connect_pads
			(clearance 0)
		)
		(min_thickness 0.25)
		(keepout
			(tracks not_allowed)
			(vias allowed)
			(pads allowed)
			(copperpour not_allowed)
			(footprints allowed)
		)
		(placement
			(enabled no)
			(sheetname "")
		)
		(fill yes
			(thermal_gap 0.5)
			(thermal_bridge_width 0.5)
			(island_removal_mode 0)
		)
		(polygon
			(pts
				(arc
					(start 374.64873 -351.611438)
					(mid 373.94515 -351.611438)
					(end 374.64873 -351.611438)
				)
			)
		)
	)
	(zone
		(layers "B.Cu" "In15.Cu")
		(hatch none 0.5)
		(connect_pads
			(clearance 0)
		)
		(min_thickness 0.25)
		(keepout
			(tracks not_allowed)
			(vias allowed)
			(pads allowed)
			(copperpour not_allowed)
			(footprints allowed)
		)
		(placement
			(enabled no)
			(sheetname "")
		)
		(fill yes
			(thermal_gap 0.5)
			(thermal_bridge_width 0.5)
			(island_removal_mode 0)
		)
		(polygon
			(pts
				(arc
					(start 389.06958 -379.590046)
					(mid 388.31012 -379.590046)
					(end 389.06958 -379.590046)
				)
			)
		)
	)
	(zone
		(layers "B.Cu" "In15.Cu")
		(hatch none 0.5)
		(connect_pads
			(clearance 0)
		)
		(min_thickness 0.25)
		(keepout
			(tracks not_allowed)
			(vias allowed)
			(pads allowed)
			(copperpour not_allowed)
			(footprints allowed)
		)
		(placement
			(enabled no)
			(sheetname "")
		)
		(fill yes
			(thermal_gap 0.5)
			(thermal_bridge_width 0.5)
			(island_removal_mode 0)
		)
		(polygon
			(pts
				(arc
					(start 48.08982 -376.790204)
					(mid 47.33036 -376.790204)
					(end 48.08982 -376.790204)
				)
			)
		)
	)
	(zone
		(layers "B.Cu" "In15.Cu")
		(hatch none 0.5)
		(connect_pads
			(clearance 0)
		)
		(min_thickness 0.25)
		(keepout
			(tracks not_allowed)
			(vias allowed)
			(pads allowed)
			(copperpour not_allowed)
			(footprints allowed)
		)
		(placement
			(enabled no)
			(sheetname "")
		)
		(fill yes
			(thermal_gap 0.5)
			(thermal_bridge_width 0.5)
			(island_removal_mode 0)
		)
		(polygon
			(pts
				(arc
					(start 319.936114 -354.732082)
					(mid 319.232534 -354.732082)
					(end 319.936114 -354.732082)
				)
			)
		)
	)
	(zone
		(layers "B.Cu" "In15.Cu")
		(hatch none 0.5)
		(connect_pads
			(clearance 0)
		)
		(min_thickness 0.25)
		(keepout
			(tracks not_allowed)
			(vias allowed)
			(pads allowed)
			(copperpour not_allowed)
			(footprints allowed)
		)
		(placement
			(enabled no)
			(sheetname "")
		)
		(fill yes
			(thermal_gap 0.5)
			(thermal_bridge_width 0.5)
			(island_removal_mode 0)
		)
		(polygon
			(pts
				(arc
					(start 116.186458 -348.58579)
					(mid 115.482878 -348.58579)
					(end 116.186458 -348.58579)
				)
			)
		)
	)
	(zone
		(layers "B.Cu" "In15.Cu")
		(hatch none 0.5)
		(connect_pads
			(clearance 0)
		)
		(min_thickness 0.25)
		(keepout
			(tracks not_allowed)
			(vias allowed)
			(pads allowed)
			(copperpour not_allowed)
			(footprints allowed)
		)
		(placement
			(enabled no)
			(sheetname "")
		)
		(fill yes
			(thermal_gap 0.5)
			(thermal_bridge_width 0.5)
			(island_removal_mode 0)
		)
		(polygon
			(pts
				(arc
					(start 62.587632 -342.439498)
					(mid 61.884052 -342.439498)
					(end 62.587632 -342.439498)
				)
			)
		)
	)
	(zone
		(layers "B.Cu" "In15.Cu")
		(hatch none 0.5)
		(connect_pads
			(clearance 0)
		)
		(min_thickness 0.25)
		(keepout
			(tracks not_allowed)
			(vias allowed)
			(pads allowed)
			(copperpour not_allowed)
			(footprints allowed)
		)
		(placement
			(enabled no)
			(sheetname "")
		)
		(fill yes
			(thermal_gap 0.5)
			(thermal_bridge_width 0.5)
			(island_removal_mode 0)
		)
		(polygon
			(pts
				(arc
					(start 122.889772 -410.589984)
					(mid 122.130312 -410.589984)
					(end 122.889772 -410.589984)
				)
			)
		)
	)
	(zone
		(layers "B.Cu" "In15.Cu")
		(hatch none 0.5)
		(connect_pads
			(clearance 0)
		)
		(min_thickness 0.25)
		(keepout
			(tracks not_allowed)
			(vias allowed)
			(pads allowed)
			(copperpour not_allowed)
			(footprints allowed)
		)
		(placement
			(enabled no)
			(sheetname "")
		)
		(fill yes
			(thermal_gap 0.5)
			(thermal_bridge_width 0.5)
			(island_removal_mode 0)
		)
		(polygon
			(pts
				(arc
					(start 87.68969 -410.589984)
					(mid 86.93023 -410.589984)
					(end 87.68969 -410.589984)
				)
			)
		)
	)
	(zone
		(layers "B.Cu" "In15.Cu")
		(hatch none 0.5)
		(connect_pads
			(clearance 0)
		)
		(min_thickness 0.25)
		(keepout
			(tracks not_allowed)
			(vias allowed)
			(pads allowed)
			(copperpour not_allowed)
			(footprints allowed)
		)
		(placement
			(enabled no)
			(sheetname "")
		)
		(fill yes
			(thermal_gap 0.5)
			(thermal_bridge_width 0.5)
			(island_removal_mode 0)
		)
		(polygon
			(pts
				(arc
					(start 46.67631 -312.999882)
					(mid 46.02353 -312.999882)
					(end 46.67631 -312.999882)
				)
			)
		)
	)
	(zone
		(layers "B.Cu" "In15.Cu")
		(hatch none 0.5)
		(connect_pads
			(clearance 0)
		)
		(min_thickness 0.25)
		(keepout
			(tracks not_allowed)
			(vias allowed)
			(pads allowed)
			(copperpour not_allowed)
			(footprints allowed)
		)
		(placement
			(enabled no)
			(sheetname "")
		)
		(fill yes
			(thermal_gap 0.5)
			(thermal_bridge_width 0.5)
			(island_removal_mode 0)
		)
		(polygon
			(pts
				(arc
					(start 387.94817 -351.611438)
					(mid 387.24459 -351.611438)
					(end 387.94817 -351.611438)
				)
			)
		)
	)
	(zone
		(layers "B.Cu" "In15.Cu")
		(hatch none 0.5)
		(connect_pads
			(clearance 0)
		)
		(min_thickness 0.25)
		(keepout
			(tracks not_allowed)
			(vias allowed)
			(pads allowed)
			(copperpour not_allowed)
			(footprints allowed)
		)
		(placement
			(enabled no)
			(sheetname "")
		)
		(fill yes
			(thermal_gap 0.5)
			(thermal_bridge_width 0.5)
			(island_removal_mode 0)
		)
		(polygon
			(pts
				(arc
					(start 165.626288 -311.099962)
					(mid 164.973508 -311.099962)
					(end 165.626288 -311.099962)
				)
			)
		)
	)
	(zone
		(layers "B.Cu" "In15.Cu")
		(hatch none 0.5)
		(connect_pads
			(clearance 0)
		)
		(min_thickness 0.25)
		(keepout
			(tracks not_allowed)
			(vias allowed)
			(pads allowed)
			(copperpour not_allowed)
			(footprints allowed)
		)
		(placement
			(enabled no)
			(sheetname "")
		)
		(fill yes
			(thermal_gap 0.5)
			(thermal_bridge_width 0.5)
			(island_removal_mode 0)
		)
		(polygon
			(pts
				(arc
					(start 337.726274 -354.732082)
					(mid 337.022694 -354.732082)
					(end 337.726274 -354.732082)
				)
			)
		)
	)
	(zone
		(layers "B.Cu" "In15.Cu")
		(hatch none 0.5)
		(connect_pads
			(clearance 0)
		)
		(min_thickness 0.25)
		(keepout
			(tracks not_allowed)
			(vias allowed)
			(pads allowed)
			(copperpour not_allowed)
			(footprints allowed)
		)
		(placement
			(enabled no)
			(sheetname "")
		)
		(fill yes
			(thermal_gap 0.5)
			(thermal_bridge_width 0.5)
			(island_removal_mode 0)
		)
		(polygon
			(pts
				(arc
					(start 43.826176 -311.099962)
					(mid 43.173396 -311.099962)
					(end 43.826176 -311.099962)
				)
			)
		)
	)
	(zone
		(layers "B.Cu" "In15.Cu")
		(hatch none 0.5)
		(connect_pads
			(clearance 0)
		)
		(min_thickness 0.25)
		(keepout
			(tracks not_allowed)
			(vias allowed)
			(pads allowed)
			(copperpour not_allowed)
			(footprints allowed)
		)
		(placement
			(enabled no)
			(sheetname "")
		)
		(fill yes
			(thermal_gap 0.5)
			(thermal_bridge_width 0.5)
			(island_removal_mode 0)
		)
		(polygon
			(pts
				(arc
					(start 377.75769 -342.439498)
					(mid 377.05411 -342.439498)
					(end 377.75769 -342.439498)
				)
			)
		)
	)
	(zone
		(layers "B.Cu" "In15.Cu")
		(hatch none 0.5)
		(connect_pads
			(clearance 0)
		)
		(min_thickness 0.25)
		(keepout
			(tracks not_allowed)
			(vias allowed)
			(pads allowed)
			(copperpour not_allowed)
			(footprints allowed)
		)
		(placement
			(enabled no)
			(sheetname "")
		)
		(fill yes
			(thermal_gap 0.5)
			(thermal_bridge_width 0.5)
			(island_removal_mode 0)
		)
		(polygon
			(pts
				(arc
					(start 78.889606 -383.290064)
					(mid 78.130146 -383.290064)
					(end 78.889606 -383.290064)
				)
			)
		)
	)
	(zone
		(layers "B.Cu" "In15.Cu")
		(hatch none 0.5)
		(connect_pads
			(clearance 0)
		)
		(min_thickness 0.25)
		(keepout
			(tracks not_allowed)
			(vias allowed)
			(pads allowed)
			(copperpour not_allowed)
			(footprints allowed)
		)
		(placement
			(enabled no)
			(sheetname "")
		)
		(fill yes
			(thermal_gap 0.5)
			(thermal_bridge_width 0.5)
			(island_removal_mode 0)
		)
		(polygon
			(pts
				(arc
					(start 331.869796 -383.490216)
					(mid 331.110336 -383.490216)
					(end 331.869796 -383.490216)
				)
			)
		)
	)
	(zone
		(layers "B.Cu" "In15.Cu")
		(hatch none 0.5)
		(connect_pads
			(clearance 0)
		)
		(min_thickness 0.25)
		(keepout
			(tracks not_allowed)
			(vias allowed)
			(pads allowed)
			(copperpour not_allowed)
			(footprints allowed)
		)
		(placement
			(enabled no)
			(sheetname "")
		)
		(fill yes
			(thermal_gap 0.5)
			(thermal_bridge_width 0.5)
			(island_removal_mode 0)
		)
		(polygon
			(pts
				(arc
					(start 380.26975 -408.190192)
					(mid 379.51029 -408.190192)
					(end 380.26975 -408.190192)
				)
			)
		)
	)
	(zone
		(layers "B.Cu" "In15.Cu")
		(hatch none 0.5)
		(connect_pads
			(clearance 0)
		)
		(min_thickness 0.25)
		(keepout
			(tracks not_allowed)
			(vias allowed)
			(pads allowed)
			(copperpour not_allowed)
			(footprints allowed)
		)
		(placement
			(enabled no)
			(sheetname "")
		)
		(fill yes
			(thermal_gap 0.5)
			(thermal_bridge_width 0.5)
			(island_removal_mode 0)
		)
		(polygon
			(pts
				(arc
					(start 127.289814 -380.69012)
					(mid 126.530354 -380.69012)
					(end 127.289814 -380.69012)
				)
			)
		)
	)
	(zone
		(layers "B.Cu" "In15.Cu")
		(hatch none 0.5)
		(connect_pads
			(clearance 0)
		)
		(min_thickness 0.25)
		(keepout
			(tracks not_allowed)
			(vias allowed)
			(pads allowed)
			(copperpour not_allowed)
			(footprints allowed)
		)
		(placement
			(enabled no)
			(sheetname "")
		)
		(fill yes
			(thermal_gap 0.5)
			(thermal_bridge_width 0.5)
			(island_removal_mode 0)
		)
		(polygon
			(pts
				(arc
					(start 125.08992 -408.190192)
					(mid 124.33046 -408.190192)
					(end 125.08992 -408.190192)
				)
			)
		)
	)
	(zone
		(layers "B.Cu" "In15.Cu")
		(hatch none 0.5)
		(connect_pads
			(clearance 0)
		)
		(min_thickness 0.25)
		(keepout
			(tracks not_allowed)
			(vias allowed)
			(pads allowed)
			(copperpour not_allowed)
			(footprints allowed)
		)
		(placement
			(enabled no)
			(sheetname "")
		)
		(fill yes
			(thermal_gap 0.5)
			(thermal_bridge_width 0.5)
			(island_removal_mode 0)
		)
		(polygon
			(pts
				(arc
					(start 414.926272 -311.099962)
					(mid 414.273492 -311.099962)
					(end 414.926272 -311.099962)
				)
			)
		)
	)
	(zone
		(layers "B.Cu" "In15.Cu")
		(hatch none 0.5)
		(connect_pads
			(clearance 0)
		)
		(min_thickness 0.25)
		(keepout
			(tracks not_allowed)
			(vias allowed)
			(pads allowed)
			(copperpour not_allowed)
			(footprints allowed)
		)
		(placement
			(enabled no)
			(sheetname "")
		)
		(fill yes
			(thermal_gap 0.5)
			(thermal_bridge_width 0.5)
			(island_removal_mode 0)
		)
		(polygon
			(pts
				(arc
					(start 119.295418 -354.732082)
					(mid 118.591838 -354.732082)
					(end 119.295418 -354.732082)
				)
			)
		)
	)
	(zone
		(layers "B.Cu" "In15.Cu")
		(hatch none 0.5)
		(connect_pads
			(clearance 0)
		)
		(min_thickness 0.25)
		(keepout
			(tracks not_allowed)
			(vias allowed)
			(pads allowed)
			(copperpour not_allowed)
			(footprints allowed)
		)
		(placement
			(enabled no)
			(sheetname "")
		)
		(fill yes
			(thermal_gap 0.5)
			(thermal_bridge_width 0.5)
			(island_removal_mode 0)
		)
		(polygon
			(pts
				(arc
					(start 397.82623 -312.049922)
					(mid 397.17345 -312.049922)
					(end 397.82623 -312.049922)
				)
			)
		)
	)
	(zone
		(layers "B.Cu" "In15.Cu")
		(hatch none 0.5)
		(connect_pads
			(clearance 0)
		)
		(min_thickness 0.25)
		(keepout
			(tracks not_allowed)
			(vias allowed)
			(pads allowed)
			(copperpour not_allowed)
			(footprints allowed)
		)
		(placement
			(enabled no)
			(sheetname "")
		)
		(fill yes
			(thermal_gap 0.5)
			(thermal_bridge_width 0.5)
			(island_removal_mode 0)
		)
		(polygon
			(pts
				(arc
					(start 133.976618 -351.611438)
					(mid 133.273038 -351.611438)
					(end 133.976618 -351.611438)
				)
			)
		)
	)
	(zone
		(layers "B.Cu" "In15.Cu")
		(hatch none 0.5)
		(connect_pads
			(clearance 0)
		)
		(min_thickness 0.25)
		(keepout
			(tracks not_allowed)
			(vias allowed)
			(pads allowed)
			(copperpour not_allowed)
			(footprints allowed)
		)
		(placement
			(enabled no)
			(sheetname "")
		)
		(fill yes
			(thermal_gap 0.5)
			(thermal_bridge_width 0.5)
			(island_removal_mode 0)
		)
		(polygon
			(pts
				(arc
					(start 287.426146 -312.049922)
					(mid 286.773366 -312.049922)
					(end 287.426146 -312.049922)
				)
			)
		)
	)
	(zone
		(layers "B.Cu" "In15.Cu")
		(hatch none 0.5)
		(connect_pads
			(clearance 0)
		)
		(min_thickness 0.25)
		(keepout
			(tracks not_allowed)
			(vias allowed)
			(pads allowed)
			(copperpour not_allowed)
			(footprints allowed)
		)
		(placement
			(enabled no)
			(sheetname "")
		)
		(fill yes
			(thermal_gap 0.5)
			(thermal_bridge_width 0.5)
			(island_removal_mode 0)
		)
		(polygon
			(pts
				(arc
					(start 118.431818 -357.75773)
					(mid 117.728238 -357.75773)
					(end 118.431818 -357.75773)
				)
			)
		)
	)
	(zone
		(layers "B.Cu" "In15.Cu")
		(hatch none 0.5)
		(connect_pads
			(clearance 0)
		)
		(min_thickness 0.25)
		(keepout
			(tracks not_allowed)
			(vias allowed)
			(pads allowed)
			(copperpour not_allowed)
			(footprints allowed)
		)
		(placement
			(enabled no)
			(sheetname "")
		)
		(fill yes
			(thermal_gap 0.5)
			(thermal_bridge_width 0.5)
			(island_removal_mode 0)
		)
		(polygon
			(pts
				(arc
					(start 43.351196 -288.774886)
					(mid 42.698416 -288.774886)
					(end 43.351196 -288.774886)
				)
			)
		)
	)
	(zone
		(layers "B.Cu" "In15.Cu")
		(hatch none 0.5)
		(connect_pads
			(clearance 0)
		)
		(min_thickness 0.25)
		(keepout
			(tracks not_allowed)
			(vias allowed)
			(pads allowed)
			(copperpour not_allowed)
			(footprints allowed)
		)
		(placement
			(enabled no)
			(sheetname "")
		)
		(fill yes
			(thermal_gap 0.5)
			(thermal_bridge_width 0.5)
			(island_removal_mode 0)
		)
		(polygon
			(pts
				(arc
					(start 286.476186 -312.999882)
					(mid 285.823406 -312.999882)
					(end 286.476186 -312.999882)
				)
			)
		)
	)
	(zone
		(layers "B.Cu" "In15.Cu")
		(hatch none 0.5)
		(connect_pads
			(clearance 0)
		)
		(min_thickness 0.25)
		(keepout
			(tracks not_allowed)
			(vias allowed)
			(pads allowed)
			(copperpour not_allowed)
			(footprints allowed)
		)
		(placement
			(enabled no)
			(sheetname "")
		)
		(fill yes
			(thermal_gap 0.5)
			(thermal_bridge_width 0.5)
			(island_removal_mode 0)
		)
		(polygon
			(pts
				(arc
					(start 144.167098 -357.75773)
					(mid 143.463518 -357.75773)
					(end 144.167098 -357.75773)
				)
			)
		)
	)
	(zone
		(layers "B.Cu" "In15.Cu")
		(hatch none 0.5)
		(connect_pads
			(clearance 0)
		)
		(min_thickness 0.25)
		(keepout
			(tracks not_allowed)
			(vias allowed)
			(pads allowed)
			(copperpour not_allowed)
			(footprints allowed)
		)
		(placement
			(enabled no)
			(sheetname "")
		)
		(fill yes
			(thermal_gap 0.5)
			(thermal_bridge_width 0.5)
			(island_removal_mode 0)
		)
		(polygon
			(pts
				(arc
					(start 67.941952 -357.75773)
					(mid 67.238372 -357.75773)
					(end 67.941952 -357.75773)
				)
			)
		)
	)
	(zone
		(layers "B.Cu" "In15.Cu")
		(hatch none 0.5)
		(connect_pads
			(clearance 0)
		)
		(min_thickness 0.25)
		(keepout
			(tracks not_allowed)
			(vias allowed)
			(pads allowed)
			(copperpour not_allowed)
			(footprints allowed)
		)
		(placement
			(enabled no)
			(sheetname "")
		)
		(fill yes
			(thermal_gap 0.5)
			(thermal_bridge_width 0.5)
			(island_removal_mode 0)
		)
		(polygon
			(pts
				(arc
					(start 85.489542 -408.190192)
					(mid 84.730082 -408.190192)
					(end 85.489542 -408.190192)
				)
			)
		)
	)
	(zone
		(layers "B.Cu" "In15.Cu")
		(hatch none 0.5)
		(connect_pads
			(clearance 0)
		)
		(min_thickness 0.25)
		(keepout
			(tracks not_allowed)
			(vias allowed)
			(pads allowed)
			(copperpour not_allowed)
			(footprints allowed)
		)
		(placement
			(enabled no)
			(sheetname "")
		)
		(fill yes
			(thermal_gap 0.5)
			(thermal_bridge_width 0.5)
			(island_removal_mode 0)
		)
		(polygon
			(pts
				(arc
					(start 329.262994 -351.611438)
					(mid 328.559414 -351.611438)
					(end 329.262994 -351.611438)
				)
			)
		)
	)
	(zone
		(layers "B.Cu" "In15.Cu")
		(hatch none 0.5)
		(connect_pads
			(clearance 0)
		)
		(min_thickness 0.25)
		(keepout
			(tracks not_allowed)
			(vias allowed)
			(pads allowed)
			(copperpour not_allowed)
			(footprints allowed)
		)
		(placement
			(enabled no)
			(sheetname "")
		)
		(fill yes
			(thermal_gap 0.5)
			(thermal_bridge_width 0.5)
			(island_removal_mode 0)
		)
		(polygon
			(pts
				(arc
					(start 71.914512 -348.58579)
					(mid 71.210932 -348.58579)
					(end 71.914512 -348.58579)
				)
			)
		)
	)
	(zone
		(layers "B.Cu" "In15.Cu")
		(hatch none 0.5)
		(connect_pads
			(clearance 0)
		)
		(min_thickness 0.25)
		(keepout
			(tracks not_allowed)
			(vias allowed)
			(pads allowed)
			(copperpour not_allowed)
			(footprints allowed)
		)
		(placement
			(enabled no)
			(sheetname "")
		)
		(fill yes
			(thermal_gap 0.5)
			(thermal_bridge_width 0.5)
			(island_removal_mode 0)
		)
		(polygon
			(pts
				(arc
					(start 159.926274 -311.099962)
					(mid 159.273494 -311.099962)
					(end 159.926274 -311.099962)
				)
			)
		)
	)
	(zone
		(layers "B.Cu" "In15.Cu")
		(hatch none 0.5)
		(connect_pads
			(clearance 0)
		)
		(min_thickness 0.25)
		(keepout
			(tracks not_allowed)
			(vias allowed)
			(pads allowed)
			(copperpour not_allowed)
			(footprints allowed)
		)
		(placement
			(enabled no)
			(sheetname "")
		)
		(fill yes
			(thermal_gap 0.5)
			(thermal_bridge_width 0.5)
			(island_removal_mode 0)
		)
		(polygon
			(pts
				(arc
					(start 383.97561 -354.732082)
					(mid 383.27203 -354.732082)
					(end 383.97561 -354.732082)
				)
			)
		)
	)
	(zone
		(layers "B.Cu" "In15.Cu")
		(hatch none 0.5)
		(connect_pads
			(clearance 0)
		)
		(min_thickness 0.25)
		(keepout
			(tracks not_allowed)
			(vias allowed)
			(pads allowed)
			(copperpour not_allowed)
			(footprints allowed)
		)
		(placement
			(enabled no)
			(sheetname "")
		)
		(fill yes
			(thermal_gap 0.5)
			(thermal_bridge_width 0.5)
			(island_removal_mode 0)
		)
		(polygon
			(pts
				(arc
					(start 277.926292 -312.049922)
					(mid 277.273512 -312.049922)
					(end 277.926292 -312.049922)
				)
			)
		)
	)
	(zone
		(layers "B.Cu" "In15.Cu")
		(hatch none 0.5)
		(connect_pads
			(clearance 0)
		)
		(min_thickness 0.25)
		(keepout
			(tracks not_allowed)
			(vias allowed)
			(pads allowed)
			(copperpour not_allowed)
			(footprints allowed)
		)
		(placement
			(enabled no)
			(sheetname "")
		)
		(fill yes
			(thermal_gap 0.5)
			(thermal_bridge_width 0.5)
			(island_removal_mode 0)
		)
		(polygon
			(pts
				(arc
					(start 288.376106 -312.999882)
					(mid 287.723326 -312.999882)
					(end 288.376106 -312.999882)
				)
			)
		)
	)
	(zone
		(layers "B.Cu" "In15.Cu")
		(hatch none 0.5)
		(connect_pads
			(clearance 0)
		)
		(min_thickness 0.25)
		(keepout
			(tracks not_allowed)
			(vias allowed)
			(pads allowed)
			(copperpour not_allowed)
			(footprints allowed)
		)
		(placement
			(enabled no)
			(sheetname "")
		)
		(fill yes
			(thermal_gap 0.5)
			(thermal_bridge_width 0.5)
			(island_removal_mode 0)
		)
		(polygon
			(pts
				(arc
					(start 131.689856 -409.290012)
					(mid 130.930396 -409.290012)
					(end 131.689856 -409.290012)
				)
			)
		)
	)
	(zone
		(layers "B.Cu" "In15.Cu")
		(hatch none 0.5)
		(connect_pads
			(clearance 0)
		)
		(min_thickness 0.25)
		(keepout
			(tracks not_allowed)
			(vias allowed)
			(pads allowed)
			(copperpour not_allowed)
			(footprints allowed)
		)
		(placement
			(enabled no)
			(sheetname "")
		)
		(fill yes
			(thermal_gap 0.5)
			(thermal_bridge_width 0.5)
			(island_removal_mode 0)
		)
		(polygon
			(pts
				(arc
					(start 187.476384 -312.999882)
					(mid 186.823604 -312.999882)
					(end 187.476384 -312.999882)
				)
			)
		)
	)
	(zone
		(layers "B.Cu" "In15.Cu")
		(hatch none 0.5)
		(connect_pads
			(clearance 0)
		)
		(min_thickness 0.25)
		(keepout
			(tracks not_allowed)
			(vias allowed)
			(pads allowed)
			(copperpour not_allowed)
			(footprints allowed)
		)
		(placement
			(enabled no)
			(sheetname "")
		)
		(fill yes
			(thermal_gap 0.5)
			(thermal_bridge_width 0.5)
			(island_removal_mode 0)
		)
		(polygon
			(pts
				(arc
					(start 403.49297 -342.439498)
					(mid 402.78939 -342.439498)
					(end 403.49297 -342.439498)
				)
			)
		)
	)
	(zone
		(layers "B.Cu" "In15.Cu")
		(hatch none 0.5)
		(connect_pads
			(clearance 0)
		)
		(min_thickness 0.25)
		(keepout
			(tracks not_allowed)
			(vias allowed)
			(pads allowed)
			(copperpour not_allowed)
			(footprints allowed)
		)
		(placement
			(enabled no)
			(sheetname "")
		)
		(fill yes
			(thermal_gap 0.5)
			(thermal_bridge_width 0.5)
			(island_removal_mode 0)
		)
		(polygon
			(pts
				(arc
					(start 47.62627 -312.049922)
					(mid 46.97349 -312.049922)
					(end 47.62627 -312.049922)
				)
			)
		)
	)
	(zone
		(layers "B.Cu" "In15.Cu")
		(hatch none 0.5)
		(connect_pads
			(clearance 0)
		)
		(min_thickness 0.25)
		(keepout
			(tracks not_allowed)
			(vias allowed)
			(pads allowed)
			(copperpour not_allowed)
			(footprints allowed)
		)
		(placement
			(enabled no)
			(sheetname "")
		)
		(fill yes
			(thermal_gap 0.5)
			(thermal_bridge_width 0.5)
			(island_removal_mode 0)
		)
		(polygon
			(pts
				(arc
					(start 39.551356 -287.824926)
					(mid 38.898576 -287.824926)
					(end 39.551356 -287.824926)
				)
			)
		)
	)
	(zone
		(layers "B.Cu" "In15.Cu")
		(hatch none 0.5)
		(connect_pads
			(clearance 0)
		)
		(min_thickness 0.25)
		(keepout
			(tracks not_allowed)
			(vias allowed)
			(pads allowed)
			(copperpour not_allowed)
			(footprints allowed)
		)
		(placement
			(enabled no)
			(sheetname "")
		)
		(fill yes
			(thermal_gap 0.5)
			(thermal_bridge_width 0.5)
			(island_removal_mode 0)
		)
		(polygon
			(pts
				(arc
					(start 83.486752 -351.611438)
					(mid 82.783172 -351.611438)
					(end 83.486752 -351.611438)
				)
			)
		)
	)
	(zone
		(layers "B.Cu" "In15.Cu")
		(hatch none 0.5)
		(connect_pads
			(clearance 0)
		)
		(min_thickness 0.25)
		(keepout
			(tracks not_allowed)
			(vias allowed)
			(pads allowed)
			(copperpour not_allowed)
			(footprints allowed)
		)
		(placement
			(enabled no)
			(sheetname "")
		)
		(fill yes
			(thermal_gap 0.5)
			(thermal_bridge_width 0.5)
			(island_removal_mode 0)
		)
		(polygon
			(pts
				(arc
					(start 383.97561 -342.439498)
					(mid 383.27203 -342.439498)
					(end 383.97561 -342.439498)
				)
			)
		)
	)
	(zone
		(layers "B.Cu" "In15.Cu")
		(hatch none 0.5)
		(connect_pads
			(clearance 0)
		)
		(min_thickness 0.25)
		(keepout
			(tracks not_allowed)
			(vias allowed)
			(pads allowed)
			(copperpour not_allowed)
			(footprints allowed)
		)
		(placement
			(enabled no)
			(sheetname "")
		)
		(fill yes
			(thermal_gap 0.5)
			(thermal_bridge_width 0.5)
			(island_removal_mode 0)
		)
		(polygon
			(pts
				(arc
					(start 38.601396 -287.824926)
					(mid 37.948616 -287.824926)
					(end 38.601396 -287.824926)
				)
			)
		)
	)
	(zone
		(layers "B.Cu" "In15.Cu")
		(hatch none 0.5)
		(connect_pads
			(clearance 0)
		)
		(min_thickness 0.25)
		(keepout
			(tracks not_allowed)
			(vias allowed)
			(pads allowed)
			(copperpour not_allowed)
			(footprints allowed)
		)
		(placement
			(enabled no)
			(sheetname "")
		)
		(fill yes
			(thermal_gap 0.5)
			(thermal_bridge_width 0.5)
			(island_removal_mode 0)
		)
		(polygon
			(pts
				(arc
					(start 51.426364 -311.099962)
					(mid 50.773584 -311.099962)
					(end 51.426364 -311.099962)
				)
			)
		)
	)
	(zone
		(layers "B.Cu" "In15.Cu")
		(hatch none 0.5)
		(connect_pads
			(clearance 0)
		)
		(min_thickness 0.25)
		(keepout
			(tracks not_allowed)
			(vias allowed)
			(pads allowed)
			(copperpour not_allowed)
			(footprints allowed)
		)
		(placement
			(enabled no)
			(sheetname "")
		)
		(fill yes
			(thermal_gap 0.5)
			(thermal_bridge_width 0.5)
			(island_removal_mode 0)
		)
		(polygon
			(pts
				(arc
					(start 137.085578 -345.465146)
					(mid 136.381998 -345.465146)
					(end 137.085578 -345.465146)
				)
			)
		)
	)
	(zone
		(layers "B.Cu" "In15.Cu")
		(hatch none 0.5)
		(connect_pads
			(clearance 0)
		)
		(min_thickness 0.25)
		(keepout
			(tracks not_allowed)
			(vias allowed)
			(pads allowed)
			(copperpour not_allowed)
			(footprints allowed)
		)
		(placement
			(enabled no)
			(sheetname "")
		)
		(fill yes
			(thermal_gap 0.5)
			(thermal_bridge_width 0.5)
			(island_removal_mode 0)
		)
		(polygon
			(pts
				(arc
					(start 340.835234 -351.611438)
					(mid 340.131654 -351.611438)
					(end 340.835234 -351.611438)
				)
			)
		)
	)
	(zone
		(layers "B.Cu" "In15.Cu")
		(hatch none 0.5)
		(connect_pads
			(clearance 0)
		)
		(min_thickness 0.25)
		(keepout
			(tracks not_allowed)
			(vias allowed)
			(pads allowed)
			(copperpour not_allowed)
			(footprints allowed)
		)
		(placement
			(enabled no)
			(sheetname "")
		)
		(fill yes
			(thermal_gap 0.5)
			(thermal_bridge_width 0.5)
			(island_removal_mode 0)
		)
		(polygon
			(pts
				(arc
					(start 85.489542 -409.490164)
					(mid 84.730082 -409.490164)
					(end 85.489542 -409.490164)
				)
			)
		)
	)
	(zone
		(layers "B.Cu" "In15.Cu")
		(hatch none 0.5)
		(connect_pads
			(clearance 0)
		)
		(min_thickness 0.25)
		(keepout
			(tracks not_allowed)
			(vias allowed)
			(pads allowed)
			(copperpour not_allowed)
			(footprints allowed)
		)
		(placement
			(enabled no)
			(sheetname "")
		)
		(fill yes
			(thermal_gap 0.5)
			(thermal_bridge_width 0.5)
			(island_removal_mode 0)
		)
		(polygon
			(pts
				(arc
					(start 342.869774 -410.589984)
					(mid 342.110314 -410.589984)
					(end 342.869774 -410.589984)
				)
			)
		)
	)
	(zone
		(layers "B.Cu" "In15.Cu")
		(hatch none 0.5)
		(connect_pads
			(clearance 0)
		)
		(min_thickness 0.25)
		(keepout
			(tracks not_allowed)
			(vias allowed)
			(pads allowed)
			(copperpour not_allowed)
			(footprints allowed)
		)
		(placement
			(enabled no)
			(sheetname "")
		)
		(fill yes
			(thermal_gap 0.5)
			(thermal_bridge_width 0.5)
			(island_removal_mode 0)
		)
		(polygon
			(pts
				(arc
					(start 140.194538 -351.611438)
					(mid 139.490958 -351.611438)
					(end 140.194538 -351.611438)
				)
			)
		)
	)
	(zone
		(layers "B.Cu" "In15.Cu")
		(hatch none 0.5)
		(connect_pads
			(clearance 0)
		)
		(min_thickness 0.25)
		(keepout
			(tracks not_allowed)
			(vias allowed)
			(pads allowed)
			(copperpour not_allowed)
			(footprints allowed)
		)
		(placement
			(enabled no)
			(sheetname "")
		)
		(fill yes
			(thermal_gap 0.5)
			(thermal_bridge_width 0.5)
			(island_removal_mode 0)
		)
		(polygon
			(pts
				(arc
					(start 381.73025 -351.611438)
					(mid 381.02667 -351.611438)
					(end 381.73025 -351.611438)
				)
			)
		)
	)
	(zone
		(layers "B.Cu" "In15.Cu")
		(hatch none 0.5)
		(connect_pads
			(clearance 0)
		)
		(min_thickness 0.25)
		(keepout
			(tracks not_allowed)
			(vias allowed)
			(pads allowed)
			(copperpour not_allowed)
			(footprints allowed)
		)
		(placement
			(enabled no)
			(sheetname "")
		)
		(fill yes
			(thermal_gap 0.5)
			(thermal_bridge_width 0.5)
			(island_removal_mode 0)
		)
		(polygon
			(pts
				(arc
					(start 81.089754 -382.18999)
					(mid 80.330294 -382.18999)
					(end 81.089754 -382.18999)
				)
			)
		)
	)
	(zone
		(layers "B.Cu" "In15.Cu")
		(hatch none 0.5)
		(connect_pads
			(clearance 0)
		)
		(min_thickness 0.25)
		(keepout
			(tracks not_allowed)
			(vias allowed)
			(pads allowed)
			(copperpour not_allowed)
			(footprints allowed)
		)
		(placement
			(enabled no)
			(sheetname "")
		)
		(fill yes
			(thermal_gap 0.5)
			(thermal_bridge_width 0.5)
			(island_removal_mode 0)
		)
		(polygon
			(pts
				(arc
					(start 75.023472 -354.732082)
					(mid 74.319892 -354.732082)
					(end 75.023472 -354.732082)
				)
			)
		)
	)
	(zone
		(layers "B.Cu" "In15.Cu")
		(hatch none 0.5)
		(connect_pads
			(clearance 0)
		)
		(min_thickness 0.25)
		(keepout
			(tracks not_allowed)
			(vias allowed)
			(pads allowed)
			(copperpour not_allowed)
			(footprints allowed)
		)
		(placement
			(enabled no)
			(sheetname "")
		)
		(fill yes
			(thermal_gap 0.5)
			(thermal_bridge_width 0.5)
			(island_removal_mode 0)
		)
		(polygon
			(pts
				(arc
					(start 417.776406 -312.999882)
					(mid 417.123626 -312.999882)
					(end 417.776406 -312.999882)
				)
			)
		)
	)
	(zone
		(layers "B.Cu" "In15.Cu")
		(hatch none 0.5)
		(connect_pads
			(clearance 0)
		)
		(min_thickness 0.25)
		(keepout
			(tracks not_allowed)
			(vias allowed)
			(pads allowed)
			(copperpour not_allowed)
			(footprints allowed)
		)
		(placement
			(enabled no)
			(sheetname "")
		)
		(fill yes
			(thermal_gap 0.5)
			(thermal_bridge_width 0.5)
			(island_removal_mode 0)
		)
		(polygon
			(pts
				(arc
					(start 37.651182 -288.774886)
					(mid 36.998402 -288.774886)
					(end 37.651182 -288.774886)
				)
			)
		)
	)
	(zone
		(layers "B.Cu" "In15.Cu")
		(hatch none 0.5)
		(connect_pads
			(clearance 0)
		)
		(min_thickness 0.25)
		(keepout
			(tracks not_allowed)
			(vias allowed)
			(pads allowed)
			(copperpour not_allowed)
			(footprints allowed)
		)
		(placement
			(enabled no)
			(sheetname "")
		)
		(fill yes
			(thermal_gap 0.5)
			(thermal_bridge_width 0.5)
			(island_removal_mode 0)
		)
		(polygon
			(pts
				(arc
					(start 338.469732 -383.290064)
					(mid 337.710272 -383.290064)
					(end 338.469732 -383.290064)
				)
			)
		)
	)
	(zone
		(layers "B.Cu" "In15.Cu")
		(hatch none 0.5)
		(connect_pads
			(clearance 0)
		)
		(min_thickness 0.25)
		(keepout
			(tracks not_allowed)
			(vias allowed)
			(pads allowed)
			(copperpour not_allowed)
			(footprints allowed)
		)
		(placement
			(enabled no)
			(sheetname "")
		)
		(fill yes
			(thermal_gap 0.5)
			(thermal_bridge_width 0.5)
			(island_removal_mode 0)
		)
		(polygon
			(pts
				(arc
					(start 68.805552 -345.465146)
					(mid 68.101972 -345.465146)
					(end 68.805552 -345.465146)
				)
			)
		)
	)
	(zone
		(layers "B.Cu" "In15.Cu")
		(hatch none 0.5)
		(connect_pads
			(clearance 0)
		)
		(min_thickness 0.25)
		(keepout
			(tracks not_allowed)
			(vias allowed)
			(pads allowed)
			(copperpour not_allowed)
			(footprints allowed)
		)
		(placement
			(enabled no)
			(sheetname "")
		)
		(fill yes
			(thermal_gap 0.5)
			(thermal_bridge_width 0.5)
			(island_removal_mode 0)
		)
		(polygon
			(pts
				(arc
					(start 288.376106 -313.949842)
					(mid 287.723326 -313.949842)
					(end 288.376106 -313.949842)
				)
			)
		)
	)
	(zone
		(layers "B.Cu" "In15.Cu")
		(hatch none 0.5)
		(connect_pads
			(clearance 0)
		)
		(min_thickness 0.25)
		(keepout
			(tracks not_allowed)
			(vias allowed)
			(pads allowed)
			(copperpour not_allowed)
			(footprints allowed)
		)
		(placement
			(enabled no)
			(sheetname "")
		)
		(fill yes
			(thermal_gap 0.5)
			(thermal_bridge_width 0.5)
			(island_removal_mode 0)
		)
		(polygon
			(pts
				(arc
					(start 44.776136 -312.999882)
					(mid 44.123356 -312.999882)
					(end 44.776136 -312.999882)
				)
			)
		)
	)
	(zone
		(layers "B.Cu" "In15.Cu")
		(hatch none 0.5)
		(connect_pads
			(clearance 0)
		)
		(min_thickness 0.25)
		(keepout
			(tracks not_allowed)
			(vias allowed)
			(pads allowed)
			(copperpour not_allowed)
			(footprints allowed)
		)
		(placement
			(enabled no)
			(sheetname "")
		)
		(fill yes
			(thermal_gap 0.5)
			(thermal_bridge_width 0.5)
			(island_removal_mode 0)
		)
		(polygon
			(pts
				(arc
					(start 127.289814 -410.589984)
					(mid 126.530354 -410.589984)
					(end 127.289814 -410.589984)
				)
			)
		)
	)
	(zone
		(layers "B.Cu" "In15.Cu")
		(hatch none 0.5)
		(connect_pads
			(clearance 0)
		)
		(min_thickness 0.25)
		(keepout
			(tracks not_allowed)
			(vias allowed)
			(pads allowed)
			(copperpour not_allowed)
			(footprints allowed)
		)
		(placement
			(enabled no)
			(sheetname "")
		)
		(fill yes
			(thermal_gap 0.5)
			(thermal_bridge_width 0.5)
			(island_removal_mode 0)
		)
		(polygon
			(pts
				(arc
					(start 382.469644 -410.589984)
					(mid 381.710184 -410.589984)
					(end 382.469644 -410.589984)
				)
			)
		)
	)
	(zone
		(layers "B.Cu" "In15.Cu")
		(hatch none 0.5)
		(connect_pads
			(clearance 0)
		)
		(min_thickness 0.25)
		(keepout
			(tracks not_allowed)
			(vias allowed)
			(pads allowed)
			(copperpour not_allowed)
			(footprints allowed)
		)
		(placement
			(enabled no)
			(sheetname "")
		)
		(fill yes
			(thermal_gap 0.5)
			(thermal_bridge_width 0.5)
			(island_removal_mode 0)
		)
		(polygon
			(pts
				(arc
					(start 87.68969 -384.590036)
					(mid 86.93023 -384.590036)
					(end 87.68969 -384.590036)
				)
			)
		)
	)
	(zone
		(layers "B.Cu" "In15.Cu")
		(hatch none 0.5)
		(connect_pads
			(clearance 0)
		)
		(min_thickness 0.25)
		(keepout
			(tracks not_allowed)
			(vias allowed)
			(pads allowed)
			(copperpour not_allowed)
			(footprints allowed)
		)
		(placement
			(enabled no)
			(sheetname "")
		)
		(fill yes
			(thermal_gap 0.5)
			(thermal_bridge_width 0.5)
			(island_removal_mode 0)
		)
		(polygon
			(pts
				(arc
					(start 166.576248 -313.949842)
					(mid 165.923468 -313.949842)
					(end 166.576248 -313.949842)
				)
			)
		)
	)
	(zone
		(layers "B.Cu" "In15.Cu")
		(hatch none 0.5)
		(connect_pads
			(clearance 0)
		)
		(min_thickness 0.25)
		(keepout
			(tracks not_allowed)
			(vias allowed)
			(pads allowed)
			(copperpour not_allowed)
			(footprints allowed)
		)
		(placement
			(enabled no)
			(sheetname "")
		)
		(fill yes
			(thermal_gap 0.5)
			(thermal_bridge_width 0.5)
			(island_removal_mode 0)
		)
		(polygon
			(pts
				(arc
					(start 48.57623 -312.999882)
					(mid 47.92345 -312.999882)
					(end 48.57623 -312.999882)
				)
			)
		)
	)
	(zone
		(layers "B.Cu" "In15.Cu")
		(hatch none 0.5)
		(connect_pads
			(clearance 0)
		)
		(min_thickness 0.25)
		(keepout
			(tracks not_allowed)
			(vias allowed)
			(pads allowed)
			(copperpour not_allowed)
			(footprints allowed)
		)
		(placement
			(enabled no)
			(sheetname "")
		)
		(fill yes
			(thermal_gap 0.5)
			(thermal_bridge_width 0.5)
			(island_removal_mode 0)
		)
		(polygon
			(pts
				(arc
					(start 118.48973 -410.589984)
					(mid 117.73027 -410.589984)
					(end 118.48973 -410.589984)
				)
			)
		)
	)
	(zone
		(layers "B.Cu" "In15.Cu")
		(hatch none 0.5)
		(connect_pads
			(clearance 0)
		)
		(min_thickness 0.25)
		(keepout
			(tracks not_allowed)
			(vias allowed)
			(pads allowed)
			(copperpour not_allowed)
			(footprints allowed)
		)
		(placement
			(enabled no)
			(sheetname "")
		)
		(fill yes
			(thermal_gap 0.5)
			(thermal_bridge_width 0.5)
			(island_removal_mode 0)
		)
		(polygon
			(pts
				(arc
					(start 391.269728 -379.390148)
					(mid 390.510268 -379.390148)
					(end 391.269728 -379.390148)
				)
			)
		)
	)
	(zone
		(layers "B.Cu" "In15.Cu")
		(hatch none 0.5)
		(connect_pads
			(clearance 0)
		)
		(min_thickness 0.25)
		(keepout
			(tracks not_allowed)
			(vias allowed)
			(pads allowed)
			(copperpour not_allowed)
			(footprints allowed)
		)
		(placement
			(enabled no)
			(sheetname "")
		)
		(fill yes
			(thermal_gap 0.5)
			(thermal_bridge_width 0.5)
			(island_removal_mode 0)
		)
		(polygon
			(pts
				(arc
					(start 286.476186 -313.949842)
					(mid 285.823406 -313.949842)
					(end 286.476186 -313.949842)
				)
			)
		)
	)
	(zone
		(layers "B.Cu" "In15.Cu")
		(hatch none 0.5)
		(connect_pads
			(clearance 0)
		)
		(min_thickness 0.25)
		(keepout
			(tracks not_allowed)
			(vias allowed)
			(pads allowed)
			(copperpour not_allowed)
			(footprints allowed)
		)
		(placement
			(enabled no)
			(sheetname "")
		)
		(fill yes
			(thermal_gap 0.5)
			(thermal_bridge_width 0.5)
			(island_removal_mode 0)
		)
		(polygon
			(pts
				(arc
					(start 86.595712 -357.75773)
					(mid 85.892132 -357.75773)
					(end 86.595712 -357.75773)
				)
			)
		)
	)
	(zone
		(layers "B.Cu" "In15.Cu")
		(hatch none 0.5)
		(connect_pads
			(clearance 0)
		)
		(min_thickness 0.25)
		(keepout
			(tracks not_allowed)
			(vias allowed)
			(pads allowed)
			(copperpour not_allowed)
			(footprints allowed)
		)
		(placement
			(enabled no)
			(sheetname "")
		)
		(fill yes
			(thermal_gap 0.5)
			(thermal_bridge_width 0.5)
			(island_removal_mode 0)
		)
		(polygon
			(pts
				(arc
					(start 384.669792 -408.190192)
					(mid 383.910332 -408.190192)
					(end 384.669792 -408.190192)
				)
			)
		)
	)
	(zone
		(layers "B.Cu" "In15.Cu")
		(hatch none 0.5)
		(connect_pads
			(clearance 0)
		)
		(min_thickness 0.25)
		(keepout
			(tracks not_allowed)
			(vias allowed)
			(pads allowed)
			(copperpour not_allowed)
			(footprints allowed)
		)
		(placement
			(enabled no)
			(sheetname "")
		)
		(fill yes
			(thermal_gap 0.5)
			(thermal_bridge_width 0.5)
			(island_removal_mode 0)
		)
		(polygon
			(pts
				(arc
					(start 50.47615 -313.949842)
					(mid 49.82337 -313.949842)
					(end 50.47615 -313.949842)
				)
			)
		)
	)
	(zone
		(layers "B.Cu" "In15.Cu")
		(hatch none 0.5)
		(connect_pads
			(clearance 0)
		)
		(min_thickness 0.25)
		(keepout
			(tracks not_allowed)
			(vias allowed)
			(pads allowed)
			(copperpour not_allowed)
			(footprints allowed)
		)
		(placement
			(enabled no)
			(sheetname "")
		)
		(fill yes
			(thermal_gap 0.5)
			(thermal_bridge_width 0.5)
			(island_removal_mode 0)
		)
		(polygon
			(pts
				(arc
					(start 316.827154 -351.611438)
					(mid 316.123574 -351.611438)
					(end 316.827154 -351.611438)
				)
			)
		)
	)
	(zone
		(layers "B.Cu" "In15.Cu")
		(hatch none 0.5)
		(connect_pads
			(clearance 0)
		)
		(min_thickness 0.25)
		(keepout
			(tracks not_allowed)
			(vias allowed)
			(pads allowed)
			(copperpour not_allowed)
			(footprints allowed)
		)
		(placement
			(enabled no)
			(sheetname "")
		)
		(fill yes
			(thermal_gap 0.5)
			(thermal_bridge_width 0.5)
			(island_removal_mode 0)
		)
		(polygon
			(pts
				(arc
					(start 86.595712 -354.732082)
					(mid 85.892132 -354.732082)
					(end 86.595712 -354.732082)
				)
			)
		)
	)
	(zone
		(layers "B.Cu" "In15.Cu")
		(hatch none 0.5)
		(connect_pads
			(clearance 0)
		)
		(min_thickness 0.25)
		(keepout
			(tracks not_allowed)
			(vias allowed)
			(pads allowed)
			(copperpour not_allowed)
			(footprints allowed)
		)
		(placement
			(enabled no)
			(sheetname "")
		)
		(fill yes
			(thermal_gap 0.5)
			(thermal_bridge_width 0.5)
			(island_removal_mode 0)
		)
		(polygon
			(pts
				(arc
					(start 131.689856 -380.69012)
					(mid 130.930396 -380.69012)
					(end 131.689856 -380.69012)
				)
			)
		)
	)
	(zone
		(layers "B.Cu" "In15.Cu")
		(hatch none 0.5)
		(connect_pads
			(clearance 0)
		)
		(min_thickness 0.25)
		(keepout
			(tracks not_allowed)
			(vias allowed)
			(pads allowed)
			(copperpour not_allowed)
			(footprints allowed)
		)
		(placement
			(enabled no)
			(sheetname "")
		)
		(fill yes
			(thermal_gap 0.5)
			(thermal_bridge_width 0.5)
			(island_removal_mode 0)
		)
		(polygon
			(pts
				(arc
					(start 391.05713 -345.465146)
					(mid 390.35355 -345.465146)
					(end 391.05713 -345.465146)
				)
			)
		)
	)
	(zone
		(layers "B.Cu" "In15.Cu")
		(hatch none 0.5)
		(connect_pads
			(clearance 0)
		)
		(min_thickness 0.25)
		(keepout
			(tracks not_allowed)
			(vias allowed)
			(pads allowed)
			(copperpour not_allowed)
			(footprints allowed)
		)
		(placement
			(enabled no)
			(sheetname "")
		)
		(fill yes
			(thermal_gap 0.5)
			(thermal_bridge_width 0.5)
			(island_removal_mode 0)
		)
		(polygon
			(pts
				(arc
					(start 68.805552 -354.732082)
					(mid 68.101972 -354.732082)
					(end 68.805552 -354.732082)
				)
			)
		)
	)
	(zone
		(layers "B.Cu" "In15.Cu")
		(hatch none 0.5)
		(connect_pads
			(clearance 0)
		)
		(min_thickness 0.25)
		(keepout
			(tracks not_allowed)
			(vias allowed)
			(pads allowed)
			(copperpour not_allowed)
			(footprints allowed)
		)
		(placement
			(enabled no)
			(sheetname "")
		)
		(fill yes
			(thermal_gap 0.5)
			(thermal_bridge_width 0.5)
			(island_removal_mode 0)
		)
		(polygon
			(pts
				(arc
					(start 345.069668 -409.490164)
					(mid 344.310208 -409.490164)
					(end 345.069668 -409.490164)
				)
			)
		)
	)
	(zone
		(layers "B.Cu" "In15.Cu")
		(hatch none 0.5)
		(connect_pads
			(clearance 0)
		)
		(min_thickness 0.25)
		(keepout
			(tracks not_allowed)
			(vias allowed)
			(pads allowed)
			(copperpour not_allowed)
			(footprints allowed)
		)
		(placement
			(enabled no)
			(sheetname "")
		)
		(fill yes
			(thermal_gap 0.5)
			(thermal_bridge_width 0.5)
			(island_removal_mode 0)
		)
		(polygon
			(pts
				(arc
					(start 185.576464 -313.949842)
					(mid 184.923684 -313.949842)
					(end 185.576464 -313.949842)
				)
			)
		)
	)
	(zone
		(layers "B.Cu" "In15.Cu")
		(hatch none 0.5)
		(connect_pads
			(clearance 0)
		)
		(min_thickness 0.25)
		(keepout
			(tracks not_allowed)
			(vias allowed)
			(pads allowed)
			(copperpour not_allowed)
			(footprints allowed)
		)
		(placement
			(enabled no)
			(sheetname "")
		)
		(fill yes
			(thermal_gap 0.5)
			(thermal_bridge_width 0.5)
			(island_removal_mode 0)
		)
		(polygon
			(pts
				(arc
					(start 124.649738 -345.465146)
					(mid 123.946158 -345.465146)
					(end 124.649738 -345.465146)
				)
			)
		)
	)
	(zone
		(layers "B.Cu" "In15.Cu")
		(hatch none 0.5)
		(connect_pads
			(clearance 0)
		)
		(min_thickness 0.25)
		(keepout
			(tracks not_allowed)
			(vias allowed)
			(pads allowed)
			(copperpour not_allowed)
			(footprints allowed)
		)
		(placement
			(enabled no)
			(sheetname "")
		)
		(fill yes
			(thermal_gap 0.5)
			(thermal_bridge_width 0.5)
			(island_removal_mode 0)
		)
		(polygon
			(pts
				(arc
					(start 417.776406 -313.949842)
					(mid 417.123626 -313.949842)
					(end 417.776406 -313.949842)
				)
			)
		)
	)
	(zone
		(layers "B.Cu" "In15.Cu")
		(hatch none 0.5)
		(connect_pads
			(clearance 0)
		)
		(min_thickness 0.25)
		(keepout
			(tracks not_allowed)
			(vias allowed)
			(pads allowed)
			(copperpour not_allowed)
			(footprints allowed)
		)
		(placement
			(enabled no)
			(sheetname "")
		)
		(fill yes
			(thermal_gap 0.5)
			(thermal_bridge_width 0.5)
			(island_removal_mode 0)
		)
		(polygon
			(pts
				(arc
					(start 384.669792 -379.590046)
					(mid 383.910332 -379.590046)
					(end 384.669792 -379.590046)
				)
			)
		)
	)
	(zone
		(layers "B.Cu" "In15.Cu")
		(hatch none 0.5)
		(connect_pads
			(clearance 0)
		)
		(min_thickness 0.25)
		(keepout
			(tracks not_allowed)
			(vias allowed)
			(pads allowed)
			(copperpour not_allowed)
			(footprints allowed)
		)
		(placement
			(enabled no)
			(sheetname "")
		)
		(fill yes
			(thermal_gap 0.5)
			(thermal_bridge_width 0.5)
			(island_removal_mode 0)
		)
		(polygon
			(pts
				(arc
					(start 48.57623 -313.949842)
					(mid 47.92345 -313.949842)
					(end 48.57623 -313.949842)
				)
			)
		)
	)
	(zone
		(layers "B.Cu" "In15.Cu")
		(hatch none 0.5)
		(connect_pads
			(clearance 0)
		)
		(min_thickness 0.25)
		(keepout
			(tracks not_allowed)
			(vias allowed)
			(pads allowed)
			(copperpour not_allowed)
			(footprints allowed)
		)
		(placement
			(enabled no)
			(sheetname "")
		)
		(fill yes
			(thermal_gap 0.5)
			(thermal_bridge_width 0.5)
			(island_removal_mode 0)
		)
		(polygon
			(pts
				(arc
					(start 384.83921 -357.75773)
					(mid 384.13563 -357.75773)
					(end 384.83921 -357.75773)
				)
			)
		)
	)
	(zone
		(layers "B.Cu" "In15.Cu")
		(hatch none 0.5)
		(connect_pads
			(clearance 0)
		)
		(min_thickness 0.25)
		(keepout
			(tracks not_allowed)
			(vias allowed)
			(pads allowed)
			(copperpour not_allowed)
			(footprints allowed)
		)
		(placement
			(enabled no)
			(sheetname "")
		)
		(fill yes
			(thermal_gap 0.5)
			(thermal_bridge_width 0.5)
			(island_removal_mode 0)
		)
		(polygon
			(pts
				(arc
					(start 122.889772 -379.390148)
					(mid 122.130312 -379.390148)
					(end 122.889772 -379.390148)
				)
			)
		)
	)
	(zone
		(layers "B.Cu" "In15.Cu")
		(hatch none 0.5)
		(connect_pads
			(clearance 0)
		)
		(min_thickness 0.25)
		(keepout
			(tracks not_allowed)
			(vias allowed)
			(pads allowed)
			(copperpour not_allowed)
			(footprints allowed)
		)
		(placement
			(enabled no)
			(sheetname "")
		)
		(fill yes
			(thermal_gap 0.5)
			(thermal_bridge_width 0.5)
			(island_removal_mode 0)
		)
		(polygon
			(pts
				(arc
					(start 284.576266 -313.949842)
					(mid 283.923486 -313.949842)
					(end 284.576266 -313.949842)
				)
			)
		)
	)
	(zone
		(layers "B.Cu" "In15.Cu")
		(hatch none 0.5)
		(connect_pads
			(clearance 0)
		)
		(min_thickness 0.25)
		(keepout
			(tracks not_allowed)
			(vias allowed)
			(pads allowed)
			(copperpour not_allowed)
			(footprints allowed)
		)
		(placement
			(enabled no)
			(sheetname "")
		)
		(fill yes
			(thermal_gap 0.5)
			(thermal_bridge_width 0.5)
			(island_removal_mode 0)
		)
		(polygon
			(pts
				(arc
					(start 386.869686 -409.290012)
					(mid 386.110226 -409.290012)
					(end 386.869686 -409.290012)
				)
			)
		)
	)
	(zone
		(layers "B.Cu" "In15.Cu")
		(hatch none 0.5)
		(connect_pads
			(clearance 0)
		)
		(min_thickness 0.25)
		(keepout
			(tracks not_allowed)
			(vias allowed)
			(pads allowed)
			(copperpour not_allowed)
			(footprints allowed)
		)
		(placement
			(enabled no)
			(sheetname "")
		)
		(fill yes
			(thermal_gap 0.5)
			(thermal_bridge_width 0.5)
			(island_removal_mode 0)
		)
		(polygon
			(pts
				(arc
					(start 322.181474 -351.611438)
					(mid 321.477894 -351.611438)
					(end 322.181474 -351.611438)
				)
			)
		)
	)
	(zone
		(layers "B.Cu" "In15.Cu")
		(hatch none 0.5)
		(connect_pads
			(clearance 0)
		)
		(min_thickness 0.25)
		(keepout
			(tracks not_allowed)
			(vias allowed)
			(pads allowed)
			(copperpour not_allowed)
			(footprints allowed)
		)
		(placement
			(enabled no)
			(sheetname "")
		)
		(fill yes
			(thermal_gap 0.5)
			(thermal_bridge_width 0.5)
			(island_removal_mode 0)
		)
		(polygon
			(pts
				(arc
					(start 65.696592 -348.58579)
					(mid 64.993012 -348.58579)
					(end 65.696592 -348.58579)
				)
			)
		)
	)
	(zone
		(layers "B.Cu" "In15.Cu")
		(hatch none 0.5)
		(connect_pads
			(clearance 0)
		)
		(min_thickness 0.25)
		(keepout
			(tracks not_allowed)
			(vias allowed)
			(pads allowed)
			(copperpour not_allowed)
			(footprints allowed)
		)
		(placement
			(enabled no)
			(sheetname "")
		)
		(fill yes
			(thermal_gap 0.5)
			(thermal_bridge_width 0.5)
			(island_removal_mode 0)
		)
		(polygon
			(pts
				(arc
					(start 45.72635 -311.099962)
					(mid 45.07357 -311.099962)
					(end 45.72635 -311.099962)
				)
			)
		)
	)
	(zone
		(layers "B.Cu" "In15.Cu")
		(hatch none 0.5)
		(connect_pads
			(clearance 0)
		)
		(min_thickness 0.25)
		(keepout
			(tracks not_allowed)
			(vias allowed)
			(pads allowed)
			(copperpour not_allowed)
			(footprints allowed)
		)
		(placement
			(enabled no)
			(sheetname "")
		)
		(fill yes
			(thermal_gap 0.5)
			(thermal_bridge_width 0.5)
			(island_removal_mode 0)
		)
		(polygon
			(pts
				(arc
					(start 119.295418 -345.465146)
					(mid 118.591838 -345.465146)
					(end 119.295418 -345.465146)
				)
			)
		)
	)
	(zone
		(layers "B.Cu" "In15.Cu")
		(hatch none 0.5)
		(connect_pads
			(clearance 0)
		)
		(min_thickness 0.25)
		(keepout
			(tracks not_allowed)
			(vias allowed)
			(pads allowed)
			(copperpour not_allowed)
			(footprints allowed)
		)
		(placement
			(enabled no)
			(sheetname "")
		)
		(fill yes
			(thermal_gap 0.5)
			(thermal_bridge_width 0.5)
			(island_removal_mode 0)
		)
		(polygon
			(pts
				(arc
					(start 397.82623 -311.099962)
					(mid 397.17345 -311.099962)
					(end 397.82623 -311.099962)
				)
			)
		)
	)
	(zone
		(layers "B.Cu" "In15.Cu")
		(hatch none 0.5)
		(connect_pads
			(clearance 0)
		)
		(min_thickness 0.25)
		(keepout
			(tracks not_allowed)
			(vias allowed)
			(pads allowed)
			(copperpour not_allowed)
			(footprints allowed)
		)
		(placement
			(enabled no)
			(sheetname "")
		)
		(fill yes
			(thermal_gap 0.5)
			(thermal_bridge_width 0.5)
			(island_removal_mode 0)
		)
		(polygon
			(pts
				(arc
					(start 81.089754 -408.190192)
					(mid 80.330294 -408.190192)
					(end 81.089754 -408.190192)
				)
			)
		)
	)
	(zone
		(layers "B.Cu" "In15.Cu")
		(hatch none 0.5)
		(connect_pads
			(clearance 0)
		)
		(min_thickness 0.25)
		(keepout
			(tracks not_allowed)
			(vias allowed)
			(pads allowed)
			(copperpour not_allowed)
			(footprints allowed)
		)
		(placement
			(enabled no)
			(sheetname "")
		)
		(fill yes
			(thermal_gap 0.5)
			(thermal_bridge_width 0.5)
			(island_removal_mode 0)
		)
		(polygon
			(pts
				(arc
					(start 90.568272 -351.611438)
					(mid 89.864692 -351.611438)
					(end 90.568272 -351.611438)
				)
			)
		)
	)
	(zone
		(layers "B.Cu" "In15.Cu")
		(hatch none 0.5)
		(connect_pads
			(clearance 0)
		)
		(min_thickness 0.25)
		(keepout
			(tracks not_allowed)
			(vias allowed)
			(pads allowed)
			(copperpour not_allowed)
			(footprints allowed)
		)
		(placement
			(enabled no)
			(sheetname "")
		)
		(fill yes
			(thermal_gap 0.5)
			(thermal_bridge_width 0.5)
			(island_removal_mode 0)
		)
		(polygon
			(pts
				(arc
					(start 326.154034 -354.732082)
					(mid 325.450454 -354.732082)
					(end 326.154034 -354.732082)
				)
			)
		)
	)
	(zone
		(layers "B.Cu" "In15.Cu")
		(hatch none 0.5)
		(connect_pads
			(clearance 0)
		)
		(min_thickness 0.25)
		(keepout
			(tracks not_allowed)
			(vias allowed)
			(pads allowed)
			(copperpour not_allowed)
			(footprints allowed)
		)
		(placement
			(enabled no)
			(sheetname "")
		)
		(fill yes
			(thermal_gap 0.5)
			(thermal_bridge_width 0.5)
			(island_removal_mode 0)
		)
		(polygon
			(pts
				(arc
					(start 382.469644 -379.390148)
					(mid 381.710184 -379.390148)
					(end 382.469644 -379.390148)
				)
			)
		)
	)
	(zone
		(layers "B.Cu" "In15.Cu")
		(hatch none 0.5)
		(connect_pads
			(clearance 0)
		)
		(min_thickness 0.25)
		(keepout
			(tracks not_allowed)
			(vias allowed)
			(pads allowed)
			(copperpour not_allowed)
			(footprints allowed)
		)
		(placement
			(enabled no)
			(sheetname "")
		)
		(fill yes
			(thermal_gap 0.5)
			(thermal_bridge_width 0.5)
			(island_removal_mode 0)
		)
		(polygon
			(pts
				(arc
					(start 396.41145 -354.732082)
					(mid 395.70787 -354.732082)
					(end 396.41145 -354.732082)
				)
			)
		)
	)
	(zone
		(layers "B.Cu" "In15.Cu")
		(hatch none 0.5)
		(connect_pads
			(clearance 0)
		)
		(min_thickness 0.25)
		(keepout
			(tracks not_allowed)
			(vias allowed)
			(pads allowed)
			(copperpour not_allowed)
			(footprints allowed)
		)
		(placement
			(enabled no)
			(sheetname "")
		)
		(fill yes
			(thermal_gap 0.5)
			(thermal_bridge_width 0.5)
			(island_removal_mode 0)
		)
		(polygon
			(pts
				(arc
					(start 344.807794 -354.732082)
					(mid 344.104214 -354.732082)
					(end 344.807794 -354.732082)
				)
			)
		)
	)
	(zone
		(layers "B.Cu" "In15.Cu")
		(hatch none 0.5)
		(connect_pads
			(clearance 0)
		)
		(min_thickness 0.25)
		(keepout
			(tracks not_allowed)
			(vias allowed)
			(pads allowed)
			(copperpour not_allowed)
			(footprints allowed)
		)
		(placement
			(enabled no)
			(sheetname "")
		)
		(fill yes
			(thermal_gap 0.5)
			(thermal_bridge_width 0.5)
			(island_removal_mode 0)
		)
		(polygon
			(pts
				(arc
					(start 338.589874 -345.465146)
					(mid 337.886294 -345.465146)
					(end 338.589874 -345.465146)
				)
			)
		)
	)
	(zone
		(layers "B.Cu" "In15.Cu")
		(hatch none 0.5)
		(connect_pads
			(clearance 0)
		)
		(min_thickness 0.25)
		(keepout
			(tracks not_allowed)
			(vias allowed)
			(pads allowed)
			(copperpour not_allowed)
			(footprints allowed)
		)
		(placement
			(enabled no)
			(sheetname "")
		)
		(fill yes
			(thermal_gap 0.5)
			(thermal_bridge_width 0.5)
			(island_removal_mode 0)
		)
		(polygon
			(pts
				(arc
					(start 347.269816 -410.589984)
					(mid 346.510356 -410.589984)
					(end 347.269816 -410.589984)
				)
			)
		)
	)
	(zone
		(layers "B.Cu" "In15.Cu")
		(hatch none 0.5)
		(connect_pads
			(clearance 0)
		)
		(min_thickness 0.25)
		(keepout
			(tracks not_allowed)
			(vias allowed)
			(pads allowed)
			(copperpour not_allowed)
			(footprints allowed)
		)
		(placement
			(enabled no)
			(sheetname "")
		)
		(fill yes
			(thermal_gap 0.5)
			(thermal_bridge_width 0.5)
			(island_removal_mode 0)
		)
		(polygon
			(pts
				(arc
					(start 189.376304 -312.999882)
					(mid 188.723524 -312.999882)
					(end 189.376304 -312.999882)
				)
			)
		)
	)
	(zone
		(layers "B.Cu" "In15.Cu")
		(hatch none 0.5)
		(connect_pads
			(clearance 0)
		)
		(min_thickness 0.25)
		(keepout
			(tracks not_allowed)
			(vias allowed)
			(pads allowed)
			(copperpour not_allowed)
			(footprints allowed)
		)
		(placement
			(enabled no)
			(sheetname "")
		)
		(fill yes
			(thermal_gap 0.5)
			(thermal_bridge_width 0.5)
			(island_removal_mode 0)
		)
		(polygon
			(pts
				(arc
					(start 42.401236 -287.824926)
					(mid 41.748456 -287.824926)
					(end 42.401236 -287.824926)
				)
			)
		)
	)
	(zone
		(layers "B.Cu" "In15.Cu")
		(hatch none 0.5)
		(connect_pads
			(clearance 0)
		)
		(min_thickness 0.25)
		(keepout
			(tracks not_allowed)
			(vias allowed)
			(pads allowed)
			(copperpour not_allowed)
			(footprints allowed)
		)
		(placement
			(enabled no)
			(sheetname "")
		)
		(fill yes
			(thermal_gap 0.5)
			(thermal_bridge_width 0.5)
			(island_removal_mode 0)
		)
		(polygon
			(pts
				(arc
					(start 87.68969 -383.290064)
					(mid 86.93023 -383.290064)
					(end 87.68969 -383.290064)
				)
			)
		)
	)
	(zone
		(layers "B.Cu" "In15.Cu")
		(hatch none 0.5)
		(connect_pads
			(clearance 0)
		)
		(min_thickness 0.25)
		(keepout
			(tracks not_allowed)
			(vias allowed)
			(pads allowed)
			(copperpour not_allowed)
			(footprints allowed)
		)
		(placement
			(enabled no)
			(sheetname "")
		)
		(fill yes
			(thermal_gap 0.5)
			(thermal_bridge_width 0.5)
			(island_removal_mode 0)
		)
		(polygon
			(pts
				(arc
					(start 372.40337 -345.465146)
					(mid 371.69979 -345.465146)
					(end 372.40337 -345.465146)
				)
			)
		)
	)
	(zone
		(layers "B.Cu" "In15.Cu")
		(hatch none 0.5)
		(connect_pads
			(clearance 0)
		)
		(min_thickness 0.25)
		(keepout
			(tracks not_allowed)
			(vias allowed)
			(pads allowed)
			(copperpour not_allowed)
			(footprints allowed)
		)
		(placement
			(enabled no)
			(sheetname "")
		)
		(fill yes
			(thermal_gap 0.5)
			(thermal_bridge_width 0.5)
			(island_removal_mode 0)
		)
		(polygon
			(pts
				(arc
					(start 280.776172 -313.949842)
					(mid 280.123392 -313.949842)
					(end 280.776172 -313.949842)
				)
			)
		)
	)
	(zone
		(layers "B.Cu" "In15.Cu")
		(hatch none 0.5)
		(connect_pads
			(clearance 0)
		)
		(min_thickness 0.25)
		(keepout
			(tracks not_allowed)
			(vias allowed)
			(pads allowed)
			(copperpour not_allowed)
			(footprints allowed)
		)
		(placement
			(enabled no)
			(sheetname "")
		)
		(fill yes
			(thermal_gap 0.5)
			(thermal_bridge_width 0.5)
			(island_removal_mode 0)
		)
		(polygon
			(pts
				(arc
					(start 341.698834 -351.611438)
					(mid 340.995254 -351.611438)
					(end 341.698834 -351.611438)
				)
			)
		)
	)
	(zone
		(layers "B.Cu" "In15.Cu")
		(hatch none 0.5)
		(connect_pads
			(clearance 0)
		)
		(min_thickness 0.25)
		(keepout
			(tracks not_allowed)
			(vias allowed)
			(pads allowed)
			(copperpour not_allowed)
			(footprints allowed)
		)
		(placement
			(enabled no)
			(sheetname "")
		)
		(fill yes
			(thermal_gap 0.5)
			(thermal_bridge_width 0.5)
			(island_removal_mode 0)
		)
		(polygon
			(pts
				(arc
					(start 398.77619 -313.949842)
					(mid 398.12341 -313.949842)
					(end 398.77619 -313.949842)
				)
			)
		)
	)
	(zone
		(layers "B.Cu" "In15.Cu")
		(hatch none 0.5)
		(connect_pads
			(clearance 0)
		)
		(min_thickness 0.25)
		(keepout
			(tracks not_allowed)
			(vias allowed)
			(pads allowed)
			(copperpour not_allowed)
			(footprints allowed)
		)
		(placement
			(enabled no)
			(sheetname "")
		)
		(fill yes
			(thermal_gap 0.5)
			(thermal_bridge_width 0.5)
			(island_removal_mode 0)
		)
		(polygon
			(pts
				(arc
					(start 375.51233 -348.58579)
					(mid 374.80875 -348.58579)
					(end 375.51233 -348.58579)
				)
			)
		)
	)
	(zone
		(layers "B.Cu" "In15.Cu")
		(hatch none 0.5)
		(connect_pads
			(clearance 0)
		)
		(min_thickness 0.25)
		(keepout
			(tracks not_allowed)
			(vias allowed)
			(pads allowed)
			(copperpour not_allowed)
			(footprints allowed)
		)
		(placement
			(enabled no)
			(sheetname "")
		)
		(fill yes
			(thermal_gap 0.5)
			(thermal_bridge_width 0.5)
			(island_removal_mode 0)
		)
		(polygon
			(pts
				(arc
					(start 92.813632 -357.75773)
					(mid 92.110052 -357.75773)
					(end 92.813632 -357.75773)
				)
			)
		)
	)
	(zone
		(layers "B.Cu" "In15.Cu")
		(hatch none 0.5)
		(connect_pads
			(clearance 0)
		)
		(min_thickness 0.25)
		(keepout
			(tracks not_allowed)
			(vias allowed)
			(pads allowed)
			(copperpour not_allowed)
			(footprints allowed)
		)
		(placement
			(enabled no)
			(sheetname "")
		)
		(fill yes
			(thermal_gap 0.5)
			(thermal_bridge_width 0.5)
			(island_removal_mode 0)
		)
		(polygon
			(pts
				(arc
					(start 372.40337 -342.439498)
					(mid 371.69979 -342.439498)
					(end 372.40337 -342.439498)
				)
			)
		)
	)
	(zone
		(layers "B.Cu" "In15.Cu")
		(hatch none 0.5)
		(connect_pads
			(clearance 0)
		)
		(min_thickness 0.25)
		(keepout
			(tracks not_allowed)
			(vias allowed)
			(pads allowed)
			(copperpour not_allowed)
			(footprints allowed)
		)
		(placement
			(enabled no)
			(sheetname "")
		)
		(fill yes
			(thermal_gap 0.5)
			(thermal_bridge_width 0.5)
			(island_removal_mode 0)
		)
		(polygon
			(pts
				(arc
					(start 137.085578 -357.75773)
					(mid 136.381998 -357.75773)
					(end 137.085578 -357.75773)
				)
			)
		)
	)
	(zone
		(layers "B.Cu" "In15.Cu")
		(hatch none 0.5)
		(connect_pads
			(clearance 0)
		)
		(min_thickness 0.25)
		(keepout
			(tracks not_allowed)
			(vias allowed)
			(pads allowed)
			(copperpour not_allowed)
			(footprints allowed)
		)
		(placement
			(enabled no)
			(sheetname "")
		)
		(fill yes
			(thermal_gap 0.5)
			(thermal_bridge_width 0.5)
			(island_removal_mode 0)
		)
		(polygon
			(pts
				(arc
					(start 77.268832 -351.611438)
					(mid 76.565252 -351.611438)
					(end 77.268832 -351.611438)
				)
			)
		)
	)
	(zone
		(layers "B.Cu" "In15.Cu")
		(hatch none 0.5)
		(connect_pads
			(clearance 0)
		)
		(min_thickness 0.25)
		(keepout
			(tracks not_allowed)
			(vias allowed)
			(pads allowed)
			(copperpour not_allowed)
			(footprints allowed)
		)
		(placement
			(enabled no)
			(sheetname "")
		)
		(fill yes
			(thermal_gap 0.5)
			(thermal_bridge_width 0.5)
			(island_removal_mode 0)
		)
		(polygon
			(pts
				(arc
					(start 277.926292 -311.099962)
					(mid 277.273512 -311.099962)
					(end 277.926292 -311.099962)
				)
			)
		)
	)
	(zone
		(layers "B.Cu" "In15.Cu")
		(hatch none 0.5)
		(connect_pads
			(clearance 0)
		)
		(min_thickness 0.25)
		(keepout
			(tracks not_allowed)
			(vias allowed)
			(pads allowed)
			(copperpour not_allowed)
			(footprints allowed)
		)
		(placement
			(enabled no)
			(sheetname "")
		)
		(fill yes
			(thermal_gap 0.5)
			(thermal_bridge_width 0.5)
			(island_removal_mode 0)
		)
		(polygon
			(pts
				(arc
					(start 118.431818 -342.439498)
					(mid 117.728238 -342.439498)
					(end 118.431818 -342.439498)
				)
			)
		)
	)
	(zone
		(layers "B.Cu" "In15.Cu")
		(hatch none 0.5)
		(connect_pads
			(clearance 0)
		)
		(min_thickness 0.25)
		(keepout
			(tracks not_allowed)
			(vias allowed)
			(pads allowed)
			(copperpour not_allowed)
			(footprints allowed)
		)
		(placement
			(enabled no)
			(sheetname "")
		)
		(fill yes
			(thermal_gap 0.5)
			(thermal_bridge_width 0.5)
			(island_removal_mode 0)
		)
		(polygon
			(pts
				(arc
					(start 112.213898 -345.465146)
					(mid 111.510318 -345.465146)
					(end 112.213898 -345.465146)
				)
			)
		)
	)
	(zone
		(layers "B.Cu" "In15.Cu")
		(hatch none 0.5)
		(connect_pads
			(clearance 0)
		)
		(min_thickness 0.25)
		(keepout
			(tracks not_allowed)
			(vias allowed)
			(pads allowed)
			(copperpour not_allowed)
			(footprints allowed)
		)
		(placement
			(enabled no)
			(sheetname "")
		)
		(fill yes
			(thermal_gap 0.5)
			(thermal_bridge_width 0.5)
			(island_removal_mode 0)
		)
		(polygon
			(pts
				(arc
					(start 386.869686 -379.390148)
					(mid 386.110226 -379.390148)
					(end 386.869686 -379.390148)
				)
			)
		)
	)
	(zone
		(layers "B.Cu" "In15.Cu")
		(hatch none 0.5)
		(connect_pads
			(clearance 0)
		)
		(min_thickness 0.25)
		(keepout
			(tracks not_allowed)
			(vias allowed)
			(pads allowed)
			(copperpour not_allowed)
			(footprints allowed)
		)
		(placement
			(enabled no)
			(sheetname "")
		)
		(fill yes
			(thermal_gap 0.5)
			(thermal_bridge_width 0.5)
			(island_removal_mode 0)
		)
		(polygon
			(pts
				(arc
					(start 131.689856 -410.589984)
					(mid 130.930396 -410.589984)
					(end 131.689856 -410.589984)
				)
			)
		)
	)
	(zone
		(layers "B.Cu" "In15.Cu")
		(hatch none 0.5)
		(connect_pads
			(clearance 0)
		)
		(min_thickness 0.25)
		(keepout
			(tracks not_allowed)
			(vias allowed)
			(pads allowed)
			(copperpour not_allowed)
			(footprints allowed)
		)
		(placement
			(enabled no)
			(sheetname "")
		)
		(fill yes
			(thermal_gap 0.5)
			(thermal_bridge_width 0.5)
			(island_removal_mode 0)
		)
		(polygon
			(pts
				(arc
					(start 285.526226 -311.099962)
					(mid 284.873446 -311.099962)
					(end 285.526226 -311.099962)
				)
			)
		)
	)
	(zone
		(layers "B.Cu" "In15.Cu")
		(hatch none 0.5)
		(connect_pads
			(clearance 0)
		)
		(min_thickness 0.25)
		(keepout
			(tracks not_allowed)
			(vias allowed)
			(pads allowed)
			(copperpour not_allowed)
			(footprints allowed)
		)
		(placement
			(enabled no)
			(sheetname "")
		)
		(fill yes
			(thermal_gap 0.5)
			(thermal_bridge_width 0.5)
			(island_removal_mode 0)
		)
		(polygon
			(pts
				(arc
					(start 393.076176 -312.999882)
					(mid 392.423396 -312.999882)
					(end 393.076176 -312.999882)
				)
			)
		)
	)
	(zone
		(layers "B.Cu" "In15.Cu")
		(hatch none 0.5)
		(connect_pads
			(clearance 0)
		)
		(min_thickness 0.25)
		(keepout
			(tracks not_allowed)
			(vias allowed)
			(pads allowed)
			(copperpour not_allowed)
			(footprints allowed)
		)
		(placement
			(enabled no)
			(sheetname "")
		)
		(fill yes
			(thermal_gap 0.5)
			(thermal_bridge_width 0.5)
			(island_removal_mode 0)
		)
		(polygon
			(pts
				(arc
					(start 120.689878 -379.590046)
					(mid 119.930418 -379.590046)
					(end 120.689878 -379.590046)
				)
			)
		)
	)
	(zone
		(layers "B.Cu" "In15.Cu")
		(hatch none 0.5)
		(connect_pads
			(clearance 0)
		)
		(min_thickness 0.25)
		(keepout
			(tracks not_allowed)
			(vias allowed)
			(pads allowed)
			(copperpour not_allowed)
			(footprints allowed)
		)
		(placement
			(enabled no)
			(sheetname "")
		)
		(fill yes
			(thermal_gap 0.5)
			(thermal_bridge_width 0.5)
			(island_removal_mode 0)
		)
		(polygon
			(pts
				(arc
					(start 329.262994 -348.58579)
					(mid 328.559414 -348.58579)
					(end 329.262994 -348.58579)
				)
			)
		)
	)
	(zone
		(layers "B.Cu" "In15.Cu")
		(hatch none 0.5)
		(connect_pads
			(clearance 0)
		)
		(min_thickness 0.25)
		(keepout
			(tracks not_allowed)
			(vias allowed)
			(pads allowed)
			(copperpour not_allowed)
			(footprints allowed)
		)
		(placement
			(enabled no)
			(sheetname "")
		)
		(fill yes
			(thermal_gap 0.5)
			(thermal_bridge_width 0.5)
			(island_removal_mode 0)
		)
		(polygon
			(pts
				(arc
					(start 380.86665 -351.611438)
					(mid 380.16307 -351.611438)
					(end 380.86665 -351.611438)
				)
			)
		)
	)
	(zone
		(layers "B.Cu" "In15.Cu")
		(hatch none 0.5)
		(connect_pads
			(clearance 0)
		)
		(min_thickness 0.25)
		(keepout
			(tracks not_allowed)
			(vias allowed)
			(pads allowed)
			(copperpour not_allowed)
			(footprints allowed)
		)
		(placement
			(enabled no)
			(sheetname "")
		)
		(fill yes
			(thermal_gap 0.5)
			(thermal_bridge_width 0.5)
			(island_removal_mode 0)
		)
		(polygon
			(pts
				(arc
					(start 393.30249 -351.611438)
					(mid 392.59891 -351.611438)
					(end 393.30249 -351.611438)
				)
			)
		)
	)
	(zone
		(layers "B.Cu" "In15.Cu")
		(hatch none 0.5)
		(connect_pads
			(clearance 0)
		)
		(min_thickness 0.25)
		(keepout
			(tracks not_allowed)
			(vias allowed)
			(pads allowed)
			(copperpour not_allowed)
			(footprints allowed)
		)
		(placement
			(enabled no)
			(sheetname "")
		)
		(fill yes
			(thermal_gap 0.5)
			(thermal_bridge_width 0.5)
			(island_removal_mode 0)
		)
		(polygon
			(pts
				(arc
					(start 83.289648 -384.590036)
					(mid 82.530188 -384.590036)
					(end 83.289648 -384.590036)
				)
			)
		)
	)
	(zone
		(layers "B.Cu" "In15.Cu")
		(hatch none 0.5)
		(connect_pads
			(clearance 0)
		)
		(min_thickness 0.25)
		(keepout
			(tracks not_allowed)
			(vias allowed)
			(pads allowed)
			(copperpour not_allowed)
			(footprints allowed)
		)
		(placement
			(enabled no)
			(sheetname "")
		)
		(fill yes
			(thermal_gap 0.5)
			(thermal_bridge_width 0.5)
			(island_removal_mode 0)
		)
		(polygon
			(pts
				(arc
					(start 289.32632 -311.099962)
					(mid 288.67354 -311.099962)
					(end 289.32632 -311.099962)
				)
			)
		)
	)
	(zone
		(layers "B.Cu" "In15.Cu")
		(hatch none 0.5)
		(connect_pads
			(clearance 0)
		)
		(min_thickness 0.25)
		(keepout
			(tracks not_allowed)
			(vias allowed)
			(pads allowed)
			(copperpour not_allowed)
			(footprints allowed)
		)
		(placement
			(enabled no)
			(sheetname "")
		)
		(fill yes
			(thermal_gap 0.5)
			(thermal_bridge_width 0.5)
			(island_removal_mode 0)
		)
		(polygon
			(pts
				(arc
					(start 49.52619 -312.049922)
					(mid 48.87341 -312.049922)
					(end 49.52619 -312.049922)
				)
			)
		)
	)
	(zone
		(layers "B.Cu" "In15.Cu")
		(hatch none 0.5)
		(connect_pads
			(clearance 0)
		)
		(min_thickness 0.25)
		(keepout
			(tracks not_allowed)
			(vias allowed)
			(pads allowed)
			(copperpour not_allowed)
			(footprints allowed)
		)
		(placement
			(enabled no)
			(sheetname "")
		)
		(fill yes
			(thermal_gap 0.5)
			(thermal_bridge_width 0.5)
			(island_removal_mode 0)
		)
		(polygon
			(pts
				(arc
					(start 328.399394 -351.611438)
					(mid 327.695814 -351.611438)
					(end 328.399394 -351.611438)
				)
			)
		)
	)
	(zone
		(layers "B.Cu" "In15.Cu")
		(hatch none 0.5)
		(connect_pads
			(clearance 0)
		)
		(min_thickness 0.25)
		(keepout
			(tracks not_allowed)
			(vias allowed)
			(pads allowed)
			(copperpour not_allowed)
			(footprints allowed)
		)
		(placement
			(enabled no)
			(sheetname "")
		)
		(fill yes
			(thermal_gap 0.5)
			(thermal_bridge_width 0.5)
			(island_removal_mode 0)
		)
		(polygon
			(pts
				(arc
					(start 55.226204 -311.099962)
					(mid 54.573424 -311.099962)
					(end 55.226204 -311.099962)
				)
			)
		)
	)
	(zone
		(layers "B.Cu" "In15.Cu")
		(hatch none 0.5)
		(connect_pads
			(clearance 0)
		)
		(min_thickness 0.25)
		(keepout
			(tracks not_allowed)
			(vias allowed)
			(pads allowed)
			(copperpour not_allowed)
			(footprints allowed)
		)
		(placement
			(enabled no)
			(sheetname "")
		)
		(fill yes
			(thermal_gap 0.5)
			(thermal_bridge_width 0.5)
			(island_removal_mode 0)
		)
		(polygon
			(pts
				(arc
					(start 61.724032 -342.439498)
					(mid 61.020452 -342.439498)
					(end 61.724032 -342.439498)
				)
			)
		)
	)
	(zone
		(layers "B.Cu" "In15.Cu")
		(hatch none 0.5)
		(connect_pads
			(clearance 0)
		)
		(min_thickness 0.25)
		(keepout
			(tracks not_allowed)
			(vias allowed)
			(pads allowed)
			(copperpour not_allowed)
			(footprints allowed)
		)
		(placement
			(enabled no)
			(sheetname "")
		)
		(fill yes
			(thermal_gap 0.5)
			(thermal_bridge_width 0.5)
			(island_removal_mode 0)
		)
		(polygon
			(pts
				(arc
					(start 394.02639 -312.049922)
					(mid 393.37361 -312.049922)
					(end 394.02639 -312.049922)
				)
			)
		)
	)
	(zone
		(layers "B.Cu" "In15.Cu")
		(hatch none 0.5)
		(connect_pads
			(clearance 0)
		)
		(min_thickness 0.25)
		(keepout
			(tracks not_allowed)
			(vias allowed)
			(pads allowed)
			(copperpour not_allowed)
			(footprints allowed)
		)
		(placement
			(enabled no)
			(sheetname "")
		)
		(fill yes
			(thermal_gap 0.5)
			(thermal_bridge_width 0.5)
			(island_removal_mode 0)
		)
		(polygon
			(pts
				(arc
					(start 81.089754 -409.490164)
					(mid 80.330294 -409.490164)
					(end 81.089754 -409.490164)
				)
			)
		)
	)
	(zone
		(layers "B.Cu" "In15.Cu")
		(hatch none 0.5)
		(connect_pads
			(clearance 0)
		)
		(min_thickness 0.25)
		(keepout
			(tracks not_allowed)
			(vias allowed)
			(pads allowed)
			(copperpour not_allowed)
			(footprints allowed)
		)
		(placement
			(enabled no)
			(sheetname "")
		)
		(fill yes
			(thermal_gap 0.5)
			(thermal_bridge_width 0.5)
			(island_removal_mode 0)
		)
		(polygon
			(pts
				(arc
					(start 390.19353 -354.732082)
					(mid 389.48995 -354.732082)
					(end 390.19353 -354.732082)
				)
			)
		)
	)
	(zone
		(layers "B.Cu" "In15.Cu")
		(hatch none 0.5)
		(connect_pads
			(clearance 0)
		)
		(min_thickness 0.25)
		(keepout
			(tracks not_allowed)
			(vias allowed)
			(pads allowed)
			(copperpour not_allowed)
			(footprints allowed)
		)
		(placement
			(enabled no)
			(sheetname "")
		)
		(fill yes
			(thermal_gap 0.5)
			(thermal_bridge_width 0.5)
			(island_removal_mode 0)
		)
		(polygon
			(pts
				(arc
					(start 118.48973 -379.390148)
					(mid 117.73027 -379.390148)
					(end 118.48973 -379.390148)
				)
			)
		)
	)
	(zone
		(layers "B.Cu" "In15.Cu")
		(hatch none 0.5)
		(connect_pads
			(clearance 0)
		)
		(min_thickness 0.25)
		(keepout
			(tracks not_allowed)
			(vias allowed)
			(pads allowed)
			(copperpour not_allowed)
			(footprints allowed)
		)
		(placement
			(enabled no)
			(sheetname "")
		)
		(fill yes
			(thermal_gap 0.5)
			(thermal_bridge_width 0.5)
			(island_removal_mode 0)
		)
		(polygon
			(pts
				(arc
					(start 315.963554 -348.58579)
					(mid 315.259974 -348.58579)
					(end 315.963554 -348.58579)
				)
			)
		)
	)
	(zone
		(layers "B.Cu" "In15.Cu")
		(hatch none 0.5)
		(connect_pads
			(clearance 0)
		)
		(min_thickness 0.25)
		(keepout
			(tracks not_allowed)
			(vias allowed)
			(pads allowed)
			(copperpour not_allowed)
			(footprints allowed)
		)
		(placement
			(enabled no)
			(sheetname "")
		)
		(fill yes
			(thermal_gap 0.5)
			(thermal_bridge_width 0.5)
			(island_removal_mode 0)
		)
		(polygon
			(pts
				(arc
					(start 334.617314 -348.58579)
					(mid 333.913734 -348.58579)
					(end 334.617314 -348.58579)
				)
			)
		)
	)
	(zone
		(layers "B.Cu" "In15.Cu")
		(hatch none 0.5)
		(connect_pads
			(clearance 0)
		)
		(min_thickness 0.25)
		(keepout
			(tracks not_allowed)
			(vias allowed)
			(pads allowed)
			(copperpour not_allowed)
			(footprints allowed)
		)
		(placement
			(enabled no)
			(sheetname "")
		)
		(fill yes
			(thermal_gap 0.5)
			(thermal_bridge_width 0.5)
			(island_removal_mode 0)
		)
		(polygon
			(pts
				(arc
					(start 389.06958 -409.490164)
					(mid 388.31012 -409.490164)
					(end 389.06958 -409.490164)
				)
			)
		)
	)
	(zone
		(layers "B.Cu" "In15.Cu")
		(hatch none 0.5)
		(connect_pads
			(clearance 0)
		)
		(min_thickness 0.25)
		(keepout
			(tracks not_allowed)
			(vias allowed)
			(pads allowed)
			(copperpour not_allowed)
			(footprints allowed)
		)
		(placement
			(enabled no)
			(sheetname "")
		)
		(fill yes
			(thermal_gap 0.5)
			(thermal_bridge_width 0.5)
			(island_removal_mode 0)
		)
		(polygon
			(pts
				(arc
					(start 331.869796 -382.18999)
					(mid 331.110336 -382.18999)
					(end 331.869796 -382.18999)
				)
			)
		)
	)
	(zone
		(layers "B.Cu" "In15.Cu")
		(hatch none 0.5)
		(connect_pads
			(clearance 0)
		)
		(min_thickness 0.25)
		(keepout
			(tracks not_allowed)
			(vias allowed)
			(pads allowed)
			(copperpour not_allowed)
			(footprints allowed)
		)
		(placement
			(enabled no)
			(sheetname "")
		)
		(fill yes
			(thermal_gap 0.5)
			(thermal_bridge_width 0.5)
			(island_removal_mode 0)
		)
		(polygon
			(pts
				(arc
					(start 338.589874 -354.732082)
					(mid 337.886294 -354.732082)
					(end 338.589874 -354.732082)
				)
			)
		)
	)
	(zone
		(layers "B.Cu" "In15.Cu")
		(hatch none 0.5)
		(connect_pads
			(clearance 0)
		)
		(min_thickness 0.25)
		(keepout
			(tracks not_allowed)
			(vias allowed)
			(pads allowed)
			(copperpour not_allowed)
			(footprints allowed)
		)
		(placement
			(enabled no)
			(sheetname "")
		)
		(fill yes
			(thermal_gap 0.5)
			(thermal_bridge_width 0.5)
			(island_removal_mode 0)
		)
		(polygon
			(pts
				(arc
					(start 127.289814 -409.290012)
					(mid 126.530354 -409.290012)
					(end 127.289814 -409.290012)
				)
			)
		)
	)
	(zone
		(layers "B.Cu" "In15.Cu")
		(hatch none 0.5)
		(connect_pads
			(clearance 0)
		)
		(min_thickness 0.25)
		(keepout
			(tracks not_allowed)
			(vias allowed)
			(pads allowed)
			(copperpour not_allowed)
			(footprints allowed)
		)
		(placement
			(enabled no)
			(sheetname "")
		)
		(fill yes
			(thermal_gap 0.5)
			(thermal_bridge_width 0.5)
			(island_removal_mode 0)
		)
		(polygon
			(pts
				(arc
					(start 416.826192 -311.099962)
					(mid 416.173412 -311.099962)
					(end 416.826192 -311.099962)
				)
			)
		)
	)
	(zone
		(layers "B.Cu" "In15.Cu")
		(hatch none 0.5)
		(connect_pads
			(clearance 0)
		)
		(min_thickness 0.25)
		(keepout
			(tracks not_allowed)
			(vias allowed)
			(pads allowed)
			(copperpour not_allowed)
			(footprints allowed)
		)
		(placement
			(enabled no)
			(sheetname "")
		)
		(fill yes
			(thermal_gap 0.5)
			(thermal_bridge_width 0.5)
			(island_removal_mode 0)
		)
		(polygon
			(pts
				(arc
					(start 48.08982 -375.490232)
					(mid 47.33036 -375.490232)
					(end 48.08982 -375.490232)
				)
			)
		)
	)
	(zone
		(layers "B.Cu" "In15.Cu")
		(hatch none 0.5)
		(connect_pads
			(clearance 0)
		)
		(min_thickness 0.25)
		(keepout
			(tracks not_allowed)
			(vias allowed)
			(pads allowed)
			(copperpour not_allowed)
			(footprints allowed)
		)
		(placement
			(enabled no)
			(sheetname "")
		)
		(fill yes
			(thermal_gap 0.5)
			(thermal_bridge_width 0.5)
			(island_removal_mode 0)
		)
		(polygon
			(pts
				(arc
					(start 384.83921 -342.439498)
					(mid 384.13563 -342.439498)
					(end 384.83921 -342.439498)
				)
			)
		)
	)
	(zone
		(layers "B.Cu" "In15.Cu")
		(hatch none 0.5)
		(connect_pads
			(clearance 0)
		)
		(min_thickness 0.25)
		(keepout
			(tracks not_allowed)
			(vias allowed)
			(pads allowed)
			(copperpour not_allowed)
			(footprints allowed)
		)
		(placement
			(enabled no)
			(sheetname "")
		)
		(fill yes
			(thermal_gap 0.5)
			(thermal_bridge_width 0.5)
			(island_removal_mode 0)
		)
		(polygon
			(pts
				(arc
					(start 119.295418 -357.75773)
					(mid 118.591838 -357.75773)
					(end 119.295418 -357.75773)
				)
			)
		)
	)
	(zone
		(layers "B.Cu" "In15.Cu")
		(hatch none 0.5)
		(connect_pads
			(clearance 0)
		)
		(min_thickness 0.25)
		(keepout
			(tracks not_allowed)
			(vias allowed)
			(pads allowed)
			(copperpour not_allowed)
			(footprints allowed)
		)
		(placement
			(enabled no)
			(sheetname "")
		)
		(fill yes
			(thermal_gap 0.5)
			(thermal_bridge_width 0.5)
			(island_removal_mode 0)
		)
		(polygon
			(pts
				(arc
					(start 56.176164 -313.949842)
					(mid 55.523384 -313.949842)
					(end 56.176164 -313.949842)
				)
			)
		)
	)
	(zone
		(layers "B.Cu" "In15.Cu")
		(hatch none 0.5)
		(connect_pads
			(clearance 0)
		)
		(min_thickness 0.25)
		(keepout
			(tracks not_allowed)
			(vias allowed)
			(pads allowed)
			(copperpour not_allowed)
			(footprints allowed)
		)
		(placement
			(enabled no)
			(sheetname "")
		)
		(fill yes
			(thermal_gap 0.5)
			(thermal_bridge_width 0.5)
			(island_removal_mode 0)
		)
		(polygon
			(pts
				(arc
					(start 283.626306 -312.049922)
					(mid 282.973526 -312.049922)
					(end 283.626306 -312.049922)
				)
			)
		)
	)
	(zone
		(layers "B.Cu" "In15.Cu")
		(hatch none 0.5)
		(connect_pads
			(clearance 0)
		)
		(min_thickness 0.25)
		(keepout
			(tracks not_allowed)
			(vias allowed)
			(pads allowed)
			(copperpour not_allowed)
			(footprints allowed)
		)
		(placement
			(enabled no)
			(sheetname "")
		)
		(fill yes
			(thermal_gap 0.5)
			(thermal_bridge_width 0.5)
			(island_removal_mode 0)
		)
		(polygon
			(pts
				(arc
					(start 75.023472 -342.439498)
					(mid 74.319892 -342.439498)
					(end 75.023472 -342.439498)
				)
			)
		)
	)
	(zone
		(layers "B.Cu" "In15.Cu")
		(hatch none 0.5)
		(connect_pads
			(clearance 0)
		)
		(min_thickness 0.25)
		(keepout
			(tracks not_allowed)
			(vias allowed)
			(pads allowed)
			(copperpour not_allowed)
			(footprints allowed)
		)
		(placement
			(enabled no)
			(sheetname "")
		)
		(fill yes
			(thermal_gap 0.5)
			(thermal_bridge_width 0.5)
			(island_removal_mode 0)
		)
		(polygon
			(pts
				(arc
					(start 345.069668 -383.490216)
					(mid 344.310208 -383.490216)
					(end 345.069668 -383.490216)
				)
			)
		)
	)
	(zone
		(layers "B.Cu" "In15.Cu")
		(hatch none 0.5)
		(connect_pads
			(clearance 0)
		)
		(min_thickness 0.25)
		(keepout
			(tracks not_allowed)
			(vias allowed)
			(pads allowed)
			(copperpour not_allowed)
			(footprints allowed)
		)
		(placement
			(enabled no)
			(sheetname "")
		)
		(fill yes
			(thermal_gap 0.5)
			(thermal_bridge_width 0.5)
			(island_removal_mode 0)
		)
		(polygon
			(pts
				(arc
					(start 337.726274 -345.465146)
					(mid 337.022694 -345.465146)
					(end 337.726274 -345.465146)
				)
			)
		)
	)
	(zone
		(layers "B.Cu" "In15.Cu")
		(hatch none 0.5)
		(connect_pads
			(clearance 0)
		)
		(min_thickness 0.25)
		(keepout
			(tracks not_allowed)
			(vias allowed)
			(pads allowed)
			(copperpour not_allowed)
			(footprints allowed)
		)
		(placement
			(enabled no)
			(sheetname "")
		)
		(fill yes
			(thermal_gap 0.5)
			(thermal_bridge_width 0.5)
			(island_removal_mode 0)
		)
		(polygon
			(pts
				(arc
					(start 129.489708 -409.490164)
					(mid 128.730248 -409.490164)
					(end 129.489708 -409.490164)
				)
			)
		)
	)
	(zone
		(layers "B.Cu" "In15.Cu")
		(hatch none 0.5)
		(connect_pads
			(clearance 0)
		)
		(min_thickness 0.25)
		(keepout
			(tracks not_allowed)
			(vias allowed)
			(pads allowed)
			(copperpour not_allowed)
			(footprints allowed)
		)
		(placement
			(enabled no)
			(sheetname "")
		)
		(fill yes
			(thermal_gap 0.5)
			(thermal_bridge_width 0.5)
			(island_removal_mode 0)
		)
		(polygon
			(pts
				(arc
					(start 382.469644 -380.69012)
					(mid 381.710184 -380.69012)
					(end 382.469644 -380.69012)
				)
			)
		)
	)
	(zone
		(layers "B.Cu" "In15.Cu")
		(hatch none 0.5)
		(connect_pads
			(clearance 0)
		)
		(min_thickness 0.25)
		(keepout
			(tracks not_allowed)
			(vias allowed)
			(pads allowed)
			(copperpour not_allowed)
			(footprints allowed)
		)
		(placement
			(enabled no)
			(sheetname "")
		)
		(fill yes
			(thermal_gap 0.5)
			(thermal_bridge_width 0.5)
			(island_removal_mode 0)
		)
		(polygon
			(pts
				(arc
					(start 128.622298 -351.611438)
					(mid 127.918718 -351.611438)
					(end 128.622298 -351.611438)
				)
			)
		)
	)
	(zone
		(layers "B.Cu" "In15.Cu")
		(hatch none 0.5)
		(connect_pads
			(clearance 0)
		)
		(min_thickness 0.25)
		(keepout
			(tracks not_allowed)
			(vias allowed)
			(pads allowed)
			(copperpour not_allowed)
			(footprints allowed)
		)
		(placement
			(enabled no)
			(sheetname "")
		)
		(fill yes
			(thermal_gap 0.5)
			(thermal_bridge_width 0.5)
			(island_removal_mode 0)
		)
		(polygon
			(pts
				(arc
					(start 137.949178 -354.732082)
					(mid 137.245598 -354.732082)
					(end 137.949178 -354.732082)
				)
			)
		)
	)
	(zone
		(layers "B.Cu" "In15.Cu")
		(hatch none 0.5)
		(connect_pads
			(clearance 0)
		)
		(min_thickness 0.25)
		(keepout
			(tracks not_allowed)
			(vias allowed)
			(pads allowed)
			(copperpour not_allowed)
			(footprints allowed)
		)
		(placement
			(enabled no)
			(sheetname "")
		)
		(fill yes
			(thermal_gap 0.5)
			(thermal_bridge_width 0.5)
			(island_removal_mode 0)
		)
		(polygon
			(pts
				(arc
					(start 384.669792 -378.290074)
					(mid 383.910332 -378.290074)
					(end 384.669792 -378.290074)
				)
			)
		)
	)
	(zone
		(layers "B.Cu" "In15.Cu")
		(hatch none 0.5)
		(connect_pads
			(clearance 0)
		)
		(min_thickness 0.25)
		(keepout
			(tracks not_allowed)
			(vias allowed)
			(pads allowed)
			(copperpour not_allowed)
			(footprints allowed)
		)
		(placement
			(enabled no)
			(sheetname "")
		)
		(fill yes
			(thermal_gap 0.5)
			(thermal_bridge_width 0.5)
			(island_removal_mode 0)
		)
		(polygon
			(pts
				(arc
					(start 391.05713 -357.75773)
					(mid 390.35355 -357.75773)
					(end 391.05713 -357.75773)
				)
			)
		)
	)
	(zone
		(layers "B.Cu" "In15.Cu")
		(hatch none 0.5)
		(connect_pads
			(clearance 0)
		)
		(min_thickness 0.25)
		(keepout
			(tracks not_allowed)
			(vias allowed)
			(pads allowed)
			(copperpour not_allowed)
			(footprints allowed)
		)
		(placement
			(enabled no)
			(sheetname "")
		)
		(fill yes
			(thermal_gap 0.5)
			(thermal_bridge_width 0.5)
			(island_removal_mode 0)
		)
		(polygon
			(pts
				(arc
					(start 121.540778 -348.58579)
					(mid 120.837198 -348.58579)
					(end 121.540778 -348.58579)
				)
			)
		)
	)
	(zone
		(layers "B.Cu" "In15.Cu")
		(hatch none 0.5)
		(connect_pads
			(clearance 0)
		)
		(min_thickness 0.25)
		(keepout
			(tracks not_allowed)
			(vias allowed)
			(pads allowed)
			(copperpour not_allowed)
			(footprints allowed)
		)
		(placement
			(enabled no)
			(sheetname "")
		)
		(fill yes
			(thermal_gap 0.5)
			(thermal_bridge_width 0.5)
			(island_removal_mode 0)
		)
		(polygon
			(pts
				(arc
					(start 382.469644 -409.290012)
					(mid 381.710184 -409.290012)
					(end 382.469644 -409.290012)
				)
			)
		)
	)
	(zone
		(layers "B.Cu" "In15.Cu")
		(hatch none 0.5)
		(connect_pads
			(clearance 0)
		)
		(min_thickness 0.25)
		(keepout
			(tracks not_allowed)
			(vias allowed)
			(pads allowed)
			(copperpour not_allowed)
			(footprints allowed)
		)
		(placement
			(enabled no)
			(sheetname "")
		)
		(fill yes
			(thermal_gap 0.5)
			(thermal_bridge_width 0.5)
			(island_removal_mode 0)
		)
		(polygon
			(pts
				(arc
					(start 92.813632 -342.439498)
					(mid 92.110052 -342.439498)
					(end 92.813632 -342.439498)
				)
			)
		)
	)
	(zone
		(layers "B.Cu" "In15.Cu")
		(hatch none 0.5)
		(connect_pads
			(clearance 0)
		)
		(min_thickness 0.25)
		(keepout
			(tracks not_allowed)
			(vias allowed)
			(pads allowed)
			(copperpour not_allowed)
			(footprints allowed)
		)
		(placement
			(enabled no)
			(sheetname "")
		)
		(fill yes
			(thermal_gap 0.5)
			(thermal_bridge_width 0.5)
			(island_removal_mode 0)
		)
		(polygon
			(pts
				(arc
					(start 390.19353 -345.465146)
					(mid 389.48995 -345.465146)
					(end 390.19353 -345.465146)
				)
			)
		)
	)
	(zone
		(layers "B.Cu" "In15.Cu")
		(hatch none 0.5)
		(connect_pads
			(clearance 0)
		)
		(min_thickness 0.25)
		(keepout
			(tracks not_allowed)
			(vias allowed)
			(pads allowed)
			(copperpour not_allowed)
			(footprints allowed)
		)
		(placement
			(enabled no)
			(sheetname "")
		)
		(fill yes
			(thermal_gap 0.5)
			(thermal_bridge_width 0.5)
			(island_removal_mode 0)
		)
		(polygon
			(pts
				(arc
					(start 186.526424 -311.099962)
					(mid 185.873644 -311.099962)
					(end 186.526424 -311.099962)
				)
			)
		)
	)
	(zone
		(layers "B.Cu" "In15.Cu")
		(hatch none 0.5)
		(connect_pads
			(clearance 0)
		)
		(min_thickness 0.25)
		(keepout
			(tracks not_allowed)
			(vias allowed)
			(pads allowed)
			(copperpour not_allowed)
			(footprints allowed)
		)
		(placement
			(enabled no)
			(sheetname "")
		)
		(fill yes
			(thermal_gap 0.5)
			(thermal_bridge_width 0.5)
			(island_removal_mode 0)
		)
		(polygon
			(pts
				(arc
					(start 92.813632 -345.465146)
					(mid 92.110052 -345.465146)
					(end 92.813632 -345.465146)
				)
			)
		)
	)
	(zone
		(layers "B.Cu" "In15.Cu")
		(hatch none 0.5)
		(connect_pads
			(clearance 0)
		)
		(min_thickness 0.25)
		(keepout
			(tracks not_allowed)
			(vias allowed)
			(pads allowed)
			(copperpour not_allowed)
			(footprints allowed)
		)
		(placement
			(enabled no)
			(sheetname "")
		)
		(fill yes
			(thermal_gap 0.5)
			(thermal_bridge_width 0.5)
			(island_removal_mode 0)
		)
		(polygon
			(pts
				(arc
					(start 319.936114 -342.439498)
					(mid 319.232534 -342.439498)
					(end 319.936114 -342.439498)
				)
			)
		)
	)
	(zone
		(layers "B.Cu" "In15.Cu")
		(hatch none 0.5)
		(connect_pads
			(clearance 0)
		)
		(min_thickness 0.25)
		(keepout
			(tracks not_allowed)
			(vias allowed)
			(pads allowed)
			(copperpour not_allowed)
			(footprints allowed)
		)
		(placement
			(enabled no)
			(sheetname "")
		)
		(fill yes
			(thermal_gap 0.5)
			(thermal_bridge_width 0.5)
			(island_removal_mode 0)
		)
		(polygon
			(pts
				(arc
					(start 130.867658 -354.732082)
					(mid 130.164078 -354.732082)
					(end 130.867658 -354.732082)
				)
			)
		)
	)
	(zone
		(layers "B.Cu" "In15.Cu")
		(hatch none 0.5)
		(connect_pads
			(clearance 0)
		)
		(min_thickness 0.25)
		(keepout
			(tracks not_allowed)
			(vias allowed)
			(pads allowed)
			(copperpour not_allowed)
			(footprints allowed)
		)
		(placement
			(enabled no)
			(sheetname "")
		)
		(fill yes
			(thermal_gap 0.5)
			(thermal_bridge_width 0.5)
			(island_removal_mode 0)
		)
		(polygon
			(pts
				(arc
					(start 87.459312 -357.75773)
					(mid 86.755732 -357.75773)
					(end 87.459312 -357.75773)
				)
			)
		)
	)
	(zone
		(layers "B.Cu" "In15.Cu")
		(hatch none 0.5)
		(connect_pads
			(clearance 0)
		)
		(min_thickness 0.25)
		(keepout
			(tracks not_allowed)
			(vias allowed)
			(pads allowed)
			(copperpour not_allowed)
			(footprints allowed)
		)
		(placement
			(enabled no)
			(sheetname "")
		)
		(fill yes
			(thermal_gap 0.5)
			(thermal_bridge_width 0.5)
			(island_removal_mode 0)
		)
		(polygon
			(pts
				(arc
					(start 141.058138 -351.611438)
					(mid 140.354558 -351.611438)
					(end 141.058138 -351.611438)
				)
			)
		)
	)
	(zone
		(layers "B.Cu" "In15.Cu")
		(hatch none 0.5)
		(connect_pads
			(clearance 0)
		)
		(min_thickness 0.25)
		(keepout
			(tracks not_allowed)
			(vias allowed)
			(pads allowed)
			(copperpour not_allowed)
			(footprints allowed)
		)
		(placement
			(enabled no)
			(sheetname "")
		)
		(fill yes
			(thermal_gap 0.5)
			(thermal_bridge_width 0.5)
			(island_removal_mode 0)
		)
		(polygon
			(pts
				(arc
					(start 54.276244 -312.999882)
					(mid 53.623464 -312.999882)
					(end 54.276244 -312.999882)
				)
			)
		)
	)
	(zone
		(layers "B.Cu" "In15.Cu")
		(hatch none 0.5)
		(connect_pads
			(clearance 0)
		)
		(min_thickness 0.25)
		(keepout
			(tracks not_allowed)
			(vias allowed)
			(pads allowed)
			(copperpour not_allowed)
			(footprints allowed)
		)
		(placement
			(enabled no)
			(sheetname "")
		)
		(fill yes
			(thermal_gap 0.5)
			(thermal_bridge_width 0.5)
			(island_removal_mode 0)
		)
		(polygon
			(pts
				(arc
					(start 122.889772 -380.69012)
					(mid 122.130312 -380.69012)
					(end 122.889772 -380.69012)
				)
			)
		)
	)
	(zone
		(layers "B.Cu" "In15.Cu")
		(hatch none 0.5)
		(connect_pads
			(clearance 0)
		)
		(min_thickness 0.25)
		(keepout
			(tracks not_allowed)
			(vias allowed)
			(pads allowed)
			(copperpour not_allowed)
			(footprints allowed)
		)
		(placement
			(enabled no)
			(sheetname "")
		)
		(fill yes
			(thermal_gap 0.5)
			(thermal_bridge_width 0.5)
			(island_removal_mode 0)
		)
		(polygon
			(pts
				(arc
					(start 58.076338 -313.949842)
					(mid 57.423558 -313.949842)
					(end 58.076338 -313.949842)
				)
			)
		)
	)
	(zone
		(layers "B.Cu" "In15.Cu")
		(hatch none 0.5)
		(connect_pads
			(clearance 0)
		)
		(min_thickness 0.25)
		(keepout
			(tracks not_allowed)
			(vias allowed)
			(pads allowed)
			(copperpour not_allowed)
			(footprints allowed)
		)
		(placement
			(enabled no)
			(sheetname "")
		)
		(fill yes
			(thermal_gap 0.5)
			(thermal_bridge_width 0.5)
			(island_removal_mode 0)
		)
		(polygon
			(pts
				(arc
					(start 54.276244 -313.949842)
					(mid 53.623464 -313.949842)
					(end 54.276244 -313.949842)
				)
			)
		)
	)
	(zone
		(layers "B.Cu" "In15.Cu")
		(hatch none 0.5)
		(connect_pads
			(clearance 0)
		)
		(min_thickness 0.25)
		(keepout
			(tracks not_allowed)
			(vias allowed)
			(pads allowed)
			(copperpour not_allowed)
			(footprints allowed)
		)
		(placement
			(enabled no)
			(sheetname "")
		)
		(fill yes
			(thermal_gap 0.5)
			(thermal_bridge_width 0.5)
			(island_removal_mode 0)
		)
		(polygon
			(pts
				(arc
					(start 127.758698 -348.58579)
					(mid 127.055118 -348.58579)
					(end 127.758698 -348.58579)
				)
			)
		)
	)
	(zone
		(layers "B.Cu" "In15.Cu")
		(hatch none 0.5)
		(connect_pads
			(clearance 0)
		)
		(min_thickness 0.25)
		(keepout
			(tracks not_allowed)
			(vias allowed)
			(pads allowed)
			(copperpour not_allowed)
			(footprints allowed)
		)
		(placement
			(enabled no)
			(sheetname "")
		)
		(fill yes
			(thermal_gap 0.5)
			(thermal_bridge_width 0.5)
			(island_removal_mode 0)
		)
		(polygon
			(pts
				(arc
					(start 74.159872 -342.439498)
					(mid 73.456292 -342.439498)
					(end 74.159872 -342.439498)
				)
			)
		)
	)
	(zone
		(layers "B.Cu" "In15.Cu")
		(hatch none 0.5)
		(connect_pads
			(clearance 0)
		)
		(min_thickness 0.25)
		(keepout
			(tracks not_allowed)
			(vias allowed)
			(pads allowed)
			(copperpour not_allowed)
			(footprints allowed)
		)
		(placement
			(enabled no)
			(sheetname "")
		)
		(fill yes
			(thermal_gap 0.5)
			(thermal_bridge_width 0.5)
			(island_removal_mode 0)
		)
		(polygon
			(pts
				(arc
					(start 165.626288 -312.049922)
					(mid 164.973508 -312.049922)
					(end 165.626288 -312.049922)
				)
			)
		)
	)
	(zone
		(layers "B.Cu" "In15.Cu")
		(hatch none 0.5)
		(connect_pads
			(clearance 0)
		)
		(min_thickness 0.25)
		(keepout
			(tracks not_allowed)
			(vias allowed)
			(pads allowed)
			(copperpour not_allowed)
			(footprints allowed)
		)
		(placement
			(enabled no)
			(sheetname "")
		)
		(fill yes
			(thermal_gap 0.5)
			(thermal_bridge_width 0.5)
			(island_removal_mode 0)
		)
		(polygon
			(pts
				(arc
					(start 81.241392 -342.439498)
					(mid 80.537812 -342.439498)
					(end 81.241392 -342.439498)
				)
			)
		)
	)
	(zone
		(layers "B.Cu" "In15.Cu")
		(hatch none 0.5)
		(connect_pads
			(clearance 0)
		)
		(min_thickness 0.25)
		(keepout
			(tracks not_allowed)
			(vias allowed)
			(pads allowed)
			(copperpour not_allowed)
			(footprints allowed)
		)
		(placement
			(enabled no)
			(sheetname "")
		)
		(fill yes
			(thermal_gap 0.5)
			(thermal_bridge_width 0.5)
			(island_removal_mode 0)
		)
		(polygon
			(pts
				(arc
					(start 337.726274 -342.439498)
					(mid 337.022694 -342.439498)
					(end 337.726274 -342.439498)
				)
			)
		)
	)
	(zone
		(layers "B.Cu" "In15.Cu")
		(hatch none 0.5)
		(connect_pads
			(clearance 0)
		)
		(min_thickness 0.25)
		(keepout
			(tracks not_allowed)
			(vias allowed)
			(pads allowed)
			(copperpour not_allowed)
			(footprints allowed)
		)
		(placement
			(enabled no)
			(sheetname "")
		)
		(fill yes
			(thermal_gap 0.5)
			(thermal_bridge_width 0.5)
			(island_removal_mode 0)
		)
		(polygon
			(pts
				(arc
					(start 335.480914 -351.611438)
					(mid 334.777334 -351.611438)
					(end 335.480914 -351.611438)
				)
			)
		)
	)
	(zone
		(layers "B.Cu" "In15.Cu")
		(hatch none 0.5)
		(connect_pads
			(clearance 0)
		)
		(min_thickness 0.25)
		(keepout
			(tracks not_allowed)
			(vias allowed)
			(pads allowed)
			(copperpour not_allowed)
			(footprints allowed)
		)
		(placement
			(enabled no)
			(sheetname "")
		)
		(fill yes
			(thermal_gap 0.5)
			(thermal_bridge_width 0.5)
			(island_removal_mode 0)
		)
		(polygon
			(pts
				(arc
					(start 46.67631 -313.949842)
					(mid 46.02353 -313.949842)
					(end 46.67631 -313.949842)
				)
			)
		)
	)
	(zone
		(layers "B.Cu" "In15.Cu")
		(hatch none 0.5)
		(connect_pads
			(clearance 0)
		)
		(min_thickness 0.25)
		(keepout
			(tracks not_allowed)
			(vias allowed)
			(pads allowed)
			(copperpour not_allowed)
			(footprints allowed)
		)
		(placement
			(enabled no)
			(sheetname "")
		)
		(fill yes
			(thermal_gap 0.5)
			(thermal_bridge_width 0.5)
			(island_removal_mode 0)
		)
		(polygon
			(pts
				(arc
					(start 129.489708 -378.290074)
					(mid 128.730248 -378.290074)
					(end 129.489708 -378.290074)
				)
			)
		)
	)
	(zone
		(layers "B.Cu" "In15.Cu")
		(hatch none 0.5)
		(connect_pads
			(clearance 0)
		)
		(min_thickness 0.25)
		(keepout
			(tracks not_allowed)
			(vias allowed)
			(pads allowed)
			(copperpour not_allowed)
			(footprints allowed)
		)
		(placement
			(enabled no)
			(sheetname "")
		)
		(fill yes
			(thermal_gap 0.5)
			(thermal_bridge_width 0.5)
			(island_removal_mode 0)
		)
		(polygon
			(pts
				(arc
					(start 116.289836 -408.190192)
					(mid 115.530376 -408.190192)
					(end 116.289836 -408.190192)
				)
			)
		)
	)
	(zone
		(layers "B.Cu" "In15.Cu")
		(hatch none 0.5)
		(connect_pads
			(clearance 0)
		)
		(min_thickness 0.25)
		(keepout
			(tracks not_allowed)
			(vias allowed)
			(pads allowed)
			(copperpour not_allowed)
			(footprints allowed)
		)
		(placement
			(enabled no)
			(sheetname "")
		)
		(fill yes
			(thermal_gap 0.5)
			(thermal_bridge_width 0.5)
			(island_removal_mode 0)
		)
		(polygon
			(pts
				(arc
					(start 74.159872 -354.732082)
					(mid 73.456292 -354.732082)
					(end 74.159872 -354.732082)
				)
			)
		)
	)
	(zone
		(layers "B.Cu" "In15.Cu")
		(hatch none 0.5)
		(connect_pads
			(clearance 0)
		)
		(min_thickness 0.25)
		(keepout
			(tracks not_allowed)
			(vias allowed)
			(pads allowed)
			(copperpour not_allowed)
			(footprints allowed)
		)
		(placement
			(enabled no)
			(sheetname "")
		)
		(fill yes
			(thermal_gap 0.5)
			(thermal_bridge_width 0.5)
			(island_removal_mode 0)
		)
		(polygon
			(pts
				(arc
					(start 71.050912 -351.611438)
					(mid 70.347332 -351.611438)
					(end 71.050912 -351.611438)
				)
			)
		)
	)
	(zone
		(layers "B.Cu" "In15.Cu")
		(hatch none 0.5)
		(connect_pads
			(clearance 0)
		)
		(min_thickness 0.25)
		(keepout
			(tracks not_allowed)
			(vias allowed)
			(pads allowed)
			(copperpour not_allowed)
			(footprints allowed)
		)
		(placement
			(enabled no)
			(sheetname "")
		)
		(fill yes
			(thermal_gap 0.5)
			(thermal_bridge_width 0.5)
			(island_removal_mode 0)
		)
		(polygon
			(pts
				(arc
					(start 166.576248 -312.999882)
					(mid 165.923468 -312.999882)
					(end 166.576248 -312.999882)
				)
			)
		)
	)
	(zone
		(layers "B.Cu" "In15.Cu")
		(hatch none 0.5)
		(connect_pads
			(clearance 0)
		)
		(min_thickness 0.25)
		(keepout
			(tracks not_allowed)
			(vias allowed)
			(pads allowed)
			(copperpour not_allowed)
			(footprints allowed)
		)
		(placement
			(enabled no)
			(sheetname "")
		)
		(fill yes
			(thermal_gap 0.5)
			(thermal_bridge_width 0.5)
			(island_removal_mode 0)
		)
		(polygon
			(pts
				(arc
					(start 116.289836 -379.590046)
					(mid 115.530376 -379.590046)
					(end 116.289836 -379.590046)
				)
			)
		)
	)
	(zone
		(layers "B.Cu" "In15.Cu")
		(hatch none 0.5)
		(connect_pads
			(clearance 0)
		)
		(min_thickness 0.25)
		(keepout
			(tracks not_allowed)
			(vias allowed)
			(pads allowed)
			(copperpour not_allowed)
			(footprints allowed)
		)
		(placement
			(enabled no)
			(sheetname "")
		)
		(fill yes
			(thermal_gap 0.5)
			(thermal_bridge_width 0.5)
			(island_removal_mode 0)
		)
		(polygon
			(pts
				(arc
					(start 164.676328 -312.999882)
					(mid 164.023548 -312.999882)
					(end 164.676328 -312.999882)
				)
			)
		)
	)
	(zone
		(layers "B.Cu" "In15.Cu")
		(hatch none 0.5)
		(connect_pads
			(clearance 0)
		)
		(min_thickness 0.25)
		(keepout
			(tracks not_allowed)
			(vias allowed)
			(pads allowed)
			(copperpour not_allowed)
			(footprints allowed)
		)
		(placement
			(enabled no)
			(sheetname "")
		)
		(fill yes
			(thermal_gap 0.5)
			(thermal_bridge_width 0.5)
			(island_removal_mode 0)
		)
		(polygon
			(pts
				(arc
					(start 83.289648 -410.589984)
					(mid 82.530188 -410.589984)
					(end 83.289648 -410.589984)
				)
			)
		)
	)
	(zone
		(layers "B.Cu" "In15.Cu")
		(hatch none 0.5)
		(connect_pads
			(clearance 0)
		)
		(min_thickness 0.25)
		(keepout
			(tracks not_allowed)
			(vias allowed)
			(pads allowed)
			(copperpour not_allowed)
			(footprints allowed)
		)
		(placement
			(enabled no)
			(sheetname "")
		)
		(fill yes
			(thermal_gap 0.5)
			(thermal_bridge_width 0.5)
			(island_removal_mode 0)
		)
		(polygon
			(pts
				(arc
					(start 72.28967 -409.490164)
					(mid 71.53021 -409.490164)
					(end 72.28967 -409.490164)
				)
			)
		)
	)
	(zone
		(layers "B.Cu" "In15.Cu")
		(hatch none 0.5)
		(connect_pads
			(clearance 0)
		)
		(min_thickness 0.25)
		(keepout
			(tracks not_allowed)
			(vias allowed)
			(pads allowed)
			(copperpour not_allowed)
			(footprints allowed)
		)
		(placement
			(enabled no)
			(sheetname "")
		)
		(fill yes
			(thermal_gap 0.5)
			(thermal_bridge_width 0.5)
			(island_removal_mode 0)
		)
		(polygon
			(pts
				(arc
					(start 130.867658 -345.465146)
					(mid 130.164078 -345.465146)
					(end 130.867658 -345.465146)
				)
			)
		)
	)
	(zone
		(layers "B.Cu" "In15.Cu")
		(hatch none 0.5)
		(connect_pads
			(clearance 0)
		)
		(min_thickness 0.25)
		(keepout
			(tracks not_allowed)
			(vias allowed)
			(pads allowed)
			(copperpour not_allowed)
			(footprints allowed)
		)
		(placement
			(enabled no)
			(sheetname "")
		)
		(fill yes
			(thermal_gap 0.5)
			(thermal_bridge_width 0.5)
			(island_removal_mode 0)
		)
		(polygon
			(pts
				(arc
					(start 143.303498 -354.732082)
					(mid 142.599918 -354.732082)
					(end 143.303498 -354.732082)
				)
			)
		)
	)
	(zone
		(layers "B.Cu" "In15.Cu")
		(hatch none 0.5)
		(connect_pads
			(clearance 0)
		)
		(min_thickness 0.25)
		(keepout
			(tracks not_allowed)
			(vias allowed)
			(pads allowed)
			(copperpour not_allowed)
			(footprints allowed)
		)
		(placement
			(enabled no)
			(sheetname "")
		)
		(fill yes
			(thermal_gap 0.5)
			(thermal_bridge_width 0.5)
			(island_removal_mode 0)
		)
		(polygon
			(pts
				(arc
					(start 315.963554 -351.611438)
					(mid 315.259974 -351.611438)
					(end 315.963554 -351.611438)
				)
			)
		)
	)
	(zone
		(layers "B.Cu" "In15.Cu")
		(hatch none 0.5)
		(connect_pads
			(clearance 0)
		)
		(min_thickness 0.25)
		(keepout
			(tracks not_allowed)
			(vias allowed)
			(pads allowed)
			(copperpour not_allowed)
			(footprints allowed)
		)
		(placement
			(enabled no)
			(sheetname "")
		)
		(fill yes
			(thermal_gap 0.5)
			(thermal_bridge_width 0.5)
			(island_removal_mode 0)
		)
		(polygon
			(pts
				(arc
					(start 332.371954 -345.465146)
					(mid 331.668374 -345.465146)
					(end 332.371954 -345.465146)
				)
			)
		)
	)
	(zone
		(layers "B.Cu" "In15.Cu")
		(hatch none 0.5)
		(connect_pads
			(clearance 0)
		)
		(min_thickness 0.25)
		(keepout
			(tracks not_allowed)
			(vias allowed)
			(pads allowed)
			(copperpour not_allowed)
			(footprints allowed)
		)
		(placement
			(enabled no)
			(sheetname "")
		)
		(fill yes
			(thermal_gap 0.5)
			(thermal_bridge_width 0.5)
			(island_removal_mode 0)
		)
		(polygon
			(pts
				(arc
					(start 159.926274 -312.049922)
					(mid 159.273494 -312.049922)
					(end 159.926274 -312.049922)
				)
			)
		)
	)
	(zone
		(layers "B.Cu" "In15.Cu")
		(hatch none 0.5)
		(connect_pads
			(clearance 0)
		)
		(min_thickness 0.25)
		(keepout
			(tracks not_allowed)
			(vias allowed)
			(pads allowed)
			(copperpour not_allowed)
			(footprints allowed)
		)
		(placement
			(enabled no)
			(sheetname "")
		)
		(fill yes
			(thermal_gap 0.5)
			(thermal_bridge_width 0.5)
			(island_removal_mode 0)
		)
		(polygon
			(pts
				(arc
					(start 71.050912 -348.58579)
					(mid 70.347332 -348.58579)
					(end 71.050912 -348.58579)
				)
			)
		)
	)
	(zone
		(layers "B.Cu" "In15.Cu")
		(hatch none 0.5)
		(connect_pads
			(clearance 0)
		)
		(min_thickness 0.25)
		(keepout
			(tracks not_allowed)
			(vias allowed)
			(pads allowed)
			(copperpour not_allowed)
			(footprints allowed)
		)
		(placement
			(enabled no)
			(sheetname "")
		)
		(fill yes
			(thermal_gap 0.5)
			(thermal_bridge_width 0.5)
			(island_removal_mode 0)
		)
		(polygon
			(pts
				(arc
					(start 380.26975 -378.290074)
					(mid 379.51029 -378.290074)
					(end 380.26975 -378.290074)
				)
			)
		)
	)
	(zone
		(layers "B.Cu" "In15.Cu")
		(hatch none 0.5)
		(connect_pads
			(clearance 0)
		)
		(min_thickness 0.25)
		(keepout
			(tracks not_allowed)
			(vias allowed)
			(pads allowed)
			(copperpour not_allowed)
			(footprints allowed)
		)
		(placement
			(enabled no)
			(sheetname "")
		)
		(fill yes
			(thermal_gap 0.5)
			(thermal_bridge_width 0.5)
			(island_removal_mode 0)
		)
		(polygon
			(pts
				(arc
					(start 164.676328 -313.949842)
					(mid 164.023548 -313.949842)
					(end 164.676328 -313.949842)
				)
			)
		)
	)
	(zone
		(layers "B.Cu" "In15.Cu")
		(hatch none 0.5)
		(connect_pads
			(clearance 0)
		)
		(min_thickness 0.25)
		(keepout
			(tracks not_allowed)
			(vias allowed)
			(pads allowed)
			(copperpour not_allowed)
			(footprints allowed)
		)
		(placement
			(enabled no)
			(sheetname "")
		)
		(fill yes
			(thermal_gap 0.5)
			(thermal_bridge_width 0.5)
			(island_removal_mode 0)
		)
		(polygon
			(pts
				(arc
					(start 122.404378 -351.611438)
					(mid 121.700798 -351.611438)
					(end 122.404378 -351.611438)
				)
			)
		)
	)
	(zone
		(layers "B.Cu" "In15.Cu")
		(hatch none 0.5)
		(connect_pads
			(clearance 0)
		)
		(min_thickness 0.25)
		(keepout
			(tracks not_allowed)
			(vias allowed)
			(pads allowed)
			(copperpour not_allowed)
			(footprints allowed)
		)
		(placement
			(enabled no)
			(sheetname "")
		)
		(fill yes
			(thermal_gap 0.5)
			(thermal_bridge_width 0.5)
			(island_removal_mode 0)
		)
		(polygon
			(pts
				(arc
					(start 162.776408 -313.949842)
					(mid 162.123628 -313.949842)
					(end 162.776408 -313.949842)
				)
			)
		)
	)
	(zone
		(layers "B.Cu" "In15.Cu")
		(hatch none 0.5)
		(connect_pads
			(clearance 0)
		)
		(min_thickness 0.25)
		(keepout
			(tracks not_allowed)
			(vias allowed)
			(pads allowed)
			(copperpour not_allowed)
			(footprints allowed)
		)
		(placement
			(enabled no)
			(sheetname "")
		)
		(fill yes
			(thermal_gap 0.5)
			(thermal_bridge_width 0.5)
			(island_removal_mode 0)
		)
		(polygon
			(pts
				(arc
					(start 389.06958 -408.190192)
					(mid 388.31012 -408.190192)
					(end 389.06958 -408.190192)
				)
			)
		)
	)
	(zone
		(layers "B.Cu" "In15.Cu")
		(hatch none 0.5)
		(connect_pads
			(clearance 0)
		)
		(min_thickness 0.25)
		(keepout
			(tracks not_allowed)
			(vias allowed)
			(pads allowed)
			(copperpour not_allowed)
			(footprints allowed)
		)
		(placement
			(enabled no)
			(sheetname "")
		)
		(fill yes
			(thermal_gap 0.5)
			(thermal_bridge_width 0.5)
			(island_removal_mode 0)
		)
		(polygon
			(pts
				(arc
					(start 129.489708 -408.190192)
					(mid 128.730248 -408.190192)
					(end 129.489708 -408.190192)
				)
			)
		)
	)
	(zone
		(layers "B.Cu" "In15.Cu")
		(hatch none 0.5)
		(connect_pads
			(clearance 0)
		)
		(min_thickness 0.25)
		(keepout
			(tracks not_allowed)
			(vias allowed)
			(pads allowed)
			(copperpour not_allowed)
			(footprints allowed)
		)
		(placement
			(enabled no)
			(sheetname "")
		)
		(fill yes
			(thermal_gap 0.5)
			(thermal_bridge_width 0.5)
			(island_removal_mode 0)
		)
		(polygon
			(pts
				(arc
					(start 313.718194 -342.439498)
					(mid 313.014614 -342.439498)
					(end 313.718194 -342.439498)
				)
			)
		)
	)
	(zone
		(layers "B.Cu" "In15.Cu")
		(hatch none 0.5)
		(connect_pads
			(clearance 0)
		)
		(min_thickness 0.25)
		(keepout
			(tracks not_allowed)
			(vias allowed)
			(pads allowed)
			(copperpour not_allowed)
			(footprints allowed)
		)
		(placement
			(enabled no)
			(sheetname "")
		)
		(fill yes
			(thermal_gap 0.5)
			(thermal_bridge_width 0.5)
			(island_removal_mode 0)
		)
		(polygon
			(pts
				(arc
					(start 124.649738 -357.75773)
					(mid 123.946158 -357.75773)
					(end 124.649738 -357.75773)
				)
			)
		)
	)
	(zone
		(layers "B.Cu" "In15.Cu")
		(hatch none 0.5)
		(connect_pads
			(clearance 0)
		)
		(min_thickness 0.25)
		(keepout
			(tracks not_allowed)
			(vias allowed)
			(pads allowed)
			(copperpour not_allowed)
			(footprints allowed)
		)
		(placement
			(enabled no)
			(sheetname "")
		)
		(fill yes
			(thermal_gap 0.5)
			(thermal_bridge_width 0.5)
			(island_removal_mode 0)
		)
		(polygon
			(pts
				(arc
					(start 375.869708 -379.590046)
					(mid 375.110248 -379.590046)
					(end 375.869708 -379.590046)
				)
			)
		)
	)
	(zone
		(layers "B.Cu" "In15.Cu")
		(hatch none 0.5)
		(connect_pads
			(clearance 0)
		)
		(min_thickness 0.25)
		(keepout
			(tracks not_allowed)
			(vias allowed)
			(pads allowed)
			(copperpour not_allowed)
			(footprints allowed)
		)
		(placement
			(enabled no)
			(sheetname "")
		)
		(fill yes
			(thermal_gap 0.5)
			(thermal_bridge_width 0.5)
			(island_removal_mode 0)
		)
		(polygon
			(pts
				(arc
					(start 395.92631 -312.049922)
					(mid 395.27353 -312.049922)
					(end 395.92631 -312.049922)
				)
			)
		)
	)
	(zone
		(layers "B.Cu" "In15.Cu")
		(hatch none 0.5)
		(connect_pads
			(clearance 0)
		)
		(min_thickness 0.25)
		(keepout
			(tracks not_allowed)
			(vias allowed)
			(pads allowed)
			(copperpour not_allowed)
			(footprints allowed)
		)
		(placement
			(enabled no)
			(sheetname "")
		)
		(fill yes
			(thermal_gap 0.5)
			(thermal_bridge_width 0.5)
			(island_removal_mode 0)
		)
		(polygon
			(pts
				(arc
					(start 124.649738 -354.732082)
					(mid 123.946158 -354.732082)
					(end 124.649738 -354.732082)
				)
			)
		)
	)
	(zone
		(layers "B.Cu" "In15.Cu")
		(hatch none 0.5)
		(connect_pads
			(clearance 0)
		)
		(min_thickness 0.25)
		(keepout
			(tracks not_allowed)
			(vias allowed)
			(pads allowed)
			(copperpour not_allowed)
			(footprints allowed)
		)
		(placement
			(enabled no)
			(sheetname "")
		)
		(fill yes
			(thermal_gap 0.5)
			(thermal_bridge_width 0.5)
			(island_removal_mode 0)
		)
		(polygon
			(pts
				(arc
					(start 120.689878 -408.190192)
					(mid 119.930418 -408.190192)
					(end 120.689878 -408.190192)
				)
			)
		)
	)
	(zone
		(layers "B.Cu" "In15.Cu")
		(hatch none 0.5)
		(connect_pads
			(clearance 0)
		)
		(min_thickness 0.25)
		(keepout
			(tracks not_allowed)
			(vias allowed)
			(pads allowed)
			(copperpour not_allowed)
			(footprints allowed)
		)
		(placement
			(enabled no)
			(sheetname "")
		)
		(fill yes
			(thermal_gap 0.5)
			(thermal_bridge_width 0.5)
			(island_removal_mode 0)
		)
		(polygon
			(pts
				(arc
					(start 326.154034 -345.465146)
					(mid 325.450454 -345.465146)
					(end 326.154034 -345.465146)
				)
			)
		)
	)
	(zone
		(layers "B.Cu" "In15.Cu")
		(hatch none 0.5)
		(connect_pads
			(clearance 0)
		)
		(min_thickness 0.25)
		(keepout
			(tracks not_allowed)
			(vias allowed)
			(pads allowed)
			(copperpour not_allowed)
			(footprints allowed)
		)
		(placement
			(enabled no)
			(sheetname "")
		)
		(fill yes
			(thermal_gap 0.5)
			(thermal_bridge_width 0.5)
			(island_removal_mode 0)
		)
		(polygon
			(pts
				(arc
					(start 120.689878 -378.290074)
					(mid 119.930418 -378.290074)
					(end 120.689878 -378.290074)
				)
			)
		)
	)
	(zone
		(layers "B.Cu" "In15.Cu")
		(hatch none 0.5)
		(connect_pads
			(clearance 0)
		)
		(min_thickness 0.25)
		(keepout
			(tracks not_allowed)
			(vias allowed)
			(pads allowed)
			(copperpour not_allowed)
			(footprints allowed)
		)
		(placement
			(enabled no)
			(sheetname "")
		)
		(fill yes
			(thermal_gap 0.5)
			(thermal_bridge_width 0.5)
			(island_removal_mode 0)
		)
		(polygon
			(pts
				(arc
					(start 397.27505 -354.732082)
					(mid 396.57147 -354.732082)
					(end 397.27505 -354.732082)
				)
			)
		)
	)
	(zone
		(layers "B.Cu" "In15.Cu")
		(hatch none 0.5)
		(connect_pads
			(clearance 0)
		)
		(min_thickness 0.25)
		(keepout
			(tracks not_allowed)
			(vias allowed)
			(pads allowed)
			(copperpour not_allowed)
			(footprints allowed)
		)
		(placement
			(enabled no)
			(sheetname "")
		)
		(fill yes
			(thermal_gap 0.5)
			(thermal_bridge_width 0.5)
			(island_removal_mode 0)
		)
		(polygon
			(pts
				(arc
					(start 87.459312 -354.732082)
					(mid 86.755732 -354.732082)
					(end 87.459312 -354.732082)
				)
			)
		)
	)
	(zone
		(layers "B.Cu" "In15.Cu")
		(hatch none 0.5)
		(connect_pads
			(clearance 0)
		)
		(min_thickness 0.25)
		(keepout
			(tracks not_allowed)
			(vias allowed)
			(pads allowed)
			(copperpour not_allowed)
			(footprints allowed)
		)
		(placement
			(enabled no)
			(sheetname "")
		)
		(fill yes
			(thermal_gap 0.5)
			(thermal_bridge_width 0.5)
			(island_removal_mode 0)
		)
		(polygon
			(pts
				(arc
					(start 58.073036 -367.653062)
					(mid 57.369456 -367.653062)
					(end 58.073036 -367.653062)
				)
			)
		)
	)
	(zone
		(layers "B.Cu" "In15.Cu")
		(hatch none 0.5)
		(connect_pads
			(clearance 0)
		)
		(min_thickness 0.25)
		(keepout
			(tracks not_allowed)
			(vias allowed)
			(pads allowed)
			(copperpour not_allowed)
			(footprints allowed)
		)
		(placement
			(enabled no)
			(sheetname "")
		)
		(fill yes
			(thermal_gap 0.5)
			(thermal_bridge_width 0.5)
			(island_removal_mode 0)
		)
		(polygon
			(pts
				(arc
					(start 67.941952 -345.465146)
					(mid 67.238372 -345.465146)
					(end 67.941952 -345.465146)
				)
			)
		)
	)
	(zone
		(layers "B.Cu" "In15.Cu")
		(hatch none 0.5)
		(connect_pads
			(clearance 0)
		)
		(min_thickness 0.25)
		(keepout
			(tracks not_allowed)
			(vias allowed)
			(pads allowed)
			(copperpour not_allowed)
			(footprints allowed)
		)
		(placement
			(enabled no)
			(sheetname "")
		)
		(fill yes
			(thermal_gap 0.5)
			(thermal_bridge_width 0.5)
			(island_removal_mode 0)
		)
		(polygon
			(pts
				(arc
					(start 331.869796 -409.490164)
					(mid 331.110336 -409.490164)
					(end 331.869796 -409.490164)
				)
			)
		)
	)
	(zone
		(layers "B.Cu" "In15.Cu")
		(hatch none 0.5)
		(connect_pads
			(clearance 0)
		)
		(min_thickness 0.25)
		(keepout
			(tracks not_allowed)
			(vias allowed)
			(pads allowed)
			(copperpour not_allowed)
			(footprints allowed)
		)
		(placement
			(enabled no)
			(sheetname "")
		)
		(fill yes
			(thermal_gap 0.5)
			(thermal_bridge_width 0.5)
			(island_removal_mode 0)
		)
		(polygon
			(pts
				(arc
					(start 161.826448 -311.099962)
					(mid 161.173668 -311.099962)
					(end 161.826448 -311.099962)
				)
			)
		)
	)
	(zone
		(layers "B.Cu" "In15.Cu")
		(hatch none 0.5)
		(connect_pads
			(clearance 0)
		)
		(min_thickness 0.25)
		(keepout
			(tracks not_allowed)
			(vias allowed)
			(pads allowed)
			(copperpour not_allowed)
			(footprints allowed)
		)
		(placement
			(enabled no)
			(sheetname "")
		)
		(fill yes
			(thermal_gap 0.5)
			(thermal_bridge_width 0.5)
			(island_removal_mode 0)
		)
		(polygon
			(pts
				(arc
					(start 118.48973 -409.290012)
					(mid 117.73027 -409.290012)
					(end 118.48973 -409.290012)
				)
			)
		)
	)
	(zone
		(layers "B.Cu" "In15.Cu")
		(hatch none 0.5)
		(connect_pads
			(clearance 0)
		)
		(min_thickness 0.25)
		(keepout
			(tracks not_allowed)
			(vias allowed)
			(pads allowed)
			(copperpour not_allowed)
			(footprints allowed)
		)
		(placement
			(enabled no)
			(sheetname "")
		)
		(fill yes
			(thermal_gap 0.5)
			(thermal_bridge_width 0.5)
			(island_removal_mode 0)
		)
		(polygon
			(pts
				(arc
					(start 418.726366 -311.099962)
					(mid 418.073586 -311.099962)
					(end 418.726366 -311.099962)
				)
			)
		)
	)
	(zone
		(layers "B.Cu" "In15.Cu")
		(hatch none 0.5)
		(connect_pads
			(clearance 0)
		)
		(min_thickness 0.25)
		(keepout
			(tracks not_allowed)
			(vias allowed)
			(pads allowed)
			(copperpour not_allowed)
			(footprints allowed)
		)
		(placement
			(enabled no)
			(sheetname "")
		)
		(fill yes
			(thermal_gap 0.5)
			(thermal_bridge_width 0.5)
			(island_removal_mode 0)
		)
		(polygon
			(pts
				(arc
					(start 86.595712 -342.439498)
					(mid 85.892132 -342.439498)
					(end 86.595712 -342.439498)
				)
			)
		)
	)
	(zone
		(layers "B.Cu" "In15.Cu")
		(hatch none 0.5)
		(connect_pads
			(clearance 0)
		)
		(min_thickness 0.25)
		(keepout
			(tracks not_allowed)
			(vias allowed)
			(pads allowed)
			(copperpour not_allowed)
			(footprints allowed)
		)
		(placement
			(enabled no)
			(sheetname "")
		)
		(fill yes
			(thermal_gap 0.5)
			(thermal_bridge_width 0.5)
			(island_removal_mode 0)
		)
		(polygon
			(pts
				(arc
					(start 125.08992 -378.290074)
					(mid 124.33046 -378.290074)
					(end 125.08992 -378.290074)
				)
			)
		)
	)
	(zone
		(layers "B.Cu" "In15.Cu")
		(hatch none 0.5)
		(connect_pads
			(clearance 0)
		)
		(min_thickness 0.25)
		(keepout
			(tracks not_allowed)
			(vias allowed)
			(pads allowed)
			(copperpour not_allowed)
			(footprints allowed)
		)
		(placement
			(enabled no)
			(sheetname "")
		)
		(fill yes
			(thermal_gap 0.5)
			(thermal_bridge_width 0.5)
			(island_removal_mode 0)
		)
		(polygon
			(pts
				(arc
					(start 115.322858 -351.611438)
					(mid 114.619278 -351.611438)
					(end 115.322858 -351.611438)
				)
			)
		)
	)
	(zone
		(layers "B.Cu" "In15.Cu")
		(hatch none 0.5)
		(connect_pads
			(clearance 0)
		)
		(min_thickness 0.25)
		(keepout
			(tracks not_allowed)
			(vias allowed)
			(pads allowed)
			(copperpour not_allowed)
			(footprints allowed)
		)
		(placement
			(enabled no)
			(sheetname "")
		)
		(fill yes
			(thermal_gap 0.5)
			(thermal_bridge_width 0.5)
			(island_removal_mode 0)
		)
		(polygon
			(pts
				(arc
					(start 72.28967 -383.490216)
					(mid 71.53021 -383.490216)
					(end 72.28967 -383.490216)
				)
			)
		)
	)
	(zone
		(layers "B.Cu" "In15.Cu")
		(hatch none 0.5)
		(connect_pads
			(clearance 0)
		)
		(min_thickness 0.25)
		(keepout
			(tracks not_allowed)
			(vias allowed)
			(pads allowed)
			(copperpour not_allowed)
			(footprints allowed)
		)
		(placement
			(enabled no)
			(sheetname "")
		)
		(fill yes
			(thermal_gap 0.5)
			(thermal_bridge_width 0.5)
			(island_removal_mode 0)
		)
		(polygon
			(pts
				(arc
					(start 84.350352 -351.611438)
					(mid 83.646772 -351.611438)
					(end 84.350352 -351.611438)
				)
			)
		)
	)
	(zone
		(layers "B.Cu" "In15.Cu")
		(hatch none 0.5)
		(connect_pads
			(clearance 0)
		)
		(min_thickness 0.25)
		(keepout
			(tracks not_allowed)
			(vias allowed)
			(pads allowed)
			(copperpour not_allowed)
			(footprints allowed)
		)
		(placement
			(enabled no)
			(sheetname "")
		)
		(fill yes
			(thermal_gap 0.5)
			(thermal_bridge_width 0.5)
			(island_removal_mode 0)
		)
		(polygon
			(pts
				(arc
					(start 281.726132 -312.049922)
					(mid 281.073352 -312.049922)
					(end 281.726132 -312.049922)
				)
			)
		)
	)
	(zone
		(layers "B.Cu" "In15.Cu")
		(hatch none 0.5)
		(connect_pads
			(clearance 0)
		)
		(min_thickness 0.25)
		(keepout
			(tracks not_allowed)
			(vias allowed)
			(pads allowed)
			(copperpour not_allowed)
			(footprints allowed)
		)
		(placement
			(enabled no)
			(sheetname "")
		)
		(fill yes
			(thermal_gap 0.5)
			(thermal_bridge_width 0.5)
			(island_removal_mode 0)
		)
		(polygon
			(pts
				(arc
					(start 144.167098 -342.439498)
					(mid 143.463518 -342.439498)
					(end 144.167098 -342.439498)
				)
			)
		)
	)
	(zone
		(layers "B.Cu" "In15.Cu")
		(hatch none 0.5)
		(connect_pads
			(clearance 0)
		)
		(min_thickness 0.25)
		(keepout
			(tracks not_allowed)
			(vias allowed)
			(pads allowed)
			(copperpour not_allowed)
			(footprints allowed)
		)
		(placement
			(enabled no)
			(sheetname "")
		)
		(fill yes
			(thermal_gap 0.5)
			(thermal_bridge_width 0.5)
			(island_removal_mode 0)
		)
		(polygon
			(pts
				(arc
					(start 345.069668 -382.18999)
					(mid 344.310208 -382.18999)
					(end 345.069668 -382.18999)
				)
			)
		)
	)
	(zone
		(layers "B.Cu" "In15.Cu")
		(hatch none 0.5)
		(connect_pads
			(clearance 0)
		)
		(min_thickness 0.25)
		(keepout
			(tracks not_allowed)
			(vias allowed)
			(pads allowed)
			(copperpour not_allowed)
			(footprints allowed)
		)
		(placement
			(enabled no)
			(sheetname "")
		)
		(fill yes
			(thermal_gap 0.5)
			(thermal_bridge_width 0.5)
			(island_removal_mode 0)
		)
		(polygon
			(pts
				(arc
					(start 319.936114 -345.465146)
					(mid 319.232534 -345.465146)
					(end 319.936114 -345.465146)
				)
			)
		)
	)
	(zone
		(layers "B.Cu" "In15.Cu")
		(hatch none 0.5)
		(connect_pads
			(clearance 0)
		)
		(min_thickness 0.25)
		(keepout
			(tracks not_allowed)
			(vias allowed)
			(pads allowed)
			(copperpour not_allowed)
			(footprints allowed)
		)
		(placement
			(enabled no)
			(sheetname "")
		)
		(fill yes
			(thermal_gap 0.5)
			(thermal_bridge_width 0.5)
			(island_removal_mode 0)
		)
		(polygon
			(pts
				(arc
					(start 92.813632 -354.732082)
					(mid 92.110052 -354.732082)
					(end 92.813632 -354.732082)
				)
			)
		)
	)
	(zone
		(layers "B.Cu" "In15.Cu")
		(hatch none 0.5)
		(connect_pads
			(clearance 0)
		)
		(min_thickness 0.25)
		(keepout
			(tracks not_allowed)
			(vias allowed)
			(pads allowed)
			(copperpour not_allowed)
			(footprints allowed)
		)
		(placement
			(enabled no)
			(sheetname "")
		)
		(fill yes
			(thermal_gap 0.5)
			(thermal_bridge_width 0.5)
			(island_removal_mode 0)
		)
		(polygon
			(pts
				(arc
					(start 83.289648 -409.290012)
					(mid 82.530188 -409.290012)
					(end 83.289648 -409.290012)
				)
			)
		)
	)
	(zone
		(layers "B.Cu" "In15.Cu")
		(hatch none 0.5)
		(connect_pads
			(clearance 0)
		)
		(min_thickness 0.25)
		(keepout
			(tracks not_allowed)
			(vias allowed)
			(pads allowed)
			(copperpour not_allowed)
			(footprints allowed)
		)
		(placement
			(enabled no)
			(sheetname "")
		)
		(fill yes
			(thermal_gap 0.5)
			(thermal_bridge_width 0.5)
			(island_removal_mode 0)
		)
		(polygon
			(pts
				(arc
					(start 64.832992 -351.611438)
					(mid 64.129412 -351.611438)
					(end 64.832992 -351.611438)
				)
			)
		)
	)
	(zone
		(layers "B.Cu" "In15.Cu")
		(hatch none 0.5)
		(connect_pads
			(clearance 0)
		)
		(min_thickness 0.25)
		(keepout
			(tracks not_allowed)
			(vias allowed)
			(pads allowed)
			(copperpour not_allowed)
			(footprints allowed)
		)
		(placement
			(enabled no)
			(sheetname "")
		)
		(fill yes
			(thermal_gap 0.5)
			(thermal_bridge_width 0.5)
			(island_removal_mode 0)
		)
		(polygon
			(pts
				(arc
					(start 392.126216 -311.099962)
					(mid 391.473436 -311.099962)
					(end 392.126216 -311.099962)
				)
			)
		)
	)
	(zone
		(layers "B.Cu" "In15.Cu")
		(hatch none 0.5)
		(connect_pads
			(clearance 0)
		)
		(min_thickness 0.25)
		(keepout
			(tracks not_allowed)
			(vias allowed)
			(pads allowed)
			(copperpour not_allowed)
			(footprints allowed)
		)
		(placement
			(enabled no)
			(sheetname "")
		)
		(fill yes
			(thermal_gap 0.5)
			(thermal_bridge_width 0.5)
			(island_removal_mode 0)
		)
		(polygon
			(pts
				(arc
					(start 56.176164 -312.999882)
					(mid 55.523384 -312.999882)
					(end 56.176164 -312.999882)
				)
			)
		)
	)
	(zone
		(layers "B.Cu" "In15.Cu")
		(hatch none 0.5)
		(connect_pads
			(clearance 0)
		)
		(min_thickness 0.25)
		(keepout
			(tracks not_allowed)
			(vias allowed)
			(pads allowed)
			(copperpour not_allowed)
			(footprints allowed)
		)
		(placement
			(enabled no)
			(sheetname "")
		)
		(fill yes
			(thermal_gap 0.5)
			(thermal_bridge_width 0.5)
			(island_removal_mode 0)
		)
		(polygon
			(pts
				(arc
					(start 377.75769 -354.732082)
					(mid 377.05411 -354.732082)
					(end 377.75769 -354.732082)
				)
			)
		)
	)
	(zone
		(layers "B.Cu" "In15.Cu")
		(hatch none 0.5)
		(connect_pads
			(clearance 0)
		)
		(min_thickness 0.25)
		(keepout
			(tracks not_allowed)
			(vias allowed)
			(pads allowed)
			(copperpour not_allowed)
			(footprints allowed)
		)
		(placement
			(enabled no)
			(sheetname "")
		)
		(fill yes
			(thermal_gap 0.5)
			(thermal_bridge_width 0.5)
			(island_removal_mode 0)
		)
		(polygon
			(pts
				(arc
					(start 344.807794 -357.75773)
					(mid 344.104214 -357.75773)
					(end 344.807794 -357.75773)
				)
			)
		)
	)
	(zone
		(layers "B.Cu" "In15.Cu")
		(hatch none 0.5)
		(connect_pads
			(clearance 0)
		)
		(min_thickness 0.25)
		(keepout
			(tracks not_allowed)
			(vias allowed)
			(pads allowed)
			(copperpour not_allowed)
			(footprints allowed)
		)
		(placement
			(enabled no)
			(sheetname "")
		)
		(fill yes
			(thermal_gap 0.5)
			(thermal_bridge_width 0.5)
			(island_removal_mode 0)
		)
		(polygon
			(pts
				(arc
					(start 338.589874 -357.75773)
					(mid 337.886294 -357.75773)
					(end 338.589874 -357.75773)
				)
			)
		)
	)
	(zone
		(layers "B.Cu" "In15.Cu")
		(hatch none 0.5)
		(connect_pads
			(clearance 0)
		)
		(min_thickness 0.25)
		(keepout
			(tracks not_allowed)
			(vias allowed)
			(pads allowed)
			(copperpour not_allowed)
			(footprints allowed)
		)
		(placement
			(enabled no)
			(sheetname "")
		)
		(fill yes
			(thermal_gap 0.5)
			(thermal_bridge_width 0.5)
			(island_removal_mode 0)
		)
		(polygon
			(pts
				(arc
					(start 76.689712 -382.18999)
					(mid 75.930252 -382.18999)
					(end 76.689712 -382.18999)
				)
			)
		)
	)
	(zone
		(layers "B.Cu" "In15.Cu")
		(hatch none 0.5)
		(connect_pads
			(clearance 0)
		)
		(min_thickness 0.25)
		(keepout
			(tracks not_allowed)
			(vias allowed)
			(pads allowed)
			(copperpour not_allowed)
			(footprints allowed)
		)
		(placement
			(enabled no)
			(sheetname "")
		)
		(fill yes
			(thermal_gap 0.5)
			(thermal_bridge_width 0.5)
			(island_removal_mode 0)
		)
		(polygon
			(pts
				(arc
					(start 163.726368 -312.049922)
					(mid 163.073588 -312.049922)
					(end 163.726368 -312.049922)
				)
			)
		)
	)
	(zone
		(layers "B.Cu" "In15.Cu")
		(hatch none 0.5)
		(connect_pads
			(clearance 0)
		)
		(min_thickness 0.25)
		(keepout
			(tracks not_allowed)
			(vias allowed)
			(pads allowed)
			(copperpour not_allowed)
			(footprints allowed)
		)
		(placement
			(enabled no)
			(sheetname "")
		)
		(fill yes
			(thermal_gap 0.5)
			(thermal_bridge_width 0.5)
			(island_removal_mode 0)
		)
		(polygon
			(pts
				(arc
					(start 129.489708 -379.590046)
					(mid 128.730248 -379.590046)
					(end 129.489708 -379.590046)
				)
			)
		)
	)
	(zone
		(layers "B.Cu" "In15.Cu")
		(hatch none 0.5)
		(connect_pads
			(clearance 0)
		)
		(min_thickness 0.25)
		(keepout
			(tracks not_allowed)
			(vias allowed)
			(pads allowed)
			(copperpour not_allowed)
			(footprints allowed)
		)
		(placement
			(enabled no)
			(sheetname "")
		)
		(fill yes
			(thermal_gap 0.5)
			(thermal_bridge_width 0.5)
			(island_removal_mode 0)
		)
		(polygon
			(pts
				(arc
					(start 421.576246 -312.999882)
					(mid 420.923466 -312.999882)
					(end 421.576246 -312.999882)
				)
			)
		)
	)
	(zone
		(layers "B.Cu" "In15.Cu")
		(hatch none 0.5)
		(connect_pads
			(clearance 0)
		)
		(min_thickness 0.25)
		(keepout
			(tracks not_allowed)
			(vias allowed)
			(pads allowed)
			(copperpour not_allowed)
			(footprints allowed)
		)
		(placement
			(enabled no)
			(sheetname "")
		)
		(fill yes
			(thermal_gap 0.5)
			(thermal_bridge_width 0.5)
			(island_removal_mode 0)
		)
		(polygon
			(pts
				(arc
					(start 343.944194 -345.465146)
					(mid 343.240614 -345.465146)
					(end 343.944194 -345.465146)
				)
			)
		)
	)
	(zone
		(layers "B.Cu" "In15.Cu")
		(hatch none 0.5)
		(connect_pads
			(clearance 0)
		)
		(min_thickness 0.25)
		(keepout
			(tracks not_allowed)
			(vias allowed)
			(pads allowed)
			(copperpour not_allowed)
			(footprints allowed)
		)
		(placement
			(enabled no)
			(sheetname "")
		)
		(fill yes
			(thermal_gap 0.5)
			(thermal_bridge_width 0.5)
			(island_removal_mode 0)
		)
		(polygon
			(pts
				(arc
					(start 80.377792 -342.439498)
					(mid 79.674212 -342.439498)
					(end 80.377792 -342.439498)
				)
			)
		)
	)
	(zone
		(layers "B.Cu" "In15.Cu")
		(hatch none 0.5)
		(connect_pads
			(clearance 0)
		)
		(min_thickness 0.25)
		(keepout
			(tracks not_allowed)
			(vias allowed)
			(pads allowed)
			(copperpour not_allowed)
			(footprints allowed)
		)
		(placement
			(enabled no)
			(sheetname "")
		)
		(fill yes
			(thermal_gap 0.5)
			(thermal_bridge_width 0.5)
			(island_removal_mode 0)
		)
		(polygon
			(pts
				(arc
					(start 325.290434 -357.75773)
					(mid 324.586854 -357.75773)
					(end 325.290434 -357.75773)
				)
			)
		)
	)
	(zone
		(layers "B.Cu" "In15.Cu")
		(hatch none 0.5)
		(connect_pads
			(clearance 0)
		)
		(min_thickness 0.25)
		(keepout
			(tracks not_allowed)
			(vias allowed)
			(pads allowed)
			(copperpour not_allowed)
			(footprints allowed)
		)
		(placement
			(enabled no)
			(sheetname "")
		)
		(fill yes
			(thermal_gap 0.5)
			(thermal_bridge_width 0.5)
			(island_removal_mode 0)
		)
		(polygon
			(pts
				(arc
					(start 131.731258 -342.439498)
					(mid 131.027678 -342.439498)
					(end 131.731258 -342.439498)
				)
			)
		)
	)
	(zone
		(layers "B.Cu" "In15.Cu")
		(hatch none 0.5)
		(connect_pads
			(clearance 0)
		)
		(min_thickness 0.25)
		(keepout
			(tracks not_allowed)
			(vias allowed)
			(pads allowed)
			(copperpour not_allowed)
			(footprints allowed)
		)
		(placement
			(enabled no)
			(sheetname "")
		)
		(fill yes
			(thermal_gap 0.5)
			(thermal_bridge_width 0.5)
			(island_removal_mode 0)
		)
		(polygon
			(pts
				(arc
					(start 85.489542 -382.18999)
					(mid 84.730082 -382.18999)
					(end 85.489542 -382.18999)
				)
			)
		)
	)
	(zone
		(layers "B.Cu" "In15.Cu")
		(hatch none 0.5)
		(connect_pads
			(clearance 0)
		)
		(min_thickness 0.25)
		(keepout
			(tracks not_allowed)
			(vias allowed)
			(pads allowed)
			(copperpour not_allowed)
			(footprints allowed)
		)
		(placement
			(enabled no)
			(sheetname "")
		)
		(fill yes
			(thermal_gap 0.5)
			(thermal_bridge_width 0.5)
			(island_removal_mode 0)
		)
		(polygon
			(pts
				(arc
					(start 397.27505 -342.439498)
					(mid 396.57147 -342.439498)
					(end 397.27505 -342.439498)
				)
			)
		)
	)
	(zone
		(layers "B.Cu" "In15.Cu")
		(hatch none 0.5)
		(connect_pads
			(clearance 0)
		)
		(min_thickness 0.25)
		(keepout
			(tracks not_allowed)
			(vias allowed)
			(pads allowed)
			(copperpour not_allowed)
			(footprints allowed)
		)
		(placement
			(enabled no)
			(sheetname "")
		)
		(fill yes
			(thermal_gap 0.5)
			(thermal_bridge_width 0.5)
			(island_removal_mode 0)
		)
		(polygon
			(pts
				(arc
					(start 131.731258 -345.465146)
					(mid 131.027678 -345.465146)
					(end 131.731258 -345.465146)
				)
			)
		)
	)
	(zone
		(layers "B.Cu" "In15.Cu")
		(hatch none 0.5)
		(connect_pads
			(clearance 0)
		)
		(min_thickness 0.25)
		(keepout
			(tracks not_allowed)
			(vias allowed)
			(pads allowed)
			(copperpour not_allowed)
			(footprints allowed)
		)
		(placement
			(enabled no)
			(sheetname "")
		)
		(fill yes
			(thermal_gap 0.5)
			(thermal_bridge_width 0.5)
			(island_removal_mode 0)
		)
		(polygon
			(pts
				(arc
					(start 402.62937 -345.465146)
					(mid 401.92579 -345.465146)
					(end 402.62937 -345.465146)
				)
			)
		)
	)
	(zone
		(layers "B.Cu" "In15.Cu")
		(hatch none 0.5)
		(connect_pads
			(clearance 0)
		)
		(min_thickness 0.25)
		(keepout
			(tracks not_allowed)
			(vias allowed)
			(pads allowed)
			(copperpour not_allowed)
			(footprints allowed)
		)
		(placement
			(enabled no)
			(sheetname "")
		)
		(fill yes
			(thermal_gap 0.5)
			(thermal_bridge_width 0.5)
			(island_removal_mode 0)
		)
		(polygon
			(pts
				(arc
					(start 290.27628 -313.949842)
					(mid 289.6235 -313.949842)
					(end 290.27628 -313.949842)
				)
			)
		)
	)
	(zone
		(layers "B.Cu" "In15.Cu")
		(hatch none 0.5)
		(connect_pads
			(clearance 0)
		)
		(min_thickness 0.25)
		(keepout
			(tracks not_allowed)
			(vias allowed)
			(pads allowed)
			(copperpour not_allowed)
			(footprints allowed)
		)
		(placement
			(enabled no)
			(sheetname "")
		)
		(fill yes
			(thermal_gap 0.5)
			(thermal_bridge_width 0.5)
			(island_removal_mode 0)
		)
		(polygon
			(pts
				(arc
					(start 279.826212 -312.049922)
					(mid 279.173432 -312.049922)
					(end 279.826212 -312.049922)
				)
			)
		)
	)
	(zone
		(layers "B.Cu" "In15.Cu")
		(hatch none 0.5)
		(connect_pads
			(clearance 0)
		)
		(min_thickness 0.25)
		(keepout
			(tracks not_allowed)
			(vias allowed)
			(pads allowed)
			(copperpour not_allowed)
			(footprints allowed)
		)
		(placement
			(enabled no)
			(sheetname "")
		)
		(fill yes
			(thermal_gap 0.5)
			(thermal_bridge_width 0.5)
			(island_removal_mode 0)
		)
		(polygon
			(pts
				(arc
					(start 93.677232 -342.439498)
					(mid 92.973652 -342.439498)
					(end 93.677232 -342.439498)
				)
			)
		)
	)
	(zone
		(layers "B.Cu" "In15.Cu")
		(hatch none 0.5)
		(connect_pads
			(clearance 0)
		)
		(min_thickness 0.25)
		(keepout
			(tracks not_allowed)
			(vias allowed)
			(pads allowed)
			(copperpour not_allowed)
			(footprints allowed)
		)
		(placement
			(enabled no)
			(sheetname "")
		)
		(fill yes
			(thermal_gap 0.5)
			(thermal_bridge_width 0.5)
			(island_removal_mode 0)
		)
		(polygon
			(pts
				(arc
					(start 130.867658 -357.75773)
					(mid 130.164078 -357.75773)
					(end 130.867658 -357.75773)
				)
			)
		)
	)
	(zone
		(layers "B.Cu" "In15.Cu")
		(hatch none 0.5)
		(connect_pads
			(clearance 0)
		)
		(min_thickness 0.25)
		(keepout
			(tracks not_allowed)
			(vias allowed)
			(pads allowed)
			(copperpour not_allowed)
			(footprints allowed)
		)
		(placement
			(enabled no)
			(sheetname "")
		)
		(fill yes
			(thermal_gap 0.5)
			(thermal_bridge_width 0.5)
			(island_removal_mode 0)
		)
		(polygon
			(pts
				(arc
					(start 313.718194 -345.465146)
					(mid 313.014614 -345.465146)
					(end 313.718194 -345.465146)
				)
			)
		)
	)
	(zone
		(layers "B.Cu" "In15.Cu")
		(hatch none 0.5)
		(connect_pads
			(clearance 0)
		)
		(min_thickness 0.25)
		(keepout
			(tracks not_allowed)
			(vias allowed)
			(pads allowed)
			(copperpour not_allowed)
			(footprints allowed)
		)
		(placement
			(enabled no)
			(sheetname "")
		)
		(fill yes
			(thermal_gap 0.5)
			(thermal_bridge_width 0.5)
			(island_removal_mode 0)
		)
		(polygon
			(pts
				(arc
					(start 336.269838 -408.190192)
					(mid 335.510378 -408.190192)
					(end 336.269838 -408.190192)
				)
			)
		)
	)
	(zone
		(layers "B.Cu" "In15.Cu")
		(hatch none 0.5)
		(connect_pads
			(clearance 0)
		)
		(min_thickness 0.25)
		(keepout
			(tracks not_allowed)
			(vias allowed)
			(pads allowed)
			(copperpour not_allowed)
			(footprints allowed)
		)
		(placement
			(enabled no)
			(sheetname "")
		)
		(fill yes
			(thermal_gap 0.5)
			(thermal_bridge_width 0.5)
			(island_removal_mode 0)
		)
		(polygon
			(pts
				(arc
					(start 331.508354 -342.439498)
					(mid 330.804774 -342.439498)
					(end 331.508354 -342.439498)
				)
			)
		)
	)
	(zone
		(layers "B.Cu" "In15.Cu")
		(hatch none 0.5)
		(connect_pads
			(clearance 0)
		)
		(min_thickness 0.25)
		(keepout
			(tracks not_allowed)
			(vias allowed)
			(pads allowed)
			(copperpour not_allowed)
			(footprints allowed)
		)
		(placement
			(enabled no)
			(sheetname "")
		)
		(fill yes
			(thermal_gap 0.5)
			(thermal_bridge_width 0.5)
			(island_removal_mode 0)
		)
		(polygon
			(pts
				(arc
					(start 347.269816 -409.290012)
					(mid 346.510356 -409.290012)
					(end 347.269816 -409.290012)
				)
			)
		)
	)
	(zone
		(layers "B.Cu" "In15.Cu")
		(hatch none 0.5)
		(connect_pads
			(clearance 0)
		)
		(min_thickness 0.25)
		(keepout
			(tracks not_allowed)
			(vias allowed)
			(pads allowed)
			(copperpour not_allowed)
			(footprints allowed)
		)
		(placement
			(enabled no)
			(sheetname "")
		)
		(fill yes
			(thermal_gap 0.5)
			(thermal_bridge_width 0.5)
			(island_removal_mode 0)
		)
		(polygon
			(pts
				(arc
					(start 137.949178 -357.75773)
					(mid 137.245598 -357.75773)
					(end 137.949178 -357.75773)
				)
			)
		)
	)
	(zone
		(layers "B.Cu" "In15.Cu")
		(hatch none 0.5)
		(connect_pads
			(clearance 0)
		)
		(min_thickness 0.25)
		(keepout
			(tracks not_allowed)
			(vias allowed)
			(pads allowed)
			(copperpour not_allowed)
			(footprints allowed)
		)
		(placement
			(enabled no)
			(sheetname "")
		)
		(fill yes
			(thermal_gap 0.5)
			(thermal_bridge_width 0.5)
			(island_removal_mode 0)
		)
		(polygon
			(pts
				(arc
					(start 78.132432 -351.611438)
					(mid 77.428852 -351.611438)
					(end 78.132432 -351.611438)
				)
			)
		)
	)
	(zone
		(layers "B.Cu" "In15.Cu")
		(hatch none 0.5)
		(connect_pads
			(clearance 0)
		)
		(min_thickness 0.25)
		(keepout
			(tracks not_allowed)
			(vias allowed)
			(pads allowed)
			(copperpour not_allowed)
			(footprints allowed)
		)
		(placement
			(enabled no)
			(sheetname "")
		)
		(fill yes
			(thermal_gap 0.5)
			(thermal_bridge_width 0.5)
			(island_removal_mode 0)
		)
		(polygon
			(pts
				(arc
					(start 162.776408 -312.999882)
					(mid 162.123628 -312.999882)
					(end 162.776408 -312.999882)
				)
			)
		)
	)
	(zone
		(layers "B.Cu" "In15.Cu")
		(hatch none 0.5)
		(connect_pads
			(clearance 0)
		)
		(min_thickness 0.25)
		(keepout
			(tracks not_allowed)
			(vias allowed)
			(pads allowed)
			(copperpour not_allowed)
			(footprints allowed)
		)
		(placement
			(enabled no)
			(sheetname "")
		)
		(fill yes
			(thermal_gap 0.5)
			(thermal_bridge_width 0.5)
			(island_removal_mode 0)
		)
		(polygon
			(pts
				(arc
					(start 378.62129 -345.465146)
					(mid 377.91771 -345.465146)
					(end 378.62129 -345.465146)
				)
			)
		)
	)
	(zone
		(layers "B.Cu" "In15.Cu")
		(hatch none 0.5)
		(connect_pads
			(clearance 0)
		)
		(min_thickness 0.25)
		(keepout
			(tracks not_allowed)
			(vias allowed)
			(pads allowed)
			(copperpour not_allowed)
			(footprints allowed)
		)
		(placement
			(enabled no)
			(sheetname "")
		)
		(fill yes
			(thermal_gap 0.5)
			(thermal_bridge_width 0.5)
			(island_removal_mode 0)
		)
		(polygon
			(pts
				(arc
					(start 340.66988 -409.490164)
					(mid 339.91042 -409.490164)
					(end 340.66988 -409.490164)
				)
			)
		)
	)
	(zone
		(layers "B.Cu" "In15.Cu")
		(hatch none 0.5)
		(connect_pads
			(clearance 0)
		)
		(min_thickness 0.25)
		(keepout
			(tracks not_allowed)
			(vias allowed)
			(pads allowed)
			(copperpour not_allowed)
			(footprints allowed)
		)
		(placement
			(enabled no)
			(sheetname "")
		)
		(fill yes
			(thermal_gap 0.5)
			(thermal_bridge_width 0.5)
			(island_removal_mode 0)
		)
		(polygon
			(pts
				(arc
					(start 81.241392 -354.732082)
					(mid 80.537812 -354.732082)
					(end 81.241392 -354.732082)
				)
			)
		)
	)
	(zone
		(layers "B.Cu" "In15.Cu")
		(hatch none 0.5)
		(connect_pads
			(clearance 0)
		)
		(min_thickness 0.25)
		(keepout
			(tracks not_allowed)
			(vias allowed)
			(pads allowed)
			(copperpour not_allowed)
			(footprints allowed)
		)
		(placement
			(enabled no)
			(sheetname "")
		)
		(fill yes
			(thermal_gap 0.5)
			(thermal_bridge_width 0.5)
			(island_removal_mode 0)
		)
		(polygon
			(pts
				(arc
					(start 338.469732 -384.590036)
					(mid 337.710272 -384.590036)
					(end 338.469732 -384.590036)
				)
			)
		)
	)
	(zone
		(layers "B.Cu" "In15.Cu")
		(hatch none 0.5)
		(connect_pads
			(clearance 0)
		)
		(min_thickness 0.25)
		(keepout
			(tracks not_allowed)
			(vias allowed)
			(pads allowed)
			(copperpour not_allowed)
			(footprints allowed)
		)
		(placement
			(enabled no)
			(sheetname "")
		)
		(fill yes
			(thermal_gap 0.5)
			(thermal_bridge_width 0.5)
			(island_removal_mode 0)
		)
		(polygon
			(pts
				(arc
					(start 397.27505 -345.465146)
					(mid 396.57147 -345.465146)
					(end 397.27505 -345.465146)
				)
			)
		)
	)
	(zone
		(layers "B.Cu" "In15.Cu")
		(hatch none 0.5)
		(connect_pads
			(clearance 0)
		)
		(min_thickness 0.25)
		(keepout
			(tracks not_allowed)
			(vias allowed)
			(pads allowed)
			(copperpour not_allowed)
			(footprints allowed)
		)
		(placement
			(enabled no)
			(sheetname "")
		)
		(fill yes
			(thermal_gap 0.5)
			(thermal_bridge_width 0.5)
			(island_removal_mode 0)
		)
		(polygon
			(pts
				(arc
					(start 394.02639 -311.099962)
					(mid 393.37361 -311.099962)
					(end 394.02639 -311.099962)
				)
			)
		)
	)
	(zone
		(layers "B.Cu" "In15.Cu")
		(hatch none 0.5)
		(connect_pads
			(clearance 0)
		)
		(min_thickness 0.25)
		(keepout
			(tracks not_allowed)
			(vias allowed)
			(pads allowed)
			(copperpour not_allowed)
			(footprints allowed)
		)
		(placement
			(enabled no)
			(sheetname "")
		)
		(fill yes
			(thermal_gap 0.5)
			(thermal_bridge_width 0.5)
			(island_removal_mode 0)
		)
		(polygon
			(pts
				(arc
					(start 331.508354 -354.732082)
					(mid 330.804774 -354.732082)
					(end 331.508354 -354.732082)
				)
			)
		)
	)
	(zone
		(layers "B.Cu" "In15.Cu")
		(hatch none 0.5)
		(connect_pads
			(clearance 0)
		)
		(min_thickness 0.25)
		(keepout
			(tracks not_allowed)
			(vias allowed)
			(pads allowed)
			(copperpour not_allowed)
			(footprints allowed)
		)
		(placement
			(enabled no)
			(sheetname "")
		)
		(fill yes
			(thermal_gap 0.5)
			(thermal_bridge_width 0.5)
			(island_removal_mode 0)
		)
		(polygon
			(pts
				(arc
					(start 381.73025 -348.58579)
					(mid 381.02667 -348.58579)
					(end 381.73025 -348.58579)
				)
			)
		)
	)
	(zone
		(layers "B.Cu" "In15.Cu")
		(hatch none 0.5)
		(connect_pads
			(clearance 0)
		)
		(min_thickness 0.25)
		(keepout
			(tracks not_allowed)
			(vias allowed)
			(pads allowed)
			(copperpour not_allowed)
			(footprints allowed)
		)
		(placement
			(enabled no)
			(sheetname "")
		)
		(fill yes
			(thermal_gap 0.5)
			(thermal_bridge_width 0.5)
			(island_removal_mode 0)
		)
		(polygon
			(pts
				(arc
					(start 143.303498 -357.75773)
					(mid 142.599918 -357.75773)
					(end 143.303498 -357.75773)
				)
			)
		)
	)
	(zone
		(layers "B.Cu" "In15.Cu")
		(hatch none 0.5)
		(connect_pads
			(clearance 0)
		)
		(min_thickness 0.25)
		(keepout
			(tracks not_allowed)
			(vias allowed)
			(pads allowed)
			(copperpour not_allowed)
			(footprints allowed)
		)
		(placement
			(enabled no)
			(sheetname "")
		)
		(fill yes
			(thermal_gap 0.5)
			(thermal_bridge_width 0.5)
			(island_removal_mode 0)
		)
		(polygon
			(pts
				(arc
					(start 182.72633 -312.049922)
					(mid 182.07355 -312.049922)
					(end 182.72633 -312.049922)
				)
			)
		)
	)
	(zone
		(layers "B.Cu" "In15.Cu")
		(hatch none 0.5)
		(connect_pads
			(clearance 0)
		)
		(min_thickness 0.25)
		(keepout
			(tracks not_allowed)
			(vias allowed)
			(pads allowed)
			(copperpour not_allowed)
			(footprints allowed)
		)
		(placement
			(enabled no)
			(sheetname "")
		)
		(fill yes
			(thermal_gap 0.5)
			(thermal_bridge_width 0.5)
			(island_removal_mode 0)
		)
		(polygon
			(pts
				(arc
					(start 45.889672 -374.390158)
					(mid 45.130212 -374.390158)
					(end 45.889672 -374.390158)
				)
			)
		)
	)
	(zone
		(layers "B.Cu" "In15.Cu")
		(hatch none 0.5)
		(connect_pads
			(clearance 0)
		)
		(min_thickness 0.25)
		(keepout
			(tracks not_allowed)
			(vias allowed)
			(pads allowed)
			(copperpour not_allowed)
			(footprints allowed)
		)
		(placement
			(enabled no)
			(sheetname "")
		)
		(fill yes
			(thermal_gap 0.5)
			(thermal_bridge_width 0.5)
			(island_removal_mode 0)
		)
		(polygon
			(pts
				(arc
					(start 403.49297 -354.732082)
					(mid 402.78939 -354.732082)
					(end 403.49297 -354.732082)
				)
			)
		)
	)
	(zone
		(layers "B.Cu" "In15.Cu")
		(hatch none 0.5)
		(connect_pads
			(clearance 0)
		)
		(min_thickness 0.25)
		(keepout
			(tracks not_allowed)
			(vias allowed)
			(pads allowed)
			(copperpour not_allowed)
			(footprints allowed)
		)
		(placement
			(enabled no)
			(sheetname "")
		)
		(fill yes
			(thermal_gap 0.5)
			(thermal_bridge_width 0.5)
			(island_removal_mode 0)
		)
		(polygon
			(pts
				(arc
					(start 41.451276 -287.824926)
					(mid 40.798496 -287.824926)
					(end 41.451276 -287.824926)
				)
			)
		)
	)
	(zone
		(layers "B.Cu" "In15.Cu")
		(hatch none 0.5)
		(connect_pads
			(clearance 0)
		)
		(min_thickness 0.25)
		(keepout
			(tracks not_allowed)
			(vias allowed)
			(pads allowed)
			(copperpour not_allowed)
			(footprints allowed)
		)
		(placement
			(enabled no)
			(sheetname "")
		)
		(fill yes
			(thermal_gap 0.5)
			(thermal_bridge_width 0.5)
			(island_removal_mode 0)
		)
		(polygon
			(pts
				(arc
					(start 131.731258 -354.732082)
					(mid 131.027678 -354.732082)
					(end 131.731258 -354.732082)
				)
			)
		)
	)
	(zone
		(layers "B.Cu" "In15.Cu")
		(hatch none 0.5)
		(connect_pads
			(clearance 0)
		)
		(min_thickness 0.25)
		(keepout
			(tracks not_allowed)
			(vias allowed)
			(pads allowed)
			(copperpour not_allowed)
			(footprints allowed)
		)
		(placement
			(enabled no)
			(sheetname "")
		)
		(fill yes
			(thermal_gap 0.5)
			(thermal_bridge_width 0.5)
			(island_removal_mode 0)
		)
		(polygon
			(pts
				(arc
					(start 340.66988 -382.18999)
					(mid 339.91042 -382.18999)
					(end 340.66988 -382.18999)
				)
			)
		)
	)
	(zone
		(layers "B.Cu" "In15.Cu")
		(hatch none 0.5)
		(connect_pads
			(clearance 0)
		)
		(min_thickness 0.25)
		(keepout
			(tracks not_allowed)
			(vias allowed)
			(pads allowed)
			(copperpour not_allowed)
			(footprints allowed)
		)
		(placement
			(enabled no)
			(sheetname "")
		)
		(fill yes
			(thermal_gap 0.5)
			(thermal_bridge_width 0.5)
			(island_removal_mode 0)
		)
		(polygon
			(pts
				(arc
					(start 399.52041 -348.58579)
					(mid 398.81683 -348.58579)
					(end 399.52041 -348.58579)
				)
			)
		)
	)
	(zone
		(layers "B.Cu" "In15.Cu")
		(hatch none 0.5)
		(connect_pads
			(clearance 0)
		)
		(min_thickness 0.25)
		(keepout
			(tracks not_allowed)
			(vias allowed)
			(pads allowed)
			(copperpour not_allowed)
			(footprints allowed)
		)
		(placement
			(enabled no)
			(sheetname "")
		)
		(fill yes
			(thermal_gap 0.5)
			(thermal_bridge_width 0.5)
			(island_removal_mode 0)
		)
		(polygon
			(pts
				(arc
					(start 283.626306 -311.099962)
					(mid 282.973526 -311.099962)
					(end 283.626306 -311.099962)
				)
			)
		)
	)
	(zone
		(layers "B.Cu" "In15.Cu")
		(hatch none 0.5)
		(connect_pads
			(clearance 0)
		)
		(min_thickness 0.25)
		(keepout
			(tracks not_allowed)
			(vias allowed)
			(pads allowed)
			(copperpour not_allowed)
			(footprints allowed)
		)
		(placement
			(enabled no)
			(sheetname "")
		)
		(fill yes
			(thermal_gap 0.5)
			(thermal_bridge_width 0.5)
			(island_removal_mode 0)
		)
		(polygon
			(pts
				(arc
					(start 383.97561 -357.75773)
					(mid 383.27203 -357.75773)
					(end 383.97561 -357.75773)
				)
			)
		)
	)
	(zone
		(layers "B.Cu" "In15.Cu")
		(hatch none 0.5)
		(connect_pads
			(clearance 0)
		)
		(min_thickness 0.25)
		(keepout
			(tracks not_allowed)
			(vias allowed)
			(pads allowed)
			(copperpour not_allowed)
			(footprints allowed)
		)
		(placement
			(enabled no)
			(sheetname "")
		)
		(fill yes
			(thermal_gap 0.5)
			(thermal_bridge_width 0.5)
			(island_removal_mode 0)
		)
		(polygon
			(pts
				(arc
					(start 391.269728 -410.589984)
					(mid 390.510268 -410.589984)
					(end 391.269728 -410.589984)
				)
			)
		)
	)
	(zone
		(layers "B.Cu" "In15.Cu")
		(hatch none 0.5)
		(connect_pads
			(clearance 0)
		)
		(min_thickness 0.25)
		(keepout
			(tracks not_allowed)
			(vias allowed)
			(pads allowed)
			(copperpour not_allowed)
			(footprints allowed)
		)
		(placement
			(enabled no)
			(sheetname "")
		)
		(fill yes
			(thermal_gap 0.5)
			(thermal_bridge_width 0.5)
			(island_removal_mode 0)
		)
		(polygon
			(pts
				(arc
					(start 276.026118 -312.049922)
					(mid 275.373338 -312.049922)
					(end 276.026118 -312.049922)
				)
			)
		)
	)
	(zone
		(layers "B.Cu" "In15.Cu")
		(hatch none 0.5)
		(connect_pads
			(clearance 0)
		)
		(min_thickness 0.25)
		(keepout
			(tracks not_allowed)
			(vias allowed)
			(pads allowed)
			(copperpour not_allowed)
			(footprints allowed)
		)
		(placement
			(enabled no)
			(sheetname "")
		)
		(fill yes
			(thermal_gap 0.5)
			(thermal_bridge_width 0.5)
			(island_removal_mode 0)
		)
		(polygon
			(pts
				(arc
					(start 397.27505 -357.75773)
					(mid 396.57147 -357.75773)
					(end 397.27505 -357.75773)
				)
			)
		)
	)
	(zone
		(layers "B.Cu" "In15.Cu")
		(hatch none 0.5)
		(connect_pads
			(clearance 0)
		)
		(min_thickness 0.25)
		(keepout
			(tracks not_allowed)
			(vias allowed)
			(pads allowed)
			(copperpour not_allowed)
			(footprints allowed)
		)
		(placement
			(enabled no)
			(sheetname "")
		)
		(fill yes
			(thermal_gap 0.5)
			(thermal_bridge_width 0.5)
			(island_removal_mode 0)
		)
		(polygon
			(pts
				(arc
					(start 331.508354 -345.465146)
					(mid 330.804774 -345.465146)
					(end 331.508354 -345.465146)
				)
			)
		)
	)
	(zone
		(layers "B.Cu" "In15.Cu")
		(hatch none 0.5)
		(connect_pads
			(clearance 0)
		)
		(min_thickness 0.25)
		(keepout
			(tracks not_allowed)
			(vias allowed)
			(pads allowed)
			(copperpour not_allowed)
			(footprints allowed)
		)
		(placement
			(enabled no)
			(sheetname "")
		)
		(fill yes
			(thermal_gap 0.5)
			(thermal_bridge_width 0.5)
			(island_removal_mode 0)
		)
		(polygon
			(pts
				(arc
					(start 398.77619 -312.999882)
					(mid 398.12341 -312.999882)
					(end 398.77619 -312.999882)
				)
			)
		)
	)
	(zone
		(layers "B.Cu" "In15.Cu")
		(hatch none 0.5)
		(connect_pads
			(clearance 0)
		)
		(min_thickness 0.25)
		(keepout
			(tracks not_allowed)
			(vias allowed)
			(pads allowed)
			(copperpour not_allowed)
			(footprints allowed)
		)
		(placement
			(enabled no)
			(sheetname "")
		)
		(fill yes
			(thermal_gap 0.5)
			(thermal_bridge_width 0.5)
			(island_removal_mode 0)
		)
		(polygon
			(pts
				(arc
					(start 420.626286 -311.099962)
					(mid 419.973506 -311.099962)
					(end 420.626286 -311.099962)
				)
			)
		)
	)
	(zone
		(layers "B.Cu" "In15.Cu")
		(hatch none 0.5)
		(connect_pads
			(clearance 0)
		)
		(min_thickness 0.25)
		(keepout
			(tracks not_allowed)
			(vias allowed)
			(pads allowed)
			(copperpour not_allowed)
			(footprints allowed)
		)
		(placement
			(enabled no)
			(sheetname "")
		)
		(fill yes
			(thermal_gap 0.5)
			(thermal_bridge_width 0.5)
			(island_removal_mode 0)
		)
		(polygon
			(pts
				(arc
					(start 57.126378 -312.049922)
					(mid 56.473598 -312.049922)
					(end 57.126378 -312.049922)
				)
			)
		)
	)
	(zone
		(layers "B.Cu" "In15.Cu")
		(hatch none 0.5)
		(connect_pads
			(clearance 0)
		)
		(min_thickness 0.25)
		(keepout
			(tracks not_allowed)
			(vias allowed)
			(pads allowed)
			(copperpour not_allowed)
			(footprints allowed)
		)
		(placement
			(enabled no)
			(sheetname "")
		)
		(fill yes
			(thermal_gap 0.5)
			(thermal_bridge_width 0.5)
			(island_removal_mode 0)
		)
		(polygon
			(pts
				(arc
					(start 282.676092 -313.949842)
					(mid 282.023312 -313.949842)
					(end 282.676092 -313.949842)
				)
			)
		)
	)
	(zone
		(layers "B.Cu" "In15.Cu")
		(hatch none 0.5)
		(connect_pads
			(clearance 0)
		)
		(min_thickness 0.25)
		(keepout
			(tracks not_allowed)
			(vias allowed)
			(pads allowed)
			(copperpour not_allowed)
			(footprints allowed)
		)
		(placement
			(enabled no)
			(sheetname "")
		)
		(fill yes
			(thermal_gap 0.5)
			(thermal_bridge_width 0.5)
			(island_removal_mode 0)
		)
		(polygon
			(pts
				(arc
					(start 371.53977 -345.465146)
					(mid 370.83619 -345.465146)
					(end 371.53977 -345.465146)
				)
			)
		)
	)
	(zone
		(layers "B.Cu" "In15.Cu")
		(hatch none 0.5)
		(connect_pads
			(clearance 0)
		)
		(min_thickness 0.25)
		(keepout
			(tracks not_allowed)
			(vias allowed)
			(pads allowed)
			(copperpour not_allowed)
			(footprints allowed)
		)
		(placement
			(enabled no)
			(sheetname "")
		)
		(fill yes
			(thermal_gap 0.5)
			(thermal_bridge_width 0.5)
			(island_removal_mode 0)
		)
		(polygon
			(pts
				(arc
					(start 57.126378 -311.099962)
					(mid 56.473598 -311.099962)
					(end 57.126378 -311.099962)
				)
			)
		)
	)
	(zone
		(layers "B.Cu" "In15.Cu")
		(hatch none 0.5)
		(connect_pads
			(clearance 0)
		)
		(min_thickness 0.25)
		(keepout
			(tracks not_allowed)
			(vias allowed)
			(pads allowed)
			(copperpour not_allowed)
			(footprints allowed)
		)
		(placement
			(enabled no)
			(sheetname "")
		)
		(fill yes
			(thermal_gap 0.5)
			(thermal_bridge_width 0.5)
			(island_removal_mode 0)
		)
		(polygon
			(pts
				(arc
					(start 402.62937 -357.75773)
					(mid 401.92579 -357.75773)
					(end 402.62937 -357.75773)
				)
			)
		)
	)
	(zone
		(layers "B.Cu" "In15.Cu")
		(hatch none 0.5)
		(connect_pads
			(clearance 0)
		)
		(min_thickness 0.25)
		(keepout
			(tracks not_allowed)
			(vias allowed)
			(pads allowed)
			(copperpour not_allowed)
			(footprints allowed)
		)
		(placement
			(enabled no)
			(sheetname "")
		)
		(fill yes
			(thermal_gap 0.5)
			(thermal_bridge_width 0.5)
			(island_removal_mode 0)
		)
		(polygon
			(pts
				(arc
					(start 134.840218 -351.611438)
					(mid 134.136638 -351.611438)
					(end 134.840218 -351.611438)
				)
			)
		)
	)
	(zone
		(layers "B.Cu" "In15.Cu")
		(hatch none 0.5)
		(connect_pads
			(clearance 0)
		)
		(min_thickness 0.25)
		(keepout
			(tracks not_allowed)
			(vias allowed)
			(pads allowed)
			(copperpour not_allowed)
			(footprints allowed)
		)
		(placement
			(enabled no)
			(sheetname "")
		)
		(fill yes
			(thermal_gap 0.5)
			(thermal_bridge_width 0.5)
			(island_removal_mode 0)
		)
		(polygon
			(pts
				(arc
					(start 285.526226 -312.049922)
					(mid 284.873446 -312.049922)
					(end 285.526226 -312.049922)
				)
			)
		)
	)
	(zone
		(layers "B.Cu" "In15.Cu")
		(hatch none 0.5)
		(connect_pads
			(clearance 0)
		)
		(min_thickness 0.25)
		(keepout
			(tracks not_allowed)
			(vias allowed)
			(pads allowed)
			(copperpour not_allowed)
			(footprints allowed)
		)
		(placement
			(enabled no)
			(sheetname "")
		)
		(fill yes
			(thermal_gap 0.5)
			(thermal_bridge_width 0.5)
			(island_removal_mode 0)
		)
		(polygon
			(pts
				(arc
					(start 375.869708 -409.490164)
					(mid 375.110248 -409.490164)
					(end 375.869708 -409.490164)
				)
			)
		)
	)
	(zone
		(layers "B.Cu" "In15.Cu")
		(hatch none 0.5)
		(connect_pads
			(clearance 0)
		)
		(min_thickness 0.25)
		(keepout
			(tracks not_allowed)
			(vias allowed)
			(pads allowed)
			(copperpour not_allowed)
			(footprints allowed)
		)
		(placement
			(enabled no)
			(sheetname "")
		)
		(fill yes
			(thermal_gap 0.5)
			(thermal_bridge_width 0.5)
			(island_removal_mode 0)
		)
		(polygon
			(pts
				(arc
					(start 421.576246 -313.949842)
					(mid 420.923466 -313.949842)
					(end 421.576246 -313.949842)
				)
			)
		)
	)
	(zone
		(layers "B.Cu" "In15.Cu")
		(hatch none 0.5)
		(connect_pads
			(clearance 0)
		)
		(min_thickness 0.25)
		(keepout
			(tracks not_allowed)
			(vias allowed)
			(pads allowed)
			(copperpour not_allowed)
			(footprints allowed)
		)
		(placement
			(enabled no)
			(sheetname "")
		)
		(fill yes
			(thermal_gap 0.5)
			(thermal_bridge_width 0.5)
			(island_removal_mode 0)
		)
		(polygon
			(pts
				(arc
					(start 416.826192 -312.049922)
					(mid 416.173412 -312.049922)
					(end 416.826192 -312.049922)
				)
			)
		)
	)
	(zone
		(layers "B.Cu" "In15.Cu")
		(hatch none 0.5)
		(connect_pads
			(clearance 0)
		)
		(min_thickness 0.25)
		(keepout
			(tracks not_allowed)
			(vias allowed)
			(pads allowed)
			(copperpour not_allowed)
			(footprints allowed)
		)
		(placement
			(enabled no)
			(sheetname "")
		)
		(fill yes
			(thermal_gap 0.5)
			(thermal_bridge_width 0.5)
			(island_removal_mode 0)
		)
		(polygon
			(pts
				(arc
					(start 337.726274 -357.75773)
					(mid 337.022694 -357.75773)
					(end 337.726274 -357.75773)
				)
			)
		)
	)
	(zone
		(layers "B.Cu" "In15.Cu")
		(hatch none 0.5)
		(connect_pads
			(clearance 0)
		)
		(min_thickness 0.25)
		(keepout
			(tracks not_allowed)
			(vias allowed)
			(pads allowed)
			(copperpour not_allowed)
			(footprints allowed)
		)
		(placement
			(enabled no)
			(sheetname "")
		)
		(fill yes
			(thermal_gap 0.5)
			(thermal_bridge_width 0.5)
			(island_removal_mode 0)
		)
		(polygon
			(pts
				(arc
					(start 390.19353 -342.439498)
					(mid 389.48995 -342.439498)
					(end 390.19353 -342.439498)
				)
			)
		)
	)
	(zone
		(layers "B.Cu" "In15.Cu")
		(hatch none 0.5)
		(connect_pads
			(clearance 0)
		)
		(min_thickness 0.25)
		(keepout
			(tracks not_allowed)
			(vias allowed)
			(pads allowed)
			(copperpour not_allowed)
			(footprints allowed)
		)
		(placement
			(enabled no)
			(sheetname "")
		)
		(fill yes
			(thermal_gap 0.5)
			(thermal_bridge_width 0.5)
			(island_removal_mode 0)
		)
		(polygon
			(pts
				(arc
					(start 331.508354 -357.75773)
					(mid 330.804774 -357.75773)
					(end 331.508354 -357.75773)
				)
			)
		)
	)
	(zone
		(layers "B.Cu" "In15.Cu")
		(hatch none 0.5)
		(connect_pads
			(clearance 0)
		)
		(min_thickness 0.25)
		(keepout
			(tracks not_allowed)
			(vias allowed)
			(pads allowed)
			(copperpour not_allowed)
			(footprints allowed)
		)
		(placement
			(enabled no)
			(sheetname "")
		)
		(fill yes
			(thermal_gap 0.5)
			(thermal_bridge_width 0.5)
			(island_removal_mode 0)
		)
		(polygon
			(pts
				(arc
					(start 120.689878 -409.490164)
					(mid 119.930418 -409.490164)
					(end 120.689878 -409.490164)
				)
			)
		)
	)
	(zone
		(layers "B.Cu" "In15.Cu")
		(hatch none 0.5)
		(connect_pads
			(clearance 0)
		)
		(min_thickness 0.25)
		(keepout
			(tracks not_allowed)
			(vias allowed)
			(pads allowed)
			(copperpour not_allowed)
			(footprints allowed)
		)
		(placement
			(enabled no)
			(sheetname "")
		)
		(fill yes
			(thermal_gap 0.5)
			(thermal_bridge_width 0.5)
			(island_removal_mode 0)
		)
		(polygon
			(pts
				(arc
					(start 143.303498 -342.439498)
					(mid 142.599918 -342.439498)
					(end 143.303498 -342.439498)
				)
			)
		)
	)
	(zone
		(layers "B.Cu" "In15.Cu")
		(hatch none 0.5)
		(connect_pads
			(clearance 0)
		)
		(min_thickness 0.25)
		(keepout
			(tracks not_allowed)
			(vias allowed)
			(pads allowed)
			(copperpour not_allowed)
			(footprints allowed)
		)
		(placement
			(enabled no)
			(sheetname "")
		)
		(fill yes
			(thermal_gap 0.5)
			(thermal_bridge_width 0.5)
			(island_removal_mode 0)
		)
		(polygon
			(pts
				(arc
					(start 414.926272 -312.049922)
					(mid 414.273492 -312.049922)
					(end 414.926272 -312.049922)
				)
			)
		)
	)
	(zone
		(layers "B.Cu" "In15.Cu")
		(hatch none 0.5)
		(connect_pads
			(clearance 0)
		)
		(min_thickness 0.25)
		(keepout
			(tracks not_allowed)
			(vias allowed)
			(pads allowed)
			(copperpour not_allowed)
			(footprints allowed)
		)
		(placement
			(enabled no)
			(sheetname "")
		)
		(fill yes
			(thermal_gap 0.5)
			(thermal_bridge_width 0.5)
			(island_removal_mode 0)
		)
		(polygon
			(pts
				(arc
					(start 188.426344 -312.049922)
					(mid 187.773564 -312.049922)
					(end 188.426344 -312.049922)
				)
			)
		)
	)
	(zone
		(layers "B.Cu" "In15.Cu")
		(hatch none 0.5)
		(connect_pads
			(clearance 0)
		)
		(min_thickness 0.25)
		(keepout
			(tracks not_allowed)
			(vias allowed)
			(pads allowed)
			(copperpour not_allowed)
			(footprints allowed)
		)
		(placement
			(enabled no)
			(sheetname "")
		)
		(fill yes
			(thermal_gap 0.5)
			(thermal_bridge_width 0.5)
			(island_removal_mode 0)
		)
		(polygon
			(pts
				(arc
					(start 131.731258 -357.75773)
					(mid 131.027678 -357.75773)
					(end 131.731258 -357.75773)
				)
			)
		)
	)
	(zone
		(layers "B.Cu" "In15.Cu")
		(hatch none 0.5)
		(connect_pads
			(clearance 0)
		)
		(min_thickness 0.25)
		(keepout
			(tracks not_allowed)
			(vias allowed)
			(pads allowed)
			(copperpour not_allowed)
			(footprints allowed)
		)
		(placement
			(enabled no)
			(sheetname "")
		)
		(fill yes
			(thermal_gap 0.5)
			(thermal_bridge_width 0.5)
			(island_removal_mode 0)
		)
		(polygon
			(pts
				(arc
					(start 378.62129 -342.439498)
					(mid 377.91771 -342.439498)
					(end 378.62129 -342.439498)
				)
			)
		)
	)
	(zone
		(layers "B.Cu" "In15.Cu")
		(hatch none 0.5)
		(connect_pads
			(clearance 0)
		)
		(min_thickness 0.25)
		(keepout
			(tracks not_allowed)
			(vias allowed)
			(pads allowed)
			(copperpour not_allowed)
			(footprints allowed)
		)
		(placement
			(enabled no)
			(sheetname "")
		)
		(fill yes
			(thermal_gap 0.5)
			(thermal_bridge_width 0.5)
			(island_removal_mode 0)
		)
		(polygon
			(pts
				(arc
					(start 74.489564 -409.290012)
					(mid 73.730104 -409.290012)
					(end 74.489564 -409.290012)
				)
			)
		)
	)
	(zone
		(layers "B.Cu" "In15.Cu")
		(hatch none 0.5)
		(connect_pads
			(clearance 0)
		)
		(min_thickness 0.25)
		(keepout
			(tracks not_allowed)
			(vias allowed)
			(pads allowed)
			(copperpour not_allowed)
			(footprints allowed)
		)
		(placement
			(enabled no)
			(sheetname "")
		)
		(fill yes
			(thermal_gap 0.5)
			(thermal_bridge_width 0.5)
			(island_removal_mode 0)
		)
		(polygon
			(pts
				(arc
					(start 420.626286 -312.049922)
					(mid 419.973506 -312.049922)
					(end 420.626286 -312.049922)
				)
			)
		)
	)
	(zone
		(layers "B.Cu" "In15.Cu")
		(hatch none 0.5)
		(connect_pads
			(clearance 0)
		)
		(min_thickness 0.25)
		(keepout
			(tracks not_allowed)
			(vias allowed)
			(pads allowed)
			(copperpour not_allowed)
			(footprints allowed)
		)
		(placement
			(enabled no)
			(sheetname "")
		)
		(fill yes
			(thermal_gap 0.5)
			(thermal_bridge_width 0.5)
			(island_removal_mode 0)
		)
		(polygon
			(pts
				(arc
					(start 87.68969 -409.290012)
					(mid 86.93023 -409.290012)
					(end 87.68969 -409.290012)
				)
			)
		)
	)
	(zone
		(layers "B.Cu" "In15.Cu")
		(hatch none 0.5)
		(connect_pads
			(clearance 0)
		)
		(min_thickness 0.25)
		(keepout
			(tracks not_allowed)
			(vias allowed)
			(pads allowed)
			(copperpour not_allowed)
			(footprints allowed)
		)
		(placement
			(enabled no)
			(sheetname "")
		)
		(fill yes
			(thermal_gap 0.5)
			(thermal_bridge_width 0.5)
			(island_removal_mode 0)
		)
		(polygon
			(pts
				(arc
					(start 284.576266 -312.999882)
					(mid 283.923486 -312.999882)
					(end 284.576266 -312.999882)
				)
			)
		)
	)
	(zone
		(layers "B.Cu" "In15.Cu")
		(hatch none 0.5)
		(connect_pads
			(clearance 0)
		)
		(min_thickness 0.25)
		(keepout
			(tracks not_allowed)
			(vias allowed)
			(pads allowed)
			(copperpour not_allowed)
			(footprints allowed)
		)
		(placement
			(enabled no)
			(sheetname "")
		)
		(fill yes
			(thermal_gap 0.5)
			(thermal_bridge_width 0.5)
			(island_removal_mode 0)
		)
		(polygon
			(pts
				(arc
					(start 371.53977 -342.439498)
					(mid 370.83619 -342.439498)
					(end 371.53977 -342.439498)
				)
			)
		)
	)
	(zone
		(layers "B.Cu" "In15.Cu")
		(hatch none 0.5)
		(connect_pads
			(clearance 0)
		)
		(min_thickness 0.25)
		(keepout
			(tracks not_allowed)
			(vias allowed)
			(pads allowed)
			(copperpour not_allowed)
			(footprints allowed)
		)
		(placement
			(enabled no)
			(sheetname "")
		)
		(fill yes
			(thermal_gap 0.5)
			(thermal_bridge_width 0.5)
			(island_removal_mode 0)
		)
		(polygon
			(pts
				(arc
					(start 375.869708 -378.290074)
					(mid 375.110248 -378.290074)
					(end 375.869708 -378.290074)
				)
			)
		)
	)
	(zone
		(layers "B.Cu" "In15.Cu")
		(hatch none 0.5)
		(connect_pads
			(clearance 0)
		)
		(min_thickness 0.25)
		(keepout
			(tracks not_allowed)
			(vias allowed)
			(pads allowed)
			(copperpour not_allowed)
			(footprints allowed)
		)
		(placement
			(enabled no)
			(sheetname "")
		)
		(fill yes
			(thermal_gap 0.5)
			(thermal_bridge_width 0.5)
			(island_removal_mode 0)
		)
		(polygon
			(pts
				(arc
					(start 278.876252 -312.999882)
					(mid 278.223472 -312.999882)
					(end 278.876252 -312.999882)
				)
			)
		)
	)
	(zone
		(layers "B.Cu" "In15.Cu")
		(hatch none 0.5)
		(connect_pads
			(clearance 0)
		)
		(min_thickness 0.25)
		(keepout
			(tracks not_allowed)
			(vias allowed)
			(pads allowed)
			(copperpour not_allowed)
			(footprints allowed)
		)
		(placement
			(enabled no)
			(sheetname "")
		)
		(fill yes
			(thermal_gap 0.5)
			(thermal_bridge_width 0.5)
			(island_removal_mode 0)
		)
		(polygon
			(pts
				(arc
					(start 144.167098 -345.465146)
					(mid 143.463518 -345.465146)
					(end 144.167098 -345.465146)
				)
			)
		)
	)
	(zone
		(layers "B.Cu" "In15.Cu")
		(hatch none 0.5)
		(connect_pads
			(clearance 0)
		)
		(min_thickness 0.25)
		(keepout
			(tracks not_allowed)
			(vias allowed)
			(pads allowed)
			(copperpour not_allowed)
			(footprints allowed)
		)
		(placement
			(enabled no)
			(sheetname "")
		)
		(fill yes
			(thermal_gap 0.5)
			(thermal_bridge_width 0.5)
			(island_removal_mode 0)
		)
		(polygon
			(pts
				(arc
					(start 116.289836 -378.290074)
					(mid 115.530376 -378.290074)
					(end 116.289836 -378.290074)
				)
			)
		)
	)
	(zone
		(layers "B.Cu" "In15.Cu")
		(hatch none 0.5)
		(connect_pads
			(clearance 0)
		)
		(min_thickness 0.25)
		(keepout
			(tracks not_allowed)
			(vias allowed)
			(pads allowed)
			(copperpour not_allowed)
			(footprints allowed)
		)
		(placement
			(enabled no)
			(sheetname "")
		)
		(fill yes
			(thermal_gap 0.5)
			(thermal_bridge_width 0.5)
			(island_removal_mode 0)
		)
		(polygon
			(pts
				(arc
					(start 113.077498 -345.465146)
					(mid 112.373918 -345.465146)
					(end 113.077498 -345.465146)
				)
			)
		)
	)
	(zone
		(layers "B.Cu" "In15.Cu")
		(hatch none 0.5)
		(connect_pads
			(clearance 0)
		)
		(min_thickness 0.25)
		(keepout
			(tracks not_allowed)
			(vias allowed)
			(pads allowed)
			(copperpour not_allowed)
			(footprints allowed)
		)
		(placement
			(enabled no)
			(sheetname "")
		)
		(fill yes
			(thermal_gap 0.5)
			(thermal_bridge_width 0.5)
			(island_removal_mode 0)
		)
		(polygon
			(pts
				(arc
					(start 68.805552 -357.75773)
					(mid 68.101972 -357.75773)
					(end 68.805552 -357.75773)
				)
			)
		)
	)
	(zone
		(layers "B.Cu" "In15.Cu")
		(hatch none 0.5)
		(connect_pads
			(clearance 0)
		)
		(min_thickness 0.25)
		(keepout
			(tracks not_allowed)
			(vias allowed)
			(pads allowed)
			(copperpour not_allowed)
			(footprints allowed)
		)
		(placement
			(enabled no)
			(sheetname "")
		)
		(fill yes
			(thermal_gap 0.5)
			(thermal_bridge_width 0.5)
			(island_removal_mode 0)
		)
		(polygon
			(pts
				(arc
					(start 393.30249 -348.58579)
					(mid 392.59891 -348.58579)
					(end 393.30249 -348.58579)
				)
			)
		)
	)
	(zone
		(layers "B.Cu" "In15.Cu")
		(hatch none 0.5)
		(connect_pads
			(clearance 0)
		)
		(min_thickness 0.25)
		(keepout
			(tracks not_allowed)
			(vias allowed)
			(pads allowed)
			(copperpour not_allowed)
			(footprints allowed)
		)
		(placement
			(enabled no)
			(sheetname "")
		)
		(fill yes
			(thermal_gap 0.5)
			(thermal_bridge_width 0.5)
			(island_removal_mode 0)
		)
		(polygon
			(pts
				(arc
					(start 119.295418 -342.439498)
					(mid 118.591838 -342.439498)
					(end 119.295418 -342.439498)
				)
			)
		)
	)
	(zone
		(layers "B.Cu" "In15.Cu")
		(hatch none 0.5)
		(connect_pads
			(clearance 0)
		)
		(min_thickness 0.25)
		(keepout
			(tracks not_allowed)
			(vias allowed)
			(pads allowed)
			(copperpour not_allowed)
			(footprints allowed)
		)
		(placement
			(enabled no)
			(sheetname "")
		)
		(fill yes
			(thermal_gap 0.5)
			(thermal_bridge_width 0.5)
			(island_removal_mode 0)
		)
		(polygon
			(pts
				(arc
					(start 378.62129 -354.732082)
					(mid 377.91771 -354.732082)
					(end 378.62129 -354.732082)
				)
			)
		)
	)
	(zone
		(layers "B.Cu" "In15.Cu")
		(hatch none 0.5)
		(connect_pads
			(clearance 0)
		)
		(min_thickness 0.25)
		(keepout
			(tracks not_allowed)
			(vias allowed)
			(pads allowed)
			(copperpour not_allowed)
			(footprints allowed)
		)
		(placement
			(enabled no)
			(sheetname "")
		)
		(fill yes
			(thermal_gap 0.5)
			(thermal_bridge_width 0.5)
			(island_removal_mode 0)
		)
		(polygon
			(pts
				(arc
					(start 128.622298 -348.58579)
					(mid 127.918718 -348.58579)
					(end 128.622298 -348.58579)
				)
			)
		)
	)
	(zone
		(layers "B.Cu" "In15.Cu")
		(hatch none 0.5)
		(connect_pads
			(clearance 0)
		)
		(min_thickness 0.25)
		(keepout
			(tracks not_allowed)
			(vias allowed)
			(pads allowed)
			(copperpour not_allowed)
			(footprints allowed)
		)
		(placement
			(enabled no)
			(sheetname "")
		)
		(fill yes
			(thermal_gap 0.5)
			(thermal_bridge_width 0.5)
			(island_removal_mode 0)
		)
		(polygon
			(pts
				(arc
					(start 394.16609 -351.611438)
					(mid 393.46251 -351.611438)
					(end 394.16609 -351.611438)
				)
			)
		)
	)
	(zone
		(layers "B.Cu" "In15.Cu")
		(hatch none 0.5)
		(connect_pads
			(clearance 0)
		)
		(min_thickness 0.25)
		(keepout
			(tracks not_allowed)
			(vias allowed)
			(pads allowed)
			(copperpour not_allowed)
			(footprints allowed)
		)
		(placement
			(enabled no)
			(sheetname "")
		)
		(fill yes
			(thermal_gap 0.5)
			(thermal_bridge_width 0.5)
			(island_removal_mode 0)
		)
		(polygon
			(pts
				(arc
					(start 328.399394 -348.58579)
					(mid 327.695814 -348.58579)
					(end 328.399394 -348.58579)
				)
			)
		)
	)
	(zone
		(layers "B.Cu" "In15.Cu")
		(hatch none 0.5)
		(connect_pads
			(clearance 0)
		)
		(min_thickness 0.25)
		(keepout
			(tracks not_allowed)
			(vias allowed)
			(pads allowed)
			(copperpour not_allowed)
			(footprints allowed)
		)
		(placement
			(enabled no)
			(sheetname "")
		)
		(fill yes
			(thermal_gap 0.5)
			(thermal_bridge_width 0.5)
			(island_removal_mode 0)
		)
		(polygon
			(pts
				(arc
					(start 325.290434 -345.465146)
					(mid 324.586854 -345.465146)
					(end 325.290434 -345.465146)
				)
			)
		)
	)
	(zone
		(layers "B.Cu" "In15.Cu")
		(hatch none 0.5)
		(connect_pads
			(clearance 0)
		)
		(min_thickness 0.25)
		(keepout
			(tracks not_allowed)
			(vias allowed)
			(pads allowed)
			(copperpour not_allowed)
			(footprints allowed)
		)
		(placement
			(enabled no)
			(sheetname "")
		)
		(fill yes
			(thermal_gap 0.5)
			(thermal_bridge_width 0.5)
			(island_removal_mode 0)
		)
		(polygon
			(pts
				(arc
					(start 332.371954 -354.732082)
					(mid 331.668374 -354.732082)
					(end 332.371954 -354.732082)
				)
			)
		)
	)
	(zone
		(layers "B.Cu" "In15.Cu")
		(hatch none 0.5)
		(connect_pads
			(clearance 0)
		)
		(min_thickness 0.25)
		(keepout
			(tracks not_allowed)
			(vias allowed)
			(pads allowed)
			(copperpour not_allowed)
			(footprints allowed)
		)
		(placement
			(enabled no)
			(sheetname "")
		)
		(fill yes
			(thermal_gap 0.5)
			(thermal_bridge_width 0.5)
			(island_removal_mode 0)
		)
		(polygon
			(pts
				(arc
					(start 184.62625 -312.049922)
					(mid 183.97347 -312.049922)
					(end 184.62625 -312.049922)
				)
			)
		)
	)
	(zone
		(layers "B.Cu" "In15.Cu")
		(hatch none 0.5)
		(connect_pads
			(clearance 0)
		)
		(min_thickness 0.25)
		(keepout
			(tracks not_allowed)
			(vias allowed)
			(pads allowed)
			(copperpour not_allowed)
			(footprints allowed)
		)
		(placement
			(enabled no)
			(sheetname "")
		)
		(fill yes
			(thermal_gap 0.5)
			(thermal_bridge_width 0.5)
			(island_removal_mode 0)
		)
		(polygon
			(pts
				(arc
					(start 378.069602 -379.390148)
					(mid 377.310142 -379.390148)
					(end 378.069602 -379.390148)
				)
			)
		)
	)
	(zone
		(layers "B.Cu" "In15.Cu")
		(hatch none 0.5)
		(connect_pads
			(clearance 0)
		)
		(min_thickness 0.25)
		(keepout
			(tracks not_allowed)
			(vias allowed)
			(pads allowed)
			(copperpour not_allowed)
			(footprints allowed)
		)
		(placement
			(enabled no)
			(sheetname "")
		)
		(fill yes
			(thermal_gap 0.5)
			(thermal_bridge_width 0.5)
			(island_removal_mode 0)
		)
		(polygon
			(pts
				(arc
					(start 374.64873 -348.58579)
					(mid 373.94515 -348.58579)
					(end 374.64873 -348.58579)
				)
			)
		)
	)
	(zone
		(layers "B.Cu" "In15.Cu")
		(hatch none 0.5)
		(connect_pads
			(clearance 0)
		)
		(min_thickness 0.25)
		(keepout
			(tracks not_allowed)
			(vias allowed)
			(pads allowed)
			(copperpour not_allowed)
			(footprints allowed)
		)
		(placement
			(enabled no)
			(sheetname "")
		)
		(fill yes
			(thermal_gap 0.5)
			(thermal_bridge_width 0.5)
			(island_removal_mode 0)
		)
		(polygon
			(pts
				(arc
					(start 49.52619 -311.099962)
					(mid 48.87341 -311.099962)
					(end 49.52619 -311.099962)
				)
			)
		)
	)
	(zone
		(layers "B.Cu" "In15.Cu")
		(hatch none 0.5)
		(connect_pads
			(clearance 0)
		)
		(min_thickness 0.25)
		(keepout
			(tracks not_allowed)
			(vias allowed)
			(pads allowed)
			(copperpour not_allowed)
			(footprints allowed)
		)
		(placement
			(enabled no)
			(sheetname "")
		)
		(fill yes
			(thermal_gap 0.5)
			(thermal_bridge_width 0.5)
			(island_removal_mode 0)
		)
		(polygon
			(pts
				(arc
					(start 332.371954 -357.75773)
					(mid 331.668374 -357.75773)
					(end 332.371954 -357.75773)
				)
			)
		)
	)
	(zone
		(layers "B.Cu" "In15.Cu")
		(hatch none 0.5)
		(connect_pads
			(clearance 0)
		)
		(min_thickness 0.25)
		(keepout
			(tracks not_allowed)
			(vias allowed)
			(pads allowed)
			(copperpour not_allowed)
			(footprints allowed)
		)
		(placement
			(enabled no)
			(sheetname "")
		)
		(fill yes
			(thermal_gap 0.5)
			(thermal_bridge_width 0.5)
			(island_removal_mode 0)
		)
		(polygon
			(pts
				(arc
					(start 380.26975 -409.490164)
					(mid 379.51029 -409.490164)
					(end 380.26975 -409.490164)
				)
			)
		)
	)
	(zone
		(layers "B.Cu" "In15.Cu")
		(hatch none 0.5)
		(connect_pads
			(clearance 0)
		)
		(min_thickness 0.25)
		(keepout
			(tracks not_allowed)
			(vias allowed)
			(pads allowed)
			(copperpour not_allowed)
			(footprints allowed)
		)
		(placement
			(enabled no)
			(sheetname "")
		)
		(fill yes
			(thermal_gap 0.5)
			(thermal_bridge_width 0.5)
			(island_removal_mode 0)
		)
		(polygon
			(pts
				(arc
					(start 312.854594 -345.465146)
					(mid 312.151014 -345.465146)
					(end 312.854594 -345.465146)
				)
			)
		)
	)
	(zone
		(layers "B.Cu" "In15.Cu")
		(hatch none 0.5)
		(connect_pads
			(clearance 0)
		)
		(min_thickness 0.25)
		(keepout
			(tracks not_allowed)
			(vias allowed)
			(pads allowed)
			(copperpour not_allowed)
			(footprints allowed)
		)
		(placement
			(enabled no)
			(sheetname "")
		)
		(fill yes
			(thermal_gap 0.5)
			(thermal_bridge_width 0.5)
			(island_removal_mode 0)
		)
		(polygon
			(pts
				(arc
					(start 78.889606 -410.589984)
					(mid 78.130146 -410.589984)
					(end 78.889606 -410.589984)
				)
			)
		)
	)
	(zone
		(layers "B.Cu" "In15.Cu")
		(hatch none 0.5)
		(connect_pads
			(clearance 0)
		)
		(min_thickness 0.25)
		(keepout
			(tracks not_allowed)
			(vias allowed)
			(pads allowed)
			(copperpour not_allowed)
			(footprints allowed)
		)
		(placement
			(enabled no)
			(sheetname "")
		)
		(fill yes
			(thermal_gap 0.5)
			(thermal_bridge_width 0.5)
			(island_removal_mode 0)
		)
		(polygon
			(pts
				(arc
					(start 380.86665 -348.58579)
					(mid 380.16307 -348.58579)
					(end 380.86665 -348.58579)
				)
			)
		)
	)
	(zone
		(layers "B.Cu" "In15.Cu")
		(hatch none 0.5)
		(connect_pads
			(clearance 0)
		)
		(min_thickness 0.25)
		(keepout
			(tracks not_allowed)
			(vias allowed)
			(pads allowed)
			(copperpour not_allowed)
			(footprints allowed)
		)
		(placement
			(enabled no)
			(sheetname "")
		)
		(fill yes
			(thermal_gap 0.5)
			(thermal_bridge_width 0.5)
			(island_removal_mode 0)
		)
		(polygon
			(pts
				(arc
					(start 90.568272 -348.58579)
					(mid 89.864692 -348.58579)
					(end 90.568272 -348.58579)
				)
			)
		)
	)
	(zone
		(layers "B.Cu" "In15.Cu")
		(hatch none 0.5)
		(connect_pads
			(clearance 0)
		)
		(min_thickness 0.25)
		(keepout
			(tracks not_allowed)
			(vias allowed)
			(pads allowed)
			(copperpour not_allowed)
			(footprints allowed)
		)
		(placement
			(enabled no)
			(sheetname "")
		)
		(fill yes
			(thermal_gap 0.5)
			(thermal_bridge_width 0.5)
			(island_removal_mode 0)
		)
		(polygon
			(pts
				(arc
					(start 36.701222 -288.774886)
					(mid 36.048442 -288.774886)
					(end 36.701222 -288.774886)
				)
			)
		)
	)
	(zone
		(layers "B.Cu" "In15.Cu")
		(hatch none 0.5)
		(connect_pads
			(clearance 0)
		)
		(min_thickness 0.25)
		(keepout
			(tracks not_allowed)
			(vias allowed)
			(pads allowed)
			(copperpour not_allowed)
			(footprints allowed)
		)
		(placement
			(enabled no)
			(sheetname "")
		)
		(fill yes
			(thermal_gap 0.5)
			(thermal_bridge_width 0.5)
			(island_removal_mode 0)
		)
		(polygon
			(pts
				(arc
					(start 325.290434 -354.732082)
					(mid 324.586854 -354.732082)
					(end 325.290434 -354.732082)
				)
			)
		)
	)
	(zone
		(layers "B.Cu" "In15.Cu")
		(hatch none 0.5)
		(connect_pads
			(clearance 0)
		)
		(min_thickness 0.25)
		(keepout
			(tracks not_allowed)
			(vias allowed)
			(pads allowed)
			(copperpour not_allowed)
			(footprints allowed)
		)
		(placement
			(enabled no)
			(sheetname "")
		)
		(fill yes
			(thermal_gap 0.5)
			(thermal_bridge_width 0.5)
			(island_removal_mode 0)
		)
		(polygon
			(pts
				(arc
					(start 342.869774 -383.290064)
					(mid 342.110314 -383.290064)
					(end 342.869774 -383.290064)
				)
			)
		)
	)
	(zone
		(layers "B.Cu" "In15.Cu")
		(hatch none 0.5)
		(connect_pads
			(clearance 0)
		)
		(min_thickness 0.25)
		(keepout
			(tracks not_allowed)
			(vias allowed)
			(pads allowed)
			(copperpour not_allowed)
			(footprints allowed)
		)
		(placement
			(enabled no)
			(sheetname "")
		)
		(fill yes
			(thermal_gap 0.5)
			(thermal_bridge_width 0.5)
			(island_removal_mode 0)
		)
		(polygon
			(pts
				(arc
					(start 133.976618 -348.58579)
					(mid 133.273038 -348.58579)
					(end 133.976618 -348.58579)
				)
			)
		)
	)
	(zone
		(layers "B.Cu" "In15.Cu")
		(hatch none 0.5)
		(connect_pads
			(clearance 0)
		)
		(min_thickness 0.25)
		(keepout
			(tracks not_allowed)
			(vias allowed)
			(pads allowed)
			(copperpour not_allowed)
			(footprints allowed)
		)
		(placement
			(enabled no)
			(sheetname "")
		)
		(fill yes
			(thermal_gap 0.5)
			(thermal_bridge_width 0.5)
			(island_removal_mode 0)
		)
		(polygon
			(pts
				(arc
					(start 75.023472 -357.75773)
					(mid 74.319892 -357.75773)
					(end 75.023472 -357.75773)
				)
			)
		)
	)
	(zone
		(layers "B.Cu" "In15.Cu")
		(hatch none 0.5)
		(connect_pads
			(clearance 0)
		)
		(min_thickness 0.25)
		(keepout
			(tracks not_allowed)
			(vias allowed)
			(pads allowed)
			(copperpour not_allowed)
			(footprints allowed)
		)
		(placement
			(enabled no)
			(sheetname "")
		)
		(fill yes
			(thermal_gap 0.5)
			(thermal_bridge_width 0.5)
			(island_removal_mode 0)
		)
		(polygon
			(pts
				(arc
					(start 137.949178 -342.439498)
					(mid 137.245598 -342.439498)
					(end 137.949178 -342.439498)
				)
			)
		)
	)
	(zone
		(layers "B.Cu" "In15.Cu")
		(hatch none 0.5)
		(connect_pads
			(clearance 0)
		)
		(min_thickness 0.25)
		(keepout
			(tracks not_allowed)
			(vias allowed)
			(pads allowed)
			(copperpour not_allowed)
			(footprints allowed)
		)
		(placement
			(enabled no)
			(sheetname "")
		)
		(fill yes
			(thermal_gap 0.5)
			(thermal_bridge_width 0.5)
			(island_removal_mode 0)
		)
		(polygon
			(pts
				(arc
					(start 278.876252 -313.949842)
					(mid 278.223472 -313.949842)
					(end 278.876252 -313.949842)
				)
			)
		)
	)
	(zone
		(layers "B.Cu" "In15.Cu")
		(hatch none 0.5)
		(connect_pads
			(clearance 0)
		)
		(min_thickness 0.25)
		(keepout
			(tracks not_allowed)
			(vias allowed)
			(pads allowed)
			(copperpour not_allowed)
			(footprints allowed)
		)
		(placement
			(enabled no)
			(sheetname "")
		)
		(fill yes
			(thermal_gap 0.5)
			(thermal_bridge_width 0.5)
			(island_removal_mode 0)
		)
		(polygon
			(pts
				(arc
					(start 391.05713 -342.439498)
					(mid 390.35355 -342.439498)
					(end 391.05713 -342.439498)
				)
			)
		)
	)
	(zone
		(layers "B.Cu" "In15.Cu")
		(hatch none 0.5)
		(connect_pads
			(clearance 0)
		)
		(min_thickness 0.25)
		(keepout
			(tracks not_allowed)
			(vias allowed)
			(pads allowed)
			(copperpour not_allowed)
			(footprints allowed)
		)
		(placement
			(enabled no)
			(sheetname "")
		)
		(fill yes
			(thermal_gap 0.5)
			(thermal_bridge_width 0.5)
			(island_removal_mode 0)
		)
		(polygon
			(pts
				(arc
					(start 400.38401 -351.611438)
					(mid 399.68043 -351.611438)
					(end 400.38401 -351.611438)
				)
			)
		)
	)
	(zone
		(layers "B.Cu" "In15.Cu")
		(hatch none 0.5)
		(connect_pads
			(clearance 0)
		)
		(min_thickness 0.25)
		(keepout
			(tracks not_allowed)
			(vias allowed)
			(pads allowed)
			(copperpour not_allowed)
			(footprints allowed)
		)
		(placement
			(enabled no)
			(sheetname "")
		)
		(fill yes
			(thermal_gap 0.5)
			(thermal_bridge_width 0.5)
			(island_removal_mode 0)
		)
		(polygon
			(pts
				(arc
					(start 65.696592 -351.611438)
					(mid 64.993012 -351.611438)
					(end 65.696592 -351.611438)
				)
			)
		)
	)
	(zone
		(layers "B.Cu" "In15.Cu")
		(hatch none 0.5)
		(connect_pads
			(clearance 0)
		)
		(min_thickness 0.25)
		(keepout
			(tracks not_allowed)
			(vias allowed)
			(pads allowed)
			(copperpour not_allowed)
			(footprints allowed)
		)
		(placement
			(enabled no)
			(sheetname "")
		)
		(fill yes
			(thermal_gap 0.5)
			(thermal_bridge_width 0.5)
			(island_removal_mode 0)
		)
		(polygon
			(pts
				(arc
					(start 391.05713 -354.732082)
					(mid 390.35355 -354.732082)
					(end 391.05713 -354.732082)
				)
			)
		)
	)
	(zone
		(layers "B.Cu" "In15.Cu")
		(hatch none 0.5)
		(connect_pads
			(clearance 0)
		)
		(min_thickness 0.25)
		(keepout
			(tracks not_allowed)
			(vias allowed)
			(pads allowed)
			(copperpour not_allowed)
			(footprints allowed)
		)
		(placement
			(enabled no)
			(sheetname "")
		)
		(fill yes
			(thermal_gap 0.5)
			(thermal_bridge_width 0.5)
			(island_removal_mode 0)
		)
		(polygon
			(pts
				(arc
					(start 387.94817 -348.58579)
					(mid 387.24459 -348.58579)
					(end 387.94817 -348.58579)
				)
			)
		)
	)
	(zone
		(layers "B.Cu" "In15.Cu")
		(hatch none 0.5)
		(connect_pads
			(clearance 0)
		)
		(min_thickness 0.25)
		(keepout
			(tracks not_allowed)
			(vias allowed)
			(pads allowed)
			(copperpour not_allowed)
			(footprints allowed)
		)
		(placement
			(enabled no)
			(sheetname "")
		)
		(fill yes
			(thermal_gap 0.5)
			(thermal_bridge_width 0.5)
			(island_removal_mode 0)
		)
		(polygon
			(pts
				(arc
					(start 342.869774 -384.590036)
					(mid 342.110314 -384.590036)
					(end 342.869774 -384.590036)
				)
			)
		)
	)
	(zone
		(layers "B.Cu" "In15.Cu")
		(hatch none 0.5)
		(connect_pads
			(clearance 0)
		)
		(min_thickness 0.25)
		(keepout
			(tracks not_allowed)
			(vias allowed)
			(pads allowed)
			(copperpour not_allowed)
			(footprints allowed)
		)
		(placement
			(enabled no)
			(sheetname "")
		)
		(fill yes
			(thermal_gap 0.5)
			(thermal_bridge_width 0.5)
			(island_removal_mode 0)
		)
		(polygon
			(pts
				(arc
					(start 312.854594 -342.439498)
					(mid 312.151014 -342.439498)
					(end 312.854594 -342.439498)
				)
			)
		)
	)
	(zone
		(layers "B.Cu" "In15.Cu")
		(hatch none 0.5)
		(connect_pads
			(clearance 0)
		)
		(min_thickness 0.25)
		(keepout
			(tracks not_allowed)
			(vias allowed)
			(pads allowed)
			(copperpour not_allowed)
			(footprints allowed)
		)
		(placement
			(enabled no)
			(sheetname "")
		)
		(fill yes
			(thermal_gap 0.5)
			(thermal_bridge_width 0.5)
			(island_removal_mode 0)
		)
		(polygon
			(pts
				(arc
					(start 402.62937 -342.439498)
					(mid 401.92579 -342.439498)
					(end 402.62937 -342.439498)
				)
			)
		)
	)
	(zone
		(layers "B.Cu" "In15.Cu")
		(hatch none 0.5)
		(connect_pads
			(clearance 0)
		)
		(min_thickness 0.25)
		(keepout
			(tracks not_allowed)
			(vias allowed)
			(pads allowed)
			(copperpour not_allowed)
			(footprints allowed)
		)
		(placement
			(enabled no)
			(sheetname "")
		)
		(fill yes
			(thermal_gap 0.5)
			(thermal_bridge_width 0.5)
			(island_removal_mode 0)
		)
		(polygon
			(pts
				(arc
					(start 319.072514 -357.75773)
					(mid 318.368934 -357.75773)
					(end 319.072514 -357.75773)
				)
			)
		)
	)
	(zone
		(layers "B.Cu" "In15.Cu")
		(hatch none 0.5)
		(connect_pads
			(clearance 0)
		)
		(min_thickness 0.25)
		(keepout
			(tracks not_allowed)
			(vias allowed)
			(pads allowed)
			(copperpour not_allowed)
			(footprints allowed)
		)
		(placement
			(enabled no)
			(sheetname "")
		)
		(fill yes
			(thermal_gap 0.5)
			(thermal_bridge_width 0.5)
			(island_removal_mode 0)
		)
		(polygon
			(pts
				(arc
					(start 89.704672 -348.58579)
					(mid 89.001092 -348.58579)
					(end 89.704672 -348.58579)
				)
			)
		)
	)
	(zone
		(layers "B.Cu" "In15.Cu")
		(hatch none 0.5)
		(connect_pads
			(clearance 0)
		)
		(min_thickness 0.25)
		(keepout
			(tracks not_allowed)
			(vias allowed)
			(pads allowed)
			(copperpour not_allowed)
			(footprints allowed)
		)
		(placement
			(enabled no)
			(sheetname "")
		)
		(fill yes
			(thermal_gap 0.5)
			(thermal_bridge_width 0.5)
			(island_removal_mode 0)
		)
		(polygon
			(pts
				(arc
					(start 335.480914 -348.58579)
					(mid 334.777334 -348.58579)
					(end 335.480914 -348.58579)
				)
			)
		)
	)
	(zone
		(layers "B.Cu" "In15.Cu")
		(hatch none 0.5)
		(connect_pads
			(clearance 0)
		)
		(min_thickness 0.25)
		(keepout
			(tracks not_allowed)
			(vias allowed)
			(pads allowed)
			(copperpour not_allowed)
			(footprints allowed)
		)
		(placement
			(enabled no)
			(sheetname "")
		)
		(fill yes
			(thermal_gap 0.5)
			(thermal_bridge_width 0.5)
			(island_removal_mode 0)
		)
		(polygon
			(pts
				(arc
					(start 394.97635 -312.999882)
					(mid 394.32357 -312.999882)
					(end 394.97635 -312.999882)
				)
			)
		)
	)
	(zone
		(layers "B.Cu" "In15.Cu")
		(hatch none 0.5)
		(connect_pads
			(clearance 0)
		)
		(min_thickness 0.25)
		(keepout
			(tracks not_allowed)
			(vias allowed)
			(pads allowed)
			(copperpour not_allowed)
			(footprints allowed)
		)
		(placement
			(enabled no)
			(sheetname "")
		)
		(fill yes
			(thermal_gap 0.5)
			(thermal_bridge_width 0.5)
			(island_removal_mode 0)
		)
		(polygon
			(pts
				(arc
					(start 163.726368 -311.099962)
					(mid 163.073588 -311.099962)
					(end 163.726368 -311.099962)
				)
			)
		)
	)
	(zone
		(layers "B.Cu" "In15.Cu")
		(hatch none 0.5)
		(connect_pads
			(clearance 0)
		)
		(min_thickness 0.25)
		(keepout
			(tracks not_allowed)
			(vias allowed)
			(pads allowed)
			(copperpour not_allowed)
			(footprints allowed)
		)
		(placement
			(enabled no)
			(sheetname "")
		)
		(fill yes
			(thermal_gap 0.5)
			(thermal_bridge_width 0.5)
			(island_removal_mode 0)
		)
		(polygon
			(pts
				(arc
					(start 347.269816 -384.590036)
					(mid 346.510356 -384.590036)
					(end 347.269816 -384.590036)
				)
			)
		)
	)
	(zone
		(layers "B.Cu" "In15.Cu")
		(hatch none 0.5)
		(connect_pads
			(clearance 0)
		)
		(min_thickness 0.25)
		(keepout
			(tracks not_allowed)
			(vias allowed)
			(pads allowed)
			(copperpour not_allowed)
			(footprints allowed)
		)
		(placement
			(enabled no)
			(sheetname "")
		)
		(fill yes
			(thermal_gap 0.5)
			(thermal_bridge_width 0.5)
			(island_removal_mode 0)
		)
		(polygon
			(pts
				(arc
					(start 384.669792 -409.490164)
					(mid 383.910332 -409.490164)
					(end 384.669792 -409.490164)
				)
			)
		)
	)
	(zone
		(layers "B.Cu" "In15.Cu")
		(hatch none 0.5)
		(connect_pads
			(clearance 0)
		)
		(min_thickness 0.25)
		(keepout
			(tracks not_allowed)
			(vias allowed)
			(pads allowed)
			(copperpour not_allowed)
			(footprints allowed)
		)
		(placement
			(enabled no)
			(sheetname "")
		)
		(fill yes
			(thermal_gap 0.5)
			(thermal_bridge_width 0.5)
			(island_removal_mode 0)
		)
		(polygon
			(pts
				(arc
					(start 419.676326 -312.999882)
					(mid 419.023546 -312.999882)
					(end 419.676326 -312.999882)
				)
			)
		)
	)
	(zone
		(layers "B.Cu" "In15.Cu")
		(hatch none 0.5)
		(connect_pads
			(clearance 0)
		)
		(min_thickness 0.25)
		(keepout
			(tracks not_allowed)
			(vias allowed)
			(pads allowed)
			(copperpour not_allowed)
			(footprints allowed)
		)
		(placement
			(enabled no)
			(sheetname "")
		)
		(fill yes
			(thermal_gap 0.5)
			(thermal_bridge_width 0.5)
			(island_removal_mode 0)
		)
		(polygon
			(pts
				(arc
					(start 74.489564 -383.290064)
					(mid 73.730104 -383.290064)
					(end 74.489564 -383.290064)
				)
			)
		)
	)
	(zone
		(layers "B.Cu" "In15.Cu")
		(hatch none 0.5)
		(connect_pads
			(clearance 0)
		)
		(min_thickness 0.25)
		(keepout
			(tracks not_allowed)
			(vias allowed)
			(pads allowed)
			(copperpour not_allowed)
			(footprints allowed)
		)
		(placement
			(enabled no)
			(sheetname "")
		)
		(fill yes
			(thermal_gap 0.5)
			(thermal_bridge_width 0.5)
			(island_removal_mode 0)
		)
		(polygon
			(pts
				(arc
					(start 122.889772 -409.290012)
					(mid 122.130312 -409.290012)
					(end 122.889772 -409.290012)
				)
			)
		)
	)
	(zone
		(layers "B.Cu" "In15.Cu")
		(hatch none 0.5)
		(connect_pads
			(clearance 0)
		)
		(min_thickness 0.25)
		(keepout
			(tracks not_allowed)
			(vias allowed)
			(pads allowed)
			(copperpour not_allowed)
			(footprints allowed)
		)
		(placement
			(enabled no)
			(sheetname "")
		)
		(fill yes
			(thermal_gap 0.5)
			(thermal_bridge_width 0.5)
			(island_removal_mode 0)
		)
		(polygon
			(pts
				(arc
					(start 67.941952 -342.439498)
					(mid 67.238372 -342.439498)
					(end 67.941952 -342.439498)
				)
			)
		)
	)
	(zone
		(layers "B.Cu" "In15.Cu")
		(hatch none 0.5)
		(connect_pads
			(clearance 0)
		)
		(min_thickness 0.25)
		(keepout
			(tracks not_allowed)
			(vias allowed)
			(pads allowed)
			(copperpour not_allowed)
			(footprints allowed)
		)
		(placement
			(enabled no)
			(sheetname "")
		)
		(fill yes
			(thermal_gap 0.5)
			(thermal_bridge_width 0.5)
			(island_removal_mode 0)
		)
		(polygon
			(pts
				(arc
					(start 81.089754 -383.490216)
					(mid 80.330294 -383.490216)
					(end 81.089754 -383.490216)
				)
			)
		)
	)
	(zone
		(layers "B.Cu" "In15.Cu")
		(hatch none 0.5)
		(connect_pads
			(clearance 0)
		)
		(min_thickness 0.25)
		(keepout
			(tracks not_allowed)
			(vias allowed)
			(pads allowed)
			(copperpour not_allowed)
			(footprints allowed)
		)
		(placement
			(enabled no)
			(sheetname "")
		)
		(fill yes
			(thermal_gap 0.5)
			(thermal_bridge_width 0.5)
			(island_removal_mode 0)
		)
		(polygon
			(pts
				(arc
					(start 344.807794 -345.465146)
					(mid 344.104214 -345.465146)
					(end 344.807794 -345.465146)
				)
			)
		)
	)
	(zone
		(layers "B.Cu" "In15.Cu")
		(hatch none 0.5)
		(connect_pads
			(clearance 0)
		)
		(min_thickness 0.25)
		(keepout
			(tracks not_allowed)
			(vias allowed)
			(pads allowed)
			(copperpour not_allowed)
			(footprints allowed)
		)
		(placement
			(enabled no)
			(sheetname "")
		)
		(fill yes
			(thermal_gap 0.5)
			(thermal_bridge_width 0.5)
			(island_removal_mode 0)
		)
		(polygon
			(pts
				(arc
					(start 326.154034 -357.75773)
					(mid 325.450454 -357.75773)
					(end 326.154034 -357.75773)
				)
			)
		)
	)
	(zone
		(layers "B.Cu" "In15.Cu")
		(hatch none 0.5)
		(connect_pads
			(clearance 0)
		)
		(min_thickness 0.25)
		(keepout
			(tracks not_allowed)
			(vias allowed)
			(pads allowed)
			(copperpour not_allowed)
			(footprints allowed)
		)
		(placement
			(enabled no)
			(sheetname "")
		)
		(fill yes
			(thermal_gap 0.5)
			(thermal_bridge_width 0.5)
			(island_removal_mode 0)
		)
		(polygon
			(pts
				(arc
					(start 76.689712 -409.490164)
					(mid 75.930252 -409.490164)
					(end 76.689712 -409.490164)
				)
			)
		)
	)
	(zone
		(layers "B.Cu" "In15.Cu")
		(hatch none 0.5)
		(connect_pads
			(clearance 0)
		)
		(min_thickness 0.25)
		(keepout
			(tracks not_allowed)
			(vias allowed)
			(pads allowed)
			(copperpour not_allowed)
			(footprints allowed)
		)
		(placement
			(enabled no)
			(sheetname "")
		)
		(fill yes
			(thermal_gap 0.5)
			(thermal_bridge_width 0.5)
			(island_removal_mode 0)
		)
		(polygon
			(pts
				(arc
					(start 334.06969 -383.290064)
					(mid 333.31023 -383.290064)
					(end 334.06969 -383.290064)
				)
			)
		)
	)
	(zone
		(layers "B.Cu" "In15.Cu")
		(hatch none 0.5)
		(connect_pads
			(clearance 0)
		)
		(min_thickness 0.25)
		(keepout
			(tracks not_allowed)
			(vias allowed)
			(pads allowed)
			(copperpour not_allowed)
			(footprints allowed)
		)
		(placement
			(enabled no)
			(sheetname "")
		)
		(fill yes
			(thermal_gap 0.5)
			(thermal_bridge_width 0.5)
			(island_removal_mode 0)
		)
		(polygon
			(pts
				(arc
					(start 64.832992 -348.58579)
					(mid 64.129412 -348.58579)
					(end 64.832992 -348.58579)
				)
			)
		)
	)
	(zone
		(layers "B.Cu" "In15.Cu")
		(hatch none 0.5)
		(connect_pads
			(clearance 0)
		)
		(min_thickness 0.25)
		(keepout
			(tracks not_allowed)
			(vias allowed)
			(pads allowed)
			(copperpour not_allowed)
			(footprints allowed)
		)
		(placement
			(enabled no)
			(sheetname "")
		)
		(fill yes
			(thermal_gap 0.5)
			(thermal_bridge_width 0.5)
			(island_removal_mode 0)
		)
		(polygon
			(pts
				(arc
					(start 45.889672 -375.69013)
					(mid 45.130212 -375.69013)
					(end 45.889672 -375.69013)
				)
			)
		)
	)
	(zone
		(layers "B.Cu" "In15.Cu")
		(hatch none 0.5)
		(connect_pads
			(clearance 0)
		)
		(min_thickness 0.25)
		(keepout
			(tracks not_allowed)
			(vias allowed)
			(pads allowed)
			(copperpour not_allowed)
			(footprints allowed)
		)
		(placement
			(enabled no)
			(sheetname "")
		)
		(fill yes
			(thermal_gap 0.5)
			(thermal_bridge_width 0.5)
			(island_removal_mode 0)
		)
		(polygon
			(pts
				(arc
					(start 183.67629 -312.999882)
					(mid 183.02351 -312.999882)
					(end 183.67629 -312.999882)
				)
			)
		)
	)
	(zone
		(layers "B.Cu" "In15.Cu")
		(hatch none 0.5)
		(connect_pads
			(clearance 0)
		)
		(min_thickness 0.25)
		(keepout
			(tracks not_allowed)
			(vias allowed)
			(pads allowed)
			(copperpour not_allowed)
			(footprints allowed)
		)
		(placement
			(enabled no)
			(sheetname "")
		)
		(fill yes
			(thermal_gap 0.5)
			(thermal_bridge_width 0.5)
			(island_removal_mode 0)
		)
		(polygon
			(pts
				(arc
					(start 78.889606 -384.590036)
					(mid 78.130146 -384.590036)
					(end 78.889606 -384.590036)
				)
			)
		)
	)
	(zone
		(layers "B.Cu" "In15.Cu")
		(hatch none 0.5)
		(connect_pads
			(clearance 0)
		)
		(min_thickness 0.25)
		(keepout
			(tracks not_allowed)
			(vias allowed)
			(pads allowed)
			(copperpour not_allowed)
			(footprints allowed)
		)
		(placement
			(enabled no)
			(sheetname "")
		)
		(fill yes
			(thermal_gap 0.5)
			(thermal_bridge_width 0.5)
			(island_removal_mode 0)
		)
		(polygon
			(pts
				(arc
					(start 316.827154 -348.58579)
					(mid 316.123574 -348.58579)
					(end 316.827154 -348.58579)
				)
			)
		)
	)
	(zone
		(layers "B.Cu" "In15.Cu")
		(hatch none 0.5)
		(connect_pads
			(clearance 0)
		)
		(min_thickness 0.25)
		(keepout
			(tracks not_allowed)
			(vias allowed)
			(pads allowed)
			(copperpour not_allowed)
			(footprints allowed)
		)
		(placement
			(enabled no)
			(sheetname "")
		)
		(fill yes
			(thermal_gap 0.5)
			(thermal_bridge_width 0.5)
			(island_removal_mode 0)
		)
		(polygon
			(pts
				(arc
					(start 393.076176 -313.949842)
					(mid 392.423396 -313.949842)
					(end 393.076176 -313.949842)
				)
			)
		)
	)
	(zone
		(layers "B.Cu" "In15.Cu")
		(hatch none 0.5)
		(connect_pads
			(clearance 0)
		)
		(min_thickness 0.25)
		(keepout
			(tracks not_allowed)
			(vias allowed)
			(pads allowed)
			(copperpour not_allowed)
			(footprints allowed)
		)
		(placement
			(enabled no)
			(sheetname "")
		)
		(fill yes
			(thermal_gap 0.5)
			(thermal_bridge_width 0.5)
			(island_removal_mode 0)
		)
		(polygon
			(pts
				(arc
					(start 125.08992 -409.490164)
					(mid 124.33046 -409.490164)
					(end 125.08992 -409.490164)
				)
			)
		)
	)
	(zone
		(layers "B.Cu" "In15.Cu")
		(hatch none 0.5)
		(connect_pads
			(clearance 0)
		)
		(min_thickness 0.25)
		(keepout
			(tracks not_allowed)
			(vias allowed)
			(pads allowed)
			(copperpour not_allowed)
			(footprints allowed)
		)
		(placement
			(enabled no)
			(sheetname "")
		)
		(fill yes
			(thermal_gap 0.5)
			(thermal_bridge_width 0.5)
			(island_removal_mode 0)
		)
		(polygon
			(pts
				(arc
					(start 323.045074 -348.58579)
					(mid 322.341494 -348.58579)
					(end 323.045074 -348.58579)
				)
			)
		)
	)
	(zone
		(layers "B.Cu" "In15.Cu")
		(hatch none 0.5)
		(connect_pads
			(clearance 0)
		)
		(min_thickness 0.25)
		(keepout
			(tracks not_allowed)
			(vias allowed)
			(pads allowed)
			(copperpour not_allowed)
			(footprints allowed)
		)
		(placement
			(enabled no)
			(sheetname "")
		)
		(fill yes
			(thermal_gap 0.5)
			(thermal_bridge_width 0.5)
			(island_removal_mode 0)
		)
		(polygon
			(pts
				(arc
					(start 334.06969 -410.589984)
					(mid 333.31023 -410.589984)
					(end 334.06969 -410.589984)
				)
			)
		)
	)
	(zone
		(layers "B.Cu" "In15.Cu")
		(hatch none 0.5)
		(connect_pads
			(clearance 0)
		)
		(min_thickness 0.25)
		(keepout
			(tracks not_allowed)
			(vias allowed)
			(pads allowed)
			(copperpour not_allowed)
			(footprints allowed)
		)
		(placement
			(enabled no)
			(sheetname "")
		)
		(fill yes
			(thermal_gap 0.5)
			(thermal_bridge_width 0.5)
			(island_removal_mode 0)
		)
		(polygon
			(pts
				(arc
					(start 134.840218 -348.58579)
					(mid 134.136638 -348.58579)
					(end 134.840218 -348.58579)
				)
			)
		)
	)
	(zone
		(layers "B.Cu" "In15.Cu")
		(hatch none 0.5)
		(connect_pads
			(clearance 0)
		)
		(min_thickness 0.25)
		(keepout
			(tracks not_allowed)
			(vias allowed)
			(pads allowed)
			(copperpour not_allowed)
			(footprints allowed)
		)
		(placement
			(enabled no)
			(sheetname "")
		)
		(fill yes
			(thermal_gap 0.5)
			(thermal_bridge_width 0.5)
			(island_removal_mode 0)
		)
		(polygon
			(pts
				(arc
					(start 403.49297 -345.465146)
					(mid 402.78939 -345.465146)
					(end 403.49297 -345.465146)
				)
			)
		)
	)
	(zone
		(layers "B.Cu" "In15.Cu")
		(hatch none 0.5)
		(connect_pads
			(clearance 0)
		)
		(min_thickness 0.25)
		(keepout
			(tracks not_allowed)
			(vias allowed)
			(pads allowed)
			(copperpour not_allowed)
			(footprints allowed)
		)
		(placement
			(enabled no)
			(sheetname "")
		)
		(fill yes
			(thermal_gap 0.5)
			(thermal_bridge_width 0.5)
			(island_removal_mode 0)
		)
		(polygon
			(pts
				(arc
					(start 58.073036 -368.516662)
					(mid 57.369456 -368.516662)
					(end 58.073036 -368.516662)
				)
			)
		)
	)
	(zone
		(layers "B.Cu" "In15.Cu")
		(hatch none 0.5)
		(connect_pads
			(clearance 0)
		)
		(min_thickness 0.25)
		(keepout
			(tracks not_allowed)
			(vias allowed)
			(pads allowed)
			(copperpour not_allowed)
			(footprints allowed)
		)
		(placement
			(enabled no)
			(sheetname "")
		)
		(fill yes
			(thermal_gap 0.5)
			(thermal_bridge_width 0.5)
			(island_removal_mode 0)
		)
		(polygon
			(pts
				(arc
					(start 334.06969 -384.590036)
					(mid 333.31023 -384.590036)
					(end 334.06969 -384.590036)
				)
			)
		)
	)
	(zone
		(layers "B.Cu" "In15.Cu")
		(hatch none 0.5)
		(connect_pads
			(clearance 0)
		)
		(min_thickness 0.25)
		(keepout
			(tracks not_allowed)
			(vias allowed)
			(pads allowed)
			(copperpour not_allowed)
			(footprints allowed)
		)
		(placement
			(enabled no)
			(sheetname "")
		)
		(fill yes
			(thermal_gap 0.5)
			(thermal_bridge_width 0.5)
			(island_removal_mode 0)
		)
		(polygon
			(pts
				(arc
					(start 338.589874 -342.439498)
					(mid 337.886294 -342.439498)
					(end 338.589874 -342.439498)
				)
			)
		)
	)
	(zone
		(layers "B.Cu" "In15.Cu")
		(hatch none 0.5)
		(connect_pads
			(clearance 0)
		)
		(min_thickness 0.25)
		(keepout
			(tracks not_allowed)
			(vias allowed)
			(pads allowed)
			(copperpour not_allowed)
			(footprints allowed)
		)
		(placement
			(enabled no)
			(sheetname "")
		)
		(fill yes
			(thermal_gap 0.5)
			(thermal_bridge_width 0.5)
			(island_removal_mode 0)
		)
		(polygon
			(pts
				(arc
					(start 72.28967 -382.18999)
					(mid 71.53021 -382.18999)
					(end 72.28967 -382.18999)
				)
			)
		)
	)
	(zone
		(layers "B.Cu" "In15.Cu")
		(hatch none 0.5)
		(connect_pads
			(clearance 0)
		)
		(min_thickness 0.25)
		(keepout
			(tracks not_allowed)
			(vias allowed)
			(pads allowed)
			(copperpour not_allowed)
			(footprints allowed)
		)
		(placement
			(enabled no)
			(sheetname "")
		)
		(fill yes
			(thermal_gap 0.5)
			(thermal_bridge_width 0.5)
			(island_removal_mode 0)
		)
		(polygon
			(pts
				(arc
					(start 338.469732 -410.589984)
					(mid 337.710272 -410.589984)
					(end 338.469732 -410.589984)
				)
			)
		)
	)
	(zone
		(layers "B.Cu" "In15.Cu")
		(hatch none 0.5)
		(connect_pads
			(clearance 0)
		)
		(min_thickness 0.25)
		(keepout
			(tracks not_allowed)
			(vias allowed)
			(pads allowed)
			(copperpour not_allowed)
			(footprints allowed)
		)
		(placement
			(enabled no)
			(sheetname "")
		)
		(fill yes
			(thermal_gap 0.5)
			(thermal_bridge_width 0.5)
			(island_removal_mode 0)
		)
		(polygon
			(pts
				(arc
					(start 71.914512 -351.611438)
					(mid 71.210932 -351.611438)
					(end 71.914512 -351.611438)
				)
			)
		)
	)
	(zone
		(layers "B.Cu" "In15.Cu")
		(hatch none 0.5)
		(connect_pads
			(clearance 0)
		)
		(min_thickness 0.25)
		(keepout
			(tracks not_allowed)
			(vias allowed)
			(pads allowed)
			(copperpour not_allowed)
			(footprints allowed)
		)
		(placement
			(enabled no)
			(sheetname "")
		)
		(fill yes
			(thermal_gap 0.5)
			(thermal_bridge_width 0.5)
			(island_removal_mode 0)
		)
		(polygon
			(pts
				(arc
					(start 189.376304 -313.949842)
					(mid 188.723524 -313.949842)
					(end 189.376304 -313.949842)
				)
			)
		)
	)
	(zone
		(layers "B.Cu" "In15.Cu")
		(hatch none 0.5)
		(connect_pads
			(clearance 0)
		)
		(min_thickness 0.25)
		(keepout
			(tracks not_allowed)
			(vias allowed)
			(pads allowed)
			(copperpour not_allowed)
			(footprints allowed)
		)
		(placement
			(enabled no)
			(sheetname "")
		)
		(fill yes
			(thermal_gap 0.5)
			(thermal_bridge_width 0.5)
			(island_removal_mode 0)
		)
		(polygon
			(pts
				(arc
					(start 80.377792 -345.465146)
					(mid 79.674212 -345.465146)
					(end 80.377792 -345.465146)
				)
			)
		)
	)
	(zone
		(layers "B.Cu" "In15.Cu")
		(hatch none 0.5)
		(connect_pads
			(clearance 0)
		)
		(min_thickness 0.25)
		(keepout
			(tracks not_allowed)
			(vias allowed)
			(pads allowed)
			(copperpour not_allowed)
			(footprints allowed)
		)
		(placement
			(enabled no)
			(sheetname "")
		)
		(fill yes
			(thermal_gap 0.5)
			(thermal_bridge_width 0.5)
			(island_removal_mode 0)
		)
		(polygon
			(pts
				(arc
					(start 390.19353 -357.75773)
					(mid 389.48995 -357.75773)
					(end 390.19353 -357.75773)
				)
			)
		)
	)
	(zone
		(layers "B.Cu" "In15.Cu")
		(hatch none 0.5)
		(connect_pads
			(clearance 0)
		)
		(min_thickness 0.25)
		(keepout
			(tracks not_allowed)
			(vias allowed)
			(pads allowed)
			(copperpour not_allowed)
			(footprints allowed)
		)
		(placement
			(enabled no)
			(sheetname "")
		)
		(fill yes
			(thermal_gap 0.5)
			(thermal_bridge_width 0.5)
			(island_removal_mode 0)
		)
		(polygon
			(pts
				(arc
					(start 342.869774 -409.290012)
					(mid 342.110314 -409.290012)
					(end 342.869774 -409.290012)
				)
			)
		)
	)
	(zone
		(layers "B.Cu" "In15.Cu")
		(hatch none 0.5)
		(connect_pads
			(clearance 0)
		)
		(min_thickness 0.25)
		(keepout
			(tracks not_allowed)
			(vias allowed)
			(pads allowed)
			(copperpour not_allowed)
			(footprints allowed)
		)
		(placement
			(enabled no)
			(sheetname "")
		)
		(fill yes
			(thermal_gap 0.5)
			(thermal_bridge_width 0.5)
			(island_removal_mode 0)
		)
		(polygon
			(pts
				(arc
					(start 386.869686 -380.69012)
					(mid 386.110226 -380.69012)
					(end 386.869686 -380.69012)
				)
			)
		)
	)
	(zone
		(layers "B.Cu" "In15.Cu")
		(hatch none 0.5)
		(connect_pads
			(clearance 0)
		)
		(min_thickness 0.25)
		(keepout
			(tracks not_allowed)
			(vias allowed)
			(pads allowed)
			(copperpour not_allowed)
			(footprints allowed)
		)
		(placement
			(enabled no)
			(sheetname "")
		)
		(fill yes
			(thermal_gap 0.5)
			(thermal_bridge_width 0.5)
			(island_removal_mode 0)
		)
		(polygon
			(pts
				(arc
					(start 281.726132 -311.099962)
					(mid 281.073352 -311.099962)
					(end 281.726132 -311.099962)
				)
			)
		)
	)
	(zone
		(layers "B.Cu" "In15.Cu")
		(hatch none 0.5)
		(connect_pads
			(clearance 0)
		)
		(min_thickness 0.25)
		(keepout
			(tracks not_allowed)
			(vias allowed)
			(pads allowed)
			(copperpour not_allowed)
			(footprints allowed)
		)
		(placement
			(enabled no)
			(sheetname "")
		)
		(fill yes
			(thermal_gap 0.5)
			(thermal_bridge_width 0.5)
			(island_removal_mode 0)
		)
		(polygon
			(pts
				(arc
					(start 61.724032 -345.465146)
					(mid 61.020452 -345.465146)
					(end 61.724032 -345.465146)
				)
			)
		)
	)
	(zone
		(layers "B.Cu" "In15.Cu")
		(hatch none 0.5)
		(connect_pads
			(clearance 0)
		)
		(min_thickness 0.25)
		(keepout
			(tracks not_allowed)
			(vias allowed)
			(pads allowed)
			(copperpour not_allowed)
			(footprints allowed)
		)
		(placement
			(enabled no)
			(sheetname "")
		)
		(fill yes
			(thermal_gap 0.5)
			(thermal_bridge_width 0.5)
			(island_removal_mode 0)
		)
		(polygon
			(pts
				(arc
					(start 62.587632 -345.465146)
					(mid 61.884052 -345.465146)
					(end 62.587632 -345.465146)
				)
			)
		)
	)
	(zone
		(layers "B.Cu" "In15.Cu")
		(hatch none 0.5)
		(connect_pads
			(clearance 0)
		)
		(min_thickness 0.25)
		(keepout
			(tracks not_allowed)
			(vias allowed)
			(pads allowed)
			(copperpour not_allowed)
			(footprints allowed)
		)
		(placement
			(enabled no)
			(sheetname "")
		)
		(fill yes
			(thermal_gap 0.5)
			(thermal_bridge_width 0.5)
			(island_removal_mode 0)
		)
		(polygon
			(pts
				(arc
					(start 44.301156 -288.774886)
					(mid 43.648376 -288.774886)
					(end 44.301156 -288.774886)
				)
			)
		)
	)
	(zone
		(layers "B.Cu" "In15.Cu")
		(hatch none 0.5)
		(connect_pads
			(clearance 0)
		)
		(min_thickness 0.25)
		(keepout
			(tracks not_allowed)
			(vias allowed)
			(pads allowed)
			(copperpour not_allowed)
			(footprints allowed)
		)
		(placement
			(enabled no)
			(sheetname "")
		)
		(fill yes
			(thermal_gap 0.5)
			(thermal_bridge_width 0.5)
			(island_removal_mode 0)
		)
		(polygon
			(pts
				(arc
					(start 345.069668 -408.190192)
					(mid 344.310208 -408.190192)
					(end 345.069668 -408.190192)
				)
			)
		)
	)
	(zone
		(layers "B.Cu" "In15.Cu")
		(hatch none 0.5)
		(connect_pads
			(clearance 0)
		)
		(min_thickness 0.25)
		(keepout
			(tracks not_allowed)
			(vias allowed)
			(pads allowed)
			(copperpour not_allowed)
			(footprints allowed)
		)
		(placement
			(enabled no)
			(sheetname "")
		)
		(fill yes
			(thermal_gap 0.5)
			(thermal_bridge_width 0.5)
			(island_removal_mode 0)
		)
		(polygon
			(pts
				(arc
					(start 319.072514 -345.465146)
					(mid 318.368934 -345.465146)
					(end 319.072514 -345.465146)
				)
			)
		)
	)
	(zone
		(layers "B.Cu" "In15.Cu")
		(hatch none 0.5)
		(connect_pads
			(clearance 0)
		)
		(min_thickness 0.25)
		(keepout
			(tracks not_allowed)
			(vias allowed)
			(pads allowed)
			(copperpour not_allowed)
			(footprints allowed)
		)
		(placement
			(enabled no)
			(sheetname "")
		)
		(fill yes
			(thermal_gap 0.5)
			(thermal_bridge_width 0.5)
			(island_removal_mode 0)
		)
		(polygon
			(pts
				(arc
					(start 81.241392 -345.465146)
					(mid 80.537812 -345.465146)
					(end 81.241392 -345.465146)
				)
			)
		)
	)
	(zone
		(layers "B.Cu" "In15.Cu")
		(hatch none 0.5)
		(connect_pads
			(clearance 0)
		)
		(min_thickness 0.25)
		(keepout
			(tracks not_allowed)
			(vias allowed)
			(pads allowed)
			(copperpour not_allowed)
			(footprints allowed)
		)
		(placement
			(enabled no)
			(sheetname "")
		)
		(fill yes
			(thermal_gap 0.5)
			(thermal_bridge_width 0.5)
			(island_removal_mode 0)
		)
		(polygon
			(pts
				(arc
					(start 415.876232 -313.949842)
					(mid 415.223452 -313.949842)
					(end 415.876232 -313.949842)
				)
			)
		)
	)
	(zone
		(layers "B.Cu" "In15.Cu")
		(hatch none 0.5)
		(connect_pads
			(clearance 0)
		)
		(min_thickness 0.25)
		(keepout
			(tracks not_allowed)
			(vias allowed)
			(pads allowed)
			(copperpour not_allowed)
			(footprints allowed)
		)
		(placement
			(enabled no)
			(sheetname "")
		)
		(fill yes
			(thermal_gap 0.5)
			(thermal_bridge_width 0.5)
			(island_removal_mode 0)
		)
		(polygon
			(pts
				(arc
					(start 403.49297 -357.75773)
					(mid 402.78939 -357.75773)
					(end 403.49297 -357.75773)
				)
			)
		)
	)
	(zone
		(layers "B.Cu" "In15.Cu")
		(hatch none 0.5)
		(connect_pads
			(clearance 0)
		)
		(min_thickness 0.25)
		(keepout
			(tracks not_allowed)
			(vias allowed)
			(pads allowed)
			(copperpour not_allowed)
			(footprints allowed)
		)
		(placement
			(enabled no)
			(sheetname "")
		)
		(fill yes
			(thermal_gap 0.5)
			(thermal_bridge_width 0.5)
			(island_removal_mode 0)
		)
		(polygon
			(pts
				(arc
					(start 118.431818 -345.465146)
					(mid 117.728238 -345.465146)
					(end 118.431818 -345.465146)
				)
			)
		)
	)
	(zone
		(layers "B.Cu" "In15.Cu")
		(hatch none 0.5)
		(connect_pads
			(clearance 0)
		)
		(min_thickness 0.25)
		(keepout
			(tracks not_allowed)
			(vias allowed)
			(pads allowed)
			(copperpour not_allowed)
			(footprints allowed)
		)
		(placement
			(enabled no)
			(sheetname "")
		)
		(fill yes
			(thermal_gap 0.5)
			(thermal_bridge_width 0.5)
			(island_removal_mode 0)
		)
		(polygon
			(pts
				(arc
					(start 389.06958 -378.290074)
					(mid 388.31012 -378.290074)
					(end 389.06958 -378.290074)
				)
			)
		)
	)
	(zone
		(layers "B.Cu" "In15.Cu")
		(hatch none 0.5)
		(connect_pads
			(clearance 0)
		)
		(min_thickness 0.25)
		(keepout
			(tracks not_allowed)
			(vias allowed)
			(pads allowed)
			(copperpour not_allowed)
			(footprints allowed)
		)
		(placement
			(enabled no)
			(sheetname "")
		)
		(fill yes
			(thermal_gap 0.5)
			(thermal_bridge_width 0.5)
			(island_removal_mode 0)
		)
		(polygon
			(pts
				(arc
					(start 331.869796 -408.190192)
					(mid 331.110336 -408.190192)
					(end 331.869796 -408.190192)
				)
			)
		)
	)
	(zone
		(layers "B.Cu" "In15.Cu")
		(hatch none 0.5)
		(connect_pads
			(clearance 0)
		)
		(min_thickness 0.25)
		(keepout
			(tracks not_allowed)
			(vias allowed)
			(pads allowed)
			(copperpour not_allowed)
			(footprints allowed)
		)
		(placement
			(enabled no)
			(sheetname "")
		)
		(fill yes
			(thermal_gap 0.5)
			(thermal_bridge_width 0.5)
			(island_removal_mode 0)
		)
		(polygon
			(pts
				(arc
					(start 86.595712 -345.465146)
					(mid 85.892132 -345.465146)
					(end 86.595712 -345.465146)
				)
			)
		)
	)
	(zone
		(layers "B.Cu" "In15.Cu")
		(hatch none 0.5)
		(connect_pads
			(clearance 0)
		)
		(min_thickness 0.25)
		(keepout
			(tracks not_allowed)
			(vias allowed)
			(pads allowed)
			(copperpour not_allowed)
			(footprints allowed)
		)
		(placement
			(enabled no)
			(sheetname "")
		)
		(fill yes
			(thermal_gap 0.5)
			(thermal_bridge_width 0.5)
			(island_removal_mode 0)
		)
		(polygon
			(pts
				(arc
					(start 93.677232 -345.465146)
					(mid 92.973652 -345.465146)
					(end 93.677232 -345.465146)
				)
			)
		)
	)
	(zone
		(layers "B.Cu" "In15.Cu")
		(hatch none 0.5)
		(connect_pads
			(clearance 0)
		)
		(min_thickness 0.25)
		(keepout
			(tracks not_allowed)
			(vias allowed)
			(pads allowed)
			(copperpour not_allowed)
			(footprints allowed)
		)
		(placement
			(enabled no)
			(sheetname "")
		)
		(fill yes
			(thermal_gap 0.5)
			(thermal_bridge_width 0.5)
			(island_removal_mode 0)
		)
		(polygon
			(pts
				(arc
					(start 144.167098 -354.732082)
					(mid 143.463518 -354.732082)
					(end 144.167098 -354.732082)
				)
			)
		)
	)
	(zone
		(layers "B.Cu" "In15.Cu")
		(hatch none 0.5)
		(connect_pads
			(clearance 0)
		)
		(min_thickness 0.25)
		(keepout
			(tracks not_allowed)
			(vias allowed)
			(pads allowed)
			(copperpour not_allowed)
			(footprints allowed)
		)
		(placement
			(enabled no)
			(sheetname "")
		)
		(fill yes
			(thermal_gap 0.5)
			(thermal_bridge_width 0.5)
			(island_removal_mode 0)
		)
		(polygon
			(pts
				(arc
					(start 76.689712 -408.190192)
					(mid 75.930252 -408.190192)
					(end 76.689712 -408.190192)
				)
			)
		)
	)
	(zone
		(layers "B.Cu" "In15.Cu")
		(hatch none 0.5)
		(connect_pads
			(clearance 0)
		)
		(min_thickness 0.25)
		(keepout
			(tracks not_allowed)
			(vias allowed)
			(pads allowed)
			(copperpour not_allowed)
			(footprints allowed)
		)
		(placement
			(enabled no)
			(sheetname "")
		)
		(fill yes
			(thermal_gap 0.5)
			(thermal_bridge_width 0.5)
			(island_removal_mode 0)
		)
		(polygon
			(pts
				(arc
					(start 80.377792 -354.732082)
					(mid 79.674212 -354.732082)
					(end 80.377792 -354.732082)
				)
			)
		)
	)
	(zone
		(layers "B.Cu" "In15.Cu")
		(hatch none 0.5)
		(connect_pads
			(clearance 0)
		)
		(min_thickness 0.25)
		(keepout
			(tracks not_allowed)
			(vias allowed)
			(pads allowed)
			(copperpour not_allowed)
			(footprints allowed)
		)
		(placement
			(enabled no)
			(sheetname "")
		)
		(fill yes
			(thermal_gap 0.5)
			(thermal_bridge_width 0.5)
			(island_removal_mode 0)
		)
		(polygon
			(pts
				(arc
					(start 68.805552 -342.439498)
					(mid 68.101972 -342.439498)
					(end 68.805552 -342.439498)
				)
			)
		)
	)
	(zone
		(layers "B.Cu" "In15.Cu")
		(hatch none 0.5)
		(connect_pads
			(clearance 0)
		)
		(min_thickness 0.25)
		(keepout
			(tracks not_allowed)
			(vias allowed)
			(pads allowed)
			(copperpour not_allowed)
			(footprints allowed)
		)
		(placement
			(enabled no)
			(sheetname "")
		)
		(fill yes
			(thermal_gap 0.5)
			(thermal_bridge_width 0.5)
			(island_removal_mode 0)
		)
		(polygon
			(pts
				(arc
					(start 378.069602 -410.589984)
					(mid 377.310142 -410.589984)
					(end 378.069602 -410.589984)
				)
			)
		)
	)
	(zone
		(layers "B.Cu" "In15.Cu")
		(hatch none 0.5)
		(connect_pads
			(clearance 0)
		)
		(min_thickness 0.25)
		(keepout
			(tracks not_allowed)
			(vias allowed)
			(pads allowed)
			(copperpour not_allowed)
			(footprints allowed)
		)
		(placement
			(enabled no)
			(sheetname "")
		)
		(fill yes
			(thermal_gap 0.5)
			(thermal_bridge_width 0.5)
			(island_removal_mode 0)
		)
		(polygon
			(pts
				(arc
					(start 84.350352 -348.58579)
					(mid 83.646772 -348.58579)
					(end 84.350352 -348.58579)
				)
			)
		)
	)
	(zone
		(layers "B.Cu" "In15.Cu")
		(hatch none 0.5)
		(connect_pads
			(clearance 0)
		)
		(min_thickness 0.25)
		(keepout
			(tracks not_allowed)
			(vias allowed)
			(pads allowed)
			(copperpour not_allowed)
			(footprints allowed)
		)
		(placement
			(enabled no)
			(sheetname "")
		)
		(fill yes
			(thermal_gap 0.5)
			(thermal_bridge_width 0.5)
			(island_removal_mode 0)
		)
		(polygon
			(pts
				(arc
					(start 127.758698 -351.611438)
					(mid 127.055118 -351.611438)
					(end 127.758698 -351.611438)
				)
			)
		)
	)
	(zone
		(layers "B.Cu" "In15.Cu")
		(hatch none 0.5)
		(connect_pads
			(clearance 0)
		)
		(min_thickness 0.25)
		(keepout
			(tracks not_allowed)
			(vias allowed)
			(pads allowed)
			(copperpour not_allowed)
			(footprints allowed)
		)
		(placement
			(enabled no)
			(sheetname "")
		)
		(fill yes
			(thermal_gap 0.5)
			(thermal_bridge_width 0.5)
			(island_removal_mode 0)
		)
		(polygon
			(pts
				(arc
					(start 325.290434 -342.439498)
					(mid 324.586854 -342.439498)
					(end 325.290434 -342.439498)
				)
			)
		)
	)
	(zone
		(layers "B.Cu" "In15.Cu")
		(hatch none 0.5)
		(connect_pads
			(clearance 0)
		)
		(min_thickness 0.25)
		(keepout
			(tracks not_allowed)
			(vias allowed)
			(pads allowed)
			(copperpour not_allowed)
			(footprints allowed)
		)
		(placement
			(enabled no)
			(sheetname "")
		)
		(fill yes
			(thermal_gap 0.5)
			(thermal_bridge_width 0.5)
			(island_removal_mode 0)
		)
		(polygon
			(pts
				(arc
					(start 336.269838 -383.490216)
					(mid 335.510378 -383.490216)
					(end 336.269838 -383.490216)
				)
			)
		)
	)
	(zone
		(layers "B.Cu" "In15.Cu")
		(hatch none 0.5)
		(connect_pads
			(clearance 0)
		)
		(min_thickness 0.25)
		(keepout
			(tracks not_allowed)
			(vias allowed)
			(pads allowed)
			(copperpour not_allowed)
			(footprints allowed)
		)
		(placement
			(enabled no)
			(sheetname "")
		)
		(fill yes
			(thermal_gap 0.5)
			(thermal_bridge_width 0.5)
			(island_removal_mode 0)
		)
		(polygon
			(pts
				(arc
					(start 319.936114 -357.75773)
					(mid 319.232534 -357.75773)
					(end 319.936114 -357.75773)
				)
			)
		)
	)
	(zone
		(layers "B.Cu" "In15.Cu")
		(hatch none 0.5)
		(connect_pads
			(clearance 0)
		)
		(min_thickness 0.25)
		(keepout
			(tracks not_allowed)
			(vias allowed)
			(pads allowed)
			(copperpour not_allowed)
			(footprints allowed)
		)
		(placement
			(enabled no)
			(sheetname "")
		)
		(fill yes
			(thermal_gap 0.5)
			(thermal_bridge_width 0.5)
			(island_removal_mode 0)
		)
		(polygon
			(pts
				(arc
					(start 187.476384 -313.949842)
					(mid 186.823604 -313.949842)
					(end 187.476384 -313.949842)
				)
			)
		)
	)
	(zone
		(layers "B.Cu" "In15.Cu")
		(hatch none 0.5)
		(connect_pads
			(clearance 0)
		)
		(min_thickness 0.25)
		(keepout
			(tracks not_allowed)
			(vias allowed)
			(pads allowed)
			(copperpour not_allowed)
			(footprints allowed)
		)
		(placement
			(enabled no)
			(sheetname "")
		)
		(fill yes
			(thermal_gap 0.5)
			(thermal_bridge_width 0.5)
			(island_removal_mode 0)
		)
		(polygon
			(pts
				(arc
					(start 338.469732 -409.290012)
					(mid 337.710272 -409.290012)
					(end 338.469732 -409.290012)
				)
			)
		)
	)
	(zone
		(layers "B.Cu" "In15.Cu")
		(hatch none 0.5)
		(connect_pads
			(clearance 0)
		)
		(min_thickness 0.25)
		(keepout
			(tracks not_allowed)
			(vias allowed)
			(pads allowed)
			(copperpour not_allowed)
			(footprints allowed)
		)
		(placement
			(enabled no)
			(sheetname "")
		)
		(fill yes
			(thermal_gap 0.5)
			(thermal_bridge_width 0.5)
			(island_removal_mode 0)
		)
		(polygon
			(pts
				(arc
					(start 161.826448 -312.049922)
					(mid 161.173668 -312.049922)
					(end 161.826448 -312.049922)
				)
			)
		)
	)
	(zone
		(layers "B.Cu" "In15.Cu")
		(hatch none 0.5)
		(connect_pads
			(clearance 0)
		)
		(min_thickness 0.25)
		(keepout
			(tracks not_allowed)
			(vias allowed)
			(pads allowed)
			(copperpour not_allowed)
			(footprints allowed)
		)
		(placement
			(enabled no)
			(sheetname "")
		)
		(fill yes
			(thermal_gap 0.5)
			(thermal_bridge_width 0.5)
			(island_removal_mode 0)
		)
		(polygon
			(pts
				(arc
					(start 399.52041 -351.611438)
					(mid 398.81683 -351.611438)
					(end 399.52041 -351.611438)
				)
			)
		)
	)
	(zone
		(layers "B.Cu" "In15.Cu")
		(hatch none 0.5)
		(connect_pads
			(clearance 0)
		)
		(min_thickness 0.25)
		(keepout
			(tracks not_allowed)
			(vias allowed)
			(pads allowed)
			(copperpour not_allowed)
			(footprints allowed)
		)
		(placement
			(enabled no)
			(sheetname "")
		)
		(fill yes
			(thermal_gap 0.5)
			(thermal_bridge_width 0.5)
			(island_removal_mode 0)
		)
		(polygon
			(pts
				(arc
					(start 125.513338 -345.465146)
					(mid 124.809758 -345.465146)
					(end 125.513338 -345.465146)
				)
			)
		)
	)
	(zone
		(layers "B.Cu" "In15.Cu")
		(hatch none 0.5)
		(connect_pads
			(clearance 0)
		)
		(min_thickness 0.25)
		(keepout
			(tracks not_allowed)
			(vias allowed)
			(pads allowed)
			(copperpour not_allowed)
			(footprints allowed)
		)
		(placement
			(enabled no)
			(sheetname "")
		)
		(fill yes
			(thermal_gap 0.5)
			(thermal_bridge_width 0.5)
			(island_removal_mode 0)
		)
		(polygon
			(pts
				(arc
					(start 343.944194 -357.75773)
					(mid 343.240614 -357.75773)
					(end 343.944194 -357.75773)
				)
			)
		)
	)
	(zone
		(layers "B.Cu" "In15.Cu")
		(hatch none 0.5)
		(connect_pads
			(clearance 0)
		)
		(min_thickness 0.25)
		(keepout
			(tracks not_allowed)
			(vias allowed)
			(pads allowed)
			(copperpour not_allowed)
			(footprints allowed)
		)
		(placement
			(enabled no)
			(sheetname "")
		)
		(fill yes
			(thermal_gap 0.5)
			(thermal_bridge_width 0.5)
			(island_removal_mode 0)
		)
		(polygon
			(pts
				(arc
					(start 67.941952 -354.732082)
					(mid 67.238372 -354.732082)
					(end 67.941952 -354.732082)
				)
			)
		)
	)
	(zone
		(layers "B.Cu" "In15.Cu")
		(hatch none 0.5)
		(connect_pads
			(clearance 0)
		)
		(min_thickness 0.25)
		(keepout
			(tracks not_allowed)
			(vias allowed)
			(pads allowed)
			(copperpour not_allowed)
			(footprints allowed)
		)
		(placement
			(enabled no)
			(sheetname "")
		)
		(fill yes
			(thermal_gap 0.5)
			(thermal_bridge_width 0.5)
			(island_removal_mode 0)
		)
		(polygon
			(pts
				(arc
					(start 141.058138 -348.58579)
					(mid 140.354558 -348.58579)
					(end 141.058138 -348.58579)
				)
			)
		)
	)
	(zone
		(layers "B.Cu" "In15.Cu")
		(hatch none 0.5)
		(connect_pads
			(clearance 0)
		)
		(min_thickness 0.25)
		(keepout
			(tracks not_allowed)
			(vias allowed)
			(pads allowed)
			(copperpour not_allowed)
			(footprints allowed)
		)
		(placement
			(enabled no)
			(sheetname "")
		)
		(fill yes
			(thermal_gap 0.5)
			(thermal_bridge_width 0.5)
			(island_removal_mode 0)
		)
		(polygon
			(pts
				(arc
					(start 334.617314 -351.611438)
					(mid 333.913734 -351.611438)
					(end 334.617314 -351.611438)
				)
			)
		)
	)
	(zone
		(layers "B.Cu" "In15.Cu")
		(hatch none 0.5)
		(connect_pads
			(clearance 0)
		)
		(min_thickness 0.25)
		(keepout
			(tracks not_allowed)
			(vias allowed)
			(pads allowed)
			(copperpour not_allowed)
			(footprints allowed)
		)
		(placement
			(enabled no)
			(sheetname "")
		)
		(fill yes
			(thermal_gap 0.5)
			(thermal_bridge_width 0.5)
			(island_removal_mode 0)
		)
		(polygon
			(pts
				(arc
					(start 396.87627 -313.949842)
					(mid 396.22349 -313.949842)
					(end 396.87627 -313.949842)
				)
			)
		)
	)
	(zone
		(layers "B.Cu" "In15.Cu")
		(hatch none 0.5)
		(connect_pads
			(clearance 0)
		)
		(min_thickness 0.25)
		(keepout
			(tracks not_allowed)
			(vias allowed)
			(pads allowed)
			(copperpour not_allowed)
			(footprints allowed)
		)
		(placement
			(enabled no)
			(sheetname "")
		)
		(fill yes
			(thermal_gap 0.5)
			(thermal_bridge_width 0.5)
			(island_removal_mode 0)
		)
		(polygon
			(pts
				(arc
					(start 121.540778 -351.611438)
					(mid 120.837198 -351.611438)
					(end 121.540778 -351.611438)
				)
			)
		)
	)
	(zone
		(layers "B.Cu" "In15.Cu")
		(hatch none 0.5)
		(connect_pads
			(clearance 0)
		)
		(min_thickness 0.25)
		(keepout
			(tracks not_allowed)
			(vias allowed)
			(pads allowed)
			(copperpour not_allowed)
			(footprints allowed)
		)
		(placement
			(enabled no)
			(sheetname "")
		)
		(fill yes
			(thermal_gap 0.5)
			(thermal_bridge_width 0.5)
			(island_removal_mode 0)
		)
		(polygon
			(pts
				(arc
					(start 53.326284 -311.099962)
					(mid 52.673504 -311.099962)
					(end 53.326284 -311.099962)
				)
			)
		)
	)
	(zone
		(layers "B.Cu" "In15.Cu")
		(hatch none 0.5)
		(connect_pads
			(clearance 0)
		)
		(min_thickness 0.25)
		(keepout
			(tracks not_allowed)
			(vias allowed)
			(pads allowed)
			(copperpour not_allowed)
			(footprints allowed)
		)
		(placement
			(enabled no)
			(sheetname "")
		)
		(fill yes
			(thermal_gap 0.5)
			(thermal_bridge_width 0.5)
			(island_removal_mode 0)
		)
		(polygon
			(pts
				(arc
					(start 93.677232 -354.732082)
					(mid 92.973652 -354.732082)
					(end 93.677232 -354.732082)
				)
			)
		)
	)
	(zone
		(layer "In1.Cu")
		(hatch none 0.5)
		(connect_pads
			(clearance 0)
		)
		(min_thickness 0.25)
		(keepout
			(tracks not_allowed)
			(vias allowed)
			(pads allowed)
			(copperpour not_allowed)
			(footprints allowed)
		)
		(placement
			(enabled no)
			(sheetname "")
		)
		(fill
			(thermal_gap 0.5)
			(thermal_bridge_width 0.5)
			(island_removal_mode 0)
		)
		(polygon
			(pts
				(arc
					(start 434.001418 -355.825806)
					(mid 433.965497 -355.840685)
					(end 433.950618 -355.876606)
				)
				(arc
					(start 433.950618 -356.613206)
					(mid 433.965497 -356.649127)
					(end 434.001418 -356.664006)
				)
				(xy 434.245258 -356.664006) (xy 434.599588 -356.431596) (xy 434.955188 -356.664006)
				(arc
					(start 435.197758 -356.664006)
					(mid 435.233679 -356.649127)
					(end 435.248558 -356.613206)
				)
				(arc
					(start 435.248558 -355.876606)
					(mid 435.233679 -355.840685)
					(end 435.197758 -355.825806)
				)
				(xy 434.955188 -355.825806) (xy 434.598318 -356.058216) (xy 434.243988 -355.825806)
			)
		)
	)
	(zone
		(layer "In1.Cu")
		(hatch none 0.5)
		(connect_pads
			(clearance 0)
		)
		(min_thickness 0.25)
		(keepout
			(tracks not_allowed)
			(vias allowed)
			(pads allowed)
			(copperpour not_allowed)
			(footprints allowed)
		)
		(placement
			(enabled no)
			(sheetname "")
		)
		(fill
			(thermal_gap 0.5)
			(thermal_bridge_width 0.5)
			(island_removal_mode 0)
		)
		(polygon
			(pts
				(arc
					(start 64.315848 -355.825806)
					(mid 64.279927 -355.840685)
					(end 64.265048 -355.876606)
				)
				(arc
					(start 64.265048 -356.613206)
					(mid 64.279927 -356.649127)
					(end 64.315848 -356.664006)
				)
				(xy 64.559688 -356.664006) (xy 64.914018 -356.431596) (xy 65.269618 -356.664006)
				(arc
					(start 65.512188 -356.664006)
					(mid 65.548109 -356.649127)
					(end 65.562988 -356.613206)
				)
				(arc
					(start 65.562988 -355.876606)
					(mid 65.548109 -355.840685)
					(end 65.512188 -355.825806)
				)
				(xy 65.269618 -355.825806) (xy 64.912748 -356.058216) (xy 64.558418 -355.825806)
			)
		)
	)
	(zone
		(layer "In1.Cu")
		(hatch none 0.5)
		(connect_pads
			(clearance 0)
		)
		(min_thickness 0.25)
		(keepout
			(tracks not_allowed)
			(vias allowed)
			(pads allowed)
			(copperpour not_allowed)
			(footprints allowed)
		)
		(placement
			(enabled no)
			(sheetname "")
		)
		(fill
			(thermal_gap 0.5)
			(thermal_bridge_width 0.5)
			(island_removal_mode 0)
		)
		(polygon
			(pts
				(arc
					(start 167.351964 -107.448096)
					(mid 167.337085 -107.484017)
					(end 167.301164 -107.498896)
				)
				(arc
					(start 166.120064 -107.498896)
					(mid 166.084143 -107.484017)
					(end 166.069264 -107.448096)
				)
				(arc
					(start 166.069264 -106.441748)
					(mid 166.084143 -106.405827)
					(end 166.120064 -106.390948)
				)
				(arc
					(start 167.301164 -106.390948)
					(mid 167.337085 -106.405827)
					(end 167.351964 -106.441748)
				)
			)
		)
	)
	(zone
		(layer "In1.Cu")
		(hatch none 0.5)
		(connect_pads
			(clearance 0)
		)
		(min_thickness 0.25)
		(keepout
			(tracks not_allowed)
			(vias allowed)
			(pads allowed)
			(copperpour not_allowed)
			(footprints allowed)
		)
		(placement
			(enabled no)
			(sheetname "")
		)
		(fill
			(thermal_gap 0.5)
			(thermal_bridge_width 0.5)
			(island_removal_mode 0)
		)
		(polygon
			(pts
				(arc
					(start 326.099678 -31.006034)
					(mid 326.084799 -31.041955)
					(end 326.048878 -31.056834)
				)
				(arc
					(start 324.816978 -31.056834)
					(mid 324.781057 -31.041955)
					(end 324.766178 -31.006034)
				)
				(arc
					(start 324.766178 -29.974286)
					(mid 324.781057 -29.938365)
					(end 324.816978 -29.923486)
				)
				(arc
					(start 326.048878 -29.923486)
					(mid 326.084799 -29.938365)
					(end 326.099678 -29.974286)
				)
			)
		)
	)
	(zone
		(layer "In1.Cu")
		(hatch none 0.5)
		(connect_pads
			(clearance 0)
		)
		(min_thickness 0.25)
		(keepout
			(tracks not_allowed)
			(vias allowed)
			(pads allowed)
			(copperpour not_allowed)
			(footprints allowed)
		)
		(placement
			(enabled no)
			(sheetname "")
		)
		(fill
			(thermal_gap 0.5)
			(thermal_bridge_width 0.5)
			(island_removal_mode 0)
		)
		(polygon
			(pts
				(arc
					(start 86.078568 -343.533222)
					(mid 86.042647 -343.548101)
					(end 86.027768 -343.584022)
				)
				(arc
					(start 86.027768 -344.320622)
					(mid 86.042647 -344.356543)
					(end 86.078568 -344.371422)
				)
				(xy 86.322408 -344.371422) (xy 86.676738 -344.139012) (xy 87.032338 -344.371422)
				(arc
					(start 87.274908 -344.371422)
					(mid 87.310829 -344.356543)
					(end 87.325708 -344.320622)
				)
				(arc
					(start 87.325708 -343.584022)
					(mid 87.310829 -343.548101)
					(end 87.274908 -343.533222)
				)
				(xy 87.032338 -343.533222) (xy 86.675468 -343.765632) (xy 86.321138 -343.533222)
			)
		)
	)
	(zone
		(layer "In1.Cu")
		(hatch none 0.5)
		(connect_pads
			(clearance 0)
		)
		(min_thickness 0.25)
		(keepout
			(tracks not_allowed)
			(vias allowed)
			(pads allowed)
			(copperpour not_allowed)
			(footprints allowed)
		)
		(placement
			(enabled no)
			(sheetname "")
		)
		(fill
			(thermal_gap 0.5)
			(thermal_bridge_width 0.5)
			(island_removal_mode 0)
		)
		(polygon
			(pts
				(arc
					(start 318.55537 -349.679514)
					(mid 318.519449 -349.694393)
					(end 318.50457 -349.730314)
				)
				(arc
					(start 318.50457 -350.466914)
					(mid 318.519449 -350.502835)
					(end 318.55537 -350.517714)
				)
				(xy 318.79921 -350.517714) (xy 319.15354 -350.285304) (xy 319.50914 -350.517714)
				(arc
					(start 319.75171 -350.517714)
					(mid 319.787631 -350.502835)
					(end 319.80251 -350.466914)
				)
				(arc
					(start 319.80251 -349.730314)
					(mid 319.787631 -349.694393)
					(end 319.75171 -349.679514)
				)
				(xy 319.50914 -349.679514) (xy 319.15227 -349.911924) (xy 318.79794 -349.679514)
			)
		)
	)
	(zone
		(layer "In1.Cu")
		(hatch none 0.5)
		(connect_pads
			(clearance 0)
		)
		(min_thickness 0.25)
		(keepout
			(tracks not_allowed)
			(vias allowed)
			(pads allowed)
			(copperpour not_allowed)
			(footprints allowed)
		)
		(placement
			(enabled no)
			(sheetname "")
		)
		(fill
			(thermal_gap 0.5)
			(thermal_bridge_width 0.5)
			(island_removal_mode 0)
		)
		(polygon
			(pts
				(arc
					(start 189.967108 -147.158202)
					(mid 189.952229 -147.194123)
					(end 189.916308 -147.209002)
				)
				(arc
					(start 188.735208 -147.209002)
					(mid 188.699287 -147.194123)
					(end 188.684408 -147.158202)
				)
				(arc
					(start 188.684408 -146.151854)
					(mid 188.699287 -146.115933)
					(end 188.735208 -146.101054)
				)
				(arc
					(start 189.916308 -146.101054)
					(mid 189.952229 -146.115933)
					(end 189.967108 -146.151854)
				)
			)
		)
	)
	(zone
		(layer "In1.Cu")
		(hatch none 0.5)
		(connect_pads
			(clearance 0)
		)
		(min_thickness 0.25)
		(keepout
			(tracks not_allowed)
			(vias allowed)
			(pads allowed)
			(copperpour not_allowed)
			(footprints allowed)
		)
		(placement
			(enabled no)
			(sheetname "")
		)
		(fill
			(thermal_gap 0.5)
			(thermal_bridge_width 0.5)
			(island_removal_mode 0)
		)
		(polygon
			(pts
				(arc
					(start 56.398922 -362.729272)
					(mid 56.488725 -362.766469)
					(end 56.525922 -362.856272)
				)
				(arc
					(start 56.525922 -363.05744)
					(mid 56.488725 -363.147243)
					(end 56.398922 -363.18444)
				)
				(arc
					(start 56.144922 -363.18444)
					(mid 56.055119 -363.147243)
					(end 56.017922 -363.05744)
				)
				(arc
					(start 56.017922 -362.856272)
					(mid 56.055119 -362.766469)
					(end 56.144922 -362.729272)
				)
			)
		)
	)
	(zone
		(layer "In1.Cu")
		(hatch none 0.5)
		(connect_pads
			(clearance 0)
		)
		(min_thickness 0.25)
		(keepout
			(tracks not_allowed)
			(vias allowed)
			(pads allowed)
			(copperpour not_allowed)
			(footprints allowed)
		)
		(placement
			(enabled no)
			(sheetname "")
		)
		(fill
			(thermal_gap 0.5)
			(thermal_bridge_width 0.5)
			(island_removal_mode 0)
		)
		(polygon
			(pts
				(arc
					(start 324.77329 -355.825806)
					(mid 324.737369 -355.840685)
					(end 324.72249 -355.876606)
				)
				(arc
					(start 324.72249 -356.613206)
					(mid 324.737369 -356.649127)
					(end 324.77329 -356.664006)
				)
				(xy 325.01713 -356.664006) (xy 325.37146 -356.431596) (xy 325.72706 -356.664006)
				(arc
					(start 325.96963 -356.664006)
					(mid 326.005551 -356.649127)
					(end 326.02043 -356.613206)
				)
				(arc
					(start 326.02043 -355.876606)
					(mid 326.005551 -355.840685)
					(end 325.96963 -355.825806)
				)
				(xy 325.72706 -355.825806) (xy 325.37019 -356.058216) (xy 325.01586 -355.825806)
			)
		)
	)
	(zone
		(layer "In1.Cu")
		(hatch none 0.5)
		(connect_pads
			(clearance 0)
		)
		(min_thickness 0.25)
		(keepout
			(tracks not_allowed)
			(vias allowed)
			(pads allowed)
			(copperpour not_allowed)
			(footprints allowed)
		)
		(placement
			(enabled no)
			(sheetname "")
		)
		(fill
			(thermal_gap 0.5)
			(thermal_bridge_width 0.5)
			(island_removal_mode 0)
		)
		(polygon
			(pts
				(arc
					(start 390.19988 -29.205936)
					(mid 390.185001 -29.241857)
					(end 390.14908 -29.256736)
				)
				(arc
					(start 388.91718 -29.256736)
					(mid 388.881259 -29.241857)
					(end 388.86638 -29.205936)
				)
				(arc
					(start 388.86638 -28.174188)
					(mid 388.881259 -28.138267)
					(end 388.91718 -28.123388)
				)
				(arc
					(start 390.14908 -28.123388)
					(mid 390.185001 -28.138267)
					(end 390.19988 -28.174188)
				)
			)
		)
	)
	(zone
		(layer "In1.Cu")
		(hatch none 0.5)
		(connect_pads
			(clearance 0)
		)
		(min_thickness 0.25)
		(keepout
			(tracks not_allowed)
			(vias allowed)
			(pads allowed)
			(copperpour not_allowed)
			(footprints allowed)
		)
		(placement
			(enabled no)
			(sheetname "")
		)
		(fill
			(thermal_gap 0.5)
			(thermal_bridge_width 0.5)
			(island_removal_mode 0)
		)
		(polygon
			(pts
				(arc
					(start 277.632668 -101.041962)
					(mid 277.647547 -101.006041)
					(end 277.683468 -100.991162)
				)
				(arc
					(start 278.864568 -100.991162)
					(mid 278.900489 -101.006041)
					(end 278.915368 -101.041962)
				)
				(arc
					(start 278.915368 -102.04831)
					(mid 278.900489 -102.084231)
					(end 278.864568 -102.09911)
				)
				(arc
					(start 277.683468 -102.09911)
					(mid 277.647547 -102.084231)
					(end 277.632668 -102.04831)
				)
			)
		)
	)
	(zone
		(layer "In1.Cu")
		(hatch none 0.5)
		(connect_pads
			(clearance 0)
		)
		(min_thickness 0.25)
		(keepout
			(tracks not_allowed)
			(vias allowed)
			(pads allowed)
			(copperpour not_allowed)
			(footprints allowed)
		)
		(placement
			(enabled no)
			(sheetname "")
		)
		(fill
			(thermal_gap 0.5)
			(thermal_bridge_width 0.5)
			(island_removal_mode 0)
		)
		(polygon
			(pts
				(arc
					(start 188.115448 -34.68624)
					(mid 188.130327 -34.722161)
					(end 188.166248 -34.73704)
				)
				(arc
					(start 188.902848 -34.73704)
					(mid 188.938769 -34.722161)
					(end 188.953648 -34.68624)
				)
				(xy 188.953648 -34.4424) (xy 188.721238 -34.08807) (xy 188.953648 -33.73247)
				(arc
					(start 188.953648 -33.4899)
					(mid 188.938769 -33.453979)
					(end 188.902848 -33.4391)
				)
				(arc
					(start 188.166248 -33.4391)
					(mid 188.130327 -33.453979)
					(end 188.115448 -33.4899)
				)
				(xy 188.115448 -33.73247) (xy 188.347858 -34.08934) (xy 188.115448 -34.44367)
			)
		)
	)
	(zone
		(layer "In1.Cu")
		(hatch none 0.5)
		(connect_pads
			(clearance 0)
		)
		(min_thickness 0.25)
		(keepout
			(tracks not_allowed)
			(vias allowed)
			(pads allowed)
			(copperpour not_allowed)
			(footprints allowed)
		)
		(placement
			(enabled no)
			(sheetname "")
		)
		(fill
			(thermal_gap 0.5)
			(thermal_bridge_width 0.5)
			(island_removal_mode 0)
		)
		(polygon
			(pts
				(arc
					(start 277.632668 -124.551948)
					(mid 277.647547 -124.516027)
					(end 277.683468 -124.501148)
				)
				(arc
					(start 278.864568 -124.501148)
					(mid 278.900489 -124.516027)
					(end 278.915368 -124.551948)
				)
				(arc
					(start 278.915368 -125.558296)
					(mid 278.900489 -125.594217)
					(end 278.864568 -125.609096)
				)
				(arc
					(start 277.683468 -125.609096)
					(mid 277.647547 -125.594217)
					(end 277.632668 -125.558296)
				)
			)
		)
	)
	(zone
		(layer "In1.Cu")
		(hatch none 0.5)
		(connect_pads
			(clearance 0)
		)
		(min_thickness 0.25)
		(keepout
			(tracks not_allowed)
			(vias allowed)
			(pads allowed)
			(copperpour not_allowed)
			(footprints allowed)
		)
		(placement
			(enabled no)
			(sheetname "")
		)
		(fill
			(thermal_gap 0.5)
			(thermal_bridge_width 0.5)
			(island_removal_mode 0)
		)
		(polygon
			(pts
				(arc
					(start 104.247442 -389.424418)
					(mid 104.262321 -389.388497)
					(end 104.298242 -389.373618)
				)
				(arc
					(start 104.95534 -389.373618)
					(mid 104.991261 -389.388497)
					(end 105.00614 -389.424418)
				)
				(arc
					(start 105.00614 -390.064752)
					(mid 104.991261 -390.100673)
					(end 104.95534 -390.115552)
				)
				(arc
					(start 104.298242 -390.115552)
					(mid 104.262321 -390.100673)
					(end 104.247442 -390.064752)
				)
			)
		)
	)
	(zone
		(layer "In1.Cu")
		(hatch none 0.5)
		(connect_pads
			(clearance 0)
		)
		(min_thickness 0.25)
		(keepout
			(tracks not_allowed)
			(vias allowed)
			(pads allowed)
			(copperpour not_allowed)
			(footprints allowed)
		)
		(placement
			(enabled no)
			(sheetname "")
		)
		(fill
			(thermal_gap 0.5)
			(thermal_bridge_width 0.5)
			(island_removal_mode 0)
		)
		(polygon
			(pts
				(arc
					(start 171.347638 -355.825806)
					(mid 171.311717 -355.840685)
					(end 171.296838 -355.876606)
				)
				(arc
					(start 171.296838 -356.613206)
					(mid 171.311717 -356.649127)
					(end 171.347638 -356.664006)
				)
				(xy 171.591478 -356.664006) (xy 171.945808 -356.431596) (xy 172.301408 -356.664006)
				(arc
					(start 172.543978 -356.664006)
					(mid 172.579899 -356.649127)
					(end 172.594778 -356.613206)
				)
				(arc
					(start 172.594778 -355.876606)
					(mid 172.579899 -355.840685)
					(end 172.543978 -355.825806)
				)
				(xy 172.301408 -355.825806) (xy 171.944538 -356.058216) (xy 171.590208 -355.825806)
			)
		)
	)
	(zone
		(layer "In1.Cu")
		(hatch none 0.5)
		(connect_pads
			(clearance 0)
		)
		(min_thickness 0.25)
		(keepout
			(tracks not_allowed)
			(vias allowed)
			(pads allowed)
			(copperpour not_allowed)
			(footprints allowed)
		)
		(placement
			(enabled no)
			(sheetname "")
		)
		(fill
			(thermal_gap 0.5)
			(thermal_bridge_width 0.5)
			(island_removal_mode 0)
		)
		(polygon
			(pts
				(arc
					(start 41.89984 -31.006034)
					(mid 41.884961 -31.041955)
					(end 41.84904 -31.056834)
				)
				(arc
					(start 40.61714 -31.056834)
					(mid 40.581219 -31.041955)
					(end 40.56634 -31.006034)
				)
				(arc
					(start 40.56634 -29.974286)
					(mid 40.581219 -29.938365)
					(end 40.61714 -29.923486)
				)
				(arc
					(start 41.84904 -29.923486)
					(mid 41.884961 -29.938365)
					(end 41.89984 -29.974286)
				)
			)
		)
	)
	(zone
		(layer "In1.Cu")
		(hatch none 0.5)
		(connect_pads
			(clearance 0)
		)
		(min_thickness 0.25)
		(keepout
			(tracks not_allowed)
			(vias allowed)
			(pads allowed)
			(copperpour not_allowed)
			(footprints allowed)
		)
		(placement
			(enabled no)
			(sheetname "")
		)
		(fill
			(thermal_gap 0.5)
			(thermal_bridge_width 0.5)
			(island_removal_mode 0)
		)
		(polygon
			(pts
				(arc
					(start 283.452062 -131.368292)
					(mid 283.437183 -131.404213)
					(end 283.401262 -131.419092)
				)
				(arc
					(start 282.220162 -131.419092)
					(mid 282.184241 -131.404213)
					(end 282.169362 -131.368292)
				)
				(arc
					(start 282.169362 -130.361944)
					(mid 282.184241 -130.326023)
					(end 282.220162 -130.311144)
				)
				(arc
					(start 283.401262 -130.311144)
					(mid 283.437183 -130.326023)
					(end 283.452062 -130.361944)
				)
			)
		)
	)
	(zone
		(layer "In1.Cu")
		(hatch none 0.5)
		(connect_pads
			(clearance 0)
		)
		(min_thickness 0.25)
		(keepout
			(tracks not_allowed)
			(vias allowed)
			(pads allowed)
			(copperpour not_allowed)
			(footprints allowed)
		)
		(placement
			(enabled no)
			(sheetname "")
		)
		(fill
			(thermal_gap 0.5)
			(thermal_bridge_width 0.5)
			(island_removal_mode 0)
		)
		(polygon
			(pts
				(arc
					(start 306.067206 -145.358104)
					(mid 306.052327 -145.394025)
					(end 306.016406 -145.408904)
				)
				(arc
					(start 304.835306 -145.408904)
					(mid 304.799385 -145.394025)
					(end 304.784506 -145.358104)
				)
				(arc
					(start 304.784506 -144.351756)
					(mid 304.799385 -144.315835)
					(end 304.835306 -144.300956)
				)
				(arc
					(start 306.016406 -144.300956)
					(mid 306.052327 -144.315835)
					(end 306.067206 -144.351756)
				)
			)
		)
	)
	(zone
		(layer "In1.Cu")
		(hatch none 0.5)
		(connect_pads
			(clearance 0)
		)
		(min_thickness 0.25)
		(keepout
			(tracks not_allowed)
			(vias allowed)
			(pads allowed)
			(copperpour not_allowed)
			(footprints allowed)
		)
		(placement
			(enabled no)
			(sheetname "")
		)
		(fill
			(thermal_gap 0.5)
			(thermal_bridge_width 0.5)
			(island_removal_mode 0)
		)
		(polygon
			(pts
				(arc
					(start 98.015298 -31.086044)
					(mid 98.030177 -31.121965)
					(end 98.066098 -31.136844)
				)
				(arc
					(start 98.802698 -31.136844)
					(mid 98.838619 -31.121965)
					(end 98.853498 -31.086044)
				)
				(xy 98.853498 -30.842204) (xy 98.621088 -30.487874) (xy 98.853498 -30.132274)
				(arc
					(start 98.853498 -29.889704)
					(mid 98.838619 -29.853783)
					(end 98.802698 -29.838904)
				)
				(arc
					(start 98.066098 -29.838904)
					(mid 98.030177 -29.853783)
					(end 98.015298 -29.889704)
				)
				(xy 98.015298 -30.132274) (xy 98.247708 -30.489144) (xy 98.015298 -30.843474)
			)
		)
	)
	(zone
		(layer "In1.Cu")
		(hatch none 0.5)
		(connect_pads
			(clearance 0)
		)
		(min_thickness 0.25)
		(keepout
			(tracks not_allowed)
			(vias allowed)
			(pads allowed)
			(copperpour not_allowed)
			(footprints allowed)
		)
		(placement
			(enabled no)
			(sheetname "")
		)
		(fill
			(thermal_gap 0.5)
			(thermal_bridge_width 0.5)
			(island_removal_mode 0)
		)
		(polygon
			(pts
				(arc
					(start 239.493298 -83.824318)
					(mid 239.530495 -83.734515)
					(end 239.620298 -83.697318)
				)
				(arc
					(start 239.823498 -83.697318)
					(mid 239.913301 -83.734515)
					(end 239.950498 -83.824318)
				)
				(arc
					(start 239.950498 -84.078318)
					(mid 239.913301 -84.168121)
					(end 239.823498 -84.205318)
				)
				(arc
					(start 239.620298 -84.205318)
					(mid 239.530495 -84.168121)
					(end 239.493298 -84.078318)
				)
			)
		)
	)
	(zone
		(layer "In1.Cu")
		(hatch none 0.5)
		(connect_pads
			(clearance 0)
		)
		(min_thickness 0.25)
		(keepout
			(tracks not_allowed)
			(vias allowed)
			(pads allowed)
			(copperpour not_allowed)
			(footprints allowed)
		)
		(placement
			(enabled no)
			(sheetname "")
		)
		(fill
			(thermal_gap 0.5)
			(thermal_bridge_width 0.5)
			(island_removal_mode 0)
		)
		(polygon
			(pts
				(arc
					(start 371.022626 -343.533222)
					(mid 370.986705 -343.548101)
					(end 370.971826 -343.584022)
				)
				(arc
					(start 370.971826 -344.320622)
					(mid 370.986705 -344.356543)
					(end 371.022626 -344.371422)
				)
				(xy 371.266466 -344.371422) (xy 371.620796 -344.139012) (xy 371.976396 -344.371422)
				(arc
					(start 372.218966 -344.371422)
					(mid 372.254887 -344.356543)
					(end 372.269766 -344.320622)
				)
				(arc
					(start 372.269766 -343.584022)
					(mid 372.254887 -343.548101)
					(end 372.218966 -343.533222)
				)
				(xy 371.976396 -343.533222) (xy 371.619526 -343.765632) (xy 371.265196 -343.533222)
			)
		)
	)
	(zone
		(layer "In1.Cu")
		(hatch none 0.5)
		(connect_pads
			(clearance 0)
		)
		(min_thickness 0.25)
		(keepout
			(tracks not_allowed)
			(vias allowed)
			(pads allowed)
			(copperpour not_allowed)
			(footprints allowed)
		)
		(placement
			(enabled no)
			(sheetname "")
		)
		(fill
			(thermal_gap 0.5)
			(thermal_bridge_width 0.5)
			(island_removal_mode 0)
		)
		(polygon
			(pts
				(arc
					(start 300.09973 -31.006034)
					(mid 300.084851 -31.041955)
					(end 300.04893 -31.056834)
				)
				(arc
					(start 298.81703 -31.056834)
					(mid 298.781109 -31.041955)
					(end 298.76623 -31.006034)
				)
				(arc
					(start 298.76623 -29.974286)
					(mid 298.781109 -29.938365)
					(end 298.81703 -29.923486)
				)
				(arc
					(start 300.04893 -29.923486)
					(mid 300.084851 -29.938365)
					(end 300.09973 -29.974286)
				)
			)
		)
	)
	(zone
		(layer "In1.Cu")
		(hatch none 0.5)
		(connect_pads
			(clearance 0)
		)
		(min_thickness 0.25)
		(keepout
			(tracks not_allowed)
			(vias allowed)
			(pads allowed)
			(copperpour not_allowed)
			(footprints allowed)
		)
		(placement
			(enabled no)
			(sheetname "")
		)
		(fill
			(thermal_gap 0.5)
			(thermal_bridge_width 0.5)
			(island_removal_mode 0)
		)
		(polygon
			(pts
				(arc
					(start 73.867264 -145.358104)
					(mid 73.852385 -145.394025)
					(end 73.816464 -145.408904)
				)
				(arc
					(start 72.635364 -145.408904)
					(mid 72.599443 -145.394025)
					(end 72.584564 -145.358104)
				)
				(arc
					(start 72.584564 -144.351756)
					(mid 72.599443 -144.315835)
					(end 72.635364 -144.300956)
				)
				(arc
					(start 73.816464 -144.300956)
					(mid 73.852385 -144.315835)
					(end 73.867264 -144.351756)
				)
			)
		)
	)
	(zone
		(layer "In1.Cu")
		(hatch none 0.5)
		(connect_pads
			(clearance 0)
		)
		(min_thickness 0.25)
		(keepout
			(tracks not_allowed)
			(vias allowed)
			(pads allowed)
			(copperpour not_allowed)
			(footprints allowed)
		)
		(placement
			(enabled no)
			(sheetname "")
		)
		(fill
			(thermal_gap 0.5)
			(thermal_bridge_width 0.5)
			(island_removal_mode 0)
		)
		(polygon
			(pts
				(arc
					(start 268.419326 -131.463288)
					(mid 268.434205 -131.499209)
					(end 268.470126 -131.514088)
				)
				(arc
					(start 269.206726 -131.514088)
					(mid 269.242647 -131.499209)
					(end 269.257526 -131.463288)
				)
				(xy 269.257526 -131.219448) (xy 269.025116 -130.865118) (xy 269.257526 -130.509518)
				(arc
					(start 269.257526 -130.266948)
					(mid 269.242647 -130.231027)
					(end 269.206726 -130.216148)
				)
				(arc
					(start 268.470126 -130.216148)
					(mid 268.434205 -130.231027)
					(end 268.419326 -130.266948)
				)
				(xy 268.419326 -130.509518) (xy 268.651736 -130.866388) (xy 268.419326 -131.220718)
			)
		)
	)
	(zone
		(layer "In1.Cu")
		(hatch none 0.5)
		(connect_pads
			(clearance 0)
		)
		(min_thickness 0.25)
		(keepout
			(tracks not_allowed)
			(vias allowed)
			(pads allowed)
			(copperpour not_allowed)
			(footprints allowed)
		)
		(placement
			(enabled no)
			(sheetname "")
		)
		(fill
			(thermal_gap 0.5)
			(thermal_bridge_width 0.5)
			(island_removal_mode 0)
		)
		(polygon
			(pts
				(arc
					(start 198.34225 -145.451068)
					(mid 198.357129 -145.486989)
					(end 198.39305 -145.501868)
				)
				(arc
					(start 199.12965 -145.501868)
					(mid 199.165571 -145.486989)
					(end 199.18045 -145.451068)
				)
				(xy 199.18045 -145.207228) (xy 198.94804 -144.852898) (xy 199.18045 -144.497298)
				(arc
					(start 199.18045 -144.254728)
					(mid 199.165571 -144.218807)
					(end 199.12965 -144.203928)
				)
				(arc
					(start 198.39305 -144.203928)
					(mid 198.357129 -144.218807)
					(end 198.34225 -144.254728)
				)
				(xy 198.34225 -144.497298) (xy 198.57466 -144.854168) (xy 198.34225 -145.208498)
			)
		)
	)
	(zone
		(layer "In1.Cu")
		(hatch none 0.5)
		(connect_pads
			(clearance 0)
		)
		(min_thickness 0.25)
		(keepout
			(tracks not_allowed)
			(vias allowed)
			(pads allowed)
			(copperpour not_allowed)
			(footprints allowed)
		)
		(placement
			(enabled no)
			(sheetname "")
		)
		(fill
			(thermal_gap 0.5)
			(thermal_bridge_width 0.5)
			(island_removal_mode 0)
		)
		(polygon
			(pts
				(arc
					(start 38.861492 -122.0597)
					(mid 38.876371 -122.095621)
					(end 38.912292 -122.1105)
				)
				(arc
					(start 39.648892 -122.1105)
					(mid 39.684813 -122.095621)
					(end 39.699692 -122.0597)
				)
				(xy 39.699692 -121.81586) (xy 39.467282 -121.46153) (xy 39.699692 -121.10593)
				(arc
					(start 39.699692 -120.86336)
					(mid 39.684813 -120.827439)
					(end 39.648892 -120.81256)
				)
				(arc
					(start 38.912292 -120.81256)
					(mid 38.876371 -120.827439)
					(end 38.861492 -120.86336)
				)
				(xy 38.861492 -121.10593) (xy 39.093902 -121.4628) (xy 38.861492 -121.81713)
			)
		)
	)
	(zone
		(layer "In1.Cu")
		(hatch none 0.5)
		(connect_pads
			(clearance 0)
		)
		(min_thickness 0.25)
		(keepout
			(tracks not_allowed)
			(vias allowed)
			(pads allowed)
			(copperpour not_allowed)
			(footprints allowed)
		)
		(placement
			(enabled no)
			(sheetname "")
		)
		(fill
			(thermal_gap 0.5)
			(thermal_bridge_width 0.5)
			(island_removal_mode 0)
		)
		(polygon
			(pts
				(arc
					(start 295.712388 -343.533222)
					(mid 295.676467 -343.548101)
					(end 295.661588 -343.584022)
				)
				(arc
					(start 295.661588 -344.320622)
					(mid 295.676467 -344.356543)
					(end 295.712388 -344.371422)
				)
				(xy 295.956228 -344.371422) (xy 296.310558 -344.139012) (xy 296.666158 -344.371422)
				(arc
					(start 296.908728 -344.371422)
					(mid 296.944649 -344.356543)
					(end 296.959528 -344.320622)
				)
				(arc
					(start 296.959528 -343.584022)
					(mid 296.944649 -343.548101)
					(end 296.908728 -343.533222)
				)
				(xy 296.666158 -343.533222) (xy 296.309288 -343.765632) (xy 295.954958 -343.533222)
			)
		)
	)
	(zone
		(layer "In1.Cu")
		(hatch none 0.5)
		(connect_pads
			(clearance 0)
		)
		(min_thickness 0.25)
		(keepout
			(tracks not_allowed)
			(vias allowed)
			(pads allowed)
			(copperpour not_allowed)
			(footprints allowed)
		)
		(placement
			(enabled no)
			(sheetname "")
		)
		(fill
			(thermal_gap 0.5)
			(thermal_bridge_width 0.5)
			(island_removal_mode 0)
		)
		(polygon
			(pts
				(arc
					(start 180.674518 -349.679514)
					(mid 180.638597 -349.694393)
					(end 180.623718 -349.730314)
				)
				(arc
					(start 180.623718 -350.466914)
					(mid 180.638597 -350.502835)
					(end 180.674518 -350.517714)
				)
				(xy 180.918358 -350.517714) (xy 181.272688 -350.285304) (xy 181.628288 -350.517714)
				(arc
					(start 181.870858 -350.517714)
					(mid 181.906779 -350.502835)
					(end 181.921658 -350.466914)
				)
				(arc
					(start 181.921658 -349.730314)
					(mid 181.906779 -349.694393)
					(end 181.870858 -349.679514)
				)
				(xy 181.628288 -349.679514) (xy 181.271418 -349.911924) (xy 180.917088 -349.679514)
			)
		)
	)
	(zone
		(layer "In1.Cu")
		(hatch none 0.5)
		(connect_pads
			(clearance 0)
		)
		(min_thickness 0.25)
		(keepout
			(tracks not_allowed)
			(vias allowed)
			(pads allowed)
			(copperpour not_allowed)
			(footprints allowed)
		)
		(placement
			(enabled no)
			(sheetname "")
		)
		(fill
			(thermal_gap 0.5)
			(thermal_bridge_width 0.5)
			(island_removal_mode 0)
		)
		(polygon
			(pts
				(arc
					(start 399.55216 -102.04831)
					(mid 399.537281 -102.084231)
					(end 399.50136 -102.09911)
				)
				(arc
					(start 398.32026 -102.09911)
					(mid 398.284339 -102.084231)
					(end 398.26946 -102.04831)
				)
				(arc
					(start 398.26946 -101.041962)
					(mid 398.284339 -101.006041)
					(end 398.32026 -100.991162)
				)
				(arc
					(start 399.50136 -100.991162)
					(mid 399.537281 -101.006041)
					(end 399.55216 -101.041962)
				)
			)
		)
	)
	(zone
		(layer "In1.Cu")
		(hatch none 0.5)
		(connect_pads
			(clearance 0)
		)
		(min_thickness 0.25)
		(keepout
			(tracks not_allowed)
			(vias allowed)
			(pads allowed)
			(copperpour not_allowed)
			(footprints allowed)
		)
		(placement
			(enabled no)
			(sheetname "")
		)
		(fill
			(thermal_gap 0.5)
			(thermal_bridge_width 0.5)
			(island_removal_mode 0)
		)
		(polygon
			(pts
				(arc
					(start 249.573288 -29.279596)
					(mid 249.588167 -29.315517)
					(end 249.624088 -29.330396)
				)
				(arc
					(start 250.360688 -29.330396)
					(mid 250.396609 -29.315517)
					(end 250.411488 -29.279596)
				)
				(xy 250.411488 -29.035756) (xy 250.179078 -28.681426) (xy 250.411488 -28.325826)
				(arc
					(start 250.411488 -28.083256)
					(mid 250.396609 -28.047335)
					(end 250.360688 -28.032456)
				)
				(arc
					(start 249.624088 -28.032456)
					(mid 249.588167 -28.047335)
					(end 249.573288 -28.083256)
				)
				(xy 249.573288 -28.325826) (xy 249.805698 -28.682696) (xy 249.573288 -29.037026)
			)
		)
	)
	(zone
		(layer "In1.Cu")
		(hatch none 0.5)
		(connect_pads
			(clearance 0)
		)
		(min_thickness 0.25)
		(keepout
			(tracks not_allowed)
			(vias allowed)
			(pads allowed)
			(copperpour not_allowed)
			(footprints allowed)
		)
		(placement
			(enabled no)
			(sheetname "")
		)
		(fill
			(thermal_gap 0.5)
			(thermal_bridge_width 0.5)
			(island_removal_mode 0)
		)
		(polygon
			(pts
				(arc
					(start 330.21524 -34.68624)
					(mid 330.230119 -34.722161)
					(end 330.26604 -34.73704)
				)
				(arc
					(start 331.00264 -34.73704)
					(mid 331.038561 -34.722161)
					(end 331.05344 -34.68624)
				)
				(xy 331.05344 -34.4424) (xy 330.82103 -34.08807) (xy 331.05344 -33.73247)
				(arc
					(start 331.05344 -33.4899)
					(mid 331.038561 -33.453979)
					(end 331.00264 -33.4391)
				)
				(arc
					(start 330.26604 -33.4391)
					(mid 330.230119 -33.453979)
					(end 330.21524 -33.4899)
				)
				(xy 330.21524 -33.73247) (xy 330.44765 -34.08934) (xy 330.21524 -34.44367)
			)
		)
	)
	(zone
		(layer "In1.Cu")
		(hatch none 0.5)
		(connect_pads
			(clearance 0)
		)
		(min_thickness 0.25)
		(keepout
			(tracks not_allowed)
			(vias allowed)
			(pads allowed)
			(copperpour not_allowed)
			(footprints allowed)
		)
		(placement
			(enabled no)
			(sheetname "")
		)
		(fill
			(thermal_gap 0.5)
			(thermal_bridge_width 0.5)
			(island_removal_mode 0)
		)
		(polygon
			(pts
				(arc
					(start 50.256694 -343.533222)
					(mid 50.220773 -343.548101)
					(end 50.205894 -343.584022)
				)
				(arc
					(start 50.205894 -344.320622)
					(mid 50.220773 -344.356543)
					(end 50.256694 -344.371422)
				)
				(xy 50.500534 -344.371422) (xy 50.854864 -344.139012) (xy 51.210464 -344.371422)
				(arc
					(start 51.453034 -344.371422)
					(mid 51.488955 -344.356543)
					(end 51.503834 -344.320622)
				)
				(arc
					(start 51.503834 -343.584022)
					(mid 51.488955 -343.548101)
					(end 51.453034 -343.533222)
				)
				(xy 51.210464 -343.533222) (xy 50.853594 -343.765632) (xy 50.499264 -343.533222)
			)
		)
	)
	(zone
		(layer "In1.Cu")
		(hatch none 0.5)
		(connect_pads
			(clearance 0)
		)
		(min_thickness 0.25)
		(keepout
			(tracks not_allowed)
			(vias allowed)
			(pads allowed)
			(copperpour not_allowed)
			(footprints allowed)
		)
		(placement
			(enabled no)
			(sheetname "")
		)
		(fill
			(thermal_gap 0.5)
			(thermal_bridge_width 0.5)
			(island_removal_mode 0)
		)
		(polygon
			(pts
				(arc
					(start 189.967108 -132.648198)
					(mid 189.952229 -132.684119)
					(end 189.916308 -132.698998)
				)
				(arc
					(start 188.735208 -132.698998)
					(mid 188.699287 -132.684119)
					(end 188.684408 -132.648198)
				)
				(arc
					(start 188.684408 -131.64185)
					(mid 188.699287 -131.605929)
					(end 188.735208 -131.59105)
				)
				(arc
					(start 189.916308 -131.59105)
					(mid 189.952229 -131.605929)
					(end 189.967108 -131.64185)
				)
			)
		)
	)
	(zone
		(layer "In1.Cu")
		(hatch none 0.5)
		(connect_pads
			(clearance 0)
		)
		(min_thickness 0.25)
		(keepout
			(tracks not_allowed)
			(vias allowed)
			(pads allowed)
			(copperpour not_allowed)
			(footprints allowed)
		)
		(placement
			(enabled no)
			(sheetname "")
		)
		(fill
			(thermal_gap 0.5)
			(thermal_bridge_width 0.5)
			(island_removal_mode 0)
		)
		(polygon
			(pts
				(arc
					(start 82.242406 -121.531126)
					(mid 82.257285 -121.567047)
					(end 82.293206 -121.581926)
				)
				(arc
					(start 83.029806 -121.581926)
					(mid 83.065727 -121.567047)
					(end 83.080606 -121.531126)
				)
				(xy 83.080606 -121.287286) (xy 82.848196 -120.932956) (xy 83.080606 -120.577356)
				(arc
					(start 83.080606 -120.334786)
					(mid 83.065727 -120.298865)
					(end 83.029806 -120.283986)
				)
				(arc
					(start 82.293206 -120.283986)
					(mid 82.257285 -120.298865)
					(end 82.242406 -120.334786)
				)
				(xy 82.242406 -120.577356) (xy 82.474816 -120.934226) (xy 82.242406 -121.288556)
			)
		)
	)
	(zone
		(layer "In1.Cu")
		(hatch none 0.5)
		(connect_pads
			(clearance 0)
		)
		(min_thickness 0.25)
		(keepout
			(tracks not_allowed)
			(vias allowed)
			(pads allowed)
			(copperpour not_allowed)
			(footprints allowed)
		)
		(placement
			(enabled no)
			(sheetname "")
		)
		(fill
			(thermal_gap 0.5)
			(thermal_bridge_width 0.5)
			(island_removal_mode 0)
		)
		(polygon
			(pts
				(arc
					(start 271.061434 -122.0597)
					(mid 271.076313 -122.095621)
					(end 271.112234 -122.1105)
				)
				(arc
					(start 271.848834 -122.1105)
					(mid 271.884755 -122.095621)
					(end 271.899634 -122.0597)
				)
				(xy 271.899634 -121.81586) (xy 271.667224 -121.46153) (xy 271.899634 -121.10593)
				(arc
					(start 271.899634 -120.86336)
					(mid 271.884755 -120.827439)
					(end 271.848834 -120.81256)
				)
				(arc
					(start 271.112234 -120.81256)
					(mid 271.076313 -120.827439)
					(end 271.061434 -120.86336)
				)
				(xy 271.061434 -121.10593) (xy 271.293844 -121.4628) (xy 271.061434 -121.81713)
			)
		)
	)
	(zone
		(layer "In1.Cu")
		(hatch none 0.5)
		(connect_pads
			(clearance 0)
		)
		(min_thickness 0.25)
		(keepout
			(tracks not_allowed)
			(vias allowed)
			(pads allowed)
			(copperpour not_allowed)
			(footprints allowed)
		)
		(placement
			(enabled no)
			(sheetname "")
		)
		(fill
			(thermal_gap 0.5)
			(thermal_bridge_width 0.5)
			(island_removal_mode 0)
		)
		(polygon
			(pts
				(arc
					(start 158.911798 -355.825806)
					(mid 158.875877 -355.840685)
					(end 158.860998 -355.876606)
				)
				(arc
					(start 158.860998 -356.613206)
					(mid 158.875877 -356.649127)
					(end 158.911798 -356.664006)
				)
				(xy 159.155638 -356.664006) (xy 159.509968 -356.431596) (xy 159.865568 -356.664006)
				(arc
					(start 160.108138 -356.664006)
					(mid 160.144059 -356.649127)
					(end 160.158938 -356.613206)
				)
				(arc
					(start 160.158938 -355.876606)
					(mid 160.144059 -355.840685)
					(end 160.108138 -355.825806)
				)
				(xy 159.865568 -355.825806) (xy 159.508698 -356.058216) (xy 159.154368 -355.825806)
			)
		)
	)
	(zone
		(layer "In1.Cu")
		(hatch none 0.5)
		(connect_pads
			(clearance 0)
		)
		(min_thickness 0.25)
		(keepout
			(tracks not_allowed)
			(vias allowed)
			(pads allowed)
			(copperpour not_allowed)
			(footprints allowed)
		)
		(placement
			(enabled no)
			(sheetname "")
		)
		(fill
			(thermal_gap 0.5)
			(thermal_bridge_width 0.5)
			(island_removal_mode 0)
		)
		(polygon
			(pts
				(arc
					(start 67.899788 -31.006034)
					(mid 67.884909 -31.041955)
					(end 67.848988 -31.056834)
				)
				(arc
					(start 66.617088 -31.056834)
					(mid 66.581167 -31.041955)
					(end 66.566288 -31.006034)
				)
				(arc
					(start 66.566288 -29.974286)
					(mid 66.581167 -29.938365)
					(end 66.617088 -29.923486)
				)
				(arc
					(start 67.848988 -29.923486)
					(mid 67.884909 -29.938365)
					(end 67.899788 -29.974286)
				)
			)
		)
	)
	(zone
		(layer "In1.Cu")
		(hatch none 0.5)
		(connect_pads
			(clearance 0)
		)
		(min_thickness 0.25)
		(keepout
			(tracks not_allowed)
			(vias allowed)
			(pads allowed)
			(copperpour not_allowed)
			(footprints allowed)
		)
		(placement
			(enabled no)
			(sheetname "")
		)
		(fill
			(thermal_gap 0.5)
			(thermal_bridge_width 0.5)
			(island_removal_mode 0)
		)
		(polygon
			(pts
				(arc
					(start 274.099782 -34.605976)
					(mid 274.084903 -34.641897)
					(end 274.048982 -34.656776)
				)
				(arc
					(start 272.817082 -34.656776)
					(mid 272.781161 -34.641897)
					(end 272.766282 -34.605976)
				)
				(arc
					(start 272.766282 -33.574228)
					(mid 272.781161 -33.538307)
					(end 272.817082 -33.523428)
				)
				(arc
					(start 274.048982 -33.523428)
					(mid 274.084903 -33.538307)
					(end 274.099782 -33.574228)
				)
			)
		)
	)
	(zone
		(layer "In1.Cu")
		(hatch none 0.5)
		(connect_pads
			(clearance 0)
		)
		(min_thickness 0.25)
		(keepout
			(tracks not_allowed)
			(vias allowed)
			(pads allowed)
			(copperpour not_allowed)
			(footprints allowed)
		)
		(placement
			(enabled no)
			(sheetname "")
		)
		(fill
			(thermal_gap 0.5)
			(thermal_bridge_width 0.5)
			(island_removal_mode 0)
		)
		(polygon
			(pts
				(arc
					(start 422.167304 -130.8481)
					(mid 422.152425 -130.884021)
					(end 422.116504 -130.8989)
				)
				(arc
					(start 420.935404 -130.8989)
					(mid 420.899483 -130.884021)
					(end 420.884604 -130.8481)
				)
				(arc
					(start 420.884604 -129.841752)
					(mid 420.899483 -129.805831)
					(end 420.935404 -129.790952)
				)
				(arc
					(start 422.116504 -129.790952)
					(mid 422.152425 -129.805831)
					(end 422.167304 -129.841752)
				)
			)
		)
	)
	(zone
		(layer "In1.Cu")
		(hatch none 0.5)
		(connect_pads
			(clearance 0)
		)
		(min_thickness 0.25)
		(keepout
			(tracks not_allowed)
			(vias allowed)
			(pads allowed)
			(copperpour not_allowed)
			(footprints allowed)
		)
		(placement
			(enabled no)
			(sheetname "")
		)
		(fill
			(thermal_gap 0.5)
			(thermal_bridge_width 0.5)
			(island_removal_mode 0)
		)
		(polygon
			(pts
				(arc
					(start 384.519424 -105.749852)
					(mid 384.534303 -105.785773)
					(end 384.570224 -105.800652)
				)
				(arc
					(start 385.306824 -105.800652)
					(mid 385.342745 -105.785773)
					(end 385.357624 -105.749852)
				)
				(xy 385.357624 -105.506012) (xy 385.125214 -105.151682) (xy 385.357624 -104.796082)
				(arc
					(start 385.357624 -104.553512)
					(mid 385.342745 -104.517591)
					(end 385.306824 -104.502712)
				)
				(arc
					(start 384.570224 -104.502712)
					(mid 384.534303 -104.517591)
					(end 384.519424 -104.553512)
				)
				(xy 384.519424 -104.796082) (xy 384.751834 -105.152952) (xy 384.519424 -105.507282)
			)
		)
	)
	(zone
		(layer "In1.Cu")
		(hatch none 0.5)
		(connect_pads
			(clearance 0)
		)
		(min_thickness 0.25)
		(keepout
			(tracks not_allowed)
			(vias allowed)
			(pads allowed)
			(copperpour not_allowed)
			(footprints allowed)
		)
		(placement
			(enabled no)
			(sheetname "")
		)
		(fill
			(thermal_gap 0.5)
			(thermal_bridge_width 0.5)
			(island_removal_mode 0)
		)
		(polygon
			(pts
				(arc
					(start 283.452062 -112.848136)
					(mid 283.437183 -112.884057)
					(end 283.401262 -112.898936)
				)
				(arc
					(start 282.220162 -112.898936)
					(mid 282.184241 -112.884057)
					(end 282.169362 -112.848136)
				)
				(arc
					(start 282.169362 -111.841788)
					(mid 282.184241 -111.805867)
					(end 282.220162 -111.790988)
				)
				(arc
					(start 283.401262 -111.790988)
					(mid 283.437183 -111.805867)
					(end 283.452062 -111.841788)
				)
			)
		)
	)
	(zone
		(layer "In1.Cu")
		(hatch none 0.5)
		(connect_pads
			(clearance 0)
		)
		(min_thickness 0.25)
		(keepout
			(tracks not_allowed)
			(vias allowed)
			(pads allowed)
			(copperpour not_allowed)
			(footprints allowed)
		)
		(placement
			(enabled no)
			(sheetname "")
		)
		(fill
			(thermal_gap 0.5)
			(thermal_bridge_width 0.5)
			(island_removal_mode 0)
		)
		(polygon
			(pts
				(arc
					(start 68.04787 -144.351756)
					(mid 68.062749 -144.315835)
					(end 68.09867 -144.300956)
				)
				(arc
					(start 69.27977 -144.300956)
					(mid 69.315691 -144.315835)
					(end 69.33057 -144.351756)
				)
				(arc
					(start 69.33057 -145.358104)
					(mid 69.315691 -145.394025)
					(end 69.27977 -145.408904)
				)
				(arc
					(start 68.09867 -145.408904)
					(mid 68.062749 -145.394025)
					(end 68.04787 -145.358104)
				)
			)
		)
	)
	(zone
		(layer "In1.Cu")
		(hatch none 0.5)
		(connect_pads
			(clearance 0)
		)
		(min_thickness 0.25)
		(keepout
			(tracks not_allowed)
			(vias allowed)
			(pads allowed)
			(copperpour not_allowed)
			(footprints allowed)
		)
		(placement
			(enabled no)
			(sheetname "")
		)
		(fill
			(thermal_gap 0.5)
			(thermal_bridge_width 0.5)
			(island_removal_mode 0)
		)
		(polygon
			(pts
				(arc
					(start 126.13005 -31.77413)
					(mid 126.144929 -31.738209)
					(end 126.18085 -31.72333)
				)
				(arc
					(start 127.41275 -31.72333)
					(mid 127.448671 -31.738209)
					(end 127.46355 -31.77413)
				)
				(arc
					(start 127.46355 -32.805878)
					(mid 127.448671 -32.841799)
					(end 127.41275 -32.856678)
				)
				(arc
					(start 126.18085 -32.856678)
					(mid 126.144929 -32.841799)
					(end 126.13005 -32.805878)
				)
			)
		)
	)
	(zone
		(layer "In1.Cu")
		(hatch none 0.5)
		(connect_pads
			(clearance 0)
		)
		(min_thickness 0.25)
		(keepout
			(tracks not_allowed)
			(vias allowed)
			(pads allowed)
			(copperpour not_allowed)
			(footprints allowed)
		)
		(placement
			(enabled no)
			(sheetname "")
		)
		(fill
			(thermal_gap 0.5)
			(thermal_bridge_width 0.5)
			(island_removal_mode 0)
		)
		(polygon
			(pts
				(arc
					(start 228.76383 -59.260232)
					(mid 228.778709 -59.224311)
					(end 228.81463 -59.209432)
				)
				(arc
					(start 230.059484 -59.209432)
					(mid 230.095405 -59.224311)
					(end 230.110284 -59.260232)
				)
				(arc
					(start 230.110284 -60.140342)
					(mid 230.095405 -60.176263)
					(end 230.059484 -60.191142)
				)
				(arc
					(start 228.81463 -60.191142)
					(mid 228.778709 -60.176263)
					(end 228.76383 -60.140342)
				)
			)
		)
	)
	(zone
		(layer "In1.Cu")
		(hatch none 0.5)
		(connect_pads
			(clearance 0)
		)
		(min_thickness 0.25)
		(keepout
			(tracks not_allowed)
			(vias allowed)
			(pads allowed)
			(copperpour not_allowed)
			(footprints allowed)
		)
		(placement
			(enabled no)
			(sheetname "")
		)
		(fill
			(thermal_gap 0.5)
			(thermal_bridge_width 0.5)
			(island_removal_mode 0)
		)
		(polygon
			(pts
				(arc
					(start 387.161532 -122.0597)
					(mid 387.176411 -122.095621)
					(end 387.212332 -122.1105)
				)
				(arc
					(start 387.948932 -122.1105)
					(mid 387.984853 -122.095621)
					(end 387.999732 -122.0597)
				)
				(xy 387.999732 -121.81586) (xy 387.767322 -121.46153) (xy 387.999732 -121.10593)
				(arc
					(start 387.999732 -120.86336)
					(mid 387.984853 -120.827439)
					(end 387.948932 -120.81256)
				)
				(arc
					(start 387.212332 -120.81256)
					(mid 387.176411 -120.827439)
					(end 387.161532 -120.86336)
				)
				(xy 387.161532 -121.10593) (xy 387.393942 -121.4628) (xy 387.161532 -121.81713)
			)
		)
	)
	(zone
		(layer "In1.Cu")
		(hatch none 0.5)
		(connect_pads
			(clearance 0)
		)
		(min_thickness 0.25)
		(keepout
			(tracks not_allowed)
			(vias allowed)
			(pads allowed)
			(copperpour not_allowed)
			(footprints allowed)
		)
		(placement
			(enabled no)
			(sheetname "")
		)
		(fill
			(thermal_gap 0.5)
			(thermal_bridge_width 0.5)
			(island_removal_mode 0)
		)
		(polygon
			(pts
				(arc
					(start 371.022626 -349.679514)
					(mid 370.986705 -349.694393)
					(end 370.971826 -349.730314)
				)
				(arc
					(start 370.971826 -350.466914)
					(mid 370.986705 -350.502835)
					(end 371.022626 -350.517714)
				)
				(xy 371.266466 -350.517714) (xy 371.620796 -350.285304) (xy 371.976396 -350.517714)
				(arc
					(start 372.218966 -350.517714)
					(mid 372.254887 -350.502835)
					(end 372.269766 -350.466914)
				)
				(arc
					(start 372.269766 -349.730314)
					(mid 372.254887 -349.694393)
					(end 372.218966 -349.679514)
				)
				(xy 371.976396 -349.679514) (xy 371.619526 -349.911924) (xy 371.265196 -349.679514)
			)
		)
	)
	(zone
		(layer "In1.Cu")
		(hatch none 0.5)
		(connect_pads
			(clearance 0)
		)
		(min_thickness 0.25)
		(keepout
			(tracks not_allowed)
			(vias allowed)
			(pads allowed)
			(copperpour not_allowed)
			(footprints allowed)
		)
		(placement
			(enabled no)
			(sheetname "")
		)
		(fill
			(thermal_gap 0.5)
			(thermal_bridge_width 0.5)
			(island_removal_mode 0)
		)
		(polygon
			(pts
				(arc
					(start 395.894306 -349.679514)
					(mid 395.858385 -349.694393)
					(end 395.843506 -349.730314)
				)
				(arc
					(start 395.843506 -350.466914)
					(mid 395.858385 -350.502835)
					(end 395.894306 -350.517714)
				)
				(xy 396.138146 -350.517714) (xy 396.492476 -350.285304) (xy 396.848076 -350.517714)
				(arc
					(start 397.090646 -350.517714)
					(mid 397.126567 -350.502835)
					(end 397.141446 -350.466914)
				)
				(arc
					(start 397.141446 -349.730314)
					(mid 397.126567 -349.694393)
					(end 397.090646 -349.679514)
				)
				(xy 396.848076 -349.679514) (xy 396.491206 -349.911924) (xy 396.136876 -349.679514)
			)
		)
	)
	(zone
		(layer "In1.Cu")
		(hatch none 0.5)
		(connect_pads
			(clearance 0)
		)
		(min_thickness 0.25)
		(keepout
			(tracks not_allowed)
			(vias allowed)
			(pads allowed)
			(copperpour not_allowed)
			(footprints allowed)
		)
		(placement
			(enabled no)
			(sheetname "")
		)
		(fill
			(thermal_gap 0.5)
			(thermal_bridge_width 0.5)
			(island_removal_mode 0)
		)
		(polygon
			(pts
				(arc
					(start 185.47334 -29.279596)
					(mid 185.488219 -29.315517)
					(end 185.52414 -29.330396)
				)
				(arc
					(start 186.26074 -29.330396)
					(mid 186.296661 -29.315517)
					(end 186.31154 -29.279596)
				)
				(xy 186.31154 -29.035756) (xy 186.07913 -28.681426) (xy 186.31154 -28.325826)
				(arc
					(start 186.31154 -28.083256)
					(mid 186.296661 -28.047335)
					(end 186.26074 -28.032456)
				)
				(arc
					(start 185.52414 -28.032456)
					(mid 185.488219 -28.047335)
					(end 185.47334 -28.083256)
				)
				(xy 185.47334 -28.325826) (xy 185.70575 -28.682696) (xy 185.47334 -29.037026)
			)
		)
	)
	(zone
		(layer "In1.Cu")
		(hatch none 0.5)
		(connect_pads
			(clearance 0)
		)
		(min_thickness 0.25)
		(keepout
			(tracks not_allowed)
			(vias allowed)
			(pads allowed)
			(copperpour not_allowed)
			(footprints allowed)
		)
		(placement
			(enabled no)
			(sheetname "")
		)
		(fill
			(thermal_gap 0.5)
			(thermal_bridge_width 0.5)
			(island_removal_mode 0)
		)
		(polygon
			(pts
				(arc
					(start 300.09973 -29.205936)
					(mid 300.084851 -29.241857)
					(end 300.04893 -29.256736)
				)
				(arc
					(start 298.81703 -29.256736)
					(mid 298.781109 -29.241857)
					(end 298.76623 -29.205936)
				)
				(arc
					(start 298.76623 -28.174188)
					(mid 298.781109 -28.138267)
					(end 298.81703 -28.123388)
				)
				(arc
					(start 300.04893 -28.123388)
					(mid 300.084851 -28.138267)
					(end 300.09973 -28.174188)
				)
			)
		)
	)
	(zone
		(layer "In1.Cu")
		(hatch none 0.5)
		(connect_pads
			(clearance 0)
		)
		(min_thickness 0.25)
		(keepout
			(tracks not_allowed)
			(vias allowed)
			(pads allowed)
			(copperpour not_allowed)
			(footprints allowed)
		)
		(placement
			(enabled no)
			(sheetname "")
		)
		(fill
			(thermal_gap 0.5)
			(thermal_bridge_width 0.5)
			(island_removal_mode 0)
		)
		(polygon
			(pts
				(arc
					(start 269.028926 -102.149656)
					(mid 269.043805 -102.185577)
					(end 269.079726 -102.200456)
				)
				(arc
					(start 269.816326 -102.200456)
					(mid 269.852247 -102.185577)
					(end 269.867126 -102.149656)
				)
				(xy 269.867126 -101.905816) (xy 269.634716 -101.551486) (xy 269.867126 -101.195886)
				(arc
					(start 269.867126 -100.953316)
					(mid 269.852247 -100.917395)
					(end 269.816326 -100.902516)
				)
				(arc
					(start 269.079726 -100.902516)
					(mid 269.043805 -100.917395)
					(end 269.028926 -100.953316)
				)
				(xy 269.028926 -101.195886) (xy 269.261336 -101.552756) (xy 269.028926 -101.907086)
			)
		)
	)
	(zone
		(layer "In1.Cu")
		(hatch none 0.5)
		(connect_pads
			(clearance 0)
		)
		(min_thickness 0.25)
		(keepout
			(tracks not_allowed)
			(vias allowed)
			(pads allowed)
			(copperpour not_allowed)
			(footprints allowed)
		)
		(placement
			(enabled no)
			(sheetname "")
		)
		(fill
			(thermal_gap 0.5)
			(thermal_bridge_width 0.5)
			(island_removal_mode 0)
		)
		(polygon
			(pts
				(arc
					(start 98.015298 -34.68624)
					(mid 98.030177 -34.722161)
					(end 98.066098 -34.73704)
				)
				(arc
					(start 98.802698 -34.73704)
					(mid 98.838619 -34.722161)
					(end 98.853498 -34.68624)
				)
				(xy 98.853498 -34.4424) (xy 98.621088 -34.08807) (xy 98.853498 -33.73247)
				(arc
					(start 98.853498 -33.4899)
					(mid 98.838619 -33.453979)
					(end 98.802698 -33.4391)
				)
				(arc
					(start 98.066098 -33.4391)
					(mid 98.030177 -33.453979)
					(end 98.015298 -33.4899)
				)
				(xy 98.015298 -33.73247) (xy 98.247708 -34.08934) (xy 98.015298 -34.44367)
			)
		)
	)
	(zone
		(layer "In1.Cu")
		(hatch none 0.5)
		(connect_pads
			(clearance 0)
		)
		(min_thickness 0.25)
		(keepout
			(tracks not_allowed)
			(vias allowed)
			(pads allowed)
			(copperpour not_allowed)
			(footprints allowed)
		)
		(placement
			(enabled no)
			(sheetname "")
		)
		(fill
			(thermal_gap 0.5)
			(thermal_bridge_width 0.5)
			(island_removal_mode 0)
		)
		(polygon
			(pts
				(arc
					(start 364.199932 -29.205936)
					(mid 364.185053 -29.241857)
					(end 364.149132 -29.256736)
				)
				(arc
					(start 362.917232 -29.256736)
					(mid 362.881311 -29.241857)
					(end 362.866432 -29.205936)
				)
				(arc
					(start 362.866432 -28.174188)
					(mid 362.881311 -28.138267)
					(end 362.917232 -28.123388)
				)
				(arc
					(start 364.149132 -28.123388)
					(mid 364.185053 -28.138267)
					(end 364.199932 -28.174188)
				)
			)
		)
	)
	(zone
		(layer "In1.Cu")
		(hatch none 0.5)
		(connect_pads
			(clearance 0)
		)
		(min_thickness 0.25)
		(keepout
			(tracks not_allowed)
			(vias allowed)
			(pads allowed)
			(copperpour not_allowed)
			(footprints allowed)
		)
		(placement
			(enabled no)
			(sheetname "")
		)
		(fill
			(thermal_gap 0.5)
			(thermal_bridge_width 0.5)
			(island_removal_mode 0)
		)
		(polygon
			(pts
				(arc
					(start 440.219338 -355.825806)
					(mid 440.183417 -355.840685)
					(end 440.168538 -355.876606)
				)
				(arc
					(start 440.168538 -356.613206)
					(mid 440.183417 -356.649127)
					(end 440.219338 -356.664006)
				)
				(xy 440.463178 -356.664006) (xy 440.817508 -356.431596) (xy 441.173108 -356.664006)
				(arc
					(start 441.415678 -356.664006)
					(mid 441.451599 -356.649127)
					(end 441.466478 -356.613206)
				)
				(arc
					(start 441.466478 -355.876606)
					(mid 441.451599 -355.840685)
					(end 441.415678 -355.825806)
				)
				(xy 441.173108 -355.825806) (xy 440.816238 -356.058216) (xy 440.461908 -355.825806)
			)
		)
	)
	(zone
		(layer "In1.Cu")
		(hatch none 0.5)
		(connect_pads
			(clearance 0)
		)
		(min_thickness 0.25)
		(keepout
			(tracks not_allowed)
			(vias allowed)
			(pads allowed)
			(copperpour not_allowed)
			(footprints allowed)
		)
		(placement
			(enabled no)
			(sheetname "")
		)
		(fill
			(thermal_gap 0.5)
			(thermal_bridge_width 0.5)
			(island_removal_mode 0)
		)
		(polygon
			(pts
				(arc
					(start 337.20913 -343.533222)
					(mid 337.173209 -343.548101)
					(end 337.15833 -343.584022)
				)
				(arc
					(start 337.15833 -344.320622)
					(mid 337.173209 -344.356543)
					(end 337.20913 -344.371422)
				)
				(xy 337.45297 -344.371422) (xy 337.8073 -344.139012) (xy 338.1629 -344.371422)
				(arc
					(start 338.40547 -344.371422)
					(mid 338.441391 -344.356543)
					(end 338.45627 -344.320622)
				)
				(arc
					(start 338.45627 -343.584022)
					(mid 338.441391 -343.548101)
					(end 338.40547 -343.533222)
				)
				(xy 338.1629 -343.533222) (xy 337.80603 -343.765632) (xy 337.4517 -343.533222)
			)
		)
	)
	(zone
		(layer "In1.Cu")
		(hatch none 0.5)
		(connect_pads
			(clearance 0)
		)
		(min_thickness 0.25)
		(keepout
			(tracks not_allowed)
			(vias allowed)
			(pads allowed)
			(copperpour not_allowed)
			(footprints allowed)
		)
		(placement
			(enabled no)
			(sheetname "")
		)
		(fill
			(thermal_gap 0.5)
			(thermal_bridge_width 0.5)
			(island_removal_mode 0)
		)
		(polygon
			(pts
				(arc
					(start 183.999886 -29.205936)
					(mid 183.985007 -29.241857)
					(end 183.949086 -29.256736)
				)
				(arc
					(start 182.717186 -29.256736)
					(mid 182.681265 -29.241857)
					(end 182.666386 -29.205936)
				)
				(arc
					(start 182.666386 -28.174188)
					(mid 182.681265 -28.138267)
					(end 182.717186 -28.123388)
				)
				(arc
					(start 183.949086 -28.123388)
					(mid 183.985007 -28.138267)
					(end 183.999886 -28.174188)
				)
			)
		)
	)
	(zone
		(layer "In1.Cu")
		(hatch none 0.5)
		(connect_pads
			(clearance 0)
		)
		(min_thickness 0.25)
		(keepout
			(tracks not_allowed)
			(vias allowed)
			(pads allowed)
			(copperpour not_allowed)
			(footprints allowed)
		)
		(placement
			(enabled no)
			(sheetname "")
		)
		(fill
			(thermal_gap 0.5)
			(thermal_bridge_width 0.5)
			(island_removal_mode 0)
		)
		(polygon
			(pts
				(arc
					(start 64.315848 -349.679514)
					(mid 64.279927 -349.694393)
					(end 64.265048 -349.730314)
				)
				(arc
					(start 64.265048 -350.466914)
					(mid 64.279927 -350.502835)
					(end 64.315848 -350.517714)
				)
				(xy 64.559688 -350.517714) (xy 64.914018 -350.285304) (xy 65.269618 -350.517714)
				(arc
					(start 65.512188 -350.517714)
					(mid 65.548109 -350.502835)
					(end 65.562988 -350.466914)
				)
				(arc
					(start 65.562988 -349.730314)
					(mid 65.548109 -349.694393)
					(end 65.512188 -349.679514)
				)
				(xy 65.269618 -349.679514) (xy 64.912748 -349.911924) (xy 64.558418 -349.679514)
			)
		)
	)
	(zone
		(layer "In1.Cu")
		(hatch none 0.5)
		(connect_pads
			(clearance 0)
		)
		(min_thickness 0.25)
		(keepout
			(tracks not_allowed)
			(vias allowed)
			(pads allowed)
			(copperpour not_allowed)
			(footprints allowed)
		)
		(placement
			(enabled no)
			(sheetname "")
		)
		(fill
			(thermal_gap 0.5)
			(thermal_bridge_width 0.5)
			(island_removal_mode 0)
		)
		(polygon
			(pts
				(arc
					(start 280.167588 -349.679514)
					(mid 280.131667 -349.694393)
					(end 280.116788 -349.730314)
				)
				(arc
					(start 280.116788 -350.466914)
					(mid 280.131667 -350.502835)
					(end 280.167588 -350.517714)
				)
				(xy 280.411428 -350.517714) (xy 280.765758 -350.285304) (xy 281.121358 -350.517714)
				(arc
					(start 281.363928 -350.517714)
					(mid 281.399849 -350.502835)
					(end 281.414728 -350.466914)
				)
				(arc
					(start 281.414728 -349.730314)
					(mid 281.399849 -349.694393)
					(end 281.363928 -349.679514)
				)
				(xy 281.121358 -349.679514) (xy 280.764488 -349.911924) (xy 280.410158 -349.679514)
			)
		)
	)
	(zone
		(layer "In1.Cu")
		(hatch none 0.5)
		(connect_pads
			(clearance 0)
		)
		(min_thickness 0.25)
		(keepout
			(tracks not_allowed)
			(vias allowed)
			(pads allowed)
			(copperpour not_allowed)
			(footprints allowed)
		)
		(placement
			(enabled no)
			(sheetname "")
		)
		(fill
			(thermal_gap 0.5)
			(thermal_bridge_width 0.5)
			(island_removal_mode 0)
		)
		(polygon
			(pts
				(arc
					(start 300.09973 -32.805878)
					(mid 300.084851 -32.841799)
					(end 300.04893 -32.856678)
				)
				(arc
					(start 298.81703 -32.856678)
					(mid 298.781109 -32.841799)
					(end 298.76623 -32.805878)
				)
				(arc
					(start 298.76623 -31.77413)
					(mid 298.781109 -31.738209)
					(end 298.81703 -31.72333)
				)
				(arc
					(start 300.04893 -31.72333)
					(mid 300.084851 -31.738209)
					(end 300.09973 -31.77413)
				)
			)
		)
	)
	(zone
		(layer "In1.Cu")
		(hatch none 0.5)
		(connect_pads
			(clearance 0)
		)
		(min_thickness 0.25)
		(keepout
			(tracks not_allowed)
			(vias allowed)
			(pads allowed)
			(copperpour not_allowed)
			(footprints allowed)
		)
		(placement
			(enabled no)
			(sheetname "")
		)
		(fill
			(thermal_gap 0.5)
			(thermal_bridge_width 0.5)
			(island_removal_mode 0)
		)
		(polygon
			(pts
				(arc
					(start 51.25212 -103.848408)
					(mid 51.237241 -103.884329)
					(end 51.20132 -103.899208)
				)
				(arc
					(start 50.02022 -103.899208)
					(mid 49.984299 -103.884329)
					(end 49.96942 -103.848408)
				)
				(arc
					(start 49.96942 -102.84206)
					(mid 49.984299 -102.806139)
					(end 50.02022 -102.79126)
				)
				(arc
					(start 51.20132 -102.79126)
					(mid 51.237241 -102.806139)
					(end 51.25212 -102.84206)
				)
			)
		)
	)
	(zone
		(layer "In1.Cu")
		(hatch none 0.5)
		(connect_pads
			(clearance 0)
		)
		(min_thickness 0.25)
		(keepout
			(tracks not_allowed)
			(vias allowed)
			(pads allowed)
			(copperpour not_allowed)
			(footprints allowed)
		)
		(placement
			(enabled no)
			(sheetname "")
		)
		(fill
			(thermal_gap 0.5)
			(thermal_bridge_width 0.5)
			(island_removal_mode 0)
		)
		(polygon
			(pts
				(arc
					(start 56.398922 -361.929172)
					(mid 56.488725 -361.966369)
					(end 56.525922 -362.056172)
				)
				(arc
					(start 56.525922 -362.25734)
					(mid 56.488725 -362.347143)
					(end 56.398922 -362.38434)
				)
				(arc
					(start 56.144922 -362.38434)
					(mid 56.055119 -362.347143)
					(end 56.017922 -362.25734)
				)
				(arc
					(start 56.017922 -362.056172)
					(mid 56.055119 -361.966369)
					(end 56.144922 -361.929172)
				)
			)
		)
	)
	(zone
		(layer "In1.Cu")
		(hatch none 0.5)
		(connect_pads
			(clearance 0)
		)
		(min_thickness 0.25)
		(keepout
			(tracks not_allowed)
			(vias allowed)
			(pads allowed)
			(copperpour not_allowed)
			(footprints allowed)
		)
		(placement
			(enabled no)
			(sheetname "")
		)
		(fill
			(thermal_gap 0.5)
			(thermal_bridge_width 0.5)
			(island_removal_mode 0)
		)
		(polygon
			(pts
				(arc
					(start 184.147714 -129.841752)
					(mid 184.162593 -129.805831)
					(end 184.198514 -129.790952)
				)
				(arc
					(start 185.379614 -129.790952)
					(mid 185.415535 -129.805831)
					(end 185.430414 -129.841752)
				)
				(arc
					(start 185.430414 -130.8481)
					(mid 185.415535 -130.884021)
					(end 185.379614 -130.8989)
				)
				(arc
					(start 184.198514 -130.8989)
					(mid 184.162593 -130.884021)
					(end 184.147714 -130.8481)
				)
			)
		)
	)
	(zone
		(layer "In1.Cu")
		(hatch none 0.5)
		(connect_pads
			(clearance 0)
		)
		(min_thickness 0.25)
		(keepout
			(tracks not_allowed)
			(vias allowed)
			(pads allowed)
			(copperpour not_allowed)
			(footprints allowed)
		)
		(placement
			(enabled no)
			(sheetname "")
		)
		(fill
			(thermal_gap 0.5)
			(thermal_bridge_width 0.5)
			(island_removal_mode 0)
		)
		(polygon
			(pts
				(arc
					(start 64.315848 -343.533222)
					(mid 64.279927 -343.548101)
					(end 64.265048 -343.584022)
				)
				(arc
					(start 64.265048 -344.320622)
					(mid 64.279927 -344.356543)
					(end 64.315848 -344.371422)
				)
				(xy 64.559688 -344.371422) (xy 64.914018 -344.139012) (xy 65.269618 -344.371422)
				(arc
					(start 65.512188 -344.371422)
					(mid 65.548109 -344.356543)
					(end 65.562988 -344.320622)
				)
				(arc
					(start 65.562988 -343.584022)
					(mid 65.548109 -343.548101)
					(end 65.512188 -343.533222)
				)
				(xy 65.269618 -343.533222) (xy 64.912748 -343.765632) (xy 64.558418 -343.533222)
			)
		)
	)
	(zone
		(layer "In1.Cu")
		(hatch none 0.5)
		(connect_pads
			(clearance 0)
		)
		(min_thickness 0.25)
		(keepout
			(tracks not_allowed)
			(vias allowed)
			(pads allowed)
			(copperpour not_allowed)
			(footprints allowed)
		)
		(placement
			(enabled no)
			(sheetname "")
		)
		(fill
			(thermal_gap 0.5)
			(thermal_bridge_width 0.5)
			(island_removal_mode 0)
		)
		(polygon
			(pts
				(arc
					(start 25.385014 -355.825806)
					(mid 25.349093 -355.840685)
					(end 25.334214 -355.876606)
				)
				(arc
					(start 25.334214 -356.613206)
					(mid 25.349093 -356.649127)
					(end 25.385014 -356.664006)
				)
				(xy 25.628854 -356.664006) (xy 25.983184 -356.431596) (xy 26.338784 -356.664006)
				(arc
					(start 26.581354 -356.664006)
					(mid 26.617275 -356.649127)
					(end 26.632154 -356.613206)
				)
				(arc
					(start 26.632154 -355.876606)
					(mid 26.617275 -355.840685)
					(end 26.581354 -355.825806)
				)
				(xy 26.338784 -355.825806) (xy 25.981914 -356.058216) (xy 25.627584 -355.825806)
			)
		)
	)
	(zone
		(layer "In1.Cu")
		(hatch none 0.5)
		(connect_pads
			(clearance 0)
		)
		(min_thickness 0.25)
		(keepout
			(tracks not_allowed)
			(vias allowed)
			(pads allowed)
			(copperpour not_allowed)
			(footprints allowed)
		)
		(placement
			(enabled no)
			(sheetname "")
		)
		(fill
			(thermal_gap 0.5)
			(thermal_bridge_width 0.5)
			(island_removal_mode 0)
		)
		(polygon
			(pts
				(arc
					(start 68.04787 -122.231912)
					(mid 68.062749 -122.195991)
					(end 68.09867 -122.181112)
				)
				(arc
					(start 69.27977 -122.181112)
					(mid 69.315691 -122.195991)
					(end 69.33057 -122.231912)
				)
				(arc
					(start 69.33057 -123.23826)
					(mid 69.315691 -123.274181)
					(end 69.27977 -123.28906)
				)
				(arc
					(start 68.09867 -123.28906)
					(mid 68.062749 -123.274181)
					(end 68.04787 -123.23826)
				)
			)
		)
	)
	(zone
		(layer "In1.Cu")
		(hatch none 0.5)
		(connect_pads
			(clearance 0)
		)
		(min_thickness 0.25)
		(keepout
			(tracks not_allowed)
			(vias allowed)
			(pads allowed)
			(copperpour not_allowed)
			(footprints allowed)
		)
		(placement
			(enabled no)
			(sheetname "")
		)
		(fill
			(thermal_gap 0.5)
			(thermal_bridge_width 0.5)
			(island_removal_mode 0)
		)
		(polygon
			(pts
				(arc
					(start 34.711894 -349.679514)
					(mid 34.675973 -349.694393)
					(end 34.661094 -349.730314)
				)
				(arc
					(start 34.661094 -350.466914)
					(mid 34.675973 -350.502835)
					(end 34.711894 -350.517714)
				)
				(xy 34.955734 -350.517714) (xy 35.310064 -350.285304) (xy 35.665664 -350.517714)
				(arc
					(start 35.908234 -350.517714)
					(mid 35.944155 -350.502835)
					(end 35.959034 -350.466914)
				)
				(arc
					(start 35.959034 -349.730314)
					(mid 35.944155 -349.694393)
					(end 35.908234 -349.679514)
				)
				(xy 35.665664 -349.679514) (xy 35.308794 -349.911924) (xy 34.954464 -349.679514)
			)
		)
	)
	(zone
		(layer "In1.Cu")
		(hatch none 0.5)
		(connect_pads
			(clearance 0)
		)
		(min_thickness 0.25)
		(keepout
			(tracks not_allowed)
			(vias allowed)
			(pads allowed)
			(copperpour not_allowed)
			(footprints allowed)
		)
		(placement
			(enabled no)
			(sheetname "")
		)
		(fill
			(thermal_gap 0.5)
			(thermal_bridge_width 0.5)
			(island_removal_mode 0)
		)
		(polygon
			(pts
				(arc
					(start 184.147714 -124.031756)
					(mid 184.162593 -123.995835)
					(end 184.198514 -123.980956)
				)
				(arc
					(start 185.379614 -123.980956)
					(mid 185.415535 -123.995835)
					(end 185.430414 -124.031756)
				)
				(arc
					(start 185.430414 -125.038104)
					(mid 185.415535 -125.074025)
					(end 185.379614 -125.088904)
				)
				(arc
					(start 184.198514 -125.088904)
					(mid 184.162593 -125.074025)
					(end 184.147714 -125.038104)
				)
			)
		)
	)
	(zone
		(layer "In1.Cu")
		(hatch none 0.5)
		(connect_pads
			(clearance 0)
		)
		(min_thickness 0.25)
		(keepout
			(tracks not_allowed)
			(vias allowed)
			(pads allowed)
			(copperpour not_allowed)
			(footprints allowed)
		)
		(placement
			(enabled no)
			(sheetname "")
		)
		(fill
			(thermal_gap 0.5)
			(thermal_bridge_width 0.5)
			(island_removal_mode 0)
		)
		(polygon
			(pts
				(arc
					(start 306.067206 -148.9583)
					(mid 306.052327 -148.994221)
					(end 306.016406 -149.0091)
				)
				(arc
					(start 304.835306 -149.0091)
					(mid 304.799385 -148.994221)
					(end 304.784506 -148.9583)
				)
				(arc
					(start 304.784506 -147.951952)
					(mid 304.799385 -147.916031)
					(end 304.835306 -147.901152)
				)
				(arc
					(start 306.016406 -147.901152)
					(mid 306.052327 -147.916031)
					(end 306.067206 -147.951952)
				)
			)
		)
	)
	(zone
		(layer "In1.Cu")
		(hatch none 0.5)
		(connect_pads
			(clearance 0)
		)
		(min_thickness 0.25)
		(keepout
			(tracks not_allowed)
			(vias allowed)
			(pads allowed)
			(copperpour not_allowed)
			(footprints allowed)
		)
		(placement
			(enabled no)
			(sheetname "")
		)
		(fill
			(thermal_gap 0.5)
			(thermal_bridge_width 0.5)
			(island_removal_mode 0)
		)
		(polygon
			(pts
				(arc
					(start 133.459474 -349.679514)
					(mid 133.423553 -349.694393)
					(end 133.408674 -349.730314)
				)
				(arc
					(start 133.408674 -350.466914)
					(mid 133.423553 -350.502835)
					(end 133.459474 -350.517714)
				)
				(xy 133.703314 -350.517714) (xy 134.057644 -350.285304) (xy 134.413244 -350.517714)
				(arc
					(start 134.655814 -350.517714)
					(mid 134.691735 -350.502835)
					(end 134.706614 -350.466914)
				)
				(arc
					(start 134.706614 -349.730314)
					(mid 134.691735 -349.694393)
					(end 134.655814 -349.679514)
				)
				(xy 134.413244 -349.679514) (xy 134.056374 -349.911924) (xy 133.702044 -349.679514)
			)
		)
	)
	(zone
		(layer "In1.Cu")
		(hatch none 0.5)
		(connect_pads
			(clearance 0)
		)
		(min_thickness 0.25)
		(keepout
			(tracks not_allowed)
			(vias allowed)
			(pads allowed)
			(copperpour not_allowed)
			(footprints allowed)
		)
		(placement
			(enabled no)
			(sheetname "")
		)
		(fill
			(thermal_gap 0.5)
			(thermal_bridge_width 0.5)
			(island_removal_mode 0)
		)
		(polygon
			(pts
				(arc
					(start 238.451898 -83.722718)
					(mid 238.541701 -83.759915)
					(end 238.578898 -83.849718)
				)
				(arc
					(start 238.578898 -84.052918)
					(mid 238.541701 -84.142721)
					(end 238.451898 -84.179918)
				)
				(arc
					(start 238.197898 -84.179918)
					(mid 238.108095 -84.142721)
					(end 238.070898 -84.052918)
				)
				(arc
					(start 238.070898 -83.849718)
					(mid 238.108095 -83.759915)
					(end 238.197898 -83.722718)
				)
			)
		)
	)
	(zone
		(layer "In1.Cu")
		(hatch none 0.5)
		(connect_pads
			(clearance 0)
		)
		(min_thickness 0.25)
		(keepout
			(tracks not_allowed)
			(vias allowed)
			(pads allowed)
			(copperpour not_allowed)
			(footprints allowed)
		)
		(placement
			(enabled no)
			(sheetname "")
		)
		(fill
			(thermal_gap 0.5)
			(thermal_bridge_width 0.5)
			(island_removal_mode 0)
		)
		(polygon
			(pts
				(arc
					(start 306.067206 -156.158184)
					(mid 306.052327 -156.194105)
					(end 306.016406 -156.208984)
				)
				(arc
					(start 304.835306 -156.208984)
					(mid 304.799385 -156.194105)
					(end 304.784506 -156.158184)
				)
				(arc
					(start 304.784506 -155.151836)
					(mid 304.799385 -155.115915)
					(end 304.835306 -155.101036)
				)
				(arc
					(start 306.016406 -155.101036)
					(mid 306.052327 -155.115915)
					(end 306.067206 -155.151836)
				)
			)
		)
	)
	(zone
		(layer "In1.Cu")
		(hatch none 0.5)
		(connect_pads
			(clearance 0)
		)
		(min_thickness 0.25)
		(keepout
			(tracks not_allowed)
			(vias allowed)
			(pads allowed)
			(copperpour not_allowed)
			(footprints allowed)
		)
		(placement
			(enabled no)
			(sheetname "")
		)
		(fill
			(thermal_gap 0.5)
			(thermal_bridge_width 0.5)
			(island_removal_mode 0)
		)
		(polygon
			(pts
				(arc
					(start 409.129738 -343.533222)
					(mid 409.093817 -343.548101)
					(end 409.078938 -343.584022)
				)
				(arc
					(start 409.078938 -344.320622)
					(mid 409.093817 -344.356543)
					(end 409.129738 -344.371422)
				)
				(xy 409.373578 -344.371422) (xy 409.727908 -344.139012) (xy 410.083508 -344.371422)
				(arc
					(start 410.326078 -344.371422)
					(mid 410.361999 -344.356543)
					(end 410.376878 -344.320622)
				)
				(arc
					(start 410.376878 -343.584022)
					(mid 410.361999 -343.548101)
					(end 410.326078 -343.533222)
				)
				(xy 410.083508 -343.533222) (xy 409.726638 -343.765632) (xy 409.372308 -343.533222)
			)
		)
	)
	(zone
		(layer "In1.Cu")
		(hatch none 0.5)
		(connect_pads
			(clearance 0)
		)
		(min_thickness 0.25)
		(keepout
			(tracks not_allowed)
			(vias allowed)
			(pads allowed)
			(copperpour not_allowed)
			(footprints allowed)
		)
		(placement
			(enabled no)
			(sheetname "")
		)
		(fill
			(thermal_gap 0.5)
			(thermal_bridge_width 0.5)
			(island_removal_mode 0)
		)
		(polygon
			(pts
				(arc
					(start 343.42705 -355.825806)
					(mid 343.391129 -355.840685)
					(end 343.37625 -355.876606)
				)
				(arc
					(start 343.37625 -356.613206)
					(mid 343.391129 -356.649127)
					(end 343.42705 -356.664006)
				)
				(xy 343.67089 -356.664006) (xy 344.02522 -356.431596) (xy 344.38082 -356.664006)
				(arc
					(start 344.62339 -356.664006)
					(mid 344.659311 -356.649127)
					(end 344.67419 -356.613206)
				)
				(arc
					(start 344.67419 -355.876606)
					(mid 344.659311 -355.840685)
					(end 344.62339 -355.825806)
				)
				(xy 344.38082 -355.825806) (xy 344.02395 -356.058216) (xy 343.66962 -355.825806)
			)
		)
	)
	(zone
		(layer "In1.Cu")
		(hatch none 0.5)
		(connect_pads
			(clearance 0)
		)
		(min_thickness 0.25)
		(keepout
			(tracks not_allowed)
			(vias allowed)
			(pads allowed)
			(copperpour not_allowed)
			(footprints allowed)
		)
		(placement
			(enabled no)
			(sheetname "")
		)
		(fill
			(thermal_gap 0.5)
			(thermal_bridge_width 0.5)
			(island_removal_mode 0)
		)
		(polygon
			(pts
				(arc
					(start 189.967108 -156.158184)
					(mid 189.952229 -156.194105)
					(end 189.916308 -156.208984)
				)
				(arc
					(start 188.735208 -156.208984)
					(mid 188.699287 -156.194105)
					(end 188.684408 -156.158184)
				)
				(arc
					(start 188.684408 -155.151836)
					(mid 188.699287 -155.115915)
					(end 188.735208 -155.101036)
				)
				(arc
					(start 189.916308 -155.101036)
					(mid 189.952229 -155.115915)
					(end 189.967108 -155.151836)
				)
			)
		)
	)
	(zone
		(layer "In1.Cu")
		(hatch none 0.5)
		(connect_pads
			(clearance 0)
		)
		(min_thickness 0.25)
		(keepout
			(tracks not_allowed)
			(vias allowed)
			(pads allowed)
			(copperpour not_allowed)
			(footprints allowed)
		)
		(placement
			(enabled no)
			(sheetname "")
		)
		(fill
			(thermal_gap 0.5)
			(thermal_bridge_width 0.5)
			(island_removal_mode 0)
		)
		(polygon
			(pts
				(arc
					(start 339.37956 17.486884)
					(mid 339.357242 17.433002)
					(end 339.30336 17.410684)
				)
				(arc
					(start 338.69122 17.410684)
					(mid 338.637338 17.433002)
					(end 338.61502 17.486884)
				)
				(arc
					(start 338.61502 18.584164)
					(mid 338.637338 18.638046)
					(end 338.69122 18.660364)
				)
				(arc
					(start 339.30336 18.660364)
					(mid 339.357242 18.638046)
					(end 339.37956 18.584164)
				)
			)
		)
	)
	(zone
		(layer "In1.Cu")
		(hatch none 0.5)
		(connect_pads
			(clearance 0)
		)
		(min_thickness 0.25)
		(keepout
			(tracks not_allowed)
			(vias allowed)
			(pads allowed)
			(copperpour not_allowed)
			(footprints allowed)
		)
		(placement
			(enabled no)
			(sheetname "")
		)
		(fill
			(thermal_gap 0.5)
			(thermal_bridge_width 0.5)
			(island_removal_mode 0)
		)
		(polygon
			(pts
				(arc
					(start 159.473392 -32.879538)
					(mid 159.488271 -32.915459)
					(end 159.524192 -32.930338)
				)
				(arc
					(start 160.260792 -32.930338)
					(mid 160.296713 -32.915459)
					(end 160.311592 -32.879538)
				)
				(xy 160.311592 -32.635698) (xy 160.079182 -32.281368) (xy 160.311592 -31.925768)
				(arc
					(start 160.311592 -31.683198)
					(mid 160.296713 -31.647277)
					(end 160.260792 -31.632398)
				)
				(arc
					(start 159.524192 -31.632398)
					(mid 159.488271 -31.647277)
					(end 159.473392 -31.683198)
				)
				(xy 159.473392 -31.925768) (xy 159.705802 -32.282638) (xy 159.473392 -32.636968)
			)
		)
	)
	(zone
		(layer "In1.Cu")
		(hatch none 0.5)
		(connect_pads
			(clearance 0)
		)
		(min_thickness 0.25)
		(keepout
			(tracks not_allowed)
			(vias allowed)
			(pads allowed)
			(copperpour not_allowed)
			(footprints allowed)
		)
		(placement
			(enabled no)
			(sheetname "")
		)
		(fill
			(thermal_gap 0.5)
			(thermal_bridge_width 0.5)
			(island_removal_mode 0)
		)
		(polygon
			(pts
				(arc
					(start 417.673282 -29.279596)
					(mid 417.688161 -29.315517)
					(end 417.724082 -29.330396)
				)
				(arc
					(start 418.460682 -29.330396)
					(mid 418.496603 -29.315517)
					(end 418.511482 -29.279596)
				)
				(xy 418.511482 -29.035756) (xy 418.279072 -28.681426) (xy 418.511482 -28.325826)
				(arc
					(start 418.511482 -28.083256)
					(mid 418.496603 -28.047335)
					(end 418.460682 -28.032456)
				)
				(arc
					(start 417.724082 -28.032456)
					(mid 417.688161 -28.047335)
					(end 417.673282 -28.083256)
				)
				(xy 417.673282 -28.325826) (xy 417.905692 -28.682696) (xy 417.673282 -29.037026)
			)
		)
	)
	(zone
		(layer "In1.Cu")
		(hatch none 0.5)
		(connect_pads
			(clearance 0)
		)
		(min_thickness 0.25)
		(keepout
			(tracks not_allowed)
			(vias allowed)
			(pads allowed)
			(copperpour not_allowed)
			(footprints allowed)
		)
		(placement
			(enabled no)
			(sheetname "")
		)
		(fill
			(thermal_gap 0.5)
			(thermal_bridge_width 0.5)
			(island_removal_mode 0)
		)
		(polygon
			(pts
				(arc
					(start 124.132594 -343.533222)
					(mid 124.096673 -343.548101)
					(end 124.081794 -343.584022)
				)
				(arc
					(start 124.081794 -344.320622)
					(mid 124.096673 -344.356543)
					(end 124.132594 -344.371422)
				)
				(xy 124.376434 -344.371422) (xy 124.730764 -344.139012) (xy 125.086364 -344.371422)
				(arc
					(start 125.328934 -344.371422)
					(mid 125.364855 -344.356543)
					(end 125.379734 -344.320622)
				)
				(arc
					(start 125.379734 -343.584022)
					(mid 125.364855 -343.548101)
					(end 125.328934 -343.533222)
				)
				(xy 125.086364 -343.533222) (xy 124.729494 -343.765632) (xy 124.375164 -343.533222)
			)
		)
	)
	(zone
		(layer "In1.Cu")
		(hatch none 0.5)
		(connect_pads
			(clearance 0)
		)
		(min_thickness 0.25)
		(keepout
			(tracks not_allowed)
			(vias allowed)
			(pads allowed)
			(copperpour not_allowed)
			(footprints allowed)
		)
		(placement
			(enabled no)
			(sheetname "")
		)
		(fill
			(thermal_gap 0.5)
			(thermal_bridge_width 0.5)
			(island_removal_mode 0)
		)
		(polygon
			(pts
				(arc
					(start 69.373242 -29.279596)
					(mid 69.388121 -29.315517)
					(end 69.424042 -29.330396)
				)
				(arc
					(start 70.160642 -29.330396)
					(mid 70.196563 -29.315517)
					(end 70.211442 -29.279596)
				)
				(xy 70.211442 -29.035756) (xy 69.979032 -28.681426) (xy 70.211442 -28.325826)
				(arc
					(start 70.211442 -28.083256)
					(mid 70.196563 -28.047335)
					(end 70.160642 -28.032456)
				)
				(arc
					(start 69.424042 -28.032456)
					(mid 69.388121 -28.047335)
					(end 69.373242 -28.083256)
				)
				(xy 69.373242 -28.325826) (xy 69.605652 -28.682696) (xy 69.373242 -29.037026)
			)
		)
	)
	(zone
		(layer "In1.Cu")
		(hatch none 0.5)
		(connect_pads
			(clearance 0)
		)
		(min_thickness 0.25)
		(keepout
			(tracks not_allowed)
			(vias allowed)
			(pads allowed)
			(copperpour not_allowed)
			(footprints allowed)
		)
		(placement
			(enabled no)
			(sheetname "")
		)
		(fill
			(thermal_gap 0.5)
			(thermal_bridge_width 0.5)
			(island_removal_mode 0)
		)
		(polygon
			(pts
				(arc
					(start 67.899788 -34.605976)
					(mid 67.884909 -34.641897)
					(end 67.848988 -34.656776)
				)
				(arc
					(start 66.617088 -34.656776)
					(mid 66.581167 -34.641897)
					(end 66.566288 -34.605976)
				)
				(arc
					(start 66.566288 -33.574228)
					(mid 66.581167 -33.538307)
					(end 66.617088 -33.523428)
				)
				(arc
					(start 67.848988 -33.523428)
					(mid 67.884909 -33.538307)
					(end 67.899788 -33.574228)
				)
			)
		)
	)
	(zone
		(layer "In1.Cu")
		(hatch none 0.5)
		(connect_pads
			(clearance 0)
		)
		(min_thickness 0.25)
		(keepout
			(tracks not_allowed)
			(vias allowed)
			(pads allowed)
			(copperpour not_allowed)
			(footprints allowed)
		)
		(placement
			(enabled no)
			(sheetname "")
		)
		(fill
			(thermal_gap 0.5)
			(thermal_bridge_width 0.5)
			(island_removal_mode 0)
		)
		(polygon
			(pts
				(arc
					(start 184.147714 -155.151836)
					(mid 184.162593 -155.115915)
					(end 184.198514 -155.101036)
				)
				(arc
					(start 185.379614 -155.101036)
					(mid 185.415535 -155.115915)
					(end 185.430414 -155.151836)
				)
				(arc
					(start 185.430414 -156.158184)
					(mid 185.415535 -156.194105)
					(end 185.379614 -156.208984)
				)
				(arc
					(start 184.198514 -156.208984)
					(mid 184.162593 -156.194105)
					(end 184.147714 -156.158184)
				)
			)
		)
	)
	(zone
		(layer "In1.Cu")
		(hatch none 0.5)
		(connect_pads
			(clearance 0)
		)
		(min_thickness 0.25)
		(keepout
			(tracks not_allowed)
			(vias allowed)
			(pads allowed)
			(copperpour not_allowed)
			(footprints allowed)
		)
		(placement
			(enabled no)
			(sheetname "")
		)
		(fill
			(thermal_gap 0.5)
			(thermal_bridge_width 0.5)
			(island_removal_mode 0)
		)
		(polygon
			(pts
				(arc
					(start 393.732766 -130.361944)
					(mid 393.747645 -130.326023)
					(end 393.783566 -130.311144)
				)
				(arc
					(start 394.964666 -130.311144)
					(mid 395.000587 -130.326023)
					(end 395.015466 -130.361944)
				)
				(arc
					(start 395.015466 -131.368292)
					(mid 395.000587 -131.404213)
					(end 394.964666 -131.419092)
				)
				(arc
					(start 393.783566 -131.419092)
					(mid 393.747645 -131.404213)
					(end 393.732766 -131.368292)
				)
			)
		)
	)
	(zone
		(layer "In1.Cu")
		(hatch none 0.5)
		(connect_pads
			(clearance 0)
		)
		(min_thickness 0.25)
		(keepout
			(tracks not_allowed)
			(vias allowed)
			(pads allowed)
			(copperpour not_allowed)
			(footprints allowed)
		)
		(placement
			(enabled no)
			(sheetname "")
		)
		(fill
			(thermal_gap 0.5)
			(thermal_bridge_width 0.5)
			(island_removal_mode 0)
		)
		(polygon
			(pts
				(arc
					(start 161.53257 -104.641904)
					(mid 161.547449 -104.605983)
					(end 161.58337 -104.591104)
				)
				(arc
					(start 162.76447 -104.591104)
					(mid 162.800391 -104.605983)
					(end 162.81527 -104.641904)
				)
				(arc
					(start 162.81527 -105.648252)
					(mid 162.800391 -105.684173)
					(end 162.76447 -105.699052)
				)
				(arc
					(start 161.58337 -105.699052)
					(mid 161.547449 -105.684173)
					(end 161.53257 -105.648252)
				)
			)
		)
	)
	(zone
		(layer "In1.Cu")
		(hatch none 0.5)
		(connect_pads
			(clearance 0)
		)
		(min_thickness 0.25)
		(keepout
			(tracks not_allowed)
			(vias allowed)
			(pads allowed)
			(copperpour not_allowed)
			(footprints allowed)
		)
		(placement
			(enabled no)
			(sheetname "")
		)
		(fill
			(thermal_gap 0.5)
			(thermal_bridge_width 0.5)
			(island_removal_mode 0)
		)
		(polygon
			(pts
				(arc
					(start 230.40721 -78.85176)
					(mid 230.392331 -78.887681)
					(end 230.35641 -78.90256)
				)
				(arc
					(start 230.30307 -78.90256)
					(mid 230.267149 -78.887681)
					(end 230.25227 -78.85176)
				)
				(arc
					(start 230.25227 -78.239874)
					(mid 230.267149 -78.203953)
					(end 230.30307 -78.189074)
				)
				(arc
					(start 230.35641 -78.189074)
					(mid 230.392331 -78.203953)
					(end 230.40721 -78.239874)
				)
			)
		)
	)
	(zone
		(layer "In1.Cu")
		(hatch none 0.5)
		(connect_pads
			(clearance 0)
		)
		(min_thickness 0.25)
		(keepout
			(tracks not_allowed)
			(vias allowed)
			(pads allowed)
			(copperpour not_allowed)
			(footprints allowed)
		)
		(placement
			(enabled no)
			(sheetname "")
		)
		(fill
			(thermal_gap 0.5)
			(thermal_bridge_width 0.5)
			(island_removal_mode 0)
		)
		(polygon
			(pts
				(arc
					(start 45.432726 -133.96214)
					(mid 45.447605 -133.926219)
					(end 45.483526 -133.91134)
				)
				(arc
					(start 46.664626 -133.91134)
					(mid 46.700547 -133.926219)
					(end 46.715426 -133.96214)
				)
				(arc
					(start 46.715426 -134.968488)
					(mid 46.700547 -135.004409)
					(end 46.664626 -135.019288)
				)
				(arc
					(start 45.483526 -135.019288)
					(mid 45.447605 -135.004409)
					(end 45.432726 -134.968488)
				)
			)
		)
	)
	(zone
		(layer "In1.Cu")
		(hatch none 0.5)
		(connect_pads
			(clearance 0)
		)
		(min_thickness 0.25)
		(keepout
			(tracks not_allowed)
			(vias allowed)
			(pads allowed)
			(copperpour not_allowed)
			(footprints allowed)
		)
		(placement
			(enabled no)
			(sheetname "")
		)
		(fill
			(thermal_gap 0.5)
			(thermal_bridge_width 0.5)
			(island_removal_mode 0)
		)
		(polygon
			(pts
				(arc
					(start 311.80024 -150.844504)
					(mid 311.815119 -150.880425)
					(end 311.85104 -150.895304)
				)
				(arc
					(start 312.58764 -150.895304)
					(mid 312.623561 -150.880425)
					(end 312.63844 -150.844504)
				)
				(xy 312.63844 -150.600664) (xy 312.40603 -150.246334) (xy 312.63844 -149.890734)
				(arc
					(start 312.63844 -149.648164)
					(mid 312.623561 -149.612243)
					(end 312.58764 -149.597364)
				)
				(arc
					(start 311.85104 -149.597364)
					(mid 311.815119 -149.612243)
					(end 311.80024 -149.648164)
				)
				(xy 311.80024 -149.890734) (xy 312.03265 -150.247604) (xy 311.80024 -150.601934)
			)
		)
	)
	(zone
		(layer "In1.Cu")
		(hatch none 0.5)
		(connect_pads
			(clearance 0)
		)
		(min_thickness 0.25)
		(keepout
			(tracks not_allowed)
			(vias allowed)
			(pads allowed)
			(copperpour not_allowed)
			(footprints allowed)
		)
		(placement
			(enabled no)
			(sheetname "")
		)
		(fill
			(thermal_gap 0.5)
			(thermal_bridge_width 0.5)
			(island_removal_mode 0)
		)
		(polygon
			(pts
				(arc
					(start 104.644698 -379.496574)
					(mid 104.734501 -379.533771)
					(end 104.771698 -379.623574)
				)
				(arc
					(start 104.771698 -379.824742)
					(mid 104.734501 -379.914545)
					(end 104.644698 -379.951742)
				)
				(arc
					(start 104.390698 -379.951742)
					(mid 104.300895 -379.914545)
					(end 104.263698 -379.824742)
				)
				(arc
					(start 104.263698 -379.623574)
					(mid 104.300895 -379.533771)
					(end 104.390698 -379.496574)
				)
			)
		)
	)
	(zone
		(layer "In1.Cu")
		(hatch none 0.5)
		(connect_pads
			(clearance 0)
		)
		(min_thickness 0.25)
		(keepout
			(tracks not_allowed)
			(vias allowed)
			(pads allowed)
			(copperpour not_allowed)
			(footprints allowed)
		)
		(placement
			(enabled no)
			(sheetname "")
		)
		(fill
			(thermal_gap 0.5)
			(thermal_bridge_width 0.5)
			(island_removal_mode 0)
		)
		(polygon
			(pts
				(arc
					(start 271.061434 -100.343208)
					(mid 271.076313 -100.379129)
					(end 271.112234 -100.394008)
				)
				(arc
					(start 271.848834 -100.394008)
					(mid 271.884755 -100.379129)
					(end 271.899634 -100.343208)
				)
				(xy 271.899634 -100.099368) (xy 271.667224 -99.745038) (xy 271.899634 -99.389438)
				(arc
					(start 271.899634 -99.146868)
					(mid 271.884755 -99.110947)
					(end 271.848834 -99.096068)
				)
				(arc
					(start 271.112234 -99.096068)
					(mid 271.076313 -99.110947)
					(end 271.061434 -99.146868)
				)
				(xy 271.061434 -99.389438) (xy 271.293844 -99.746308) (xy 271.061434 -100.100638)
			)
		)
	)
	(zone
		(layer "In1.Cu")
		(hatch none 0.5)
		(connect_pads
			(clearance 0)
		)
		(min_thickness 0.25)
		(keepout
			(tracks not_allowed)
			(vias allowed)
			(pads allowed)
			(copperpour not_allowed)
			(footprints allowed)
		)
		(placement
			(enabled no)
			(sheetname "")
		)
		(fill
			(thermal_gap 0.5)
			(thermal_bridge_width 0.5)
			(island_removal_mode 0)
		)
		(polygon
			(pts
				(arc
					(start 232.59669 -83.490308)
					(mid 232.686493 -83.527505)
					(end 232.72369 -83.617308)
				)
				(arc
					(start 232.72369 -83.820508)
					(mid 232.686493 -83.910311)
					(end 232.59669 -83.947508)
				)
				(arc
					(start 232.34269 -83.947508)
					(mid 232.252887 -83.910311)
					(end 232.21569 -83.820508)
				)
				(arc
					(start 232.21569 -83.617308)
					(mid 232.252887 -83.527505)
					(end 232.34269 -83.490308)
				)
			)
		)
	)
	(zone
		(layer "In1.Cu")
		(hatch none 0.5)
		(connect_pads
			(clearance 0)
		)
		(min_thickness 0.25)
		(keepout
			(tracks not_allowed)
			(vias allowed)
			(pads allowed)
			(copperpour not_allowed)
			(footprints allowed)
		)
		(placement
			(enabled no)
			(sheetname "")
		)
		(fill
			(thermal_gap 0.5)
			(thermal_bridge_width 0.5)
			(island_removal_mode 0)
		)
		(polygon
			(pts
				(arc
					(start 189.967108 -119.638064)
					(mid 189.952229 -119.673985)
					(end 189.916308 -119.688864)
				)
				(arc
					(start 188.735208 -119.688864)
					(mid 188.699287 -119.673985)
					(end 188.684408 -119.638064)
				)
				(arc
					(start 188.684408 -118.631716)
					(mid 188.699287 -118.595795)
					(end 188.735208 -118.580916)
				)
				(arc
					(start 189.916308 -118.580916)
					(mid 189.952229 -118.595795)
					(end 189.967108 -118.631716)
				)
			)
		)
	)
	(zone
		(layer "In1.Cu")
		(hatch none 0.5)
		(connect_pads
			(clearance 0)
		)
		(min_thickness 0.25)
		(keepout
			(tracks not_allowed)
			(vias allowed)
			(pads allowed)
			(copperpour not_allowed)
			(footprints allowed)
		)
		(placement
			(enabled no)
			(sheetname "")
		)
		(fill
			(thermal_gap 0.5)
			(thermal_bridge_width 0.5)
			(island_removal_mode 0)
		)
		(polygon
			(pts
				(arc
					(start 321.66433 -343.533222)
					(mid 321.628409 -343.548101)
					(end 321.61353 -343.584022)
				)
				(arc
					(start 321.61353 -344.320622)
					(mid 321.628409 -344.356543)
					(end 321.66433 -344.371422)
				)
				(xy 321.90817 -344.371422) (xy 322.2625 -344.139012) (xy 322.6181 -344.371422)
				(arc
					(start 322.86067 -344.371422)
					(mid 322.896591 -344.356543)
					(end 322.91147 -344.320622)
				)
				(arc
					(start 322.91147 -343.584022)
					(mid 322.896591 -343.548101)
					(end 322.86067 -343.533222)
				)
				(xy 322.6181 -343.533222) (xy 322.26123 -343.765632) (xy 321.9069 -343.533222)
			)
		)
	)
	(zone
		(layer "In1.Cu")
		(hatch none 0.5)
		(connect_pads
			(clearance 0)
		)
		(min_thickness 0.25)
		(keepout
			(tracks not_allowed)
			(vias allowed)
			(pads allowed)
			(copperpour not_allowed)
			(footprints allowed)
		)
		(placement
			(enabled no)
			(sheetname "")
		)
		(fill
			(thermal_gap 0.5)
			(thermal_bridge_width 0.5)
			(island_removal_mode 0)
		)
		(polygon
			(pts
				(arc
					(start 14.280134 -382.75387)
					(mid 14.317331 -382.664067)
					(end 14.407134 -382.62687)
				)
				(arc
					(start 14.753082 -382.62687)
					(mid 14.842885 -382.664067)
					(end 14.880082 -382.75387)
				)
				(arc
					(start 14.880082 -383.239772)
					(mid 14.842885 -383.329575)
					(end 14.753082 -383.366772)
				)
				(arc
					(start 14.407134 -383.366772)
					(mid 14.317331 -383.329575)
					(end 14.280134 -383.239772)
				)
			)
		)
	)
	(zone
		(layer "In1.Cu")
		(hatch none 0.5)
		(connect_pads
			(clearance 0)
		)
		(min_thickness 0.25)
		(keepout
			(tracks not_allowed)
			(vias allowed)
			(pads allowed)
			(copperpour not_allowed)
			(footprints allowed)
		)
		(placement
			(enabled no)
			(sheetname "")
		)
		(fill
			(thermal_gap 0.5)
			(thermal_bridge_width 0.5)
			(island_removal_mode 0)
		)
		(polygon
			(pts
				(arc
					(start 13.60043 -378.204984)
					(mid 13.564509 -378.190105)
					(end 13.54963 -378.154184)
				)
				(arc
					(start 13.54963 -377.74753)
					(mid 13.564509 -377.711609)
					(end 13.60043 -377.69673)
				)
				(arc
					(start 14.002766 -377.69673)
					(mid 14.038687 -377.711609)
					(end 14.053566 -377.74753)
				)
				(arc
					(start 14.053566 -378.154184)
					(mid 14.038687 -378.190105)
					(end 14.002766 -378.204984)
				)
			)
		)
	)
	(zone
		(layer "In1.Cu")
		(hatch none 0.5)
		(connect_pads
			(clearance 0)
		)
		(min_thickness 0.25)
		(keepout
			(tracks not_allowed)
			(vias allowed)
			(pads allowed)
			(copperpour not_allowed)
			(footprints allowed)
		)
		(placement
			(enabled no)
			(sheetname "")
		)
		(fill
			(thermal_gap 0.5)
			(thermal_bridge_width 0.5)
			(island_removal_mode 0)
		)
		(polygon
			(pts
				(arc
					(start 10.029952 -33.574228)
					(mid 10.044831 -33.538307)
					(end 10.080752 -33.523428)
				)
				(arc
					(start 11.312652 -33.523428)
					(mid 11.348573 -33.538307)
					(end 11.363452 -33.574228)
				)
				(arc
					(start 11.363452 -34.605976)
					(mid 11.348573 -34.641897)
					(end 11.312652 -34.656776)
				)
				(arc
					(start 10.080752 -34.656776)
					(mid 10.044831 -34.641897)
					(end 10.029952 -34.605976)
				)
			)
		)
	)
	(zone
		(layer "In1.Cu")
		(hatch none 0.5)
		(connect_pads
			(clearance 0)
		)
		(min_thickness 0.25)
		(keepout
			(tracks not_allowed)
			(vias allowed)
			(pads allowed)
			(copperpour not_allowed)
			(footprints allowed)
		)
		(placement
			(enabled no)
			(sheetname "")
		)
		(fill
			(thermal_gap 0.5)
			(thermal_bridge_width 0.5)
			(island_removal_mode 0)
		)
		(polygon
			(pts
				(arc
					(start 387.161532 -107.543092)
					(mid 387.176411 -107.579013)
					(end 387.212332 -107.593892)
				)
				(arc
					(start 387.948932 -107.593892)
					(mid 387.984853 -107.579013)
					(end 387.999732 -107.543092)
				)
				(xy 387.999732 -107.299252) (xy 387.767322 -106.944922) (xy 387.999732 -106.589322)
				(arc
					(start 387.999732 -106.346752)
					(mid 387.984853 -106.310831)
					(end 387.948932 -106.295952)
				)
				(arc
					(start 387.212332 -106.295952)
					(mid 387.176411 -106.310831)
					(end 387.161532 -106.346752)
				)
				(xy 387.161532 -106.589322) (xy 387.393942 -106.946192) (xy 387.161532 -107.300522)
			)
		)
	)
	(zone
		(layer "In1.Cu")
		(hatch none 0.5)
		(connect_pads
			(clearance 0)
		)
		(min_thickness 0.25)
		(keepout
			(tracks not_allowed)
			(vias allowed)
			(pads allowed)
			(copperpour not_allowed)
			(footprints allowed)
		)
		(placement
			(enabled no)
			(sheetname "")
		)
		(fill
			(thermal_gap 0.5)
			(thermal_bridge_width 0.5)
			(island_removal_mode 0)
		)
		(polygon
			(pts
				(arc
					(start 393.732766 -132.162042)
					(mid 393.747645 -132.126121)
					(end 393.783566 -132.111242)
				)
				(arc
					(start 394.964666 -132.111242)
					(mid 395.000587 -132.126121)
					(end 395.015466 -132.162042)
				)
				(arc
					(start 395.015466 -133.16839)
					(mid 395.000587 -133.204311)
					(end 394.964666 -133.21919)
				)
				(arc
					(start 393.783566 -133.21919)
					(mid 393.747645 -133.204311)
					(end 393.732766 -133.16839)
				)
			)
		)
	)
	(zone
		(layer "In1.Cu")
		(hatch none 0.5)
		(connect_pads
			(clearance 0)
		)
		(min_thickness 0.25)
		(keepout
			(tracks not_allowed)
			(vias allowed)
			(pads allowed)
			(copperpour not_allowed)
			(footprints allowed)
		)
		(placement
			(enabled no)
			(sheetname "")
		)
		(fill
			(thermal_gap 0.5)
			(thermal_bridge_width 0.5)
			(island_removal_mode 0)
		)
		(polygon
			(pts
				(arc
					(start 79.600298 -147.244562)
					(mid 79.615177 -147.280483)
					(end 79.651098 -147.295362)
				)
				(arc
					(start 80.387698 -147.295362)
					(mid 80.423619 -147.280483)
					(end 80.438498 -147.244562)
				)
				(xy 80.438498 -147.000722) (xy 80.206088 -146.646392) (xy 80.438498 -146.290792)
				(arc
					(start 80.438498 -146.048222)
					(mid 80.423619 -146.012301)
					(end 80.387698 -145.997422)
				)
				(arc
					(start 79.651098 -145.997422)
					(mid 79.615177 -146.012301)
					(end 79.600298 -146.048222)
				)
				(xy 79.600298 -146.290792) (xy 79.832708 -146.647662) (xy 79.600298 -147.001992)
			)
		)
	)
	(zone
		(layer "In1.Cu")
		(hatch none 0.5)
		(connect_pads
			(clearance 0)
		)
		(min_thickness 0.25)
		(keepout
			(tracks not_allowed)
			(vias allowed)
			(pads allowed)
			(copperpour not_allowed)
			(footprints allowed)
		)
		(placement
			(enabled no)
			(sheetname "")
		)
		(fill
			(thermal_gap 0.5)
			(thermal_bridge_width 0.5)
			(island_removal_mode 0)
		)
		(polygon
			(pts
				(arc
					(start 292.603428 -343.533222)
					(mid 292.567507 -343.548101)
					(end 292.552628 -343.584022)
				)
				(arc
					(start 292.552628 -344.320622)
					(mid 292.567507 -344.356543)
					(end 292.603428 -344.371422)
				)
				(xy 292.847268 -344.371422) (xy 293.201598 -344.139012) (xy 293.557198 -344.371422)
				(arc
					(start 293.799768 -344.371422)
					(mid 293.835689 -344.356543)
					(end 293.850568 -344.320622)
				)
				(arc
					(start 293.850568 -343.584022)
					(mid 293.835689 -343.548101)
					(end 293.799768 -343.533222)
				)
				(xy 293.557198 -343.533222) (xy 293.200328 -343.765632) (xy 292.845998 -343.533222)
			)
		)
	)
	(zone
		(layer "In1.Cu")
		(hatch none 0.5)
		(connect_pads
			(clearance 0)
		)
		(min_thickness 0.25)
		(keepout
			(tracks not_allowed)
			(vias allowed)
			(pads allowed)
			(copperpour not_allowed)
			(footprints allowed)
		)
		(placement
			(enabled no)
			(sheetname "")
		)
		(fill
			(thermal_gap 0.5)
			(thermal_bridge_width 0.5)
			(island_removal_mode 0)
		)
		(polygon
			(pts
				(arc
					(start 306.067206 -130.8481)
					(mid 306.052327 -130.884021)
					(end 306.016406 -130.8989)
				)
				(arc
					(start 304.835306 -130.8989)
					(mid 304.799385 -130.884021)
					(end 304.784506 -130.8481)
				)
				(arc
					(start 304.784506 -129.841752)
					(mid 304.799385 -129.805831)
					(end 304.835306 -129.790952)
				)
				(arc
					(start 306.016406 -129.790952)
					(mid 306.052327 -129.805831)
					(end 306.067206 -129.841752)
				)
			)
		)
	)
	(zone
		(layer "In1.Cu")
		(hatch none 0.5)
		(connect_pads
			(clearance 0)
		)
		(min_thickness 0.25)
		(keepout
			(tracks not_allowed)
			(vias allowed)
			(pads allowed)
			(copperpour not_allowed)
			(footprints allowed)
		)
		(placement
			(enabled no)
			(sheetname "")
		)
		(fill
			(thermal_gap 0.5)
			(thermal_bridge_width 0.5)
			(island_removal_mode 0)
		)
		(polygon
			(pts
				(arc
					(start 248.099834 -31.006034)
					(mid 248.084955 -31.041955)
					(end 248.049034 -31.056834)
				)
				(arc
					(start 246.817134 -31.056834)
					(mid 246.781213 -31.041955)
					(end 246.766334 -31.006034)
				)
				(arc
					(start 246.766334 -29.974286)
					(mid 246.781213 -29.938365)
					(end 246.817134 -29.923486)
				)
				(arc
					(start 248.049034 -29.923486)
					(mid 248.084955 -29.938365)
					(end 248.099834 -29.974286)
				)
			)
		)
	)
	(zone
		(layer "In1.Cu")
		(hatch none 0.5)
		(connect_pads
			(clearance 0)
		)
		(min_thickness 0.25)
		(keepout
			(tracks not_allowed)
			(vias allowed)
			(pads allowed)
			(copperpour not_allowed)
			(footprints allowed)
		)
		(placement
			(enabled no)
			(sheetname "")
		)
		(fill
			(thermal_gap 0.5)
			(thermal_bridge_width 0.5)
			(island_removal_mode 0)
		)
		(polygon
			(pts
				(arc
					(start 311.80024 -143.64462)
					(mid 311.815119 -143.680541)
					(end 311.85104 -143.69542)
				)
				(arc
					(start 312.58764 -143.69542)
					(mid 312.623561 -143.680541)
					(end 312.63844 -143.64462)
				)
				(xy 312.63844 -143.40078) (xy 312.40603 -143.04645) (xy 312.63844 -142.69085)
				(arc
					(start 312.63844 -142.44828)
					(mid 312.623561 -142.412359)
					(end 312.58764 -142.39748)
				)
				(arc
					(start 311.85104 -142.39748)
					(mid 311.815119 -142.412359)
					(end 311.80024 -142.44828)
				)
				(xy 311.80024 -142.69085) (xy 312.03265 -143.04772) (xy 311.80024 -143.40205)
			)
		)
	)
	(zone
		(layer "In1.Cu")
		(hatch none 0.5)
		(connect_pads
			(clearance 0)
		)
		(min_thickness 0.25)
		(keepout
			(tracks not_allowed)
			(vias allowed)
			(pads allowed)
			(copperpour not_allowed)
			(footprints allowed)
		)
		(placement
			(enabled no)
			(sheetname "")
		)
		(fill
			(thermal_gap 0.5)
			(thermal_bridge_width 0.5)
			(island_removal_mode 0)
		)
		(polygon
			(pts
				(arc
					(start 422.167304 -136.24814)
					(mid 422.152425 -136.284061)
					(end 422.116504 -136.29894)
				)
				(arc
					(start 420.935404 -136.29894)
					(mid 420.899483 -136.284061)
					(end 420.884604 -136.24814)
				)
				(arc
					(start 420.884604 -135.241792)
					(mid 420.899483 -135.205871)
					(end 420.935404 -135.190992)
				)
				(arc
					(start 422.116504 -135.190992)
					(mid 422.152425 -135.205871)
					(end 422.167304 -135.241792)
				)
			)
		)
	)
	(zone
		(layer "In1.Cu")
		(hatch none 0.5)
		(connect_pads
			(clearance 0)
		)
		(min_thickness 0.25)
		(keepout
			(tracks not_allowed)
			(vias allowed)
			(pads allowed)
			(copperpour not_allowed)
			(footprints allowed)
		)
		(placement
			(enabled no)
			(sheetname "")
		)
		(fill
			(thermal_gap 0.5)
			(thermal_bridge_width 0.5)
			(island_removal_mode 0)
		)
		(polygon
			(pts
				(arc
					(start 92.296488 -355.825806)
					(mid 92.260567 -355.840685)
					(end 92.245688 -355.876606)
				)
				(arc
					(start 92.245688 -356.613206)
					(mid 92.260567 -356.649127)
					(end 92.296488 -356.664006)
				)
				(xy 92.540328 -356.664006) (xy 92.894658 -356.431596) (xy 93.250258 -356.664006)
				(arc
					(start 93.492828 -356.664006)
					(mid 93.528749 -356.649127)
					(end 93.543628 -356.613206)
				)
				(arc
					(start 93.543628 -355.876606)
					(mid 93.528749 -355.840685)
					(end 93.492828 -355.825806)
				)
				(xy 93.250258 -355.825806) (xy 92.893388 -356.058216) (xy 92.539058 -355.825806)
			)
		)
	)
	(zone
		(layer "In1.Cu")
		(hatch none 0.5)
		(connect_pads
			(clearance 0)
		)
		(min_thickness 0.25)
		(keepout
			(tracks not_allowed)
			(vias allowed)
			(pads allowed)
			(copperpour not_allowed)
			(footprints allowed)
		)
		(placement
			(enabled no)
			(sheetname "")
		)
		(fill
			(thermal_gap 0.5)
			(thermal_bridge_width 0.5)
			(island_removal_mode 0)
		)
		(polygon
			(pts
				(arc
					(start 395.894306 -355.825806)
					(mid 395.858385 -355.840685)
					(end 395.843506 -355.876606)
				)
				(arc
					(start 395.843506 -356.613206)
					(mid 395.858385 -356.649127)
					(end 395.894306 -356.664006)
				)
				(xy 396.138146 -356.664006) (xy 396.492476 -356.431596) (xy 396.848076 -356.664006)
				(arc
					(start 397.090646 -356.664006)
					(mid 397.126567 -356.649127)
					(end 397.141446 -356.613206)
				)
				(arc
					(start 397.141446 -355.876606)
					(mid 397.126567 -355.840685)
					(end 397.090646 -355.825806)
				)
				(xy 396.848076 -355.825806) (xy 396.491206 -356.058216) (xy 396.136876 -355.825806)
			)
		)
	)
	(zone
		(layer "In1.Cu")
		(hatch none 0.5)
		(connect_pads
			(clearance 0)
		)
		(min_thickness 0.25)
		(keepout
			(tracks not_allowed)
			(vias allowed)
			(pads allowed)
			(copperpour not_allowed)
			(footprints allowed)
		)
		(placement
			(enabled no)
			(sheetname "")
		)
		(fill
			(thermal_gap 0.5)
			(thermal_bridge_width 0.5)
			(island_removal_mode 0)
		)
		(polygon
			(pts
				(arc
					(start 161.53257 -120.952006)
					(mid 161.547449 -120.916085)
					(end 161.58337 -120.901206)
				)
				(arc
					(start 162.76447 -120.901206)
					(mid 162.800391 -120.916085)
					(end 162.81527 -120.952006)
				)
				(arc
					(start 162.81527 -121.958354)
					(mid 162.800391 -121.994275)
					(end 162.76447 -122.009154)
				)
				(arc
					(start 161.58337 -122.009154)
					(mid 161.547449 -121.994275)
					(end 161.53257 -121.958354)
				)
			)
		)
	)
	(zone
		(layer "In1.Cu")
		(hatch none 0.5)
		(connect_pads
			(clearance 0)
		)
		(min_thickness 0.25)
		(keepout
			(tracks not_allowed)
			(vias allowed)
			(pads allowed)
			(copperpour not_allowed)
			(footprints allowed)
		)
		(placement
			(enabled no)
			(sheetname "")
		)
		(fill
			(thermal_gap 0.5)
			(thermal_bridge_width 0.5)
			(island_removal_mode 0)
		)
		(polygon
			(pts
				(arc
					(start 104.819958 -386.715508)
					(mid 104.834837 -386.679587)
					(end 104.870758 -386.664708)
				)
				(arc
					(start 105.277412 -386.664708)
					(mid 105.313333 -386.679587)
					(end 105.328212 -386.715508)
				)
				(arc
					(start 105.328212 -387.117844)
					(mid 105.313333 -387.153765)
					(end 105.277412 -387.168644)
				)
				(arc
					(start 104.870758 -387.168644)
					(mid 104.834837 -387.153765)
					(end 104.819958 -387.117844)
				)
			)
		)
	)
	(zone
		(layer "In1.Cu")
		(hatch none 0.5)
		(connect_pads
			(clearance 0)
		)
		(min_thickness 0.25)
		(keepout
			(tracks not_allowed)
			(vias allowed)
			(pads allowed)
			(copperpour not_allowed)
			(footprints allowed)
		)
		(placement
			(enabled no)
			(sheetname "")
		)
		(fill
			(thermal_gap 0.5)
			(thermal_bridge_width 0.5)
			(island_removal_mode 0)
		)
		(polygon
			(pts
				(arc
					(start 36.0299 -33.574228)
					(mid 36.044779 -33.538307)
					(end 36.0807 -33.523428)
				)
				(arc
					(start 37.3126 -33.523428)
					(mid 37.348521 -33.538307)
					(end 37.3634 -33.574228)
				)
				(arc
					(start 37.3634 -34.605976)
					(mid 37.348521 -34.641897)
					(end 37.3126 -34.656776)
				)
				(arc
					(start 36.0807 -34.656776)
					(mid 36.044779 -34.641897)
					(end 36.0299 -34.605976)
				)
			)
		)
	)
	(zone
		(layer "In1.Cu")
		(hatch none 0.5)
		(connect_pads
			(clearance 0)
		)
		(min_thickness 0.25)
		(keepout
			(tracks not_allowed)
			(vias allowed)
			(pads allowed)
			(copperpour not_allowed)
			(footprints allowed)
		)
		(placement
			(enabled no)
			(sheetname "")
		)
		(fill
			(thermal_gap 0.5)
			(thermal_bridge_width 0.5)
			(island_removal_mode 0)
		)
		(polygon
			(pts
				(arc
					(start 73.867264 -143.55826)
					(mid 73.852385 -143.594181)
					(end 73.816464 -143.60906)
				)
				(arc
					(start 72.635364 -143.60906)
					(mid 72.599443 -143.594181)
					(end 72.584564 -143.55826)
				)
				(arc
					(start 72.584564 -142.551912)
					(mid 72.599443 -142.515991)
					(end 72.635364 -142.501112)
				)
				(arc
					(start 73.816464 -142.501112)
					(mid 73.852385 -142.515991)
					(end 73.867264 -142.551912)
				)
			)
		)
	)
	(zone
		(layer "In1.Cu")
		(hatch none 0.5)
		(connect_pads
			(clearance 0)
		)
		(min_thickness 0.25)
		(keepout
			(tracks not_allowed)
			(vias allowed)
			(pads allowed)
			(copperpour not_allowed)
			(footprints allowed)
		)
		(placement
			(enabled no)
			(sheetname "")
		)
		(fill
			(thermal_gap 0.5)
			(thermal_bridge_width 0.5)
			(island_removal_mode 0)
		)
		(polygon
			(pts
				(arc
					(start 111.696754 -343.533222)
					(mid 111.660833 -343.548101)
					(end 111.645954 -343.584022)
				)
				(arc
					(start 111.645954 -344.320622)
					(mid 111.660833 -344.356543)
					(end 111.696754 -344.371422)
				)
				(xy 111.940594 -344.371422) (xy 112.294924 -344.139012) (xy 112.650524 -344.371422)
				(arc
					(start 112.893094 -344.371422)
					(mid 112.929015 -344.356543)
					(end 112.943894 -344.320622)
				)
				(arc
					(start 112.943894 -343.584022)
					(mid 112.929015 -343.548101)
					(end 112.893094 -343.533222)
				)
				(xy 112.650524 -343.533222) (xy 112.293654 -343.765632) (xy 111.939324 -343.533222)
			)
		)
	)
	(zone
		(layer "In1.Cu")
		(hatch none 0.5)
		(connect_pads
			(clearance 0)
		)
		(min_thickness 0.25)
		(keepout
			(tracks not_allowed)
			(vias allowed)
			(pads allowed)
			(copperpour not_allowed)
			(footprints allowed)
		)
		(placement
			(enabled no)
			(sheetname "")
		)
		(fill
			(thermal_gap 0.5)
			(thermal_bridge_width 0.5)
			(island_removal_mode 0)
		)
		(polygon
			(pts
				(arc
					(start 449.11137 -232.31348)
					(mid 449.021567 -232.276283)
					(end 448.98437 -232.18648)
				)
				(arc
					(start 448.98437 -231.57688)
					(mid 449.021567 -231.487077)
					(end 449.11137 -231.44988)
				)
				(arc
					(start 449.636642 -231.44988)
					(mid 449.726445 -231.487077)
					(end 449.763642 -231.57688)
				)
				(arc
					(start 449.763642 -232.18648)
					(mid 449.726445 -232.276283)
					(end 449.636642 -232.31348)
				)
			)
		)
	)
	(zone
		(layer "In1.Cu")
		(hatch none 0.5)
		(connect_pads
			(clearance 0)
		)
		(min_thickness 0.25)
		(keepout
			(tracks not_allowed)
			(vias allowed)
			(pads allowed)
			(copperpour not_allowed)
			(footprints allowed)
		)
		(placement
			(enabled no)
			(sheetname "")
		)
		(fill
			(thermal_gap 0.5)
			(thermal_bridge_width 0.5)
			(island_removal_mode 0)
		)
		(polygon
			(pts
				(arc
					(start 73.642728 -349.679514)
					(mid 73.606807 -349.694393)
					(end 73.591928 -349.730314)
				)
				(arc
					(start 73.591928 -350.466914)
					(mid 73.606807 -350.502835)
					(end 73.642728 -350.517714)
				)
				(xy 73.886568 -350.517714) (xy 74.240898 -350.285304) (xy 74.596498 -350.517714)
				(arc
					(start 74.839068 -350.517714)
					(mid 74.874989 -350.502835)
					(end 74.889868 -350.466914)
				)
				(arc
					(start 74.889868 -349.730314)
					(mid 74.874989 -349.694393)
					(end 74.839068 -349.679514)
				)
				(xy 74.596498 -349.679514) (xy 74.239628 -349.911924) (xy 73.885298 -349.679514)
			)
		)
	)
	(zone
		(layer "In1.Cu")
		(hatch none 0.5)
		(connect_pads
			(clearance 0)
		)
		(min_thickness 0.25)
		(keepout
			(tracks not_allowed)
			(vias allowed)
			(pads allowed)
			(copperpour not_allowed)
			(footprints allowed)
		)
		(placement
			(enabled no)
			(sheetname "")
		)
		(fill
			(thermal_gap 0.5)
			(thermal_bridge_width 0.5)
			(island_removal_mode 0)
		)
		(polygon
			(pts
				(arc
					(start 193.110358 -343.533222)
					(mid 193.074437 -343.548101)
					(end 193.059558 -343.584022)
				)
				(arc
					(start 193.059558 -344.320622)
					(mid 193.074437 -344.356543)
					(end 193.110358 -344.371422)
				)
				(xy 193.354198 -344.371422) (xy 193.708528 -344.139012) (xy 194.064128 -344.371422)
				(arc
					(start 194.306698 -344.371422)
					(mid 194.342619 -344.356543)
					(end 194.357498 -344.320622)
				)
				(arc
					(start 194.357498 -343.584022)
					(mid 194.342619 -343.548101)
					(end 194.306698 -343.533222)
				)
				(xy 194.064128 -343.533222) (xy 193.707258 -343.765632) (xy 193.352928 -343.533222)
			)
		)
	)
	(zone
		(layer "In1.Cu")
		(hatch none 0.5)
		(connect_pads
			(clearance 0)
		)
		(min_thickness 0.25)
		(keepout
			(tracks not_allowed)
			(vias allowed)
			(pads allowed)
			(copperpour not_allowed)
			(footprints allowed)
		)
		(placement
			(enabled no)
			(sheetname "")
		)
		(fill
			(thermal_gap 0.5)
			(thermal_bridge_width 0.5)
			(island_removal_mode 0)
		)
		(polygon
			(pts
				(arc
					(start 38.861492 -103.94315)
					(mid 38.876371 -103.979071)
					(end 38.912292 -103.99395)
				)
				(arc
					(start 39.648892 -103.99395)
					(mid 39.684813 -103.979071)
					(end 39.699692 -103.94315)
				)
				(xy 39.699692 -103.69931) (xy 39.467282 -103.34498) (xy 39.699692 -102.98938)
				(arc
					(start 39.699692 -102.74681)
					(mid 39.684813 -102.710889)
					(end 39.648892 -102.69601)
				)
				(arc
					(start 38.912292 -102.69601)
					(mid 38.876371 -102.710889)
					(end 38.861492 -102.74681)
				)
				(xy 38.861492 -102.98938) (xy 39.093902 -103.34625) (xy 38.861492 -103.70058)
			)
		)
	)
	(zone
		(layer "In1.Cu")
		(hatch none 0.5)
		(connect_pads
			(clearance 0)
		)
		(min_thickness 0.25)
		(keepout
			(tracks not_allowed)
			(vias allowed)
			(pads allowed)
			(copperpour not_allowed)
			(footprints allowed)
		)
		(placement
			(enabled no)
			(sheetname "")
		)
		(fill
			(thermal_gap 0.5)
			(thermal_bridge_width 0.5)
			(island_removal_mode 0)
		)
		(polygon
			(pts
				(arc
					(start 195.700142 -150.844504)
					(mid 195.715021 -150.880425)
					(end 195.750942 -150.895304)
				)
				(arc
					(start 196.487542 -150.895304)
					(mid 196.523463 -150.880425)
					(end 196.538342 -150.844504)
				)
				(xy 196.538342 -150.600664) (xy 196.305932 -150.246334) (xy 196.538342 -149.890734)
				(arc
					(start 196.538342 -149.648164)
					(mid 196.523463 -149.612243)
					(end 196.487542 -149.597364)
				)
				(arc
					(start 195.750942 -149.597364)
					(mid 195.715021 -149.612243)
					(end 195.700142 -149.648164)
				)
				(xy 195.700142 -149.890734) (xy 195.932552 -150.247604) (xy 195.700142 -150.601934)
			)
		)
	)
	(zone
		(layer "In1.Cu")
		(hatch none 0.5)
		(connect_pads
			(clearance 0)
		)
		(min_thickness 0.25)
		(keepout
			(tracks not_allowed)
			(vias allowed)
			(pads allowed)
			(copperpour not_allowed)
			(footprints allowed)
		)
		(placement
			(enabled no)
			(sheetname "")
		)
		(fill
			(thermal_gap 0.5)
			(thermal_bridge_width 0.5)
			(island_removal_mode 0)
		)
		(polygon
			(pts
				(arc
					(start 106.229912 -387.11886)
					(mid 106.215033 -387.154781)
					(end 106.179112 -387.16966)
				)
				(arc
					(start 105.772458 -387.16966)
					(mid 105.736537 -387.154781)
					(end 105.721658 -387.11886)
				)
				(arc
					(start 105.721658 -386.716524)
					(mid 105.736537 -386.680603)
					(end 105.772458 -386.665724)
				)
				(arc
					(start 106.179112 -386.665724)
					(mid 106.215033 -386.680603)
					(end 106.229912 -386.716524)
				)
			)
		)
	)
	(zone
		(layer "In1.Cu")
		(hatch none 0.5)
		(connect_pads
			(clearance 0)
		)
		(min_thickness 0.25)
		(keepout
			(tracks not_allowed)
			(vias allowed)
			(pads allowed)
			(copperpour not_allowed)
			(footprints allowed)
		)
		(placement
			(enabled no)
			(sheetname "")
		)
		(fill
			(thermal_gap 0.5)
			(thermal_bridge_width 0.5)
			(island_removal_mode 0)
		)
		(polygon
			(pts
				(arc
					(start 422.167304 -143.55826)
					(mid 422.152425 -143.594181)
					(end 422.116504 -143.60906)
				)
				(arc
					(start 420.935404 -143.60906)
					(mid 420.899483 -143.594181)
					(end 420.884604 -143.55826)
				)
				(arc
					(start 420.884604 -142.551912)
					(mid 420.899483 -142.515991)
					(end 420.935404 -142.501112)
				)
				(arc
					(start 422.116504 -142.501112)
					(mid 422.152425 -142.515991)
					(end 422.167304 -142.551912)
				)
			)
		)
	)
	(zone
		(layer "In1.Cu")
		(hatch none 0.5)
		(connect_pads
			(clearance 0)
		)
		(min_thickness 0.25)
		(keepout
			(tracks not_allowed)
			(vias allowed)
			(pads allowed)
			(copperpour not_allowed)
			(footprints allowed)
		)
		(placement
			(enabled no)
			(sheetname "")
		)
		(fill
			(thermal_gap 0.5)
			(thermal_bridge_width 0.5)
			(island_removal_mode 0)
		)
		(polygon
			(pts
				(arc
					(start 289.494468 -349.679514)
					(mid 289.458547 -349.694393)
					(end 289.443668 -349.730314)
				)
				(arc
					(start 289.443668 -350.466914)
					(mid 289.458547 -350.502835)
					(end 289.494468 -350.517714)
				)
				(xy 289.738308 -350.517714) (xy 290.092638 -350.285304) (xy 290.448238 -350.517714)
				(arc
					(start 290.690808 -350.517714)
					(mid 290.726729 -350.502835)
					(end 290.741608 -350.466914)
				)
				(arc
					(start 290.741608 -349.730314)
					(mid 290.726729 -349.694393)
					(end 290.690808 -349.679514)
				)
				(xy 290.448238 -349.679514) (xy 290.091368 -349.911924) (xy 289.737038 -349.679514)
			)
		)
	)
	(zone
		(layer "In1.Cu")
		(hatch none 0.5)
		(connect_pads
			(clearance 0)
		)
		(min_thickness 0.25)
		(keepout
			(tracks not_allowed)
			(vias allowed)
			(pads allowed)
			(copperpour not_allowed)
			(footprints allowed)
		)
		(placement
			(enabled no)
			(sheetname "")
		)
		(fill
			(thermal_gap 0.5)
			(thermal_bridge_width 0.5)
			(island_removal_mode 0)
		)
		(polygon
			(pts
				(arc
					(start 416.34791 -146.151854)
					(mid 416.362789 -146.115933)
					(end 416.39871 -146.101054)
				)
				(arc
					(start 417.57981 -146.101054)
					(mid 417.615731 -146.115933)
					(end 417.63061 -146.151854)
				)
				(arc
					(start 417.63061 -147.158202)
					(mid 417.615731 -147.194123)
					(end 417.57981 -147.209002)
				)
				(arc
					(start 416.39871 -147.209002)
					(mid 416.362789 -147.194123)
					(end 416.34791 -147.158202)
				)
			)
		)
	)
	(zone
		(layer "In1.Cu")
		(hatch none 0.5)
		(connect_pads
			(clearance 0)
		)
		(min_thickness 0.25)
		(keepout
			(tracks not_allowed)
			(vias allowed)
			(pads allowed)
			(copperpour not_allowed)
			(footprints allowed)
		)
		(placement
			(enabled no)
			(sheetname "")
		)
		(fill
			(thermal_gap 0.5)
			(thermal_bridge_width 0.5)
			(island_removal_mode 0)
		)
		(polygon
			(pts
				(arc
					(start 19.167094 -349.679514)
					(mid 19.131173 -349.694393)
					(end 19.116294 -349.730314)
				)
				(arc
					(start 19.116294 -350.466914)
					(mid 19.131173 -350.502835)
					(end 19.167094 -350.517714)
				)
				(xy 19.410934 -350.517714) (xy 19.765264 -350.285304) (xy 20.120864 -350.517714)
				(arc
					(start 20.363434 -350.517714)
					(mid 20.399355 -350.502835)
					(end 20.414234 -350.466914)
				)
				(arc
					(start 20.414234 -349.730314)
					(mid 20.399355 -349.694393)
					(end 20.363434 -349.679514)
				)
				(xy 20.120864 -349.679514) (xy 19.763994 -349.911924) (xy 19.409664 -349.679514)
			)
		)
	)
	(zone
		(layer "In1.Cu")
		(hatch none 0.5)
		(connect_pads
			(clearance 0)
		)
		(min_thickness 0.25)
		(keepout
			(tracks not_allowed)
			(vias allowed)
			(pads allowed)
			(copperpour not_allowed)
			(footprints allowed)
		)
		(placement
			(enabled no)
			(sheetname "")
		)
		(fill
			(thermal_gap 0.5)
			(thermal_bridge_width 0.5)
			(island_removal_mode 0)
		)
		(polygon
			(pts
				(arc
					(start 326.099678 -27.405838)
					(mid 326.084799 -27.441759)
					(end 326.048878 -27.456638)
				)
				(arc
					(start 324.816978 -27.456638)
					(mid 324.781057 -27.441759)
					(end 324.766178 -27.405838)
				)
				(arc
					(start 324.766178 -26.37409)
					(mid 324.781057 -26.338169)
					(end 324.816978 -26.32329)
				)
				(arc
					(start 326.048878 -26.32329)
					(mid 326.084799 -26.338169)
					(end 326.099678 -26.37409)
				)
			)
		)
	)
	(zone
		(layer "In1.Cu")
		(hatch none 0.5)
		(connect_pads
			(clearance 0)
		)
		(min_thickness 0.25)
		(keepout
			(tracks not_allowed)
			(vias allowed)
			(pads allowed)
			(copperpour not_allowed)
			(footprints allowed)
		)
		(placement
			(enabled no)
			(sheetname "")
		)
		(fill
			(thermal_gap 0.5)
			(thermal_bridge_width 0.5)
			(island_removal_mode 0)
		)
		(polygon
			(pts
				(arc
					(start 385.777232 8.691372)
					(mid 385.79955 8.745254)
					(end 385.853432 8.767572)
				)
				(arc
					(start 386.465572 8.767572)
					(mid 386.519454 8.745254)
					(end 386.541772 8.691372)
				)
				(arc
					(start 386.541772 7.594092)
					(mid 386.519454 7.54021)
					(end 386.465572 7.517892)
				)
				(arc
					(start 385.853432 7.517892)
					(mid 385.79955 7.54021)
					(end 385.777232 7.594092)
				)
			)
		)
	)
	(zone
		(layer "In1.Cu")
		(hatch none 0.5)
		(connect_pads
			(clearance 0)
		)
		(min_thickness 0.25)
		(keepout
			(tracks not_allowed)
			(vias allowed)
			(pads allowed)
			(copperpour not_allowed)
			(footprints allowed)
		)
		(placement
			(enabled no)
			(sheetname "")
		)
		(fill
			(thermal_gap 0.5)
			(thermal_bridge_width 0.5)
			(island_removal_mode 0)
		)
		(polygon
			(pts
				(arc
					(start 36.219384 -135.06323)
					(mid 36.234263 -135.099151)
					(end 36.270184 -135.11403)
				)
				(arc
					(start 37.006784 -135.11403)
					(mid 37.042705 -135.099151)
					(end 37.057584 -135.06323)
				)
				(xy 37.057584 -134.81939) (xy 36.825174 -134.46506) (xy 37.057584 -134.10946)
				(arc
					(start 37.057584 -133.86689)
					(mid 37.042705 -133.830969)
					(end 37.006784 -133.81609)
				)
				(arc
					(start 36.270184 -133.81609)
					(mid 36.234263 -133.830969)
					(end 36.219384 -133.86689)
				)
				(xy 36.219384 -134.10946) (xy 36.451794 -134.46633) (xy 36.219384 -134.82066)
			)
		)
	)
	(zone
		(layer "In1.Cu")
		(hatch none 0.5)
		(connect_pads
			(clearance 0)
		)
		(min_thickness 0.25)
		(keepout
			(tracks not_allowed)
			(vias allowed)
			(pads allowed)
			(copperpour not_allowed)
			(footprints allowed)
		)
		(placement
			(enabled no)
			(sheetname "")
		)
		(fill
			(thermal_gap 0.5)
			(thermal_bridge_width 0.5)
			(island_removal_mode 0)
		)
		(polygon
			(pts
				(arc
					(start 230.807006 -78.85176)
					(mid 230.792127 -78.887681)
					(end 230.756206 -78.90256)
				)
				(arc
					(start 230.702866 -78.90256)
					(mid 230.666945 -78.887681)
					(end 230.652066 -78.85176)
				)
				(arc
					(start 230.652066 -78.239874)
					(mid 230.666945 -78.203953)
					(end 230.702866 -78.189074)
				)
				(arc
					(start 230.756206 -78.189074)
					(mid 230.792127 -78.203953)
					(end 230.807006 -78.239874)
				)
			)
		)
	)
	(zone
		(layer "In1.Cu")
		(hatch none 0.5)
		(connect_pads
			(clearance 0)
		)
		(min_thickness 0.25)
		(keepout
			(tracks not_allowed)
			(vias allowed)
			(pads allowed)
			(copperpour not_allowed)
			(footprints allowed)
		)
		(placement
			(enabled no)
			(sheetname "")
		)
		(fill
			(thermal_gap 0.5)
			(thermal_bridge_width 0.5)
			(island_removal_mode 0)
		)
		(polygon
			(pts
				(arc
					(start 387.161532 -111.143288)
					(mid 387.176411 -111.179209)
					(end 387.212332 -111.194088)
				)
				(arc
					(start 387.948932 -111.194088)
					(mid 387.984853 -111.179209)
					(end 387.999732 -111.143288)
				)
				(xy 387.999732 -110.899448) (xy 387.767322 -110.545118) (xy 387.999732 -110.189518)
				(arc
					(start 387.999732 -109.946948)
					(mid 387.984853 -109.911027)
					(end 387.948932 -109.896148)
				)
				(arc
					(start 387.212332 -109.896148)
					(mid 387.176411 -109.911027)
					(end 387.161532 -109.946948)
				)
				(xy 387.161532 -110.189518) (xy 387.393942 -110.546388) (xy 387.161532 -110.900718)
			)
		)
	)
	(zone
		(layer "In1.Cu")
		(hatch none 0.5)
		(connect_pads
			(clearance 0)
		)
		(min_thickness 0.25)
		(keepout
			(tracks not_allowed)
			(vias allowed)
			(pads allowed)
			(copperpour not_allowed)
			(footprints allowed)
		)
		(placement
			(enabled no)
			(sheetname "")
		)
		(fill
			(thermal_gap 0.5)
			(thermal_bridge_width 0.5)
			(island_removal_mode 0)
		)
		(polygon
			(pts
				(arc
					(start 440.219338 -343.533222)
					(mid 440.183417 -343.548101)
					(end 440.168538 -343.584022)
				)
				(arc
					(start 440.168538 -344.320622)
					(mid 440.183417 -344.356543)
					(end 440.219338 -344.371422)
				)
				(xy 440.463178 -344.371422) (xy 440.817508 -344.139012) (xy 441.173108 -344.371422)
				(arc
					(start 441.415678 -344.371422)
					(mid 441.451599 -344.356543)
					(end 441.466478 -344.320622)
				)
				(arc
					(start 441.466478 -343.584022)
					(mid 441.451599 -343.548101)
					(end 441.415678 -343.533222)
				)
				(xy 441.173108 -343.533222) (xy 440.816238 -343.765632) (xy 440.461908 -343.533222)
			)
		)
	)
	(zone
		(layer "In1.Cu")
		(hatch none 0.5)
		(connect_pads
			(clearance 0)
		)
		(min_thickness 0.25)
		(keepout
			(tracks not_allowed)
			(vias allowed)
			(pads allowed)
			(copperpour not_allowed)
			(footprints allowed)
		)
		(placement
			(enabled no)
			(sheetname "")
		)
		(fill
			(thermal_gap 0.5)
			(thermal_bridge_width 0.5)
			(island_removal_mode 0)
		)
		(polygon
			(pts
				(arc
					(start 330.99121 -343.533222)
					(mid 330.955289 -343.548101)
					(end 330.94041 -343.584022)
				)
				(arc
					(start 330.94041 -344.320622)
					(mid 330.955289 -344.356543)
					(end 330.99121 -344.371422)
				)
				(xy 331.23505 -344.371422) (xy 331.58938 -344.139012) (xy 331.94498 -344.371422)
				(arc
					(start 332.18755 -344.371422)
					(mid 332.223471 -344.356543)
					(end 332.23835 -344.320622)
				)
				(arc
					(start 332.23835 -343.584022)
					(mid 332.223471 -343.548101)
					(end 332.18755 -343.533222)
				)
				(xy 331.94498 -343.533222) (xy 331.58811 -343.765632) (xy 331.23378 -343.533222)
			)
		)
	)
	(zone
		(layer "In1.Cu")
		(hatch none 0.5)
		(connect_pads
			(clearance 0)
		)
		(min_thickness 0.25)
		(keepout
			(tracks not_allowed)
			(vias allowed)
			(pads allowed)
			(copperpour not_allowed)
			(footprints allowed)
		)
		(placement
			(enabled no)
			(sheetname "")
		)
		(fill
			(thermal_gap 0.5)
			(thermal_bridge_width 0.5)
			(island_removal_mode 0)
		)
		(polygon
			(pts
				(arc
					(start 311.80024 -134.534656)
					(mid 311.815119 -134.570577)
					(end 311.85104 -134.585456)
				)
				(arc
					(start 312.58764 -134.585456)
					(mid 312.623561 -134.570577)
					(end 312.63844 -134.534656)
				)
				(xy 312.63844 -134.290816) (xy 312.40603 -133.936486) (xy 312.63844 -133.580886)
				(arc
					(start 312.63844 -133.338316)
					(mid 312.623561 -133.302395)
					(end 312.58764 -133.287516)
				)
				(arc
					(start 311.85104 -133.287516)
					(mid 311.815119 -133.302395)
					(end 311.80024 -133.338316)
				)
				(xy 311.80024 -133.580886) (xy 312.03265 -133.937756) (xy 311.80024 -134.292086)
			)
		)
	)
	(zone
		(layer "In1.Cu")
		(hatch none 0.5)
		(connect_pads
			(clearance 0)
		)
		(min_thickness 0.25)
		(keepout
			(tracks not_allowed)
			(vias allowed)
			(pads allowed)
			(copperpour not_allowed)
			(footprints allowed)
		)
		(placement
			(enabled no)
			(sheetname "")
		)
		(fill
			(thermal_gap 0.5)
			(thermal_bridge_width 0.5)
			(island_removal_mode 0)
		)
		(polygon
			(pts
				(arc
					(start 38.861492 -100.343208)
					(mid 38.876371 -100.379129)
					(end 38.912292 -100.394008)
				)
				(arc
					(start 39.648892 -100.394008)
					(mid 39.684813 -100.379129)
					(end 39.699692 -100.343208)
				)
				(xy 39.699692 -100.099368) (xy 39.467282 -99.745038) (xy 39.699692 -99.389438)
				(arc
					(start 39.699692 -99.146868)
					(mid 39.684813 -99.110947)
					(end 39.648892 -99.096068)
				)
				(arc
					(start 38.912292 -99.096068)
					(mid 38.876371 -99.110947)
					(end 38.861492 -99.146868)
				)
				(xy 38.861492 -99.389438) (xy 39.093902 -99.746308) (xy 38.861492 -100.100638)
			)
		)
	)
	(zone
		(layer "In1.Cu")
		(hatch none 0.5)
		(connect_pads
			(clearance 0)
		)
		(min_thickness 0.25)
		(keepout
			(tracks not_allowed)
			(vias allowed)
			(pads allowed)
			(copperpour not_allowed)
			(footprints allowed)
		)
		(placement
			(enabled no)
			(sheetname "")
		)
		(fill
			(thermal_gap 0.5)
			(thermal_bridge_width 0.5)
			(island_removal_mode 0)
		)
		(polygon
			(pts
				(arc
					(start 399.55216 -131.368292)
					(mid 399.537281 -131.404213)
					(end 399.50136 -131.419092)
				)
				(arc
					(start 398.32026 -131.419092)
					(mid 398.284339 -131.404213)
					(end 398.26946 -131.368292)
				)
				(arc
					(start 398.26946 -130.361944)
					(mid 398.284339 -130.326023)
					(end 398.32026 -130.311144)
				)
				(arc
					(start 399.50136 -130.311144)
					(mid 399.537281 -130.326023)
					(end 399.55216 -130.361944)
				)
			)
		)
	)
	(zone
		(layer "In1.Cu")
		(hatch none 0.5)
		(connect_pads
			(clearance 0)
		)
		(min_thickness 0.25)
		(keepout
			(tracks not_allowed)
			(vias allowed)
			(pads allowed)
			(copperpour not_allowed)
			(footprints allowed)
		)
		(placement
			(enabled no)
			(sheetname "")
		)
		(fill
			(thermal_gap 0.5)
			(thermal_bridge_width 0.5)
			(island_removal_mode 0)
		)
		(polygon
			(pts
				(arc
					(start 393.732766 -99.241864)
					(mid 393.747645 -99.205943)
					(end 393.783566 -99.191064)
				)
				(arc
					(start 394.964666 -99.191064)
					(mid 395.000587 -99.205943)
					(end 395.015466 -99.241864)
				)
				(arc
					(start 395.015466 -100.248212)
					(mid 395.000587 -100.284133)
					(end 394.964666 -100.299012)
				)
				(arc
					(start 393.783566 -100.299012)
					(mid 393.747645 -100.284133)
					(end 393.732766 -100.248212)
				)
			)
		)
	)
	(zone
		(layer "In1.Cu")
		(hatch none 0.5)
		(connect_pads
			(clearance 0)
		)
		(min_thickness 0.25)
		(keepout
			(tracks not_allowed)
			(vias allowed)
			(pads allowed)
			(copperpour not_allowed)
			(footprints allowed)
		)
		(placement
			(enabled no)
			(sheetname "")
		)
		(fill
			(thermal_gap 0.5)
			(thermal_bridge_width 0.5)
			(island_removal_mode 0)
		)
		(polygon
			(pts
				(arc
					(start 38.861492 -125.659896)
					(mid 38.876371 -125.695817)
					(end 38.912292 -125.710696)
				)
				(arc
					(start 39.648892 -125.710696)
					(mid 39.684813 -125.695817)
					(end 39.699692 -125.659896)
				)
				(xy 39.699692 -125.416056) (xy 39.467282 -125.061726) (xy 39.699692 -124.706126)
				(arc
					(start 39.699692 -124.463556)
					(mid 39.684813 -124.427635)
					(end 39.648892 -124.412756)
				)
				(arc
					(start 38.912292 -124.412756)
					(mid 38.876371 -124.427635)
					(end 38.861492 -124.463556)
				)
				(xy 38.861492 -124.706126) (xy 39.093902 -125.062996) (xy 38.861492 -125.417326)
			)
		)
	)
	(zone
		(layer "In1.Cu")
		(hatch none 0.5)
		(connect_pads
			(clearance 0)
		)
		(min_thickness 0.25)
		(keepout
			(tracks not_allowed)
			(vias allowed)
			(pads allowed)
			(copperpour not_allowed)
			(footprints allowed)
		)
		(placement
			(enabled no)
			(sheetname "")
		)
		(fill
			(thermal_gap 0.5)
			(thermal_bridge_width 0.5)
			(island_removal_mode 0)
		)
		(polygon
			(pts
				(arc
					(start 130.350514 -343.533222)
					(mid 130.314593 -343.548101)
					(end 130.299714 -343.584022)
				)
				(arc
					(start 130.299714 -344.320622)
					(mid 130.314593 -344.356543)
					(end 130.350514 -344.371422)
				)
				(xy 130.594354 -344.371422) (xy 130.948684 -344.139012) (xy 131.304284 -344.371422)
				(arc
					(start 131.546854 -344.371422)
					(mid 131.582775 -344.356543)
					(end 131.597654 -344.320622)
				)
				(arc
					(start 131.597654 -343.584022)
					(mid 131.582775 -343.548101)
					(end 131.546854 -343.533222)
				)
				(xy 131.304284 -343.533222) (xy 130.947414 -343.765632) (xy 130.593084 -343.533222)
			)
		)
	)
	(zone
		(layer "In1.Cu")
		(hatch none 0.5)
		(connect_pads
			(clearance 0)
		)
		(min_thickness 0.25)
		(keepout
			(tracks not_allowed)
			(vias allowed)
			(pads allowed)
			(copperpour not_allowed)
			(footprints allowed)
		)
		(placement
			(enabled no)
			(sheetname "")
		)
		(fill
			(thermal_gap 0.5)
			(thermal_bridge_width 0.5)
			(island_removal_mode 0)
		)
		(polygon
			(pts
				(arc
					(start 270.840708 -355.825806)
					(mid 270.804787 -355.840685)
					(end 270.789908 -355.876606)
				)
				(arc
					(start 270.789908 -356.613206)
					(mid 270.804787 -356.649127)
					(end 270.840708 -356.664006)
				)
				(xy 271.084548 -356.664006) (xy 271.438878 -356.431596) (xy 271.794478 -356.664006)
				(arc
					(start 272.037048 -356.664006)
					(mid 272.072969 -356.649127)
					(end 272.087848 -356.613206)
				)
				(arc
					(start 272.087848 -355.876606)
					(mid 272.072969 -355.840685)
					(end 272.037048 -355.825806)
				)
				(xy 271.794478 -355.825806) (xy 271.437608 -356.058216) (xy 271.083278 -355.825806)
			)
		)
	)
	(zone
		(layer "In1.Cu")
		(hatch none 0.5)
		(connect_pads
			(clearance 0)
		)
		(min_thickness 0.25)
		(keepout
			(tracks not_allowed)
			(vias allowed)
			(pads allowed)
			(copperpour not_allowed)
			(footprints allowed)
		)
		(placement
			(enabled no)
			(sheetname "")
		)
		(fill
			(thermal_gap 0.5)
			(thermal_bridge_width 0.5)
			(island_removal_mode 0)
		)
		(polygon
			(pts
				(arc
					(start 184.147714 -149.751796)
					(mid 184.162593 -149.715875)
					(end 184.198514 -149.700996)
				)
				(arc
					(start 185.379614 -149.700996)
					(mid 185.415535 -149.715875)
					(end 185.430414 -149.751796)
				)
				(arc
					(start 185.430414 -150.758144)
					(mid 185.415535 -150.794065)
					(end 185.379614 -150.808944)
				)
				(arc
					(start 184.198514 -150.808944)
					(mid 184.162593 -150.794065)
					(end 184.147714 -150.758144)
				)
			)
		)
	)
	(zone
		(layer "In1.Cu")
		(hatch none 0.5)
		(connect_pads
			(clearance 0)
		)
		(min_thickness 0.25)
		(keepout
			(tracks not_allowed)
			(vias allowed)
			(pads allowed)
			(copperpour not_allowed)
			(footprints allowed)
		)
		(placement
			(enabled no)
			(sheetname "")
		)
		(fill
			(thermal_gap 0.5)
			(thermal_bridge_width 0.5)
			(island_removal_mode 0)
		)
		(polygon
			(pts
				(arc
					(start 70.533768 -343.533222)
					(mid 70.497847 -343.548101)
					(end 70.482968 -343.584022)
				)
				(arc
					(start 70.482968 -344.320622)
					(mid 70.497847 -344.356543)
					(end 70.533768 -344.371422)
				)
				(xy 70.777608 -344.371422) (xy 71.131938 -344.139012) (xy 71.487538 -344.371422)
				(arc
					(start 71.730108 -344.371422)
					(mid 71.766029 -344.356543)
					(end 71.780908 -344.320622)
				)
				(arc
					(start 71.780908 -343.584022)
					(mid 71.766029 -343.548101)
					(end 71.730108 -343.533222)
				)
				(xy 71.487538 -343.533222) (xy 71.130668 -343.765632) (xy 70.776338 -343.533222)
			)
		)
	)
	(zone
		(layer "In1.Cu")
		(hatch none 0.5)
		(connect_pads
			(clearance 0)
		)
		(min_thickness 0.25)
		(keepout
			(tracks not_allowed)
			(vias allowed)
			(pads allowed)
			(copperpour not_allowed)
			(footprints allowed)
		)
		(placement
			(enabled no)
			(sheetname "")
		)
		(fill
			(thermal_gap 0.5)
			(thermal_bridge_width 0.5)
			(island_removal_mode 0)
		)
		(polygon
			(pts
				(arc
					(start 152.319228 -135.06323)
					(mid 152.334107 -135.099151)
					(end 152.370028 -135.11403)
				)
				(arc
					(start 153.106628 -135.11403)
					(mid 153.142549 -135.099151)
					(end 153.157428 -135.06323)
				)
				(xy 153.157428 -134.81939) (xy 152.925018 -134.46506) (xy 153.157428 -134.10946)
				(arc
					(start 153.157428 -133.86689)
					(mid 153.142549 -133.830969)
					(end 153.106628 -133.81609)
				)
				(arc
					(start 152.370028 -133.81609)
					(mid 152.334107 -133.830969)
					(end 152.319228 -133.86689)
				)
				(xy 152.319228 -134.10946) (xy 152.551638 -134.46633) (xy 152.319228 -134.82066)
			)
		)
	)
	(zone
		(layer "In1.Cu")
		(hatch none 0.5)
		(connect_pads
			(clearance 0)
		)
		(min_thickness 0.25)
		(keepout
			(tracks not_allowed)
			(vias allowed)
			(pads allowed)
			(copperpour not_allowed)
			(footprints allowed)
		)
		(placement
			(enabled no)
			(sheetname "")
		)
		(fill
			(thermal_gap 0.5)
			(thermal_bridge_width 0.5)
			(island_removal_mode 0)
		)
		(polygon
			(pts
				(arc
					(start 73.867264 -156.158184)
					(mid 73.852385 -156.194105)
					(end 73.816464 -156.208984)
				)
				(arc
					(start 72.635364 -156.208984)
					(mid 72.599443 -156.194105)
					(end 72.584564 -156.158184)
				)
				(arc
					(start 72.584564 -155.151836)
					(mid 72.599443 -155.115915)
					(end 72.635364 -155.101036)
				)
				(arc
					(start 73.816464 -155.101036)
					(mid 73.852385 -155.115915)
					(end 73.867264 -155.151836)
				)
			)
		)
	)
	(zone
		(layer "In1.Cu")
		(hatch none 0.5)
		(connect_pads
			(clearance 0)
		)
		(min_thickness 0.25)
		(keepout
			(tracks not_allowed)
			(vias allowed)
			(pads allowed)
			(copperpour not_allowed)
			(footprints allowed)
		)
		(placement
			(enabled no)
			(sheetname "")
		)
		(fill
			(thermal_gap 0.5)
			(thermal_bridge_width 0.5)
			(island_removal_mode 0)
		)
		(polygon
			(pts
				(arc
					(start 184.147714 -153.351992)
					(mid 184.162593 -153.316071)
					(end 184.198514 -153.301192)
				)
				(arc
					(start 185.379614 -153.301192)
					(mid 185.415535 -153.316071)
					(end 185.430414 -153.351992)
				)
				(arc
					(start 185.430414 -154.35834)
					(mid 185.415535 -154.394261)
					(end 185.379614 -154.40914)
				)
				(arc
					(start 184.198514 -154.40914)
					(mid 184.162593 -154.394261)
					(end 184.147714 -154.35834)
				)
			)
		)
	)
	(zone
		(layer "In1.Cu")
		(hatch none 0.5)
		(connect_pads
			(clearance 0)
		)
		(min_thickness 0.25)
		(keepout
			(tracks not_allowed)
			(vias allowed)
			(pads allowed)
			(copperpour not_allowed)
			(footprints allowed)
		)
		(placement
			(enabled no)
			(sheetname "")
		)
		(fill
			(thermal_gap 0.5)
			(thermal_bridge_width 0.5)
			(island_removal_mode 0)
		)
		(polygon
			(pts
				(arc
					(start 17.373346 -32.879538)
					(mid 17.388225 -32.915459)
					(end 17.424146 -32.930338)
				)
				(arc
					(start 18.160746 -32.930338)
					(mid 18.196667 -32.915459)
					(end 18.211546 -32.879538)
				)
				(xy 18.211546 -32.635698) (xy 17.979136 -32.281368) (xy 18.211546 -31.925768)
				(arc
					(start 18.211546 -31.683198)
					(mid 18.196667 -31.647277)
					(end 18.160746 -31.632398)
				)
				(arc
					(start 17.424146 -31.632398)
					(mid 17.388225 -31.647277)
					(end 17.373346 -31.683198)
				)
				(xy 17.373346 -31.925768) (xy 17.605756 -32.282638) (xy 17.373346 -32.636968)
			)
		)
	)
	(zone
		(layer "In1.Cu")
		(hatch none 0.5)
		(connect_pads
			(clearance 0)
		)
		(min_thickness 0.25)
		(keepout
			(tracks not_allowed)
			(vias allowed)
			(pads allowed)
			(copperpour not_allowed)
			(footprints allowed)
		)
		(placement
			(enabled no)
			(sheetname "")
		)
		(fill
			(thermal_gap 0.5)
			(thermal_bridge_width 0.5)
			(island_removal_mode 0)
		)
		(polygon
			(pts
				(arc
					(start 136.568434 -349.679514)
					(mid 136.532513 -349.694393)
					(end 136.517634 -349.730314)
				)
				(arc
					(start 136.517634 -350.466914)
					(mid 136.532513 -350.502835)
					(end 136.568434 -350.517714)
				)
				(xy 136.812274 -350.517714) (xy 137.166604 -350.285304) (xy 137.522204 -350.517714)
				(arc
					(start 137.764774 -350.517714)
					(mid 137.800695 -350.502835)
					(end 137.815574 -350.466914)
				)
				(arc
					(start 137.815574 -349.730314)
					(mid 137.800695 -349.694393)
					(end 137.764774 -349.679514)
				)
				(xy 137.522204 -349.679514) (xy 137.165334 -349.911924) (xy 136.811004 -349.679514)
			)
		)
	)
	(zone
		(layer "In1.Cu")
		(hatch none 0.5)
		(connect_pads
			(clearance 0)
		)
		(min_thickness 0.25)
		(keepout
			(tracks not_allowed)
			(vias allowed)
			(pads allowed)
			(copperpour not_allowed)
			(footprints allowed)
		)
		(placement
			(enabled no)
			(sheetname "")
		)
		(fill
			(thermal_gap 0.5)
			(thermal_bridge_width 0.5)
			(island_removal_mode 0)
		)
		(polygon
			(pts
				(arc
					(start 44.038774 -343.533222)
					(mid 44.002853 -343.548101)
					(end 43.987974 -343.584022)
				)
				(arc
					(start 43.987974 -344.320622)
					(mid 44.002853 -344.356543)
					(end 44.038774 -344.371422)
				)
				(xy 44.282614 -344.371422) (xy 44.636944 -344.139012) (xy 44.992544 -344.371422)
				(arc
					(start 45.235114 -344.371422)
					(mid 45.271035 -344.356543)
					(end 45.285914 -344.320622)
				)
				(arc
					(start 45.285914 -343.584022)
					(mid 45.271035 -343.548101)
					(end 45.235114 -343.533222)
				)
				(xy 44.992544 -343.533222) (xy 44.635674 -343.765632) (xy 44.281344 -343.533222)
			)
		)
	)
	(zone
		(layer "In1.Cu")
		(hatch none 0.5)
		(connect_pads
			(clearance 0)
		)
		(min_thickness 0.25)
		(keepout
			(tracks not_allowed)
			(vias allowed)
			(pads allowed)
			(copperpour not_allowed)
			(footprints allowed)
		)
		(placement
			(enabled no)
			(sheetname "")
		)
		(fill
			(thermal_gap 0.5)
			(thermal_bridge_width 0.5)
			(island_removal_mode 0)
		)
		(polygon
			(pts
				(arc
					(start 455.545444 -208.454752)
					(mid 455.560323 -208.418831)
					(end 455.596244 -208.403952)
				)
				(arc
					(start 456.99426 -208.403952)
					(mid 457.030181 -208.418831)
					(end 457.04506 -208.454752)
				)
				(arc
					(start 457.04506 -209.439764)
					(mid 457.030181 -209.475685)
					(end 456.99426 -209.490564)
				)
				(arc
					(start 455.596244 -209.490564)
					(mid 455.560323 -209.475685)
					(end 455.545444 -209.439764)
				)
			)
		)
	)
	(zone
		(layer "In1.Cu")
		(hatch none 0.5)
		(connect_pads
			(clearance 0)
		)
		(min_thickness 0.25)
		(keepout
			(tracks not_allowed)
			(vias allowed)
			(pads allowed)
			(copperpour not_allowed)
			(footprints allowed)
		)
		(placement
			(enabled no)
			(sheetname "")
		)
		(fill
			(thermal_gap 0.5)
			(thermal_bridge_width 0.5)
			(island_removal_mode 0)
		)
		(polygon
			(pts
				(arc
					(start 121.023634 -349.679514)
					(mid 120.987713 -349.694393)
					(end 120.972834 -349.730314)
				)
				(arc
					(start 120.972834 -350.466914)
					(mid 120.987713 -350.502835)
					(end 121.023634 -350.517714)
				)
				(xy 121.267474 -350.517714) (xy 121.621804 -350.285304) (xy 121.977404 -350.517714)
				(arc
					(start 122.219974 -350.517714)
					(mid 122.255895 -350.502835)
					(end 122.270774 -350.466914)
				)
				(arc
					(start 122.270774 -349.730314)
					(mid 122.255895 -349.694393)
					(end 122.219974 -349.679514)
				)
				(xy 121.977404 -349.679514) (xy 121.620534 -349.911924) (xy 121.266204 -349.679514)
			)
		)
	)
	(zone
		(layer "In1.Cu")
		(hatch none 0.5)
		(connect_pads
			(clearance 0)
		)
		(min_thickness 0.25)
		(keepout
			(tracks not_allowed)
			(vias allowed)
			(pads allowed)
			(copperpour not_allowed)
			(footprints allowed)
		)
		(placement
			(enabled no)
			(sheetname "")
		)
		(fill
			(thermal_gap 0.5)
			(thermal_bridge_width 0.5)
			(island_removal_mode 0)
		)
		(polygon
			(pts
				(arc
					(start 286.385508 -343.533222)
					(mid 286.349587 -343.548101)
					(end 286.334708 -343.584022)
				)
				(arc
					(start 286.334708 -344.320622)
					(mid 286.349587 -344.356543)
					(end 286.385508 -344.371422)
				)
				(xy 286.629348 -344.371422) (xy 286.983678 -344.139012) (xy 287.339278 -344.371422)
				(arc
					(start 287.581848 -344.371422)
					(mid 287.617769 -344.356543)
					(end 287.632648 -344.320622)
				)
				(arc
					(start 287.632648 -343.584022)
					(mid 287.617769 -343.548101)
					(end 287.581848 -343.533222)
				)
				(xy 287.339278 -343.533222) (xy 286.982408 -343.765632) (xy 286.628078 -343.533222)
			)
		)
	)
	(zone
		(layer "In1.Cu")
		(hatch none 0.5)
		(connect_pads
			(clearance 0)
		)
		(min_thickness 0.25)
		(keepout
			(tracks not_allowed)
			(vias allowed)
			(pads allowed)
			(copperpour not_allowed)
			(footprints allowed)
		)
		(placement
			(enabled no)
			(sheetname "")
		)
		(fill
			(thermal_gap 0.5)
			(thermal_bridge_width 0.5)
			(island_removal_mode 0)
		)
		(polygon
			(pts
				(arc
					(start 315.44641 -349.679514)
					(mid 315.410489 -349.694393)
					(end 315.39561 -349.730314)
				)
				(arc
					(start 315.39561 -350.466914)
					(mid 315.410489 -350.502835)
					(end 315.44641 -350.517714)
				)
				(xy 315.69025 -350.517714) (xy 316.04458 -350.285304) (xy 316.40018 -350.517714)
				(arc
					(start 316.64275 -350.517714)
					(mid 316.678671 -350.502835)
					(end 316.69355 -350.466914)
				)
				(arc
					(start 316.69355 -349.730314)
					(mid 316.678671 -349.694393)
					(end 316.64275 -349.679514)
				)
				(xy 316.40018 -349.679514) (xy 316.04331 -349.911924) (xy 315.68898 -349.679514)
			)
		)
	)
	(zone
		(layer "In1.Cu")
		(hatch none 0.5)
		(connect_pads
			(clearance 0)
		)
		(min_thickness 0.25)
		(keepout
			(tracks not_allowed)
			(vias allowed)
			(pads allowed)
			(copperpour not_allowed)
			(footprints allowed)
		)
		(placement
			(enabled no)
			(sheetname "")
		)
		(fill
			(thermal_gap 0.5)
			(thermal_bridge_width 0.5)
			(island_removal_mode 0)
		)
		(polygon
			(pts
				(arc
					(start 183.783478 -355.80193)
					(mid 183.747557 -355.816809)
					(end 183.732678 -355.85273)
				)
				(arc
					(start 183.732678 -356.58933)
					(mid 183.747557 -356.625251)
					(end 183.783478 -356.64013)
				)
				(xy 184.027318 -356.64013) (xy 184.381648 -356.40772) (xy 184.737248 -356.64013)
				(arc
					(start 184.979818 -356.64013)
					(mid 185.015739 -356.625251)
					(end 185.030618 -356.58933)
				)
				(arc
					(start 185.030618 -355.85273)
					(mid 185.015739 -355.816809)
					(end 184.979818 -355.80193)
				)
				(xy 184.737248 -355.80193) (xy 184.380378 -356.03434) (xy 184.026048 -355.80193)
			)
		)
	)
	(zone
		(layer "In1.Cu")
		(hatch none 0.5)
		(connect_pads
			(clearance 0)
		)
		(min_thickness 0.25)
		(keepout
			(tracks not_allowed)
			(vias allowed)
			(pads allowed)
			(copperpour not_allowed)
			(footprints allowed)
		)
		(placement
			(enabled no)
			(sheetname "")
		)
		(fill
			(thermal_gap 0.5)
			(thermal_bridge_width 0.5)
			(island_removal_mode 0)
		)
		(polygon
			(pts
				(arc
					(start 93.899736 -31.006034)
					(mid 93.884857 -31.041955)
					(end 93.848936 -31.056834)
				)
				(arc
					(start 92.617036 -31.056834)
					(mid 92.581115 -31.041955)
					(end 92.566236 -31.006034)
				)
				(arc
					(start 92.566236 -29.974286)
					(mid 92.581115 -29.938365)
					(end 92.617036 -29.923486)
				)
				(arc
					(start 93.848936 -29.923486)
					(mid 93.884857 -29.938365)
					(end 93.899736 -29.974286)
				)
			)
		)
	)
	(zone
		(layer "In1.Cu")
		(hatch none 0.5)
		(connect_pads
			(clearance 0)
		)
		(min_thickness 0.25)
		(keepout
			(tracks not_allowed)
			(vias allowed)
			(pads allowed)
			(copperpour not_allowed)
			(footprints allowed)
		)
		(placement
			(enabled no)
			(sheetname "")
		)
		(fill
			(thermal_gap 0.5)
			(thermal_bridge_width 0.5)
			(island_removal_mode 0)
		)
		(polygon
			(pts
				(arc
					(start 82.969608 -343.533222)
					(mid 82.933687 -343.548101)
					(end 82.918808 -343.584022)
				)
				(arc
					(start 82.918808 -344.320622)
					(mid 82.933687 -344.356543)
					(end 82.969608 -344.371422)
				)
				(xy 83.213448 -344.371422) (xy 83.567778 -344.139012) (xy 83.923378 -344.371422)
				(arc
					(start 84.165948 -344.371422)
					(mid 84.201869 -344.356543)
					(end 84.216748 -344.320622)
				)
				(arc
					(start 84.216748 -343.584022)
					(mid 84.201869 -343.548101)
					(end 84.165948 -343.533222)
				)
				(xy 83.923378 -343.533222) (xy 83.566508 -343.765632) (xy 83.212178 -343.533222)
			)
		)
	)
	(zone
		(layer "In1.Cu")
		(hatch none 0.5)
		(connect_pads
			(clearance 0)
		)
		(min_thickness 0.25)
		(keepout
			(tracks not_allowed)
			(vias allowed)
			(pads allowed)
			(copperpour not_allowed)
			(footprints allowed)
		)
		(placement
			(enabled no)
			(sheetname "")
		)
		(fill
			(thermal_gap 0.5)
			(thermal_bridge_width 0.5)
			(island_removal_mode 0)
		)
		(polygon
			(pts
				(arc
					(start 442.199776 -32.805878)
					(mid 442.184897 -32.841799)
					(end 442.148976 -32.856678)
				)
				(arc
					(start 440.917076 -32.856678)
					(mid 440.881155 -32.841799)
					(end 440.866276 -32.805878)
				)
				(arc
					(start 440.866276 -31.77413)
					(mid 440.881155 -31.738209)
					(end 440.917076 -31.72333)
				)
				(arc
					(start 442.148976 -31.72333)
					(mid 442.184897 -31.738209)
					(end 442.199776 -31.77413)
				)
			)
		)
	)
	(zone
		(layer "In1.Cu")
		(hatch none 0.5)
		(connect_pads
			(clearance 0)
		)
		(min_thickness 0.25)
		(keepout
			(tracks not_allowed)
			(vias allowed)
			(pads allowed)
			(copperpour not_allowed)
			(footprints allowed)
		)
		(placement
			(enabled no)
			(sheetname "")
		)
		(fill
			(thermal_gap 0.5)
			(thermal_bridge_width 0.5)
			(island_removal_mode 0)
		)
		(polygon
			(pts
				(arc
					(start 168.238678 -355.825806)
					(mid 168.202757 -355.840685)
					(end 168.187878 -355.876606)
				)
				(arc
					(start 168.187878 -356.613206)
					(mid 168.202757 -356.649127)
					(end 168.238678 -356.664006)
				)
				(xy 168.482518 -356.664006) (xy 168.836848 -356.431596) (xy 169.192448 -356.664006)
				(arc
					(start 169.435018 -356.664006)
					(mid 169.470939 -356.649127)
					(end 169.485818 -356.613206)
				)
				(arc
					(start 169.485818 -355.876606)
					(mid 169.470939 -355.840685)
					(end 169.435018 -355.825806)
				)
				(xy 169.192448 -355.825806) (xy 168.835578 -356.058216) (xy 168.481248 -355.825806)
			)
		)
	)
	(zone
		(layer "In1.Cu")
		(hatch none 0.5)
		(connect_pads
			(clearance 0)
		)
		(min_thickness 0.25)
		(keepout
			(tracks not_allowed)
			(vias allowed)
			(pads allowed)
			(copperpour not_allowed)
			(footprints allowed)
		)
		(placement
			(enabled no)
			(sheetname "")
		)
		(fill
			(thermal_gap 0.5)
			(thermal_bridge_width 0.5)
			(island_removal_mode 0)
		)
		(polygon
			(pts
				(arc
					(start 50.256694 -349.679514)
					(mid 50.220773 -349.694393)
					(end 50.205894 -349.730314)
				)
				(arc
					(start 50.205894 -350.466914)
					(mid 50.220773 -350.502835)
					(end 50.256694 -350.517714)
				)
				(xy 50.500534 -350.517714) (xy 50.854864 -350.285304) (xy 51.210464 -350.517714)
				(arc
					(start 51.453034 -350.517714)
					(mid 51.488955 -350.502835)
					(end 51.503834 -350.466914)
				)
				(arc
					(start 51.503834 -349.730314)
					(mid 51.488955 -349.694393)
					(end 51.453034 -349.679514)
				)
				(xy 51.210464 -349.679514) (xy 50.853594 -349.911924) (xy 50.499264 -349.679514)
			)
		)
	)
	(zone
		(layer "In1.Cu")
		(hatch none 0.5)
		(connect_pads
			(clearance 0)
		)
		(min_thickness 0.25)
		(keepout
			(tracks not_allowed)
			(vias allowed)
			(pads allowed)
			(copperpour not_allowed)
			(footprints allowed)
		)
		(placement
			(enabled no)
			(sheetname "")
		)
		(fill
			(thermal_gap 0.5)
			(thermal_bridge_width 0.5)
			(island_removal_mode 0)
		)
		(polygon
			(pts
				(arc
					(start 252.215396 -31.086044)
					(mid 252.230275 -31.121965)
					(end 252.266196 -31.136844)
				)
				(arc
					(start 253.002796 -31.136844)
					(mid 253.038717 -31.121965)
					(end 253.053596 -31.086044)
				)
				(xy 253.053596 -30.842204) (xy 252.821186 -30.487874) (xy 253.053596 -30.132274)
				(arc
					(start 253.053596 -29.889704)
					(mid 253.038717 -29.853783)
					(end 253.002796 -29.838904)
				)
				(arc
					(start 252.266196 -29.838904)
					(mid 252.230275 -29.853783)
					(end 252.215396 -29.889704)
				)
				(xy 252.215396 -30.132274) (xy 252.447806 -30.489144) (xy 252.215396 -30.843474)
			)
		)
	)
	(zone
		(layer "In1.Cu")
		(hatch none 0.5)
		(connect_pads
			(clearance 0)
		)
		(min_thickness 0.25)
		(keepout
			(tracks not_allowed)
			(vias allowed)
			(pads allowed)
			(copperpour not_allowed)
			(footprints allowed)
		)
		(placement
			(enabled no)
			(sheetname "")
		)
		(fill
			(thermal_gap 0.5)
			(thermal_bridge_width 0.5)
			(island_removal_mode 0)
		)
		(polygon
			(pts
				(arc
					(start 283.452062 -133.16839)
					(mid 283.437183 -133.204311)
					(end 283.401262 -133.21919)
				)
				(arc
					(start 282.220162 -133.21919)
					(mid 282.184241 -133.204311)
					(end 282.169362 -133.16839)
				)
				(arc
					(start 282.169362 -132.162042)
					(mid 282.184241 -132.126121)
					(end 282.220162 -132.111242)
				)
				(arc
					(start 283.401262 -132.111242)
					(mid 283.437183 -132.126121)
					(end 283.452062 -132.162042)
				)
			)
		)
	)
	(zone
		(layer "In1.Cu")
		(hatch none 0.5)
		(connect_pads
			(clearance 0)
		)
		(min_thickness 0.25)
		(keepout
			(tracks not_allowed)
			(vias allowed)
			(pads allowed)
			(copperpour not_allowed)
			(footprints allowed)
		)
		(placement
			(enabled no)
			(sheetname "")
		)
		(fill
			(thermal_gap 0.5)
			(thermal_bridge_width 0.5)
			(island_removal_mode 0)
		)
		(polygon
			(pts
				(arc
					(start 271.061434 -107.543092)
					(mid 271.076313 -107.579013)
					(end 271.112234 -107.593892)
				)
				(arc
					(start 271.848834 -107.593892)
					(mid 271.884755 -107.579013)
					(end 271.899634 -107.543092)
				)
				(xy 271.899634 -107.299252) (xy 271.667224 -106.944922) (xy 271.899634 -106.589322)
				(arc
					(start 271.899634 -106.346752)
					(mid 271.884755 -106.310831)
					(end 271.848834 -106.295952)
				)
				(arc
					(start 271.112234 -106.295952)
					(mid 271.076313 -106.310831)
					(end 271.061434 -106.346752)
				)
				(xy 271.061434 -106.589322) (xy 271.293844 -106.946192) (xy 271.061434 -107.300522)
			)
		)
	)
	(zone
		(layer "In1.Cu")
		(hatch none 0.5)
		(connect_pads
			(clearance 0)
		)
		(min_thickness 0.25)
		(keepout
			(tracks not_allowed)
			(vias allowed)
			(pads allowed)
			(copperpour not_allowed)
			(footprints allowed)
		)
		(placement
			(enabled no)
			(sheetname "")
		)
		(fill
			(thermal_gap 0.5)
			(thermal_bridge_width 0.5)
			(island_removal_mode 0)
		)
		(polygon
			(pts
				(arc
					(start 232.385362 -89.536524)
					(mid 232.400241 -89.500603)
					(end 232.436162 -89.485724)
				)
				(arc
					(start 233.100372 -89.485724)
					(mid 233.136293 -89.500603)
					(end 233.151172 -89.536524)
				)
				(arc
					(start 233.151172 -90.174826)
					(mid 233.136293 -90.210747)
					(end 233.100372 -90.225626)
				)
				(arc
					(start 232.436162 -90.225626)
					(mid 232.400241 -90.210747)
					(end 232.385362 -90.174826)
				)
			)
		)
	)
	(zone
		(layer "In1.Cu")
		(hatch none 0.5)
		(connect_pads
			(clearance 0)
		)
		(min_thickness 0.25)
		(keepout
			(tracks not_allowed)
			(vias allowed)
			(pads allowed)
			(copperpour not_allowed)
			(footprints allowed)
		)
		(placement
			(enabled no)
			(sheetname "")
		)
		(fill
			(thermal_gap 0.5)
			(thermal_bridge_width 0.5)
			(island_removal_mode 0)
		)
		(polygon
			(pts
				(arc
					(start 131.99999 -27.405838)
					(mid 131.985111 -27.441759)
					(end 131.94919 -27.456638)
				)
				(arc
					(start 130.71729 -27.456638)
					(mid 130.681369 -27.441759)
					(end 130.66649 -27.405838)
				)
				(arc
					(start 130.66649 -26.37409)
					(mid 130.681369 -26.338169)
					(end 130.71729 -26.32329)
				)
				(arc
					(start 131.94919 -26.32329)
					(mid 131.985111 -26.338169)
					(end 131.99999 -26.37409)
				)
			)
		)
	)
	(zone
		(layer "In1.Cu")
		(hatch none 0.5)
		(connect_pads
			(clearance 0)
		)
		(min_thickness 0.25)
		(keepout
			(tracks not_allowed)
			(vias allowed)
			(pads allowed)
			(copperpour not_allowed)
			(footprints allowed)
		)
		(placement
			(enabled no)
			(sheetname "")
		)
		(fill
			(thermal_gap 0.5)
			(thermal_bridge_width 0.5)
			(island_removal_mode 0)
		)
		(polygon
			(pts
				(arc
					(start 161.53257 -111.841788)
					(mid 161.547449 -111.805867)
					(end 161.58337 -111.790988)
				)
				(arc
					(start 162.76447 -111.790988)
					(mid 162.800391 -111.805867)
					(end 162.81527 -111.841788)
				)
				(arc
					(start 162.81527 -112.848136)
					(mid 162.800391 -112.884057)
					(end 162.76447 -112.898936)
				)
				(arc
					(start 161.58337 -112.898936)
					(mid 161.547449 -112.884057)
					(end 161.53257 -112.848136)
				)
			)
		)
	)
	(zone
		(layer "In1.Cu")
		(hatch none 0.5)
		(connect_pads
			(clearance 0)
		)
		(min_thickness 0.25)
		(keepout
			(tracks not_allowed)
			(vias allowed)
			(pads allowed)
			(copperpour not_allowed)
			(footprints allowed)
		)
		(placement
			(enabled no)
			(sheetname "")
		)
		(fill
			(thermal_gap 0.5)
			(thermal_bridge_width 0.5)
			(island_removal_mode 0)
		)
		(polygon
			(pts
				(arc
					(start 180.674518 -343.533222)
					(mid 180.638597 -343.548101)
					(end 180.623718 -343.584022)
				)
				(arc
					(start 180.623718 -344.320622)
					(mid 180.638597 -344.356543)
					(end 180.674518 -344.371422)
				)
				(xy 180.918358 -344.371422) (xy 181.272688 -344.139012) (xy 181.628288 -344.371422)
				(arc
					(start 181.870858 -344.371422)
					(mid 181.906779 -344.356543)
					(end 181.921658 -344.320622)
				)
				(arc
					(start 181.921658 -343.584022)
					(mid 181.906779 -343.548101)
					(end 181.870858 -343.533222)
				)
				(xy 181.628288 -343.533222) (xy 181.271418 -343.765632) (xy 180.917088 -343.533222)
			)
		)
	)
	(zone
		(layer "In1.Cu")
		(hatch none 0.5)
		(connect_pads
			(clearance 0)
		)
		(min_thickness 0.25)
		(keepout
			(tracks not_allowed)
			(vias allowed)
			(pads allowed)
			(copperpour not_allowed)
			(footprints allowed)
		)
		(placement
			(enabled no)
			(sheetname "")
		)
		(fill
			(thermal_gap 0.5)
			(thermal_bridge_width 0.5)
			(island_removal_mode 0)
		)
		(polygon
			(pts
				(arc
					(start 36.0299 -31.77413)
					(mid 36.044779 -31.738209)
					(end 36.0807 -31.72333)
				)
				(arc
					(start 37.3126 -31.72333)
					(mid 37.348521 -31.738209)
					(end 37.3634 -31.77413)
				)
				(arc
					(start 37.3634 -32.805878)
					(mid 37.348521 -32.841799)
					(end 37.3126 -32.856678)
				)
				(arc
					(start 36.0807 -32.856678)
					(mid 36.044779 -32.841799)
					(end 36.0299 -32.805878)
				)
			)
		)
	)
	(zone
		(layer "In1.Cu")
		(hatch none 0.5)
		(connect_pads
			(clearance 0)
		)
		(min_thickness 0.25)
		(keepout
			(tracks not_allowed)
			(vias allowed)
			(pads allowed)
			(copperpour not_allowed)
			(footprints allowed)
		)
		(placement
			(enabled no)
			(sheetname "")
		)
		(fill
			(thermal_gap 0.5)
			(thermal_bridge_width 0.5)
			(island_removal_mode 0)
		)
		(polygon
			(pts
				(arc
					(start 311.80024 -130.93446)
					(mid 311.815119 -130.970381)
					(end 311.85104 -130.98526)
				)
				(arc
					(start 312.58764 -130.98526)
					(mid 312.623561 -130.970381)
					(end 312.63844 -130.93446)
				)
				(xy 312.63844 -130.69062) (xy 312.40603 -130.33629) (xy 312.63844 -129.98069)
				(arc
					(start 312.63844 -129.73812)
					(mid 312.623561 -129.702199)
					(end 312.58764 -129.68732)
				)
				(arc
					(start 311.85104 -129.68732)
					(mid 311.815119 -129.702199)
					(end 311.80024 -129.73812)
				)
				(xy 311.80024 -129.98069) (xy 312.03265 -130.33756) (xy 311.80024 -130.69189)
			)
		)
	)
	(zone
		(layer "In1.Cu")
		(hatch none 0.5)
		(connect_pads
			(clearance 0)
		)
		(min_thickness 0.25)
		(keepout
			(tracks not_allowed)
			(vias allowed)
			(pads allowed)
			(copperpour not_allowed)
			(footprints allowed)
		)
		(placement
			(enabled no)
			(sheetname "")
		)
		(fill
			(thermal_gap 0.5)
			(thermal_bridge_width 0.5)
			(island_removal_mode 0)
		)
		(polygon
			(pts
				(arc
					(start 274.099782 -31.006034)
					(mid 274.084903 -31.041955)
					(end 274.048982 -31.056834)
				)
				(arc
					(start 272.817082 -31.056834)
					(mid 272.781161 -31.041955)
					(end 272.766282 -31.006034)
				)
				(arc
					(start 272.766282 -29.974286)
					(mid 272.781161 -29.938365)
					(end 272.817082 -29.923486)
				)
				(arc
					(start 274.048982 -29.923486)
					(mid 274.084903 -29.938365)
					(end 274.099782 -29.974286)
				)
			)
		)
	)
	(zone
		(layer "In1.Cu")
		(hatch none 0.5)
		(connect_pads
			(clearance 0)
		)
		(min_thickness 0.25)
		(keepout
			(tracks not_allowed)
			(vias allowed)
			(pads allowed)
			(copperpour not_allowed)
			(footprints allowed)
		)
		(placement
			(enabled no)
			(sheetname "")
		)
		(fill
			(thermal_gap 0.5)
			(thermal_bridge_width 0.5)
			(island_removal_mode 0)
		)
		(polygon
			(pts
				(arc
					(start 421.565578 -355.825806)
					(mid 421.529657 -355.840685)
					(end 421.514778 -355.876606)
				)
				(arc
					(start 421.514778 -356.613206)
					(mid 421.529657 -356.649127)
					(end 421.565578 -356.664006)
				)
				(xy 421.809418 -356.664006) (xy 422.163748 -356.431596) (xy 422.519348 -356.664006)
				(arc
					(start 422.761918 -356.664006)
					(mid 422.797839 -356.649127)
					(end 422.812718 -356.613206)
				)
				(arc
					(start 422.812718 -355.876606)
					(mid 422.797839 -355.840685)
					(end 422.761918 -355.825806)
				)
				(xy 422.519348 -355.825806) (xy 422.162478 -356.058216) (xy 421.808148 -355.825806)
			)
		)
	)
	(zone
		(layer "In1.Cu")
		(hatch none 0.5)
		(connect_pads
			(clearance 0)
		)
		(min_thickness 0.25)
		(keepout
			(tracks not_allowed)
			(vias allowed)
			(pads allowed)
			(copperpour not_allowed)
			(footprints allowed)
		)
		(placement
			(enabled no)
			(sheetname "")
		)
		(fill
			(thermal_gap 0.5)
			(thermal_bridge_width 0.5)
			(island_removal_mode 0)
		)
		(polygon
			(pts
				(arc
					(start 387.161532 -136.869678)
					(mid 387.176411 -136.905599)
					(end 387.212332 -136.920478)
				)
				(arc
					(start 387.948932 -136.920478)
					(mid 387.984853 -136.905599)
					(end 387.999732 -136.869678)
				)
				(xy 387.999732 -136.625838) (xy 387.767322 -136.271508) (xy 387.999732 -135.915908)
				(arc
					(start 387.999732 -135.673338)
					(mid 387.984853 -135.637417)
					(end 387.948932 -135.622538)
				)
				(arc
					(start 387.212332 -135.622538)
					(mid 387.176411 -135.637417)
					(end 387.161532 -135.673338)
				)
				(xy 387.161532 -135.915908) (xy 387.393942 -136.272778) (xy 387.161532 -136.627108)
			)
		)
	)
	(zone
		(layer "In1.Cu")
		(hatch none 0.5)
		(connect_pads
			(clearance 0)
		)
		(min_thickness 0.25)
		(keepout
			(tracks not_allowed)
			(vias allowed)
			(pads allowed)
			(copperpour not_allowed)
			(footprints allowed)
		)
		(placement
			(enabled no)
			(sheetname "")
		)
		(fill
			(thermal_gap 0.5)
			(thermal_bridge_width 0.5)
			(island_removal_mode 0)
		)
		(polygon
			(pts
				(arc
					(start 51.25212 -112.848136)
					(mid 51.237241 -112.884057)
					(end 51.20132 -112.898936)
				)
				(arc
					(start 50.02022 -112.898936)
					(mid 49.984299 -112.884057)
					(end 49.96942 -112.848136)
				)
				(arc
					(start 49.96942 -111.841788)
					(mid 49.984299 -111.805867)
					(end 50.02022 -111.790988)
				)
				(arc
					(start 51.20132 -111.790988)
					(mid 51.237241 -111.805867)
					(end 51.25212 -111.841788)
				)
			)
		)
	)
	(zone
		(layer "In1.Cu")
		(hatch none 0.5)
		(connect_pads
			(clearance 0)
		)
		(min_thickness 0.25)
		(keepout
			(tracks not_allowed)
			(vias allowed)
			(pads allowed)
			(copperpour not_allowed)
			(footprints allowed)
		)
		(placement
			(enabled no)
			(sheetname "")
		)
		(fill
			(thermal_gap 0.5)
			(thermal_bridge_width 0.5)
			(island_removal_mode 0)
		)
		(polygon
			(pts
				(arc
					(start 88.029796 -29.974286)
					(mid 88.044675 -29.938365)
					(end 88.080596 -29.923486)
				)
				(arc
					(start 89.312496 -29.923486)
					(mid 89.348417 -29.938365)
					(end 89.363296 -29.974286)
				)
				(arc
					(start 89.363296 -31.006034)
					(mid 89.348417 -31.041955)
					(end 89.312496 -31.056834)
				)
				(arc
					(start 88.080596 -31.056834)
					(mid 88.044675 -31.041955)
					(end 88.029796 -31.006034)
				)
			)
		)
	)
	(zone
		(layer "In1.Cu")
		(hatch none 0.5)
		(connect_pads
			(clearance 0)
		)
		(min_thickness 0.25)
		(keepout
			(tracks not_allowed)
			(vias allowed)
			(pads allowed)
			(copperpour not_allowed)
			(footprints allowed)
		)
		(placement
			(enabled no)
			(sheetname "")
		)
		(fill
			(thermal_gap 0.5)
			(thermal_bridge_width 0.5)
			(island_removal_mode 0)
		)
		(polygon
			(pts
				(arc
					(start 178.129946 -28.174188)
					(mid 178.144825 -28.138267)
					(end 178.180746 -28.123388)
				)
				(arc
					(start 179.412646 -28.123388)
					(mid 179.448567 -28.138267)
					(end 179.463446 -28.174188)
				)
				(arc
					(start 179.463446 -29.205936)
					(mid 179.448567 -29.241857)
					(end 179.412646 -29.256736)
				)
				(arc
					(start 178.180746 -29.256736)
					(mid 178.144825 -29.241857)
					(end 178.129946 -29.205936)
				)
			)
		)
	)
	(zone
		(layer "In1.Cu")
		(hatch none 0.5)
		(connect_pads
			(clearance 0)
		)
		(min_thickness 0.25)
		(keepout
			(tracks not_allowed)
			(vias allowed)
			(pads allowed)
			(copperpour not_allowed)
			(footprints allowed)
		)
		(placement
			(enabled no)
			(sheetname "")
		)
		(fill
			(thermal_gap 0.5)
			(thermal_bridge_width 0.5)
			(island_removal_mode 0)
		)
		(polygon
			(pts
				(arc
					(start 295.712388 -349.679514)
					(mid 295.676467 -349.694393)
					(end 295.661588 -349.730314)
				)
				(arc
					(start 295.661588 -350.466914)
					(mid 295.676467 -350.502835)
					(end 295.712388 -350.517714)
				)
				(xy 295.956228 -350.517714) (xy 296.310558 -350.285304) (xy 296.666158 -350.517714)
				(arc
					(start 296.908728 -350.517714)
					(mid 296.944649 -350.502835)
					(end 296.959528 -350.466914)
				)
				(arc
					(start 296.959528 -349.730314)
					(mid 296.944649 -349.694393)
					(end 296.908728 -349.679514)
				)
				(xy 296.666158 -349.679514) (xy 296.309288 -349.911924) (xy 295.954958 -349.679514)
			)
		)
	)
	(zone
		(layer "In1.Cu")
		(hatch none 0.5)
		(connect_pads
			(clearance 0)
		)
		(min_thickness 0.25)
		(keepout
			(tracks not_allowed)
			(vias allowed)
			(pads allowed)
			(copperpour not_allowed)
			(footprints allowed)
		)
		(placement
			(enabled no)
			(sheetname "")
		)
		(fill
			(thermal_gap 0.5)
			(thermal_bridge_width 0.5)
			(island_removal_mode 0)
		)
		(polygon
			(pts
				(arc
					(start 430.542446 -149.051264)
					(mid 430.557325 -149.087185)
					(end 430.593246 -149.102064)
				)
				(arc
					(start 431.329846 -149.102064)
					(mid 431.365767 -149.087185)
					(end 431.380646 -149.051264)
				)
				(xy 431.380646 -148.807424) (xy 431.148236 -148.453094) (xy 431.380646 -148.097494)
				(arc
					(start 431.380646 -147.854924)
					(mid 431.365767 -147.819003)
					(end 431.329846 -147.804124)
				)
				(arc
					(start 430.593246 -147.804124)
					(mid 430.557325 -147.819003)
					(end 430.542446 -147.854924)
				)
				(xy 430.542446 -148.097494) (xy 430.774856 -148.454364) (xy 430.542446 -148.808694)
			)
		)
	)
	(zone
		(layer "In1.Cu")
		(hatch none 0.5)
		(connect_pads
			(clearance 0)
		)
		(min_thickness 0.25)
		(keepout
			(tracks not_allowed)
			(vias allowed)
			(pads allowed)
			(copperpour not_allowed)
			(footprints allowed)
		)
		(placement
			(enabled no)
			(sheetname "")
		)
		(fill
			(thermal_gap 0.5)
			(thermal_bridge_width 0.5)
			(island_removal_mode 0)
		)
		(polygon
			(pts
				(arc
					(start 416.34791 -120.431814)
					(mid 416.362789 -120.395893)
					(end 416.39871 -120.381014)
				)
				(arc
					(start 417.57981 -120.381014)
					(mid 417.615731 -120.395893)
					(end 417.63061 -120.431814)
				)
				(arc
					(start 417.63061 -121.438162)
					(mid 417.615731 -121.474083)
					(end 417.57981 -121.488962)
				)
				(arc
					(start 416.39871 -121.488962)
					(mid 416.362789 -121.474083)
					(end 416.34791 -121.438162)
				)
			)
		)
	)
	(zone
		(layer "In1.Cu")
		(hatch none 0.5)
		(connect_pads
			(clearance 0)
		)
		(min_thickness 0.25)
		(keepout
			(tracks not_allowed)
			(vias allowed)
			(pads allowed)
			(copperpour not_allowed)
			(footprints allowed)
		)
		(placement
			(enabled no)
			(sheetname "")
		)
		(fill
			(thermal_gap 0.5)
			(thermal_bridge_width 0.5)
			(island_removal_mode 0)
		)
		(polygon
			(pts
				(arc
					(start 51.25212 -123.758452)
					(mid 51.237241 -123.794373)
					(end 51.20132 -123.809252)
				)
				(arc
					(start 50.02022 -123.809252)
					(mid 49.984299 -123.794373)
					(end 49.96942 -123.758452)
				)
				(arc
					(start 49.96942 -122.752104)
					(mid 49.984299 -122.716183)
					(end 50.02022 -122.701304)
				)
				(arc
					(start 51.20132 -122.701304)
					(mid 51.237241 -122.716183)
					(end 51.25212 -122.752104)
				)
			)
		)
	)
	(zone
		(layer "In1.Cu")
		(hatch none 0.5)
		(connect_pads
			(clearance 0)
		)
		(min_thickness 0.25)
		(keepout
			(tracks not_allowed)
			(vias allowed)
			(pads allowed)
			(copperpour not_allowed)
			(footprints allowed)
		)
		(placement
			(enabled no)
			(sheetname "")
		)
		(fill
			(thermal_gap 0.5)
			(thermal_bridge_width 0.5)
			(island_removal_mode 0)
		)
		(polygon
			(pts
				(arc
					(start 446.315338 -34.68624)
					(mid 446.330217 -34.722161)
					(end 446.366138 -34.73704)
				)
				(arc
					(start 447.102738 -34.73704)
					(mid 447.138659 -34.722161)
					(end 447.153538 -34.68624)
				)
				(xy 447.153538 -34.4424) (xy 446.921128 -34.08807) (xy 447.153538 -33.73247)
				(arc
					(start 447.153538 -33.4899)
					(mid 447.138659 -33.453979)
					(end 447.102738 -33.4391)
				)
				(arc
					(start 446.366138 -33.4391)
					(mid 446.330217 -33.453979)
					(end 446.315338 -33.4899)
				)
				(xy 446.315338 -33.73247) (xy 446.547748 -34.08934) (xy 446.315338 -34.44367)
			)
		)
	)
	(zone
		(layer "In1.Cu")
		(hatch none 0.5)
		(connect_pads
			(clearance 0)
		)
		(min_thickness 0.25)
		(keepout
			(tracks not_allowed)
			(vias allowed)
			(pads allowed)
			(copperpour not_allowed)
			(footprints allowed)
		)
		(placement
			(enabled no)
			(sheetname "")
		)
		(fill
			(thermal_gap 0.5)
			(thermal_bridge_width 0.5)
			(island_removal_mode 0)
		)
		(polygon
			(pts
				(arc
					(start 393.732766 -122.752104)
					(mid 393.747645 -122.716183)
					(end 393.783566 -122.701304)
				)
				(arc
					(start 394.964666 -122.701304)
					(mid 395.000587 -122.716183)
					(end 395.015466 -122.752104)
				)
				(arc
					(start 395.015466 -123.758452)
					(mid 395.000587 -123.794373)
					(end 394.964666 -123.809252)
				)
				(arc
					(start 393.783566 -123.809252)
					(mid 393.747645 -123.794373)
					(end 393.732766 -123.758452)
				)
			)
		)
	)
	(zone
		(layer "In1.Cu")
		(hatch none 0.5)
		(connect_pads
			(clearance 0)
		)
		(min_thickness 0.25)
		(keepout
			(tracks not_allowed)
			(vias allowed)
			(pads allowed)
			(copperpour not_allowed)
			(footprints allowed)
		)
		(placement
			(enabled no)
			(sheetname "")
		)
		(fill
			(thermal_gap 0.5)
			(thermal_bridge_width 0.5)
			(island_removal_mode 0)
		)
		(polygon
			(pts
				(arc
					(start 189.967108 -152.558242)
					(mid 189.952229 -152.594163)
					(end 189.916308 -152.609042)
				)
				(arc
					(start 188.735208 -152.609042)
					(mid 188.699287 -152.594163)
					(end 188.684408 -152.558242)
				)
				(arc
					(start 188.684408 -151.551894)
					(mid 188.699287 -151.515973)
					(end 188.735208 -151.501094)
				)
				(arc
					(start 189.916308 -151.501094)
					(mid 189.952229 -151.515973)
					(end 189.967108 -151.551894)
				)
			)
		)
	)
	(zone
		(layer "In1.Cu")
		(hatch none 0.5)
		(connect_pads
			(clearance 0)
		)
		(min_thickness 0.25)
		(keepout
			(tracks not_allowed)
			(vias allowed)
			(pads allowed)
			(copperpour not_allowed)
			(footprints allowed)
		)
		(placement
			(enabled no)
			(sheetname "")
		)
		(fill
			(thermal_gap 0.5)
			(thermal_bridge_width 0.5)
			(island_removal_mode 0)
		)
		(polygon
			(pts
				(arc
					(start 385.129024 -102.149656)
					(mid 385.143903 -102.185577)
					(end 385.179824 -102.200456)
				)
				(arc
					(start 385.916424 -102.200456)
					(mid 385.952345 -102.185577)
					(end 385.967224 -102.149656)
				)
				(xy 385.967224 -101.905816) (xy 385.734814 -101.551486) (xy 385.967224 -101.195886)
				(arc
					(start 385.967224 -100.953316)
					(mid 385.952345 -100.917395)
					(end 385.916424 -100.902516)
				)
				(arc
					(start 385.179824 -100.902516)
					(mid 385.143903 -100.917395)
					(end 385.129024 -100.953316)
				)
				(xy 385.129024 -101.195886) (xy 385.361434 -101.552756) (xy 385.129024 -101.907086)
			)
		)
	)
	(zone
		(layer "In1.Cu")
		(hatch none 0.5)
		(connect_pads
			(clearance 0)
		)
		(min_thickness 0.25)
		(keepout
			(tracks not_allowed)
			(vias allowed)
			(pads allowed)
			(copperpour not_allowed)
			(footprints allowed)
		)
		(placement
			(enabled no)
			(sheetname "")
		)
		(fill
			(thermal_gap 0.5)
			(thermal_bridge_width 0.5)
			(island_removal_mode 0)
		)
		(polygon
			(pts
				(arc
					(start 283.276548 -349.679514)
					(mid 283.240627 -349.694393)
					(end 283.225748 -349.730314)
				)
				(arc
					(start 283.225748 -350.466914)
					(mid 283.240627 -350.502835)
					(end 283.276548 -350.517714)
				)
				(xy 283.520388 -350.517714) (xy 283.874718 -350.285304) (xy 284.230318 -350.517714)
				(arc
					(start 284.472888 -350.517714)
					(mid 284.508809 -350.502835)
					(end 284.523688 -350.466914)
				)
				(arc
					(start 284.523688 -349.730314)
					(mid 284.508809 -349.694393)
					(end 284.472888 -349.679514)
				)
				(xy 284.230318 -349.679514) (xy 283.873448 -349.911924) (xy 283.519118 -349.679514)
			)
		)
	)
	(zone
		(layer "In1.Cu")
		(hatch none 0.5)
		(connect_pads
			(clearance 0)
		)
		(min_thickness 0.25)
		(keepout
			(tracks not_allowed)
			(vias allowed)
			(pads allowed)
			(copperpour not_allowed)
			(footprints allowed)
		)
		(placement
			(enabled no)
			(sheetname "")
		)
		(fill
			(thermal_gap 0.5)
			(thermal_bridge_width 0.5)
			(island_removal_mode 0)
		)
		(polygon
			(pts
				(arc
					(start 452.685404 -209.705194)
					(mid 452.700283 -209.669273)
					(end 452.736204 -209.654394)
				)
				(arc
					(start 453.265794 -209.654394)
					(mid 453.301715 -209.669273)
					(end 453.316594 -209.705194)
				)
				(arc
					(start 453.316594 -210.259422)
					(mid 453.301715 -210.295343)
					(end 453.265794 -210.310222)
				)
				(arc
					(start 452.736204 -210.310222)
					(mid 452.700283 -210.295343)
					(end 452.685404 -210.259422)
				)
			)
		)
	)
	(zone
		(layer "In1.Cu")
		(hatch none 0.5)
		(connect_pads
			(clearance 0)
		)
		(min_thickness 0.25)
		(keepout
			(tracks not_allowed)
			(vias allowed)
			(pads allowed)
			(copperpour not_allowed)
			(footprints allowed)
		)
		(placement
			(enabled no)
			(sheetname "")
		)
		(fill
			(thermal_gap 0.5)
			(thermal_bridge_width 0.5)
			(island_removal_mode 0)
		)
		(polygon
			(pts
				(arc
					(start 161.53257 -106.441748)
					(mid 161.547449 -106.405827)
					(end 161.58337 -106.390948)
				)
				(arc
					(start 162.76447 -106.390948)
					(mid 162.800391 -106.405827)
					(end 162.81527 -106.441748)
				)
				(arc
					(start 162.81527 -107.448096)
					(mid 162.800391 -107.484017)
					(end 162.76447 -107.498896)
				)
				(arc
					(start 161.58337 -107.498896)
					(mid 161.547449 -107.484017)
					(end 161.53257 -107.448096)
				)
			)
		)
	)
	(zone
		(layer "In1.Cu")
		(hatch none 0.5)
		(connect_pads
			(clearance 0)
		)
		(min_thickness 0.25)
		(keepout
			(tracks not_allowed)
			(vias allowed)
			(pads allowed)
			(copperpour not_allowed)
			(footprints allowed)
		)
		(placement
			(enabled no)
			(sheetname "")
		)
		(fill
			(thermal_gap 0.5)
			(thermal_bridge_width 0.5)
			(island_removal_mode 0)
		)
		(polygon
			(pts
				(arc
					(start 50.256694 -355.825806)
					(mid 50.220773 -355.840685)
					(end 50.205894 -355.876606)
				)
				(arc
					(start 50.205894 -356.613206)
					(mid 50.220773 -356.649127)
					(end 50.256694 -356.664006)
				)
				(xy 50.500534 -356.664006) (xy 50.854864 -356.431596) (xy 51.210464 -356.664006)
				(arc
					(start 51.453034 -356.664006)
					(mid 51.488955 -356.649127)
					(end 51.503834 -356.613206)
				)
				(arc
					(start 51.503834 -355.876606)
					(mid 51.488955 -355.840685)
					(end 51.453034 -355.825806)
				)
				(xy 51.210464 -355.825806) (xy 50.853594 -356.058216) (xy 50.499264 -355.825806)
			)
		)
	)
	(zone
		(layer "In1.Cu")
		(hatch none 0.5)
		(connect_pads
			(clearance 0)
		)
		(min_thickness 0.25)
		(keepout
			(tracks not_allowed)
			(vias allowed)
			(pads allowed)
			(copperpour not_allowed)
			(footprints allowed)
		)
		(placement
			(enabled no)
			(sheetname "")
		)
		(fill
			(thermal_gap 0.5)
			(thermal_bridge_width 0.5)
			(island_removal_mode 0)
		)
		(polygon
			(pts
				(arc
					(start 10.029952 -28.174188)
					(mid 10.044831 -28.138267)
					(end 10.080752 -28.123388)
				)
				(arc
					(start 11.312652 -28.123388)
					(mid 11.348573 -28.138267)
					(end 11.363452 -28.174188)
				)
				(arc
					(start 11.363452 -29.205936)
					(mid 11.348573 -29.241857)
					(end 11.312652 -29.256736)
				)
				(arc
					(start 10.080752 -29.256736)
					(mid 10.044831 -29.241857)
					(end 10.029952 -29.205936)
				)
			)
		)
	)
	(zone
		(layer "In1.Cu")
		(hatch none 0.5)
		(connect_pads
			(clearance 0)
		)
		(min_thickness 0.25)
		(keepout
			(tracks not_allowed)
			(vias allowed)
			(pads allowed)
			(copperpour not_allowed)
			(footprints allowed)
		)
		(placement
			(enabled no)
			(sheetname "")
		)
		(fill
			(thermal_gap 0.5)
			(thermal_bridge_width 0.5)
			(island_removal_mode 0)
		)
		(polygon
			(pts
				(arc
					(start 268.419326 -112.949736)
					(mid 268.434205 -112.985657)
					(end 268.470126 -113.000536)
				)
				(arc
					(start 269.206726 -113.000536)
					(mid 269.242647 -112.985657)
					(end 269.257526 -112.949736)
				)
				(xy 269.257526 -112.705896) (xy 269.025116 -112.351566) (xy 269.257526 -111.995966)
				(arc
					(start 269.257526 -111.753396)
					(mid 269.242647 -111.717475)
					(end 269.206726 -111.702596)
				)
				(arc
					(start 268.470126 -111.702596)
					(mid 268.434205 -111.717475)
					(end 268.419326 -111.753396)
				)
				(xy 268.419326 -111.995966) (xy 268.651736 -112.352836) (xy 268.419326 -112.707166)
			)
		)
	)
	(zone
		(layer "In1.Cu")
		(hatch none 0.5)
		(connect_pads
			(clearance 0)
		)
		(min_thickness 0.25)
		(keepout
			(tracks not_allowed)
			(vias allowed)
			(pads allowed)
			(copperpour not_allowed)
			(footprints allowed)
		)
		(placement
			(enabled no)
			(sheetname "")
		)
		(fill
			(thermal_gap 0.5)
			(thermal_bridge_width 0.5)
			(island_removal_mode 0)
		)
		(polygon
			(pts
				(arc
					(start 14.00683 -376.646186)
					(mid 14.042751 -376.661065)
					(end 14.05763 -376.696986)
				)
				(arc
					(start 14.05763 -377.10364)
					(mid 14.042751 -377.139561)
					(end 14.00683 -377.15444)
				)
				(arc
					(start 13.604494 -377.15444)
					(mid 13.568573 -377.139561)
					(end 13.553694 -377.10364)
				)
				(arc
					(start 13.553694 -376.696986)
					(mid 13.568573 -376.661065)
					(end 13.604494 -376.646186)
				)
			)
		)
	)
	(zone
		(layer "In1.Cu")
		(hatch none 0.5)
		(connect_pads
			(clearance 0)
		)
		(min_thickness 0.25)
		(keepout
			(tracks not_allowed)
			(vias allowed)
			(pads allowed)
			(copperpour not_allowed)
			(footprints allowed)
		)
		(placement
			(enabled no)
			(sheetname "")
		)
		(fill
			(thermal_gap 0.5)
			(thermal_bridge_width 0.5)
			(island_removal_mode 0)
		)
		(polygon
			(pts
				(arc
					(start 165.129718 -355.825806)
					(mid 165.093797 -355.840685)
					(end 165.078918 -355.876606)
				)
				(arc
					(start 165.078918 -356.613206)
					(mid 165.093797 -356.649127)
					(end 165.129718 -356.664006)
				)
				(xy 165.373558 -356.664006) (xy 165.727888 -356.431596) (xy 166.083488 -356.664006)
				(arc
					(start 166.326058 -356.664006)
					(mid 166.361979 -356.649127)
					(end 166.376858 -356.613206)
				)
				(arc
					(start 166.376858 -355.876606)
					(mid 166.361979 -355.840685)
					(end 166.326058 -355.825806)
				)
				(xy 166.083488 -355.825806) (xy 165.726618 -356.058216) (xy 165.372288 -355.825806)
			)
		)
	)
	(zone
		(layer "In1.Cu")
		(hatch none 0.5)
		(connect_pads
			(clearance 0)
		)
		(min_thickness 0.25)
		(keepout
			(tracks not_allowed)
			(vias allowed)
			(pads allowed)
			(copperpour not_allowed)
			(footprints allowed)
		)
		(placement
			(enabled no)
			(sheetname "")
		)
		(fill
			(thermal_gap 0.5)
			(thermal_bridge_width 0.5)
			(island_removal_mode 0)
		)
		(polygon
			(pts
				(arc
					(start 358.329992 -33.574228)
					(mid 358.344871 -33.538307)
					(end 358.380792 -33.523428)
				)
				(arc
					(start 359.612692 -33.523428)
					(mid 359.648613 -33.538307)
					(end 359.663492 -33.574228)
				)
				(arc
					(start 359.663492 -34.605976)
					(mid 359.648613 -34.641897)
					(end 359.612692 -34.656776)
				)
				(arc
					(start 358.380792 -34.656776)
					(mid 358.344871 -34.641897)
					(end 358.329992 -34.605976)
				)
			)
		)
	)
	(zone
		(layer "In1.Cu")
		(hatch none 0.5)
		(connect_pads
			(clearance 0)
		)
		(min_thickness 0.25)
		(keepout
			(tracks not_allowed)
			(vias allowed)
			(pads allowed)
			(copperpour not_allowed)
			(footprints allowed)
		)
		(placement
			(enabled no)
			(sheetname "")
		)
		(fill
			(thermal_gap 0.5)
			(thermal_bridge_width 0.5)
			(island_removal_mode 0)
		)
		(polygon
			(pts
				(arc
					(start 198.34225 -156.251148)
					(mid 198.357129 -156.287069)
					(end 198.39305 -156.301948)
				)
				(arc
					(start 199.12965 -156.301948)
					(mid 199.165571 -156.287069)
					(end 199.18045 -156.251148)
				)
				(xy 199.18045 -156.007308) (xy 198.94804 -155.652978) (xy 199.18045 -155.297378)
				(arc
					(start 199.18045 -155.054808)
					(mid 199.165571 -155.018887)
					(end 199.12965 -155.004008)
				)
				(arc
					(start 198.39305 -155.004008)
					(mid 198.357129 -155.018887)
					(end 198.34225 -155.054808)
				)
				(xy 198.34225 -155.297378) (xy 198.57466 -155.654248) (xy 198.34225 -156.008578)
			)
		)
	)
	(zone
		(layer "In1.Cu")
		(hatch none 0.5)
		(connect_pads
			(clearance 0)
		)
		(min_thickness 0.25)
		(keepout
			(tracks not_allowed)
			(vias allowed)
			(pads allowed)
			(copperpour not_allowed)
			(footprints allowed)
		)
		(placement
			(enabled no)
			(sheetname "")
		)
		(fill
			(thermal_gap 0.5)
			(thermal_bridge_width 0.5)
			(island_removal_mode 0)
		)
		(polygon
			(pts
				(arc
					(start 415.347658 -343.533222)
					(mid 415.311737 -343.548101)
					(end 415.296858 -343.584022)
				)
				(arc
					(start 415.296858 -344.320622)
					(mid 415.311737 -344.356543)
					(end 415.347658 -344.371422)
				)
				(xy 415.591498 -344.371422) (xy 415.945828 -344.139012) (xy 416.301428 -344.371422)
				(arc
					(start 416.543998 -344.371422)
					(mid 416.579919 -344.356543)
					(end 416.594798 -344.320622)
				)
				(arc
					(start 416.594798 -343.584022)
					(mid 416.579919 -343.548101)
					(end 416.543998 -343.533222)
				)
				(xy 416.301428 -343.533222) (xy 415.944558 -343.765632) (xy 415.590228 -343.533222)
			)
		)
	)
	(zone
		(layer "In1.Cu")
		(hatch none 0.5)
		(connect_pads
			(clearance 0)
		)
		(min_thickness 0.25)
		(keepout
			(tracks not_allowed)
			(vias allowed)
			(pads allowed)
			(copperpour not_allowed)
			(footprints allowed)
		)
		(placement
			(enabled no)
			(sheetname "")
		)
		(fill
			(thermal_gap 0.5)
			(thermal_bridge_width 0.5)
			(island_removal_mode 0)
		)
		(polygon
			(pts
				(arc
					(start 248.099834 -32.805878)
					(mid 248.084955 -32.841799)
					(end 248.049034 -32.856678)
				)
				(arc
					(start 246.817134 -32.856678)
					(mid 246.781213 -32.841799)
					(end 246.766334 -32.805878)
				)
				(arc
					(start 246.766334 -31.77413)
					(mid 246.781213 -31.738209)
					(end 246.817134 -31.72333)
				)
				(arc
					(start 248.049034 -31.72333)
					(mid 248.084955 -31.738209)
					(end 248.099834 -31.77413)
				)
			)
		)
	)
	(zone
		(layer "In1.Cu")
		(hatch none 0.5)
		(connect_pads
			(clearance 0)
		)
		(min_thickness 0.25)
		(keepout
			(tracks not_allowed)
			(vias allowed)
			(pads allowed)
			(copperpour not_allowed)
			(footprints allowed)
		)
		(placement
			(enabled no)
			(sheetname "")
		)
		(fill
			(thermal_gap 0.5)
			(thermal_bridge_width 0.5)
			(island_removal_mode 0)
		)
		(polygon
			(pts
				(arc
					(start 283.452062 -103.848408)
					(mid 283.437183 -103.884329)
					(end 283.401262 -103.899208)
				)
				(arc
					(start 282.220162 -103.899208)
					(mid 282.184241 -103.884329)
					(end 282.169362 -103.848408)
				)
				(arc
					(start 282.169362 -102.84206)
					(mid 282.184241 -102.806139)
					(end 282.220162 -102.79126)
				)
				(arc
					(start 283.401262 -102.79126)
					(mid 283.437183 -102.806139)
					(end 283.452062 -102.84206)
				)
			)
		)
	)
	(zone
		(layer "In1.Cu")
		(hatch none 0.5)
		(connect_pads
			(clearance 0)
		)
		(min_thickness 0.25)
		(keepout
			(tracks not_allowed)
			(vias allowed)
			(pads allowed)
			(copperpour not_allowed)
			(footprints allowed)
		)
		(placement
			(enabled no)
			(sheetname "")
		)
		(fill
			(thermal_gap 0.5)
			(thermal_bridge_width 0.5)
			(island_removal_mode 0)
		)
		(polygon
			(pts
				(arc
					(start 311.80024 -147.244562)
					(mid 311.815119 -147.280483)
					(end 311.85104 -147.295362)
				)
				(arc
					(start 312.58764 -147.295362)
					(mid 312.623561 -147.280483)
					(end 312.63844 -147.244562)
				)
				(xy 312.63844 -147.000722) (xy 312.40603 -146.646392) (xy 312.63844 -146.290792)
				(arc
					(start 312.63844 -146.048222)
					(mid 312.623561 -146.012301)
					(end 312.58764 -145.997422)
				)
				(arc
					(start 311.85104 -145.997422)
					(mid 311.815119 -146.012301)
					(end 311.80024 -146.048222)
				)
				(xy 311.80024 -146.290792) (xy 312.03265 -146.647662) (xy 311.80024 -147.001992)
			)
		)
	)
	(zone
		(layer "In1.Cu")
		(hatch none 0.5)
		(connect_pads
			(clearance 0)
		)
		(min_thickness 0.25)
		(keepout
			(tracks not_allowed)
			(vias allowed)
			(pads allowed)
			(copperpour not_allowed)
			(footprints allowed)
		)
		(placement
			(enabled no)
			(sheetname "")
		)
		(fill
			(thermal_gap 0.5)
			(thermal_bridge_width 0.5)
			(island_removal_mode 0)
		)
		(polygon
			(pts
				(arc
					(start 268.419326 -105.749852)
					(mid 268.434205 -105.785773)
					(end 268.470126 -105.800652)
				)
				(arc
					(start 269.206726 -105.800652)
					(mid 269.242647 -105.785773)
					(end 269.257526 -105.749852)
				)
				(xy 269.257526 -105.506012) (xy 269.025116 -105.151682) (xy 269.257526 -104.796082)
				(arc
					(start 269.257526 -104.553512)
					(mid 269.242647 -104.517591)
					(end 269.206726 -104.502712)
				)
				(arc
					(start 268.470126 -104.502712)
					(mid 268.434205 -104.517591)
					(end 268.419326 -104.553512)
				)
				(xy 268.419326 -104.796082) (xy 268.651736 -105.152952) (xy 268.419326 -105.507282)
			)
		)
	)
	(zone
		(layer "In1.Cu")
		(hatch none 0.5)
		(connect_pads
			(clearance 0)
		)
		(min_thickness 0.25)
		(keepout
			(tracks not_allowed)
			(vias allowed)
			(pads allowed)
			(copperpour not_allowed)
			(footprints allowed)
		)
		(placement
			(enabled no)
			(sheetname "")
		)
		(fill
			(thermal_gap 0.5)
			(thermal_bridge_width 0.5)
			(island_removal_mode 0)
		)
		(polygon
			(pts
				(arc
					(start 283.452062 -105.648252)
					(mid 283.437183 -105.684173)
					(end 283.401262 -105.699052)
				)
				(arc
					(start 282.220162 -105.699052)
					(mid 282.184241 -105.684173)
					(end 282.169362 -105.648252)
				)
				(arc
					(start 282.169362 -104.641904)
					(mid 282.184241 -104.605983)
					(end 282.220162 -104.591104)
				)
				(arc
					(start 283.401262 -104.591104)
					(mid 283.437183 -104.605983)
					(end 283.452062 -104.641904)
				)
			)
		)
	)
	(zone
		(layer "In1.Cu")
		(hatch none 0.5)
		(connect_pads
			(clearance 0)
		)
		(min_thickness 0.25)
		(keepout
			(tracks not_allowed)
			(vias allowed)
			(pads allowed)
			(copperpour not_allowed)
			(footprints allowed)
		)
		(placement
			(enabled no)
			(sheetname "")
		)
		(fill
			(thermal_gap 0.5)
			(thermal_bridge_width 0.5)
			(island_removal_mode 0)
		)
		(polygon
			(pts
				(arc
					(start 47.147734 -343.533222)
					(mid 47.111813 -343.548101)
					(end 47.096934 -343.584022)
				)
				(arc
					(start 47.096934 -344.320622)
					(mid 47.111813 -344.356543)
					(end 47.147734 -344.371422)
				)
				(xy 47.391574 -344.371422) (xy 47.745904 -344.139012) (xy 48.101504 -344.371422)
				(arc
					(start 48.344074 -344.371422)
					(mid 48.379995 -344.356543)
					(end 48.394874 -344.320622)
				)
				(arc
					(start 48.394874 -343.584022)
					(mid 48.379995 -343.548101)
					(end 48.344074 -343.533222)
				)
				(xy 48.101504 -343.533222) (xy 47.744634 -343.765632) (xy 47.390304 -343.533222)
			)
		)
	)
	(zone
		(layer "In1.Cu")
		(hatch none 0.5)
		(connect_pads
			(clearance 0)
		)
		(min_thickness 0.25)
		(keepout
			(tracks not_allowed)
			(vias allowed)
			(pads allowed)
			(copperpour not_allowed)
			(footprints allowed)
		)
		(placement
			(enabled no)
			(sheetname "")
		)
		(fill
			(thermal_gap 0.5)
			(thermal_bridge_width 0.5)
			(island_removal_mode 0)
		)
		(polygon
			(pts
				(arc
					(start 68.04787 -124.031756)
					(mid 68.062749 -123.995835)
					(end 68.09867 -123.980956)
				)
				(arc
					(start 69.27977 -123.980956)
					(mid 69.315691 -123.995835)
					(end 69.33057 -124.031756)
				)
				(arc
					(start 69.33057 -125.038104)
					(mid 69.315691 -125.074025)
					(end 69.27977 -125.088904)
				)
				(arc
					(start 68.09867 -125.088904)
					(mid 68.062749 -125.074025)
					(end 68.04787 -125.038104)
				)
			)
		)
	)
	(zone
		(layer "In1.Cu")
		(hatch none 0.5)
		(connect_pads
			(clearance 0)
		)
		(min_thickness 0.25)
		(keepout
			(tracks not_allowed)
			(vias allowed)
			(pads allowed)
			(copperpour not_allowed)
			(footprints allowed)
		)
		(placement
			(enabled no)
			(sheetname "")
		)
		(fill
			(thermal_gap 0.5)
			(thermal_bridge_width 0.5)
			(island_removal_mode 0)
		)
		(polygon
			(pts
				(arc
					(start 320.229738 -28.174188)
					(mid 320.244617 -28.138267)
					(end 320.280538 -28.123388)
				)
				(arc
					(start 321.512438 -28.123388)
					(mid 321.548359 -28.138267)
					(end 321.563238 -28.174188)
				)
				(arc
					(start 321.563238 -29.205936)
					(mid 321.548359 -29.241857)
					(end 321.512438 -29.256736)
				)
				(arc
					(start 320.280538 -29.256736)
					(mid 320.244617 -29.241857)
					(end 320.229738 -29.205936)
				)
			)
		)
	)
	(zone
		(layer "In1.Cu")
		(hatch none 0.5)
		(connect_pads
			(clearance 0)
		)
		(min_thickness 0.25)
		(keepout
			(tracks not_allowed)
			(vias allowed)
			(pads allowed)
			(copperpour not_allowed)
			(footprints allowed)
		)
		(placement
			(enabled no)
			(sheetname "")
		)
		(fill
			(thermal_gap 0.5)
			(thermal_bridge_width 0.5)
			(island_removal_mode 0)
		)
		(polygon
			(pts
				(arc
					(start 271.061434 -125.659896)
					(mid 271.076313 -125.695817)
					(end 271.112234 -125.710696)
				)
				(arc
					(start 271.848834 -125.710696)
					(mid 271.884755 -125.695817)
					(end 271.899634 -125.659896)
				)
				(xy 271.899634 -125.416056) (xy 271.667224 -125.061726) (xy 271.899634 -124.706126)
				(arc
					(start 271.899634 -124.463556)
					(mid 271.884755 -124.427635)
					(end 271.848834 -124.412756)
				)
				(arc
					(start 271.112234 -124.412756)
					(mid 271.076313 -124.427635)
					(end 271.061434 -124.463556)
				)
				(xy 271.061434 -124.706126) (xy 271.293844 -125.062996) (xy 271.061434 -125.417326)
			)
		)
	)
	(zone
		(layer "In1.Cu")
		(hatch none 0.5)
		(connect_pads
			(clearance 0)
		)
		(min_thickness 0.25)
		(keepout
			(tracks not_allowed)
			(vias allowed)
			(pads allowed)
			(copperpour not_allowed)
			(footprints allowed)
		)
		(placement
			(enabled no)
			(sheetname "")
		)
		(fill
			(thermal_gap 0.5)
			(thermal_bridge_width 0.5)
			(island_removal_mode 0)
		)
		(polygon
			(pts
				(arc
					(start 334.10017 -349.679514)
					(mid 334.064249 -349.694393)
					(end 334.04937 -349.730314)
				)
				(arc
					(start 334.04937 -350.466914)
					(mid 334.064249 -350.502835)
					(end 334.10017 -350.517714)
				)
				(xy 334.34401 -350.517714) (xy 334.69834 -350.285304) (xy 335.05394 -350.517714)
				(arc
					(start 335.29651 -350.517714)
					(mid 335.332431 -350.502835)
					(end 335.34731 -350.466914)
				)
				(arc
					(start 335.34731 -349.730314)
					(mid 335.332431 -349.694393)
					(end 335.29651 -349.679514)
				)
				(xy 335.05394 -349.679514) (xy 334.69707 -349.911924) (xy 334.34274 -349.679514)
			)
		)
	)
	(zone
		(layer "In1.Cu")
		(hatch none 0.5)
		(connect_pads
			(clearance 0)
		)
		(min_thickness 0.25)
		(keepout
			(tracks not_allowed)
			(vias allowed)
			(pads allowed)
			(copperpour not_allowed)
			(footprints allowed)
		)
		(placement
			(enabled no)
			(sheetname "")
		)
		(fill
			(thermal_gap 0.5)
			(thermal_bridge_width 0.5)
			(island_removal_mode 0)
		)
		(polygon
			(pts
				(arc
					(start 268.419326 -109.349794)
					(mid 268.434205 -109.385715)
					(end 268.470126 -109.400594)
				)
				(arc
					(start 269.206726 -109.400594)
					(mid 269.242647 -109.385715)
					(end 269.257526 -109.349794)
				)
				(xy 269.257526 -109.105954) (xy 269.025116 -108.751624) (xy 269.257526 -108.396024)
				(arc
					(start 269.257526 -108.153454)
					(mid 269.242647 -108.117533)
					(end 269.206726 -108.102654)
				)
				(arc
					(start 268.470126 -108.102654)
					(mid 268.434205 -108.117533)
					(end 268.419326 -108.153454)
				)
				(xy 268.419326 -108.396024) (xy 268.651736 -108.752894) (xy 268.419326 -109.107224)
			)
		)
	)
	(zone
		(layer "In1.Cu")
		(hatch none 0.5)
		(connect_pads
			(clearance 0)
		)
		(min_thickness 0.25)
		(keepout
			(tracks not_allowed)
			(vias allowed)
			(pads allowed)
			(copperpour not_allowed)
			(footprints allowed)
		)
		(placement
			(enabled no)
			(sheetname "")
		)
		(fill
			(thermal_gap 0.5)
			(thermal_bridge_width 0.5)
			(island_removal_mode 0)
		)
		(polygon
			(pts
				(arc
					(start 214.115396 -34.68624)
					(mid 214.130275 -34.722161)
					(end 214.166196 -34.73704)
				)
				(arc
					(start 214.902796 -34.73704)
					(mid 214.938717 -34.722161)
					(end 214.953596 -34.68624)
				)
				(xy 214.953596 -34.4424) (xy 214.721186 -34.08807) (xy 214.953596 -33.73247)
				(arc
					(start 214.953596 -33.4899)
					(mid 214.938717 -33.453979)
					(end 214.902796 -33.4391)
				)
				(arc
					(start 214.166196 -33.4391)
					(mid 214.130275 -33.453979)
					(end 214.115396 -33.4899)
				)
				(xy 214.115396 -33.73247) (xy 214.347806 -34.08934) (xy 214.115396 -34.44367)
			)
		)
	)
	(zone
		(layer "In1.Cu")
		(hatch none 0.5)
		(connect_pads
			(clearance 0)
		)
		(min_thickness 0.25)
		(keepout
			(tracks not_allowed)
			(vias allowed)
			(pads allowed)
			(copperpour not_allowed)
			(footprints allowed)
		)
		(placement
			(enabled no)
			(sheetname "")
		)
		(fill
			(thermal_gap 0.5)
			(thermal_bridge_width 0.5)
			(island_removal_mode 0)
		)
		(polygon
			(pts
				(arc
					(start 252.215396 -34.68624)
					(mid 252.230275 -34.722161)
					(end 252.266196 -34.73704)
				)
				(arc
					(start 253.002796 -34.73704)
					(mid 253.038717 -34.722161)
					(end 253.053596 -34.68624)
				)
				(xy 253.053596 -34.4424) (xy 252.821186 -34.08807) (xy 253.053596 -33.73247)
				(arc
					(start 253.053596 -33.4899)
					(mid 253.038717 -33.453979)
					(end 253.002796 -33.4391)
				)
				(arc
					(start 252.266196 -33.4391)
					(mid 252.230275 -33.453979)
					(end 252.215396 -33.4899)
				)
				(xy 252.215396 -33.73247) (xy 252.447806 -34.08934) (xy 252.215396 -34.44367)
			)
		)
	)
	(zone
		(layer "In1.Cu")
		(hatch none 0.5)
		(connect_pads
			(clearance 0)
		)
		(min_thickness 0.25)
		(keepout
			(tracks not_allowed)
			(vias allowed)
			(pads allowed)
			(copperpour not_allowed)
			(footprints allowed)
		)
		(placement
			(enabled no)
			(sheetname "")
		)
		(fill
			(thermal_gap 0.5)
			(thermal_bridge_width 0.5)
			(island_removal_mode 0)
		)
		(polygon
			(pts
				(arc
					(start 51.25212 -131.368292)
					(mid 51.237241 -131.404213)
					(end 51.20132 -131.419092)
				)
				(arc
					(start 50.02022 -131.419092)
					(mid 49.984299 -131.404213)
					(end 49.96942 -131.368292)
				)
				(arc
					(start 49.96942 -130.361944)
					(mid 49.984299 -130.326023)
					(end 50.02022 -130.311144)
				)
				(arc
					(start 51.20132 -130.311144)
					(mid 51.237241 -130.326023)
					(end 51.25212 -130.361944)
				)
			)
		)
	)
	(zone
		(layer "In1.Cu")
		(hatch none 0.5)
		(connect_pads
			(clearance 0)
		)
		(min_thickness 0.25)
		(keepout
			(tracks not_allowed)
			(vias allowed)
			(pads allowed)
			(copperpour not_allowed)
			(footprints allowed)
		)
		(placement
			(enabled no)
			(sheetname "")
		)
		(fill
			(thermal_gap 0.5)
			(thermal_bridge_width 0.5)
			(island_removal_mode 0)
		)
		(polygon
			(pts
				(arc
					(start 399.003266 -343.533222)
					(mid 398.967345 -343.548101)
					(end 398.952466 -343.584022)
				)
				(arc
					(start 398.952466 -344.320622)
					(mid 398.967345 -344.356543)
					(end 399.003266 -344.371422)
				)
				(xy 399.247106 -344.371422) (xy 399.601436 -344.139012) (xy 399.957036 -344.371422)
				(arc
					(start 400.199606 -344.371422)
					(mid 400.235527 -344.356543)
					(end 400.250406 -344.320622)
				)
				(arc
					(start 400.250406 -343.584022)
					(mid 400.235527 -343.548101)
					(end 400.199606 -343.533222)
				)
				(xy 399.957036 -343.533222) (xy 399.600166 -343.765632) (xy 399.245836 -343.533222)
			)
		)
	)
	(zone
		(layer "In1.Cu")
		(hatch none 0.5)
		(connect_pads
			(clearance 0)
		)
		(min_thickness 0.25)
		(keepout
			(tracks not_allowed)
			(vias allowed)
			(pads allowed)
			(copperpour not_allowed)
			(footprints allowed)
		)
		(placement
			(enabled no)
			(sheetname "")
		)
		(fill
			(thermal_gap 0.5)
			(thermal_bridge_width 0.5)
			(island_removal_mode 0)
		)
		(polygon
			(pts
				(arc
					(start 51.25212 -120.158256)
					(mid 51.237241 -120.194177)
					(end 51.20132 -120.209056)
				)
				(arc
					(start 50.02022 -120.209056)
					(mid 49.984299 -120.194177)
					(end 49.96942 -120.158256)
				)
				(arc
					(start 49.96942 -119.151908)
					(mid 49.984299 -119.115987)
					(end 50.02022 -119.101108)
				)
				(arc
					(start 51.20132 -119.101108)
					(mid 51.237241 -119.115987)
					(end 51.25212 -119.151908)
				)
			)
		)
	)
	(zone
		(layer "In1.Cu")
		(hatch none 0.5)
		(connect_pads
			(clearance 0)
		)
		(min_thickness 0.25)
		(keepout
			(tracks not_allowed)
			(vias allowed)
			(pads allowed)
			(copperpour not_allowed)
			(footprints allowed)
		)
		(placement
			(enabled no)
			(sheetname "")
		)
		(fill
			(thermal_gap 0.5)
			(thermal_bridge_width 0.5)
			(island_removal_mode 0)
		)
		(polygon
			(pts
				(arc
					(start 306.067206 -117.838474)
					(mid 306.052327 -117.874395)
					(end 306.016406 -117.889274)
				)
				(arc
					(start 304.835306 -117.889274)
					(mid 304.799385 -117.874395)
					(end 304.784506 -117.838474)
				)
				(arc
					(start 304.784506 -116.832126)
					(mid 304.799385 -116.796205)
					(end 304.835306 -116.781326)
				)
				(arc
					(start 306.016406 -116.781326)
					(mid 306.052327 -116.796205)
					(end 306.067206 -116.832126)
				)
			)
		)
	)
	(zone
		(layer "In1.Cu")
		(hatch none 0.5)
		(connect_pads
			(clearance 0)
		)
		(min_thickness 0.25)
		(keepout
			(tracks not_allowed)
			(vias allowed)
			(pads allowed)
			(copperpour not_allowed)
			(footprints allowed)
		)
		(placement
			(enabled no)
			(sheetname "")
		)
		(fill
			(thermal_gap 0.5)
			(thermal_bridge_width 0.5)
			(island_removal_mode 0)
		)
		(polygon
			(pts
				(arc
					(start 73.642728 -355.825806)
					(mid 73.606807 -355.840685)
					(end 73.591928 -355.876606)
				)
				(arc
					(start 73.591928 -356.613206)
					(mid 73.606807 -356.649127)
					(end 73.642728 -356.664006)
				)
				(xy 73.886568 -356.664006) (xy 74.240898 -356.431596) (xy 74.596498 -356.664006)
				(arc
					(start 74.839068 -356.664006)
					(mid 74.874989 -356.649127)
					(end 74.889868 -356.613206)
				)
				(arc
					(start 74.889868 -355.876606)
					(mid 74.874989 -355.840685)
					(end 74.839068 -355.825806)
				)
				(xy 74.596498 -355.825806) (xy 74.239628 -356.058216) (xy 73.885298 -355.825806)
			)
		)
	)
	(zone
		(layer "In1.Cu")
		(hatch none 0.5)
		(connect_pads
			(clearance 0)
		)
		(min_thickness 0.25)
		(keepout
			(tracks not_allowed)
			(vias allowed)
			(pads allowed)
			(copperpour not_allowed)
			(footprints allowed)
		)
		(placement
			(enabled no)
			(sheetname "")
		)
		(fill
			(thermal_gap 0.5)
			(thermal_bridge_width 0.5)
			(island_removal_mode 0)
		)
		(polygon
			(pts
				(arc
					(start 376.796808 18.577052)
					(mid 376.819126 18.630934)
					(end 376.873008 18.653252)
				)
				(arc
					(start 377.485148 18.653252)
					(mid 377.53903 18.630934)
					(end 377.561348 18.577052)
				)
				(arc
					(start 377.561348 17.479772)
					(mid 377.53903 17.42589)
					(end 377.485148 17.403572)
				)
				(arc
					(start 376.873008 17.403572)
					(mid 376.819126 17.42589)
					(end 376.796808 17.479772)
				)
			)
		)
	)
	(zone
		(layer "In1.Cu")
		(hatch none 0.5)
		(connect_pads
			(clearance 0)
		)
		(min_thickness 0.25)
		(keepout
			(tracks not_allowed)
			(vias allowed)
			(pads allowed)
			(copperpour not_allowed)
			(footprints allowed)
		)
		(placement
			(enabled no)
			(sheetname "")
		)
		(fill
			(thermal_gap 0.5)
			(thermal_bridge_width 0.5)
			(island_removal_mode 0)
		)
		(polygon
			(pts
				(arc
					(start 79.600298 -134.534656)
					(mid 79.615177 -134.570577)
					(end 79.651098 -134.585456)
				)
				(arc
					(start 80.387698 -134.585456)
					(mid 80.423619 -134.570577)
					(end 80.438498 -134.534656)
				)
				(xy 80.438498 -134.290816) (xy 80.206088 -133.936486) (xy 80.438498 -133.580886)
				(arc
					(start 80.438498 -133.338316)
					(mid 80.423619 -133.302395)
					(end 80.387698 -133.287516)
				)
				(arc
					(start 79.651098 -133.287516)
					(mid 79.615177 -133.302395)
					(end 79.600298 -133.338316)
				)
				(xy 79.600298 -133.580886) (xy 79.832708 -133.937756) (xy 79.600298 -134.292086)
			)
		)
	)
	(zone
		(layer "In1.Cu")
		(hatch none 0.5)
		(connect_pads
			(clearance 0)
		)
		(min_thickness 0.25)
		(keepout
			(tracks not_allowed)
			(vias allowed)
			(pads allowed)
			(copperpour not_allowed)
			(footprints allowed)
		)
		(placement
			(enabled no)
			(sheetname "")
		)
		(fill
			(thermal_gap 0.5)
			(thermal_bridge_width 0.5)
			(island_removal_mode 0)
		)
		(polygon
			(pts
				(arc
					(start 157.999938 -34.605976)
					(mid 157.985059 -34.641897)
					(end 157.949138 -34.656776)
				)
				(arc
					(start 156.717238 -34.656776)
					(mid 156.681317 -34.641897)
					(end 156.666438 -34.605976)
				)
				(arc
					(start 156.666438 -33.574228)
					(mid 156.681317 -33.538307)
					(end 156.717238 -33.523428)
				)
				(arc
					(start 157.949138 -33.523428)
					(mid 157.985059 -33.538307)
					(end 157.999938 -33.574228)
				)
			)
		)
	)
	(zone
		(layer "In1.Cu")
		(hatch none 0.5)
		(connect_pads
			(clearance 0)
		)
		(min_thickness 0.25)
		(keepout
			(tracks not_allowed)
			(vias allowed)
			(pads allowed)
			(copperpour not_allowed)
			(footprints allowed)
		)
		(placement
			(enabled no)
			(sheetname "")
		)
		(fill
			(thermal_gap 0.5)
			(thermal_bridge_width 0.5)
			(island_removal_mode 0)
		)
		(polygon
			(pts
				(arc
					(start 82.242406 -156.251148)
					(mid 82.257285 -156.287069)
					(end 82.293206 -156.301948)
				)
				(arc
					(start 83.029806 -156.301948)
					(mid 83.065727 -156.287069)
					(end 83.080606 -156.251148)
				)
				(xy 83.080606 -156.007308) (xy 82.848196 -155.652978) (xy 83.080606 -155.297378)
				(arc
					(start 83.080606 -155.054808)
					(mid 83.065727 -155.018887)
					(end 83.029806 -155.004008)
				)
				(arc
					(start 82.293206 -155.004008)
					(mid 82.257285 -155.018887)
					(end 82.242406 -155.054808)
				)
				(xy 82.242406 -155.297378) (xy 82.474816 -155.654248) (xy 82.242406 -156.008578)
			)
		)
	)
	(zone
		(layer "In1.Cu")
		(hatch none 0.5)
		(connect_pads
			(clearance 0)
		)
		(min_thickness 0.25)
		(keepout
			(tracks not_allowed)
			(vias allowed)
			(pads allowed)
			(copperpour not_allowed)
			(footprints allowed)
		)
		(placement
			(enabled no)
			(sheetname "")
		)
		(fill
			(thermal_gap 0.5)
			(thermal_bridge_width 0.5)
			(island_removal_mode 0)
		)
		(polygon
			(pts
				(arc
					(start 277.632668 -119.151908)
					(mid 277.647547 -119.115987)
					(end 277.683468 -119.101108)
				)
				(arc
					(start 278.864568 -119.101108)
					(mid 278.900489 -119.115987)
					(end 278.915368 -119.151908)
				)
				(arc
					(start 278.915368 -120.158256)
					(mid 278.900489 -120.194177)
					(end 278.864568 -120.209056)
				)
				(arc
					(start 277.683468 -120.209056)
					(mid 277.647547 -120.194177)
					(end 277.632668 -120.158256)
				)
			)
		)
	)
	(zone
		(layer "In1.Cu")
		(hatch none 0.5)
		(connect_pads
			(clearance 0)
		)
		(min_thickness 0.25)
		(keepout
			(tracks not_allowed)
			(vias allowed)
			(pads allowed)
			(copperpour not_allowed)
			(footprints allowed)
		)
		(placement
			(enabled no)
			(sheetname "")
		)
		(fill
			(thermal_gap 0.5)
			(thermal_bridge_width 0.5)
			(island_removal_mode 0)
		)
		(polygon
			(pts
				(arc
					(start 242.229894 -31.77413)
					(mid 242.244773 -31.738209)
					(end 242.280694 -31.72333)
				)
				(arc
					(start 243.512594 -31.72333)
					(mid 243.548515 -31.738209)
					(end 243.563394 -31.77413)
				)
				(arc
					(start 243.563394 -32.805878)
					(mid 243.548515 -32.841799)
					(end 243.512594 -32.856678)
				)
				(arc
					(start 242.280694 -32.856678)
					(mid 242.244773 -32.841799)
					(end 242.229894 -32.805878)
				)
			)
		)
	)
	(zone
		(layer "In1.Cu")
		(hatch none 0.5)
		(connect_pads
			(clearance 0)
		)
		(min_thickness 0.25)
		(keepout
			(tracks not_allowed)
			(vias allowed)
			(pads allowed)
			(copperpour not_allowed)
			(footprints allowed)
		)
		(placement
			(enabled no)
			(sheetname "")
		)
		(fill
			(thermal_gap 0.5)
			(thermal_bridge_width 0.5)
			(island_removal_mode 0)
		)
		(polygon
			(pts
				(arc
					(start 101.74732 -389.424418)
					(mid 101.762199 -389.388497)
					(end 101.79812 -389.373618)
				)
				(arc
					(start 102.455218 -389.373618)
					(mid 102.491139 -389.388497)
					(end 102.506018 -389.424418)
				)
				(arc
					(start 102.506018 -390.064752)
					(mid 102.491139 -390.100673)
					(end 102.455218 -390.115552)
				)
				(arc
					(start 101.79812 -390.115552)
					(mid 101.762199 -390.100673)
					(end 101.74732 -390.064752)
				)
			)
		)
	)
	(zone
		(layer "In1.Cu")
		(hatch none 0.5)
		(connect_pads
			(clearance 0)
		)
		(min_thickness 0.25)
		(keepout
			(tracks not_allowed)
			(vias allowed)
			(pads allowed)
			(copperpour not_allowed)
			(footprints allowed)
		)
		(placement
			(enabled no)
			(sheetname "")
		)
		(fill
			(thermal_gap 0.5)
			(thermal_bridge_width 0.5)
			(island_removal_mode 0)
		)
		(polygon
			(pts
				(arc
					(start 304.215292 -31.086044)
					(mid 304.230171 -31.121965)
					(end 304.266092 -31.136844)
				)
				(arc
					(start 305.002692 -31.136844)
					(mid 305.038613 -31.121965)
					(end 305.053492 -31.086044)
				)
				(xy 305.053492 -30.842204) (xy 304.821082 -30.487874) (xy 305.053492 -30.132274)
				(arc
					(start 305.053492 -29.889704)
					(mid 305.038613 -29.853783)
					(end 305.002692 -29.838904)
				)
				(arc
					(start 304.266092 -29.838904)
					(mid 304.230171 -29.853783)
					(end 304.215292 -29.889704)
				)
				(xy 304.215292 -30.132274) (xy 304.447702 -30.489144) (xy 304.215292 -30.843474)
			)
		)
	)
	(zone
		(layer "In1.Cu")
		(hatch none 0.5)
		(connect_pads
			(clearance 0)
		)
		(min_thickness 0.25)
		(keepout
			(tracks not_allowed)
			(vias allowed)
			(pads allowed)
			(copperpour not_allowed)
			(footprints allowed)
		)
		(placement
			(enabled no)
			(sheetname "")
		)
		(fill
			(thermal_gap 0.5)
			(thermal_bridge_width 0.5)
			(island_removal_mode 0)
		)
		(polygon
			(pts
				(arc
					(start 314.442348 -121.531126)
					(mid 314.457227 -121.567047)
					(end 314.493148 -121.581926)
				)
				(arc
					(start 315.229748 -121.581926)
					(mid 315.265669 -121.567047)
					(end 315.280548 -121.531126)
				)
				(xy 315.280548 -121.287286) (xy 315.048138 -120.932956) (xy 315.280548 -120.577356)
				(arc
					(start 315.280548 -120.334786)
					(mid 315.265669 -120.298865)
					(end 315.229748 -120.283986)
				)
				(arc
					(start 314.493148 -120.283986)
					(mid 314.457227 -120.298865)
					(end 314.442348 -120.334786)
				)
				(xy 314.442348 -120.577356) (xy 314.674758 -120.934226) (xy 314.442348 -121.288556)
			)
		)
	)
	(zone
		(layer "In1.Cu")
		(hatch none 0.5)
		(connect_pads
			(clearance 0)
		)
		(min_thickness 0.25)
		(keepout
			(tracks not_allowed)
			(vias allowed)
			(pads allowed)
			(copperpour not_allowed)
			(footprints allowed)
		)
		(placement
			(enabled no)
			(sheetname "")
		)
		(fill
			(thermal_gap 0.5)
			(thermal_bridge_width 0.5)
			(island_removal_mode 0)
		)
		(polygon
			(pts
				(arc
					(start 195.700142 -147.244562)
					(mid 195.715021 -147.280483)
					(end 195.750942 -147.295362)
				)
				(arc
					(start 196.487542 -147.295362)
					(mid 196.523463 -147.280483)
					(end 196.538342 -147.244562)
				)
				(xy 196.538342 -147.000722) (xy 196.305932 -146.646392) (xy 196.538342 -146.290792)
				(arc
					(start 196.538342 -146.048222)
					(mid 196.523463 -146.012301)
					(end 196.487542 -145.997422)
				)
				(arc
					(start 195.750942 -145.997422)
					(mid 195.715021 -146.012301)
					(end 195.700142 -146.048222)
				)
				(xy 195.700142 -146.290792) (xy 195.932552 -146.647662) (xy 195.700142 -147.001992)
			)
		)
	)
	(zone
		(layer "In1.Cu")
		(hatch none 0.5)
		(connect_pads
			(clearance 0)
		)
		(min_thickness 0.25)
		(keepout
			(tracks not_allowed)
			(vias allowed)
			(pads allowed)
			(copperpour not_allowed)
			(footprints allowed)
		)
		(placement
			(enabled no)
			(sheetname "")
		)
		(fill
			(thermal_gap 0.5)
			(thermal_bridge_width 0.5)
			(island_removal_mode 0)
		)
		(polygon
			(pts
				(arc
					(start 188.115448 -31.086044)
					(mid 188.130327 -31.121965)
					(end 188.166248 -31.136844)
				)
				(arc
					(start 188.902848 -31.136844)
					(mid 188.938769 -31.121965)
					(end 188.953648 -31.086044)
				)
				(xy 188.953648 -30.842204) (xy 188.721238 -30.487874) (xy 188.953648 -30.132274)
				(arc
					(start 188.953648 -29.889704)
					(mid 188.938769 -29.853783)
					(end 188.902848 -29.838904)
				)
				(arc
					(start 188.166248 -29.838904)
					(mid 188.130327 -29.853783)
					(end 188.115448 -29.889704)
				)
				(xy 188.115448 -30.132274) (xy 188.347858 -30.489144) (xy 188.115448 -30.843474)
			)
		)
	)
	(zone
		(layer "In1.Cu")
		(hatch none 0.5)
		(connect_pads
			(clearance 0)
		)
		(min_thickness 0.25)
		(keepout
			(tracks not_allowed)
			(vias allowed)
			(pads allowed)
			(copperpour not_allowed)
			(footprints allowed)
		)
		(placement
			(enabled no)
			(sheetname "")
		)
		(fill
			(thermal_gap 0.5)
			(thermal_bridge_width 0.5)
			(island_removal_mode 0)
		)
		(polygon
			(pts
				(arc
					(start 393.732766 -110.041944)
					(mid 393.747645 -110.006023)
					(end 393.783566 -109.991144)
				)
				(arc
					(start 394.964666 -109.991144)
					(mid 395.000587 -110.006023)
					(end 395.015466 -110.041944)
				)
				(arc
					(start 395.015466 -111.048292)
					(mid 395.000587 -111.084213)
					(end 394.964666 -111.099092)
				)
				(arc
					(start 393.783566 -111.099092)
					(mid 393.747645 -111.084213)
					(end 393.732766 -111.048292)
				)
			)
		)
	)
	(zone
		(layer "In1.Cu")
		(hatch none 0.5)
		(connect_pads
			(clearance 0)
		)
		(min_thickness 0.25)
		(keepout
			(tracks not_allowed)
			(vias allowed)
			(pads allowed)
			(copperpour not_allowed)
			(footprints allowed)
		)
		(placement
			(enabled no)
			(sheetname "")
		)
		(fill
			(thermal_gap 0.5)
			(thermal_bridge_width 0.5)
			(island_removal_mode 0)
		)
		(polygon
			(pts
				(arc
					(start 313.006232 8.658352)
					(mid 313.02855 8.712234)
					(end 313.082432 8.734552)
				)
				(arc
					(start 313.694572 8.734552)
					(mid 313.748454 8.712234)
					(end 313.770772 8.658352)
				)
				(arc
					(start 313.770772 7.561072)
					(mid 313.748454 7.50719)
					(end 313.694572 7.484872)
				)
				(arc
					(start 313.082432 7.484872)
					(mid 313.02855 7.50719)
					(end 313.006232 7.561072)
				)
			)
		)
	)
	(zone
		(layer "In1.Cu")
		(hatch none 0.5)
		(connect_pads
			(clearance 0)
		)
		(min_thickness 0.25)
		(keepout
			(tracks not_allowed)
			(vias allowed)
			(pads allowed)
			(copperpour not_allowed)
			(footprints allowed)
		)
		(placement
			(enabled no)
			(sheetname "")
		)
		(fill
			(thermal_gap 0.5)
			(thermal_bridge_width 0.5)
			(island_removal_mode 0)
		)
		(polygon
			(pts
				(arc
					(start 424.674538 -349.679514)
					(mid 424.638617 -349.694393)
					(end 424.623738 -349.730314)
				)
				(arc
					(start 424.623738 -350.466914)
					(mid 424.638617 -350.502835)
					(end 424.674538 -350.517714)
				)
				(xy 424.918378 -350.517714) (xy 425.272708 -350.285304) (xy 425.628308 -350.517714)
				(arc
					(start 425.870878 -350.517714)
					(mid 425.906799 -350.502835)
					(end 425.921678 -350.466914)
				)
				(arc
					(start 425.921678 -349.730314)
					(mid 425.906799 -349.694393)
					(end 425.870878 -349.679514)
				)
				(xy 425.628308 -349.679514) (xy 425.271438 -349.911924) (xy 424.917108 -349.679514)
			)
		)
	)
	(zone
		(layer "In1.Cu")
		(hatch none 0.5)
		(connect_pads
			(clearance 0)
		)
		(min_thickness 0.25)
		(keepout
			(tracks not_allowed)
			(vias allowed)
			(pads allowed)
			(copperpour not_allowed)
			(footprints allowed)
		)
		(placement
			(enabled no)
			(sheetname "")
		)
		(fill
			(thermal_gap 0.5)
			(thermal_bridge_width 0.5)
			(island_removal_mode 0)
		)
		(polygon
			(pts
				(arc
					(start 68.04787 -146.151854)
					(mid 68.062749 -146.115933)
					(end 68.09867 -146.101054)
				)
				(arc
					(start 69.27977 -146.101054)
					(mid 69.315691 -146.115933)
					(end 69.33057 -146.151854)
				)
				(arc
					(start 69.33057 -147.158202)
					(mid 69.315691 -147.194123)
					(end 69.27977 -147.209002)
				)
				(arc
					(start 68.09867 -147.209002)
					(mid 68.062749 -147.194123)
					(end 68.04787 -147.158202)
				)
			)
		)
	)
	(zone
		(layer "In1.Cu")
		(hatch none 0.5)
		(connect_pads
			(clearance 0)
		)
		(min_thickness 0.25)
		(keepout
			(tracks not_allowed)
			(vias allowed)
			(pads allowed)
			(copperpour not_allowed)
			(footprints allowed)
		)
		(placement
			(enabled no)
			(sheetname "")
		)
		(fill
			(thermal_gap 0.5)
			(thermal_bridge_width 0.5)
			(island_removal_mode 0)
		)
		(polygon
			(pts
				(arc
					(start 430.892458 -349.679514)
					(mid 430.856537 -349.694393)
					(end 430.841658 -349.730314)
				)
				(arc
					(start 430.841658 -350.466914)
					(mid 430.856537 -350.502835)
					(end 430.892458 -350.517714)
				)
				(xy 431.136298 -350.517714) (xy 431.490628 -350.285304) (xy 431.846228 -350.517714)
				(arc
					(start 432.088798 -350.517714)
					(mid 432.124719 -350.502835)
					(end 432.139598 -350.466914)
				)
				(arc
					(start 432.139598 -349.730314)
					(mid 432.124719 -349.694393)
					(end 432.088798 -349.679514)
				)
				(xy 431.846228 -349.679514) (xy 431.489358 -349.911924) (xy 431.135028 -349.679514)
			)
		)
	)
	(zone
		(layer "In1.Cu")
		(hatch none 0.5)
		(connect_pads
			(clearance 0)
		)
		(min_thickness 0.25)
		(keepout
			(tracks not_allowed)
			(vias allowed)
			(pads allowed)
			(copperpour not_allowed)
			(footprints allowed)
		)
		(placement
			(enabled no)
			(sheetname "")
		)
		(fill
			(thermal_gap 0.5)
			(thermal_bridge_width 0.5)
			(island_removal_mode 0)
		)
		(polygon
			(pts
				(arc
					(start 38.861492 -136.869678)
					(mid 38.876371 -136.905599)
					(end 38.912292 -136.920478)
				)
				(arc
					(start 39.648892 -136.920478)
					(mid 39.684813 -136.905599)
					(end 39.699692 -136.869678)
				)
				(xy 39.699692 -136.625838) (xy 39.467282 -136.271508) (xy 39.699692 -135.915908)
				(arc
					(start 39.699692 -135.673338)
					(mid 39.684813 -135.637417)
					(end 39.648892 -135.622538)
				)
				(arc
					(start 38.912292 -135.622538)
					(mid 38.876371 -135.637417)
					(end 38.861492 -135.673338)
				)
				(xy 38.861492 -135.915908) (xy 39.093902 -136.272778) (xy 38.861492 -136.627108)
			)
		)
	)
	(zone
		(layer "In1.Cu")
		(hatch none 0.5)
		(connect_pads
			(clearance 0)
		)
		(min_thickness 0.25)
		(keepout
			(tracks not_allowed)
			(vias allowed)
			(pads allowed)
			(copperpour not_allowed)
			(footprints allowed)
		)
		(placement
			(enabled no)
			(sheetname "")
		)
		(fill
			(thermal_gap 0.5)
			(thermal_bridge_width 0.5)
			(island_removal_mode 0)
		)
		(polygon
			(pts
				(arc
					(start 47.147734 -349.679514)
					(mid 47.111813 -349.694393)
					(end 47.096934 -349.730314)
				)
				(arc
					(start 47.096934 -350.466914)
					(mid 47.111813 -350.502835)
					(end 47.147734 -350.517714)
				)
				(xy 47.391574 -350.517714) (xy 47.745904 -350.285304) (xy 48.101504 -350.517714)
				(arc
					(start 48.344074 -350.517714)
					(mid 48.379995 -350.502835)
					(end 48.394874 -350.466914)
				)
				(arc
					(start 48.394874 -349.730314)
					(mid 48.379995 -349.694393)
					(end 48.344074 -349.679514)
				)
				(xy 48.101504 -349.679514) (xy 47.744634 -349.911924) (xy 47.390304 -349.679514)
			)
		)
	)
	(zone
		(layer "In1.Cu")
		(hatch none 0.5)
		(connect_pads
			(clearance 0)
		)
		(min_thickness 0.25)
		(keepout
			(tracks not_allowed)
			(vias allowed)
			(pads allowed)
			(copperpour not_allowed)
			(footprints allowed)
		)
		(placement
			(enabled no)
			(sheetname "")
		)
		(fill
			(thermal_gap 0.5)
			(thermal_bridge_width 0.5)
			(island_removal_mode 0)
		)
		(polygon
			(pts
				(arc
					(start 131.99999 -32.805878)
					(mid 131.985111 -32.841799)
					(end 131.94919 -32.856678)
				)
				(arc
					(start 130.71729 -32.856678)
					(mid 130.681369 -32.841799)
					(end 130.66649 -32.805878)
				)
				(arc
					(start 130.66649 -31.77413)
					(mid 130.681369 -31.738209)
					(end 130.71729 -31.72333)
				)
				(arc
					(start 131.94919 -31.72333)
					(mid 131.985111 -31.738209)
					(end 131.99999 -31.77413)
				)
			)
		)
	)
	(zone
		(layer "In1.Cu")
		(hatch none 0.5)
		(connect_pads
			(clearance 0)
		)
		(min_thickness 0.25)
		(keepout
			(tracks not_allowed)
			(vias allowed)
			(pads allowed)
			(copperpour not_allowed)
			(footprints allowed)
		)
		(placement
			(enabled no)
			(sheetname "")
		)
		(fill
			(thermal_gap 0.5)
			(thermal_bridge_width 0.5)
			(island_removal_mode 0)
		)
		(polygon
			(pts
				(arc
					(start 384.32994 -29.974286)
					(mid 384.344819 -29.938365)
					(end 384.38074 -29.923486)
				)
				(arc
					(start 385.61264 -29.923486)
					(mid 385.648561 -29.938365)
					(end 385.66344 -29.974286)
				)
				(arc
					(start 385.66344 -31.006034)
					(mid 385.648561 -31.041955)
					(end 385.61264 -31.056834)
				)
				(arc
					(start 384.38074 -31.056834)
					(mid 384.344819 -31.041955)
					(end 384.32994 -31.006034)
				)
			)
		)
	)
	(zone
		(layer "In1.Cu")
		(hatch none 0.5)
		(connect_pads
			(clearance 0)
		)
		(min_thickness 0.25)
		(keepout
			(tracks not_allowed)
			(vias allowed)
			(pads allowed)
			(copperpour not_allowed)
			(footprints allowed)
		)
		(placement
			(enabled no)
			(sheetname "")
		)
		(fill
			(thermal_gap 0.5)
			(thermal_bridge_width 0.5)
			(island_removal_mode 0)
		)
		(polygon
			(pts
				(arc
					(start 76.751688 -349.679514)
					(mid 76.715767 -349.694393)
					(end 76.700888 -349.730314)
				)
				(arc
					(start 76.700888 -350.466914)
					(mid 76.715767 -350.502835)
					(end 76.751688 -350.517714)
				)
				(xy 76.995528 -350.517714) (xy 77.349858 -350.285304) (xy 77.705458 -350.517714)
				(arc
					(start 77.948028 -350.517714)
					(mid 77.983949 -350.502835)
					(end 77.998828 -350.466914)
				)
				(arc
					(start 77.998828 -349.730314)
					(mid 77.983949 -349.694393)
					(end 77.948028 -349.679514)
				)
				(xy 77.705458 -349.679514) (xy 77.348588 -349.911924) (xy 76.994258 -349.679514)
			)
		)
	)
	(zone
		(layer "In1.Cu")
		(hatch none 0.5)
		(connect_pads
			(clearance 0)
		)
		(min_thickness 0.25)
		(keepout
			(tracks not_allowed)
			(vias allowed)
			(pads allowed)
			(copperpour not_allowed)
			(footprints allowed)
		)
		(placement
			(enabled no)
			(sheetname "")
		)
		(fill
			(thermal_gap 0.5)
			(thermal_bridge_width 0.5)
			(island_removal_mode 0)
		)
		(polygon
			(pts
				(arc
					(start 114.805714 -349.679514)
					(mid 114.769793 -349.694393)
					(end 114.754914 -349.730314)
				)
				(arc
					(start 114.754914 -350.466914)
					(mid 114.769793 -350.502835)
					(end 114.805714 -350.517714)
				)
				(xy 115.049554 -350.517714) (xy 115.403884 -350.285304) (xy 115.759484 -350.517714)
				(arc
					(start 116.002054 -350.517714)
					(mid 116.037975 -350.502835)
					(end 116.052854 -350.466914)
				)
				(arc
					(start 116.052854 -349.730314)
					(mid 116.037975 -349.694393)
					(end 116.002054 -349.679514)
				)
				(xy 115.759484 -349.679514) (xy 115.402614 -349.911924) (xy 115.048284 -349.679514)
			)
		)
	)
	(zone
		(layer "In1.Cu")
		(hatch none 0.5)
		(connect_pads
			(clearance 0)
		)
		(min_thickness 0.25)
		(keepout
			(tracks not_allowed)
			(vias allowed)
			(pads allowed)
			(copperpour not_allowed)
			(footprints allowed)
		)
		(placement
			(enabled no)
			(sheetname "")
		)
		(fill
			(thermal_gap 0.5)
			(thermal_bridge_width 0.5)
			(island_removal_mode 0)
		)
		(polygon
			(pts
				(arc
					(start 104.644698 -380.296674)
					(mid 104.734501 -380.333871)
					(end 104.771698 -380.423674)
				)
				(arc
					(start 104.771698 -380.624842)
					(mid 104.734501 -380.714645)
					(end 104.644698 -380.751842)
				)
				(arc
					(start 104.390698 -380.751842)
					(mid 104.300895 -380.714645)
					(end 104.263698 -380.624842)
				)
				(arc
					(start 104.263698 -380.423674)
					(mid 104.300895 -380.333871)
					(end 104.390698 -380.296674)
				)
			)
		)
	)
	(zone
		(layer "In1.Cu")
		(hatch none 0.5)
		(connect_pads
			(clearance 0)
		)
		(min_thickness 0.25)
		(keepout
			(tracks not_allowed)
			(vias allowed)
			(pads allowed)
			(copperpour not_allowed)
			(footprints allowed)
		)
		(placement
			(enabled no)
			(sheetname "")
		)
		(fill
			(thermal_gap 0.5)
			(thermal_bridge_width 0.5)
			(island_removal_mode 0)
		)
		(polygon
			(pts
				(arc
					(start 314.442348 -145.451068)
					(mid 314.457227 -145.486989)
					(end 314.493148 -145.501868)
				)
				(arc
					(start 315.229748 -145.501868)
					(mid 315.265669 -145.486989)
					(end 315.280548 -145.451068)
				)
				(xy 315.280548 -145.207228) (xy 315.048138 -144.852898) (xy 315.280548 -144.497298)
				(arc
					(start 315.280548 -144.254728)
					(mid 315.265669 -144.218807)
					(end 315.229748 -144.203928)
				)
				(arc
					(start 314.493148 -144.203928)
					(mid 314.457227 -144.218807)
					(end 314.442348 -144.254728)
				)
				(xy 314.442348 -144.497298) (xy 314.674758 -144.854168) (xy 314.442348 -145.208498)
			)
		)
	)
	(zone
		(layer "In1.Cu")
		(hatch none 0.5)
		(connect_pads
			(clearance 0)
		)
		(min_thickness 0.25)
		(keepout
			(tracks not_allowed)
			(vias allowed)
			(pads allowed)
			(copperpour not_allowed)
			(footprints allowed)
		)
		(placement
			(enabled no)
			(sheetname "")
		)
		(fill
			(thermal_gap 0.5)
			(thermal_bridge_width 0.5)
			(island_removal_mode 0)
		)
		(polygon
			(pts
				(arc
					(start 283.452062 -109.248194)
					(mid 283.437183 -109.284115)
					(end 283.401262 -109.298994)
				)
				(arc
					(start 282.220162 -109.298994)
					(mid 282.184241 -109.284115)
					(end 282.169362 -109.248194)
				)
				(arc
					(start 282.169362 -108.241846)
					(mid 282.184241 -108.205925)
					(end 282.220162 -108.191046)
				)
				(arc
					(start 283.401262 -108.191046)
					(mid 283.437183 -108.205925)
					(end 283.452062 -108.241846)
				)
			)
		)
	)
	(zone
		(layer "In1.Cu")
		(hatch none 0.5)
		(connect_pads
			(clearance 0)
		)
		(min_thickness 0.25)
		(keepout
			(tracks not_allowed)
			(vias allowed)
			(pads allowed)
			(copperpour not_allowed)
			(footprints allowed)
		)
		(placement
			(enabled no)
			(sheetname "")
		)
		(fill
			(thermal_gap 0.5)
			(thermal_bridge_width 0.5)
			(island_removal_mode 0)
		)
		(polygon
			(pts
				(arc
					(start 383.712974 -232.200958)
					(mid 383.727853 -232.165037)
					(end 383.763774 -232.150158)
				)
				(arc
					(start 384.44424 -232.150158)
					(mid 384.480161 -232.165037)
					(end 384.49504 -232.200958)
				)
				(arc
					(start 384.49504 -233.48188)
					(mid 384.480161 -233.517801)
					(end 384.44424 -233.53268)
				)
				(arc
					(start 383.763774 -233.53268)
					(mid 383.727853 -233.517801)
					(end 383.712974 -233.48188)
				)
			)
		)
	)
	(zone
		(layer "In1.Cu")
		(hatch none 0.5)
		(connect_pads
			(clearance 0)
		)
		(min_thickness 0.25)
		(keepout
			(tracks not_allowed)
			(vias allowed)
			(pads allowed)
			(copperpour not_allowed)
			(footprints allowed)
		)
		(placement
			(enabled no)
			(sheetname "")
		)
		(fill
			(thermal_gap 0.5)
			(thermal_bridge_width 0.5)
			(island_removal_mode 0)
		)
		(polygon
			(pts
				(arc
					(start 68.04787 -129.841752)
					(mid 68.062749 -129.805831)
					(end 68.09867 -129.790952)
				)
				(arc
					(start 69.27977 -129.790952)
					(mid 69.315691 -129.805831)
					(end 69.33057 -129.841752)
				)
				(arc
					(start 69.33057 -130.8481)
					(mid 69.315691 -130.884021)
					(end 69.27977 -130.8989)
				)
				(arc
					(start 68.09867 -130.8989)
					(mid 68.062749 -130.884021)
					(end 68.04787 -130.8481)
				)
			)
		)
	)
	(zone
		(layer "In1.Cu")
		(hatch none 0.5)
		(connect_pads
			(clearance 0)
		)
		(min_thickness 0.25)
		(keepout
			(tracks not_allowed)
			(vias allowed)
			(pads allowed)
			(copperpour not_allowed)
			(footprints allowed)
		)
		(placement
			(enabled no)
			(sheetname "")
		)
		(fill
			(thermal_gap 0.5)
			(thermal_bridge_width 0.5)
			(island_removal_mode 0)
		)
		(polygon
			(pts
				(arc
					(start 184.147714 -142.551912)
					(mid 184.162593 -142.515991)
					(end 184.198514 -142.501112)
				)
				(arc
					(start 185.379614 -142.501112)
					(mid 185.415535 -142.515991)
					(end 185.430414 -142.551912)
				)
				(arc
					(start 185.430414 -143.55826)
					(mid 185.415535 -143.594181)
					(end 185.379614 -143.60906)
				)
				(arc
					(start 184.198514 -143.60906)
					(mid 184.162593 -143.594181)
					(end 184.147714 -143.55826)
				)
			)
		)
	)
	(zone
		(layer "In1.Cu")
		(hatch none 0.5)
		(connect_pads
			(clearance 0)
		)
		(min_thickness 0.25)
		(keepout
			(tracks not_allowed)
			(vias allowed)
			(pads allowed)
			(copperpour not_allowed)
			(footprints allowed)
		)
		(placement
			(enabled no)
			(sheetname "")
		)
		(fill
			(thermal_gap 0.5)
			(thermal_bridge_width 0.5)
			(island_removal_mode 0)
		)
		(polygon
			(pts
				(arc
					(start 422.167304 -150.758144)
					(mid 422.152425 -150.794065)
					(end 422.116504 -150.808944)
				)
				(arc
					(start 420.935404 -150.808944)
					(mid 420.899483 -150.794065)
					(end 420.884604 -150.758144)
				)
				(arc
					(start 420.884604 -149.751796)
					(mid 420.899483 -149.715875)
					(end 420.935404 -149.700996)
				)
				(arc
					(start 422.116504 -149.700996)
					(mid 422.152425 -149.715875)
					(end 422.167304 -149.751796)
				)
			)
		)
	)
	(zone
		(layer "In1.Cu")
		(hatch none 0.5)
		(connect_pads
			(clearance 0)
		)
		(min_thickness 0.25)
		(keepout
			(tracks not_allowed)
			(vias allowed)
			(pads allowed)
			(copperpour not_allowed)
			(footprints allowed)
		)
		(placement
			(enabled no)
			(sheetname "")
		)
		(fill
			(thermal_gap 0.5)
			(thermal_bridge_width 0.5)
			(island_removal_mode 0)
		)
		(polygon
			(pts
				(arc
					(start 45.432726 -120.952006)
					(mid 45.447605 -120.916085)
					(end 45.483526 -120.901206)
				)
				(arc
					(start 46.664626 -120.901206)
					(mid 46.700547 -120.916085)
					(end 46.715426 -120.952006)
				)
				(arc
					(start 46.715426 -121.958354)
					(mid 46.700547 -121.994275)
					(end 46.664626 -122.009154)
				)
				(arc
					(start 45.483526 -122.009154)
					(mid 45.447605 -121.994275)
					(end 45.432726 -121.958354)
				)
			)
		)
	)
	(zone
		(layer "In1.Cu")
		(hatch none 0.5)
		(connect_pads
			(clearance 0)
		)
		(min_thickness 0.25)
		(keepout
			(tracks not_allowed)
			(vias allowed)
			(pads allowed)
			(copperpour not_allowed)
			(footprints allowed)
		)
		(placement
			(enabled no)
			(sheetname "")
		)
		(fill
			(thermal_gap 0.5)
			(thermal_bridge_width 0.5)
			(island_removal_mode 0)
		)
		(polygon
			(pts
				(arc
					(start 268.229842 -31.77413)
					(mid 268.244721 -31.738209)
					(end 268.280642 -31.72333)
				)
				(arc
					(start 269.512542 -31.72333)
					(mid 269.548463 -31.738209)
					(end 269.563342 -31.77413)
				)
				(arc
					(start 269.563342 -32.805878)
					(mid 269.548463 -32.841799)
					(end 269.512542 -32.856678)
				)
				(arc
					(start 268.280642 -32.856678)
					(mid 268.244721 -32.841799)
					(end 268.229842 -32.805878)
				)
			)
		)
	)
	(zone
		(layer "In1.Cu")
		(hatch none 0.5)
		(connect_pads
			(clearance 0)
		)
		(min_thickness 0.25)
		(keepout
			(tracks not_allowed)
			(vias allowed)
			(pads allowed)
			(copperpour not_allowed)
			(footprints allowed)
		)
		(placement
			(enabled no)
			(sheetname "")
		)
		(fill
			(thermal_gap 0.5)
			(thermal_bridge_width 0.5)
			(island_removal_mode 0)
		)
		(polygon
			(pts
				(arc
					(start 183.783478 -343.533222)
					(mid 183.747557 -343.548101)
					(end 183.732678 -343.584022)
				)
				(arc
					(start 183.732678 -344.320622)
					(mid 183.747557 -344.356543)
					(end 183.783478 -344.371422)
				)
				(xy 184.027318 -344.371422) (xy 184.381648 -344.139012) (xy 184.737248 -344.371422)
				(arc
					(start 184.979818 -344.371422)
					(mid 185.015739 -344.356543)
					(end 185.030618 -344.320622)
				)
				(arc
					(start 185.030618 -343.584022)
					(mid 185.015739 -343.548101)
					(end 184.979818 -343.533222)
				)
				(xy 184.737248 -343.533222) (xy 184.380378 -343.765632) (xy 184.026048 -343.533222)
			)
		)
	)
	(zone
		(layer "In1.Cu")
		(hatch none 0.5)
		(connect_pads
			(clearance 0)
		)
		(min_thickness 0.25)
		(keepout
			(tracks not_allowed)
			(vias allowed)
			(pads allowed)
			(copperpour not_allowed)
			(footprints allowed)
		)
		(placement
			(enabled no)
			(sheetname "")
		)
		(fill
			(thermal_gap 0.5)
			(thermal_bridge_width 0.5)
			(island_removal_mode 0)
		)
		(polygon
			(pts
				(arc
					(start 300.247812 -135.241792)
					(mid 300.262691 -135.205871)
					(end 300.298612 -135.190992)
				)
				(arc
					(start 301.479712 -135.190992)
					(mid 301.515633 -135.205871)
					(end 301.530512 -135.241792)
				)
				(arc
					(start 301.530512 -136.24814)
					(mid 301.515633 -136.284061)
					(end 301.479712 -136.29894)
				)
				(arc
					(start 300.298612 -136.29894)
					(mid 300.262691 -136.284061)
					(end 300.247812 -136.24814)
				)
			)
		)
	)
	(zone
		(layer "In1.Cu")
		(hatch none 0.5)
		(connect_pads
			(clearance 0)
		)
		(min_thickness 0.25)
		(keepout
			(tracks not_allowed)
			(vias allowed)
			(pads allowed)
			(copperpour not_allowed)
			(footprints allowed)
		)
		(placement
			(enabled no)
			(sheetname "")
		)
		(fill
			(thermal_gap 0.5)
			(thermal_bridge_width 0.5)
			(island_removal_mode 0)
		)
		(polygon
			(pts
				(arc
					(start 384.519424 -135.06323)
					(mid 384.534303 -135.099151)
					(end 384.570224 -135.11403)
				)
				(arc
					(start 385.306824 -135.11403)
					(mid 385.342745 -135.099151)
					(end 385.357624 -135.06323)
				)
				(xy 385.357624 -134.81939) (xy 385.125214 -134.46506) (xy 385.357624 -134.10946)
				(arc
					(start 385.357624 -133.86689)
					(mid 385.342745 -133.830969)
					(end 385.306824 -133.81609)
				)
				(arc
					(start 384.570224 -133.81609)
					(mid 384.534303 -133.830969)
					(end 384.519424 -133.86689)
				)
				(xy 384.519424 -134.10946) (xy 384.751834 -134.46633) (xy 384.519424 -134.82066)
			)
		)
	)
	(zone
		(layer "In1.Cu")
		(hatch none 0.5)
		(connect_pads
			(clearance 0)
		)
		(min_thickness 0.25)
		(keepout
			(tracks not_allowed)
			(vias allowed)
			(pads allowed)
			(copperpour not_allowed)
			(footprints allowed)
		)
		(placement
			(enabled no)
			(sheetname "")
		)
		(fill
			(thermal_gap 0.5)
			(thermal_bridge_width 0.5)
			(island_removal_mode 0)
		)
		(polygon
			(pts
				(arc
					(start 114.805714 -343.533222)
					(mid 114.769793 -343.548101)
					(end 114.754914 -343.584022)
				)
				(arc
					(start 114.754914 -344.320622)
					(mid 114.769793 -344.356543)
					(end 114.805714 -344.371422)
				)
				(xy 115.049554 -344.371422) (xy 115.403884 -344.139012) (xy 115.759484 -344.371422)
				(arc
					(start 116.002054 -344.371422)
					(mid 116.037975 -344.356543)
					(end 116.052854 -344.320622)
				)
				(arc
					(start 116.052854 -343.584022)
					(mid 116.037975 -343.548101)
					(end 116.002054 -343.533222)
				)
				(xy 115.759484 -343.533222) (xy 115.402614 -343.765632) (xy 115.048284 -343.533222)
			)
		)
	)
	(zone
		(layer "In1.Cu")
		(hatch none 0.5)
		(connect_pads
			(clearance 0)
		)
		(min_thickness 0.25)
		(keepout
			(tracks not_allowed)
			(vias allowed)
			(pads allowed)
			(copperpour not_allowed)
			(footprints allowed)
		)
		(placement
			(enabled no)
			(sheetname "")
		)
		(fill
			(thermal_gap 0.5)
			(thermal_bridge_width 0.5)
			(island_removal_mode 0)
		)
		(polygon
			(pts
				(arc
					(start 393.732766 -108.241846)
					(mid 393.747645 -108.205925)
					(end 393.783566 -108.191046)
				)
				(arc
					(start 394.964666 -108.191046)
					(mid 395.000587 -108.205925)
					(end 395.015466 -108.241846)
				)
				(arc
					(start 395.015466 -109.248194)
					(mid 395.000587 -109.284115)
					(end 394.964666 -109.298994)
				)
				(arc
					(start 393.783566 -109.298994)
					(mid 393.747645 -109.284115)
					(end 393.732766 -109.248194)
				)
			)
		)
	)
	(zone
		(layer "In1.Cu")
		(hatch none 0.5)
		(connect_pads
			(clearance 0)
		)
		(min_thickness 0.25)
		(keepout
			(tracks not_allowed)
			(vias allowed)
			(pads allowed)
			(copperpour not_allowed)
			(footprints allowed)
		)
		(placement
			(enabled no)
			(sheetname "")
		)
		(fill
			(thermal_gap 0.5)
			(thermal_bridge_width 0.5)
			(island_removal_mode 0)
		)
		(polygon
			(pts
				(arc
					(start 380.349506 -355.825806)
					(mid 380.313585 -355.840685)
					(end 380.298706 -355.876606)
				)
				(arc
					(start 380.298706 -356.613206)
					(mid 380.313585 -356.649127)
					(end 380.349506 -356.664006)
				)
				(xy 380.593346 -356.664006) (xy 380.947676 -356.431596) (xy 381.303276 -356.664006)
				(arc
					(start 381.545846 -356.664006)
					(mid 381.581767 -356.649127)
					(end 381.596646 -356.613206)
				)
				(arc
					(start 381.596646 -355.876606)
					(mid 381.581767 -355.840685)
					(end 381.545846 -355.825806)
				)
				(xy 381.303276 -355.825806) (xy 380.946406 -356.058216) (xy 380.592076 -355.825806)
			)
		)
	)
	(zone
		(layer "In1.Cu")
		(hatch none 0.5)
		(connect_pads
			(clearance 0)
		)
		(min_thickness 0.25)
		(keepout
			(tracks not_allowed)
			(vias allowed)
			(pads allowed)
			(copperpour not_allowed)
			(footprints allowed)
		)
		(placement
			(enabled no)
			(sheetname "")
		)
		(fill
			(thermal_gap 0.5)
			(thermal_bridge_width 0.5)
			(island_removal_mode 0)
		)
		(polygon
			(pts
				(arc
					(start 101.702362 -385.432046)
					(mid 101.612559 -385.394849)
					(end 101.575362 -385.305046)
				)
				(arc
					(start 101.575362 -385.103878)
					(mid 101.612559 -385.014075)
					(end 101.702362 -384.976878)
				)
				(arc
					(start 101.956362 -384.976878)
					(mid 102.046165 -385.014075)
					(end 102.083362 -385.103878)
				)
				(arc
					(start 102.083362 -385.305046)
					(mid 102.046165 -385.394849)
					(end 101.956362 -385.432046)
				)
			)
		)
	)
	(zone
		(layer "In1.Cu")
		(hatch none 0.5)
		(connect_pads
			(clearance 0)
		)
		(min_thickness 0.25)
		(keepout
			(tracks not_allowed)
			(vias allowed)
			(pads allowed)
			(copperpour not_allowed)
			(footprints allowed)
		)
		(placement
			(enabled no)
			(sheetname "")
		)
		(fill
			(thermal_gap 0.5)
			(thermal_bridge_width 0.5)
			(island_removal_mode 0)
		)
		(polygon
			(pts
				(arc
					(start 416.34791 -135.241792)
					(mid 416.362789 -135.205871)
					(end 416.39871 -135.190992)
				)
				(arc
					(start 417.57981 -135.190992)
					(mid 417.615731 -135.205871)
					(end 417.63061 -135.241792)
				)
				(arc
					(start 417.63061 -136.24814)
					(mid 417.615731 -136.284061)
					(end 417.57981 -136.29894)
				)
				(arc
					(start 416.39871 -136.29894)
					(mid 416.362789 -136.284061)
					(end 416.34791 -136.24814)
				)
			)
		)
	)
	(zone
		(layer "In1.Cu")
		(hatch none 0.5)
		(connect_pads
			(clearance 0)
		)
		(min_thickness 0.25)
		(keepout
			(tracks not_allowed)
			(vias allowed)
			(pads allowed)
			(copperpour not_allowed)
			(footprints allowed)
		)
		(placement
			(enabled no)
			(sheetname "")
		)
		(fill
			(thermal_gap 0.5)
			(thermal_bridge_width 0.5)
			(island_removal_mode 0)
		)
		(polygon
			(pts
				(arc
					(start 189.967108 -123.23826)
					(mid 189.952229 -123.274181)
					(end 189.916308 -123.28906)
				)
				(arc
					(start 188.735208 -123.28906)
					(mid 188.699287 -123.274181)
					(end 188.684408 -123.23826)
				)
				(arc
					(start 188.684408 -122.231912)
					(mid 188.699287 -122.195991)
					(end 188.735208 -122.181112)
				)
				(arc
					(start 189.916308 -122.181112)
					(mid 189.952229 -122.195991)
					(end 189.967108 -122.231912)
				)
			)
		)
	)
	(zone
		(layer "In1.Cu")
		(hatch none 0.5)
		(connect_pads
			(clearance 0)
		)
		(min_thickness 0.25)
		(keepout
			(tracks not_allowed)
			(vias allowed)
			(pads allowed)
			(copperpour not_allowed)
			(footprints allowed)
		)
		(placement
			(enabled no)
			(sheetname "")
		)
		(fill
			(thermal_gap 0.5)
			(thermal_bridge_width 0.5)
			(island_removal_mode 0)
		)
		(polygon
			(pts
				(arc
					(start 418.456618 -349.679514)
					(mid 418.420697 -349.694393)
					(end 418.405818 -349.730314)
				)
				(arc
					(start 418.405818 -350.466914)
					(mid 418.420697 -350.502835)
					(end 418.456618 -350.517714)
				)
				(xy 418.700458 -350.517714) (xy 419.054788 -350.285304) (xy 419.410388 -350.517714)
				(arc
					(start 419.652958 -350.517714)
					(mid 419.688879 -350.502835)
					(end 419.703758 -350.466914)
				)
				(arc
					(start 419.703758 -349.730314)
					(mid 419.688879 -349.694393)
					(end 419.652958 -349.679514)
				)
				(xy 419.410388 -349.679514) (xy 419.053518 -349.911924) (xy 418.699188 -349.679514)
			)
		)
	)
	(zone
		(layer "In1.Cu")
		(hatch none 0.5)
		(connect_pads
			(clearance 0)
		)
		(min_thickness 0.25)
		(keepout
			(tracks not_allowed)
			(vias allowed)
			(pads allowed)
			(copperpour not_allowed)
			(footprints allowed)
		)
		(placement
			(enabled no)
			(sheetname "")
		)
		(fill
			(thermal_gap 0.5)
			(thermal_bridge_width 0.5)
			(island_removal_mode 0)
		)
		(polygon
			(pts
				(arc
					(start 306.067206 -152.558242)
					(mid 306.052327 -152.594163)
					(end 306.016406 -152.609042)
				)
				(arc
					(start 304.835306 -152.609042)
					(mid 304.799385 -152.594163)
					(end 304.784506 -152.558242)
				)
				(arc
					(start 304.784506 -151.551894)
					(mid 304.799385 -151.515973)
					(end 304.835306 -151.501094)
				)
				(arc
					(start 306.016406 -151.501094)
					(mid 306.052327 -151.515973)
					(end 306.067206 -151.551894)
				)
			)
		)
	)
	(zone
		(layer "In1.Cu")
		(hatch none 0.5)
		(connect_pads
			(clearance 0)
		)
		(min_thickness 0.25)
		(keepout
			(tracks not_allowed)
			(vias allowed)
			(pads allowed)
			(copperpour not_allowed)
			(footprints allowed)
		)
		(placement
			(enabled no)
			(sheetname "")
		)
		(fill
			(thermal_gap 0.5)
			(thermal_bridge_width 0.5)
			(island_removal_mode 0)
		)
		(polygon
			(pts
				(arc
					(start 56.453786 -370.281708)
					(mid 56.438907 -370.245787)
					(end 56.402986 -370.230908)
				)
				(arc
					(start 55.666386 -370.230908)
					(mid 55.630465 -370.245787)
					(end 55.615586 -370.281708)
				)
				(xy 55.615586 -370.525548) (xy 55.847996 -370.879878) (xy 55.615586 -371.235478)
				(arc
					(start 55.615586 -371.478048)
					(mid 55.630465 -371.513969)
					(end 55.666386 -371.528848)
				)
				(arc
					(start 56.402986 -371.528848)
					(mid 56.438907 -371.513969)
					(end 56.453786 -371.478048)
				)
				(xy 56.453786 -371.235478) (xy 56.221376 -370.878608) (xy 56.453786 -370.524278)
			)
		)
	)
	(zone
		(layer "In1.Cu")
		(hatch none 0.5)
		(connect_pads
			(clearance 0)
		)
		(min_thickness 0.25)
		(keepout
			(tracks not_allowed)
			(vias allowed)
			(pads allowed)
			(copperpour not_allowed)
			(footprints allowed)
		)
		(placement
			(enabled no)
			(sheetname "")
		)
		(fill
			(thermal_gap 0.5)
			(thermal_bridge_width 0.5)
			(island_removal_mode 0)
		)
		(polygon
			(pts
				(arc
					(start 79.600298 -123.32462)
					(mid 79.615177 -123.360541)
					(end 79.651098 -123.37542)
				)
				(arc
					(start 80.387698 -123.37542)
					(mid 80.423619 -123.360541)
					(end 80.438498 -123.32462)
				)
				(xy 80.438498 -123.08078) (xy 80.206088 -122.72645) (xy 80.438498 -122.37085)
				(arc
					(start 80.438498 -122.12828)
					(mid 80.423619 -122.092359)
					(end 80.387698 -122.07748)
				)
				(arc
					(start 79.651098 -122.07748)
					(mid 79.615177 -122.092359)
					(end 79.600298 -122.12828)
				)
				(xy 79.600298 -122.37085) (xy 79.832708 -122.72772) (xy 79.600298 -123.08205)
			)
		)
	)
	(zone
		(layer "In1.Cu")
		(hatch none 0.5)
		(connect_pads
			(clearance 0)
		)
		(min_thickness 0.25)
		(keepout
			(tracks not_allowed)
			(vias allowed)
			(pads allowed)
			(copperpour not_allowed)
			(footprints allowed)
		)
		(placement
			(enabled no)
			(sheetname "")
		)
		(fill
			(thermal_gap 0.5)
			(thermal_bridge_width 0.5)
			(island_removal_mode 0)
		)
		(polygon
			(pts
				(arc
					(start 138.665204 -199.854058)
					(mid 138.680083 -199.818137)
					(end 138.716004 -199.803258)
				)
				(arc
					(start 139.395708 -199.803258)
					(mid 139.431629 -199.818137)
					(end 139.446508 -199.854058)
				)
				(arc
					(start 139.446508 -201.125074)
					(mid 139.431629 -201.160995)
					(end 139.395708 -201.175874)
				)
				(arc
					(start 138.716004 -201.175874)
					(mid 138.680083 -201.160995)
					(end 138.665204 -201.125074)
				)
			)
		)
	)
	(zone
		(layer "In1.Cu")
		(hatch none 0.5)
		(connect_pads
			(clearance 0)
		)
		(min_thickness 0.25)
		(keepout
			(tracks not_allowed)
			(vias allowed)
			(pads allowed)
			(copperpour not_allowed)
			(footprints allowed)
		)
		(placement
			(enabled no)
			(sheetname "")
		)
		(fill
			(thermal_gap 0.5)
			(thermal_bridge_width 0.5)
			(island_removal_mode 0)
		)
		(polygon
			(pts
				(arc
					(start 286.385508 -355.825806)
					(mid 286.349587 -355.840685)
					(end 286.334708 -355.876606)
				)
				(arc
					(start 286.334708 -356.613206)
					(mid 286.349587 -356.649127)
					(end 286.385508 -356.664006)
				)
				(xy 286.629348 -356.664006) (xy 286.983678 -356.431596) (xy 287.339278 -356.664006)
				(arc
					(start 287.581848 -356.664006)
					(mid 287.617769 -356.649127)
					(end 287.632648 -356.613206)
				)
				(arc
					(start 287.632648 -355.876606)
					(mid 287.617769 -355.840685)
					(end 287.581848 -355.825806)
				)
				(xy 287.339278 -355.825806) (xy 286.982408 -356.058216) (xy 286.628078 -355.825806)
			)
		)
	)
	(zone
		(layer "In1.Cu")
		(hatch none 0.5)
		(connect_pads
			(clearance 0)
		)
		(min_thickness 0.25)
		(keepout
			(tracks not_allowed)
			(vias allowed)
			(pads allowed)
			(copperpour not_allowed)
			(footprints allowed)
		)
		(placement
			(enabled no)
			(sheetname "")
		)
		(fill
			(thermal_gap 0.5)
			(thermal_bridge_width 0.5)
			(island_removal_mode 0)
		)
		(polygon
			(pts
				(arc
					(start 3.190748 -387.159246)
					(mid 3.226669 -387.174125)
					(end 3.241548 -387.210046)
				)
				(arc
					(start 3.241548 -387.6167)
					(mid 3.226669 -387.652621)
					(end 3.190748 -387.6675)
				)
				(arc
					(start 2.788412 -387.6675)
					(mid 2.752491 -387.652621)
					(end 2.737612 -387.6167)
				)
				(arc
					(start 2.737612 -387.210046)
					(mid 2.752491 -387.174125)
					(end 2.788412 -387.159246)
				)
			)
		)
	)
	(zone
		(layer "In1.Cu")
		(hatch none 0.5)
		(connect_pads
			(clearance 0)
		)
		(min_thickness 0.25)
		(keepout
			(tracks not_allowed)
			(vias allowed)
			(pads allowed)
			(copperpour not_allowed)
			(footprints allowed)
		)
		(placement
			(enabled no)
			(sheetname "")
		)
		(fill
			(thermal_gap 0.5)
			(thermal_bridge_width 0.5)
			(island_removal_mode 0)
		)
		(polygon
			(pts
				(arc
					(start 410.329888 -29.974286)
					(mid 410.344767 -29.938365)
					(end 410.380688 -29.923486)
				)
				(arc
					(start 411.612588 -29.923486)
					(mid 411.648509 -29.938365)
					(end 411.663388 -29.974286)
				)
				(arc
					(start 411.663388 -31.006034)
					(mid 411.648509 -31.041955)
					(end 411.612588 -31.056834)
				)
				(arc
					(start 410.380688 -31.056834)
					(mid 410.344767 -31.041955)
					(end 410.329888 -31.006034)
				)
			)
		)
	)
	(zone
		(layer "In1.Cu")
		(hatch none 0.5)
		(connect_pads
			(clearance 0)
		)
		(min_thickness 0.25)
		(keepout
			(tracks not_allowed)
			(vias allowed)
			(pads allowed)
			(copperpour not_allowed)
			(footprints allowed)
		)
		(placement
			(enabled no)
			(sheetname "")
		)
		(fill
			(thermal_gap 0.5)
			(thermal_bridge_width 0.5)
			(island_removal_mode 0)
		)
		(polygon
			(pts
				(arc
					(start 161.53257 -133.96214)
					(mid 161.547449 -133.926219)
					(end 161.58337 -133.91134)
				)
				(arc
					(start 162.76447 -133.91134)
					(mid 162.800391 -133.926219)
					(end 162.81527 -133.96214)
				)
				(arc
					(start 162.81527 -134.968488)
					(mid 162.800391 -135.004409)
					(end 162.76447 -135.019288)
				)
				(arc
					(start 161.58337 -135.019288)
					(mid 161.547449 -135.004409)
					(end 161.53257 -134.968488)
				)
			)
		)
	)
	(zone
		(layer "In1.Cu")
		(hatch none 0.5)
		(connect_pads
			(clearance 0)
		)
		(min_thickness 0.25)
		(keepout
			(tracks not_allowed)
			(vias allowed)
			(pads allowed)
			(copperpour not_allowed)
			(footprints allowed)
		)
		(placement
			(enabled no)
			(sheetname "")
		)
		(fill
			(thermal_gap 0.5)
			(thermal_bridge_width 0.5)
			(island_removal_mode 0)
		)
		(polygon
			(pts
				(arc
					(start 190.001398 -343.533222)
					(mid 189.965477 -343.548101)
					(end 189.950598 -343.584022)
				)
				(arc
					(start 189.950598 -344.320622)
					(mid 189.965477 -344.356543)
					(end 190.001398 -344.371422)
				)
				(xy 190.245238 -344.371422) (xy 190.599568 -344.139012) (xy 190.955168 -344.371422)
				(arc
					(start 191.197738 -344.371422)
					(mid 191.233659 -344.356543)
					(end 191.248538 -344.320622)
				)
				(arc
					(start 191.248538 -343.584022)
					(mid 191.233659 -343.548101)
					(end 191.197738 -343.533222)
				)
				(xy 190.955168 -343.533222) (xy 190.598298 -343.765632) (xy 190.243968 -343.533222)
			)
		)
	)
	(zone
		(layer "In1.Cu")
		(hatch none 0.5)
		(connect_pads
			(clearance 0)
		)
		(min_thickness 0.25)
		(keepout
			(tracks not_allowed)
			(vias allowed)
			(pads allowed)
			(copperpour not_allowed)
			(footprints allowed)
		)
		(placement
			(enabled no)
			(sheetname "")
		)
		(fill
			(thermal_gap 0.5)
			(thermal_bridge_width 0.5)
			(island_removal_mode 0)
		)
		(polygon
			(pts
				(arc
					(start 242.229894 -28.174188)
					(mid 242.244773 -28.138267)
					(end 242.280694 -28.123388)
				)
				(arc
					(start 243.512594 -28.123388)
					(mid 243.548515 -28.138267)
					(end 243.563394 -28.174188)
				)
				(arc
					(start 243.563394 -29.205936)
					(mid 243.548515 -29.241857)
					(end 243.512594 -29.256736)
				)
				(arc
					(start 242.280694 -29.256736)
					(mid 242.244773 -29.241857)
					(end 242.229894 -29.205936)
				)
			)
		)
	)
	(zone
		(layer "In1.Cu")
		(hatch none 0.5)
		(connect_pads
			(clearance 0)
		)
		(min_thickness 0.25)
		(keepout
			(tracks not_allowed)
			(vias allowed)
			(pads allowed)
			(copperpour not_allowed)
			(footprints allowed)
		)
		(placement
			(enabled no)
			(sheetname "")
		)
		(fill
			(thermal_gap 0.5)
			(thermal_bridge_width 0.5)
			(island_removal_mode 0)
		)
		(polygon
			(pts
				(arc
					(start 142.786354 -355.825806)
					(mid 142.750433 -355.840685)
					(end 142.735554 -355.876606)
				)
				(arc
					(start 142.735554 -356.613206)
					(mid 142.750433 -356.649127)
					(end 142.786354 -356.664006)
				)
				(xy 143.030194 -356.664006) (xy 143.384524 -356.431596) (xy 143.740124 -356.664006)
				(arc
					(start 143.982694 -356.664006)
					(mid 144.018615 -356.649127)
					(end 144.033494 -356.613206)
				)
				(arc
					(start 144.033494 -355.876606)
					(mid 144.018615 -355.840685)
					(end 143.982694 -355.825806)
				)
				(xy 143.740124 -355.825806) (xy 143.383254 -356.058216) (xy 143.028924 -355.825806)
			)
		)
	)
	(zone
		(layer "In1.Cu")
		(hatch none 0.5)
		(connect_pads
			(clearance 0)
		)
		(min_thickness 0.25)
		(keepout
			(tracks not_allowed)
			(vias allowed)
			(pads allowed)
			(copperpour not_allowed)
			(footprints allowed)
		)
		(placement
			(enabled no)
			(sheetname "")
		)
		(fill
			(thermal_gap 0.5)
			(thermal_bridge_width 0.5)
			(island_removal_mode 0)
		)
		(polygon
			(pts
				(arc
					(start 318.55537 -355.825806)
					(mid 318.519449 -355.840685)
					(end 318.50457 -355.876606)
				)
				(arc
					(start 318.50457 -356.613206)
					(mid 318.519449 -356.649127)
					(end 318.55537 -356.664006)
				)
				(xy 318.79921 -356.664006) (xy 319.15354 -356.431596) (xy 319.50914 -356.664006)
				(arc
					(start 319.75171 -356.664006)
					(mid 319.787631 -356.649127)
					(end 319.80251 -356.613206)
				)
				(arc
					(start 319.80251 -355.876606)
					(mid 319.787631 -355.840685)
					(end 319.75171 -355.825806)
				)
				(xy 319.50914 -355.825806) (xy 319.15227 -356.058216) (xy 318.79794 -355.825806)
			)
		)
	)
	(zone
		(layer "In1.Cu")
		(hatch none 0.5)
		(connect_pads
			(clearance 0)
		)
		(min_thickness 0.25)
		(keepout
			(tracks not_allowed)
			(vias allowed)
			(pads allowed)
			(copperpour not_allowed)
			(footprints allowed)
		)
		(placement
			(enabled no)
			(sheetname "")
		)
		(fill
			(thermal_gap 0.5)
			(thermal_bridge_width 0.5)
			(island_removal_mode 0)
		)
		(polygon
			(pts
				(arc
					(start 209.999834 -29.205936)
					(mid 209.984955 -29.241857)
					(end 209.949034 -29.256736)
				)
				(arc
					(start 208.717134 -29.256736)
					(mid 208.681213 -29.241857)
					(end 208.666334 -29.205936)
				)
				(arc
					(start 208.666334 -28.174188)
					(mid 208.681213 -28.138267)
					(end 208.717134 -28.123388)
				)
				(arc
					(start 209.949034 -28.123388)
					(mid 209.984955 -28.138267)
					(end 209.999834 -28.174188)
				)
			)
		)
	)
	(zone
		(layer "In1.Cu")
		(hatch none 0.5)
		(connect_pads
			(clearance 0)
		)
		(min_thickness 0.25)
		(keepout
			(tracks not_allowed)
			(vias allowed)
			(pads allowed)
			(copperpour not_allowed)
			(footprints allowed)
		)
		(placement
			(enabled no)
			(sheetname "")
		)
		(fill
			(thermal_gap 0.5)
			(thermal_bridge_width 0.5)
			(island_removal_mode 0)
		)
		(polygon
			(pts
				(arc
					(start 416.34791 -133.441948)
					(mid 416.362789 -133.406027)
					(end 416.39871 -133.391148)
				)
				(arc
					(start 417.57981 -133.391148)
					(mid 417.615731 -133.406027)
					(end 417.63061 -133.441948)
				)
				(arc
					(start 417.63061 -134.448296)
					(mid 417.615731 -134.484217)
					(end 417.57981 -134.499096)
				)
				(arc
					(start 416.39871 -134.499096)
					(mid 416.362789 -134.484217)
					(end 416.34791 -134.448296)
				)
			)
		)
	)
	(zone
		(layer "In1.Cu")
		(hatch none 0.5)
		(connect_pads
			(clearance 0)
		)
		(min_thickness 0.25)
		(keepout
			(tracks not_allowed)
			(vias allowed)
			(pads allowed)
			(copperpour not_allowed)
			(footprints allowed)
		)
		(placement
			(enabled no)
			(sheetname "")
		)
		(fill
			(thermal_gap 0.5)
			(thermal_bridge_width 0.5)
			(island_removal_mode 0)
		)
		(polygon
			(pts
				(arc
					(start 130.350514 -355.825806)
					(mid 130.314593 -355.840685)
					(end 130.299714 -355.876606)
				)
				(arc
					(start 130.299714 -356.613206)
					(mid 130.314593 -356.649127)
					(end 130.350514 -356.664006)
				)
				(xy 130.594354 -356.664006) (xy 130.948684 -356.431596) (xy 131.304284 -356.664006)
				(arc
					(start 131.546854 -356.664006)
					(mid 131.582775 -356.649127)
					(end 131.597654 -356.613206)
				)
				(arc
					(start 131.597654 -355.876606)
					(mid 131.582775 -355.840685)
					(end 131.546854 -355.825806)
				)
				(xy 131.304284 -355.825806) (xy 130.947414 -356.058216) (xy 130.593084 -355.825806)
			)
		)
	)
	(zone
		(layer "In1.Cu")
		(hatch none 0.5)
		(connect_pads
			(clearance 0)
		)
		(min_thickness 0.25)
		(keepout
			(tracks not_allowed)
			(vias allowed)
			(pads allowed)
			(copperpour not_allowed)
			(footprints allowed)
		)
		(placement
			(enabled no)
			(sheetname "")
		)
		(fill
			(thermal_gap 0.5)
			(thermal_bridge_width 0.5)
			(island_removal_mode 0)
		)
		(polygon
			(pts
				(arc
					(start 45.432726 -119.151908)
					(mid 45.447605 -119.115987)
					(end 45.483526 -119.101108)
				)
				(arc
					(start 46.664626 -119.101108)
					(mid 46.700547 -119.115987)
					(end 46.715426 -119.151908)
				)
				(arc
					(start 46.715426 -120.158256)
					(mid 46.700547 -120.194177)
					(end 46.664626 -120.209056)
				)
				(arc
					(start 45.483526 -120.209056)
					(mid 45.447605 -120.194177)
					(end 45.432726 -120.158256)
				)
			)
		)
	)
	(zone
		(layer "In1.Cu")
		(hatch none 0.5)
		(connect_pads
			(clearance 0)
		)
		(min_thickness 0.25)
		(keepout
			(tracks not_allowed)
			(vias allowed)
			(pads allowed)
			(copperpour not_allowed)
			(footprints allowed)
		)
		(placement
			(enabled no)
			(sheetname "")
		)
		(fill
			(thermal_gap 0.5)
			(thermal_bridge_width 0.5)
			(island_removal_mode 0)
		)
		(polygon
			(pts
				(arc
					(start 45.432726 -124.551948)
					(mid 45.447605 -124.516027)
					(end 45.483526 -124.501148)
				)
				(arc
					(start 46.664626 -124.501148)
					(mid 46.700547 -124.516027)
					(end 46.715426 -124.551948)
				)
				(arc
					(start 46.715426 -125.558296)
					(mid 46.700547 -125.594217)
					(end 46.664626 -125.609096)
				)
				(arc
					(start 45.483526 -125.609096)
					(mid 45.447605 -125.594217)
					(end 45.432726 -125.558296)
				)
			)
		)
	)
	(zone
		(layer "In1.Cu")
		(hatch none 0.5)
		(connect_pads
			(clearance 0)
		)
		(min_thickness 0.25)
		(keepout
			(tracks not_allowed)
			(vias allowed)
			(pads allowed)
			(copperpour not_allowed)
			(footprints allowed)
		)
		(placement
			(enabled no)
			(sheetname "")
		)
		(fill
			(thermal_gap 0.5)
			(thermal_bridge_width 0.5)
			(island_removal_mode 0)
		)
		(polygon
			(pts
				(arc
					(start 167.351964 -134.968488)
					(mid 167.337085 -135.004409)
					(end 167.301164 -135.019288)
				)
				(arc
					(start 166.120064 -135.019288)
					(mid 166.084143 -135.004409)
					(end 166.069264 -134.968488)
				)
				(arc
					(start 166.069264 -133.96214)
					(mid 166.084143 -133.926219)
					(end 166.120064 -133.91134)
				)
				(arc
					(start 167.301164 -133.91134)
					(mid 167.337085 -133.926219)
					(end 167.351964 -133.96214)
				)
			)
		)
	)
	(zone
		(layer "In1.Cu")
		(hatch none 0.5)
		(connect_pads
			(clearance 0)
		)
		(min_thickness 0.25)
		(keepout
			(tracks not_allowed)
			(vias allowed)
			(pads allowed)
			(copperpour not_allowed)
			(footprints allowed)
		)
		(placement
			(enabled no)
			(sheetname "")
		)
		(fill
			(thermal_gap 0.5)
			(thermal_bridge_width 0.5)
			(island_removal_mode 0)
		)
		(polygon
			(pts
				(arc
					(start 211.473288 -32.879538)
					(mid 211.488167 -32.915459)
					(end 211.524088 -32.930338)
				)
				(arc
					(start 212.260688 -32.930338)
					(mid 212.296609 -32.915459)
					(end 212.311488 -32.879538)
				)
				(xy 212.311488 -32.635698) (xy 212.079078 -32.281368) (xy 212.311488 -31.925768)
				(arc
					(start 212.311488 -31.683198)
					(mid 212.296609 -31.647277)
					(end 212.260688 -31.632398)
				)
				(arc
					(start 211.524088 -31.632398)
					(mid 211.488167 -31.647277)
					(end 211.473288 -31.683198)
				)
				(xy 211.473288 -31.925768) (xy 211.705698 -32.282638) (xy 211.473288 -32.636968)
			)
		)
	)
	(zone
		(layer "In1.Cu")
		(hatch none 0.5)
		(connect_pads
			(clearance 0)
		)
		(min_thickness 0.25)
		(keepout
			(tracks not_allowed)
			(vias allowed)
			(pads allowed)
			(copperpour not_allowed)
			(footprints allowed)
		)
		(placement
			(enabled no)
			(sheetname "")
		)
		(fill
			(thermal_gap 0.5)
			(thermal_bridge_width 0.5)
			(island_removal_mode 0)
		)
		(polygon
			(pts
				(arc
					(start 36.0299 -28.174188)
					(mid 36.044779 -28.138267)
					(end 36.0807 -28.123388)
				)
				(arc
					(start 37.3126 -28.123388)
					(mid 37.348521 -28.138267)
					(end 37.3634 -28.174188)
				)
				(arc
					(start 37.3634 -29.205936)
					(mid 37.348521 -29.241857)
					(end 37.3126 -29.256736)
				)
				(arc
					(start 36.0807 -29.256736)
					(mid 36.044779 -29.241857)
					(end 36.0299 -29.205936)
				)
			)
		)
	)
	(zone
		(layer "In1.Cu")
		(hatch none 0.5)
		(connect_pads
			(clearance 0)
		)
		(min_thickness 0.25)
		(keepout
			(tracks not_allowed)
			(vias allowed)
			(pads allowed)
			(copperpour not_allowed)
			(footprints allowed)
		)
		(placement
			(enabled no)
			(sheetname "")
		)
		(fill
			(thermal_gap 0.5)
			(thermal_bridge_width 0.5)
			(island_removal_mode 0)
		)
		(polygon
			(pts
				(arc
					(start 76.751688 -355.825806)
					(mid 76.715767 -355.840685)
					(end 76.700888 -355.876606)
				)
				(arc
					(start 76.700888 -356.613206)
					(mid 76.715767 -356.649127)
					(end 76.751688 -356.664006)
				)
				(xy 76.995528 -356.664006) (xy 77.349858 -356.431596) (xy 77.705458 -356.664006)
				(arc
					(start 77.948028 -356.664006)
					(mid 77.983949 -356.649127)
					(end 77.998828 -356.613206)
				)
				(arc
					(start 77.998828 -355.876606)
					(mid 77.983949 -355.840685)
					(end 77.948028 -355.825806)
				)
				(xy 77.705458 -355.825806) (xy 77.348588 -356.058216) (xy 76.994258 -355.825806)
			)
		)
	)
	(zone
		(layer "In1.Cu")
		(hatch none 0.5)
		(connect_pads
			(clearance 0)
		)
		(min_thickness 0.25)
		(keepout
			(tracks not_allowed)
			(vias allowed)
			(pads allowed)
			(copperpour not_allowed)
			(footprints allowed)
		)
		(placement
			(enabled no)
			(sheetname "")
		)
		(fill
			(thermal_gap 0.5)
			(thermal_bridge_width 0.5)
			(island_removal_mode 0)
		)
		(polygon
			(pts
				(arc
					(start 10.029952 -29.974286)
					(mid 10.044831 -29.938365)
					(end 10.080752 -29.923486)
				)
				(arc
					(start 11.312652 -29.923486)
					(mid 11.348573 -29.938365)
					(end 11.363452 -29.974286)
				)
				(arc
					(start 11.363452 -31.006034)
					(mid 11.348573 -31.041955)
					(end 11.312652 -31.056834)
				)
				(arc
					(start 10.080752 -31.056834)
					(mid 10.044831 -31.041955)
					(end 10.029952 -31.006034)
				)
			)
		)
	)
	(zone
		(layer "In1.Cu")
		(hatch none 0.5)
		(connect_pads
			(clearance 0)
		)
		(min_thickness 0.25)
		(keepout
			(tracks not_allowed)
			(vias allowed)
			(pads allowed)
			(copperpour not_allowed)
			(footprints allowed)
		)
		(placement
			(enabled no)
			(sheetname "")
		)
		(fill
			(thermal_gap 0.5)
			(thermal_bridge_width 0.5)
			(island_removal_mode 0)
		)
		(polygon
			(pts
				(arc
					(start 410.329888 -31.77413)
					(mid 410.344767 -31.738209)
					(end 410.380688 -31.72333)
				)
				(arc
					(start 411.612588 -31.72333)
					(mid 411.648509 -31.738209)
					(end 411.663388 -31.77413)
				)
				(arc
					(start 411.663388 -32.805878)
					(mid 411.648509 -32.841799)
					(end 411.612588 -32.856678)
				)
				(arc
					(start 410.380688 -32.856678)
					(mid 410.344767 -32.841799)
					(end 410.329888 -32.805878)
				)
			)
		)
	)
	(zone
		(layer "In1.Cu")
		(hatch none 0.5)
		(connect_pads
			(clearance 0)
		)
		(min_thickness 0.25)
		(keepout
			(tracks not_allowed)
			(vias allowed)
			(pads allowed)
			(copperpour not_allowed)
			(footprints allowed)
		)
		(placement
			(enabled no)
			(sheetname "")
		)
		(fill
			(thermal_gap 0.5)
			(thermal_bridge_width 0.5)
			(island_removal_mode 0)
		)
		(polygon
			(pts
				(arc
					(start 51.25212 -133.16839)
					(mid 51.237241 -133.204311)
					(end 51.20132 -133.21919)
				)
				(arc
					(start 50.02022 -133.21919)
					(mid 49.984299 -133.204311)
					(end 49.96942 -133.16839)
				)
				(arc
					(start 49.96942 -132.162042)
					(mid 49.984299 -132.126121)
					(end 50.02022 -132.111242)
				)
				(arc
					(start 51.20132 -132.111242)
					(mid 51.237241 -132.126121)
					(end 51.25212 -132.162042)
				)
			)
		)
	)
	(zone
		(layer "In1.Cu")
		(hatch none 0.5)
		(connect_pads
			(clearance 0)
		)
		(min_thickness 0.25)
		(keepout
			(tracks not_allowed)
			(vias allowed)
			(pads allowed)
			(copperpour not_allowed)
			(footprints allowed)
		)
		(placement
			(enabled no)
			(sheetname "")
		)
		(fill
			(thermal_gap 0.5)
			(thermal_bridge_width 0.5)
			(island_removal_mode 0)
		)
		(polygon
			(pts
				(arc
					(start 121.023634 -343.533222)
					(mid 120.987713 -343.548101)
					(end 120.972834 -343.584022)
				)
				(arc
					(start 120.972834 -344.320622)
					(mid 120.987713 -344.356543)
					(end 121.023634 -344.371422)
				)
				(xy 121.267474 -344.371422) (xy 121.621804 -344.139012) (xy 121.977404 -344.371422)
				(arc
					(start 122.219974 -344.371422)
					(mid 122.255895 -344.356543)
					(end 122.270774 -344.320622)
				)
				(arc
					(start 122.270774 -343.584022)
					(mid 122.255895 -343.548101)
					(end 122.219974 -343.533222)
				)
				(xy 121.977404 -343.533222) (xy 121.620534 -343.765632) (xy 121.266204 -343.533222)
			)
		)
	)
	(zone
		(layer "In1.Cu")
		(hatch none 0.5)
		(connect_pads
			(clearance 0)
		)
		(min_thickness 0.25)
		(keepout
			(tracks not_allowed)
			(vias allowed)
			(pads allowed)
			(copperpour not_allowed)
			(footprints allowed)
		)
		(placement
			(enabled no)
			(sheetname "")
		)
		(fill
			(thermal_gap 0.5)
			(thermal_bridge_width 0.5)
			(island_removal_mode 0)
		)
		(polygon
			(pts
				(arc
					(start 277.632668 -130.361944)
					(mid 277.647547 -130.326023)
					(end 277.683468 -130.311144)
				)
				(arc
					(start 278.864568 -130.311144)
					(mid 278.900489 -130.326023)
					(end 278.915368 -130.361944)
				)
				(arc
					(start 278.915368 -131.368292)
					(mid 278.900489 -131.404213)
					(end 278.864568 -131.419092)
				)
				(arc
					(start 277.683468 -131.419092)
					(mid 277.647547 -131.404213)
					(end 277.632668 -131.368292)
				)
			)
		)
	)
	(zone
		(layer "In1.Cu")
		(hatch none 0.5)
		(connect_pads
			(clearance 0)
		)
		(min_thickness 0.25)
		(keepout
			(tracks not_allowed)
			(vias allowed)
			(pads allowed)
			(copperpour not_allowed)
			(footprints allowed)
		)
		(placement
			(enabled no)
			(sheetname "")
		)
		(fill
			(thermal_gap 0.5)
			(thermal_bridge_width 0.5)
			(island_removal_mode 0)
		)
		(polygon
			(pts
				(arc
					(start 165.129718 -343.533222)
					(mid 165.093797 -343.548101)
					(end 165.078918 -343.584022)
				)
				(arc
					(start 165.078918 -344.320622)
					(mid 165.093797 -344.356543)
					(end 165.129718 -344.371422)
				)
				(xy 165.373558 -344.371422) (xy 165.727888 -344.139012) (xy 166.083488 -344.371422)
				(arc
					(start 166.326058 -344.371422)
					(mid 166.361979 -344.356543)
					(end 166.376858 -344.320622)
				)
				(arc
					(start 166.376858 -343.584022)
					(mid 166.361979 -343.548101)
					(end 166.326058 -343.533222)
				)
				(xy 166.083488 -343.533222) (xy 165.726618 -343.765632) (xy 165.372288 -343.533222)
			)
		)
	)
	(zone
		(layer "In1.Cu")
		(hatch none 0.5)
		(connect_pads
			(clearance 0)
		)
		(min_thickness 0.25)
		(keepout
			(tracks not_allowed)
			(vias allowed)
			(pads allowed)
			(copperpour not_allowed)
			(footprints allowed)
		)
		(placement
			(enabled no)
			(sheetname "")
		)
		(fill
			(thermal_gap 0.5)
			(thermal_bridge_width 0.5)
			(island_removal_mode 0)
		)
		(polygon
			(pts
				(arc
					(start 233.744008 -83.147408)
					(mid 233.654205 -83.110211)
					(end 233.617008 -83.020408)
				)
				(arc
					(start 233.617008 -82.817208)
					(mid 233.654205 -82.727405)
					(end 233.744008 -82.690208)
				)
				(arc
					(start 233.998008 -82.690208)
					(mid 234.087811 -82.727405)
					(end 234.125008 -82.817208)
				)
				(arc
					(start 234.125008 -83.020408)
					(mid 234.087811 -83.110211)
					(end 233.998008 -83.147408)
				)
			)
		)
	)
	(zone
		(layer "In1.Cu")
		(hatch none 0.5)
		(connect_pads
			(clearance 0)
		)
		(min_thickness 0.25)
		(keepout
			(tracks not_allowed)
			(vias allowed)
			(pads allowed)
			(copperpour not_allowed)
			(footprints allowed)
		)
		(placement
			(enabled no)
			(sheetname "")
		)
		(fill
			(thermal_gap 0.5)
			(thermal_bridge_width 0.5)
			(island_removal_mode 0)
		)
		(polygon
			(pts
				(arc
					(start 67.899788 -27.405838)
					(mid 67.884909 -27.441759)
					(end 67.848988 -27.456638)
				)
				(arc
					(start 66.617088 -27.456638)
					(mid 66.581167 -27.441759)
					(end 66.566288 -27.405838)
				)
				(arc
					(start 66.566288 -26.37409)
					(mid 66.581167 -26.338169)
					(end 66.617088 -26.32329)
				)
				(arc
					(start 67.848988 -26.32329)
					(mid 67.884909 -26.338169)
					(end 67.899788 -26.37409)
				)
			)
		)
	)
	(zone
		(layer "In1.Cu")
		(hatch none 0.5)
		(connect_pads
			(clearance 0)
		)
		(min_thickness 0.25)
		(keepout
			(tracks not_allowed)
			(vias allowed)
			(pads allowed)
			(copperpour not_allowed)
			(footprints allowed)
		)
		(placement
			(enabled no)
			(sheetname "")
		)
		(fill
			(thermal_gap 0.5)
			(thermal_bridge_width 0.5)
			(island_removal_mode 0)
		)
		(polygon
			(pts
				(arc
					(start 184.147714 -120.431814)
					(mid 184.162593 -120.395893)
					(end 184.198514 -120.381014)
				)
				(arc
					(start 185.379614 -120.381014)
					(mid 185.415535 -120.395893)
					(end 185.430414 -120.431814)
				)
				(arc
					(start 185.430414 -121.438162)
					(mid 185.415535 -121.474083)
					(end 185.379614 -121.488962)
				)
				(arc
					(start 184.198514 -121.488962)
					(mid 184.162593 -121.474083)
					(end 184.147714 -121.438162)
				)
			)
		)
	)
	(zone
		(layer "In1.Cu")
		(hatch none 0.5)
		(connect_pads
			(clearance 0)
		)
		(min_thickness 0.25)
		(keepout
			(tracks not_allowed)
			(vias allowed)
			(pads allowed)
			(copperpour not_allowed)
			(footprints allowed)
		)
		(placement
			(enabled no)
			(sheetname "")
		)
		(fill
			(thermal_gap 0.5)
			(thermal_bridge_width 0.5)
			(island_removal_mode 0)
		)
		(polygon
			(pts
				(arc
					(start 189.967108 -150.758144)
					(mid 189.952229 -150.794065)
					(end 189.916308 -150.808944)
				)
				(arc
					(start 188.735208 -150.808944)
					(mid 188.699287 -150.794065)
					(end 188.684408 -150.758144)
				)
				(arc
					(start 188.684408 -149.751796)
					(mid 188.699287 -149.715875)
					(end 188.735208 -149.700996)
				)
				(arc
					(start 189.916308 -149.700996)
					(mid 189.952229 -149.715875)
					(end 189.967108 -149.751796)
				)
			)
		)
	)
	(zone
		(layer "In1.Cu")
		(hatch none 0.5)
		(connect_pads
			(clearance 0)
		)
		(min_thickness 0.25)
		(keepout
			(tracks not_allowed)
			(vias allowed)
			(pads allowed)
			(copperpour not_allowed)
			(footprints allowed)
		)
		(placement
			(enabled no)
			(sheetname "")
		)
		(fill
			(thermal_gap 0.5)
			(thermal_bridge_width 0.5)
			(island_removal_mode 0)
		)
		(polygon
			(pts
				(arc
					(start 416.34791 -142.551912)
					(mid 416.362789 -142.515991)
					(end 416.39871 -142.501112)
				)
				(arc
					(start 417.57981 -142.501112)
					(mid 417.615731 -142.515991)
					(end 417.63061 -142.551912)
				)
				(arc
					(start 417.63061 -143.55826)
					(mid 417.615731 -143.594181)
					(end 417.57981 -143.60906)
				)
				(arc
					(start 416.39871 -143.60906)
					(mid 416.362789 -143.594181)
					(end 416.34791 -143.55826)
				)
			)
		)
	)
	(zone
		(layer "In1.Cu")
		(hatch none 0.5)
		(connect_pads
			(clearance 0)
		)
		(min_thickness 0.25)
		(keepout
			(tracks not_allowed)
			(vias allowed)
			(pads allowed)
			(copperpour not_allowed)
			(footprints allowed)
		)
		(placement
			(enabled no)
			(sheetname "")
		)
		(fill
			(thermal_gap 0.5)
			(thermal_bridge_width 0.5)
			(island_removal_mode 0)
		)
		(polygon
			(pts
				(arc
					(start 133.459474 -343.533222)
					(mid 133.423553 -343.548101)
					(end 133.408674 -343.584022)
				)
				(arc
					(start 133.408674 -344.320622)
					(mid 133.423553 -344.356543)
					(end 133.459474 -344.371422)
				)
				(xy 133.703314 -344.371422) (xy 134.057644 -344.139012) (xy 134.413244 -344.371422)
				(arc
					(start 134.655814 -344.371422)
					(mid 134.691735 -344.356543)
					(end 134.706614 -344.320622)
				)
				(arc
					(start 134.706614 -343.584022)
					(mid 134.691735 -343.548101)
					(end 134.655814 -343.533222)
				)
				(xy 134.413244 -343.533222) (xy 134.056374 -343.765632) (xy 133.702044 -343.533222)
			)
		)
	)
	(zone
		(layer "In1.Cu")
		(hatch none 0.5)
		(connect_pads
			(clearance 0)
		)
		(min_thickness 0.25)
		(keepout
			(tracks not_allowed)
			(vias allowed)
			(pads allowed)
			(copperpour not_allowed)
			(footprints allowed)
		)
		(placement
			(enabled no)
			(sheetname "")
		)
		(fill
			(thermal_gap 0.5)
			(thermal_bridge_width 0.5)
			(island_removal_mode 0)
		)
		(polygon
			(pts
				(arc
					(start 311.80024 -123.32462)
					(mid 311.815119 -123.360541)
					(end 311.85104 -123.37542)
				)
				(arc
					(start 312.58764 -123.37542)
					(mid 312.623561 -123.360541)
					(end 312.63844 -123.32462)
				)
				(xy 312.63844 -123.08078) (xy 312.40603 -122.72645) (xy 312.63844 -122.37085)
				(arc
					(start 312.63844 -122.12828)
					(mid 312.623561 -122.092359)
					(end 312.58764 -122.07748)
				)
				(arc
					(start 311.85104 -122.07748)
					(mid 311.815119 -122.092359)
					(end 311.80024 -122.12828)
				)
				(xy 311.80024 -122.37085) (xy 312.03265 -122.72772) (xy 311.80024 -123.08205)
			)
		)
	)
	(zone
		(layer "In1.Cu")
		(hatch none 0.5)
		(connect_pads
			(clearance 0)
		)
		(min_thickness 0.25)
		(keepout
			(tracks not_allowed)
			(vias allowed)
			(pads allowed)
			(copperpour not_allowed)
			(footprints allowed)
		)
		(placement
			(enabled no)
			(sheetname "")
		)
		(fill
			(thermal_gap 0.5)
			(thermal_bridge_width 0.5)
			(island_removal_mode 0)
		)
		(polygon
			(pts
				(arc
					(start 19.167094 -343.533222)
					(mid 19.131173 -343.548101)
					(end 19.116294 -343.584022)
				)
				(arc
					(start 19.116294 -344.320622)
					(mid 19.131173 -344.356543)
					(end 19.167094 -344.371422)
				)
				(xy 19.410934 -344.371422) (xy 19.765264 -344.139012) (xy 20.120864 -344.371422)
				(arc
					(start 20.363434 -344.371422)
					(mid 20.399355 -344.356543)
					(end 20.414234 -344.320622)
				)
				(arc
					(start 20.414234 -343.584022)
					(mid 20.399355 -343.548101)
					(end 20.363434 -343.533222)
				)
				(xy 20.120864 -343.533222) (xy 19.763994 -343.765632) (xy 19.409664 -343.533222)
			)
		)
	)
	(zone
		(layer "In1.Cu")
		(hatch none 0.5)
		(connect_pads
			(clearance 0)
		)
		(min_thickness 0.25)
		(keepout
			(tracks not_allowed)
			(vias allowed)
			(pads allowed)
			(copperpour not_allowed)
			(footprints allowed)
		)
		(placement
			(enabled no)
			(sheetname "")
		)
		(fill
			(thermal_gap 0.5)
			(thermal_bridge_width 0.5)
			(island_removal_mode 0)
		)
		(polygon
			(pts
				(arc
					(start 184.147714 -144.351756)
					(mid 184.162593 -144.315835)
					(end 184.198514 -144.300956)
				)
				(arc
					(start 185.379614 -144.300956)
					(mid 185.415535 -144.315835)
					(end 185.430414 -144.351756)
				)
				(arc
					(start 185.430414 -145.358104)
					(mid 185.415535 -145.394025)
					(end 185.379614 -145.408904)
				)
				(arc
					(start 184.198514 -145.408904)
					(mid 184.162593 -145.394025)
					(end 184.147714 -145.358104)
				)
			)
		)
	)
	(zone
		(layer "In1.Cu")
		(hatch none 0.5)
		(connect_pads
			(clearance 0)
		)
		(min_thickness 0.25)
		(keepout
			(tracks not_allowed)
			(vias allowed)
			(pads allowed)
			(copperpour not_allowed)
			(footprints allowed)
		)
		(placement
			(enabled no)
			(sheetname "")
		)
		(fill
			(thermal_gap 0.5)
			(thermal_bridge_width 0.5)
			(island_removal_mode 0)
		)
		(polygon
			(pts
				(arc
					(start 38.861492 -111.143288)
					(mid 38.876371 -111.179209)
					(end 38.912292 -111.194088)
				)
				(arc
					(start 39.648892 -111.194088)
					(mid 39.684813 -111.179209)
					(end 39.699692 -111.143288)
				)
				(xy 39.699692 -110.899448) (xy 39.467282 -110.545118) (xy 39.699692 -110.189518)
				(arc
					(start 39.699692 -109.946948)
					(mid 39.684813 -109.911027)
					(end 39.648892 -109.896148)
				)
				(arc
					(start 38.912292 -109.896148)
					(mid 38.876371 -109.911027)
					(end 38.861492 -109.946948)
				)
				(xy 38.861492 -110.189518) (xy 39.093902 -110.546388) (xy 38.861492 -110.900718)
			)
		)
	)
	(zone
		(layer "In1.Cu")
		(hatch none 0.5)
		(connect_pads
			(clearance 0)
		)
		(min_thickness 0.25)
		(keepout
			(tracks not_allowed)
			(vias allowed)
			(pads allowed)
			(copperpour not_allowed)
			(footprints allowed)
		)
		(placement
			(enabled no)
			(sheetname "")
		)
		(fill
			(thermal_gap 0.5)
			(thermal_bridge_width 0.5)
			(island_removal_mode 0)
		)
		(polygon
			(pts
				(arc
					(start 204.129894 -33.574228)
					(mid 204.144773 -33.538307)
					(end 204.180694 -33.523428)
				)
				(arc
					(start 205.412594 -33.523428)
					(mid 205.448515 -33.538307)
					(end 205.463394 -33.574228)
				)
				(arc
					(start 205.463394 -34.605976)
					(mid 205.448515 -34.641897)
					(end 205.412594 -34.656776)
				)
				(arc
					(start 204.180694 -34.656776)
					(mid 204.144773 -34.641897)
					(end 204.129894 -34.605976)
				)
			)
		)
	)
	(zone
		(layer "In1.Cu")
		(hatch none 0.5)
		(connect_pads
			(clearance 0)
		)
		(min_thickness 0.25)
		(keepout
			(tracks not_allowed)
			(vias allowed)
			(pads allowed)
			(copperpour not_allowed)
			(footprints allowed)
		)
		(placement
			(enabled no)
			(sheetname "")
		)
		(fill
			(thermal_gap 0.5)
			(thermal_bridge_width 0.5)
			(island_removal_mode 0)
		)
		(polygon
			(pts
				(arc
					(start 189.967108 -121.438162)
					(mid 189.952229 -121.474083)
					(end 189.916308 -121.488962)
				)
				(arc
					(start 188.735208 -121.488962)
					(mid 188.699287 -121.474083)
					(end 188.684408 -121.438162)
				)
				(arc
					(start 188.684408 -120.431814)
					(mid 188.699287 -120.395893)
					(end 188.735208 -120.381014)
				)
				(arc
					(start 189.916308 -120.381014)
					(mid 189.952229 -120.395893)
					(end 189.967108 -120.431814)
				)
			)
		)
	)
	(zone
		(layer "In1.Cu")
		(hatch none 0.5)
		(connect_pads
			(clearance 0)
		)
		(min_thickness 0.25)
		(keepout
			(tracks not_allowed)
			(vias allowed)
			(pads allowed)
			(copperpour not_allowed)
			(footprints allowed)
		)
		(placement
			(enabled no)
			(sheetname "")
		)
		(fill
			(thermal_gap 0.5)
			(thermal_bridge_width 0.5)
			(island_removal_mode 0)
		)
		(polygon
			(pts
				(arc
					(start 154.961336 -122.0597)
					(mid 154.976215 -122.095621)
					(end 155.012136 -122.1105)
				)
				(arc
					(start 155.748736 -122.1105)
					(mid 155.784657 -122.095621)
					(end 155.799536 -122.0597)
				)
				(xy 155.799536 -121.81586) (xy 155.567126 -121.46153) (xy 155.799536 -121.10593)
				(arc
					(start 155.799536 -120.86336)
					(mid 155.784657 -120.827439)
					(end 155.748736 -120.81256)
				)
				(arc
					(start 155.012136 -120.81256)
					(mid 154.976215 -120.827439)
					(end 154.961336 -120.86336)
				)
				(xy 154.961336 -121.10593) (xy 155.193746 -121.4628) (xy 154.961336 -121.81713)
			)
		)
	)
	(zone
		(layer "In1.Cu")
		(hatch none 0.5)
		(connect_pads
			(clearance 0)
		)
		(min_thickness 0.25)
		(keepout
			(tracks not_allowed)
			(vias allowed)
			(pads allowed)
			(copperpour not_allowed)
			(footprints allowed)
		)
		(placement
			(enabled no)
			(sheetname "")
		)
		(fill
			(thermal_gap 0.5)
			(thermal_bridge_width 0.5)
			(island_removal_mode 0)
		)
		(polygon
			(pts
				(arc
					(start 427.900338 -150.844504)
					(mid 427.915217 -150.880425)
					(end 427.951138 -150.895304)
				)
				(arc
					(start 428.687738 -150.895304)
					(mid 428.723659 -150.880425)
					(end 428.738538 -150.844504)
				)
				(xy 428.738538 -150.600664) (xy 428.506128 -150.246334) (xy 428.738538 -149.890734)
				(arc
					(start 428.738538 -149.648164)
					(mid 428.723659 -149.612243)
					(end 428.687738 -149.597364)
				)
				(arc
					(start 427.951138 -149.597364)
					(mid 427.915217 -149.612243)
					(end 427.900338 -149.648164)
				)
				(xy 427.900338 -149.890734) (xy 428.132748 -150.247604) (xy 427.900338 -150.601934)
			)
		)
	)
	(zone
		(layer "In1.Cu")
		(hatch none 0.5)
		(connect_pads
			(clearance 0)
		)
		(min_thickness 0.25)
		(keepout
			(tracks not_allowed)
			(vias allowed)
			(pads allowed)
			(copperpour not_allowed)
			(footprints allowed)
		)
		(placement
			(enabled no)
			(sheetname "")
		)
		(fill
			(thermal_gap 0.5)
			(thermal_bridge_width 0.5)
			(island_removal_mode 0)
		)
		(polygon
			(pts
				(arc
					(start 56.453786 -367.487708)
					(mid 56.438907 -367.451787)
					(end 56.402986 -367.436908)
				)
				(arc
					(start 55.666386 -367.436908)
					(mid 55.630465 -367.451787)
					(end 55.615586 -367.487708)
				)
				(xy 55.615586 -367.731548) (xy 55.847996 -368.085878) (xy 55.615586 -368.441478)
				(arc
					(start 55.615586 -368.684048)
					(mid 55.630465 -368.719969)
					(end 55.666386 -368.734848)
				)
				(arc
					(start 56.402986 -368.734848)
					(mid 56.438907 -368.719969)
					(end 56.453786 -368.684048)
				)
				(xy 56.453786 -368.441478) (xy 56.221376 -368.084608) (xy 56.453786 -367.730278)
			)
		)
	)
	(zone
		(layer "In1.Cu")
		(hatch none 0.5)
		(connect_pads
			(clearance 0)
		)
		(min_thickness 0.25)
		(keepout
			(tracks not_allowed)
			(vias allowed)
			(pads allowed)
			(copperpour not_allowed)
			(footprints allowed)
		)
		(placement
			(enabled no)
			(sheetname "")
		)
		(fill
			(thermal_gap 0.5)
			(thermal_bridge_width 0.5)
			(island_removal_mode 0)
		)
		(polygon
			(pts
				(arc
					(start 394.315442 -34.68624)
					(mid 394.330321 -34.722161)
					(end 394.366242 -34.73704)
				)
				(arc
					(start 395.102842 -34.73704)
					(mid 395.138763 -34.722161)
					(end 395.153642 -34.68624)
				)
				(xy 395.153642 -34.4424) (xy 394.921232 -34.08807) (xy 395.153642 -33.73247)
				(arc
					(start 395.153642 -33.4899)
					(mid 395.138763 -33.453979)
					(end 395.102842 -33.4391)
				)
				(arc
					(start 394.366242 -33.4391)
					(mid 394.330321 -33.453979)
					(end 394.315442 -33.4899)
				)
				(xy 394.315442 -33.73247) (xy 394.547852 -34.08934) (xy 394.315442 -34.44367)
			)
		)
	)
	(zone
		(layer "In1.Cu")
		(hatch none 0.5)
		(connect_pads
			(clearance 0)
		)
		(min_thickness 0.25)
		(keepout
			(tracks not_allowed)
			(vias allowed)
			(pads allowed)
			(copperpour not_allowed)
			(footprints allowed)
		)
		(placement
			(enabled no)
			(sheetname "")
		)
		(fill
			(thermal_gap 0.5)
			(thermal_bridge_width 0.5)
			(island_removal_mode 0)
		)
		(polygon
			(pts
				(arc
					(start 248.099834 -29.205936)
					(mid 248.084955 -29.241857)
					(end 248.049034 -29.256736)
				)
				(arc
					(start 246.817134 -29.256736)
					(mid 246.781213 -29.241857)
					(end 246.766334 -29.205936)
				)
				(arc
					(start 246.766334 -28.174188)
					(mid 246.781213 -28.138267)
					(end 246.817134 -28.123388)
				)
				(arc
					(start 248.049034 -28.123388)
					(mid 248.084955 -28.138267)
					(end 248.099834 -28.174188)
				)
			)
		)
	)
	(zone
		(layer "In1.Cu")
		(hatch none 0.5)
		(connect_pads
			(clearance 0)
		)
		(min_thickness 0.25)
		(keepout
			(tracks not_allowed)
			(vias allowed)
			(pads allowed)
			(copperpour not_allowed)
			(footprints allowed)
		)
		(placement
			(enabled no)
			(sheetname "")
		)
		(fill
			(thermal_gap 0.5)
			(thermal_bridge_width 0.5)
			(island_removal_mode 0)
		)
		(polygon
			(pts
				(arc
					(start 46.015402 -34.68624)
					(mid 46.030281 -34.722161)
					(end 46.066202 -34.73704)
				)
				(arc
					(start 46.802802 -34.73704)
					(mid 46.838723 -34.722161)
					(end 46.853602 -34.68624)
				)
				(xy 46.853602 -34.4424) (xy 46.621192 -34.08807) (xy 46.853602 -33.73247)
				(arc
					(start 46.853602 -33.4899)
					(mid 46.838723 -33.453979)
					(end 46.802802 -33.4391)
				)
				(arc
					(start 46.066202 -33.4391)
					(mid 46.030281 -33.453979)
					(end 46.015402 -33.4899)
				)
				(xy 46.015402 -33.73247) (xy 46.247812 -34.08934) (xy 46.015402 -34.44367)
			)
		)
	)
	(zone
		(layer "In1.Cu")
		(hatch none 0.5)
		(connect_pads
			(clearance 0)
		)
		(min_thickness 0.25)
		(keepout
			(tracks not_allowed)
			(vias allowed)
			(pads allowed)
			(copperpour not_allowed)
			(footprints allowed)
		)
		(placement
			(enabled no)
			(sheetname "")
		)
		(fill
			(thermal_gap 0.5)
			(thermal_bridge_width 0.5)
			(island_removal_mode 0)
		)
		(polygon
			(pts
				(arc
					(start 301.573184 -32.879538)
					(mid 301.588063 -32.915459)
					(end 301.623984 -32.930338)
				)
				(arc
					(start 302.360584 -32.930338)
					(mid 302.396505 -32.915459)
					(end 302.411384 -32.879538)
				)
				(xy 302.411384 -32.635698) (xy 302.178974 -32.281368) (xy 302.411384 -31.925768)
				(arc
					(start 302.411384 -31.683198)
					(mid 302.396505 -31.647277)
					(end 302.360584 -31.632398)
				)
				(arc
					(start 301.623984 -31.632398)
					(mid 301.588063 -31.647277)
					(end 301.573184 -31.683198)
				)
				(xy 301.573184 -31.925768) (xy 301.805594 -32.282638) (xy 301.573184 -32.636968)
			)
		)
	)
	(zone
		(layer "In1.Cu")
		(hatch none 0.5)
		(connect_pads
			(clearance 0)
		)
		(min_thickness 0.25)
		(keepout
			(tracks not_allowed)
			(vias allowed)
			(pads allowed)
			(copperpour not_allowed)
			(footprints allowed)
		)
		(placement
			(enabled no)
			(sheetname "")
		)
		(fill
			(thermal_gap 0.5)
			(thermal_bridge_width 0.5)
			(island_removal_mode 0)
		)
		(polygon
			(pts
				(arc
					(start 365.673386 -32.879538)
					(mid 365.688265 -32.915459)
					(end 365.724186 -32.930338)
				)
				(arc
					(start 366.460786 -32.930338)
					(mid 366.496707 -32.915459)
					(end 366.511586 -32.879538)
				)
				(xy 366.511586 -32.635698) (xy 366.279176 -32.281368) (xy 366.511586 -31.925768)
				(arc
					(start 366.511586 -31.683198)
					(mid 366.496707 -31.647277)
					(end 366.460786 -31.632398)
				)
				(arc
					(start 365.724186 -31.632398)
					(mid 365.688265 -31.647277)
					(end 365.673386 -31.683198)
				)
				(xy 365.673386 -31.925768) (xy 365.905796 -32.282638) (xy 365.673386 -32.636968)
			)
		)
	)
	(zone
		(layer "In1.Cu")
		(hatch none 0.5)
		(connect_pads
			(clearance 0)
		)
		(min_thickness 0.25)
		(keepout
			(tracks not_allowed)
			(vias allowed)
			(pads allowed)
			(copperpour not_allowed)
			(footprints allowed)
		)
		(placement
			(enabled no)
			(sheetname "")
		)
		(fill
			(thermal_gap 0.5)
			(thermal_bridge_width 0.5)
			(island_removal_mode 0)
		)
		(polygon
			(pts
				(arc
					(start 277.058628 -349.679514)
					(mid 277.022707 -349.694393)
					(end 277.007828 -349.730314)
				)
				(arc
					(start 277.007828 -350.466914)
					(mid 277.022707 -350.502835)
					(end 277.058628 -350.517714)
				)
				(xy 277.302468 -350.517714) (xy 277.656798 -350.285304) (xy 278.012398 -350.517714)
				(arc
					(start 278.254968 -350.517714)
					(mid 278.290889 -350.502835)
					(end 278.305768 -350.466914)
				)
				(arc
					(start 278.305768 -349.730314)
					(mid 278.290889 -349.694393)
					(end 278.254968 -349.679514)
				)
				(xy 278.012398 -349.679514) (xy 277.655528 -349.911924) (xy 277.301198 -349.679514)
			)
		)
	)
	(zone
		(layer "In1.Cu")
		(hatch none 0.5)
		(connect_pads
			(clearance 0)
		)
		(min_thickness 0.25)
		(keepout
			(tracks not_allowed)
			(vias allowed)
			(pads allowed)
			(copperpour not_allowed)
			(footprints allowed)
		)
		(placement
			(enabled no)
			(sheetname "")
		)
		(fill
			(thermal_gap 0.5)
			(thermal_bridge_width 0.5)
			(island_removal_mode 0)
		)
		(polygon
			(pts
				(arc
					(start 45.432726 -132.162042)
					(mid 45.447605 -132.126121)
					(end 45.483526 -132.111242)
				)
				(arc
					(start 46.664626 -132.111242)
					(mid 46.700547 -132.126121)
					(end 46.715426 -132.162042)
				)
				(arc
					(start 46.715426 -133.16839)
					(mid 46.700547 -133.204311)
					(end 46.664626 -133.21919)
				)
				(arc
					(start 45.483526 -133.21919)
					(mid 45.447605 -133.204311)
					(end 45.432726 -133.16839)
				)
			)
		)
	)
	(zone
		(layer "In1.Cu")
		(hatch none 0.5)
		(connect_pads
			(clearance 0)
		)
		(min_thickness 0.25)
		(keepout
			(tracks not_allowed)
			(vias allowed)
			(pads allowed)
			(copperpour not_allowed)
			(footprints allowed)
		)
		(placement
			(enabled no)
			(sheetname "")
		)
		(fill
			(thermal_gap 0.5)
			(thermal_bridge_width 0.5)
			(island_removal_mode 0)
		)
		(polygon
			(pts
				(arc
					(start 51.25212 -100.248212)
					(mid 51.237241 -100.284133)
					(end 51.20132 -100.299012)
				)
				(arc
					(start 50.02022 -100.299012)
					(mid 49.984299 -100.284133)
					(end 49.96942 -100.248212)
				)
				(arc
					(start 49.96942 -99.241864)
					(mid 49.984299 -99.205943)
					(end 50.02022 -99.191064)
				)
				(arc
					(start 51.20132 -99.191064)
					(mid 51.237241 -99.205943)
					(end 51.25212 -99.241864)
				)
			)
		)
	)
	(zone
		(layer "In1.Cu")
		(hatch none 0.5)
		(connect_pads
			(clearance 0)
		)
		(min_thickness 0.25)
		(keepout
			(tracks not_allowed)
			(vias allowed)
			(pads allowed)
			(copperpour not_allowed)
			(footprints allowed)
		)
		(placement
			(enabled no)
			(sheetname "")
		)
		(fill
			(thermal_gap 0.5)
			(thermal_bridge_width 0.5)
			(island_removal_mode 0)
		)
		(polygon
			(pts
				(arc
					(start 62.029848 -31.77413)
					(mid 62.044727 -31.738209)
					(end 62.080648 -31.72333)
				)
				(arc
					(start 63.312548 -31.72333)
					(mid 63.348469 -31.738209)
					(end 63.363348 -31.77413)
				)
				(arc
					(start 63.363348 -32.805878)
					(mid 63.348469 -32.841799)
					(end 63.312548 -32.856678)
				)
				(arc
					(start 62.080648 -32.856678)
					(mid 62.044727 -32.841799)
					(end 62.029848 -32.805878)
				)
			)
		)
	)
	(zone
		(layer "In1.Cu")
		(hatch none 0.5)
		(connect_pads
			(clearance 0)
		)
		(min_thickness 0.25)
		(keepout
			(tracks not_allowed)
			(vias allowed)
			(pads allowed)
			(copperpour not_allowed)
			(footprints allowed)
		)
		(placement
			(enabled no)
			(sheetname "")
		)
		(fill
			(thermal_gap 0.5)
			(thermal_bridge_width 0.5)
			(island_removal_mode 0)
		)
		(polygon
			(pts
				(arc
					(start 300.247812 -147.951952)
					(mid 300.262691 -147.916031)
					(end 300.298612 -147.901152)
				)
				(arc
					(start 301.479712 -147.901152)
					(mid 301.515633 -147.916031)
					(end 301.530512 -147.951952)
				)
				(arc
					(start 301.530512 -148.9583)
					(mid 301.515633 -148.994221)
					(end 301.479712 -149.0091)
				)
				(arc
					(start 300.298612 -149.0091)
					(mid 300.262691 -148.994221)
					(end 300.247812 -148.9583)
				)
			)
		)
	)
	(zone
		(layer "In1.Cu")
		(hatch none 0.5)
		(connect_pads
			(clearance 0)
		)
		(min_thickness 0.25)
		(keepout
			(tracks not_allowed)
			(vias allowed)
			(pads allowed)
			(copperpour not_allowed)
			(footprints allowed)
		)
		(placement
			(enabled no)
			(sheetname "")
		)
		(fill
			(thermal_gap 0.5)
			(thermal_bridge_width 0.5)
			(island_removal_mode 0)
		)
		(polygon
			(pts
				(arc
					(start 283.452062 -134.968488)
					(mid 283.437183 -135.004409)
					(end 283.401262 -135.019288)
				)
				(arc
					(start 282.220162 -135.019288)
					(mid 282.184241 -135.004409)
					(end 282.169362 -134.968488)
				)
				(arc
					(start 282.169362 -133.96214)
					(mid 282.184241 -133.926219)
					(end 282.220162 -133.91134)
				)
				(arc
					(start 283.401262 -133.91134)
					(mid 283.437183 -133.926219)
					(end 283.452062 -133.96214)
				)
			)
		)
	)
	(zone
		(layer "In1.Cu")
		(hatch none 0.5)
		(connect_pads
			(clearance 0)
		)
		(min_thickness 0.25)
		(keepout
			(tracks not_allowed)
			(vias allowed)
			(pads allowed)
			(copperpour not_allowed)
			(footprints allowed)
		)
		(placement
			(enabled no)
			(sheetname "")
		)
		(fill
			(thermal_gap 0.5)
			(thermal_bridge_width 0.5)
			(island_removal_mode 0)
		)
		(polygon
			(pts
				(arc
					(start 392.785346 -355.825806)
					(mid 392.749425 -355.840685)
					(end 392.734546 -355.876606)
				)
				(arc
					(start 392.734546 -356.613206)
					(mid 392.749425 -356.649127)
					(end 392.785346 -356.664006)
				)
				(xy 393.029186 -356.664006) (xy 393.383516 -356.431596) (xy 393.739116 -356.664006)
				(arc
					(start 393.981686 -356.664006)
					(mid 394.017607 -356.649127)
					(end 394.032486 -356.613206)
				)
				(arc
					(start 394.032486 -355.876606)
					(mid 394.017607 -355.840685)
					(end 393.981686 -355.825806)
				)
				(xy 393.739116 -355.825806) (xy 393.382246 -356.058216) (xy 393.027916 -355.825806)
			)
		)
	)
	(zone
		(layer "In1.Cu")
		(hatch none 0.5)
		(connect_pads
			(clearance 0)
		)
		(min_thickness 0.25)
		(keepout
			(tracks not_allowed)
			(vias allowed)
			(pads allowed)
			(copperpour not_allowed)
			(footprints allowed)
		)
		(placement
			(enabled no)
			(sheetname "")
		)
		(fill
			(thermal_gap 0.5)
			(thermal_bridge_width 0.5)
			(island_removal_mode 0)
		)
		(polygon
			(pts
				(arc
					(start 36.828984 -102.149656)
					(mid 36.843863 -102.185577)
					(end 36.879784 -102.200456)
				)
				(arc
					(start 37.616384 -102.200456)
					(mid 37.652305 -102.185577)
					(end 37.667184 -102.149656)
				)
				(xy 37.667184 -101.905816) (xy 37.434774 -101.551486) (xy 37.667184 -101.195886)
				(arc
					(start 37.667184 -100.953316)
					(mid 37.652305 -100.917395)
					(end 37.616384 -100.902516)
				)
				(arc
					(start 36.879784 -100.902516)
					(mid 36.843863 -100.917395)
					(end 36.828984 -100.953316)
				)
				(xy 36.828984 -101.195886) (xy 37.061394 -101.552756) (xy 36.828984 -101.907086)
			)
		)
	)
	(zone
		(layer "In1.Cu")
		(hatch none 0.5)
		(connect_pads
			(clearance 0)
		)
		(min_thickness 0.25)
		(keepout
			(tracks not_allowed)
			(vias allowed)
			(pads allowed)
			(copperpour not_allowed)
			(footprints allowed)
		)
		(placement
			(enabled no)
			(sheetname "")
		)
		(fill
			(thermal_gap 0.5)
			(thermal_bridge_width 0.5)
			(island_removal_mode 0)
		)
		(polygon
			(pts
				(arc
					(start 273.949668 -349.679514)
					(mid 273.913747 -349.694393)
					(end 273.898868 -349.730314)
				)
				(arc
					(start 273.898868 -350.466914)
					(mid 273.913747 -350.502835)
					(end 273.949668 -350.517714)
				)
				(xy 274.193508 -350.517714) (xy 274.547838 -350.285304) (xy 274.903438 -350.517714)
				(arc
					(start 275.146008 -350.517714)
					(mid 275.181929 -350.502835)
					(end 275.196808 -350.466914)
				)
				(arc
					(start 275.196808 -349.730314)
					(mid 275.181929 -349.694393)
					(end 275.146008 -349.679514)
				)
				(xy 274.903438 -349.679514) (xy 274.546568 -349.911924) (xy 274.192238 -349.679514)
			)
		)
	)
	(zone
		(layer "In1.Cu")
		(hatch none 0.5)
		(connect_pads
			(clearance 0)
		)
		(min_thickness 0.25)
		(keepout
			(tracks not_allowed)
			(vias allowed)
			(pads allowed)
			(copperpour not_allowed)
			(footprints allowed)
		)
		(placement
			(enabled no)
			(sheetname "")
		)
		(fill
			(thermal_gap 0.5)
			(thermal_bridge_width 0.5)
			(island_removal_mode 0)
		)
		(polygon
			(pts
				(arc
					(start 28.493974 -349.679514)
					(mid 28.458053 -349.694393)
					(end 28.443174 -349.730314)
				)
				(arc
					(start 28.443174 -350.466914)
					(mid 28.458053 -350.502835)
					(end 28.493974 -350.517714)
				)
				(xy 28.737814 -350.517714) (xy 29.092144 -350.285304) (xy 29.447744 -350.517714)
				(arc
					(start 29.690314 -350.517714)
					(mid 29.726235 -350.502835)
					(end 29.741114 -350.466914)
				)
				(arc
					(start 29.741114 -349.730314)
					(mid 29.726235 -349.694393)
					(end 29.690314 -349.679514)
				)
				(xy 29.447744 -349.679514) (xy 29.090874 -349.911924) (xy 28.736544 -349.679514)
			)
		)
	)
	(zone
		(layer "In1.Cu")
		(hatch none 0.5)
		(connect_pads
			(clearance 0)
		)
		(min_thickness 0.25)
		(keepout
			(tracks not_allowed)
			(vias allowed)
			(pads allowed)
			(copperpour not_allowed)
			(footprints allowed)
		)
		(placement
			(enabled no)
			(sheetname "")
		)
		(fill
			(thermal_gap 0.5)
			(thermal_bridge_width 0.5)
			(island_removal_mode 0)
		)
		(polygon
			(pts
				(arc
					(start 93.899736 -29.205936)
					(mid 93.884857 -29.241857)
					(end 93.848936 -29.256736)
				)
				(arc
					(start 92.617036 -29.256736)
					(mid 92.581115 -29.241857)
					(end 92.566236 -29.205936)
				)
				(arc
					(start 92.566236 -28.174188)
					(mid 92.581115 -28.138267)
					(end 92.617036 -28.123388)
				)
				(arc
					(start 93.848936 -28.123388)
					(mid 93.884857 -28.138267)
					(end 93.899736 -28.174188)
				)
			)
		)
	)
	(zone
		(layer "In1.Cu")
		(hatch none 0.5)
		(connect_pads
			(clearance 0)
		)
		(min_thickness 0.25)
		(keepout
			(tracks not_allowed)
			(vias allowed)
			(pads allowed)
			(copperpour not_allowed)
			(footprints allowed)
		)
		(placement
			(enabled no)
			(sheetname "")
		)
		(fill
			(thermal_gap 0.5)
			(thermal_bridge_width 0.5)
			(island_removal_mode 0)
		)
		(polygon
			(pts
				(arc
					(start 242.084352 -228.773736)
					(mid 242.069473 -228.809657)
					(end 242.033552 -228.824536)
				)
				(arc
					(start 241.626898 -228.824536)
					(mid 241.590977 -228.809657)
					(end 241.576098 -228.773736)
				)
				(arc
					(start 241.576098 -228.3714)
					(mid 241.590977 -228.335479)
					(end 241.626898 -228.3206)
				)
				(arc
					(start 242.033552 -228.3206)
					(mid 242.069473 -228.335479)
					(end 242.084352 -228.3714)
				)
			)
		)
	)
	(zone
		(layer "In1.Cu")
		(hatch none 0.5)
		(connect_pads
			(clearance 0)
		)
		(min_thickness 0.25)
		(keepout
			(tracks not_allowed)
			(vias allowed)
			(pads allowed)
			(copperpour not_allowed)
			(footprints allowed)
		)
		(placement
			(enabled no)
			(sheetname "")
		)
		(fill
			(thermal_gap 0.5)
			(thermal_bridge_width 0.5)
			(island_removal_mode 0)
		)
		(polygon
			(pts
				(arc
					(start 415.347658 -355.825806)
					(mid 415.311737 -355.840685)
					(end 415.296858 -355.876606)
				)
				(arc
					(start 415.296858 -356.613206)
					(mid 415.311737 -356.649127)
					(end 415.347658 -356.664006)
				)
				(xy 415.591498 -356.664006) (xy 415.945828 -356.431596) (xy 416.301428 -356.664006)
				(arc
					(start 416.543998 -356.664006)
					(mid 416.579919 -356.649127)
					(end 416.594798 -356.613206)
				)
				(arc
					(start 416.594798 -355.876606)
					(mid 416.579919 -355.840685)
					(end 416.543998 -355.825806)
				)
				(xy 416.301428 -355.825806) (xy 415.944558 -356.058216) (xy 415.590228 -355.825806)
			)
		)
	)
	(zone
		(layer "In1.Cu")
		(hatch none 0.5)
		(connect_pads
			(clearance 0)
		)
		(min_thickness 0.25)
		(keepout
			(tracks not_allowed)
			(vias allowed)
			(pads allowed)
			(copperpour not_allowed)
			(footprints allowed)
		)
		(placement
			(enabled no)
			(sheetname "")
		)
		(fill
			(thermal_gap 0.5)
			(thermal_bridge_width 0.5)
			(island_removal_mode 0)
		)
		(polygon
			(pts
				(arc
					(start 239.493298 -85.424518)
					(mid 239.530495 -85.334715)
					(end 239.620298 -85.297518)
				)
				(arc
					(start 239.823498 -85.297518)
					(mid 239.913301 -85.334715)
					(end 239.950498 -85.424518)
				)
				(arc
					(start 239.950498 -85.678518)
					(mid 239.913301 -85.768321)
					(end 239.823498 -85.805518)
				)
				(arc
					(start 239.620298 -85.805518)
					(mid 239.530495 -85.768321)
					(end 239.493298 -85.678518)
				)
			)
		)
	)
	(zone
		(layer "In1.Cu")
		(hatch none 0.5)
		(connect_pads
			(clearance 0)
		)
		(min_thickness 0.25)
		(keepout
			(tracks not_allowed)
			(vias allowed)
			(pads allowed)
			(copperpour not_allowed)
			(footprints allowed)
		)
		(placement
			(enabled no)
			(sheetname "")
		)
		(fill
			(thermal_gap 0.5)
			(thermal_bridge_width 0.5)
			(island_removal_mode 0)
		)
		(polygon
			(pts
				(arc
					(start 422.167304 -147.158202)
					(mid 422.152425 -147.194123)
					(end 422.116504 -147.209002)
				)
				(arc
					(start 420.935404 -147.209002)
					(mid 420.899483 -147.194123)
					(end 420.884604 -147.158202)
				)
				(arc
					(start 420.884604 -146.151854)
					(mid 420.899483 -146.115933)
					(end 420.935404 -146.101054)
				)
				(arc
					(start 422.116504 -146.101054)
					(mid 422.152425 -146.115933)
					(end 422.167304 -146.151854)
				)
			)
		)
	)
	(zone
		(layer "In1.Cu")
		(hatch none 0.5)
		(connect_pads
			(clearance 0)
		)
		(min_thickness 0.25)
		(keepout
			(tracks not_allowed)
			(vias allowed)
			(pads allowed)
			(copperpour not_allowed)
			(footprints allowed)
		)
		(placement
			(enabled no)
			(sheetname "")
		)
		(fill
			(thermal_gap 0.5)
			(thermal_bridge_width 0.5)
			(island_removal_mode 0)
		)
		(polygon
			(pts
				(arc
					(start 436.329836 -29.974286)
					(mid 436.344715 -29.938365)
					(end 436.380636 -29.923486)
				)
				(arc
					(start 437.612536 -29.923486)
					(mid 437.648457 -29.938365)
					(end 437.663336 -29.974286)
				)
				(arc
					(start 437.663336 -31.006034)
					(mid 437.648457 -31.041955)
					(end 437.612536 -31.056834)
				)
				(arc
					(start 436.380636 -31.056834)
					(mid 436.344715 -31.041955)
					(end 436.329836 -31.006034)
				)
			)
		)
	)
	(zone
		(layer "In1.Cu")
		(hatch none 0.5)
		(connect_pads
			(clearance 0)
		)
		(min_thickness 0.25)
		(keepout
			(tracks not_allowed)
			(vias allowed)
			(pads allowed)
			(copperpour not_allowed)
			(footprints allowed)
		)
		(placement
			(enabled no)
			(sheetname "")
		)
		(fill
			(thermal_gap 0.5)
			(thermal_bridge_width 0.5)
			(island_removal_mode 0)
		)
		(polygon
			(pts
				(arc
					(start 300.247812 -149.751796)
					(mid 300.262691 -149.715875)
					(end 300.298612 -149.700996)
				)
				(arc
					(start 301.479712 -149.700996)
					(mid 301.515633 -149.715875)
					(end 301.530512 -149.751796)
				)
				(arc
					(start 301.530512 -150.758144)
					(mid 301.515633 -150.794065)
					(end 301.479712 -150.808944)
				)
				(arc
					(start 300.298612 -150.808944)
					(mid 300.262691 -150.794065)
					(end 300.247812 -150.758144)
				)
			)
		)
	)
	(zone
		(layer "In1.Cu")
		(hatch none 0.5)
		(connect_pads
			(clearance 0)
		)
		(min_thickness 0.25)
		(keepout
			(tracks not_allowed)
			(vias allowed)
			(pads allowed)
			(copperpour not_allowed)
			(footprints allowed)
		)
		(placement
			(enabled no)
			(sheetname "")
		)
		(fill
			(thermal_gap 0.5)
			(thermal_bridge_width 0.5)
			(island_removal_mode 0)
		)
		(polygon
			(pts
				(arc
					(start 178.129946 -31.77413)
					(mid 178.144825 -31.738209)
					(end 178.180746 -31.72333)
				)
				(arc
					(start 179.412646 -31.72333)
					(mid 179.448567 -31.738209)
					(end 179.463446 -31.77413)
				)
				(arc
					(start 179.463446 -32.805878)
					(mid 179.448567 -32.841799)
					(end 179.412646 -32.856678)
				)
				(arc
					(start 178.180746 -32.856678)
					(mid 178.144825 -32.841799)
					(end 178.129946 -32.805878)
				)
			)
		)
	)
	(zone
		(layer "In1.Cu")
		(hatch none 0.5)
		(connect_pads
			(clearance 0)
		)
		(min_thickness 0.25)
		(keepout
			(tracks not_allowed)
			(vias allowed)
			(pads allowed)
			(copperpour not_allowed)
			(footprints allowed)
		)
		(placement
			(enabled no)
			(sheetname "")
		)
		(fill
			(thermal_gap 0.5)
			(thermal_bridge_width 0.5)
			(island_removal_mode 0)
		)
		(polygon
			(pts
				(arc
					(start 40.929814 -349.679514)
					(mid 40.893893 -349.694393)
					(end 40.879014 -349.730314)
				)
				(arc
					(start 40.879014 -350.466914)
					(mid 40.893893 -350.502835)
					(end 40.929814 -350.517714)
				)
				(xy 41.173654 -350.517714) (xy 41.527984 -350.285304) (xy 41.883584 -350.517714)
				(arc
					(start 42.126154 -350.517714)
					(mid 42.162075 -350.502835)
					(end 42.176954 -350.466914)
				)
				(arc
					(start 42.176954 -349.730314)
					(mid 42.162075 -349.694393)
					(end 42.126154 -349.679514)
				)
				(xy 41.883584 -349.679514) (xy 41.526714 -349.911924) (xy 41.172384 -349.679514)
			)
		)
	)
	(zone
		(layer "In1.Cu")
		(hatch none 0.5)
		(connect_pads
			(clearance 0)
		)
		(min_thickness 0.25)
		(keepout
			(tracks not_allowed)
			(vias allowed)
			(pads allowed)
			(copperpour not_allowed)
			(footprints allowed)
		)
		(placement
			(enabled no)
			(sheetname "")
		)
		(fill
			(thermal_gap 0.5)
			(thermal_bridge_width 0.5)
			(island_removal_mode 0)
		)
		(polygon
			(pts
				(arc
					(start 74.205084 -3.381248)
					(mid 74.138693 -3.480654)
					(end 74.115422 -3.59791)
				)
				(arc
					(start 74.115422 -7.817358)
					(mid 74.138762 -7.934586)
					(end 74.205084 -8.03402)
				)
				(xy 74.2061 -8.035036)
				(arc
					(start 80.74152 -8.035036)
					(mid 80.858951 -8.011718)
					(end 80.958436 -7.94512)
				)
				(arc
					(start 81.005426 -7.89813)
					(mid 81.071769 -7.798697)
					(end 81.095088 -7.681468)
				)
				(arc
					(start 81.095088 -3.582924)
					(mid 81.071649 -3.465558)
					(end 81.005172 -3.366008)
				)
				(arc
					(start 80.958182 -3.319018)
					(mid 80.858702 -3.252387)
					(end 80.741266 -3.229102)
				)
				(arc
					(start 74.48423 -3.229102)
					(mid 74.36681 -3.252458)
					(end 74.267314 -3.319018)
				)
			)
		)
	)
	(zone
		(layer "In1.Cu")
		(hatch none 0.5)
		(connect_pads
			(clearance 0)
		)
		(min_thickness 0.25)
		(keepout
			(tracks not_allowed)
			(vias allowed)
			(pads allowed)
			(copperpour not_allowed)
			(footprints allowed)
		)
		(placement
			(enabled no)
			(sheetname "")
		)
		(fill
			(thermal_gap 0.5)
			(thermal_bridge_width 0.5)
			(island_removal_mode 0)
		)
		(polygon
			(pts
				(arc
					(start 384.519424 -109.349794)
					(mid 384.534303 -109.385715)
					(end 384.570224 -109.400594)
				)
				(arc
					(start 385.306824 -109.400594)
					(mid 385.342745 -109.385715)
					(end 385.357624 -109.349794)
				)
				(xy 385.357624 -109.105954) (xy 385.125214 -108.751624) (xy 385.357624 -108.396024)
				(arc
					(start 385.357624 -108.153454)
					(mid 385.342745 -108.117533)
					(end 385.306824 -108.102654)
				)
				(arc
					(start 384.570224 -108.102654)
					(mid 384.534303 -108.117533)
					(end 384.519424 -108.153454)
				)
				(xy 384.519424 -108.396024) (xy 384.751834 -108.752894) (xy 384.519424 -109.107224)
			)
		)
	)
	(zone
		(layer "In1.Cu")
		(hatch none 0.5)
		(connect_pads
			(clearance 0)
		)
		(min_thickness 0.25)
		(keepout
			(tracks not_allowed)
			(vias allowed)
			(pads allowed)
			(copperpour not_allowed)
			(footprints allowed)
		)
		(placement
			(enabled no)
			(sheetname "")
		)
		(fill
			(thermal_gap 0.5)
			(thermal_bridge_width 0.5)
			(island_removal_mode 0)
		)
		(polygon
			(pts
				(arc
					(start 174.456598 -355.825806)
					(mid 174.420677 -355.840685)
					(end 174.405798 -355.876606)
				)
				(arc
					(start 174.405798 -356.613206)
					(mid 174.420677 -356.649127)
					(end 174.456598 -356.664006)
				)
				(xy 174.700438 -356.664006) (xy 175.054768 -356.431596) (xy 175.410368 -356.664006)
				(arc
					(start 175.652938 -356.664006)
					(mid 175.688859 -356.649127)
					(end 175.703738 -356.613206)
				)
				(arc
					(start 175.703738 -355.876606)
					(mid 175.688859 -355.840685)
					(end 175.652938 -355.825806)
				)
				(xy 175.410368 -355.825806) (xy 175.053498 -356.058216) (xy 174.699168 -355.825806)
			)
		)
	)
	(zone
		(layer "In1.Cu")
		(hatch none 0.5)
		(connect_pads
			(clearance 0)
		)
		(min_thickness 0.25)
		(keepout
			(tracks not_allowed)
			(vias allowed)
			(pads allowed)
			(copperpour not_allowed)
			(footprints allowed)
		)
		(placement
			(enabled no)
			(sheetname "")
		)
		(fill
			(thermal_gap 0.5)
			(thermal_bridge_width 0.5)
			(island_removal_mode 0)
		)
		(polygon
			(pts
				(arc
					(start 214.115396 -31.086044)
					(mid 214.130275 -31.121965)
					(end 214.166196 -31.136844)
				)
				(arc
					(start 214.902796 -31.136844)
					(mid 214.938717 -31.121965)
					(end 214.953596 -31.086044)
				)
				(xy 214.953596 -30.842204) (xy 214.721186 -30.487874) (xy 214.953596 -30.132274)
				(arc
					(start 214.953596 -29.889704)
					(mid 214.938717 -29.853783)
					(end 214.902796 -29.838904)
				)
				(arc
					(start 214.166196 -29.838904)
					(mid 214.130275 -29.853783)
					(end 214.115396 -29.889704)
				)
				(xy 214.115396 -30.132274) (xy 214.347806 -30.489144) (xy 214.115396 -30.843474)
			)
		)
	)
	(zone
		(layer "In1.Cu")
		(hatch none 0.5)
		(connect_pads
			(clearance 0)
		)
		(min_thickness 0.25)
		(keepout
			(tracks not_allowed)
			(vias allowed)
			(pads allowed)
			(copperpour not_allowed)
			(footprints allowed)
		)
		(placement
			(enabled no)
			(sheetname "")
		)
		(fill
			(thermal_gap 0.5)
			(thermal_bridge_width 0.5)
			(island_removal_mode 0)
		)
		(polygon
			(pts
				(arc
					(start 104.644698 -381.096774)
					(mid 104.734501 -381.133971)
					(end 104.771698 -381.223774)
				)
				(arc
					(start 104.771698 -381.424942)
					(mid 104.734501 -381.514745)
					(end 104.644698 -381.551942)
				)
				(arc
					(start 104.390698 -381.551942)
					(mid 104.300895 -381.514745)
					(end 104.263698 -381.424942)
				)
				(arc
					(start 104.263698 -381.223774)
					(mid 104.300895 -381.133971)
					(end 104.390698 -381.096774)
				)
			)
		)
	)
	(zone
		(layer "In1.Cu")
		(hatch none 0.5)
		(connect_pads
			(clearance 0)
		)
		(min_thickness 0.25)
		(keepout
			(tracks not_allowed)
			(vias allowed)
			(pads allowed)
			(copperpour not_allowed)
			(footprints allowed)
		)
		(placement
			(enabled no)
			(sheetname "")
		)
		(fill
			(thermal_gap 0.5)
			(thermal_bridge_width 0.5)
			(island_removal_mode 0)
		)
		(polygon
			(pts
				(arc
					(start 437.110378 -349.679514)
					(mid 437.074457 -349.694393)
					(end 437.059578 -349.730314)
				)
				(arc
					(start 437.059578 -350.466914)
					(mid 437.074457 -350.502835)
					(end 437.110378 -350.517714)
				)
				(xy 437.354218 -350.517714) (xy 437.708548 -350.285304) (xy 438.064148 -350.517714)
				(arc
					(start 438.306718 -350.517714)
					(mid 438.342639 -350.502835)
					(end 438.357518 -350.466914)
				)
				(arc
					(start 438.357518 -349.730314)
					(mid 438.342639 -349.694393)
					(end 438.306718 -349.679514)
				)
				(xy 438.064148 -349.679514) (xy 437.707278 -349.911924) (xy 437.352948 -349.679514)
			)
		)
	)
	(zone
		(layer "In1.Cu")
		(hatch none 0.5)
		(connect_pads
			(clearance 0)
		)
		(min_thickness 0.25)
		(keepout
			(tracks not_allowed)
			(vias allowed)
			(pads allowed)
			(copperpour not_allowed)
			(footprints allowed)
		)
		(placement
			(enabled no)
			(sheetname "")
		)
		(fill
			(thermal_gap 0.5)
			(thermal_bridge_width 0.5)
			(island_removal_mode 0)
		)
		(polygon
			(pts
				(arc
					(start 380.349506 -349.679514)
					(mid 380.313585 -349.694393)
					(end 380.298706 -349.730314)
				)
				(arc
					(start 380.298706 -350.466914)
					(mid 380.313585 -350.502835)
					(end 380.349506 -350.517714)
				)
				(xy 380.593346 -350.517714) (xy 380.947676 -350.285304) (xy 381.303276 -350.517714)
				(arc
					(start 381.545846 -350.517714)
					(mid 381.581767 -350.502835)
					(end 381.596646 -350.466914)
				)
				(arc
					(start 381.596646 -349.730314)
					(mid 381.581767 -349.694393)
					(end 381.545846 -349.679514)
				)
				(xy 381.303276 -349.679514) (xy 380.946406 -349.911924) (xy 380.592076 -349.679514)
			)
		)
	)
	(zone
		(layer "In1.Cu")
		(hatch none 0.5)
		(connect_pads
			(clearance 0)
		)
		(min_thickness 0.25)
		(keepout
			(tracks not_allowed)
			(vias allowed)
			(pads allowed)
			(copperpour not_allowed)
			(footprints allowed)
		)
		(placement
			(enabled no)
			(sheetname "")
		)
		(fill
			(thermal_gap 0.5)
			(thermal_bridge_width 0.5)
			(island_removal_mode 0)
		)
		(polygon
			(pts
				(arc
					(start 340.31809 -349.679514)
					(mid 340.282169 -349.694393)
					(end 340.26729 -349.730314)
				)
				(arc
					(start 340.26729 -350.466914)
					(mid 340.282169 -350.502835)
					(end 340.31809 -350.517714)
				)
				(xy 340.56193 -350.517714) (xy 340.91626 -350.285304) (xy 341.27186 -350.517714)
				(arc
					(start 341.51443 -350.517714)
					(mid 341.550351 -350.502835)
					(end 341.56523 -350.466914)
				)
				(arc
					(start 341.56523 -349.730314)
					(mid 341.550351 -349.694393)
					(end 341.51443 -349.679514)
				)
				(xy 341.27186 -349.679514) (xy 340.91499 -349.911924) (xy 340.56066 -349.679514)
			)
		)
	)
	(zone
		(layer "In1.Cu")
		(hatch none 0.5)
		(connect_pads
			(clearance 0)
		)
		(min_thickness 0.25)
		(keepout
			(tracks not_allowed)
			(vias allowed)
			(pads allowed)
			(copperpour not_allowed)
			(footprints allowed)
		)
		(placement
			(enabled no)
			(sheetname "")
		)
		(fill
			(thermal_gap 0.5)
			(thermal_bridge_width 0.5)
			(island_removal_mode 0)
		)
		(polygon
			(pts
				(arc
					(start 82.242406 -149.051264)
					(mid 82.257285 -149.087185)
					(end 82.293206 -149.102064)
				)
				(arc
					(start 83.029806 -149.102064)
					(mid 83.065727 -149.087185)
					(end 83.080606 -149.051264)
				)
				(xy 83.080606 -148.807424) (xy 82.848196 -148.453094) (xy 83.080606 -148.097494)
				(arc
					(start 83.080606 -147.854924)
					(mid 83.065727 -147.819003)
					(end 83.029806 -147.804124)
				)
				(arc
					(start 82.293206 -147.804124)
					(mid 82.257285 -147.819003)
					(end 82.242406 -147.854924)
				)
				(xy 82.242406 -148.097494) (xy 82.474816 -148.454364) (xy 82.242406 -148.808694)
			)
		)
	)
	(zone
		(layer "In1.Cu")
		(hatch none 0.5)
		(connect_pads
			(clearance 0)
		)
		(min_thickness 0.25)
		(keepout
			(tracks not_allowed)
			(vias allowed)
			(pads allowed)
			(copperpour not_allowed)
			(footprints allowed)
		)
		(placement
			(enabled no)
			(sheetname "")
		)
		(fill
			(thermal_gap 0.5)
			(thermal_bridge_width 0.5)
			(island_removal_mode 0)
		)
		(polygon
			(pts
				(arc
					(start 67.899788 -29.205936)
					(mid 67.884909 -29.241857)
					(end 67.848988 -29.256736)
				)
				(arc
					(start 66.617088 -29.256736)
					(mid 66.581167 -29.241857)
					(end 66.566288 -29.205936)
				)
				(arc
					(start 66.566288 -28.174188)
					(mid 66.581167 -28.138267)
					(end 66.617088 -28.123388)
				)
				(arc
					(start 67.848988 -28.123388)
					(mid 67.884909 -28.138267)
					(end 67.899788 -28.174188)
				)
			)
		)
	)
	(zone
		(layer "In1.Cu")
		(hatch none 0.5)
		(connect_pads
			(clearance 0)
		)
		(min_thickness 0.25)
		(keepout
			(tracks not_allowed)
			(vias allowed)
			(pads allowed)
			(copperpour not_allowed)
			(footprints allowed)
		)
		(placement
			(enabled no)
			(sheetname "")
		)
		(fill
			(thermal_gap 0.5)
			(thermal_bridge_width 0.5)
			(island_removal_mode 0)
		)
		(polygon
			(pts
				(arc
					(start 136.568434 -355.825806)
					(mid 136.532513 -355.840685)
					(end 136.517634 -355.876606)
				)
				(arc
					(start 136.517634 -356.613206)
					(mid 136.532513 -356.649127)
					(end 136.568434 -356.664006)
				)
				(xy 136.812274 -356.664006) (xy 137.166604 -356.431596) (xy 137.522204 -356.664006)
				(arc
					(start 137.764774 -356.664006)
					(mid 137.800695 -356.649127)
					(end 137.815574 -356.613206)
				)
				(arc
					(start 137.815574 -355.876606)
					(mid 137.800695 -355.840685)
					(end 137.764774 -355.825806)
				)
				(xy 137.522204 -355.825806) (xy 137.165334 -356.058216) (xy 136.811004 -355.825806)
			)
		)
	)
	(zone
		(layer "In1.Cu")
		(hatch none 0.5)
		(connect_pads
			(clearance 0)
		)
		(min_thickness 0.25)
		(keepout
			(tracks not_allowed)
			(vias allowed)
			(pads allowed)
			(copperpour not_allowed)
			(footprints allowed)
		)
		(placement
			(enabled no)
			(sheetname "")
		)
		(fill
			(thermal_gap 0.5)
			(thermal_bridge_width 0.5)
			(island_removal_mode 0)
		)
		(polygon
			(pts
				(arc
					(start 306.067206 -119.638064)
					(mid 306.052327 -119.673985)
					(end 306.016406 -119.688864)
				)
				(arc
					(start 304.835306 -119.688864)
					(mid 304.799385 -119.673985)
					(end 304.784506 -119.638064)
				)
				(arc
					(start 304.784506 -118.631716)
					(mid 304.799385 -118.595795)
					(end 304.835306 -118.580916)
				)
				(arc
					(start 306.016406 -118.580916)
					(mid 306.052327 -118.595795)
					(end 306.067206 -118.631716)
				)
			)
		)
	)
	(zone
		(layer "In1.Cu")
		(hatch none 0.5)
		(connect_pads
			(clearance 0)
		)
		(min_thickness 0.25)
		(keepout
			(tracks not_allowed)
			(vias allowed)
			(pads allowed)
			(copperpour not_allowed)
			(footprints allowed)
		)
		(placement
			(enabled no)
			(sheetname "")
		)
		(fill
			(thermal_gap 0.5)
			(thermal_bridge_width 0.5)
			(island_removal_mode 0)
		)
		(polygon
			(pts
				(arc
					(start 204.129894 -31.77413)
					(mid 204.144773 -31.738209)
					(end 204.180694 -31.72333)
				)
				(arc
					(start 205.412594 -31.72333)
					(mid 205.448515 -31.738209)
					(end 205.463394 -31.77413)
				)
				(arc
					(start 205.463394 -32.805878)
					(mid 205.448515 -32.841799)
					(end 205.412594 -32.856678)
				)
				(arc
					(start 204.180694 -32.856678)
					(mid 204.144773 -32.841799)
					(end 204.129894 -32.805878)
				)
			)
		)
	)
	(zone
		(layer "In1.Cu")
		(hatch none 0.5)
		(connect_pads
			(clearance 0)
		)
		(min_thickness 0.25)
		(keepout
			(tracks not_allowed)
			(vias allowed)
			(pads allowed)
			(copperpour not_allowed)
			(footprints allowed)
		)
		(placement
			(enabled no)
			(sheetname "")
		)
		(fill
			(thermal_gap 0.5)
			(thermal_bridge_width 0.5)
			(island_removal_mode 0)
		)
		(polygon
			(pts
				(arc
					(start 384.519424 -123.853194)
					(mid 384.534303 -123.889115)
					(end 384.570224 -123.903994)
				)
				(arc
					(start 385.306824 -123.903994)
					(mid 385.342745 -123.889115)
					(end 385.357624 -123.853194)
				)
				(xy 385.357624 -123.609354) (xy 385.125214 -123.255024) (xy 385.357624 -122.899424)
				(arc
					(start 385.357624 -122.656854)
					(mid 385.342745 -122.620933)
					(end 385.306824 -122.606054)
				)
				(arc
					(start 384.570224 -122.606054)
					(mid 384.534303 -122.620933)
					(end 384.519424 -122.656854)
				)
				(xy 384.519424 -122.899424) (xy 384.751834 -123.256294) (xy 384.519424 -123.610624)
			)
		)
	)
	(zone
		(layer "In1.Cu")
		(hatch none 0.5)
		(connect_pads
			(clearance 0)
		)
		(min_thickness 0.25)
		(keepout
			(tracks not_allowed)
			(vias allowed)
			(pads allowed)
			(copperpour not_allowed)
			(footprints allowed)
		)
		(placement
			(enabled no)
			(sheetname "")
		)
		(fill
			(thermal_gap 0.5)
			(thermal_bridge_width 0.5)
			(island_removal_mode 0)
		)
		(polygon
			(pts
				(arc
					(start 79.860648 -355.825806)
					(mid 79.824727 -355.840685)
					(end 79.809848 -355.876606)
				)
				(arc
					(start 79.809848 -356.613206)
					(mid 79.824727 -356.649127)
					(end 79.860648 -356.664006)
				)
				(xy 80.104488 -356.664006) (xy 80.458818 -356.431596) (xy 80.814418 -356.664006)
				(arc
					(start 81.056988 -356.664006)
					(mid 81.092909 -356.649127)
					(end 81.107788 -356.613206)
				)
				(arc
					(start 81.107788 -355.876606)
					(mid 81.092909 -355.840685)
					(end 81.056988 -355.825806)
				)
				(xy 80.814418 -355.825806) (xy 80.457548 -356.058216) (xy 80.103218 -355.825806)
			)
		)
	)
	(zone
		(layer "In1.Cu")
		(hatch none 0.5)
		(connect_pads
			(clearance 0)
		)
		(min_thickness 0.25)
		(keepout
			(tracks not_allowed)
			(vias allowed)
			(pads allowed)
			(copperpour not_allowed)
			(footprints allowed)
		)
		(placement
			(enabled no)
			(sheetname "")
		)
		(fill
			(thermal_gap 0.5)
			(thermal_bridge_width 0.5)
			(island_removal_mode 0)
		)
		(polygon
			(pts
				(arc
					(start 54.531514 -362.75391)
					(mid 54.621317 -362.791107)
					(end 54.658514 -362.88091)
				)
				(arc
					(start 54.658514 -363.082078)
					(mid 54.621317 -363.171881)
					(end 54.531514 -363.209078)
				)
				(arc
					(start 54.277514 -363.209078)
					(mid 54.187711 -363.171881)
					(end 54.150514 -363.082078)
				)
				(arc
					(start 54.150514 -362.88091)
					(mid 54.187711 -362.791107)
					(end 54.277514 -362.75391)
				)
			)
		)
	)
	(zone
		(layer "In1.Cu")
		(hatch none 0.5)
		(connect_pads
			(clearance 0)
		)
		(min_thickness 0.25)
		(keepout
			(tracks not_allowed)
			(vias allowed)
			(pads allowed)
			(copperpour not_allowed)
			(footprints allowed)
		)
		(placement
			(enabled no)
			(sheetname "")
		)
		(fill
			(thermal_gap 0.5)
			(thermal_bridge_width 0.5)
			(island_removal_mode 0)
		)
		(polygon
			(pts
				(arc
					(start 306.067206 -132.648198)
					(mid 306.052327 -132.684119)
					(end 306.016406 -132.698998)
				)
				(arc
					(start 304.835306 -132.698998)
					(mid 304.799385 -132.684119)
					(end 304.784506 -132.648198)
				)
				(arc
					(start 304.784506 -131.64185)
					(mid 304.799385 -131.605929)
					(end 304.835306 -131.59105)
				)
				(arc
					(start 306.016406 -131.59105)
					(mid 306.052327 -131.605929)
					(end 306.067206 -131.64185)
				)
			)
		)
	)
	(zone
		(layer "In1.Cu")
		(hatch none 0.5)
		(connect_pads
			(clearance 0)
		)
		(min_thickness 0.25)
		(keepout
			(tracks not_allowed)
			(vias allowed)
			(pads allowed)
			(copperpour not_allowed)
			(footprints allowed)
		)
		(placement
			(enabled no)
			(sheetname "")
		)
		(fill
			(thermal_gap 0.5)
			(thermal_bridge_width 0.5)
			(island_removal_mode 0)
		)
		(polygon
			(pts
				(arc
					(start 311.645808 18.577052)
					(mid 311.668126 18.630934)
					(end 311.722008 18.653252)
				)
				(arc
					(start 312.334148 18.653252)
					(mid 312.38803 18.630934)
					(end 312.410348 18.577052)
				)
				(arc
					(start 312.410348 17.479772)
					(mid 312.38803 17.42589)
					(end 312.334148 17.403572)
				)
				(arc
					(start 311.722008 17.403572)
					(mid 311.668126 17.42589)
					(end 311.645808 17.479772)
				)
			)
		)
	)
	(zone
		(layer "In1.Cu")
		(hatch none 0.5)
		(connect_pads
			(clearance 0)
		)
		(min_thickness 0.25)
		(keepout
			(tracks not_allowed)
			(vias allowed)
			(pads allowed)
			(copperpour not_allowed)
			(footprints allowed)
		)
		(placement
			(enabled no)
			(sheetname "")
		)
		(fill
			(thermal_gap 0.5)
			(thermal_bridge_width 0.5)
			(island_removal_mode 0)
		)
		(polygon
			(pts
				(arc
					(start 177.565558 -355.825806)
					(mid 177.529637 -355.840685)
					(end 177.514758 -355.876606)
				)
				(arc
					(start 177.514758 -356.613206)
					(mid 177.529637 -356.649127)
					(end 177.565558 -356.664006)
				)
				(xy 177.809398 -356.664006) (xy 178.163728 -356.431596) (xy 178.519328 -356.664006)
				(arc
					(start 178.761898 -356.664006)
					(mid 178.797819 -356.649127)
					(end 178.812698 -356.613206)
				)
				(arc
					(start 178.812698 -355.876606)
					(mid 178.797819 -355.840685)
					(end 178.761898 -355.825806)
				)
				(xy 178.519328 -355.825806) (xy 178.162458 -356.058216) (xy 177.808128 -355.825806)
			)
		)
	)
	(zone
		(layer "In1.Cu")
		(hatch none 0.5)
		(connect_pads
			(clearance 0)
		)
		(min_thickness 0.25)
		(keepout
			(tracks not_allowed)
			(vias allowed)
			(pads allowed)
			(copperpour not_allowed)
			(footprints allowed)
		)
		(placement
			(enabled no)
			(sheetname "")
		)
		(fill
			(thermal_gap 0.5)
			(thermal_bridge_width 0.5)
			(island_removal_mode 0)
		)
		(polygon
			(pts
				(arc
					(start 152.319228 -123.853194)
					(mid 152.334107 -123.889115)
					(end 152.370028 -123.903994)
				)
				(arc
					(start 153.106628 -123.903994)
					(mid 153.142549 -123.889115)
					(end 153.157428 -123.853194)
				)
				(xy 153.157428 -123.609354) (xy 152.925018 -123.255024) (xy 153.157428 -122.899424)
				(arc
					(start 153.157428 -122.656854)
					(mid 153.142549 -122.620933)
					(end 153.106628 -122.606054)
				)
				(arc
					(start 152.370028 -122.606054)
					(mid 152.334107 -122.620933)
					(end 152.319228 -122.656854)
				)
				(xy 152.319228 -122.899424) (xy 152.551638 -123.256294) (xy 152.319228 -123.610624)
			)
		)
	)
	(zone
		(layer "In1.Cu")
		(hatch none 0.5)
		(connect_pads
			(clearance 0)
		)
		(min_thickness 0.25)
		(keepout
			(tracks not_allowed)
			(vias allowed)
			(pads allowed)
			(copperpour not_allowed)
			(footprints allowed)
		)
		(placement
			(enabled no)
			(sheetname "")
		)
		(fill
			(thermal_gap 0.5)
			(thermal_bridge_width 0.5)
			(island_removal_mode 0)
		)
		(polygon
			(pts
				(arc
					(start 327.88225 -343.533222)
					(mid 327.846329 -343.548101)
					(end 327.83145 -343.584022)
				)
				(arc
					(start 327.83145 -344.320622)
					(mid 327.846329 -344.356543)
					(end 327.88225 -344.371422)
				)
				(xy 328.12609 -344.371422) (xy 328.48042 -344.139012) (xy 328.83602 -344.371422)
				(arc
					(start 329.07859 -344.371422)
					(mid 329.114511 -344.356543)
					(end 329.12939 -344.320622)
				)
				(arc
					(start 329.12939 -343.584022)
					(mid 329.114511 -343.548101)
					(end 329.07859 -343.533222)
				)
				(xy 328.83602 -343.533222) (xy 328.47915 -343.765632) (xy 328.12482 -343.533222)
			)
		)
	)
	(zone
		(layer "In1.Cu")
		(hatch none 0.5)
		(connect_pads
			(clearance 0)
		)
		(min_thickness 0.25)
		(keepout
			(tracks not_allowed)
			(vias allowed)
			(pads allowed)
			(copperpour not_allowed)
			(footprints allowed)
		)
		(placement
			(enabled no)
			(sheetname "")
		)
		(fill
			(thermal_gap 0.5)
			(thermal_bridge_width 0.5)
			(island_removal_mode 0)
		)
		(polygon
			(pts
				(arc
					(start 340.31809 -343.533222)
					(mid 340.282169 -343.548101)
					(end 340.26729 -343.584022)
				)
				(arc
					(start 340.26729 -344.320622)
					(mid 340.282169 -344.356543)
					(end 340.31809 -344.371422)
				)
				(xy 340.56193 -344.371422) (xy 340.91626 -344.139012) (xy 341.27186 -344.371422)
				(arc
					(start 341.51443 -344.371422)
					(mid 341.550351 -344.356543)
					(end 341.56523 -344.320622)
				)
				(arc
					(start 341.56523 -343.584022)
					(mid 341.550351 -343.548101)
					(end 341.51443 -343.533222)
				)
				(xy 341.27186 -343.533222) (xy 340.91499 -343.765632) (xy 340.56066 -343.533222)
			)
		)
	)
	(zone
		(layer "In1.Cu")
		(hatch none 0.5)
		(connect_pads
			(clearance 0)
		)
		(min_thickness 0.25)
		(keepout
			(tracks not_allowed)
			(vias allowed)
			(pads allowed)
			(copperpour not_allowed)
			(footprints allowed)
		)
		(placement
			(enabled no)
			(sheetname "")
		)
		(fill
			(thermal_gap 0.5)
			(thermal_bridge_width 0.5)
			(island_removal_mode 0)
		)
		(polygon
			(pts
				(arc
					(start 45.432726 -102.84206)
					(mid 45.447605 -102.806139)
					(end 45.483526 -102.79126)
				)
				(arc
					(start 46.664626 -102.79126)
					(mid 46.700547 -102.806139)
					(end 46.715426 -102.84206)
				)
				(arc
					(start 46.715426 -103.848408)
					(mid 46.700547 -103.884329)
					(end 46.664626 -103.899208)
				)
				(arc
					(start 45.483526 -103.899208)
					(mid 45.447605 -103.884329)
					(end 45.432726 -103.848408)
				)
			)
		)
	)
	(zone
		(layer "In1.Cu")
		(hatch none 0.5)
		(connect_pads
			(clearance 0)
		)
		(min_thickness 0.25)
		(keepout
			(tracks not_allowed)
			(vias allowed)
			(pads allowed)
			(copperpour not_allowed)
			(footprints allowed)
		)
		(placement
			(enabled no)
			(sheetname "")
		)
		(fill
			(thermal_gap 0.5)
			(thermal_bridge_width 0.5)
			(island_removal_mode 0)
		)
		(polygon
			(pts
				(arc
					(start 280.167588 -355.825806)
					(mid 280.131667 -355.840685)
					(end 280.116788 -355.876606)
				)
				(arc
					(start 280.116788 -356.613206)
					(mid 280.131667 -356.649127)
					(end 280.167588 -356.664006)
				)
				(xy 280.411428 -356.664006) (xy 280.765758 -356.431596) (xy 281.121358 -356.664006)
				(arc
					(start 281.363928 -356.664006)
					(mid 281.399849 -356.649127)
					(end 281.414728 -356.613206)
				)
				(arc
					(start 281.414728 -355.876606)
					(mid 281.399849 -355.840685)
					(end 281.363928 -355.825806)
				)
				(xy 281.121358 -355.825806) (xy 280.764488 -356.058216) (xy 280.410158 -355.825806)
			)
		)
	)
	(zone
		(layer "In1.Cu")
		(hatch none 0.5)
		(connect_pads
			(clearance 0)
		)
		(min_thickness 0.25)
		(keepout
			(tracks not_allowed)
			(vias allowed)
			(pads allowed)
			(copperpour not_allowed)
			(footprints allowed)
		)
		(placement
			(enabled no)
			(sheetname "")
		)
		(fill
			(thermal_gap 0.5)
			(thermal_bridge_width 0.5)
			(island_removal_mode 0)
		)
		(polygon
			(pts
				(arc
					(start 152.319228 -109.349794)
					(mid 152.334107 -109.385715)
					(end 152.370028 -109.400594)
				)
				(arc
					(start 153.106628 -109.400594)
					(mid 153.142549 -109.385715)
					(end 153.157428 -109.349794)
				)
				(xy 153.157428 -109.105954) (xy 152.925018 -108.751624) (xy 153.157428 -108.396024)
				(arc
					(start 153.157428 -108.153454)
					(mid 153.142549 -108.117533)
					(end 153.106628 -108.102654)
				)
				(arc
					(start 152.370028 -108.102654)
					(mid 152.334107 -108.117533)
					(end 152.319228 -108.153454)
				)
				(xy 152.319228 -108.396024) (xy 152.551638 -108.752894) (xy 152.319228 -109.107224)
			)
		)
	)
	(zone
		(layer "In1.Cu")
		(hatch none 0.5)
		(connect_pads
			(clearance 0)
		)
		(min_thickness 0.25)
		(keepout
			(tracks not_allowed)
			(vias allowed)
			(pads allowed)
			(copperpour not_allowed)
			(footprints allowed)
		)
		(placement
			(enabled no)
			(sheetname "")
		)
		(fill
			(thermal_gap 0.5)
			(thermal_bridge_width 0.5)
			(island_removal_mode 0)
		)
		(polygon
			(pts
				(arc
					(start 117.914674 -349.679514)
					(mid 117.878753 -349.694393)
					(end 117.863874 -349.730314)
				)
				(arc
					(start 117.863874 -350.466914)
					(mid 117.878753 -350.502835)
					(end 117.914674 -350.517714)
				)
				(xy 118.158514 -350.517714) (xy 118.512844 -350.285304) (xy 118.868444 -350.517714)
				(arc
					(start 119.111014 -350.517714)
					(mid 119.146935 -350.502835)
					(end 119.161814 -350.466914)
				)
				(arc
					(start 119.161814 -349.730314)
					(mid 119.146935 -349.694393)
					(end 119.111014 -349.679514)
				)
				(xy 118.868444 -349.679514) (xy 118.511574 -349.911924) (xy 118.157244 -349.679514)
			)
		)
	)
	(zone
		(layer "In1.Cu")
		(hatch none 0.5)
		(connect_pads
			(clearance 0)
		)
		(min_thickness 0.25)
		(keepout
			(tracks not_allowed)
			(vias allowed)
			(pads allowed)
			(copperpour not_allowed)
			(footprints allowed)
		)
		(placement
			(enabled no)
			(sheetname "")
		)
		(fill
			(thermal_gap 0.5)
			(thermal_bridge_width 0.5)
			(island_removal_mode 0)
		)
		(polygon
			(pts
				(arc
					(start 399.55216 -123.758452)
					(mid 399.537281 -123.794373)
					(end 399.50136 -123.809252)
				)
				(arc
					(start 398.32026 -123.809252)
					(mid 398.284339 -123.794373)
					(end 398.26946 -123.758452)
				)
				(arc
					(start 398.26946 -122.752104)
					(mid 398.284339 -122.716183)
					(end 398.32026 -122.701304)
				)
				(arc
					(start 399.50136 -122.701304)
					(mid 399.537281 -122.716183)
					(end 399.55216 -122.752104)
				)
			)
		)
	)
	(zone
		(layer "In1.Cu")
		(hatch none 0.5)
		(connect_pads
			(clearance 0)
		)
		(min_thickness 0.25)
		(keepout
			(tracks not_allowed)
			(vias allowed)
			(pads allowed)
			(copperpour not_allowed)
			(footprints allowed)
		)
		(placement
			(enabled no)
			(sheetname "")
		)
		(fill
			(thermal_gap 0.5)
			(thermal_bridge_width 0.5)
			(island_removal_mode 0)
		)
		(polygon
			(pts
				(arc
					(start 211.473288 -29.279596)
					(mid 211.488167 -29.315517)
					(end 211.524088 -29.330396)
				)
				(arc
					(start 212.260688 -29.330396)
					(mid 212.296609 -29.315517)
					(end 212.311488 -29.279596)
				)
				(xy 212.311488 -29.035756) (xy 212.079078 -28.681426) (xy 212.311488 -28.325826)
				(arc
					(start 212.311488 -28.083256)
					(mid 212.296609 -28.047335)
					(end 212.260688 -28.032456)
				)
				(arc
					(start 211.524088 -28.032456)
					(mid 211.488167 -28.047335)
					(end 211.473288 -28.083256)
				)
				(xy 211.473288 -28.325826) (xy 211.705698 -28.682696) (xy 211.473288 -29.037026)
			)
		)
	)
	(zone
		(layer "In1.Cu")
		(hatch none 0.5)
		(connect_pads
			(clearance 0)
		)
		(min_thickness 0.25)
		(keepout
			(tracks not_allowed)
			(vias allowed)
			(pads allowed)
			(copperpour not_allowed)
			(footprints allowed)
		)
		(placement
			(enabled no)
			(sheetname "")
		)
		(fill
			(thermal_gap 0.5)
			(thermal_bridge_width 0.5)
			(island_removal_mode 0)
		)
		(polygon
			(pts
				(arc
					(start 410.329888 -28.174188)
					(mid 410.344767 -28.138267)
					(end 410.380688 -28.123388)
				)
				(arc
					(start 411.612588 -28.123388)
					(mid 411.648509 -28.138267)
					(end 411.663388 -28.174188)
				)
				(arc
					(start 411.663388 -29.205936)
					(mid 411.648509 -29.241857)
					(end 411.612588 -29.256736)
				)
				(arc
					(start 410.380688 -29.256736)
					(mid 410.344767 -29.241857)
					(end 410.329888 -29.205936)
				)
			)
		)
	)
	(zone
		(layer "In1.Cu")
		(hatch none 0.5)
		(connect_pads
			(clearance 0)
		)
		(min_thickness 0.25)
		(keepout
			(tracks not_allowed)
			(vias allowed)
			(pads allowed)
			(copperpour not_allowed)
			(footprints allowed)
		)
		(placement
			(enabled no)
			(sheetname "")
		)
		(fill
			(thermal_gap 0.5)
			(thermal_bridge_width 0.5)
			(island_removal_mode 0)
		)
		(polygon
			(pts
				(arc
					(start 82.969608 -349.679514)
					(mid 82.933687 -349.694393)
					(end 82.918808 -349.730314)
				)
				(arc
					(start 82.918808 -350.466914)
					(mid 82.933687 -350.502835)
					(end 82.969608 -350.517714)
				)
				(xy 83.213448 -350.517714) (xy 83.567778 -350.285304) (xy 83.923378 -350.517714)
				(arc
					(start 84.165948 -350.517714)
					(mid 84.201869 -350.502835)
					(end 84.216748 -350.466914)
				)
				(arc
					(start 84.216748 -349.730314)
					(mid 84.201869 -349.694393)
					(end 84.165948 -349.679514)
				)
				(xy 83.923378 -349.679514) (xy 83.566508 -349.911924) (xy 83.212178 -349.679514)
			)
		)
	)
	(zone
		(layer "In1.Cu")
		(hatch none 0.5)
		(connect_pads
			(clearance 0)
		)
		(min_thickness 0.25)
		(keepout
			(tracks not_allowed)
			(vias allowed)
			(pads allowed)
			(copperpour not_allowed)
			(footprints allowed)
		)
		(placement
			(enabled no)
			(sheetname "")
		)
		(fill
			(thermal_gap 0.5)
			(thermal_bridge_width 0.5)
			(island_removal_mode 0)
		)
		(polygon
			(pts
				(arc
					(start 300.247812 -146.151854)
					(mid 300.262691 -146.115933)
					(end 300.298612 -146.101054)
				)
				(arc
					(start 301.479712 -146.101054)
					(mid 301.515633 -146.115933)
					(end 301.530512 -146.151854)
				)
				(arc
					(start 301.530512 -147.158202)
					(mid 301.515633 -147.194123)
					(end 301.479712 -147.209002)
				)
				(arc
					(start 300.298612 -147.209002)
					(mid 300.262691 -147.194123)
					(end 300.247812 -147.158202)
				)
			)
		)
	)
	(zone
		(layer "In1.Cu")
		(hatch none 0.5)
		(connect_pads
			(clearance 0)
		)
		(min_thickness 0.25)
		(keepout
			(tracks not_allowed)
			(vias allowed)
			(pads allowed)
			(copperpour not_allowed)
			(footprints allowed)
		)
		(placement
			(enabled no)
			(sheetname "")
		)
		(fill
			(thermal_gap 0.5)
			(thermal_bridge_width 0.5)
			(island_removal_mode 0)
		)
		(polygon
			(pts
				(arc
					(start 46.015402 -31.086044)
					(mid 46.030281 -31.121965)
					(end 46.066202 -31.136844)
				)
				(arc
					(start 46.802802 -31.136844)
					(mid 46.838723 -31.121965)
					(end 46.853602 -31.086044)
				)
				(xy 46.853602 -30.842204) (xy 46.621192 -30.487874) (xy 46.853602 -30.132274)
				(arc
					(start 46.853602 -29.889704)
					(mid 46.838723 -29.853783)
					(end 46.802802 -29.838904)
				)
				(arc
					(start 46.066202 -29.838904)
					(mid 46.030281 -29.853783)
					(end 46.015402 -29.889704)
				)
				(xy 46.015402 -30.132274) (xy 46.247812 -30.489144) (xy 46.015402 -30.843474)
			)
		)
	)
	(zone
		(layer "In1.Cu")
		(hatch none 0.5)
		(connect_pads
			(clearance 0)
		)
		(min_thickness 0.25)
		(keepout
			(tracks not_allowed)
			(vias allowed)
			(pads allowed)
			(copperpour not_allowed)
			(footprints allowed)
		)
		(placement
			(enabled no)
			(sheetname "")
		)
		(fill
			(thermal_gap 0.5)
			(thermal_bridge_width 0.5)
			(island_removal_mode 0)
		)
		(polygon
			(pts
				(arc
					(start 22.276054 -355.825806)
					(mid 22.240133 -355.840685)
					(end 22.225254 -355.876606)
				)
				(arc
					(start 22.225254 -356.613206)
					(mid 22.240133 -356.649127)
					(end 22.276054 -356.664006)
				)
				(xy 22.519894 -356.664006) (xy 22.874224 -356.431596) (xy 23.229824 -356.664006)
				(arc
					(start 23.472394 -356.664006)
					(mid 23.508315 -356.649127)
					(end 23.523194 -356.613206)
				)
				(arc
					(start 23.523194 -355.876606)
					(mid 23.508315 -355.840685)
					(end 23.472394 -355.825806)
				)
				(xy 23.229824 -355.825806) (xy 22.872954 -356.058216) (xy 22.518624 -355.825806)
			)
		)
	)
	(zone
		(layer "In1.Cu")
		(hatch none 0.5)
		(connect_pads
			(clearance 0)
		)
		(min_thickness 0.25)
		(keepout
			(tracks not_allowed)
			(vias allowed)
			(pads allowed)
			(copperpour not_allowed)
			(footprints allowed)
		)
		(placement
			(enabled no)
			(sheetname "")
		)
		(fill
			(thermal_gap 0.5)
			(thermal_bridge_width 0.5)
			(island_removal_mode 0)
		)
		(polygon
			(pts
				(arc
					(start 274.22856 17.486884)
					(mid 274.206242 17.433002)
					(end 274.15236 17.410684)
				)
				(arc
					(start 273.54022 17.410684)
					(mid 273.486338 17.433002)
					(end 273.46402 17.486884)
				)
				(arc
					(start 273.46402 18.584164)
					(mid 273.486338 18.638046)
					(end 273.54022 18.660364)
				)
				(arc
					(start 274.15236 18.660364)
					(mid 274.206242 18.638046)
					(end 274.22856 18.584164)
				)
			)
		)
	)
	(zone
		(layer "In1.Cu")
		(hatch none 0.5)
		(connect_pads
			(clearance 0)
		)
		(min_thickness 0.25)
		(keepout
			(tracks not_allowed)
			(vias allowed)
			(pads allowed)
			(copperpour not_allowed)
			(footprints allowed)
		)
		(placement
			(enabled no)
			(sheetname "")
		)
		(fill
			(thermal_gap 0.5)
			(thermal_bridge_width 0.5)
			(island_removal_mode 0)
		)
		(polygon
			(pts
				(arc
					(start 68.04787 -149.751796)
					(mid 68.062749 -149.715875)
					(end 68.09867 -149.700996)
				)
				(arc
					(start 69.27977 -149.700996)
					(mid 69.315691 -149.715875)
					(end 69.33057 -149.751796)
				)
				(arc
					(start 69.33057 -150.758144)
					(mid 69.315691 -150.794065)
					(end 69.27977 -150.808944)
				)
				(arc
					(start 68.09867 -150.808944)
					(mid 68.062749 -150.794065)
					(end 68.04787 -150.758144)
				)
			)
		)
	)
	(zone
		(layer "In1.Cu")
		(hatch none 0.5)
		(connect_pads
			(clearance 0)
		)
		(min_thickness 0.25)
		(keepout
			(tracks not_allowed)
			(vias allowed)
			(pads allowed)
			(copperpour not_allowed)
			(footprints allowed)
		)
		(placement
			(enabled no)
			(sheetname "")
		)
		(fill
			(thermal_gap 0.5)
			(thermal_bridge_width 0.5)
			(island_removal_mode 0)
		)
		(polygon
			(pts
				(arc
					(start 99.85248 -385.404614)
					(mid 99.762677 -385.367417)
					(end 99.72548 -385.277614)
				)
				(arc
					(start 99.72548 -385.076446)
					(mid 99.762677 -384.986643)
					(end 99.85248 -384.949446)
				)
				(arc
					(start 100.10648 -384.949446)
					(mid 100.196283 -384.986643)
					(end 100.23348 -385.076446)
				)
				(arc
					(start 100.23348 -385.277614)
					(mid 100.196283 -385.367417)
					(end 100.10648 -385.404614)
				)
			)
		)
	)
	(zone
		(layer "In1.Cu")
		(hatch none 0.5)
		(connect_pads
			(clearance 0)
		)
		(min_thickness 0.25)
		(keepout
			(tracks not_allowed)
			(vias allowed)
			(pads allowed)
			(copperpour not_allowed)
			(footprints allowed)
		)
		(placement
			(enabled no)
			(sheetname "")
		)
		(fill
			(thermal_gap 0.5)
			(thermal_bridge_width 0.5)
			(island_removal_mode 0)
		)
		(polygon
			(pts
				(arc
					(start 283.276548 -355.825806)
					(mid 283.240627 -355.840685)
					(end 283.225748 -355.876606)
				)
				(arc
					(start 283.225748 -356.613206)
					(mid 283.240627 -356.649127)
					(end 283.276548 -356.664006)
				)
				(xy 283.520388 -356.664006) (xy 283.874718 -356.431596) (xy 284.230318 -356.664006)
				(arc
					(start 284.472888 -356.664006)
					(mid 284.508809 -356.649127)
					(end 284.523688 -356.613206)
				)
				(arc
					(start 284.523688 -355.876606)
					(mid 284.508809 -355.840685)
					(end 284.472888 -355.825806)
				)
				(xy 284.230318 -355.825806) (xy 283.873448 -356.058216) (xy 283.519118 -355.825806)
			)
		)
	)
	(zone
		(layer "In1.Cu")
		(hatch none 0.5)
		(connect_pads
			(clearance 0)
		)
		(min_thickness 0.25)
		(keepout
			(tracks not_allowed)
			(vias allowed)
			(pads allowed)
			(copperpour not_allowed)
			(footprints allowed)
		)
		(placement
			(enabled no)
			(sheetname "")
		)
		(fill
			(thermal_gap 0.5)
			(thermal_bridge_width 0.5)
			(island_removal_mode 0)
		)
		(polygon
			(pts
				(arc
					(start 233.38536 -89.536524)
					(mid 233.400239 -89.500603)
					(end 233.43616 -89.485724)
				)
				(arc
					(start 234.10037 -89.485724)
					(mid 234.136291 -89.500603)
					(end 234.15117 -89.536524)
				)
				(arc
					(start 234.15117 -90.174826)
					(mid 234.136291 -90.210747)
					(end 234.10037 -90.225626)
				)
				(arc
					(start 233.43616 -90.225626)
					(mid 233.400239 -90.210747)
					(end 233.38536 -90.174826)
				)
			)
		)
	)
	(zone
		(layer "In1.Cu")
		(hatch none 0.5)
		(connect_pads
			(clearance 0)
		)
		(min_thickness 0.25)
		(keepout
			(tracks not_allowed)
			(vias allowed)
			(pads allowed)
			(copperpour not_allowed)
			(footprints allowed)
		)
		(placement
			(enabled no)
			(sheetname "")
		)
		(fill
			(thermal_gap 0.5)
			(thermal_bridge_width 0.5)
			(island_removal_mode 0)
		)
		(polygon
			(pts
				(arc
					(start 126.13005 -29.974286)
					(mid 126.144929 -29.938365)
					(end 126.18085 -29.923486)
				)
				(arc
					(start 127.41275 -29.923486)
					(mid 127.448671 -29.938365)
					(end 127.46355 -29.974286)
				)
				(arc
					(start 127.46355 -31.006034)
					(mid 127.448671 -31.041955)
					(end 127.41275 -31.056834)
				)
				(arc
					(start 126.18085 -31.056834)
					(mid 126.144929 -31.041955)
					(end 126.13005 -31.006034)
				)
			)
		)
	)
	(zone
		(layer "In1.Cu")
		(hatch none 0.5)
		(connect_pads
			(clearance 0)
		)
		(min_thickness 0.25)
		(keepout
			(tracks not_allowed)
			(vias allowed)
			(pads allowed)
			(copperpour not_allowed)
			(footprints allowed)
		)
		(placement
			(enabled no)
			(sheetname "")
		)
		(fill
			(thermal_gap 0.5)
			(thermal_bridge_width 0.5)
			(island_removal_mode 0)
		)
		(polygon
			(pts
				(arc
					(start 5.48005 -387.75386)
					(mid 5.517247 -387.664057)
					(end 5.60705 -387.62686)
				)
				(arc
					(start 5.952998 -387.62686)
					(mid 6.042801 -387.664057)
					(end 6.079998 -387.75386)
				)
				(arc
					(start 6.079998 -388.239762)
					(mid 6.042801 -388.329565)
					(end 5.952998 -388.366762)
				)
				(arc
					(start 5.60705 -388.366762)
					(mid 5.517247 -388.329565)
					(end 5.48005 -388.239762)
				)
			)
		)
	)
	(zone
		(layer "In1.Cu")
		(hatch none 0.5)
		(connect_pads
			(clearance 0)
		)
		(min_thickness 0.25)
		(keepout
			(tracks not_allowed)
			(vias allowed)
			(pads allowed)
			(copperpour not_allowed)
			(footprints allowed)
		)
		(placement
			(enabled no)
			(sheetname "")
		)
		(fill
			(thermal_gap 0.5)
			(thermal_bridge_width 0.5)
			(island_removal_mode 0)
		)
		(polygon
			(pts
				(arc
					(start 430.542446 -121.531126)
					(mid 430.557325 -121.567047)
					(end 430.593246 -121.581926)
				)
				(arc
					(start 431.329846 -121.581926)
					(mid 431.365767 -121.567047)
					(end 431.380646 -121.531126)
				)
				(xy 431.380646 -121.287286) (xy 431.148236 -120.932956) (xy 431.380646 -120.577356)
				(arc
					(start 431.380646 -120.334786)
					(mid 431.365767 -120.298865)
					(end 431.329846 -120.283986)
				)
				(arc
					(start 430.593246 -120.283986)
					(mid 430.557325 -120.298865)
					(end 430.542446 -120.334786)
				)
				(xy 430.542446 -120.577356) (xy 430.774856 -120.934226) (xy 430.542446 -121.288556)
			)
		)
	)
	(zone
		(layer "In1.Cu")
		(hatch none 0.5)
		(connect_pads
			(clearance 0)
		)
		(min_thickness 0.25)
		(keepout
			(tracks not_allowed)
			(vias allowed)
			(pads allowed)
			(copperpour not_allowed)
			(footprints allowed)
		)
		(placement
			(enabled no)
			(sheetname "")
		)
		(fill
			(thermal_gap 0.5)
			(thermal_bridge_width 0.5)
			(island_removal_mode 0)
		)
		(polygon
			(pts
				(arc
					(start 28.493974 -343.533222)
					(mid 28.458053 -343.548101)
					(end 28.443174 -343.584022)
				)
				(arc
					(start 28.443174 -344.320622)
					(mid 28.458053 -344.356543)
					(end 28.493974 -344.371422)
				)
				(xy 28.737814 -344.371422) (xy 29.092144 -344.139012) (xy 29.447744 -344.371422)
				(arc
					(start 29.690314 -344.371422)
					(mid 29.726235 -344.356543)
					(end 29.741114 -344.320622)
				)
				(arc
					(start 29.741114 -343.584022)
					(mid 29.726235 -343.548101)
					(end 29.690314 -343.533222)
				)
				(xy 29.447744 -343.533222) (xy 29.090874 -343.765632) (xy 28.736544 -343.533222)
			)
		)
	)
	(zone
		(layer "In1.Cu")
		(hatch none 0.5)
		(connect_pads
			(clearance 0)
		)
		(min_thickness 0.25)
		(keepout
			(tracks not_allowed)
			(vias allowed)
			(pads allowed)
			(copperpour not_allowed)
			(footprints allowed)
		)
		(placement
			(enabled no)
			(sheetname "")
		)
		(fill
			(thermal_gap 0.5)
			(thermal_bridge_width 0.5)
			(island_removal_mode 0)
		)
		(polygon
			(pts
				(arc
					(start 422.167304 -154.358086)
					(mid 422.152425 -154.394007)
					(end 422.116504 -154.408886)
				)
				(arc
					(start 420.935404 -154.408886)
					(mid 420.899483 -154.394007)
					(end 420.884604 -154.358086)
				)
				(arc
					(start 420.884604 -153.351738)
					(mid 420.899483 -153.315817)
					(end 420.935404 -153.300938)
				)
				(arc
					(start 422.116504 -153.300938)
					(mid 422.152425 -153.315817)
					(end 422.167304 -153.351738)
				)
			)
		)
	)
	(zone
		(layer "In1.Cu")
		(hatch none 0.5)
		(connect_pads
			(clearance 0)
		)
		(min_thickness 0.25)
		(keepout
			(tracks not_allowed)
			(vias allowed)
			(pads allowed)
			(copperpour not_allowed)
			(footprints allowed)
		)
		(placement
			(enabled no)
			(sheetname "")
		)
		(fill
			(thermal_gap 0.5)
			(thermal_bridge_width 0.5)
			(island_removal_mode 0)
		)
		(polygon
			(pts
				(arc
					(start 136.115552 -34.68624)
					(mid 136.130431 -34.722161)
					(end 136.166352 -34.73704)
				)
				(arc
					(start 136.902952 -34.73704)
					(mid 136.938873 -34.722161)
					(end 136.953752 -34.68624)
				)
				(xy 136.953752 -34.4424) (xy 136.721342 -34.08807) (xy 136.953752 -33.73247)
				(arc
					(start 136.953752 -33.4899)
					(mid 136.938873 -33.453979)
					(end 136.902952 -33.4391)
				)
				(arc
					(start 136.166352 -33.4391)
					(mid 136.130431 -33.453979)
					(end 136.115552 -33.4899)
				)
				(xy 136.115552 -33.73247) (xy 136.347962 -34.08934) (xy 136.115552 -34.44367)
			)
		)
	)
	(zone
		(layer "In1.Cu")
		(hatch none 0.5)
		(connect_pads
			(clearance 0)
		)
		(min_thickness 0.25)
		(keepout
			(tracks not_allowed)
			(vias allowed)
			(pads allowed)
			(copperpour not_allowed)
			(footprints allowed)
		)
		(placement
			(enabled no)
			(sheetname "")
		)
		(fill
			(thermal_gap 0.5)
			(thermal_bridge_width 0.5)
			(island_removal_mode 0)
		)
		(polygon
			(pts
				(arc
					(start 178.129946 -29.974286)
					(mid 178.144825 -29.938365)
					(end 178.180746 -29.923486)
				)
				(arc
					(start 179.412646 -29.923486)
					(mid 179.448567 -29.938365)
					(end 179.463446 -29.974286)
				)
				(arc
					(start 179.463446 -31.006034)
					(mid 179.448567 -31.041955)
					(end 179.412646 -31.056834)
				)
				(arc
					(start 178.180746 -31.056834)
					(mid 178.144825 -31.041955)
					(end 178.129946 -31.006034)
				)
			)
		)
	)
	(zone
		(layer "In1.Cu")
		(hatch none 0.5)
		(connect_pads
			(clearance 0)
		)
		(min_thickness 0.25)
		(keepout
			(tracks not_allowed)
			(vias allowed)
			(pads allowed)
			(copperpour not_allowed)
			(footprints allowed)
		)
		(placement
			(enabled no)
			(sheetname "")
		)
		(fill
			(thermal_gap 0.5)
			(thermal_bridge_width 0.5)
			(island_removal_mode 0)
		)
		(polygon
			(pts
				(arc
					(start 157.999938 -27.405838)
					(mid 157.985059 -27.441759)
					(end 157.949138 -27.456638)
				)
				(arc
					(start 156.717238 -27.456638)
					(mid 156.681317 -27.441759)
					(end 156.666438 -27.405838)
				)
				(arc
					(start 156.666438 -26.37409)
					(mid 156.681317 -26.338169)
					(end 156.717238 -26.32329)
				)
				(arc
					(start 157.949138 -26.32329)
					(mid 157.985059 -26.338169)
					(end 157.999938 -26.37409)
				)
			)
		)
	)
	(zone
		(layer "In1.Cu")
		(hatch none 0.5)
		(connect_pads
			(clearance 0)
		)
		(min_thickness 0.25)
		(keepout
			(tracks not_allowed)
			(vias allowed)
			(pads allowed)
			(copperpour not_allowed)
			(footprints allowed)
		)
		(placement
			(enabled no)
			(sheetname "")
		)
		(fill
			(thermal_gap 0.5)
			(thermal_bridge_width 0.5)
			(island_removal_mode 0)
		)
		(polygon
			(pts
				(arc
					(start 387.161532 -103.94315)
					(mid 387.176411 -103.979071)
					(end 387.212332 -103.99395)
				)
				(arc
					(start 387.948932 -103.99395)
					(mid 387.984853 -103.979071)
					(end 387.999732 -103.94315)
				)
				(xy 387.999732 -103.69931) (xy 387.767322 -103.34498) (xy 387.999732 -102.98938)
				(arc
					(start 387.999732 -102.74681)
					(mid 387.984853 -102.710889)
					(end 387.948932 -102.69601)
				)
				(arc
					(start 387.212332 -102.69601)
					(mid 387.176411 -102.710889)
					(end 387.161532 -102.74681)
				)
				(xy 387.161532 -102.98938) (xy 387.393942 -103.34625) (xy 387.161532 -103.70058)
			)
		)
	)
	(zone
		(layer "In1.Cu")
		(hatch none 0.5)
		(connect_pads
			(clearance 0)
		)
		(min_thickness 0.25)
		(keepout
			(tracks not_allowed)
			(vias allowed)
			(pads allowed)
			(copperpour not_allowed)
			(footprints allowed)
		)
		(placement
			(enabled no)
			(sheetname "")
		)
		(fill
			(thermal_gap 0.5)
			(thermal_bridge_width 0.5)
			(island_removal_mode 0)
		)
		(polygon
			(pts
				(arc
					(start 271.061434 -136.869678)
					(mid 271.076313 -136.905599)
					(end 271.112234 -136.920478)
				)
				(arc
					(start 271.848834 -136.920478)
					(mid 271.884755 -136.905599)
					(end 271.899634 -136.869678)
				)
				(xy 271.899634 -136.625838) (xy 271.667224 -136.271508) (xy 271.899634 -135.915908)
				(arc
					(start 271.899634 -135.673338)
					(mid 271.884755 -135.637417)
					(end 271.848834 -135.622538)
				)
				(arc
					(start 271.112234 -135.622538)
					(mid 271.076313 -135.637417)
					(end 271.061434 -135.673338)
				)
				(xy 271.061434 -135.915908) (xy 271.293844 -136.272778) (xy 271.061434 -136.627108)
			)
		)
	)
	(zone
		(layer "In1.Cu")
		(hatch none 0.5)
		(connect_pads
			(clearance 0)
		)
		(min_thickness 0.25)
		(keepout
			(tracks not_allowed)
			(vias allowed)
			(pads allowed)
			(copperpour not_allowed)
			(footprints allowed)
		)
		(placement
			(enabled no)
			(sheetname "")
		)
		(fill
			(thermal_gap 0.5)
			(thermal_bridge_width 0.5)
			(island_removal_mode 0)
		)
		(polygon
			(pts
				(arc
					(start 242.229894 -33.574228)
					(mid 242.244773 -33.538307)
					(end 242.280694 -33.523428)
				)
				(arc
					(start 243.512594 -33.523428)
					(mid 243.548515 -33.538307)
					(end 243.563394 -33.574228)
				)
				(arc
					(start 243.563394 -34.605976)
					(mid 243.548515 -34.641897)
					(end 243.512594 -34.656776)
				)
				(arc
					(start 242.280694 -34.656776)
					(mid 242.244773 -34.641897)
					(end 242.229894 -34.605976)
				)
			)
		)
	)
	(zone
		(layer "In1.Cu")
		(hatch none 0.5)
		(connect_pads
			(clearance 0)
		)
		(min_thickness 0.25)
		(keepout
			(tracks not_allowed)
			(vias allowed)
			(pads allowed)
			(copperpour not_allowed)
			(footprints allowed)
		)
		(placement
			(enabled no)
			(sheetname "")
		)
		(fill
			(thermal_gap 0.5)
			(thermal_bridge_width 0.5)
			(island_removal_mode 0)
		)
		(polygon
			(pts
				(arc
					(start 167.351964 -121.958354)
					(mid 167.337085 -121.994275)
					(end 167.301164 -122.009154)
				)
				(arc
					(start 166.120064 -122.009154)
					(mid 166.084143 -121.994275)
					(end 166.069264 -121.958354)
				)
				(arc
					(start 166.069264 -120.952006)
					(mid 166.084143 -120.916085)
					(end 166.120064 -120.901206)
				)
				(arc
					(start 167.301164 -120.901206)
					(mid 167.337085 -120.916085)
					(end 167.351964 -120.952006)
				)
			)
		)
	)
	(zone
		(layer "In1.Cu")
		(hatch none 0.5)
		(connect_pads
			(clearance 0)
		)
		(min_thickness 0.25)
		(keepout
			(tracks not_allowed)
			(vias allowed)
			(pads allowed)
			(copperpour not_allowed)
			(footprints allowed)
		)
		(placement
			(enabled no)
			(sheetname "")
		)
		(fill
			(thermal_gap 0.5)
			(thermal_bridge_width 0.5)
			(island_removal_mode 0)
		)
		(polygon
			(pts
				(arc
					(start 422.167304 -119.638064)
					(mid 422.152425 -119.673985)
					(end 422.116504 -119.688864)
				)
				(arc
					(start 420.935404 -119.688864)
					(mid 420.899483 -119.673985)
					(end 420.884604 -119.638064)
				)
				(arc
					(start 420.884604 -118.631716)
					(mid 420.899483 -118.595795)
					(end 420.935404 -118.580916)
				)
				(arc
					(start 422.116504 -118.580916)
					(mid 422.152425 -118.595795)
					(end 422.167304 -118.631716)
				)
			)
		)
	)
	(zone
		(layer "In1.Cu")
		(hatch none 0.5)
		(connect_pads
			(clearance 0)
		)
		(min_thickness 0.25)
		(keepout
			(tracks not_allowed)
			(vias allowed)
			(pads allowed)
			(copperpour not_allowed)
			(footprints allowed)
		)
		(placement
			(enabled no)
			(sheetname "")
		)
		(fill
			(thermal_gap 0.5)
			(thermal_bridge_width 0.5)
			(island_removal_mode 0)
		)
		(polygon
			(pts
				(arc
					(start 62.029848 -28.174188)
					(mid 62.044727 -28.138267)
					(end 62.080648 -28.123388)
				)
				(arc
					(start 63.312548 -28.123388)
					(mid 63.348469 -28.138267)
					(end 63.363348 -28.174188)
				)
				(arc
					(start 63.363348 -29.205936)
					(mid 63.348469 -29.241857)
					(end 63.312548 -29.256736)
				)
				(arc
					(start 62.080648 -29.256736)
					(mid 62.044727 -29.241857)
					(end 62.029848 -29.205936)
				)
			)
		)
	)
	(zone
		(layer "In1.Cu")
		(hatch none 0.5)
		(connect_pads
			(clearance 0)
		)
		(min_thickness 0.25)
		(keepout
			(tracks not_allowed)
			(vias allowed)
			(pads allowed)
			(copperpour not_allowed)
			(footprints allowed)
		)
		(placement
			(enabled no)
			(sheetname "")
		)
		(fill
			(thermal_gap 0.5)
			(thermal_bridge_width 0.5)
			(island_removal_mode 0)
		)
		(polygon
			(pts
				(arc
					(start 73.867264 -154.358086)
					(mid 73.852385 -154.394007)
					(end 73.816464 -154.408886)
				)
				(arc
					(start 72.635364 -154.408886)
					(mid 72.599443 -154.394007)
					(end 72.584564 -154.358086)
				)
				(arc
					(start 72.584564 -153.351738)
					(mid 72.599443 -153.315817)
					(end 72.635364 -153.300938)
				)
				(arc
					(start 73.816464 -153.300938)
					(mid 73.852385 -153.315817)
					(end 73.867264 -153.351738)
				)
			)
		)
	)
	(zone
		(layer "In1.Cu")
		(hatch none 0.5)
		(connect_pads
			(clearance 0)
		)
		(min_thickness 0.25)
		(keepout
			(tracks not_allowed)
			(vias allowed)
			(pads allowed)
			(copperpour not_allowed)
			(footprints allowed)
		)
		(placement
			(enabled no)
			(sheetname "")
		)
		(fill
			(thermal_gap 0.5)
			(thermal_bridge_width 0.5)
			(island_removal_mode 0)
		)
		(polygon
			(pts
				(arc
					(start 31.602934 -355.825806)
					(mid 31.567013 -355.840685)
					(end 31.552134 -355.876606)
				)
				(arc
					(start 31.552134 -356.613206)
					(mid 31.567013 -356.649127)
					(end 31.602934 -356.664006)
				)
				(xy 31.846774 -356.664006) (xy 32.201104 -356.431596) (xy 32.556704 -356.664006)
				(arc
					(start 32.799274 -356.664006)
					(mid 32.835195 -356.649127)
					(end 32.850074 -356.613206)
				)
				(arc
					(start 32.850074 -355.876606)
					(mid 32.835195 -355.840685)
					(end 32.799274 -355.825806)
				)
				(xy 32.556704 -355.825806) (xy 32.199834 -356.058216) (xy 31.845504 -355.825806)
			)
		)
	)
	(zone
		(layer "In1.Cu")
		(hatch none 0.5)
		(connect_pads
			(clearance 0)
		)
		(min_thickness 0.25)
		(keepout
			(tracks not_allowed)
			(vias allowed)
			(pads allowed)
			(copperpour not_allowed)
			(footprints allowed)
		)
		(placement
			(enabled no)
			(sheetname "")
		)
		(fill
			(thermal_gap 0.5)
			(thermal_bridge_width 0.5)
			(island_removal_mode 0)
		)
		(polygon
			(pts
				(arc
					(start 389.676386 -355.825806)
					(mid 389.640465 -355.840685)
					(end 389.625586 -355.876606)
				)
				(arc
					(start 389.625586 -356.613206)
					(mid 389.640465 -356.649127)
					(end 389.676386 -356.664006)
				)
				(xy 389.920226 -356.664006) (xy 390.274556 -356.431596) (xy 390.630156 -356.664006)
				(arc
					(start 390.872726 -356.664006)
					(mid 390.908647 -356.649127)
					(end 390.923526 -356.613206)
				)
				(arc
					(start 390.923526 -355.876606)
					(mid 390.908647 -355.840685)
					(end 390.872726 -355.825806)
				)
				(xy 390.630156 -355.825806) (xy 390.273286 -356.058216) (xy 389.918956 -355.825806)
			)
		)
	)
	(zone
		(layer "In1.Cu")
		(hatch none 0.5)
		(connect_pads
			(clearance 0)
		)
		(min_thickness 0.25)
		(keepout
			(tracks not_allowed)
			(vias allowed)
			(pads allowed)
			(copperpour not_allowed)
			(footprints allowed)
		)
		(placement
			(enabled no)
			(sheetname "")
		)
		(fill
			(thermal_gap 0.5)
			(thermal_bridge_width 0.5)
			(island_removal_mode 0)
		)
		(polygon
			(pts
				(arc
					(start 189.967108 -143.55826)
					(mid 189.952229 -143.594181)
					(end 189.916308 -143.60906)
				)
				(arc
					(start 188.735208 -143.60906)
					(mid 188.699287 -143.594181)
					(end 188.684408 -143.55826)
				)
				(arc
					(start 188.684408 -142.551912)
					(mid 188.699287 -142.515991)
					(end 188.735208 -142.501112)
				)
				(arc
					(start 189.916308 -142.501112)
					(mid 189.952229 -142.515991)
					(end 189.967108 -142.551912)
				)
			)
		)
	)
	(zone
		(layer "In1.Cu")
		(hatch none 0.5)
		(connect_pads
			(clearance 0)
		)
		(min_thickness 0.25)
		(keepout
			(tracks not_allowed)
			(vias allowed)
			(pads allowed)
			(copperpour not_allowed)
			(footprints allowed)
		)
		(placement
			(enabled no)
			(sheetname "")
		)
		(fill
			(thermal_gap 0.5)
			(thermal_bridge_width 0.5)
			(island_removal_mode 0)
		)
		(polygon
			(pts
				(arc
					(start 422.167304 -134.448296)
					(mid 422.152425 -134.484217)
					(end 422.116504 -134.499096)
				)
				(arc
					(start 420.935404 -134.499096)
					(mid 420.899483 -134.484217)
					(end 420.884604 -134.448296)
				)
				(arc
					(start 420.884604 -133.441948)
					(mid 420.899483 -133.406027)
					(end 420.935404 -133.391148)
				)
				(arc
					(start 422.116504 -133.391148)
					(mid 422.152425 -133.406027)
					(end 422.167304 -133.441948)
				)
			)
		)
	)
	(zone
		(layer "In1.Cu")
		(hatch none 0.5)
		(connect_pads
			(clearance 0)
		)
		(min_thickness 0.25)
		(keepout
			(tracks not_allowed)
			(vias allowed)
			(pads allowed)
			(copperpour not_allowed)
			(footprints allowed)
		)
		(placement
			(enabled no)
			(sheetname "")
		)
		(fill
			(thermal_gap 0.5)
			(thermal_bridge_width 0.5)
			(island_removal_mode 0)
		)
		(polygon
			(pts
				(arc
					(start 73.867264 -150.758144)
					(mid 73.852385 -150.794065)
					(end 73.816464 -150.808944)
				)
				(arc
					(start 72.635364 -150.808944)
					(mid 72.599443 -150.794065)
					(end 72.584564 -150.758144)
				)
				(arc
					(start 72.584564 -149.751796)
					(mid 72.599443 -149.715875)
					(end 72.635364 -149.700996)
				)
				(arc
					(start 73.816464 -149.700996)
					(mid 73.852385 -149.715875)
					(end 73.867264 -149.751796)
				)
			)
		)
	)
	(zone
		(layer "In1.Cu")
		(hatch none 0.5)
		(connect_pads
			(clearance 0)
		)
		(min_thickness 0.25)
		(keepout
			(tracks not_allowed)
			(vias allowed)
			(pads allowed)
			(copperpour not_allowed)
			(footprints allowed)
		)
		(placement
			(enabled no)
			(sheetname "")
		)
		(fill
			(thermal_gap 0.5)
			(thermal_bridge_width 0.5)
			(island_removal_mode 0)
		)
		(polygon
			(pts
				(arc
					(start 422.167304 -117.838474)
					(mid 422.152425 -117.874395)
					(end 422.116504 -117.889274)
				)
				(arc
					(start 420.935404 -117.889274)
					(mid 420.899483 -117.874395)
					(end 420.884604 -117.838474)
				)
				(arc
					(start 420.884604 -116.832126)
					(mid 420.899483 -116.796205)
					(end 420.935404 -116.781326)
				)
				(arc
					(start 422.116504 -116.781326)
					(mid 422.152425 -116.796205)
					(end 422.167304 -116.832126)
				)
			)
		)
	)
	(zone
		(layer "In1.Cu")
		(hatch none 0.5)
		(connect_pads
			(clearance 0)
		)
		(min_thickness 0.25)
		(keepout
			(tracks not_allowed)
			(vias allowed)
			(pads allowed)
			(copperpour not_allowed)
			(footprints allowed)
		)
		(placement
			(enabled no)
			(sheetname "")
		)
		(fill
			(thermal_gap 0.5)
			(thermal_bridge_width 0.5)
			(island_removal_mode 0)
		)
		(polygon
			(pts
				(arc
					(start 54.531514 -363.55401)
					(mid 54.621317 -363.591207)
					(end 54.658514 -363.68101)
				)
				(arc
					(start 54.658514 -363.882178)
					(mid 54.621317 -363.971981)
					(end 54.531514 -364.009178)
				)
				(arc
					(start 54.277514 -364.009178)
					(mid 54.187711 -363.971981)
					(end 54.150514 -363.882178)
				)
				(arc
					(start 54.150514 -363.68101)
					(mid 54.187711 -363.591207)
					(end 54.277514 -363.55401)
				)
			)
		)
	)
	(zone
		(layer "In1.Cu")
		(hatch none 0.5)
		(connect_pads
			(clearance 0)
		)
		(min_thickness 0.25)
		(keepout
			(tracks not_allowed)
			(vias allowed)
			(pads allowed)
			(copperpour not_allowed)
			(footprints allowed)
		)
		(placement
			(enabled no)
			(sheetname "")
		)
		(fill
			(thermal_gap 0.5)
			(thermal_bridge_width 0.5)
			(island_removal_mode 0)
		)
		(polygon
			(pts
				(arc
					(start 267.731748 -343.533222)
					(mid 267.695827 -343.548101)
					(end 267.680948 -343.584022)
				)
				(arc
					(start 267.680948 -344.320622)
					(mid 267.695827 -344.356543)
					(end 267.731748 -344.371422)
				)
				(xy 267.975588 -344.371422) (xy 268.329918 -344.139012) (xy 268.685518 -344.371422)
				(arc
					(start 268.928088 -344.371422)
					(mid 268.964009 -344.356543)
					(end 268.978888 -344.320622)
				)
				(arc
					(start 268.978888 -343.584022)
					(mid 268.964009 -343.548101)
					(end 268.928088 -343.533222)
				)
				(xy 268.685518 -343.533222) (xy 268.328648 -343.765632) (xy 267.974318 -343.533222)
			)
		)
	)
	(zone
		(layer "In1.Cu")
		(hatch none 0.5)
		(connect_pads
			(clearance 0)
		)
		(min_thickness 0.25)
		(keepout
			(tracks not_allowed)
			(vias allowed)
			(pads allowed)
			(copperpour not_allowed)
			(footprints allowed)
		)
		(placement
			(enabled no)
			(sheetname "")
		)
		(fill
			(thermal_gap 0.5)
			(thermal_bridge_width 0.5)
			(island_removal_mode 0)
		)
		(polygon
			(pts
				(arc
					(start 51.25212 -102.04831)
					(mid 51.237241 -102.084231)
					(end 51.20132 -102.09911)
				)
				(arc
					(start 50.02022 -102.09911)
					(mid 49.984299 -102.084231)
					(end 49.96942 -102.04831)
				)
				(arc
					(start 49.96942 -101.041962)
					(mid 49.984299 -101.006041)
					(end 50.02022 -100.991162)
				)
				(arc
					(start 51.20132 -100.991162)
					(mid 51.237241 -101.006041)
					(end 51.25212 -101.041962)
				)
			)
		)
	)
	(zone
		(layer "In1.Cu")
		(hatch none 0.5)
		(connect_pads
			(clearance 0)
		)
		(min_thickness 0.25)
		(keepout
			(tracks not_allowed)
			(vias allowed)
			(pads allowed)
			(copperpour not_allowed)
			(footprints allowed)
		)
		(placement
			(enabled no)
			(sheetname "")
		)
		(fill
			(thermal_gap 0.5)
			(thermal_bridge_width 0.5)
			(island_removal_mode 0)
		)
		(polygon
			(pts
				(arc
					(start 89.187528 -349.679514)
					(mid 89.151607 -349.694393)
					(end 89.136728 -349.730314)
				)
				(arc
					(start 89.136728 -350.466914)
					(mid 89.151607 -350.502835)
					(end 89.187528 -350.517714)
				)
				(xy 89.431368 -350.517714) (xy 89.785698 -350.285304) (xy 90.141298 -350.517714)
				(arc
					(start 90.383868 -350.517714)
					(mid 90.419789 -350.502835)
					(end 90.434668 -350.466914)
				)
				(arc
					(start 90.434668 -349.730314)
					(mid 90.419789 -349.694393)
					(end 90.383868 -349.679514)
				)
				(xy 90.141298 -349.679514) (xy 89.784428 -349.911924) (xy 89.430098 -349.679514)
			)
		)
	)
	(zone
		(layer "In1.Cu")
		(hatch none 0.5)
		(connect_pads
			(clearance 0)
		)
		(min_thickness 0.25)
		(keepout
			(tracks not_allowed)
			(vias allowed)
			(pads allowed)
			(copperpour not_allowed)
			(footprints allowed)
		)
		(placement
			(enabled no)
			(sheetname "")
		)
		(fill
			(thermal_gap 0.5)
			(thermal_bridge_width 0.5)
			(island_removal_mode 0)
		)
		(polygon
			(pts
				(arc
					(start 277.632668 -102.84206)
					(mid 277.647547 -102.806139)
					(end 277.683468 -102.79126)
				)
				(arc
					(start 278.864568 -102.79126)
					(mid 278.900489 -102.806139)
					(end 278.915368 -102.84206)
				)
				(arc
					(start 278.915368 -103.848408)
					(mid 278.900489 -103.884329)
					(end 278.864568 -103.899208)
				)
				(arc
					(start 277.683468 -103.899208)
					(mid 277.647547 -103.884329)
					(end 277.632668 -103.848408)
				)
			)
		)
	)
	(zone
		(layer "In1.Cu")
		(hatch none 0.5)
		(connect_pads
			(clearance 0)
		)
		(min_thickness 0.25)
		(keepout
			(tracks not_allowed)
			(vias allowed)
			(pads allowed)
			(copperpour not_allowed)
			(footprints allowed)
		)
		(placement
			(enabled no)
			(sheetname "")
		)
		(fill
			(thermal_gap 0.5)
			(thermal_bridge_width 0.5)
			(island_removal_mode 0)
		)
		(polygon
			(pts
				(arc
					(start 447.555874 -208.705958)
					(mid 447.540995 -208.741879)
					(end 447.505074 -208.756758)
				)
				(arc
					(start 447.09842 -208.756758)
					(mid 447.062499 -208.741879)
					(end 447.04762 -208.705958)
				)
				(arc
					(start 447.04762 -208.303622)
					(mid 447.062499 -208.267701)
					(end 447.09842 -208.252822)
				)
				(arc
					(start 447.505074 -208.252822)
					(mid 447.540995 -208.267701)
					(end 447.555874 -208.303622)
				)
			)
		)
	)
	(zone
		(layer "In1.Cu")
		(hatch none 0.5)
		(connect_pads
			(clearance 0)
		)
		(min_thickness 0.25)
		(keepout
			(tracks not_allowed)
			(vias allowed)
			(pads allowed)
			(copperpour not_allowed)
			(footprints allowed)
		)
		(placement
			(enabled no)
			(sheetname "")
		)
		(fill
			(thermal_gap 0.5)
			(thermal_bridge_width 0.5)
			(island_removal_mode 0)
		)
		(polygon
			(pts
				(arc
					(start 239.848898 -85.322918)
					(mid 239.938701 -85.360115)
					(end 239.975898 -85.449918)
				)
				(arc
					(start 239.975898 -85.653118)
					(mid 239.938701 -85.742921)
					(end 239.848898 -85.780118)
				)
				(arc
					(start 239.594898 -85.780118)
					(mid 239.505095 -85.742921)
					(end 239.467898 -85.653118)
				)
				(arc
					(start 239.467898 -85.449918)
					(mid 239.505095 -85.360115)
					(end 239.594898 -85.322918)
				)
			)
		)
	)
	(zone
		(layer "In1.Cu")
		(hatch none 0.5)
		(connect_pads
			(clearance 0)
		)
		(min_thickness 0.25)
		(keepout
			(tracks not_allowed)
			(vias allowed)
			(pads allowed)
			(copperpour not_allowed)
			(footprints allowed)
		)
		(placement
			(enabled no)
			(sheetname "")
		)
		(fill
			(thermal_gap 0.5)
			(thermal_bridge_width 0.5)
			(island_removal_mode 0)
		)
		(polygon
			(pts
				(arc
					(start 412.238698 -349.679514)
					(mid 412.202777 -349.694393)
					(end 412.187898 -349.730314)
				)
				(arc
					(start 412.187898 -350.466914)
					(mid 412.202777 -350.502835)
					(end 412.238698 -350.517714)
				)
				(xy 412.482538 -350.517714) (xy 412.836868 -350.285304) (xy 413.192468 -350.517714)
				(arc
					(start 413.435038 -350.517714)
					(mid 413.470959 -350.502835)
					(end 413.485838 -350.466914)
				)
				(arc
					(start 413.485838 -349.730314)
					(mid 413.470959 -349.694393)
					(end 413.435038 -349.679514)
				)
				(xy 413.192468 -349.679514) (xy 412.835598 -349.911924) (xy 412.481268 -349.679514)
			)
		)
	)
	(zone
		(layer "In1.Cu")
		(hatch none 0.5)
		(connect_pads
			(clearance 0)
		)
		(min_thickness 0.25)
		(keepout
			(tracks not_allowed)
			(vias allowed)
			(pads allowed)
			(copperpour not_allowed)
			(footprints allowed)
		)
		(placement
			(enabled no)
			(sheetname "")
		)
		(fill
			(thermal_gap 0.5)
			(thermal_bridge_width 0.5)
			(island_removal_mode 0)
		)
		(polygon
			(pts
				(arc
					(start 22.276054 -343.533222)
					(mid 22.240133 -343.548101)
					(end 22.225254 -343.584022)
				)
				(arc
					(start 22.225254 -344.320622)
					(mid 22.240133 -344.356543)
					(end 22.276054 -344.371422)
				)
				(xy 22.519894 -344.371422) (xy 22.874224 -344.139012) (xy 23.229824 -344.371422)
				(arc
					(start 23.472394 -344.371422)
					(mid 23.508315 -344.356543)
					(end 23.523194 -344.320622)
				)
				(arc
					(start 23.523194 -343.584022)
					(mid 23.508315 -343.548101)
					(end 23.472394 -343.533222)
				)
				(xy 23.229824 -343.533222) (xy 22.872954 -343.765632) (xy 22.518624 -343.533222)
			)
		)
	)
	(zone
		(layer "In1.Cu")
		(hatch none 0.5)
		(connect_pads
			(clearance 0)
		)
		(min_thickness 0.25)
		(keepout
			(tracks not_allowed)
			(vias allowed)
			(pads allowed)
			(copperpour not_allowed)
			(footprints allowed)
		)
		(placement
			(enabled no)
			(sheetname "")
		)
		(fill
			(thermal_gap 0.5)
			(thermal_bridge_width 0.5)
			(island_removal_mode 0)
		)
		(polygon
			(pts
				(arc
					(start 100.44557 -198.63308)
					(mid 100.355767 -198.595883)
					(end 100.31857 -198.50608)
				)
				(arc
					(start 100.31857 -197.89648)
					(mid 100.355767 -197.806677)
					(end 100.44557 -197.76948)
				)
				(arc
					(start 100.970842 -197.76948)
					(mid 101.060645 -197.806677)
					(end 101.097842 -197.89648)
				)
				(arc
					(start 101.097842 -198.50608)
					(mid 101.060645 -198.595883)
					(end 100.970842 -198.63308)
				)
			)
		)
	)
	(zone
		(layer "In1.Cu")
		(hatch none 0.5)
		(connect_pads
			(clearance 0)
		)
		(min_thickness 0.25)
		(keepout
			(tracks not_allowed)
			(vias allowed)
			(pads allowed)
			(copperpour not_allowed)
			(footprints allowed)
		)
		(placement
			(enabled no)
			(sheetname "")
		)
		(fill
			(thermal_gap 0.5)
			(thermal_bridge_width 0.5)
			(island_removal_mode 0)
		)
		(polygon
			(pts
				(arc
					(start 399.55216 -121.958354)
					(mid 399.537281 -121.994275)
					(end 399.50136 -122.009154)
				)
				(arc
					(start 398.32026 -122.009154)
					(mid 398.284339 -121.994275)
					(end 398.26946 -121.958354)
				)
				(arc
					(start 398.26946 -120.952006)
					(mid 398.284339 -120.916085)
					(end 398.32026 -120.901206)
				)
				(arc
					(start 399.50136 -120.901206)
					(mid 399.537281 -120.916085)
					(end 399.55216 -120.952006)
				)
			)
		)
	)
	(zone
		(layer "In1.Cu")
		(hatch none 0.5)
		(connect_pads
			(clearance 0)
		)
		(min_thickness 0.25)
		(keepout
			(tracks not_allowed)
			(vias allowed)
			(pads allowed)
			(copperpour not_allowed)
			(footprints allowed)
		)
		(placement
			(enabled no)
			(sheetname "")
		)
		(fill
			(thermal_gap 0.5)
			(thermal_bridge_width 0.5)
			(island_removal_mode 0)
		)
		(polygon
			(pts
				(arc
					(start 436.329836 -31.77413)
					(mid 436.344715 -31.738209)
					(end 436.380636 -31.72333)
				)
				(arc
					(start 437.612536 -31.72333)
					(mid 437.648457 -31.738209)
					(end 437.663336 -31.77413)
				)
				(arc
					(start 437.663336 -32.805878)
					(mid 437.648457 -32.841799)
					(end 437.612536 -32.856678)
				)
				(arc
					(start 436.380636 -32.856678)
					(mid 436.344715 -32.841799)
					(end 436.329836 -32.805878)
				)
			)
		)
	)
	(zone
		(layer "In1.Cu")
		(hatch none 0.5)
		(connect_pads
			(clearance 0)
		)
		(min_thickness 0.25)
		(keepout
			(tracks not_allowed)
			(vias allowed)
			(pads allowed)
			(copperpour not_allowed)
			(footprints allowed)
		)
		(placement
			(enabled no)
			(sheetname "")
		)
		(fill
			(thermal_gap 0.5)
			(thermal_bridge_width 0.5)
			(island_removal_mode 0)
		)
		(polygon
			(pts
				(arc
					(start 189.967108 -148.9583)
					(mid 189.952229 -148.994221)
					(end 189.916308 -149.0091)
				)
				(arc
					(start 188.735208 -149.0091)
					(mid 188.699287 -148.994221)
					(end 188.684408 -148.9583)
				)
				(arc
					(start 188.684408 -147.951952)
					(mid 188.699287 -147.916031)
					(end 188.735208 -147.901152)
				)
				(arc
					(start 189.916308 -147.901152)
					(mid 189.952229 -147.916031)
					(end 189.967108 -147.951952)
				)
			)
		)
	)
	(zone
		(layer "In1.Cu")
		(hatch none 0.5)
		(connect_pads
			(clearance 0)
		)
		(min_thickness 0.25)
		(keepout
			(tracks not_allowed)
			(vias allowed)
			(pads allowed)
			(copperpour not_allowed)
			(footprints allowed)
		)
		(placement
			(enabled no)
			(sheetname "")
		)
		(fill
			(thermal_gap 0.5)
			(thermal_bridge_width 0.5)
			(island_removal_mode 0)
		)
		(polygon
			(pts
				(arc
					(start 167.351964 -109.248194)
					(mid 167.337085 -109.284115)
					(end 167.301164 -109.298994)
				)
				(arc
					(start 166.120064 -109.298994)
					(mid 166.084143 -109.284115)
					(end 166.069264 -109.248194)
				)
				(arc
					(start 166.069264 -108.241846)
					(mid 166.084143 -108.205925)
					(end 166.120064 -108.191046)
				)
				(arc
					(start 167.301164 -108.191046)
					(mid 167.337085 -108.205925)
					(end 167.351964 -108.241846)
				)
			)
		)
	)
	(zone
		(layer "In1.Cu")
		(hatch none 0.5)
		(connect_pads
			(clearance 0)
		)
		(min_thickness 0.25)
		(keepout
			(tracks not_allowed)
			(vias allowed)
			(pads allowed)
			(copperpour not_allowed)
			(footprints allowed)
		)
		(placement
			(enabled no)
			(sheetname "")
		)
		(fill
			(thermal_gap 0.5)
			(thermal_bridge_width 0.5)
			(island_removal_mode 0)
		)
		(polygon
			(pts
				(arc
					(start 36.219384 -120.253252)
					(mid 36.234263 -120.289173)
					(end 36.270184 -120.304052)
				)
				(arc
					(start 37.006784 -120.304052)
					(mid 37.042705 -120.289173)
					(end 37.057584 -120.253252)
				)
				(xy 37.057584 -120.009412) (xy 36.825174 -119.655082) (xy 37.057584 -119.299482)
				(arc
					(start 37.057584 -119.056912)
					(mid 37.042705 -119.020991)
					(end 37.006784 -119.006112)
				)
				(arc
					(start 36.270184 -119.006112)
					(mid 36.234263 -119.020991)
					(end 36.219384 -119.056912)
				)
				(xy 36.219384 -119.299482) (xy 36.451794 -119.656352) (xy 36.219384 -120.010682)
			)
		)
	)
	(zone
		(layer "In1.Cu")
		(hatch none 0.5)
		(connect_pads
			(clearance 0)
		)
		(min_thickness 0.25)
		(keepout
			(tracks not_allowed)
			(vias allowed)
			(pads allowed)
			(copperpour not_allowed)
			(footprints allowed)
		)
		(placement
			(enabled no)
			(sheetname "")
		)
		(fill
			(thermal_gap 0.5)
			(thermal_bridge_width 0.5)
			(island_removal_mode 0)
		)
		(polygon
			(pts
				(arc
					(start 277.058628 -355.825806)
					(mid 277.022707 -355.840685)
					(end 277.007828 -355.876606)
				)
				(arc
					(start 277.007828 -356.613206)
					(mid 277.022707 -356.649127)
					(end 277.058628 -356.664006)
				)
				(xy 277.302468 -356.664006) (xy 277.656798 -356.431596) (xy 278.012398 -356.664006)
				(arc
					(start 278.254968 -356.664006)
					(mid 278.290889 -356.649127)
					(end 278.305768 -356.613206)
				)
				(arc
					(start 278.305768 -355.876606)
					(mid 278.290889 -355.840685)
					(end 278.254968 -355.825806)
				)
				(xy 278.012398 -355.825806) (xy 277.655528 -356.058216) (xy 277.301198 -355.825806)
			)
		)
	)
	(zone
		(layer "In1.Cu")
		(hatch none 0.5)
		(connect_pads
			(clearance 0)
		)
		(min_thickness 0.25)
		(keepout
			(tracks not_allowed)
			(vias allowed)
			(pads allowed)
			(copperpour not_allowed)
			(footprints allowed)
		)
		(placement
			(enabled no)
			(sheetname "")
		)
		(fill
			(thermal_gap 0.5)
			(thermal_bridge_width 0.5)
			(island_removal_mode 0)
		)
		(polygon
			(pts
				(arc
					(start 304.215292 -34.68624)
					(mid 304.230171 -34.722161)
					(end 304.266092 -34.73704)
				)
				(arc
					(start 305.002692 -34.73704)
					(mid 305.038613 -34.722161)
					(end 305.053492 -34.68624)
				)
				(xy 305.053492 -34.4424) (xy 304.821082 -34.08807) (xy 305.053492 -33.73247)
				(arc
					(start 305.053492 -33.4899)
					(mid 305.038613 -33.453979)
					(end 305.002692 -33.4391)
				)
				(arc
					(start 304.266092 -33.4391)
					(mid 304.230171 -33.453979)
					(end 304.215292 -33.4899)
				)
				(xy 304.215292 -33.73247) (xy 304.447702 -34.08934) (xy 304.215292 -34.44367)
			)
		)
	)
	(zone
		(layer "In1.Cu")
		(hatch none 0.5)
		(connect_pads
			(clearance 0)
		)
		(min_thickness 0.25)
		(keepout
			(tracks not_allowed)
			(vias allowed)
			(pads allowed)
			(copperpour not_allowed)
			(footprints allowed)
		)
		(placement
			(enabled no)
			(sheetname "")
		)
		(fill
			(thermal_gap 0.5)
			(thermal_bridge_width 0.5)
			(island_removal_mode 0)
		)
		(polygon
			(pts
				(arc
					(start 393.732766 -135.761984)
					(mid 393.747645 -135.726063)
					(end 393.783566 -135.711184)
				)
				(arc
					(start 394.964666 -135.711184)
					(mid 395.000587 -135.726063)
					(end 395.015466 -135.761984)
				)
				(arc
					(start 395.015466 -136.768332)
					(mid 395.000587 -136.804253)
					(end 394.964666 -136.819132)
				)
				(arc
					(start 393.783566 -136.819132)
					(mid 393.747645 -136.804253)
					(end 393.732766 -136.768332)
				)
			)
		)
	)
	(zone
		(layer "In1.Cu")
		(hatch none 0.5)
		(connect_pads
			(clearance 0)
		)
		(min_thickness 0.25)
		(keepout
			(tracks not_allowed)
			(vias allowed)
			(pads allowed)
			(copperpour not_allowed)
			(footprints allowed)
		)
		(placement
			(enabled no)
			(sheetname "")
		)
		(fill
			(thermal_gap 0.5)
			(thermal_bridge_width 0.5)
			(island_removal_mode 0)
		)
		(polygon
			(pts
				(arc
					(start 277.632668 -106.441748)
					(mid 277.647547 -106.405827)
					(end 277.683468 -106.390948)
				)
				(arc
					(start 278.864568 -106.390948)
					(mid 278.900489 -106.405827)
					(end 278.915368 -106.441748)
				)
				(arc
					(start 278.915368 -107.448096)
					(mid 278.900489 -107.484017)
					(end 278.864568 -107.498896)
				)
				(arc
					(start 277.683468 -107.498896)
					(mid 277.647547 -107.484017)
					(end 277.632668 -107.448096)
				)
			)
		)
	)
	(zone
		(layer "In1.Cu")
		(hatch none 0.5)
		(connect_pads
			(clearance 0)
		)
		(min_thickness 0.25)
		(keepout
			(tracks not_allowed)
			(vias allowed)
			(pads allowed)
			(copperpour not_allowed)
			(footprints allowed)
		)
		(placement
			(enabled no)
			(sheetname "")
		)
		(fill
			(thermal_gap 0.5)
			(thermal_bridge_width 0.5)
			(island_removal_mode 0)
		)
		(polygon
			(pts
				(arc
					(start 142.786354 -343.533222)
					(mid 142.750433 -343.548101)
					(end 142.735554 -343.584022)
				)
				(arc
					(start 142.735554 -344.320622)
					(mid 142.750433 -344.356543)
					(end 142.786354 -344.371422)
				)
				(xy 143.030194 -344.371422) (xy 143.384524 -344.139012) (xy 143.740124 -344.371422)
				(arc
					(start 143.982694 -344.371422)
					(mid 144.018615 -344.356543)
					(end 144.033494 -344.320622)
				)
				(arc
					(start 144.033494 -343.584022)
					(mid 144.018615 -343.548101)
					(end 143.982694 -343.533222)
				)
				(xy 143.740124 -343.533222) (xy 143.383254 -343.765632) (xy 143.028924 -343.533222)
			)
		)
	)
	(zone
		(layer "In1.Cu")
		(hatch none 0.5)
		(connect_pads
			(clearance 0)
		)
		(min_thickness 0.25)
		(keepout
			(tracks not_allowed)
			(vias allowed)
			(pads allowed)
			(copperpour not_allowed)
			(footprints allowed)
		)
		(placement
			(enabled no)
			(sheetname "")
		)
		(fill
			(thermal_gap 0.5)
			(thermal_bridge_width 0.5)
			(island_removal_mode 0)
		)
		(polygon
			(pts
				(arc
					(start 434.001418 -349.679514)
					(mid 433.965497 -349.694393)
					(end 433.950618 -349.730314)
				)
				(arc
					(start 433.950618 -350.466914)
					(mid 433.965497 -350.502835)
					(end 434.001418 -350.517714)
				)
				(xy 434.245258 -350.517714) (xy 434.599588 -350.285304) (xy 434.955188 -350.517714)
				(arc
					(start 435.197758 -350.517714)
					(mid 435.233679 -350.502835)
					(end 435.248558 -350.466914)
				)
				(arc
					(start 435.248558 -349.730314)
					(mid 435.233679 -349.694393)
					(end 435.197758 -349.679514)
				)
				(xy 434.955188 -349.679514) (xy 434.598318 -349.911924) (xy 434.243988 -349.679514)
			)
		)
	)
	(zone
		(layer "In1.Cu")
		(hatch none 0.5)
		(connect_pads
			(clearance 0)
		)
		(min_thickness 0.25)
		(keepout
			(tracks not_allowed)
			(vias allowed)
			(pads allowed)
			(copperpour not_allowed)
			(footprints allowed)
		)
		(placement
			(enabled no)
			(sheetname "")
		)
		(fill
			(thermal_gap 0.5)
			(thermal_bridge_width 0.5)
			(island_removal_mode 0)
		)
		(polygon
			(pts
				(arc
					(start 133.459474 -355.825806)
					(mid 133.423553 -355.840685)
					(end 133.408674 -355.876606)
				)
				(arc
					(start 133.408674 -356.613206)
					(mid 133.423553 -356.649127)
					(end 133.459474 -356.664006)
				)
				(xy 133.703314 -356.664006) (xy 134.057644 -356.431596) (xy 134.413244 -356.664006)
				(arc
					(start 134.655814 -356.664006)
					(mid 134.691735 -356.649127)
					(end 134.706614 -356.613206)
				)
				(arc
					(start 134.706614 -355.876606)
					(mid 134.691735 -355.840685)
					(end 134.655814 -355.825806)
				)
				(xy 134.413244 -355.825806) (xy 134.056374 -356.058216) (xy 133.702044 -355.825806)
			)
		)
	)
	(zone
		(layer "In1.Cu")
		(hatch none 0.5)
		(connect_pads
			(clearance 0)
		)
		(min_thickness 0.25)
		(keepout
			(tracks not_allowed)
			(vias allowed)
			(pads allowed)
			(copperpour not_allowed)
			(footprints allowed)
		)
		(placement
			(enabled no)
			(sheetname "")
		)
		(fill
			(thermal_gap 0.5)
			(thermal_bridge_width 0.5)
			(island_removal_mode 0)
		)
		(polygon
			(pts
				(arc
					(start 229.539038 -78.567534)
					(mid 229.553917 -78.531613)
					(end 229.589838 -78.516734)
				)
				(arc
					(start 229.998016 -78.516734)
					(mid 230.033937 -78.531613)
					(end 230.048816 -78.567534)
				)
				(arc
					(start 230.048816 -79.0448)
					(mid 230.033937 -79.080721)
					(end 229.998016 -79.0956)
				)
				(arc
					(start 229.589838 -79.0956)
					(mid 229.553917 -79.080721)
					(end 229.539038 -79.0448)
				)
			)
		)
	)
	(zone
		(layer "In1.Cu")
		(hatch none 0.5)
		(connect_pads
			(clearance 0)
		)
		(min_thickness 0.25)
		(keepout
			(tracks not_allowed)
			(vias allowed)
			(pads allowed)
			(copperpour not_allowed)
			(footprints allowed)
		)
		(placement
			(enabled no)
			(sheetname "")
		)
		(fill
			(thermal_gap 0.5)
			(thermal_bridge_width 0.5)
			(island_removal_mode 0)
		)
		(polygon
			(pts
				(arc
					(start 38.861492 -133.269736)
					(mid 38.876371 -133.305657)
					(end 38.912292 -133.320536)
				)
				(arc
					(start 39.648892 -133.320536)
					(mid 39.684813 -133.305657)
					(end 39.699692 -133.269736)
				)
				(xy 39.699692 -133.025896) (xy 39.467282 -132.671566) (xy 39.699692 -132.315966)
				(arc
					(start 39.699692 -132.073396)
					(mid 39.684813 -132.037475)
					(end 39.648892 -132.022596)
				)
				(arc
					(start 38.912292 -132.022596)
					(mid 38.876371 -132.037475)
					(end 38.861492 -132.073396)
				)
				(xy 38.861492 -132.315966) (xy 39.093902 -132.672836) (xy 38.861492 -133.027166)
			)
		)
	)
	(zone
		(layer "In1.Cu")
		(hatch none 0.5)
		(connect_pads
			(clearance 0)
		)
		(min_thickness 0.25)
		(keepout
			(tracks not_allowed)
			(vias allowed)
			(pads allowed)
			(copperpour not_allowed)
			(footprints allowed)
		)
		(placement
			(enabled no)
			(sheetname "")
		)
		(fill
			(thermal_gap 0.5)
			(thermal_bridge_width 0.5)
			(island_removal_mode 0)
		)
		(polygon
			(pts
				(arc
					(start 337.20913 -355.825806)
					(mid 337.173209 -355.840685)
					(end 337.15833 -355.876606)
				)
				(arc
					(start 337.15833 -356.613206)
					(mid 337.173209 -356.649127)
					(end 337.20913 -356.664006)
				)
				(xy 337.45297 -356.664006) (xy 337.8073 -356.431596) (xy 338.1629 -356.664006)
				(arc
					(start 338.40547 -356.664006)
					(mid 338.441391 -356.649127)
					(end 338.45627 -356.613206)
				)
				(arc
					(start 338.45627 -355.876606)
					(mid 338.441391 -355.840685)
					(end 338.40547 -355.825806)
				)
				(xy 338.1629 -355.825806) (xy 337.80603 -356.058216) (xy 337.4517 -355.825806)
			)
		)
	)
	(zone
		(layer "In1.Cu")
		(hatch none 0.5)
		(connect_pads
			(clearance 0)
		)
		(min_thickness 0.25)
		(keepout
			(tracks not_allowed)
			(vias allowed)
			(pads allowed)
			(copperpour not_allowed)
			(footprints allowed)
		)
		(placement
			(enabled no)
			(sheetname "")
		)
		(fill
			(thermal_gap 0.5)
			(thermal_bridge_width 0.5)
			(island_removal_mode 0)
		)
		(polygon
			(pts
				(arc
					(start 69.373242 -32.879538)
					(mid 69.388121 -32.915459)
					(end 69.424042 -32.930338)
				)
				(arc
					(start 70.160642 -32.930338)
					(mid 70.196563 -32.915459)
					(end 70.211442 -32.879538)
				)
				(xy 70.211442 -32.635698) (xy 69.979032 -32.281368) (xy 70.211442 -31.925768)
				(arc
					(start 70.211442 -31.683198)
					(mid 70.196563 -31.647277)
					(end 70.160642 -31.632398)
				)
				(arc
					(start 69.424042 -31.632398)
					(mid 69.388121 -31.647277)
					(end 69.373242 -31.683198)
				)
				(xy 69.373242 -31.925768) (xy 69.605652 -32.282638) (xy 69.373242 -32.636968)
			)
		)
	)
	(zone
		(layer "In1.Cu")
		(hatch none 0.5)
		(connect_pads
			(clearance 0)
		)
		(min_thickness 0.25)
		(keepout
			(tracks not_allowed)
			(vias allowed)
			(pads allowed)
			(copperpour not_allowed)
			(footprints allowed)
		)
		(placement
			(enabled no)
			(sheetname "")
		)
		(fill
			(thermal_gap 0.5)
			(thermal_bridge_width 0.5)
			(island_removal_mode 0)
		)
		(polygon
			(pts
				(arc
					(start 102.747318 -389.424418)
					(mid 102.762197 -389.388497)
					(end 102.798118 -389.373618)
				)
				(arc
					(start 103.455216 -389.373618)
					(mid 103.491137 -389.388497)
					(end 103.506016 -389.424418)
				)
				(arc
					(start 103.506016 -390.064752)
					(mid 103.491137 -390.100673)
					(end 103.455216 -390.115552)
				)
				(arc
					(start 102.798118 -390.115552)
					(mid 102.762197 -390.100673)
					(end 102.747318 -390.064752)
				)
			)
		)
	)
	(zone
		(layer "In1.Cu")
		(hatch none 0.5)
		(connect_pads
			(clearance 0)
		)
		(min_thickness 0.25)
		(keepout
			(tracks not_allowed)
			(vias allowed)
			(pads allowed)
			(copperpour not_allowed)
			(footprints allowed)
		)
		(placement
			(enabled no)
			(sheetname "")
		)
		(fill
			(thermal_gap 0.5)
			(thermal_bridge_width 0.5)
			(island_removal_mode 0)
		)
		(polygon
			(pts
				(arc
					(start 168.238678 -349.679514)
					(mid 168.202757 -349.694393)
					(end 168.187878 -349.730314)
				)
				(arc
					(start 168.187878 -350.466914)
					(mid 168.202757 -350.502835)
					(end 168.238678 -350.517714)
				)
				(xy 168.482518 -350.517714) (xy 168.836848 -350.285304) (xy 169.192448 -350.517714)
				(arc
					(start 169.435018 -350.517714)
					(mid 169.470939 -350.502835)
					(end 169.485818 -350.466914)
				)
				(arc
					(start 169.485818 -349.730314)
					(mid 169.470939 -349.694393)
					(end 169.435018 -349.679514)
				)
				(xy 169.192448 -349.679514) (xy 168.835578 -349.911924) (xy 168.481248 -349.679514)
			)
		)
	)
	(zone
		(layer "In1.Cu")
		(hatch none 0.5)
		(connect_pads
			(clearance 0)
		)
		(min_thickness 0.25)
		(keepout
			(tracks not_allowed)
			(vias allowed)
			(pads allowed)
			(copperpour not_allowed)
			(footprints allowed)
		)
		(placement
			(enabled no)
			(sheetname "")
		)
		(fill
			(thermal_gap 0.5)
			(thermal_bridge_width 0.5)
			(island_removal_mode 0)
		)
		(polygon
			(pts
				(arc
					(start 167.351964 -123.758452)
					(mid 167.337085 -123.794373)
					(end 167.301164 -123.809252)
				)
				(arc
					(start 166.120064 -123.809252)
					(mid 166.084143 -123.794373)
					(end 166.069264 -123.758452)
				)
				(arc
					(start 166.069264 -122.752104)
					(mid 166.084143 -122.716183)
					(end 166.120064 -122.701304)
				)
				(arc
					(start 167.301164 -122.701304)
					(mid 167.337085 -122.716183)
					(end 167.351964 -122.752104)
				)
			)
		)
	)
	(zone
		(layer "In1.Cu")
		(hatch none 0.5)
		(connect_pads
			(clearance 0)
		)
		(min_thickness 0.25)
		(keepout
			(tracks not_allowed)
			(vias allowed)
			(pads allowed)
			(copperpour not_allowed)
			(footprints allowed)
		)
		(placement
			(enabled no)
			(sheetname "")
		)
		(fill
			(thermal_gap 0.5)
			(thermal_bridge_width 0.5)
			(island_removal_mode 0)
		)
		(polygon
			(pts
				(arc
					(start 393.732766 -119.151908)
					(mid 393.747645 -119.115987)
					(end 393.783566 -119.101108)
				)
				(arc
					(start 394.964666 -119.101108)
					(mid 395.000587 -119.115987)
					(end 395.015466 -119.151908)
				)
				(arc
					(start 395.015466 -120.158256)
					(mid 395.000587 -120.194177)
					(end 394.964666 -120.209056)
				)
				(arc
					(start 393.783566 -120.209056)
					(mid 393.747645 -120.194177)
					(end 393.732766 -120.158256)
				)
			)
		)
	)
	(zone
		(layer "In1.Cu")
		(hatch none 0.5)
		(connect_pads
			(clearance 0)
		)
		(min_thickness 0.25)
		(keepout
			(tracks not_allowed)
			(vias allowed)
			(pads allowed)
			(copperpour not_allowed)
			(footprints allowed)
		)
		(placement
			(enabled no)
			(sheetname "")
		)
		(fill
			(thermal_gap 0.5)
			(thermal_bridge_width 0.5)
			(island_removal_mode 0)
		)
		(polygon
			(pts
				(arc
					(start 198.34225 -149.051264)
					(mid 198.357129 -149.087185)
					(end 198.39305 -149.102064)
				)
				(arc
					(start 199.12965 -149.102064)
					(mid 199.165571 -149.087185)
					(end 199.18045 -149.051264)
				)
				(xy 199.18045 -148.807424) (xy 198.94804 -148.453094) (xy 199.18045 -148.097494)
				(arc
					(start 199.18045 -147.854924)
					(mid 199.165571 -147.819003)
					(end 199.12965 -147.804124)
				)
				(arc
					(start 198.39305 -147.804124)
					(mid 198.357129 -147.819003)
					(end 198.34225 -147.854924)
				)
				(xy 198.34225 -148.097494) (xy 198.57466 -148.454364) (xy 198.34225 -148.808694)
			)
		)
	)
	(zone
		(layer "In1.Cu")
		(hatch none 0.5)
		(connect_pads
			(clearance 0)
		)
		(min_thickness 0.25)
		(keepout
			(tracks not_allowed)
			(vias allowed)
			(pads allowed)
			(copperpour not_allowed)
			(footprints allowed)
		)
		(placement
			(enabled no)
			(sheetname "")
		)
		(fill
			(thermal_gap 0.5)
			(thermal_bridge_width 0.5)
			(island_removal_mode 0)
		)
		(polygon
			(pts
				(arc
					(start 277.058628 -343.533222)
					(mid 277.022707 -343.548101)
					(end 277.007828 -343.584022)
				)
				(arc
					(start 277.007828 -344.320622)
					(mid 277.022707 -344.356543)
					(end 277.058628 -344.371422)
				)
				(xy 277.302468 -344.371422) (xy 277.656798 -344.139012) (xy 278.012398 -344.371422)
				(arc
					(start 278.254968 -344.371422)
					(mid 278.290889 -344.356543)
					(end 278.305768 -344.320622)
				)
				(arc
					(start 278.305768 -343.584022)
					(mid 278.290889 -343.548101)
					(end 278.254968 -343.533222)
				)
				(xy 278.012398 -343.533222) (xy 277.655528 -343.765632) (xy 277.301198 -343.533222)
			)
		)
	)
	(zone
		(layer "In1.Cu")
		(hatch none 0.5)
		(connect_pads
			(clearance 0)
		)
		(min_thickness 0.25)
		(keepout
			(tracks not_allowed)
			(vias allowed)
			(pads allowed)
			(copperpour not_allowed)
			(footprints allowed)
		)
		(placement
			(enabled no)
			(sheetname "")
		)
		(fill
			(thermal_gap 0.5)
			(thermal_bridge_width 0.5)
			(island_removal_mode 0)
		)
		(polygon
			(pts
				(arc
					(start 430.542446 -125.131068)
					(mid 430.557325 -125.166989)
					(end 430.593246 -125.181868)
				)
				(arc
					(start 431.329846 -125.181868)
					(mid 431.365767 -125.166989)
					(end 431.380646 -125.131068)
				)
				(xy 431.380646 -124.887228) (xy 431.148236 -124.532898) (xy 431.380646 -124.177298)
				(arc
					(start 431.380646 -123.934728)
					(mid 431.365767 -123.898807)
					(end 431.329846 -123.883928)
				)
				(arc
					(start 430.593246 -123.883928)
					(mid 430.557325 -123.898807)
					(end 430.542446 -123.934728)
				)
				(xy 430.542446 -124.177298) (xy 430.774856 -124.534168) (xy 430.542446 -124.888498)
			)
		)
	)
	(zone
		(layer "In1.Cu")
		(hatch none 0.5)
		(connect_pads
			(clearance 0)
		)
		(min_thickness 0.25)
		(keepout
			(tracks not_allowed)
			(vias allowed)
			(pads allowed)
			(copperpour not_allowed)
			(footprints allowed)
		)
		(placement
			(enabled no)
			(sheetname "")
		)
		(fill
			(thermal_gap 0.5)
			(thermal_bridge_width 0.5)
			(island_removal_mode 0)
		)
		(polygon
			(pts
				(arc
					(start 121.023634 -355.825806)
					(mid 120.987713 -355.840685)
					(end 120.972834 -355.876606)
				)
				(arc
					(start 120.972834 -356.613206)
					(mid 120.987713 -356.649127)
					(end 121.023634 -356.664006)
				)
				(xy 121.267474 -356.664006) (xy 121.621804 -356.431596) (xy 121.977404 -356.664006)
				(arc
					(start 122.219974 -356.664006)
					(mid 122.255895 -356.649127)
					(end 122.270774 -356.613206)
				)
				(arc
					(start 122.270774 -355.876606)
					(mid 122.255895 -355.840685)
					(end 122.219974 -355.825806)
				)
				(xy 121.977404 -355.825806) (xy 121.620534 -356.058216) (xy 121.266204 -355.825806)
			)
		)
	)
	(zone
		(layer "In1.Cu")
		(hatch none 0.5)
		(connect_pads
			(clearance 0)
		)
		(min_thickness 0.25)
		(keepout
			(tracks not_allowed)
			(vias allowed)
			(pads allowed)
			(copperpour not_allowed)
			(footprints allowed)
		)
		(placement
			(enabled no)
			(sheetname "")
		)
		(fill
			(thermal_gap 0.5)
			(thermal_bridge_width 0.5)
			(island_removal_mode 0)
		)
		(polygon
			(pts
				(arc
					(start 73.867264 -123.23826)
					(mid 73.852385 -123.274181)
					(end 73.816464 -123.28906)
				)
				(arc
					(start 72.635364 -123.28906)
					(mid 72.599443 -123.274181)
					(end 72.584564 -123.23826)
				)
				(arc
					(start 72.584564 -122.231912)
					(mid 72.599443 -122.195991)
					(end 72.635364 -122.181112)
				)
				(arc
					(start 73.816464 -122.181112)
					(mid 73.852385 -122.195991)
					(end 73.867264 -122.231912)
				)
			)
		)
	)
	(zone
		(layer "In1.Cu")
		(hatch none 0.5)
		(connect_pads
			(clearance 0)
		)
		(min_thickness 0.25)
		(keepout
			(tracks not_allowed)
			(vias allowed)
			(pads allowed)
			(copperpour not_allowed)
			(footprints allowed)
		)
		(placement
			(enabled no)
			(sheetname "")
		)
		(fill
			(thermal_gap 0.5)
			(thermal_bridge_width 0.5)
			(island_removal_mode 0)
		)
		(polygon
			(pts
				(arc
					(start 167.351964 -131.368292)
					(mid 167.337085 -131.404213)
					(end 167.301164 -131.419092)
				)
				(arc
					(start 166.120064 -131.419092)
					(mid 166.084143 -131.404213)
					(end 166.069264 -131.368292)
				)
				(arc
					(start 166.069264 -130.361944)
					(mid 166.084143 -130.326023)
					(end 166.120064 -130.311144)
				)
				(arc
					(start 167.301164 -130.311144)
					(mid 167.337085 -130.326023)
					(end 167.351964 -130.361944)
				)
			)
		)
	)
	(zone
		(layer "In1.Cu")
		(hatch none 0.5)
		(connect_pads
			(clearance 0)
		)
		(min_thickness 0.25)
		(keepout
			(tracks not_allowed)
			(vias allowed)
			(pads allowed)
			(copperpour not_allowed)
			(footprints allowed)
		)
		(placement
			(enabled no)
			(sheetname "")
		)
		(fill
			(thermal_gap 0.5)
			(thermal_bridge_width 0.5)
			(island_removal_mode 0)
		)
		(polygon
			(pts
				(arc
					(start 389.676386 -343.533222)
					(mid 389.640465 -343.548101)
					(end 389.625586 -343.584022)
				)
				(arc
					(start 389.625586 -344.320622)
					(mid 389.640465 -344.356543)
					(end 389.676386 -344.371422)
				)
				(xy 389.920226 -344.371422) (xy 390.274556 -344.139012) (xy 390.630156 -344.371422)
				(arc
					(start 390.872726 -344.371422)
					(mid 390.908647 -344.356543)
					(end 390.923526 -344.320622)
				)
				(arc
					(start 390.923526 -343.584022)
					(mid 390.908647 -343.548101)
					(end 390.872726 -343.533222)
				)
				(xy 390.630156 -343.533222) (xy 390.273286 -343.765632) (xy 389.918956 -343.533222)
			)
		)
	)
	(zone
		(layer "In1.Cu")
		(hatch none 0.5)
		(connect_pads
			(clearance 0)
		)
		(min_thickness 0.25)
		(keepout
			(tracks not_allowed)
			(vias allowed)
			(pads allowed)
			(copperpour not_allowed)
			(footprints allowed)
		)
		(placement
			(enabled no)
			(sheetname "")
		)
		(fill
			(thermal_gap 0.5)
			(thermal_bridge_width 0.5)
			(island_removal_mode 0)
		)
		(polygon
			(pts
				(arc
					(start 274.099782 -27.405838)
					(mid 274.084903 -27.441759)
					(end 274.048982 -27.456638)
				)
				(arc
					(start 272.817082 -27.456638)
					(mid 272.781161 -27.441759)
					(end 272.766282 -27.405838)
				)
				(arc
					(start 272.766282 -26.37409)
					(mid 272.781161 -26.338169)
					(end 272.817082 -26.32329)
				)
				(arc
					(start 274.048982 -26.32329)
					(mid 274.084903 -26.338169)
					(end 274.099782 -26.37409)
				)
			)
		)
	)
	(zone
		(layer "In1.Cu")
		(hatch none 0.5)
		(connect_pads
			(clearance 0)
		)
		(min_thickness 0.25)
		(keepout
			(tracks not_allowed)
			(vias allowed)
			(pads allowed)
			(copperpour not_allowed)
			(footprints allowed)
		)
		(placement
			(enabled no)
			(sheetname "")
		)
		(fill
			(thermal_gap 0.5)
			(thermal_bridge_width 0.5)
			(island_removal_mode 0)
		)
		(polygon
			(pts
				(arc
					(start 283.452062 -102.04831)
					(mid 283.437183 -102.084231)
					(end 283.401262 -102.09911)
				)
				(arc
					(start 282.220162 -102.09911)
					(mid 282.184241 -102.084231)
					(end 282.169362 -102.04831)
				)
				(arc
					(start 282.169362 -101.041962)
					(mid 282.184241 -101.006041)
					(end 282.220162 -100.991162)
				)
				(arc
					(start 283.401262 -100.991162)
					(mid 283.437183 -101.006041)
					(end 283.452062 -101.041962)
				)
			)
		)
	)
	(zone
		(layer "In1.Cu")
		(hatch none 0.5)
		(connect_pads
			(clearance 0)
		)
		(min_thickness 0.25)
		(keepout
			(tracks not_allowed)
			(vias allowed)
			(pads allowed)
			(copperpour not_allowed)
			(footprints allowed)
		)
		(placement
			(enabled no)
			(sheetname "")
		)
		(fill
			(thermal_gap 0.5)
			(thermal_bridge_width 0.5)
			(island_removal_mode 0)
		)
		(polygon
			(pts
				(arc
					(start 441.439808 18.577052)
					(mid 441.462126 18.630934)
					(end 441.516008 18.653252)
				)
				(arc
					(start 442.128148 18.653252)
					(mid 442.18203 18.630934)
					(end 442.204348 18.577052)
				)
				(arc
					(start 442.204348 17.479772)
					(mid 442.18203 17.42589)
					(end 442.128148 17.403572)
				)
				(arc
					(start 441.516008 17.403572)
					(mid 441.462126 17.42589)
					(end 441.439808 17.479772)
				)
			)
		)
	)
	(zone
		(layer "In1.Cu")
		(hatch none 0.5)
		(connect_pads
			(clearance 0)
		)
		(min_thickness 0.25)
		(keepout
			(tracks not_allowed)
			(vias allowed)
			(pads allowed)
			(copperpour not_allowed)
			(footprints allowed)
		)
		(placement
			(enabled no)
			(sheetname "")
		)
		(fill
			(thermal_gap 0.5)
			(thermal_bridge_width 0.5)
			(island_removal_mode 0)
		)
		(polygon
			(pts
				(arc
					(start 154.961336 -136.869678)
					(mid 154.976215 -136.905599)
					(end 155.012136 -136.920478)
				)
				(arc
					(start 155.748736 -136.920478)
					(mid 155.784657 -136.905599)
					(end 155.799536 -136.869678)
				)
				(xy 155.799536 -136.625838) (xy 155.567126 -136.271508) (xy 155.799536 -135.915908)
				(arc
					(start 155.799536 -135.673338)
					(mid 155.784657 -135.637417)
					(end 155.748736 -135.622538)
				)
				(arc
					(start 155.012136 -135.622538)
					(mid 154.976215 -135.637417)
					(end 154.961336 -135.673338)
				)
				(xy 154.961336 -135.915908) (xy 155.193746 -136.272778) (xy 154.961336 -136.627108)
			)
		)
	)
	(zone
		(layer "In1.Cu")
		(hatch none 0.5)
		(connect_pads
			(clearance 0)
		)
		(min_thickness 0.25)
		(keepout
			(tracks not_allowed)
			(vias allowed)
			(pads allowed)
			(copperpour not_allowed)
			(footprints allowed)
		)
		(placement
			(enabled no)
			(sheetname "")
		)
		(fill
			(thermal_gap 0.5)
			(thermal_bridge_width 0.5)
			(island_removal_mode 0)
		)
		(polygon
			(pts
				(arc
					(start 280.167588 -343.533222)
					(mid 280.131667 -343.548101)
					(end 280.116788 -343.584022)
				)
				(arc
					(start 280.116788 -344.320622)
					(mid 280.131667 -344.356543)
					(end 280.167588 -344.371422)
				)
				(xy 280.411428 -344.371422) (xy 280.765758 -344.139012) (xy 281.121358 -344.371422)
				(arc
					(start 281.363928 -344.371422)
					(mid 281.399849 -344.356543)
					(end 281.414728 -344.320622)
				)
				(arc
					(start 281.414728 -343.584022)
					(mid 281.399849 -343.548101)
					(end 281.363928 -343.533222)
				)
				(xy 281.121358 -343.533222) (xy 280.764488 -343.765632) (xy 280.410158 -343.533222)
			)
		)
	)
	(zone
		(layer "In1.Cu")
		(hatch none 0.5)
		(connect_pads
			(clearance 0)
		)
		(min_thickness 0.25)
		(keepout
			(tracks not_allowed)
			(vias allowed)
			(pads allowed)
			(copperpour not_allowed)
			(footprints allowed)
		)
		(placement
			(enabled no)
			(sheetname "")
		)
		(fill
			(thermal_gap 0.5)
			(thermal_bridge_width 0.5)
			(island_removal_mode 0)
		)
		(polygon
			(pts
				(arc
					(start 76.751688 -343.533222)
					(mid 76.715767 -343.548101)
					(end 76.700888 -343.584022)
				)
				(arc
					(start 76.700888 -344.320622)
					(mid 76.715767 -344.356543)
					(end 76.751688 -344.371422)
				)
				(xy 76.995528 -344.371422) (xy 77.349858 -344.139012) (xy 77.705458 -344.371422)
				(arc
					(start 77.948028 -344.371422)
					(mid 77.983949 -344.356543)
					(end 77.998828 -344.320622)
				)
				(arc
					(start 77.998828 -343.584022)
					(mid 77.983949 -343.548101)
					(end 77.948028 -343.533222)
				)
				(xy 77.705458 -343.533222) (xy 77.348588 -343.765632) (xy 76.994258 -343.533222)
			)
		)
	)
	(zone
		(layer "In1.Cu")
		(hatch none 0.5)
		(connect_pads
			(clearance 0)
		)
		(min_thickness 0.25)
		(keepout
			(tracks not_allowed)
			(vias allowed)
			(pads allowed)
			(copperpour not_allowed)
			(footprints allowed)
		)
		(placement
			(enabled no)
			(sheetname "")
		)
		(fill
			(thermal_gap 0.5)
			(thermal_bridge_width 0.5)
			(island_removal_mode 0)
		)
		(polygon
			(pts
				(arc
					(start 36.219384 -112.949736)
					(mid 36.234263 -112.985657)
					(end 36.270184 -113.000536)
				)
				(arc
					(start 37.006784 -113.000536)
					(mid 37.042705 -112.985657)
					(end 37.057584 -112.949736)
				)
				(xy 37.057584 -112.705896) (xy 36.825174 -112.351566) (xy 37.057584 -111.995966)
				(arc
					(start 37.057584 -111.753396)
					(mid 37.042705 -111.717475)
					(end 37.006784 -111.702596)
				)
				(arc
					(start 36.270184 -111.702596)
					(mid 36.234263 -111.717475)
					(end 36.219384 -111.753396)
				)
				(xy 36.219384 -111.995966) (xy 36.451794 -112.352836) (xy 36.219384 -112.707166)
			)
		)
	)
	(zone
		(layer "In1.Cu")
		(hatch none 0.5)
		(connect_pads
			(clearance 0)
		)
		(min_thickness 0.25)
		(keepout
			(tracks not_allowed)
			(vias allowed)
			(pads allowed)
			(copperpour not_allowed)
			(footprints allowed)
		)
		(placement
			(enabled no)
			(sheetname "")
		)
		(fill
			(thermal_gap 0.5)
			(thermal_bridge_width 0.5)
			(island_removal_mode 0)
		)
		(polygon
			(pts
				(arc
					(start 416.199828 -32.805878)
					(mid 416.184949 -32.841799)
					(end 416.149028 -32.856678)
				)
				(arc
					(start 414.917128 -32.856678)
					(mid 414.881207 -32.841799)
					(end 414.866328 -32.805878)
				)
				(arc
					(start 414.866328 -31.77413)
					(mid 414.881207 -31.738209)
					(end 414.917128 -31.72333)
				)
				(arc
					(start 416.149028 -31.72333)
					(mid 416.184949 -31.738209)
					(end 416.199828 -31.77413)
				)
			)
		)
	)
	(zone
		(layer "In1.Cu")
		(hatch none 0.5)
		(connect_pads
			(clearance 0)
		)
		(min_thickness 0.25)
		(keepout
			(tracks not_allowed)
			(vias allowed)
			(pads allowed)
			(copperpour not_allowed)
			(footprints allowed)
		)
		(placement
			(enabled no)
			(sheetname "")
		)
		(fill
			(thermal_gap 0.5)
			(thermal_bridge_width 0.5)
			(island_removal_mode 0)
		)
		(polygon
			(pts
				(arc
					(start 36.219384 -123.853194)
					(mid 36.234263 -123.889115)
					(end 36.270184 -123.903994)
				)
				(arc
					(start 37.006784 -123.903994)
					(mid 37.042705 -123.889115)
					(end 37.057584 -123.853194)
				)
				(xy 37.057584 -123.609354) (xy 36.825174 -123.255024) (xy 37.057584 -122.899424)
				(arc
					(start 37.057584 -122.656854)
					(mid 37.042705 -122.620933)
					(end 37.006784 -122.606054)
				)
				(arc
					(start 36.270184 -122.606054)
					(mid 36.234263 -122.620933)
					(end 36.219384 -122.656854)
				)
				(xy 36.219384 -122.899424) (xy 36.451794 -123.256294) (xy 36.219384 -123.610624)
			)
		)
	)
	(zone
		(layer "In1.Cu")
		(hatch none 0.5)
		(connect_pads
			(clearance 0)
		)
		(min_thickness 0.25)
		(keepout
			(tracks not_allowed)
			(vias allowed)
			(pads allowed)
			(copperpour not_allowed)
			(footprints allowed)
		)
		(placement
			(enabled no)
			(sheetname "")
		)
		(fill
			(thermal_gap 0.5)
			(thermal_bridge_width 0.5)
			(island_removal_mode 0)
		)
		(polygon
			(pts
				(arc
					(start 277.632668 -110.041944)
					(mid 277.647547 -110.006023)
					(end 277.683468 -109.991144)
				)
				(arc
					(start 278.864568 -109.991144)
					(mid 278.900489 -110.006023)
					(end 278.915368 -110.041944)
				)
				(arc
					(start 278.915368 -111.048292)
					(mid 278.900489 -111.084213)
					(end 278.864568 -111.099092)
				)
				(arc
					(start 277.683468 -111.099092)
					(mid 277.647547 -111.084213)
					(end 277.632668 -111.048292)
				)
			)
		)
	)
	(zone
		(layer "In1.Cu")
		(hatch none 0.5)
		(connect_pads
			(clearance 0)
		)
		(min_thickness 0.25)
		(keepout
			(tracks not_allowed)
			(vias allowed)
			(pads allowed)
			(copperpour not_allowed)
			(footprints allowed)
		)
		(placement
			(enabled no)
			(sheetname "")
		)
		(fill
			(thermal_gap 0.5)
			(thermal_bridge_width 0.5)
			(island_removal_mode 0)
		)
		(polygon
			(pts
				(arc
					(start 399.55216 -120.158256)
					(mid 399.537281 -120.194177)
					(end 399.50136 -120.209056)
				)
				(arc
					(start 398.32026 -120.209056)
					(mid 398.284339 -120.194177)
					(end 398.26946 -120.158256)
				)
				(arc
					(start 398.26946 -119.151908)
					(mid 398.284339 -119.115987)
					(end 398.32026 -119.101108)
				)
				(arc
					(start 399.50136 -119.101108)
					(mid 399.537281 -119.115987)
					(end 399.55216 -119.151908)
				)
			)
		)
	)
	(zone
		(layer "In1.Cu")
		(hatch none 0.5)
		(connect_pads
			(clearance 0)
		)
		(min_thickness 0.25)
		(keepout
			(tracks not_allowed)
			(vias allowed)
			(pads allowed)
			(copperpour not_allowed)
			(footprints allowed)
		)
		(placement
			(enabled no)
			(sheetname "")
		)
		(fill
			(thermal_gap 0.5)
			(thermal_bridge_width 0.5)
			(island_removal_mode 0)
		)
		(polygon
			(pts
				(arc
					(start 15.899892 -29.205936)
					(mid 15.885013 -29.241857)
					(end 15.849092 -29.256736)
				)
				(arc
					(start 14.617192 -29.256736)
					(mid 14.581271 -29.241857)
					(end 14.566392 -29.205936)
				)
				(arc
					(start 14.566392 -28.174188)
					(mid 14.581271 -28.138267)
					(end 14.617192 -28.123388)
				)
				(arc
					(start 15.849092 -28.123388)
					(mid 15.885013 -28.138267)
					(end 15.899892 -28.174188)
				)
			)
		)
	)
	(zone
		(layer "In1.Cu")
		(hatch none 0.5)
		(connect_pads
			(clearance 0)
		)
		(min_thickness 0.25)
		(keepout
			(tracks not_allowed)
			(vias allowed)
			(pads allowed)
			(copperpour not_allowed)
			(footprints allowed)
		)
		(placement
			(enabled no)
			(sheetname "")
		)
		(fill
			(thermal_gap 0.5)
			(thermal_bridge_width 0.5)
			(island_removal_mode 0)
		)
		(polygon
			(pts
				(arc
					(start 430.892458 -355.825806)
					(mid 430.856537 -355.840685)
					(end 430.841658 -355.876606)
				)
				(arc
					(start 430.841658 -356.613206)
					(mid 430.856537 -356.649127)
					(end 430.892458 -356.664006)
				)
				(xy 431.136298 -356.664006) (xy 431.490628 -356.431596) (xy 431.846228 -356.664006)
				(arc
					(start 432.088798 -356.664006)
					(mid 432.124719 -356.649127)
					(end 432.139598 -356.613206)
				)
				(arc
					(start 432.139598 -355.876606)
					(mid 432.124719 -355.840685)
					(end 432.088798 -355.825806)
				)
				(xy 431.846228 -355.825806) (xy 431.489358 -356.058216) (xy 431.135028 -355.825806)
			)
		)
	)
	(zone
		(layer "In1.Cu")
		(hatch none 0.5)
		(connect_pads
			(clearance 0)
		)
		(min_thickness 0.25)
		(keepout
			(tracks not_allowed)
			(vias allowed)
			(pads allowed)
			(copperpour not_allowed)
			(footprints allowed)
		)
		(placement
			(enabled no)
			(sheetname "")
		)
		(fill
			(thermal_gap 0.5)
			(thermal_bridge_width 0.5)
			(island_removal_mode 0)
		)
		(polygon
			(pts
				(arc
					(start 68.04787 -155.151836)
					(mid 68.062749 -155.115915)
					(end 68.09867 -155.101036)
				)
				(arc
					(start 69.27977 -155.101036)
					(mid 69.315691 -155.115915)
					(end 69.33057 -155.151836)
				)
				(arc
					(start 69.33057 -156.158184)
					(mid 69.315691 -156.194105)
					(end 69.27977 -156.208984)
				)
				(arc
					(start 68.09867 -156.208984)
					(mid 68.062749 -156.194105)
					(end 68.04787 -156.158184)
				)
			)
		)
	)
	(zone
		(layer "In1.Cu")
		(hatch none 0.5)
		(connect_pads
			(clearance 0)
		)
		(min_thickness 0.25)
		(keepout
			(tracks not_allowed)
			(vias allowed)
			(pads allowed)
			(copperpour not_allowed)
			(footprints allowed)
		)
		(placement
			(enabled no)
			(sheetname "")
		)
		(fill
			(thermal_gap 0.5)
			(thermal_bridge_width 0.5)
			(island_removal_mode 0)
		)
		(polygon
			(pts
				(arc
					(start 41.89984 -34.605976)
					(mid 41.884961 -34.641897)
					(end 41.84904 -34.656776)
				)
				(arc
					(start 40.61714 -34.656776)
					(mid 40.581219 -34.641897)
					(end 40.56634 -34.605976)
				)
				(arc
					(start 40.56634 -33.574228)
					(mid 40.581219 -33.538307)
					(end 40.61714 -33.523428)
				)
				(arc
					(start 41.84904 -33.523428)
					(mid 41.884961 -33.538307)
					(end 41.89984 -33.574228)
				)
			)
		)
	)
	(zone
		(layer "In1.Cu")
		(hatch none 0.5)
		(connect_pads
			(clearance 0)
		)
		(min_thickness 0.25)
		(keepout
			(tracks not_allowed)
			(vias allowed)
			(pads allowed)
			(copperpour not_allowed)
			(footprints allowed)
		)
		(placement
			(enabled no)
			(sheetname "")
		)
		(fill
			(thermal_gap 0.5)
			(thermal_bridge_width 0.5)
			(island_removal_mode 0)
		)
		(polygon
			(pts
				(arc
					(start 415.347658 -349.679514)
					(mid 415.311737 -349.694393)
					(end 415.296858 -349.730314)
				)
				(arc
					(start 415.296858 -350.466914)
					(mid 415.311737 -350.502835)
					(end 415.347658 -350.517714)
				)
				(xy 415.591498 -350.517714) (xy 415.945828 -350.285304) (xy 416.301428 -350.517714)
				(arc
					(start 416.543998 -350.517714)
					(mid 416.579919 -350.502835)
					(end 416.594798 -350.466914)
				)
				(arc
					(start 416.594798 -349.730314)
					(mid 416.579919 -349.694393)
					(end 416.543998 -349.679514)
				)
				(xy 416.301428 -349.679514) (xy 415.944558 -349.911924) (xy 415.590228 -349.679514)
			)
		)
	)
	(zone
		(layer "In1.Cu")
		(hatch none 0.5)
		(connect_pads
			(clearance 0)
		)
		(min_thickness 0.25)
		(keepout
			(tracks not_allowed)
			(vias allowed)
			(pads allowed)
			(copperpour not_allowed)
			(footprints allowed)
		)
		(placement
			(enabled no)
			(sheetname "")
		)
		(fill
			(thermal_gap 0.5)
			(thermal_bridge_width 0.5)
			(island_removal_mode 0)
		)
		(polygon
			(pts
				(arc
					(start 45.432726 -104.641904)
					(mid 45.447605 -104.605983)
					(end 45.483526 -104.591104)
				)
				(arc
					(start 46.664626 -104.591104)
					(mid 46.700547 -104.605983)
					(end 46.715426 -104.641904)
				)
				(arc
					(start 46.715426 -105.648252)
					(mid 46.700547 -105.684173)
					(end 46.664626 -105.699052)
				)
				(arc
					(start 45.483526 -105.699052)
					(mid 45.447605 -105.684173)
					(end 45.432726 -105.648252)
				)
			)
		)
	)
	(zone
		(layer "In1.Cu")
		(hatch none 0.5)
		(connect_pads
			(clearance 0)
		)
		(min_thickness 0.25)
		(keepout
			(tracks not_allowed)
			(vias allowed)
			(pads allowed)
			(copperpour not_allowed)
			(footprints allowed)
		)
		(placement
			(enabled no)
			(sheetname "")
		)
		(fill
			(thermal_gap 0.5)
			(thermal_bridge_width 0.5)
			(island_removal_mode 0)
		)
		(polygon
			(pts
				(arc
					(start 73.867264 -147.158202)
					(mid 73.852385 -147.194123)
					(end 73.816464 -147.209002)
				)
				(arc
					(start 72.635364 -147.209002)
					(mid 72.599443 -147.194123)
					(end 72.584564 -147.158202)
				)
				(arc
					(start 72.584564 -146.151854)
					(mid 72.599443 -146.115933)
					(end 72.635364 -146.101054)
				)
				(arc
					(start 73.816464 -146.101054)
					(mid 73.852385 -146.115933)
					(end 73.867264 -146.151854)
				)
			)
		)
	)
	(zone
		(layer "In1.Cu")
		(hatch none 0.5)
		(connect_pads
			(clearance 0)
		)
		(min_thickness 0.25)
		(keepout
			(tracks not_allowed)
			(vias allowed)
			(pads allowed)
			(copperpour not_allowed)
			(footprints allowed)
		)
		(placement
			(enabled no)
			(sheetname "")
		)
		(fill
			(thermal_gap 0.5)
			(thermal_bridge_width 0.5)
			(island_removal_mode 0)
		)
		(polygon
			(pts
				(arc
					(start 422.167304 -145.358104)
					(mid 422.152425 -145.394025)
					(end 422.116504 -145.408904)
				)
				(arc
					(start 420.935404 -145.408904)
					(mid 420.899483 -145.394025)
					(end 420.884604 -145.358104)
				)
				(arc
					(start 420.884604 -144.351756)
					(mid 420.899483 -144.315835)
					(end 420.935404 -144.300956)
				)
				(arc
					(start 422.116504 -144.300956)
					(mid 422.152425 -144.315835)
					(end 422.167304 -144.351756)
				)
			)
		)
	)
	(zone
		(layer "In1.Cu")
		(hatch none 0.5)
		(connect_pads
			(clearance 0)
		)
		(min_thickness 0.25)
		(keepout
			(tracks not_allowed)
			(vias allowed)
			(pads allowed)
			(copperpour not_allowed)
			(footprints allowed)
		)
		(placement
			(enabled no)
			(sheetname "")
		)
		(fill
			(thermal_gap 0.5)
			(thermal_bridge_width 0.5)
			(island_removal_mode 0)
		)
		(polygon
			(pts
				(arc
					(start 161.53257 -101.041962)
					(mid 161.547449 -101.006041)
					(end 161.58337 -100.991162)
				)
				(arc
					(start 162.76447 -100.991162)
					(mid 162.800391 -101.006041)
					(end 162.81527 -101.041962)
				)
				(arc
					(start 162.81527 -102.04831)
					(mid 162.800391 -102.084231)
					(end 162.76447 -102.09911)
				)
				(arc
					(start 161.58337 -102.09911)
					(mid 161.547449 -102.084231)
					(end 161.53257 -102.04831)
				)
			)
		)
	)
	(zone
		(layer "In1.Cu")
		(hatch none 0.5)
		(connect_pads
			(clearance 0)
		)
		(min_thickness 0.25)
		(keepout
			(tracks not_allowed)
			(vias allowed)
			(pads allowed)
			(copperpour not_allowed)
			(footprints allowed)
		)
		(placement
			(enabled no)
			(sheetname "")
		)
		(fill
			(thermal_gap 0.5)
			(thermal_bridge_width 0.5)
			(island_removal_mode 0)
		)
		(polygon
			(pts
				(arc
					(start 171.347638 -349.679514)
					(mid 171.311717 -349.694393)
					(end 171.296838 -349.730314)
				)
				(arc
					(start 171.296838 -350.466914)
					(mid 171.311717 -350.502835)
					(end 171.347638 -350.517714)
				)
				(xy 171.591478 -350.517714) (xy 171.945808 -350.285304) (xy 172.301408 -350.517714)
				(arc
					(start 172.543978 -350.517714)
					(mid 172.579899 -350.502835)
					(end 172.594778 -350.466914)
				)
				(arc
					(start 172.594778 -349.730314)
					(mid 172.579899 -349.694393)
					(end 172.543978 -349.679514)
				)
				(xy 172.301408 -349.679514) (xy 171.944538 -349.911924) (xy 171.590208 -349.679514)
			)
		)
	)
	(zone
		(layer "In1.Cu")
		(hatch none 0.5)
		(connect_pads
			(clearance 0)
		)
		(min_thickness 0.25)
		(keepout
			(tracks not_allowed)
			(vias allowed)
			(pads allowed)
			(copperpour not_allowed)
			(footprints allowed)
		)
		(placement
			(enabled no)
			(sheetname "")
		)
		(fill
			(thermal_gap 0.5)
			(thermal_bridge_width 0.5)
			(island_removal_mode 0)
		)
		(polygon
			(pts
				(arc
					(start 283.452062 -121.958354)
					(mid 283.437183 -121.994275)
					(end 283.401262 -122.009154)
				)
				(arc
					(start 282.220162 -122.009154)
					(mid 282.184241 -121.994275)
					(end 282.169362 -121.958354)
				)
				(arc
					(start 282.169362 -120.952006)
					(mid 282.184241 -120.916085)
					(end 282.220162 -120.901206)
				)
				(arc
					(start 283.401262 -120.901206)
					(mid 283.437183 -120.916085)
					(end 283.452062 -120.952006)
				)
			)
		)
	)
	(zone
		(layer "In1.Cu")
		(hatch none 0.5)
		(connect_pads
			(clearance 0)
		)
		(min_thickness 0.25)
		(keepout
			(tracks not_allowed)
			(vias allowed)
			(pads allowed)
			(copperpour not_allowed)
			(footprints allowed)
		)
		(placement
			(enabled no)
			(sheetname "")
		)
		(fill
			(thermal_gap 0.5)
			(thermal_bridge_width 0.5)
			(island_removal_mode 0)
		)
		(polygon
			(pts
				(arc
					(start 283.452062 -123.758452)
					(mid 283.437183 -123.794373)
					(end 283.401262 -123.809252)
				)
				(arc
					(start 282.220162 -123.809252)
					(mid 282.184241 -123.794373)
					(end 282.169362 -123.758452)
				)
				(arc
					(start 282.169362 -122.752104)
					(mid 282.184241 -122.716183)
					(end 282.220162 -122.701304)
				)
				(arc
					(start 283.401262 -122.701304)
					(mid 283.437183 -122.716183)
					(end 283.452062 -122.752104)
				)
			)
		)
	)
	(zone
		(layer "In1.Cu")
		(hatch none 0.5)
		(connect_pads
			(clearance 0)
		)
		(min_thickness 0.25)
		(keepout
			(tracks not_allowed)
			(vias allowed)
			(pads allowed)
			(copperpour not_allowed)
			(footprints allowed)
		)
		(placement
			(enabled no)
			(sheetname "")
		)
		(fill
			(thermal_gap 0.5)
			(thermal_bridge_width 0.5)
			(island_removal_mode 0)
		)
		(polygon
			(pts
				(arc
					(start 409.129738 -349.679514)
					(mid 409.093817 -349.694393)
					(end 409.078938 -349.730314)
				)
				(arc
					(start 409.078938 -350.466914)
					(mid 409.093817 -350.502835)
					(end 409.129738 -350.517714)
				)
				(xy 409.373578 -350.517714) (xy 409.727908 -350.285304) (xy 410.083508 -350.517714)
				(arc
					(start 410.326078 -350.517714)
					(mid 410.361999 -350.502835)
					(end 410.376878 -350.466914)
				)
				(arc
					(start 410.376878 -349.730314)
					(mid 410.361999 -349.694393)
					(end 410.326078 -349.679514)
				)
				(xy 410.083508 -349.679514) (xy 409.726638 -349.911924) (xy 409.372308 -349.679514)
			)
		)
	)
	(zone
		(layer "In1.Cu")
		(hatch none 0.5)
		(connect_pads
			(clearance 0)
		)
		(min_thickness 0.25)
		(keepout
			(tracks not_allowed)
			(vias allowed)
			(pads allowed)
			(copperpour not_allowed)
			(footprints allowed)
		)
		(placement
			(enabled no)
			(sheetname "")
		)
		(fill
			(thermal_gap 0.5)
			(thermal_bridge_width 0.5)
			(island_removal_mode 0)
		)
		(polygon
			(pts
				(arc
					(start 458.040232 8.724392)
					(mid 458.06255 8.778274)
					(end 458.116432 8.800592)
				)
				(arc
					(start 458.728572 8.800592)
					(mid 458.782454 8.778274)
					(end 458.804772 8.724392)
				)
				(arc
					(start 458.804772 7.627112)
					(mid 458.782454 7.57323)
					(end 458.728572 7.550912)
				)
				(arc
					(start 458.116432 7.550912)
					(mid 458.06255 7.57323)
					(end 458.040232 7.627112)
				)
			)
		)
	)
	(zone
		(layer "In1.Cu")
		(hatch none 0.5)
		(connect_pads
			(clearance 0)
		)
		(min_thickness 0.25)
		(keepout
			(tracks not_allowed)
			(vias allowed)
			(pads allowed)
			(copperpour not_allowed)
			(footprints allowed)
		)
		(placement
			(enabled no)
			(sheetname "")
		)
		(fill
			(thermal_gap 0.5)
			(thermal_bridge_width 0.5)
			(island_removal_mode 0)
		)
		(polygon
			(pts
				(arc
					(start 300.247812 -124.031756)
					(mid 300.262691 -123.995835)
					(end 300.298612 -123.980956)
				)
				(arc
					(start 301.479712 -123.980956)
					(mid 301.515633 -123.995835)
					(end 301.530512 -124.031756)
				)
				(arc
					(start 301.530512 -125.038104)
					(mid 301.515633 -125.074025)
					(end 301.479712 -125.088904)
				)
				(arc
					(start 300.298612 -125.088904)
					(mid 300.262691 -125.074025)
					(end 300.247812 -125.038104)
				)
			)
		)
	)
	(zone
		(layer "In1.Cu")
		(hatch none 0.5)
		(connect_pads
			(clearance 0)
		)
		(min_thickness 0.25)
		(keepout
			(tracks not_allowed)
			(vias allowed)
			(pads allowed)
			(copperpour not_allowed)
			(footprints allowed)
		)
		(placement
			(enabled no)
			(sheetname "")
		)
		(fill
			(thermal_gap 0.5)
			(thermal_bridge_width 0.5)
			(island_removal_mode 0)
		)
		(polygon
			(pts
				(arc
					(start 111.696754 -349.679514)
					(mid 111.660833 -349.694393)
					(end 111.645954 -349.730314)
				)
				(arc
					(start 111.645954 -350.466914)
					(mid 111.660833 -350.502835)
					(end 111.696754 -350.517714)
				)
				(xy 111.940594 -350.517714) (xy 112.294924 -350.285304) (xy 112.650524 -350.517714)
				(arc
					(start 112.893094 -350.517714)
					(mid 112.929015 -350.502835)
					(end 112.943894 -350.466914)
				)
				(arc
					(start 112.943894 -349.730314)
					(mid 112.929015 -349.694393)
					(end 112.893094 -349.679514)
				)
				(xy 112.650524 -349.679514) (xy 112.293654 -349.911924) (xy 111.939324 -349.679514)
			)
		)
	)
	(zone
		(layer "In1.Cu")
		(hatch none 0.5)
		(connect_pads
			(clearance 0)
		)
		(min_thickness 0.25)
		(keepout
			(tracks not_allowed)
			(vias allowed)
			(pads allowed)
			(copperpour not_allowed)
			(footprints allowed)
		)
		(placement
			(enabled no)
			(sheetname "")
		)
		(fill
			(thermal_gap 0.5)
			(thermal_bridge_width 0.5)
			(island_removal_mode 0)
		)
		(polygon
			(pts
				(arc
					(start 412.238698 -355.825806)
					(mid 412.202777 -355.840685)
					(end 412.187898 -355.876606)
				)
				(arc
					(start 412.187898 -356.613206)
					(mid 412.202777 -356.649127)
					(end 412.238698 -356.664006)
				)
				(xy 412.482538 -356.664006) (xy 412.836868 -356.431596) (xy 413.192468 -356.664006)
				(arc
					(start 413.435038 -356.664006)
					(mid 413.470959 -356.649127)
					(end 413.485838 -356.613206)
				)
				(arc
					(start 413.485838 -355.876606)
					(mid 413.470959 -355.840685)
					(end 413.435038 -355.825806)
				)
				(xy 413.192468 -355.825806) (xy 412.835598 -356.058216) (xy 412.481268 -355.825806)
			)
		)
	)
	(zone
		(layer "In1.Cu")
		(hatch none 0.5)
		(connect_pads
			(clearance 0)
		)
		(min_thickness 0.25)
		(keepout
			(tracks not_allowed)
			(vias allowed)
			(pads allowed)
			(copperpour not_allowed)
			(footprints allowed)
		)
		(placement
			(enabled no)
			(sheetname "")
		)
		(fill
			(thermal_gap 0.5)
			(thermal_bridge_width 0.5)
			(island_removal_mode 0)
		)
		(polygon
			(pts
				(arc
					(start 162.020758 -355.825806)
					(mid 161.984837 -355.840685)
					(end 161.969958 -355.876606)
				)
				(arc
					(start 161.969958 -356.613206)
					(mid 161.984837 -356.649127)
					(end 162.020758 -356.664006)
				)
				(xy 162.264598 -356.664006) (xy 162.618928 -356.431596) (xy 162.974528 -356.664006)
				(arc
					(start 163.217098 -356.664006)
					(mid 163.253019 -356.649127)
					(end 163.267898 -356.613206)
				)
				(arc
					(start 163.267898 -355.876606)
					(mid 163.253019 -355.840685)
					(end 163.217098 -355.825806)
				)
				(xy 162.974528 -355.825806) (xy 162.617658 -356.058216) (xy 162.263328 -355.825806)
			)
		)
	)
	(zone
		(layer "In1.Cu")
		(hatch none 0.5)
		(connect_pads
			(clearance 0)
		)
		(min_thickness 0.25)
		(keepout
			(tracks not_allowed)
			(vias allowed)
			(pads allowed)
			(copperpour not_allowed)
			(footprints allowed)
		)
		(placement
			(enabled no)
			(sheetname "")
		)
		(fill
			(thermal_gap 0.5)
			(thermal_bridge_width 0.5)
			(island_removal_mode 0)
		)
		(polygon
			(pts
				(arc
					(start 427.900338 -143.64462)
					(mid 427.915217 -143.680541)
					(end 427.951138 -143.69542)
				)
				(arc
					(start 428.687738 -143.69542)
					(mid 428.723659 -143.680541)
					(end 428.738538 -143.64462)
				)
				(xy 428.738538 -143.40078) (xy 428.506128 -143.04645) (xy 428.738538 -142.69085)
				(arc
					(start 428.738538 -142.44828)
					(mid 428.723659 -142.412359)
					(end 428.687738 -142.39748)
				)
				(arc
					(start 427.951138 -142.39748)
					(mid 427.915217 -142.412359)
					(end 427.900338 -142.44828)
				)
				(xy 427.900338 -142.69085) (xy 428.132748 -143.04772) (xy 427.900338 -143.40205)
			)
		)
	)
	(zone
		(layer "In1.Cu")
		(hatch none 0.5)
		(connect_pads
			(clearance 0)
		)
		(min_thickness 0.25)
		(keepout
			(tracks not_allowed)
			(vias allowed)
			(pads allowed)
			(copperpour not_allowed)
			(footprints allowed)
		)
		(placement
			(enabled no)
			(sheetname "")
		)
		(fill
			(thermal_gap 0.5)
			(thermal_bridge_width 0.5)
			(island_removal_mode 0)
		)
		(polygon
			(pts
				(arc
					(start 277.632668 -111.841788)
					(mid 277.647547 -111.805867)
					(end 277.683468 -111.790988)
				)
				(arc
					(start 278.864568 -111.790988)
					(mid 278.900489 -111.805867)
					(end 278.915368 -111.841788)
				)
				(arc
					(start 278.915368 -112.848136)
					(mid 278.900489 -112.884057)
					(end 278.864568 -112.898936)
				)
				(arc
					(start 277.683468 -112.898936)
					(mid 277.647547 -112.884057)
					(end 277.632668 -112.848136)
				)
			)
		)
	)
	(zone
		(layer "In1.Cu")
		(hatch none 0.5)
		(connect_pads
			(clearance 0)
		)
		(min_thickness 0.25)
		(keepout
			(tracks not_allowed)
			(vias allowed)
			(pads allowed)
			(copperpour not_allowed)
			(footprints allowed)
		)
		(placement
			(enabled no)
			(sheetname "")
		)
		(fill
			(thermal_gap 0.5)
			(thermal_bridge_width 0.5)
			(island_removal_mode 0)
		)
		(polygon
			(pts
				(arc
					(start 232.24109 -81.991708)
					(mid 232.278287 -81.901905)
					(end 232.36809 -81.864708)
				)
				(arc
					(start 232.57129 -81.864708)
					(mid 232.661093 -81.901905)
					(end 232.69829 -81.991708)
				)
				(arc
					(start 232.69829 -82.245708)
					(mid 232.661093 -82.335511)
					(end 232.57129 -82.372708)
				)
				(arc
					(start 232.36809 -82.372708)
					(mid 232.278287 -82.335511)
					(end 232.24109 -82.245708)
				)
			)
		)
	)
	(zone
		(layer "In1.Cu")
		(hatch none 0.5)
		(connect_pads
			(clearance 0)
		)
		(min_thickness 0.25)
		(keepout
			(tracks not_allowed)
			(vias allowed)
			(pads allowed)
			(copperpour not_allowed)
			(footprints allowed)
		)
		(placement
			(enabled no)
			(sheetname "")
		)
		(fill
			(thermal_gap 0.5)
			(thermal_bridge_width 0.5)
			(island_removal_mode 0)
		)
		(polygon
			(pts
				(arc
					(start 358.329992 -29.974286)
					(mid 358.344871 -29.938365)
					(end 358.380792 -29.923486)
				)
				(arc
					(start 359.612692 -29.923486)
					(mid 359.648613 -29.938365)
					(end 359.663492 -29.974286)
				)
				(arc
					(start 359.663492 -31.006034)
					(mid 359.648613 -31.041955)
					(end 359.612692 -31.056834)
				)
				(arc
					(start 358.380792 -31.056834)
					(mid 358.344871 -31.041955)
					(end 358.329992 -31.006034)
				)
			)
		)
	)
	(zone
		(layer "In1.Cu")
		(hatch none 0.5)
		(connect_pads
			(clearance 0)
		)
		(min_thickness 0.25)
		(keepout
			(tracks not_allowed)
			(vias allowed)
			(pads allowed)
			(copperpour not_allowed)
			(footprints allowed)
		)
		(placement
			(enabled no)
			(sheetname "")
		)
		(fill
			(thermal_gap 0.5)
			(thermal_bridge_width 0.5)
			(island_removal_mode 0)
		)
		(polygon
			(pts
				(arc
					(start 73.867264 -119.638064)
					(mid 73.852385 -119.673985)
					(end 73.816464 -119.688864)
				)
				(arc
					(start 72.635364 -119.688864)
					(mid 72.599443 -119.673985)
					(end 72.584564 -119.638064)
				)
				(arc
					(start 72.584564 -118.631716)
					(mid 72.599443 -118.595795)
					(end 72.635364 -118.580916)
				)
				(arc
					(start 73.816464 -118.580916)
					(mid 73.852385 -118.595795)
					(end 73.867264 -118.631716)
				)
			)
		)
	)
	(zone
		(layer "In1.Cu")
		(hatch none 0.5)
		(connect_pads
			(clearance 0)
		)
		(min_thickness 0.25)
		(keepout
			(tracks not_allowed)
			(vias allowed)
			(pads allowed)
			(copperpour not_allowed)
			(footprints allowed)
		)
		(placement
			(enabled no)
			(sheetname "")
		)
		(fill
			(thermal_gap 0.5)
			(thermal_bridge_width 0.5)
			(island_removal_mode 0)
		)
		(polygon
			(pts
				(arc
					(start 68.04787 -133.441948)
					(mid 68.062749 -133.406027)
					(end 68.09867 -133.391148)
				)
				(arc
					(start 69.27977 -133.391148)
					(mid 69.315691 -133.406027)
					(end 69.33057 -133.441948)
				)
				(arc
					(start 69.33057 -134.448296)
					(mid 69.315691 -134.484217)
					(end 69.27977 -134.499096)
				)
				(arc
					(start 68.09867 -134.499096)
					(mid 68.062749 -134.484217)
					(end 68.04787 -134.448296)
				)
			)
		)
	)
	(zone
		(layer "In1.Cu")
		(hatch none 0.5)
		(connect_pads
			(clearance 0)
		)
		(min_thickness 0.25)
		(keepout
			(tracks not_allowed)
			(vias allowed)
			(pads allowed)
			(copperpour not_allowed)
			(footprints allowed)
		)
		(placement
			(enabled no)
			(sheetname "")
		)
		(fill
			(thermal_gap 0.5)
			(thermal_bridge_width 0.5)
			(island_removal_mode 0)
		)
		(polygon
			(pts
				(arc
					(start 36.219384 -105.749852)
					(mid 36.234263 -105.785773)
					(end 36.270184 -105.800652)
				)
				(arc
					(start 37.006784 -105.800652)
					(mid 37.042705 -105.785773)
					(end 37.057584 -105.749852)
				)
				(xy 37.057584 -105.506012) (xy 36.825174 -105.151682) (xy 37.057584 -104.796082)
				(arc
					(start 37.057584 -104.553512)
					(mid 37.042705 -104.517591)
					(end 37.006784 -104.502712)
				)
				(arc
					(start 36.270184 -104.502712)
					(mid 36.234263 -104.517591)
					(end 36.219384 -104.553512)
				)
				(xy 36.219384 -104.796082) (xy 36.451794 -105.152952) (xy 36.219384 -105.507282)
			)
		)
	)
	(zone
		(layer "In1.Cu")
		(hatch none 0.5)
		(connect_pads
			(clearance 0)
		)
		(min_thickness 0.25)
		(keepout
			(tracks not_allowed)
			(vias allowed)
			(pads allowed)
			(copperpour not_allowed)
			(footprints allowed)
		)
		(placement
			(enabled no)
			(sheetname "")
		)
		(fill
			(thermal_gap 0.5)
			(thermal_bridge_width 0.5)
			(island_removal_mode 0)
		)
		(polygon
			(pts
				(arc
					(start 67.899788 -32.805878)
					(mid 67.884909 -32.841799)
					(end 67.848988 -32.856678)
				)
				(arc
					(start 66.617088 -32.856678)
					(mid 66.581167 -32.841799)
					(end 66.566288 -32.805878)
				)
				(arc
					(start 66.566288 -31.77413)
					(mid 66.581167 -31.738209)
					(end 66.617088 -31.72333)
				)
				(arc
					(start 67.848988 -31.72333)
					(mid 67.884909 -31.738209)
					(end 67.899788 -31.77413)
				)
			)
		)
	)
	(zone
		(layer "In1.Cu")
		(hatch none 0.5)
		(connect_pads
			(clearance 0)
		)
		(min_thickness 0.25)
		(keepout
			(tracks not_allowed)
			(vias allowed)
			(pads allowed)
			(copperpour not_allowed)
			(footprints allowed)
		)
		(placement
			(enabled no)
			(sheetname "")
		)
		(fill
			(thermal_gap 0.5)
			(thermal_bridge_width 0.5)
			(island_removal_mode 0)
		)
		(polygon
			(pts
				(arc
					(start 283.452062 -111.048292)
					(mid 283.437183 -111.084213)
					(end 283.401262 -111.099092)
				)
				(arc
					(start 282.220162 -111.099092)
					(mid 282.184241 -111.084213)
					(end 282.169362 -111.048292)
				)
				(arc
					(start 282.169362 -110.041944)
					(mid 282.184241 -110.006023)
					(end 282.220162 -109.991144)
				)
				(arc
					(start 283.401262 -109.991144)
					(mid 283.437183 -110.006023)
					(end 283.452062 -110.041944)
				)
			)
		)
	)
	(zone
		(layer "In1.Cu")
		(hatch none 0.5)
		(connect_pads
			(clearance 0)
		)
		(min_thickness 0.25)
		(keepout
			(tracks not_allowed)
			(vias allowed)
			(pads allowed)
			(copperpour not_allowed)
			(footprints allowed)
		)
		(placement
			(enabled no)
			(sheetname "")
		)
		(fill
			(thermal_gap 0.5)
			(thermal_bridge_width 0.5)
			(island_removal_mode 0)
		)
		(polygon
			(pts
				(arc
					(start 72.01535 -34.68624)
					(mid 72.030229 -34.722161)
					(end 72.06615 -34.73704)
				)
				(arc
					(start 72.80275 -34.73704)
					(mid 72.838671 -34.722161)
					(end 72.85355 -34.68624)
				)
				(xy 72.85355 -34.4424) (xy 72.62114 -34.08807) (xy 72.85355 -33.73247)
				(arc
					(start 72.85355 -33.4899)
					(mid 72.838671 -33.453979)
					(end 72.80275 -33.4391)
				)
				(arc
					(start 72.06615 -33.4391)
					(mid 72.030229 -33.453979)
					(end 72.01535 -33.4899)
				)
				(xy 72.01535 -33.73247) (xy 72.24776 -34.08934) (xy 72.01535 -34.44367)
			)
		)
	)
	(zone
		(layer "In1.Cu")
		(hatch none 0.5)
		(connect_pads
			(clearance 0)
		)
		(min_thickness 0.25)
		(keepout
			(tracks not_allowed)
			(vias allowed)
			(pads allowed)
			(copperpour not_allowed)
			(footprints allowed)
		)
		(placement
			(enabled no)
			(sheetname "")
		)
		(fill
			(thermal_gap 0.5)
			(thermal_bridge_width 0.5)
			(island_removal_mode 0)
		)
		(polygon
			(pts
				(arc
					(start 393.732766 -106.441748)
					(mid 393.747645 -106.405827)
					(end 393.783566 -106.390948)
				)
				(arc
					(start 394.964666 -106.390948)
					(mid 395.000587 -106.405827)
					(end 395.015466 -106.441748)
				)
				(arc
					(start 395.015466 -107.448096)
					(mid 395.000587 -107.484017)
					(end 394.964666 -107.498896)
				)
				(arc
					(start 393.783566 -107.498896)
					(mid 393.747645 -107.484017)
					(end 393.732766 -107.448096)
				)
			)
		)
	)
	(zone
		(layer "In1.Cu")
		(hatch none 0.5)
		(connect_pads
			(clearance 0)
		)
		(min_thickness 0.25)
		(keepout
			(tracks not_allowed)
			(vias allowed)
			(pads allowed)
			(copperpour not_allowed)
			(footprints allowed)
		)
		(placement
			(enabled no)
			(sheetname "")
		)
		(fill
			(thermal_gap 0.5)
			(thermal_bridge_width 0.5)
			(island_removal_mode 0)
		)
		(polygon
			(pts
				(arc
					(start 410.329888 -33.574228)
					(mid 410.344767 -33.538307)
					(end 410.380688 -33.523428)
				)
				(arc
					(start 411.612588 -33.523428)
					(mid 411.648509 -33.538307)
					(end 411.663388 -33.574228)
				)
				(arc
					(start 411.663388 -34.605976)
					(mid 411.648509 -34.641897)
					(end 411.612588 -34.656776)
				)
				(arc
					(start 410.380688 -34.656776)
					(mid 410.344767 -34.641897)
					(end 410.329888 -34.605976)
				)
			)
		)
	)
	(zone
		(layer "In1.Cu")
		(hatch none 0.5)
		(connect_pads
			(clearance 0)
		)
		(min_thickness 0.25)
		(keepout
			(tracks not_allowed)
			(vias allowed)
			(pads allowed)
			(copperpour not_allowed)
			(footprints allowed)
		)
		(placement
			(enabled no)
			(sheetname "")
		)
		(fill
			(thermal_gap 0.5)
			(thermal_bridge_width 0.5)
			(island_removal_mode 0)
		)
		(polygon
			(pts
				(arc
					(start 161.53257 -137.561574)
					(mid 161.547449 -137.525653)
					(end 161.58337 -137.510774)
				)
				(arc
					(start 162.76447 -137.510774)
					(mid 162.800391 -137.525653)
					(end 162.81527 -137.561574)
				)
				(arc
					(start 162.81527 -138.567922)
					(mid 162.800391 -138.603843)
					(end 162.76447 -138.618722)
				)
				(arc
					(start 161.58337 -138.618722)
					(mid 161.547449 -138.603843)
					(end 161.53257 -138.567922)
				)
			)
		)
	)
	(zone
		(layer "In1.Cu")
		(hatch none 0.5)
		(connect_pads
			(clearance 0)
		)
		(min_thickness 0.25)
		(keepout
			(tracks not_allowed)
			(vias allowed)
			(pads allowed)
			(copperpour not_allowed)
			(footprints allowed)
		)
		(placement
			(enabled no)
			(sheetname "")
		)
		(fill
			(thermal_gap 0.5)
			(thermal_bridge_width 0.5)
			(island_removal_mode 0)
		)
		(polygon
			(pts
				(arc
					(start 270.840708 -349.679514)
					(mid 270.804787 -349.694393)
					(end 270.789908 -349.730314)
				)
				(arc
					(start 270.789908 -350.466914)
					(mid 270.804787 -350.502835)
					(end 270.840708 -350.517714)
				)
				(xy 271.084548 -350.517714) (xy 271.438878 -350.285304) (xy 271.794478 -350.517714)
				(arc
					(start 272.037048 -350.517714)
					(mid 272.072969 -350.502835)
					(end 272.087848 -350.466914)
				)
				(arc
					(start 272.087848 -349.730314)
					(mid 272.072969 -349.694393)
					(end 272.037048 -349.679514)
				)
				(xy 271.794478 -349.679514) (xy 271.437608 -349.911924) (xy 271.083278 -349.679514)
			)
		)
	)
	(zone
		(layer "In1.Cu")
		(hatch none 0.5)
		(connect_pads
			(clearance 0)
		)
		(min_thickness 0.25)
		(keepout
			(tracks not_allowed)
			(vias allowed)
			(pads allowed)
			(copperpour not_allowed)
			(footprints allowed)
		)
		(placement
			(enabled no)
			(sheetname "")
		)
		(fill
			(thermal_gap 0.5)
			(thermal_bridge_width 0.5)
			(island_removal_mode 0)
		)
		(polygon
			(pts
				(arc
					(start 15.899892 -27.405838)
					(mid 15.885013 -27.441759)
					(end 15.849092 -27.456638)
				)
				(arc
					(start 14.617192 -27.456638)
					(mid 14.581271 -27.441759)
					(end 14.566392 -27.405838)
				)
				(arc
					(start 14.566392 -26.37409)
					(mid 14.581271 -26.338169)
					(end 14.617192 -26.32329)
				)
				(arc
					(start 15.849092 -26.32329)
					(mid 15.885013 -26.338169)
					(end 15.899892 -26.37409)
				)
			)
		)
	)
	(zone
		(layer "In1.Cu")
		(hatch none 0.5)
		(connect_pads
			(clearance 0)
		)
		(min_thickness 0.25)
		(keepout
			(tracks not_allowed)
			(vias allowed)
			(pads allowed)
			(copperpour not_allowed)
			(footprints allowed)
		)
		(placement
			(enabled no)
			(sheetname "")
		)
		(fill
			(thermal_gap 0.5)
			(thermal_bridge_width 0.5)
			(island_removal_mode 0)
		)
		(polygon
			(pts
				(arc
					(start 45.432726 -110.041944)
					(mid 45.447605 -110.006023)
					(end 45.483526 -109.991144)
				)
				(arc
					(start 46.664626 -109.991144)
					(mid 46.700547 -110.006023)
					(end 46.715426 -110.041944)
				)
				(arc
					(start 46.715426 -111.048292)
					(mid 46.700547 -111.084213)
					(end 46.664626 -111.099092)
				)
				(arc
					(start 45.483526 -111.099092)
					(mid 45.447605 -111.084213)
					(end 45.432726 -111.048292)
				)
			)
		)
	)
	(zone
		(layer "In1.Cu")
		(hatch none 0.5)
		(connect_pads
			(clearance 0)
		)
		(min_thickness 0.25)
		(keepout
			(tracks not_allowed)
			(vias allowed)
			(pads allowed)
			(copperpour not_allowed)
			(footprints allowed)
		)
		(placement
			(enabled no)
			(sheetname "")
		)
		(fill
			(thermal_gap 0.5)
			(thermal_bridge_width 0.5)
			(island_removal_mode 0)
		)
		(polygon
			(pts
				(arc
					(start 443.67323 -32.879538)
					(mid 443.688109 -32.915459)
					(end 443.72403 -32.930338)
				)
				(arc
					(start 444.46063 -32.930338)
					(mid 444.496551 -32.915459)
					(end 444.51143 -32.879538)
				)
				(xy 444.51143 -32.635698) (xy 444.27902 -32.281368) (xy 444.51143 -31.925768)
				(arc
					(start 444.51143 -31.683198)
					(mid 444.496551 -31.647277)
					(end 444.46063 -31.632398)
				)
				(arc
					(start 443.72403 -31.632398)
					(mid 443.688109 -31.647277)
					(end 443.67323 -31.683198)
				)
				(xy 443.67323 -31.925768) (xy 443.90564 -32.282638) (xy 443.67323 -32.636968)
			)
		)
	)
	(zone
		(layer "In1.Cu")
		(hatch none 0.5)
		(connect_pads
			(clearance 0)
		)
		(min_thickness 0.25)
		(keepout
			(tracks not_allowed)
			(vias allowed)
			(pads allowed)
			(copperpour not_allowed)
			(footprints allowed)
		)
		(placement
			(enabled no)
			(sheetname "")
		)
		(fill
			(thermal_gap 0.5)
			(thermal_bridge_width 0.5)
			(island_removal_mode 0)
		)
		(polygon
			(pts
				(arc
					(start 430.542446 -136.341104)
					(mid 430.557325 -136.377025)
					(end 430.593246 -136.391904)
				)
				(arc
					(start 431.329846 -136.391904)
					(mid 431.365767 -136.377025)
					(end 431.380646 -136.341104)
				)
				(xy 431.380646 -136.097264) (xy 431.148236 -135.742934) (xy 431.380646 -135.387334)
				(arc
					(start 431.380646 -135.144764)
					(mid 431.365767 -135.108843)
					(end 431.329846 -135.093964)
				)
				(arc
					(start 430.593246 -135.093964)
					(mid 430.557325 -135.108843)
					(end 430.542446 -135.144764)
				)
				(xy 430.542446 -135.387334) (xy 430.774856 -135.744204) (xy 430.542446 -136.098534)
			)
		)
	)
	(zone
		(layer "In1.Cu")
		(hatch none 0.5)
		(connect_pads
			(clearance 0)
		)
		(min_thickness 0.25)
		(keepout
			(tracks not_allowed)
			(vias allowed)
			(pads allowed)
			(copperpour not_allowed)
			(footprints allowed)
		)
		(placement
			(enabled no)
			(sheetname "")
		)
		(fill
			(thermal_gap 0.5)
			(thermal_bridge_width 0.5)
			(island_removal_mode 0)
		)
		(polygon
			(pts
				(arc
					(start 232.59669 -81.890108)
					(mid 232.686493 -81.927305)
					(end 232.72369 -82.017108)
				)
				(arc
					(start 232.72369 -82.220308)
					(mid 232.686493 -82.310111)
					(end 232.59669 -82.347308)
				)
				(arc
					(start 232.34269 -82.347308)
					(mid 232.252887 -82.310111)
					(end 232.21569 -82.220308)
				)
				(arc
					(start 232.21569 -82.017108)
					(mid 232.252887 -81.927305)
					(end 232.34269 -81.890108)
				)
			)
		)
	)
	(zone
		(layer "In1.Cu")
		(hatch none 0.5)
		(connect_pads
			(clearance 0)
		)
		(min_thickness 0.25)
		(keepout
			(tracks not_allowed)
			(vias allowed)
			(pads allowed)
			(copperpour not_allowed)
			(footprints allowed)
		)
		(placement
			(enabled no)
			(sheetname "")
		)
		(fill
			(thermal_gap 0.5)
			(thermal_bridge_width 0.5)
			(island_removal_mode 0)
		)
		(polygon
			(pts
				(arc
					(start 45.432726 -101.041962)
					(mid 45.447605 -101.006041)
					(end 45.483526 -100.991162)
				)
				(arc
					(start 46.664626 -100.991162)
					(mid 46.700547 -101.006041)
					(end 46.715426 -101.041962)
				)
				(arc
					(start 46.715426 -102.04831)
					(mid 46.700547 -102.084231)
					(end 46.664626 -102.09911)
				)
				(arc
					(start 45.483526 -102.09911)
					(mid 45.447605 -102.084231)
					(end 45.432726 -102.04831)
				)
			)
		)
	)
	(zone
		(layer "In1.Cu")
		(hatch none 0.5)
		(connect_pads
			(clearance 0)
		)
		(min_thickness 0.25)
		(keepout
			(tracks not_allowed)
			(vias allowed)
			(pads allowed)
			(copperpour not_allowed)
			(footprints allowed)
		)
		(placement
			(enabled no)
			(sheetname "")
		)
		(fill
			(thermal_gap 0.5)
			(thermal_bridge_width 0.5)
			(island_removal_mode 0)
		)
		(polygon
			(pts
				(arc
					(start 399.003266 -355.825806)
					(mid 398.967345 -355.840685)
					(end 398.952466 -355.876606)
				)
				(arc
					(start 398.952466 -356.613206)
					(mid 398.967345 -356.649127)
					(end 399.003266 -356.664006)
				)
				(xy 399.247106 -356.664006) (xy 399.601436 -356.431596) (xy 399.957036 -356.664006)
				(arc
					(start 400.199606 -356.664006)
					(mid 400.235527 -356.649127)
					(end 400.250406 -356.613206)
				)
				(arc
					(start 400.250406 -355.876606)
					(mid 400.235527 -355.840685)
					(end 400.199606 -355.825806)
				)
				(xy 399.957036 -355.825806) (xy 399.600166 -356.058216) (xy 399.245836 -355.825806)
			)
		)
	)
	(zone
		(layer "In1.Cu")
		(hatch none 0.5)
		(connect_pads
			(clearance 0)
		)
		(min_thickness 0.25)
		(keepout
			(tracks not_allowed)
			(vias allowed)
			(pads allowed)
			(copperpour not_allowed)
			(footprints allowed)
		)
		(placement
			(enabled no)
			(sheetname "")
		)
		(fill
			(thermal_gap 0.5)
			(thermal_bridge_width 0.5)
			(island_removal_mode 0)
		)
		(polygon
			(pts
				(arc
					(start 167.351964 -133.16839)
					(mid 167.337085 -133.204311)
					(end 167.301164 -133.21919)
				)
				(arc
					(start 166.120064 -133.21919)
					(mid 166.084143 -133.204311)
					(end 166.069264 -133.16839)
				)
				(arc
					(start 166.069264 -132.162042)
					(mid 166.084143 -132.126121)
					(end 166.120064 -132.111242)
				)
				(arc
					(start 167.301164 -132.111242)
					(mid 167.337085 -132.126121)
					(end 167.351964 -132.162042)
				)
			)
		)
	)
	(zone
		(layer "In1.Cu")
		(hatch none 0.5)
		(connect_pads
			(clearance 0)
		)
		(min_thickness 0.25)
		(keepout
			(tracks not_allowed)
			(vias allowed)
			(pads allowed)
			(copperpour not_allowed)
			(footprints allowed)
		)
		(placement
			(enabled no)
			(sheetname "")
		)
		(fill
			(thermal_gap 0.5)
			(thermal_bridge_width 0.5)
			(island_removal_mode 0)
		)
		(polygon
			(pts
				(arc
					(start 392.785346 -343.533222)
					(mid 392.749425 -343.548101)
					(end 392.734546 -343.584022)
				)
				(arc
					(start 392.734546 -344.320622)
					(mid 392.749425 -344.356543)
					(end 392.785346 -344.371422)
				)
				(xy 393.029186 -344.371422) (xy 393.383516 -344.139012) (xy 393.739116 -344.371422)
				(arc
					(start 393.981686 -344.371422)
					(mid 394.017607 -344.356543)
					(end 394.032486 -344.320622)
				)
				(arc
					(start 394.032486 -343.584022)
					(mid 394.017607 -343.548101)
					(end 393.981686 -343.533222)
				)
				(xy 393.739116 -343.533222) (xy 393.382246 -343.765632) (xy 393.027916 -343.533222)
			)
		)
	)
	(zone
		(layer "In1.Cu")
		(hatch none 0.5)
		(connect_pads
			(clearance 0)
		)
		(min_thickness 0.25)
		(keepout
			(tracks not_allowed)
			(vias allowed)
			(pads allowed)
			(copperpour not_allowed)
			(footprints allowed)
		)
		(placement
			(enabled no)
			(sheetname "")
		)
		(fill
			(thermal_gap 0.5)
			(thermal_bridge_width 0.5)
			(island_removal_mode 0)
		)
		(polygon
			(pts
				(arc
					(start 399.55216 -111.048292)
					(mid 399.537281 -111.084213)
					(end 399.50136 -111.099092)
				)
				(arc
					(start 398.32026 -111.099092)
					(mid 398.284339 -111.084213)
					(end 398.26946 -111.048292)
				)
				(arc
					(start 398.26946 -110.041944)
					(mid 398.284339 -110.006023)
					(end 398.32026 -109.991144)
				)
				(arc
					(start 399.50136 -109.991144)
					(mid 399.537281 -110.006023)
					(end 399.55216 -110.041944)
				)
			)
		)
	)
	(zone
		(layer "In1.Cu")
		(hatch none 0.5)
		(connect_pads
			(clearance 0)
		)
		(min_thickness 0.25)
		(keepout
			(tracks not_allowed)
			(vias allowed)
			(pads allowed)
			(copperpour not_allowed)
			(footprints allowed)
		)
		(placement
			(enabled no)
			(sheetname "")
		)
		(fill
			(thermal_gap 0.5)
			(thermal_bridge_width 0.5)
			(island_removal_mode 0)
		)
		(polygon
			(pts
				(arc
					(start 334.10017 -343.533222)
					(mid 334.064249 -343.548101)
					(end 334.04937 -343.584022)
				)
				(arc
					(start 334.04937 -344.320622)
					(mid 334.064249 -344.356543)
					(end 334.10017 -344.371422)
				)
				(xy 334.34401 -344.371422) (xy 334.69834 -344.139012) (xy 335.05394 -344.371422)
				(arc
					(start 335.29651 -344.371422)
					(mid 335.332431 -344.356543)
					(end 335.34731 -344.320622)
				)
				(arc
					(start 335.34731 -343.584022)
					(mid 335.332431 -343.548101)
					(end 335.29651 -343.533222)
				)
				(xy 335.05394 -343.533222) (xy 334.69707 -343.765632) (xy 334.34274 -343.533222)
			)
		)
	)
	(zone
		(layer "In1.Cu")
		(hatch none 0.5)
		(connect_pads
			(clearance 0)
		)
		(min_thickness 0.25)
		(keepout
			(tracks not_allowed)
			(vias allowed)
			(pads allowed)
			(copperpour not_allowed)
			(footprints allowed)
		)
		(placement
			(enabled no)
			(sheetname "")
		)
		(fill
			(thermal_gap 0.5)
			(thermal_bridge_width 0.5)
			(island_removal_mode 0)
		)
		(polygon
			(pts
				(arc
					(start 189.967108 -130.8481)
					(mid 189.952229 -130.884021)
					(end 189.916308 -130.8989)
				)
				(arc
					(start 188.735208 -130.8989)
					(mid 188.699287 -130.884021)
					(end 188.684408 -130.8481)
				)
				(arc
					(start 188.684408 -129.841752)
					(mid 188.699287 -129.805831)
					(end 188.735208 -129.790952)
				)
				(arc
					(start 189.916308 -129.790952)
					(mid 189.952229 -129.805831)
					(end 189.967108 -129.841752)
				)
			)
		)
	)
	(zone
		(layer "In1.Cu")
		(hatch none 0.5)
		(connect_pads
			(clearance 0)
		)
		(min_thickness 0.25)
		(keepout
			(tracks not_allowed)
			(vias allowed)
			(pads allowed)
			(copperpour not_allowed)
			(footprints allowed)
		)
		(placement
			(enabled no)
			(sheetname "")
		)
		(fill
			(thermal_gap 0.5)
			(thermal_bridge_width 0.5)
			(island_removal_mode 0)
		)
		(polygon
			(pts
				(arc
					(start 167.351964 -125.558296)
					(mid 167.337085 -125.594217)
					(end 167.301164 -125.609096)
				)
				(arc
					(start 166.120064 -125.609096)
					(mid 166.084143 -125.594217)
					(end 166.069264 -125.558296)
				)
				(arc
					(start 166.069264 -124.551948)
					(mid 166.084143 -124.516027)
					(end 166.120064 -124.501148)
				)
				(arc
					(start 167.301164 -124.501148)
					(mid 167.337085 -124.516027)
					(end 167.351964 -124.551948)
				)
			)
		)
	)
	(zone
		(layer "In1.Cu")
		(hatch none 0.5)
		(connect_pads
			(clearance 0)
		)
		(min_thickness 0.25)
		(keepout
			(tracks not_allowed)
			(vias allowed)
			(pads allowed)
			(copperpour not_allowed)
			(footprints allowed)
		)
		(placement
			(enabled no)
			(sheetname "")
		)
		(fill
			(thermal_gap 0.5)
			(thermal_bridge_width 0.5)
			(island_removal_mode 0)
		)
		(polygon
			(pts
				(arc
					(start 161.53257 -135.761984)
					(mid 161.547449 -135.726063)
					(end 161.58337 -135.711184)
				)
				(arc
					(start 162.76447 -135.711184)
					(mid 162.800391 -135.726063)
					(end 162.81527 -135.761984)
				)
				(arc
					(start 162.81527 -136.768332)
					(mid 162.800391 -136.804253)
					(end 162.76447 -136.819132)
				)
				(arc
					(start 161.58337 -136.819132)
					(mid 161.547449 -136.804253)
					(end 161.53257 -136.768332)
				)
			)
		)
	)
	(zone
		(layer "In1.Cu")
		(hatch none 0.5)
		(connect_pads
			(clearance 0)
		)
		(min_thickness 0.25)
		(keepout
			(tracks not_allowed)
			(vias allowed)
			(pads allowed)
			(copperpour not_allowed)
			(footprints allowed)
		)
		(placement
			(enabled no)
			(sheetname "")
		)
		(fill
			(thermal_gap 0.5)
			(thermal_bridge_width 0.5)
			(island_removal_mode 0)
		)
		(polygon
			(pts
				(arc
					(start 189.967108 -125.038104)
					(mid 189.952229 -125.074025)
					(end 189.916308 -125.088904)
				)
				(arc
					(start 188.735208 -125.088904)
					(mid 188.699287 -125.074025)
					(end 188.684408 -125.038104)
				)
				(arc
					(start 188.684408 -124.031756)
					(mid 188.699287 -123.995835)
					(end 188.735208 -123.980956)
				)
				(arc
					(start 189.916308 -123.980956)
					(mid 189.952229 -123.995835)
					(end 189.967108 -124.031756)
				)
			)
		)
	)
	(zone
		(layer "In1.Cu")
		(hatch none 0.5)
		(connect_pads
			(clearance 0)
		)
		(min_thickness 0.25)
		(keepout
			(tracks not_allowed)
			(vias allowed)
			(pads allowed)
			(copperpour not_allowed)
			(footprints allowed)
		)
		(placement
			(enabled no)
			(sheetname "")
		)
		(fill
			(thermal_gap 0.5)
			(thermal_bridge_width 0.5)
			(island_removal_mode 0)
		)
		(polygon
			(pts
				(arc
					(start 193.110358 -349.679514)
					(mid 193.074437 -349.694393)
					(end 193.059558 -349.730314)
				)
				(arc
					(start 193.059558 -350.466914)
					(mid 193.074437 -350.502835)
					(end 193.110358 -350.517714)
				)
				(xy 193.354198 -350.517714) (xy 193.708528 -350.285304) (xy 194.064128 -350.517714)
				(arc
					(start 194.306698 -350.517714)
					(mid 194.342619 -350.502835)
					(end 194.357498 -350.466914)
				)
				(arc
					(start 194.357498 -349.730314)
					(mid 194.342619 -349.694393)
					(end 194.306698 -349.679514)
				)
				(xy 194.064128 -349.679514) (xy 193.707258 -349.911924) (xy 193.352928 -349.679514)
			)
		)
	)
	(zone
		(layer "In1.Cu")
		(hatch none 0.5)
		(connect_pads
			(clearance 0)
		)
		(min_thickness 0.25)
		(keepout
			(tracks not_allowed)
			(vias allowed)
			(pads allowed)
			(copperpour not_allowed)
			(footprints allowed)
		)
		(placement
			(enabled no)
			(sheetname "")
		)
		(fill
			(thermal_gap 0.5)
			(thermal_bridge_width 0.5)
			(island_removal_mode 0)
		)
		(polygon
			(pts
				(arc
					(start 417.673282 -32.879538)
					(mid 417.688161 -32.915459)
					(end 417.724082 -32.930338)
				)
				(arc
					(start 418.460682 -32.930338)
					(mid 418.496603 -32.915459)
					(end 418.511482 -32.879538)
				)
				(xy 418.511482 -32.635698) (xy 418.279072 -32.281368) (xy 418.511482 -31.925768)
				(arc
					(start 418.511482 -31.683198)
					(mid 418.496603 -31.647277)
					(end 418.460682 -31.632398)
				)
				(arc
					(start 417.724082 -31.632398)
					(mid 417.688161 -31.647277)
					(end 417.673282 -31.683198)
				)
				(xy 417.673282 -31.925768) (xy 417.905692 -32.282638) (xy 417.673282 -32.636968)
			)
		)
	)
	(zone
		(layer "In1.Cu")
		(hatch none 0.5)
		(connect_pads
			(clearance 0)
		)
		(min_thickness 0.25)
		(keepout
			(tracks not_allowed)
			(vias allowed)
			(pads allowed)
			(copperpour not_allowed)
			(footprints allowed)
		)
		(placement
			(enabled no)
			(sheetname "")
		)
		(fill
			(thermal_gap 0.5)
			(thermal_bridge_width 0.5)
			(island_removal_mode 0)
		)
		(polygon
			(pts
				(arc
					(start 79.860648 -343.533222)
					(mid 79.824727 -343.548101)
					(end 79.809848 -343.584022)
				)
				(arc
					(start 79.809848 -344.320622)
					(mid 79.824727 -344.356543)
					(end 79.860648 -344.371422)
				)
				(xy 80.104488 -344.371422) (xy 80.458818 -344.139012) (xy 80.814418 -344.371422)
				(arc
					(start 81.056988 -344.371422)
					(mid 81.092909 -344.356543)
					(end 81.107788 -344.320622)
				)
				(arc
					(start 81.107788 -343.584022)
					(mid 81.092909 -343.548101)
					(end 81.056988 -343.533222)
				)
				(xy 80.814418 -343.533222) (xy 80.457548 -343.765632) (xy 80.103218 -343.533222)
			)
		)
	)
	(zone
		(layer "In1.Cu")
		(hatch none 0.5)
		(connect_pads
			(clearance 0)
		)
		(min_thickness 0.25)
		(keepout
			(tracks not_allowed)
			(vias allowed)
			(pads allowed)
			(copperpour not_allowed)
			(footprints allowed)
		)
		(placement
			(enabled no)
			(sheetname "")
		)
		(fill
			(thermal_gap 0.5)
			(thermal_bridge_width 0.5)
			(island_removal_mode 0)
		)
		(polygon
			(pts
				(arc
					(start 436.329836 -28.174188)
					(mid 436.344715 -28.138267)
					(end 436.380636 -28.123388)
				)
				(arc
					(start 437.612536 -28.123388)
					(mid 437.648457 -28.138267)
					(end 437.663336 -28.174188)
				)
				(arc
					(start 437.663336 -29.205936)
					(mid 437.648457 -29.241857)
					(end 437.612536 -29.256736)
				)
				(arc
					(start 436.380636 -29.256736)
					(mid 436.344715 -29.241857)
					(end 436.329836 -29.205936)
				)
			)
		)
	)
	(zone
		(layer "In1.Cu")
		(hatch none 0.5)
		(connect_pads
			(clearance 0)
		)
		(min_thickness 0.25)
		(keepout
			(tracks not_allowed)
			(vias allowed)
			(pads allowed)
			(copperpour not_allowed)
			(footprints allowed)
		)
		(placement
			(enabled no)
			(sheetname "")
		)
		(fill
			(thermal_gap 0.5)
			(thermal_bridge_width 0.5)
			(island_removal_mode 0)
		)
		(polygon
			(pts
				(arc
					(start 270.840708 -343.533222)
					(mid 270.804787 -343.548101)
					(end 270.789908 -343.584022)
				)
				(arc
					(start 270.789908 -344.320622)
					(mid 270.804787 -344.356543)
					(end 270.840708 -344.371422)
				)
				(xy 271.084548 -344.371422) (xy 271.438878 -344.139012) (xy 271.794478 -344.371422)
				(arc
					(start 272.037048 -344.371422)
					(mid 272.072969 -344.356543)
					(end 272.087848 -344.320622)
				)
				(arc
					(start 272.087848 -343.584022)
					(mid 272.072969 -343.548101)
					(end 272.037048 -343.533222)
				)
				(xy 271.794478 -343.533222) (xy 271.437608 -343.765632) (xy 271.083278 -343.533222)
			)
		)
	)
	(zone
		(layer "In1.Cu")
		(hatch none 0.5)
		(connect_pads
			(clearance 0)
		)
		(min_thickness 0.25)
		(keepout
			(tracks not_allowed)
			(vias allowed)
			(pads allowed)
			(copperpour not_allowed)
			(footprints allowed)
		)
		(placement
			(enabled no)
			(sheetname "")
		)
		(fill
			(thermal_gap 0.5)
			(thermal_bridge_width 0.5)
			(island_removal_mode 0)
		)
		(polygon
			(pts
				(arc
					(start 390.19988 -27.405838)
					(mid 390.185001 -27.441759)
					(end 390.14908 -27.456638)
				)
				(arc
					(start 388.91718 -27.456638)
					(mid 388.881259 -27.441759)
					(end 388.86638 -27.405838)
				)
				(arc
					(start 388.86638 -26.37409)
					(mid 388.881259 -26.338169)
					(end 388.91718 -26.32329)
				)
				(arc
					(start 390.14908 -26.32329)
					(mid 390.185001 -26.338169)
					(end 390.19988 -26.37409)
				)
			)
		)
	)
	(zone
		(layer "In1.Cu")
		(hatch none 0.5)
		(connect_pads
			(clearance 0)
		)
		(min_thickness 0.25)
		(keepout
			(tracks not_allowed)
			(vias allowed)
			(pads allowed)
			(copperpour not_allowed)
			(footprints allowed)
		)
		(placement
			(enabled no)
			(sheetname "")
		)
		(fill
			(thermal_gap 0.5)
			(thermal_bridge_width 0.5)
			(island_removal_mode 0)
		)
		(polygon
			(pts
				(arc
					(start 420.31539 -34.68624)
					(mid 420.330269 -34.722161)
					(end 420.36619 -34.73704)
				)
				(arc
					(start 421.10279 -34.73704)
					(mid 421.138711 -34.722161)
					(end 421.15359 -34.68624)
				)
				(xy 421.15359 -34.4424) (xy 420.92118 -34.08807) (xy 421.15359 -33.73247)
				(arc
					(start 421.15359 -33.4899)
					(mid 421.138711 -33.453979)
					(end 421.10279 -33.4391)
				)
				(arc
					(start 420.36619 -33.4391)
					(mid 420.330269 -33.453979)
					(end 420.31539 -33.4899)
				)
				(xy 420.31539 -33.73247) (xy 420.5478 -34.08934) (xy 420.31539 -34.44367)
			)
		)
	)
	(zone
		(layer "In1.Cu")
		(hatch none 0.5)
		(connect_pads
			(clearance 0)
		)
		(min_thickness 0.25)
		(keepout
			(tracks not_allowed)
			(vias allowed)
			(pads allowed)
			(copperpour not_allowed)
			(footprints allowed)
		)
		(placement
			(enabled no)
			(sheetname "")
		)
		(fill
			(thermal_gap 0.5)
			(thermal_bridge_width 0.5)
			(island_removal_mode 0)
		)
		(polygon
			(pts
				(arc
					(start 136.568434 -343.533222)
					(mid 136.532513 -343.548101)
					(end 136.517634 -343.584022)
				)
				(arc
					(start 136.517634 -344.320622)
					(mid 136.532513 -344.356543)
					(end 136.568434 -344.371422)
				)
				(xy 136.812274 -344.371422) (xy 137.166604 -344.139012) (xy 137.522204 -344.371422)
				(arc
					(start 137.764774 -344.371422)
					(mid 137.800695 -344.356543)
					(end 137.815574 -344.320622)
				)
				(arc
					(start 137.815574 -343.584022)
					(mid 137.800695 -343.548101)
					(end 137.764774 -343.533222)
				)
				(xy 137.522204 -343.533222) (xy 137.165334 -343.765632) (xy 136.811004 -343.533222)
			)
		)
	)
	(zone
		(layer "In1.Cu")
		(hatch none 0.5)
		(connect_pads
			(clearance 0)
		)
		(min_thickness 0.25)
		(keepout
			(tracks not_allowed)
			(vias allowed)
			(pads allowed)
			(copperpour not_allowed)
			(footprints allowed)
		)
		(placement
			(enabled no)
			(sheetname "")
		)
		(fill
			(thermal_gap 0.5)
			(thermal_bridge_width 0.5)
			(island_removal_mode 0)
		)
		(polygon
			(pts
				(arc
					(start 184.147714 -131.64185)
					(mid 184.162593 -131.605929)
					(end 184.198514 -131.59105)
				)
				(arc
					(start 185.379614 -131.59105)
					(mid 185.415535 -131.605929)
					(end 185.430414 -131.64185)
				)
				(arc
					(start 185.430414 -132.648198)
					(mid 185.415535 -132.684119)
					(end 185.379614 -132.698998)
				)
				(arc
					(start 184.198514 -132.698998)
					(mid 184.162593 -132.684119)
					(end 184.147714 -132.648198)
				)
			)
		)
	)
	(zone
		(layer "In1.Cu")
		(hatch none 0.5)
		(connect_pads
			(clearance 0)
		)
		(min_thickness 0.25)
		(keepout
			(tracks not_allowed)
			(vias allowed)
			(pads allowed)
			(copperpour not_allowed)
			(footprints allowed)
		)
		(placement
			(enabled no)
			(sheetname "")
		)
		(fill
			(thermal_gap 0.5)
			(thermal_bridge_width 0.5)
			(island_removal_mode 0)
		)
		(polygon
			(pts
				(arc
					(start 358.329992 -28.174188)
					(mid 358.344871 -28.138267)
					(end 358.380792 -28.123388)
				)
				(arc
					(start 359.612692 -28.123388)
					(mid 359.648613 -28.138267)
					(end 359.663492 -28.174188)
				)
				(arc
					(start 359.663492 -29.205936)
					(mid 359.648613 -29.241857)
					(end 359.612692 -29.256736)
				)
				(arc
					(start 358.380792 -29.256736)
					(mid 358.344871 -29.241857)
					(end 358.329992 -29.205936)
				)
			)
		)
	)
	(zone
		(layer "In1.Cu")
		(hatch none 0.5)
		(connect_pads
			(clearance 0)
		)
		(min_thickness 0.25)
		(keepout
			(tracks not_allowed)
			(vias allowed)
			(pads allowed)
			(copperpour not_allowed)
			(footprints allowed)
		)
		(placement
			(enabled no)
			(sheetname "")
		)
		(fill
			(thermal_gap 0.5)
			(thermal_bridge_width 0.5)
			(island_removal_mode 0)
		)
		(polygon
			(pts
				(arc
					(start 45.432726 -130.361944)
					(mid 45.447605 -130.326023)
					(end 45.483526 -130.311144)
				)
				(arc
					(start 46.664626 -130.311144)
					(mid 46.700547 -130.326023)
					(end 46.715426 -130.361944)
				)
				(arc
					(start 46.715426 -131.368292)
					(mid 46.700547 -131.404213)
					(end 46.664626 -131.419092)
				)
				(arc
					(start 45.483526 -131.419092)
					(mid 45.447605 -131.404213)
					(end 45.432726 -131.368292)
				)
			)
		)
	)
	(zone
		(layer "In1.Cu")
		(hatch none 0.5)
		(connect_pads
			(clearance 0)
		)
		(min_thickness 0.25)
		(keepout
			(tracks not_allowed)
			(vias allowed)
			(pads allowed)
			(copperpour not_allowed)
			(footprints allowed)
		)
		(placement
			(enabled no)
			(sheetname "")
		)
		(fill
			(thermal_gap 0.5)
			(thermal_bridge_width 0.5)
			(island_removal_mode 0)
		)
		(polygon
			(pts
				(arc
					(start 343.42705 -349.679514)
					(mid 343.391129 -349.694393)
					(end 343.37625 -349.730314)
				)
				(arc
					(start 343.37625 -350.466914)
					(mid 343.391129 -350.502835)
					(end 343.42705 -350.517714)
				)
				(xy 343.67089 -350.517714) (xy 344.02522 -350.285304) (xy 344.38082 -350.517714)
				(arc
					(start 344.62339 -350.517714)
					(mid 344.659311 -350.502835)
					(end 344.67419 -350.466914)
				)
				(arc
					(start 344.67419 -349.730314)
					(mid 344.659311 -349.694393)
					(end 344.62339 -349.679514)
				)
				(xy 344.38082 -349.679514) (xy 344.02395 -349.911924) (xy 343.66962 -349.679514)
			)
		)
	)
	(zone
		(layer "In1.Cu")
		(hatch none 0.5)
		(connect_pads
			(clearance 0)
		)
		(min_thickness 0.25)
		(keepout
			(tracks not_allowed)
			(vias allowed)
			(pads allowed)
			(copperpour not_allowed)
			(footprints allowed)
		)
		(placement
			(enabled no)
			(sheetname "")
		)
		(fill
			(thermal_gap 0.5)
			(thermal_bridge_width 0.5)
			(island_removal_mode 0)
		)
		(polygon
			(pts
				(arc
					(start 330.21524 -31.086044)
					(mid 330.230119 -31.121965)
					(end 330.26604 -31.136844)
				)
				(arc
					(start 331.00264 -31.136844)
					(mid 331.038561 -31.121965)
					(end 331.05344 -31.086044)
				)
				(xy 331.05344 -30.842204) (xy 330.82103 -30.487874) (xy 331.05344 -30.132274)
				(arc
					(start 331.05344 -29.889704)
					(mid 331.038561 -29.853783)
					(end 331.00264 -29.838904)
				)
				(arc
					(start 330.26604 -29.838904)
					(mid 330.230119 -29.853783)
					(end 330.21524 -29.889704)
				)
				(xy 330.21524 -30.132274) (xy 330.44765 -30.489144) (xy 330.21524 -30.843474)
			)
		)
	)
	(zone
		(layer "In1.Cu")
		(hatch none 0.5)
		(connect_pads
			(clearance 0)
		)
		(min_thickness 0.25)
		(keepout
			(tracks not_allowed)
			(vias allowed)
			(pads allowed)
			(copperpour not_allowed)
			(footprints allowed)
		)
		(placement
			(enabled no)
			(sheetname "")
		)
		(fill
			(thermal_gap 0.5)
			(thermal_bridge_width 0.5)
			(island_removal_mode 0)
		)
		(polygon
			(pts
				(arc
					(start 314.442348 -149.051264)
					(mid 314.457227 -149.087185)
					(end 314.493148 -149.102064)
				)
				(arc
					(start 315.229748 -149.102064)
					(mid 315.265669 -149.087185)
					(end 315.280548 -149.051264)
				)
				(xy 315.280548 -148.807424) (xy 315.048138 -148.453094) (xy 315.280548 -148.097494)
				(arc
					(start 315.280548 -147.854924)
					(mid 315.265669 -147.819003)
					(end 315.229748 -147.804124)
				)
				(arc
					(start 314.493148 -147.804124)
					(mid 314.457227 -147.819003)
					(end 314.442348 -147.854924)
				)
				(xy 314.442348 -148.097494) (xy 314.674758 -148.454364) (xy 314.442348 -148.808694)
			)
		)
	)
	(zone
		(layer "In1.Cu")
		(hatch none 0.5)
		(connect_pads
			(clearance 0)
		)
		(min_thickness 0.25)
		(keepout
			(tracks not_allowed)
			(vias allowed)
			(pads allowed)
			(copperpour not_allowed)
			(footprints allowed)
		)
		(placement
			(enabled no)
			(sheetname "")
		)
		(fill
			(thermal_gap 0.5)
			(thermal_bridge_width 0.5)
			(island_removal_mode 0)
		)
		(polygon
			(pts
				(arc
					(start 174.456598 -349.679514)
					(mid 174.420677 -349.694393)
					(end 174.405798 -349.730314)
				)
				(arc
					(start 174.405798 -350.466914)
					(mid 174.420677 -350.502835)
					(end 174.456598 -350.517714)
				)
				(xy 174.700438 -350.517714) (xy 175.054768 -350.285304) (xy 175.410368 -350.517714)
				(arc
					(start 175.652938 -350.517714)
					(mid 175.688859 -350.502835)
					(end 175.703738 -350.466914)
				)
				(arc
					(start 175.703738 -349.730314)
					(mid 175.688859 -349.694393)
					(end 175.652938 -349.679514)
				)
				(xy 175.410368 -349.679514) (xy 175.053498 -349.911924) (xy 174.699168 -349.679514)
			)
		)
	)
	(zone
		(layer "In1.Cu")
		(hatch none 0.5)
		(connect_pads
			(clearance 0)
		)
		(min_thickness 0.25)
		(keepout
			(tracks not_allowed)
			(vias allowed)
			(pads allowed)
			(copperpour not_allowed)
			(footprints allowed)
		)
		(placement
			(enabled no)
			(sheetname "")
		)
		(fill
			(thermal_gap 0.5)
			(thermal_bridge_width 0.5)
			(island_removal_mode 0)
		)
		(polygon
			(pts
				(arc
					(start 300.247812 -142.551912)
					(mid 300.262691 -142.515991)
					(end 300.298612 -142.501112)
				)
				(arc
					(start 301.479712 -142.501112)
					(mid 301.515633 -142.515991)
					(end 301.530512 -142.551912)
				)
				(arc
					(start 301.530512 -143.55826)
					(mid 301.515633 -143.594181)
					(end 301.479712 -143.60906)
				)
				(arc
					(start 300.298612 -143.60906)
					(mid 300.262691 -143.594181)
					(end 300.247812 -143.55826)
				)
			)
		)
	)
	(zone
		(layer "In1.Cu")
		(hatch none 0.5)
		(connect_pads
			(clearance 0)
		)
		(min_thickness 0.25)
		(keepout
			(tracks not_allowed)
			(vias allowed)
			(pads allowed)
			(copperpour not_allowed)
			(footprints allowed)
		)
		(placement
			(enabled no)
			(sheetname "")
		)
		(fill
			(thermal_gap 0.5)
			(thermal_bridge_width 0.5)
			(island_removal_mode 0)
		)
		(polygon
			(pts
				(arc
					(start 387.161532 -100.343208)
					(mid 387.176411 -100.379129)
					(end 387.212332 -100.394008)
				)
				(arc
					(start 387.948932 -100.394008)
					(mid 387.984853 -100.379129)
					(end 387.999732 -100.343208)
				)
				(xy 387.999732 -100.099368) (xy 387.767322 -99.745038) (xy 387.999732 -99.389438)
				(arc
					(start 387.999732 -99.146868)
					(mid 387.984853 -99.110947)
					(end 387.948932 -99.096068)
				)
				(arc
					(start 387.212332 -99.096068)
					(mid 387.176411 -99.110947)
					(end 387.161532 -99.146868)
				)
				(xy 387.161532 -99.389438) (xy 387.393942 -99.746308) (xy 387.161532 -100.100638)
			)
		)
	)
	(zone
		(layer "In1.Cu")
		(hatch none 0.5)
		(connect_pads
			(clearance 0)
		)
		(min_thickness 0.25)
		(keepout
			(tracks not_allowed)
			(vias allowed)
			(pads allowed)
			(copperpour not_allowed)
			(footprints allowed)
		)
		(placement
			(enabled no)
			(sheetname "")
		)
		(fill
			(thermal_gap 0.5)
			(thermal_bridge_width 0.5)
			(island_removal_mode 0)
		)
		(polygon
			(pts
				(arc
					(start 184.147714 -151.551894)
					(mid 184.162593 -151.515973)
					(end 184.198514 -151.501094)
				)
				(arc
					(start 185.379614 -151.501094)
					(mid 185.415535 -151.515973)
					(end 185.430414 -151.551894)
				)
				(arc
					(start 185.430414 -152.558242)
					(mid 185.415535 -152.594163)
					(end 185.379614 -152.609042)
				)
				(arc
					(start 184.198514 -152.609042)
					(mid 184.162593 -152.594163)
					(end 184.147714 -152.558242)
				)
			)
		)
	)
	(zone
		(layer "In1.Cu")
		(hatch none 0.5)
		(connect_pads
			(clearance 0)
		)
		(min_thickness 0.25)
		(keepout
			(tracks not_allowed)
			(vias allowed)
			(pads allowed)
			(copperpour not_allowed)
			(footprints allowed)
		)
		(placement
			(enabled no)
			(sheetname "")
		)
		(fill
			(thermal_gap 0.5)
			(thermal_bridge_width 0.5)
			(island_removal_mode 0)
		)
		(polygon
			(pts
				(arc
					(start 229.57028 -86.712552)
					(mid 229.534359 -86.697673)
					(end 229.51948 -86.661752)
				)
				(arc
					(start 229.51948 -86.255098)
					(mid 229.534359 -86.219177)
					(end 229.57028 -86.204298)
				)
				(arc
					(start 229.972616 -86.204298)
					(mid 230.008537 -86.219177)
					(end 230.023416 -86.255098)
				)
				(arc
					(start 230.023416 -86.661752)
					(mid 230.008537 -86.697673)
					(end 229.972616 -86.712552)
				)
			)
		)
	)
	(zone
		(layer "In1.Cu")
		(hatch none 0.5)
		(connect_pads
			(clearance 0)
		)
		(min_thickness 0.25)
		(keepout
			(tracks not_allowed)
			(vias allowed)
			(pads allowed)
			(copperpour not_allowed)
			(footprints allowed)
		)
		(placement
			(enabled no)
			(sheetname "")
		)
		(fill
			(thermal_gap 0.5)
			(thermal_bridge_width 0.5)
			(island_removal_mode 0)
		)
		(polygon
			(pts
				(arc
					(start 183.999886 -34.605976)
					(mid 183.985007 -34.641897)
					(end 183.949086 -34.656776)
				)
				(arc
					(start 182.717186 -34.656776)
					(mid 182.681265 -34.641897)
					(end 182.666386 -34.605976)
				)
				(arc
					(start 182.666386 -33.574228)
					(mid 182.681265 -33.538307)
					(end 182.717186 -33.523428)
				)
				(arc
					(start 183.949086 -33.523428)
					(mid 183.985007 -33.538307)
					(end 183.999886 -33.574228)
				)
			)
		)
	)
	(zone
		(layer "In1.Cu")
		(hatch none 0.5)
		(connect_pads
			(clearance 0)
		)
		(min_thickness 0.25)
		(keepout
			(tracks not_allowed)
			(vias allowed)
			(pads allowed)
			(copperpour not_allowed)
			(footprints allowed)
		)
		(placement
			(enabled no)
			(sheetname "")
		)
		(fill
			(thermal_gap 0.5)
			(thermal_bridge_width 0.5)
			(island_removal_mode 0)
		)
		(polygon
			(pts
				(arc
					(start 416.34791 -153.351992)
					(mid 416.362789 -153.316071)
					(end 416.39871 -153.301192)
				)
				(arc
					(start 417.57981 -153.301192)
					(mid 417.615731 -153.316071)
					(end 417.63061 -153.351992)
				)
				(arc
					(start 417.63061 -154.35834)
					(mid 417.615731 -154.394261)
					(end 417.57981 -154.40914)
				)
				(arc
					(start 416.39871 -154.40914)
					(mid 416.362789 -154.394261)
					(end 416.34791 -154.35834)
				)
			)
		)
	)
	(zone
		(layer "In1.Cu")
		(hatch none 0.5)
		(connect_pads
			(clearance 0)
		)
		(min_thickness 0.25)
		(keepout
			(tracks not_allowed)
			(vias allowed)
			(pads allowed)
			(copperpour not_allowed)
			(footprints allowed)
		)
		(placement
			(enabled no)
			(sheetname "")
		)
		(fill
			(thermal_gap 0.5)
			(thermal_bridge_width 0.5)
			(island_removal_mode 0)
		)
		(polygon
			(pts
				(arc
					(start 326.099678 -34.605976)
					(mid 326.084799 -34.641897)
					(end 326.048878 -34.656776)
				)
				(arc
					(start 324.816978 -34.656776)
					(mid 324.781057 -34.641897)
					(end 324.766178 -34.605976)
				)
				(arc
					(start 324.766178 -33.574228)
					(mid 324.781057 -33.538307)
					(end 324.816978 -33.523428)
				)
				(arc
					(start 326.048878 -33.523428)
					(mid 326.084799 -33.538307)
					(end 326.099678 -33.574228)
				)
			)
		)
	)
	(zone
		(layer "In1.Cu")
		(hatch none 0.5)
		(connect_pads
			(clearance 0)
		)
		(min_thickness 0.25)
		(keepout
			(tracks not_allowed)
			(vias allowed)
			(pads allowed)
			(copperpour not_allowed)
			(footprints allowed)
		)
		(placement
			(enabled no)
			(sheetname "")
		)
		(fill
			(thermal_gap 0.5)
			(thermal_bridge_width 0.5)
			(island_removal_mode 0)
		)
		(polygon
			(pts
				(arc
					(start 189.967108 -117.838474)
					(mid 189.952229 -117.874395)
					(end 189.916308 -117.889274)
				)
				(arc
					(start 188.735208 -117.889274)
					(mid 188.699287 -117.874395)
					(end 188.684408 -117.838474)
				)
				(arc
					(start 188.684408 -116.832126)
					(mid 188.699287 -116.796205)
					(end 188.735208 -116.781326)
				)
				(arc
					(start 189.916308 -116.781326)
					(mid 189.952229 -116.796205)
					(end 189.967108 -116.832126)
				)
			)
		)
	)
	(zone
		(layer "In1.Cu")
		(hatch none 0.5)
		(connect_pads
			(clearance 0)
		)
		(min_thickness 0.25)
		(keepout
			(tracks not_allowed)
			(vias allowed)
			(pads allowed)
			(copperpour not_allowed)
			(footprints allowed)
		)
		(placement
			(enabled no)
			(sheetname "")
		)
		(fill
			(thermal_gap 0.5)
			(thermal_bridge_width 0.5)
			(island_removal_mode 0)
		)
		(polygon
			(pts
				(arc
					(start 384.519424 -131.463288)
					(mid 384.534303 -131.499209)
					(end 384.570224 -131.514088)
				)
				(arc
					(start 385.306824 -131.514088)
					(mid 385.342745 -131.499209)
					(end 385.357624 -131.463288)
				)
				(xy 385.357624 -131.219448) (xy 385.125214 -130.865118) (xy 385.357624 -130.509518)
				(arc
					(start 385.357624 -130.266948)
					(mid 385.342745 -130.231027)
					(end 385.306824 -130.216148)
				)
				(arc
					(start 384.570224 -130.216148)
					(mid 384.534303 -130.231027)
					(end 384.519424 -130.266948)
				)
				(xy 384.519424 -130.509518) (xy 384.751834 -130.866388) (xy 384.519424 -131.220718)
			)
		)
	)
	(zone
		(layer "In1.Cu")
		(hatch none 0.5)
		(connect_pads
			(clearance 0)
		)
		(min_thickness 0.25)
		(keepout
			(tracks not_allowed)
			(vias allowed)
			(pads allowed)
			(copperpour not_allowed)
			(footprints allowed)
		)
		(placement
			(enabled no)
			(sheetname "")
		)
		(fill
			(thermal_gap 0.5)
			(thermal_bridge_width 0.5)
			(island_removal_mode 0)
		)
		(polygon
			(pts
				(arc
					(start 31.602934 -349.679514)
					(mid 31.567013 -349.694393)
					(end 31.552134 -349.730314)
				)
				(arc
					(start 31.552134 -350.466914)
					(mid 31.567013 -350.502835)
					(end 31.602934 -350.517714)
				)
				(xy 31.846774 -350.517714) (xy 32.201104 -350.285304) (xy 32.556704 -350.517714)
				(arc
					(start 32.799274 -350.517714)
					(mid 32.835195 -350.502835)
					(end 32.850074 -350.466914)
				)
				(arc
					(start 32.850074 -349.730314)
					(mid 32.835195 -349.694393)
					(end 32.799274 -349.679514)
				)
				(xy 32.556704 -349.679514) (xy 32.199834 -349.911924) (xy 31.845504 -349.679514)
			)
		)
	)
	(zone
		(layer "In1.Cu")
		(hatch none 0.5)
		(connect_pads
			(clearance 0)
		)
		(min_thickness 0.25)
		(keepout
			(tracks not_allowed)
			(vias allowed)
			(pads allowed)
			(copperpour not_allowed)
			(footprints allowed)
		)
		(placement
			(enabled no)
			(sheetname "")
		)
		(fill
			(thermal_gap 0.5)
			(thermal_bridge_width 0.5)
			(island_removal_mode 0)
		)
		(polygon
			(pts
				(arc
					(start 229.973632 -86.95436)
					(mid 230.009553 -86.969239)
					(end 230.024432 -87.00516)
				)
				(arc
					(start 230.024432 -87.411814)
					(mid 230.009553 -87.447735)
					(end 229.973632 -87.462614)
				)
				(arc
					(start 229.571296 -87.462614)
					(mid 229.535375 -87.447735)
					(end 229.520496 -87.411814)
				)
				(arc
					(start 229.520496 -87.00516)
					(mid 229.535375 -86.969239)
					(end 229.571296 -86.95436)
				)
			)
		)
	)
	(zone
		(layer "In1.Cu")
		(hatch none 0.5)
		(connect_pads
			(clearance 0)
		)
		(min_thickness 0.25)
		(keepout
			(tracks not_allowed)
			(vias allowed)
			(pads allowed)
			(copperpour not_allowed)
			(footprints allowed)
		)
		(placement
			(enabled no)
			(sheetname "")
		)
		(fill
			(thermal_gap 0.5)
			(thermal_bridge_width 0.5)
			(island_removal_mode 0)
		)
		(polygon
			(pts
				(arc
					(start 154.961336 -107.543092)
					(mid 154.976215 -107.579013)
					(end 155.012136 -107.593892)
				)
				(arc
					(start 155.748736 -107.593892)
					(mid 155.784657 -107.579013)
					(end 155.799536 -107.543092)
				)
				(xy 155.799536 -107.299252) (xy 155.567126 -106.944922) (xy 155.799536 -106.589322)
				(arc
					(start 155.799536 -106.346752)
					(mid 155.784657 -106.310831)
					(end 155.748736 -106.295952)
				)
				(arc
					(start 155.012136 -106.295952)
					(mid 154.976215 -106.310831)
					(end 154.961336 -106.346752)
				)
				(xy 154.961336 -106.589322) (xy 155.193746 -106.946192) (xy 154.961336 -107.300522)
			)
		)
	)
	(zone
		(layer "In1.Cu")
		(hatch none 0.5)
		(connect_pads
			(clearance 0)
		)
		(min_thickness 0.25)
		(keepout
			(tracks not_allowed)
			(vias allowed)
			(pads allowed)
			(copperpour not_allowed)
			(footprints allowed)
		)
		(placement
			(enabled no)
			(sheetname "")
		)
		(fill
			(thermal_gap 0.5)
			(thermal_bridge_width 0.5)
			(island_removal_mode 0)
		)
		(polygon
			(pts
				(arc
					(start 126.13005 -28.174188)
					(mid 126.144929 -28.138267)
					(end 126.18085 -28.123388)
				)
				(arc
					(start 127.41275 -28.123388)
					(mid 127.448671 -28.138267)
					(end 127.46355 -28.174188)
				)
				(arc
					(start 127.46355 -29.205936)
					(mid 127.448671 -29.241857)
					(end 127.41275 -29.256736)
				)
				(arc
					(start 126.18085 -29.256736)
					(mid 126.144929 -29.241857)
					(end 126.13005 -29.205936)
				)
			)
		)
	)
	(zone
		(layer "In1.Cu")
		(hatch none 0.5)
		(connect_pads
			(clearance 0)
		)
		(min_thickness 0.25)
		(keepout
			(tracks not_allowed)
			(vias allowed)
			(pads allowed)
			(copperpour not_allowed)
			(footprints allowed)
		)
		(placement
			(enabled no)
			(sheetname "")
		)
		(fill
			(thermal_gap 0.5)
			(thermal_bridge_width 0.5)
			(island_removal_mode 0)
		)
		(polygon
			(pts
				(arc
					(start 62.029848 -33.574228)
					(mid 62.044727 -33.538307)
					(end 62.080648 -33.523428)
				)
				(arc
					(start 63.312548 -33.523428)
					(mid 63.348469 -33.538307)
					(end 63.363348 -33.574228)
				)
				(arc
					(start 63.363348 -34.605976)
					(mid 63.348469 -34.641897)
					(end 63.312548 -34.656776)
				)
				(arc
					(start 62.080648 -34.656776)
					(mid 62.044727 -34.641897)
					(end 62.029848 -34.605976)
				)
			)
		)
	)
	(zone
		(layer "In1.Cu")
		(hatch none 0.5)
		(connect_pads
			(clearance 0)
		)
		(min_thickness 0.25)
		(keepout
			(tracks not_allowed)
			(vias allowed)
			(pads allowed)
			(copperpour not_allowed)
			(footprints allowed)
		)
		(placement
			(enabled no)
			(sheetname "")
		)
		(fill
			(thermal_gap 0.5)
			(thermal_bridge_width 0.5)
			(island_removal_mode 0)
		)
		(polygon
			(pts
				(arc
					(start 189.967108 -134.448296)
					(mid 189.952229 -134.484217)
					(end 189.916308 -134.499096)
				)
				(arc
					(start 188.735208 -134.499096)
					(mid 188.699287 -134.484217)
					(end 188.684408 -134.448296)
				)
				(arc
					(start 188.684408 -133.441948)
					(mid 188.699287 -133.406027)
					(end 188.735208 -133.391148)
				)
				(arc
					(start 189.916308 -133.391148)
					(mid 189.952229 -133.406027)
					(end 189.967108 -133.441948)
				)
			)
		)
	)
	(zone
		(layer "In1.Cu")
		(hatch none 0.5)
		(connect_pads
			(clearance 0)
		)
		(min_thickness 0.25)
		(keepout
			(tracks not_allowed)
			(vias allowed)
			(pads allowed)
			(copperpour not_allowed)
			(footprints allowed)
		)
		(placement
			(enabled no)
			(sheetname "")
		)
		(fill
			(thermal_gap 0.5)
			(thermal_bridge_width 0.5)
			(island_removal_mode 0)
		)
		(polygon
			(pts
				(arc
					(start 277.632668 -99.241864)
					(mid 277.647547 -99.205943)
					(end 277.683468 -99.191064)
				)
				(arc
					(start 278.864568 -99.191064)
					(mid 278.900489 -99.205943)
					(end 278.915368 -99.241864)
				)
				(arc
					(start 278.915368 -100.248212)
					(mid 278.900489 -100.284133)
					(end 278.864568 -100.299012)
				)
				(arc
					(start 277.683468 -100.299012)
					(mid 277.647547 -100.284133)
					(end 277.632668 -100.248212)
				)
			)
		)
	)
	(zone
		(layer "In1.Cu")
		(hatch none 0.5)
		(connect_pads
			(clearance 0)
		)
		(min_thickness 0.25)
		(keepout
			(tracks not_allowed)
			(vias allowed)
			(pads allowed)
			(copperpour not_allowed)
			(footprints allowed)
		)
		(placement
			(enabled no)
			(sheetname "")
		)
		(fill
			(thermal_gap 0.5)
			(thermal_bridge_width 0.5)
			(island_removal_mode 0)
		)
		(polygon
			(pts
				(arc
					(start 391.673334 -32.879538)
					(mid 391.688213 -32.915459)
					(end 391.724134 -32.930338)
				)
				(arc
					(start 392.460734 -32.930338)
					(mid 392.496655 -32.915459)
					(end 392.511534 -32.879538)
				)
				(xy 392.511534 -32.635698) (xy 392.279124 -32.281368) (xy 392.511534 -31.925768)
				(arc
					(start 392.511534 -31.683198)
					(mid 392.496655 -31.647277)
					(end 392.460734 -31.632398)
				)
				(arc
					(start 391.724134 -31.632398)
					(mid 391.688213 -31.647277)
					(end 391.673334 -31.683198)
				)
				(xy 391.673334 -31.925768) (xy 391.905744 -32.282638) (xy 391.673334 -32.636968)
			)
		)
	)
	(zone
		(layer "In1.Cu")
		(hatch none 0.5)
		(connect_pads
			(clearance 0)
		)
		(min_thickness 0.25)
		(keepout
			(tracks not_allowed)
			(vias allowed)
			(pads allowed)
			(copperpour not_allowed)
			(footprints allowed)
		)
		(placement
			(enabled no)
			(sheetname "")
		)
		(fill
			(thermal_gap 0.5)
			(thermal_bridge_width 0.5)
			(island_removal_mode 0)
		)
		(polygon
			(pts
				(arc
					(start 271.061434 -133.269736)
					(mid 271.076313 -133.305657)
					(end 271.112234 -133.320536)
				)
				(arc
					(start 271.848834 -133.320536)
					(mid 271.884755 -133.305657)
					(end 271.899634 -133.269736)
				)
				(xy 271.899634 -133.025896) (xy 271.667224 -132.671566) (xy 271.899634 -132.315966)
				(arc
					(start 271.899634 -132.073396)
					(mid 271.884755 -132.037475)
					(end 271.848834 -132.022596)
				)
				(arc
					(start 271.112234 -132.022596)
					(mid 271.076313 -132.037475)
					(end 271.061434 -132.073396)
				)
				(xy 271.061434 -132.315966) (xy 271.293844 -132.672836) (xy 271.061434 -133.027166)
			)
		)
	)
	(zone
		(layer "In1.Cu")
		(hatch none 0.5)
		(connect_pads
			(clearance 0)
		)
		(min_thickness 0.25)
		(keepout
			(tracks not_allowed)
			(vias allowed)
			(pads allowed)
			(copperpour not_allowed)
			(footprints allowed)
		)
		(placement
			(enabled no)
			(sheetname "")
		)
		(fill
			(thermal_gap 0.5)
			(thermal_bridge_width 0.5)
			(island_removal_mode 0)
		)
		(polygon
			(pts
				(arc
					(start 314.442348 -152.651206)
					(mid 314.457227 -152.687127)
					(end 314.493148 -152.702006)
				)
				(arc
					(start 315.229748 -152.702006)
					(mid 315.265669 -152.687127)
					(end 315.280548 -152.651206)
				)
				(xy 315.280548 -152.407366) (xy 315.048138 -152.053036) (xy 315.280548 -151.697436)
				(arc
					(start 315.280548 -151.454866)
					(mid 315.265669 -151.418945)
					(end 315.229748 -151.404066)
				)
				(arc
					(start 314.493148 -151.404066)
					(mid 314.457227 -151.418945)
					(end 314.442348 -151.454866)
				)
				(xy 314.442348 -151.697436) (xy 314.674758 -152.054306) (xy 314.442348 -152.408636)
			)
		)
	)
	(zone
		(layer "In1.Cu")
		(hatch none 0.5)
		(connect_pads
			(clearance 0)
		)
		(min_thickness 0.25)
		(keepout
			(tracks not_allowed)
			(vias allowed)
			(pads allowed)
			(copperpour not_allowed)
			(footprints allowed)
		)
		(placement
			(enabled no)
			(sheetname "")
		)
		(fill
			(thermal_gap 0.5)
			(thermal_bridge_width 0.5)
			(island_removal_mode 0)
		)
		(polygon
			(pts
				(arc
					(start 394.315442 -31.086044)
					(mid 394.330321 -31.121965)
					(end 394.366242 -31.136844)
				)
				(arc
					(start 395.102842 -31.136844)
					(mid 395.138763 -31.121965)
					(end 395.153642 -31.086044)
				)
				(xy 395.153642 -30.842204) (xy 394.921232 -30.487874) (xy 395.153642 -30.132274)
				(arc
					(start 395.153642 -29.889704)
					(mid 395.138763 -29.853783)
					(end 395.102842 -29.838904)
				)
				(arc
					(start 394.366242 -29.838904)
					(mid 394.330321 -29.853783)
					(end 394.315442 -29.889704)
				)
				(xy 394.315442 -30.132274) (xy 394.547852 -30.489144) (xy 394.315442 -30.843474)
			)
		)
	)
	(zone
		(layer "In1.Cu")
		(hatch none 0.5)
		(connect_pads
			(clearance 0)
		)
		(min_thickness 0.25)
		(keepout
			(tracks not_allowed)
			(vias allowed)
			(pads allowed)
			(copperpour not_allowed)
			(footprints allowed)
		)
		(placement
			(enabled no)
			(sheetname "")
		)
		(fill
			(thermal_gap 0.5)
			(thermal_bridge_width 0.5)
			(island_removal_mode 0)
		)
		(polygon
			(pts
				(arc
					(start 51.25212 -107.448096)
					(mid 51.237241 -107.484017)
					(end 51.20132 -107.498896)
				)
				(arc
					(start 50.02022 -107.498896)
					(mid 49.984299 -107.484017)
					(end 49.96942 -107.448096)
				)
				(arc
					(start 49.96942 -106.441748)
					(mid 49.984299 -106.405827)
					(end 50.02022 -106.390948)
				)
				(arc
					(start 51.20132 -106.390948)
					(mid 51.237241 -106.405827)
					(end 51.25212 -106.441748)
				)
			)
		)
	)
	(zone
		(layer "In1.Cu")
		(hatch none 0.5)
		(connect_pads
			(clearance 0)
		)
		(min_thickness 0.25)
		(keepout
			(tracks not_allowed)
			(vias allowed)
			(pads allowed)
			(copperpour not_allowed)
			(footprints allowed)
		)
		(placement
			(enabled no)
			(sheetname "")
		)
		(fill
			(thermal_gap 0.5)
			(thermal_bridge_width 0.5)
			(island_removal_mode 0)
		)
		(polygon
			(pts
				(arc
					(start 177.565558 -343.533222)
					(mid 177.529637 -343.548101)
					(end 177.514758 -343.584022)
				)
				(arc
					(start 177.514758 -344.320622)
					(mid 177.529637 -344.356543)
					(end 177.565558 -344.371422)
				)
				(xy 177.809398 -344.371422) (xy 178.163728 -344.139012) (xy 178.519328 -344.371422)
				(arc
					(start 178.761898 -344.371422)
					(mid 178.797819 -344.356543)
					(end 178.812698 -344.320622)
				)
				(arc
					(start 178.812698 -343.584022)
					(mid 178.797819 -343.548101)
					(end 178.761898 -343.533222)
				)
				(xy 178.519328 -343.533222) (xy 178.162458 -343.765632) (xy 177.808128 -343.533222)
			)
		)
	)
	(zone
		(layer "In1.Cu")
		(hatch none 0.5)
		(connect_pads
			(clearance 0)
		)
		(min_thickness 0.25)
		(keepout
			(tracks not_allowed)
			(vias allowed)
			(pads allowed)
			(copperpour not_allowed)
			(footprints allowed)
		)
		(placement
			(enabled no)
			(sheetname "")
		)
		(fill
			(thermal_gap 0.5)
			(thermal_bridge_width 0.5)
			(island_removal_mode 0)
		)
		(polygon
			(pts
				(arc
					(start 37.820854 -343.533222)
					(mid 37.784933 -343.548101)
					(end 37.770054 -343.584022)
				)
				(arc
					(start 37.770054 -344.320622)
					(mid 37.784933 -344.356543)
					(end 37.820854 -344.371422)
				)
				(xy 38.064694 -344.371422) (xy 38.419024 -344.139012) (xy 38.774624 -344.371422)
				(arc
					(start 39.017194 -344.371422)
					(mid 39.053115 -344.356543)
					(end 39.067994 -344.320622)
				)
				(arc
					(start 39.067994 -343.584022)
					(mid 39.053115 -343.548101)
					(end 39.017194 -343.533222)
				)
				(xy 38.774624 -343.533222) (xy 38.417754 -343.765632) (xy 38.063424 -343.533222)
			)
		)
	)
	(zone
		(layer "In1.Cu")
		(hatch none 0.5)
		(connect_pads
			(clearance 0)
		)
		(min_thickness 0.25)
		(keepout
			(tracks not_allowed)
			(vias allowed)
			(pads allowed)
			(copperpour not_allowed)
			(footprints allowed)
		)
		(placement
			(enabled no)
			(sheetname "")
		)
		(fill
			(thermal_gap 0.5)
			(thermal_bridge_width 0.5)
			(island_removal_mode 0)
		)
		(polygon
			(pts
				(arc
					(start 17.168622 -411.869636)
					(mid 17.268028 -411.936027)
					(end 17.385284 -411.959298)
				)
				(arc
					(start 21.604732 -411.959298)
					(mid 21.72196 -411.935958)
					(end 21.821394 -411.869636)
				)
				(xy 21.82241 -411.86862)
				(arc
					(start 21.82241 -405.3332)
					(mid 21.799092 -405.215769)
					(end 21.732494 -405.116284)
				)
				(arc
					(start 21.685504 -405.069294)
					(mid 21.586071 -405.002951)
					(end 21.468842 -404.979632)
				)
				(arc
					(start 17.370298 -404.979632)
					(mid 17.252932 -405.003071)
					(end 17.153382 -405.069548)
				)
				(arc
					(start 17.106392 -405.116538)
					(mid 17.039761 -405.216018)
					(end 17.016476 -405.333454)
				)
				(arc
					(start 17.016476 -411.59049)
					(mid 17.039832 -411.70791)
					(end 17.106392 -411.807406)
				)
			)
		)
	)
	(zone
		(layer "In1.Cu")
		(hatch none 0.5)
		(connect_pads
			(clearance 0)
		)
		(min_thickness 0.25)
		(keepout
			(tracks not_allowed)
			(vias allowed)
			(pads allowed)
			(copperpour not_allowed)
			(footprints allowed)
		)
		(placement
			(enabled no)
			(sheetname "")
		)
		(fill
			(thermal_gap 0.5)
			(thermal_bridge_width 0.5)
			(island_removal_mode 0)
		)
		(polygon
			(pts
				(arc
					(start 45.432726 -137.561574)
					(mid 45.447605 -137.525653)
					(end 45.483526 -137.510774)
				)
				(arc
					(start 46.664626 -137.510774)
					(mid 46.700547 -137.525653)
					(end 46.715426 -137.561574)
				)
				(arc
					(start 46.715426 -138.567922)
					(mid 46.700547 -138.603843)
					(end 46.664626 -138.618722)
				)
				(arc
					(start 45.483526 -138.618722)
					(mid 45.447605 -138.603843)
					(end 45.432726 -138.567922)
				)
			)
		)
	)
	(zone
		(layer "In1.Cu")
		(hatch none 0.5)
		(connect_pads
			(clearance 0)
		)
		(min_thickness 0.25)
		(keepout
			(tracks not_allowed)
			(vias allowed)
			(pads allowed)
			(copperpour not_allowed)
			(footprints allowed)
		)
		(placement
			(enabled no)
			(sheetname "")
		)
		(fill
			(thermal_gap 0.5)
			(thermal_bridge_width 0.5)
			(island_removal_mode 0)
		)
		(polygon
			(pts
				(arc
					(start 20.015454 -34.68624)
					(mid 20.030333 -34.722161)
					(end 20.066254 -34.73704)
				)
				(arc
					(start 20.802854 -34.73704)
					(mid 20.838775 -34.722161)
					(end 20.853654 -34.68624)
				)
				(xy 20.853654 -34.4424) (xy 20.621244 -34.08807) (xy 20.853654 -33.73247)
				(arc
					(start 20.853654 -33.4899)
					(mid 20.838775 -33.453979)
					(end 20.802854 -33.4391)
				)
				(arc
					(start 20.066254 -33.4391)
					(mid 20.030333 -33.453979)
					(end 20.015454 -33.4899)
				)
				(xy 20.015454 -33.73247) (xy 20.247864 -34.08934) (xy 20.015454 -34.44367)
			)
		)
	)
	(zone
		(layer "In1.Cu")
		(hatch none 0.5)
		(connect_pads
			(clearance 0)
		)
		(min_thickness 0.25)
		(keepout
			(tracks not_allowed)
			(vias allowed)
			(pads allowed)
			(copperpour not_allowed)
			(footprints allowed)
		)
		(placement
			(enabled no)
			(sheetname "")
		)
		(fill
			(thermal_gap 0.5)
			(thermal_bridge_width 0.5)
			(island_removal_mode 0)
		)
		(polygon
			(pts
				(arc
					(start 93.899736 -32.805878)
					(mid 93.884857 -32.841799)
					(end 93.848936 -32.856678)
				)
				(arc
					(start 92.617036 -32.856678)
					(mid 92.581115 -32.841799)
					(end 92.566236 -32.805878)
				)
				(arc
					(start 92.566236 -31.77413)
					(mid 92.581115 -31.738209)
					(end 92.617036 -31.72333)
				)
				(arc
					(start 93.848936 -31.72333)
					(mid 93.884857 -31.738209)
					(end 93.899736 -31.77413)
				)
			)
		)
	)
	(zone
		(layer "In1.Cu")
		(hatch none 0.5)
		(connect_pads
			(clearance 0)
		)
		(min_thickness 0.25)
		(keepout
			(tracks not_allowed)
			(vias allowed)
			(pads allowed)
			(copperpour not_allowed)
			(footprints allowed)
		)
		(placement
			(enabled no)
			(sheetname "")
		)
		(fill
			(thermal_gap 0.5)
			(thermal_bridge_width 0.5)
			(island_removal_mode 0)
		)
		(polygon
			(pts
				(arc
					(start 45.432726 -99.241864)
					(mid 45.447605 -99.205943)
					(end 45.483526 -99.191064)
				)
				(arc
					(start 46.664626 -99.191064)
					(mid 46.700547 -99.205943)
					(end 46.715426 -99.241864)
				)
				(arc
					(start 46.715426 -100.248212)
					(mid 46.700547 -100.284133)
					(end 46.664626 -100.299012)
				)
				(arc
					(start 45.483526 -100.299012)
					(mid 45.447605 -100.284133)
					(end 45.432726 -100.248212)
				)
			)
		)
	)
	(zone
		(layer "In1.Cu")
		(hatch none 0.5)
		(connect_pads
			(clearance 0)
		)
		(min_thickness 0.25)
		(keepout
			(tracks not_allowed)
			(vias allowed)
			(pads allowed)
			(copperpour not_allowed)
			(footprints allowed)
		)
		(placement
			(enabled no)
			(sheetname "")
		)
		(fill
			(thermal_gap 0.5)
			(thermal_bridge_width 0.5)
			(island_removal_mode 0)
		)
		(polygon
			(pts
				(arc
					(start 45.432726 -111.841788)
					(mid 45.447605 -111.805867)
					(end 45.483526 -111.790988)
				)
				(arc
					(start 46.664626 -111.790988)
					(mid 46.700547 -111.805867)
					(end 46.715426 -111.841788)
				)
				(arc
					(start 46.715426 -112.848136)
					(mid 46.700547 -112.884057)
					(end 46.664626 -112.898936)
				)
				(arc
					(start 45.483526 -112.898936)
					(mid 45.447605 -112.884057)
					(end 45.432726 -112.848136)
				)
			)
		)
	)
	(zone
		(layer "In1.Cu")
		(hatch none 0.5)
		(connect_pads
			(clearance 0)
		)
		(min_thickness 0.25)
		(keepout
			(tracks not_allowed)
			(vias allowed)
			(pads allowed)
			(copperpour not_allowed)
			(footprints allowed)
		)
		(placement
			(enabled no)
			(sheetname "")
		)
		(fill
			(thermal_gap 0.5)
			(thermal_bridge_width 0.5)
			(island_removal_mode 0)
		)
		(polygon
			(pts
				(arc
					(start 209.999834 -27.405838)
					(mid 209.984955 -27.441759)
					(end 209.949034 -27.456638)
				)
				(arc
					(start 208.717134 -27.456638)
					(mid 208.681213 -27.441759)
					(end 208.666334 -27.405838)
				)
				(arc
					(start 208.666334 -26.37409)
					(mid 208.681213 -26.338169)
					(end 208.717134 -26.32329)
				)
				(arc
					(start 209.949034 -26.32329)
					(mid 209.984955 -26.338169)
					(end 209.999834 -26.37409)
				)
			)
		)
	)
	(zone
		(layer "In1.Cu")
		(hatch none 0.5)
		(connect_pads
			(clearance 0)
		)
		(min_thickness 0.25)
		(keepout
			(tracks not_allowed)
			(vias allowed)
			(pads allowed)
			(copperpour not_allowed)
			(footprints allowed)
		)
		(placement
			(enabled no)
			(sheetname "")
		)
		(fill
			(thermal_gap 0.5)
			(thermal_bridge_width 0.5)
			(island_removal_mode 0)
		)
		(polygon
			(pts
				(arc
					(start 364.199932 -31.006034)
					(mid 364.185053 -31.041955)
					(end 364.149132 -31.056834)
				)
				(arc
					(start 362.917232 -31.056834)
					(mid 362.881311 -31.041955)
					(end 362.866432 -31.006034)
				)
				(arc
					(start 362.866432 -29.974286)
					(mid 362.881311 -29.938365)
					(end 362.917232 -29.923486)
				)
				(arc
					(start 364.149132 -29.923486)
					(mid 364.185053 -29.938365)
					(end 364.199932 -29.974286)
				)
			)
		)
	)
	(zone
		(layer "In1.Cu")
		(hatch none 0.5)
		(connect_pads
			(clearance 0)
		)
		(min_thickness 0.25)
		(keepout
			(tracks not_allowed)
			(vias allowed)
			(pads allowed)
			(copperpour not_allowed)
			(footprints allowed)
		)
		(placement
			(enabled no)
			(sheetname "")
		)
		(fill
			(thermal_gap 0.5)
			(thermal_bridge_width 0.5)
			(island_removal_mode 0)
		)
		(polygon
			(pts
				(arc
					(start 82.242406 -145.451068)
					(mid 82.257285 -145.486989)
					(end 82.293206 -145.501868)
				)
				(arc
					(start 83.029806 -145.501868)
					(mid 83.065727 -145.486989)
					(end 83.080606 -145.451068)
				)
				(xy 83.080606 -145.207228) (xy 82.848196 -144.852898) (xy 83.080606 -144.497298)
				(arc
					(start 83.080606 -144.254728)
					(mid 83.065727 -144.218807)
					(end 83.029806 -144.203928)
				)
				(arc
					(start 82.293206 -144.203928)
					(mid 82.257285 -144.218807)
					(end 82.242406 -144.254728)
				)
				(xy 82.242406 -144.497298) (xy 82.474816 -144.854168) (xy 82.242406 -145.208498)
			)
		)
	)
	(zone
		(layer "In1.Cu")
		(hatch none 0.5)
		(connect_pads
			(clearance 0)
		)
		(min_thickness 0.25)
		(keepout
			(tracks not_allowed)
			(vias allowed)
			(pads allowed)
			(copperpour not_allowed)
			(footprints allowed)
		)
		(placement
			(enabled no)
			(sheetname "")
		)
		(fill
			(thermal_gap 0.5)
			(thermal_bridge_width 0.5)
			(island_removal_mode 0)
		)
		(polygon
			(pts
				(arc
					(start 402.112226 -343.533222)
					(mid 402.076305 -343.548101)
					(end 402.061426 -343.584022)
				)
				(arc
					(start 402.061426 -344.320622)
					(mid 402.076305 -344.356543)
					(end 402.112226 -344.371422)
				)
				(xy 402.356066 -344.371422) (xy 402.710396 -344.139012) (xy 403.065996 -344.371422)
				(arc
					(start 403.308566 -344.371422)
					(mid 403.344487 -344.356543)
					(end 403.359366 -344.320622)
				)
				(arc
					(start 403.359366 -343.584022)
					(mid 403.344487 -343.548101)
					(end 403.308566 -343.533222)
				)
				(xy 403.065996 -343.533222) (xy 402.709126 -343.765632) (xy 402.354796 -343.533222)
			)
		)
	)
	(zone
		(layer "In1.Cu")
		(hatch none 0.5)
		(connect_pads
			(clearance 0)
		)
		(min_thickness 0.25)
		(keepout
			(tracks not_allowed)
			(vias allowed)
			(pads allowed)
			(copperpour not_allowed)
			(footprints allowed)
		)
		(placement
			(enabled no)
			(sheetname "")
		)
		(fill
			(thermal_gap 0.5)
			(thermal_bridge_width 0.5)
			(island_removal_mode 0)
		)
		(polygon
			(pts
				(arc
					(start 315.44641 -355.825806)
					(mid 315.410489 -355.840685)
					(end 315.39561 -355.876606)
				)
				(arc
					(start 315.39561 -356.613206)
					(mid 315.410489 -356.649127)
					(end 315.44641 -356.664006)
				)
				(xy 315.69025 -356.664006) (xy 316.04458 -356.431596) (xy 316.40018 -356.664006)
				(arc
					(start 316.64275 -356.664006)
					(mid 316.678671 -356.649127)
					(end 316.69355 -356.613206)
				)
				(arc
					(start 316.69355 -355.876606)
					(mid 316.678671 -355.840685)
					(end 316.64275 -355.825806)
				)
				(xy 316.40018 -355.825806) (xy 316.04331 -356.058216) (xy 315.68898 -355.825806)
			)
		)
	)
	(zone
		(layer "In1.Cu")
		(hatch none 0.5)
		(connect_pads
			(clearance 0)
		)
		(min_thickness 0.25)
		(keepout
			(tracks not_allowed)
			(vias allowed)
			(pads allowed)
			(copperpour not_allowed)
			(footprints allowed)
		)
		(placement
			(enabled no)
			(sheetname "")
		)
		(fill
			(thermal_gap 0.5)
			(thermal_bridge_width 0.5)
			(island_removal_mode 0)
		)
		(polygon
			(pts
				(arc
					(start 209.999834 -32.805878)
					(mid 209.984955 -32.841799)
					(end 209.949034 -32.856678)
				)
				(arc
					(start 208.717134 -32.856678)
					(mid 208.681213 -32.841799)
					(end 208.666334 -32.805878)
				)
				(arc
					(start 208.666334 -31.77413)
					(mid 208.681213 -31.738209)
					(end 208.717134 -31.72333)
				)
				(arc
					(start 209.949034 -31.72333)
					(mid 209.984955 -31.738209)
					(end 209.999834 -31.77413)
				)
			)
		)
	)
	(zone
		(layer "In1.Cu")
		(hatch none 0.5)
		(connect_pads
			(clearance 0)
		)
		(min_thickness 0.25)
		(keepout
			(tracks not_allowed)
			(vias allowed)
			(pads allowed)
			(copperpour not_allowed)
			(footprints allowed)
		)
		(placement
			(enabled no)
			(sheetname "")
		)
		(fill
			(thermal_gap 0.5)
			(thermal_bridge_width 0.5)
			(island_removal_mode 0)
		)
		(polygon
			(pts
				(arc
					(start 443.67323 -29.279596)
					(mid 443.688109 -29.315517)
					(end 443.72403 -29.330396)
				)
				(arc
					(start 444.46063 -29.330396)
					(mid 444.496551 -29.315517)
					(end 444.51143 -29.279596)
				)
				(xy 444.51143 -29.035756) (xy 444.27902 -28.681426) (xy 444.51143 -28.325826)
				(arc
					(start 444.51143 -28.083256)
					(mid 444.496551 -28.047335)
					(end 444.46063 -28.032456)
				)
				(arc
					(start 443.72403 -28.032456)
					(mid 443.688109 -28.047335)
					(end 443.67323 -28.083256)
				)
				(xy 443.67323 -28.325826) (xy 443.90564 -28.682696) (xy 443.67323 -29.037026)
			)
		)
	)
	(zone
		(layer "In1.Cu")
		(hatch none 0.5)
		(connect_pads
			(clearance 0)
		)
		(min_thickness 0.25)
		(keepout
			(tracks not_allowed)
			(vias allowed)
			(pads allowed)
			(copperpour not_allowed)
			(footprints allowed)
		)
		(placement
			(enabled no)
			(sheetname "")
		)
		(fill
			(thermal_gap 0.5)
			(thermal_bridge_width 0.5)
			(island_removal_mode 0)
		)
		(polygon
			(pts
				(arc
					(start 242.229894 -29.974286)
					(mid 242.244773 -29.938365)
					(end 242.280694 -29.923486)
				)
				(arc
					(start 243.512594 -29.923486)
					(mid 243.548515 -29.938365)
					(end 243.563394 -29.974286)
				)
				(arc
					(start 243.563394 -31.006034)
					(mid 243.548515 -31.041955)
					(end 243.512594 -31.056834)
				)
				(arc
					(start 242.280694 -31.056834)
					(mid 242.244773 -31.041955)
					(end 242.229894 -31.006034)
				)
			)
		)
	)
	(zone
		(layer "In1.Cu")
		(hatch none 0.5)
		(connect_pads
			(clearance 0)
		)
		(min_thickness 0.25)
		(keepout
			(tracks not_allowed)
			(vias allowed)
			(pads allowed)
			(copperpour not_allowed)
			(footprints allowed)
		)
		(placement
			(enabled no)
			(sheetname "")
		)
		(fill
			(thermal_gap 0.5)
			(thermal_bridge_width 0.5)
			(island_removal_mode 0)
		)
		(polygon
			(pts
				(arc
					(start 422.167304 -156.158184)
					(mid 422.152425 -156.194105)
					(end 422.116504 -156.208984)
				)
				(arc
					(start 420.935404 -156.208984)
					(mid 420.899483 -156.194105)
					(end 420.884604 -156.158184)
				)
				(arc
					(start 420.884604 -155.151836)
					(mid 420.899483 -155.115915)
					(end 420.935404 -155.101036)
				)
				(arc
					(start 422.116504 -155.101036)
					(mid 422.152425 -155.115915)
					(end 422.167304 -155.151836)
				)
			)
		)
	)
	(zone
		(layer "In1.Cu")
		(hatch none 0.5)
		(connect_pads
			(clearance 0)
		)
		(min_thickness 0.25)
		(keepout
			(tracks not_allowed)
			(vias allowed)
			(pads allowed)
			(copperpour not_allowed)
			(footprints allowed)
		)
		(placement
			(enabled no)
			(sheetname "")
		)
		(fill
			(thermal_gap 0.5)
			(thermal_bridge_width 0.5)
			(island_removal_mode 0)
		)
		(polygon
			(pts
				(arc
					(start 289.494468 -343.533222)
					(mid 289.458547 -343.548101)
					(end 289.443668 -343.584022)
				)
				(arc
					(start 289.443668 -344.320622)
					(mid 289.458547 -344.356543)
					(end 289.494468 -344.371422)
				)
				(xy 289.738308 -344.371422) (xy 290.092638 -344.139012) (xy 290.448238 -344.371422)
				(arc
					(start 290.690808 -344.371422)
					(mid 290.726729 -344.356543)
					(end 290.741608 -344.320622)
				)
				(arc
					(start 290.741608 -343.584022)
					(mid 290.726729 -343.548101)
					(end 290.690808 -343.533222)
				)
				(xy 290.448238 -343.533222) (xy 290.091368 -343.765632) (xy 289.737038 -343.533222)
			)
		)
	)
	(zone
		(layer "In1.Cu")
		(hatch none 0.5)
		(connect_pads
			(clearance 0)
		)
		(min_thickness 0.25)
		(keepout
			(tracks not_allowed)
			(vias allowed)
			(pads allowed)
			(copperpour not_allowed)
			(footprints allowed)
		)
		(placement
			(enabled no)
			(sheetname "")
		)
		(fill
			(thermal_gap 0.5)
			(thermal_bridge_width 0.5)
			(island_removal_mode 0)
		)
		(polygon
			(pts
				(arc
					(start 442.199776 -34.605976)
					(mid 442.184897 -34.641897)
					(end 442.148976 -34.656776)
				)
				(arc
					(start 440.917076 -34.656776)
					(mid 440.881155 -34.641897)
					(end 440.866276 -34.605976)
				)
				(arc
					(start 440.866276 -33.574228)
					(mid 440.881155 -33.538307)
					(end 440.917076 -33.523428)
				)
				(arc
					(start 442.148976 -33.523428)
					(mid 442.184897 -33.538307)
					(end 442.199776 -33.574228)
				)
			)
		)
	)
	(zone
		(layer "In1.Cu")
		(hatch none 0.5)
		(connect_pads
			(clearance 0)
		)
		(min_thickness 0.25)
		(keepout
			(tracks not_allowed)
			(vias allowed)
			(pads allowed)
			(copperpour not_allowed)
			(footprints allowed)
		)
		(placement
			(enabled no)
			(sheetname "")
		)
		(fill
			(thermal_gap 0.5)
			(thermal_bridge_width 0.5)
			(island_removal_mode 0)
		)
		(polygon
			(pts
				(arc
					(start 209.999834 -31.006034)
					(mid 209.984955 -31.041955)
					(end 209.949034 -31.056834)
				)
				(arc
					(start 208.717134 -31.056834)
					(mid 208.681213 -31.041955)
					(end 208.666334 -31.006034)
				)
				(arc
					(start 208.666334 -29.974286)
					(mid 208.681213 -29.938365)
					(end 208.717134 -29.923486)
				)
				(arc
					(start 209.949034 -29.923486)
					(mid 209.984955 -29.938365)
					(end 209.999834 -29.974286)
				)
			)
		)
	)
	(zone
		(layer "In1.Cu")
		(hatch none 0.5)
		(connect_pads
			(clearance 0)
		)
		(min_thickness 0.25)
		(keepout
			(tracks not_allowed)
			(vias allowed)
			(pads allowed)
			(copperpour not_allowed)
			(footprints allowed)
		)
		(placement
			(enabled no)
			(sheetname "")
		)
		(fill
			(thermal_gap 0.5)
			(thermal_bridge_width 0.5)
			(island_removal_mode 0)
		)
		(polygon
			(pts
				(arc
					(start 38.861492 -107.543092)
					(mid 38.876371 -107.579013)
					(end 38.912292 -107.593892)
				)
				(arc
					(start 39.648892 -107.593892)
					(mid 39.684813 -107.579013)
					(end 39.699692 -107.543092)
				)
				(xy 39.699692 -107.299252) (xy 39.467282 -106.944922) (xy 39.699692 -106.589322)
				(arc
					(start 39.699692 -106.346752)
					(mid 39.684813 -106.310831)
					(end 39.648892 -106.295952)
				)
				(arc
					(start 38.912292 -106.295952)
					(mid 38.876371 -106.310831)
					(end 38.861492 -106.346752)
				)
				(xy 38.861492 -106.589322) (xy 39.093902 -106.946192) (xy 38.861492 -107.300522)
			)
		)
	)
	(zone
		(layer "In1.Cu")
		(hatch none 0.5)
		(connect_pads
			(clearance 0)
		)
		(min_thickness 0.25)
		(keepout
			(tracks not_allowed)
			(vias allowed)
			(pads allowed)
			(copperpour not_allowed)
			(footprints allowed)
		)
		(placement
			(enabled no)
			(sheetname "")
		)
		(fill
			(thermal_gap 0.5)
			(thermal_bridge_width 0.5)
			(island_removal_mode 0)
		)
		(polygon
			(pts
				(arc
					(start 37.820854 -355.825806)
					(mid 37.784933 -355.840685)
					(end 37.770054 -355.876606)
				)
				(arc
					(start 37.770054 -356.613206)
					(mid 37.784933 -356.649127)
					(end 37.820854 -356.664006)
				)
				(xy 38.064694 -356.664006) (xy 38.419024 -356.431596) (xy 38.774624 -356.664006)
				(arc
					(start 39.017194 -356.664006)
					(mid 39.053115 -356.649127)
					(end 39.067994 -356.613206)
				)
				(arc
					(start 39.067994 -355.876606)
					(mid 39.053115 -355.840685)
					(end 39.017194 -355.825806)
				)
				(xy 38.774624 -355.825806) (xy 38.417754 -356.058216) (xy 38.063424 -355.825806)
			)
		)
	)
	(zone
		(layer "In1.Cu")
		(hatch none 0.5)
		(connect_pads
			(clearance 0)
		)
		(min_thickness 0.25)
		(keepout
			(tracks not_allowed)
			(vias allowed)
			(pads allowed)
			(copperpour not_allowed)
			(footprints allowed)
		)
		(placement
			(enabled no)
			(sheetname "")
		)
		(fill
			(thermal_gap 0.5)
			(thermal_bridge_width 0.5)
			(island_removal_mode 0)
		)
		(polygon
			(pts
				(arc
					(start 370.804948 -4.203446)
					(mid 370.738557 -4.302852)
					(end 370.715286 -4.420108)
				)
				(arc
					(start 370.715286 -8.639556)
					(mid 370.738626 -8.756784)
					(end 370.804948 -8.856218)
				)
				(xy 370.805964 -8.857234)
				(arc
					(start 377.341384 -8.857234)
					(mid 377.458815 -8.833916)
					(end 377.5583 -8.767318)
				)
				(arc
					(start 377.60529 -8.720328)
					(mid 377.671633 -8.620895)
					(end 377.694952 -8.503666)
				)
				(arc
					(start 377.694952 -4.405122)
					(mid 377.671513 -4.287756)
					(end 377.605036 -4.188206)
				)
				(arc
					(start 377.558046 -4.141216)
					(mid 377.458566 -4.074585)
					(end 377.34113 -4.0513)
				)
				(arc
					(start 371.084094 -4.0513)
					(mid 370.966674 -4.074656)
					(end 370.867178 -4.141216)
				)
			)
		)
	)
	(zone
		(layer "In1.Cu")
		(hatch none 0.5)
		(connect_pads
			(clearance 0)
		)
		(min_thickness 0.25)
		(keepout
			(tracks not_allowed)
			(vias allowed)
			(pads allowed)
			(copperpour not_allowed)
			(footprints allowed)
		)
		(placement
			(enabled no)
			(sheetname "")
		)
		(fill
			(thermal_gap 0.5)
			(thermal_bridge_width 0.5)
			(island_removal_mode 0)
		)
		(polygon
			(pts
				(arc
					(start 167.351964 -100.248212)
					(mid 167.337085 -100.284133)
					(end 167.301164 -100.299012)
				)
				(arc
					(start 166.120064 -100.299012)
					(mid 166.084143 -100.284133)
					(end 166.069264 -100.248212)
				)
				(arc
					(start 166.069264 -99.241864)
					(mid 166.084143 -99.205943)
					(end 166.120064 -99.191064)
				)
				(arc
					(start 167.301164 -99.191064)
					(mid 167.337085 -99.205943)
					(end 167.351964 -99.241864)
				)
			)
		)
	)
	(zone
		(layer "In1.Cu")
		(hatch none 0.5)
		(connect_pads
			(clearance 0)
		)
		(min_thickness 0.25)
		(keepout
			(tracks not_allowed)
			(vias allowed)
			(pads allowed)
			(copperpour not_allowed)
			(footprints allowed)
		)
		(placement
			(enabled no)
			(sheetname "")
		)
		(fill
			(thermal_gap 0.5)
			(thermal_bridge_width 0.5)
			(island_removal_mode 0)
		)
		(polygon
			(pts
				(arc
					(start 326.099678 -29.205936)
					(mid 326.084799 -29.241857)
					(end 326.048878 -29.256736)
				)
				(arc
					(start 324.816978 -29.256736)
					(mid 324.781057 -29.241857)
					(end 324.766178 -29.205936)
				)
				(arc
					(start 324.766178 -28.174188)
					(mid 324.781057 -28.138267)
					(end 324.816978 -28.123388)
				)
				(arc
					(start 326.048878 -28.123388)
					(mid 326.084799 -28.138267)
					(end 326.099678 -28.174188)
				)
			)
		)
	)
	(zone
		(layer "In1.Cu")
		(hatch none 0.5)
		(connect_pads
			(clearance 0)
		)
		(min_thickness 0.25)
		(keepout
			(tracks not_allowed)
			(vias allowed)
			(pads allowed)
			(copperpour not_allowed)
			(footprints allowed)
		)
		(placement
			(enabled no)
			(sheetname "")
		)
		(fill
			(thermal_gap 0.5)
			(thermal_bridge_width 0.5)
			(island_removal_mode 0)
		)
		(polygon
			(pts
				(arc
					(start 56.398922 -363.529372)
					(mid 56.488725 -363.566569)
					(end 56.525922 -363.656372)
				)
				(arc
					(start 56.525922 -363.85754)
					(mid 56.488725 -363.947343)
					(end 56.398922 -363.98454)
				)
				(arc
					(start 56.144922 -363.98454)
					(mid 56.055119 -363.947343)
					(end 56.017922 -363.85754)
				)
				(arc
					(start 56.017922 -363.656372)
					(mid 56.055119 -363.566569)
					(end 56.144922 -363.529372)
				)
			)
		)
	)
	(zone
		(layer "In1.Cu")
		(hatch none 0.5)
		(connect_pads
			(clearance 0)
		)
		(min_thickness 0.25)
		(keepout
			(tracks not_allowed)
			(vias allowed)
			(pads allowed)
			(copperpour not_allowed)
			(footprints allowed)
		)
		(placement
			(enabled no)
			(sheetname "")
		)
		(fill
			(thermal_gap 0.5)
			(thermal_bridge_width 0.5)
			(island_removal_mode 0)
		)
		(polygon
			(pts
				(arc
					(start 184.147714 -118.631716)
					(mid 184.162593 -118.595795)
					(end 184.198514 -118.580916)
				)
				(arc
					(start 185.379614 -118.580916)
					(mid 185.415535 -118.595795)
					(end 185.430414 -118.631716)
				)
				(arc
					(start 185.430414 -119.638064)
					(mid 185.415535 -119.673985)
					(end 185.379614 -119.688864)
				)
				(arc
					(start 184.198514 -119.688864)
					(mid 184.162593 -119.673985)
					(end 184.147714 -119.638064)
				)
			)
		)
	)
	(zone
		(layer "In1.Cu")
		(hatch none 0.5)
		(connect_pads
			(clearance 0)
		)
		(min_thickness 0.25)
		(keepout
			(tracks not_allowed)
			(vias allowed)
			(pads allowed)
			(copperpour not_allowed)
			(footprints allowed)
		)
		(placement
			(enabled no)
			(sheetname "")
		)
		(fill
			(thermal_gap 0.5)
			(thermal_bridge_width 0.5)
			(island_removal_mode 0)
		)
		(polygon
			(pts
				(arc
					(start 131.99999 -29.205936)
					(mid 131.985111 -29.241857)
					(end 131.94919 -29.256736)
				)
				(arc
					(start 130.71729 -29.256736)
					(mid 130.681369 -29.241857)
					(end 130.66649 -29.205936)
				)
				(arc
					(start 130.66649 -28.174188)
					(mid 130.681369 -28.138267)
					(end 130.71729 -28.123388)
				)
				(arc
					(start 131.94919 -28.123388)
					(mid 131.985111 -28.138267)
					(end 131.99999 -28.174188)
				)
			)
		)
	)
	(zone
		(layer "In1.Cu")
		(hatch none 0.5)
		(connect_pads
			(clearance 0)
		)
		(min_thickness 0.25)
		(keepout
			(tracks not_allowed)
			(vias allowed)
			(pads allowed)
			(copperpour not_allowed)
			(footprints allowed)
		)
		(placement
			(enabled no)
			(sheetname "")
		)
		(fill
			(thermal_gap 0.5)
			(thermal_bridge_width 0.5)
			(island_removal_mode 0)
		)
		(polygon
			(pts
				(arc
					(start 292.603428 -349.679514)
					(mid 292.567507 -349.694393)
					(end 292.552628 -349.730314)
				)
				(arc
					(start 292.552628 -350.466914)
					(mid 292.567507 -350.502835)
					(end 292.603428 -350.517714)
				)
				(xy 292.847268 -350.517714) (xy 293.201598 -350.285304) (xy 293.557198 -350.517714)
				(arc
					(start 293.799768 -350.517714)
					(mid 293.835689 -350.502835)
					(end 293.850568 -350.466914)
				)
				(arc
					(start 293.850568 -349.730314)
					(mid 293.835689 -349.694393)
					(end 293.799768 -349.679514)
				)
				(xy 293.557198 -349.679514) (xy 293.200328 -349.911924) (xy 292.845998 -349.679514)
			)
		)
	)
	(zone
		(layer "In1.Cu")
		(hatch none 0.5)
		(connect_pads
			(clearance 0)
		)
		(min_thickness 0.25)
		(keepout
			(tracks not_allowed)
			(vias allowed)
			(pads allowed)
			(copperpour not_allowed)
			(footprints allowed)
		)
		(placement
			(enabled no)
			(sheetname "")
		)
		(fill
			(thermal_gap 0.5)
			(thermal_bridge_width 0.5)
			(island_removal_mode 0)
		)
		(polygon
			(pts
				(arc
					(start 389.676386 -349.679514)
					(mid 389.640465 -349.694393)
					(end 389.625586 -349.730314)
				)
				(arc
					(start 389.625586 -350.466914)
					(mid 389.640465 -350.502835)
					(end 389.676386 -350.517714)
				)
				(xy 389.920226 -350.517714) (xy 390.274556 -350.285304) (xy 390.630156 -350.517714)
				(arc
					(start 390.872726 -350.517714)
					(mid 390.908647 -350.502835)
					(end 390.923526 -350.466914)
				)
				(arc
					(start 390.923526 -349.730314)
					(mid 390.908647 -349.694393)
					(end 390.872726 -349.679514)
				)
				(xy 390.630156 -349.679514) (xy 390.273286 -349.911924) (xy 389.918956 -349.679514)
			)
		)
	)
	(zone
		(layer "In1.Cu")
		(hatch none 0.5)
		(connect_pads
			(clearance 0)
		)
		(min_thickness 0.25)
		(keepout
			(tracks not_allowed)
			(vias allowed)
			(pads allowed)
			(copperpour not_allowed)
			(footprints allowed)
		)
		(placement
			(enabled no)
			(sheetname "")
		)
		(fill
			(thermal_gap 0.5)
			(thermal_bridge_width 0.5)
			(island_removal_mode 0)
		)
		(polygon
			(pts
				(arc
					(start 161.53257 -132.162042)
					(mid 161.547449 -132.126121)
					(end 161.58337 -132.111242)
				)
				(arc
					(start 162.76447 -132.111242)
					(mid 162.800391 -132.126121)
					(end 162.81527 -132.162042)
				)
				(arc
					(start 162.81527 -133.16839)
					(mid 162.800391 -133.204311)
					(end 162.76447 -133.21919)
				)
				(arc
					(start 161.58337 -133.21919)
					(mid 161.547449 -133.204311)
					(end 161.53257 -133.16839)
				)
			)
		)
	)
	(zone
		(layer "In1.Cu")
		(hatch none 0.5)
		(connect_pads
			(clearance 0)
		)
		(min_thickness 0.25)
		(keepout
			(tracks not_allowed)
			(vias allowed)
			(pads allowed)
			(copperpour not_allowed)
			(footprints allowed)
		)
		(placement
			(enabled no)
			(sheetname "")
		)
		(fill
			(thermal_gap 0.5)
			(thermal_bridge_width 0.5)
			(island_removal_mode 0)
		)
		(polygon
			(pts
				(arc
					(start 340.31809 -355.825806)
					(mid 340.282169 -355.840685)
					(end 340.26729 -355.876606)
				)
				(arc
					(start 340.26729 -356.613206)
					(mid 340.282169 -356.649127)
					(end 340.31809 -356.664006)
				)
				(xy 340.56193 -356.664006) (xy 340.91626 -356.431596) (xy 341.27186 -356.664006)
				(arc
					(start 341.51443 -356.664006)
					(mid 341.550351 -356.649127)
					(end 341.56523 -356.613206)
				)
				(arc
					(start 341.56523 -355.876606)
					(mid 341.550351 -355.840685)
					(end 341.51443 -355.825806)
				)
				(xy 341.27186 -355.825806) (xy 340.91499 -356.058216) (xy 340.56066 -355.825806)
			)
		)
	)
	(zone
		(layer "In1.Cu")
		(hatch none 0.5)
		(connect_pads
			(clearance 0)
		)
		(min_thickness 0.25)
		(keepout
			(tracks not_allowed)
			(vias allowed)
			(pads allowed)
			(copperpour not_allowed)
			(footprints allowed)
		)
		(placement
			(enabled no)
			(sheetname "")
		)
		(fill
			(thermal_gap 0.5)
			(thermal_bridge_width 0.5)
			(island_removal_mode 0)
		)
		(polygon
			(pts
				(arc
					(start 384.32994 -31.77413)
					(mid 384.344819 -31.738209)
					(end 384.38074 -31.72333)
				)
				(arc
					(start 385.61264 -31.72333)
					(mid 385.648561 -31.738209)
					(end 385.66344 -31.77413)
				)
				(arc
					(start 385.66344 -32.805878)
					(mid 385.648561 -32.841799)
					(end 385.61264 -32.856678)
				)
				(arc
					(start 384.38074 -32.856678)
					(mid 384.344819 -32.841799)
					(end 384.32994 -32.805878)
				)
			)
		)
	)
	(zone
		(layer "In1.Cu")
		(hatch none 0.5)
		(connect_pads
			(clearance 0)
		)
		(min_thickness 0.25)
		(keepout
			(tracks not_allowed)
			(vias allowed)
			(pads allowed)
			(copperpour not_allowed)
			(footprints allowed)
		)
		(placement
			(enabled no)
			(sheetname "")
		)
		(fill
			(thermal_gap 0.5)
			(thermal_bridge_width 0.5)
			(island_removal_mode 0)
		)
		(polygon
			(pts
				(arc
					(start 73.867264 -130.8481)
					(mid 73.852385 -130.884021)
					(end 73.816464 -130.8989)
				)
				(arc
					(start 72.635364 -130.8989)
					(mid 72.599443 -130.884021)
					(end 72.584564 -130.8481)
				)
				(arc
					(start 72.584564 -129.841752)
					(mid 72.599443 -129.805831)
					(end 72.635364 -129.790952)
				)
				(arc
					(start 73.816464 -129.790952)
					(mid 73.852385 -129.805831)
					(end 73.867264 -129.841752)
				)
			)
		)
	)
	(zone
		(layer "In1.Cu")
		(hatch none 0.5)
		(connect_pads
			(clearance 0)
		)
		(min_thickness 0.25)
		(keepout
			(tracks not_allowed)
			(vias allowed)
			(pads allowed)
			(copperpour not_allowed)
			(footprints allowed)
		)
		(placement
			(enabled no)
			(sheetname "")
		)
		(fill
			(thermal_gap 0.5)
			(thermal_bridge_width 0.5)
			(island_removal_mode 0)
		)
		(polygon
			(pts
				(arc
					(start 283.276548 -343.533222)
					(mid 283.240627 -343.548101)
					(end 283.225748 -343.584022)
				)
				(arc
					(start 283.225748 -344.320622)
					(mid 283.240627 -344.356543)
					(end 283.276548 -344.371422)
				)
				(xy 283.520388 -344.371422) (xy 283.874718 -344.139012) (xy 284.230318 -344.371422)
				(arc
					(start 284.472888 -344.371422)
					(mid 284.508809 -344.356543)
					(end 284.523688 -344.320622)
				)
				(arc
					(start 284.523688 -343.584022)
					(mid 284.508809 -343.548101)
					(end 284.472888 -343.533222)
				)
				(xy 284.230318 -343.533222) (xy 283.873448 -343.765632) (xy 283.519118 -343.533222)
			)
		)
	)
	(zone
		(layer "In1.Cu")
		(hatch none 0.5)
		(connect_pads
			(clearance 0)
		)
		(min_thickness 0.25)
		(keepout
			(tracks not_allowed)
			(vias allowed)
			(pads allowed)
			(copperpour not_allowed)
			(footprints allowed)
		)
		(placement
			(enabled no)
			(sheetname "")
		)
		(fill
			(thermal_gap 0.5)
			(thermal_bridge_width 0.5)
			(island_removal_mode 0)
		)
		(polygon
			(pts
				(arc
					(start 127.241554 -355.825806)
					(mid 127.205633 -355.840685)
					(end 127.190754 -355.876606)
				)
				(arc
					(start 127.190754 -356.613206)
					(mid 127.205633 -356.649127)
					(end 127.241554 -356.664006)
				)
				(xy 127.485394 -356.664006) (xy 127.839724 -356.431596) (xy 128.195324 -356.664006)
				(arc
					(start 128.437894 -356.664006)
					(mid 128.473815 -356.649127)
					(end 128.488694 -356.613206)
				)
				(arc
					(start 128.488694 -355.876606)
					(mid 128.473815 -355.840685)
					(end 128.437894 -355.825806)
				)
				(xy 128.195324 -355.825806) (xy 127.838454 -356.058216) (xy 127.484124 -355.825806)
			)
		)
	)
	(zone
		(layer "In1.Cu")
		(hatch none 0.5)
		(connect_pads
			(clearance 0)
		)
		(min_thickness 0.25)
		(keepout
			(tracks not_allowed)
			(vias allowed)
			(pads allowed)
			(copperpour not_allowed)
			(footprints allowed)
		)
		(placement
			(enabled no)
			(sheetname "")
		)
		(fill
			(thermal_gap 0.5)
			(thermal_bridge_width 0.5)
			(island_removal_mode 0)
		)
		(polygon
			(pts
				(arc
					(start 127.241554 -349.679514)
					(mid 127.205633 -349.694393)
					(end 127.190754 -349.730314)
				)
				(arc
					(start 127.190754 -350.466914)
					(mid 127.205633 -350.502835)
					(end 127.241554 -350.517714)
				)
				(xy 127.485394 -350.517714) (xy 127.839724 -350.285304) (xy 128.195324 -350.517714)
				(arc
					(start 128.437894 -350.517714)
					(mid 128.473815 -350.502835)
					(end 128.488694 -350.466914)
				)
				(arc
					(start 128.488694 -349.730314)
					(mid 128.473815 -349.694393)
					(end 128.437894 -349.679514)
				)
				(xy 128.195324 -349.679514) (xy 127.838454 -349.911924) (xy 127.484124 -349.679514)
			)
		)
	)
	(zone
		(layer "In1.Cu")
		(hatch none 0.5)
		(connect_pads
			(clearance 0)
		)
		(min_thickness 0.25)
		(keepout
			(tracks not_allowed)
			(vias allowed)
			(pads allowed)
			(copperpour not_allowed)
			(footprints allowed)
		)
		(placement
			(enabled no)
			(sheetname "")
		)
		(fill
			(thermal_gap 0.5)
			(thermal_bridge_width 0.5)
			(island_removal_mode 0)
		)
		(polygon
			(pts
				(arc
					(start 40.929814 -355.825806)
					(mid 40.893893 -355.840685)
					(end 40.879014 -355.876606)
				)
				(arc
					(start 40.879014 -356.613206)
					(mid 40.893893 -356.649127)
					(end 40.929814 -356.664006)
				)
				(xy 41.173654 -356.664006) (xy 41.527984 -356.431596) (xy 41.883584 -356.664006)
				(arc
					(start 42.126154 -356.664006)
					(mid 42.162075 -356.649127)
					(end 42.176954 -356.613206)
				)
				(arc
					(start 42.176954 -355.876606)
					(mid 42.162075 -355.840685)
					(end 42.126154 -355.825806)
				)
				(xy 41.883584 -355.825806) (xy 41.526714 -356.058216) (xy 41.172384 -355.825806)
			)
		)
	)
	(zone
		(layer "In1.Cu")
		(hatch none 0.5)
		(connect_pads
			(clearance 0)
		)
		(min_thickness 0.25)
		(keepout
			(tracks not_allowed)
			(vias allowed)
			(pads allowed)
			(copperpour not_allowed)
			(footprints allowed)
		)
		(placement
			(enabled no)
			(sheetname "")
		)
		(fill
			(thermal_gap 0.5)
			(thermal_bridge_width 0.5)
			(island_removal_mode 0)
		)
		(polygon
			(pts
				(arc
					(start 157.999938 -31.006034)
					(mid 157.985059 -31.041955)
					(end 157.949138 -31.056834)
				)
				(arc
					(start 156.717238 -31.056834)
					(mid 156.681317 -31.041955)
					(end 156.666438 -31.006034)
				)
				(arc
					(start 156.666438 -29.974286)
					(mid 156.681317 -29.938365)
					(end 156.717238 -29.923486)
				)
				(arc
					(start 157.949138 -29.923486)
					(mid 157.985059 -29.938365)
					(end 157.999938 -29.974286)
				)
			)
		)
	)
	(zone
		(layer "In1.Cu")
		(hatch none 0.5)
		(connect_pads
			(clearance 0)
		)
		(min_thickness 0.25)
		(keepout
			(tracks not_allowed)
			(vias allowed)
			(pads allowed)
			(copperpour not_allowed)
			(footprints allowed)
		)
		(placement
			(enabled no)
			(sheetname "")
		)
		(fill
			(thermal_gap 0.5)
			(thermal_bridge_width 0.5)
			(island_removal_mode 0)
		)
		(polygon
			(pts
				(arc
					(start 154.961336 -103.94315)
					(mid 154.976215 -103.979071)
					(end 155.012136 -103.99395)
				)
				(arc
					(start 155.748736 -103.99395)
					(mid 155.784657 -103.979071)
					(end 155.799536 -103.94315)
				)
				(xy 155.799536 -103.69931) (xy 155.567126 -103.34498) (xy 155.799536 -102.98938)
				(arc
					(start 155.799536 -102.74681)
					(mid 155.784657 -102.710889)
					(end 155.748736 -102.69601)
				)
				(arc
					(start 155.012136 -102.69601)
					(mid 154.976215 -102.710889)
					(end 154.961336 -102.74681)
				)
				(xy 154.961336 -102.98938) (xy 155.193746 -103.34625) (xy 154.961336 -103.70058)
			)
		)
	)
	(zone
		(layer "In1.Cu")
		(hatch none 0.5)
		(connect_pads
			(clearance 0)
		)
		(min_thickness 0.25)
		(keepout
			(tracks not_allowed)
			(vias allowed)
			(pads allowed)
			(copperpour not_allowed)
			(footprints allowed)
		)
		(placement
			(enabled no)
			(sheetname "")
		)
		(fill
			(thermal_gap 0.5)
			(thermal_bridge_width 0.5)
			(island_removal_mode 0)
		)
		(polygon
			(pts
				(arc
					(start 275.573236 -32.879538)
					(mid 275.588115 -32.915459)
					(end 275.624036 -32.930338)
				)
				(arc
					(start 276.360636 -32.930338)
					(mid 276.396557 -32.915459)
					(end 276.411436 -32.879538)
				)
				(xy 276.411436 -32.635698) (xy 276.179026 -32.281368) (xy 276.411436 -31.925768)
				(arc
					(start 276.411436 -31.683198)
					(mid 276.396557 -31.647277)
					(end 276.360636 -31.632398)
				)
				(arc
					(start 275.624036 -31.632398)
					(mid 275.588115 -31.647277)
					(end 275.573236 -31.683198)
				)
				(xy 275.573236 -31.925768) (xy 275.805646 -32.282638) (xy 275.573236 -32.636968)
			)
		)
	)
	(zone
		(layer "In1.Cu")
		(hatch none 0.5)
		(connect_pads
			(clearance 0)
		)
		(min_thickness 0.25)
		(keepout
			(tracks not_allowed)
			(vias allowed)
			(pads allowed)
			(copperpour not_allowed)
			(footprints allowed)
		)
		(placement
			(enabled no)
			(sheetname "")
		)
		(fill
			(thermal_gap 0.5)
			(thermal_bridge_width 0.5)
			(island_removal_mode 0)
		)
		(polygon
			(pts
				(arc
					(start 327.88225 -355.825806)
					(mid 327.846329 -355.840685)
					(end 327.83145 -355.876606)
				)
				(arc
					(start 327.83145 -356.613206)
					(mid 327.846329 -356.649127)
					(end 327.88225 -356.664006)
				)
				(xy 328.12609 -356.664006) (xy 328.48042 -356.431596) (xy 328.83602 -356.664006)
				(arc
					(start 329.07859 -356.664006)
					(mid 329.114511 -356.649127)
					(end 329.12939 -356.613206)
				)
				(arc
					(start 329.12939 -355.876606)
					(mid 329.114511 -355.840685)
					(end 329.07859 -355.825806)
				)
				(xy 328.83602 -355.825806) (xy 328.47915 -356.058216) (xy 328.12482 -355.825806)
			)
		)
	)
	(zone
		(layer "In1.Cu")
		(hatch none 0.5)
		(connect_pads
			(clearance 0)
		)
		(min_thickness 0.25)
		(keepout
			(tracks not_allowed)
			(vias allowed)
			(pads allowed)
			(copperpour not_allowed)
			(footprints allowed)
		)
		(placement
			(enabled no)
			(sheetname "")
		)
		(fill
			(thermal_gap 0.5)
			(thermal_bridge_width 0.5)
			(island_removal_mode 0)
		)
		(polygon
			(pts
				(arc
					(start 61.206888 -343.533222)
					(mid 61.170967 -343.548101)
					(end 61.156088 -343.584022)
				)
				(arc
					(start 61.156088 -344.320622)
					(mid 61.170967 -344.356543)
					(end 61.206888 -344.371422)
				)
				(xy 61.450728 -344.371422) (xy 61.805058 -344.139012) (xy 62.160658 -344.371422)
				(arc
					(start 62.403228 -344.371422)
					(mid 62.439149 -344.356543)
					(end 62.454028 -344.320622)
				)
				(arc
					(start 62.454028 -343.584022)
					(mid 62.439149 -343.548101)
					(end 62.403228 -343.533222)
				)
				(xy 62.160658 -343.533222) (xy 61.803788 -343.765632) (xy 61.449458 -343.533222)
			)
		)
	)
	(zone
		(layer "In1.Cu")
		(hatch none 0.5)
		(connect_pads
			(clearance 0)
		)
		(min_thickness 0.25)
		(keepout
			(tracks not_allowed)
			(vias allowed)
			(pads allowed)
			(copperpour not_allowed)
			(footprints allowed)
		)
		(placement
			(enabled no)
			(sheetname "")
		)
		(fill
			(thermal_gap 0.5)
			(thermal_bridge_width 0.5)
			(island_removal_mode 0)
		)
		(polygon
			(pts
				(arc
					(start 248.099834 -27.405838)
					(mid 248.084955 -27.441759)
					(end 248.049034 -27.456638)
				)
				(arc
					(start 246.817134 -27.456638)
					(mid 246.781213 -27.441759)
					(end 246.766334 -27.405838)
				)
				(arc
					(start 246.766334 -26.37409)
					(mid 246.781213 -26.338169)
					(end 246.817134 -26.32329)
				)
				(arc
					(start 248.049034 -26.32329)
					(mid 248.084955 -26.338169)
					(end 248.099834 -26.37409)
				)
			)
		)
	)
	(zone
		(layer "In1.Cu")
		(hatch none 0.5)
		(connect_pads
			(clearance 0)
		)
		(min_thickness 0.25)
		(keepout
			(tracks not_allowed)
			(vias allowed)
			(pads allowed)
			(copperpour not_allowed)
			(footprints allowed)
		)
		(placement
			(enabled no)
			(sheetname "")
		)
		(fill
			(thermal_gap 0.5)
			(thermal_bridge_width 0.5)
			(island_removal_mode 0)
		)
		(polygon
			(pts
				(arc
					(start 427.900338 -119.724678)
					(mid 427.915217 -119.760599)
					(end 427.951138 -119.775478)
				)
				(arc
					(start 428.687738 -119.775478)
					(mid 428.723659 -119.760599)
					(end 428.738538 -119.724678)
				)
				(xy 428.738538 -119.480838) (xy 428.506128 -119.126508) (xy 428.738538 -118.770908)
				(arc
					(start 428.738538 -118.528338)
					(mid 428.723659 -118.492417)
					(end 428.687738 -118.477538)
				)
				(arc
					(start 427.951138 -118.477538)
					(mid 427.915217 -118.492417)
					(end 427.900338 -118.528338)
				)
				(xy 427.900338 -118.770908) (xy 428.132748 -119.127778) (xy 427.900338 -119.482108)
			)
		)
	)
	(zone
		(layer "In1.Cu")
		(hatch none 0.5)
		(connect_pads
			(clearance 0)
		)
		(min_thickness 0.25)
		(keepout
			(tracks not_allowed)
			(vias allowed)
			(pads allowed)
			(copperpour not_allowed)
			(footprints allowed)
		)
		(placement
			(enabled no)
			(sheetname "")
		)
		(fill
			(thermal_gap 0.5)
			(thermal_bridge_width 0.5)
			(island_removal_mode 0)
		)
		(polygon
			(pts
				(arc
					(start 273.949668 -343.533222)
					(mid 273.913747 -343.548101)
					(end 273.898868 -343.584022)
				)
				(arc
					(start 273.898868 -344.320622)
					(mid 273.913747 -344.356543)
					(end 273.949668 -344.371422)
				)
				(xy 274.193508 -344.371422) (xy 274.547838 -344.139012) (xy 274.903438 -344.371422)
				(arc
					(start 275.146008 -344.371422)
					(mid 275.181929 -344.356543)
					(end 275.196808 -344.320622)
				)
				(arc
					(start 275.196808 -343.584022)
					(mid 275.181929 -343.548101)
					(end 275.146008 -343.533222)
				)
				(xy 274.903438 -343.533222) (xy 274.546568 -343.765632) (xy 274.192238 -343.533222)
			)
		)
	)
	(zone
		(layer "In1.Cu")
		(hatch none 0.5)
		(connect_pads
			(clearance 0)
		)
		(min_thickness 0.25)
		(keepout
			(tracks not_allowed)
			(vias allowed)
			(pads allowed)
			(copperpour not_allowed)
			(footprints allowed)
		)
		(placement
			(enabled no)
			(sheetname "")
		)
		(fill
			(thermal_gap 0.5)
			(thermal_bridge_width 0.5)
			(island_removal_mode 0)
		)
		(polygon
			(pts
				(arc
					(start 273.949668 -355.825806)
					(mid 273.913747 -355.840685)
					(end 273.898868 -355.876606)
				)
				(arc
					(start 273.898868 -356.613206)
					(mid 273.913747 -356.649127)
					(end 273.949668 -356.664006)
				)
				(xy 274.193508 -356.664006) (xy 274.547838 -356.431596) (xy 274.903438 -356.664006)
				(arc
					(start 275.146008 -356.664006)
					(mid 275.181929 -356.649127)
					(end 275.196808 -356.613206)
				)
				(arc
					(start 275.196808 -355.876606)
					(mid 275.181929 -355.840685)
					(end 275.146008 -355.825806)
				)
				(xy 274.903438 -355.825806) (xy 274.546568 -356.058216) (xy 274.192238 -355.825806)
			)
		)
	)
	(zone
		(layer "In1.Cu")
		(hatch none 0.5)
		(connect_pads
			(clearance 0)
		)
		(min_thickness 0.25)
		(keepout
			(tracks not_allowed)
			(vias allowed)
			(pads allowed)
			(copperpour not_allowed)
			(footprints allowed)
		)
		(placement
			(enabled no)
			(sheetname "")
		)
		(fill
			(thermal_gap 0.5)
			(thermal_bridge_width 0.5)
			(island_removal_mode 0)
		)
		(polygon
			(pts
				(arc
					(start 139.677394 -343.533222)
					(mid 139.641473 -343.548101)
					(end 139.626594 -343.584022)
				)
				(arc
					(start 139.626594 -344.320622)
					(mid 139.641473 -344.356543)
					(end 139.677394 -344.371422)
				)
				(xy 139.921234 -344.371422) (xy 140.275564 -344.139012) (xy 140.631164 -344.371422)
				(arc
					(start 140.873734 -344.371422)
					(mid 140.909655 -344.356543)
					(end 140.924534 -344.320622)
				)
				(arc
					(start 140.924534 -343.584022)
					(mid 140.909655 -343.548101)
					(end 140.873734 -343.533222)
				)
				(xy 140.631164 -343.533222) (xy 140.274294 -343.765632) (xy 139.919964 -343.533222)
			)
		)
	)
	(zone
		(layer "In1.Cu")
		(hatch none 0.5)
		(connect_pads
			(clearance 0)
		)
		(min_thickness 0.25)
		(keepout
			(tracks not_allowed)
			(vias allowed)
			(pads allowed)
			(copperpour not_allowed)
			(footprints allowed)
		)
		(placement
			(enabled no)
			(sheetname "")
		)
		(fill
			(thermal_gap 0.5)
			(thermal_bridge_width 0.5)
			(island_removal_mode 0)
		)
		(polygon
			(pts
				(arc
					(start 79.600298 -130.93446)
					(mid 79.615177 -130.970381)
					(end 79.651098 -130.98526)
				)
				(arc
					(start 80.387698 -130.98526)
					(mid 80.423619 -130.970381)
					(end 80.438498 -130.93446)
				)
				(xy 80.438498 -130.69062) (xy 80.206088 -130.33629) (xy 80.438498 -129.98069)
				(arc
					(start 80.438498 -129.73812)
					(mid 80.423619 -129.702199)
					(end 80.387698 -129.68732)
				)
				(arc
					(start 79.651098 -129.68732)
					(mid 79.615177 -129.702199)
					(end 79.600298 -129.73812)
				)
				(xy 79.600298 -129.98069) (xy 79.832708 -130.33756) (xy 79.600298 -130.69189)
			)
		)
	)
	(zone
		(layer "In1.Cu")
		(hatch none 0.5)
		(connect_pads
			(clearance 0)
		)
		(min_thickness 0.25)
		(keepout
			(tracks not_allowed)
			(vias allowed)
			(pads allowed)
			(copperpour not_allowed)
			(footprints allowed)
		)
		(placement
			(enabled no)
			(sheetname "")
		)
		(fill
			(thermal_gap 0.5)
			(thermal_bridge_width 0.5)
			(island_removal_mode 0)
		)
		(polygon
			(pts
				(arc
					(start 395.894306 -343.533222)
					(mid 395.858385 -343.548101)
					(end 395.843506 -343.584022)
				)
				(arc
					(start 395.843506 -344.320622)
					(mid 395.858385 -344.356543)
					(end 395.894306 -344.371422)
				)
				(xy 396.138146 -344.371422) (xy 396.492476 -344.139012) (xy 396.848076 -344.371422)
				(arc
					(start 397.090646 -344.371422)
					(mid 397.126567 -344.356543)
					(end 397.141446 -344.320622)
				)
				(arc
					(start 397.141446 -343.584022)
					(mid 397.126567 -343.548101)
					(end 397.090646 -343.533222)
				)
				(xy 396.848076 -343.533222) (xy 396.491206 -343.765632) (xy 396.136876 -343.533222)
			)
		)
	)
	(zone
		(layer "In1.Cu")
		(hatch none 0.5)
		(connect_pads
			(clearance 0)
		)
		(min_thickness 0.25)
		(keepout
			(tracks not_allowed)
			(vias allowed)
			(pads allowed)
			(copperpour not_allowed)
			(footprints allowed)
		)
		(placement
			(enabled no)
			(sheetname "")
		)
		(fill
			(thermal_gap 0.5)
			(thermal_bridge_width 0.5)
			(island_removal_mode 0)
		)
		(polygon
			(pts
				(arc
					(start 277.632668 -108.241846)
					(mid 277.647547 -108.205925)
					(end 277.683468 -108.191046)
				)
				(arc
					(start 278.864568 -108.191046)
					(mid 278.900489 -108.205925)
					(end 278.915368 -108.241846)
				)
				(arc
					(start 278.915368 -109.248194)
					(mid 278.900489 -109.284115)
					(end 278.864568 -109.298994)
				)
				(arc
					(start 277.683468 -109.298994)
					(mid 277.647547 -109.284115)
					(end 277.632668 -109.248194)
				)
			)
		)
	)
	(zone
		(layer "In1.Cu")
		(hatch none 0.5)
		(connect_pads
			(clearance 0)
		)
		(min_thickness 0.25)
		(keepout
			(tracks not_allowed)
			(vias allowed)
			(pads allowed)
			(copperpour not_allowed)
			(footprints allowed)
		)
		(placement
			(enabled no)
			(sheetname "")
		)
		(fill
			(thermal_gap 0.5)
			(thermal_bridge_width 0.5)
			(island_removal_mode 0)
		)
		(polygon
			(pts
				(arc
					(start 248.099834 -34.605976)
					(mid 248.084955 -34.641897)
					(end 248.049034 -34.656776)
				)
				(arc
					(start 246.817134 -34.656776)
					(mid 246.781213 -34.641897)
					(end 246.766334 -34.605976)
				)
				(arc
					(start 246.766334 -33.574228)
					(mid 246.781213 -33.538307)
					(end 246.817134 -33.523428)
				)
				(arc
					(start 248.049034 -33.523428)
					(mid 248.084955 -33.538307)
					(end 248.099834 -33.574228)
				)
			)
		)
	)
	(zone
		(layer "In1.Cu")
		(hatch none 0.5)
		(connect_pads
			(clearance 0)
		)
		(min_thickness 0.25)
		(keepout
			(tracks not_allowed)
			(vias allowed)
			(pads allowed)
			(copperpour not_allowed)
			(footprints allowed)
		)
		(placement
			(enabled no)
			(sheetname "")
		)
		(fill
			(thermal_gap 0.5)
			(thermal_bridge_width 0.5)
			(island_removal_mode 0)
		)
		(polygon
			(pts
				(arc
					(start 31.602934 -343.533222)
					(mid 31.567013 -343.548101)
					(end 31.552134 -343.584022)
				)
				(arc
					(start 31.552134 -344.320622)
					(mid 31.567013 -344.356543)
					(end 31.602934 -344.371422)
				)
				(xy 31.846774 -344.371422) (xy 32.201104 -344.139012) (xy 32.556704 -344.371422)
				(arc
					(start 32.799274 -344.371422)
					(mid 32.835195 -344.356543)
					(end 32.850074 -344.320622)
				)
				(arc
					(start 32.850074 -343.584022)
					(mid 32.835195 -343.548101)
					(end 32.799274 -343.533222)
				)
				(xy 32.556704 -343.533222) (xy 32.199834 -343.765632) (xy 31.845504 -343.533222)
			)
		)
	)
	(zone
		(layer "In1.Cu")
		(hatch none 0.5)
		(connect_pads
			(clearance 0)
		)
		(min_thickness 0.25)
		(keepout
			(tracks not_allowed)
			(vias allowed)
			(pads allowed)
			(copperpour not_allowed)
			(footprints allowed)
		)
		(placement
			(enabled no)
			(sheetname "")
		)
		(fill
			(thermal_gap 0.5)
			(thermal_bridge_width 0.5)
			(island_removal_mode 0)
		)
		(polygon
			(pts
				(arc
					(start 239.848898 -83.722718)
					(mid 239.938701 -83.759915)
					(end 239.975898 -83.849718)
				)
				(arc
					(start 239.975898 -84.052918)
					(mid 239.938701 -84.142721)
					(end 239.848898 -84.179918)
				)
				(arc
					(start 239.594898 -84.179918)
					(mid 239.505095 -84.142721)
					(end 239.467898 -84.052918)
				)
				(arc
					(start 239.467898 -83.849718)
					(mid 239.505095 -83.759915)
					(end 239.594898 -83.722718)
				)
			)
		)
	)
	(zone
		(layer "In1.Cu")
		(hatch none 0.5)
		(connect_pads
			(clearance 0)
		)
		(min_thickness 0.25)
		(keepout
			(tracks not_allowed)
			(vias allowed)
			(pads allowed)
			(copperpour not_allowed)
			(footprints allowed)
		)
		(placement
			(enabled no)
			(sheetname "")
		)
		(fill
			(thermal_gap 0.5)
			(thermal_bridge_width 0.5)
			(island_removal_mode 0)
		)
		(polygon
			(pts
				(arc
					(start 45.432726 -122.752104)
					(mid 45.447605 -122.716183)
					(end 45.483526 -122.701304)
				)
				(arc
					(start 46.664626 -122.701304)
					(mid 46.700547 -122.716183)
					(end 46.715426 -122.752104)
				)
				(arc
					(start 46.715426 -123.758452)
					(mid 46.700547 -123.794373)
					(end 46.664626 -123.809252)
				)
				(arc
					(start 45.483526 -123.809252)
					(mid 45.447605 -123.794373)
					(end 45.432726 -123.758452)
				)
			)
		)
	)
	(zone
		(layer "In1.Cu")
		(hatch none 0.5)
		(connect_pads
			(clearance 0)
		)
		(min_thickness 0.25)
		(keepout
			(tracks not_allowed)
			(vias allowed)
			(pads allowed)
			(copperpour not_allowed)
			(footprints allowed)
		)
		(placement
			(enabled no)
			(sheetname "")
		)
		(fill
			(thermal_gap 0.5)
			(thermal_bridge_width 0.5)
			(island_removal_mode 0)
		)
		(polygon
			(pts
				(arc
					(start 447.797682 -209.191606)
					(mid 447.812561 -209.155685)
					(end 447.848482 -209.140806)
				)
				(arc
					(start 448.255136 -209.140806)
					(mid 448.291057 -209.155685)
					(end 448.305936 -209.191606)
				)
				(arc
					(start 448.305936 -209.593942)
					(mid 448.291057 -209.629863)
					(end 448.255136 -209.644742)
				)
				(arc
					(start 447.848482 -209.644742)
					(mid 447.812561 -209.629863)
					(end 447.797682 -209.593942)
				)
			)
		)
	)
	(zone
		(layer "In1.Cu")
		(hatch none 0.5)
		(connect_pads
			(clearance 0)
		)
		(min_thickness 0.25)
		(keepout
			(tracks not_allowed)
			(vias allowed)
			(pads allowed)
			(copperpour not_allowed)
			(footprints allowed)
		)
		(placement
			(enabled no)
			(sheetname "")
		)
		(fill
			(thermal_gap 0.5)
			(thermal_bridge_width 0.5)
			(island_removal_mode 0)
		)
		(polygon
			(pts
				(arc
					(start 37.820854 -349.679514)
					(mid 37.784933 -349.694393)
					(end 37.770054 -349.730314)
				)
				(arc
					(start 37.770054 -350.466914)
					(mid 37.784933 -350.502835)
					(end 37.820854 -350.517714)
				)
				(xy 38.064694 -350.517714) (xy 38.419024 -350.285304) (xy 38.774624 -350.517714)
				(arc
					(start 39.017194 -350.517714)
					(mid 39.053115 -350.502835)
					(end 39.067994 -350.466914)
				)
				(arc
					(start 39.067994 -349.730314)
					(mid 39.053115 -349.694393)
					(end 39.017194 -349.679514)
				)
				(xy 38.774624 -349.679514) (xy 38.417754 -349.911924) (xy 38.063424 -349.679514)
			)
		)
	)
	(zone
		(layer "In1.Cu")
		(hatch none 0.5)
		(connect_pads
			(clearance 0)
		)
		(min_thickness 0.25)
		(keepout
			(tracks not_allowed)
			(vias allowed)
			(pads allowed)
			(copperpour not_allowed)
			(footprints allowed)
		)
		(placement
			(enabled no)
			(sheetname "")
		)
		(fill
			(thermal_gap 0.5)
			(thermal_bridge_width 0.5)
			(island_removal_mode 0)
		)
		(polygon
			(pts
				(arc
					(start 88.029796 -31.77413)
					(mid 88.044675 -31.738209)
					(end 88.080596 -31.72333)
				)
				(arc
					(start 89.312496 -31.72333)
					(mid 89.348417 -31.738209)
					(end 89.363296 -31.77413)
				)
				(arc
					(start 89.363296 -32.805878)
					(mid 89.348417 -32.841799)
					(end 89.312496 -32.856678)
				)
				(arc
					(start 88.080596 -32.856678)
					(mid 88.044675 -32.841799)
					(end 88.029796 -32.805878)
				)
			)
		)
	)
	(zone
		(layer "In1.Cu")
		(hatch none 0.5)
		(connect_pads
			(clearance 0)
		)
		(min_thickness 0.25)
		(keepout
			(tracks not_allowed)
			(vias allowed)
			(pads allowed)
			(copperpour not_allowed)
			(footprints allowed)
		)
		(placement
			(enabled no)
			(sheetname "")
		)
		(fill
			(thermal_gap 0.5)
			(thermal_bridge_width 0.5)
			(island_removal_mode 0)
		)
		(polygon
			(pts
				(arc
					(start 314.442348 -125.131068)
					(mid 314.457227 -125.166989)
					(end 314.493148 -125.181868)
				)
				(arc
					(start 315.229748 -125.181868)
					(mid 315.265669 -125.166989)
					(end 315.280548 -125.131068)
				)
				(xy 315.280548 -124.887228) (xy 315.048138 -124.532898) (xy 315.280548 -124.177298)
				(arc
					(start 315.280548 -123.934728)
					(mid 315.265669 -123.898807)
					(end 315.229748 -123.883928)
				)
				(arc
					(start 314.493148 -123.883928)
					(mid 314.457227 -123.898807)
					(end 314.442348 -123.934728)
				)
				(xy 314.442348 -124.177298) (xy 314.674758 -124.534168) (xy 314.442348 -124.888498)
			)
		)
	)
	(zone
		(layer "In1.Cu")
		(hatch none 0.5)
		(connect_pads
			(clearance 0)
		)
		(min_thickness 0.25)
		(keepout
			(tracks not_allowed)
			(vias allowed)
			(pads allowed)
			(copperpour not_allowed)
			(footprints allowed)
		)
		(placement
			(enabled no)
			(sheetname "")
		)
		(fill
			(thermal_gap 0.5)
			(thermal_bridge_width 0.5)
			(island_removal_mode 0)
		)
		(polygon
			(pts
				(arc
					(start 152.129998 -31.77413)
					(mid 152.144877 -31.738209)
					(end 152.180798 -31.72333)
				)
				(arc
					(start 153.412698 -31.72333)
					(mid 153.448619 -31.738209)
					(end 153.463498 -31.77413)
				)
				(arc
					(start 153.463498 -32.805878)
					(mid 153.448619 -32.841799)
					(end 153.412698 -32.856678)
				)
				(arc
					(start 152.180798 -32.856678)
					(mid 152.144877 -32.841799)
					(end 152.129998 -32.805878)
				)
			)
		)
	)
	(zone
		(layer "In1.Cu")
		(hatch none 0.5)
		(connect_pads
			(clearance 0)
		)
		(min_thickness 0.25)
		(keepout
			(tracks not_allowed)
			(vias allowed)
			(pads allowed)
			(copperpour not_allowed)
			(footprints allowed)
		)
		(placement
			(enabled no)
			(sheetname "")
		)
		(fill
			(thermal_gap 0.5)
			(thermal_bridge_width 0.5)
			(island_removal_mode 0)
		)
		(polygon
			(pts
				(arc
					(start 306.067206 -143.55826)
					(mid 306.052327 -143.594181)
					(end 306.016406 -143.60906)
				)
				(arc
					(start 304.835306 -143.60906)
					(mid 304.799385 -143.594181)
					(end 304.784506 -143.55826)
				)
				(arc
					(start 304.784506 -142.551912)
					(mid 304.799385 -142.515991)
					(end 304.835306 -142.501112)
				)
				(arc
					(start 306.016406 -142.501112)
					(mid 306.052327 -142.515991)
					(end 306.067206 -142.551912)
				)
			)
		)
	)
	(zone
		(layer "In1.Cu")
		(hatch none 0.5)
		(connect_pads
			(clearance 0)
		)
		(min_thickness 0.25)
		(keepout
			(tracks not_allowed)
			(vias allowed)
			(pads allowed)
			(copperpour not_allowed)
			(footprints allowed)
		)
		(placement
			(enabled no)
			(sheetname "")
		)
		(fill
			(thermal_gap 0.5)
			(thermal_bridge_width 0.5)
			(island_removal_mode 0)
		)
		(polygon
			(pts
				(arc
					(start 300.247812 -153.351992)
					(mid 300.262691 -153.316071)
					(end 300.298612 -153.301192)
				)
				(arc
					(start 301.479712 -153.301192)
					(mid 301.515633 -153.316071)
					(end 301.530512 -153.351992)
				)
				(arc
					(start 301.530512 -154.35834)
					(mid 301.515633 -154.394261)
					(end 301.479712 -154.40914)
				)
				(arc
					(start 300.298612 -154.40914)
					(mid 300.262691 -154.394261)
					(end 300.247812 -154.35834)
				)
			)
		)
	)
	(zone
		(layer "In1.Cu")
		(hatch none 0.5)
		(connect_pads
			(clearance 0)
		)
		(min_thickness 0.25)
		(keepout
			(tracks not_allowed)
			(vias allowed)
			(pads allowed)
			(copperpour not_allowed)
			(footprints allowed)
		)
		(placement
			(enabled no)
			(sheetname "")
		)
		(fill
			(thermal_gap 0.5)
			(thermal_bridge_width 0.5)
			(island_removal_mode 0)
		)
		(polygon
			(pts
				(arc
					(start 390.19988 -34.605976)
					(mid 390.185001 -34.641897)
					(end 390.14908 -34.656776)
				)
				(arc
					(start 388.91718 -34.656776)
					(mid 388.881259 -34.641897)
					(end 388.86638 -34.605976)
				)
				(arc
					(start 388.86638 -33.574228)
					(mid 388.881259 -33.538307)
					(end 388.91718 -33.523428)
				)
				(arc
					(start 390.14908 -33.523428)
					(mid 390.185001 -33.538307)
					(end 390.19988 -33.574228)
				)
			)
		)
	)
	(zone
		(layer "In1.Cu")
		(hatch none 0.5)
		(connect_pads
			(clearance 0)
		)
		(min_thickness 0.25)
		(keepout
			(tracks not_allowed)
			(vias allowed)
			(pads allowed)
			(copperpour not_allowed)
			(footprints allowed)
		)
		(placement
			(enabled no)
			(sheetname "")
		)
		(fill
			(thermal_gap 0.5)
			(thermal_bridge_width 0.5)
			(island_removal_mode 0)
		)
		(polygon
			(pts
				(arc
					(start 161.53257 -99.241864)
					(mid 161.547449 -99.205943)
					(end 161.58337 -99.191064)
				)
				(arc
					(start 162.76447 -99.191064)
					(mid 162.800391 -99.205943)
					(end 162.81527 -99.241864)
				)
				(arc
					(start 162.81527 -100.248212)
					(mid 162.800391 -100.284133)
					(end 162.76447 -100.299012)
				)
				(arc
					(start 161.58337 -100.299012)
					(mid 161.547449 -100.284133)
					(end 161.53257 -100.248212)
				)
			)
		)
	)
	(zone
		(layer "In1.Cu")
		(hatch none 0.5)
		(connect_pads
			(clearance 0)
		)
		(min_thickness 0.25)
		(keepout
			(tracks not_allowed)
			(vias allowed)
			(pads allowed)
			(copperpour not_allowed)
			(footprints allowed)
		)
		(placement
			(enabled no)
			(sheetname "")
		)
		(fill
			(thermal_gap 0.5)
			(thermal_bridge_width 0.5)
			(island_removal_mode 0)
		)
		(polygon
			(pts
				(arc
					(start 51.25212 -125.558296)
					(mid 51.237241 -125.594217)
					(end 51.20132 -125.609096)
				)
				(arc
					(start 50.02022 -125.609096)
					(mid 49.984299 -125.594217)
					(end 49.96942 -125.558296)
				)
				(arc
					(start 49.96942 -124.551948)
					(mid 49.984299 -124.516027)
					(end 50.02022 -124.501148)
				)
				(arc
					(start 51.20132 -124.501148)
					(mid 51.237241 -124.516027)
					(end 51.25212 -124.551948)
				)
			)
		)
	)
	(zone
		(layer "In1.Cu")
		(hatch none 0.5)
		(connect_pads
			(clearance 0)
		)
		(min_thickness 0.25)
		(keepout
			(tracks not_allowed)
			(vias allowed)
			(pads allowed)
			(copperpour not_allowed)
			(footprints allowed)
		)
		(placement
			(enabled no)
			(sheetname "")
		)
		(fill
			(thermal_gap 0.5)
			(thermal_bridge_width 0.5)
			(island_removal_mode 0)
		)
		(polygon
			(pts
				(arc
					(start 161.53257 -130.361944)
					(mid 161.547449 -130.326023)
					(end 161.58337 -130.311144)
				)
				(arc
					(start 162.76447 -130.311144)
					(mid 162.800391 -130.326023)
					(end 162.81527 -130.361944)
				)
				(arc
					(start 162.81527 -131.368292)
					(mid 162.800391 -131.404213)
					(end 162.76447 -131.419092)
				)
				(arc
					(start 161.58337 -131.419092)
					(mid 161.547449 -131.404213)
					(end 161.53257 -131.368292)
				)
			)
		)
	)
	(zone
		(layer "In1.Cu")
		(hatch none 0.5)
		(connect_pads
			(clearance 0)
		)
		(min_thickness 0.25)
		(keepout
			(tracks not_allowed)
			(vias allowed)
			(pads allowed)
			(copperpour not_allowed)
			(footprints allowed)
		)
		(placement
			(enabled no)
			(sheetname "")
		)
		(fill
			(thermal_gap 0.5)
			(thermal_bridge_width 0.5)
			(island_removal_mode 0)
		)
		(polygon
			(pts
				(arc
					(start 36.219384 -131.463288)
					(mid 36.234263 -131.499209)
					(end 36.270184 -131.514088)
				)
				(arc
					(start 37.006784 -131.514088)
					(mid 37.042705 -131.499209)
					(end 37.057584 -131.463288)
				)
				(xy 37.057584 -131.219448) (xy 36.825174 -130.865118) (xy 37.057584 -130.509518)
				(arc
					(start 37.057584 -130.266948)
					(mid 37.042705 -130.231027)
					(end 37.006784 -130.216148)
				)
				(arc
					(start 36.270184 -130.216148)
					(mid 36.234263 -130.231027)
					(end 36.219384 -130.266948)
				)
				(xy 36.219384 -130.509518) (xy 36.451794 -130.866388) (xy 36.219384 -131.220718)
			)
		)
	)
	(zone
		(layer "In1.Cu")
		(hatch none 0.5)
		(connect_pads
			(clearance 0)
		)
		(min_thickness 0.25)
		(keepout
			(tracks not_allowed)
			(vias allowed)
			(pads allowed)
			(copperpour not_allowed)
			(footprints allowed)
		)
		(placement
			(enabled no)
			(sheetname "")
		)
		(fill
			(thermal_gap 0.5)
			(thermal_bridge_width 0.5)
			(island_removal_mode 0)
		)
		(polygon
			(pts
				(arc
					(start 79.600298 -154.4447)
					(mid 79.615177 -154.480621)
					(end 79.651098 -154.4955)
				)
				(arc
					(start 80.387698 -154.4955)
					(mid 80.423619 -154.480621)
					(end 80.438498 -154.4447)
				)
				(xy 80.438498 -154.20086) (xy 80.206088 -153.84653) (xy 80.438498 -153.49093)
				(arc
					(start 80.438498 -153.24836)
					(mid 80.423619 -153.212439)
					(end 80.387698 -153.19756)
				)
				(arc
					(start 79.651098 -153.19756)
					(mid 79.615177 -153.212439)
					(end 79.600298 -153.24836)
				)
				(xy 79.600298 -153.49093) (xy 79.832708 -153.8478) (xy 79.600298 -154.20213)
			)
		)
	)
	(zone
		(layer "In1.Cu")
		(hatch none 0.5)
		(connect_pads
			(clearance 0)
		)
		(min_thickness 0.25)
		(keepout
			(tracks not_allowed)
			(vias allowed)
			(pads allowed)
			(copperpour not_allowed)
			(footprints allowed)
		)
		(placement
			(enabled no)
			(sheetname "")
		)
		(fill
			(thermal_gap 0.5)
			(thermal_bridge_width 0.5)
			(island_removal_mode 0)
		)
		(polygon
			(pts
				(arc
					(start 233.642408 -81.991708)
					(mid 233.679605 -81.901905)
					(end 233.769408 -81.864708)
				)
				(arc
					(start 233.972608 -81.864708)
					(mid 234.062411 -81.901905)
					(end 234.099608 -81.991708)
				)
				(arc
					(start 234.099608 -82.245708)
					(mid 234.062411 -82.335511)
					(end 233.972608 -82.372708)
				)
				(arc
					(start 233.769408 -82.372708)
					(mid 233.679605 -82.335511)
					(end 233.642408 -82.245708)
				)
			)
		)
	)
	(zone
		(layer "In1.Cu")
		(hatch none 0.5)
		(connect_pads
			(clearance 0)
		)
		(min_thickness 0.25)
		(keepout
			(tracks not_allowed)
			(vias allowed)
			(pads allowed)
			(copperpour not_allowed)
			(footprints allowed)
		)
		(placement
			(enabled no)
			(sheetname "")
		)
		(fill
			(thermal_gap 0.5)
			(thermal_bridge_width 0.5)
			(island_removal_mode 0)
		)
		(polygon
			(pts
				(arc
					(start 274.099782 -32.805878)
					(mid 274.084903 -32.841799)
					(end 274.048982 -32.856678)
				)
				(arc
					(start 272.817082 -32.856678)
					(mid 272.781161 -32.841799)
					(end 272.766282 -32.805878)
				)
				(arc
					(start 272.766282 -31.77413)
					(mid 272.781161 -31.738209)
					(end 272.817082 -31.72333)
				)
				(arc
					(start 274.048982 -31.72333)
					(mid 274.084903 -31.738209)
					(end 274.099782 -31.77413)
				)
			)
		)
	)
	(zone
		(layer "In1.Cu")
		(hatch none 0.5)
		(connect_pads
			(clearance 0)
		)
		(min_thickness 0.25)
		(keepout
			(tracks not_allowed)
			(vias allowed)
			(pads allowed)
			(copperpour not_allowed)
			(footprints allowed)
		)
		(placement
			(enabled no)
			(sheetname "")
		)
		(fill
			(thermal_gap 0.5)
			(thermal_bridge_width 0.5)
			(island_removal_mode 0)
		)
		(polygon
			(pts
				(arc
					(start 289.494468 -355.825806)
					(mid 289.458547 -355.840685)
					(end 289.443668 -355.876606)
				)
				(arc
					(start 289.443668 -356.613206)
					(mid 289.458547 -356.649127)
					(end 289.494468 -356.664006)
				)
				(xy 289.738308 -356.664006) (xy 290.092638 -356.431596) (xy 290.448238 -356.664006)
				(arc
					(start 290.690808 -356.664006)
					(mid 290.726729 -356.649127)
					(end 290.741608 -356.613206)
				)
				(arc
					(start 290.741608 -355.876606)
					(mid 290.726729 -355.840685)
					(end 290.690808 -355.825806)
				)
				(xy 290.448238 -355.825806) (xy 290.091368 -356.058216) (xy 289.737038 -355.825806)
			)
		)
	)
	(zone
		(layer "In1.Cu")
		(hatch none 0.5)
		(connect_pads
			(clearance 0)
		)
		(min_thickness 0.25)
		(keepout
			(tracks not_allowed)
			(vias allowed)
			(pads allowed)
			(copperpour not_allowed)
			(footprints allowed)
		)
		(placement
			(enabled no)
			(sheetname "")
		)
		(fill
			(thermal_gap 0.5)
			(thermal_bridge_width 0.5)
			(island_removal_mode 0)
		)
		(polygon
			(pts
				(arc
					(start 430.542446 -145.451068)
					(mid 430.557325 -145.486989)
					(end 430.593246 -145.501868)
				)
				(arc
					(start 431.329846 -145.501868)
					(mid 431.365767 -145.486989)
					(end 431.380646 -145.451068)
				)
				(xy 431.380646 -145.207228) (xy 431.148236 -144.852898) (xy 431.380646 -144.497298)
				(arc
					(start 431.380646 -144.254728)
					(mid 431.365767 -144.218807)
					(end 431.329846 -144.203928)
				)
				(arc
					(start 430.593246 -144.203928)
					(mid 430.557325 -144.218807)
					(end 430.542446 -144.254728)
				)
				(xy 430.542446 -144.497298) (xy 430.774856 -144.854168) (xy 430.542446 -145.208498)
			)
		)
	)
	(zone
		(layer "In1.Cu")
		(hatch none 0.5)
		(connect_pads
			(clearance 0)
		)
		(min_thickness 0.25)
		(keepout
			(tracks not_allowed)
			(vias allowed)
			(pads allowed)
			(copperpour not_allowed)
			(footprints allowed)
		)
		(placement
			(enabled no)
			(sheetname "")
		)
		(fill
			(thermal_gap 0.5)
			(thermal_bridge_width 0.5)
			(island_removal_mode 0)
		)
		(polygon
			(pts
				(arc
					(start 416.34791 -155.151836)
					(mid 416.362789 -155.115915)
					(end 416.39871 -155.101036)
				)
				(arc
					(start 417.57981 -155.101036)
					(mid 417.615731 -155.115915)
					(end 417.63061 -155.151836)
				)
				(arc
					(start 417.63061 -156.158184)
					(mid 417.615731 -156.194105)
					(end 417.57981 -156.208984)
				)
				(arc
					(start 416.39871 -156.208984)
					(mid 416.362789 -156.194105)
					(end 416.34791 -156.158184)
				)
			)
		)
	)
	(zone
		(layer "In1.Cu")
		(hatch none 0.5)
		(connect_pads
			(clearance 0)
		)
		(min_thickness 0.25)
		(keepout
			(tracks not_allowed)
			(vias allowed)
			(pads allowed)
			(copperpour not_allowed)
			(footprints allowed)
		)
		(placement
			(enabled no)
			(sheetname "")
		)
		(fill
			(thermal_gap 0.5)
			(thermal_bridge_width 0.5)
			(island_removal_mode 0)
		)
		(polygon
			(pts
				(arc
					(start 374.131586 -349.679514)
					(mid 374.095665 -349.694393)
					(end 374.080786 -349.730314)
				)
				(arc
					(start 374.080786 -350.466914)
					(mid 374.095665 -350.502835)
					(end 374.131586 -350.517714)
				)
				(xy 374.375426 -350.517714) (xy 374.729756 -350.285304) (xy 375.085356 -350.517714)
				(arc
					(start 375.327926 -350.517714)
					(mid 375.363847 -350.502835)
					(end 375.378726 -350.466914)
				)
				(arc
					(start 375.378726 -349.730314)
					(mid 375.363847 -349.694393)
					(end 375.327926 -349.679514)
				)
				(xy 375.085356 -349.679514) (xy 374.728486 -349.911924) (xy 374.374156 -349.679514)
			)
		)
	)
	(zone
		(layer "In1.Cu")
		(hatch none 0.5)
		(connect_pads
			(clearance 0)
		)
		(min_thickness 0.25)
		(keepout
			(tracks not_allowed)
			(vias allowed)
			(pads allowed)
			(copperpour not_allowed)
			(footprints allowed)
		)
		(placement
			(enabled no)
			(sheetname "")
		)
		(fill
			(thermal_gap 0.5)
			(thermal_bridge_width 0.5)
			(island_removal_mode 0)
		)
		(polygon
			(pts
				(arc
					(start 384.519424 -120.253252)
					(mid 384.534303 -120.289173)
					(end 384.570224 -120.304052)
				)
				(arc
					(start 385.306824 -120.304052)
					(mid 385.342745 -120.289173)
					(end 385.357624 -120.253252)
				)
				(xy 385.357624 -120.009412) (xy 385.125214 -119.655082) (xy 385.357624 -119.299482)
				(arc
					(start 385.357624 -119.056912)
					(mid 385.342745 -119.020991)
					(end 385.306824 -119.006112)
				)
				(arc
					(start 384.570224 -119.006112)
					(mid 384.534303 -119.020991)
					(end 384.519424 -119.056912)
				)
				(xy 384.519424 -119.299482) (xy 384.751834 -119.656352) (xy 384.519424 -120.010682)
			)
		)
	)
	(zone
		(layer "In1.Cu")
		(hatch none 0.5)
		(connect_pads
			(clearance 0)
		)
		(min_thickness 0.25)
		(keepout
			(tracks not_allowed)
			(vias allowed)
			(pads allowed)
			(copperpour not_allowed)
			(footprints allowed)
		)
		(placement
			(enabled no)
			(sheetname "")
		)
		(fill
			(thermal_gap 0.5)
			(thermal_bridge_width 0.5)
			(island_removal_mode 0)
		)
		(polygon
			(pts
				(arc
					(start 22.276054 -349.679514)
					(mid 22.240133 -349.694393)
					(end 22.225254 -349.730314)
				)
				(arc
					(start 22.225254 -350.466914)
					(mid 22.240133 -350.502835)
					(end 22.276054 -350.517714)
				)
				(xy 22.519894 -350.517714) (xy 22.874224 -350.285304) (xy 23.229824 -350.517714)
				(arc
					(start 23.472394 -350.517714)
					(mid 23.508315 -350.502835)
					(end 23.523194 -350.466914)
				)
				(arc
					(start 23.523194 -349.730314)
					(mid 23.508315 -349.694393)
					(end 23.472394 -349.679514)
				)
				(xy 23.229824 -349.679514) (xy 22.872954 -349.911924) (xy 22.518624 -349.679514)
			)
		)
	)
	(zone
		(layer "In1.Cu")
		(hatch none 0.5)
		(connect_pads
			(clearance 0)
		)
		(min_thickness 0.25)
		(keepout
			(tracks not_allowed)
			(vias allowed)
			(pads allowed)
			(copperpour not_allowed)
			(footprints allowed)
		)
		(placement
			(enabled no)
			(sheetname "")
		)
		(fill
			(thermal_gap 0.5)
			(thermal_bridge_width 0.5)
			(island_removal_mode 0)
		)
		(polygon
			(pts
				(arc
					(start 152.319228 -131.463288)
					(mid 152.334107 -131.499209)
					(end 152.370028 -131.514088)
				)
				(arc
					(start 153.106628 -131.514088)
					(mid 153.142549 -131.499209)
					(end 153.157428 -131.463288)
				)
				(xy 153.157428 -131.219448) (xy 152.925018 -130.865118) (xy 153.157428 -130.509518)
				(arc
					(start 153.157428 -130.266948)
					(mid 153.142549 -130.231027)
					(end 153.106628 -130.216148)
				)
				(arc
					(start 152.370028 -130.216148)
					(mid 152.334107 -130.231027)
					(end 152.319228 -130.266948)
				)
				(xy 152.319228 -130.509518) (xy 152.551638 -130.866388) (xy 152.319228 -131.220718)
			)
		)
	)
	(zone
		(layer "In1.Cu")
		(hatch none 0.5)
		(connect_pads
			(clearance 0)
		)
		(min_thickness 0.25)
		(keepout
			(tracks not_allowed)
			(vias allowed)
			(pads allowed)
			(copperpour not_allowed)
			(footprints allowed)
		)
		(placement
			(enabled no)
			(sheetname "")
		)
		(fill
			(thermal_gap 0.5)
			(thermal_bridge_width 0.5)
			(island_removal_mode 0)
		)
		(polygon
			(pts
				(arc
					(start 283.452062 -125.558296)
					(mid 283.437183 -125.594217)
					(end 283.401262 -125.609096)
				)
				(arc
					(start 282.220162 -125.609096)
					(mid 282.184241 -125.594217)
					(end 282.169362 -125.558296)
				)
				(arc
					(start 282.169362 -124.551948)
					(mid 282.184241 -124.516027)
					(end 282.220162 -124.501148)
				)
				(arc
					(start 283.401262 -124.501148)
					(mid 283.437183 -124.516027)
					(end 283.452062 -124.551948)
				)
			)
		)
	)
	(zone
		(layer "In1.Cu")
		(hatch none 0.5)
		(connect_pads
			(clearance 0)
		)
		(min_thickness 0.25)
		(keepout
			(tracks not_allowed)
			(vias allowed)
			(pads allowed)
			(copperpour not_allowed)
			(footprints allowed)
		)
		(placement
			(enabled no)
			(sheetname "")
		)
		(fill
			(thermal_gap 0.5)
			(thermal_bridge_width 0.5)
			(island_removal_mode 0)
		)
		(polygon
			(pts
				(arc
					(start 327.88225 -349.679514)
					(mid 327.846329 -349.694393)
					(end 327.83145 -349.730314)
				)
				(arc
					(start 327.83145 -350.466914)
					(mid 327.846329 -350.502835)
					(end 327.88225 -350.517714)
				)
				(xy 328.12609 -350.517714) (xy 328.48042 -350.285304) (xy 328.83602 -350.517714)
				(arc
					(start 329.07859 -350.517714)
					(mid 329.114511 -350.502835)
					(end 329.12939 -350.466914)
				)
				(arc
					(start 329.12939 -349.730314)
					(mid 329.114511 -349.694393)
					(end 329.07859 -349.679514)
				)
				(xy 328.83602 -349.679514) (xy 328.47915 -349.911924) (xy 328.12482 -349.679514)
			)
		)
	)
	(zone
		(layer "In1.Cu")
		(hatch none 0.5)
		(connect_pads
			(clearance 0)
		)
		(min_thickness 0.25)
		(keepout
			(tracks not_allowed)
			(vias allowed)
			(pads allowed)
			(copperpour not_allowed)
			(footprints allowed)
		)
		(placement
			(enabled no)
			(sheetname "")
		)
		(fill
			(thermal_gap 0.5)
			(thermal_bridge_width 0.5)
			(island_removal_mode 0)
		)
		(polygon
			(pts
				(arc
					(start 249.573288 -32.879538)
					(mid 249.588167 -32.915459)
					(end 249.624088 -32.930338)
				)
				(arc
					(start 250.360688 -32.930338)
					(mid 250.396609 -32.915459)
					(end 250.411488 -32.879538)
				)
				(xy 250.411488 -32.635698) (xy 250.179078 -32.281368) (xy 250.411488 -31.925768)
				(arc
					(start 250.411488 -31.683198)
					(mid 250.396609 -31.647277)
					(end 250.360688 -31.632398)
				)
				(arc
					(start 249.624088 -31.632398)
					(mid 249.588167 -31.647277)
					(end 249.573288 -31.683198)
				)
				(xy 249.573288 -31.925768) (xy 249.805698 -32.282638) (xy 249.573288 -32.636968)
			)
		)
	)
	(zone
		(layer "In1.Cu")
		(hatch none 0.5)
		(connect_pads
			(clearance 0)
		)
		(min_thickness 0.25)
		(keepout
			(tracks not_allowed)
			(vias allowed)
			(pads allowed)
			(copperpour not_allowed)
			(footprints allowed)
		)
		(placement
			(enabled no)
			(sheetname "")
		)
		(fill
			(thermal_gap 0.5)
			(thermal_bridge_width 0.5)
			(island_removal_mode 0)
		)
		(polygon
			(pts
				(arc
					(start 298.821348 -349.679514)
					(mid 298.785427 -349.694393)
					(end 298.770548 -349.730314)
				)
				(arc
					(start 298.770548 -350.466914)
					(mid 298.785427 -350.502835)
					(end 298.821348 -350.517714)
				)
				(xy 299.065188 -350.517714) (xy 299.419518 -350.285304) (xy 299.775118 -350.517714)
				(arc
					(start 300.017688 -350.517714)
					(mid 300.053609 -350.502835)
					(end 300.068488 -350.466914)
				)
				(arc
					(start 300.068488 -349.730314)
					(mid 300.053609 -349.694393)
					(end 300.017688 -349.679514)
				)
				(xy 299.775118 -349.679514) (xy 299.418248 -349.911924) (xy 299.063918 -349.679514)
			)
		)
	)
	(zone
		(layer "In1.Cu")
		(hatch none 0.5)
		(connect_pads
			(clearance 0)
		)
		(min_thickness 0.25)
		(keepout
			(tracks not_allowed)
			(vias allowed)
			(pads allowed)
			(copperpour not_allowed)
			(footprints allowed)
		)
		(placement
			(enabled no)
			(sheetname "")
		)
		(fill
			(thermal_gap 0.5)
			(thermal_bridge_width 0.5)
			(island_removal_mode 0)
		)
		(polygon
			(pts
				(arc
					(start 278.215344 -34.68624)
					(mid 278.230223 -34.722161)
					(end 278.266144 -34.73704)
				)
				(arc
					(start 279.002744 -34.73704)
					(mid 279.038665 -34.722161)
					(end 279.053544 -34.68624)
				)
				(xy 279.053544 -34.4424) (xy 278.821134 -34.08807) (xy 279.053544 -33.73247)
				(arc
					(start 279.053544 -33.4899)
					(mid 279.038665 -33.453979)
					(end 279.002744 -33.4391)
				)
				(arc
					(start 278.266144 -33.4391)
					(mid 278.230223 -33.453979)
					(end 278.215344 -33.4899)
				)
				(xy 278.215344 -33.73247) (xy 278.447754 -34.08934) (xy 278.215344 -34.44367)
			)
		)
	)
	(zone
		(layer "In1.Cu")
		(hatch none 0.5)
		(connect_pads
			(clearance 0)
		)
		(min_thickness 0.25)
		(keepout
			(tracks not_allowed)
			(vias allowed)
			(pads allowed)
			(copperpour not_allowed)
			(footprints allowed)
		)
		(placement
			(enabled no)
			(sheetname "")
		)
		(fill
			(thermal_gap 0.5)
			(thermal_bridge_width 0.5)
			(island_removal_mode 0)
		)
		(polygon
			(pts
				(arc
					(start 152.129998 -28.174188)
					(mid 152.144877 -28.138267)
					(end 152.180798 -28.123388)
				)
				(arc
					(start 153.412698 -28.123388)
					(mid 153.448619 -28.138267)
					(end 153.463498 -28.174188)
				)
				(arc
					(start 153.463498 -29.205936)
					(mid 153.448619 -29.241857)
					(end 153.412698 -29.256736)
				)
				(arc
					(start 152.180798 -29.256736)
					(mid 152.144877 -29.241857)
					(end 152.129998 -29.205936)
				)
			)
		)
	)
	(zone
		(layer "In1.Cu")
		(hatch none 0.5)
		(connect_pads
			(clearance 0)
		)
		(min_thickness 0.25)
		(keepout
			(tracks not_allowed)
			(vias allowed)
			(pads allowed)
			(copperpour not_allowed)
			(footprints allowed)
		)
		(placement
			(enabled no)
			(sheetname "")
		)
		(fill
			(thermal_gap 0.5)
			(thermal_bridge_width 0.5)
			(island_removal_mode 0)
		)
		(polygon
			(pts
				(arc
					(start 427.783498 -355.825806)
					(mid 427.747577 -355.840685)
					(end 427.732698 -355.876606)
				)
				(arc
					(start 427.732698 -356.613206)
					(mid 427.747577 -356.649127)
					(end 427.783498 -356.664006)
				)
				(xy 428.027338 -356.664006) (xy 428.381668 -356.431596) (xy 428.737268 -356.664006)
				(arc
					(start 428.979838 -356.664006)
					(mid 429.015759 -356.649127)
					(end 429.030638 -356.613206)
				)
				(arc
					(start 429.030638 -355.876606)
					(mid 429.015759 -355.840685)
					(end 428.979838 -355.825806)
				)
				(xy 428.737268 -355.825806) (xy 428.380398 -356.058216) (xy 428.026068 -355.825806)
			)
		)
	)
	(zone
		(layer "In1.Cu")
		(hatch none 0.5)
		(connect_pads
			(clearance 0)
		)
		(min_thickness 0.25)
		(keepout
			(tracks not_allowed)
			(vias allowed)
			(pads allowed)
			(copperpour not_allowed)
			(footprints allowed)
		)
		(placement
			(enabled no)
			(sheetname "")
		)
		(fill
			(thermal_gap 0.5)
			(thermal_bridge_width 0.5)
			(island_removal_mode 0)
		)
		(polygon
			(pts
				(arc
					(start 230.652574 -79.159608)
					(mid 230.667453 -79.123687)
					(end 230.703374 -79.108808)
				)
				(arc
					(start 230.756714 -79.108808)
					(mid 230.792635 -79.123687)
					(end 230.807514 -79.159608)
				)
				(arc
					(start 230.807514 -79.771494)
					(mid 230.792635 -79.807415)
					(end 230.756714 -79.822294)
				)
				(arc
					(start 230.703374 -79.822294)
					(mid 230.667453 -79.807415)
					(end 230.652574 -79.771494)
				)
			)
		)
	)
	(zone
		(layer "In1.Cu")
		(hatch none 0.5)
		(connect_pads
			(clearance 0)
		)
		(min_thickness 0.25)
		(keepout
			(tracks not_allowed)
			(vias allowed)
			(pads allowed)
			(copperpour not_allowed)
			(footprints allowed)
		)
		(placement
			(enabled no)
			(sheetname "")
		)
		(fill
			(thermal_gap 0.5)
			(thermal_bridge_width 0.5)
			(island_removal_mode 0)
		)
		(polygon
			(pts
				(arc
					(start 442.199776 -27.405838)
					(mid 442.184897 -27.441759)
					(end 442.148976 -27.456638)
				)
				(arc
					(start 440.917076 -27.456638)
					(mid 440.881155 -27.441759)
					(end 440.866276 -27.405838)
				)
				(arc
					(start 440.866276 -26.37409)
					(mid 440.881155 -26.338169)
					(end 440.917076 -26.32329)
				)
				(arc
					(start 442.148976 -26.32329)
					(mid 442.184897 -26.338169)
					(end 442.199776 -26.37409)
				)
			)
		)
	)
	(zone
		(layer "In1.Cu")
		(hatch none 0.5)
		(connect_pads
			(clearance 0)
		)
		(min_thickness 0.25)
		(keepout
			(tracks not_allowed)
			(vias allowed)
			(pads allowed)
			(copperpour not_allowed)
			(footprints allowed)
		)
		(placement
			(enabled no)
			(sheetname "")
		)
		(fill
			(thermal_gap 0.5)
			(thermal_bridge_width 0.5)
			(island_removal_mode 0)
		)
		(polygon
			(pts
				(arc
					(start 186.892438 -349.679514)
					(mid 186.856517 -349.694393)
					(end 186.841638 -349.730314)
				)
				(arc
					(start 186.841638 -350.466914)
					(mid 186.856517 -350.502835)
					(end 186.892438 -350.517714)
				)
				(xy 187.136278 -350.517714) (xy 187.490608 -350.285304) (xy 187.846208 -350.517714)
				(arc
					(start 188.088778 -350.517714)
					(mid 188.124699 -350.502835)
					(end 188.139578 -350.466914)
				)
				(arc
					(start 188.139578 -349.730314)
					(mid 188.124699 -349.694393)
					(end 188.088778 -349.679514)
				)
				(xy 187.846208 -349.679514) (xy 187.489338 -349.911924) (xy 187.135008 -349.679514)
			)
		)
	)
	(zone
		(layer "In1.Cu")
		(hatch none 0.5)
		(connect_pads
			(clearance 0)
		)
		(min_thickness 0.25)
		(keepout
			(tracks not_allowed)
			(vias allowed)
			(pads allowed)
			(copperpour not_allowed)
			(footprints allowed)
		)
		(placement
			(enabled no)
			(sheetname "")
		)
		(fill
			(thermal_gap 0.5)
			(thermal_bridge_width 0.5)
			(island_removal_mode 0)
		)
		(polygon
			(pts
				(arc
					(start 159.473392 -29.279596)
					(mid 159.488271 -29.315517)
					(end 159.524192 -29.330396)
				)
				(arc
					(start 160.260792 -29.330396)
					(mid 160.296713 -29.315517)
					(end 160.311592 -29.279596)
				)
				(xy 160.311592 -29.035756) (xy 160.079182 -28.681426) (xy 160.311592 -28.325826)
				(arc
					(start 160.311592 -28.083256)
					(mid 160.296713 -28.047335)
					(end 160.260792 -28.032456)
				)
				(arc
					(start 159.524192 -28.032456)
					(mid 159.488271 -28.047335)
					(end 159.473392 -28.083256)
				)
				(xy 159.473392 -28.325826) (xy 159.705802 -28.682696) (xy 159.473392 -29.037026)
			)
		)
	)
	(zone
		(layer "In1.Cu")
		(hatch none 0.5)
		(connect_pads
			(clearance 0)
		)
		(min_thickness 0.25)
		(keepout
			(tracks not_allowed)
			(vias allowed)
			(pads allowed)
			(copperpour not_allowed)
			(footprints allowed)
		)
		(placement
			(enabled no)
			(sheetname "")
		)
		(fill
			(thermal_gap 0.5)
			(thermal_bridge_width 0.5)
			(island_removal_mode 0)
		)
		(polygon
			(pts
				(arc
					(start 330.99121 -355.825806)
					(mid 330.955289 -355.840685)
					(end 330.94041 -355.876606)
				)
				(arc
					(start 330.94041 -356.613206)
					(mid 330.955289 -356.649127)
					(end 330.99121 -356.664006)
				)
				(xy 331.23505 -356.664006) (xy 331.58938 -356.431596) (xy 331.94498 -356.664006)
				(arc
					(start 332.18755 -356.664006)
					(mid 332.223471 -356.649127)
					(end 332.23835 -356.613206)
				)
				(arc
					(start 332.23835 -355.876606)
					(mid 332.223471 -355.840685)
					(end 332.18755 -355.825806)
				)
				(xy 331.94498 -355.825806) (xy 331.58811 -356.058216) (xy 331.23378 -355.825806)
			)
		)
	)
	(zone
		(layer "In1.Cu")
		(hatch none 0.5)
		(connect_pads
			(clearance 0)
		)
		(min_thickness 0.25)
		(keepout
			(tracks not_allowed)
			(vias allowed)
			(pads allowed)
			(copperpour not_allowed)
			(footprints allowed)
		)
		(placement
			(enabled no)
			(sheetname "")
		)
		(fill
			(thermal_gap 0.5)
			(thermal_bridge_width 0.5)
			(island_removal_mode 0)
		)
		(polygon
			(pts
				(arc
					(start 399.55216 -100.248212)
					(mid 399.537281 -100.284133)
					(end 399.50136 -100.299012)
				)
				(arc
					(start 398.32026 -100.299012)
					(mid 398.284339 -100.284133)
					(end 398.26946 -100.248212)
				)
				(arc
					(start 398.26946 -99.241864)
					(mid 398.284339 -99.205943)
					(end 398.32026 -99.191064)
				)
				(arc
					(start 399.50136 -99.191064)
					(mid 399.537281 -99.205943)
					(end 399.55216 -99.241864)
				)
			)
		)
	)
	(zone
		(layer "In1.Cu")
		(hatch none 0.5)
		(connect_pads
			(clearance 0)
		)
		(min_thickness 0.25)
		(keepout
			(tracks not_allowed)
			(vias allowed)
			(pads allowed)
			(copperpour not_allowed)
			(footprints allowed)
		)
		(placement
			(enabled no)
			(sheetname "")
		)
		(fill
			(thermal_gap 0.5)
			(thermal_bridge_width 0.5)
			(island_removal_mode 0)
		)
		(polygon
			(pts
				(arc
					(start 239.594898 -84.980018)
					(mid 239.505095 -84.942821)
					(end 239.467898 -84.853018)
				)
				(arc
					(start 239.467898 -84.649818)
					(mid 239.505095 -84.560015)
					(end 239.594898 -84.522818)
				)
				(arc
					(start 239.848898 -84.522818)
					(mid 239.938701 -84.560015)
					(end 239.975898 -84.649818)
				)
				(arc
					(start 239.975898 -84.853018)
					(mid 239.938701 -84.942821)
					(end 239.848898 -84.980018)
				)
			)
		)
	)
	(zone
		(layer "In1.Cu")
		(hatch none 0.5)
		(connect_pads
			(clearance 0)
		)
		(min_thickness 0.25)
		(keepout
			(tracks not_allowed)
			(vias allowed)
			(pads allowed)
			(copperpour not_allowed)
			(footprints allowed)
		)
		(placement
			(enabled no)
			(sheetname "")
		)
		(fill
			(thermal_gap 0.5)
			(thermal_bridge_width 0.5)
			(island_removal_mode 0)
		)
		(polygon
			(pts
				(arc
					(start 15.899892 -31.006034)
					(mid 15.885013 -31.041955)
					(end 15.849092 -31.056834)
				)
				(arc
					(start 14.617192 -31.056834)
					(mid 14.581271 -31.041955)
					(end 14.566392 -31.006034)
				)
				(arc
					(start 14.566392 -29.974286)
					(mid 14.581271 -29.938365)
					(end 14.617192 -29.923486)
				)
				(arc
					(start 15.849092 -29.923486)
					(mid 15.885013 -29.938365)
					(end 15.899892 -29.974286)
				)
			)
		)
	)
	(zone
		(layer "In1.Cu")
		(hatch none 0.5)
		(connect_pads
			(clearance 0)
		)
		(min_thickness 0.25)
		(keepout
			(tracks not_allowed)
			(vias allowed)
			(pads allowed)
			(copperpour not_allowed)
			(footprints allowed)
		)
		(placement
			(enabled no)
			(sheetname "")
		)
		(fill
			(thermal_gap 0.5)
			(thermal_bridge_width 0.5)
			(island_removal_mode 0)
		)
		(polygon
			(pts
				(arc
					(start 446.461896 -413.521144)
					(mid 446.561302 -413.587535)
					(end 446.678558 -413.610806)
				)
				(arc
					(start 450.898006 -413.610806)
					(mid 451.015234 -413.587466)
					(end 451.114668 -413.521144)
				)
				(xy 451.115684 -413.520128)
				(arc
					(start 451.115684 -406.984708)
					(mid 451.092366 -406.867277)
					(end 451.025768 -406.767792)
				)
				(arc
					(start 450.978778 -406.720802)
					(mid 450.879345 -406.654459)
					(end 450.762116 -406.63114)
				)
				(arc
					(start 446.663572 -406.63114)
					(mid 446.546206 -406.654579)
					(end 446.446656 -406.721056)
				)
				(arc
					(start 446.399666 -406.768046)
					(mid 446.333035 -406.867526)
					(end 446.30975 -406.984962)
				)
				(arc
					(start 446.30975 -413.241998)
					(mid 446.333106 -413.359418)
					(end 446.399666 -413.458914)
				)
			)
		)
	)
	(zone
		(layer "In1.Cu")
		(hatch none 0.5)
		(connect_pads
			(clearance 0)
		)
		(min_thickness 0.25)
		(keepout
			(tracks not_allowed)
			(vias allowed)
			(pads allowed)
			(copperpour not_allowed)
			(footprints allowed)
		)
		(placement
			(enabled no)
			(sheetname "")
		)
		(fill
			(thermal_gap 0.5)
			(thermal_bridge_width 0.5)
			(island_removal_mode 0)
		)
		(polygon
			(pts
				(arc
					(start 311.80024 -119.724678)
					(mid 311.815119 -119.760599)
					(end 311.85104 -119.775478)
				)
				(arc
					(start 312.58764 -119.775478)
					(mid 312.623561 -119.760599)
					(end 312.63844 -119.724678)
				)
				(xy 312.63844 -119.480838) (xy 312.40603 -119.126508) (xy 312.63844 -118.770908)
				(arc
					(start 312.63844 -118.528338)
					(mid 312.623561 -118.492417)
					(end 312.58764 -118.477538)
				)
				(arc
					(start 311.85104 -118.477538)
					(mid 311.815119 -118.492417)
					(end 311.80024 -118.528338)
				)
				(xy 311.80024 -118.770908) (xy 312.03265 -119.127778) (xy 311.80024 -119.482108)
			)
		)
	)
	(zone
		(layer "In1.Cu")
		(hatch none 0.5)
		(connect_pads
			(clearance 0)
		)
		(min_thickness 0.25)
		(keepout
			(tracks not_allowed)
			(vias allowed)
			(pads allowed)
			(copperpour not_allowed)
			(footprints allowed)
		)
		(placement
			(enabled no)
			(sheetname "")
		)
		(fill
			(thermal_gap 0.5)
			(thermal_bridge_width 0.5)
			(island_removal_mode 0)
		)
		(polygon
			(pts
				(arc
					(start 390.19988 -31.006034)
					(mid 390.185001 -31.041955)
					(end 390.14908 -31.056834)
				)
				(arc
					(start 388.91718 -31.056834)
					(mid 388.881259 -31.041955)
					(end 388.86638 -31.006034)
				)
				(arc
					(start 388.86638 -29.974286)
					(mid 388.881259 -29.938365)
					(end 388.91718 -29.923486)
				)
				(arc
					(start 390.14908 -29.923486)
					(mid 390.185001 -29.938365)
					(end 390.19988 -29.974286)
				)
			)
		)
	)
	(zone
		(layer "In1.Cu")
		(hatch none 0.5)
		(connect_pads
			(clearance 0)
		)
		(min_thickness 0.25)
		(keepout
			(tracks not_allowed)
			(vias allowed)
			(pads allowed)
			(copperpour not_allowed)
			(footprints allowed)
		)
		(placement
			(enabled no)
			(sheetname "")
		)
		(fill
			(thermal_gap 0.5)
			(thermal_bridge_width 0.5)
			(island_removal_mode 0)
		)
		(polygon
			(pts
				(arc
					(start 161.53257 -108.241846)
					(mid 161.547449 -108.205925)
					(end 161.58337 -108.191046)
				)
				(arc
					(start 162.76447 -108.191046)
					(mid 162.800391 -108.205925)
					(end 162.81527 -108.241846)
				)
				(arc
					(start 162.81527 -109.248194)
					(mid 162.800391 -109.284115)
					(end 162.76447 -109.298994)
				)
				(arc
					(start 161.58337 -109.298994)
					(mid 161.547449 -109.284115)
					(end 161.53257 -109.248194)
				)
			)
		)
	)
	(zone
		(layer "In1.Cu")
		(hatch none 0.5)
		(connect_pads
			(clearance 0)
		)
		(min_thickness 0.25)
		(keepout
			(tracks not_allowed)
			(vias allowed)
			(pads allowed)
			(copperpour not_allowed)
			(footprints allowed)
		)
		(placement
			(enabled no)
			(sheetname "")
		)
		(fill
			(thermal_gap 0.5)
			(thermal_bridge_width 0.5)
			(island_removal_mode 0)
		)
		(polygon
			(pts
				(arc
					(start 167.351964 -112.848136)
					(mid 167.337085 -112.884057)
					(end 167.301164 -112.898936)
				)
				(arc
					(start 166.120064 -112.898936)
					(mid 166.084143 -112.884057)
					(end 166.069264 -112.848136)
				)
				(arc
					(start 166.069264 -111.841788)
					(mid 166.084143 -111.805867)
					(end 166.120064 -111.790988)
				)
				(arc
					(start 167.301164 -111.790988)
					(mid 167.337085 -111.805867)
					(end 167.351964 -111.841788)
				)
			)
		)
	)
	(zone
		(layer "In1.Cu")
		(hatch none 0.5)
		(connect_pads
			(clearance 0)
		)
		(min_thickness 0.25)
		(keepout
			(tracks not_allowed)
			(vias allowed)
			(pads allowed)
			(copperpour not_allowed)
			(footprints allowed)
		)
		(placement
			(enabled no)
			(sheetname "")
		)
		(fill
			(thermal_gap 0.5)
			(thermal_bridge_width 0.5)
			(island_removal_mode 0)
		)
		(polygon
			(pts
				(arc
					(start 422.167304 -121.438162)
					(mid 422.152425 -121.474083)
					(end 422.116504 -121.488962)
				)
				(arc
					(start 420.935404 -121.488962)
					(mid 420.899483 -121.474083)
					(end 420.884604 -121.438162)
				)
				(arc
					(start 420.884604 -120.431814)
					(mid 420.899483 -120.395893)
					(end 420.935404 -120.381014)
				)
				(arc
					(start 422.116504 -120.381014)
					(mid 422.152425 -120.395893)
					(end 422.167304 -120.431814)
				)
			)
		)
	)
	(zone
		(layer "In1.Cu")
		(hatch none 0.5)
		(connect_pads
			(clearance 0)
		)
		(min_thickness 0.25)
		(keepout
			(tracks not_allowed)
			(vias allowed)
			(pads allowed)
			(copperpour not_allowed)
			(footprints allowed)
		)
		(placement
			(enabled no)
			(sheetname "")
		)
		(fill
			(thermal_gap 0.5)
			(thermal_bridge_width 0.5)
			(island_removal_mode 0)
		)
		(polygon
			(pts
				(arc
					(start 442.199776 -31.006034)
					(mid 442.184897 -31.041955)
					(end 442.148976 -31.056834)
				)
				(arc
					(start 440.917076 -31.056834)
					(mid 440.881155 -31.041955)
					(end 440.866276 -31.006034)
				)
				(arc
					(start 440.866276 -29.974286)
					(mid 440.881155 -29.938365)
					(end 440.917076 -29.923486)
				)
				(arc
					(start 442.148976 -29.923486)
					(mid 442.184897 -29.938365)
					(end 442.199776 -29.974286)
				)
			)
		)
	)
	(zone
		(layer "In1.Cu")
		(hatch none 0.5)
		(connect_pads
			(clearance 0)
		)
		(min_thickness 0.25)
		(keepout
			(tracks not_allowed)
			(vias allowed)
			(pads allowed)
			(copperpour not_allowed)
			(footprints allowed)
		)
		(placement
			(enabled no)
			(sheetname "")
		)
		(fill
			(thermal_gap 0.5)
			(thermal_bridge_width 0.5)
			(island_removal_mode 0)
		)
		(polygon
			(pts
				(arc
					(start 117.914674 -343.533222)
					(mid 117.878753 -343.548101)
					(end 117.863874 -343.584022)
				)
				(arc
					(start 117.863874 -344.320622)
					(mid 117.878753 -344.356543)
					(end 117.914674 -344.371422)
				)
				(xy 118.158514 -344.371422) (xy 118.512844 -344.139012) (xy 118.868444 -344.371422)
				(arc
					(start 119.111014 -344.371422)
					(mid 119.146935 -344.356543)
					(end 119.161814 -344.320622)
				)
				(arc
					(start 119.161814 -343.584022)
					(mid 119.146935 -343.548101)
					(end 119.111014 -343.533222)
				)
				(xy 118.868444 -343.533222) (xy 118.511574 -343.765632) (xy 118.157244 -343.533222)
			)
		)
	)
	(zone
		(layer "In1.Cu")
		(hatch none 0.5)
		(connect_pads
			(clearance 0)
		)
		(min_thickness 0.25)
		(keepout
			(tracks not_allowed)
			(vias allowed)
			(pads allowed)
			(copperpour not_allowed)
			(footprints allowed)
		)
		(placement
			(enabled no)
			(sheetname "")
		)
		(fill
			(thermal_gap 0.5)
			(thermal_bridge_width 0.5)
			(island_removal_mode 0)
		)
		(polygon
			(pts
				(arc
					(start 195.700142 -130.93446)
					(mid 195.715021 -130.970381)
					(end 195.750942 -130.98526)
				)
				(arc
					(start 196.487542 -130.98526)
					(mid 196.523463 -130.970381)
					(end 196.538342 -130.93446)
				)
				(xy 196.538342 -130.69062) (xy 196.305932 -130.33629) (xy 196.538342 -129.98069)
				(arc
					(start 196.538342 -129.73812)
					(mid 196.523463 -129.702199)
					(end 196.487542 -129.68732)
				)
				(arc
					(start 195.750942 -129.68732)
					(mid 195.715021 -129.702199)
					(end 195.700142 -129.73812)
				)
				(xy 195.700142 -129.98069) (xy 195.932552 -130.33756) (xy 195.700142 -130.69189)
			)
		)
	)
	(zone
		(layer "In1.Cu")
		(hatch none 0.5)
		(connect_pads
			(clearance 0)
		)
		(min_thickness 0.25)
		(keepout
			(tracks not_allowed)
			(vias allowed)
			(pads allowed)
			(copperpour not_allowed)
			(footprints allowed)
		)
		(placement
			(enabled no)
			(sheetname "")
		)
		(fill
			(thermal_gap 0.5)
			(thermal_bridge_width 0.5)
			(island_removal_mode 0)
		)
		(polygon
			(pts
				(arc
					(start 186.892438 -343.533222)
					(mid 186.856517 -343.548101)
					(end 186.841638 -343.584022)
				)
				(arc
					(start 186.841638 -344.320622)
					(mid 186.856517 -344.356543)
					(end 186.892438 -344.371422)
				)
				(xy 187.136278 -344.371422) (xy 187.490608 -344.139012) (xy 187.846208 -344.371422)
				(arc
					(start 188.088778 -344.371422)
					(mid 188.124699 -344.356543)
					(end 188.139578 -344.320622)
				)
				(arc
					(start 188.139578 -343.584022)
					(mid 188.124699 -343.548101)
					(end 188.088778 -343.533222)
				)
				(xy 187.846208 -343.533222) (xy 187.489338 -343.765632) (xy 187.135008 -343.533222)
			)
		)
	)
	(zone
		(layer "In1.Cu")
		(hatch none 0.5)
		(connect_pads
			(clearance 0)
		)
		(min_thickness 0.25)
		(keepout
			(tracks not_allowed)
			(vias allowed)
			(pads allowed)
			(copperpour not_allowed)
			(footprints allowed)
		)
		(placement
			(enabled no)
			(sheetname "")
		)
		(fill
			(thermal_gap 0.5)
			(thermal_bridge_width 0.5)
			(island_removal_mode 0)
		)
		(polygon
			(pts
				(arc
					(start 154.961336 -100.343208)
					(mid 154.976215 -100.379129)
					(end 155.012136 -100.394008)
				)
				(arc
					(start 155.748736 -100.394008)
					(mid 155.784657 -100.379129)
					(end 155.799536 -100.343208)
				)
				(xy 155.799536 -100.099368) (xy 155.567126 -99.745038) (xy 155.799536 -99.389438)
				(arc
					(start 155.799536 -99.146868)
					(mid 155.784657 -99.110947)
					(end 155.748736 -99.096068)
				)
				(arc
					(start 155.012136 -99.096068)
					(mid 154.976215 -99.110947)
					(end 154.961336 -99.146868)
				)
				(xy 154.961336 -99.389438) (xy 155.193746 -99.746308) (xy 154.961336 -100.100638)
			)
		)
	)
	(zone
		(layer "In1.Cu")
		(hatch none 0.5)
		(connect_pads
			(clearance 0)
		)
		(min_thickness 0.25)
		(keepout
			(tracks not_allowed)
			(vias allowed)
			(pads allowed)
			(copperpour not_allowed)
			(footprints allowed)
		)
		(placement
			(enabled no)
			(sheetname "")
		)
		(fill
			(thermal_gap 0.5)
			(thermal_bridge_width 0.5)
			(island_removal_mode 0)
		)
		(polygon
			(pts
				(arc
					(start 36.0299 -29.974286)
					(mid 36.044779 -29.938365)
					(end 36.0807 -29.923486)
				)
				(arc
					(start 37.3126 -29.923486)
					(mid 37.348521 -29.938365)
					(end 37.3634 -29.974286)
				)
				(arc
					(start 37.3634 -31.006034)
					(mid 37.348521 -31.041955)
					(end 37.3126 -31.056834)
				)
				(arc
					(start 36.0807 -31.056834)
					(mid 36.044779 -31.041955)
					(end 36.0299 -31.006034)
				)
			)
		)
	)
	(zone
		(layer "In1.Cu")
		(hatch none 0.5)
		(connect_pads
			(clearance 0)
		)
		(min_thickness 0.25)
		(keepout
			(tracks not_allowed)
			(vias allowed)
			(pads allowed)
			(copperpour not_allowed)
			(footprints allowed)
		)
		(placement
			(enabled no)
			(sheetname "")
		)
		(fill
			(thermal_gap 0.5)
			(thermal_bridge_width 0.5)
			(island_removal_mode 0)
		)
		(polygon
			(pts
				(arc
					(start 393.732766 -101.041962)
					(mid 393.747645 -101.006041)
					(end 393.783566 -100.991162)
				)
				(arc
					(start 394.964666 -100.991162)
					(mid 395.000587 -101.006041)
					(end 395.015466 -101.041962)
				)
				(arc
					(start 395.015466 -102.04831)
					(mid 395.000587 -102.084231)
					(end 394.964666 -102.09911)
				)
				(arc
					(start 393.783566 -102.09911)
					(mid 393.747645 -102.084231)
					(end 393.732766 -102.04831)
				)
			)
		)
	)
	(zone
		(layer "In1.Cu")
		(hatch none 0.5)
		(connect_pads
			(clearance 0)
		)
		(min_thickness 0.25)
		(keepout
			(tracks not_allowed)
			(vias allowed)
			(pads allowed)
			(copperpour not_allowed)
			(footprints allowed)
		)
		(placement
			(enabled no)
			(sheetname "")
		)
		(fill
			(thermal_gap 0.5)
			(thermal_bridge_width 0.5)
			(island_removal_mode 0)
		)
		(polygon
			(pts
				(arc
					(start 127.241554 -343.533222)
					(mid 127.205633 -343.548101)
					(end 127.190754 -343.584022)
				)
				(arc
					(start 127.190754 -344.320622)
					(mid 127.205633 -344.356543)
					(end 127.241554 -344.371422)
				)
				(xy 127.485394 -344.371422) (xy 127.839724 -344.139012) (xy 128.195324 -344.371422)
				(arc
					(start 128.437894 -344.371422)
					(mid 128.473815 -344.356543)
					(end 128.488694 -344.320622)
				)
				(arc
					(start 128.488694 -343.584022)
					(mid 128.473815 -343.548101)
					(end 128.437894 -343.533222)
				)
				(xy 128.195324 -343.533222) (xy 127.838454 -343.765632) (xy 127.484124 -343.533222)
			)
		)
	)
	(zone
		(layer "In1.Cu")
		(hatch none 0.5)
		(connect_pads
			(clearance 0)
		)
		(min_thickness 0.25)
		(keepout
			(tracks not_allowed)
			(vias allowed)
			(pads allowed)
			(copperpour not_allowed)
			(footprints allowed)
		)
		(placement
			(enabled no)
			(sheetname "")
		)
		(fill
			(thermal_gap 0.5)
			(thermal_bridge_width 0.5)
			(island_removal_mode 0)
		)
		(polygon
			(pts
				(arc
					(start 283.452062 -107.448096)
					(mid 283.437183 -107.484017)
					(end 283.401262 -107.498896)
				)
				(arc
					(start 282.220162 -107.498896)
					(mid 282.184241 -107.484017)
					(end 282.169362 -107.448096)
				)
				(arc
					(start 282.169362 -106.441748)
					(mid 282.184241 -106.405827)
					(end 282.220162 -106.390948)
				)
				(arc
					(start 283.401262 -106.390948)
					(mid 283.437183 -106.405827)
					(end 283.452062 -106.441748)
				)
			)
		)
	)
	(zone
		(layer "In1.Cu")
		(hatch none 0.5)
		(connect_pads
			(clearance 0)
		)
		(min_thickness 0.25)
		(keepout
			(tracks not_allowed)
			(vias allowed)
			(pads allowed)
			(copperpour not_allowed)
			(footprints allowed)
		)
		(placement
			(enabled no)
			(sheetname "")
		)
		(fill
			(thermal_gap 0.5)
			(thermal_bridge_width 0.5)
			(island_removal_mode 0)
		)
		(polygon
			(pts
				(arc
					(start 416.34791 -147.951952)
					(mid 416.362789 -147.916031)
					(end 416.39871 -147.901152)
				)
				(arc
					(start 417.57981 -147.901152)
					(mid 417.615731 -147.916031)
					(end 417.63061 -147.951952)
				)
				(arc
					(start 417.63061 -148.9583)
					(mid 417.615731 -148.994221)
					(end 417.57981 -149.0091)
				)
				(arc
					(start 416.39871 -149.0091)
					(mid 416.362789 -148.994221)
					(end 416.34791 -148.9583)
				)
			)
		)
	)
	(zone
		(layer "In1.Cu")
		(hatch none 0.5)
		(connect_pads
			(clearance 0)
		)
		(min_thickness 0.25)
		(keepout
			(tracks not_allowed)
			(vias allowed)
			(pads allowed)
			(copperpour not_allowed)
			(footprints allowed)
		)
		(placement
			(enabled no)
			(sheetname "")
		)
		(fill
			(thermal_gap 0.5)
			(thermal_bridge_width 0.5)
			(island_removal_mode 0)
		)
		(polygon
			(pts
				(arc
					(start 51.25212 -136.768332)
					(mid 51.237241 -136.804253)
					(end 51.20132 -136.819132)
				)
				(arc
					(start 50.02022 -136.819132)
					(mid 49.984299 -136.804253)
					(end 49.96942 -136.768332)
				)
				(arc
					(start 49.96942 -135.761984)
					(mid 49.984299 -135.726063)
					(end 50.02022 -135.711184)
				)
				(arc
					(start 51.20132 -135.711184)
					(mid 51.237241 -135.726063)
					(end 51.25212 -135.761984)
				)
			)
		)
	)
	(zone
		(layer "In1.Cu")
		(hatch none 0.5)
		(connect_pads
			(clearance 0)
		)
		(min_thickness 0.25)
		(keepout
			(tracks not_allowed)
			(vias allowed)
			(pads allowed)
			(copperpour not_allowed)
			(footprints allowed)
		)
		(placement
			(enabled no)
			(sheetname "")
		)
		(fill
			(thermal_gap 0.5)
			(thermal_bridge_width 0.5)
			(island_removal_mode 0)
		)
		(polygon
			(pts
				(arc
					(start 184.147714 -135.241792)
					(mid 184.162593 -135.205871)
					(end 184.198514 -135.190992)
				)
				(arc
					(start 185.379614 -135.190992)
					(mid 185.415535 -135.205871)
					(end 185.430414 -135.241792)
				)
				(arc
					(start 185.430414 -136.24814)
					(mid 185.415535 -136.284061)
					(end 185.379614 -136.29894)
				)
				(arc
					(start 184.198514 -136.29894)
					(mid 184.162593 -136.284061)
					(end 184.147714 -136.24814)
				)
			)
		)
	)
	(zone
		(layer "In1.Cu")
		(hatch none 0.5)
		(connect_pads
			(clearance 0)
		)
		(min_thickness 0.25)
		(keepout
			(tracks not_allowed)
			(vias allowed)
			(pads allowed)
			(copperpour not_allowed)
			(footprints allowed)
		)
		(placement
			(enabled no)
			(sheetname "")
		)
		(fill
			(thermal_gap 0.5)
			(thermal_bridge_width 0.5)
			(island_removal_mode 0)
		)
		(polygon
			(pts
				(arc
					(start 95.37319 -32.879538)
					(mid 95.388069 -32.915459)
					(end 95.42399 -32.930338)
				)
				(arc
					(start 96.16059 -32.930338)
					(mid 96.196511 -32.915459)
					(end 96.21139 -32.879538)
				)
				(xy 96.21139 -32.635698) (xy 95.97898 -32.281368) (xy 96.21139 -31.925768)
				(arc
					(start 96.21139 -31.683198)
					(mid 96.196511 -31.647277)
					(end 96.16059 -31.632398)
				)
				(arc
					(start 95.42399 -31.632398)
					(mid 95.388069 -31.647277)
					(end 95.37319 -31.683198)
				)
				(xy 95.37319 -31.925768) (xy 95.6056 -32.282638) (xy 95.37319 -32.636968)
			)
		)
	)
	(zone
		(layer "In1.Cu")
		(hatch none 0.5)
		(connect_pads
			(clearance 0)
		)
		(min_thickness 0.25)
		(keepout
			(tracks not_allowed)
			(vias allowed)
			(pads allowed)
			(copperpour not_allowed)
			(footprints allowed)
		)
		(placement
			(enabled no)
			(sheetname "")
		)
		(fill
			(thermal_gap 0.5)
			(thermal_bridge_width 0.5)
			(island_removal_mode 0)
		)
		(polygon
			(pts
				(arc
					(start 274.099782 -29.205936)
					(mid 274.084903 -29.241857)
					(end 274.048982 -29.256736)
				)
				(arc
					(start 272.817082 -29.256736)
					(mid 272.781161 -29.241857)
					(end 272.766282 -29.205936)
				)
				(arc
					(start 272.766282 -28.174188)
					(mid 272.781161 -28.138267)
					(end 272.817082 -28.123388)
				)
				(arc
					(start 274.048982 -28.123388)
					(mid 274.084903 -28.138267)
					(end 274.099782 -28.174188)
				)
			)
		)
	)
	(zone
		(layer "In1.Cu")
		(hatch none 0.5)
		(connect_pads
			(clearance 0)
		)
		(min_thickness 0.25)
		(keepout
			(tracks not_allowed)
			(vias allowed)
			(pads allowed)
			(copperpour not_allowed)
			(footprints allowed)
		)
		(placement
			(enabled no)
			(sheetname "")
		)
		(fill
			(thermal_gap 0.5)
			(thermal_bridge_width 0.5)
			(island_removal_mode 0)
		)
		(polygon
			(pts
				(arc
					(start 198.34225 -136.341104)
					(mid 198.357129 -136.377025)
					(end 198.39305 -136.391904)
				)
				(arc
					(start 199.12965 -136.391904)
					(mid 199.165571 -136.377025)
					(end 199.18045 -136.341104)
				)
				(xy 199.18045 -136.097264) (xy 198.94804 -135.742934) (xy 199.18045 -135.387334)
				(arc
					(start 199.18045 -135.144764)
					(mid 199.165571 -135.108843)
					(end 199.12965 -135.093964)
				)
				(arc
					(start 198.39305 -135.093964)
					(mid 198.357129 -135.108843)
					(end 198.34225 -135.144764)
				)
				(xy 198.34225 -135.387334) (xy 198.57466 -135.744204) (xy 198.34225 -136.098534)
			)
		)
	)
	(zone
		(layer "In1.Cu")
		(hatch none 0.5)
		(connect_pads
			(clearance 0)
		)
		(min_thickness 0.25)
		(keepout
			(tracks not_allowed)
			(vias allowed)
			(pads allowed)
			(copperpour not_allowed)
			(footprints allowed)
		)
		(placement
			(enabled no)
			(sheetname "")
		)
		(fill
			(thermal_gap 0.5)
			(thermal_bridge_width 0.5)
			(island_removal_mode 0)
		)
		(polygon
			(pts
				(arc
					(start 142.786354 -349.679514)
					(mid 142.750433 -349.694393)
					(end 142.735554 -349.730314)
				)
				(arc
					(start 142.735554 -350.466914)
					(mid 142.750433 -350.502835)
					(end 142.786354 -350.517714)
				)
				(xy 143.030194 -350.517714) (xy 143.384524 -350.285304) (xy 143.740124 -350.517714)
				(arc
					(start 143.982694 -350.517714)
					(mid 144.018615 -350.502835)
					(end 144.033494 -350.466914)
				)
				(arc
					(start 144.033494 -349.730314)
					(mid 144.018615 -349.694393)
					(end 143.982694 -349.679514)
				)
				(xy 143.740124 -349.679514) (xy 143.383254 -349.911924) (xy 143.028924 -349.679514)
			)
		)
	)
	(zone
		(layer "In1.Cu")
		(hatch none 0.5)
		(connect_pads
			(clearance 0)
		)
		(min_thickness 0.25)
		(keepout
			(tracks not_allowed)
			(vias allowed)
			(pads allowed)
			(copperpour not_allowed)
			(footprints allowed)
		)
		(placement
			(enabled no)
			(sheetname "")
		)
		(fill
			(thermal_gap 0.5)
			(thermal_bridge_width 0.5)
			(island_removal_mode 0)
		)
		(polygon
			(pts
				(arc
					(start 88.029796 -28.174188)
					(mid 88.044675 -28.138267)
					(end 88.080596 -28.123388)
				)
				(arc
					(start 89.312496 -28.123388)
					(mid 89.348417 -28.138267)
					(end 89.363296 -28.174188)
				)
				(arc
					(start 89.363296 -29.205936)
					(mid 89.348417 -29.241857)
					(end 89.312496 -29.256736)
				)
				(arc
					(start 88.080596 -29.256736)
					(mid 88.044675 -29.241857)
					(end 88.029796 -29.205936)
				)
			)
		)
	)
	(zone
		(layer "In1.Cu")
		(hatch none 0.5)
		(connect_pads
			(clearance 0)
		)
		(min_thickness 0.25)
		(keepout
			(tracks not_allowed)
			(vias allowed)
			(pads allowed)
			(copperpour not_allowed)
			(footprints allowed)
		)
		(placement
			(enabled no)
			(sheetname "")
		)
		(fill
			(thermal_gap 0.5)
			(thermal_bridge_width 0.5)
			(island_removal_mode 0)
		)
		(polygon
			(pts
				(arc
					(start 393.732766 -133.96214)
					(mid 393.747645 -133.926219)
					(end 393.783566 -133.91134)
				)
				(arc
					(start 394.964666 -133.91134)
					(mid 395.000587 -133.926219)
					(end 395.015466 -133.96214)
				)
				(arc
					(start 395.015466 -134.968488)
					(mid 395.000587 -135.004409)
					(end 394.964666 -135.019288)
				)
				(arc
					(start 393.783566 -135.019288)
					(mid 393.747645 -135.004409)
					(end 393.732766 -134.968488)
				)
			)
		)
	)
	(zone
		(layer "In1.Cu")
		(hatch none 0.5)
		(connect_pads
			(clearance 0)
		)
		(min_thickness 0.25)
		(keepout
			(tracks not_allowed)
			(vias allowed)
			(pads allowed)
			(copperpour not_allowed)
			(footprints allowed)
		)
		(placement
			(enabled no)
			(sheetname "")
		)
		(fill
			(thermal_gap 0.5)
			(thermal_bridge_width 0.5)
			(island_removal_mode 0)
		)
		(polygon
			(pts
				(arc
					(start 41.89984 -29.205936)
					(mid 41.884961 -29.241857)
					(end 41.84904 -29.256736)
				)
				(arc
					(start 40.61714 -29.256736)
					(mid 40.581219 -29.241857)
					(end 40.56634 -29.205936)
				)
				(arc
					(start 40.56634 -28.174188)
					(mid 40.581219 -28.138267)
					(end 40.61714 -28.123388)
				)
				(arc
					(start 41.84904 -28.123388)
					(mid 41.884961 -28.138267)
					(end 41.89984 -28.174188)
				)
			)
		)
	)
	(zone
		(layer "In1.Cu")
		(hatch none 0.5)
		(connect_pads
			(clearance 0)
		)
		(min_thickness 0.25)
		(keepout
			(tracks not_allowed)
			(vias allowed)
			(pads allowed)
			(copperpour not_allowed)
			(footprints allowed)
		)
		(placement
			(enabled no)
			(sheetname "")
		)
		(fill
			(thermal_gap 0.5)
			(thermal_bridge_width 0.5)
			(island_removal_mode 0)
		)
		(polygon
			(pts
				(arc
					(start 418.456618 -343.533222)
					(mid 418.420697 -343.548101)
					(end 418.405818 -343.584022)
				)
				(arc
					(start 418.405818 -344.320622)
					(mid 418.420697 -344.356543)
					(end 418.456618 -344.371422)
				)
				(xy 418.700458 -344.371422) (xy 419.054788 -344.139012) (xy 419.410388 -344.371422)
				(arc
					(start 419.652958 -344.371422)
					(mid 419.688879 -344.356543)
					(end 419.703758 -344.320622)
				)
				(arc
					(start 419.703758 -343.584022)
					(mid 419.688879 -343.548101)
					(end 419.652958 -343.533222)
				)
				(xy 419.410388 -343.533222) (xy 419.053518 -343.765632) (xy 418.699188 -343.533222)
			)
		)
	)
	(zone
		(layer "In1.Cu")
		(hatch none 0.5)
		(connect_pads
			(clearance 0)
		)
		(min_thickness 0.25)
		(keepout
			(tracks not_allowed)
			(vias allowed)
			(pads allowed)
			(copperpour not_allowed)
			(footprints allowed)
		)
		(placement
			(enabled no)
			(sheetname "")
		)
		(fill
			(thermal_gap 0.5)
			(thermal_bridge_width 0.5)
			(island_removal_mode 0)
		)
		(polygon
			(pts
				(arc
					(start 2.790698 -388.724394)
					(mid 2.754777 -388.709515)
					(end 2.739898 -388.673594)
				)
				(arc
					(start 2.739898 -388.26694)
					(mid 2.754777 -388.231019)
					(end 2.790698 -388.21614)
				)
				(arc
					(start 3.193034 -388.21614)
					(mid 3.228955 -388.231019)
					(end 3.243834 -388.26694)
				)
				(arc
					(start 3.243834 -388.673594)
					(mid 3.228955 -388.709515)
					(end 3.193034 -388.724394)
				)
			)
		)
	)
	(zone
		(layer "In1.Cu")
		(hatch none 0.5)
		(connect_pads
			(clearance 0)
		)
		(min_thickness 0.25)
		(keepout
			(tracks not_allowed)
			(vias allowed)
			(pads allowed)
			(copperpour not_allowed)
			(footprints allowed)
		)
		(placement
			(enabled no)
			(sheetname "")
		)
		(fill
			(thermal_gap 0.5)
			(thermal_bridge_width 0.5)
			(island_removal_mode 0)
		)
		(polygon
			(pts
				(arc
					(start 314.442348 -132.741162)
					(mid 314.457227 -132.777083)
					(end 314.493148 -132.791962)
				)
				(arc
					(start 315.229748 -132.791962)
					(mid 315.265669 -132.777083)
					(end 315.280548 -132.741162)
				)
				(xy 315.280548 -132.497322) (xy 315.048138 -132.142992) (xy 315.280548 -131.787392)
				(arc
					(start 315.280548 -131.544822)
					(mid 315.265669 -131.508901)
					(end 315.229748 -131.494022)
				)
				(arc
					(start 314.493148 -131.494022)
					(mid 314.457227 -131.508901)
					(end 314.442348 -131.544822)
				)
				(xy 314.442348 -131.787392) (xy 314.674758 -132.144262) (xy 314.442348 -132.498592)
			)
		)
	)
	(zone
		(layer "In1.Cu")
		(hatch none 0.5)
		(connect_pads
			(clearance 0)
		)
		(min_thickness 0.25)
		(keepout
			(tracks not_allowed)
			(vias allowed)
			(pads allowed)
			(copperpour not_allowed)
			(footprints allowed)
		)
		(placement
			(enabled no)
			(sheetname "")
		)
		(fill
			(thermal_gap 0.5)
			(thermal_bridge_width 0.5)
			(island_removal_mode 0)
		)
		(polygon
			(pts
				(arc
					(start 374.131586 -343.533222)
					(mid 374.095665 -343.548101)
					(end 374.080786 -343.584022)
				)
				(arc
					(start 374.080786 -344.320622)
					(mid 374.095665 -344.356543)
					(end 374.131586 -344.371422)
				)
				(xy 374.375426 -344.371422) (xy 374.729756 -344.139012) (xy 375.085356 -344.371422)
				(arc
					(start 375.327926 -344.371422)
					(mid 375.363847 -344.356543)
					(end 375.378726 -344.320622)
				)
				(arc
					(start 375.378726 -343.584022)
					(mid 375.363847 -343.548101)
					(end 375.327926 -343.533222)
				)
				(xy 375.085356 -343.533222) (xy 374.728486 -343.765632) (xy 374.374156 -343.533222)
			)
		)
	)
	(zone
		(layer "In1.Cu")
		(hatch none 0.5)
		(connect_pads
			(clearance 0)
		)
		(min_thickness 0.25)
		(keepout
			(tracks not_allowed)
			(vias allowed)
			(pads allowed)
			(copperpour not_allowed)
			(footprints allowed)
		)
		(placement
			(enabled no)
			(sheetname "")
		)
		(fill
			(thermal_gap 0.5)
			(thermal_bridge_width 0.5)
			(island_removal_mode 0)
		)
		(polygon
			(pts
				(arc
					(start 442.199776 -29.205936)
					(mid 442.184897 -29.241857)
					(end 442.148976 -29.256736)
				)
				(arc
					(start 440.917076 -29.256736)
					(mid 440.881155 -29.241857)
					(end 440.866276 -29.205936)
				)
				(arc
					(start 440.866276 -28.174188)
					(mid 440.881155 -28.138267)
					(end 440.917076 -28.123388)
				)
				(arc
					(start 442.148976 -28.123388)
					(mid 442.184897 -28.138267)
					(end 442.199776 -28.174188)
				)
			)
		)
	)
	(zone
		(layer "In1.Cu")
		(hatch none 0.5)
		(connect_pads
			(clearance 0)
		)
		(min_thickness 0.25)
		(keepout
			(tracks not_allowed)
			(vias allowed)
			(pads allowed)
			(copperpour not_allowed)
			(footprints allowed)
		)
		(placement
			(enabled no)
			(sheetname "")
		)
		(fill
			(thermal_gap 0.5)
			(thermal_bridge_width 0.5)
			(island_removal_mode 0)
		)
		(polygon
			(pts
				(arc
					(start 34.711894 -355.825806)
					(mid 34.675973 -355.840685)
					(end 34.661094 -355.876606)
				)
				(arc
					(start 34.661094 -356.613206)
					(mid 34.675973 -356.649127)
					(end 34.711894 -356.664006)
				)
				(xy 34.955734 -356.664006) (xy 35.310064 -356.431596) (xy 35.665664 -356.664006)
				(arc
					(start 35.908234 -356.664006)
					(mid 35.944155 -356.649127)
					(end 35.959034 -356.613206)
				)
				(arc
					(start 35.959034 -355.876606)
					(mid 35.944155 -355.840685)
					(end 35.908234 -355.825806)
				)
				(xy 35.665664 -355.825806) (xy 35.308794 -356.058216) (xy 34.954464 -355.825806)
			)
		)
	)
	(zone
		(layer "In1.Cu")
		(hatch none 0.5)
		(connect_pads
			(clearance 0)
		)
		(min_thickness 0.25)
		(keepout
			(tracks not_allowed)
			(vias allowed)
			(pads allowed)
			(copperpour not_allowed)
			(footprints allowed)
		)
		(placement
			(enabled no)
			(sheetname "")
		)
		(fill
			(thermal_gap 0.5)
			(thermal_bridge_width 0.5)
			(island_removal_mode 0)
		)
		(polygon
			(pts
				(arc
					(start 268.419326 -135.06323)
					(mid 268.434205 -135.099151)
					(end 268.470126 -135.11403)
				)
				(arc
					(start 269.206726 -135.11403)
					(mid 269.242647 -135.099151)
					(end 269.257526 -135.06323)
				)
				(xy 269.257526 -134.81939) (xy 269.025116 -134.46506) (xy 269.257526 -134.10946)
				(arc
					(start 269.257526 -133.86689)
					(mid 269.242647 -133.830969)
					(end 269.206726 -133.81609)
				)
				(arc
					(start 268.470126 -133.81609)
					(mid 268.434205 -133.830969)
					(end 268.419326 -133.86689)
				)
				(xy 268.419326 -134.10946) (xy 268.651736 -134.46633) (xy 268.419326 -134.82066)
			)
		)
	)
	(zone
		(layer "In1.Cu")
		(hatch none 0.5)
		(connect_pads
			(clearance 0)
		)
		(min_thickness 0.25)
		(keepout
			(tracks not_allowed)
			(vias allowed)
			(pads allowed)
			(copperpour not_allowed)
			(footprints allowed)
		)
		(placement
			(enabled no)
			(sheetname "")
		)
		(fill
			(thermal_gap 0.5)
			(thermal_bridge_width 0.5)
			(island_removal_mode 0)
		)
		(polygon
			(pts
				(arc
					(start 390.19988 -32.805878)
					(mid 390.185001 -32.841799)
					(end 390.14908 -32.856678)
				)
				(arc
					(start 388.91718 -32.856678)
					(mid 388.881259 -32.841799)
					(end 388.86638 -32.805878)
				)
				(arc
					(start 388.86638 -31.77413)
					(mid 388.881259 -31.738209)
					(end 388.91718 -31.72333)
				)
				(arc
					(start 390.14908 -31.72333)
					(mid 390.185001 -31.738209)
					(end 390.19988 -31.77413)
				)
			)
		)
	)
	(zone
		(layer "In1.Cu")
		(hatch none 0.5)
		(connect_pads
			(clearance 0)
		)
		(min_thickness 0.25)
		(keepout
			(tracks not_allowed)
			(vias allowed)
			(pads allowed)
			(copperpour not_allowed)
			(footprints allowed)
		)
		(placement
			(enabled no)
			(sheetname "")
		)
		(fill
			(thermal_gap 0.5)
			(thermal_bridge_width 0.5)
			(island_removal_mode 0)
		)
		(polygon
			(pts
				(arc
					(start 399.55216 -125.558296)
					(mid 399.537281 -125.594217)
					(end 399.50136 -125.609096)
				)
				(arc
					(start 398.32026 -125.609096)
					(mid 398.284339 -125.594217)
					(end 398.26946 -125.558296)
				)
				(arc
					(start 398.26946 -124.551948)
					(mid 398.284339 -124.516027)
					(end 398.32026 -124.501148)
				)
				(arc
					(start 399.50136 -124.501148)
					(mid 399.537281 -124.516027)
					(end 399.55216 -124.551948)
				)
			)
		)
	)
	(zone
		(layer "In1.Cu")
		(hatch none 0.5)
		(connect_pads
			(clearance 0)
		)
		(min_thickness 0.25)
		(keepout
			(tracks not_allowed)
			(vias allowed)
			(pads allowed)
			(copperpour not_allowed)
			(footprints allowed)
		)
		(placement
			(enabled no)
			(sheetname "")
		)
		(fill
			(thermal_gap 0.5)
			(thermal_bridge_width 0.5)
			(island_removal_mode 0)
		)
		(polygon
			(pts
				(arc
					(start 162.020758 -349.679514)
					(mid 161.984837 -349.694393)
					(end 161.969958 -349.730314)
				)
				(arc
					(start 161.969958 -350.466914)
					(mid 161.984837 -350.502835)
					(end 162.020758 -350.517714)
				)
				(xy 162.264598 -350.517714) (xy 162.618928 -350.285304) (xy 162.974528 -350.517714)
				(arc
					(start 163.217098 -350.517714)
					(mid 163.253019 -350.502835)
					(end 163.267898 -350.466914)
				)
				(arc
					(start 163.267898 -349.730314)
					(mid 163.253019 -349.694393)
					(end 163.217098 -349.679514)
				)
				(xy 162.974528 -349.679514) (xy 162.617658 -349.911924) (xy 162.263328 -349.679514)
			)
		)
	)
	(zone
		(layer "In1.Cu")
		(hatch none 0.5)
		(connect_pads
			(clearance 0)
		)
		(min_thickness 0.25)
		(keepout
			(tracks not_allowed)
			(vias allowed)
			(pads allowed)
			(copperpour not_allowed)
			(footprints allowed)
		)
		(placement
			(enabled no)
			(sheetname "")
		)
		(fill
			(thermal_gap 0.5)
			(thermal_bridge_width 0.5)
			(island_removal_mode 0)
		)
		(polygon
			(pts
				(arc
					(start 386.567426 -355.825806)
					(mid 386.531505 -355.840685)
					(end 386.516626 -355.876606)
				)
				(arc
					(start 386.516626 -356.613206)
					(mid 386.531505 -356.649127)
					(end 386.567426 -356.664006)
				)
				(xy 386.811266 -356.664006) (xy 387.165596 -356.431596) (xy 387.521196 -356.664006)
				(arc
					(start 387.763766 -356.664006)
					(mid 387.799687 -356.649127)
					(end 387.814566 -356.613206)
				)
				(arc
					(start 387.814566 -355.876606)
					(mid 387.799687 -355.840685)
					(end 387.763766 -355.825806)
				)
				(xy 387.521196 -355.825806) (xy 387.164326 -356.058216) (xy 386.809996 -355.825806)
			)
		)
	)
	(zone
		(layer "In1.Cu")
		(hatch none 0.5)
		(connect_pads
			(clearance 0)
		)
		(min_thickness 0.25)
		(keepout
			(tracks not_allowed)
			(vias allowed)
			(pads allowed)
			(copperpour not_allowed)
			(footprints allowed)
		)
		(placement
			(enabled no)
			(sheetname "")
		)
		(fill
			(thermal_gap 0.5)
			(thermal_bridge_width 0.5)
			(island_removal_mode 0)
		)
		(polygon
			(pts
				(arc
					(start 184.147714 -146.151854)
					(mid 184.162593 -146.115933)
					(end 184.198514 -146.101054)
				)
				(arc
					(start 185.379614 -146.101054)
					(mid 185.415535 -146.115933)
					(end 185.430414 -146.151854)
				)
				(arc
					(start 185.430414 -147.158202)
					(mid 185.415535 -147.194123)
					(end 185.379614 -147.209002)
				)
				(arc
					(start 184.198514 -147.209002)
					(mid 184.162593 -147.194123)
					(end 184.147714 -147.158202)
				)
			)
		)
	)
	(zone
		(layer "In1.Cu")
		(hatch none 0.5)
		(connect_pads
			(clearance 0)
		)
		(min_thickness 0.25)
		(keepout
			(tracks not_allowed)
			(vias allowed)
			(pads allowed)
			(copperpour not_allowed)
			(footprints allowed)
		)
		(placement
			(enabled no)
			(sheetname "")
		)
		(fill
			(thermal_gap 0.5)
			(thermal_bridge_width 0.5)
			(island_removal_mode 0)
		)
		(polygon
			(pts
				(arc
					(start 17.373346 -29.279596)
					(mid 17.388225 -29.315517)
					(end 17.424146 -29.330396)
				)
				(arc
					(start 18.160746 -29.330396)
					(mid 18.196667 -29.315517)
					(end 18.211546 -29.279596)
				)
				(xy 18.211546 -29.035756) (xy 17.979136 -28.681426) (xy 18.211546 -28.325826)
				(arc
					(start 18.211546 -28.083256)
					(mid 18.196667 -28.047335)
					(end 18.160746 -28.032456)
				)
				(arc
					(start 17.424146 -28.032456)
					(mid 17.388225 -28.047335)
					(end 17.373346 -28.083256)
				)
				(xy 17.373346 -28.325826) (xy 17.605756 -28.682696) (xy 17.373346 -29.037026)
			)
		)
	)
	(zone
		(layer "In1.Cu")
		(hatch none 0.5)
		(connect_pads
			(clearance 0)
		)
		(min_thickness 0.25)
		(keepout
			(tracks not_allowed)
			(vias allowed)
			(pads allowed)
			(copperpour not_allowed)
			(footprints allowed)
		)
		(placement
			(enabled no)
			(sheetname "")
		)
		(fill
			(thermal_gap 0.5)
			(thermal_bridge_width 0.5)
			(island_removal_mode 0)
		)
		(polygon
			(pts
				(arc
					(start 45.432726 -135.761984)
					(mid 45.447605 -135.726063)
					(end 45.483526 -135.711184)
				)
				(arc
					(start 46.664626 -135.711184)
					(mid 46.700547 -135.726063)
					(end 46.715426 -135.761984)
				)
				(arc
					(start 46.715426 -136.768332)
					(mid 46.700547 -136.804253)
					(end 46.664626 -136.819132)
				)
				(arc
					(start 45.483526 -136.819132)
					(mid 45.447605 -136.804253)
					(end 45.432726 -136.768332)
				)
			)
		)
	)
	(zone
		(layer "In1.Cu")
		(hatch none 0.5)
		(connect_pads
			(clearance 0)
		)
		(min_thickness 0.25)
		(keepout
			(tracks not_allowed)
			(vias allowed)
			(pads allowed)
			(copperpour not_allowed)
			(footprints allowed)
		)
		(placement
			(enabled no)
			(sheetname "")
		)
		(fill
			(thermal_gap 0.5)
			(thermal_bridge_width 0.5)
			(island_removal_mode 0)
		)
		(polygon
			(pts
				(arc
					(start 61.206888 -349.679514)
					(mid 61.170967 -349.694393)
					(end 61.156088 -349.730314)
				)
				(arc
					(start 61.156088 -350.466914)
					(mid 61.170967 -350.502835)
					(end 61.206888 -350.517714)
				)
				(xy 61.450728 -350.517714) (xy 61.805058 -350.285304) (xy 62.160658 -350.517714)
				(arc
					(start 62.403228 -350.517714)
					(mid 62.439149 -350.502835)
					(end 62.454028 -350.466914)
				)
				(arc
					(start 62.454028 -349.730314)
					(mid 62.439149 -349.694393)
					(end 62.403228 -349.679514)
				)
				(xy 62.160658 -349.679514) (xy 61.803788 -349.911924) (xy 61.449458 -349.679514)
			)
		)
	)
	(zone
		(layer "In1.Cu")
		(hatch none 0.5)
		(connect_pads
			(clearance 0)
		)
		(min_thickness 0.25)
		(keepout
			(tracks not_allowed)
			(vias allowed)
			(pads allowed)
			(copperpour not_allowed)
			(footprints allowed)
		)
		(placement
			(enabled no)
			(sheetname "")
		)
		(fill
			(thermal_gap 0.5)
			(thermal_bridge_width 0.5)
			(island_removal_mode 0)
		)
		(polygon
			(pts
				(arc
					(start 195.700142 -134.534656)
					(mid 195.715021 -134.570577)
					(end 195.750942 -134.585456)
				)
				(arc
					(start 196.487542 -134.585456)
					(mid 196.523463 -134.570577)
					(end 196.538342 -134.534656)
				)
				(xy 196.538342 -134.290816) (xy 196.305932 -133.936486) (xy 196.538342 -133.580886)
				(arc
					(start 196.538342 -133.338316)
					(mid 196.523463 -133.302395)
					(end 196.487542 -133.287516)
				)
				(arc
					(start 195.750942 -133.287516)
					(mid 195.715021 -133.302395)
					(end 195.700142 -133.338316)
				)
				(xy 195.700142 -133.580886) (xy 195.932552 -133.937756) (xy 195.700142 -134.292086)
			)
		)
	)
	(zone
		(layer "In1.Cu")
		(hatch none 0.5)
		(connect_pads
			(clearance 0)
		)
		(min_thickness 0.25)
		(keepout
			(tracks not_allowed)
			(vias allowed)
			(pads allowed)
			(copperpour not_allowed)
			(footprints allowed)
		)
		(placement
			(enabled no)
			(sheetname "")
		)
		(fill
			(thermal_gap 0.5)
			(thermal_bridge_width 0.5)
			(island_removal_mode 0)
		)
		(polygon
			(pts
				(arc
					(start 283.452062 -136.768332)
					(mid 283.437183 -136.804253)
					(end 283.401262 -136.819132)
				)
				(arc
					(start 282.220162 -136.819132)
					(mid 282.184241 -136.804253)
					(end 282.169362 -136.768332)
				)
				(arc
					(start 282.169362 -135.761984)
					(mid 282.184241 -135.726063)
					(end 282.220162 -135.711184)
				)
				(arc
					(start 283.401262 -135.711184)
					(mid 283.437183 -135.726063)
					(end 283.452062 -135.761984)
				)
			)
		)
	)
	(zone
		(layer "In1.Cu")
		(hatch none 0.5)
		(connect_pads
			(clearance 0)
		)
		(min_thickness 0.25)
		(keepout
			(tracks not_allowed)
			(vias allowed)
			(pads allowed)
			(copperpour not_allowed)
			(footprints allowed)
		)
		(placement
			(enabled no)
			(sheetname "")
		)
		(fill
			(thermal_gap 0.5)
			(thermal_bridge_width 0.5)
			(island_removal_mode 0)
		)
		(polygon
			(pts
				(arc
					(start 25.385014 -343.533222)
					(mid 25.349093 -343.548101)
					(end 25.334214 -343.584022)
				)
				(arc
					(start 25.334214 -344.320622)
					(mid 25.349093 -344.356543)
					(end 25.385014 -344.371422)
				)
				(xy 25.628854 -344.371422) (xy 25.983184 -344.139012) (xy 26.338784 -344.371422)
				(arc
					(start 26.581354 -344.371422)
					(mid 26.617275 -344.356543)
					(end 26.632154 -344.320622)
				)
				(arc
					(start 26.632154 -343.584022)
					(mid 26.617275 -343.548101)
					(end 26.581354 -343.533222)
				)
				(xy 26.338784 -343.533222) (xy 25.981914 -343.765632) (xy 25.627584 -343.533222)
			)
		)
	)
	(zone
		(layer "In1.Cu")
		(hatch none 0.5)
		(connect_pads
			(clearance 0)
		)
		(min_thickness 0.25)
		(keepout
			(tracks not_allowed)
			(vias allowed)
			(pads allowed)
			(copperpour not_allowed)
			(footprints allowed)
		)
		(placement
			(enabled no)
			(sheetname "")
		)
		(fill
			(thermal_gap 0.5)
			(thermal_bridge_width 0.5)
			(island_removal_mode 0)
		)
		(polygon
			(pts
				(arc
					(start 161.53257 -110.041944)
					(mid 161.547449 -110.006023)
					(end 161.58337 -109.991144)
				)
				(arc
					(start 162.76447 -109.991144)
					(mid 162.800391 -110.006023)
					(end 162.81527 -110.041944)
				)
				(arc
					(start 162.81527 -111.048292)
					(mid 162.800391 -111.084213)
					(end 162.76447 -111.099092)
				)
				(arc
					(start 161.58337 -111.099092)
					(mid 161.547449 -111.084213)
					(end 161.53257 -111.048292)
				)
			)
		)
	)
	(zone
		(layer "In1.Cu")
		(hatch none 0.5)
		(connect_pads
			(clearance 0)
		)
		(min_thickness 0.25)
		(keepout
			(tracks not_allowed)
			(vias allowed)
			(pads allowed)
			(copperpour not_allowed)
			(footprints allowed)
		)
		(placement
			(enabled no)
			(sheetname "")
		)
		(fill
			(thermal_gap 0.5)
			(thermal_bridge_width 0.5)
			(island_removal_mode 0)
		)
		(polygon
			(pts
				(arc
					(start 437.110378 -355.825806)
					(mid 437.074457 -355.840685)
					(end 437.059578 -355.876606)
				)
				(arc
					(start 437.059578 -356.613206)
					(mid 437.074457 -356.649127)
					(end 437.110378 -356.664006)
				)
				(xy 437.354218 -356.664006) (xy 437.708548 -356.431596) (xy 438.064148 -356.664006)
				(arc
					(start 438.306718 -356.664006)
					(mid 438.342639 -356.649127)
					(end 438.357518 -356.613206)
				)
				(arc
					(start 438.357518 -355.876606)
					(mid 438.342639 -355.840685)
					(end 438.306718 -355.825806)
				)
				(xy 438.064148 -355.825806) (xy 437.707278 -356.058216) (xy 437.352948 -355.825806)
			)
		)
	)
	(zone
		(layer "In1.Cu")
		(hatch none 0.5)
		(connect_pads
			(clearance 0)
		)
		(min_thickness 0.25)
		(keepout
			(tracks not_allowed)
			(vias allowed)
			(pads allowed)
			(copperpour not_allowed)
			(footprints allowed)
		)
		(placement
			(enabled no)
			(sheetname "")
		)
		(fill
			(thermal_gap 0.5)
			(thermal_bridge_width 0.5)
			(island_removal_mode 0)
		)
		(polygon
			(pts
				(arc
					(start 301.573184 -29.279596)
					(mid 301.588063 -29.315517)
					(end 301.623984 -29.330396)
				)
				(arc
					(start 302.360584 -29.330396)
					(mid 302.396505 -29.315517)
					(end 302.411384 -29.279596)
				)
				(xy 302.411384 -29.035756) (xy 302.178974 -28.681426) (xy 302.411384 -28.325826)
				(arc
					(start 302.411384 -28.083256)
					(mid 302.396505 -28.047335)
					(end 302.360584 -28.032456)
				)
				(arc
					(start 301.623984 -28.032456)
					(mid 301.588063 -28.047335)
					(end 301.573184 -28.083256)
				)
				(xy 301.573184 -28.325826) (xy 301.805594 -28.682696) (xy 301.573184 -29.037026)
			)
		)
	)
	(zone
		(layer "In1.Cu")
		(hatch none 0.5)
		(connect_pads
			(clearance 0)
		)
		(min_thickness 0.25)
		(keepout
			(tracks not_allowed)
			(vias allowed)
			(pads allowed)
			(copperpour not_allowed)
			(footprints allowed)
		)
		(placement
			(enabled no)
			(sheetname "")
		)
		(fill
			(thermal_gap 0.5)
			(thermal_bridge_width 0.5)
			(island_removal_mode 0)
		)
		(polygon
			(pts
				(arc
					(start 277.632668 -132.162042)
					(mid 277.647547 -132.126121)
					(end 277.683468 -132.111242)
				)
				(arc
					(start 278.864568 -132.111242)
					(mid 278.900489 -132.126121)
					(end 278.915368 -132.162042)
				)
				(arc
					(start 278.915368 -133.16839)
					(mid 278.900489 -133.204311)
					(end 278.864568 -133.21919)
				)
				(arc
					(start 277.683468 -133.21919)
					(mid 277.647547 -133.204311)
					(end 277.632668 -133.16839)
				)
			)
		)
	)
	(zone
		(layer "In1.Cu")
		(hatch none 0.5)
		(connect_pads
			(clearance 0)
		)
		(min_thickness 0.25)
		(keepout
			(tracks not_allowed)
			(vias allowed)
			(pads allowed)
			(copperpour not_allowed)
			(footprints allowed)
		)
		(placement
			(enabled no)
			(sheetname "")
		)
		(fill
			(thermal_gap 0.5)
			(thermal_bridge_width 0.5)
			(island_removal_mode 0)
		)
		(polygon
			(pts
				(arc
					(start 101.60254 -385.078224)
					(mid 101.639737 -384.988421)
					(end 101.72954 -384.951224)
				)
				(arc
					(start 101.930708 -384.951224)
					(mid 102.020511 -384.988421)
					(end 102.057708 -385.078224)
				)
				(arc
					(start 102.057708 -385.332224)
					(mid 102.020511 -385.422027)
					(end 101.930708 -385.459224)
				)
				(arc
					(start 101.72954 -385.459224)
					(mid 101.639737 -385.422027)
					(end 101.60254 -385.332224)
				)
			)
		)
	)
	(zone
		(layer "In1.Cu")
		(hatch none 0.5)
		(connect_pads
			(clearance 0)
		)
		(min_thickness 0.25)
		(keepout
			(tracks not_allowed)
			(vias allowed)
			(pads allowed)
			(copperpour not_allowed)
			(footprints allowed)
		)
		(placement
			(enabled no)
			(sheetname "")
		)
		(fill
			(thermal_gap 0.5)
			(thermal_bridge_width 0.5)
			(island_removal_mode 0)
		)
		(polygon
			(pts
				(arc
					(start 79.860648 -349.679514)
					(mid 79.824727 -349.694393)
					(end 79.809848 -349.730314)
				)
				(arc
					(start 79.809848 -350.466914)
					(mid 79.824727 -350.502835)
					(end 79.860648 -350.517714)
				)
				(xy 80.104488 -350.517714) (xy 80.458818 -350.285304) (xy 80.814418 -350.517714)
				(arc
					(start 81.056988 -350.517714)
					(mid 81.092909 -350.502835)
					(end 81.107788 -350.466914)
				)
				(arc
					(start 81.107788 -349.730314)
					(mid 81.092909 -349.694393)
					(end 81.056988 -349.679514)
				)
				(xy 80.814418 -349.679514) (xy 80.457548 -349.911924) (xy 80.103218 -349.679514)
			)
		)
	)
	(zone
		(layer "In1.Cu")
		(hatch none 0.5)
		(connect_pads
			(clearance 0)
		)
		(min_thickness 0.25)
		(keepout
			(tracks not_allowed)
			(vias allowed)
			(pads allowed)
			(copperpour not_allowed)
			(footprints allowed)
		)
		(placement
			(enabled no)
			(sheetname "")
		)
		(fill
			(thermal_gap 0.5)
			(thermal_bridge_width 0.5)
			(island_removal_mode 0)
		)
		(polygon
			(pts
				(arc
					(start 195.700142 -154.4447)
					(mid 195.715021 -154.480621)
					(end 195.750942 -154.4955)
				)
				(arc
					(start 196.487542 -154.4955)
					(mid 196.523463 -154.480621)
					(end 196.538342 -154.4447)
				)
				(xy 196.538342 -154.20086) (xy 196.305932 -153.84653) (xy 196.538342 -153.49093)
				(arc
					(start 196.538342 -153.24836)
					(mid 196.523463 -153.212439)
					(end 196.487542 -153.19756)
				)
				(arc
					(start 195.750942 -153.19756)
					(mid 195.715021 -153.212439)
					(end 195.700142 -153.24836)
				)
				(xy 195.700142 -153.49093) (xy 195.932552 -153.8478) (xy 195.700142 -154.20213)
			)
		)
	)
	(zone
		(layer "In1.Cu")
		(hatch none 0.5)
		(connect_pads
			(clearance 0)
		)
		(min_thickness 0.25)
		(keepout
			(tracks not_allowed)
			(vias allowed)
			(pads allowed)
			(copperpour not_allowed)
			(footprints allowed)
		)
		(placement
			(enabled no)
			(sheetname "")
		)
		(fill
			(thermal_gap 0.5)
			(thermal_bridge_width 0.5)
			(island_removal_mode 0)
		)
		(polygon
			(pts
				(arc
					(start 315.44641 -343.533222)
					(mid 315.410489 -343.548101)
					(end 315.39561 -343.584022)
				)
				(arc
					(start 315.39561 -344.320622)
					(mid 315.410489 -344.356543)
					(end 315.44641 -344.371422)
				)
				(xy 315.69025 -344.371422) (xy 316.04458 -344.139012) (xy 316.40018 -344.371422)
				(arc
					(start 316.64275 -344.371422)
					(mid 316.678671 -344.356543)
					(end 316.69355 -344.320622)
				)
				(arc
					(start 316.69355 -343.584022)
					(mid 316.678671 -343.548101)
					(end 316.64275 -343.533222)
				)
				(xy 316.40018 -343.533222) (xy 316.04331 -343.765632) (xy 315.68898 -343.533222)
			)
		)
	)
	(zone
		(layer "In1.Cu")
		(hatch none 0.5)
		(connect_pads
			(clearance 0)
		)
		(min_thickness 0.25)
		(keepout
			(tracks not_allowed)
			(vias allowed)
			(pads allowed)
			(copperpour not_allowed)
			(footprints allowed)
		)
		(placement
			(enabled no)
			(sheetname "")
		)
		(fill
			(thermal_gap 0.5)
			(thermal_bridge_width 0.5)
			(island_removal_mode 0)
		)
		(polygon
			(pts
				(arc
					(start 330.99121 -349.679514)
					(mid 330.955289 -349.694393)
					(end 330.94041 -349.730314)
				)
				(arc
					(start 330.94041 -350.466914)
					(mid 330.955289 -350.502835)
					(end 330.99121 -350.517714)
				)
				(xy 331.23505 -350.517714) (xy 331.58938 -350.285304) (xy 331.94498 -350.517714)
				(arc
					(start 332.18755 -350.517714)
					(mid 332.223471 -350.502835)
					(end 332.23835 -350.466914)
				)
				(arc
					(start 332.23835 -349.730314)
					(mid 332.223471 -349.694393)
					(end 332.18755 -349.679514)
				)
				(xy 331.94498 -349.679514) (xy 331.58811 -349.911924) (xy 331.23378 -349.679514)
			)
		)
	)
	(zone
		(layer "In1.Cu")
		(hatch none 0.5)
		(connect_pads
			(clearance 0)
		)
		(min_thickness 0.25)
		(keepout
			(tracks not_allowed)
			(vias allowed)
			(pads allowed)
			(copperpour not_allowed)
			(footprints allowed)
		)
		(placement
			(enabled no)
			(sheetname "")
		)
		(fill
			(thermal_gap 0.5)
			(thermal_bridge_width 0.5)
			(island_removal_mode 0)
		)
		(polygon
			(pts
				(arc
					(start 383.458466 -355.825806)
					(mid 383.422545 -355.840685)
					(end 383.407666 -355.876606)
				)
				(arc
					(start 383.407666 -356.613206)
					(mid 383.422545 -356.649127)
					(end 383.458466 -356.664006)
				)
				(xy 383.702306 -356.664006) (xy 384.056636 -356.431596) (xy 384.412236 -356.664006)
				(arc
					(start 384.654806 -356.664006)
					(mid 384.690727 -356.649127)
					(end 384.705606 -356.613206)
				)
				(arc
					(start 384.705606 -355.876606)
					(mid 384.690727 -355.840685)
					(end 384.654806 -355.825806)
				)
				(xy 384.412236 -355.825806) (xy 384.055366 -356.058216) (xy 383.701036 -355.825806)
			)
		)
	)
	(zone
		(layer "In1.Cu")
		(hatch none 0.5)
		(connect_pads
			(clearance 0)
		)
		(min_thickness 0.25)
		(keepout
			(tracks not_allowed)
			(vias allowed)
			(pads allowed)
			(copperpour not_allowed)
			(footprints allowed)
		)
		(placement
			(enabled no)
			(sheetname "")
		)
		(fill
			(thermal_gap 0.5)
			(thermal_bridge_width 0.5)
			(island_removal_mode 0)
		)
		(polygon
			(pts
				(arc
					(start 452.696072 -207.643984)
					(mid 452.710951 -207.608063)
					(end 452.746872 -207.593184)
				)
				(arc
					(start 453.25411 -207.593184)
					(mid 453.290031 -207.608063)
					(end 453.30491 -207.643984)
				)
				(arc
					(start 453.30491 -208.252822)
					(mid 453.290031 -208.288743)
					(end 453.25411 -208.303622)
				)
				(arc
					(start 452.746872 -208.303622)
					(mid 452.710951 -208.288743)
					(end 452.696072 -208.252822)
				)
			)
		)
	)
	(zone
		(layer "In1.Cu")
		(hatch none 0.5)
		(connect_pads
			(clearance 0)
		)
		(min_thickness 0.25)
		(keepout
			(tracks not_allowed)
			(vias allowed)
			(pads allowed)
			(copperpour not_allowed)
			(footprints allowed)
		)
		(placement
			(enabled no)
			(sheetname "")
		)
		(fill
			(thermal_gap 0.5)
			(thermal_bridge_width 0.5)
			(island_removal_mode 0)
		)
		(polygon
			(pts
				(arc
					(start 324.77329 -349.679514)
					(mid 324.737369 -349.694393)
					(end 324.72249 -349.730314)
				)
				(arc
					(start 324.72249 -350.466914)
					(mid 324.737369 -350.502835)
					(end 324.77329 -350.517714)
				)
				(xy 325.01713 -350.517714) (xy 325.37146 -350.285304) (xy 325.72706 -350.517714)
				(arc
					(start 325.96963 -350.517714)
					(mid 326.005551 -350.502835)
					(end 326.02043 -350.466914)
				)
				(arc
					(start 326.02043 -349.730314)
					(mid 326.005551 -349.694393)
					(end 325.96963 -349.679514)
				)
				(xy 325.72706 -349.679514) (xy 325.37019 -349.911924) (xy 325.01586 -349.679514)
			)
		)
	)
	(zone
		(layer "In1.Cu")
		(hatch none 0.5)
		(connect_pads
			(clearance 0)
		)
		(min_thickness 0.25)
		(keepout
			(tracks not_allowed)
			(vias allowed)
			(pads allowed)
			(copperpour not_allowed)
			(footprints allowed)
		)
		(placement
			(enabled no)
			(sheetname "")
		)
		(fill
			(thermal_gap 0.5)
			(thermal_bridge_width 0.5)
			(island_removal_mode 0)
		)
		(polygon
			(pts
				(arc
					(start 327.573132 -29.279596)
					(mid 327.588011 -29.315517)
					(end 327.623932 -29.330396)
				)
				(arc
					(start 328.360532 -29.330396)
					(mid 328.396453 -29.315517)
					(end 328.411332 -29.279596)
				)
				(xy 328.411332 -29.035756) (xy 328.178922 -28.681426) (xy 328.411332 -28.325826)
				(arc
					(start 328.411332 -28.083256)
					(mid 328.396453 -28.047335)
					(end 328.360532 -28.032456)
				)
				(arc
					(start 327.623932 -28.032456)
					(mid 327.588011 -28.047335)
					(end 327.573132 -28.083256)
				)
				(xy 327.573132 -28.325826) (xy 327.805542 -28.682696) (xy 327.573132 -29.037026)
			)
		)
	)
	(zone
		(layer "In1.Cu")
		(hatch none 0.5)
		(connect_pads
			(clearance 0)
		)
		(min_thickness 0.25)
		(keepout
			(tracks not_allowed)
			(vias allowed)
			(pads allowed)
			(copperpour not_allowed)
			(footprints allowed)
		)
		(placement
			(enabled no)
			(sheetname "")
		)
		(fill
			(thermal_gap 0.5)
			(thermal_bridge_width 0.5)
			(island_removal_mode 0)
		)
		(polygon
			(pts
				(arc
					(start 15.899892 -34.605976)
					(mid 15.885013 -34.641897)
					(end 15.849092 -34.656776)
				)
				(arc
					(start 14.617192 -34.656776)
					(mid 14.581271 -34.641897)
					(end 14.566392 -34.605976)
				)
				(arc
					(start 14.566392 -33.574228)
					(mid 14.581271 -33.538307)
					(end 14.617192 -33.523428)
				)
				(arc
					(start 15.849092 -33.523428)
					(mid 15.885013 -33.538307)
					(end 15.899892 -33.574228)
				)
			)
		)
	)
	(zone
		(layer "In1.Cu")
		(hatch none 0.5)
		(connect_pads
			(clearance 0)
		)
		(min_thickness 0.25)
		(keepout
			(tracks not_allowed)
			(vias allowed)
			(pads allowed)
			(copperpour not_allowed)
			(footprints allowed)
		)
		(placement
			(enabled no)
			(sheetname "")
		)
		(fill
			(thermal_gap 0.5)
			(thermal_bridge_width 0.5)
			(island_removal_mode 0)
		)
		(polygon
			(pts
				(arc
					(start 416.199828 -31.006034)
					(mid 416.184949 -31.041955)
					(end 416.149028 -31.056834)
				)
				(arc
					(start 414.917128 -31.056834)
					(mid 414.881207 -31.041955)
					(end 414.866328 -31.006034)
				)
				(arc
					(start 414.866328 -29.974286)
					(mid 414.881207 -29.938365)
					(end 414.917128 -29.923486)
				)
				(arc
					(start 416.149028 -29.923486)
					(mid 416.184949 -29.938365)
					(end 416.199828 -29.974286)
				)
			)
		)
	)
	(zone
		(layer "In1.Cu")
		(hatch none 0.5)
		(connect_pads
			(clearance 0)
		)
		(min_thickness 0.25)
		(keepout
			(tracks not_allowed)
			(vias allowed)
			(pads allowed)
			(copperpour not_allowed)
			(footprints allowed)
		)
		(placement
			(enabled no)
			(sheetname "")
		)
		(fill
			(thermal_gap 0.5)
			(thermal_bridge_width 0.5)
			(island_removal_mode 0)
		)
		(polygon
			(pts
				(arc
					(start 20.015454 -31.086044)
					(mid 20.030333 -31.121965)
					(end 20.066254 -31.136844)
				)
				(arc
					(start 20.802854 -31.136844)
					(mid 20.838775 -31.121965)
					(end 20.853654 -31.086044)
				)
				(xy 20.853654 -30.842204) (xy 20.621244 -30.487874) (xy 20.853654 -30.132274)
				(arc
					(start 20.853654 -29.889704)
					(mid 20.838775 -29.853783)
					(end 20.802854 -29.838904)
				)
				(arc
					(start 20.066254 -29.838904)
					(mid 20.030333 -29.853783)
					(end 20.015454 -29.889704)
				)
				(xy 20.015454 -30.132274) (xy 20.247864 -30.489144) (xy 20.015454 -30.843474)
			)
		)
	)
	(zone
		(layer "In1.Cu")
		(hatch none 0.5)
		(connect_pads
			(clearance 0)
		)
		(min_thickness 0.25)
		(keepout
			(tracks not_allowed)
			(vias allowed)
			(pads allowed)
			(copperpour not_allowed)
			(footprints allowed)
		)
		(placement
			(enabled no)
			(sheetname "")
		)
		(fill
			(thermal_gap 0.5)
			(thermal_bridge_width 0.5)
			(island_removal_mode 0)
		)
		(polygon
			(pts
				(arc
					(start 286.385508 -349.679514)
					(mid 286.349587 -349.694393)
					(end 286.334708 -349.730314)
				)
				(arc
					(start 286.334708 -350.466914)
					(mid 286.349587 -350.502835)
					(end 286.385508 -350.517714)
				)
				(xy 286.629348 -350.517714) (xy 286.983678 -350.285304) (xy 287.339278 -350.517714)
				(arc
					(start 287.581848 -350.517714)
					(mid 287.617769 -350.502835)
					(end 287.632648 -350.466914)
				)
				(arc
					(start 287.632648 -349.730314)
					(mid 287.617769 -349.694393)
					(end 287.581848 -349.679514)
				)
				(xy 287.339278 -349.679514) (xy 286.982408 -349.911924) (xy 286.628078 -349.679514)
			)
		)
	)
	(zone
		(layer "In1.Cu")
		(hatch none 0.5)
		(connect_pads
			(clearance 0)
		)
		(min_thickness 0.25)
		(keepout
			(tracks not_allowed)
			(vias allowed)
			(pads allowed)
			(copperpour not_allowed)
			(footprints allowed)
		)
		(placement
			(enabled no)
			(sheetname "")
		)
		(fill
			(thermal_gap 0.5)
			(thermal_bridge_width 0.5)
			(island_removal_mode 0)
		)
		(polygon
			(pts
				(arc
					(start 436.329836 -33.574228)
					(mid 436.344715 -33.538307)
					(end 436.380636 -33.523428)
				)
				(arc
					(start 437.612536 -33.523428)
					(mid 437.648457 -33.538307)
					(end 437.663336 -33.574228)
				)
				(arc
					(start 437.663336 -34.605976)
					(mid 437.648457 -34.641897)
					(end 437.612536 -34.656776)
				)
				(arc
					(start 436.380636 -34.656776)
					(mid 436.344715 -34.641897)
					(end 436.329836 -34.605976)
				)
			)
		)
	)
	(zone
		(layer "In1.Cu")
		(hatch none 0.5)
		(connect_pads
			(clearance 0)
		)
		(min_thickness 0.25)
		(keepout
			(tracks not_allowed)
			(vias allowed)
			(pads allowed)
			(copperpour not_allowed)
			(footprints allowed)
		)
		(placement
			(enabled no)
			(sheetname "")
		)
		(fill
			(thermal_gap 0.5)
			(thermal_bridge_width 0.5)
			(island_removal_mode 0)
		)
		(polygon
			(pts
				(arc
					(start 430.542446 -132.741162)
					(mid 430.557325 -132.777083)
					(end 430.593246 -132.791962)
				)
				(arc
					(start 431.329846 -132.791962)
					(mid 431.365767 -132.777083)
					(end 431.380646 -132.741162)
				)
				(xy 431.380646 -132.497322) (xy 431.148236 -132.142992) (xy 431.380646 -131.787392)
				(arc
					(start 431.380646 -131.544822)
					(mid 431.365767 -131.508901)
					(end 431.329846 -131.494022)
				)
				(arc
					(start 430.593246 -131.494022)
					(mid 430.557325 -131.508901)
					(end 430.542446 -131.544822)
				)
				(xy 430.542446 -131.787392) (xy 430.774856 -132.144262) (xy 430.542446 -132.498592)
			)
		)
	)
	(zone
		(layer "In1.Cu")
		(hatch none 0.5)
		(connect_pads
			(clearance 0)
		)
		(min_thickness 0.25)
		(keepout
			(tracks not_allowed)
			(vias allowed)
			(pads allowed)
			(copperpour not_allowed)
			(footprints allowed)
		)
		(placement
			(enabled no)
			(sheetname "")
		)
		(fill
			(thermal_gap 0.5)
			(thermal_bridge_width 0.5)
			(island_removal_mode 0)
		)
		(polygon
			(pts
				(arc
					(start 446.315338 -31.086044)
					(mid 446.330217 -31.121965)
					(end 446.366138 -31.136844)
				)
				(arc
					(start 447.102738 -31.136844)
					(mid 447.138659 -31.121965)
					(end 447.153538 -31.086044)
				)
				(xy 447.153538 -30.842204) (xy 446.921128 -30.487874) (xy 447.153538 -30.132274)
				(arc
					(start 447.153538 -29.889704)
					(mid 447.138659 -29.853783)
					(end 447.102738 -29.838904)
				)
				(arc
					(start 446.366138 -29.838904)
					(mid 446.330217 -29.853783)
					(end 446.315338 -29.889704)
				)
				(xy 446.315338 -30.132274) (xy 446.547748 -30.489144) (xy 446.315338 -30.843474)
			)
		)
	)
	(zone
		(layer "In1.Cu")
		(hatch none 0.5)
		(connect_pads
			(clearance 0)
		)
		(min_thickness 0.25)
		(keepout
			(tracks not_allowed)
			(vias allowed)
			(pads allowed)
			(copperpour not_allowed)
			(footprints allowed)
		)
		(placement
			(enabled no)
			(sheetname "")
		)
		(fill
			(thermal_gap 0.5)
			(thermal_bridge_width 0.5)
			(island_removal_mode 0)
		)
		(polygon
			(pts
				(arc
					(start 51.25212 -105.648252)
					(mid 51.237241 -105.684173)
					(end 51.20132 -105.699052)
				)
				(arc
					(start 50.02022 -105.699052)
					(mid 49.984299 -105.684173)
					(end 49.96942 -105.648252)
				)
				(arc
					(start 49.96942 -104.641904)
					(mid 49.984299 -104.605983)
					(end 50.02022 -104.591104)
				)
				(arc
					(start 51.20132 -104.591104)
					(mid 51.237241 -104.605983)
					(end 51.25212 -104.641904)
				)
			)
		)
	)
	(zone
		(layer "In1.Cu")
		(hatch none 0.5)
		(connect_pads
			(clearance 0)
		)
		(min_thickness 0.25)
		(keepout
			(tracks not_allowed)
			(vias allowed)
			(pads allowed)
			(copperpour not_allowed)
			(footprints allowed)
		)
		(placement
			(enabled no)
			(sheetname "")
		)
		(fill
			(thermal_gap 0.5)
			(thermal_bridge_width 0.5)
			(island_removal_mode 0)
		)
		(polygon
			(pts
				(arc
					(start 374.131586 -355.825806)
					(mid 374.095665 -355.840685)
					(end 374.080786 -355.876606)
				)
				(arc
					(start 374.080786 -356.613206)
					(mid 374.095665 -356.649127)
					(end 374.131586 -356.664006)
				)
				(xy 374.375426 -356.664006) (xy 374.729756 -356.431596) (xy 375.085356 -356.664006)
				(arc
					(start 375.327926 -356.664006)
					(mid 375.363847 -356.649127)
					(end 375.378726 -356.613206)
				)
				(arc
					(start 375.378726 -355.876606)
					(mid 375.363847 -355.840685)
					(end 375.327926 -355.825806)
				)
				(xy 375.085356 -355.825806) (xy 374.728486 -356.058216) (xy 374.374156 -355.825806)
			)
		)
	)
	(zone
		(layer "In1.Cu")
		(hatch none 0.5)
		(connect_pads
			(clearance 0)
		)
		(min_thickness 0.25)
		(keepout
			(tracks not_allowed)
			(vias allowed)
			(pads allowed)
			(copperpour not_allowed)
			(footprints allowed)
		)
		(placement
			(enabled no)
			(sheetname "")
		)
		(fill
			(thermal_gap 0.5)
			(thermal_bridge_width 0.5)
			(island_removal_mode 0)
		)
		(polygon
			(pts
				(arc
					(start 234.885484 -89.536524)
					(mid 234.900363 -89.500603)
					(end 234.936284 -89.485724)
				)
				(arc
					(start 235.600494 -89.485724)
					(mid 235.636415 -89.500603)
					(end 235.651294 -89.536524)
				)
				(arc
					(start 235.651294 -90.174826)
					(mid 235.636415 -90.210747)
					(end 235.600494 -90.225626)
				)
				(arc
					(start 234.936284 -90.225626)
					(mid 234.900363 -90.210747)
					(end 234.885484 -90.174826)
				)
			)
		)
	)
	(zone
		(layer "In1.Cu")
		(hatch none 0.5)
		(connect_pads
			(clearance 0)
		)
		(min_thickness 0.25)
		(keepout
			(tracks not_allowed)
			(vias allowed)
			(pads allowed)
			(copperpour not_allowed)
			(footprints allowed)
		)
		(placement
			(enabled no)
			(sheetname "")
		)
		(fill
			(thermal_gap 0.5)
			(thermal_bridge_width 0.5)
			(island_removal_mode 0)
		)
		(polygon
			(pts
				(arc
					(start 393.732766 -111.841788)
					(mid 393.747645 -111.805867)
					(end 393.783566 -111.790988)
				)
				(arc
					(start 394.964666 -111.790988)
					(mid 395.000587 -111.805867)
					(end 395.015466 -111.841788)
				)
				(arc
					(start 395.015466 -112.848136)
					(mid 395.000587 -112.884057)
					(end 394.964666 -112.898936)
				)
				(arc
					(start 393.783566 -112.898936)
					(mid 393.747645 -112.884057)
					(end 393.732766 -112.848136)
				)
			)
		)
	)
	(zone
		(layer "In1.Cu")
		(hatch none 0.5)
		(connect_pads
			(clearance 0)
		)
		(min_thickness 0.25)
		(keepout
			(tracks not_allowed)
			(vias allowed)
			(pads allowed)
			(copperpour not_allowed)
			(footprints allowed)
		)
		(placement
			(enabled no)
			(sheetname "")
		)
		(fill
			(thermal_gap 0.5)
			(thermal_bridge_width 0.5)
			(island_removal_mode 0)
		)
		(polygon
			(pts
				(arc
					(start 189.967108 -145.358104)
					(mid 189.952229 -145.394025)
					(end 189.916308 -145.408904)
				)
				(arc
					(start 188.735208 -145.408904)
					(mid 188.699287 -145.394025)
					(end 188.684408 -145.358104)
				)
				(arc
					(start 188.684408 -144.351756)
					(mid 188.699287 -144.315835)
					(end 188.735208 -144.300956)
				)
				(arc
					(start 189.916308 -144.300956)
					(mid 189.952229 -144.315835)
					(end 189.967108 -144.351756)
				)
			)
		)
	)
	(zone
		(layer "In1.Cu")
		(hatch none 0.5)
		(connect_pads
			(clearance 0)
		)
		(min_thickness 0.25)
		(keepout
			(tracks not_allowed)
			(vias allowed)
			(pads allowed)
			(copperpour not_allowed)
			(footprints allowed)
		)
		(placement
			(enabled no)
			(sheetname "")
		)
		(fill
			(thermal_gap 0.5)
			(thermal_bridge_width 0.5)
			(island_removal_mode 0)
		)
		(polygon
			(pts
				(arc
					(start 416.199828 -29.205936)
					(mid 416.184949 -29.241857)
					(end 416.149028 -29.256736)
				)
				(arc
					(start 414.917128 -29.256736)
					(mid 414.881207 -29.241857)
					(end 414.866328 -29.205936)
				)
				(arc
					(start 414.866328 -28.174188)
					(mid 414.881207 -28.138267)
					(end 414.917128 -28.123388)
				)
				(arc
					(start 416.149028 -28.123388)
					(mid 416.184949 -28.138267)
					(end 416.199828 -28.174188)
				)
			)
		)
	)
	(zone
		(layer "In1.Cu")
		(hatch none 0.5)
		(connect_pads
			(clearance 0)
		)
		(min_thickness 0.25)
		(keepout
			(tracks not_allowed)
			(vias allowed)
			(pads allowed)
			(copperpour not_allowed)
			(footprints allowed)
		)
		(placement
			(enabled no)
			(sheetname "")
		)
		(fill
			(thermal_gap 0.5)
			(thermal_bridge_width 0.5)
			(island_removal_mode 0)
		)
		(polygon
			(pts
				(arc
					(start 434.001418 -343.533222)
					(mid 433.965497 -343.548101)
					(end 433.950618 -343.584022)
				)
				(arc
					(start 433.950618 -344.320622)
					(mid 433.965497 -344.356543)
					(end 434.001418 -344.371422)
				)
				(xy 434.245258 -344.371422) (xy 434.599588 -344.139012) (xy 434.955188 -344.371422)
				(arc
					(start 435.197758 -344.371422)
					(mid 435.233679 -344.356543)
					(end 435.248558 -344.320622)
				)
				(arc
					(start 435.248558 -343.584022)
					(mid 435.233679 -343.548101)
					(end 435.197758 -343.533222)
				)
				(xy 434.955188 -343.533222) (xy 434.598318 -343.765632) (xy 434.243988 -343.533222)
			)
		)
	)
	(zone
		(layer "In1.Cu")
		(hatch none 0.5)
		(connect_pads
			(clearance 0)
		)
		(min_thickness 0.25)
		(keepout
			(tracks not_allowed)
			(vias allowed)
			(pads allowed)
			(copperpour not_allowed)
			(footprints allowed)
		)
		(placement
			(enabled no)
			(sheetname "")
		)
		(fill
			(thermal_gap 0.5)
			(thermal_bridge_width 0.5)
			(island_removal_mode 0)
		)
		(polygon
			(pts
				(arc
					(start 86.078568 -355.825806)
					(mid 86.042647 -355.840685)
					(end 86.027768 -355.876606)
				)
				(arc
					(start 86.027768 -356.613206)
					(mid 86.042647 -356.649127)
					(end 86.078568 -356.664006)
				)
				(xy 86.322408 -356.664006) (xy 86.676738 -356.431596) (xy 87.032338 -356.664006)
				(arc
					(start 87.274908 -356.664006)
					(mid 87.310829 -356.649127)
					(end 87.325708 -356.613206)
				)
				(arc
					(start 87.325708 -355.876606)
					(mid 87.310829 -355.840685)
					(end 87.274908 -355.825806)
				)
				(xy 87.032338 -355.825806) (xy 86.675468 -356.058216) (xy 86.321138 -355.825806)
			)
		)
	)
	(zone
		(layer "In1.Cu")
		(hatch none 0.5)
		(connect_pads
			(clearance 0)
		)
		(min_thickness 0.25)
		(keepout
			(tracks not_allowed)
			(vias allowed)
			(pads allowed)
			(copperpour not_allowed)
			(footprints allowed)
		)
		(placement
			(enabled no)
			(sheetname "")
		)
		(fill
			(thermal_gap 0.5)
			(thermal_bridge_width 0.5)
			(island_removal_mode 0)
		)
		(polygon
			(pts
				(arc
					(start 139.677394 -349.679514)
					(mid 139.641473 -349.694393)
					(end 139.626594 -349.730314)
				)
				(arc
					(start 139.626594 -350.466914)
					(mid 139.641473 -350.502835)
					(end 139.677394 -350.517714)
				)
				(xy 139.921234 -350.517714) (xy 140.275564 -350.285304) (xy 140.631164 -350.517714)
				(arc
					(start 140.873734 -350.517714)
					(mid 140.909655 -350.502835)
					(end 140.924534 -350.466914)
				)
				(arc
					(start 140.924534 -349.730314)
					(mid 140.909655 -349.694393)
					(end 140.873734 -349.679514)
				)
				(xy 140.631164 -349.679514) (xy 140.274294 -349.911924) (xy 139.919964 -349.679514)
			)
		)
	)
	(zone
		(layer "In1.Cu")
		(hatch none 0.5)
		(connect_pads
			(clearance 0)
		)
		(min_thickness 0.25)
		(keepout
			(tracks not_allowed)
			(vias allowed)
			(pads allowed)
			(copperpour not_allowed)
			(footprints allowed)
		)
		(placement
			(enabled no)
			(sheetname "")
		)
		(fill
			(thermal_gap 0.5)
			(thermal_bridge_width 0.5)
			(island_removal_mode 0)
		)
		(polygon
			(pts
				(arc
					(start 93.899736 -34.605976)
					(mid 93.884857 -34.641897)
					(end 93.848936 -34.656776)
				)
				(arc
					(start 92.617036 -34.656776)
					(mid 92.581115 -34.641897)
					(end 92.566236 -34.605976)
				)
				(arc
					(start 92.566236 -33.574228)
					(mid 92.581115 -33.538307)
					(end 92.617036 -33.523428)
				)
				(arc
					(start 93.848936 -33.523428)
					(mid 93.884857 -33.538307)
					(end 93.899736 -33.574228)
				)
			)
		)
	)
	(zone
		(layer "In1.Cu")
		(hatch none 0.5)
		(connect_pads
			(clearance 0)
		)
		(min_thickness 0.25)
		(keepout
			(tracks not_allowed)
			(vias allowed)
			(pads allowed)
			(copperpour not_allowed)
			(footprints allowed)
		)
		(placement
			(enabled no)
			(sheetname "")
		)
		(fill
			(thermal_gap 0.5)
			(thermal_bridge_width 0.5)
			(island_removal_mode 0)
		)
		(polygon
			(pts
				(arc
					(start 318.55537 -343.533222)
					(mid 318.519449 -343.548101)
					(end 318.50457 -343.584022)
				)
				(arc
					(start 318.50457 -344.320622)
					(mid 318.519449 -344.356543)
					(end 318.55537 -344.371422)
				)
				(xy 318.79921 -344.371422) (xy 319.15354 -344.139012) (xy 319.50914 -344.371422)
				(arc
					(start 319.75171 -344.371422)
					(mid 319.787631 -344.356543)
					(end 319.80251 -344.320622)
				)
				(arc
					(start 319.80251 -343.584022)
					(mid 319.787631 -343.548101)
					(end 319.75171 -343.533222)
				)
				(xy 319.50914 -343.533222) (xy 319.15227 -343.765632) (xy 318.79794 -343.533222)
			)
		)
	)
	(zone
		(layer "In1.Cu")
		(hatch none 0.5)
		(connect_pads
			(clearance 0)
		)
		(min_thickness 0.25)
		(keepout
			(tracks not_allowed)
			(vias allowed)
			(pads allowed)
			(copperpour not_allowed)
			(footprints allowed)
		)
		(placement
			(enabled no)
			(sheetname "")
		)
		(fill
			(thermal_gap 0.5)
			(thermal_bridge_width 0.5)
			(island_removal_mode 0)
		)
		(polygon
			(pts
				(arc
					(start 380.349506 -343.533222)
					(mid 380.313585 -343.548101)
					(end 380.298706 -343.584022)
				)
				(arc
					(start 380.298706 -344.320622)
					(mid 380.313585 -344.356543)
					(end 380.349506 -344.371422)
				)
				(xy 380.593346 -344.371422) (xy 380.947676 -344.139012) (xy 381.303276 -344.371422)
				(arc
					(start 381.545846 -344.371422)
					(mid 381.581767 -344.356543)
					(end 381.596646 -344.320622)
				)
				(arc
					(start 381.596646 -343.584022)
					(mid 381.581767 -343.548101)
					(end 381.545846 -343.533222)
				)
				(xy 381.303276 -343.533222) (xy 380.946406 -343.765632) (xy 380.592076 -343.533222)
			)
		)
	)
	(zone
		(layer "In1.Cu")
		(hatch none 0.5)
		(connect_pads
			(clearance 0)
		)
		(min_thickness 0.25)
		(keepout
			(tracks not_allowed)
			(vias allowed)
			(pads allowed)
			(copperpour not_allowed)
			(footprints allowed)
		)
		(placement
			(enabled no)
			(sheetname "")
		)
		(fill
			(thermal_gap 0.5)
			(thermal_bridge_width 0.5)
			(island_removal_mode 0)
		)
		(polygon
			(pts
				(arc
					(start 73.867264 -136.24814)
					(mid 73.852385 -136.284061)
					(end 73.816464 -136.29894)
				)
				(arc
					(start 72.635364 -136.29894)
					(mid 72.599443 -136.284061)
					(end 72.584564 -136.24814)
				)
				(arc
					(start 72.584564 -135.241792)
					(mid 72.599443 -135.205871)
					(end 72.635364 -135.190992)
				)
				(arc
					(start 73.816464 -135.190992)
					(mid 73.852385 -135.205871)
					(end 73.867264 -135.241792)
				)
			)
		)
	)
	(zone
		(layer "In1.Cu")
		(hatch none 0.5)
		(connect_pads
			(clearance 0)
		)
		(min_thickness 0.25)
		(keepout
			(tracks not_allowed)
			(vias allowed)
			(pads allowed)
			(copperpour not_allowed)
			(footprints allowed)
		)
		(placement
			(enabled no)
			(sheetname "")
		)
		(fill
			(thermal_gap 0.5)
			(thermal_bridge_width 0.5)
			(island_removal_mode 0)
		)
		(polygon
			(pts
				(arc
					(start 268.229842 -28.174188)
					(mid 268.244721 -28.138267)
					(end 268.280642 -28.123388)
				)
				(arc
					(start 269.512542 -28.123388)
					(mid 269.548463 -28.138267)
					(end 269.563342 -28.174188)
				)
				(arc
					(start 269.563342 -29.205936)
					(mid 269.548463 -29.241857)
					(end 269.512542 -29.256736)
				)
				(arc
					(start 268.280642 -29.256736)
					(mid 268.244721 -29.241857)
					(end 268.229842 -29.205936)
				)
			)
		)
	)
	(zone
		(layer "In1.Cu")
		(hatch none 0.5)
		(connect_pads
			(clearance 0)
		)
		(min_thickness 0.25)
		(keepout
			(tracks not_allowed)
			(vias allowed)
			(pads allowed)
			(copperpour not_allowed)
			(footprints allowed)
		)
		(placement
			(enabled no)
			(sheetname "")
		)
		(fill
			(thermal_gap 0.5)
			(thermal_bridge_width 0.5)
			(island_removal_mode 0)
		)
		(polygon
			(pts
				(arc
					(start 277.632668 -137.561574)
					(mid 277.647547 -137.525653)
					(end 277.683468 -137.510774)
				)
				(arc
					(start 278.864568 -137.510774)
					(mid 278.900489 -137.525653)
					(end 278.915368 -137.561574)
				)
				(arc
					(start 278.915368 -138.567922)
					(mid 278.900489 -138.603843)
					(end 278.864568 -138.618722)
				)
				(arc
					(start 277.683468 -138.618722)
					(mid 277.647547 -138.603843)
					(end 277.632668 -138.567922)
				)
			)
		)
	)
	(zone
		(layer "In1.Cu")
		(hatch none 0.5)
		(connect_pads
			(clearance 0)
		)
		(min_thickness 0.25)
		(keepout
			(tracks not_allowed)
			(vias allowed)
			(pads allowed)
			(copperpour not_allowed)
			(footprints allowed)
		)
		(placement
			(enabled no)
			(sheetname "")
		)
		(fill
			(thermal_gap 0.5)
			(thermal_bridge_width 0.5)
			(island_removal_mode 0)
		)
		(polygon
			(pts
				(arc
					(start 268.419326 -123.853194)
					(mid 268.434205 -123.889115)
					(end 268.470126 -123.903994)
				)
				(arc
					(start 269.206726 -123.903994)
					(mid 269.242647 -123.889115)
					(end 269.257526 -123.853194)
				)
				(xy 269.257526 -123.609354) (xy 269.025116 -123.255024) (xy 269.257526 -122.899424)
				(arc
					(start 269.257526 -122.656854)
					(mid 269.242647 -122.620933)
					(end 269.206726 -122.606054)
				)
				(arc
					(start 268.470126 -122.606054)
					(mid 268.434205 -122.620933)
					(end 268.419326 -122.656854)
				)
				(xy 268.419326 -122.899424) (xy 268.651736 -123.256294) (xy 268.419326 -123.610624)
			)
		)
	)
	(zone
		(layer "In1.Cu")
		(hatch none 0.5)
		(connect_pads
			(clearance 0)
		)
		(min_thickness 0.25)
		(keepout
			(tracks not_allowed)
			(vias allowed)
			(pads allowed)
			(copperpour not_allowed)
			(footprints allowed)
		)
		(placement
			(enabled no)
			(sheetname "")
		)
		(fill
			(thermal_gap 0.5)
			(thermal_bridge_width 0.5)
			(island_removal_mode 0)
		)
		(polygon
			(pts
				(arc
					(start 391.673334 -29.279596)
					(mid 391.688213 -29.315517)
					(end 391.724134 -29.330396)
				)
				(arc
					(start 392.460734 -29.330396)
					(mid 392.496655 -29.315517)
					(end 392.511534 -29.279596)
				)
				(xy 392.511534 -29.035756) (xy 392.279124 -28.681426) (xy 392.511534 -28.325826)
				(arc
					(start 392.511534 -28.083256)
					(mid 392.496655 -28.047335)
					(end 392.460734 -28.032456)
				)
				(arc
					(start 391.724134 -28.032456)
					(mid 391.688213 -28.047335)
					(end 391.673334 -28.083256)
				)
				(xy 391.673334 -28.325826) (xy 391.905744 -28.682696) (xy 391.673334 -29.037026)
			)
		)
	)
	(zone
		(layer "In1.Cu")
		(hatch none 0.5)
		(connect_pads
			(clearance 0)
		)
		(min_thickness 0.25)
		(keepout
			(tracks not_allowed)
			(vias allowed)
			(pads allowed)
			(copperpour not_allowed)
			(footprints allowed)
		)
		(placement
			(enabled no)
			(sheetname "")
		)
		(fill
			(thermal_gap 0.5)
			(thermal_bridge_width 0.5)
			(island_removal_mode 0)
		)
		(polygon
			(pts
				(arc
					(start 73.867264 -117.838474)
					(mid 73.852385 -117.874395)
					(end 73.816464 -117.889274)
				)
				(arc
					(start 72.635364 -117.889274)
					(mid 72.599443 -117.874395)
					(end 72.584564 -117.838474)
				)
				(arc
					(start 72.584564 -116.832126)
					(mid 72.599443 -116.796205)
					(end 72.635364 -116.781326)
				)
				(arc
					(start 73.816464 -116.781326)
					(mid 73.852385 -116.796205)
					(end 73.867264 -116.832126)
				)
			)
		)
	)
	(zone
		(layer "In1.Cu")
		(hatch none 0.5)
		(connect_pads
			(clearance 0)
		)
		(min_thickness 0.25)
		(keepout
			(tracks not_allowed)
			(vias allowed)
			(pads allowed)
			(copperpour not_allowed)
			(footprints allowed)
		)
		(placement
			(enabled no)
			(sheetname "")
		)
		(fill
			(thermal_gap 0.5)
			(thermal_bridge_width 0.5)
			(island_removal_mode 0)
		)
		(polygon
			(pts
				(arc
					(start 337.20913 -349.679514)
					(mid 337.173209 -349.694393)
					(end 337.15833 -349.730314)
				)
				(arc
					(start 337.15833 -350.466914)
					(mid 337.173209 -350.502835)
					(end 337.20913 -350.517714)
				)
				(xy 337.45297 -350.517714) (xy 337.8073 -350.285304) (xy 338.1629 -350.517714)
				(arc
					(start 338.40547 -350.517714)
					(mid 338.441391 -350.502835)
					(end 338.45627 -350.466914)
				)
				(arc
					(start 338.45627 -349.730314)
					(mid 338.441391 -349.694393)
					(end 338.40547 -349.679514)
				)
				(xy 338.1629 -349.679514) (xy 337.80603 -349.911924) (xy 337.4517 -349.679514)
			)
		)
	)
	(zone
		(layer "In1.Cu")
		(hatch none 0.5)
		(connect_pads
			(clearance 0)
		)
		(min_thickness 0.25)
		(keepout
			(tracks not_allowed)
			(vias allowed)
			(pads allowed)
			(copperpour not_allowed)
			(footprints allowed)
		)
		(placement
			(enabled no)
			(sheetname "")
		)
		(fill
			(thermal_gap 0.5)
			(thermal_bridge_width 0.5)
			(island_removal_mode 0)
		)
		(polygon
			(pts
				(arc
					(start 300.247812 -120.431814)
					(mid 300.262691 -120.395893)
					(end 300.298612 -120.381014)
				)
				(arc
					(start 301.479712 -120.381014)
					(mid 301.515633 -120.395893)
					(end 301.530512 -120.431814)
				)
				(arc
					(start 301.530512 -121.438162)
					(mid 301.515633 -121.474083)
					(end 301.479712 -121.488962)
				)
				(arc
					(start 300.298612 -121.488962)
					(mid 300.262691 -121.474083)
					(end 300.247812 -121.438162)
				)
			)
		)
	)
	(zone
		(layer "In1.Cu")
		(hatch none 0.5)
		(connect_pads
			(clearance 0)
		)
		(min_thickness 0.25)
		(keepout
			(tracks not_allowed)
			(vias allowed)
			(pads allowed)
			(copperpour not_allowed)
			(footprints allowed)
		)
		(placement
			(enabled no)
			(sheetname "")
		)
		(fill
			(thermal_gap 0.5)
			(thermal_bridge_width 0.5)
			(island_removal_mode 0)
		)
		(polygon
			(pts
				(arc
					(start 51.25212 -109.248194)
					(mid 51.237241 -109.284115)
					(end 51.20132 -109.298994)
				)
				(arc
					(start 50.02022 -109.298994)
					(mid 49.984299 -109.284115)
					(end 49.96942 -109.248194)
				)
				(arc
					(start 49.96942 -108.241846)
					(mid 49.984299 -108.205925)
					(end 50.02022 -108.191046)
				)
				(arc
					(start 51.20132 -108.191046)
					(mid 51.237241 -108.205925)
					(end 51.25212 -108.241846)
				)
			)
		)
	)
	(zone
		(layer "In1.Cu")
		(hatch none 0.5)
		(connect_pads
			(clearance 0)
		)
		(min_thickness 0.25)
		(keepout
			(tracks not_allowed)
			(vias allowed)
			(pads allowed)
			(copperpour not_allowed)
			(footprints allowed)
		)
		(placement
			(enabled no)
			(sheetname "")
		)
		(fill
			(thermal_gap 0.5)
			(thermal_bridge_width 0.5)
			(island_removal_mode 0)
		)
		(polygon
			(pts
				(arc
					(start 399.55216 -107.448096)
					(mid 399.537281 -107.484017)
					(end 399.50136 -107.498896)
				)
				(arc
					(start 398.32026 -107.498896)
					(mid 398.284339 -107.484017)
					(end 398.26946 -107.448096)
				)
				(arc
					(start 398.26946 -106.441748)
					(mid 398.284339 -106.405827)
					(end 398.32026 -106.390948)
				)
				(arc
					(start 399.50136 -106.390948)
					(mid 399.537281 -106.405827)
					(end 399.55216 -106.441748)
				)
			)
		)
	)
	(zone
		(layer "In1.Cu")
		(hatch none 0.5)
		(connect_pads
			(clearance 0)
		)
		(min_thickness 0.25)
		(keepout
			(tracks not_allowed)
			(vias allowed)
			(pads allowed)
			(copperpour not_allowed)
			(footprints allowed)
		)
		(placement
			(enabled no)
			(sheetname "")
		)
		(fill
			(thermal_gap 0.5)
			(thermal_bridge_width 0.5)
			(island_removal_mode 0)
		)
		(polygon
			(pts
				(arc
					(start 268.419326 -120.253252)
					(mid 268.434205 -120.289173)
					(end 268.470126 -120.304052)
				)
				(arc
					(start 269.206726 -120.304052)
					(mid 269.242647 -120.289173)
					(end 269.257526 -120.253252)
				)
				(xy 269.257526 -120.009412) (xy 269.025116 -119.655082) (xy 269.257526 -119.299482)
				(arc
					(start 269.257526 -119.056912)
					(mid 269.242647 -119.020991)
					(end 269.206726 -119.006112)
				)
				(arc
					(start 268.470126 -119.006112)
					(mid 268.434205 -119.020991)
					(end 268.419326 -119.056912)
				)
				(xy 268.419326 -119.299482) (xy 268.651736 -119.656352) (xy 268.419326 -120.010682)
			)
		)
	)
	(zone
		(layer "In1.Cu")
		(hatch none 0.5)
		(connect_pads
			(clearance 0)
		)
		(min_thickness 0.25)
		(keepout
			(tracks not_allowed)
			(vias allowed)
			(pads allowed)
			(copperpour not_allowed)
			(footprints allowed)
		)
		(placement
			(enabled no)
			(sheetname "")
		)
		(fill
			(thermal_gap 0.5)
			(thermal_bridge_width 0.5)
			(island_removal_mode 0)
		)
		(polygon
			(pts
				(arc
					(start 377.240546 -355.825806)
					(mid 377.204625 -355.840685)
					(end 377.189746 -355.876606)
				)
				(arc
					(start 377.189746 -356.613206)
					(mid 377.204625 -356.649127)
					(end 377.240546 -356.664006)
				)
				(xy 377.484386 -356.664006) (xy 377.838716 -356.431596) (xy 378.194316 -356.664006)
				(arc
					(start 378.436886 -356.664006)
					(mid 378.472807 -356.649127)
					(end 378.487686 -356.613206)
				)
				(arc
					(start 378.487686 -355.876606)
					(mid 378.472807 -355.840685)
					(end 378.436886 -355.825806)
				)
				(xy 378.194316 -355.825806) (xy 377.837446 -356.058216) (xy 377.483116 -355.825806)
			)
		)
	)
	(zone
		(layer "In1.Cu")
		(hatch none 0.5)
		(connect_pads
			(clearance 0)
		)
		(min_thickness 0.25)
		(keepout
			(tracks not_allowed)
			(vias allowed)
			(pads allowed)
			(copperpour not_allowed)
			(footprints allowed)
		)
		(placement
			(enabled no)
			(sheetname "")
		)
		(fill
			(thermal_gap 0.5)
			(thermal_bridge_width 0.5)
			(island_removal_mode 0)
		)
		(polygon
			(pts
				(arc
					(start 189.967108 -136.24814)
					(mid 189.952229 -136.284061)
					(end 189.916308 -136.29894)
				)
				(arc
					(start 188.735208 -136.29894)
					(mid 188.699287 -136.284061)
					(end 188.684408 -136.24814)
				)
				(arc
					(start 188.684408 -135.241792)
					(mid 188.699287 -135.205871)
					(end 188.735208 -135.190992)
				)
				(arc
					(start 189.916308 -135.190992)
					(mid 189.952229 -135.205871)
					(end 189.967108 -135.241792)
				)
			)
		)
	)
	(zone
		(layer "In1.Cu")
		(hatch none 0.5)
		(connect_pads
			(clearance 0)
		)
		(min_thickness 0.25)
		(keepout
			(tracks not_allowed)
			(vias allowed)
			(pads allowed)
			(copperpour not_allowed)
			(footprints allowed)
		)
		(placement
			(enabled no)
			(sheetname "")
		)
		(fill
			(thermal_gap 0.5)
			(thermal_bridge_width 0.5)
			(island_removal_mode 0)
		)
		(polygon
			(pts
				(arc
					(start 422.167304 -132.648198)
					(mid 422.152425 -132.684119)
					(end 422.116504 -132.698998)
				)
				(arc
					(start 420.935404 -132.698998)
					(mid 420.899483 -132.684119)
					(end 420.884604 -132.648198)
				)
				(arc
					(start 420.884604 -131.64185)
					(mid 420.899483 -131.605929)
					(end 420.935404 -131.59105)
				)
				(arc
					(start 422.116504 -131.59105)
					(mid 422.152425 -131.605929)
					(end 422.167304 -131.64185)
				)
			)
		)
	)
	(zone
		(layer "In1.Cu")
		(hatch none 0.5)
		(connect_pads
			(clearance 0)
		)
		(min_thickness 0.25)
		(keepout
			(tracks not_allowed)
			(vias allowed)
			(pads allowed)
			(copperpour not_allowed)
			(footprints allowed)
		)
		(placement
			(enabled no)
			(sheetname "")
		)
		(fill
			(thermal_gap 0.5)
			(thermal_bridge_width 0.5)
			(island_removal_mode 0)
		)
		(polygon
			(pts
				(arc
					(start 283.452062 -100.248212)
					(mid 283.437183 -100.284133)
					(end 283.401262 -100.299012)
				)
				(arc
					(start 282.220162 -100.299012)
					(mid 282.184241 -100.284133)
					(end 282.169362 -100.248212)
				)
				(arc
					(start 282.169362 -99.241864)
					(mid 282.184241 -99.205943)
					(end 282.220162 -99.191064)
				)
				(arc
					(start 283.401262 -99.191064)
					(mid 283.437183 -99.205943)
					(end 283.452062 -99.241864)
				)
			)
		)
	)
	(zone
		(layer "In1.Cu")
		(hatch none 0.5)
		(connect_pads
			(clearance 0)
		)
		(min_thickness 0.25)
		(keepout
			(tracks not_allowed)
			(vias allowed)
			(pads allowed)
			(copperpour not_allowed)
			(footprints allowed)
		)
		(placement
			(enabled no)
			(sheetname "")
		)
		(fill
			(thermal_gap 0.5)
			(thermal_bridge_width 0.5)
			(island_removal_mode 0)
		)
		(polygon
			(pts
				(arc
					(start 295.712388 -355.825806)
					(mid 295.676467 -355.840685)
					(end 295.661588 -355.876606)
				)
				(arc
					(start 295.661588 -356.613206)
					(mid 295.676467 -356.649127)
					(end 295.712388 -356.664006)
				)
				(xy 295.956228 -356.664006) (xy 296.310558 -356.431596) (xy 296.666158 -356.664006)
				(arc
					(start 296.908728 -356.664006)
					(mid 296.944649 -356.649127)
					(end 296.959528 -356.613206)
				)
				(arc
					(start 296.959528 -355.876606)
					(mid 296.944649 -355.840685)
					(end 296.908728 -355.825806)
				)
				(xy 296.666158 -355.825806) (xy 296.309288 -356.058216) (xy 295.954958 -355.825806)
			)
		)
	)
	(zone
		(layer "In1.Cu")
		(hatch none 0.5)
		(connect_pads
			(clearance 0)
		)
		(min_thickness 0.25)
		(keepout
			(tracks not_allowed)
			(vias allowed)
			(pads allowed)
			(copperpour not_allowed)
			(footprints allowed)
		)
		(placement
			(enabled no)
			(sheetname "")
		)
		(fill
			(thermal_gap 0.5)
			(thermal_bridge_width 0.5)
			(island_removal_mode 0)
		)
		(polygon
			(pts
				(arc
					(start 174.456598 -343.533222)
					(mid 174.420677 -343.548101)
					(end 174.405798 -343.584022)
				)
				(arc
					(start 174.405798 -344.320622)
					(mid 174.420677 -344.356543)
					(end 174.456598 -344.371422)
				)
				(xy 174.700438 -344.371422) (xy 175.054768 -344.139012) (xy 175.410368 -344.371422)
				(arc
					(start 175.652938 -344.371422)
					(mid 175.688859 -344.356543)
					(end 175.703738 -344.320622)
				)
				(arc
					(start 175.703738 -343.584022)
					(mid 175.688859 -343.548101)
					(end 175.652938 -343.533222)
				)
				(xy 175.410368 -343.533222) (xy 175.053498 -343.765632) (xy 174.699168 -343.533222)
			)
		)
	)
	(zone
		(layer "In1.Cu")
		(hatch none 0.5)
		(connect_pads
			(clearance 0)
		)
		(min_thickness 0.25)
		(keepout
			(tracks not_allowed)
			(vias allowed)
			(pads allowed)
			(copperpour not_allowed)
			(footprints allowed)
		)
		(placement
			(enabled no)
			(sheetname "")
		)
		(fill
			(thermal_gap 0.5)
			(thermal_bridge_width 0.5)
			(island_removal_mode 0)
		)
		(polygon
			(pts
				(arc
					(start 393.732766 -104.641904)
					(mid 393.747645 -104.605983)
					(end 393.783566 -104.591104)
				)
				(arc
					(start 394.964666 -104.591104)
					(mid 395.000587 -104.605983)
					(end 395.015466 -104.641904)
				)
				(arc
					(start 395.015466 -105.648252)
					(mid 395.000587 -105.684173)
					(end 394.964666 -105.699052)
				)
				(arc
					(start 393.783566 -105.699052)
					(mid 393.747645 -105.684173)
					(end 393.732766 -105.648252)
				)
			)
		)
	)
	(zone
		(layer "In1.Cu")
		(hatch none 0.5)
		(connect_pads
			(clearance 0)
		)
		(min_thickness 0.25)
		(keepout
			(tracks not_allowed)
			(vias allowed)
			(pads allowed)
			(copperpour not_allowed)
			(footprints allowed)
		)
		(placement
			(enabled no)
			(sheetname "")
		)
		(fill
			(thermal_gap 0.5)
			(thermal_bridge_width 0.5)
			(island_removal_mode 0)
		)
		(polygon
			(pts
				(arc
					(start 334.10017 -355.825806)
					(mid 334.064249 -355.840685)
					(end 334.04937 -355.876606)
				)
				(arc
					(start 334.04937 -356.613206)
					(mid 334.064249 -356.649127)
					(end 334.10017 -356.664006)
				)
				(xy 334.34401 -356.664006) (xy 334.69834 -356.431596) (xy 335.05394 -356.664006)
				(arc
					(start 335.29651 -356.664006)
					(mid 335.332431 -356.649127)
					(end 335.34731 -356.613206)
				)
				(arc
					(start 335.34731 -355.876606)
					(mid 335.332431 -355.840685)
					(end 335.29651 -355.825806)
				)
				(xy 335.05394 -355.825806) (xy 334.69707 -356.058216) (xy 334.34274 -355.825806)
			)
		)
	)
	(zone
		(layer "In1.Cu")
		(hatch none 0.5)
		(connect_pads
			(clearance 0)
		)
		(min_thickness 0.25)
		(keepout
			(tracks not_allowed)
			(vias allowed)
			(pads allowed)
			(copperpour not_allowed)
			(footprints allowed)
		)
		(placement
			(enabled no)
			(sheetname "")
		)
		(fill
			(thermal_gap 0.5)
			(thermal_bridge_width 0.5)
			(island_removal_mode 0)
		)
		(polygon
			(pts
				(arc
					(start 418.456618 -355.825806)
					(mid 418.420697 -355.840685)
					(end 418.405818 -355.876606)
				)
				(arc
					(start 418.405818 -356.613206)
					(mid 418.420697 -356.649127)
					(end 418.456618 -356.664006)
				)
				(xy 418.700458 -356.664006) (xy 419.054788 -356.431596) (xy 419.410388 -356.664006)
				(arc
					(start 419.652958 -356.664006)
					(mid 419.688879 -356.649127)
					(end 419.703758 -356.613206)
				)
				(arc
					(start 419.703758 -355.876606)
					(mid 419.688879 -355.840685)
					(end 419.652958 -355.825806)
				)
				(xy 419.410388 -355.825806) (xy 419.053518 -356.058216) (xy 418.699188 -355.825806)
			)
		)
	)
	(zone
		(layer "In1.Cu")
		(hatch none 0.5)
		(connect_pads
			(clearance 0)
		)
		(min_thickness 0.25)
		(keepout
			(tracks not_allowed)
			(vias allowed)
			(pads allowed)
			(copperpour not_allowed)
			(footprints allowed)
		)
		(placement
			(enabled no)
			(sheetname "")
		)
		(fill
			(thermal_gap 0.5)
			(thermal_bridge_width 0.5)
			(island_removal_mode 0)
		)
		(polygon
			(pts
				(arc
					(start 73.867264 -125.038104)
					(mid 73.852385 -125.074025)
					(end 73.816464 -125.088904)
				)
				(arc
					(start 72.635364 -125.088904)
					(mid 72.599443 -125.074025)
					(end 72.584564 -125.038104)
				)
				(arc
					(start 72.584564 -124.031756)
					(mid 72.599443 -123.995835)
					(end 72.635364 -123.980956)
				)
				(arc
					(start 73.816464 -123.980956)
					(mid 73.852385 -123.995835)
					(end 73.867264 -124.031756)
				)
			)
		)
	)
	(zone
		(layer "In1.Cu")
		(hatch none 0.5)
		(connect_pads
			(clearance 0)
		)
		(min_thickness 0.25)
		(keepout
			(tracks not_allowed)
			(vias allowed)
			(pads allowed)
			(copperpour not_allowed)
			(footprints allowed)
		)
		(placement
			(enabled no)
			(sheetname "")
		)
		(fill
			(thermal_gap 0.5)
			(thermal_bridge_width 0.5)
			(island_removal_mode 0)
		)
		(polygon
			(pts
				(arc
					(start 190.001398 -349.679514)
					(mid 189.965477 -349.694393)
					(end 189.950598 -349.730314)
				)
				(arc
					(start 189.950598 -350.466914)
					(mid 189.965477 -350.502835)
					(end 190.001398 -350.517714)
				)
				(xy 190.245238 -350.517714) (xy 190.599568 -350.285304) (xy 190.955168 -350.517714)
				(arc
					(start 191.197738 -350.517714)
					(mid 191.233659 -350.502835)
					(end 191.248538 -350.466914)
				)
				(arc
					(start 191.248538 -349.730314)
					(mid 191.233659 -349.694393)
					(end 191.197738 -349.679514)
				)
				(xy 190.955168 -349.679514) (xy 190.598298 -349.911924) (xy 190.243968 -349.679514)
			)
		)
	)
	(zone
		(layer "In1.Cu")
		(hatch none 0.5)
		(connect_pads
			(clearance 0)
		)
		(min_thickness 0.25)
		(keepout
			(tracks not_allowed)
			(vias allowed)
			(pads allowed)
			(copperpour not_allowed)
			(footprints allowed)
		)
		(placement
			(enabled no)
			(sheetname "")
		)
		(fill
			(thermal_gap 0.5)
			(thermal_bridge_width 0.5)
			(island_removal_mode 0)
		)
		(polygon
			(pts
				(arc
					(start 68.04787 -153.351992)
					(mid 68.062749 -153.316071)
					(end 68.09867 -153.301192)
				)
				(arc
					(start 69.27977 -153.301192)
					(mid 69.315691 -153.316071)
					(end 69.33057 -153.351992)
				)
				(arc
					(start 69.33057 -154.35834)
					(mid 69.315691 -154.394261)
					(end 69.27977 -154.40914)
				)
				(arc
					(start 68.09867 -154.40914)
					(mid 68.062749 -154.394261)
					(end 68.04787 -154.35834)
				)
			)
		)
	)
	(zone
		(layer "In1.Cu")
		(hatch none 0.5)
		(connect_pads
			(clearance 0)
		)
		(min_thickness 0.25)
		(keepout
			(tracks not_allowed)
			(vias allowed)
			(pads allowed)
			(copperpour not_allowed)
			(footprints allowed)
		)
		(placement
			(enabled no)
			(sheetname "")
		)
		(fill
			(thermal_gap 0.5)
			(thermal_bridge_width 0.5)
			(island_removal_mode 0)
		)
		(polygon
			(pts
				(arc
					(start 232.34269 -83.147408)
					(mid 232.252887 -83.110211)
					(end 232.21569 -83.020408)
				)
				(arc
					(start 232.21569 -82.817208)
					(mid 232.252887 -82.727405)
					(end 232.34269 -82.690208)
				)
				(arc
					(start 232.59669 -82.690208)
					(mid 232.686493 -82.727405)
					(end 232.72369 -82.817208)
				)
				(arc
					(start 232.72369 -83.020408)
					(mid 232.686493 -83.110211)
					(end 232.59669 -83.147408)
				)
			)
		)
	)
	(zone
		(layer "In1.Cu")
		(hatch none 0.5)
		(connect_pads
			(clearance 0)
		)
		(min_thickness 0.25)
		(keepout
			(tracks not_allowed)
			(vias allowed)
			(pads allowed)
			(copperpour not_allowed)
			(footprints allowed)
		)
		(placement
			(enabled no)
			(sheetname "")
		)
		(fill
			(thermal_gap 0.5)
			(thermal_bridge_width 0.5)
			(island_removal_mode 0)
		)
		(polygon
			(pts
				(arc
					(start 189.967108 -154.358086)
					(mid 189.952229 -154.394007)
					(end 189.916308 -154.408886)
				)
				(arc
					(start 188.735208 -154.408886)
					(mid 188.699287 -154.394007)
					(end 188.684408 -154.358086)
				)
				(arc
					(start 188.684408 -153.351738)
					(mid 188.699287 -153.315817)
					(end 188.735208 -153.300938)
				)
				(arc
					(start 189.916308 -153.300938)
					(mid 189.952229 -153.315817)
					(end 189.967108 -153.351738)
				)
			)
		)
	)
	(zone
		(layer "In1.Cu")
		(hatch none 0.5)
		(connect_pads
			(clearance 0)
		)
		(min_thickness 0.25)
		(keepout
			(tracks not_allowed)
			(vias allowed)
			(pads allowed)
			(copperpour not_allowed)
			(footprints allowed)
		)
		(placement
			(enabled no)
			(sheetname "")
		)
		(fill
			(thermal_gap 0.5)
			(thermal_bridge_width 0.5)
			(island_removal_mode 0)
		)
		(polygon
			(pts
				(arc
					(start 277.632668 -120.952006)
					(mid 277.647547 -120.916085)
					(end 277.683468 -120.901206)
				)
				(arc
					(start 278.864568 -120.901206)
					(mid 278.900489 -120.916085)
					(end 278.915368 -120.952006)
				)
				(arc
					(start 278.915368 -121.958354)
					(mid 278.900489 -121.994275)
					(end 278.864568 -122.009154)
				)
				(arc
					(start 277.683468 -122.009154)
					(mid 277.647547 -121.994275)
					(end 277.632668 -121.958354)
				)
			)
		)
	)
	(zone
		(layer "In1.Cu")
		(hatch none 0.5)
		(connect_pads
			(clearance 0)
		)
		(min_thickness 0.25)
		(keepout
			(tracks not_allowed)
			(vias allowed)
			(pads allowed)
			(copperpour not_allowed)
			(footprints allowed)
		)
		(placement
			(enabled no)
			(sheetname "")
		)
		(fill
			(thermal_gap 0.5)
			(thermal_bridge_width 0.5)
			(island_removal_mode 0)
		)
		(polygon
			(pts
				(arc
					(start 377.240546 -343.533222)
					(mid 377.204625 -343.548101)
					(end 377.189746 -343.584022)
				)
				(arc
					(start 377.189746 -344.320622)
					(mid 377.204625 -344.356543)
					(end 377.240546 -344.371422)
				)
				(xy 377.484386 -344.371422) (xy 377.838716 -344.139012) (xy 378.194316 -344.371422)
				(arc
					(start 378.436886 -344.371422)
					(mid 378.472807 -344.356543)
					(end 378.487686 -344.320622)
				)
				(arc
					(start 378.487686 -343.584022)
					(mid 378.472807 -343.548101)
					(end 378.436886 -343.533222)
				)
				(xy 378.194316 -343.533222) (xy 377.837446 -343.765632) (xy 377.483116 -343.533222)
			)
		)
	)
	(zone
		(layer "In1.Cu")
		(hatch none 0.5)
		(connect_pads
			(clearance 0)
		)
		(min_thickness 0.25)
		(keepout
			(tracks not_allowed)
			(vias allowed)
			(pads allowed)
			(copperpour not_allowed)
			(footprints allowed)
		)
		(placement
			(enabled no)
			(sheetname "")
		)
		(fill
			(thermal_gap 0.5)
			(thermal_bridge_width 0.5)
			(island_removal_mode 0)
		)
		(polygon
			(pts
				(arc
					(start 79.600298 -150.844504)
					(mid 79.615177 -150.880425)
					(end 79.651098 -150.895304)
				)
				(arc
					(start 80.387698 -150.895304)
					(mid 80.423619 -150.880425)
					(end 80.438498 -150.844504)
				)
				(xy 80.438498 -150.600664) (xy 80.206088 -150.246334) (xy 80.438498 -149.890734)
				(arc
					(start 80.438498 -149.648164)
					(mid 80.423619 -149.612243)
					(end 80.387698 -149.597364)
				)
				(arc
					(start 79.651098 -149.597364)
					(mid 79.615177 -149.612243)
					(end 79.600298 -149.648164)
				)
				(xy 79.600298 -149.890734) (xy 79.832708 -150.247604) (xy 79.600298 -150.601934)
			)
		)
	)
	(zone
		(layer "In1.Cu")
		(hatch none 0.5)
		(connect_pads
			(clearance 0)
		)
		(min_thickness 0.25)
		(keepout
			(tracks not_allowed)
			(vias allowed)
			(pads allowed)
			(copperpour not_allowed)
			(footprints allowed)
		)
		(placement
			(enabled no)
			(sheetname "")
		)
		(fill
			(thermal_gap 0.5)
			(thermal_bridge_width 0.5)
			(island_removal_mode 0)
		)
		(polygon
			(pts
				(arc
					(start 161.53257 -119.151908)
					(mid 161.547449 -119.115987)
					(end 161.58337 -119.101108)
				)
				(arc
					(start 162.76447 -119.101108)
					(mid 162.800391 -119.115987)
					(end 162.81527 -119.151908)
				)
				(arc
					(start 162.81527 -120.158256)
					(mid 162.800391 -120.194177)
					(end 162.76447 -120.209056)
				)
				(arc
					(start 161.58337 -120.209056)
					(mid 161.547449 -120.194177)
					(end 161.53257 -120.158256)
				)
			)
		)
	)
	(zone
		(layer "In1.Cu")
		(hatch none 0.5)
		(connect_pads
			(clearance 0)
		)
		(min_thickness 0.25)
		(keepout
			(tracks not_allowed)
			(vias allowed)
			(pads allowed)
			(copperpour not_allowed)
			(footprints allowed)
		)
		(placement
			(enabled no)
			(sheetname "")
		)
		(fill
			(thermal_gap 0.5)
			(thermal_bridge_width 0.5)
			(island_removal_mode 0)
		)
		(polygon
			(pts
				(arc
					(start 101.702362 -384.631946)
					(mid 101.612559 -384.594749)
					(end 101.575362 -384.504946)
				)
				(arc
					(start 101.575362 -384.303778)
					(mid 101.612559 -384.213975)
					(end 101.702362 -384.176778)
				)
				(arc
					(start 101.956362 -384.176778)
					(mid 102.046165 -384.213975)
					(end 102.083362 -384.303778)
				)
				(arc
					(start 102.083362 -384.504946)
					(mid 102.046165 -384.594749)
					(end 101.956362 -384.631946)
				)
			)
		)
	)
	(zone
		(layer "In1.Cu")
		(hatch none 0.5)
		(connect_pads
			(clearance 0)
		)
		(min_thickness 0.25)
		(keepout
			(tracks not_allowed)
			(vias allowed)
			(pads allowed)
			(copperpour not_allowed)
			(footprints allowed)
		)
		(placement
			(enabled no)
			(sheetname "")
		)
		(fill
			(thermal_gap 0.5)
			(thermal_bridge_width 0.5)
			(island_removal_mode 0)
		)
		(polygon
			(pts
				(arc
					(start 178.129946 -33.574228)
					(mid 178.144825 -33.538307)
					(end 178.180746 -33.523428)
				)
				(arc
					(start 179.412646 -33.523428)
					(mid 179.448567 -33.538307)
					(end 179.463446 -33.574228)
				)
				(arc
					(start 179.463446 -34.605976)
					(mid 179.448567 -34.641897)
					(end 179.412646 -34.656776)
				)
				(arc
					(start 178.180746 -34.656776)
					(mid 178.144825 -34.641897)
					(end 178.129946 -34.605976)
				)
			)
		)
	)
	(zone
		(layer "In1.Cu")
		(hatch none 0.5)
		(connect_pads
			(clearance 0)
		)
		(min_thickness 0.25)
		(keepout
			(tracks not_allowed)
			(vias allowed)
			(pads allowed)
			(copperpour not_allowed)
			(footprints allowed)
		)
		(placement
			(enabled no)
			(sheetname "")
		)
		(fill
			(thermal_gap 0.5)
			(thermal_bridge_width 0.5)
			(island_removal_mode 0)
		)
		(polygon
			(pts
				(arc
					(start 402.112226 -349.679514)
					(mid 402.076305 -349.694393)
					(end 402.061426 -349.730314)
				)
				(arc
					(start 402.061426 -350.466914)
					(mid 402.076305 -350.502835)
					(end 402.112226 -350.517714)
				)
				(xy 402.356066 -350.517714) (xy 402.710396 -350.285304) (xy 403.065996 -350.517714)
				(arc
					(start 403.308566 -350.517714)
					(mid 403.344487 -350.502835)
					(end 403.359366 -350.466914)
				)
				(arc
					(start 403.359366 -349.730314)
					(mid 403.344487 -349.694393)
					(end 403.308566 -349.679514)
				)
				(xy 403.065996 -349.679514) (xy 402.709126 -349.911924) (xy 402.354796 -349.679514)
			)
		)
	)
	(zone
		(layer "In1.Cu")
		(hatch none 0.5)
		(connect_pads
			(clearance 0)
		)
		(min_thickness 0.25)
		(keepout
			(tracks not_allowed)
			(vias allowed)
			(pads allowed)
			(copperpour not_allowed)
			(footprints allowed)
		)
		(placement
			(enabled no)
			(sheetname "")
		)
		(fill
			(thermal_gap 0.5)
			(thermal_bridge_width 0.5)
			(island_removal_mode 0)
		)
		(polygon
			(pts
				(arc
					(start 298.821348 -343.533222)
					(mid 298.785427 -343.548101)
					(end 298.770548 -343.584022)
				)
				(arc
					(start 298.770548 -344.320622)
					(mid 298.785427 -344.356543)
					(end 298.821348 -344.371422)
				)
				(xy 299.065188 -344.371422) (xy 299.419518 -344.139012) (xy 299.775118 -344.371422)
				(arc
					(start 300.017688 -344.371422)
					(mid 300.053609 -344.356543)
					(end 300.068488 -344.320622)
				)
				(arc
					(start 300.068488 -343.584022)
					(mid 300.053609 -343.548101)
					(end 300.017688 -343.533222)
				)
				(xy 299.775118 -343.533222) (xy 299.418248 -343.765632) (xy 299.063918 -343.533222)
			)
		)
	)
	(zone
		(layer "In1.Cu")
		(hatch none 0.5)
		(connect_pads
			(clearance 0)
		)
		(min_thickness 0.25)
		(keepout
			(tracks not_allowed)
			(vias allowed)
			(pads allowed)
			(copperpour not_allowed)
			(footprints allowed)
		)
		(placement
			(enabled no)
			(sheetname "")
		)
		(fill
			(thermal_gap 0.5)
			(thermal_bridge_width 0.5)
			(island_removal_mode 0)
		)
		(polygon
			(pts
				(arc
					(start 383.458466 -349.679514)
					(mid 383.422545 -349.694393)
					(end 383.407666 -349.730314)
				)
				(arc
					(start 383.407666 -350.466914)
					(mid 383.422545 -350.502835)
					(end 383.458466 -350.517714)
				)
				(xy 383.702306 -350.517714) (xy 384.056636 -350.285304) (xy 384.412236 -350.517714)
				(arc
					(start 384.654806 -350.517714)
					(mid 384.690727 -350.502835)
					(end 384.705606 -350.466914)
				)
				(arc
					(start 384.705606 -349.730314)
					(mid 384.690727 -349.694393)
					(end 384.654806 -349.679514)
				)
				(xy 384.412236 -349.679514) (xy 384.055366 -349.911924) (xy 383.701036 -349.679514)
			)
		)
	)
	(zone
		(layer "In1.Cu")
		(hatch none 0.5)
		(connect_pads
			(clearance 0)
		)
		(min_thickness 0.25)
		(keepout
			(tracks not_allowed)
			(vias allowed)
			(pads allowed)
			(copperpour not_allowed)
			(footprints allowed)
		)
		(placement
			(enabled no)
			(sheetname "")
		)
		(fill
			(thermal_gap 0.5)
			(thermal_bridge_width 0.5)
			(island_removal_mode 0)
		)
		(polygon
			(pts
				(arc
					(start 306.067206 -123.23826)
					(mid 306.052327 -123.274181)
					(end 306.016406 -123.28906)
				)
				(arc
					(start 304.835306 -123.28906)
					(mid 304.799385 -123.274181)
					(end 304.784506 -123.23826)
				)
				(arc
					(start 304.784506 -122.231912)
					(mid 304.799385 -122.195991)
					(end 304.835306 -122.181112)
				)
				(arc
					(start 306.016406 -122.181112)
					(mid 306.052327 -122.195991)
					(end 306.067206 -122.231912)
				)
			)
		)
	)
	(zone
		(layer "In1.Cu")
		(hatch none 0.5)
		(connect_pads
			(clearance 0)
		)
		(min_thickness 0.25)
		(keepout
			(tracks not_allowed)
			(vias allowed)
			(pads allowed)
			(copperpour not_allowed)
			(footprints allowed)
		)
		(placement
			(enabled no)
			(sheetname "")
		)
		(fill
			(thermal_gap 0.5)
			(thermal_bridge_width 0.5)
			(island_removal_mode 0)
		)
		(polygon
			(pts
				(arc
					(start 106.512106 -379.471936)
					(mid 106.601909 -379.509133)
					(end 106.639106 -379.598936)
				)
				(arc
					(start 106.639106 -379.800104)
					(mid 106.601909 -379.889907)
					(end 106.512106 -379.927104)
				)
				(arc
					(start 106.258106 -379.927104)
					(mid 106.168303 -379.889907)
					(end 106.131106 -379.800104)
				)
				(arc
					(start 106.131106 -379.598936)
					(mid 106.168303 -379.509133)
					(end 106.258106 -379.471936)
				)
			)
		)
	)
	(zone
		(layer "In1.Cu")
		(hatch none 0.5)
		(connect_pads
			(clearance 0)
		)
		(min_thickness 0.25)
		(keepout
			(tracks not_allowed)
			(vias allowed)
			(pads allowed)
			(copperpour not_allowed)
			(footprints allowed)
		)
		(placement
			(enabled no)
			(sheetname "")
		)
		(fill
			(thermal_gap 0.5)
			(thermal_bridge_width 0.5)
			(island_removal_mode 0)
		)
		(polygon
			(pts
				(arc
					(start 399.55216 -133.16839)
					(mid 399.537281 -133.204311)
					(end 399.50136 -133.21919)
				)
				(arc
					(start 398.32026 -133.21919)
					(mid 398.284339 -133.204311)
					(end 398.26946 -133.16839)
				)
				(arc
					(start 398.26946 -132.162042)
					(mid 398.284339 -132.126121)
					(end 398.32026 -132.111242)
				)
				(arc
					(start 399.50136 -132.111242)
					(mid 399.537281 -132.126121)
					(end 399.55216 -132.162042)
				)
			)
		)
	)
	(zone
		(layer "In1.Cu")
		(hatch none 0.5)
		(connect_pads
			(clearance 0)
		)
		(min_thickness 0.25)
		(keepout
			(tracks not_allowed)
			(vias allowed)
			(pads allowed)
			(copperpour not_allowed)
			(footprints allowed)
		)
		(placement
			(enabled no)
			(sheetname "")
		)
		(fill
			(thermal_gap 0.5)
			(thermal_bridge_width 0.5)
			(island_removal_mode 0)
		)
		(polygon
			(pts
				(arc
					(start 68.04787 -142.551912)
					(mid 68.062749 -142.515991)
					(end 68.09867 -142.501112)
				)
				(arc
					(start 69.27977 -142.501112)
					(mid 69.315691 -142.515991)
					(end 69.33057 -142.551912)
				)
				(arc
					(start 69.33057 -143.55826)
					(mid 69.315691 -143.594181)
					(end 69.27977 -143.60906)
				)
				(arc
					(start 68.09867 -143.60906)
					(mid 68.062749 -143.594181)
					(end 68.04787 -143.55826)
				)
			)
		)
	)
	(zone
		(layer "In1.Cu")
		(hatch none 0.5)
		(connect_pads
			(clearance 0)
		)
		(min_thickness 0.25)
		(keepout
			(tracks not_allowed)
			(vias allowed)
			(pads allowed)
			(copperpour not_allowed)
			(footprints allowed)
		)
		(placement
			(enabled no)
			(sheetname "")
		)
		(fill
			(thermal_gap 0.5)
			(thermal_bridge_width 0.5)
			(island_removal_mode 0)
		)
		(polygon
			(pts
				(arc
					(start 230.45928 -86.712552)
					(mid 230.423359 -86.697673)
					(end 230.40848 -86.661752)
				)
				(arc
					(start 230.40848 -86.255098)
					(mid 230.423359 -86.219177)
					(end 230.45928 -86.204298)
				)
				(arc
					(start 230.861616 -86.204298)
					(mid 230.897537 -86.219177)
					(end 230.912416 -86.255098)
				)
				(arc
					(start 230.912416 -86.661752)
					(mid 230.897537 -86.697673)
					(end 230.861616 -86.712552)
				)
			)
		)
	)
	(zone
		(layer "In1.Cu")
		(hatch none 0.5)
		(connect_pads
			(clearance 0)
		)
		(min_thickness 0.25)
		(keepout
			(tracks not_allowed)
			(vias allowed)
			(pads allowed)
			(copperpour not_allowed)
			(footprints allowed)
		)
		(placement
			(enabled no)
			(sheetname "")
		)
		(fill
			(thermal_gap 0.5)
			(thermal_bridge_width 0.5)
			(island_removal_mode 0)
		)
		(polygon
			(pts
				(arc
					(start 114.805714 -355.825806)
					(mid 114.769793 -355.840685)
					(end 114.754914 -355.876606)
				)
				(arc
					(start 114.754914 -356.613206)
					(mid 114.769793 -356.649127)
					(end 114.805714 -356.664006)
				)
				(xy 115.049554 -356.664006) (xy 115.403884 -356.431596) (xy 115.759484 -356.664006)
				(arc
					(start 116.002054 -356.664006)
					(mid 116.037975 -356.649127)
					(end 116.052854 -356.613206)
				)
				(arc
					(start 116.052854 -355.876606)
					(mid 116.037975 -355.840685)
					(end 116.002054 -355.825806)
				)
				(xy 115.759484 -355.825806) (xy 115.402614 -356.058216) (xy 115.048284 -355.825806)
			)
		)
	)
	(zone
		(layer "In1.Cu")
		(hatch none 0.5)
		(connect_pads
			(clearance 0)
		)
		(min_thickness 0.25)
		(keepout
			(tracks not_allowed)
			(vias allowed)
			(pads allowed)
			(copperpour not_allowed)
			(footprints allowed)
		)
		(placement
			(enabled no)
			(sheetname "")
		)
		(fill
			(thermal_gap 0.5)
			(thermal_bridge_width 0.5)
			(island_removal_mode 0)
		)
		(polygon
			(pts
				(arc
					(start 292.603428 -355.825806)
					(mid 292.567507 -355.840685)
					(end 292.552628 -355.876606)
				)
				(arc
					(start 292.552628 -356.613206)
					(mid 292.567507 -356.649127)
					(end 292.603428 -356.664006)
				)
				(xy 292.847268 -356.664006) (xy 293.201598 -356.431596) (xy 293.557198 -356.664006)
				(arc
					(start 293.799768 -356.664006)
					(mid 293.835689 -356.649127)
					(end 293.850568 -356.613206)
				)
				(arc
					(start 293.850568 -355.876606)
					(mid 293.835689 -355.840685)
					(end 293.799768 -355.825806)
				)
				(xy 293.557198 -355.825806) (xy 293.200328 -356.058216) (xy 292.845998 -355.825806)
			)
		)
	)
	(zone
		(layer "In1.Cu")
		(hatch none 0.5)
		(connect_pads
			(clearance 0)
		)
		(min_thickness 0.25)
		(keepout
			(tracks not_allowed)
			(vias allowed)
			(pads allowed)
			(copperpour not_allowed)
			(footprints allowed)
		)
		(placement
			(enabled no)
			(sheetname "")
		)
		(fill
			(thermal_gap 0.5)
			(thermal_bridge_width 0.5)
			(island_removal_mode 0)
		)
		(polygon
			(pts
				(arc
					(start 68.04787 -151.551894)
					(mid 68.062749 -151.515973)
					(end 68.09867 -151.501094)
				)
				(arc
					(start 69.27977 -151.501094)
					(mid 69.315691 -151.515973)
					(end 69.33057 -151.551894)
				)
				(arc
					(start 69.33057 -152.558242)
					(mid 69.315691 -152.594163)
					(end 69.27977 -152.609042)
				)
				(arc
					(start 68.09867 -152.609042)
					(mid 68.062749 -152.594163)
					(end 68.04787 -152.558242)
				)
			)
		)
	)
	(zone
		(layer "In1.Cu")
		(hatch none 0.5)
		(connect_pads
			(clearance 0)
		)
		(min_thickness 0.25)
		(keepout
			(tracks not_allowed)
			(vias allowed)
			(pads allowed)
			(copperpour not_allowed)
			(footprints allowed)
		)
		(placement
			(enabled no)
			(sheetname "")
		)
		(fill
			(thermal_gap 0.5)
			(thermal_bridge_width 0.5)
			(island_removal_mode 0)
		)
		(polygon
			(pts
				(arc
					(start 399.55216 -109.248194)
					(mid 399.537281 -109.284115)
					(end 399.50136 -109.298994)
				)
				(arc
					(start 398.32026 -109.298994)
					(mid 398.284339 -109.284115)
					(end 398.26946 -109.248194)
				)
				(arc
					(start 398.26946 -108.241846)
					(mid 398.284339 -108.205925)
					(end 398.32026 -108.191046)
				)
				(arc
					(start 399.50136 -108.191046)
					(mid 399.537281 -108.205925)
					(end 399.55216 -108.241846)
				)
			)
		)
	)
	(zone
		(layer "In1.Cu")
		(hatch none 0.5)
		(connect_pads
			(clearance 0)
		)
		(min_thickness 0.25)
		(keepout
			(tracks not_allowed)
			(vias allowed)
			(pads allowed)
			(copperpour not_allowed)
			(footprints allowed)
		)
		(placement
			(enabled no)
			(sheetname "")
		)
		(fill
			(thermal_gap 0.5)
			(thermal_bridge_width 0.5)
			(island_removal_mode 0)
		)
		(polygon
			(pts
				(arc
					(start 68.04787 -120.431814)
					(mid 68.062749 -120.395893)
					(end 68.09867 -120.381014)
				)
				(arc
					(start 69.27977 -120.381014)
					(mid 69.315691 -120.395893)
					(end 69.33057 -120.431814)
				)
				(arc
					(start 69.33057 -121.438162)
					(mid 69.315691 -121.474083)
					(end 69.27977 -121.488962)
				)
				(arc
					(start 68.09867 -121.488962)
					(mid 68.062749 -121.474083)
					(end 68.04787 -121.438162)
				)
			)
		)
	)
	(zone
		(layer "In1.Cu")
		(hatch none 0.5)
		(connect_pads
			(clearance 0)
		)
		(min_thickness 0.25)
		(keepout
			(tracks not_allowed)
			(vias allowed)
			(pads allowed)
			(copperpour not_allowed)
			(footprints allowed)
		)
		(placement
			(enabled no)
			(sheetname "")
		)
		(fill
			(thermal_gap 0.5)
			(thermal_bridge_width 0.5)
			(island_removal_mode 0)
		)
		(polygon
			(pts
				(arc
					(start 416.34791 -131.64185)
					(mid 416.362789 -131.605929)
					(end 416.39871 -131.59105)
				)
				(arc
					(start 417.57981 -131.59105)
					(mid 417.615731 -131.605929)
					(end 417.63061 -131.64185)
				)
				(arc
					(start 417.63061 -132.648198)
					(mid 417.615731 -132.684119)
					(end 417.57981 -132.698998)
				)
				(arc
					(start 416.39871 -132.698998)
					(mid 416.362789 -132.684119)
					(end 416.34791 -132.648198)
				)
			)
		)
	)
	(zone
		(layer "In1.Cu")
		(hatch none 0.5)
		(connect_pads
			(clearance 0)
		)
		(min_thickness 0.25)
		(keepout
			(tracks not_allowed)
			(vias allowed)
			(pads allowed)
			(copperpour not_allowed)
			(footprints allowed)
		)
		(placement
			(enabled no)
			(sheetname "")
		)
		(fill
			(thermal_gap 0.5)
			(thermal_bridge_width 0.5)
			(island_removal_mode 0)
		)
		(polygon
			(pts
				(arc
					(start 152.129998 -33.574228)
					(mid 152.144877 -33.538307)
					(end 152.180798 -33.523428)
				)
				(arc
					(start 153.412698 -33.523428)
					(mid 153.448619 -33.538307)
					(end 153.463498 -33.574228)
				)
				(arc
					(start 153.463498 -34.605976)
					(mid 153.448619 -34.641897)
					(end 153.412698 -34.656776)
				)
				(arc
					(start 152.180798 -34.656776)
					(mid 152.144877 -34.641897)
					(end 152.129998 -34.605976)
				)
			)
		)
	)
	(zone
		(layer "In1.Cu")
		(hatch none 0.5)
		(connect_pads
			(clearance 0)
		)
		(min_thickness 0.25)
		(keepout
			(tracks not_allowed)
			(vias allowed)
			(pads allowed)
			(copperpour not_allowed)
			(footprints allowed)
		)
		(placement
			(enabled no)
			(sheetname "")
		)
		(fill
			(thermal_gap 0.5)
			(thermal_bridge_width 0.5)
			(island_removal_mode 0)
		)
		(polygon
			(pts
				(arc
					(start 392.785346 -349.679514)
					(mid 392.749425 -349.694393)
					(end 392.734546 -349.730314)
				)
				(arc
					(start 392.734546 -350.466914)
					(mid 392.749425 -350.502835)
					(end 392.785346 -350.517714)
				)
				(xy 393.029186 -350.517714) (xy 393.383516 -350.285304) (xy 393.739116 -350.517714)
				(arc
					(start 393.981686 -350.517714)
					(mid 394.017607 -350.502835)
					(end 394.032486 -350.466914)
				)
				(arc
					(start 394.032486 -349.730314)
					(mid 394.017607 -349.694393)
					(end 393.981686 -349.679514)
				)
				(xy 393.739116 -349.679514) (xy 393.382246 -349.911924) (xy 393.027916 -349.679514)
			)
		)
	)
	(zone
		(layer "In1.Cu")
		(hatch none 0.5)
		(connect_pads
			(clearance 0)
		)
		(min_thickness 0.25)
		(keepout
			(tracks not_allowed)
			(vias allowed)
			(pads allowed)
			(copperpour not_allowed)
			(footprints allowed)
		)
		(placement
			(enabled no)
			(sheetname "")
		)
		(fill
			(thermal_gap 0.5)
			(thermal_bridge_width 0.5)
			(island_removal_mode 0)
		)
		(polygon
			(pts
				(arc
					(start 412.238698 -343.533222)
					(mid 412.202777 -343.548101)
					(end 412.187898 -343.584022)
				)
				(arc
					(start 412.187898 -344.320622)
					(mid 412.202777 -344.356543)
					(end 412.238698 -344.371422)
				)
				(xy 412.482538 -344.371422) (xy 412.836868 -344.139012) (xy 413.192468 -344.371422)
				(arc
					(start 413.435038 -344.371422)
					(mid 413.470959 -344.356543)
					(end 413.485838 -344.320622)
				)
				(arc
					(start 413.485838 -343.584022)
					(mid 413.470959 -343.548101)
					(end 413.435038 -343.533222)
				)
				(xy 413.192468 -343.533222) (xy 412.835598 -343.765632) (xy 412.481268 -343.533222)
			)
		)
	)
	(zone
		(layer "In1.Cu")
		(hatch none 0.5)
		(connect_pads
			(clearance 0)
		)
		(min_thickness 0.25)
		(keepout
			(tracks not_allowed)
			(vias allowed)
			(pads allowed)
			(copperpour not_allowed)
			(footprints allowed)
		)
		(placement
			(enabled no)
			(sheetname "")
		)
		(fill
			(thermal_gap 0.5)
			(thermal_bridge_width 0.5)
			(island_removal_mode 0)
		)
		(polygon
			(pts
				(arc
					(start 416.34791 -118.631716)
					(mid 416.362789 -118.595795)
					(end 416.39871 -118.580916)
				)
				(arc
					(start 417.57981 -118.580916)
					(mid 417.615731 -118.595795)
					(end 417.63061 -118.631716)
				)
				(arc
					(start 417.63061 -119.638064)
					(mid 417.615731 -119.673985)
					(end 417.57981 -119.688864)
				)
				(arc
					(start 416.39871 -119.688864)
					(mid 416.362789 -119.673985)
					(end 416.34791 -119.638064)
				)
			)
		)
	)
	(zone
		(layer "In1.Cu")
		(hatch none 0.5)
		(connect_pads
			(clearance 0)
		)
		(min_thickness 0.25)
		(keepout
			(tracks not_allowed)
			(vias allowed)
			(pads allowed)
			(copperpour not_allowed)
			(footprints allowed)
		)
		(placement
			(enabled no)
			(sheetname "")
		)
		(fill
			(thermal_gap 0.5)
			(thermal_bridge_width 0.5)
			(island_removal_mode 0)
		)
		(polygon
			(pts
				(arc
					(start 393.732766 -137.561574)
					(mid 393.747645 -137.525653)
					(end 393.783566 -137.510774)
				)
				(arc
					(start 394.964666 -137.510774)
					(mid 395.000587 -137.525653)
					(end 395.015466 -137.561574)
				)
				(arc
					(start 395.015466 -138.567922)
					(mid 395.000587 -138.603843)
					(end 394.964666 -138.618722)
				)
				(arc
					(start 393.783566 -138.618722)
					(mid 393.747645 -138.603843)
					(end 393.732766 -138.567922)
				)
			)
		)
	)
	(zone
		(layer "In1.Cu")
		(hatch none 0.5)
		(connect_pads
			(clearance 0)
		)
		(min_thickness 0.25)
		(keepout
			(tracks not_allowed)
			(vias allowed)
			(pads allowed)
			(copperpour not_allowed)
			(footprints allowed)
		)
		(placement
			(enabled no)
			(sheetname "")
		)
		(fill
			(thermal_gap 0.5)
			(thermal_bridge_width 0.5)
			(island_removal_mode 0)
		)
		(polygon
			(pts
				(arc
					(start 422.167304 -152.558242)
					(mid 422.152425 -152.594163)
					(end 422.116504 -152.609042)
				)
				(arc
					(start 420.935404 -152.609042)
					(mid 420.899483 -152.594163)
					(end 420.884604 -152.558242)
				)
				(arc
					(start 420.884604 -151.551894)
					(mid 420.899483 -151.515973)
					(end 420.935404 -151.501094)
				)
				(arc
					(start 422.116504 -151.501094)
					(mid 422.152425 -151.515973)
					(end 422.167304 -151.551894)
				)
			)
		)
	)
	(zone
		(layer "In1.Cu")
		(hatch none 0.5)
		(connect_pads
			(clearance 0)
		)
		(min_thickness 0.25)
		(keepout
			(tracks not_allowed)
			(vias allowed)
			(pads allowed)
			(copperpour not_allowed)
			(footprints allowed)
		)
		(placement
			(enabled no)
			(sheetname "")
		)
		(fill
			(thermal_gap 0.5)
			(thermal_bridge_width 0.5)
			(island_removal_mode 0)
		)
		(polygon
			(pts
				(arc
					(start 204.129894 -28.174188)
					(mid 204.144773 -28.138267)
					(end 204.180694 -28.123388)
				)
				(arc
					(start 205.412594 -28.123388)
					(mid 205.448515 -28.138267)
					(end 205.463394 -28.174188)
				)
				(arc
					(start 205.463394 -29.205936)
					(mid 205.448515 -29.241857)
					(end 205.412594 -29.256736)
				)
				(arc
					(start 204.180694 -29.256736)
					(mid 204.144773 -29.241857)
					(end 204.129894 -29.205936)
				)
			)
		)
	)
	(zone
		(layer "In1.Cu")
		(hatch none 0.5)
		(connect_pads
			(clearance 0)
		)
		(min_thickness 0.25)
		(keepout
			(tracks not_allowed)
			(vias allowed)
			(pads allowed)
			(copperpour not_allowed)
			(footprints allowed)
		)
		(placement
			(enabled no)
			(sheetname "")
		)
		(fill
			(thermal_gap 0.5)
			(thermal_bridge_width 0.5)
			(island_removal_mode 0)
		)
		(polygon
			(pts
				(arc
					(start 416.34791 -124.031756)
					(mid 416.362789 -123.995835)
					(end 416.39871 -123.980956)
				)
				(arc
					(start 417.57981 -123.980956)
					(mid 417.615731 -123.995835)
					(end 417.63061 -124.031756)
				)
				(arc
					(start 417.63061 -125.038104)
					(mid 417.615731 -125.074025)
					(end 417.57981 -125.088904)
				)
				(arc
					(start 416.39871 -125.088904)
					(mid 416.362789 -125.074025)
					(end 416.34791 -125.038104)
				)
			)
		)
	)
	(zone
		(layer "In1.Cu")
		(hatch none 0.5)
		(connect_pads
			(clearance 0)
		)
		(min_thickness 0.25)
		(keepout
			(tracks not_allowed)
			(vias allowed)
			(pads allowed)
			(copperpour not_allowed)
			(footprints allowed)
		)
		(placement
			(enabled no)
			(sheetname "")
		)
		(fill
			(thermal_gap 0.5)
			(thermal_bridge_width 0.5)
			(island_removal_mode 0)
		)
		(polygon
			(pts
				(arc
					(start 427.900338 -123.32462)
					(mid 427.915217 -123.360541)
					(end 427.951138 -123.37542)
				)
				(arc
					(start 428.687738 -123.37542)
					(mid 428.723659 -123.360541)
					(end 428.738538 -123.32462)
				)
				(xy 428.738538 -123.08078) (xy 428.506128 -122.72645) (xy 428.738538 -122.37085)
				(arc
					(start 428.738538 -122.12828)
					(mid 428.723659 -122.092359)
					(end 428.687738 -122.07748)
				)
				(arc
					(start 427.951138 -122.07748)
					(mid 427.915217 -122.092359)
					(end 427.900338 -122.12828)
				)
				(xy 427.900338 -122.37085) (xy 428.132748 -122.72772) (xy 427.900338 -123.08205)
			)
		)
	)
	(zone
		(layer "In1.Cu")
		(hatch none 0.5)
		(connect_pads
			(clearance 0)
		)
		(min_thickness 0.25)
		(keepout
			(tracks not_allowed)
			(vias allowed)
			(pads allowed)
			(copperpour not_allowed)
			(footprints allowed)
		)
		(placement
			(enabled no)
			(sheetname "")
		)
		(fill
			(thermal_gap 0.5)
			(thermal_bridge_width 0.5)
			(island_removal_mode 0)
		)
		(polygon
			(pts
				(arc
					(start 278.215344 -31.086044)
					(mid 278.230223 -31.121965)
					(end 278.266144 -31.136844)
				)
				(arc
					(start 279.002744 -31.136844)
					(mid 279.038665 -31.121965)
					(end 279.053544 -31.086044)
				)
				(xy 279.053544 -30.842204) (xy 278.821134 -30.487874) (xy 279.053544 -30.132274)
				(arc
					(start 279.053544 -29.889704)
					(mid 279.038665 -29.853783)
					(end 279.002744 -29.838904)
				)
				(arc
					(start 278.266144 -29.838904)
					(mid 278.230223 -29.853783)
					(end 278.215344 -29.889704)
				)
				(xy 278.215344 -30.132274) (xy 278.447754 -30.489144) (xy 278.215344 -30.843474)
			)
		)
	)
	(zone
		(layer "In1.Cu")
		(hatch none 0.5)
		(connect_pads
			(clearance 0)
		)
		(min_thickness 0.25)
		(keepout
			(tracks not_allowed)
			(vias allowed)
			(pads allowed)
			(copperpour not_allowed)
			(footprints allowed)
		)
		(placement
			(enabled no)
			(sheetname "")
		)
		(fill
			(thermal_gap 0.5)
			(thermal_bridge_width 0.5)
			(island_removal_mode 0)
		)
		(polygon
			(pts
				(arc
					(start 401.48256 7.601204)
					(mid 401.460242 7.547322)
					(end 401.40636 7.525004)
				)
				(arc
					(start 400.79422 7.525004)
					(mid 400.740338 7.547322)
					(end 400.71802 7.601204)
				)
				(arc
					(start 400.71802 8.698484)
					(mid 400.740338 8.752366)
					(end 400.79422 8.774684)
				)
				(arc
					(start 401.40636 8.774684)
					(mid 401.460242 8.752366)
					(end 401.48256 8.698484)
				)
			)
		)
	)
	(zone
		(layer "In1.Cu")
		(hatch none 0.5)
		(connect_pads
			(clearance 0)
		)
		(min_thickness 0.25)
		(keepout
			(tracks not_allowed)
			(vias allowed)
			(pads allowed)
			(copperpour not_allowed)
			(footprints allowed)
		)
		(placement
			(enabled no)
			(sheetname "")
		)
		(fill
			(thermal_gap 0.5)
			(thermal_bridge_width 0.5)
			(island_removal_mode 0)
		)
		(polygon
			(pts
				(arc
					(start 300.09973 -27.405838)
					(mid 300.084851 -27.441759)
					(end 300.04893 -27.456638)
				)
				(arc
					(start 298.81703 -27.456638)
					(mid 298.781109 -27.441759)
					(end 298.76623 -27.405838)
				)
				(arc
					(start 298.76623 -26.37409)
					(mid 298.781109 -26.338169)
					(end 298.81703 -26.32329)
				)
				(arc
					(start 300.04893 -26.32329)
					(mid 300.084851 -26.338169)
					(end 300.09973 -26.37409)
				)
			)
		)
	)
	(zone
		(layer "In1.Cu")
		(hatch none 0.5)
		(connect_pads
			(clearance 0)
		)
		(min_thickness 0.25)
		(keepout
			(tracks not_allowed)
			(vias allowed)
			(pads allowed)
			(copperpour not_allowed)
			(footprints allowed)
		)
		(placement
			(enabled no)
			(sheetname "")
		)
		(fill
			(thermal_gap 0.5)
			(thermal_bridge_width 0.5)
			(island_removal_mode 0)
		)
		(polygon
			(pts
				(arc
					(start 312.33745 -343.533222)
					(mid 312.301529 -343.548101)
					(end 312.28665 -343.584022)
				)
				(arc
					(start 312.28665 -344.320622)
					(mid 312.301529 -344.356543)
					(end 312.33745 -344.371422)
				)
				(xy 312.58129 -344.371422) (xy 312.93562 -344.139012) (xy 313.29122 -344.371422)
				(arc
					(start 313.53379 -344.371422)
					(mid 313.569711 -344.356543)
					(end 313.58459 -344.320622)
				)
				(arc
					(start 313.58459 -343.584022)
					(mid 313.569711 -343.548101)
					(end 313.53379 -343.533222)
				)
				(xy 313.29122 -343.533222) (xy 312.93435 -343.765632) (xy 312.58002 -343.533222)
			)
		)
	)
	(zone
		(layer "In1.Cu")
		(hatch none 0.5)
		(connect_pads
			(clearance 0)
		)
		(min_thickness 0.25)
		(keepout
			(tracks not_allowed)
			(vias allowed)
			(pads allowed)
			(copperpour not_allowed)
			(footprints allowed)
		)
		(placement
			(enabled no)
			(sheetname "")
		)
		(fill
			(thermal_gap 0.5)
			(thermal_bridge_width 0.5)
			(island_removal_mode 0)
		)
		(polygon
			(pts
				(arc
					(start 131.99999 -31.006034)
					(mid 131.985111 -31.041955)
					(end 131.94919 -31.056834)
				)
				(arc
					(start 130.71729 -31.056834)
					(mid 130.681369 -31.041955)
					(end 130.66649 -31.006034)
				)
				(arc
					(start 130.66649 -29.974286)
					(mid 130.681369 -29.938365)
					(end 130.71729 -29.923486)
				)
				(arc
					(start 131.94919 -29.923486)
					(mid 131.985111 -29.938365)
					(end 131.99999 -29.974286)
				)
			)
		)
	)
	(zone
		(layer "In1.Cu")
		(hatch none 0.5)
		(connect_pads
			(clearance 0)
		)
		(min_thickness 0.25)
		(keepout
			(tracks not_allowed)
			(vias allowed)
			(pads allowed)
			(copperpour not_allowed)
			(footprints allowed)
		)
		(placement
			(enabled no)
			(sheetname "")
		)
		(fill
			(thermal_gap 0.5)
			(thermal_bridge_width 0.5)
			(island_removal_mode 0)
		)
		(polygon
			(pts
				(arc
					(start 306.067206 -150.758144)
					(mid 306.052327 -150.794065)
					(end 306.016406 -150.808944)
				)
				(arc
					(start 304.835306 -150.808944)
					(mid 304.799385 -150.794065)
					(end 304.784506 -150.758144)
				)
				(arc
					(start 304.784506 -149.751796)
					(mid 304.799385 -149.715875)
					(end 304.835306 -149.700996)
				)
				(arc
					(start 306.016406 -149.700996)
					(mid 306.052327 -149.715875)
					(end 306.067206 -149.751796)
				)
			)
		)
	)
	(zone
		(layer "In1.Cu")
		(hatch none 0.5)
		(connect_pads
			(clearance 0)
		)
		(min_thickness 0.25)
		(keepout
			(tracks not_allowed)
			(vias allowed)
			(pads allowed)
			(copperpour not_allowed)
			(footprints allowed)
		)
		(placement
			(enabled no)
			(sheetname "")
		)
		(fill
			(thermal_gap 0.5)
			(thermal_bridge_width 0.5)
			(island_removal_mode 0)
		)
		(polygon
			(pts
				(arc
					(start 41.89984 -27.405838)
					(mid 41.884961 -27.441759)
					(end 41.84904 -27.456638)
				)
				(arc
					(start 40.61714 -27.456638)
					(mid 40.581219 -27.441759)
					(end 40.56634 -27.405838)
				)
				(arc
					(start 40.56634 -26.37409)
					(mid 40.581219 -26.338169)
					(end 40.61714 -26.32329)
				)
				(arc
					(start 41.84904 -26.32329)
					(mid 41.884961 -26.338169)
					(end 41.89984 -26.37409)
				)
			)
		)
	)
	(zone
		(layer "In1.Cu")
		(hatch none 0.5)
		(connect_pads
			(clearance 0)
		)
		(min_thickness 0.25)
		(keepout
			(tracks not_allowed)
			(vias allowed)
			(pads allowed)
			(copperpour not_allowed)
			(footprints allowed)
		)
		(placement
			(enabled no)
			(sheetname "")
		)
		(fill
			(thermal_gap 0.5)
			(thermal_bridge_width 0.5)
			(island_removal_mode 0)
		)
		(polygon
			(pts
				(arc
					(start 300.247812 -155.151836)
					(mid 300.262691 -155.115915)
					(end 300.298612 -155.101036)
				)
				(arc
					(start 301.479712 -155.101036)
					(mid 301.515633 -155.115915)
					(end 301.530512 -155.151836)
				)
				(arc
					(start 301.530512 -156.158184)
					(mid 301.515633 -156.194105)
					(end 301.479712 -156.208984)
				)
				(arc
					(start 300.298612 -156.208984)
					(mid 300.262691 -156.194105)
					(end 300.247812 -156.158184)
				)
			)
		)
	)
	(zone
		(layer "In1.Cu")
		(hatch none 0.5)
		(connect_pads
			(clearance 0)
		)
		(min_thickness 0.25)
		(keepout
			(tracks not_allowed)
			(vias allowed)
			(pads allowed)
			(copperpour not_allowed)
			(footprints allowed)
		)
		(placement
			(enabled no)
			(sheetname "")
		)
		(fill
			(thermal_gap 0.5)
			(thermal_bridge_width 0.5)
			(island_removal_mode 0)
		)
		(polygon
			(pts
				(arc
					(start 399.55216 -103.848408)
					(mid 399.537281 -103.884329)
					(end 399.50136 -103.899208)
				)
				(arc
					(start 398.32026 -103.899208)
					(mid 398.284339 -103.884329)
					(end 398.26946 -103.848408)
				)
				(arc
					(start 398.26946 -102.84206)
					(mid 398.284339 -102.806139)
					(end 398.32026 -102.79126)
				)
				(arc
					(start 399.50136 -102.79126)
					(mid 399.537281 -102.806139)
					(end 399.55216 -102.84206)
				)
			)
		)
	)
	(zone
		(layer "In1.Cu")
		(hatch none 0.5)
		(connect_pads
			(clearance 0)
		)
		(min_thickness 0.25)
		(keepout
			(tracks not_allowed)
			(vias allowed)
			(pads allowed)
			(copperpour not_allowed)
			(footprints allowed)
		)
		(placement
			(enabled no)
			(sheetname "")
		)
		(fill
			(thermal_gap 0.5)
			(thermal_bridge_width 0.5)
			(island_removal_mode 0)
		)
		(polygon
			(pts
				(arc
					(start 196.219318 -343.533222)
					(mid 196.183397 -343.548101)
					(end 196.168518 -343.584022)
				)
				(arc
					(start 196.168518 -344.320622)
					(mid 196.183397 -344.356543)
					(end 196.219318 -344.371422)
				)
				(xy 196.463158 -344.371422) (xy 196.817488 -344.139012) (xy 197.173088 -344.371422)
				(arc
					(start 197.415658 -344.371422)
					(mid 197.451579 -344.356543)
					(end 197.466458 -344.320622)
				)
				(arc
					(start 197.466458 -343.584022)
					(mid 197.451579 -343.548101)
					(end 197.415658 -343.533222)
				)
				(xy 197.173088 -343.533222) (xy 196.816218 -343.765632) (xy 196.461888 -343.533222)
			)
		)
	)
	(zone
		(layer "In1.Cu")
		(hatch none 0.5)
		(connect_pads
			(clearance 0)
		)
		(min_thickness 0.25)
		(keepout
			(tracks not_allowed)
			(vias allowed)
			(pads allowed)
			(copperpour not_allowed)
			(footprints allowed)
		)
		(placement
			(enabled no)
			(sheetname "")
		)
		(fill
			(thermal_gap 0.5)
			(thermal_bridge_width 0.5)
			(island_removal_mode 0)
		)
		(polygon
			(pts
				(arc
					(start 314.442348 -156.251148)
					(mid 314.457227 -156.287069)
					(end 314.493148 -156.301948)
				)
				(arc
					(start 315.229748 -156.301948)
					(mid 315.265669 -156.287069)
					(end 315.280548 -156.251148)
				)
				(xy 315.280548 -156.007308) (xy 315.048138 -155.652978) (xy 315.280548 -155.297378)
				(arc
					(start 315.280548 -155.054808)
					(mid 315.265669 -155.018887)
					(end 315.229748 -155.004008)
				)
				(arc
					(start 314.493148 -155.004008)
					(mid 314.457227 -155.018887)
					(end 314.442348 -155.054808)
				)
				(xy 314.442348 -155.297378) (xy 314.674758 -155.654248) (xy 314.442348 -156.008578)
			)
		)
	)
	(zone
		(layer "In1.Cu")
		(hatch none 0.5)
		(connect_pads
			(clearance 0)
		)
		(min_thickness 0.25)
		(keepout
			(tracks not_allowed)
			(vias allowed)
			(pads allowed)
			(copperpour not_allowed)
			(footprints allowed)
		)
		(placement
			(enabled no)
			(sheetname "")
		)
		(fill
			(thermal_gap 0.5)
			(thermal_bridge_width 0.5)
			(island_removal_mode 0)
		)
		(polygon
			(pts
				(arc
					(start 399.55216 -112.848136)
					(mid 399.537281 -112.884057)
					(end 399.50136 -112.898936)
				)
				(arc
					(start 398.32026 -112.898936)
					(mid 398.284339 -112.884057)
					(end 398.26946 -112.848136)
				)
				(arc
					(start 398.26946 -111.841788)
					(mid 398.284339 -111.805867)
					(end 398.32026 -111.790988)
				)
				(arc
					(start 399.50136 -111.790988)
					(mid 399.537281 -111.805867)
					(end 399.55216 -111.841788)
				)
			)
		)
	)
	(zone
		(layer "In1.Cu")
		(hatch none 0.5)
		(connect_pads
			(clearance 0)
		)
		(min_thickness 0.25)
		(keepout
			(tracks not_allowed)
			(vias allowed)
			(pads allowed)
			(copperpour not_allowed)
			(footprints allowed)
		)
		(placement
			(enabled no)
			(sheetname "")
		)
		(fill
			(thermal_gap 0.5)
			(thermal_bridge_width 0.5)
			(island_removal_mode 0)
		)
		(polygon
			(pts
				(arc
					(start 167.351964 -120.158256)
					(mid 167.337085 -120.194177)
					(end 167.301164 -120.209056)
				)
				(arc
					(start 166.120064 -120.209056)
					(mid 166.084143 -120.194177)
					(end 166.069264 -120.158256)
				)
				(arc
					(start 166.069264 -119.151908)
					(mid 166.084143 -119.115987)
					(end 166.120064 -119.101108)
				)
				(arc
					(start 167.301164 -119.101108)
					(mid 167.337085 -119.115987)
					(end 167.351964 -119.151908)
				)
			)
		)
	)
	(zone
		(layer "In1.Cu")
		(hatch none 0.5)
		(connect_pads
			(clearance 0)
		)
		(min_thickness 0.25)
		(keepout
			(tracks not_allowed)
			(vias allowed)
			(pads allowed)
			(copperpour not_allowed)
			(footprints allowed)
		)
		(placement
			(enabled no)
			(sheetname "")
		)
		(fill
			(thermal_gap 0.5)
			(thermal_bridge_width 0.5)
			(island_removal_mode 0)
		)
		(polygon
			(pts
				(arc
					(start 267.731748 -349.679514)
					(mid 267.695827 -349.694393)
					(end 267.680948 -349.730314)
				)
				(arc
					(start 267.680948 -350.466914)
					(mid 267.695827 -350.502835)
					(end 267.731748 -350.517714)
				)
				(xy 267.975588 -350.517714) (xy 268.329918 -350.285304) (xy 268.685518 -350.517714)
				(arc
					(start 268.928088 -350.517714)
					(mid 268.964009 -350.502835)
					(end 268.978888 -350.466914)
				)
				(arc
					(start 268.978888 -349.730314)
					(mid 268.964009 -349.694393)
					(end 268.928088 -349.679514)
				)
				(xy 268.685518 -349.679514) (xy 268.328648 -349.911924) (xy 267.974318 -349.679514)
			)
		)
	)
	(zone
		(layer "In1.Cu")
		(hatch none 0.5)
		(connect_pads
			(clearance 0)
		)
		(min_thickness 0.25)
		(keepout
			(tracks not_allowed)
			(vias allowed)
			(pads allowed)
			(copperpour not_allowed)
			(footprints allowed)
		)
		(placement
			(enabled no)
			(sheetname "")
		)
		(fill
			(thermal_gap 0.5)
			(thermal_bridge_width 0.5)
			(island_removal_mode 0)
		)
		(polygon
			(pts
				(arc
					(start 180.674518 -355.825806)
					(mid 180.638597 -355.840685)
					(end 180.623718 -355.876606)
				)
				(arc
					(start 180.623718 -356.613206)
					(mid 180.638597 -356.649127)
					(end 180.674518 -356.664006)
				)
				(xy 180.918358 -356.664006) (xy 181.272688 -356.431596) (xy 181.628288 -356.664006)
				(arc
					(start 181.870858 -356.664006)
					(mid 181.906779 -356.649127)
					(end 181.921658 -356.613206)
				)
				(arc
					(start 181.921658 -355.876606)
					(mid 181.906779 -355.840685)
					(end 181.870858 -355.825806)
				)
				(xy 181.628288 -355.825806) (xy 181.271418 -356.058216) (xy 180.917088 -355.825806)
			)
		)
	)
	(zone
		(layer "In1.Cu")
		(hatch none 0.5)
		(connect_pads
			(clearance 0)
		)
		(min_thickness 0.25)
		(keepout
			(tracks not_allowed)
			(vias allowed)
			(pads allowed)
			(copperpour not_allowed)
			(footprints allowed)
		)
		(placement
			(enabled no)
			(sheetname "")
		)
		(fill
			(thermal_gap 0.5)
			(thermal_bridge_width 0.5)
			(island_removal_mode 0)
		)
		(polygon
			(pts
				(arc
					(start 99.752658 -385.050792)
					(mid 99.789855 -384.960989)
					(end 99.879658 -384.923792)
				)
				(arc
					(start 100.080826 -384.923792)
					(mid 100.170629 -384.960989)
					(end 100.207826 -385.050792)
				)
				(arc
					(start 100.207826 -385.304792)
					(mid 100.170629 -385.394595)
					(end 100.080826 -385.431792)
				)
				(arc
					(start 99.879658 -385.431792)
					(mid 99.789855 -385.394595)
					(end 99.752658 -385.304792)
				)
			)
		)
	)
	(zone
		(layer "In1.Cu")
		(hatch none 0.5)
		(connect_pads
			(clearance 0)
		)
		(min_thickness 0.25)
		(keepout
			(tracks not_allowed)
			(vias allowed)
			(pads allowed)
			(copperpour not_allowed)
			(footprints allowed)
		)
		(placement
			(enabled no)
			(sheetname "")
		)
		(fill
			(thermal_gap 0.5)
			(thermal_bridge_width 0.5)
			(island_removal_mode 0)
		)
		(polygon
			(pts
				(arc
					(start 157.999938 -32.805878)
					(mid 157.985059 -32.841799)
					(end 157.949138 -32.856678)
				)
				(arc
					(start 156.717238 -32.856678)
					(mid 156.681317 -32.841799)
					(end 156.666438 -32.805878)
				)
				(arc
					(start 156.666438 -31.77413)
					(mid 156.681317 -31.738209)
					(end 156.717238 -31.72333)
				)
				(arc
					(start 157.949138 -31.72333)
					(mid 157.985059 -31.738209)
					(end 157.999938 -31.77413)
				)
			)
		)
	)
	(zone
		(layer "In1.Cu")
		(hatch none 0.5)
		(connect_pads
			(clearance 0)
		)
		(min_thickness 0.25)
		(keepout
			(tracks not_allowed)
			(vias allowed)
			(pads allowed)
			(copperpour not_allowed)
			(footprints allowed)
		)
		(placement
			(enabled no)
			(sheetname "")
		)
		(fill
			(thermal_gap 0.5)
			(thermal_bridge_width 0.5)
			(island_removal_mode 0)
		)
		(polygon
			(pts
				(arc
					(start 195.700142 -123.32462)
					(mid 195.715021 -123.360541)
					(end 195.750942 -123.37542)
				)
				(arc
					(start 196.487542 -123.37542)
					(mid 196.523463 -123.360541)
					(end 196.538342 -123.32462)
				)
				(xy 196.538342 -123.08078) (xy 196.305932 -122.72645) (xy 196.538342 -122.37085)
				(arc
					(start 196.538342 -122.12828)
					(mid 196.523463 -122.092359)
					(end 196.487542 -122.07748)
				)
				(arc
					(start 195.750942 -122.07748)
					(mid 195.715021 -122.092359)
					(end 195.700142 -122.12828)
				)
				(xy 195.700142 -122.37085) (xy 195.932552 -122.72772) (xy 195.700142 -123.08205)
			)
		)
	)
	(zone
		(layer "In1.Cu")
		(hatch none 0.5)
		(connect_pads
			(clearance 0)
		)
		(min_thickness 0.25)
		(keepout
			(tracks not_allowed)
			(vias allowed)
			(pads allowed)
			(copperpour not_allowed)
			(footprints allowed)
		)
		(placement
			(enabled no)
			(sheetname "")
		)
		(fill
			(thermal_gap 0.5)
			(thermal_bridge_width 0.5)
			(island_removal_mode 0)
		)
		(polygon
			(pts
				(arc
					(start 306.067206 -154.358086)
					(mid 306.052327 -154.394007)
					(end 306.016406 -154.408886)
				)
				(arc
					(start 304.835306 -154.408886)
					(mid 304.799385 -154.394007)
					(end 304.784506 -154.358086)
				)
				(arc
					(start 304.784506 -153.351738)
					(mid 304.799385 -153.315817)
					(end 304.835306 -153.300938)
				)
				(arc
					(start 306.016406 -153.300938)
					(mid 306.052327 -153.315817)
					(end 306.067206 -153.351738)
				)
			)
		)
	)
	(zone
		(layer "In1.Cu")
		(hatch none 0.5)
		(connect_pads
			(clearance 0)
		)
		(min_thickness 0.25)
		(keepout
			(tracks not_allowed)
			(vias allowed)
			(pads allowed)
			(copperpour not_allowed)
			(footprints allowed)
		)
		(placement
			(enabled no)
			(sheetname "")
		)
		(fill
			(thermal_gap 0.5)
			(thermal_bridge_width 0.5)
			(island_removal_mode 0)
		)
		(polygon
			(pts
				(arc
					(start 384.32994 -28.174188)
					(mid 384.344819 -28.138267)
					(end 384.38074 -28.123388)
				)
				(arc
					(start 385.61264 -28.123388)
					(mid 385.648561 -28.138267)
					(end 385.66344 -28.174188)
				)
				(arc
					(start 385.66344 -29.205936)
					(mid 385.648561 -29.241857)
					(end 385.61264 -29.256736)
				)
				(arc
					(start 384.38074 -29.256736)
					(mid 384.344819 -29.241857)
					(end 384.32994 -29.205936)
				)
			)
		)
	)
	(zone
		(layer "In1.Cu")
		(hatch none 0.5)
		(connect_pads
			(clearance 0)
		)
		(min_thickness 0.25)
		(keepout
			(tracks not_allowed)
			(vias allowed)
			(pads allowed)
			(copperpour not_allowed)
			(footprints allowed)
		)
		(placement
			(enabled no)
			(sheetname "")
		)
		(fill
			(thermal_gap 0.5)
			(thermal_bridge_width 0.5)
			(island_removal_mode 0)
		)
		(polygon
			(pts
				(arc
					(start 283.452062 -120.158256)
					(mid 283.437183 -120.194177)
					(end 283.401262 -120.209056)
				)
				(arc
					(start 282.220162 -120.209056)
					(mid 282.184241 -120.194177)
					(end 282.169362 -120.158256)
				)
				(arc
					(start 282.169362 -119.151908)
					(mid 282.184241 -119.115987)
					(end 282.220162 -119.101108)
				)
				(arc
					(start 283.401262 -119.101108)
					(mid 283.437183 -119.115987)
					(end 283.452062 -119.151908)
				)
			)
		)
	)
	(zone
		(layer "In1.Cu")
		(hatch none 0.5)
		(connect_pads
			(clearance 0)
		)
		(min_thickness 0.25)
		(keepout
			(tracks not_allowed)
			(vias allowed)
			(pads allowed)
			(copperpour not_allowed)
			(footprints allowed)
		)
		(placement
			(enabled no)
			(sheetname "")
		)
		(fill
			(thermal_gap 0.5)
			(thermal_bridge_width 0.5)
			(island_removal_mode 0)
		)
		(polygon
			(pts
				(arc
					(start 421.565578 -343.533222)
					(mid 421.529657 -343.548101)
					(end 421.514778 -343.584022)
				)
				(arc
					(start 421.514778 -344.320622)
					(mid 421.529657 -344.356543)
					(end 421.565578 -344.371422)
				)
				(xy 421.809418 -344.371422) (xy 422.163748 -344.139012) (xy 422.519348 -344.371422)
				(arc
					(start 422.761918 -344.371422)
					(mid 422.797839 -344.356543)
					(end 422.812718 -344.320622)
				)
				(arc
					(start 422.812718 -343.584022)
					(mid 422.797839 -343.548101)
					(end 422.761918 -343.533222)
				)
				(xy 422.519348 -343.533222) (xy 422.162478 -343.765632) (xy 421.808148 -343.533222)
			)
		)
	)
	(zone
		(layer "In1.Cu")
		(hatch none 0.5)
		(connect_pads
			(clearance 0)
		)
		(min_thickness 0.25)
		(keepout
			(tracks not_allowed)
			(vias allowed)
			(pads allowed)
			(copperpour not_allowed)
			(footprints allowed)
		)
		(placement
			(enabled no)
			(sheetname "")
		)
		(fill
			(thermal_gap 0.5)
			(thermal_bridge_width 0.5)
			(island_removal_mode 0)
		)
		(polygon
			(pts
				(arc
					(start 393.732766 -120.952006)
					(mid 393.747645 -120.916085)
					(end 393.783566 -120.901206)
				)
				(arc
					(start 394.964666 -120.901206)
					(mid 395.000587 -120.916085)
					(end 395.015466 -120.952006)
				)
				(arc
					(start 395.015466 -121.958354)
					(mid 395.000587 -121.994275)
					(end 394.964666 -122.009154)
				)
				(arc
					(start 393.783566 -122.009154)
					(mid 393.747645 -121.994275)
					(end 393.732766 -121.958354)
				)
			)
		)
	)
	(zone
		(layer "In1.Cu")
		(hatch none 0.5)
		(connect_pads
			(clearance 0)
		)
		(min_thickness 0.25)
		(keepout
			(tracks not_allowed)
			(vias allowed)
			(pads allowed)
			(copperpour not_allowed)
			(footprints allowed)
		)
		(placement
			(enabled no)
			(sheetname "")
		)
		(fill
			(thermal_gap 0.5)
			(thermal_bridge_width 0.5)
			(island_removal_mode 0)
		)
		(polygon
			(pts
				(arc
					(start 277.632668 -133.96214)
					(mid 277.647547 -133.926219)
					(end 277.683468 -133.91134)
				)
				(arc
					(start 278.864568 -133.91134)
					(mid 278.900489 -133.926219)
					(end 278.915368 -133.96214)
				)
				(arc
					(start 278.915368 -134.968488)
					(mid 278.900489 -135.004409)
					(end 278.864568 -135.019288)
				)
				(arc
					(start 277.683468 -135.019288)
					(mid 277.647547 -135.004409)
					(end 277.632668 -134.968488)
				)
			)
		)
	)
	(zone
		(layer "In1.Cu")
		(hatch none 0.5)
		(connect_pads
			(clearance 0)
		)
		(min_thickness 0.25)
		(keepout
			(tracks not_allowed)
			(vias allowed)
			(pads allowed)
			(copperpour not_allowed)
			(footprints allowed)
		)
		(placement
			(enabled no)
			(sheetname "")
		)
		(fill
			(thermal_gap 0.5)
			(thermal_bridge_width 0.5)
			(island_removal_mode 0)
		)
		(polygon
			(pts
				(arc
					(start 306.067206 -136.24814)
					(mid 306.052327 -136.284061)
					(end 306.016406 -136.29894)
				)
				(arc
					(start 304.835306 -136.29894)
					(mid 304.799385 -136.284061)
					(end 304.784506 -136.24814)
				)
				(arc
					(start 304.784506 -135.241792)
					(mid 304.799385 -135.205871)
					(end 304.835306 -135.190992)
				)
				(arc
					(start 306.016406 -135.190992)
					(mid 306.052327 -135.205871)
					(end 306.067206 -135.241792)
				)
			)
		)
	)
	(zone
		(layer "In1.Cu")
		(hatch none 0.5)
		(connect_pads
			(clearance 0)
		)
		(min_thickness 0.25)
		(keepout
			(tracks not_allowed)
			(vias allowed)
			(pads allowed)
			(copperpour not_allowed)
			(footprints allowed)
		)
		(placement
			(enabled no)
			(sheetname "")
		)
		(fill
			(thermal_gap 0.5)
			(thermal_bridge_width 0.5)
			(island_removal_mode 0)
		)
		(polygon
			(pts
				(arc
					(start 447.797682 -208.302606)
					(mid 447.812561 -208.266685)
					(end 447.848482 -208.251806)
				)
				(arc
					(start 448.255136 -208.251806)
					(mid 448.291057 -208.266685)
					(end 448.305936 -208.302606)
				)
				(arc
					(start 448.305936 -208.704942)
					(mid 448.291057 -208.740863)
					(end 448.255136 -208.755742)
				)
				(arc
					(start 447.848482 -208.755742)
					(mid 447.812561 -208.740863)
					(end 447.797682 -208.704942)
				)
			)
		)
	)
	(zone
		(layer "In1.Cu")
		(hatch none 0.5)
		(connect_pads
			(clearance 0)
		)
		(min_thickness 0.25)
		(keepout
			(tracks not_allowed)
			(vias allowed)
			(pads allowed)
			(copperpour not_allowed)
			(footprints allowed)
		)
		(placement
			(enabled no)
			(sheetname "")
		)
		(fill
			(thermal_gap 0.5)
			(thermal_bridge_width 0.5)
			(island_removal_mode 0)
		)
		(polygon
			(pts
				(arc
					(start 99.85248 -386.204714)
					(mid 99.762677 -386.167517)
					(end 99.72548 -386.077714)
				)
				(arc
					(start 99.72548 -385.876546)
					(mid 99.762677 -385.786743)
					(end 99.85248 -385.749546)
				)
				(arc
					(start 100.10648 -385.749546)
					(mid 100.196283 -385.786743)
					(end 100.23348 -385.876546)
				)
				(arc
					(start 100.23348 -386.077714)
					(mid 100.196283 -386.167517)
					(end 100.10648 -386.204714)
				)
			)
		)
	)
	(zone
		(layer "In1.Cu")
		(hatch none 0.5)
		(connect_pads
			(clearance 0)
		)
		(min_thickness 0.25)
		(keepout
			(tracks not_allowed)
			(vias allowed)
			(pads allowed)
			(copperpour not_allowed)
			(footprints allowed)
		)
		(placement
			(enabled no)
			(sheetname "")
		)
		(fill
			(thermal_gap 0.5)
			(thermal_bridge_width 0.5)
			(island_removal_mode 0)
		)
		(polygon
			(pts
				(arc
					(start 232.24109 -83.591908)
					(mid 232.278287 -83.502105)
					(end 232.36809 -83.464908)
				)
				(arc
					(start 232.57129 -83.464908)
					(mid 232.661093 -83.502105)
					(end 232.69829 -83.591908)
				)
				(arc
					(start 232.69829 -83.845908)
					(mid 232.661093 -83.935711)
					(end 232.57129 -83.972908)
				)
				(arc
					(start 232.36809 -83.972908)
					(mid 232.278287 -83.935711)
					(end 232.24109 -83.845908)
				)
			)
		)
	)
	(zone
		(layer "In1.Cu")
		(hatch none 0.5)
		(connect_pads
			(clearance 0)
		)
		(min_thickness 0.25)
		(keepout
			(tracks not_allowed)
			(vias allowed)
			(pads allowed)
			(copperpour not_allowed)
			(footprints allowed)
		)
		(placement
			(enabled no)
			(sheetname "")
		)
		(fill
			(thermal_gap 0.5)
			(thermal_bridge_width 0.5)
			(island_removal_mode 0)
		)
		(polygon
			(pts
				(arc
					(start 320.229738 -31.77413)
					(mid 320.244617 -31.738209)
					(end 320.280538 -31.72333)
				)
				(arc
					(start 321.512438 -31.72333)
					(mid 321.548359 -31.738209)
					(end 321.563238 -31.77413)
				)
				(arc
					(start 321.563238 -32.805878)
					(mid 321.548359 -32.841799)
					(end 321.512438 -32.856678)
				)
				(arc
					(start 320.280538 -32.856678)
					(mid 320.244617 -32.841799)
					(end 320.229738 -32.805878)
				)
			)
		)
	)
	(zone
		(layer "In1.Cu")
		(hatch none 0.5)
		(connect_pads
			(clearance 0)
		)
		(min_thickness 0.25)
		(keepout
			(tracks not_allowed)
			(vias allowed)
			(pads allowed)
			(copperpour not_allowed)
			(footprints allowed)
		)
		(placement
			(enabled no)
			(sheetname "")
		)
		(fill
			(thermal_gap 0.5)
			(thermal_bridge_width 0.5)
			(island_removal_mode 0)
		)
		(polygon
			(pts
				(arc
					(start 300.09973 -34.605976)
					(mid 300.084851 -34.641897)
					(end 300.04893 -34.656776)
				)
				(arc
					(start 298.81703 -34.656776)
					(mid 298.781109 -34.641897)
					(end 298.76623 -34.605976)
				)
				(arc
					(start 298.76623 -33.574228)
					(mid 298.781109 -33.538307)
					(end 298.81703 -33.523428)
				)
				(arc
					(start 300.04893 -33.523428)
					(mid 300.084851 -33.538307)
					(end 300.09973 -33.574228)
				)
			)
		)
	)
	(zone
		(layer "In1.Cu")
		(hatch none 0.5)
		(connect_pads
			(clearance 0)
		)
		(min_thickness 0.25)
		(keepout
			(tracks not_allowed)
			(vias allowed)
			(pads allowed)
			(copperpour not_allowed)
			(footprints allowed)
		)
		(placement
			(enabled no)
			(sheetname "")
		)
		(fill
			(thermal_gap 0.5)
			(thermal_bridge_width 0.5)
			(island_removal_mode 0)
		)
		(polygon
			(pts
				(arc
					(start 92.296488 -343.533222)
					(mid 92.260567 -343.548101)
					(end 92.245688 -343.584022)
				)
				(arc
					(start 92.245688 -344.320622)
					(mid 92.260567 -344.356543)
					(end 92.296488 -344.371422)
				)
				(xy 92.540328 -344.371422) (xy 92.894658 -344.139012) (xy 93.250258 -344.371422)
				(arc
					(start 93.492828 -344.371422)
					(mid 93.528749 -344.356543)
					(end 93.543628 -344.320622)
				)
				(arc
					(start 93.543628 -343.584022)
					(mid 93.528749 -343.548101)
					(end 93.492828 -343.533222)
				)
				(xy 93.250258 -343.533222) (xy 92.893388 -343.765632) (xy 92.539058 -343.533222)
			)
		)
	)
	(zone
		(layer "In1.Cu")
		(hatch none 0.5)
		(connect_pads
			(clearance 0)
		)
		(min_thickness 0.25)
		(keepout
			(tracks not_allowed)
			(vias allowed)
			(pads allowed)
			(copperpour not_allowed)
			(footprints allowed)
		)
		(placement
			(enabled no)
			(sheetname "")
		)
		(fill
			(thermal_gap 0.5)
			(thermal_bridge_width 0.5)
			(island_removal_mode 0)
		)
		(polygon
			(pts
				(arc
					(start 430.542446 -156.251148)
					(mid 430.557325 -156.287069)
					(end 430.593246 -156.301948)
				)
				(arc
					(start 431.329846 -156.301948)
					(mid 431.365767 -156.287069)
					(end 431.380646 -156.251148)
				)
				(xy 431.380646 -156.007308) (xy 431.148236 -155.652978) (xy 431.380646 -155.297378)
				(arc
					(start 431.380646 -155.054808)
					(mid 431.365767 -155.018887)
					(end 431.329846 -155.004008)
				)
				(arc
					(start 430.593246 -155.004008)
					(mid 430.557325 -155.018887)
					(end 430.542446 -155.054808)
				)
				(xy 430.542446 -155.297378) (xy 430.774856 -155.654248) (xy 430.542446 -156.008578)
			)
		)
	)
	(zone
		(layer "In1.Cu")
		(hatch none 0.5)
		(connect_pads
			(clearance 0)
		)
		(min_thickness 0.25)
		(keepout
			(tracks not_allowed)
			(vias allowed)
			(pads allowed)
			(copperpour not_allowed)
			(footprints allowed)
		)
		(placement
			(enabled no)
			(sheetname "")
		)
		(fill
			(thermal_gap 0.5)
			(thermal_bridge_width 0.5)
			(island_removal_mode 0)
		)
		(polygon
			(pts
				(arc
					(start 157.999938 -29.205936)
					(mid 157.985059 -29.241857)
					(end 157.949138 -29.256736)
				)
				(arc
					(start 156.717238 -29.256736)
					(mid 156.681317 -29.241857)
					(end 156.666438 -29.205936)
				)
				(arc
					(start 156.666438 -28.174188)
					(mid 156.681317 -28.138267)
					(end 156.717238 -28.123388)
				)
				(arc
					(start 157.949138 -28.123388)
					(mid 157.985059 -28.138267)
					(end 157.999938 -28.174188)
				)
			)
		)
	)
	(zone
		(layer "In1.Cu")
		(hatch none 0.5)
		(connect_pads
			(clearance 0)
		)
		(min_thickness 0.25)
		(keepout
			(tracks not_allowed)
			(vias allowed)
			(pads allowed)
			(copperpour not_allowed)
			(footprints allowed)
		)
		(placement
			(enabled no)
			(sheetname "")
		)
		(fill
			(thermal_gap 0.5)
			(thermal_bridge_width 0.5)
			(island_removal_mode 0)
		)
		(polygon
			(pts
				(arc
					(start 300.247812 -144.351756)
					(mid 300.262691 -144.315835)
					(end 300.298612 -144.300956)
				)
				(arc
					(start 301.479712 -144.300956)
					(mid 301.515633 -144.315835)
					(end 301.530512 -144.351756)
				)
				(arc
					(start 301.530512 -145.358104)
					(mid 301.515633 -145.394025)
					(end 301.479712 -145.408904)
				)
				(arc
					(start 300.298612 -145.408904)
					(mid 300.262691 -145.394025)
					(end 300.247812 -145.358104)
				)
			)
		)
	)
	(zone
		(layer "In1.Cu")
		(hatch none 0.5)
		(connect_pads
			(clearance 0)
		)
		(min_thickness 0.25)
		(keepout
			(tracks not_allowed)
			(vias allowed)
			(pads allowed)
			(copperpour not_allowed)
			(footprints allowed)
		)
		(placement
			(enabled no)
			(sheetname "")
		)
		(fill
			(thermal_gap 0.5)
			(thermal_bridge_width 0.5)
			(island_removal_mode 0)
		)
		(polygon
			(pts
				(arc
					(start 387.161532 -133.269736)
					(mid 387.176411 -133.305657)
					(end 387.212332 -133.320536)
				)
				(arc
					(start 387.948932 -133.320536)
					(mid 387.984853 -133.305657)
					(end 387.999732 -133.269736)
				)
				(xy 387.999732 -133.025896) (xy 387.767322 -132.671566) (xy 387.999732 -132.315966)
				(arc
					(start 387.999732 -132.073396)
					(mid 387.984853 -132.037475)
					(end 387.948932 -132.022596)
				)
				(arc
					(start 387.212332 -132.022596)
					(mid 387.176411 -132.037475)
					(end 387.161532 -132.073396)
				)
				(xy 387.161532 -132.315966) (xy 387.393942 -132.672836) (xy 387.161532 -133.027166)
			)
		)
	)
	(zone
		(layer "In1.Cu")
		(hatch none 0.5)
		(connect_pads
			(clearance 0)
		)
		(min_thickness 0.25)
		(keepout
			(tracks not_allowed)
			(vias allowed)
			(pads allowed)
			(copperpour not_allowed)
			(footprints allowed)
		)
		(placement
			(enabled no)
			(sheetname "")
		)
		(fill
			(thermal_gap 0.5)
			(thermal_bridge_width 0.5)
			(island_removal_mode 0)
		)
		(polygon
			(pts
				(arc
					(start 79.600298 -143.64462)
					(mid 79.615177 -143.680541)
					(end 79.651098 -143.69542)
				)
				(arc
					(start 80.387698 -143.69542)
					(mid 80.423619 -143.680541)
					(end 80.438498 -143.64462)
				)
				(xy 80.438498 -143.40078) (xy 80.206088 -143.04645) (xy 80.438498 -142.69085)
				(arc
					(start 80.438498 -142.44828)
					(mid 80.423619 -142.412359)
					(end 80.387698 -142.39748)
				)
				(arc
					(start 79.651098 -142.39748)
					(mid 79.615177 -142.412359)
					(end 79.600298 -142.44828)
				)
				(xy 79.600298 -142.69085) (xy 79.832708 -143.04772) (xy 79.600298 -143.40205)
			)
		)
	)
	(zone
		(layer "In1.Cu")
		(hatch none 0.5)
		(connect_pads
			(clearance 0)
		)
		(min_thickness 0.25)
		(keepout
			(tracks not_allowed)
			(vias allowed)
			(pads allowed)
			(copperpour not_allowed)
			(footprints allowed)
		)
		(placement
			(enabled no)
			(sheetname "")
		)
		(fill
			(thermal_gap 0.5)
			(thermal_bridge_width 0.5)
			(island_removal_mode 0)
		)
		(polygon
			(pts
				(arc
					(start 368.315494 -34.68624)
					(mid 368.330373 -34.722161)
					(end 368.366294 -34.73704)
				)
				(arc
					(start 369.102894 -34.73704)
					(mid 369.138815 -34.722161)
					(end 369.153694 -34.68624)
				)
				(xy 369.153694 -34.4424) (xy 368.921284 -34.08807) (xy 369.153694 -33.73247)
				(arc
					(start 369.153694 -33.4899)
					(mid 369.138815 -33.453979)
					(end 369.102894 -33.4391)
				)
				(arc
					(start 368.366294 -33.4391)
					(mid 368.330373 -33.453979)
					(end 368.315494 -33.4899)
				)
				(xy 368.315494 -33.73247) (xy 368.547904 -34.08934) (xy 368.315494 -34.44367)
			)
		)
	)
	(zone
		(layer "In1.Cu")
		(hatch none 0.5)
		(connect_pads
			(clearance 0)
		)
		(min_thickness 0.25)
		(keepout
			(tracks not_allowed)
			(vias allowed)
			(pads allowed)
			(copperpour not_allowed)
			(footprints allowed)
		)
		(placement
			(enabled no)
			(sheetname "")
		)
		(fill
			(thermal_gap 0.5)
			(thermal_bridge_width 0.5)
			(island_removal_mode 0)
		)
		(polygon
			(pts
				(arc
					(start 106.512106 -380.272036)
					(mid 106.601909 -380.309233)
					(end 106.639106 -380.399036)
				)
				(arc
					(start 106.639106 -380.600204)
					(mid 106.601909 -380.690007)
					(end 106.512106 -380.727204)
				)
				(arc
					(start 106.258106 -380.727204)
					(mid 106.168303 -380.690007)
					(end 106.131106 -380.600204)
				)
				(arc
					(start 106.131106 -380.399036)
					(mid 106.168303 -380.309233)
					(end 106.258106 -380.272036)
				)
			)
		)
	)
	(zone
		(layer "In1.Cu")
		(hatch none 0.5)
		(connect_pads
			(clearance 0)
		)
		(min_thickness 0.25)
		(keepout
			(tracks not_allowed)
			(vias allowed)
			(pads allowed)
			(copperpour not_allowed)
			(footprints allowed)
		)
		(placement
			(enabled no)
			(sheetname "")
		)
		(fill
			(thermal_gap 0.5)
			(thermal_bridge_width 0.5)
			(island_removal_mode 0)
		)
		(polygon
			(pts
				(arc
					(start 230.252778 -79.159608)
					(mid 230.267657 -79.123687)
					(end 230.303578 -79.108808)
				)
				(arc
					(start 230.356918 -79.108808)
					(mid 230.392839 -79.123687)
					(end 230.407718 -79.159608)
				)
				(arc
					(start 230.407718 -79.771494)
					(mid 230.392839 -79.807415)
					(end 230.356918 -79.822294)
				)
				(arc
					(start 230.303578 -79.822294)
					(mid 230.267657 -79.807415)
					(end 230.252778 -79.771494)
				)
			)
		)
	)
	(zone
		(layer "In1.Cu")
		(hatch none 0.5)
		(connect_pads
			(clearance 0)
		)
		(min_thickness 0.25)
		(keepout
			(tracks not_allowed)
			(vias allowed)
			(pads allowed)
			(copperpour not_allowed)
			(footprints allowed)
		)
		(placement
			(enabled no)
			(sheetname "")
		)
		(fill
			(thermal_gap 0.5)
			(thermal_bridge_width 0.5)
			(island_removal_mode 0)
		)
		(polygon
			(pts
				(arc
					(start 152.319228 -105.749852)
					(mid 152.334107 -105.785773)
					(end 152.370028 -105.800652)
				)
				(arc
					(start 153.106628 -105.800652)
					(mid 153.142549 -105.785773)
					(end 153.157428 -105.749852)
				)
				(xy 153.157428 -105.506012) (xy 152.925018 -105.151682) (xy 153.157428 -104.796082)
				(arc
					(start 153.157428 -104.553512)
					(mid 153.142549 -104.517591)
					(end 153.106628 -104.502712)
				)
				(arc
					(start 152.370028 -104.502712)
					(mid 152.334107 -104.517591)
					(end 152.319228 -104.553512)
				)
				(xy 152.319228 -104.796082) (xy 152.551638 -105.152952) (xy 152.319228 -105.507282)
			)
		)
	)
	(zone
		(layer "In1.Cu")
		(hatch none 0.5)
		(connect_pads
			(clearance 0)
		)
		(min_thickness 0.25)
		(keepout
			(tracks not_allowed)
			(vias allowed)
			(pads allowed)
			(copperpour not_allowed)
			(footprints allowed)
		)
		(placement
			(enabled no)
			(sheetname "")
		)
		(fill
			(thermal_gap 0.5)
			(thermal_bridge_width 0.5)
			(island_removal_mode 0)
		)
		(polygon
			(pts
				(arc
					(start 294.22979 -33.574228)
					(mid 294.244669 -33.538307)
					(end 294.28059 -33.523428)
				)
				(arc
					(start 295.51249 -33.523428)
					(mid 295.548411 -33.538307)
					(end 295.56329 -33.574228)
				)
				(arc
					(start 295.56329 -34.605976)
					(mid 295.548411 -34.641897)
					(end 295.51249 -34.656776)
				)
				(arc
					(start 294.28059 -34.656776)
					(mid 294.244669 -34.641897)
					(end 294.22979 -34.605976)
				)
			)
		)
	)
	(zone
		(layer "In1.Cu")
		(hatch none 0.5)
		(connect_pads
			(clearance 0)
		)
		(min_thickness 0.25)
		(keepout
			(tracks not_allowed)
			(vias allowed)
			(pads allowed)
			(copperpour not_allowed)
			(footprints allowed)
		)
		(placement
			(enabled no)
			(sheetname "")
		)
		(fill
			(thermal_gap 0.5)
			(thermal_bridge_width 0.5)
			(island_removal_mode 0)
		)
		(polygon
			(pts
				(arc
					(start 73.867264 -152.558242)
					(mid 73.852385 -152.594163)
					(end 73.816464 -152.609042)
				)
				(arc
					(start 72.635364 -152.609042)
					(mid 72.599443 -152.594163)
					(end 72.584564 -152.558242)
				)
				(arc
					(start 72.584564 -151.551894)
					(mid 72.599443 -151.515973)
					(end 72.635364 -151.501094)
				)
				(arc
					(start 73.816464 -151.501094)
					(mid 73.852385 -151.515973)
					(end 73.867264 -151.551894)
				)
			)
		)
	)
	(zone
		(layer "In1.Cu")
		(hatch none 0.5)
		(connect_pads
			(clearance 0)
		)
		(min_thickness 0.25)
		(keepout
			(tracks not_allowed)
			(vias allowed)
			(pads allowed)
			(copperpour not_allowed)
			(footprints allowed)
		)
		(placement
			(enabled no)
			(sheetname "")
		)
		(fill
			(thermal_gap 0.5)
			(thermal_bridge_width 0.5)
			(island_removal_mode 0)
		)
		(polygon
			(pts
				(arc
					(start 89.187528 -355.825806)
					(mid 89.151607 -355.840685)
					(end 89.136728 -355.876606)
				)
				(arc
					(start 89.136728 -356.613206)
					(mid 89.151607 -356.649127)
					(end 89.187528 -356.664006)
				)
				(xy 89.431368 -356.664006) (xy 89.785698 -356.431596) (xy 90.141298 -356.664006)
				(arc
					(start 90.383868 -356.664006)
					(mid 90.419789 -356.649127)
					(end 90.434668 -356.613206)
				)
				(arc
					(start 90.434668 -355.876606)
					(mid 90.419789 -355.840685)
					(end 90.383868 -355.825806)
				)
				(xy 90.141298 -355.825806) (xy 89.784428 -356.058216) (xy 89.430098 -355.825806)
			)
		)
	)
	(zone
		(layer "In1.Cu")
		(hatch none 0.5)
		(connect_pads
			(clearance 0)
		)
		(min_thickness 0.25)
		(keepout
			(tracks not_allowed)
			(vias allowed)
			(pads allowed)
			(copperpour not_allowed)
			(footprints allowed)
		)
		(placement
			(enabled no)
			(sheetname "")
		)
		(fill
			(thermal_gap 0.5)
			(thermal_bridge_width 0.5)
			(island_removal_mode 0)
		)
		(polygon
			(pts
				(arc
					(start 70.533768 -349.679514)
					(mid 70.497847 -349.694393)
					(end 70.482968 -349.730314)
				)
				(arc
					(start 70.482968 -350.466914)
					(mid 70.497847 -350.502835)
					(end 70.533768 -350.517714)
				)
				(xy 70.777608 -350.517714) (xy 71.131938 -350.285304) (xy 71.487538 -350.517714)
				(arc
					(start 71.730108 -350.517714)
					(mid 71.766029 -350.502835)
					(end 71.780908 -350.466914)
				)
				(arc
					(start 71.780908 -349.730314)
					(mid 71.766029 -349.694393)
					(end 71.730108 -349.679514)
				)
				(xy 71.487538 -349.679514) (xy 71.130668 -349.911924) (xy 70.776338 -349.679514)
			)
		)
	)
	(zone
		(layer "In1.Cu")
		(hatch none 0.5)
		(connect_pads
			(clearance 0)
		)
		(min_thickness 0.25)
		(keepout
			(tracks not_allowed)
			(vias allowed)
			(pads allowed)
			(copperpour not_allowed)
			(footprints allowed)
		)
		(placement
			(enabled no)
			(sheetname "")
		)
		(fill
			(thermal_gap 0.5)
			(thermal_bridge_width 0.5)
			(island_removal_mode 0)
		)
		(polygon
			(pts
				(arc
					(start 294.22979 -31.77413)
					(mid 294.244669 -31.738209)
					(end 294.28059 -31.72333)
				)
				(arc
					(start 295.51249 -31.72333)
					(mid 295.548411 -31.738209)
					(end 295.56329 -31.77413)
				)
				(arc
					(start 295.56329 -32.805878)
					(mid 295.548411 -32.841799)
					(end 295.51249 -32.856678)
				)
				(arc
					(start 294.28059 -32.856678)
					(mid 294.244669 -32.841799)
					(end 294.22979 -32.805878)
				)
			)
		)
	)
	(zone
		(layer "In1.Cu")
		(hatch none 0.5)
		(connect_pads
			(clearance 0)
		)
		(min_thickness 0.25)
		(keepout
			(tracks not_allowed)
			(vias allowed)
			(pads allowed)
			(copperpour not_allowed)
			(footprints allowed)
		)
		(placement
			(enabled no)
			(sheetname "")
		)
		(fill
			(thermal_gap 0.5)
			(thermal_bridge_width 0.5)
			(island_removal_mode 0)
		)
		(polygon
			(pts
				(arc
					(start 44.038774 -349.679514)
					(mid 44.002853 -349.694393)
					(end 43.987974 -349.730314)
				)
				(arc
					(start 43.987974 -350.466914)
					(mid 44.002853 -350.502835)
					(end 44.038774 -350.517714)
				)
				(xy 44.282614 -350.517714) (xy 44.636944 -350.285304) (xy 44.992544 -350.517714)
				(arc
					(start 45.235114 -350.517714)
					(mid 45.271035 -350.502835)
					(end 45.285914 -350.466914)
				)
				(arc
					(start 45.285914 -349.730314)
					(mid 45.271035 -349.694393)
					(end 45.235114 -349.679514)
				)
				(xy 44.992544 -349.679514) (xy 44.635674 -349.911924) (xy 44.281344 -349.679514)
			)
		)
	)
	(zone
		(layer "In1.Cu")
		(hatch none 0.5)
		(connect_pads
			(clearance 0)
		)
		(min_thickness 0.25)
		(keepout
			(tracks not_allowed)
			(vias allowed)
			(pads allowed)
			(copperpour not_allowed)
			(footprints allowed)
		)
		(placement
			(enabled no)
			(sheetname "")
		)
		(fill
			(thermal_gap 0.5)
			(thermal_bridge_width 0.5)
			(island_removal_mode 0)
		)
		(polygon
			(pts
				(arc
					(start 306.067206 -147.158202)
					(mid 306.052327 -147.194123)
					(end 306.016406 -147.209002)
				)
				(arc
					(start 304.835306 -147.209002)
					(mid 304.799385 -147.194123)
					(end 304.784506 -147.158202)
				)
				(arc
					(start 304.784506 -146.151854)
					(mid 304.799385 -146.115933)
					(end 304.835306 -146.101054)
				)
				(arc
					(start 306.016406 -146.101054)
					(mid 306.052327 -146.115933)
					(end 306.067206 -146.151854)
				)
			)
		)
	)
	(zone
		(layer "In1.Cu")
		(hatch none 0.5)
		(connect_pads
			(clearance 0)
		)
		(min_thickness 0.25)
		(keepout
			(tracks not_allowed)
			(vias allowed)
			(pads allowed)
			(copperpour not_allowed)
			(footprints allowed)
		)
		(placement
			(enabled no)
			(sheetname "")
		)
		(fill
			(thermal_gap 0.5)
			(thermal_bridge_width 0.5)
			(island_removal_mode 0)
		)
		(polygon
			(pts
				(arc
					(start 185.47334 -32.879538)
					(mid 185.488219 -32.915459)
					(end 185.52414 -32.930338)
				)
				(arc
					(start 186.26074 -32.930338)
					(mid 186.296661 -32.915459)
					(end 186.31154 -32.879538)
				)
				(xy 186.31154 -32.635698) (xy 186.07913 -32.281368) (xy 186.31154 -31.925768)
				(arc
					(start 186.31154 -31.683198)
					(mid 186.296661 -31.647277)
					(end 186.26074 -31.632398)
				)
				(arc
					(start 185.52414 -31.632398)
					(mid 185.488219 -31.647277)
					(end 185.47334 -31.683198)
				)
				(xy 185.47334 -31.925768) (xy 185.70575 -32.282638) (xy 185.47334 -32.636968)
			)
		)
	)
	(zone
		(layer "In1.Cu")
		(hatch none 0.5)
		(connect_pads
			(clearance 0)
		)
		(min_thickness 0.25)
		(keepout
			(tracks not_allowed)
			(vias allowed)
			(pads allowed)
			(copperpour not_allowed)
			(footprints allowed)
		)
		(placement
			(enabled no)
			(sheetname "")
		)
		(fill
			(thermal_gap 0.5)
			(thermal_bridge_width 0.5)
			(island_removal_mode 0)
		)
		(polygon
			(pts
				(arc
					(start 416.34791 -122.231912)
					(mid 416.362789 -122.195991)
					(end 416.39871 -122.181112)
				)
				(arc
					(start 417.57981 -122.181112)
					(mid 417.615731 -122.195991)
					(end 417.63061 -122.231912)
				)
				(arc
					(start 417.63061 -123.23826)
					(mid 417.615731 -123.274181)
					(end 417.57981 -123.28906)
				)
				(arc
					(start 416.39871 -123.28906)
					(mid 416.362789 -123.274181)
					(end 416.34791 -123.23826)
				)
			)
		)
	)
	(zone
		(layer "In1.Cu")
		(hatch none 0.5)
		(connect_pads
			(clearance 0)
		)
		(min_thickness 0.25)
		(keepout
			(tracks not_allowed)
			(vias allowed)
			(pads allowed)
			(copperpour not_allowed)
			(footprints allowed)
		)
		(placement
			(enabled no)
			(sheetname "")
		)
		(fill
			(thermal_gap 0.5)
			(thermal_bridge_width 0.5)
			(island_removal_mode 0)
		)
		(polygon
			(pts
				(arc
					(start 82.242406 -132.741162)
					(mid 82.257285 -132.777083)
					(end 82.293206 -132.791962)
				)
				(arc
					(start 83.029806 -132.791962)
					(mid 83.065727 -132.777083)
					(end 83.080606 -132.741162)
				)
				(xy 83.080606 -132.497322) (xy 82.848196 -132.142992) (xy 83.080606 -131.787392)
				(arc
					(start 83.080606 -131.544822)
					(mid 83.065727 -131.508901)
					(end 83.029806 -131.494022)
				)
				(arc
					(start 82.293206 -131.494022)
					(mid 82.257285 -131.508901)
					(end 82.242406 -131.544822)
				)
				(xy 82.242406 -131.787392) (xy 82.474816 -132.144262) (xy 82.242406 -132.498592)
			)
		)
	)
	(zone
		(layer "In1.Cu")
		(hatch none 0.5)
		(connect_pads
			(clearance 0)
		)
		(min_thickness 0.25)
		(keepout
			(tracks not_allowed)
			(vias allowed)
			(pads allowed)
			(copperpour not_allowed)
			(footprints allowed)
		)
		(placement
			(enabled no)
			(sheetname "")
		)
		(fill
			(thermal_gap 0.5)
			(thermal_bridge_width 0.5)
			(island_removal_mode 0)
		)
		(polygon
			(pts
				(arc
					(start 399.55216 -105.648252)
					(mid 399.537281 -105.684173)
					(end 399.50136 -105.699052)
				)
				(arc
					(start 398.32026 -105.699052)
					(mid 398.284339 -105.684173)
					(end 398.26946 -105.648252)
				)
				(arc
					(start 398.26946 -104.641904)
					(mid 398.284339 -104.605983)
					(end 398.32026 -104.591104)
				)
				(arc
					(start 399.50136 -104.591104)
					(mid 399.537281 -104.605983)
					(end 399.55216 -104.641904)
				)
			)
		)
	)
	(zone
		(layer "In1.Cu")
		(hatch none 0.5)
		(connect_pads
			(clearance 0)
		)
		(min_thickness 0.25)
		(keepout
			(tracks not_allowed)
			(vias allowed)
			(pads allowed)
			(copperpour not_allowed)
			(footprints allowed)
		)
		(placement
			(enabled no)
			(sheetname "")
		)
		(fill
			(thermal_gap 0.5)
			(thermal_bridge_width 0.5)
			(island_removal_mode 0)
		)
		(polygon
			(pts
				(arc
					(start 198.34225 -152.651206)
					(mid 198.357129 -152.687127)
					(end 198.39305 -152.702006)
				)
				(arc
					(start 199.12965 -152.702006)
					(mid 199.165571 -152.687127)
					(end 199.18045 -152.651206)
				)
				(xy 199.18045 -152.407366) (xy 198.94804 -152.053036) (xy 199.18045 -151.697436)
				(arc
					(start 199.18045 -151.454866)
					(mid 199.165571 -151.418945)
					(end 199.12965 -151.404066)
				)
				(arc
					(start 198.39305 -151.404066)
					(mid 198.357129 -151.418945)
					(end 198.34225 -151.454866)
				)
				(xy 198.34225 -151.697436) (xy 198.57466 -152.054306) (xy 198.34225 -152.408636)
			)
		)
	)
	(zone
		(layer "In1.Cu")
		(hatch none 0.5)
		(connect_pads
			(clearance 0)
		)
		(min_thickness 0.25)
		(keepout
			(tracks not_allowed)
			(vias allowed)
			(pads allowed)
			(copperpour not_allowed)
			(footprints allowed)
		)
		(placement
			(enabled no)
			(sheetname "")
		)
		(fill
			(thermal_gap 0.5)
			(thermal_bridge_width 0.5)
			(island_removal_mode 0)
		)
		(polygon
			(pts
				(arc
					(start 117.914674 -355.825806)
					(mid 117.878753 -355.840685)
					(end 117.863874 -355.876606)
				)
				(arc
					(start 117.863874 -356.613206)
					(mid 117.878753 -356.649127)
					(end 117.914674 -356.664006)
				)
				(xy 118.158514 -356.664006) (xy 118.512844 -356.431596) (xy 118.868444 -356.664006)
				(arc
					(start 119.111014 -356.664006)
					(mid 119.146935 -356.649127)
					(end 119.161814 -356.613206)
				)
				(arc
					(start 119.161814 -355.876606)
					(mid 119.146935 -355.840685)
					(end 119.111014 -355.825806)
				)
				(xy 118.868444 -355.825806) (xy 118.511574 -356.058216) (xy 118.157244 -355.825806)
			)
		)
	)
	(zone
		(layer "In1.Cu")
		(hatch none 0.5)
		(connect_pads
			(clearance 0)
		)
		(min_thickness 0.25)
		(keepout
			(tracks not_allowed)
			(vias allowed)
			(pads allowed)
			(copperpour not_allowed)
			(footprints allowed)
		)
		(placement
			(enabled no)
			(sheetname "")
		)
		(fill
			(thermal_gap 0.5)
			(thermal_bridge_width 0.5)
			(island_removal_mode 0)
		)
		(polygon
			(pts
				(arc
					(start 364.199932 -27.405838)
					(mid 364.185053 -27.441759)
					(end 364.149132 -27.456638)
				)
				(arc
					(start 362.917232 -27.456638)
					(mid 362.881311 -27.441759)
					(end 362.866432 -27.405838)
				)
				(arc
					(start 362.866432 -26.37409)
					(mid 362.881311 -26.338169)
					(end 362.917232 -26.32329)
				)
				(arc
					(start 364.149132 -26.32329)
					(mid 364.185053 -26.338169)
					(end 364.199932 -26.37409)
				)
			)
		)
	)
	(zone
		(layer "In1.Cu")
		(hatch none 0.5)
		(connect_pads
			(clearance 0)
		)
		(min_thickness 0.25)
		(keepout
			(tracks not_allowed)
			(vias allowed)
			(pads allowed)
			(copperpour not_allowed)
			(footprints allowed)
		)
		(placement
			(enabled no)
			(sheetname "")
		)
		(fill
			(thermal_gap 0.5)
			(thermal_bridge_width 0.5)
			(island_removal_mode 0)
		)
		(polygon
			(pts
				(arc
					(start 79.600298 -119.724678)
					(mid 79.615177 -119.760599)
					(end 79.651098 -119.775478)
				)
				(arc
					(start 80.387698 -119.775478)
					(mid 80.423619 -119.760599)
					(end 80.438498 -119.724678)
				)
				(xy 80.438498 -119.480838) (xy 80.206088 -119.126508) (xy 80.438498 -118.770908)
				(arc
					(start 80.438498 -118.528338)
					(mid 80.423619 -118.492417)
					(end 80.387698 -118.477538)
				)
				(arc
					(start 79.651098 -118.477538)
					(mid 79.615177 -118.492417)
					(end 79.600298 -118.528338)
				)
				(xy 79.600298 -118.770908) (xy 79.832708 -119.127778) (xy 79.600298 -119.482108)
			)
		)
	)
	(zone
		(layer "In1.Cu")
		(hatch none 0.5)
		(connect_pads
			(clearance 0)
		)
		(min_thickness 0.25)
		(keepout
			(tracks not_allowed)
			(vias allowed)
			(pads allowed)
			(copperpour not_allowed)
			(footprints allowed)
		)
		(placement
			(enabled no)
			(sheetname "")
		)
		(fill
			(thermal_gap 0.5)
			(thermal_bridge_width 0.5)
			(island_removal_mode 0)
		)
		(polygon
			(pts
				(arc
					(start 124.132594 -355.825806)
					(mid 124.096673 -355.840685)
					(end 124.081794 -355.876606)
				)
				(arc
					(start 124.081794 -356.613206)
					(mid 124.096673 -356.649127)
					(end 124.132594 -356.664006)
				)
				(xy 124.376434 -356.664006) (xy 124.730764 -356.431596) (xy 125.086364 -356.664006)
				(arc
					(start 125.328934 -356.664006)
					(mid 125.364855 -356.649127)
					(end 125.379734 -356.613206)
				)
				(arc
					(start 125.379734 -355.876606)
					(mid 125.364855 -355.840685)
					(end 125.328934 -355.825806)
				)
				(xy 125.086364 -355.825806) (xy 124.729494 -356.058216) (xy 124.375164 -355.825806)
			)
		)
	)
	(zone
		(layer "In1.Cu")
		(hatch none 0.5)
		(connect_pads
			(clearance 0)
		)
		(min_thickness 0.25)
		(keepout
			(tracks not_allowed)
			(vias allowed)
			(pads allowed)
			(copperpour not_allowed)
			(footprints allowed)
		)
		(placement
			(enabled no)
			(sheetname "")
		)
		(fill
			(thermal_gap 0.5)
			(thermal_bridge_width 0.5)
			(island_removal_mode 0)
		)
		(polygon
			(pts
				(arc
					(start 161.53257 -124.551948)
					(mid 161.547449 -124.516027)
					(end 161.58337 -124.501148)
				)
				(arc
					(start 162.76447 -124.501148)
					(mid 162.800391 -124.516027)
					(end 162.81527 -124.551948)
				)
				(arc
					(start 162.81527 -125.558296)
					(mid 162.800391 -125.594217)
					(end 162.76447 -125.609096)
				)
				(arc
					(start 161.58337 -125.609096)
					(mid 161.547449 -125.594217)
					(end 161.53257 -125.558296)
				)
			)
		)
	)
	(zone
		(layer "In1.Cu")
		(hatch none 0.5)
		(connect_pads
			(clearance 0)
		)
		(min_thickness 0.25)
		(keepout
			(tracks not_allowed)
			(vias allowed)
			(pads allowed)
			(copperpour not_allowed)
			(footprints allowed)
		)
		(placement
			(enabled no)
			(sheetname "")
		)
		(fill
			(thermal_gap 0.5)
			(thermal_bridge_width 0.5)
			(island_removal_mode 0)
		)
		(polygon
			(pts
				(arc
					(start 51.25212 -111.048292)
					(mid 51.237241 -111.084213)
					(end 51.20132 -111.099092)
				)
				(arc
					(start 50.02022 -111.099092)
					(mid 49.984299 -111.084213)
					(end 49.96942 -111.048292)
				)
				(arc
					(start 49.96942 -110.041944)
					(mid 49.984299 -110.006023)
					(end 50.02022 -109.991144)
				)
				(arc
					(start 51.20132 -109.991144)
					(mid 51.237241 -110.006023)
					(end 51.25212 -110.041944)
				)
			)
		)
	)
	(zone
		(layer "In1.Cu")
		(hatch none 0.5)
		(connect_pads
			(clearance 0)
		)
		(min_thickness 0.25)
		(keepout
			(tracks not_allowed)
			(vias allowed)
			(pads allowed)
			(copperpour not_allowed)
			(footprints allowed)
		)
		(placement
			(enabled no)
			(sheetname "")
		)
		(fill
			(thermal_gap 0.5)
			(thermal_bridge_width 0.5)
			(island_removal_mode 0)
		)
		(polygon
			(pts
				(arc
					(start 327.573132 -32.879538)
					(mid 327.588011 -32.915459)
					(end 327.623932 -32.930338)
				)
				(arc
					(start 328.360532 -32.930338)
					(mid 328.396453 -32.915459)
					(end 328.411332 -32.879538)
				)
				(xy 328.411332 -32.635698) (xy 328.178922 -32.281368) (xy 328.411332 -31.925768)
				(arc
					(start 328.411332 -31.683198)
					(mid 328.396453 -31.647277)
					(end 328.360532 -31.632398)
				)
				(arc
					(start 327.623932 -31.632398)
					(mid 327.588011 -31.647277)
					(end 327.573132 -31.683198)
				)
				(xy 327.573132 -31.925768) (xy 327.805542 -32.282638) (xy 327.573132 -32.636968)
			)
		)
	)
	(zone
		(layer "In1.Cu")
		(hatch none 0.5)
		(connect_pads
			(clearance 0)
		)
		(min_thickness 0.25)
		(keepout
			(tracks not_allowed)
			(vias allowed)
			(pads allowed)
			(copperpour not_allowed)
			(footprints allowed)
		)
		(placement
			(enabled no)
			(sheetname "")
		)
		(fill
			(thermal_gap 0.5)
			(thermal_bridge_width 0.5)
			(island_removal_mode 0)
		)
		(polygon
			(pts
				(arc
					(start 209.999834 -34.605976)
					(mid 209.984955 -34.641897)
					(end 209.949034 -34.656776)
				)
				(arc
					(start 208.717134 -34.656776)
					(mid 208.681213 -34.641897)
					(end 208.666334 -34.605976)
				)
				(arc
					(start 208.666334 -33.574228)
					(mid 208.681213 -33.538307)
					(end 208.717134 -33.523428)
				)
				(arc
					(start 209.949034 -33.523428)
					(mid 209.984955 -33.538307)
					(end 209.999834 -33.574228)
				)
			)
		)
	)
	(zone
		(layer "In1.Cu")
		(hatch none 0.5)
		(connect_pads
			(clearance 0)
		)
		(min_thickness 0.25)
		(keepout
			(tracks not_allowed)
			(vias allowed)
			(pads allowed)
			(copperpour not_allowed)
			(footprints allowed)
		)
		(placement
			(enabled no)
			(sheetname "")
		)
		(fill
			(thermal_gap 0.5)
			(thermal_bridge_width 0.5)
			(island_removal_mode 0)
		)
		(polygon
			(pts
				(arc
					(start 36.219384 -109.349794)
					(mid 36.234263 -109.385715)
					(end 36.270184 -109.400594)
				)
				(arc
					(start 37.006784 -109.400594)
					(mid 37.042705 -109.385715)
					(end 37.057584 -109.349794)
				)
				(xy 37.057584 -109.105954) (xy 36.825174 -108.751624) (xy 37.057584 -108.396024)
				(arc
					(start 37.057584 -108.153454)
					(mid 37.042705 -108.117533)
					(end 37.006784 -108.102654)
				)
				(arc
					(start 36.270184 -108.102654)
					(mid 36.234263 -108.117533)
					(end 36.219384 -108.153454)
				)
				(xy 36.219384 -108.396024) (xy 36.451794 -108.752894) (xy 36.219384 -109.107224)
			)
		)
	)
	(zone
		(layer "In1.Cu")
		(hatch none 0.5)
		(connect_pads
			(clearance 0)
		)
		(min_thickness 0.25)
		(keepout
			(tracks not_allowed)
			(vias allowed)
			(pads allowed)
			(copperpour not_allowed)
			(footprints allowed)
		)
		(placement
			(enabled no)
			(sheetname "")
		)
		(fill
			(thermal_gap 0.5)
			(thermal_bridge_width 0.5)
			(island_removal_mode 0)
		)
		(polygon
			(pts
				(arc
					(start 167.351964 -111.048292)
					(mid 167.337085 -111.084213)
					(end 167.301164 -111.099092)
				)
				(arc
					(start 166.120064 -111.099092)
					(mid 166.084143 -111.084213)
					(end 166.069264 -111.048292)
				)
				(arc
					(start 166.069264 -110.041944)
					(mid 166.084143 -110.006023)
					(end 166.120064 -109.991144)
				)
				(arc
					(start 167.301164 -109.991144)
					(mid 167.337085 -110.006023)
					(end 167.351964 -110.041944)
				)
			)
		)
	)
	(zone
		(layer "In1.Cu")
		(hatch none 0.5)
		(connect_pads
			(clearance 0)
		)
		(min_thickness 0.25)
		(keepout
			(tracks not_allowed)
			(vias allowed)
			(pads allowed)
			(copperpour not_allowed)
			(footprints allowed)
		)
		(placement
			(enabled no)
			(sheetname "")
		)
		(fill
			(thermal_gap 0.5)
			(thermal_bridge_width 0.5)
			(island_removal_mode 0)
		)
		(polygon
			(pts
				(arc
					(start 73.867264 -132.648198)
					(mid 73.852385 -132.684119)
					(end 73.816464 -132.698998)
				)
				(arc
					(start 72.635364 -132.698998)
					(mid 72.599443 -132.684119)
					(end 72.584564 -132.648198)
				)
				(arc
					(start 72.584564 -131.64185)
					(mid 72.599443 -131.605929)
					(end 72.635364 -131.59105)
				)
				(arc
					(start 73.816464 -131.59105)
					(mid 73.852385 -131.605929)
					(end 73.867264 -131.64185)
				)
			)
		)
	)
	(zone
		(layer "In1.Cu")
		(hatch none 0.5)
		(connect_pads
			(clearance 0)
		)
		(min_thickness 0.25)
		(keepout
			(tracks not_allowed)
			(vias allowed)
			(pads allowed)
			(copperpour not_allowed)
			(footprints allowed)
		)
		(placement
			(enabled no)
			(sheetname "")
		)
		(fill
			(thermal_gap 0.5)
			(thermal_bridge_width 0.5)
			(island_removal_mode 0)
		)
		(polygon
			(pts
				(arc
					(start 183.999886 -31.006034)
					(mid 183.985007 -31.041955)
					(end 183.949086 -31.056834)
				)
				(arc
					(start 182.717186 -31.056834)
					(mid 182.681265 -31.041955)
					(end 182.666386 -31.006034)
				)
				(arc
					(start 182.666386 -29.974286)
					(mid 182.681265 -29.938365)
					(end 182.717186 -29.923486)
				)
				(arc
					(start 183.949086 -29.923486)
					(mid 183.985007 -29.938365)
					(end 183.999886 -29.974286)
				)
			)
		)
	)
	(zone
		(layer "In1.Cu")
		(hatch none 0.5)
		(connect_pads
			(clearance 0)
		)
		(min_thickness 0.25)
		(keepout
			(tracks not_allowed)
			(vias allowed)
			(pads allowed)
			(copperpour not_allowed)
			(footprints allowed)
		)
		(placement
			(enabled no)
			(sheetname "")
		)
		(fill
			(thermal_gap 0.5)
			(thermal_bridge_width 0.5)
			(island_removal_mode 0)
		)
		(polygon
			(pts
				(arc
					(start 73.867264 -148.9583)
					(mid 73.852385 -148.994221)
					(end 73.816464 -149.0091)
				)
				(arc
					(start 72.635364 -149.0091)
					(mid 72.599443 -148.994221)
					(end 72.584564 -148.9583)
				)
				(arc
					(start 72.584564 -147.951952)
					(mid 72.599443 -147.916031)
					(end 72.635364 -147.901152)
				)
				(arc
					(start 73.816464 -147.901152)
					(mid 73.852385 -147.916031)
					(end 73.867264 -147.951952)
				)
			)
		)
	)
	(zone
		(layer "In1.Cu")
		(hatch none 0.5)
		(connect_pads
			(clearance 0)
		)
		(min_thickness 0.25)
		(keepout
			(tracks not_allowed)
			(vias allowed)
			(pads allowed)
			(copperpour not_allowed)
			(footprints allowed)
		)
		(placement
			(enabled no)
			(sheetname "")
		)
		(fill
			(thermal_gap 0.5)
			(thermal_bridge_width 0.5)
			(island_removal_mode 0)
		)
		(polygon
			(pts
				(arc
					(start 427.900338 -130.93446)
					(mid 427.915217 -130.970381)
					(end 427.951138 -130.98526)
				)
				(arc
					(start 428.687738 -130.98526)
					(mid 428.723659 -130.970381)
					(end 428.738538 -130.93446)
				)
				(xy 428.738538 -130.69062) (xy 428.506128 -130.33629) (xy 428.738538 -129.98069)
				(arc
					(start 428.738538 -129.73812)
					(mid 428.723659 -129.702199)
					(end 428.687738 -129.68732)
				)
				(arc
					(start 427.951138 -129.68732)
					(mid 427.915217 -129.702199)
					(end 427.900338 -129.73812)
				)
				(xy 427.900338 -129.98069) (xy 428.132748 -130.33756) (xy 427.900338 -130.69189)
			)
		)
	)
	(zone
		(layer "In1.Cu")
		(hatch none 0.5)
		(connect_pads
			(clearance 0)
		)
		(min_thickness 0.25)
		(keepout
			(tracks not_allowed)
			(vias allowed)
			(pads allowed)
			(copperpour not_allowed)
			(footprints allowed)
		)
		(placement
			(enabled no)
			(sheetname "")
		)
		(fill
			(thermal_gap 0.5)
			(thermal_bridge_width 0.5)
			(island_removal_mode 0)
		)
		(polygon
			(pts
				(arc
					(start 167.351964 -136.768332)
					(mid 167.337085 -136.804253)
					(end 167.301164 -136.819132)
				)
				(arc
					(start 166.120064 -136.819132)
					(mid 166.084143 -136.804253)
					(end 166.069264 -136.768332)
				)
				(arc
					(start 166.069264 -135.761984)
					(mid 166.084143 -135.726063)
					(end 166.120064 -135.711184)
				)
				(arc
					(start 167.301164 -135.711184)
					(mid 167.337085 -135.726063)
					(end 167.351964 -135.761984)
				)
			)
		)
	)
	(zone
		(layer "In1.Cu")
		(hatch none 0.5)
		(connect_pads
			(clearance 0)
		)
		(min_thickness 0.25)
		(keepout
			(tracks not_allowed)
			(vias allowed)
			(pads allowed)
			(copperpour not_allowed)
			(footprints allowed)
		)
		(placement
			(enabled no)
			(sheetname "")
		)
		(fill
			(thermal_gap 0.5)
			(thermal_bridge_width 0.5)
			(island_removal_mode 0)
		)
		(polygon
			(pts
				(arc
					(start 45.432726 -106.441748)
					(mid 45.447605 -106.405827)
					(end 45.483526 -106.390948)
				)
				(arc
					(start 46.664626 -106.390948)
					(mid 46.700547 -106.405827)
					(end 46.715426 -106.441748)
				)
				(arc
					(start 46.715426 -107.448096)
					(mid 46.700547 -107.484017)
					(end 46.664626 -107.498896)
				)
				(arc
					(start 45.483526 -107.498896)
					(mid 45.447605 -107.484017)
					(end 45.432726 -107.448096)
				)
			)
		)
	)
	(zone
		(layer "In1.Cu")
		(hatch none 0.5)
		(connect_pads
			(clearance 0)
		)
		(min_thickness 0.25)
		(keepout
			(tracks not_allowed)
			(vias allowed)
			(pads allowed)
			(copperpour not_allowed)
			(footprints allowed)
		)
		(placement
			(enabled no)
			(sheetname "")
		)
		(fill
			(thermal_gap 0.5)
			(thermal_bridge_width 0.5)
			(island_removal_mode 0)
		)
		(polygon
			(pts
				(arc
					(start 427.900338 -147.244562)
					(mid 427.915217 -147.280483)
					(end 427.951138 -147.295362)
				)
				(arc
					(start 428.687738 -147.295362)
					(mid 428.723659 -147.280483)
					(end 428.738538 -147.244562)
				)
				(xy 428.738538 -147.000722) (xy 428.506128 -146.646392) (xy 428.738538 -146.290792)
				(arc
					(start 428.738538 -146.048222)
					(mid 428.723659 -146.012301)
					(end 428.687738 -145.997422)
				)
				(arc
					(start 427.951138 -145.997422)
					(mid 427.915217 -146.012301)
					(end 427.900338 -146.048222)
				)
				(xy 427.900338 -146.290792) (xy 428.132748 -146.647662) (xy 427.900338 -147.001992)
			)
		)
	)
	(zone
		(layer "In1.Cu")
		(hatch none 0.5)
		(connect_pads
			(clearance 0)
		)
		(min_thickness 0.25)
		(keepout
			(tracks not_allowed)
			(vias allowed)
			(pads allowed)
			(copperpour not_allowed)
			(footprints allowed)
		)
		(placement
			(enabled no)
			(sheetname "")
		)
		(fill
			(thermal_gap 0.5)
			(thermal_bridge_width 0.5)
			(island_removal_mode 0)
		)
		(polygon
			(pts
				(arc
					(start 427.783498 -343.533222)
					(mid 427.747577 -343.548101)
					(end 427.732698 -343.584022)
				)
				(arc
					(start 427.732698 -344.320622)
					(mid 427.747577 -344.356543)
					(end 427.783498 -344.371422)
				)
				(xy 428.027338 -344.371422) (xy 428.381668 -344.139012) (xy 428.737268 -344.371422)
				(arc
					(start 428.979838 -344.371422)
					(mid 429.015759 -344.356543)
					(end 429.030638 -344.320622)
				)
				(arc
					(start 429.030638 -343.584022)
					(mid 429.015759 -343.548101)
					(end 428.979838 -343.533222)
				)
				(xy 428.737268 -343.533222) (xy 428.380398 -343.765632) (xy 428.026068 -343.533222)
			)
		)
	)
	(zone
		(layer "In1.Cu")
		(hatch none 0.5)
		(connect_pads
			(clearance 0)
		)
		(min_thickness 0.25)
		(keepout
			(tracks not_allowed)
			(vias allowed)
			(pads allowed)
			(copperpour not_allowed)
			(footprints allowed)
		)
		(placement
			(enabled no)
			(sheetname "")
		)
		(fill
			(thermal_gap 0.5)
			(thermal_bridge_width 0.5)
			(island_removal_mode 0)
		)
		(polygon
			(pts
				(arc
					(start 124.132594 -349.679514)
					(mid 124.096673 -349.694393)
					(end 124.081794 -349.730314)
				)
				(arc
					(start 124.081794 -350.466914)
					(mid 124.096673 -350.502835)
					(end 124.132594 -350.517714)
				)
				(xy 124.376434 -350.517714) (xy 124.730764 -350.285304) (xy 125.086364 -350.517714)
				(arc
					(start 125.328934 -350.517714)
					(mid 125.364855 -350.502835)
					(end 125.379734 -350.466914)
				)
				(arc
					(start 125.379734 -349.730314)
					(mid 125.364855 -349.694393)
					(end 125.328934 -349.679514)
				)
				(xy 125.086364 -349.679514) (xy 124.729494 -349.911924) (xy 124.375164 -349.679514)
			)
		)
	)
	(zone
		(layer "In1.Cu")
		(hatch none 0.5)
		(connect_pads
			(clearance 0)
		)
		(min_thickness 0.25)
		(keepout
			(tracks not_allowed)
			(vias allowed)
			(pads allowed)
			(copperpour not_allowed)
			(footprints allowed)
		)
		(placement
			(enabled no)
			(sheetname "")
		)
		(fill
			(thermal_gap 0.5)
			(thermal_bridge_width 0.5)
			(island_removal_mode 0)
		)
		(polygon
			(pts
				(arc
					(start 383.458466 -343.533222)
					(mid 383.422545 -343.548101)
					(end 383.407666 -343.584022)
				)
				(arc
					(start 383.407666 -344.320622)
					(mid 383.422545 -344.356543)
					(end 383.458466 -344.371422)
				)
				(xy 383.702306 -344.371422) (xy 384.056636 -344.139012) (xy 384.412236 -344.371422)
				(arc
					(start 384.654806 -344.371422)
					(mid 384.690727 -344.356543)
					(end 384.705606 -344.320622)
				)
				(arc
					(start 384.705606 -343.584022)
					(mid 384.690727 -343.548101)
					(end 384.654806 -343.533222)
				)
				(xy 384.412236 -343.533222) (xy 384.055366 -343.765632) (xy 383.701036 -343.533222)
			)
		)
	)
	(zone
		(layer "In1.Cu")
		(hatch none 0.5)
		(connect_pads
			(clearance 0)
		)
		(min_thickness 0.25)
		(keepout
			(tracks not_allowed)
			(vias allowed)
			(pads allowed)
			(copperpour not_allowed)
			(footprints allowed)
		)
		(placement
			(enabled no)
			(sheetname "")
		)
		(fill
			(thermal_gap 0.5)
			(thermal_bridge_width 0.5)
			(island_removal_mode 0)
		)
		(polygon
			(pts
				(arc
					(start 28.493974 -355.825806)
					(mid 28.458053 -355.840685)
					(end 28.443174 -355.876606)
				)
				(arc
					(start 28.443174 -356.613206)
					(mid 28.458053 -356.649127)
					(end 28.493974 -356.664006)
				)
				(xy 28.737814 -356.664006) (xy 29.092144 -356.431596) (xy 29.447744 -356.664006)
				(arc
					(start 29.690314 -356.664006)
					(mid 29.726235 -356.649127)
					(end 29.741114 -356.613206)
				)
				(arc
					(start 29.741114 -355.876606)
					(mid 29.726235 -355.840685)
					(end 29.690314 -355.825806)
				)
				(xy 29.447744 -355.825806) (xy 29.090874 -356.058216) (xy 28.736544 -355.825806)
			)
		)
	)
	(zone
		(layer "In1.Cu")
		(hatch none 0.5)
		(connect_pads
			(clearance 0)
		)
		(min_thickness 0.25)
		(keepout
			(tracks not_allowed)
			(vias allowed)
			(pads allowed)
			(copperpour not_allowed)
			(footprints allowed)
		)
		(placement
			(enabled no)
			(sheetname "")
		)
		(fill
			(thermal_gap 0.5)
			(thermal_bridge_width 0.5)
			(island_removal_mode 0)
		)
		(polygon
			(pts
				(arc
					(start 152.928828 -102.149656)
					(mid 152.943707 -102.185577)
					(end 152.979628 -102.200456)
				)
				(arc
					(start 153.716228 -102.200456)
					(mid 153.752149 -102.185577)
					(end 153.767028 -102.149656)
				)
				(xy 153.767028 -101.905816) (xy 153.534618 -101.551486) (xy 153.767028 -101.195886)
				(arc
					(start 153.767028 -100.953316)
					(mid 153.752149 -100.917395)
					(end 153.716228 -100.902516)
				)
				(arc
					(start 152.979628 -100.902516)
					(mid 152.943707 -100.917395)
					(end 152.928828 -100.953316)
				)
				(xy 152.928828 -101.195886) (xy 153.161238 -101.552756) (xy 152.928828 -101.907086)
			)
		)
	)
	(zone
		(layer "In1.Cu")
		(hatch none 0.5)
		(connect_pads
			(clearance 0)
		)
		(min_thickness 0.25)
		(keepout
			(tracks not_allowed)
			(vias allowed)
			(pads allowed)
			(copperpour not_allowed)
			(footprints allowed)
		)
		(placement
			(enabled no)
			(sheetname "")
		)
		(fill
			(thermal_gap 0.5)
			(thermal_bridge_width 0.5)
			(island_removal_mode 0)
		)
		(polygon
			(pts
				(arc
					(start 67.424808 -355.825806)
					(mid 67.388887 -355.840685)
					(end 67.374008 -355.876606)
				)
				(arc
					(start 67.374008 -356.613206)
					(mid 67.388887 -356.649127)
					(end 67.424808 -356.664006)
				)
				(xy 67.668648 -356.664006) (xy 68.022978 -356.431596) (xy 68.378578 -356.664006)
				(arc
					(start 68.621148 -356.664006)
					(mid 68.657069 -356.649127)
					(end 68.671948 -356.613206)
				)
				(arc
					(start 68.671948 -355.876606)
					(mid 68.657069 -355.840685)
					(end 68.621148 -355.825806)
				)
				(xy 68.378578 -355.825806) (xy 68.021708 -356.058216) (xy 67.667378 -355.825806)
			)
		)
	)
	(zone
		(layer "In1.Cu")
		(hatch none 0.5)
		(connect_pads
			(clearance 0)
		)
		(min_thickness 0.25)
		(keepout
			(tracks not_allowed)
			(vias allowed)
			(pads allowed)
			(copperpour not_allowed)
			(footprints allowed)
		)
		(placement
			(enabled no)
			(sheetname "")
		)
		(fill
			(thermal_gap 0.5)
			(thermal_bridge_width 0.5)
			(island_removal_mode 0)
		)
		(polygon
			(pts
				(arc
					(start 41.89984 -32.805878)
					(mid 41.884961 -32.841799)
					(end 41.84904 -32.856678)
				)
				(arc
					(start 40.61714 -32.856678)
					(mid 40.581219 -32.841799)
					(end 40.56634 -32.805878)
				)
				(arc
					(start 40.56634 -31.77413)
					(mid 40.581219 -31.738209)
					(end 40.61714 -31.72333)
				)
				(arc
					(start 41.84904 -31.72333)
					(mid 41.884961 -31.738209)
					(end 41.89984 -31.77413)
				)
			)
		)
	)
	(zone
		(layer "In1.Cu")
		(hatch none 0.5)
		(connect_pads
			(clearance 0)
		)
		(min_thickness 0.25)
		(keepout
			(tracks not_allowed)
			(vias allowed)
			(pads allowed)
			(copperpour not_allowed)
			(footprints allowed)
		)
		(placement
			(enabled no)
			(sheetname "")
		)
		(fill
			(thermal_gap 0.5)
			(thermal_bridge_width 0.5)
			(island_removal_mode 0)
		)
		(polygon
			(pts
				(arc
					(start 167.351964 -105.648252)
					(mid 167.337085 -105.684173)
					(end 167.301164 -105.699052)
				)
				(arc
					(start 166.120064 -105.699052)
					(mid 166.084143 -105.684173)
					(end 166.069264 -105.648252)
				)
				(arc
					(start 166.069264 -104.641904)
					(mid 166.084143 -104.605983)
					(end 166.120064 -104.591104)
				)
				(arc
					(start 167.301164 -104.591104)
					(mid 167.337085 -104.605983)
					(end 167.351964 -104.641904)
				)
			)
		)
	)
	(zone
		(layer "In1.Cu")
		(hatch none 0.5)
		(connect_pads
			(clearance 0)
		)
		(min_thickness 0.25)
		(keepout
			(tracks not_allowed)
			(vias allowed)
			(pads allowed)
			(copperpour not_allowed)
			(footprints allowed)
		)
		(placement
			(enabled no)
			(sheetname "")
		)
		(fill
			(thermal_gap 0.5)
			(thermal_bridge_width 0.5)
			(island_removal_mode 0)
		)
		(polygon
			(pts
				(arc
					(start 402.112226 -355.825806)
					(mid 402.076305 -355.840685)
					(end 402.061426 -355.876606)
				)
				(arc
					(start 402.061426 -356.613206)
					(mid 402.076305 -356.649127)
					(end 402.112226 -356.664006)
				)
				(xy 402.356066 -356.664006) (xy 402.710396 -356.431596) (xy 403.065996 -356.664006)
				(arc
					(start 403.308566 -356.664006)
					(mid 403.344487 -356.649127)
					(end 403.359366 -356.613206)
				)
				(arc
					(start 403.359366 -355.876606)
					(mid 403.344487 -355.840685)
					(end 403.308566 -355.825806)
				)
				(xy 403.065996 -355.825806) (xy 402.709126 -356.058216) (xy 402.354796 -355.825806)
			)
		)
	)
	(zone
		(layer "In1.Cu")
		(hatch none 0.5)
		(connect_pads
			(clearance 0)
		)
		(min_thickness 0.25)
		(keepout
			(tracks not_allowed)
			(vias allowed)
			(pads allowed)
			(copperpour not_allowed)
			(footprints allowed)
		)
		(placement
			(enabled no)
			(sheetname "")
		)
		(fill
			(thermal_gap 0.5)
			(thermal_bridge_width 0.5)
			(island_removal_mode 0)
		)
		(polygon
			(pts
				(arc
					(start 67.424808 -343.533222)
					(mid 67.388887 -343.548101)
					(end 67.374008 -343.584022)
				)
				(arc
					(start 67.374008 -344.320622)
					(mid 67.388887 -344.356543)
					(end 67.424808 -344.371422)
				)
				(xy 67.668648 -344.371422) (xy 68.022978 -344.139012) (xy 68.378578 -344.371422)
				(arc
					(start 68.621148 -344.371422)
					(mid 68.657069 -344.356543)
					(end 68.671948 -344.320622)
				)
				(arc
					(start 68.671948 -343.584022)
					(mid 68.657069 -343.548101)
					(end 68.621148 -343.533222)
				)
				(xy 68.378578 -343.533222) (xy 68.021708 -343.765632) (xy 67.667378 -343.533222)
			)
		)
	)
	(zone
		(layer "In1.Cu")
		(hatch none 0.5)
		(connect_pads
			(clearance 0)
		)
		(min_thickness 0.25)
		(keepout
			(tracks not_allowed)
			(vias allowed)
			(pads allowed)
			(copperpour not_allowed)
			(footprints allowed)
		)
		(placement
			(enabled no)
			(sheetname "")
		)
		(fill
			(thermal_gap 0.5)
			(thermal_bridge_width 0.5)
			(island_removal_mode 0)
		)
		(polygon
			(pts
				(arc
					(start 233.642408 -83.591908)
					(mid 233.679605 -83.502105)
					(end 233.769408 -83.464908)
				)
				(arc
					(start 233.972608 -83.464908)
					(mid 234.062411 -83.502105)
					(end 234.099608 -83.591908)
				)
				(arc
					(start 234.099608 -83.845908)
					(mid 234.062411 -83.935711)
					(end 233.972608 -83.972908)
				)
				(arc
					(start 233.769408 -83.972908)
					(mid 233.679605 -83.935711)
					(end 233.642408 -83.845908)
				)
			)
		)
	)
	(zone
		(layer "In1.Cu")
		(hatch none 0.5)
		(connect_pads
			(clearance 0)
		)
		(min_thickness 0.25)
		(keepout
			(tracks not_allowed)
			(vias allowed)
			(pads allowed)
			(copperpour not_allowed)
			(footprints allowed)
		)
		(placement
			(enabled no)
			(sheetname "")
		)
		(fill
			(thermal_gap 0.5)
			(thermal_bridge_width 0.5)
			(island_removal_mode 0)
		)
		(polygon
			(pts
				(arc
					(start 300.247812 -122.231912)
					(mid 300.262691 -122.195991)
					(end 300.298612 -122.181112)
				)
				(arc
					(start 301.479712 -122.181112)
					(mid 301.515633 -122.195991)
					(end 301.530512 -122.231912)
				)
				(arc
					(start 301.530512 -123.23826)
					(mid 301.515633 -123.274181)
					(end 301.479712 -123.28906)
				)
				(arc
					(start 300.298612 -123.28906)
					(mid 300.262691 -123.274181)
					(end 300.247812 -123.23826)
				)
			)
		)
	)
	(zone
		(layer "In1.Cu")
		(hatch none 0.5)
		(connect_pads
			(clearance 0)
		)
		(min_thickness 0.25)
		(keepout
			(tracks not_allowed)
			(vias allowed)
			(pads allowed)
			(copperpour not_allowed)
			(footprints allowed)
		)
		(placement
			(enabled no)
			(sheetname "")
		)
		(fill
			(thermal_gap 0.5)
			(thermal_bridge_width 0.5)
			(island_removal_mode 0)
		)
		(polygon
			(pts
				(arc
					(start 88.029796 -33.574228)
					(mid 88.044675 -33.538307)
					(end 88.080596 -33.523428)
				)
				(arc
					(start 89.312496 -33.523428)
					(mid 89.348417 -33.538307)
					(end 89.363296 -33.574228)
				)
				(arc
					(start 89.363296 -34.605976)
					(mid 89.348417 -34.641897)
					(end 89.312496 -34.656776)
				)
				(arc
					(start 88.080596 -34.656776)
					(mid 88.044675 -34.641897)
					(end 88.029796 -34.605976)
				)
			)
		)
	)
	(zone
		(layer "In1.Cu")
		(hatch none 0.5)
		(connect_pads
			(clearance 0)
		)
		(min_thickness 0.25)
		(keepout
			(tracks not_allowed)
			(vias allowed)
			(pads allowed)
			(copperpour not_allowed)
			(footprints allowed)
		)
		(placement
			(enabled no)
			(sheetname "")
		)
		(fill
			(thermal_gap 0.5)
			(thermal_bridge_width 0.5)
			(island_removal_mode 0)
		)
		(polygon
			(pts
				(arc
					(start 162.1155 -31.086044)
					(mid 162.130379 -31.121965)
					(end 162.1663 -31.136844)
				)
				(arc
					(start 162.9029 -31.136844)
					(mid 162.938821 -31.121965)
					(end 162.9537 -31.086044)
				)
				(xy 162.9537 -30.842204) (xy 162.72129 -30.487874) (xy 162.9537 -30.132274)
				(arc
					(start 162.9537 -29.889704)
					(mid 162.938821 -29.853783)
					(end 162.9029 -29.838904)
				)
				(arc
					(start 162.1663 -29.838904)
					(mid 162.130379 -29.853783)
					(end 162.1155 -29.889704)
				)
				(xy 162.1155 -30.132274) (xy 162.34791 -30.489144) (xy 162.1155 -30.843474)
			)
		)
	)
	(zone
		(layer "In1.Cu")
		(hatch none 0.5)
		(connect_pads
			(clearance 0)
		)
		(min_thickness 0.25)
		(keepout
			(tracks not_allowed)
			(vias allowed)
			(pads allowed)
			(copperpour not_allowed)
			(footprints allowed)
		)
		(placement
			(enabled no)
			(sheetname "")
		)
		(fill
			(thermal_gap 0.5)
			(thermal_bridge_width 0.5)
			(island_removal_mode 0)
		)
		(polygon
			(pts
				(arc
					(start 40.929814 -343.533222)
					(mid 40.893893 -343.548101)
					(end 40.879014 -343.584022)
				)
				(arc
					(start 40.879014 -344.320622)
					(mid 40.893893 -344.356543)
					(end 40.929814 -344.371422)
				)
				(xy 41.173654 -344.371422) (xy 41.527984 -344.139012) (xy 41.883584 -344.371422)
				(arc
					(start 42.126154 -344.371422)
					(mid 42.162075 -344.356543)
					(end 42.176954 -344.320622)
				)
				(arc
					(start 42.176954 -343.584022)
					(mid 42.162075 -343.548101)
					(end 42.126154 -343.533222)
				)
				(xy 41.883584 -343.533222) (xy 41.526714 -343.765632) (xy 41.172384 -343.533222)
			)
		)
	)
	(zone
		(layer "In1.Cu")
		(hatch none 0.5)
		(connect_pads
			(clearance 0)
		)
		(min_thickness 0.25)
		(keepout
			(tracks not_allowed)
			(vias allowed)
			(pads allowed)
			(copperpour not_allowed)
			(footprints allowed)
		)
		(placement
			(enabled no)
			(sheetname "")
		)
		(fill
			(thermal_gap 0.5)
			(thermal_bridge_width 0.5)
			(island_removal_mode 0)
		)
		(polygon
			(pts
				(arc
					(start 422.167304 -125.038104)
					(mid 422.152425 -125.074025)
					(end 422.116504 -125.088904)
				)
				(arc
					(start 420.935404 -125.088904)
					(mid 420.899483 -125.074025)
					(end 420.884604 -125.038104)
				)
				(arc
					(start 420.884604 -124.031756)
					(mid 420.899483 -123.995835)
					(end 420.935404 -123.980956)
				)
				(arc
					(start 422.116504 -123.980956)
					(mid 422.152425 -123.995835)
					(end 422.167304 -124.031756)
				)
			)
		)
	)
	(zone
		(layer "In1.Cu")
		(hatch none 0.5)
		(connect_pads
			(clearance 0)
		)
		(min_thickness 0.25)
		(keepout
			(tracks not_allowed)
			(vias allowed)
			(pads allowed)
			(copperpour not_allowed)
			(footprints allowed)
		)
		(placement
			(enabled no)
			(sheetname "")
		)
		(fill
			(thermal_gap 0.5)
			(thermal_bridge_width 0.5)
			(island_removal_mode 0)
		)
		(polygon
			(pts
				(arc
					(start 183.783478 -349.679514)
					(mid 183.747557 -349.694393)
					(end 183.732678 -349.730314)
				)
				(arc
					(start 183.732678 -350.466914)
					(mid 183.747557 -350.502835)
					(end 183.783478 -350.517714)
				)
				(xy 184.027318 -350.517714) (xy 184.381648 -350.285304) (xy 184.737248 -350.517714)
				(arc
					(start 184.979818 -350.517714)
					(mid 185.015739 -350.502835)
					(end 185.030618 -350.466914)
				)
				(arc
					(start 185.030618 -349.730314)
					(mid 185.015739 -349.694393)
					(end 184.979818 -349.679514)
				)
				(xy 184.737248 -349.679514) (xy 184.380378 -349.911924) (xy 184.026048 -349.679514)
			)
		)
	)
	(zone
		(layer "In1.Cu")
		(hatch none 0.5)
		(connect_pads
			(clearance 0)
		)
		(min_thickness 0.25)
		(keepout
			(tracks not_allowed)
			(vias allowed)
			(pads allowed)
			(copperpour not_allowed)
			(footprints allowed)
		)
		(placement
			(enabled no)
			(sheetname "")
		)
		(fill
			(thermal_gap 0.5)
			(thermal_bridge_width 0.5)
			(island_removal_mode 0)
		)
		(polygon
			(pts
				(arc
					(start 427.900338 -154.4447)
					(mid 427.915217 -154.480621)
					(end 427.951138 -154.4955)
				)
				(arc
					(start 428.687738 -154.4955)
					(mid 428.723659 -154.480621)
					(end 428.738538 -154.4447)
				)
				(xy 428.738538 -154.20086) (xy 428.506128 -153.84653) (xy 428.738538 -153.49093)
				(arc
					(start 428.738538 -153.24836)
					(mid 428.723659 -153.212439)
					(end 428.687738 -153.19756)
				)
				(arc
					(start 427.951138 -153.19756)
					(mid 427.915217 -153.212439)
					(end 427.900338 -153.24836)
				)
				(xy 427.900338 -153.49093) (xy 428.132748 -153.8478) (xy 427.900338 -154.20213)
			)
		)
	)
	(zone
		(layer "In1.Cu")
		(hatch none 0.5)
		(connect_pads
			(clearance 0)
		)
		(min_thickness 0.25)
		(keepout
			(tracks not_allowed)
			(vias allowed)
			(pads allowed)
			(copperpour not_allowed)
			(footprints allowed)
		)
		(placement
			(enabled no)
			(sheetname "")
		)
		(fill
			(thermal_gap 0.5)
			(thermal_bridge_width 0.5)
			(island_removal_mode 0)
		)
		(polygon
			(pts
				(arc
					(start 421.565578 -349.679514)
					(mid 421.529657 -349.694393)
					(end 421.514778 -349.730314)
				)
				(arc
					(start 421.514778 -350.466914)
					(mid 421.529657 -350.502835)
					(end 421.565578 -350.517714)
				)
				(xy 421.809418 -350.517714) (xy 422.163748 -350.285304) (xy 422.519348 -350.517714)
				(arc
					(start 422.761918 -350.517714)
					(mid 422.797839 -350.502835)
					(end 422.812718 -350.466914)
				)
				(arc
					(start 422.812718 -349.730314)
					(mid 422.797839 -349.694393)
					(end 422.761918 -349.679514)
				)
				(xy 422.519348 -349.679514) (xy 422.162478 -349.911924) (xy 421.808148 -349.679514)
			)
		)
	)
	(zone
		(layer "In1.Cu")
		(hatch none 0.5)
		(connect_pads
			(clearance 0)
		)
		(min_thickness 0.25)
		(keepout
			(tracks not_allowed)
			(vias allowed)
			(pads allowed)
			(copperpour not_allowed)
			(footprints allowed)
		)
		(placement
			(enabled no)
			(sheetname "")
		)
		(fill
			(thermal_gap 0.5)
			(thermal_bridge_width 0.5)
			(island_removal_mode 0)
		)
		(polygon
			(pts
				(arc
					(start 386.567426 -349.679514)
					(mid 386.531505 -349.694393)
					(end 386.516626 -349.730314)
				)
				(arc
					(start 386.516626 -350.466914)
					(mid 386.531505 -350.502835)
					(end 386.567426 -350.517714)
				)
				(xy 386.811266 -350.517714) (xy 387.165596 -350.285304) (xy 387.521196 -350.517714)
				(arc
					(start 387.763766 -350.517714)
					(mid 387.799687 -350.502835)
					(end 387.814566 -350.466914)
				)
				(arc
					(start 387.814566 -349.730314)
					(mid 387.799687 -349.694393)
					(end 387.763766 -349.679514)
				)
				(xy 387.521196 -349.679514) (xy 387.164326 -349.911924) (xy 386.809996 -349.679514)
			)
		)
	)
	(zone
		(layer "In1.Cu")
		(hatch none 0.5)
		(connect_pads
			(clearance 0)
		)
		(min_thickness 0.25)
		(keepout
			(tracks not_allowed)
			(vias allowed)
			(pads allowed)
			(copperpour not_allowed)
			(footprints allowed)
		)
		(placement
			(enabled no)
			(sheetname "")
		)
		(fill
			(thermal_gap 0.5)
			(thermal_bridge_width 0.5)
			(island_removal_mode 0)
		)
		(polygon
			(pts
				(arc
					(start 154.961336 -111.143288)
					(mid 154.976215 -111.179209)
					(end 155.012136 -111.194088)
				)
				(arc
					(start 155.748736 -111.194088)
					(mid 155.784657 -111.179209)
					(end 155.799536 -111.143288)
				)
				(xy 155.799536 -110.899448) (xy 155.567126 -110.545118) (xy 155.799536 -110.189518)
				(arc
					(start 155.799536 -109.946948)
					(mid 155.784657 -109.911027)
					(end 155.748736 -109.896148)
				)
				(arc
					(start 155.012136 -109.896148)
					(mid 154.976215 -109.911027)
					(end 154.961336 -109.946948)
				)
				(xy 154.961336 -110.189518) (xy 155.193746 -110.546388) (xy 154.961336 -110.900718)
			)
		)
	)
	(zone
		(layer "In1.Cu")
		(hatch none 0.5)
		(connect_pads
			(clearance 0)
		)
		(min_thickness 0.25)
		(keepout
			(tracks not_allowed)
			(vias allowed)
			(pads allowed)
			(copperpour not_allowed)
			(footprints allowed)
		)
		(placement
			(enabled no)
			(sheetname "")
		)
		(fill
			(thermal_gap 0.5)
			(thermal_bridge_width 0.5)
			(island_removal_mode 0)
		)
		(polygon
			(pts
				(arc
					(start 306.067206 -134.448296)
					(mid 306.052327 -134.484217)
					(end 306.016406 -134.499096)
				)
				(arc
					(start 304.835306 -134.499096)
					(mid 304.799385 -134.484217)
					(end 304.784506 -134.448296)
				)
				(arc
					(start 304.784506 -133.441948)
					(mid 304.799385 -133.406027)
					(end 304.835306 -133.391148)
				)
				(arc
					(start 306.016406 -133.391148)
					(mid 306.052327 -133.406027)
					(end 306.067206 -133.441948)
				)
			)
		)
	)
	(zone
		(layer "In1.Cu")
		(hatch none 0.5)
		(connect_pads
			(clearance 0)
		)
		(min_thickness 0.25)
		(keepout
			(tracks not_allowed)
			(vias allowed)
			(pads allowed)
			(copperpour not_allowed)
			(footprints allowed)
		)
		(placement
			(enabled no)
			(sheetname "")
		)
		(fill
			(thermal_gap 0.5)
			(thermal_bridge_width 0.5)
			(island_removal_mode 0)
		)
		(polygon
			(pts
				(arc
					(start 358.329992 -31.77413)
					(mid 358.344871 -31.738209)
					(end 358.380792 -31.72333)
				)
				(arc
					(start 359.612692 -31.72333)
					(mid 359.648613 -31.738209)
					(end 359.663492 -31.77413)
				)
				(arc
					(start 359.663492 -32.805878)
					(mid 359.648613 -32.841799)
					(end 359.612692 -32.856678)
				)
				(arc
					(start 358.380792 -32.856678)
					(mid 358.344871 -32.841799)
					(end 358.329992 -32.805878)
				)
			)
		)
	)
	(zone
		(layer "In1.Cu")
		(hatch none 0.5)
		(connect_pads
			(clearance 0)
		)
		(min_thickness 0.25)
		(keepout
			(tracks not_allowed)
			(vias allowed)
			(pads allowed)
			(copperpour not_allowed)
			(footprints allowed)
		)
		(placement
			(enabled no)
			(sheetname "")
		)
		(fill
			(thermal_gap 0.5)
			(thermal_bridge_width 0.5)
			(island_removal_mode 0)
		)
		(polygon
			(pts
				(arc
					(start 384.519424 -112.949736)
					(mid 384.534303 -112.985657)
					(end 384.570224 -113.000536)
				)
				(arc
					(start 385.306824 -113.000536)
					(mid 385.342745 -112.985657)
					(end 385.357624 -112.949736)
				)
				(xy 385.357624 -112.705896) (xy 385.125214 -112.351566) (xy 385.357624 -111.995966)
				(arc
					(start 385.357624 -111.753396)
					(mid 385.342745 -111.717475)
					(end 385.306824 -111.702596)
				)
				(arc
					(start 384.570224 -111.702596)
					(mid 384.534303 -111.717475)
					(end 384.519424 -111.753396)
				)
				(xy 384.519424 -111.995966) (xy 384.751834 -112.352836) (xy 384.519424 -112.707166)
			)
		)
	)
	(zone
		(layer "In1.Cu")
		(hatch none 0.5)
		(connect_pads
			(clearance 0)
		)
		(min_thickness 0.25)
		(keepout
			(tracks not_allowed)
			(vias allowed)
			(pads allowed)
			(copperpour not_allowed)
			(footprints allowed)
		)
		(placement
			(enabled no)
			(sheetname "")
		)
		(fill
			(thermal_gap 0.5)
			(thermal_bridge_width 0.5)
			(island_removal_mode 0)
		)
		(polygon
			(pts
				(arc
					(start 162.1155 -34.68624)
					(mid 162.130379 -34.722161)
					(end 162.1663 -34.73704)
				)
				(arc
					(start 162.9029 -34.73704)
					(mid 162.938821 -34.722161)
					(end 162.9537 -34.68624)
				)
				(xy 162.9537 -34.4424) (xy 162.72129 -34.08807) (xy 162.9537 -33.73247)
				(arc
					(start 162.9537 -33.4899)
					(mid 162.938821 -33.453979)
					(end 162.9029 -33.4391)
				)
				(arc
					(start 162.1663 -33.4391)
					(mid 162.130379 -33.453979)
					(end 162.1155 -33.4899)
				)
				(xy 162.1155 -33.73247) (xy 162.34791 -34.08934) (xy 162.1155 -34.44367)
			)
		)
	)
	(zone
		(layer "In1.Cu")
		(hatch none 0.5)
		(connect_pads
			(clearance 0)
		)
		(min_thickness 0.25)
		(keepout
			(tracks not_allowed)
			(vias allowed)
			(pads allowed)
			(copperpour not_allowed)
			(footprints allowed)
		)
		(placement
			(enabled no)
			(sheetname "")
		)
		(fill
			(thermal_gap 0.5)
			(thermal_bridge_width 0.5)
			(island_removal_mode 0)
		)
		(polygon
			(pts
				(arc
					(start 321.66433 -349.679514)
					(mid 321.628409 -349.694393)
					(end 321.61353 -349.730314)
				)
				(arc
					(start 321.61353 -350.466914)
					(mid 321.628409 -350.502835)
					(end 321.66433 -350.517714)
				)
				(xy 321.90817 -350.517714) (xy 322.2625 -350.285304) (xy 322.6181 -350.517714)
				(arc
					(start 322.86067 -350.517714)
					(mid 322.896591 -350.502835)
					(end 322.91147 -350.466914)
				)
				(arc
					(start 322.91147 -349.730314)
					(mid 322.896591 -349.694393)
					(end 322.86067 -349.679514)
				)
				(xy 322.6181 -349.679514) (xy 322.26123 -349.911924) (xy 321.9069 -349.679514)
			)
		)
	)
	(zone
		(layer "In1.Cu")
		(hatch none 0.5)
		(connect_pads
			(clearance 0)
		)
		(min_thickness 0.25)
		(keepout
			(tracks not_allowed)
			(vias allowed)
			(pads allowed)
			(copperpour not_allowed)
			(footprints allowed)
		)
		(placement
			(enabled no)
			(sheetname "")
		)
		(fill
			(thermal_gap 0.5)
			(thermal_bridge_width 0.5)
			(island_removal_mode 0)
		)
		(polygon
			(pts
				(arc
					(start 404.02256 17.486884)
					(mid 404.000242 17.433002)
					(end 403.94636 17.410684)
				)
				(arc
					(start 403.33422 17.410684)
					(mid 403.280338 17.433002)
					(end 403.25802 17.486884)
				)
				(arc
					(start 403.25802 18.584164)
					(mid 403.280338 18.638046)
					(end 403.33422 18.660364)
				)
				(arc
					(start 403.94636 18.660364)
					(mid 404.000242 18.638046)
					(end 404.02256 18.584164)
				)
			)
		)
	)
	(zone
		(layer "In1.Cu")
		(hatch none 0.5)
		(connect_pads
			(clearance 0)
		)
		(min_thickness 0.25)
		(keepout
			(tracks not_allowed)
			(vias allowed)
			(pads allowed)
			(copperpour not_allowed)
			(footprints allowed)
		)
		(placement
			(enabled no)
			(sheetname "")
		)
		(fill
			(thermal_gap 0.5)
			(thermal_bridge_width 0.5)
			(island_removal_mode 0)
		)
		(polygon
			(pts
				(arc
					(start 82.969608 -355.825806)
					(mid 82.933687 -355.840685)
					(end 82.918808 -355.876606)
				)
				(arc
					(start 82.918808 -356.613206)
					(mid 82.933687 -356.649127)
					(end 82.969608 -356.664006)
				)
				(xy 83.213448 -356.664006) (xy 83.567778 -356.431596) (xy 83.923378 -356.664006)
				(arc
					(start 84.165948 -356.664006)
					(mid 84.201869 -356.649127)
					(end 84.216748 -356.613206)
				)
				(arc
					(start 84.216748 -355.876606)
					(mid 84.201869 -355.840685)
					(end 84.165948 -355.825806)
				)
				(xy 83.923378 -355.825806) (xy 83.566508 -356.058216) (xy 83.212178 -355.825806)
			)
		)
	)
	(zone
		(layer "In1.Cu")
		(hatch none 0.5)
		(connect_pads
			(clearance 0)
		)
		(min_thickness 0.25)
		(keepout
			(tracks not_allowed)
			(vias allowed)
			(pads allowed)
			(copperpour not_allowed)
			(footprints allowed)
		)
		(placement
			(enabled no)
			(sheetname "")
		)
		(fill
			(thermal_gap 0.5)
			(thermal_bridge_width 0.5)
			(island_removal_mode 0)
		)
		(polygon
			(pts
				(arc
					(start 294.22979 -28.174188)
					(mid 294.244669 -28.138267)
					(end 294.28059 -28.123388)
				)
				(arc
					(start 295.51249 -28.123388)
					(mid 295.548411 -28.138267)
					(end 295.56329 -28.174188)
				)
				(arc
					(start 295.56329 -29.205936)
					(mid 295.548411 -29.241857)
					(end 295.51249 -29.256736)
				)
				(arc
					(start 294.28059 -29.256736)
					(mid 294.244669 -29.241857)
					(end 294.22979 -29.205936)
				)
			)
		)
	)
	(zone
		(layer "In1.Cu")
		(hatch none 0.5)
		(connect_pads
			(clearance 0)
		)
		(min_thickness 0.25)
		(keepout
			(tracks not_allowed)
			(vias allowed)
			(pads allowed)
			(copperpour not_allowed)
			(footprints allowed)
		)
		(placement
			(enabled no)
			(sheetname "")
		)
		(fill
			(thermal_gap 0.5)
			(thermal_bridge_width 0.5)
			(island_removal_mode 0)
		)
		(polygon
			(pts
				(arc
					(start 131.99999 -34.605976)
					(mid 131.985111 -34.641897)
					(end 131.94919 -34.656776)
				)
				(arc
					(start 130.71729 -34.656776)
					(mid 130.681369 -34.641897)
					(end 130.66649 -34.605976)
				)
				(arc
					(start 130.66649 -33.574228)
					(mid 130.681369 -33.538307)
					(end 130.71729 -33.523428)
				)
				(arc
					(start 131.94919 -33.523428)
					(mid 131.985111 -33.538307)
					(end 131.99999 -33.574228)
				)
			)
		)
	)
	(zone
		(layer "In1.Cu")
		(hatch none 0.5)
		(connect_pads
			(clearance 0)
		)
		(min_thickness 0.25)
		(keepout
			(tracks not_allowed)
			(vias allowed)
			(pads allowed)
			(copperpour not_allowed)
			(footprints allowed)
		)
		(placement
			(enabled no)
			(sheetname "")
		)
		(fill
			(thermal_gap 0.5)
			(thermal_bridge_width 0.5)
			(island_removal_mode 0)
		)
		(polygon
			(pts
				(arc
					(start 314.442348 -136.341104)
					(mid 314.457227 -136.377025)
					(end 314.493148 -136.391904)
				)
				(arc
					(start 315.229748 -136.391904)
					(mid 315.265669 -136.377025)
					(end 315.280548 -136.341104)
				)
				(xy 315.280548 -136.097264) (xy 315.048138 -135.742934) (xy 315.280548 -135.387334)
				(arc
					(start 315.280548 -135.144764)
					(mid 315.265669 -135.108843)
					(end 315.229748 -135.093964)
				)
				(arc
					(start 314.493148 -135.093964)
					(mid 314.457227 -135.108843)
					(end 314.442348 -135.144764)
				)
				(xy 314.442348 -135.387334) (xy 314.674758 -135.744204) (xy 314.442348 -136.098534)
			)
		)
	)
	(zone
		(layer "In1.Cu")
		(hatch none 0.5)
		(connect_pads
			(clearance 0)
		)
		(min_thickness 0.25)
		(keepout
			(tracks not_allowed)
			(vias allowed)
			(pads allowed)
			(copperpour not_allowed)
			(footprints allowed)
		)
		(placement
			(enabled no)
			(sheetname "")
		)
		(fill
			(thermal_gap 0.5)
			(thermal_bridge_width 0.5)
			(island_removal_mode 0)
		)
		(polygon
			(pts
				(arc
					(start 427.783498 -349.679514)
					(mid 427.747577 -349.694393)
					(end 427.732698 -349.730314)
				)
				(arc
					(start 427.732698 -350.466914)
					(mid 427.747577 -350.502835)
					(end 427.783498 -350.517714)
				)
				(xy 428.027338 -350.517714) (xy 428.381668 -350.285304) (xy 428.737268 -350.517714)
				(arc
					(start 428.979838 -350.517714)
					(mid 429.015759 -350.502835)
					(end 429.030638 -350.466914)
				)
				(arc
					(start 429.030638 -349.730314)
					(mid 429.015759 -349.694393)
					(end 428.979838 -349.679514)
				)
				(xy 428.737268 -349.679514) (xy 428.380398 -349.911924) (xy 428.026068 -349.679514)
			)
		)
	)
	(zone
		(layer "In1.Cu")
		(hatch none 0.5)
		(connect_pads
			(clearance 0)
		)
		(min_thickness 0.25)
		(keepout
			(tracks not_allowed)
			(vias allowed)
			(pads allowed)
			(copperpour not_allowed)
			(footprints allowed)
		)
		(placement
			(enabled no)
			(sheetname "")
		)
		(fill
			(thermal_gap 0.5)
			(thermal_bridge_width 0.5)
			(island_removal_mode 0)
		)
		(polygon
			(pts
				(arc
					(start 393.732766 -124.551948)
					(mid 393.747645 -124.516027)
					(end 393.783566 -124.501148)
				)
				(arc
					(start 394.964666 -124.501148)
					(mid 395.000587 -124.516027)
					(end 395.015466 -124.551948)
				)
				(arc
					(start 395.015466 -125.558296)
					(mid 395.000587 -125.594217)
					(end 394.964666 -125.609096)
				)
				(arc
					(start 393.783566 -125.609096)
					(mid 393.747645 -125.594217)
					(end 393.732766 -125.558296)
				)
			)
		)
	)
	(zone
		(layer "In1.Cu")
		(hatch none 0.5)
		(connect_pads
			(clearance 0)
		)
		(min_thickness 0.25)
		(keepout
			(tracks not_allowed)
			(vias allowed)
			(pads allowed)
			(copperpour not_allowed)
			(footprints allowed)
		)
		(placement
			(enabled no)
			(sheetname "")
		)
		(fill
			(thermal_gap 0.5)
			(thermal_bridge_width 0.5)
			(island_removal_mode 0)
		)
		(polygon
			(pts
				(arc
					(start 424.674538 -355.825806)
					(mid 424.638617 -355.840685)
					(end 424.623738 -355.876606)
				)
				(arc
					(start 424.623738 -356.613206)
					(mid 424.638617 -356.649127)
					(end 424.674538 -356.664006)
				)
				(xy 424.918378 -356.664006) (xy 425.272708 -356.431596) (xy 425.628308 -356.664006)
				(arc
					(start 425.870878 -356.664006)
					(mid 425.906799 -356.649127)
					(end 425.921678 -356.613206)
				)
				(arc
					(start 425.921678 -355.876606)
					(mid 425.906799 -355.840685)
					(end 425.870878 -355.825806)
				)
				(xy 425.628308 -355.825806) (xy 425.271438 -356.058216) (xy 424.917108 -355.825806)
			)
		)
	)
	(zone
		(layer "In1.Cu")
		(hatch none 0.5)
		(connect_pads
			(clearance 0)
		)
		(min_thickness 0.25)
		(keepout
			(tracks not_allowed)
			(vias allowed)
			(pads allowed)
			(copperpour not_allowed)
			(footprints allowed)
		)
		(placement
			(enabled no)
			(sheetname "")
		)
		(fill
			(thermal_gap 0.5)
			(thermal_bridge_width 0.5)
			(island_removal_mode 0)
		)
		(polygon
			(pts
				(arc
					(start 399.003266 -349.679514)
					(mid 398.967345 -349.694393)
					(end 398.952466 -349.730314)
				)
				(arc
					(start 398.952466 -350.466914)
					(mid 398.967345 -350.502835)
					(end 399.003266 -350.517714)
				)
				(xy 399.247106 -350.517714) (xy 399.601436 -350.285304) (xy 399.957036 -350.517714)
				(arc
					(start 400.199606 -350.517714)
					(mid 400.235527 -350.502835)
					(end 400.250406 -350.466914)
				)
				(arc
					(start 400.250406 -349.730314)
					(mid 400.235527 -349.694393)
					(end 400.199606 -349.679514)
				)
				(xy 399.957036 -349.679514) (xy 399.600166 -349.911924) (xy 399.245836 -349.679514)
			)
		)
	)
	(zone
		(layer "In1.Cu")
		(hatch none 0.5)
		(connect_pads
			(clearance 0)
		)
		(min_thickness 0.25)
		(keepout
			(tracks not_allowed)
			(vias allowed)
			(pads allowed)
			(copperpour not_allowed)
			(footprints allowed)
		)
		(placement
			(enabled no)
			(sheetname "")
		)
		(fill
			(thermal_gap 0.5)
			(thermal_bridge_width 0.5)
			(island_removal_mode 0)
		)
		(polygon
			(pts
				(arc
					(start 320.229738 -29.974286)
					(mid 320.244617 -29.938365)
					(end 320.280538 -29.923486)
				)
				(arc
					(start 321.512438 -29.923486)
					(mid 321.548359 -29.938365)
					(end 321.563238 -29.974286)
				)
				(arc
					(start 321.563238 -31.006034)
					(mid 321.548359 -31.041955)
					(end 321.512438 -31.056834)
				)
				(arc
					(start 320.280538 -31.056834)
					(mid 320.244617 -31.041955)
					(end 320.229738 -31.006034)
				)
			)
		)
	)
	(zone
		(layer "In1.Cu")
		(hatch none 0.5)
		(connect_pads
			(clearance 0)
		)
		(min_thickness 0.25)
		(keepout
			(tracks not_allowed)
			(vias allowed)
			(pads allowed)
			(copperpour not_allowed)
			(footprints allowed)
		)
		(placement
			(enabled no)
			(sheetname "")
		)
		(fill
			(thermal_gap 0.5)
			(thermal_bridge_width 0.5)
			(island_removal_mode 0)
		)
		(polygon
			(pts
				(arc
					(start 186.892438 -355.80193)
					(mid 186.856517 -355.816809)
					(end 186.841638 -355.85273)
				)
				(arc
					(start 186.841638 -356.58933)
					(mid 186.856517 -356.625251)
					(end 186.892438 -356.64013)
				)
				(xy 187.136278 -356.64013) (xy 187.490608 -356.40772) (xy 187.846208 -356.64013)
				(arc
					(start 188.088778 -356.64013)
					(mid 188.124699 -356.625251)
					(end 188.139578 -356.58933)
				)
				(arc
					(start 188.139578 -355.85273)
					(mid 188.124699 -355.816809)
					(end 188.088778 -355.80193)
				)
				(xy 187.846208 -355.80193) (xy 187.489338 -356.03434) (xy 187.135008 -355.80193)
			)
		)
	)
	(zone
		(layer "In1.Cu")
		(hatch none 0.5)
		(connect_pads
			(clearance 0)
		)
		(min_thickness 0.25)
		(keepout
			(tracks not_allowed)
			(vias allowed)
			(pads allowed)
			(copperpour not_allowed)
			(footprints allowed)
		)
		(placement
			(enabled no)
			(sheetname "")
		)
		(fill
			(thermal_gap 0.5)
			(thermal_bridge_width 0.5)
			(island_removal_mode 0)
		)
		(polygon
			(pts
				(arc
					(start 300.247812 -129.841752)
					(mid 300.262691 -129.805831)
					(end 300.298612 -129.790952)
				)
				(arc
					(start 301.479712 -129.790952)
					(mid 301.515633 -129.805831)
					(end 301.530512 -129.841752)
				)
				(arc
					(start 301.530512 -130.8481)
					(mid 301.515633 -130.884021)
					(end 301.479712 -130.8989)
				)
				(arc
					(start 300.298612 -130.8989)
					(mid 300.262691 -130.884021)
					(end 300.247812 -130.8481)
				)
			)
		)
	)
	(zone
		(layer "In1.Cu")
		(hatch none 0.5)
		(connect_pads
			(clearance 0)
		)
		(min_thickness 0.25)
		(keepout
			(tracks not_allowed)
			(vias allowed)
			(pads allowed)
			(copperpour not_allowed)
			(footprints allowed)
		)
		(placement
			(enabled no)
			(sheetname "")
		)
		(fill
			(thermal_gap 0.5)
			(thermal_bridge_width 0.5)
			(island_removal_mode 0)
		)
		(polygon
			(pts
				(arc
					(start 195.700142 -143.64462)
					(mid 195.715021 -143.680541)
					(end 195.750942 -143.69542)
				)
				(arc
					(start 196.487542 -143.69542)
					(mid 196.523463 -143.680541)
					(end 196.538342 -143.64462)
				)
				(xy 196.538342 -143.40078) (xy 196.305932 -143.04645) (xy 196.538342 -142.69085)
				(arc
					(start 196.538342 -142.44828)
					(mid 196.523463 -142.412359)
					(end 196.487542 -142.39748)
				)
				(arc
					(start 195.750942 -142.39748)
					(mid 195.715021 -142.412359)
					(end 195.700142 -142.44828)
				)
				(xy 195.700142 -142.69085) (xy 195.932552 -143.04772) (xy 195.700142 -143.40205)
			)
		)
	)
	(zone
		(layer "In1.Cu")
		(hatch none 0.5)
		(connect_pads
			(clearance 0)
		)
		(min_thickness 0.25)
		(keepout
			(tracks not_allowed)
			(vias allowed)
			(pads allowed)
			(copperpour not_allowed)
			(footprints allowed)
		)
		(placement
			(enabled no)
			(sheetname "")
		)
		(fill
			(thermal_gap 0.5)
			(thermal_bridge_width 0.5)
			(island_removal_mode 0)
		)
		(polygon
			(pts
				(arc
					(start 73.867264 -134.448296)
					(mid 73.852385 -134.484217)
					(end 73.816464 -134.499096)
				)
				(arc
					(start 72.635364 -134.499096)
					(mid 72.599443 -134.484217)
					(end 72.584564 -134.448296)
				)
				(arc
					(start 72.584564 -133.441948)
					(mid 72.599443 -133.406027)
					(end 72.635364 -133.391148)
				)
				(arc
					(start 73.816464 -133.391148)
					(mid 73.852385 -133.406027)
					(end 73.867264 -133.441948)
				)
			)
		)
	)
	(zone
		(layer "In1.Cu")
		(hatch none 0.5)
		(connect_pads
			(clearance 0)
		)
		(min_thickness 0.25)
		(keepout
			(tracks not_allowed)
			(vias allowed)
			(pads allowed)
			(copperpour not_allowed)
			(footprints allowed)
		)
		(placement
			(enabled no)
			(sheetname "")
		)
		(fill
			(thermal_gap 0.5)
			(thermal_bridge_width 0.5)
			(island_removal_mode 0)
		)
		(polygon
			(pts
				(arc
					(start 326.099678 -32.805878)
					(mid 326.084799 -32.841799)
					(end 326.048878 -32.856678)
				)
				(arc
					(start 324.816978 -32.856678)
					(mid 324.781057 -32.841799)
					(end 324.766178 -32.805878)
				)
				(arc
					(start 324.766178 -31.77413)
					(mid 324.781057 -31.738209)
					(end 324.816978 -31.72333)
				)
				(arc
					(start 326.048878 -31.72333)
					(mid 326.084799 -31.738209)
					(end 326.099678 -31.77413)
				)
			)
		)
	)
	(zone
		(layer "In1.Cu")
		(hatch none 0.5)
		(connect_pads
			(clearance 0)
		)
		(min_thickness 0.25)
		(keepout
			(tracks not_allowed)
			(vias allowed)
			(pads allowed)
			(copperpour not_allowed)
			(footprints allowed)
		)
		(placement
			(enabled no)
			(sheetname "")
		)
		(fill
			(thermal_gap 0.5)
			(thermal_bridge_width 0.5)
			(island_removal_mode 0)
		)
		(polygon
			(pts
				(arc
					(start 422.167304 -123.23826)
					(mid 422.152425 -123.274181)
					(end 422.116504 -123.28906)
				)
				(arc
					(start 420.935404 -123.28906)
					(mid 420.899483 -123.274181)
					(end 420.884604 -123.23826)
				)
				(arc
					(start 420.884604 -122.231912)
					(mid 420.899483 -122.195991)
					(end 420.935404 -122.181112)
				)
				(arc
					(start 422.116504 -122.181112)
					(mid 422.152425 -122.195991)
					(end 422.167304 -122.231912)
				)
			)
		)
	)
	(zone
		(layer "In1.Cu")
		(hatch none 0.5)
		(connect_pads
			(clearance 0)
		)
		(min_thickness 0.25)
		(keepout
			(tracks not_allowed)
			(vias allowed)
			(pads allowed)
			(copperpour not_allowed)
			(footprints allowed)
		)
		(placement
			(enabled no)
			(sheetname "")
		)
		(fill
			(thermal_gap 0.5)
			(thermal_bridge_width 0.5)
			(island_removal_mode 0)
		)
		(polygon
			(pts
				(arc
					(start 72.01535 -31.086044)
					(mid 72.030229 -31.121965)
					(end 72.06615 -31.136844)
				)
				(arc
					(start 72.80275 -31.136844)
					(mid 72.838671 -31.121965)
					(end 72.85355 -31.086044)
				)
				(xy 72.85355 -30.842204) (xy 72.62114 -30.487874) (xy 72.85355 -30.132274)
				(arc
					(start 72.85355 -29.889704)
					(mid 72.838671 -29.853783)
					(end 72.80275 -29.838904)
				)
				(arc
					(start 72.06615 -29.838904)
					(mid 72.030229 -29.853783)
					(end 72.01535 -29.889704)
				)
				(xy 72.01535 -30.132274) (xy 72.24776 -30.489144) (xy 72.01535 -30.843474)
			)
		)
	)
	(zone
		(layer "In1.Cu")
		(hatch none 0.5)
		(connect_pads
			(clearance 0)
		)
		(min_thickness 0.25)
		(keepout
			(tracks not_allowed)
			(vias allowed)
			(pads allowed)
			(copperpour not_allowed)
			(footprints allowed)
		)
		(placement
			(enabled no)
			(sheetname "")
		)
		(fill
			(thermal_gap 0.5)
			(thermal_bridge_width 0.5)
			(island_removal_mode 0)
		)
		(polygon
			(pts
				(arc
					(start 167.351964 -102.04831)
					(mid 167.337085 -102.084231)
					(end 167.301164 -102.09911)
				)
				(arc
					(start 166.120064 -102.09911)
					(mid 166.084143 -102.084231)
					(end 166.069264 -102.04831)
				)
				(arc
					(start 166.069264 -101.041962)
					(mid 166.084143 -101.006041)
					(end 166.120064 -100.991162)
				)
				(arc
					(start 167.301164 -100.991162)
					(mid 167.337085 -101.006041)
					(end 167.351964 -101.041962)
				)
			)
		)
	)
	(zone
		(layer "In1.Cu")
		(hatch none 0.5)
		(connect_pads
			(clearance 0)
		)
		(min_thickness 0.25)
		(keepout
			(tracks not_allowed)
			(vias allowed)
			(pads allowed)
			(copperpour not_allowed)
			(footprints allowed)
		)
		(placement
			(enabled no)
			(sheetname "")
		)
		(fill
			(thermal_gap 0.5)
			(thermal_bridge_width 0.5)
			(island_removal_mode 0)
		)
		(polygon
			(pts
				(arc
					(start 183.999886 -32.805878)
					(mid 183.985007 -32.841799)
					(end 183.949086 -32.856678)
				)
				(arc
					(start 182.717186 -32.856678)
					(mid 182.681265 -32.841799)
					(end 182.666386 -32.805878)
				)
				(arc
					(start 182.666386 -31.77413)
					(mid 182.681265 -31.738209)
					(end 182.717186 -31.72333)
				)
				(arc
					(start 183.949086 -31.72333)
					(mid 183.985007 -31.738209)
					(end 183.999886 -31.77413)
				)
			)
		)
	)
	(zone
		(layer "In1.Cu")
		(hatch none 0.5)
		(connect_pads
			(clearance 0)
		)
		(min_thickness 0.25)
		(keepout
			(tracks not_allowed)
			(vias allowed)
			(pads allowed)
			(copperpour not_allowed)
			(footprints allowed)
		)
		(placement
			(enabled no)
			(sheetname "")
		)
		(fill
			(thermal_gap 0.5)
			(thermal_bridge_width 0.5)
			(island_removal_mode 0)
		)
		(polygon
			(pts
				(arc
					(start 177.565558 -349.679514)
					(mid 177.529637 -349.694393)
					(end 177.514758 -349.730314)
				)
				(arc
					(start 177.514758 -350.466914)
					(mid 177.529637 -350.502835)
					(end 177.565558 -350.517714)
				)
				(xy 177.809398 -350.517714) (xy 178.163728 -350.285304) (xy 178.519328 -350.517714)
				(arc
					(start 178.761898 -350.517714)
					(mid 178.797819 -350.502835)
					(end 178.812698 -350.466914)
				)
				(arc
					(start 178.812698 -349.730314)
					(mid 178.797819 -349.694393)
					(end 178.761898 -349.679514)
				)
				(xy 178.519328 -349.679514) (xy 178.162458 -349.911924) (xy 177.808128 -349.679514)
			)
		)
	)
	(zone
		(layer "In1.Cu")
		(hatch none 0.5)
		(connect_pads
			(clearance 0)
		)
		(min_thickness 0.25)
		(keepout
			(tracks not_allowed)
			(vias allowed)
			(pads allowed)
			(copperpour not_allowed)
			(footprints allowed)
		)
		(placement
			(enabled no)
			(sheetname "")
		)
		(fill
			(thermal_gap 0.5)
			(thermal_bridge_width 0.5)
			(island_removal_mode 0)
		)
		(polygon
			(pts
				(arc
					(start 34.711894 -343.533222)
					(mid 34.675973 -343.548101)
					(end 34.661094 -343.584022)
				)
				(arc
					(start 34.661094 -344.320622)
					(mid 34.675973 -344.356543)
					(end 34.711894 -344.371422)
				)
				(xy 34.955734 -344.371422) (xy 35.310064 -344.139012) (xy 35.665664 -344.371422)
				(arc
					(start 35.908234 -344.371422)
					(mid 35.944155 -344.356543)
					(end 35.959034 -344.320622)
				)
				(arc
					(start 35.959034 -343.584022)
					(mid 35.944155 -343.548101)
					(end 35.908234 -343.533222)
				)
				(xy 35.665664 -343.533222) (xy 35.308794 -343.765632) (xy 34.954464 -343.533222)
			)
		)
	)
	(zone
		(layer "In1.Cu")
		(hatch none 0.5)
		(connect_pads
			(clearance 0)
		)
		(min_thickness 0.25)
		(keepout
			(tracks not_allowed)
			(vias allowed)
			(pads allowed)
			(copperpour not_allowed)
			(footprints allowed)
		)
		(placement
			(enabled no)
			(sheetname "")
		)
		(fill
			(thermal_gap 0.5)
			(thermal_bridge_width 0.5)
			(island_removal_mode 0)
		)
		(polygon
			(pts
				(arc
					(start 152.319228 -112.949736)
					(mid 152.334107 -112.985657)
					(end 152.370028 -113.000536)
				)
				(arc
					(start 153.106628 -113.000536)
					(mid 153.142549 -112.985657)
					(end 153.157428 -112.949736)
				)
				(xy 153.157428 -112.705896) (xy 152.925018 -112.351566) (xy 153.157428 -111.995966)
				(arc
					(start 153.157428 -111.753396)
					(mid 153.142549 -111.717475)
					(end 153.106628 -111.702596)
				)
				(arc
					(start 152.370028 -111.702596)
					(mid 152.334107 -111.717475)
					(end 152.319228 -111.753396)
				)
				(xy 152.319228 -111.995966) (xy 152.551638 -112.352836) (xy 152.319228 -112.707166)
			)
		)
	)
	(zone
		(layer "In1.Cu")
		(hatch none 0.5)
		(connect_pads
			(clearance 0)
		)
		(min_thickness 0.25)
		(keepout
			(tracks not_allowed)
			(vias allowed)
			(pads allowed)
			(copperpour not_allowed)
			(footprints allowed)
		)
		(placement
			(enabled no)
			(sheetname "")
		)
		(fill
			(thermal_gap 0.5)
			(thermal_bridge_width 0.5)
			(island_removal_mode 0)
		)
		(polygon
			(pts
				(arc
					(start 168.238678 -343.533222)
					(mid 168.202757 -343.548101)
					(end 168.187878 -343.584022)
				)
				(arc
					(start 168.187878 -344.320622)
					(mid 168.202757 -344.356543)
					(end 168.238678 -344.371422)
				)
				(xy 168.482518 -344.371422) (xy 168.836848 -344.139012) (xy 169.192448 -344.371422)
				(arc
					(start 169.435018 -344.371422)
					(mid 169.470939 -344.356543)
					(end 169.485818 -344.320622)
				)
				(arc
					(start 169.485818 -343.584022)
					(mid 169.470939 -343.548101)
					(end 169.435018 -343.533222)
				)
				(xy 169.192448 -343.533222) (xy 168.835578 -343.765632) (xy 168.481248 -343.533222)
			)
		)
	)
	(zone
		(layer "In1.Cu")
		(hatch none 0.5)
		(connect_pads
			(clearance 0)
		)
		(min_thickness 0.25)
		(keepout
			(tracks not_allowed)
			(vias allowed)
			(pads allowed)
			(copperpour not_allowed)
			(footprints allowed)
		)
		(placement
			(enabled no)
			(sheetname "")
		)
		(fill
			(thermal_gap 0.5)
			(thermal_bridge_width 0.5)
			(island_removal_mode 0)
		)
		(polygon
			(pts
				(arc
					(start 93.899736 -27.405838)
					(mid 93.884857 -27.441759)
					(end 93.848936 -27.456638)
				)
				(arc
					(start 92.617036 -27.456638)
					(mid 92.581115 -27.441759)
					(end 92.566236 -27.405838)
				)
				(arc
					(start 92.566236 -26.37409)
					(mid 92.581115 -26.338169)
					(end 92.617036 -26.32329)
				)
				(arc
					(start 93.848936 -26.32329)
					(mid 93.884857 -26.338169)
					(end 93.899736 -26.37409)
				)
			)
		)
	)
	(zone
		(layer "In1.Cu")
		(hatch none 0.5)
		(connect_pads
			(clearance 0)
		)
		(min_thickness 0.25)
		(keepout
			(tracks not_allowed)
			(vias allowed)
			(pads allowed)
			(copperpour not_allowed)
			(footprints allowed)
		)
		(placement
			(enabled no)
			(sheetname "")
		)
		(fill
			(thermal_gap 0.5)
			(thermal_bridge_width 0.5)
			(island_removal_mode 0)
		)
		(polygon
			(pts
				(arc
					(start 43.373294 -29.279596)
					(mid 43.388173 -29.315517)
					(end 43.424094 -29.330396)
				)
				(arc
					(start 44.160694 -29.330396)
					(mid 44.196615 -29.315517)
					(end 44.211494 -29.279596)
				)
				(xy 44.211494 -29.035756) (xy 43.979084 -28.681426) (xy 44.211494 -28.325826)
				(arc
					(start 44.211494 -28.083256)
					(mid 44.196615 -28.047335)
					(end 44.160694 -28.032456)
				)
				(arc
					(start 43.424094 -28.032456)
					(mid 43.388173 -28.047335)
					(end 43.373294 -28.083256)
				)
				(xy 43.373294 -28.325826) (xy 43.605704 -28.682696) (xy 43.373294 -29.037026)
			)
		)
	)
	(zone
		(layer "In1.Cu")
		(hatch none 0.5)
		(connect_pads
			(clearance 0)
		)
		(min_thickness 0.25)
		(keepout
			(tracks not_allowed)
			(vias allowed)
			(pads allowed)
			(copperpour not_allowed)
			(footprints allowed)
		)
		(placement
			(enabled no)
			(sheetname "")
		)
		(fill
			(thermal_gap 0.5)
			(thermal_bridge_width 0.5)
			(island_removal_mode 0)
		)
		(polygon
			(pts
				(arc
					(start 10.437114 -382.396746)
					(mid 10.347311 -382.359549)
					(end 10.310114 -382.269746)
				)
				(arc
					(start 10.310114 -381.923798)
					(mid 10.347311 -381.833995)
					(end 10.437114 -381.796798)
				)
				(arc
					(start 10.923016 -381.796798)
					(mid 11.012819 -381.833995)
					(end 11.050016 -381.923798)
				)
				(arc
					(start 11.050016 -382.269746)
					(mid 11.012819 -382.359549)
					(end 10.923016 -382.396746)
				)
			)
		)
	)
	(zone
		(layer "In1.Cu")
		(hatch none 0.5)
		(connect_pads
			(clearance 0)
		)
		(min_thickness 0.25)
		(keepout
			(tracks not_allowed)
			(vias allowed)
			(pads allowed)
			(copperpour not_allowed)
			(footprints allowed)
		)
		(placement
			(enabled no)
			(sheetname "")
		)
		(fill
			(thermal_gap 0.5)
			(thermal_bridge_width 0.5)
			(island_removal_mode 0)
		)
		(polygon
			(pts
				(arc
					(start 152.319228 -120.253252)
					(mid 152.334107 -120.289173)
					(end 152.370028 -120.304052)
				)
				(arc
					(start 153.106628 -120.304052)
					(mid 153.142549 -120.289173)
					(end 153.157428 -120.253252)
				)
				(xy 153.157428 -120.009412) (xy 152.925018 -119.655082) (xy 153.157428 -119.299482)
				(arc
					(start 153.157428 -119.056912)
					(mid 153.142549 -119.020991)
					(end 153.106628 -119.006112)
				)
				(arc
					(start 152.370028 -119.006112)
					(mid 152.334107 -119.020991)
					(end 152.319228 -119.056912)
				)
				(xy 152.319228 -119.299482) (xy 152.551638 -119.656352) (xy 152.319228 -120.010682)
			)
		)
	)
	(zone
		(layer "In1.Cu")
		(hatch none 0.5)
		(connect_pads
			(clearance 0)
		)
		(min_thickness 0.25)
		(keepout
			(tracks not_allowed)
			(vias allowed)
			(pads allowed)
			(copperpour not_allowed)
			(footprints allowed)
		)
		(placement
			(enabled no)
			(sheetname "")
		)
		(fill
			(thermal_gap 0.5)
			(thermal_bridge_width 0.5)
			(island_removal_mode 0)
		)
		(polygon
			(pts
				(arc
					(start 427.900338 -134.534656)
					(mid 427.915217 -134.570577)
					(end 427.951138 -134.585456)
				)
				(arc
					(start 428.687738 -134.585456)
					(mid 428.723659 -134.570577)
					(end 428.738538 -134.534656)
				)
				(xy 428.738538 -134.290816) (xy 428.506128 -133.936486) (xy 428.738538 -133.580886)
				(arc
					(start 428.738538 -133.338316)
					(mid 428.723659 -133.302395)
					(end 428.687738 -133.287516)
				)
				(arc
					(start 427.951138 -133.287516)
					(mid 427.915217 -133.302395)
					(end 427.900338 -133.338316)
				)
				(xy 427.900338 -133.580886) (xy 428.132748 -133.937756) (xy 427.900338 -134.292086)
			)
		)
	)
	(zone
		(layer "In1.Cu")
		(hatch none 0.5)
		(connect_pads
			(clearance 0)
		)
		(min_thickness 0.25)
		(keepout
			(tracks not_allowed)
			(vias allowed)
			(pads allowed)
			(copperpour not_allowed)
			(footprints allowed)
		)
		(placement
			(enabled no)
			(sheetname "")
		)
		(fill
			(thermal_gap 0.5)
			(thermal_bridge_width 0.5)
			(island_removal_mode 0)
		)
		(polygon
			(pts
				(arc
					(start 416.34791 -149.751796)
					(mid 416.362789 -149.715875)
					(end 416.39871 -149.700996)
				)
				(arc
					(start 417.57981 -149.700996)
					(mid 417.615731 -149.715875)
					(end 417.63061 -149.751796)
				)
				(arc
					(start 417.63061 -150.758144)
					(mid 417.615731 -150.794065)
					(end 417.57981 -150.808944)
				)
				(arc
					(start 416.39871 -150.808944)
					(mid 416.362789 -150.794065)
					(end 416.34791 -150.758144)
				)
			)
		)
	)
	(zone
		(layer "In1.Cu")
		(hatch none 0.5)
		(connect_pads
			(clearance 0)
		)
		(min_thickness 0.25)
		(keepout
			(tracks not_allowed)
			(vias allowed)
			(pads allowed)
			(copperpour not_allowed)
			(footprints allowed)
		)
		(placement
			(enabled no)
			(sheetname "")
		)
		(fill
			(thermal_gap 0.5)
			(thermal_bridge_width 0.5)
			(island_removal_mode 0)
		)
		(polygon
			(pts
				(arc
					(start 101.702362 -386.232146)
					(mid 101.612559 -386.194949)
					(end 101.575362 -386.105146)
				)
				(arc
					(start 101.575362 -385.903978)
					(mid 101.612559 -385.814175)
					(end 101.702362 -385.776978)
				)
				(arc
					(start 101.956362 -385.776978)
					(mid 102.046165 -385.814175)
					(end 102.083362 -385.903978)
				)
				(arc
					(start 102.083362 -386.105146)
					(mid 102.046165 -386.194949)
					(end 101.956362 -386.232146)
				)
			)
		)
	)
	(zone
		(layer "In1.Cu")
		(hatch none 0.5)
		(connect_pads
			(clearance 0)
		)
		(min_thickness 0.25)
		(keepout
			(tracks not_allowed)
			(vias allowed)
			(pads allowed)
			(copperpour not_allowed)
			(footprints allowed)
		)
		(placement
			(enabled no)
			(sheetname "")
		)
		(fill
			(thermal_gap 0.5)
			(thermal_bridge_width 0.5)
			(island_removal_mode 0)
		)
		(polygon
			(pts
				(arc
					(start 198.34225 -132.741162)
					(mid 198.357129 -132.777083)
					(end 198.39305 -132.791962)
				)
				(arc
					(start 199.12965 -132.791962)
					(mid 199.165571 -132.777083)
					(end 199.18045 -132.741162)
				)
				(xy 199.18045 -132.497322) (xy 198.94804 -132.142992) (xy 199.18045 -131.787392)
				(arc
					(start 199.18045 -131.544822)
					(mid 199.165571 -131.508901)
					(end 199.12965 -131.494022)
				)
				(arc
					(start 198.39305 -131.494022)
					(mid 198.357129 -131.508901)
					(end 198.34225 -131.544822)
				)
				(xy 198.34225 -131.787392) (xy 198.57466 -132.144262) (xy 198.34225 -132.498592)
			)
		)
	)
	(zone
		(layer "In1.Cu")
		(hatch none 0.5)
		(connect_pads
			(clearance 0)
		)
		(min_thickness 0.25)
		(keepout
			(tracks not_allowed)
			(vias allowed)
			(pads allowed)
			(copperpour not_allowed)
			(footprints allowed)
		)
		(placement
			(enabled no)
			(sheetname "")
		)
		(fill
			(thermal_gap 0.5)
			(thermal_bridge_width 0.5)
			(island_removal_mode 0)
		)
		(polygon
			(pts
				(arc
					(start 67.424808 -349.679514)
					(mid 67.388887 -349.694393)
					(end 67.374008 -349.730314)
				)
				(arc
					(start 67.374008 -350.466914)
					(mid 67.388887 -350.502835)
					(end 67.424808 -350.517714)
				)
				(xy 67.668648 -350.517714) (xy 68.022978 -350.285304) (xy 68.378578 -350.517714)
				(arc
					(start 68.621148 -350.517714)
					(mid 68.657069 -350.502835)
					(end 68.671948 -350.466914)
				)
				(arc
					(start 68.671948 -349.730314)
					(mid 68.657069 -349.694393)
					(end 68.621148 -349.679514)
				)
				(xy 68.378578 -349.679514) (xy 68.021708 -349.911924) (xy 67.667378 -349.679514)
			)
		)
	)
	(zone
		(layer "In1.Cu")
		(hatch none 0.5)
		(connect_pads
			(clearance 0)
		)
		(min_thickness 0.25)
		(keepout
			(tracks not_allowed)
			(vias allowed)
			(pads allowed)
			(copperpour not_allowed)
			(footprints allowed)
		)
		(placement
			(enabled no)
			(sheetname "")
		)
		(fill
			(thermal_gap 0.5)
			(thermal_bridge_width 0.5)
			(island_removal_mode 0)
		)
		(polygon
			(pts
				(arc
					(start 365.673386 -29.279596)
					(mid 365.688265 -29.315517)
					(end 365.724186 -29.330396)
				)
				(arc
					(start 366.460786 -29.330396)
					(mid 366.496707 -29.315517)
					(end 366.511586 -29.279596)
				)
				(xy 366.511586 -29.035756) (xy 366.279176 -28.681426) (xy 366.511586 -28.325826)
				(arc
					(start 366.511586 -28.083256)
					(mid 366.496707 -28.047335)
					(end 366.460786 -28.032456)
				)
				(arc
					(start 365.724186 -28.032456)
					(mid 365.688265 -28.047335)
					(end 365.673386 -28.083256)
				)
				(xy 365.673386 -28.325826) (xy 365.905796 -28.682696) (xy 365.673386 -29.037026)
			)
		)
	)
	(zone
		(layer "In1.Cu")
		(hatch none 0.5)
		(connect_pads
			(clearance 0)
		)
		(min_thickness 0.25)
		(keepout
			(tracks not_allowed)
			(vias allowed)
			(pads allowed)
			(copperpour not_allowed)
			(footprints allowed)
		)
		(placement
			(enabled no)
			(sheetname "")
		)
		(fill
			(thermal_gap 0.5)
			(thermal_bridge_width 0.5)
			(island_removal_mode 0)
		)
		(polygon
			(pts
				(arc
					(start 364.199932 -34.605976)
					(mid 364.185053 -34.641897)
					(end 364.149132 -34.656776)
				)
				(arc
					(start 362.917232 -34.656776)
					(mid 362.881311 -34.641897)
					(end 362.866432 -34.605976)
				)
				(arc
					(start 362.866432 -33.574228)
					(mid 362.881311 -33.538307)
					(end 362.917232 -33.523428)
				)
				(arc
					(start 364.149132 -33.523428)
					(mid 364.185053 -33.538307)
					(end 364.199932 -33.574228)
				)
			)
		)
	)
	(zone
		(layer "In1.Cu")
		(hatch none 0.5)
		(connect_pads
			(clearance 0)
		)
		(min_thickness 0.25)
		(keepout
			(tracks not_allowed)
			(vias allowed)
			(pads allowed)
			(copperpour not_allowed)
			(footprints allowed)
		)
		(placement
			(enabled no)
			(sheetname "")
		)
		(fill
			(thermal_gap 0.5)
			(thermal_bridge_width 0.5)
			(island_removal_mode 0)
		)
		(polygon
			(pts
				(arc
					(start 126.13005 -33.574228)
					(mid 126.144929 -33.538307)
					(end 126.18085 -33.523428)
				)
				(arc
					(start 127.41275 -33.523428)
					(mid 127.448671 -33.538307)
					(end 127.46355 -33.574228)
				)
				(arc
					(start 127.46355 -34.605976)
					(mid 127.448671 -34.641897)
					(end 127.41275 -34.656776)
				)
				(arc
					(start 126.18085 -34.656776)
					(mid 126.144929 -34.641897)
					(end 126.13005 -34.605976)
				)
			)
		)
	)
	(zone
		(layer "In1.Cu")
		(hatch none 0.5)
		(connect_pads
			(clearance 0)
		)
		(min_thickness 0.25)
		(keepout
			(tracks not_allowed)
			(vias allowed)
			(pads allowed)
			(copperpour not_allowed)
			(footprints allowed)
		)
		(placement
			(enabled no)
			(sheetname "")
		)
		(fill
			(thermal_gap 0.5)
			(thermal_bridge_width 0.5)
			(island_removal_mode 0)
		)
		(polygon
			(pts
				(arc
					(start 268.229842 -29.974286)
					(mid 268.244721 -29.938365)
					(end 268.280642 -29.923486)
				)
				(arc
					(start 269.512542 -29.923486)
					(mid 269.548463 -29.938365)
					(end 269.563342 -29.974286)
				)
				(arc
					(start 269.563342 -31.006034)
					(mid 269.548463 -31.041955)
					(end 269.512542 -31.056834)
				)
				(arc
					(start 268.280642 -31.056834)
					(mid 268.244721 -31.041955)
					(end 268.229842 -31.006034)
				)
			)
		)
	)
	(zone
		(layer "In1.Cu")
		(hatch none 0.5)
		(connect_pads
			(clearance 0)
		)
		(min_thickness 0.25)
		(keepout
			(tracks not_allowed)
			(vias allowed)
			(pads allowed)
			(copperpour not_allowed)
			(footprints allowed)
		)
		(placement
			(enabled no)
			(sheetname "")
		)
		(fill
			(thermal_gap 0.5)
			(thermal_bridge_width 0.5)
			(island_removal_mode 0)
		)
		(polygon
			(pts
				(arc
					(start 238.451898 -85.322918)
					(mid 238.541701 -85.360115)
					(end 238.578898 -85.449918)
				)
				(arc
					(start 238.578898 -85.653118)
					(mid 238.541701 -85.742921)
					(end 238.451898 -85.780118)
				)
				(arc
					(start 238.197898 -85.780118)
					(mid 238.108095 -85.742921)
					(end 238.070898 -85.653118)
				)
				(arc
					(start 238.070898 -85.449918)
					(mid 238.108095 -85.360115)
					(end 238.197898 -85.322918)
				)
			)
		)
	)
	(zone
		(layer "In1.Cu")
		(hatch none 0.5)
		(connect_pads
			(clearance 0)
		)
		(min_thickness 0.25)
		(keepout
			(tracks not_allowed)
			(vias allowed)
			(pads allowed)
			(copperpour not_allowed)
			(footprints allowed)
		)
		(placement
			(enabled no)
			(sheetname "")
		)
		(fill
			(thermal_gap 0.5)
			(thermal_bridge_width 0.5)
			(island_removal_mode 0)
		)
		(polygon
			(pts
				(arc
					(start 70.533768 -355.825806)
					(mid 70.497847 -355.840685)
					(end 70.482968 -355.876606)
				)
				(arc
					(start 70.482968 -356.613206)
					(mid 70.497847 -356.649127)
					(end 70.533768 -356.664006)
				)
				(xy 70.777608 -356.664006) (xy 71.131938 -356.431596) (xy 71.487538 -356.664006)
				(arc
					(start 71.730108 -356.664006)
					(mid 71.766029 -356.649127)
					(end 71.780908 -356.613206)
				)
				(arc
					(start 71.780908 -355.876606)
					(mid 71.766029 -355.840685)
					(end 71.730108 -355.825806)
				)
				(xy 71.487538 -355.825806) (xy 71.130668 -356.058216) (xy 70.776338 -355.825806)
			)
		)
	)
	(zone
		(layer "In1.Cu")
		(hatch none 0.5)
		(connect_pads
			(clearance 0)
		)
		(min_thickness 0.25)
		(keepout
			(tracks not_allowed)
			(vias allowed)
			(pads allowed)
			(copperpour not_allowed)
			(footprints allowed)
		)
		(placement
			(enabled no)
			(sheetname "")
		)
		(fill
			(thermal_gap 0.5)
			(thermal_bridge_width 0.5)
			(island_removal_mode 0)
		)
		(polygon
			(pts
				(arc
					(start 184.147714 -147.951952)
					(mid 184.162593 -147.916031)
					(end 184.198514 -147.901152)
				)
				(arc
					(start 185.379614 -147.901152)
					(mid 185.415535 -147.916031)
					(end 185.430414 -147.951952)
				)
				(arc
					(start 185.430414 -148.9583)
					(mid 185.415535 -148.994221)
					(end 185.379614 -149.0091)
				)
				(arc
					(start 184.198514 -149.0091)
					(mid 184.162593 -148.994221)
					(end 184.147714 -148.9583)
				)
			)
		)
	)
	(zone
		(layer "In1.Cu")
		(hatch none 0.5)
		(connect_pads
			(clearance 0)
		)
		(min_thickness 0.25)
		(keepout
			(tracks not_allowed)
			(vias allowed)
			(pads allowed)
			(copperpour not_allowed)
			(footprints allowed)
		)
		(placement
			(enabled no)
			(sheetname "")
		)
		(fill
			(thermal_gap 0.5)
			(thermal_bridge_width 0.5)
			(island_removal_mode 0)
		)
		(polygon
			(pts
				(arc
					(start 300.247812 -131.64185)
					(mid 300.262691 -131.605929)
					(end 300.298612 -131.59105)
				)
				(arc
					(start 301.479712 -131.59105)
					(mid 301.515633 -131.605929)
					(end 301.530512 -131.64185)
				)
				(arc
					(start 301.530512 -132.648198)
					(mid 301.515633 -132.684119)
					(end 301.479712 -132.698998)
				)
				(arc
					(start 300.298612 -132.698998)
					(mid 300.262691 -132.684119)
					(end 300.247812 -132.648198)
				)
			)
		)
	)
	(zone
		(layer "In1.Cu")
		(hatch none 0.5)
		(connect_pads
			(clearance 0)
		)
		(min_thickness 0.25)
		(keepout
			(tracks not_allowed)
			(vias allowed)
			(pads allowed)
			(copperpour not_allowed)
			(footprints allowed)
		)
		(placement
			(enabled no)
			(sheetname "")
		)
		(fill
			(thermal_gap 0.5)
			(thermal_bridge_width 0.5)
			(island_removal_mode 0)
		)
		(polygon
			(pts
				(arc
					(start 54.531514 -361.95381)
					(mid 54.621317 -361.991007)
					(end 54.658514 -362.08081)
				)
				(arc
					(start 54.658514 -362.281978)
					(mid 54.621317 -362.371781)
					(end 54.531514 -362.408978)
				)
				(arc
					(start 54.277514 -362.408978)
					(mid 54.187711 -362.371781)
					(end 54.150514 -362.281978)
				)
				(arc
					(start 54.150514 -362.08081)
					(mid 54.187711 -361.991007)
					(end 54.277514 -361.95381)
				)
			)
		)
	)
	(zone
		(layer "In1.Cu")
		(hatch none 0.5)
		(connect_pads
			(clearance 0)
		)
		(min_thickness 0.25)
		(keepout
			(tracks not_allowed)
			(vias allowed)
			(pads allowed)
			(copperpour not_allowed)
			(footprints allowed)
		)
		(placement
			(enabled no)
			(sheetname "")
		)
		(fill
			(thermal_gap 0.5)
			(thermal_bridge_width 0.5)
			(island_removal_mode 0)
		)
		(polygon
			(pts
				(arc
					(start 364.199932 -32.805878)
					(mid 364.185053 -32.841799)
					(end 364.149132 -32.856678)
				)
				(arc
					(start 362.917232 -32.856678)
					(mid 362.881311 -32.841799)
					(end 362.866432 -32.805878)
				)
				(arc
					(start 362.866432 -31.77413)
					(mid 362.881311 -31.738209)
					(end 362.917232 -31.72333)
				)
				(arc
					(start 364.149132 -31.72333)
					(mid 364.185053 -31.738209)
					(end 364.199932 -31.77413)
				)
			)
		)
	)
	(zone
		(layer "In1.Cu")
		(hatch none 0.5)
		(connect_pads
			(clearance 0)
		)
		(min_thickness 0.25)
		(keepout
			(tracks not_allowed)
			(vias allowed)
			(pads allowed)
			(copperpour not_allowed)
			(footprints allowed)
		)
		(placement
			(enabled no)
			(sheetname "")
		)
		(fill
			(thermal_gap 0.5)
			(thermal_bridge_width 0.5)
			(island_removal_mode 0)
		)
		(polygon
			(pts
				(arc
					(start 133.473444 -32.879538)
					(mid 133.488323 -32.915459)
					(end 133.524244 -32.930338)
				)
				(arc
					(start 134.260844 -32.930338)
					(mid 134.296765 -32.915459)
					(end 134.311644 -32.879538)
				)
				(xy 134.311644 -32.635698) (xy 134.079234 -32.281368) (xy 134.311644 -31.925768)
				(arc
					(start 134.311644 -31.683198)
					(mid 134.296765 -31.647277)
					(end 134.260844 -31.632398)
				)
				(arc
					(start 133.524244 -31.632398)
					(mid 133.488323 -31.647277)
					(end 133.473444 -31.683198)
				)
				(xy 133.473444 -31.925768) (xy 133.705854 -32.282638) (xy 133.473444 -32.636968)
			)
		)
	)
	(zone
		(layer "In1.Cu")
		(hatch none 0.5)
		(connect_pads
			(clearance 0)
		)
		(min_thickness 0.25)
		(keepout
			(tracks not_allowed)
			(vias allowed)
			(pads allowed)
			(copperpour not_allowed)
			(footprints allowed)
		)
		(placement
			(enabled no)
			(sheetname "")
		)
		(fill
			(thermal_gap 0.5)
			(thermal_bridge_width 0.5)
			(island_removal_mode 0)
		)
		(polygon
			(pts
				(arc
					(start 268.229842 -33.574228)
					(mid 268.244721 -33.538307)
					(end 268.280642 -33.523428)
				)
				(arc
					(start 269.512542 -33.523428)
					(mid 269.548463 -33.538307)
					(end 269.563342 -33.574228)
				)
				(arc
					(start 269.563342 -34.605976)
					(mid 269.548463 -34.641897)
					(end 269.512542 -34.656776)
				)
				(arc
					(start 268.280642 -34.656776)
					(mid 268.244721 -34.641897)
					(end 268.229842 -34.605976)
				)
			)
		)
	)
	(zone
		(layer "In1.Cu")
		(hatch none 0.5)
		(connect_pads
			(clearance 0)
		)
		(min_thickness 0.25)
		(keepout
			(tracks not_allowed)
			(vias allowed)
			(pads allowed)
			(copperpour not_allowed)
			(footprints allowed)
		)
		(placement
			(enabled no)
			(sheetname "")
		)
		(fill
			(thermal_gap 0.5)
			(thermal_bridge_width 0.5)
			(island_removal_mode 0)
		)
		(polygon
			(pts
				(arc
					(start 82.242406 -152.651206)
					(mid 82.257285 -152.687127)
					(end 82.293206 -152.702006)
				)
				(arc
					(start 83.029806 -152.702006)
					(mid 83.065727 -152.687127)
					(end 83.080606 -152.651206)
				)
				(xy 83.080606 -152.407366) (xy 82.848196 -152.053036) (xy 83.080606 -151.697436)
				(arc
					(start 83.080606 -151.454866)
					(mid 83.065727 -151.418945)
					(end 83.029806 -151.404066)
				)
				(arc
					(start 82.293206 -151.404066)
					(mid 82.257285 -151.418945)
					(end 82.242406 -151.454866)
				)
				(xy 82.242406 -151.697436) (xy 82.474816 -152.054306) (xy 82.242406 -152.408636)
			)
		)
	)
	(zone
		(layer "In1.Cu")
		(hatch none 0.5)
		(connect_pads
			(clearance 0)
		)
		(min_thickness 0.25)
		(keepout
			(tracks not_allowed)
			(vias allowed)
			(pads allowed)
			(copperpour not_allowed)
			(footprints allowed)
		)
		(placement
			(enabled no)
			(sheetname "")
		)
		(fill
			(thermal_gap 0.5)
			(thermal_bridge_width 0.5)
			(island_removal_mode 0)
		)
		(polygon
			(pts
				(arc
					(start 424.674538 -343.533222)
					(mid 424.638617 -343.548101)
					(end 424.623738 -343.584022)
				)
				(arc
					(start 424.623738 -344.320622)
					(mid 424.638617 -344.356543)
					(end 424.674538 -344.371422)
				)
				(xy 424.918378 -344.371422) (xy 425.272708 -344.139012) (xy 425.628308 -344.371422)
				(arc
					(start 425.870878 -344.371422)
					(mid 425.906799 -344.356543)
					(end 425.921678 -344.320622)
				)
				(arc
					(start 425.921678 -343.584022)
					(mid 425.906799 -343.548101)
					(end 425.870878 -343.533222)
				)
				(xy 425.628308 -343.533222) (xy 425.271438 -343.765632) (xy 424.917108 -343.533222)
			)
		)
	)
	(zone
		(layer "In1.Cu")
		(hatch none 0.5)
		(connect_pads
			(clearance 0)
		)
		(min_thickness 0.25)
		(keepout
			(tracks not_allowed)
			(vias allowed)
			(pads allowed)
			(copperpour not_allowed)
			(footprints allowed)
		)
		(placement
			(enabled no)
			(sheetname "")
		)
		(fill
			(thermal_gap 0.5)
			(thermal_bridge_width 0.5)
			(island_removal_mode 0)
		)
		(polygon
			(pts
				(arc
					(start 68.04787 -135.241792)
					(mid 68.062749 -135.205871)
					(end 68.09867 -135.190992)
				)
				(arc
					(start 69.27977 -135.190992)
					(mid 69.315691 -135.205871)
					(end 69.33057 -135.241792)
				)
				(arc
					(start 69.33057 -136.24814)
					(mid 69.315691 -136.284061)
					(end 69.27977 -136.29894)
				)
				(arc
					(start 68.09867 -136.29894)
					(mid 68.062749 -136.284061)
					(end 68.04787 -136.24814)
				)
			)
		)
	)
	(zone
		(layer "In1.Cu")
		(hatch none 0.5)
		(connect_pads
			(clearance 0)
		)
		(min_thickness 0.25)
		(keepout
			(tracks not_allowed)
			(vias allowed)
			(pads allowed)
			(copperpour not_allowed)
			(footprints allowed)
		)
		(placement
			(enabled no)
			(sheetname "")
		)
		(fill
			(thermal_gap 0.5)
			(thermal_bridge_width 0.5)
			(island_removal_mode 0)
		)
		(polygon
			(pts
				(arc
					(start 238.197898 -84.980018)
					(mid 238.108095 -84.942821)
					(end 238.070898 -84.853018)
				)
				(arc
					(start 238.070898 -84.649818)
					(mid 238.108095 -84.560015)
					(end 238.197898 -84.522818)
				)
				(arc
					(start 238.451898 -84.522818)
					(mid 238.541701 -84.560015)
					(end 238.578898 -84.649818)
				)
				(arc
					(start 238.578898 -84.853018)
					(mid 238.541701 -84.942821)
					(end 238.451898 -84.980018)
				)
			)
		)
	)
	(zone
		(layer "In1.Cu")
		(hatch none 0.5)
		(connect_pads
			(clearance 0)
		)
		(min_thickness 0.25)
		(keepout
			(tracks not_allowed)
			(vias allowed)
			(pads allowed)
			(copperpour not_allowed)
			(footprints allowed)
		)
		(placement
			(enabled no)
			(sheetname "")
		)
		(fill
			(thermal_gap 0.5)
			(thermal_bridge_width 0.5)
			(island_removal_mode 0)
		)
		(polygon
			(pts
				(arc
					(start 343.42705 -343.533222)
					(mid 343.391129 -343.548101)
					(end 343.37625 -343.584022)
				)
				(arc
					(start 343.37625 -344.320622)
					(mid 343.391129 -344.356543)
					(end 343.42705 -344.371422)
				)
				(xy 343.67089 -344.371422) (xy 344.02522 -344.139012) (xy 344.38082 -344.371422)
				(arc
					(start 344.62339 -344.371422)
					(mid 344.659311 -344.356543)
					(end 344.67419 -344.320622)
				)
				(arc
					(start 344.67419 -343.584022)
					(mid 344.659311 -343.548101)
					(end 344.62339 -343.533222)
				)
				(xy 344.38082 -343.533222) (xy 344.02395 -343.765632) (xy 343.66962 -343.533222)
			)
		)
	)
	(zone
		(layer "In1.Cu")
		(hatch none 0.5)
		(connect_pads
			(clearance 0)
		)
		(min_thickness 0.25)
		(keepout
			(tracks not_allowed)
			(vias allowed)
			(pads allowed)
			(copperpour not_allowed)
			(footprints allowed)
		)
		(placement
			(enabled no)
			(sheetname "")
		)
		(fill
			(thermal_gap 0.5)
			(thermal_bridge_width 0.5)
			(island_removal_mode 0)
		)
		(polygon
			(pts
				(arc
					(start 320.229738 -33.574228)
					(mid 320.244617 -33.538307)
					(end 320.280538 -33.523428)
				)
				(arc
					(start 321.512438 -33.523428)
					(mid 321.548359 -33.538307)
					(end 321.563238 -33.574228)
				)
				(arc
					(start 321.563238 -34.605976)
					(mid 321.548359 -34.641897)
					(end 321.512438 -34.656776)
				)
				(arc
					(start 320.280538 -34.656776)
					(mid 320.244617 -34.641897)
					(end 320.229738 -34.605976)
				)
			)
		)
	)
	(zone
		(layer "In1.Cu")
		(hatch none 0.5)
		(connect_pads
			(clearance 0)
		)
		(min_thickness 0.25)
		(keepout
			(tracks not_allowed)
			(vias allowed)
			(pads allowed)
			(copperpour not_allowed)
			(footprints allowed)
		)
		(placement
			(enabled no)
			(sheetname "")
		)
		(fill
			(thermal_gap 0.5)
			(thermal_bridge_width 0.5)
			(island_removal_mode 0)
		)
		(polygon
			(pts
				(arc
					(start 416.34791 -144.351756)
					(mid 416.362789 -144.315835)
					(end 416.39871 -144.300956)
				)
				(arc
					(start 417.57981 -144.300956)
					(mid 417.615731 -144.315835)
					(end 417.63061 -144.351756)
				)
				(arc
					(start 417.63061 -145.358104)
					(mid 417.615731 -145.394025)
					(end 417.57981 -145.408904)
				)
				(arc
					(start 416.39871 -145.408904)
					(mid 416.362789 -145.394025)
					(end 416.34791 -145.358104)
				)
			)
		)
	)
	(zone
		(layer "In1.Cu")
		(hatch none 0.5)
		(connect_pads
			(clearance 0)
		)
		(min_thickness 0.25)
		(keepout
			(tracks not_allowed)
			(vias allowed)
			(pads allowed)
			(copperpour not_allowed)
			(footprints allowed)
		)
		(placement
			(enabled no)
			(sheetname "")
		)
		(fill
			(thermal_gap 0.5)
			(thermal_bridge_width 0.5)
			(island_removal_mode 0)
		)
		(polygon
			(pts
				(arc
					(start 68.04787 -118.631716)
					(mid 68.062749 -118.595795)
					(end 68.09867 -118.580916)
				)
				(arc
					(start 69.27977 -118.580916)
					(mid 69.315691 -118.595795)
					(end 69.33057 -118.631716)
				)
				(arc
					(start 69.33057 -119.638064)
					(mid 69.315691 -119.673985)
					(end 69.27977 -119.688864)
				)
				(arc
					(start 68.09867 -119.688864)
					(mid 68.062749 -119.673985)
					(end 68.04787 -119.638064)
				)
			)
		)
	)
	(zone
		(layer "In1.Cu")
		(hatch none 0.5)
		(connect_pads
			(clearance 0)
		)
		(min_thickness 0.25)
		(keepout
			(tracks not_allowed)
			(vias allowed)
			(pads allowed)
			(copperpour not_allowed)
			(footprints allowed)
		)
		(placement
			(enabled no)
			(sheetname "")
		)
		(fill
			(thermal_gap 0.5)
			(thermal_bridge_width 0.5)
			(island_removal_mode 0)
		)
		(polygon
			(pts
				(arc
					(start 45.432726 -108.241846)
					(mid 45.447605 -108.205925)
					(end 45.483526 -108.191046)
				)
				(arc
					(start 46.664626 -108.191046)
					(mid 46.700547 -108.205925)
					(end 46.715426 -108.241846)
				)
				(arc
					(start 46.715426 -109.248194)
					(mid 46.700547 -109.284115)
					(end 46.664626 -109.298994)
				)
				(arc
					(start 45.483526 -109.298994)
					(mid 45.447605 -109.284115)
					(end 45.432726 -109.248194)
				)
			)
		)
	)
	(zone
		(layer "In1.Cu")
		(hatch none 0.5)
		(connect_pads
			(clearance 0)
		)
		(min_thickness 0.25)
		(keepout
			(tracks not_allowed)
			(vias allowed)
			(pads allowed)
			(copperpour not_allowed)
			(footprints allowed)
		)
		(placement
			(enabled no)
			(sheetname "")
		)
		(fill
			(thermal_gap 0.5)
			(thermal_bridge_width 0.5)
			(island_removal_mode 0)
		)
		(polygon
			(pts
				(arc
					(start 275.573236 -29.279596)
					(mid 275.588115 -29.315517)
					(end 275.624036 -29.330396)
				)
				(arc
					(start 276.360636 -29.330396)
					(mid 276.396557 -29.315517)
					(end 276.411436 -29.279596)
				)
				(xy 276.411436 -29.035756) (xy 276.179026 -28.681426) (xy 276.411436 -28.325826)
				(arc
					(start 276.411436 -28.083256)
					(mid 276.396557 -28.047335)
					(end 276.360636 -28.032456)
				)
				(arc
					(start 275.624036 -28.032456)
					(mid 275.588115 -28.047335)
					(end 275.573236 -28.083256)
				)
				(xy 275.573236 -28.325826) (xy 275.805646 -28.682696) (xy 275.573236 -29.037026)
			)
		)
	)
	(zone
		(layer "In1.Cu")
		(hatch none 0.5)
		(connect_pads
			(clearance 0)
		)
		(min_thickness 0.25)
		(keepout
			(tracks not_allowed)
			(vias allowed)
			(pads allowed)
			(copperpour not_allowed)
			(footprints allowed)
		)
		(placement
			(enabled no)
			(sheetname "")
		)
		(fill
			(thermal_gap 0.5)
			(thermal_bridge_width 0.5)
			(island_removal_mode 0)
		)
		(polygon
			(pts
				(arc
					(start 422.167304 -148.9583)
					(mid 422.152425 -148.994221)
					(end 422.116504 -149.0091)
				)
				(arc
					(start 420.935404 -149.0091)
					(mid 420.899483 -148.994221)
					(end 420.884604 -148.9583)
				)
				(arc
					(start 420.884604 -147.951952)
					(mid 420.899483 -147.916031)
					(end 420.935404 -147.901152)
				)
				(arc
					(start 422.116504 -147.901152)
					(mid 422.152425 -147.916031)
					(end 422.167304 -147.951952)
				)
			)
		)
	)
	(zone
		(layer "In1.Cu")
		(hatch none 0.5)
		(connect_pads
			(clearance 0)
		)
		(min_thickness 0.25)
		(keepout
			(tracks not_allowed)
			(vias allowed)
			(pads allowed)
			(copperpour not_allowed)
			(footprints allowed)
		)
		(placement
			(enabled no)
			(sheetname "")
		)
		(fill
			(thermal_gap 0.5)
			(thermal_bridge_width 0.5)
			(island_removal_mode 0)
		)
		(polygon
			(pts
				(arc
					(start 300.247812 -133.441948)
					(mid 300.262691 -133.406027)
					(end 300.298612 -133.391148)
				)
				(arc
					(start 301.479712 -133.391148)
					(mid 301.515633 -133.406027)
					(end 301.530512 -133.441948)
				)
				(arc
					(start 301.530512 -134.448296)
					(mid 301.515633 -134.484217)
					(end 301.479712 -134.499096)
				)
				(arc
					(start 300.298612 -134.499096)
					(mid 300.262691 -134.484217)
					(end 300.247812 -134.448296)
				)
			)
		)
	)
	(zone
		(layer "In1.Cu")
		(hatch none 0.5)
		(connect_pads
			(clearance 0)
		)
		(min_thickness 0.25)
		(keepout
			(tracks not_allowed)
			(vias allowed)
			(pads allowed)
			(copperpour not_allowed)
			(footprints allowed)
		)
		(placement
			(enabled no)
			(sheetname "")
		)
		(fill
			(thermal_gap 0.5)
			(thermal_bridge_width 0.5)
			(island_removal_mode 0)
		)
		(polygon
			(pts
				(arc
					(start 298.821348 -355.825806)
					(mid 298.785427 -355.840685)
					(end 298.770548 -355.876606)
				)
				(arc
					(start 298.770548 -356.613206)
					(mid 298.785427 -356.649127)
					(end 298.821348 -356.664006)
				)
				(xy 299.065188 -356.664006) (xy 299.419518 -356.431596) (xy 299.775118 -356.664006)
				(arc
					(start 300.017688 -356.664006)
					(mid 300.053609 -356.649127)
					(end 300.068488 -356.613206)
				)
				(arc
					(start 300.068488 -355.876606)
					(mid 300.053609 -355.840685)
					(end 300.017688 -355.825806)
				)
				(xy 299.775118 -355.825806) (xy 299.418248 -356.058216) (xy 299.063918 -355.825806)
			)
		)
	)
	(zone
		(layer "In1.Cu")
		(hatch none 0.5)
		(connect_pads
			(clearance 0)
		)
		(min_thickness 0.25)
		(keepout
			(tracks not_allowed)
			(vias allowed)
			(pads allowed)
			(copperpour not_allowed)
			(footprints allowed)
		)
		(placement
			(enabled no)
			(sheetname "")
		)
		(fill
			(thermal_gap 0.5)
			(thermal_bridge_width 0.5)
			(island_removal_mode 0)
		)
		(polygon
			(pts
				(arc
					(start 233.998008 -81.890108)
					(mid 234.087811 -81.927305)
					(end 234.125008 -82.017108)
				)
				(arc
					(start 234.125008 -82.220308)
					(mid 234.087811 -82.310111)
					(end 233.998008 -82.347308)
				)
				(arc
					(start 233.744008 -82.347308)
					(mid 233.654205 -82.310111)
					(end 233.617008 -82.220308)
				)
				(arc
					(start 233.617008 -82.017108)
					(mid 233.654205 -81.927305)
					(end 233.744008 -81.890108)
				)
			)
		)
	)
	(zone
		(layer "In1.Cu")
		(hatch none 0.5)
		(connect_pads
			(clearance 0)
		)
		(min_thickness 0.25)
		(keepout
			(tracks not_allowed)
			(vias allowed)
			(pads allowed)
			(copperpour not_allowed)
			(footprints allowed)
		)
		(placement
			(enabled no)
			(sheetname "")
		)
		(fill
			(thermal_gap 0.5)
			(thermal_bridge_width 0.5)
			(island_removal_mode 0)
		)
		(polygon
			(pts
				(arc
					(start 321.66433 -355.825806)
					(mid 321.628409 -355.840685)
					(end 321.61353 -355.876606)
				)
				(arc
					(start 321.61353 -356.613206)
					(mid 321.628409 -356.649127)
					(end 321.66433 -356.664006)
				)
				(xy 321.90817 -356.664006) (xy 322.2625 -356.431596) (xy 322.6181 -356.664006)
				(arc
					(start 322.86067 -356.664006)
					(mid 322.896591 -356.649127)
					(end 322.91147 -356.613206)
				)
				(arc
					(start 322.91147 -355.876606)
					(mid 322.896591 -355.840685)
					(end 322.86067 -355.825806)
				)
				(xy 322.6181 -355.825806) (xy 322.26123 -356.058216) (xy 321.9069 -355.825806)
			)
		)
	)
	(zone
		(layer "In1.Cu")
		(hatch none 0.5)
		(connect_pads
			(clearance 0)
		)
		(min_thickness 0.25)
		(keepout
			(tracks not_allowed)
			(vias allowed)
			(pads allowed)
			(copperpour not_allowed)
			(footprints allowed)
		)
		(placement
			(enabled no)
			(sheetname "")
		)
		(fill
			(thermal_gap 0.5)
			(thermal_bridge_width 0.5)
			(island_removal_mode 0)
		)
		(polygon
			(pts
				(arc
					(start 399.55216 -134.968488)
					(mid 399.537281 -135.004409)
					(end 399.50136 -135.019288)
				)
				(arc
					(start 398.32026 -135.019288)
					(mid 398.284339 -135.004409)
					(end 398.26946 -134.968488)
				)
				(arc
					(start 398.26946 -133.96214)
					(mid 398.284339 -133.926219)
					(end 398.32026 -133.91134)
				)
				(arc
					(start 399.50136 -133.91134)
					(mid 399.537281 -133.926219)
					(end 399.55216 -133.96214)
				)
			)
		)
	)
	(zone
		(layer "In1.Cu")
		(hatch none 0.5)
		(connect_pads
			(clearance 0)
		)
		(min_thickness 0.25)
		(keepout
			(tracks not_allowed)
			(vias allowed)
			(pads allowed)
			(copperpour not_allowed)
			(footprints allowed)
		)
		(placement
			(enabled no)
			(sheetname "")
		)
		(fill
			(thermal_gap 0.5)
			(thermal_bridge_width 0.5)
			(island_removal_mode 0)
		)
		(polygon
			(pts
				(arc
					(start 387.161532 -125.659896)
					(mid 387.176411 -125.695817)
					(end 387.212332 -125.710696)
				)
				(arc
					(start 387.948932 -125.710696)
					(mid 387.984853 -125.695817)
					(end 387.999732 -125.659896)
				)
				(xy 387.999732 -125.416056) (xy 387.767322 -125.061726) (xy 387.999732 -124.706126)
				(arc
					(start 387.999732 -124.463556)
					(mid 387.984853 -124.427635)
					(end 387.948932 -124.412756)
				)
				(arc
					(start 387.212332 -124.412756)
					(mid 387.176411 -124.427635)
					(end 387.161532 -124.463556)
				)
				(xy 387.161532 -124.706126) (xy 387.393942 -125.062996) (xy 387.161532 -125.417326)
			)
		)
	)
	(zone
		(layer "In1.Cu")
		(hatch none 0.5)
		(connect_pads
			(clearance 0)
		)
		(min_thickness 0.25)
		(keepout
			(tracks not_allowed)
			(vias allowed)
			(pads allowed)
			(copperpour not_allowed)
			(footprints allowed)
		)
		(placement
			(enabled no)
			(sheetname "")
		)
		(fill
			(thermal_gap 0.5)
			(thermal_bridge_width 0.5)
			(island_removal_mode 0)
		)
		(polygon
			(pts
				(arc
					(start 130.350514 -349.679514)
					(mid 130.314593 -349.694393)
					(end 130.299714 -349.730314)
				)
				(arc
					(start 130.299714 -350.466914)
					(mid 130.314593 -350.502835)
					(end 130.350514 -350.517714)
				)
				(xy 130.594354 -350.517714) (xy 130.948684 -350.285304) (xy 131.304284 -350.517714)
				(arc
					(start 131.546854 -350.517714)
					(mid 131.582775 -350.502835)
					(end 131.597654 -350.466914)
				)
				(arc
					(start 131.597654 -349.730314)
					(mid 131.582775 -349.694393)
					(end 131.546854 -349.679514)
				)
				(xy 131.304284 -349.679514) (xy 130.947414 -349.911924) (xy 130.593084 -349.679514)
			)
		)
	)
	(zone
		(layer "In1.Cu")
		(hatch none 0.5)
		(connect_pads
			(clearance 0)
		)
		(min_thickness 0.25)
		(keepout
			(tracks not_allowed)
			(vias allowed)
			(pads allowed)
			(copperpour not_allowed)
			(footprints allowed)
		)
		(placement
			(enabled no)
			(sheetname "")
		)
		(fill
			(thermal_gap 0.5)
			(thermal_bridge_width 0.5)
			(island_removal_mode 0)
		)
		(polygon
			(pts
				(arc
					(start 277.632668 -122.752104)
					(mid 277.647547 -122.716183)
					(end 277.683468 -122.701304)
				)
				(arc
					(start 278.864568 -122.701304)
					(mid 278.900489 -122.716183)
					(end 278.915368 -122.752104)
				)
				(arc
					(start 278.915368 -123.758452)
					(mid 278.900489 -123.794373)
					(end 278.864568 -123.809252)
				)
				(arc
					(start 277.683468 -123.809252)
					(mid 277.647547 -123.794373)
					(end 277.632668 -123.758452)
				)
			)
		)
	)
	(zone
		(layer "In1.Cu")
		(hatch none 0.5)
		(connect_pads
			(clearance 0)
		)
		(min_thickness 0.25)
		(keepout
			(tracks not_allowed)
			(vias allowed)
			(pads allowed)
			(copperpour not_allowed)
			(footprints allowed)
		)
		(placement
			(enabled no)
			(sheetname "")
		)
		(fill
			(thermal_gap 0.5)
			(thermal_bridge_width 0.5)
			(island_removal_mode 0)
		)
		(polygon
			(pts
				(arc
					(start 447.555874 -209.594958)
					(mid 447.540995 -209.630879)
					(end 447.505074 -209.645758)
				)
				(arc
					(start 447.09842 -209.645758)
					(mid 447.062499 -209.630879)
					(end 447.04762 -209.594958)
				)
				(arc
					(start 447.04762 -209.192622)
					(mid 447.062499 -209.156701)
					(end 447.09842 -209.141822)
				)
				(arc
					(start 447.505074 -209.141822)
					(mid 447.540995 -209.156701)
					(end 447.555874 -209.192622)
				)
			)
		)
	)
	(zone
		(layer "In1.Cu")
		(hatch none 0.5)
		(connect_pads
			(clearance 0)
		)
		(min_thickness 0.25)
		(keepout
			(tracks not_allowed)
			(vias allowed)
			(pads allowed)
			(copperpour not_allowed)
			(footprints allowed)
		)
		(placement
			(enabled no)
			(sheetname "")
		)
		(fill
			(thermal_gap 0.5)
			(thermal_bridge_width 0.5)
			(island_removal_mode 0)
		)
		(polygon
			(pts
				(arc
					(start 311.80024 -154.4447)
					(mid 311.815119 -154.480621)
					(end 311.85104 -154.4955)
				)
				(arc
					(start 312.58764 -154.4955)
					(mid 312.623561 -154.480621)
					(end 312.63844 -154.4447)
				)
				(xy 312.63844 -154.20086) (xy 312.40603 -153.84653) (xy 312.63844 -153.49093)
				(arc
					(start 312.63844 -153.24836)
					(mid 312.623561 -153.212439)
					(end 312.58764 -153.19756)
				)
				(arc
					(start 311.85104 -153.19756)
					(mid 311.815119 -153.212439)
					(end 311.80024 -153.24836)
				)
				(xy 311.80024 -153.49093) (xy 312.03265 -153.8478) (xy 311.80024 -154.20213)
			)
		)
	)
	(zone
		(layer "In1.Cu")
		(hatch none 0.5)
		(connect_pads
			(clearance 0)
		)
		(min_thickness 0.25)
		(keepout
			(tracks not_allowed)
			(vias allowed)
			(pads allowed)
			(copperpour not_allowed)
			(footprints allowed)
		)
		(placement
			(enabled no)
			(sheetname "")
		)
		(fill
			(thermal_gap 0.5)
			(thermal_bridge_width 0.5)
			(island_removal_mode 0)
		)
		(polygon
			(pts
				(arc
					(start 277.632668 -135.761984)
					(mid 277.647547 -135.726063)
					(end 277.683468 -135.711184)
				)
				(arc
					(start 278.864568 -135.711184)
					(mid 278.900489 -135.726063)
					(end 278.915368 -135.761984)
				)
				(arc
					(start 278.915368 -136.768332)
					(mid 278.900489 -136.804253)
					(end 278.864568 -136.819132)
				)
				(arc
					(start 277.683468 -136.819132)
					(mid 277.647547 -136.804253)
					(end 277.632668 -136.768332)
				)
			)
		)
	)
	(zone
		(layer "In1.Cu")
		(hatch none 0.5)
		(connect_pads
			(clearance 0)
		)
		(min_thickness 0.25)
		(keepout
			(tracks not_allowed)
			(vias allowed)
			(pads allowed)
			(copperpour not_allowed)
			(footprints allowed)
		)
		(placement
			(enabled no)
			(sheetname "")
		)
		(fill
			(thermal_gap 0.5)
			(thermal_bridge_width 0.5)
			(island_removal_mode 0)
		)
		(polygon
			(pts
				(arc
					(start 306.067206 -125.038104)
					(mid 306.052327 -125.074025)
					(end 306.016406 -125.088904)
				)
				(arc
					(start 304.835306 -125.088904)
					(mid 304.799385 -125.074025)
					(end 304.784506 -125.038104)
				)
				(arc
					(start 304.784506 -124.031756)
					(mid 304.799385 -123.995835)
					(end 304.835306 -123.980956)
				)
				(arc
					(start 306.016406 -123.980956)
					(mid 306.052327 -123.995835)
					(end 306.067206 -124.031756)
				)
			)
		)
	)
	(zone
		(layer "In1.Cu")
		(hatch none 0.5)
		(connect_pads
			(clearance 0)
		)
		(min_thickness 0.25)
		(keepout
			(tracks not_allowed)
			(vias allowed)
			(pads allowed)
			(copperpour not_allowed)
			(footprints allowed)
		)
		(placement
			(enabled no)
			(sheetname "")
		)
		(fill
			(thermal_gap 0.5)
			(thermal_bridge_width 0.5)
			(island_removal_mode 0)
		)
		(polygon
			(pts
				(arc
					(start 368.315494 -31.086044)
					(mid 368.330373 -31.121965)
					(end 368.366294 -31.136844)
				)
				(arc
					(start 369.102894 -31.136844)
					(mid 369.138815 -31.121965)
					(end 369.153694 -31.086044)
				)
				(xy 369.153694 -30.842204) (xy 368.921284 -30.487874) (xy 369.153694 -30.132274)
				(arc
					(start 369.153694 -29.889704)
					(mid 369.138815 -29.853783)
					(end 369.102894 -29.838904)
				)
				(arc
					(start 368.366294 -29.838904)
					(mid 368.330373 -29.853783)
					(end 368.315494 -29.889704)
				)
				(xy 368.315494 -30.132274) (xy 368.547904 -30.489144) (xy 368.315494 -30.843474)
			)
		)
	)
	(zone
		(layer "In1.Cu")
		(hatch none 0.5)
		(connect_pads
			(clearance 0)
		)
		(min_thickness 0.25)
		(keepout
			(tracks not_allowed)
			(vias allowed)
			(pads allowed)
			(copperpour not_allowed)
			(footprints allowed)
		)
		(placement
			(enabled no)
			(sheetname "")
		)
		(fill
			(thermal_gap 0.5)
			(thermal_bridge_width 0.5)
			(island_removal_mode 0)
		)
		(polygon
			(pts
				(arc
					(start 165.129718 -349.679514)
					(mid 165.093797 -349.694393)
					(end 165.078918 -349.730314)
				)
				(arc
					(start 165.078918 -350.466914)
					(mid 165.093797 -350.502835)
					(end 165.129718 -350.517714)
				)
				(xy 165.373558 -350.517714) (xy 165.727888 -350.285304) (xy 166.083488 -350.517714)
				(arc
					(start 166.326058 -350.517714)
					(mid 166.361979 -350.502835)
					(end 166.376858 -350.466914)
				)
				(arc
					(start 166.376858 -349.730314)
					(mid 166.361979 -349.694393)
					(end 166.326058 -349.679514)
				)
				(xy 166.083488 -349.679514) (xy 165.726618 -349.911924) (xy 165.372288 -349.679514)
			)
		)
	)
	(zone
		(layer "In1.Cu")
		(hatch none 0.5)
		(connect_pads
			(clearance 0)
		)
		(min_thickness 0.25)
		(keepout
			(tracks not_allowed)
			(vias allowed)
			(pads allowed)
			(copperpour not_allowed)
			(footprints allowed)
		)
		(placement
			(enabled no)
			(sheetname "")
		)
		(fill
			(thermal_gap 0.5)
			(thermal_bridge_width 0.5)
			(island_removal_mode 0)
		)
		(polygon
			(pts
				(arc
					(start 184.147714 -133.441948)
					(mid 184.162593 -133.406027)
					(end 184.198514 -133.391148)
				)
				(arc
					(start 185.379614 -133.391148)
					(mid 185.415535 -133.406027)
					(end 185.430414 -133.441948)
				)
				(arc
					(start 185.430414 -134.448296)
					(mid 185.415535 -134.484217)
					(end 185.379614 -134.499096)
				)
				(arc
					(start 184.198514 -134.499096)
					(mid 184.162593 -134.484217)
					(end 184.147714 -134.448296)
				)
			)
		)
	)
	(zone
		(layer "In1.Cu")
		(hatch none 0.5)
		(connect_pads
			(clearance 0)
		)
		(min_thickness 0.25)
		(keepout
			(tracks not_allowed)
			(vias allowed)
			(pads allowed)
			(copperpour not_allowed)
			(footprints allowed)
		)
		(placement
			(enabled no)
			(sheetname "")
		)
		(fill
			(thermal_gap 0.5)
			(thermal_bridge_width 0.5)
			(island_removal_mode 0)
		)
		(polygon
			(pts
				(arc
					(start 184.147714 -122.231912)
					(mid 184.162593 -122.195991)
					(end 184.198514 -122.181112)
				)
				(arc
					(start 185.379614 -122.181112)
					(mid 185.415535 -122.195991)
					(end 185.430414 -122.231912)
				)
				(arc
					(start 185.430414 -123.23826)
					(mid 185.415535 -123.274181)
					(end 185.379614 -123.28906)
				)
				(arc
					(start 184.198514 -123.28906)
					(mid 184.162593 -123.274181)
					(end 184.147714 -123.23826)
				)
			)
		)
	)
	(zone
		(layer "In1.Cu")
		(hatch none 0.5)
		(connect_pads
			(clearance 0)
		)
		(min_thickness 0.25)
		(keepout
			(tracks not_allowed)
			(vias allowed)
			(pads allowed)
			(copperpour not_allowed)
			(footprints allowed)
		)
		(placement
			(enabled no)
			(sheetname "")
		)
		(fill
			(thermal_gap 0.5)
			(thermal_bridge_width 0.5)
			(island_removal_mode 0)
		)
		(polygon
			(pts
				(arc
					(start 230.862632 -86.95436)
					(mid 230.898553 -86.969239)
					(end 230.913432 -87.00516)
				)
				(arc
					(start 230.913432 -87.411814)
					(mid 230.898553 -87.447735)
					(end 230.862632 -87.462614)
				)
				(arc
					(start 230.460296 -87.462614)
					(mid 230.424375 -87.447735)
					(end 230.409496 -87.411814)
				)
				(arc
					(start 230.409496 -87.00516)
					(mid 230.424375 -86.969239)
					(end 230.460296 -86.95436)
				)
			)
		)
	)
	(zone
		(layer "In1.Cu")
		(hatch none 0.5)
		(connect_pads
			(clearance 0)
		)
		(min_thickness 0.25)
		(keepout
			(tracks not_allowed)
			(vias allowed)
			(pads allowed)
			(copperpour not_allowed)
			(footprints allowed)
		)
		(placement
			(enabled no)
			(sheetname "")
		)
		(fill
			(thermal_gap 0.5)
			(thermal_bridge_width 0.5)
			(island_removal_mode 0)
		)
		(polygon
			(pts
				(arc
					(start 183.999886 -27.405838)
					(mid 183.985007 -27.441759)
					(end 183.949086 -27.456638)
				)
				(arc
					(start 182.717186 -27.456638)
					(mid 182.681265 -27.441759)
					(end 182.666386 -27.405838)
				)
				(arc
					(start 182.666386 -26.37409)
					(mid 182.681265 -26.338169)
					(end 182.717186 -26.32329)
				)
				(arc
					(start 183.949086 -26.32329)
					(mid 183.985007 -26.338169)
					(end 183.999886 -26.37409)
				)
			)
		)
	)
	(zone
		(layer "In1.Cu")
		(hatch none 0.5)
		(connect_pads
			(clearance 0)
		)
		(min_thickness 0.25)
		(keepout
			(tracks not_allowed)
			(vias allowed)
			(pads allowed)
			(copperpour not_allowed)
			(footprints allowed)
		)
		(placement
			(enabled no)
			(sheetname "")
		)
		(fill
			(thermal_gap 0.5)
			(thermal_bridge_width 0.5)
			(island_removal_mode 0)
		)
		(polygon
			(pts
				(arc
					(start 386.567426 -343.533222)
					(mid 386.531505 -343.548101)
					(end 386.516626 -343.584022)
				)
				(arc
					(start 386.516626 -344.320622)
					(mid 386.531505 -344.356543)
					(end 386.567426 -344.371422)
				)
				(xy 386.811266 -344.371422) (xy 387.165596 -344.139012) (xy 387.521196 -344.371422)
				(arc
					(start 387.763766 -344.371422)
					(mid 387.799687 -344.356543)
					(end 387.814566 -344.320622)
				)
				(arc
					(start 387.814566 -343.584022)
					(mid 387.799687 -343.548101)
					(end 387.763766 -343.533222)
				)
				(xy 387.521196 -343.533222) (xy 387.164326 -343.765632) (xy 386.809996 -343.533222)
			)
		)
	)
	(zone
		(layer "In1.Cu")
		(hatch none 0.5)
		(connect_pads
			(clearance 0)
		)
		(min_thickness 0.25)
		(keepout
			(tracks not_allowed)
			(vias allowed)
			(pads allowed)
			(copperpour not_allowed)
			(footprints allowed)
		)
		(placement
			(enabled no)
			(sheetname "")
		)
		(fill
			(thermal_gap 0.5)
			(thermal_bridge_width 0.5)
			(island_removal_mode 0)
		)
		(polygon
			(pts
				(arc
					(start 416.34791 -151.551894)
					(mid 416.362789 -151.515973)
					(end 416.39871 -151.501094)
				)
				(arc
					(start 417.57981 -151.501094)
					(mid 417.615731 -151.515973)
					(end 417.63061 -151.551894)
				)
				(arc
					(start 417.63061 -152.558242)
					(mid 417.615731 -152.594163)
					(end 417.57981 -152.609042)
				)
				(arc
					(start 416.39871 -152.609042)
					(mid 416.362789 -152.594163)
					(end 416.34791 -152.558242)
				)
			)
		)
	)
	(zone
		(layer "In1.Cu")
		(hatch none 0.5)
		(connect_pads
			(clearance 0)
		)
		(min_thickness 0.25)
		(keepout
			(tracks not_allowed)
			(vias allowed)
			(pads allowed)
			(copperpour not_allowed)
			(footprints allowed)
		)
		(placement
			(enabled no)
			(sheetname "")
		)
		(fill
			(thermal_gap 0.5)
			(thermal_bridge_width 0.5)
			(island_removal_mode 0)
		)
		(polygon
			(pts
				(arc
					(start 154.961336 -133.269736)
					(mid 154.976215 -133.305657)
					(end 155.012136 -133.320536)
				)
				(arc
					(start 155.748736 -133.320536)
					(mid 155.784657 -133.305657)
					(end 155.799536 -133.269736)
				)
				(xy 155.799536 -133.025896) (xy 155.567126 -132.671566) (xy 155.799536 -132.315966)
				(arc
					(start 155.799536 -132.073396)
					(mid 155.784657 -132.037475)
					(end 155.748736 -132.022596)
				)
				(arc
					(start 155.012136 -132.022596)
					(mid 154.976215 -132.037475)
					(end 154.961336 -132.073396)
				)
				(xy 154.961336 -132.315966) (xy 155.193746 -132.672836) (xy 154.961336 -133.027166)
			)
		)
	)
	(zone
		(layer "In1.Cu")
		(hatch none 0.5)
		(connect_pads
			(clearance 0)
		)
		(min_thickness 0.25)
		(keepout
			(tracks not_allowed)
			(vias allowed)
			(pads allowed)
			(copperpour not_allowed)
			(footprints allowed)
		)
		(placement
			(enabled no)
			(sheetname "")
		)
		(fill
			(thermal_gap 0.5)
			(thermal_bridge_width 0.5)
			(island_removal_mode 0)
		)
		(polygon
			(pts
				(arc
					(start 399.55216 -136.768332)
					(mid 399.537281 -136.804253)
					(end 399.50136 -136.819132)
				)
				(arc
					(start 398.32026 -136.819132)
					(mid 398.284339 -136.804253)
					(end 398.26946 -136.768332)
				)
				(arc
					(start 398.26946 -135.761984)
					(mid 398.284339 -135.726063)
					(end 398.32026 -135.711184)
				)
				(arc
					(start 399.50136 -135.711184)
					(mid 399.537281 -135.726063)
					(end 399.55216 -135.761984)
				)
			)
		)
	)
	(zone
		(layer "In1.Cu")
		(hatch none 0.5)
		(connect_pads
			(clearance 0)
		)
		(min_thickness 0.25)
		(keepout
			(tracks not_allowed)
			(vias allowed)
			(pads allowed)
			(copperpour not_allowed)
			(footprints allowed)
		)
		(placement
			(enabled no)
			(sheetname "")
		)
		(fill
			(thermal_gap 0.5)
			(thermal_bridge_width 0.5)
			(island_removal_mode 0)
		)
		(polygon
			(pts
				(arc
					(start 95.37319 -29.279596)
					(mid 95.388069 -29.315517)
					(end 95.42399 -29.330396)
				)
				(arc
					(start 96.16059 -29.330396)
					(mid 96.196511 -29.315517)
					(end 96.21139 -29.279596)
				)
				(xy 96.21139 -29.035756) (xy 95.97898 -28.681426) (xy 96.21139 -28.325826)
				(arc
					(start 96.21139 -28.083256)
					(mid 96.196511 -28.047335)
					(end 96.16059 -28.032456)
				)
				(arc
					(start 95.42399 -28.032456)
					(mid 95.388069 -28.047335)
					(end 95.37319 -28.083256)
				)
				(xy 95.37319 -28.325826) (xy 95.6056 -28.682696) (xy 95.37319 -29.037026)
			)
		)
	)
	(zone
		(layer "In1.Cu")
		(hatch none 0.5)
		(connect_pads
			(clearance 0)
		)
		(min_thickness 0.25)
		(keepout
			(tracks not_allowed)
			(vias allowed)
			(pads allowed)
			(copperpour not_allowed)
			(footprints allowed)
		)
		(placement
			(enabled no)
			(sheetname "")
		)
		(fill
			(thermal_gap 0.5)
			(thermal_bridge_width 0.5)
			(island_removal_mode 0)
		)
		(polygon
			(pts
				(arc
					(start 240.51006 -228.370384)
					(mid 240.524939 -228.334463)
					(end 240.56086 -228.319584)
				)
				(arc
					(start 240.967514 -228.319584)
					(mid 241.003435 -228.334463)
					(end 241.018314 -228.370384)
				)
				(arc
					(start 241.018314 -228.77272)
					(mid 241.003435 -228.808641)
					(end 240.967514 -228.82352)
				)
				(arc
					(start 240.56086 -228.82352)
					(mid 240.524939 -228.808641)
					(end 240.51006 -228.77272)
				)
			)
		)
	)
	(zone
		(layer "In1.Cu")
		(hatch none 0.5)
		(connect_pads
			(clearance 0)
		)
		(min_thickness 0.25)
		(keepout
			(tracks not_allowed)
			(vias allowed)
			(pads allowed)
			(copperpour not_allowed)
			(footprints allowed)
		)
		(placement
			(enabled no)
			(sheetname "")
		)
		(fill
			(thermal_gap 0.5)
			(thermal_bridge_width 0.5)
			(island_removal_mode 0)
		)
		(polygon
			(pts
				(arc
					(start 300.247812 -118.631716)
					(mid 300.262691 -118.595795)
					(end 300.298612 -118.580916)
				)
				(arc
					(start 301.479712 -118.580916)
					(mid 301.515633 -118.595795)
					(end 301.530512 -118.631716)
				)
				(arc
					(start 301.530512 -119.638064)
					(mid 301.515633 -119.673985)
					(end 301.479712 -119.688864)
				)
				(arc
					(start 300.298612 -119.688864)
					(mid 300.262691 -119.673985)
					(end 300.247812 -119.638064)
				)
			)
		)
	)
	(zone
		(layer "In1.Cu")
		(hatch none 0.5)
		(connect_pads
			(clearance 0)
		)
		(min_thickness 0.25)
		(keepout
			(tracks not_allowed)
			(vias allowed)
			(pads allowed)
			(copperpour not_allowed)
			(footprints allowed)
		)
		(placement
			(enabled no)
			(sheetname "")
		)
		(fill
			(thermal_gap 0.5)
			(thermal_bridge_width 0.5)
			(island_removal_mode 0)
		)
		(polygon
			(pts
				(arc
					(start 133.473444 -29.279596)
					(mid 133.488323 -29.315517)
					(end 133.524244 -29.330396)
				)
				(arc
					(start 134.260844 -29.330396)
					(mid 134.296765 -29.315517)
					(end 134.311644 -29.279596)
				)
				(xy 134.311644 -29.035756) (xy 134.079234 -28.681426) (xy 134.311644 -28.325826)
				(arc
					(start 134.311644 -28.083256)
					(mid 134.296765 -28.047335)
					(end 134.260844 -28.032456)
				)
				(arc
					(start 133.524244 -28.032456)
					(mid 133.488323 -28.047335)
					(end 133.473444 -28.083256)
				)
				(xy 133.473444 -28.325826) (xy 133.705854 -28.682696) (xy 133.473444 -29.037026)
			)
		)
	)
	(zone
		(layer "In1.Cu")
		(hatch none 0.5)
		(connect_pads
			(clearance 0)
		)
		(min_thickness 0.25)
		(keepout
			(tracks not_allowed)
			(vias allowed)
			(pads allowed)
			(copperpour not_allowed)
			(footprints allowed)
		)
		(placement
			(enabled no)
			(sheetname "")
		)
		(fill
			(thermal_gap 0.5)
			(thermal_bridge_width 0.5)
			(island_removal_mode 0)
		)
		(polygon
			(pts
				(arc
					(start 51.25212 -134.968488)
					(mid 51.237241 -135.004409)
					(end 51.20132 -135.019288)
				)
				(arc
					(start 50.02022 -135.019288)
					(mid 49.984299 -135.004409)
					(end 49.96942 -134.968488)
				)
				(arc
					(start 49.96942 -133.96214)
					(mid 49.984299 -133.926219)
					(end 50.02022 -133.91134)
				)
				(arc
					(start 51.20132 -133.91134)
					(mid 51.237241 -133.926219)
					(end 51.25212 -133.96214)
				)
			)
		)
	)
	(zone
		(layer "In1.Cu")
		(hatch none 0.5)
		(connect_pads
			(clearance 0)
		)
		(min_thickness 0.25)
		(keepout
			(tracks not_allowed)
			(vias allowed)
			(pads allowed)
			(copperpour not_allowed)
			(footprints allowed)
		)
		(placement
			(enabled no)
			(sheetname "")
		)
		(fill
			(thermal_gap 0.5)
			(thermal_bridge_width 0.5)
			(island_removal_mode 0)
		)
		(polygon
			(pts
				(arc
					(start 238.096298 -85.424518)
					(mid 238.133495 -85.334715)
					(end 238.223298 -85.297518)
				)
				(arc
					(start 238.426498 -85.297518)
					(mid 238.516301 -85.334715)
					(end 238.553498 -85.424518)
				)
				(arc
					(start 238.553498 -85.678518)
					(mid 238.516301 -85.768321)
					(end 238.426498 -85.805518)
				)
				(arc
					(start 238.223298 -85.805518)
					(mid 238.133495 -85.768321)
					(end 238.096298 -85.678518)
				)
			)
		)
	)
	(zone
		(layer "In1.Cu")
		(hatch none 0.5)
		(connect_pads
			(clearance 0)
		)
		(min_thickness 0.25)
		(keepout
			(tracks not_allowed)
			(vias allowed)
			(pads allowed)
			(copperpour not_allowed)
			(footprints allowed)
		)
		(placement
			(enabled no)
			(sheetname "")
		)
		(fill
			(thermal_gap 0.5)
			(thermal_bridge_width 0.5)
			(island_removal_mode 0)
		)
		(polygon
			(pts
				(arc
					(start 139.677394 -355.825806)
					(mid 139.641473 -355.840685)
					(end 139.626594 -355.876606)
				)
				(arc
					(start 139.626594 -356.613206)
					(mid 139.641473 -356.649127)
					(end 139.677394 -356.664006)
				)
				(xy 139.921234 -356.664006) (xy 140.275564 -356.431596) (xy 140.631164 -356.664006)
				(arc
					(start 140.873734 -356.664006)
					(mid 140.909655 -356.649127)
					(end 140.924534 -356.613206)
				)
				(arc
					(start 140.924534 -355.876606)
					(mid 140.909655 -355.840685)
					(end 140.873734 -355.825806)
				)
				(xy 140.631164 -355.825806) (xy 140.274294 -356.058216) (xy 139.919964 -355.825806)
			)
		)
	)
	(zone
		(layer "In1.Cu")
		(hatch none 0.5)
		(connect_pads
			(clearance 0)
		)
		(min_thickness 0.25)
		(keepout
			(tracks not_allowed)
			(vias allowed)
			(pads allowed)
			(copperpour not_allowed)
			(footprints allowed)
		)
		(placement
			(enabled no)
			(sheetname "")
		)
		(fill
			(thermal_gap 0.5)
			(thermal_bridge_width 0.5)
			(island_removal_mode 0)
		)
		(polygon
			(pts
				(arc
					(start 68.04787 -147.951952)
					(mid 68.062749 -147.916031)
					(end 68.09867 -147.901152)
				)
				(arc
					(start 69.27977 -147.901152)
					(mid 69.315691 -147.916031)
					(end 69.33057 -147.951952)
				)
				(arc
					(start 69.33057 -148.9583)
					(mid 69.315691 -148.994221)
					(end 69.27977 -149.0091)
				)
				(arc
					(start 68.09867 -149.0091)
					(mid 68.062749 -148.994221)
					(end 68.04787 -148.9583)
				)
			)
		)
	)
	(zone
		(layer "In1.Cu")
		(hatch none 0.5)
		(connect_pads
			(clearance 0)
		)
		(min_thickness 0.25)
		(keepout
			(tracks not_allowed)
			(vias allowed)
			(pads allowed)
			(copperpour not_allowed)
			(footprints allowed)
		)
		(placement
			(enabled no)
			(sheetname "")
		)
		(fill
			(thermal_gap 0.5)
			(thermal_bridge_width 0.5)
			(island_removal_mode 0)
		)
		(polygon
			(pts
				(arc
					(start 416.34791 -129.841752)
					(mid 416.362789 -129.805831)
					(end 416.39871 -129.790952)
				)
				(arc
					(start 417.57981 -129.790952)
					(mid 417.615731 -129.805831)
					(end 417.63061 -129.841752)
				)
				(arc
					(start 417.63061 -130.8481)
					(mid 417.615731 -130.884021)
					(end 417.57981 -130.8989)
				)
				(arc
					(start 416.39871 -130.8989)
					(mid 416.362789 -130.884021)
					(end 416.34791 -130.8481)
				)
			)
		)
	)
	(zone
		(layer "In1.Cu")
		(hatch none 0.5)
		(connect_pads
			(clearance 0)
		)
		(min_thickness 0.25)
		(keepout
			(tracks not_allowed)
			(vias allowed)
			(pads allowed)
			(copperpour not_allowed)
			(footprints allowed)
		)
		(placement
			(enabled no)
			(sheetname "")
		)
		(fill
			(thermal_gap 0.5)
			(thermal_bridge_width 0.5)
			(island_removal_mode 0)
		)
		(polygon
			(pts
				(arc
					(start 82.242406 -136.341104)
					(mid 82.257285 -136.377025)
					(end 82.293206 -136.391904)
				)
				(arc
					(start 83.029806 -136.391904)
					(mid 83.065727 -136.377025)
					(end 83.080606 -136.341104)
				)
				(xy 83.080606 -136.097264) (xy 82.848196 -135.742934) (xy 83.080606 -135.387334)
				(arc
					(start 83.080606 -135.144764)
					(mid 83.065727 -135.108843)
					(end 83.029806 -135.093964)
				)
				(arc
					(start 82.293206 -135.093964)
					(mid 82.257285 -135.108843)
					(end 82.242406 -135.144764)
				)
				(xy 82.242406 -135.387334) (xy 82.474816 -135.744204) (xy 82.242406 -136.098534)
			)
		)
	)
	(zone
		(layer "In1.Cu")
		(hatch none 0.5)
		(connect_pads
			(clearance 0)
		)
		(min_thickness 0.25)
		(keepout
			(tracks not_allowed)
			(vias allowed)
			(pads allowed)
			(copperpour not_allowed)
			(footprints allowed)
		)
		(placement
			(enabled no)
			(sheetname "")
		)
		(fill
			(thermal_gap 0.5)
			(thermal_bridge_width 0.5)
			(island_removal_mode 0)
		)
		(polygon
			(pts
				(arc
					(start 329.21956 7.568184)
					(mid 329.197242 7.514302)
					(end 329.14336 7.491984)
				)
				(arc
					(start 328.53122 7.491984)
					(mid 328.477338 7.514302)
					(end 328.45502 7.568184)
				)
				(arc
					(start 328.45502 8.665464)
					(mid 328.477338 8.719346)
					(end 328.53122 8.741664)
				)
				(arc
					(start 329.14336 8.741664)
					(mid 329.197242 8.719346)
					(end 329.21956 8.665464)
				)
			)
		)
	)
	(zone
		(layer "In1.Cu")
		(hatch none 0.5)
		(connect_pads
			(clearance 0)
		)
		(min_thickness 0.25)
		(keepout
			(tracks not_allowed)
			(vias allowed)
			(pads allowed)
			(copperpour not_allowed)
			(footprints allowed)
		)
		(placement
			(enabled no)
			(sheetname "")
		)
		(fill
			(thermal_gap 0.5)
			(thermal_bridge_width 0.5)
			(island_removal_mode 0)
		)
		(polygon
			(pts
				(arc
					(start 10.029952 -31.77413)
					(mid 10.044831 -31.738209)
					(end 10.080752 -31.72333)
				)
				(arc
					(start 11.312652 -31.72333)
					(mid 11.348573 -31.738209)
					(end 11.363452 -31.77413)
				)
				(arc
					(start 11.363452 -32.805878)
					(mid 11.348573 -32.841799)
					(end 11.312652 -32.856678)
				)
				(arc
					(start 10.080752 -32.856678)
					(mid 10.044831 -32.841799)
					(end 10.029952 -32.805878)
				)
			)
		)
	)
	(zone
		(layer "In1.Cu")
		(hatch none 0.5)
		(connect_pads
			(clearance 0)
		)
		(min_thickness 0.25)
		(keepout
			(tracks not_allowed)
			(vias allowed)
			(pads allowed)
			(copperpour not_allowed)
			(footprints allowed)
		)
		(placement
			(enabled no)
			(sheetname "")
		)
		(fill
			(thermal_gap 0.5)
			(thermal_bridge_width 0.5)
			(island_removal_mode 0)
		)
		(polygon
			(pts
				(arc
					(start 136.115552 -31.086044)
					(mid 136.130431 -31.121965)
					(end 136.166352 -31.136844)
				)
				(arc
					(start 136.902952 -31.136844)
					(mid 136.938873 -31.121965)
					(end 136.953752 -31.086044)
				)
				(xy 136.953752 -30.842204) (xy 136.721342 -30.487874) (xy 136.953752 -30.132274)
				(arc
					(start 136.953752 -29.889704)
					(mid 136.938873 -29.853783)
					(end 136.902952 -29.838904)
				)
				(arc
					(start 136.166352 -29.838904)
					(mid 136.130431 -29.853783)
					(end 136.115552 -29.889704)
				)
				(xy 136.115552 -30.132274) (xy 136.347962 -30.489144) (xy 136.115552 -30.843474)
			)
		)
	)
	(zone
		(layer "In1.Cu")
		(hatch none 0.5)
		(connect_pads
			(clearance 0)
		)
		(min_thickness 0.25)
		(keepout
			(tracks not_allowed)
			(vias allowed)
			(pads allowed)
			(copperpour not_allowed)
			(footprints allowed)
		)
		(placement
			(enabled no)
			(sheetname "")
		)
		(fill
			(thermal_gap 0.5)
			(thermal_bridge_width 0.5)
			(island_removal_mode 0)
		)
		(polygon
			(pts
				(arc
					(start 377.240546 -349.679514)
					(mid 377.204625 -349.694393)
					(end 377.189746 -349.730314)
				)
				(arc
					(start 377.189746 -350.466914)
					(mid 377.204625 -350.502835)
					(end 377.240546 -350.517714)
				)
				(xy 377.484386 -350.517714) (xy 377.838716 -350.285304) (xy 378.194316 -350.517714)
				(arc
					(start 378.436886 -350.517714)
					(mid 378.472807 -350.502835)
					(end 378.487686 -350.466914)
				)
				(arc
					(start 378.487686 -349.730314)
					(mid 378.472807 -349.694393)
					(end 378.436886 -349.679514)
				)
				(xy 378.194316 -349.679514) (xy 377.837446 -349.911924) (xy 377.483116 -349.679514)
			)
		)
	)
	(zone
		(layer "In1.Cu")
		(hatch none 0.5)
		(connect_pads
			(clearance 0)
		)
		(min_thickness 0.25)
		(keepout
			(tracks not_allowed)
			(vias allowed)
			(pads allowed)
			(copperpour not_allowed)
			(footprints allowed)
		)
		(placement
			(enabled no)
			(sheetname "")
		)
		(fill
			(thermal_gap 0.5)
			(thermal_bridge_width 0.5)
			(island_removal_mode 0)
		)
		(polygon
			(pts
				(arc
					(start 195.700142 -119.724678)
					(mid 195.715021 -119.760599)
					(end 195.750942 -119.775478)
				)
				(arc
					(start 196.487542 -119.775478)
					(mid 196.523463 -119.760599)
					(end 196.538342 -119.724678)
				)
				(xy 196.538342 -119.480838) (xy 196.305932 -119.126508) (xy 196.538342 -118.770908)
				(arc
					(start 196.538342 -118.528338)
					(mid 196.523463 -118.492417)
					(end 196.487542 -118.477538)
				)
				(arc
					(start 195.750942 -118.477538)
					(mid 195.715021 -118.492417)
					(end 195.700142 -118.528338)
				)
				(xy 195.700142 -118.770908) (xy 195.932552 -119.127778) (xy 195.700142 -119.482108)
			)
		)
	)
	(zone
		(layer "In1.Cu")
		(hatch none 0.5)
		(connect_pads
			(clearance 0)
		)
		(min_thickness 0.25)
		(keepout
			(tracks not_allowed)
			(vias allowed)
			(pads allowed)
			(copperpour not_allowed)
			(footprints allowed)
		)
		(placement
			(enabled no)
			(sheetname "")
		)
		(fill
			(thermal_gap 0.5)
			(thermal_bridge_width 0.5)
			(island_removal_mode 0)
		)
		(polygon
			(pts
				(arc
					(start 47.147734 -355.825806)
					(mid 47.111813 -355.840685)
					(end 47.096934 -355.876606)
				)
				(arc
					(start 47.096934 -356.613206)
					(mid 47.111813 -356.649127)
					(end 47.147734 -356.664006)
				)
				(xy 47.391574 -356.664006) (xy 47.745904 -356.431596) (xy 48.101504 -356.664006)
				(arc
					(start 48.344074 -356.664006)
					(mid 48.379995 -356.649127)
					(end 48.394874 -356.613206)
				)
				(arc
					(start 48.394874 -355.876606)
					(mid 48.379995 -355.840685)
					(end 48.344074 -355.825806)
				)
				(xy 48.101504 -355.825806) (xy 47.744634 -356.058216) (xy 47.390304 -355.825806)
			)
		)
	)
	(zone
		(layer "In1.Cu")
		(hatch none 0.5)
		(connect_pads
			(clearance 0)
		)
		(min_thickness 0.25)
		(keepout
			(tracks not_allowed)
			(vias allowed)
			(pads allowed)
			(copperpour not_allowed)
			(footprints allowed)
		)
		(placement
			(enabled no)
			(sheetname "")
		)
		(fill
			(thermal_gap 0.5)
			(thermal_bridge_width 0.5)
			(island_removal_mode 0)
		)
		(polygon
			(pts
				(arc
					(start 68.04787 -131.64185)
					(mid 68.062749 -131.605929)
					(end 68.09867 -131.59105)
				)
				(arc
					(start 69.27977 -131.59105)
					(mid 69.315691 -131.605929)
					(end 69.33057 -131.64185)
				)
				(arc
					(start 69.33057 -132.648198)
					(mid 69.315691 -132.684119)
					(end 69.27977 -132.698998)
				)
				(arc
					(start 68.09867 -132.698998)
					(mid 68.062749 -132.684119)
					(end 68.04787 -132.648198)
				)
			)
		)
	)
	(zone
		(layer "In1.Cu")
		(hatch none 0.5)
		(connect_pads
			(clearance 0)
		)
		(min_thickness 0.25)
		(keepout
			(tracks not_allowed)
			(vias allowed)
			(pads allowed)
			(copperpour not_allowed)
			(footprints allowed)
		)
		(placement
			(enabled no)
			(sheetname "")
		)
		(fill
			(thermal_gap 0.5)
			(thermal_bridge_width 0.5)
			(island_removal_mode 0)
		)
		(polygon
			(pts
				(arc
					(start 238.096298 -83.824318)
					(mid 238.133495 -83.734515)
					(end 238.223298 -83.697318)
				)
				(arc
					(start 238.426498 -83.697318)
					(mid 238.516301 -83.734515)
					(end 238.553498 -83.824318)
				)
				(arc
					(start 238.553498 -84.078318)
					(mid 238.516301 -84.168121)
					(end 238.426498 -84.205318)
				)
				(arc
					(start 238.223298 -84.205318)
					(mid 238.133495 -84.168121)
					(end 238.096298 -84.078318)
				)
			)
		)
	)
	(zone
		(layer "In1.Cu")
		(hatch none 0.5)
		(connect_pads
			(clearance 0)
		)
		(min_thickness 0.25)
		(keepout
			(tracks not_allowed)
			(vias allowed)
			(pads allowed)
			(copperpour not_allowed)
			(footprints allowed)
		)
		(placement
			(enabled no)
			(sheetname "")
		)
		(fill
			(thermal_gap 0.5)
			(thermal_bridge_width 0.5)
			(island_removal_mode 0)
		)
		(polygon
			(pts
				(arc
					(start 306.067206 -121.438162)
					(mid 306.052327 -121.474083)
					(end 306.016406 -121.488962)
				)
				(arc
					(start 304.835306 -121.488962)
					(mid 304.799385 -121.474083)
					(end 304.784506 -121.438162)
				)
				(arc
					(start 304.784506 -120.431814)
					(mid 304.799385 -120.395893)
					(end 304.835306 -120.381014)
				)
				(arc
					(start 306.016406 -120.381014)
					(mid 306.052327 -120.395893)
					(end 306.067206 -120.431814)
				)
			)
		)
	)
	(zone
		(layer "In1.Cu")
		(hatch none 0.5)
		(connect_pads
			(clearance 0)
		)
		(min_thickness 0.25)
		(keepout
			(tracks not_allowed)
			(vias allowed)
			(pads allowed)
			(copperpour not_allowed)
			(footprints allowed)
		)
		(placement
			(enabled no)
			(sheetname "")
		)
		(fill
			(thermal_gap 0.5)
			(thermal_bridge_width 0.5)
			(island_removal_mode 0)
		)
		(polygon
			(pts
				(arc
					(start 161.53257 -122.752104)
					(mid 161.547449 -122.716183)
					(end 161.58337 -122.701304)
				)
				(arc
					(start 162.76447 -122.701304)
					(mid 162.800391 -122.716183)
					(end 162.81527 -122.752104)
				)
				(arc
					(start 162.81527 -123.758452)
					(mid 162.800391 -123.794373)
					(end 162.76447 -123.809252)
				)
				(arc
					(start 161.58337 -123.809252)
					(mid 161.547449 -123.794373)
					(end 161.53257 -123.758452)
				)
			)
		)
	)
	(zone
		(layer "In1.Cu")
		(hatch none 0.5)
		(connect_pads
			(clearance 0)
		)
		(min_thickness 0.25)
		(keepout
			(tracks not_allowed)
			(vias allowed)
			(pads allowed)
			(copperpour not_allowed)
			(footprints allowed)
		)
		(placement
			(enabled no)
			(sheetname "")
		)
		(fill
			(thermal_gap 0.5)
			(thermal_bridge_width 0.5)
			(island_removal_mode 0)
		)
		(polygon
			(pts
				(arc
					(start 430.892458 -343.533222)
					(mid 430.856537 -343.548101)
					(end 430.841658 -343.584022)
				)
				(arc
					(start 430.841658 -344.320622)
					(mid 430.856537 -344.356543)
					(end 430.892458 -344.371422)
				)
				(xy 431.136298 -344.371422) (xy 431.490628 -344.139012) (xy 431.846228 -344.371422)
				(arc
					(start 432.088798 -344.371422)
					(mid 432.124719 -344.356543)
					(end 432.139598 -344.320622)
				)
				(arc
					(start 432.139598 -343.584022)
					(mid 432.124719 -343.548101)
					(end 432.088798 -343.533222)
				)
				(xy 431.846228 -343.533222) (xy 431.489358 -343.765632) (xy 431.135028 -343.533222)
			)
		)
	)
	(zone
		(layer "In1.Cu")
		(hatch none 0.5)
		(connect_pads
			(clearance 0)
		)
		(min_thickness 0.25)
		(keepout
			(tracks not_allowed)
			(vias allowed)
			(pads allowed)
			(copperpour not_allowed)
			(footprints allowed)
		)
		(placement
			(enabled no)
			(sheetname "")
		)
		(fill
			(thermal_gap 0.5)
			(thermal_bridge_width 0.5)
			(island_removal_mode 0)
		)
		(polygon
			(pts
				(arc
					(start 256.44856 7.535164)
					(mid 256.426242 7.481282)
					(end 256.37236 7.458964)
				)
				(arc
					(start 255.76022 7.458964)
					(mid 255.706338 7.481282)
					(end 255.68402 7.535164)
				)
				(arc
					(start 255.68402 8.632444)
					(mid 255.706338 8.686326)
					(end 255.76022 8.708644)
				)
				(arc
					(start 256.37236 8.708644)
					(mid 256.426242 8.686326)
					(end 256.44856 8.632444)
				)
			)
		)
	)
	(zone
		(layer "In1.Cu")
		(hatch none 0.5)
		(connect_pads
			(clearance 0)
		)
		(min_thickness 0.25)
		(keepout
			(tracks not_allowed)
			(vias allowed)
			(pads allowed)
			(copperpour not_allowed)
			(footprints allowed)
		)
		(placement
			(enabled no)
			(sheetname "")
		)
		(fill
			(thermal_gap 0.5)
			(thermal_bridge_width 0.5)
			(island_removal_mode 0)
		)
		(polygon
			(pts
				(arc
					(start 198.34225 -125.131068)
					(mid 198.357129 -125.166989)
					(end 198.39305 -125.181868)
				)
				(arc
					(start 199.12965 -125.181868)
					(mid 199.165571 -125.166989)
					(end 199.18045 -125.131068)
				)
				(xy 199.18045 -124.887228) (xy 198.94804 -124.532898) (xy 199.18045 -124.177298)
				(arc
					(start 199.18045 -123.934728)
					(mid 199.165571 -123.898807)
					(end 199.12965 -123.883928)
				)
				(arc
					(start 198.39305 -123.883928)
					(mid 198.357129 -123.898807)
					(end 198.34225 -123.934728)
				)
				(xy 198.34225 -124.177298) (xy 198.57466 -124.534168) (xy 198.34225 -124.888498)
			)
		)
	)
	(zone
		(layer "In1.Cu")
		(hatch none 0.5)
		(connect_pads
			(clearance 0)
		)
		(min_thickness 0.25)
		(keepout
			(tracks not_allowed)
			(vias allowed)
			(pads allowed)
			(copperpour not_allowed)
			(footprints allowed)
		)
		(placement
			(enabled no)
			(sheetname "")
		)
		(fill
			(thermal_gap 0.5)
			(thermal_bridge_width 0.5)
			(island_removal_mode 0)
		)
		(polygon
			(pts
				(arc
					(start 437.110378 -343.533222)
					(mid 437.074457 -343.548101)
					(end 437.059578 -343.584022)
				)
				(arc
					(start 437.059578 -344.320622)
					(mid 437.074457 -344.356543)
					(end 437.110378 -344.371422)
				)
				(xy 437.354218 -344.371422) (xy 437.708548 -344.139012) (xy 438.064148 -344.371422)
				(arc
					(start 438.306718 -344.371422)
					(mid 438.342639 -344.356543)
					(end 438.357518 -344.320622)
				)
				(arc
					(start 438.357518 -343.584022)
					(mid 438.342639 -343.548101)
					(end 438.306718 -343.533222)
				)
				(xy 438.064148 -343.533222) (xy 437.707278 -343.765632) (xy 437.352948 -343.533222)
			)
		)
	)
	(zone
		(layer "In1.Cu")
		(hatch none 0.5)
		(connect_pads
			(clearance 0)
		)
		(min_thickness 0.25)
		(keepout
			(tracks not_allowed)
			(vias allowed)
			(pads allowed)
			(copperpour not_allowed)
			(footprints allowed)
		)
		(placement
			(enabled no)
			(sheetname "")
		)
		(fill
			(thermal_gap 0.5)
			(thermal_bridge_width 0.5)
			(island_removal_mode 0)
		)
		(polygon
			(pts
				(arc
					(start 82.242406 -125.131068)
					(mid 82.257285 -125.166989)
					(end 82.293206 -125.181868)
				)
				(arc
					(start 83.029806 -125.181868)
					(mid 83.065727 -125.166989)
					(end 83.080606 -125.131068)
				)
				(xy 83.080606 -124.887228) (xy 82.848196 -124.532898) (xy 83.080606 -124.177298)
				(arc
					(start 83.080606 -123.934728)
					(mid 83.065727 -123.898807)
					(end 83.029806 -123.883928)
				)
				(arc
					(start 82.293206 -123.883928)
					(mid 82.257285 -123.898807)
					(end 82.242406 -123.934728)
				)
				(xy 82.242406 -124.177298) (xy 82.474816 -124.534168) (xy 82.242406 -124.888498)
			)
		)
	)
	(zone
		(layer "In1.Cu")
		(hatch none 0.5)
		(connect_pads
			(clearance 0)
		)
		(min_thickness 0.25)
		(keepout
			(tracks not_allowed)
			(vias allowed)
			(pads allowed)
			(copperpour not_allowed)
			(footprints allowed)
		)
		(placement
			(enabled no)
			(sheetname "")
		)
		(fill
			(thermal_gap 0.5)
			(thermal_bridge_width 0.5)
			(island_removal_mode 0)
		)
		(polygon
			(pts
				(arc
					(start 161.53257 -102.84206)
					(mid 161.547449 -102.806139)
					(end 161.58337 -102.79126)
				)
				(arc
					(start 162.76447 -102.79126)
					(mid 162.800391 -102.806139)
					(end 162.81527 -102.84206)
				)
				(arc
					(start 162.81527 -103.848408)
					(mid 162.800391 -103.884329)
					(end 162.76447 -103.899208)
				)
				(arc
					(start 161.58337 -103.899208)
					(mid 161.547449 -103.884329)
					(end 161.53257 -103.848408)
				)
			)
		)
	)
	(zone
		(layer "In1.Cu")
		(hatch none 0.5)
		(connect_pads
			(clearance 0)
		)
		(min_thickness 0.25)
		(keepout
			(tracks not_allowed)
			(vias allowed)
			(pads allowed)
			(copperpour not_allowed)
			(footprints allowed)
		)
		(placement
			(enabled no)
			(sheetname "")
		)
		(fill
			(thermal_gap 0.5)
			(thermal_bridge_width 0.5)
			(island_removal_mode 0)
		)
		(polygon
			(pts
				(arc
					(start 44.038774 -355.825806)
					(mid 44.002853 -355.840685)
					(end 43.987974 -355.876606)
				)
				(arc
					(start 43.987974 -356.613206)
					(mid 44.002853 -356.649127)
					(end 44.038774 -356.664006)
				)
				(xy 44.282614 -356.664006) (xy 44.636944 -356.431596) (xy 44.992544 -356.664006)
				(arc
					(start 45.235114 -356.664006)
					(mid 45.271035 -356.649127)
					(end 45.285914 -356.613206)
				)
				(arc
					(start 45.285914 -355.876606)
					(mid 45.271035 -355.840685)
					(end 45.235114 -355.825806)
				)
				(xy 44.992544 -355.825806) (xy 44.635674 -356.058216) (xy 44.281344 -355.825806)
			)
		)
	)
	(zone
		(layer "In1.Cu")
		(hatch none 0.5)
		(connect_pads
			(clearance 0)
		)
		(min_thickness 0.25)
		(keepout
			(tracks not_allowed)
			(vias allowed)
			(pads allowed)
			(copperpour not_allowed)
			(footprints allowed)
		)
		(placement
			(enabled no)
			(sheetname "")
		)
		(fill
			(thermal_gap 0.5)
			(thermal_bridge_width 0.5)
			(island_removal_mode 0)
		)
		(polygon
			(pts
				(arc
					(start 152.129998 -29.974286)
					(mid 152.144877 -29.938365)
					(end 152.180798 -29.923486)
				)
				(arc
					(start 153.412698 -29.923486)
					(mid 153.448619 -29.938365)
					(end 153.463498 -29.974286)
				)
				(arc
					(start 153.463498 -31.006034)
					(mid 153.448619 -31.041955)
					(end 153.412698 -31.056834)
				)
				(arc
					(start 152.180798 -31.056834)
					(mid 152.144877 -31.041955)
					(end 152.129998 -31.006034)
				)
			)
		)
	)
	(zone
		(layer "In1.Cu")
		(hatch none 0.5)
		(connect_pads
			(clearance 0)
		)
		(min_thickness 0.25)
		(keepout
			(tracks not_allowed)
			(vias allowed)
			(pads allowed)
			(copperpour not_allowed)
			(footprints allowed)
		)
		(placement
			(enabled no)
			(sheetname "")
		)
		(fill
			(thermal_gap 0.5)
			(thermal_bridge_width 0.5)
			(island_removal_mode 0)
		)
		(polygon
			(pts
				(arc
					(start 312.33745 -349.679514)
					(mid 312.301529 -349.694393)
					(end 312.28665 -349.730314)
				)
				(arc
					(start 312.28665 -350.466914)
					(mid 312.301529 -350.502835)
					(end 312.33745 -350.517714)
				)
				(xy 312.58129 -350.517714) (xy 312.93562 -350.285304) (xy 313.29122 -350.517714)
				(arc
					(start 313.53379 -350.517714)
					(mid 313.569711 -350.502835)
					(end 313.58459 -350.466914)
				)
				(arc
					(start 313.58459 -349.730314)
					(mid 313.569711 -349.694393)
					(end 313.53379 -349.679514)
				)
				(xy 313.29122 -349.679514) (xy 312.93435 -349.911924) (xy 312.58002 -349.679514)
			)
		)
	)
	(zone
		(layer "In1.Cu")
		(hatch none 0.5)
		(connect_pads
			(clearance 0)
		)
		(min_thickness 0.25)
		(keepout
			(tracks not_allowed)
			(vias allowed)
			(pads allowed)
			(copperpour not_allowed)
			(footprints allowed)
		)
		(placement
			(enabled no)
			(sheetname "")
		)
		(fill
			(thermal_gap 0.5)
			(thermal_bridge_width 0.5)
			(island_removal_mode 0)
		)
		(polygon
			(pts
				(arc
					(start 430.542446 -152.651206)
					(mid 430.557325 -152.687127)
					(end 430.593246 -152.702006)
				)
				(arc
					(start 431.329846 -152.702006)
					(mid 431.365767 -152.687127)
					(end 431.380646 -152.651206)
				)
				(xy 431.380646 -152.407366) (xy 431.148236 -152.053036) (xy 431.380646 -151.697436)
				(arc
					(start 431.380646 -151.454866)
					(mid 431.365767 -151.418945)
					(end 431.329846 -151.404066)
				)
				(arc
					(start 430.593246 -151.404066)
					(mid 430.557325 -151.418945)
					(end 430.542446 -151.454866)
				)
				(xy 430.542446 -151.697436) (xy 430.774856 -152.054306) (xy 430.542446 -152.408636)
			)
		)
	)
	(zone
		(layer "In1.Cu")
		(hatch none 0.5)
		(connect_pads
			(clearance 0)
		)
		(min_thickness 0.25)
		(keepout
			(tracks not_allowed)
			(vias allowed)
			(pads allowed)
			(copperpour not_allowed)
			(footprints allowed)
		)
		(placement
			(enabled no)
			(sheetname "")
		)
		(fill
			(thermal_gap 0.5)
			(thermal_bridge_width 0.5)
			(island_removal_mode 0)
		)
		(polygon
			(pts
				(arc
					(start 73.642728 -343.533222)
					(mid 73.606807 -343.548101)
					(end 73.591928 -343.584022)
				)
				(arc
					(start 73.591928 -344.320622)
					(mid 73.606807 -344.356543)
					(end 73.642728 -344.371422)
				)
				(xy 73.886568 -344.371422) (xy 74.240898 -344.139012) (xy 74.596498 -344.371422)
				(arc
					(start 74.839068 -344.371422)
					(mid 74.874989 -344.356543)
					(end 74.889868 -344.320622)
				)
				(arc
					(start 74.889868 -343.584022)
					(mid 74.874989 -343.548101)
					(end 74.839068 -343.533222)
				)
				(xy 74.596498 -343.533222) (xy 74.239628 -343.765632) (xy 73.885298 -343.533222)
			)
		)
	)
	(zone
		(layer "In1.Cu")
		(hatch none 0.5)
		(connect_pads
			(clearance 0)
		)
		(min_thickness 0.25)
		(keepout
			(tracks not_allowed)
			(vias allowed)
			(pads allowed)
			(copperpour not_allowed)
			(footprints allowed)
		)
		(placement
			(enabled no)
			(sheetname "")
		)
		(fill
			(thermal_gap 0.5)
			(thermal_bridge_width 0.5)
			(island_removal_mode 0)
		)
		(polygon
			(pts
				(arc
					(start 271.061434 -103.94315)
					(mid 271.076313 -103.979071)
					(end 271.112234 -103.99395)
				)
				(arc
					(start 271.848834 -103.99395)
					(mid 271.884755 -103.979071)
					(end 271.899634 -103.94315)
				)
				(xy 271.899634 -103.69931) (xy 271.667224 -103.34498) (xy 271.899634 -102.98938)
				(arc
					(start 271.899634 -102.74681)
					(mid 271.884755 -102.710889)
					(end 271.848834 -102.69601)
				)
				(arc
					(start 271.112234 -102.69601)
					(mid 271.076313 -102.710889)
					(end 271.061434 -102.74681)
				)
				(xy 271.061434 -102.98938) (xy 271.293844 -103.34625) (xy 271.061434 -103.70058)
			)
		)
	)
	(zone
		(layer "In1.Cu")
		(hatch none 0.5)
		(connect_pads
			(clearance 0)
		)
		(min_thickness 0.25)
		(keepout
			(tracks not_allowed)
			(vias allowed)
			(pads allowed)
			(copperpour not_allowed)
			(footprints allowed)
		)
		(placement
			(enabled no)
			(sheetname "")
		)
		(fill
			(thermal_gap 0.5)
			(thermal_bridge_width 0.5)
			(island_removal_mode 0)
		)
		(polygon
			(pts
				(arc
					(start 43.373294 -32.879538)
					(mid 43.388173 -32.915459)
					(end 43.424094 -32.930338)
				)
				(arc
					(start 44.160694 -32.930338)
					(mid 44.196615 -32.915459)
					(end 44.211494 -32.879538)
				)
				(xy 44.211494 -32.635698) (xy 43.979084 -32.281368) (xy 44.211494 -31.925768)
				(arc
					(start 44.211494 -31.683198)
					(mid 44.196615 -31.647277)
					(end 44.160694 -31.632398)
				)
				(arc
					(start 43.424094 -31.632398)
					(mid 43.388173 -31.647277)
					(end 43.373294 -31.683198)
				)
				(xy 43.373294 -31.925768) (xy 43.605704 -32.282638) (xy 43.373294 -32.636968)
			)
		)
	)
	(zone
		(layer "In1.Cu")
		(hatch none 0.5)
		(connect_pads
			(clearance 0)
		)
		(min_thickness 0.25)
		(keepout
			(tracks not_allowed)
			(vias allowed)
			(pads allowed)
			(copperpour not_allowed)
			(footprints allowed)
		)
		(placement
			(enabled no)
			(sheetname "")
		)
		(fill
			(thermal_gap 0.5)
			(thermal_bridge_width 0.5)
			(island_removal_mode 0)
		)
		(polygon
			(pts
				(arc
					(start 171.347638 -343.533222)
					(mid 171.311717 -343.548101)
					(end 171.296838 -343.584022)
				)
				(arc
					(start 171.296838 -344.320622)
					(mid 171.311717 -344.356543)
					(end 171.347638 -344.371422)
				)
				(xy 171.591478 -344.371422) (xy 171.945808 -344.139012) (xy 172.301408 -344.371422)
				(arc
					(start 172.543978 -344.371422)
					(mid 172.579899 -344.356543)
					(end 172.594778 -344.320622)
				)
				(arc
					(start 172.594778 -343.584022)
					(mid 172.579899 -343.548101)
					(end 172.543978 -343.533222)
				)
				(xy 172.301408 -343.533222) (xy 171.944538 -343.765632) (xy 171.590208 -343.533222)
			)
		)
	)
	(zone
		(layer "In1.Cu")
		(hatch none 0.5)
		(connect_pads
			(clearance 0)
		)
		(min_thickness 0.25)
		(keepout
			(tracks not_allowed)
			(vias allowed)
			(pads allowed)
			(copperpour not_allowed)
			(footprints allowed)
		)
		(placement
			(enabled no)
			(sheetname "")
		)
		(fill
			(thermal_gap 0.5)
			(thermal_bridge_width 0.5)
			(island_removal_mode 0)
		)
		(polygon
			(pts
				(arc
					(start 92.296488 -349.679514)
					(mid 92.260567 -349.694393)
					(end 92.245688 -349.730314)
				)
				(arc
					(start 92.245688 -350.466914)
					(mid 92.260567 -350.502835)
					(end 92.296488 -350.517714)
				)
				(xy 92.540328 -350.517714) (xy 92.894658 -350.285304) (xy 93.250258 -350.517714)
				(arc
					(start 93.492828 -350.517714)
					(mid 93.528749 -350.502835)
					(end 93.543628 -350.466914)
				)
				(arc
					(start 93.543628 -349.730314)
					(mid 93.528749 -349.694393)
					(end 93.492828 -349.679514)
				)
				(xy 93.250258 -349.679514) (xy 92.893388 -349.911924) (xy 92.539058 -349.679514)
			)
		)
	)
	(zone
		(layer "In1.Cu")
		(hatch none 0.5)
		(connect_pads
			(clearance 0)
		)
		(min_thickness 0.25)
		(keepout
			(tracks not_allowed)
			(vias allowed)
			(pads allowed)
			(copperpour not_allowed)
			(footprints allowed)
		)
		(placement
			(enabled no)
			(sheetname "")
		)
		(fill
			(thermal_gap 0.5)
			(thermal_bridge_width 0.5)
			(island_removal_mode 0)
		)
		(polygon
			(pts
				(arc
					(start 86.078568 -349.679514)
					(mid 86.042647 -349.694393)
					(end 86.027768 -349.730314)
				)
				(arc
					(start 86.027768 -350.466914)
					(mid 86.042647 -350.502835)
					(end 86.078568 -350.517714)
				)
				(xy 86.322408 -350.517714) (xy 86.676738 -350.285304) (xy 87.032338 -350.517714)
				(arc
					(start 87.274908 -350.517714)
					(mid 87.310829 -350.502835)
					(end 87.325708 -350.466914)
				)
				(arc
					(start 87.325708 -349.730314)
					(mid 87.310829 -349.694393)
					(end 87.274908 -349.679514)
				)
				(xy 87.032338 -349.679514) (xy 86.675468 -349.911924) (xy 86.321138 -349.679514)
			)
		)
	)
	(zone
		(layer "In1.Cu")
		(hatch none 0.5)
		(connect_pads
			(clearance 0)
		)
		(min_thickness 0.25)
		(keepout
			(tracks not_allowed)
			(vias allowed)
			(pads allowed)
			(copperpour not_allowed)
			(footprints allowed)
		)
		(placement
			(enabled no)
			(sheetname "")
		)
		(fill
			(thermal_gap 0.5)
			(thermal_bridge_width 0.5)
			(island_removal_mode 0)
		)
		(polygon
			(pts
				(arc
					(start 416.199828 -27.405838)
					(mid 416.184949 -27.441759)
					(end 416.149028 -27.456638)
				)
				(arc
					(start 414.917128 -27.456638)
					(mid 414.881207 -27.441759)
					(end 414.866328 -27.405838)
				)
				(arc
					(start 414.866328 -26.37409)
					(mid 414.881207 -26.338169)
					(end 414.917128 -26.32329)
				)
				(arc
					(start 416.149028 -26.32329)
					(mid 416.184949 -26.338169)
					(end 416.199828 -26.37409)
				)
			)
		)
	)
	(zone
		(layer "In1.Cu")
		(hatch none 0.5)
		(connect_pads
			(clearance 0)
		)
		(min_thickness 0.25)
		(keepout
			(tracks not_allowed)
			(vias allowed)
			(pads allowed)
			(copperpour not_allowed)
			(footprints allowed)
		)
		(placement
			(enabled no)
			(sheetname "")
		)
		(fill
			(thermal_gap 0.5)
			(thermal_bridge_width 0.5)
			(island_removal_mode 0)
		)
		(polygon
			(pts
				(arc
					(start 99.85248 -384.604514)
					(mid 99.762677 -384.567317)
					(end 99.72548 -384.477514)
				)
				(arc
					(start 99.72548 -384.276346)
					(mid 99.762677 -384.186543)
					(end 99.85248 -384.149346)
				)
				(arc
					(start 100.10648 -384.149346)
					(mid 100.196283 -384.186543)
					(end 100.23348 -384.276346)
				)
				(arc
					(start 100.23348 -384.477514)
					(mid 100.196283 -384.567317)
					(end 100.10648 -384.604514)
				)
			)
		)
	)
	(zone
		(layer "In1.Cu")
		(hatch none 0.5)
		(connect_pads
			(clearance 0)
		)
		(min_thickness 0.25)
		(keepout
			(tracks not_allowed)
			(vias allowed)
			(pads allowed)
			(copperpour not_allowed)
			(footprints allowed)
		)
		(placement
			(enabled no)
			(sheetname "")
		)
		(fill
			(thermal_gap 0.5)
			(thermal_bridge_width 0.5)
			(island_removal_mode 0)
		)
		(polygon
			(pts
				(arc
					(start 294.22979 -29.974286)
					(mid 294.244669 -29.938365)
					(end 294.28059 -29.923486)
				)
				(arc
					(start 295.51249 -29.923486)
					(mid 295.548411 -29.938365)
					(end 295.56329 -29.974286)
				)
				(arc
					(start 295.56329 -31.006034)
					(mid 295.548411 -31.041955)
					(end 295.51249 -31.056834)
				)
				(arc
					(start 294.28059 -31.056834)
					(mid 294.244669 -31.041955)
					(end 294.22979 -31.006034)
				)
			)
		)
	)
	(zone
		(layer "In1.Cu")
		(hatch none 0.5)
		(connect_pads
			(clearance 0)
		)
		(min_thickness 0.25)
		(keepout
			(tracks not_allowed)
			(vias allowed)
			(pads allowed)
			(copperpour not_allowed)
			(footprints allowed)
		)
		(placement
			(enabled no)
			(sheetname "")
		)
		(fill
			(thermal_gap 0.5)
			(thermal_bridge_width 0.5)
			(island_removal_mode 0)
		)
		(polygon
			(pts
				(arc
					(start 393.732766 -102.84206)
					(mid 393.747645 -102.806139)
					(end 393.783566 -102.79126)
				)
				(arc
					(start 394.964666 -102.79126)
					(mid 395.000587 -102.806139)
					(end 395.015466 -102.84206)
				)
				(arc
					(start 395.015466 -103.848408)
					(mid 395.000587 -103.884329)
					(end 394.964666 -103.899208)
				)
				(arc
					(start 393.783566 -103.899208)
					(mid 393.747645 -103.884329)
					(end 393.732766 -103.848408)
				)
			)
		)
	)
	(zone
		(layer "In1.Cu")
		(hatch none 0.5)
		(connect_pads
			(clearance 0)
		)
		(min_thickness 0.25)
		(keepout
			(tracks not_allowed)
			(vias allowed)
			(pads allowed)
			(copperpour not_allowed)
			(footprints allowed)
		)
		(placement
			(enabled no)
			(sheetname "")
		)
		(fill
			(thermal_gap 0.5)
			(thermal_bridge_width 0.5)
			(island_removal_mode 0)
		)
		(polygon
			(pts
				(arc
					(start 420.31539 -31.086044)
					(mid 420.330269 -31.121965)
					(end 420.36619 -31.136844)
				)
				(arc
					(start 421.10279 -31.136844)
					(mid 421.138711 -31.121965)
					(end 421.15359 -31.086044)
				)
				(xy 421.15359 -30.842204) (xy 420.92118 -30.487874) (xy 421.15359 -30.132274)
				(arc
					(start 421.15359 -29.889704)
					(mid 421.138711 -29.853783)
					(end 421.10279 -29.838904)
				)
				(arc
					(start 420.36619 -29.838904)
					(mid 420.330269 -29.853783)
					(end 420.31539 -29.889704)
				)
				(xy 420.31539 -30.132274) (xy 420.5478 -30.489144) (xy 420.31539 -30.843474)
			)
		)
	)
	(zone
		(layer "In1.Cu")
		(hatch none 0.5)
		(connect_pads
			(clearance 0)
		)
		(min_thickness 0.25)
		(keepout
			(tracks not_allowed)
			(vias allowed)
			(pads allowed)
			(copperpour not_allowed)
			(footprints allowed)
		)
		(placement
			(enabled no)
			(sheetname "")
		)
		(fill
			(thermal_gap 0.5)
			(thermal_bridge_width 0.5)
			(island_removal_mode 0)
		)
		(polygon
			(pts
				(arc
					(start 89.187528 -343.533222)
					(mid 89.151607 -343.548101)
					(end 89.136728 -343.584022)
				)
				(arc
					(start 89.136728 -344.320622)
					(mid 89.151607 -344.356543)
					(end 89.187528 -344.371422)
				)
				(xy 89.431368 -344.371422) (xy 89.785698 -344.139012) (xy 90.141298 -344.371422)
				(arc
					(start 90.383868 -344.371422)
					(mid 90.419789 -344.356543)
					(end 90.434668 -344.320622)
				)
				(arc
					(start 90.434668 -343.584022)
					(mid 90.419789 -343.548101)
					(end 90.383868 -343.533222)
				)
				(xy 90.141298 -343.533222) (xy 89.784428 -343.765632) (xy 89.430098 -343.533222)
			)
		)
	)
	(zone
		(layer "In1.Cu")
		(hatch none 0.5)
		(connect_pads
			(clearance 0)
		)
		(min_thickness 0.25)
		(keepout
			(tracks not_allowed)
			(vias allowed)
			(pads allowed)
			(copperpour not_allowed)
			(footprints allowed)
		)
		(placement
			(enabled no)
			(sheetname "")
		)
		(fill
			(thermal_gap 0.5)
			(thermal_bridge_width 0.5)
			(island_removal_mode 0)
		)
		(polygon
			(pts
				(arc
					(start 51.25212 -121.958354)
					(mid 51.237241 -121.994275)
					(end 51.20132 -122.009154)
				)
				(arc
					(start 50.02022 -122.009154)
					(mid 49.984299 -121.994275)
					(end 49.96942 -121.958354)
				)
				(arc
					(start 49.96942 -120.952006)
					(mid 49.984299 -120.916085)
					(end 50.02022 -120.901206)
				)
				(arc
					(start 51.20132 -120.901206)
					(mid 51.237241 -120.916085)
					(end 51.25212 -120.952006)
				)
			)
		)
	)
	(zone
		(layer "In1.Cu")
		(hatch none 0.5)
		(connect_pads
			(clearance 0)
		)
		(min_thickness 0.25)
		(keepout
			(tracks not_allowed)
			(vias allowed)
			(pads allowed)
			(copperpour not_allowed)
			(footprints allowed)
		)
		(placement
			(enabled no)
			(sheetname "")
		)
		(fill
			(thermal_gap 0.5)
			(thermal_bridge_width 0.5)
			(island_removal_mode 0)
		)
		(polygon
			(pts
				(arc
					(start 154.961336 -125.659896)
					(mid 154.976215 -125.695817)
					(end 155.012136 -125.710696)
				)
				(arc
					(start 155.748736 -125.710696)
					(mid 155.784657 -125.695817)
					(end 155.799536 -125.659896)
				)
				(xy 155.799536 -125.416056) (xy 155.567126 -125.061726) (xy 155.799536 -124.706126)
				(arc
					(start 155.799536 -124.463556)
					(mid 155.784657 -124.427635)
					(end 155.748736 -124.412756)
				)
				(arc
					(start 155.012136 -124.412756)
					(mid 154.976215 -124.427635)
					(end 154.961336 -124.463556)
				)
				(xy 154.961336 -124.706126) (xy 155.193746 -125.062996) (xy 154.961336 -125.417326)
			)
		)
	)
	(zone
		(layer "In1.Cu")
		(hatch none 0.5)
		(connect_pads
			(clearance 0)
		)
		(min_thickness 0.25)
		(keepout
			(tracks not_allowed)
			(vias allowed)
			(pads allowed)
			(copperpour not_allowed)
			(footprints allowed)
		)
		(placement
			(enabled no)
			(sheetname "")
		)
		(fill
			(thermal_gap 0.5)
			(thermal_bridge_width 0.5)
			(island_removal_mode 0)
		)
		(polygon
			(pts
				(arc
					(start 73.867264 -121.438162)
					(mid 73.852385 -121.474083)
					(end 73.816464 -121.488962)
				)
				(arc
					(start 72.635364 -121.488962)
					(mid 72.599443 -121.474083)
					(end 72.584564 -121.438162)
				)
				(arc
					(start 72.584564 -120.431814)
					(mid 72.599443 -120.395893)
					(end 72.635364 -120.381014)
				)
				(arc
					(start 73.816464 -120.381014)
					(mid 73.852385 -120.395893)
					(end 73.867264 -120.431814)
				)
			)
		)
	)
	(zone
		(layer "In1.Cu")
		(hatch none 0.5)
		(connect_pads
			(clearance 0)
		)
		(min_thickness 0.25)
		(keepout
			(tracks not_allowed)
			(vias allowed)
			(pads allowed)
			(copperpour not_allowed)
			(footprints allowed)
		)
		(placement
			(enabled no)
			(sheetname "")
		)
		(fill
			(thermal_gap 0.5)
			(thermal_bridge_width 0.5)
			(island_removal_mode 0)
		)
		(polygon
			(pts
				(arc
					(start 324.77329 -343.533222)
					(mid 324.737369 -343.548101)
					(end 324.72249 -343.584022)
				)
				(arc
					(start 324.72249 -344.320622)
					(mid 324.737369 -344.356543)
					(end 324.77329 -344.371422)
				)
				(xy 325.01713 -344.371422) (xy 325.37146 -344.139012) (xy 325.72706 -344.371422)
				(arc
					(start 325.96963 -344.371422)
					(mid 326.005551 -344.356543)
					(end 326.02043 -344.320622)
				)
				(arc
					(start 326.02043 -343.584022)
					(mid 326.005551 -343.548101)
					(end 325.96963 -343.533222)
				)
				(xy 325.72706 -343.533222) (xy 325.37019 -343.765632) (xy 325.01586 -343.533222)
			)
		)
	)
	(zone
		(layer "In1.Cu")
		(hatch none 0.5)
		(connect_pads
			(clearance 0)
		)
		(min_thickness 0.25)
		(keepout
			(tracks not_allowed)
			(vias allowed)
			(pads allowed)
			(copperpour not_allowed)
			(footprints allowed)
		)
		(placement
			(enabled no)
			(sheetname "")
		)
		(fill
			(thermal_gap 0.5)
			(thermal_bridge_width 0.5)
			(island_removal_mode 0)
		)
		(polygon
			(pts
				(arc
					(start 277.632668 -104.641904)
					(mid 277.647547 -104.605983)
					(end 277.683468 -104.591104)
				)
				(arc
					(start 278.864568 -104.591104)
					(mid 278.900489 -104.605983)
					(end 278.915368 -104.641904)
				)
				(arc
					(start 278.915368 -105.648252)
					(mid 278.900489 -105.684173)
					(end 278.864568 -105.699052)
				)
				(arc
					(start 277.683468 -105.699052)
					(mid 277.647547 -105.684173)
					(end 277.632668 -105.648252)
				)
			)
		)
	)
	(zone
		(layer "In1.Cu")
		(hatch none 0.5)
		(connect_pads
			(clearance 0)
		)
		(min_thickness 0.25)
		(keepout
			(tracks not_allowed)
			(vias allowed)
			(pads allowed)
			(copperpour not_allowed)
			(footprints allowed)
		)
		(placement
			(enabled no)
			(sheetname "")
		)
		(fill
			(thermal_gap 0.5)
			(thermal_bridge_width 0.5)
			(island_removal_mode 0)
		)
		(polygon
			(pts
				(arc
					(start 106.512106 -381.072136)
					(mid 106.601909 -381.109333)
					(end 106.639106 -381.199136)
				)
				(arc
					(start 106.639106 -381.400304)
					(mid 106.601909 -381.490107)
					(end 106.512106 -381.527304)
				)
				(arc
					(start 106.258106 -381.527304)
					(mid 106.168303 -381.490107)
					(end 106.131106 -381.400304)
				)
				(arc
					(start 106.131106 -381.199136)
					(mid 106.168303 -381.109333)
					(end 106.258106 -381.072136)
				)
			)
		)
	)
	(zone
		(layer "In1.Cu")
		(hatch none 0.5)
		(connect_pads
			(clearance 0)
		)
		(min_thickness 0.25)
		(keepout
			(tracks not_allowed)
			(vias allowed)
			(pads allowed)
			(copperpour not_allowed)
			(footprints allowed)
		)
		(placement
			(enabled no)
			(sheetname "")
		)
		(fill
			(thermal_gap 0.5)
			(thermal_bridge_width 0.5)
			(island_removal_mode 0)
		)
		(polygon
			(pts
				(arc
					(start 198.34225 -121.531126)
					(mid 198.357129 -121.567047)
					(end 198.39305 -121.581926)
				)
				(arc
					(start 199.12965 -121.581926)
					(mid 199.165571 -121.567047)
					(end 199.18045 -121.531126)
				)
				(xy 199.18045 -121.287286) (xy 198.94804 -120.932956) (xy 199.18045 -120.577356)
				(arc
					(start 199.18045 -120.334786)
					(mid 199.165571 -120.298865)
					(end 199.12965 -120.283986)
				)
				(arc
					(start 198.39305 -120.283986)
					(mid 198.357129 -120.298865)
					(end 198.34225 -120.334786)
				)
				(xy 198.34225 -120.577356) (xy 198.57466 -120.934226) (xy 198.34225 -121.288556)
			)
		)
	)
	(zone
		(layer "In1.Cu")
		(hatch none 0.5)
		(connect_pads
			(clearance 0)
		)
		(min_thickness 0.25)
		(keepout
			(tracks not_allowed)
			(vias allowed)
			(pads allowed)
			(copperpour not_allowed)
			(footprints allowed)
		)
		(placement
			(enabled no)
			(sheetname "")
		)
		(fill
			(thermal_gap 0.5)
			(thermal_bridge_width 0.5)
			(island_removal_mode 0)
		)
		(polygon
			(pts
				(arc
					(start 416.199828 -34.605976)
					(mid 416.184949 -34.641897)
					(end 416.149028 -34.656776)
				)
				(arc
					(start 414.917128 -34.656776)
					(mid 414.881207 -34.641897)
					(end 414.866328 -34.605976)
				)
				(arc
					(start 414.866328 -33.574228)
					(mid 414.881207 -33.538307)
					(end 414.917128 -33.523428)
				)
				(arc
					(start 416.149028 -33.523428)
					(mid 416.184949 -33.538307)
					(end 416.199828 -33.574228)
				)
			)
		)
	)
	(zone
		(layer "In1.Cu")
		(hatch none 0.5)
		(connect_pads
			(clearance 0)
		)
		(min_thickness 0.25)
		(keepout
			(tracks not_allowed)
			(vias allowed)
			(pads allowed)
			(copperpour not_allowed)
			(footprints allowed)
		)
		(placement
			(enabled no)
			(sheetname "")
		)
		(fill
			(thermal_gap 0.5)
			(thermal_bridge_width 0.5)
			(island_removal_mode 0)
		)
		(polygon
			(pts
				(arc
					(start 204.129894 -29.974286)
					(mid 204.144773 -29.938365)
					(end 204.180694 -29.923486)
				)
				(arc
					(start 205.412594 -29.923486)
					(mid 205.448515 -29.938365)
					(end 205.463394 -29.974286)
				)
				(arc
					(start 205.463394 -31.006034)
					(mid 205.448515 -31.041955)
					(end 205.412594 -31.056834)
				)
				(arc
					(start 204.180694 -31.056834)
					(mid 204.144773 -31.041955)
					(end 204.129894 -31.006034)
				)
			)
		)
	)
	(zone
		(layer "In1.Cu")
		(hatch none 0.5)
		(connect_pads
			(clearance 0)
		)
		(min_thickness 0.25)
		(keepout
			(tracks not_allowed)
			(vias allowed)
			(pads allowed)
			(copperpour not_allowed)
			(footprints allowed)
		)
		(placement
			(enabled no)
			(sheetname "")
		)
		(fill
			(thermal_gap 0.5)
			(thermal_bridge_width 0.5)
			(island_removal_mode 0)
		)
		(polygon
			(pts
				(arc
					(start 233.998008 -83.490308)
					(mid 234.087811 -83.527505)
					(end 234.125008 -83.617308)
				)
				(arc
					(start 234.125008 -83.820508)
					(mid 234.087811 -83.910311)
					(end 233.998008 -83.947508)
				)
				(arc
					(start 233.744008 -83.947508)
					(mid 233.654205 -83.910311)
					(end 233.617008 -83.820508)
				)
				(arc
					(start 233.617008 -83.617308)
					(mid 233.654205 -83.527505)
					(end 233.744008 -83.490308)
				)
			)
		)
	)
	(zone
		(layer "In1.Cu")
		(hatch none 0.5)
		(connect_pads
			(clearance 0)
		)
		(min_thickness 0.25)
		(keepout
			(tracks not_allowed)
			(vias allowed)
			(pads allowed)
			(copperpour not_allowed)
			(footprints allowed)
		)
		(placement
			(enabled no)
			(sheetname "")
		)
		(fill
			(thermal_gap 0.5)
			(thermal_bridge_width 0.5)
			(island_removal_mode 0)
		)
		(polygon
			(pts
				(arc
					(start 15.899892 -32.805878)
					(mid 15.885013 -32.841799)
					(end 15.849092 -32.856678)
				)
				(arc
					(start 14.617192 -32.856678)
					(mid 14.581271 -32.841799)
					(end 14.566392 -32.805878)
				)
				(arc
					(start 14.566392 -31.77413)
					(mid 14.581271 -31.738209)
					(end 14.617192 -31.72333)
				)
				(arc
					(start 15.849092 -31.72333)
					(mid 15.885013 -31.738209)
					(end 15.899892 -31.77413)
				)
			)
		)
	)
	(zone
		(layer "In1.Cu")
		(hatch none 0.5)
		(connect_pads
			(clearance 0)
		)
		(min_thickness 0.25)
		(keepout
			(tracks not_allowed)
			(vias allowed)
			(pads allowed)
			(copperpour not_allowed)
			(footprints allowed)
		)
		(placement
			(enabled no)
			(sheetname "")
		)
		(fill
			(thermal_gap 0.5)
			(thermal_bridge_width 0.5)
			(island_removal_mode 0)
		)
		(polygon
			(pts
				(arc
					(start 440.219338 -349.679514)
					(mid 440.183417 -349.694393)
					(end 440.168538 -349.730314)
				)
				(arc
					(start 440.168538 -350.466914)
					(mid 440.183417 -350.502835)
					(end 440.219338 -350.517714)
				)
				(xy 440.463178 -350.517714) (xy 440.817508 -350.285304) (xy 441.173108 -350.517714)
				(arc
					(start 441.415678 -350.517714)
					(mid 441.451599 -350.502835)
					(end 441.466478 -350.466914)
				)
				(arc
					(start 441.466478 -349.730314)
					(mid 441.451599 -349.694393)
					(end 441.415678 -349.679514)
				)
				(xy 441.173108 -349.679514) (xy 440.816238 -349.911924) (xy 440.461908 -349.679514)
			)
		)
	)
	(zone
		(layer "In1.Cu")
		(hatch none 0.5)
		(connect_pads
			(clearance 0)
		)
		(min_thickness 0.25)
		(keepout
			(tracks not_allowed)
			(vias allowed)
			(pads allowed)
			(copperpour not_allowed)
			(footprints allowed)
		)
		(placement
			(enabled no)
			(sheetname "")
		)
		(fill
			(thermal_gap 0.5)
			(thermal_bridge_width 0.5)
			(island_removal_mode 0)
		)
		(polygon
			(pts
				(arc
					(start 62.029848 -29.974286)
					(mid 62.044727 -29.938365)
					(end 62.080648 -29.923486)
				)
				(arc
					(start 63.312548 -29.923486)
					(mid 63.348469 -29.938365)
					(end 63.363348 -29.974286)
				)
				(arc
					(start 63.363348 -31.006034)
					(mid 63.348469 -31.041955)
					(end 63.312548 -31.056834)
				)
				(arc
					(start 62.080648 -31.056834)
					(mid 62.044727 -31.041955)
					(end 62.029848 -31.006034)
				)
			)
		)
	)
	(zone
		(layer "In1.Cu")
		(hatch none 0.5)
		(connect_pads
			(clearance 0)
		)
		(min_thickness 0.25)
		(keepout
			(tracks not_allowed)
			(vias allowed)
			(pads allowed)
			(copperpour not_allowed)
			(footprints allowed)
		)
		(placement
			(enabled no)
			(sheetname "")
		)
		(fill
			(thermal_gap 0.5)
			(thermal_bridge_width 0.5)
			(island_removal_mode 0)
		)
		(polygon
			(pts
				(arc
					(start 271.061434 -111.143288)
					(mid 271.076313 -111.179209)
					(end 271.112234 -111.194088)
				)
				(arc
					(start 271.848834 -111.194088)
					(mid 271.884755 -111.179209)
					(end 271.899634 -111.143288)
				)
				(xy 271.899634 -110.899448) (xy 271.667224 -110.545118) (xy 271.899634 -110.189518)
				(arc
					(start 271.899634 -109.946948)
					(mid 271.884755 -109.911027)
					(end 271.848834 -109.896148)
				)
				(arc
					(start 271.112234 -109.896148)
					(mid 271.076313 -109.911027)
					(end 271.061434 -109.946948)
				)
				(xy 271.061434 -110.189518) (xy 271.293844 -110.546388) (xy 271.061434 -110.900718)
			)
		)
	)
	(zone
		(layer "In1.Cu")
		(hatch none 0.5)
		(connect_pads
			(clearance 0)
		)
		(min_thickness 0.25)
		(keepout
			(tracks not_allowed)
			(vias allowed)
			(pads allowed)
			(copperpour not_allowed)
			(footprints allowed)
		)
		(placement
			(enabled no)
			(sheetname "")
		)
		(fill
			(thermal_gap 0.5)
			(thermal_bridge_width 0.5)
			(island_removal_mode 0)
		)
		(polygon
			(pts
				(arc
					(start 300.247812 -151.551894)
					(mid 300.262691 -151.515973)
					(end 300.298612 -151.501094)
				)
				(arc
					(start 301.479712 -151.501094)
					(mid 301.515633 -151.515973)
					(end 301.530512 -151.551894)
				)
				(arc
					(start 301.530512 -152.558242)
					(mid 301.515633 -152.594163)
					(end 301.479712 -152.609042)
				)
				(arc
					(start 300.298612 -152.609042)
					(mid 300.262691 -152.594163)
					(end 300.247812 -152.558242)
				)
			)
		)
	)
	(zone
		(layer "In1.Cu")
		(hatch none 0.5)
		(connect_pads
			(clearance 0)
		)
		(min_thickness 0.25)
		(keepout
			(tracks not_allowed)
			(vias allowed)
			(pads allowed)
			(copperpour not_allowed)
			(footprints allowed)
		)
		(placement
			(enabled no)
			(sheetname "")
		)
		(fill
			(thermal_gap 0.5)
			(thermal_bridge_width 0.5)
			(island_removal_mode 0)
		)
		(polygon
			(pts
				(arc
					(start 167.351964 -103.848408)
					(mid 167.337085 -103.884329)
					(end 167.301164 -103.899208)
				)
				(arc
					(start 166.120064 -103.899208)
					(mid 166.084143 -103.884329)
					(end 166.069264 -103.848408)
				)
				(arc
					(start 166.069264 -102.84206)
					(mid 166.084143 -102.806139)
					(end 166.120064 -102.79126)
				)
				(arc
					(start 167.301164 -102.79126)
					(mid 167.337085 -102.806139)
					(end 167.351964 -102.84206)
				)
			)
		)
	)
	(zone
		(layer "In1.Cu")
		(hatch none 0.5)
		(connect_pads
			(clearance 0)
		)
		(min_thickness 0.25)
		(keepout
			(tracks not_allowed)
			(vias allowed)
			(pads allowed)
			(copperpour not_allowed)
			(footprints allowed)
		)
		(placement
			(enabled no)
			(sheetname "")
		)
		(fill
			(thermal_gap 0.5)
			(thermal_bridge_width 0.5)
			(island_removal_mode 0)
		)
		(polygon
			(pts
				(arc
					(start 384.32994 -33.574228)
					(mid 384.344819 -33.538307)
					(end 384.38074 -33.523428)
				)
				(arc
					(start 385.61264 -33.523428)
					(mid 385.648561 -33.538307)
					(end 385.66344 -33.574228)
				)
				(arc
					(start 385.66344 -34.605976)
					(mid 385.648561 -34.641897)
					(end 385.61264 -34.656776)
				)
				(arc
					(start 384.38074 -34.656776)
					(mid 384.344819 -34.641897)
					(end 384.32994 -34.605976)
				)
			)
		)
	)
	(zone
		(layer "In1.Cu")
		(hatch none 0.5)
		(connect_pads
			(clearance 0)
		)
		(min_thickness 0.25)
		(keepout
			(tracks not_allowed)
			(vias allowed)
			(pads allowed)
			(copperpour not_allowed)
			(footprints allowed)
		)
		(placement
			(enabled no)
			(sheetname "")
		)
		(fill
			(thermal_gap 0.5)
			(thermal_bridge_width 0.5)
			(island_removal_mode 0)
		)
		(polygon
			(pts
				(arc
					(start 25.385014 -349.679514)
					(mid 25.349093 -349.694393)
					(end 25.334214 -349.730314)
				)
				(arc
					(start 25.334214 -350.466914)
					(mid 25.349093 -350.502835)
					(end 25.385014 -350.517714)
				)
				(xy 25.628854 -350.517714) (xy 25.983184 -350.285304) (xy 26.338784 -350.517714)
				(arc
					(start 26.581354 -350.517714)
					(mid 26.617275 -350.502835)
					(end 26.632154 -350.466914)
				)
				(arc
					(start 26.632154 -349.730314)
					(mid 26.617275 -349.694393)
					(end 26.581354 -349.679514)
				)
				(xy 26.338784 -349.679514) (xy 25.981914 -349.911924) (xy 25.627584 -349.679514)
			)
		)
	)
	(zone
		(layers "In1.Cu" "In16.Cu")
		(hatch none 0.5)
		(connect_pads
			(clearance 0)
		)
		(min_thickness 0.25)
		(keepout
			(tracks not_allowed)
			(vias allowed)
			(pads allowed)
			(copperpour not_allowed)
			(footprints allowed)
		)
		(placement
			(enabled no)
			(sheetname "")
		)
		(fill yes
			(thermal_gap 0.5)
			(thermal_bridge_width 0.5)
			(island_removal_mode 0)
		)
		(polygon
			(pts
				(arc
					(start 240.997232 8.625332)
					(mid 241.01955 8.679214)
					(end 241.073432 8.701532)
				)
				(arc
					(start 241.685572 8.701532)
					(mid 241.739454 8.679214)
					(end 241.761772 8.625332)
				)
				(arc
					(start 241.761772 7.528052)
					(mid 241.739454 7.47417)
					(end 241.685572 7.451852)
				)
				(arc
					(start 241.073432 7.451852)
					(mid 241.01955 7.47417)
					(end 240.997232 7.528052)
				)
			)
		)
	)
	(zone
		(layers "In1.Cu" "In16.Cu")
		(hatch none 0.5)
		(connect_pads
			(clearance 0)
		)
		(min_thickness 0.25)
		(keepout
			(tracks not_allowed)
			(vias allowed)
			(pads allowed)
			(copperpour not_allowed)
			(footprints allowed)
		)
		(placement
			(enabled no)
			(sheetname "")
		)
		(fill yes
			(thermal_gap 0.5)
			(thermal_bridge_width 0.5)
			(island_removal_mode 0)
		)
		(polygon
			(pts
				(arc
					(start 247.307608 18.577052)
					(mid 247.329926 18.630934)
					(end 247.383808 18.653252)
				)
				(arc
					(start 247.995948 18.653252)
					(mid 248.04983 18.630934)
					(end 248.072148 18.577052)
				)
				(arc
					(start 248.072148 17.479772)
					(mid 248.04983 17.42589)
					(end 247.995948 17.403572)
				)
				(arc
					(start 247.383808 17.403572)
					(mid 247.329926 17.42589)
					(end 247.307608 17.479772)
				)
			)
		)
	)
	(zone
		(layers "In1.Cu" "In16.Cu")
		(hatch none 0.5)
		(connect_pads
			(clearance 0)
		)
		(min_thickness 0.25)
		(keepout
			(tracks not_allowed)
			(vias allowed)
			(pads allowed)
			(copperpour not_allowed)
			(footprints allowed)
		)
		(placement
			(enabled no)
			(sheetname "")
		)
		(fill yes
			(thermal_gap 0.5)
			(thermal_bridge_width 0.5)
			(island_removal_mode 0)
		)
		(polygon
			(pts
				(arc
					(start 214.91956 17.486884)
					(mid 214.897242 17.433002)
					(end 214.84336 17.410684)
				)
				(arc
					(start 214.23122 17.410684)
					(mid 214.177338 17.433002)
					(end 214.15502 17.486884)
				)
				(arc
					(start 214.15502 18.584164)
					(mid 214.177338 18.638046)
					(end 214.23122 18.660364)
				)
				(arc
					(start 214.84336 18.660364)
					(mid 214.897242 18.638046)
					(end 214.91956 18.584164)
				)
			)
		)
	)
	(zone
		(layers "In1.Cu" "In16.Cu")
		(hatch none 0.5)
		(connect_pads
			(clearance 0)
		)
		(min_thickness 0.25)
		(keepout
			(tracks not_allowed)
			(vias allowed)
			(pads allowed)
			(copperpour not_allowed)
			(footprints allowed)
		)
		(placement
			(enabled no)
			(sheetname "")
		)
		(fill yes
			(thermal_gap 0.5)
			(thermal_bridge_width 0.5)
			(island_removal_mode 0)
		)
		(polygon
			(pts
				(arc
					(start 184.43956 7.535164)
					(mid 184.417242 7.481282)
					(end 184.36336 7.458964)
				)
				(arc
					(start 183.75122 7.458964)
					(mid 183.697338 7.481282)
					(end 183.67502 7.535164)
				)
				(arc
					(start 183.67502 8.632444)
					(mid 183.697338 8.686326)
					(end 183.75122 8.708644)
				)
				(arc
					(start 184.36336 8.708644)
					(mid 184.417242 8.686326)
					(end 184.43956 8.632444)
				)
			)
		)
	)
	(zone
		(layers "In2.Cu" "In3.Cu")
		(hatch none 0.5)
		(connect_pads
			(clearance 0)
		)
		(min_thickness 0.25)
		(keepout
			(tracks not_allowed)
			(vias allowed)
			(pads allowed)
			(copperpour not_allowed)
			(footprints allowed)
		)
		(placement
			(enabled no)
			(sheetname "")
		)
		(fill yes
			(thermal_gap 0.5)
			(thermal_bridge_width 0.5)
			(island_removal_mode 0)
		)
		(polygon
			(pts
				(arc
					(start 461.19034 -5.999988)
					(mid 450.67474 -5.999988)
					(end 461.19034 -5.999988)
				)
			)
		)
		(polygon
			(pts
				(arc
					(start 460.96174 -5.999988)
					(mid 450.90334 -5.999988)
					(end 460.96174 -5.999988)
				)
			)
		)
	)
	(zone
		(layers "In2.Cu" "In3.Cu")
		(hatch none 0.5)
		(connect_pads
			(clearance 0)
		)
		(min_thickness 0.25)
		(keepout
			(tracks not_allowed)
			(vias allowed)
			(pads allowed)
			(copperpour not_allowed)
			(footprints allowed)
		)
		(placement
			(enabled no)
			(sheetname "")
		)
		(fill yes
			(thermal_gap 0.5)
			(thermal_bridge_width 0.5)
			(island_removal_mode 0)
		)
		(polygon
			(pts
				(arc
					(start 368.847878 -407.599896)
					(mid 358.332278 -407.599896)
					(end 368.847878 -407.599896)
				)
			)
		)
		(polygon
			(pts
				(arc
					(start 368.619278 -407.599896)
					(mid 358.560878 -407.599896)
					(end 368.619278 -407.599896)
				)
			)
		)
	)
	(zone
		(layers "In2.Cu" "In3.Cu")
		(hatch none 0.5)
		(connect_pads
			(clearance 0)
		)
		(min_thickness 0.25)
		(keepout
			(tracks not_allowed)
			(vias allowed)
			(pads allowed)
			(copperpour not_allowed)
			(footprints allowed)
		)
		(placement
			(enabled no)
			(sheetname "")
		)
		(fill yes
			(thermal_gap 0.5)
			(thermal_bridge_width 0.5)
			(island_removal_mode 0)
		)
		(polygon
			(pts
				(arc
					(start 173.322996 -5.999988)
					(mid 162.807396 -5.999988)
					(end 173.322996 -5.999988)
				)
			)
		)
		(polygon
			(pts
				(arc
					(start 173.094396 -5.999988)
					(mid 163.035996 -5.999988)
					(end 173.094396 -5.999988)
				)
			)
		)
	)
	(zone
		(layers "In2.Cu" "In3.Cu")
		(hatch none 0.5)
		(connect_pads
			(clearance 0)
		)
		(min_thickness 0.25)
		(keepout
			(tracks not_allowed)
			(vias allowed)
			(pads allowed)
			(copperpour not_allowed)
			(footprints allowed)
		)
		(placement
			(enabled no)
			(sheetname "")
		)
		(fill yes
			(thermal_gap 0.5)
			(thermal_bridge_width 0.5)
			(island_removal_mode 0)
		)
		(polygon
			(pts
				(arc
					(start 405.522684 -5.999988)
					(mid 395.007084 -5.999988)
					(end 405.522684 -5.999988)
				)
			)
		)
		(polygon
			(pts
				(arc
					(start 405.294084 -5.999988)
					(mid 395.235684 -5.999988)
					(end 405.294084 -5.999988)
				)
			)
		)
	)
	(zone
		(layers "In2.Cu" "In3.Cu")
		(hatch none 0.5)
		(connect_pads
			(clearance 0)
		)
		(min_thickness 0.25)
		(keepout
			(tracks not_allowed)
			(vias allowed)
			(pads allowed)
			(copperpour not_allowed)
			(footprints allowed)
		)
		(placement
			(enabled no)
			(sheetname "")
		)
		(fill yes
			(thermal_gap 0.5)
			(thermal_bridge_width 0.5)
			(island_removal_mode 0)
		)
		(polygon
			(pts
				(arc
					(start 289.42284 -5.999988)
					(mid 278.90724 -5.999988)
					(end 289.42284 -5.999988)
				)
			)
		)
		(polygon
			(pts
				(arc
					(start 289.19424 -5.999988)
					(mid 279.13584 -5.999988)
					(end 289.19424 -5.999988)
				)
			)
		)
	)
	(zone
		(layers "In2.Cu" "In3.Cu")
		(hatch none 0.5)
		(connect_pads
			(clearance 0)
		)
		(min_thickness 0.25)
		(keepout
			(tracks not_allowed)
			(vias allowed)
			(pads allowed)
			(copperpour not_allowed)
			(footprints allowed)
		)
		(placement
			(enabled no)
			(sheetname "")
		)
		(fill yes
			(thermal_gap 0.5)
			(thermal_bridge_width 0.5)
			(island_removal_mode 0)
		)
		(polygon
			(pts
				(arc
					(start 219.758514 -347.400118)
					(mid 211.757514 -347.400118)
					(end 219.758514 -347.400118)
				)
			)
		)
	)
	(zone
		(layers "In2.Cu" "In3.Cu")
		(hatch none 0.5)
		(connect_pads
			(clearance 0)
		)
		(min_thickness 0.25)
		(keepout
			(tracks not_allowed)
			(vias allowed)
			(pads allowed)
			(copperpour not_allowed)
			(footprints allowed)
		)
		(placement
			(enabled no)
			(sheetname "")
		)
		(fill yes
			(thermal_gap 0.5)
			(thermal_bridge_width 0.5)
			(island_removal_mode 0)
		)
		(polygon
			(pts
				(arc
					(start 231.372918 -5.999988)
					(mid 220.857318 -5.999988)
					(end 231.372918 -5.999988)
				)
			)
		)
		(polygon
			(pts
				(arc
					(start 231.144318 -5.999988)
					(mid 221.085918 -5.999988)
					(end 231.144318 -5.999988)
				)
			)
		)
	)
	(zone
		(layers "In2.Cu" "In3.Cu")
		(hatch none 0.5)
		(connect_pads
			(clearance 0)
		)
		(min_thickness 0.25)
		(keepout
			(tracks not_allowed)
			(vias allowed)
			(pads allowed)
			(copperpour not_allowed)
			(footprints allowed)
		)
		(placement
			(enabled no)
			(sheetname "")
		)
		(fill yes
			(thermal_gap 0.5)
			(thermal_bridge_width 0.5)
			(island_removal_mode 0)
		)
		(polygon
			(pts
				(arc
					(start 457.05776 -194.360038)
					(mid 446.54216 -194.360038)
					(end 457.05776 -194.360038)
				)
			)
		)
		(polygon
			(pts
				(arc
					(start 456.82916 -194.360038)
					(mid 446.77076 -194.360038)
					(end 456.82916 -194.360038)
				)
			)
		)
	)
	(zone
		(layers "In2.Cu" "In3.Cu" "In5.Cu")
		(hatch none 0.5)
		(connect_pads
			(clearance 0)
		)
		(min_thickness 0.25)
		(keepout
			(tracks not_allowed)
			(vias allowed)
			(pads allowed)
			(copperpour not_allowed)
			(footprints allowed)
		)
		(placement
			(enabled no)
			(sheetname "")
		)
		(fill yes
			(thermal_gap 0.5)
			(thermal_bridge_width 0.5)
			(island_removal_mode 0)
		)
		(polygon
			(pts
				(arc
					(start 466.857842 -407.599896)
					(mid 456.342242 -407.599896)
					(end 466.857842 -407.599896)
				)
			)
		)
		(polygon
			(pts
				(arc
					(start 466.629242 -407.599896)
					(mid 456.570842 -407.599896)
					(end 466.629242 -407.599896)
				)
			)
		)
	)
	(zone
		(layers "In2.Cu" "In3.Cu" "In5.Cu")
		(hatch none 0.5)
		(connect_pads
			(clearance 0)
		)
		(min_thickness 0.25)
		(keepout
			(tracks not_allowed)
			(vias allowed)
			(pads allowed)
			(copperpour not_allowed)
			(footprints allowed)
		)
		(placement
			(enabled no)
			(sheetname "")
		)
		(fill yes
			(thermal_gap 0.5)
			(thermal_bridge_width 0.5)
			(island_removal_mode 0)
		)
		(polygon
			(pts
				(arc
					(start 11.257788 -407.599896)
					(mid 0.742188 -407.599896)
					(end 11.257788 -407.599896)
				)
			)
		)
		(polygon
			(pts
				(arc
					(start 11.029188 -407.599896)
					(mid 0.970788 -407.599896)
					(end 11.029188 -407.599896)
				)
			)
		)
	)
	(zone
		(layers "In2.Cu" "In3.Cu" "In5.Cu" "In7.Cu" "In9.Cu" "In11.Cu")
		(hatch none 0.5)
		(connect_pads
			(clearance 0)
		)
		(min_thickness 0.25)
		(keepout
			(tracks not_allowed)
			(vias allowed)
			(pads allowed)
			(copperpour not_allowed)
			(footprints allowed)
		)
		(placement
			(enabled no)
			(sheetname "")
		)
		(fill yes
			(thermal_gap 0.5)
			(thermal_bridge_width 0.5)
			(island_removal_mode 0)
		)
		(polygon
			(pts
				(arc
					(start 442.699648 -320.900044)
					(mid 433.200048 -320.900044)
					(end 442.699648 -320.900044)
				)
			)
		)
		(polygon
			(pts
				(arc
					(start 442.471048 -320.900044)
					(mid 433.428648 -320.900044)
					(end 442.471048 -320.900044)
				)
			)
		)
	)
	(zone
		(layers "In2.Cu" "In3.Cu" "In5.Cu" "In7.Cu" "In9.Cu" "In11.Cu" "In13.Cu"
			"In15.Cu"
		)
		(hatch none 0.5)
		(connect_pads
			(clearance 0)
		)
		(min_thickness 0.25)
		(keepout
			(tracks not_allowed)
			(vias allowed)
			(pads allowed)
			(copperpour not_allowed)
			(footprints allowed)
		)
		(placement
			(enabled no)
			(sheetname "")
		)
		(fill yes
			(thermal_gap 0.5)
			(thermal_bridge_width 0.5)
			(island_removal_mode 0)
		)
		(polygon
			(pts
				(arc
					(start 210.499452 -270.89989)
					(mid 200.999852 -270.89989)
					(end 210.499452 -270.89989)
				)
			)
		)
		(polygon
			(pts
				(arc
					(start 210.270852 -270.89989)
					(mid 201.228452 -270.89989)
					(end 210.270852 -270.89989)
				)
			)
		)
	)
	(zone
		(layers "In2.Cu" "In3.Cu" "In5.Cu" "In7.Cu" "In9.Cu" "In11.Cu" "In13.Cu"
			"In15.Cu"
		)
		(hatch none 0.5)
		(connect_pads
			(clearance 0)
		)
		(min_thickness 0.25)
		(keepout
			(tracks not_allowed)
			(vias allowed)
			(pads allowed)
			(copperpour not_allowed)
			(footprints allowed)
		)
		(placement
			(enabled no)
			(sheetname "")
		)
		(fill yes
			(thermal_gap 0.5)
			(thermal_bridge_width 0.5)
			(island_removal_mode 0)
		)
		(polygon
			(pts
				(arc
					(start 150.499572 -320.900044)
					(mid 140.999972 -320.900044)
					(end 150.499572 -320.900044)
				)
			)
		)
		(polygon
			(pts
				(arc
					(start 150.270972 -320.900044)
					(mid 141.228572 -320.900044)
					(end 150.270972 -320.900044)
				)
			)
		)
	)
	(zone
		(layers "In2.Cu" "In3.Cu" "In5.Cu" "In7.Cu" "In9.Cu" "In11.Cu" "In13.Cu"
			"In15.Cu"
		)
		(hatch none 0.5)
		(connect_pads
			(clearance 0)
		)
		(min_thickness 0.25)
		(keepout
			(tracks not_allowed)
			(vias allowed)
			(pads allowed)
			(copperpour not_allowed)
			(footprints allowed)
		)
		(placement
			(enabled no)
			(sheetname "")
		)
		(fill yes
			(thermal_gap 0.5)
			(thermal_bridge_width 0.5)
			(island_removal_mode 0)
		)
		(polygon
			(pts
				(arc
					(start 382.699514 -320.900044)
					(mid 373.199914 -320.900044)
					(end 382.699514 -320.900044)
				)
			)
		)
		(polygon
			(pts
				(arc
					(start 382.470914 -320.900044)
					(mid 373.428514 -320.900044)
					(end 382.470914 -320.900044)
				)
			)
		)
	)
	(zone
		(layers "In2.Cu" "In3.Cu" "In5.Cu" "In7.Cu" "In9.Cu" "In11.Cu" "In13.Cu"
			"In15.Cu"
		)
		(hatch none 0.5)
		(connect_pads
			(clearance 0)
		)
		(min_thickness 0.25)
		(keepout
			(tracks not_allowed)
			(vias allowed)
			(pads allowed)
			(copperpour not_allowed)
			(footprints allowed)
		)
		(placement
			(enabled no)
			(sheetname "")
		)
		(fill yes
			(thermal_gap 0.5)
			(thermal_bridge_width 0.5)
			(island_removal_mode 0)
		)
		(polygon
			(pts
				(arc
					(start 94.399608 -270.89989)
					(mid 84.900008 -270.89989)
					(end 94.399608 -270.89989)
				)
			)
		)
		(polygon
			(pts
				(arc
					(start 94.171008 -270.89989)
					(mid 85.128608 -270.89989)
					(end 94.171008 -270.89989)
				)
			)
		)
	)
	(zone
		(layers "In2.Cu" "In3.Cu" "In5.Cu" "In7.Cu" "In9.Cu" "In11.Cu" "In13.Cu"
			"In15.Cu"
		)
		(hatch none 0.5)
		(connect_pads
			(clearance 0)
		)
		(min_thickness 0.25)
		(keepout
			(tracks not_allowed)
			(vias allowed)
			(pads allowed)
			(copperpour not_allowed)
			(footprints allowed)
		)
		(placement
			(enabled no)
			(sheetname "")
		)
		(fill yes
			(thermal_gap 0.5)
			(thermal_bridge_width 0.5)
			(island_removal_mode 0)
		)
		(polygon
			(pts
				(arc
					(start 442.699648 -270.89989)
					(mid 433.200048 -270.89989)
					(end 442.699648 -270.89989)
				)
			)
		)
		(polygon
			(pts
				(arc
					(start 442.471048 -270.89989)
					(mid 433.428648 -270.89989)
					(end 442.471048 -270.89989)
				)
			)
		)
	)
	(zone
		(layers "In2.Cu" "In3.Cu" "In5.Cu" "In7.Cu" "In9.Cu" "In11.Cu" "In13.Cu"
			"In15.Cu"
		)
		(hatch none 0.5)
		(connect_pads
			(clearance 0)
		)
		(min_thickness 0.25)
		(keepout
			(tracks not_allowed)
			(vias allowed)
			(pads allowed)
			(copperpour not_allowed)
			(footprints allowed)
		)
		(placement
			(enabled no)
			(sheetname "")
		)
		(fill yes
			(thermal_gap 0.5)
			(thermal_bridge_width 0.5)
			(island_removal_mode 0)
		)
		(polygon
			(pts
				(arc
					(start 34.399474 -270.89989)
					(mid 24.899874 -270.89989)
					(end 34.399474 -270.89989)
				)
			)
		)
		(polygon
			(pts
				(arc
					(start 34.170874 -270.89989)
					(mid 25.128474 -270.89989)
					(end 34.170874 -270.89989)
				)
			)
		)
	)
	(zone
		(layers "In2.Cu" "In3.Cu" "In5.Cu" "In7.Cu" "In9.Cu" "In11.Cu" "In15.Cu")
		(hatch none 0.5)
		(connect_pads
			(clearance 0)
		)
		(min_thickness 0.25)
		(keepout
			(tracks not_allowed)
			(vias allowed)
			(pads allowed)
			(copperpour not_allowed)
			(footprints allowed)
		)
		(placement
			(enabled no)
			(sheetname "")
		)
		(fill yes
			(thermal_gap 0.5)
			(thermal_bridge_width 0.5)
			(island_removal_mode 0)
		)
		(polygon
			(pts
				(arc
					(start 273.45767 -393.099798)
					(mid 262.94207 -393.099798)
					(end 273.45767 -393.099798)
				)
			)
		)
		(polygon
			(pts
				(arc
					(start 273.22907 -393.099798)
					(mid 263.17067 -393.099798)
					(end 273.22907 -393.099798)
				)
			)
		)
	)
	(zone
		(layers "In2.Cu" "In3.Cu" "In5.Cu" "In7.Cu" "In9.Cu" "In11.Cu" "In15.Cu")
		(hatch none 0.5)
		(connect_pads
			(clearance 0)
		)
		(min_thickness 0.25)
		(keepout
			(tracks not_allowed)
			(vias allowed)
			(pads allowed)
			(copperpour not_allowed)
			(footprints allowed)
		)
		(placement
			(enabled no)
			(sheetname "")
		)
		(fill yes
			(thermal_gap 0.5)
			(thermal_bridge_width 0.5)
			(island_removal_mode 0)
		)
		(polygon
			(pts
				(arc
					(start 266.59967 -270.89989)
					(mid 257.10007 -270.89989)
					(end 266.59967 -270.89989)
				)
			)
		)
		(polygon
			(pts
				(arc
					(start 266.37107 -270.89989)
					(mid 257.32867 -270.89989)
					(end 266.37107 -270.89989)
				)
			)
		)
	)
	(zone
		(layers "In2.Cu" "In3.Cu" "In5.Cu" "In7.Cu" "In9.Cu" "In11.Cu" "In15.Cu")
		(hatch none 0.5)
		(connect_pads
			(clearance 0)
		)
		(min_thickness 0.25)
		(keepout
			(tracks not_allowed)
			(vias allowed)
			(pads allowed)
			(copperpour not_allowed)
			(footprints allowed)
		)
		(placement
			(enabled no)
			(sheetname "")
		)
		(fill yes
			(thermal_gap 0.5)
			(thermal_bridge_width 0.5)
			(island_removal_mode 0)
		)
		(polygon
			(pts
				(arc
					(start 271.899888 -373.44604)
					(mid 277.153878 -378.70003)
					(end 271.899888 -383.95402)
				)
				(arc
					(start 271.899888 -383.72542)
					(mid 276.925278 -378.70003)
					(end 271.899888 -373.67464)
				)
			)
		)
	)
	(zone
		(layers "In2.Cu" "In3.Cu" "In5.Cu" "In7.Cu" "In9.Cu" "In11.Cu" "In15.Cu")
		(hatch none 0.5)
		(connect_pads
			(clearance 0)
		)
		(min_thickness 0.25)
		(keepout
			(tracks not_allowed)
			(vias allowed)
			(pads allowed)
			(copperpour not_allowed)
			(footprints allowed)
		)
		(placement
			(enabled no)
			(sheetname "")
		)
		(fill yes
			(thermal_gap 0.5)
			(thermal_bridge_width 0.5)
			(island_removal_mode 0)
		)
		(polygon
			(pts
				(arc
					(start 271.899888 -373.44604)
					(mid 266.645898 -378.70003)
					(end 271.899888 -383.95402)
				)
				(arc
					(start 271.899888 -383.72542)
					(mid 266.874498 -378.70003)
					(end 271.899888 -373.67464)
				)
			)
		)
	)
	(zone
		(layers "In2.Cu" "In3.Cu" "In5.Cu" "In7.Cu" "In9.Cu" "In13.Cu" "In15.Cu")
		(hatch none 0.5)
		(connect_pads
			(clearance 0)
		)
		(min_thickness 0.25)
		(keepout
			(tracks not_allowed)
			(vias allowed)
			(pads allowed)
			(copperpour not_allowed)
			(footprints allowed)
		)
		(placement
			(enabled no)
			(sheetname "")
		)
		(fill yes
			(thermal_gap 0.5)
			(thermal_bridge_width 0.5)
			(island_removal_mode 0)
		)
		(polygon
			(pts
				(arc
					(start 355.157786 -194.360038)
					(mid 344.642186 -194.360038)
					(end 355.157786 -194.360038)
				)
			)
		)
		(polygon
			(pts
				(arc
					(start 354.929186 -194.360038)
					(mid 344.870786 -194.360038)
					(end 354.929186 -194.360038)
				)
			)
		)
	)
	(zone
		(layers "In2.Cu" "In3.Cu" "In5.Cu" "In7.Cu" "In9.Cu" "In13.Cu" "In15.Cu")
		(hatch none 0.5)
		(connect_pads
			(clearance 0)
		)
		(min_thickness 0.25)
		(keepout
			(tracks not_allowed)
			(vias allowed)
			(pads allowed)
			(copperpour not_allowed)
			(footprints allowed)
		)
		(placement
			(enabled no)
			(sheetname "")
		)
		(fill yes
			(thermal_gap 0.5)
			(thermal_bridge_width 0.5)
			(island_removal_mode 0)
		)
		(polygon
			(pts
				(arc
					(start 326.59955 -270.89989)
					(mid 317.09995 -270.89989)
					(end 326.59955 -270.89989)
				)
			)
		)
		(polygon
			(pts
				(arc
					(start 326.37095 -270.89989)
					(mid 317.32855 -270.89989)
					(end 326.37095 -270.89989)
				)
			)
		)
	)
	(zone
		(layers "In2.Cu" "In3.Cu" "In5.Cu" "In7.Cu" "In11.Cu")
		(hatch none 0.5)
		(connect_pads
			(clearance 0)
		)
		(min_thickness 0.25)
		(keepout
			(tracks not_allowed)
			(vias allowed)
			(pads allowed)
			(copperpour not_allowed)
			(footprints allowed)
		)
		(placement
			(enabled no)
			(sheetname "")
		)
		(fill yes
			(thermal_gap 0.5)
			(thermal_bridge_width 0.5)
			(island_removal_mode 0)
		)
		(polygon
			(pts
				(arc
					(start 210.499452 -320.900044)
					(mid 200.999852 -320.900044)
					(end 210.499452 -320.900044)
				)
			)
		)
		(polygon
			(pts
				(arc
					(start 210.270852 -320.900044)
					(mid 201.228452 -320.900044)
					(end 210.270852 -320.900044)
				)
			)
		)
	)
	(zone
		(layers "In2.Cu" "In3.Cu" "In5.Cu" "In7.Cu" "In11.Cu" "In13.Cu" "In15.Cu")
		(hatch none 0.5)
		(connect_pads
			(clearance 0)
		)
		(min_thickness 0.25)
		(keepout
			(tracks not_allowed)
			(vias allowed)
			(pads allowed)
			(copperpour not_allowed)
			(footprints allowed)
		)
		(placement
			(enabled no)
			(sheetname "")
		)
		(fill yes
			(thermal_gap 0.5)
			(thermal_bridge_width 0.5)
			(island_removal_mode 0)
		)
		(polygon
			(pts
				(arc
					(start 326.59955 -320.900044)
					(mid 317.09995 -320.900044)
					(end 326.59955 -320.900044)
				)
			)
		)
		(polygon
			(pts
				(arc
					(start 326.37095 -320.900044)
					(mid 317.32855 -320.900044)
					(end 326.37095 -320.900044)
				)
			)
		)
	)
	(zone
		(layers "In2.Cu" "In3.Cu" "In5.Cu" "In7.Cu" "In11.Cu" "In13.Cu" "In15.Cu")
		(hatch none 0.5)
		(connect_pads
			(clearance 0)
		)
		(min_thickness 0.25)
		(keepout
			(tracks not_allowed)
			(vias allowed)
			(pads allowed)
			(copperpour not_allowed)
			(footprints allowed)
		)
		(placement
			(enabled no)
			(sheetname "")
		)
		(fill yes
			(thermal_gap 0.5)
			(thermal_bridge_width 0.5)
			(island_removal_mode 0)
		)
		(polygon
			(pts
				(arc
					(start 266.59967 -320.900044)
					(mid 257.10007 -320.900044)
					(end 266.59967 -320.900044)
				)
			)
		)
		(polygon
			(pts
				(arc
					(start 266.37107 -320.900044)
					(mid 257.32867 -320.900044)
					(end 266.37107 -320.900044)
				)
			)
		)
	)
	(zone
		(layers "In2.Cu" "In3.Cu" "In5.Cu" "In7.Cu" "In11.Cu" "In13.Cu" "In15.Cu")
		(hatch none 0.5)
		(connect_pads
			(clearance 0)
		)
		(min_thickness 0.25)
		(keepout
			(tracks not_allowed)
			(vias allowed)
			(pads allowed)
			(copperpour not_allowed)
			(footprints allowed)
		)
		(placement
			(enabled no)
			(sheetname "")
		)
		(fill yes
			(thermal_gap 0.5)
			(thermal_bridge_width 0.5)
			(island_removal_mode 0)
		)
		(polygon
			(pts
				(arc
					(start 34.399474 -320.900044)
					(mid 24.899874 -320.900044)
					(end 34.399474 -320.900044)
				)
			)
		)
		(polygon
			(pts
				(arc
					(start 34.170874 -320.900044)
					(mid 25.128474 -320.900044)
					(end 34.170874 -320.900044)
				)
			)
		)
	)
	(zone
		(layers "In2.Cu" "In3.Cu" "In5.Cu" "In7.Cu" "In13.Cu" "In15.Cu")
		(hatch none 0.5)
		(connect_pads
			(clearance 0)
		)
		(min_thickness 0.25)
		(keepout
			(tracks not_allowed)
			(vias allowed)
			(pads allowed)
			(copperpour not_allowed)
			(footprints allowed)
		)
		(placement
			(enabled no)
			(sheetname "")
		)
		(fill yes
			(thermal_gap 0.5)
			(thermal_bridge_width 0.5)
			(island_removal_mode 0)
		)
		(polygon
			(pts
				(arc
					(start 239.057942 -194.359784)
					(mid 228.542342 -194.359784)
					(end 239.057942 -194.359784)
				)
			)
		)
		(polygon
			(pts
				(arc
					(start 238.829342 -194.359784)
					(mid 228.770942 -194.359784)
					(end 238.829342 -194.359784)
				)
			)
		)
	)
	(zone
		(layers "In2.Cu" "In3.Cu" "In5.Cu" "In9.Cu" "In11.Cu" "In15.Cu")
		(hatch none 0.5)
		(connect_pads
			(clearance 0)
		)
		(min_thickness 0.25)
		(keepout
			(tracks not_allowed)
			(vias allowed)
			(pads allowed)
			(copperpour not_allowed)
			(footprints allowed)
		)
		(placement
			(enabled no)
			(sheetname "")
		)
		(fill yes
			(thermal_gap 0.5)
			(thermal_bridge_width 0.5)
			(island_removal_mode 0)
		)
		(polygon
			(pts
				(arc
					(start 382.699514 -270.89989)
					(mid 373.199914 -270.89989)
					(end 382.699514 -270.89989)
				)
			)
		)
		(polygon
			(pts
				(arc
					(start 382.470914 -270.89989)
					(mid 373.428514 -270.89989)
					(end 382.470914 -270.89989)
				)
			)
		)
	)
	(zone
		(layers "In2.Cu" "In3.Cu" "In5.Cu" "In9.Cu" "In15.Cu")
		(hatch none 0.5)
		(connect_pads
			(clearance 0)
		)
		(min_thickness 0.25)
		(keepout
			(tracks not_allowed)
			(vias allowed)
			(pads allowed)
			(copperpour not_allowed)
			(footprints allowed)
		)
		(placement
			(enabled no)
			(sheetname "")
		)
		(fill yes
			(thermal_gap 0.5)
			(thermal_bridge_width 0.5)
			(island_removal_mode 0)
		)
		(polygon
			(pts
				(arc
					(start 195.699888 -373.44604)
					(mid 190.445898 -378.70003)
					(end 195.699888 -383.95402)
				)
				(arc
					(start 195.699888 -383.72542)
					(mid 190.674498 -378.70003)
					(end 195.699888 -373.67464)
				)
			)
		)
	)
	(zone
		(layers "In2.Cu" "In3.Cu" "In5.Cu" "In9.Cu" "In15.Cu")
		(hatch none 0.5)
		(connect_pads
			(clearance 0)
		)
		(min_thickness 0.25)
		(keepout
			(tracks not_allowed)
			(vias allowed)
			(pads allowed)
			(copperpour not_allowed)
			(footprints allowed)
		)
		(placement
			(enabled no)
			(sheetname "")
		)
		(fill yes
			(thermal_gap 0.5)
			(thermal_bridge_width 0.5)
			(island_removal_mode 0)
		)
		(polygon
			(pts
				(arc
					(start 195.699888 -373.44604)
					(mid 200.953878 -378.70003)
					(end 195.699888 -383.95402)
				)
				(arc
					(start 195.699888 -383.72542)
					(mid 200.725278 -378.70003)
					(end 195.699888 -373.67464)
				)
			)
		)
	)
	(zone
		(layers "In2.Cu" "In3.Cu" "In5.Cu" "In11.Cu" "In15.Cu")
		(hatch none 0.5)
		(connect_pads
			(clearance 0)
		)
		(min_thickness 0.25)
		(keepout
			(tracks not_allowed)
			(vias allowed)
			(pads allowed)
			(copperpour not_allowed)
			(footprints allowed)
		)
		(placement
			(enabled no)
			(sheetname "")
		)
		(fill yes
			(thermal_gap 0.5)
			(thermal_bridge_width 0.5)
			(island_removal_mode 0)
		)
		(polygon
			(pts
				(arc
					(start 150.499572 -270.89989)
					(mid 140.999972 -270.89989)
					(end 150.499572 -270.89989)
				)
			)
		)
		(polygon
			(pts
				(arc
					(start 150.270972 -270.89989)
					(mid 141.228572 -270.89989)
					(end 150.270972 -270.89989)
				)
			)
		)
	)
	(zone
		(layers "In2.Cu" "In3.Cu" "In7.Cu" "In9.Cu" "In11.Cu" "In13.Cu" "In15.Cu")
		(hatch none 0.5)
		(connect_pads
			(clearance 0)
		)
		(min_thickness 0.25)
		(keepout
			(tracks not_allowed)
			(vias allowed)
			(pads allowed)
			(copperpour not_allowed)
			(footprints allowed)
		)
		(placement
			(enabled no)
			(sheetname "")
		)
		(fill yes
			(thermal_gap 0.5)
			(thermal_bridge_width 0.5)
			(island_removal_mode 0)
		)
		(polygon
			(pts
				(arc
					(start 94.399608 -320.900044)
					(mid 84.900008 -320.900044)
					(end 94.399608 -320.900044)
				)
			)
		)
		(polygon
			(pts
				(arc
					(start 94.171008 -320.900044)
					(mid 85.128608 -320.900044)
					(end 94.171008 -320.900044)
				)
			)
		)
	)
	(zone
		(layers "In2.Cu" "In3.Cu" "In7.Cu" "In13.Cu" "In15.Cu")
		(hatch none 0.5)
		(connect_pads
			(clearance 0)
		)
		(min_thickness 0.25)
		(keepout
			(tracks not_allowed)
			(vias allowed)
			(pads allowed)
			(copperpour not_allowed)
			(footprints allowed)
		)
		(placement
			(enabled no)
			(sheetname "")
		)
		(fill yes
			(thermal_gap 0.5)
			(thermal_bridge_width 0.5)
			(island_removal_mode 0)
		)
		(polygon
			(pts
				(arc
					(start 259.299964 -93.446092)
					(mid 264.553954 -98.700082)
					(end 259.299964 -103.954072)
				)
				(arc
					(start 259.299964 -103.725472)
					(mid 264.325354 -98.700082)
					(end 259.299964 -93.674692)
				)
			)
		)
	)
	(zone
		(layers "In2.Cu" "In3.Cu" "In7.Cu" "In13.Cu" "In15.Cu")
		(hatch none 0.5)
		(connect_pads
			(clearance 0)
		)
		(min_thickness 0.25)
		(keepout
			(tracks not_allowed)
			(vias allowed)
			(pads allowed)
			(copperpour not_allowed)
			(footprints allowed)
		)
		(placement
			(enabled no)
			(sheetname "")
		)
		(fill yes
			(thermal_gap 0.5)
			(thermal_bridge_width 0.5)
			(island_removal_mode 0)
		)
		(polygon
			(pts
				(arc
					(start 208.300066 -93.446092)
					(mid 203.046076 -98.700082)
					(end 208.300066 -103.954072)
				)
				(arc
					(start 208.300066 -103.725472)
					(mid 203.274676 -98.700082)
					(end 208.300066 -93.674692)
				)
			)
		)
	)
	(zone
		(layers "In2.Cu" "In3.Cu" "In7.Cu" "In13.Cu" "In15.Cu")
		(hatch none 0.5)
		(connect_pads
			(clearance 0)
		)
		(min_thickness 0.25)
		(keepout
			(tracks not_allowed)
			(vias allowed)
			(pads allowed)
			(copperpour not_allowed)
			(footprints allowed)
		)
		(placement
			(enabled no)
			(sheetname "")
		)
		(fill yes
			(thermal_gap 0.5)
			(thermal_bridge_width 0.5)
			(island_removal_mode 0)
		)
		(polygon
			(pts
				(arc
					(start 208.300066 -93.446092)
					(mid 213.554056 -98.700082)
					(end 208.300066 -103.954072)
				)
				(arc
					(start 208.300066 -103.725472)
					(mid 213.325456 -98.700082)
					(end 208.300066 -93.674692)
				)
			)
		)
	)
	(zone
		(layers "In2.Cu" "In3.Cu" "In7.Cu" "In13.Cu" "In15.Cu")
		(hatch none 0.5)
		(connect_pads
			(clearance 0)
		)
		(min_thickness 0.25)
		(keepout
			(tracks not_allowed)
			(vias allowed)
			(pads allowed)
			(copperpour not_allowed)
			(footprints allowed)
		)
		(placement
			(enabled no)
			(sheetname "")
		)
		(fill yes
			(thermal_gap 0.5)
			(thermal_bridge_width 0.5)
			(island_removal_mode 0)
		)
		(polygon
			(pts
				(arc
					(start 259.299964 -93.446092)
					(mid 254.045974 -98.700082)
					(end 259.299964 -103.954072)
				)
				(arc
					(start 259.299964 -103.725472)
					(mid 254.274574 -98.700082)
					(end 259.299964 -93.674692)
				)
			)
		)
	)
	(zone
		(layers "In2.Cu" "In3.Cu" "In7.Cu" "In13.Cu" "In15.Cu")
		(hatch none 0.5)
		(connect_pads
			(clearance 0)
		)
		(min_thickness 0.25)
		(keepout
			(tracks not_allowed)
			(vias allowed)
			(pads allowed)
			(copperpour not_allowed)
			(footprints allowed)
		)
		(placement
			(enabled no)
			(sheetname "")
		)
		(fill yes
			(thermal_gap 0.5)
			(thermal_bridge_width 0.5)
			(island_removal_mode 0)
		)
		(polygon
			(pts
				(arc
					(start 264.557764 -98.700082)
					(mid 254.042164 -98.700082)
					(end 264.557764 -98.700082)
				)
			)
		)
		(polygon
			(pts
				(arc
					(start 264.329164 -98.700082)
					(mid 254.270764 -98.700082)
					(end 264.329164 -98.700082)
				)
			)
		)
	)
	(zone
		(layers "In2.Cu" "In3.Cu" "In7.Cu" "In13.Cu" "In15.Cu")
		(hatch none 0.5)
		(connect_pads
			(clearance 0)
		)
		(min_thickness 0.25)
		(keepout
			(tracks not_allowed)
			(vias allowed)
			(pads allowed)
			(copperpour not_allowed)
			(footprints allowed)
		)
		(placement
			(enabled no)
			(sheetname "")
		)
		(fill yes
			(thermal_gap 0.5)
			(thermal_bridge_width 0.5)
			(island_removal_mode 0)
		)
		(polygon
			(pts
				(arc
					(start 213.557866 -98.700082)
					(mid 203.042266 -98.700082)
					(end 213.557866 -98.700082)
				)
			)
		)
		(polygon
			(pts
				(arc
					(start 213.329266 -98.700082)
					(mid 203.270866 -98.700082)
					(end 213.329266 -98.700082)
				)
			)
		)
	)
	(zone
		(layers "In2.Cu" "In3.Cu" "In9.Cu" "In13.Cu" "In15.Cu")
		(hatch none 0.5)
		(connect_pads
			(clearance 0)
		)
		(min_thickness 0.25)
		(keepout
			(tracks not_allowed)
			(vias allowed)
			(pads allowed)
			(copperpour not_allowed)
			(footprints allowed)
		)
		(placement
			(enabled no)
			(sheetname "")
		)
		(fill yes
			(thermal_gap 0.5)
			(thermal_bridge_width 0.5)
			(island_removal_mode 0)
		)
		(polygon
			(pts
				(arc
					(start 122.958098 -72.700134)
					(mid 112.442498 -72.700134)
					(end 122.958098 -72.700134)
				)
			)
		)
		(polygon
			(pts
				(arc
					(start 122.729498 -72.700134)
					(mid 112.671098 -72.700134)
					(end 122.729498 -72.700134)
				)
			)
		)
	)
	(zone
		(layers "In2.Cu" "In3.Cu" "In9.Cu" "In15.Cu")
		(hatch none 0.5)
		(connect_pads
			(clearance 0)
		)
		(min_thickness 0.25)
		(keepout
			(tracks not_allowed)
			(vias allowed)
			(pads allowed)
			(copperpour not_allowed)
			(footprints allowed)
		)
		(placement
			(enabled no)
			(sheetname "")
		)
		(fill yes
			(thermal_gap 0.5)
			(thermal_bridge_width 0.5)
			(island_removal_mode 0)
		)
		(polygon
			(pts
				(arc
					(start 115.27282 -17.999964)
					(mid 104.75722 -17.999964)
					(end 115.27282 -17.999964)
				)
			)
		)
		(polygon
			(pts
				(arc
					(start 115.04422 -17.999964)
					(mid 104.98582 -17.999964)
					(end 115.04422 -17.999964)
				)
			)
		)
	)
	(zone
		(layers "In2.Cu" "In3.Cu" "In9.Cu" "In15.Cu")
		(hatch none 0.5)
		(connect_pads
			(clearance 0)
		)
		(min_thickness 0.25)
		(keepout
			(tracks not_allowed)
			(vias allowed)
			(pads allowed)
			(copperpour not_allowed)
			(footprints allowed)
		)
		(placement
			(enabled no)
			(sheetname "")
		)
		(fill yes
			(thermal_gap 0.5)
			(thermal_bridge_width 0.5)
			(island_removal_mode 0)
		)
		(polygon
			(pts
				(arc
					(start 454.057766 -84.699856)
					(mid 443.542166 -84.699856)
					(end 454.057766 -84.699856)
				)
			)
		)
		(polygon
			(pts
				(arc
					(start 453.829166 -84.699856)
					(mid 443.770766 -84.699856)
					(end 453.829166 -84.699856)
				)
			)
		)
	)
	(zone
		(layers "In2.Cu" "In3.Cu" "In9.Cu" "In15.Cu")
		(hatch none 0.5)
		(connect_pads
			(clearance 0)
		)
		(min_thickness 0.25)
		(keepout
			(tracks not_allowed)
			(vias allowed)
			(pads allowed)
			(copperpour not_allowed)
			(footprints allowed)
		)
		(placement
			(enabled no)
			(sheetname "")
		)
		(fill yes
			(thermal_gap 0.5)
			(thermal_bridge_width 0.5)
			(island_removal_mode 0)
		)
		(polygon
			(pts
				(arc
					(start 204.657706 -393.100052)
					(mid 194.142106 -393.100052)
					(end 204.657706 -393.100052)
				)
			)
		)
		(polygon
			(pts
				(arc
					(start 204.429106 -393.100052)
					(mid 194.370706 -393.100052)
					(end 204.429106 -393.100052)
				)
			)
		)
	)
	(zone
		(layers "In2.Cu" "In3.Cu" "In9.Cu" "In15.Cu")
		(hatch none 0.5)
		(connect_pads
			(clearance 0)
		)
		(min_thickness 0.25)
		(keepout
			(tracks not_allowed)
			(vias allowed)
			(pads allowed)
			(copperpour not_allowed)
			(footprints allowed)
		)
		(placement
			(enabled no)
			(sheetname "")
		)
		(fill yes
			(thermal_gap 0.5)
			(thermal_bridge_width 0.5)
			(island_removal_mode 0)
		)
		(polygon
			(pts
				(arc
					(start 355.157786 -72.69988)
					(mid 344.642186 -72.69988)
					(end 355.157786 -72.69988)
				)
			)
		)
		(polygon
			(pts
				(arc
					(start 354.929186 -72.69988)
					(mid 344.870786 -72.69988)
					(end 354.929186 -72.69988)
				)
			)
		)
	)
	(zone
		(layers "In2.Cu" "In3.Cu" "In9.Cu" "In15.Cu")
		(hatch none 0.5)
		(connect_pads
			(clearance 0)
		)
		(min_thickness 0.25)
		(keepout
			(tracks not_allowed)
			(vias allowed)
			(pads allowed)
			(copperpour not_allowed)
			(footprints allowed)
		)
		(placement
			(enabled no)
			(sheetname "")
		)
		(fill yes
			(thermal_gap 0.5)
			(thermal_bridge_width 0.5)
			(island_removal_mode 0)
		)
		(polygon
			(pts
				(arc
					(start 31.222696 -17.999964)
					(mid 20.707096 -17.999964)
					(end 31.222696 -17.999964)
				)
			)
		)
		(polygon
			(pts
				(arc
					(start 30.994096 -17.999964)
					(mid 20.935696 -17.999964)
					(end 30.994096 -17.999964)
				)
			)
		)
	)
	(zone
		(layers "In2.Cu" "In3.Cu" "In13.Cu" "In15.Cu")
		(hatch none 0.5)
		(connect_pads
			(clearance 0)
		)
		(min_thickness 0.25)
		(keepout
			(tracks not_allowed)
			(vias allowed)
			(pads allowed)
			(copperpour not_allowed)
			(footprints allowed)
		)
		(placement
			(enabled no)
			(sheetname "")
		)
		(fill yes
			(thermal_gap 0.5)
			(thermal_bridge_width 0.5)
			(island_removal_mode 0)
		)
		(polygon
			(pts
				(arc
					(start 122.957844 -194.360038)
					(mid 112.442244 -194.360038)
					(end 122.957844 -194.360038)
				)
			)
		)
		(polygon
			(pts
				(arc
					(start 122.729244 -194.360038)
					(mid 112.670844 -194.360038)
					(end 122.729244 -194.360038)
				)
			)
		)
	)
	(zone
		(layers "In2.Cu" "In3.Cu" "In15.Cu")
		(hatch none 0.5)
		(connect_pads
			(clearance 0)
		)
		(min_thickness 0.25)
		(keepout
			(tracks not_allowed)
			(vias allowed)
			(pads allowed)
			(copperpour not_allowed)
			(footprints allowed)
		)
		(placement
			(enabled no)
			(sheetname "")
		)
		(fill yes
			(thermal_gap 0.5)
			(thermal_bridge_width 0.5)
			(island_removal_mode 0)
		)
		(polygon
			(pts
				(arc
					(start 24.057864 -84.699856)
					(mid 13.542264 -84.699856)
					(end 24.057864 -84.699856)
				)
			)
		)
		(polygon
			(pts
				(arc
					(start 23.829264 -84.699856)
					(mid 13.770864 -84.699856)
					(end 23.829264 -84.699856)
				)
			)
		)
	)
	(zone
		(layers "In2.Cu" "In3.Cu" "In15.Cu")
		(hatch none 0.5)
		(connect_pads
			(clearance 0)
		)
		(min_thickness 0.25)
		(keepout
			(tracks not_allowed)
			(vias allowed)
			(pads allowed)
			(copperpour not_allowed)
			(footprints allowed)
		)
		(placement
			(enabled no)
			(sheetname "")
		)
		(fill yes
			(thermal_gap 0.5)
			(thermal_bridge_width 0.5)
			(island_removal_mode 0)
		)
		(polygon
			(pts
				(arc
					(start 109.267752 -407.599896)
					(mid 98.752152 -407.599896)
					(end 109.267752 -407.599896)
				)
			)
		)
		(polygon
			(pts
				(arc
					(start 109.039152 -407.599896)
					(mid 98.980752 -407.599896)
					(end 109.039152 -407.599896)
				)
			)
		)
	)
	(zone
		(layers "In2.Cu" "In3.Cu" "In15.Cu")
		(hatch none 0.5)
		(connect_pads
			(clearance 0)
		)
		(min_thickness 0.25)
		(keepout
			(tracks not_allowed)
			(vias allowed)
			(pads allowed)
			(copperpour not_allowed)
			(footprints allowed)
		)
		(placement
			(enabled no)
			(sheetname "")
		)
		(fill yes
			(thermal_gap 0.5)
			(thermal_bridge_width 0.5)
			(island_removal_mode 0)
		)
		(polygon
			(pts
				(arc
					(start 347.472762 -17.999964)
					(mid 336.957162 -17.999964)
					(end 347.472762 -17.999964)
				)
			)
		)
		(polygon
			(pts
				(arc
					(start 347.244162 -17.999964)
					(mid 337.185762 -17.999964)
					(end 347.244162 -17.999964)
				)
			)
		)
	)
	(zone
		(layers "In2.Cu" "In3.Cu" "In15.Cu")
		(hatch none 0.5)
		(connect_pads
			(clearance 0)
		)
		(min_thickness 0.25)
		(keepout
			(tracks not_allowed)
			(vias allowed)
			(pads allowed)
			(copperpour not_allowed)
			(footprints allowed)
		)
		(placement
			(enabled no)
			(sheetname "")
		)
		(fill yes
			(thermal_gap 0.5)
			(thermal_bridge_width 0.5)
			(island_removal_mode 0)
		)
		(polygon
			(pts
				(arc
					(start 21.05787 -194.360038)
					(mid 10.54227 -194.360038)
					(end 21.05787 -194.360038)
				)
			)
		)
		(polygon
			(pts
				(arc
					(start 20.82927 -194.360038)
					(mid 10.77087 -194.360038)
					(end 20.82927 -194.360038)
				)
			)
		)
	)
	(zone
		(layer "In5.Cu")
		(hatch none 0.5)
		(connect_pads
			(clearance 0)
		)
		(min_thickness 0.25)
		(keepout
			(tracks allowed)
			(vias allowed)
			(pads allowed)
			(copperpour allowed)
			(footprints allowed)
		)
		(placement
			(enabled no)
			(sheetname "")
		)
		(fill
			(thermal_gap 0.5)
			(thermal_bridge_width 0.5)
			(island_removal_mode 0)
		)
		(polygon
			(pts
				(xy 32.6898 -300.8884) (xy 32.6898 -303.2252) (xy 33.4518 -303.9872) (xy 33.4518 -306.7558) (xy 34.798 -308.102)
				(xy 35.306 -308.102) (xy 35.56 -307.848) (xy 35.56 -300.9646) (xy 35.306 -300.7106) (xy 32.8676 -300.7106)
			)
		)
	)
	(zone
		(layer "In5.Cu")
		(hatch none 0.5)
		(connect_pads
			(clearance 0)
		)
		(min_thickness 0.25)
		(keepout
			(tracks allowed)
			(vias allowed)
			(pads allowed)
			(copperpour allowed)
			(footprints allowed)
		)
		(placement
			(enabled no)
			(sheetname "")
		)
		(fill
			(thermal_gap 0.5)
			(thermal_bridge_width 0.5)
			(island_removal_mode 0)
		)
		(polygon
			(pts
				(xy 431.7746 -309.118) (xy 431.7746 -305.308) (xy 432.5366 -304.546) (xy 433.6542 -304.546) (xy 434.0352 -304.927)
				(xy 434.0352 -308.7116) (xy 433.5018 -309.245) (xy 431.9016 -309.245)
			)
		)
	)
	(zone
		(layer "In5.Cu")
		(hatch none 0.5)
		(connect_pads
			(clearance 0)
		)
		(min_thickness 0.25)
		(keepout
			(tracks allowed)
			(vias allowed)
			(pads allowed)
			(copperpour allowed)
			(footprints allowed)
		)
		(placement
			(enabled no)
			(sheetname "")
		)
		(fill
			(thermal_gap 0.5)
			(thermal_bridge_width 0.5)
			(island_removal_mode 0)
		)
		(polygon
			(pts
				(xy 174.394622 -323.207126)
				(arc
					(start 172.62475 -323.207126)
					(mid 172.588829 -323.192247)
					(end 172.57395 -323.156326)
				)
				(xy 172.57395 -320.123566) (xy 174.445422 -320.123566) (xy 179.966366 -320.123566) (xy 181.3052 -321.4624)
				(xy 181.3052 -324.3072) (xy 181.1782 -324.4342) (xy 180.6194 -324.4342) (xy 180.4416 -324.2564)
				(xy 177.3428 -324.2564) (xy 176.293526 -323.207126)
			)
		)
	)
	(zone
		(layer "In5.Cu")
		(hatch none 0.5)
		(connect_pads
			(clearance 0)
		)
		(min_thickness 0.25)
		(keepout
			(tracks allowed)
			(vias allowed)
			(pads allowed)
			(copperpour allowed)
			(footprints allowed)
		)
		(placement
			(enabled no)
			(sheetname "")
		)
		(fill
			(thermal_gap 0.5)
			(thermal_bridge_width 0.5)
			(island_removal_mode 0)
		)
		(polygon
			(pts
				(xy 291.585142 -271.6784) (xy 312.667142 -271.6784) (xy 313.225942 -271.1196) (xy 313.225942 -269.7226)
				(xy 312.463942 -268.9606) (xy 306.875942 -268.9606) (xy 304.658776 -266.743434) (xy 291.102542 -269.203678)
				(xy 291.102542 -271.1958)
			)
		)
	)
	(zone
		(layer "In5.Cu")
		(hatch none 0.5)
		(connect_pads
			(clearance 0)
		)
		(min_thickness 0.25)
		(keepout
			(tracks allowed)
			(vias allowed)
			(pads allowed)
			(copperpour allowed)
			(footprints allowed)
		)
		(placement
			(enabled no)
			(sheetname "")
		)
		(fill
			(thermal_gap 0.5)
			(thermal_bridge_width 0.5)
			(island_removal_mode 0)
		)
		(polygon
			(pts
				(xy 432.32324 -288.5186) (xy 434.63464 -288.5186) (xy 435.14264 -288.0106) (xy 435.14264 -286.9438)
				(xy 432.57724 -280.5684) (xy 432.22164 -280.5684) (xy 432.14544 -280.6446) (xy 432.14544 -288.3408)
			)
		)
	)
	(zone
		(layer "In5.Cu")
		(hatch none 0.5)
		(connect_pads
			(clearance 0)
		)
		(min_thickness 0.25)
		(keepout
			(tracks allowed)
			(vias allowed)
			(pads allowed)
			(copperpour allowed)
			(footprints allowed)
		)
		(placement
			(enabled no)
			(sheetname "")
		)
		(fill
			(thermal_gap 0.5)
			(thermal_bridge_width 0.5)
			(island_removal_mode 0)
		)
		(polygon
			(pts
				(xy 407.68524 -271.6784) (xy 428.76724 -271.6784) (xy 429.32604 -271.1196) (xy 429.32604 -269.7226)
				(xy 428.56404 -268.9606) (xy 422.97604 -268.9606) (xy 420.758874 -266.743434) (xy 407.20264 -269.203678)
				(xy 407.20264 -271.1958)
			)
		)
	)
	(zone
		(layer "In5.Cu")
		(hatch none 0.5)
		(connect_pads
			(clearance 0)
		)
		(min_thickness 0.25)
		(keepout
			(tracks allowed)
			(vias allowed)
			(pads allowed)
			(copperpour allowed)
			(footprints allowed)
		)
		(placement
			(enabled no)
			(sheetname "")
		)
		(fill
			(thermal_gap 0.5)
			(thermal_bridge_width 0.5)
			(island_removal_mode 0)
		)
		(polygon
			(pts
				(xy 175.485298 -271.6784) (xy 196.567298 -271.6784) (xy 197.126098 -271.1196) (xy 197.126098 -269.7226)
				(xy 196.364098 -268.9606) (xy 190.776098 -268.9606) (xy 188.558932 -266.743434) (xy 175.002698 -269.203678)
				(xy 175.002698 -271.1958)
			)
		)
	)
	(zone
		(layer "In5.Cu")
		(hatch none 0.5)
		(connect_pads
			(clearance 0)
		)
		(min_thickness 0.25)
		(keepout
			(tracks allowed)
			(vias allowed)
			(pads allowed)
			(copperpour allowed)
			(footprints allowed)
		)
		(placement
			(enabled no)
			(sheetname "")
		)
		(fill
			(thermal_gap 0.5)
			(thermal_bridge_width 0.5)
			(island_removal_mode 0)
		)
		(polygon
			(pts
				(xy 406.594564 -323.207126) (xy 404.824692 -323.207126) (xy 399.000726 -323.207126) (xy 398.0434 -322.2498)
				(xy 398.0434 -320.3956) (xy 398.315434 -320.123566) (xy 404.773892 -320.123566) (xy 406.645364 -320.123566)
				(xy 412.681166 -320.123566) (xy 413.1564 -320.5988) (xy 413.1564 -323.6722) (xy 412.8008 -324.0278)
				(xy 410.083 -324.0278) (xy 409.262326 -323.207126)
			)
		)
	)
	(zone
		(layer "In5.Cu")
		(hatch none 0.5)
		(connect_pads
			(clearance 0)
		)
		(min_thickness 0.25)
		(keepout
			(tracks allowed)
			(vias allowed)
			(pads allowed)
			(copperpour allowed)
			(footprints allowed)
		)
		(placement
			(enabled no)
			(sheetname "")
		)
		(fill
			(thermal_gap 0.5)
			(thermal_bridge_width 0.5)
			(island_removal_mode 0)
		)
		(polygon
			(pts
				(xy 233.7562 -219.075) (xy 235.8136 -219.075) (xy 236.1438 -219.4052) (xy 236.1438 -219.6846) (xy 235.7374 -220.091)
				(xy 235.1024 -220.091) (xy 234.8484 -220.345) (xy 234.8484 -222.5294) (xy 235.6358 -223.3168) (xy 235.6358 -224.9932)
				(xy 235.5596 -225.0694) (xy 234.0102 -225.0694) (xy 233.807 -224.8662) (xy 233.807 -223.8756) (xy 233.172 -223.2406)
				(xy 231.394 -223.2406) (xy 231.3432 -223.2914) (xy 231.3432 -222.3008) (xy 231.5718 -222.0722) (xy 234.3404 -222.0722)
				(xy 234.3658 -222.0976) (xy 234.3658 -220.0656) (xy 233.7562 -219.456)
			)
		)
	)
	(zone
		(layer "In5.Cu")
		(hatch none 0.5)
		(connect_pads
			(clearance 0)
		)
		(min_thickness 0.25)
		(keepout
			(tracks allowed)
			(vias allowed)
			(pads allowed)
			(copperpour allowed)
			(footprints allowed)
		)
		(placement
			(enabled no)
			(sheetname "")
		)
		(fill
			(thermal_gap 0.5)
			(thermal_bridge_width 0.5)
			(island_removal_mode 0)
		)
		(polygon
			(pts
				(xy 298.704 -320.1162) (xy 304.0888 -320.1162) (xy 304.3936 -320.421) (xy 304.3936 -320.5988) (xy 303.0728 -321.9196)
				(xy 298.5008 -321.9196) (xy 298.5008 -320.3194)
			)
		)
	)
	(zone
		(layer "In5.Cu")
		(hatch none 0.5)
		(connect_pads
			(clearance 0)
		)
		(min_thickness 0.25)
		(keepout
			(tracks allowed)
			(vias allowed)
			(pads allowed)
			(copperpour allowed)
			(footprints allowed)
		)
		(placement
			(enabled no)
			(sheetname "")
		)
		(fill
			(thermal_gap 0.5)
			(thermal_bridge_width 0.5)
			(island_removal_mode 0)
		)
		(polygon
			(pts
				(xy 59.3852 -271.6784) (xy 80.4672 -271.6784) (xy 81.026 -271.1196) (xy 81.026 -269.7226) (xy 80.264 -268.9606)
				(xy 74.676 -268.9606) (xy 72.458834 -266.743434) (xy 58.9026 -269.203678) (xy 58.9026 -271.1958)
			)
		)
	)
	(zone
		(layer "In5.Cu")
		(hatch none 0.5)
		(connect_pads
			(clearance 0)
		)
		(min_thickness 0.25)
		(keepout
			(tracks allowed)
			(vias allowed)
			(pads allowed)
			(copperpour allowed)
			(footprints allowed)
		)
		(placement
			(enabled no)
			(sheetname "")
		)
		(fill
			(thermal_gap 0.5)
			(thermal_bridge_width 0.5)
			(island_removal_mode 0)
		)
		(polygon
			(pts
				(xy 41.37787 -320.013584) (xy 42.726356 -320.013584) (xy 49.808384 -320.013584) (xy 50.0126 -320.2178)
				(xy 50.0126 -321.2084) (xy 49.9364 -321.2846) (xy 48.8188 -321.2846) (xy 48.6156 -321.4878) (xy 48.6156 -321.5894)
				(xy 48.2092 -321.9958) (xy 47.3202 -321.9958) (xy 46.4566 -322.8594) (xy 44.704 -322.8594) (xy 44.200572 -323.362828)
				(xy 42.9514 -324.612) (xy 41.8338 -324.612) (xy 41.275 -325.1708) (xy 40.8178 -325.1708) (xy 40.3606 -325.628)
				(xy 40.3606 -325.755) (xy 39.8272 -325.755) (xy 39.8018 -325.7296) (xy 39.5478 -325.9836) (xy 39.5478 -326.3138)
				(xy 39.4716 -326.39) (xy 38.1 -326.39) (xy 37.5158 -325.8058) (xy 37.5158 -321.5132) (xy 37.1348 -321.1322)
				(xy 37.1348 -320.2432) (xy 37.364416 -320.013584)
			)
		)
	)
	(zone
		(layer "In5.Cu")
		(hatch none 0.5)
		(connect_pads
			(clearance 0)
		)
		(min_thickness 0.25)
		(keepout
			(tracks allowed)
			(vias allowed)
			(pads allowed)
			(copperpour allowed)
			(footprints allowed)
		)
		(placement
			(enabled no)
			(sheetname "")
		)
		(fill
			(thermal_gap 0.5)
			(thermal_bridge_width 0.5)
			(island_removal_mode 0)
		)
		(polygon
			(pts
				(xy 316.023498 -352.404934) (xy 357.515922 -352.404934) (xy 357.986584 -351.934272) (xy 357.986584 -342.698832)
				(xy 357.986584 -342.118696) (xy 357.484934 -341.617046) (xy 314.642754 -341.617046) (xy 314.611258 -341.648542)
				(xy 314.611258 -342.250522) (xy 314.611258 -350.992694)
			)
		)
	)
	(zone
		(layer "In5.Cu")
		(hatch none 0.5)
		(connect_pads
			(clearance 0)
		)
		(min_thickness 0.25)
		(keepout
			(tracks allowed)
			(vias allowed)
			(pads allowed)
			(copperpour allowed)
			(footprints allowed)
		)
		(placement
			(enabled no)
			(sheetname "")
		)
		(fill
			(thermal_gap 0.5)
			(thermal_bridge_width 0.5)
			(island_removal_mode 0)
		)
		(polygon
			(pts
				(xy 359.942638 -352.404934) (xy 401.435062 -352.404934) (xy 401.905724 -351.934272) (xy 401.905724 -342.698832)
				(xy 401.905724 -342.118696) (xy 401.404074 -341.617046) (xy 358.561894 -341.617046) (xy 358.530398 -341.648542)
				(xy 358.530398 -342.250522) (xy 358.530398 -350.992694)
			)
		)
	)
	(zone
		(layer "In5.Cu")
		(hatch none 0.5)
		(connect_pads
			(clearance 0)
		)
		(min_thickness 0.25)
		(keepout
			(tracks allowed)
			(vias allowed)
			(pads allowed)
			(copperpour allowed)
			(footprints allowed)
		)
		(placement
			(enabled no)
			(sheetname "")
		)
		(fill
			(thermal_gap 0.5)
			(thermal_bridge_width 0.5)
			(island_removal_mode 0)
		)
		(polygon
			(pts
				(xy 84.0232 -288.5186) (xy 86.3346 -288.5186) (xy 86.8426 -288.0106) (xy 86.8426 -286.9438) (xy 84.2772 -280.5684)
				(xy 83.9216 -280.5684) (xy 83.8454 -280.6446) (xy 83.8454 -288.3408)
			)
		)
	)
	(zone
		(layer "In5.Cu")
		(hatch none 0.5)
		(connect_pads
			(clearance 0)
		)
		(min_thickness 0.25)
		(keepout
			(tracks allowed)
			(vias allowed)
			(pads allowed)
			(copperpour allowed)
			(footprints allowed)
		)
		(placement
			(enabled no)
			(sheetname "")
		)
		(fill
			(thermal_gap 0.5)
			(thermal_bridge_width 0.5)
			(island_removal_mode 0)
		)
		(polygon
			(pts
				(xy 334.0608 -211.7344) (xy 335.6356 -211.7344) (xy 336.5246 -212.6234) (xy 348.4372 -212.6234)
				(xy 348.8182 -212.2424) (xy 349.3262 -212.2424) (xy 349.8596 -212.7758) (xy 349.8596 -213.2838)
				(xy 350.1136 -213.5378) (xy 350.1898 -213.5378) (xy 350.266 -213.614) (xy 350.266 -217.7796) (xy 350.6978 -218.2114)
				(xy 350.6978 -218.5162) (xy 350.5962 -218.6178) (xy 349.504 -218.6178) (xy 349.3008 -218.821) (xy 349.3008 -220.472)
				(xy 349.4532 -220.6244) (xy 350.8248 -220.6244) (xy 350.9264 -220.726) (xy 350.9264 -225.8822) (xy 350.2914 -226.5172)
				(xy 343.5096 -226.5172) (xy 343.0524 -226.06) (xy 343.0524 -225.0694) (xy 342.4682 -224.4852) (xy 342.4428 -224.4852)
				(xy 342.3666 -224.409) (xy 342.3666 -222.758) (xy 341.9856 -222.758) (xy 341.8332 -222.9104) (xy 341.8332 -223.266)
				(xy 341.4014 -223.6978) (xy 341.0204 -223.6978) (xy 341.0204 -225.0694) (xy 341.0458 -225.0948)
				(xy 341.0458 -226.06) (xy 340.4616 -226.6442) (xy 336.6008 -226.6442) (xy 335.2292 -225.2726) (xy 335.2292 -220.8022)
				(xy 335.5086 -220.5228) (xy 338.6074 -220.5228) (xy 338.7598 -220.3704) (xy 338.7598 -217.3224)
				(xy 338.3788 -216.9414) (xy 335.6102 -216.9414) (xy 335.2038 -216.535) (xy 335.2038 -214.503) (xy 333.9084 -213.2076)
				(xy 333.9084 -211.8868)
			)
		)
	)
	(zone
		(layer "In5.Cu")
		(hatch none 0.5)
		(connect_pads
			(clearance 0)
		)
		(min_thickness 0.25)
		(keepout
			(tracks allowed)
			(vias allowed)
			(pads allowed)
			(copperpour allowed)
			(footprints allowed)
		)
		(placement
			(enabled no)
			(sheetname "")
		)
		(fill
			(thermal_gap 0.5)
			(thermal_bridge_width 0.5)
			(island_removal_mode 0)
		)
		(polygon
			(pts
				(xy 266.3952 -308.483) (xy 267.4112 -308.483) (xy 267.7922 -308.102) (xy 267.7922 -301.0916) (xy 267.5128 -300.8122)
				(xy 263.8806 -300.8122) (xy 263.6266 -301.0662) (xy 263.6266 -303.3014) (xy 265.6332 -305.308) (xy 265.6332 -307.721)
			)
		)
	)
	(zone
		(layer "In5.Cu")
		(hatch none 0.5)
		(connect_pads
			(clearance 0)
		)
		(min_thickness 0.25)
		(keepout
			(tracks allowed)
			(vias allowed)
			(pads allowed)
			(copperpour allowed)
			(footprints allowed)
		)
		(placement
			(enabled no)
			(sheetname "")
		)
		(fill
			(thermal_gap 0.5)
			(thermal_bridge_width 0.5)
			(island_removal_mode 0)
		)
		(polygon
			(pts
				(xy 405.009604 -352.611944) (xy 446.502028 -352.611944) (xy 446.97269 -352.141282) (xy 446.97269 -342.905842)
				(xy 446.97269 -342.325706) (xy 446.97269 -342.054942) (xy 446.408302 -341.490554) (xy 403.962362 -341.490554)
				(xy 403.62886 -341.824056) (xy 403.597364 -341.855552) (xy 403.597364 -342.457532) (xy 403.597364 -351.199704)
			)
		)
	)
	(zone
		(layer "In5.Cu")
		(hatch none 0.5)
		(connect_pads
			(clearance 0)
		)
		(min_thickness 0.25)
		(keepout
			(tracks not_allowed)
			(vias allowed)
			(pads allowed)
			(copperpour not_allowed)
			(footprints allowed)
		)
		(placement
			(enabled no)
			(sheetname "")
		)
		(fill
			(thermal_gap 0.5)
			(thermal_bridge_width 0.5)
			(island_removal_mode 0)
		)
		(polygon
			(pts
				(arc
					(start 71.63054 -128.638808)
					(mid 72.82434 -127.445008)
					(end 71.63054 -126.251208)
				)
				(arc
					(start 70.28434 -126.251208)
					(mid 69.09054 -127.445008)
					(end 70.28434 -128.638808)
				)
			)
		)
	)
	(zone
		(layer "In5.Cu")
		(hatch none 0.5)
		(connect_pads
			(clearance 0)
		)
		(min_thickness 0.25)
		(keepout
			(tracks allowed)
			(vias allowed)
			(pads allowed)
			(copperpour allowed)
			(footprints allowed)
		)
		(placement
			(enabled no)
			(sheetname "")
		)
		(fill
			(thermal_gap 0.5)
			(thermal_bridge_width 0.5)
			(island_removal_mode 0)
		)
		(polygon
			(pts
				(xy 273.577812 -320.224404) (xy 274.926298 -320.224404) (xy 281.819604 -320.224404) (xy 282.1178 -320.5226)
				(xy 282.1178 -323.3166) (xy 280.924 -324.5104) (xy 273.5326 -324.5104) (xy 271.7038 -326.3392) (xy 269.2908 -326.3392)
				(xy 269.1892 -326.2376) (xy 269.1892 -320.4718) (xy 269.436596 -320.224404)
			)
		)
	)
	(zone
		(layer "In5.Cu")
		(hatch none 0.5)
		(connect_pads
			(clearance 0)
		)
		(min_thickness 0.25)
		(keepout
			(tracks allowed)
			(vias allowed)
			(pads allowed)
			(copperpour allowed)
			(footprints allowed)
		)
		(placement
			(enabled no)
			(sheetname "")
		)
		(fill
			(thermal_gap 0.5)
			(thermal_bridge_width 0.5)
			(island_removal_mode 0)
		)
		(polygon
			(pts
				(xy 200.123298 -288.5186) (xy 202.434698 -288.5186) (xy 202.942698 -288.0106) (xy 202.942698 -286.9438)
				(xy 200.377298 -280.5684) (xy 200.021698 -280.5684) (xy 199.945498 -280.6446) (xy 199.945498 -288.3408)
			)
		)
	)
	(zone
		(layer "In5.Cu")
		(hatch none 0.5)
		(connect_pads
			(clearance 0)
		)
		(min_thickness 0.25)
		(keepout
			(tracks allowed)
			(vias allowed)
			(pads allowed)
			(copperpour allowed)
			(footprints allowed)
		)
		(placement
			(enabled no)
			(sheetname "")
		)
		(fill
			(thermal_gap 0.5)
			(thermal_bridge_width 0.5)
			(island_removal_mode 0)
		)
		(polygon
			(pts
				(xy 239.600232 -225.881946) (xy 239.600232 -224.47504) (xy 241.66703 -224.47504) (xy 241.66703 -225.881946)
			)
		)
	)
	(zone
		(layer "In5.Cu")
		(hatch none 0.5)
		(connect_pads
			(clearance 0)
		)
		(min_thickness 0.25)
		(keepout
			(tracks allowed)
			(vias allowed)
			(pads allowed)
			(copperpour allowed)
			(footprints allowed)
		)
		(placement
			(enabled no)
			(sheetname "")
		)
		(fill
			(thermal_gap 0.5)
			(thermal_bridge_width 0.5)
			(island_removal_mode 0)
		)
		(polygon
			(pts
				(xy 421.513 -319.9384) (xy 427.7868 -319.9384) (xy 427.9646 -320.1162) (xy 427.9646 -324.5866) (xy 427.609 -324.9422)
				(xy 425.958 -324.9422) (xy 422.8338 -321.818) (xy 421.3352 -321.818) (xy 421.3352 -320.1162)
			)
		)
	)
	(zone
		(layer "In5.Cu")
		(hatch none 0.5)
		(connect_pads
			(clearance 0)
		)
		(min_thickness 0.25)
		(keepout
			(tracks allowed)
			(vias allowed)
			(pads allowed)
			(copperpour allowed)
			(footprints allowed)
		)
		(placement
			(enabled no)
			(sheetname "")
		)
		(fill
			(thermal_gap 0.5)
			(thermal_bridge_width 0.5)
			(island_removal_mode 0)
		)
		(polygon
			(pts
				(xy 194.6148 -322.3768) (xy 194.6148 -321.2592) (xy 194.8434 -321.0306) (xy 195.5292 -321.0306)
				(xy 195.7832 -321.2846) (xy 195.7832 -322.2244) (xy 195.6308 -322.3768)
			)
		)
	)
	(zone
		(layer "In5.Cu")
		(hatch none 0.5)
		(connect_pads
			(clearance 0)
		)
		(min_thickness 0.25)
		(keepout
			(tracks allowed)
			(vias allowed)
			(pads allowed)
			(copperpour allowed)
			(footprints allowed)
		)
		(placement
			(enabled no)
			(sheetname "")
		)
		(fill
			(thermal_gap 0.5)
			(thermal_bridge_width 0.5)
			(island_removal_mode 0)
		)
		(polygon
			(pts
				(xy 66.4718 -320.1416) (xy 71.755 -320.1416) (xy 71.8566 -320.2432) (xy 71.8566 -320.3956) (xy 70.485 -321.7672)
				(xy 66.4718 -321.7672)
			)
		)
	)
	(zone
		(layer "In5.Cu")
		(hatch none 0.5)
		(connect_pads
			(clearance 0)
		)
		(min_thickness 0.25)
		(keepout
			(tracks allowed)
			(vias allowed)
			(pads allowed)
			(copperpour allowed)
			(footprints allowed)
		)
		(placement
			(enabled no)
			(sheetname "")
		)
		(fill
			(thermal_gap 0.5)
			(thermal_bridge_width 0.5)
			(island_removal_mode 0)
		)
		(polygon
			(pts
				(xy 316.223142 -288.5186) (xy 318.534542 -288.5186) (xy 319.042542 -288.0106) (xy 319.042542 -286.9438)
				(xy 316.477142 -280.5684) (xy 316.121542 -280.5684) (xy 316.045342 -280.6446) (xy 316.045342 -288.3408)
			)
		)
	)
	(zone
		(layer "In5.Cu")
		(hatch none 0.5)
		(connect_pads
			(clearance 0)
		)
		(min_thickness 0.25)
		(keepout
			(tracks allowed)
			(vias allowed)
			(pads allowed)
			(copperpour allowed)
			(footprints allowed)
		)
		(placement
			(enabled no)
			(sheetname "")
		)
		(fill
			(thermal_gap 0.5)
			(thermal_bridge_width 0.5)
			(island_removal_mode 0)
		)
		(polygon
			(pts
				(xy 268.488668 -352.611944) (xy 309.981092 -352.611944) (xy 310.451754 -352.141282) (xy 310.451754 -342.905842)
				(xy 310.451754 -342.325706) (xy 309.950104 -341.824056) (xy 267.107924 -341.824056) (xy 267.076428 -341.855552)
				(xy 267.076428 -342.457532) (xy 267.076428 -351.199704)
			)
		)
	)
	(zone
		(layers "In5.Cu" "In7.Cu" "In9.Cu" "In11.Cu")
		(hatch none 0.5)
		(connect_pads
			(clearance 0)
		)
		(min_thickness 0.25)
		(keepout
			(tracks not_allowed)
			(vias allowed)
			(pads allowed)
			(copperpour not_allowed)
			(footprints allowed)
		)
		(placement
			(enabled no)
			(sheetname "")
		)
		(fill yes
			(thermal_gap 0.5)
			(thermal_bridge_width 0.5)
			(island_removal_mode 0)
		)
		(polygon
			(pts
				(arc
					(start 76.468224 -139.70508)
					(mid 73.826624 -139.70508)
					(end 76.468224 -139.70508)
				)
			)
		)
	)
	(zone
		(layers "In5.Cu" "In7.Cu" "In9.Cu" "In11.Cu")
		(hatch none 0.5)
		(connect_pads
			(clearance 0)
		)
		(min_thickness 0.25)
		(keepout
			(tracks not_allowed)
			(vias allowed)
			(pads allowed)
			(copperpour not_allowed)
			(footprints allowed)
		)
		(placement
			(enabled no)
			(sheetname "")
		)
		(fill yes
			(thermal_gap 0.5)
			(thermal_bridge_width 0.5)
			(island_removal_mode 0)
		)
		(polygon
			(pts
				(arc
					(start 47.66945 -147.004278)
					(mid 46.34865 -148.325078)
					(end 47.66945 -149.645878)
				)
				(arc
					(start 49.01565 -149.645878)
					(mid 50.33645 -148.325078)
					(end 49.01565 -147.004278)
				)
			)
		)
	)
	(zone
		(layers "In5.Cu" "In7.Cu" "In9.Cu" "In11.Cu")
		(hatch none 0.5)
		(connect_pads
			(clearance 0)
		)
		(min_thickness 0.25)
		(keepout
			(tracks not_allowed)
			(vias allowed)
			(pads allowed)
			(copperpour not_allowed)
			(footprints allowed)
		)
		(placement
			(enabled no)
			(sheetname "")
		)
		(fill yes
			(thermal_gap 0.5)
			(thermal_bridge_width 0.5)
			(island_removal_mode 0)
		)
		(polygon
			(pts
				(arc
					(start 47.66945 -114.374168)
					(mid 46.34865 -115.694968)
					(end 47.66945 -117.015768)
				)
				(arc
					(start 49.01565 -117.015768)
					(mid 50.33645 -115.694968)
					(end 49.01565 -114.374168)
				)
			)
		)
	)
	(zone
		(layers "In5.Cu" "In7.Cu" "In9.Cu" "In11.Cu")
		(hatch none 0.5)
		(connect_pads
			(clearance 0)
		)
		(min_thickness 0.25)
		(keepout
			(tracks not_allowed)
			(vias allowed)
			(pads allowed)
			(copperpour not_allowed)
			(footprints allowed)
		)
		(placement
			(enabled no)
			(sheetname "")
		)
		(fill yes
			(thermal_gap 0.5)
			(thermal_bridge_width 0.5)
			(island_removal_mode 0)
		)
		(polygon
			(pts
				(arc
					(start 76.468224 -107.07497)
					(mid 73.826624 -107.07497)
					(end 76.468224 -107.07497)
				)
			)
		)
	)
	(zone
		(layers "In5.Cu" "In7.Cu" "In9.Cu" "In11.Cu")
		(hatch none 0.5)
		(connect_pads
			(clearance 0)
		)
		(min_thickness 0.25)
		(keepout
			(tracks not_allowed)
			(vias allowed)
			(pads allowed)
			(copperpour not_allowed)
			(footprints allowed)
		)
		(placement
			(enabled no)
			(sheetname "")
		)
		(fill yes
			(thermal_gap 0.5)
			(thermal_bridge_width 0.5)
			(island_removal_mode 0)
		)
		(polygon
			(pts
				(arc
					(start 47.66945 -126.63424)
					(mid 46.34865 -127.95504)
					(end 47.66945 -129.27584)
				)
				(arc
					(start 49.01565 -129.27584)
					(mid 50.33645 -127.95504)
					(end 49.01565 -126.63424)
				)
			)
		)
	)
	(zone
		(layers "In5.Cu" "In7.Cu" "In9.Cu" "In11.Cu")
		(hatch none 0.5)
		(connect_pads
			(clearance 0)
		)
		(min_thickness 0.25)
		(keepout
			(tracks not_allowed)
			(vias allowed)
			(pads allowed)
			(copperpour not_allowed)
			(footprints allowed)
		)
		(placement
			(enabled no)
			(sheetname "")
		)
		(fill yes
			(thermal_gap 0.5)
			(thermal_bridge_width 0.5)
			(island_removal_mode 0)
		)
		(polygon
			(pts
				(arc
					(start 69.098414 -107.07497)
					(mid 66.456814 -107.07497)
					(end 69.098414 -107.07497)
				)
			)
		)
	)
	(zone
		(layers "In5.Cu" "In7.Cu" "In9.Cu" "In11.Cu")
		(hatch none 0.5)
		(connect_pads
			(clearance 0)
		)
		(min_thickness 0.25)
		(keepout
			(tracks not_allowed)
			(vias allowed)
			(pads allowed)
			(copperpour not_allowed)
			(footprints allowed)
		)
		(placement
			(enabled no)
			(sheetname "")
		)
		(fill yes
			(thermal_gap 0.5)
			(thermal_bridge_width 0.5)
			(island_removal_mode 0)
		)
		(polygon
			(pts
				(arc
					(start 47.66945 -160.414208)
					(mid 46.34865 -161.735008)
					(end 47.66945 -163.055808)
				)
				(arc
					(start 49.01565 -163.055808)
					(mid 50.33645 -161.735008)
					(end 49.01565 -160.414208)
				)
			)
		)
	)
	(zone
		(layers "In5.Cu" "In7.Cu" "In9.Cu" "In11.Cu")
		(hatch none 0.5)
		(connect_pads
			(clearance 0)
		)
		(min_thickness 0.25)
		(keepout
			(tracks not_allowed)
			(vias allowed)
			(pads allowed)
			(copperpour not_allowed)
			(footprints allowed)
		)
		(placement
			(enabled no)
			(sheetname "")
		)
		(fill yes
			(thermal_gap 0.5)
			(thermal_bridge_width 0.5)
			(island_removal_mode 0)
		)
		(polygon
			(pts
				(arc
					(start 52.843176 -148.325078)
					(mid 50.201576 -148.325078)
					(end 52.843176 -148.325078)
				)
			)
		)
	)
	(zone
		(layers "In5.Cu" "In7.Cu" "In9.Cu" "In11.Cu")
		(hatch none 0.5)
		(connect_pads
			(clearance 0)
		)
		(min_thickness 0.25)
		(keepout
			(tracks not_allowed)
			(vias allowed)
			(pads allowed)
			(copperpour not_allowed)
			(footprints allowed)
		)
		(placement
			(enabled no)
			(sheetname "")
		)
		(fill yes
			(thermal_gap 0.5)
			(thermal_bridge_width 0.5)
			(island_removal_mode 0)
		)
		(polygon
			(pts
				(arc
					(start 70.28434 -160.414208)
					(mid 68.96354 -161.735008)
					(end 70.28434 -163.055808)
				)
				(arc
					(start 71.63054 -163.055808)
					(mid 72.95134 -161.735008)
					(end 71.63054 -160.414208)
				)
			)
		)
	)
	(zone
		(layers "In5.Cu" "In7.Cu" "In9.Cu" "In11.Cu")
		(hatch none 0.5)
		(connect_pads
			(clearance 0)
		)
		(min_thickness 0.25)
		(keepout
			(tracks not_allowed)
			(vias allowed)
			(pads allowed)
			(copperpour not_allowed)
			(footprints allowed)
		)
		(placement
			(enabled no)
			(sheetname "")
		)
		(fill yes
			(thermal_gap 0.5)
			(thermal_bridge_width 0.5)
			(island_removal_mode 0)
		)
		(polygon
			(pts
				(arc
					(start 45.219366 -148.325078)
					(mid 43.085766 -148.325078)
					(end 45.219366 -148.325078)
				)
			)
		)
	)
	(zone
		(layers "In5.Cu" "In7.Cu" "In9.Cu" "In11.Cu")
		(hatch none 0.5)
		(connect_pads
			(clearance 0)
		)
		(min_thickness 0.25)
		(keepout
			(tracks not_allowed)
			(vias allowed)
			(pads allowed)
			(copperpour not_allowed)
			(footprints allowed)
		)
		(placement
			(enabled no)
			(sheetname "")
		)
		(fill yes
			(thermal_gap 0.5)
			(thermal_bridge_width 0.5)
			(island_removal_mode 0)
		)
		(polygon
			(pts
				(arc
					(start 52.843176 -115.694968)
					(mid 50.201576 -115.694968)
					(end 52.843176 -115.694968)
				)
			)
		)
	)
	(zone
		(layers "In5.Cu" "In7.Cu" "In9.Cu" "In11.Cu")
		(hatch none 0.5)
		(connect_pads
			(clearance 0)
		)
		(min_thickness 0.25)
		(keepout
			(tracks not_allowed)
			(vias allowed)
			(pads allowed)
			(copperpour not_allowed)
			(footprints allowed)
		)
		(placement
			(enabled no)
			(sheetname "")
		)
		(fill yes
			(thermal_gap 0.5)
			(thermal_bridge_width 0.5)
			(island_removal_mode 0)
		)
		(polygon
			(pts
				(arc
					(start 70.28434 -138.38428)
					(mid 68.96354 -139.70508)
					(end 70.28434 -141.02588)
				)
				(arc
					(start 71.63054 -141.02588)
					(mid 72.95134 -139.70508)
					(end 71.63054 -138.38428)
				)
			)
		)
	)
	(zone
		(layers "In5.Cu" "In7.Cu" "In9.Cu" "In11.Cu")
		(hatch none 0.5)
		(connect_pads
			(clearance 0)
		)
		(min_thickness 0.25)
		(keepout
			(tracks not_allowed)
			(vias allowed)
			(pads allowed)
			(copperpour not_allowed)
			(footprints allowed)
		)
		(placement
			(enabled no)
			(sheetname "")
		)
		(fill yes
			(thermal_gap 0.5)
			(thermal_bridge_width 0.5)
			(island_removal_mode 0)
		)
		(polygon
			(pts
				(arc
					(start 45.219366 -115.694968)
					(mid 43.085766 -115.694968)
					(end 45.219366 -115.694968)
				)
			)
		)
	)
	(zone
		(layers "In5.Cu" "In7.Cu" "In9.Cu" "In11.Cu")
		(hatch none 0.5)
		(connect_pads
			(clearance 0)
		)
		(min_thickness 0.25)
		(keepout
			(tracks not_allowed)
			(vias allowed)
			(pads allowed)
			(copperpour not_allowed)
			(footprints allowed)
		)
		(placement
			(enabled no)
			(sheetname "")
		)
		(fill yes
			(thermal_gap 0.5)
			(thermal_bridge_width 0.5)
			(island_removal_mode 0)
		)
		(polygon
			(pts
				(arc
					(start 70.28434 -105.75417)
					(mid 68.96354 -107.07497)
					(end 70.28434 -108.39577)
				)
				(arc
					(start 71.63054 -108.39577)
					(mid 72.95134 -107.07497)
					(end 71.63054 -105.75417)
				)
			)
		)
	)
	(zone
		(layers "In5.Cu" "In7.Cu" "In9.Cu" "In11.Cu")
		(hatch none 0.5)
		(connect_pads
			(clearance 0)
		)
		(min_thickness 0.25)
		(keepout
			(tracks not_allowed)
			(vias allowed)
			(pads allowed)
			(copperpour not_allowed)
			(footprints allowed)
		)
		(placement
			(enabled no)
			(sheetname "")
		)
		(fill yes
			(thermal_gap 0.5)
			(thermal_bridge_width 0.5)
			(island_removal_mode 0)
		)
		(polygon
			(pts
				(arc
					(start 69.098414 -139.70508)
					(mid 66.456814 -139.70508)
					(end 69.098414 -139.70508)
				)
			)
		)
	)
	(zone
		(layer "In7.Cu")
		(hatch none 0.5)
		(connect_pads
			(clearance 0)
		)
		(min_thickness 0.25)
		(keepout
			(tracks allowed)
			(vias allowed)
			(pads allowed)
			(copperpour allowed)
			(footprints allowed)
		)
		(placement
			(enabled no)
			(sheetname "")
		)
		(fill
			(thermal_gap 0.5)
			(thermal_bridge_width 0.5)
			(island_removal_mode 0)
		)
		(polygon
			(pts
				(xy 31.2928 -301.6758) (xy 34.8996 -301.6758) (xy 35.2552 -302.0314) (xy 35.2552 -308.0258) (xy 35.1536 -308.1274)
				(xy 34.3916 -308.1274) (xy 31.2166 -304.9524) (xy 31.2166 -301.752)
			)
		)
	)
	(zone
		(layer "In7.Cu")
		(hatch none 0.5)
		(connect_pads
			(clearance 0)
		)
		(min_thickness 0.25)
		(keepout
			(tracks allowed)
			(vias allowed)
			(pads allowed)
			(copperpour allowed)
			(footprints allowed)
		)
		(placement
			(enabled no)
			(sheetname "")
		)
		(fill
			(thermal_gap 0.5)
			(thermal_bridge_width 0.5)
			(island_removal_mode 0)
		)
		(polygon
			(pts
				(xy 402.682456 -352.556826) (xy 446.538604 -352.556826) (xy 447.1035 -351.99193) (xy 447.1035 -341.945976)
				(xy 446.820036 -341.662512) (xy 401.959572 -341.662512) (xy 401.739354 -341.88273) (xy 401.739354 -351.613724)
			)
		)
	)
	(zone
		(layer "In7.Cu")
		(hatch none 0.5)
		(connect_pads
			(clearance 0)
		)
		(min_thickness 0.25)
		(keepout
			(tracks allowed)
			(vias allowed)
			(pads allowed)
			(copperpour allowed)
			(footprints allowed)
		)
		(placement
			(enabled no)
			(sheetname "")
		)
		(fill
			(thermal_gap 0.5)
			(thermal_bridge_width 0.5)
			(island_removal_mode 0)
		)
		(polygon
			(pts
				(xy 290.2458 -320.167) (xy 303.2252 -320.167) (xy 303.5046 -320.4464) (xy 303.5046 -321.437) (xy 302.6918 -322.2498)
				(xy 296.3672 -322.2498) (xy 294.767 -323.85) (xy 290.3728 -323.85) (xy 290.2458 -323.723)
			)
		)
	)
	(zone
		(layer "In7.Cu")
		(hatch none 0.5)
		(connect_pads
			(clearance 0)
		)
		(min_thickness 0.25)
		(keepout
			(tracks allowed)
			(vias allowed)
			(pads allowed)
			(copperpour allowed)
			(footprints allowed)
		)
		(placement
			(enabled no)
			(sheetname "")
		)
		(fill
			(thermal_gap 0.5)
			(thermal_bridge_width 0.5)
			(island_removal_mode 0)
		)
		(polygon
			(pts
				(xy 273.939 -321.31) (xy 272.8214 -322.4276) (xy 270.9672 -322.4276) (xy 270.2306 -322.4276) (xy 270.1036 -322.3006)
				(xy 270.1036 -320.2178) (xy 270.2052 -320.1162) (xy 274.6502 -320.1162) (xy 274.6756 -320.1416)
				(xy 274.6756 -320.5734)
			)
		)
	)
	(zone
		(layer "In7.Cu")
		(hatch none 0.5)
		(connect_pads
			(clearance 0)
		)
		(min_thickness 0.25)
		(keepout
			(tracks allowed)
			(vias allowed)
			(pads allowed)
			(copperpour allowed)
			(footprints allowed)
		)
		(placement
			(enabled no)
			(sheetname "")
		)
		(fill
			(thermal_gap 0.5)
			(thermal_bridge_width 0.5)
			(island_removal_mode 0)
		)
		(polygon
			(pts
				(xy 42.8498 -271.4752) (xy 58.674 -271.4752) (xy 58.9026 -271.2466) (xy 58.9026 -270.0528) (xy 53.2384 -264.3886)
				(xy 47.9806 -264.3886) (xy 42.6212 -269.748) (xy 42.6212 -271.2466)
			)
		)
	)
	(zone
		(layer "In7.Cu")
		(hatch none 0.5)
		(connect_pads
			(clearance 0)
		)
		(min_thickness 0.25)
		(keepout
			(tracks allowed)
			(vias allowed)
			(pads allowed)
			(copperpour allowed)
			(footprints allowed)
		)
		(placement
			(enabled no)
			(sheetname "")
		)
		(fill
			(thermal_gap 0.5)
			(thermal_bridge_width 0.5)
			(island_removal_mode 0)
		)
		(polygon
			(pts
				(xy 357.494078 -352.501962) (xy 401.350226 -352.501962) (xy 401.915122 -351.937066) (xy 401.915122 -341.891112)
				(xy 401.631658 -341.607648) (xy 356.771194 -341.607648) (xy 356.550976 -341.827866) (xy 356.550976 -351.55886)
			)
		)
	)
	(zone
		(layer "In7.Cu")
		(hatch none 0.5)
		(connect_pads
			(clearance 0)
		)
		(min_thickness 0.25)
		(keepout
			(tracks allowed)
			(vias allowed)
			(pads allowed)
			(copperpour allowed)
			(footprints allowed)
		)
		(placement
			(enabled no)
			(sheetname "")
		)
		(fill
			(thermal_gap 0.5)
			(thermal_bridge_width 0.5)
			(island_removal_mode 0)
		)
		(polygon
			(pts
				(xy 173.9138 -321.3354) (xy 180.0606 -321.3354) (xy 180.5686 -321.8434) (xy 180.5686 -324.5612)
				(xy 180.34 -324.7898) (xy 176.8094 -324.7898) (xy 174.6377 -322.6181) (xy 172.9867 -322.6181) (xy 172.5676 -322.199)
				(xy 172.5676 -321.4878) (xy 172.72 -321.3354)
			)
		)
	)
	(zone
		(layer "In7.Cu")
		(hatch none 0.5)
		(connect_pads
			(clearance 0)
		)
		(min_thickness 0.25)
		(keepout
			(tracks allowed)
			(vias allowed)
			(pads allowed)
			(copperpour allowed)
			(footprints allowed)
		)
		(placement
			(enabled no)
			(sheetname "")
		)
		(fill
			(thermal_gap 0.5)
			(thermal_bridge_width 0.5)
			(island_removal_mode 0)
		)
		(polygon
			(pts
				(xy 275.049742 -271.4752) (xy 290.873942 -271.4752) (xy 291.102542 -271.2466) (xy 291.102542 -270.0528)
				(xy 285.438342 -264.3886) (xy 280.180542 -264.3886) (xy 274.821142 -269.748) (xy 274.821142 -271.2466)
			)
		)
	)
	(zone
		(layer "In7.Cu")
		(hatch none 0.5)
		(connect_pads
			(clearance 0)
		)
		(min_thickness 0.25)
		(keepout
			(tracks allowed)
			(vias allowed)
			(pads allowed)
			(copperpour allowed)
			(footprints allowed)
		)
		(placement
			(enabled no)
			(sheetname "")
		)
		(fill
			(thermal_gap 0.5)
			(thermal_bridge_width 0.5)
			(island_removal_mode 0)
		)
		(polygon
			(pts
				(xy 224.2566 -214.0458) (xy 234.7214 -214.0458) (xy 235.966 -215.2904) (xy 235.966 -223.774) (xy 234.9246 -224.8154)
				(xy 233.9848 -224.8154) (xy 232.1306 -222.9612) (xy 232.1306 -217.7288) (xy 231.0384 -216.6366)
				(xy 224.4598 -216.6366) (xy 224.2566 -216.4334)
			)
		)
	)
	(zone
		(layer "In7.Cu")
		(hatch none 0.5)
		(connect_pads
			(clearance 0)
		)
		(min_thickness 0.25)
		(keepout
			(tracks allowed)
			(vias allowed)
			(pads allowed)
			(copperpour allowed)
			(footprints allowed)
		)
		(placement
			(enabled no)
			(sheetname "")
		)
		(fill
			(thermal_gap 0.5)
			(thermal_bridge_width 0.5)
			(island_removal_mode 0)
		)
		(polygon
			(pts
				(xy 58.0136 -320.2432) (xy 71.628 -320.2432) (xy 71.7804 -320.3956) (xy 71.7804 -320.4718) (xy 66.3702 -325.882)
				(xy 57.8104 -325.882) (xy 57.8104 -320.4464)
			)
		)
	)
	(zone
		(layer "In7.Cu")
		(hatch none 0.5)
		(connect_pads
			(clearance 0)
		)
		(min_thickness 0.25)
		(keepout
			(tracks allowed)
			(vias allowed)
			(pads allowed)
			(copperpour allowed)
			(footprints allowed)
		)
		(placement
			(enabled no)
			(sheetname "")
		)
		(fill
			(thermal_gap 0.5)
			(thermal_bridge_width 0.5)
			(island_removal_mode 0)
		)
		(polygon
			(pts
				(xy 158.949898 -271.4752) (xy 174.774098 -271.4752) (xy 175.002698 -271.2466) (xy 175.002698 -270.0528)
				(xy 169.338498 -264.3886) (xy 164.080698 -264.3886) (xy 158.721298 -269.748) (xy 158.721298 -271.2466)
			)
		)
	)
	(zone
		(layer "In7.Cu")
		(hatch none 0.5)
		(connect_pads
			(clearance 0)
		)
		(min_thickness 0.25)
		(keepout
			(tracks allowed)
			(vias allowed)
			(pads allowed)
			(copperpour allowed)
			(footprints allowed)
		)
		(placement
			(enabled no)
			(sheetname "")
		)
		(fill
			(thermal_gap 0.5)
			(thermal_bridge_width 0.5)
			(island_removal_mode 0)
		)
		(polygon
			(pts
				(xy 315.754766 -352.415094) (xy 357.614982 -352.415094) (xy 358.179878 -351.850198) (xy 358.179878 -341.804244)
				(xy 357.896414 -341.52078) (xy 314.107068 -341.52078) (xy 313.96559 -341.662258) (xy 313.96559 -350.625918)
			)
		)
	)
	(zone
		(layer "In7.Cu")
		(hatch none 0.5)
		(connect_pads
			(clearance 0)
		)
		(min_thickness 0.25)
		(keepout
			(tracks allowed)
			(vias allowed)
			(pads allowed)
			(copperpour allowed)
			(footprints allowed)
		)
		(placement
			(enabled no)
			(sheetname "")
		)
		(fill
			(thermal_gap 0.5)
			(thermal_bridge_width 0.5)
			(island_removal_mode 0)
		)
		(polygon
			(pts
				(xy 266.0142 -305.3842) (xy 266.0142 -300.9138) (xy 266.2936 -300.6344) (xy 267.208 -300.6344) (xy 267.4366 -300.863)
				(xy 267.4366 -305.1048) (xy 267.1572 -305.3842)
			)
		)
	)
	(zone
		(layer "In7.Cu")
		(hatch none 0.5)
		(connect_pads
			(clearance 0)
		)
		(min_thickness 0.25)
		(keepout
			(tracks allowed)
			(vias allowed)
			(pads allowed)
			(copperpour allowed)
			(footprints allowed)
		)
		(placement
			(enabled no)
			(sheetname "")
		)
		(fill
			(thermal_gap 0.5)
			(thermal_bridge_width 0.5)
			(island_removal_mode 0)
		)
		(polygon
			(pts
				(xy 391.14984 -271.4752) (xy 406.97404 -271.4752) (xy 407.20264 -271.2466) (xy 407.20264 -270.0528)
				(xy 401.53844 -264.3886) (xy 396.28064 -264.3886) (xy 390.92124 -269.748) (xy 390.92124 -271.2466)
			)
		)
	)
	(zone
		(layer "In7.Cu")
		(hatch none 0.5)
		(connect_pads
			(clearance 0)
		)
		(min_thickness 0.25)
		(keepout
			(tracks allowed)
			(vias allowed)
			(pads allowed)
			(copperpour allowed)
			(footprints allowed)
		)
		(placement
			(enabled no)
			(sheetname "")
		)
		(fill
			(thermal_gap 0.5)
			(thermal_bridge_width 0.5)
			(island_removal_mode 0)
		)
		(polygon
			(pts
				(xy 266.224004 -352.622104) (xy 310.080152 -352.622104) (xy 310.645048 -352.057208) (xy 310.645048 -342.011254)
				(xy 310.361584 -341.72779) (xy 265.50112 -341.72779) (xy 265.280902 -341.948008) (xy 265.280902 -351.679002)
			)
		)
	)
	(zone
		(layer "In7.Cu")
		(hatch none 0.5)
		(connect_pads
			(clearance 0)
		)
		(min_thickness 0.25)
		(keepout
			(tracks allowed)
			(vias allowed)
			(pads allowed)
			(copperpour allowed)
			(footprints allowed)
		)
		(placement
			(enabled no)
			(sheetname "")
		)
		(fill
			(thermal_gap 0.5)
			(thermal_bridge_width 0.5)
			(island_removal_mode 0)
		)
		(polygon
			(pts
				(xy 432.2064 -307.2384) (xy 432.2064 -304.7746) (xy 432.5366 -304.4444) (xy 432.9176 -304.4444)
				(xy 433.1462 -304.673) (xy 433.1462 -306.959) (xy 432.8668 -307.2384)
			)
		)
	)
	(zone
		(layer "In7.Cu")
		(hatch none 0.5)
		(connect_pads
			(clearance 0)
		)
		(min_thickness 0.25)
		(keepout
			(tracks allowed)
			(vias allowed)
			(pads allowed)
			(copperpour allowed)
			(footprints allowed)
		)
		(placement
			(enabled no)
			(sheetname "")
		)
		(fill
			(thermal_gap 0.5)
			(thermal_bridge_width 0.5)
			(island_removal_mode 0)
		)
		(polygon
			(pts
				(xy 421.2082 -319.9384) (xy 428.4218 -319.9384) (xy 428.9806 -320.4972) (xy 428.9806 -323.1134)
				(xy 423.2148 -323.1134) (xy 422.7576 -322.6562) (xy 420.5732 -322.6562) (xy 420.4716 -322.5546)
				(xy 420.4716 -320.675)
			)
		)
	)
	(zone
		(layer "In7.Cu")
		(hatch none 0.5)
		(connect_pads
			(clearance 0)
		)
		(min_thickness 0.25)
		(keepout
			(tracks allowed)
			(vias allowed)
			(pads allowed)
			(copperpour allowed)
			(footprints allowed)
		)
		(placement
			(enabled no)
			(sheetname "")
		)
		(fill
			(thermal_gap 0.5)
			(thermal_bridge_width 0.5)
			(island_removal_mode 0)
		)
		(polygon
			(pts
				(xy 399.3642 -319.9892) (xy 412.6992 -319.9892) (xy 413.0294 -320.3194) (xy 413.0294 -324.739) (xy 412.496 -325.2724)
				(xy 403.5806 -325.2724) (xy 399.3642 -321.056)
			)
		)
	)
	(zone
		(layer "In7.Cu")
		(hatch none 0.5)
		(connect_pads
			(clearance 0)
		)
		(min_thickness 0.25)
		(keepout
			(tracks allowed)
			(vias allowed)
			(pads allowed)
			(copperpour allowed)
			(footprints allowed)
		)
		(placement
			(enabled no)
			(sheetname "")
		)
		(fill
			(thermal_gap 0.5)
			(thermal_bridge_width 0.5)
			(island_removal_mode 0)
		)
		(polygon
			(pts
				(xy 336.296 -211.6328) (xy 339.979 -211.6328) (xy 340.0806 -211.5312) (xy 340.4108 -211.5312) (xy 340.7664 -211.8868)
				(xy 340.7664 -213.3092) (xy 340.7156 -213.36) (xy 340.7156 -213.868) (xy 341.4776 -214.63) (xy 341.4776 -215.5444)
				(xy 341.6808 -215.7476) (xy 344.3478 -215.7476) (xy 345.1352 -214.9602) (xy 345.1352 -212.3186)
				(xy 345.2622 -212.1916) (xy 348.6912 -212.1916) (xy 349.0214 -212.5218) (xy 349.7326 -212.5218)
				(xy 350.0882 -212.8774) (xy 350.0882 -213.0298) (xy 351.028 -213.9696) (xy 351.5106 -213.9696) (xy 351.536 -213.995)
				(xy 351.536 -224.282) (xy 351.2566 -224.5614) (xy 342.8746 -224.5614) (xy 340.614 -226.822) (xy 335.3562 -226.822)
				(xy 335.026 -226.4918) (xy 335.026 -212.9028)
			)
		)
	)
	(zone
		(layer "In7.Cu")
		(hatch none 0.5)
		(connect_pads
			(clearance 0)
		)
		(min_thickness 0.25)
		(keepout
			(tracks allowed)
			(vias allowed)
			(pads allowed)
			(copperpour allowed)
			(footprints allowed)
		)
		(placement
			(enabled no)
			(sheetname "")
		)
		(fill
			(thermal_gap 0.5)
			(thermal_bridge_width 0.5)
			(island_removal_mode 0)
		)
		(polygon
			(pts
				(xy 194.8434 -322.199) (xy 194.8434 -320.5988) (xy 195.0212 -320.421) (xy 195.4784 -320.421) (xy 195.5292 -320.4718)
				(xy 195.5292 -322.326) (xy 195.5038 -322.3514) (xy 194.9958 -322.3514)
			)
		)
	)
	(zone
		(layer "In7.Cu")
		(hatch none 0.5)
		(connect_pads
			(clearance 0)
		)
		(min_thickness 0.25)
		(keepout
			(tracks allowed)
			(vias allowed)
			(pads allowed)
			(copperpour allowed)
			(footprints allowed)
		)
		(placement
			(enabled no)
			(sheetname "")
		)
		(fill
			(thermal_gap 0.5)
			(thermal_bridge_width 0.5)
			(island_removal_mode 0)
		)
		(polygon
			(pts
				(xy 38.1254 -320.294) (xy 41.3004 -320.294) (xy 41.656 -320.6496) (xy 41.656 -321.9196) (xy 39.878 -323.6976)
				(xy 37.8714 -323.6976) (xy 37.8714 -320.548)
			)
		)
	)
	(zone
		(layers "In7.Cu" "In9.Cu" "In11.Cu")
		(hatch none 0.5)
		(connect_pads
			(clearance 0)
		)
		(min_thickness 0.25)
		(keepout
			(tracks not_allowed)
			(vias allowed)
			(pads allowed)
			(copperpour not_allowed)
			(footprints allowed)
		)
		(placement
			(enabled no)
			(sheetname "")
		)
		(fill yes
			(thermal_gap 0.5)
			(thermal_bridge_width 0.5)
			(island_removal_mode 0)
		)
		(polygon
			(pts
				(arc
					(start 70.28434 -126.124208)
					(mid 68.96354 -127.445008)
					(end 70.28434 -128.765808)
				)
				(arc
					(start 71.63054 -128.765808)
					(mid 72.95134 -127.445008)
					(end 71.63054 -126.124208)
				)
			)
		)
	)
	(zone
		(layers "In7.Cu" "In15.Cu")
		(hatch none 0.5)
		(connect_pads
			(clearance 0)
		)
		(min_thickness 0.25)
		(keepout
			(tracks not_allowed)
			(vias allowed)
			(pads allowed)
			(copperpour not_allowed)
			(footprints allowed)
		)
		(placement
			(enabled no)
			(sheetname "")
		)
		(fill yes
			(thermal_gap 0.5)
			(thermal_bridge_width 0.5)
			(island_removal_mode 0)
		)
		(polygon
			(pts
				(arc
					(start 442.599064 -270.89989)
					(mid 433.300632 -270.89989)
					(end 442.599064 -270.89989)
				)
			)
		)
	)
	(zone
		(layer "Cmts.User")
		(hatch none 0.5)
		(connect_pads
			(clearance 0)
		)
		(min_thickness 0.25)
		(keepout
			(tracks allowed)
			(vias allowed)
			(pads allowed)
			(copperpour allowed)
			(footprints allowed)
		)
		(placement
			(enabled no)
			(sheetname "")
		)
		(fill
			(thermal_gap 0.5)
			(thermal_bridge_width 0.5)
			(island_removal_mode 0)
		)
		(polygon
			(pts
				(xy 418.174932 15.80261) (xy 408.167332 15.80261) (xy 408.167332 21.92401) (xy 418.174932 21.92401)
			)
		)
	)
	(zone
		(layer "Cmts.User")
		(hatch none 0.5)
		(connect_pads
			(clearance 0)
		)
		(min_thickness 0.25)
		(keepout
			(tracks allowed)
			(vias allowed)
			(pads allowed)
			(copperpour allowed)
			(footprints allowed)
		)
		(placement
			(enabled no)
			(sheetname "")
		)
		(fill
			(thermal_gap 0.5)
			(thermal_bridge_width 0.5)
			(island_removal_mode 0)
		)
		(polygon
			(pts
				(xy 197.76694 -321.564) (xy 201.295 -318.03594) (xy 201.295 -272.966942) (xy 199.854058 -271.526)
				(xy 198.584058 -271.526) (xy 175.470058 -271.526) (xy 175.089058 -271.145) (xy 157.436058 -271.145)
				(xy 153.499058 -271.145) (xy 151.848058 -272.796) (xy 151.632666 -273.011392) (xy 151.632666 -271.719548)
				(xy 151.23922 -271.326102) (xy 151.23922 -319.95872) (xy 152.8445 -321.564)
			)
		)
	)
	(zone
		(layer "Cmts.User")
		(hatch none 0.5)
		(connect_pads
			(clearance 0)
		)
		(min_thickness 0.25)
		(keepout
			(tracks allowed)
			(vias allowed)
			(pads allowed)
			(copperpour allowed)
			(footprints allowed)
		)
		(placement
			(enabled no)
			(sheetname "")
		)
		(fill
			(thermal_gap 0.5)
			(thermal_bridge_width 0.5)
			(island_removal_mode 0)
		)
		(polygon
			(pts
				(xy 418.174932 5.91693) (xy 408.167332 5.91693) (xy 408.167332 12.03833) (xy 418.174932 12.03833)
			)
		)
	)
	(zone
		(layer "Cmts.User")
		(hatch none 0.5)
		(connect_pads
			(clearance 0)
		)
		(min_thickness 0.25)
		(keepout
			(tracks allowed)
			(vias allowed)
			(pads allowed)
			(copperpour allowed)
			(footprints allowed)
		)
		(placement
			(enabled no)
			(sheetname "")
		)
		(fill
			(thermal_gap 0.5)
			(thermal_bridge_width 0.5)
			(island_removal_mode 0)
		)
		(polygon
			(pts
				(arc
					(start 332.867 -210.312)
					(mid 332.941395 -210.132395)
					(end 333.121 -210.058)
				)
				(arc
					(start 351.79 -210.058)
					(mid 351.969605 -210.132395)
					(end 352.044 -210.312)
				)
				(arc
					(start 352.044 -228.981)
					(mid 351.969605 -229.160605)
					(end 351.79 -229.235)
				)
				(arc
					(start 333.121 -229.235)
					(mid 332.941395 -229.160605)
					(end 332.867 -228.981)
				)
			)
		)
	)
	(zone
		(layer "Cmts.User")
		(hatch none 0.5)
		(connect_pads
			(clearance 0)
		)
		(min_thickness 0.25)
		(keepout
			(tracks allowed)
			(vias allowed)
			(pads allowed)
			(copperpour allowed)
			(footprints allowed)
		)
		(placement
			(enabled no)
			(sheetname "")
		)
		(fill
			(thermal_gap 0.5)
			(thermal_bridge_width 0.5)
			(island_removal_mode 0)
		)
		(polygon
			(pts
				(xy 438.796176 22.113494) (xy 448.803776 22.113494) (xy 448.803776 15.992094) (xy 438.796176 15.992094)
			)
		)
	)
	(zone
		(layer "Cmts.User")
		(hatch none 0.5)
		(connect_pads
			(clearance 0)
		)
		(min_thickness 0.25)
		(keepout
			(tracks allowed)
			(vias allowed)
			(pads allowed)
			(copperpour allowed)
			(footprints allowed)
		)
		(placement
			(enabled no)
			(sheetname "")
		)
		(fill
			(thermal_gap 0.5)
			(thermal_bridge_width 0.5)
			(island_removal_mode 0)
		)
		(polygon
			(pts
				(xy 222.94342 -225.254566) (xy 222.94342 -212.098128) (xy 236.125258 -212.098128) (xy 236.125258 -225.254566)
			)
		)
	)
	(zone
		(layer "Cmts.User")
		(hatch none 0.5)
		(connect_pads
			(clearance 0)
		)
		(min_thickness 0.25)
		(keepout
			(tracks allowed)
			(vias allowed)
			(pads allowed)
			(copperpour allowed)
			(footprints allowed)
		)
		(placement
			(enabled no)
			(sheetname "")
		)
		(fill
			(thermal_gap 0.5)
			(thermal_bridge_width 0.5)
			(island_removal_mode 0)
		)
		(polygon
			(pts
				(xy 269.95374 14.53261) (xy 259.94614 14.53261) (xy 259.94614 20.65401) (xy 269.95374 20.65401)
			)
		)
	)
	(zone
		(layer "Cmts.User")
		(hatch none 0.5)
		(connect_pads
			(clearance 0)
		)
		(min_thickness 0.25)
		(keepout
			(tracks allowed)
			(vias allowed)
			(pads allowed)
			(copperpour allowed)
			(footprints allowed)
		)
		(placement
			(enabled no)
			(sheetname "")
		)
		(fill
			(thermal_gap 0.5)
			(thermal_bridge_width 0.5)
			(island_removal_mode 0)
		)
		(polygon
			(pts
				(xy 358.611932 15.80261) (xy 348.604332 15.80261) (xy 348.604332 21.92401) (xy 358.611932 21.92401)
			)
		)
	)
	(zone
		(layer "Cmts.User")
		(hatch none 0.5)
		(connect_pads
			(clearance 0)
		)
		(min_thickness 0.25)
		(keepout
			(tracks allowed)
			(vias allowed)
			(pads allowed)
			(copperpour allowed)
			(footprints allowed)
		)
		(placement
			(enabled no)
			(sheetname "")
		)
		(fill
			(thermal_gap 0.5)
			(thermal_bridge_width 0.5)
			(island_removal_mode 0)
		)
		(polygon
			(pts
				(xy 286.503364 4.58089) (xy 276.495764 4.58089) (xy 276.495764 10.70229) (xy 286.503364 10.70229)
			)
		)
	)
	(zone
		(layer "Cmts.User")
		(hatch none 0.5)
		(connect_pads
			(clearance 0)
		)
		(min_thickness 0.25)
		(keepout
			(tracks allowed)
			(vias allowed)
			(pads allowed)
			(copperpour allowed)
			(footprints allowed)
		)
		(placement
			(enabled no)
			(sheetname "")
		)
		(fill
			(thermal_gap 0.5)
			(thermal_bridge_width 0.5)
			(island_removal_mode 0)
		)
		(polygon
			(pts
				(xy 48.57496 -320.294) (xy 81.72196 -320.294) (xy 82.936842 -320.294) (xy 84.13496 -319.095882)
				(xy 84.13496 -316.484) (xy 84.13496 -271.907) (xy 83.75396 -271.526) (xy 82.48396 -271.526) (xy 59.36996 -271.526)
				(xy 58.98896 -271.145) (xy 41.33596 -271.145) (xy 37.39896 -271.145) (xy 35.74796 -272.796) (xy 35.532568 -273.011392)
				(xy 35.532568 -271.719548) (xy 35.139122 -271.326102) (xy 35.139122 -319.95872) (xy 35.474402 -320.294)
				(xy 36.014406 -320.294) (xy 36.50996 -320.294)
			)
		)
	)
	(zone
		(layer "Cmts.User")
		(hatch none 0.5)
		(connect_pads
			(clearance 0)
		)
		(min_thickness 0.25)
		(keepout
			(tracks allowed)
			(vias allowed)
			(pads allowed)
			(copperpour allowed)
			(footprints allowed)
		)
		(placement
			(enabled no)
			(sheetname "")
		)
		(fill
			(thermal_gap 0.5)
			(thermal_bridge_width 0.5)
			(island_removal_mode 0)
		)
		(polygon
			(pts
				(xy 379.233176 22.113494) (xy 389.240776 22.113494) (xy 389.240776 15.992094) (xy 379.233176 15.992094)
			)
		)
	)
	(zone
		(layer "Cmts.User")
		(hatch none 0.5)
		(connect_pads
			(clearance 0)
		)
		(min_thickness 0.25)
		(keepout
			(tracks allowed)
			(vias allowed)
			(pads allowed)
			(copperpour allowed)
			(footprints allowed)
		)
		(placement
			(enabled no)
			(sheetname "")
		)
		(fill
			(thermal_gap 0.5)
			(thermal_bridge_width 0.5)
			(island_removal_mode 0)
		)
		(polygon
			(pts
				(xy 396.875 -320.294) (xy 430.022 -320.294) (xy 431.236882 -320.294) (xy 432.435 -319.095882) (xy 432.435 -316.484)
				(xy 432.435 -271.907) (xy 432.054 -271.526) (xy 430.784 -271.526) (xy 407.67 -271.526) (xy 407.289 -271.145)
				(xy 389.636 -271.145) (xy 385.699 -271.145) (xy 384.048 -272.796) (xy 383.832608 -273.011392) (xy 383.832608 -271.719548)
				(xy 383.439162 -271.326102) (xy 383.439162 -319.95872) (xy 383.774442 -320.294) (xy 384.314446 -320.294)
				(xy 384.81 -320.294)
			)
		)
	)
	(zone
		(layer "Cmts.User")
		(hatch none 0.5)
		(connect_pads
			(clearance 0)
		)
		(min_thickness 0.25)
		(keepout
			(tracks allowed)
			(vias allowed)
			(pads allowed)
			(copperpour allowed)
			(footprints allowed)
		)
		(placement
			(enabled no)
			(sheetname "")
		)
		(fill
			(thermal_gap 0.5)
			(thermal_bridge_width 0.5)
			(island_removal_mode 0)
		)
		(polygon
			(pts
				(xy 232.477564 6.847332) (xy 232.477564 9.258554) (xy 235.0897 9.258554) (xy 235.0897 6.847332)
			)
		)
	)
	(zone
		(layer "Cmts.User")
		(hatch none 0.5)
		(connect_pads
			(clearance 0)
		)
		(min_thickness 0.25)
		(keepout
			(tracks allowed)
			(vias allowed)
			(pads allowed)
			(copperpour allowed)
			(footprints allowed)
		)
		(placement
			(enabled no)
			(sheetname "")
		)
		(fill
			(thermal_gap 0.5)
			(thermal_bridge_width 0.5)
			(island_removal_mode 0)
		)
		(polygon
			(pts
				(xy 280.774902 -320.294) (xy 313.921902 -320.294) (xy 315.136784 -320.294) (xy 316.334902 -319.095882)
				(xy 316.334902 -316.484) (xy 316.334902 -271.907) (xy 315.953902 -271.526) (xy 314.683902 -271.526)
				(xy 291.569902 -271.526) (xy 291.188902 -271.145) (xy 273.535902 -271.145) (xy 269.598902 -271.145)
				(xy 267.947902 -272.796) (xy 267.73251 -273.011392) (xy 267.73251 -271.719548) (xy 267.339064 -271.326102)
				(xy 267.339064 -319.95872) (xy 267.674344 -320.294) (xy 268.214348 -320.294) (xy 268.709902 -320.294)
			)
		)
	)
	(zone
		(layer "Cmts.User")
		(hatch none 0.5)
		(connect_pads
			(clearance 0)
		)
		(min_thickness 0.25)
		(keepout
			(tracks allowed)
			(vias allowed)
			(pads allowed)
			(copperpour allowed)
			(footprints allowed)
		)
		(placement
			(enabled no)
			(sheetname "")
		)
		(fill
			(thermal_gap 0.5)
			(thermal_bridge_width 0.5)
			(island_removal_mode 0)
		)
		(polygon
			(pts
				(xy 229.182168 20.843494) (xy 239.189768 20.843494) (xy 239.189768 14.722094) (xy 229.182168 14.722094)
			)
		)
	)
	(zone
		(layer "Cmts.User")
		(hatch none 0.5)
		(connect_pads
			(clearance 0)
		)
		(min_thickness 0.25)
		(keepout
			(tracks allowed)
			(vias allowed)
			(pads allowed)
			(copperpour allowed)
			(footprints allowed)
		)
		(placement
			(enabled no)
			(sheetname "")
		)
		(fill
			(thermal_gap 0.5)
			(thermal_bridge_width 0.5)
			(island_removal_mode 0)
		)
		(polygon
			(pts
				(xy 335.7626 12.194794) (xy 345.7702 12.194794) (xy 345.7702 6.073394) (xy 335.7626 6.073394)
			)
		)
	)
	(zone
		(layer "Cmts.User")
		(hatch none 0.5)
		(connect_pads
			(clearance 0)
		)
		(min_thickness 0.25)
		(keepout
			(tracks allowed)
			(vias allowed)
			(pads allowed)
			(copperpour allowed)
			(footprints allowed)
		)
		(placement
			(enabled no)
			(sheetname "")
		)
		(fill
			(thermal_gap 0.5)
			(thermal_bridge_width 0.5)
			(island_removal_mode 0)
		)
		(polygon
			(pts
				(xy 455.3966 12.260834) (xy 465.4042 12.260834) (xy 465.4042 6.139434) (xy 455.3966 6.139434)
			)
		)
	)
	(zone
		(layer "Cmts.User")
		(hatch none 0.5)
		(connect_pads
			(clearance 0)
		)
		(min_thickness 0.25)
		(keepout
			(tracks allowed)
			(vias allowed)
			(pads allowed)
			(copperpour allowed)
			(footprints allowed)
		)
		(placement
			(enabled no)
			(sheetname "")
		)
		(fill
			(thermal_gap 0.5)
			(thermal_bridge_width 0.5)
			(island_removal_mode 0)
		)
		(polygon
			(pts
				(xy 298.540932 15.80261) (xy 288.533332 15.80261) (xy 288.533332 21.92401) (xy 298.540932 21.92401)
			)
		)
	)
	(zone
		(layer "Cmts.User")
		(hatch none 0.5)
		(connect_pads
			(clearance 0)
		)
		(min_thickness 0.25)
		(keepout
			(tracks allowed)
			(vias allowed)
			(pads allowed)
			(copperpour allowed)
			(footprints allowed)
		)
		(placement
			(enabled no)
			(sheetname "")
		)
		(fill
			(thermal_gap 0.5)
			(thermal_bridge_width 0.5)
			(island_removal_mode 0)
		)
		(polygon
			(pts
				(xy 298.540932 5.85089) (xy 288.533332 5.85089) (xy 288.533332 11.97229) (xy 298.540932 11.97229)
			)
		)
	)
	(zone
		(layer "Cmts.User")
		(hatch none 0.5)
		(connect_pads
			(clearance 0)
		)
		(min_thickness 0.25)
		(keepout
			(tracks allowed)
			(vias allowed)
			(pads allowed)
			(copperpour allowed)
			(footprints allowed)
		)
		(placement
			(enabled no)
			(sheetname "")
		)
		(fill
			(thermal_gap 0.5)
			(thermal_bridge_width 0.5)
			(island_removal_mode 0)
		)
		(polygon
			(pts
				(xy 358.611932 5.88391) (xy 348.604332 5.88391) (xy 348.604332 12.00531) (xy 358.611932 12.00531)
			)
		)
	)
	(zone
		(layer "Cmts.User")
		(hatch none 0.5)
		(connect_pads
			(clearance 0)
		)
		(min_thickness 0.25)
		(keepout
			(tracks allowed)
			(vias allowed)
			(pads allowed)
			(copperpour allowed)
			(footprints allowed)
		)
		(placement
			(enabled no)
			(sheetname "")
		)
		(fill
			(thermal_gap 0.5)
			(thermal_bridge_width 0.5)
			(island_removal_mode 0)
		)
		(polygon
			(pts
				(xy 395.8336 12.227814) (xy 405.8412 12.227814) (xy 405.8412 6.106414) (xy 395.8336 6.106414)
			)
		)
	)
	(zone
		(layer "Cmts.User")
		(hatch none 0.5)
		(connect_pads
			(clearance 0.5)
		)
		(min_thickness 0.25)
		(fill
			(thermal_gap 0.5)
			(thermal_bridge_width 0.5)
			(island_removal_mode 0)
		)
		(polygon
			(pts
				(xy -94.286832 -123.791218) (xy 490.114336 -123.791218) (xy 490.114336 40.184324) (xy -94.286832 40.184324)
			)
		)
	)
	(zone
		(layer "Cmts.User")
		(hatch none 0.5)
		(connect_pads
			(clearance 0)
		)
		(min_thickness 0.25)
		(keepout
			(tracks allowed)
			(vias allowed)
			(pads allowed)
			(copperpour allowed)
			(footprints allowed)
		)
		(placement
			(enabled no)
			(sheetname "")
		)
		(fill
			(thermal_gap 0.5)
			(thermal_bridge_width 0.5)
			(island_removal_mode 0)
		)
		(polygon
			(pts
				(xy 319.162176 22.113494) (xy 329.169776 22.113494) (xy 329.169776 15.992094) (xy 319.162176 15.992094)
			)
		)
	)
	(zone
		(layer "In9.Cu")
		(hatch none 0.5)
		(connect_pads
			(clearance 0)
		)
		(min_thickness 0.25)
		(keepout
			(tracks allowed)
			(vias allowed)
			(pads allowed)
			(copperpour allowed)
			(footprints allowed)
		)
		(placement
			(enabled no)
			(sheetname "")
		)
		(fill
			(thermal_gap 0.5)
			(thermal_bridge_width 0.5)
			(island_removal_mode 0)
		)
		(polygon
			(pts
				(xy 1.524254 -389.001254) (xy 1.524254 -386.886196) (xy 2.930906 -386.886196) (xy 2.930906 -389.001254)
			)
		)
	)
	(zone
		(layer "In9.Cu")
		(hatch none 0.5)
		(connect_pads
			(clearance 0)
		)
		(min_thickness 0.25)
		(keepout
			(tracks allowed)
			(vias allowed)
			(pads allowed)
			(copperpour allowed)
			(footprints allowed)
		)
		(placement
			(enabled no)
			(sheetname "")
		)
		(fill
			(thermal_gap 0.5)
			(thermal_bridge_width 0.5)
			(island_removal_mode 0)
		)
		(polygon
			(pts
				(xy 282.6766 -320.1416) (xy 294.6908 -320.1416) (xy 294.9448 -320.3956) (xy 294.9448 -321.3354)
				(xy 294.8432 -321.437) (xy 291.8968 -321.437) (xy 291.7698 -321.31) (xy 290.576 -321.31) (xy 290.0426 -321.8434)
				(xy 290.0426 -323.342) (xy 289.4838 -323.9008) (xy 287.2486 -323.9008) (xy 285.9532 -325.1962) (xy 283.1592 -325.1962)
				(xy 282.6766 -324.7136)
			)
		)
	)
	(zone
		(layer "In9.Cu")
		(hatch none 0.5)
		(connect_pads
			(clearance 0)
		)
		(min_thickness 0.25)
		(keepout
			(tracks allowed)
			(vias allowed)
			(pads allowed)
			(copperpour allowed)
			(footprints allowed)
		)
		(placement
			(enabled no)
			(sheetname "")
		)
		(fill
			(thermal_gap 0.5)
			(thermal_bridge_width 0.5)
			(island_removal_mode 0)
		)
		(polygon
			(pts
				(xy 407.71064 -271.7038) (xy 430.74844 -271.7038) (xy 430.90084 -271.5514) (xy 430.90084 -270.8402)
				(xy 430.477422 -270.416782) (xy 423.23004 -267.649198) (xy 423.23004 -264.5156) (xy 421.23741 -262.52297)
				(xy 407.38044 -265.64336) (xy 407.38044 -271.3736)
			)
		)
	)
	(zone
		(layer "In9.Cu")
		(hatch none 0.5)
		(connect_pads
			(clearance 0)
		)
		(min_thickness 0.25)
		(keepout
			(tracks allowed)
			(vias allowed)
			(pads allowed)
			(copperpour allowed)
			(footprints allowed)
		)
		(placement
			(enabled no)
			(sheetname "")
		)
		(fill
			(thermal_gap 0.5)
			(thermal_bridge_width 0.5)
			(island_removal_mode 0)
		)
		(polygon
			(pts
				(xy 59.4106 -271.7038) (xy 82.4484 -271.7038) (xy 82.6008 -271.5514) (xy 82.6008 -270.8402) (xy 82.177382 -270.416782)
				(xy 74.93 -267.649198) (xy 74.93 -264.5156) (xy 72.93737 -262.52297) (xy 59.0804 -265.64336) (xy 59.0804 -271.3736)
			)
		)
	)
	(zone
		(layer "In9.Cu")
		(hatch none 0.5)
		(connect_pads
			(clearance 0)
		)
		(min_thickness 0.25)
		(keepout
			(tracks not_allowed)
			(vias allowed)
			(pads allowed)
			(copperpour not_allowed)
			(footprints allowed)
		)
		(placement
			(enabled no)
			(sheetname "")
		)
		(fill
			(thermal_gap 0.5)
			(thermal_bridge_width 0.5)
			(island_removal_mode 0)
		)
		(polygon
			(pts
				(xy 18.415 -305.353974) (xy 22.013164 -305.353974) (xy 25.08504 -302.282098) (xy 28.971748 -302.282098)
				(xy 29.096716 -302.15713) (xy 29.096716 -296.368978) (xy 30.788356 -294.677338) (xy 35.062414 -294.677338)
				(xy 35.63493 -295.249854) (xy 48.506888 -295.249854) (xy 48.541432 -295.21531) (xy 48.541432 -294.997124)
				(xy 48.49876 -294.954452) (xy 35.706812 -294.954452) (xy 35.184588 -294.432228) (xy 30.644592 -294.432228)
				(xy 28.828746 -296.248074) (xy 28.828746 -301.818802) (xy 28.626308 -302.02124) (xy 24.962358 -302.02124)
				(xy 21.926804 -305.056794) (xy 18.731484 -305.056794) (xy 18.28419 -304.6095) (xy 17.698466 -304.6095)
				(xy 17.517364 -304.790602) (xy 17.517364 -305.366166) (xy 17.70888 -305.557682) (xy 18.211292 -305.557682)
			)
		)
	)
	(zone
		(layer "In9.Cu")
		(hatch none 0.5)
		(connect_pads
			(clearance 0)
		)
		(min_thickness 0.25)
		(keepout
			(tracks allowed)
			(vias allowed)
			(pads allowed)
			(copperpour allowed)
			(footprints allowed)
		)
		(placement
			(enabled no)
			(sheetname "")
		)
		(fill
			(thermal_gap 0.5)
			(thermal_bridge_width 0.5)
			(island_removal_mode 0)
		)
		(polygon
			(pts
				(xy 98.274378 -202.146408) (xy 98.274378 -200.758806) (xy 100.11791 -200.758806) (xy 100.11791 -202.146408)
			)
		)
	)
	(zone
		(layer "In9.Cu")
		(hatch none 0.5)
		(connect_pads
			(clearance 0)
		)
		(min_thickness 0.25)
		(keepout
			(tracks allowed)
			(vias allowed)
			(pads allowed)
			(copperpour allowed)
			(footprints allowed)
		)
		(placement
			(enabled no)
			(sheetname "")
		)
		(fill
			(thermal_gap 0.5)
			(thermal_bridge_width 0.5)
			(island_removal_mode 0)
		)
		(polygon
			(pts
				(xy 138.072876 -199.112886) (xy 138.072876 -197.832218) (xy 139.974574 -197.832218) (xy 139.974574 -199.112886)
			)
		)
	)
	(zone
		(layer "In9.Cu")
		(hatch none 0.5)
		(connect_pads
			(clearance 0)
		)
		(min_thickness 0.25)
		(keepout
			(tracks allowed)
			(vias allowed)
			(pads allowed)
			(copperpour allowed)
			(footprints allowed)
		)
		(placement
			(enabled no)
			(sheetname "")
		)
		(fill
			(thermal_gap 0.5)
			(thermal_bridge_width 0.5)
			(island_removal_mode 0)
		)
		(polygon
			(pts
				(xy 343.4842 -211.4296) (xy 350.774 -211.4296) (xy 351.9424 -212.598) (xy 351.9424 -218.4908) (xy 351.282 -219.1512)
				(xy 347.3958 -219.1512) (xy 343.154 -214.9094) (xy 343.154 -211.7598)
			)
		)
	)
	(zone
		(layer "In9.Cu")
		(hatch none 0.5)
		(connect_pads
			(clearance 0)
		)
		(min_thickness 0.25)
		(keepout
			(tracks allowed)
			(vias allowed)
			(pads allowed)
			(copperpour allowed)
			(footprints allowed)
		)
		(placement
			(enabled no)
			(sheetname "")
		)
		(fill
			(thermal_gap 0.5)
			(thermal_bridge_width 0.5)
			(island_removal_mode 0)
		)
		(polygon
			(pts
				(xy 380.2634 -300.7106) (xy 383.3622 -300.7106) (xy 383.4892 -300.8376) (xy 383.4892 -308.102) (xy 383.4384 -308.1528)
				(xy 382.9304 -308.1528) (xy 382.1684 -307.3908) (xy 382.1684 -305.2826) (xy 380.238 -303.3522) (xy 380.238 -300.736)
			)
		)
	)
	(zone
		(layer "In9.Cu")
		(hatch none 0.5)
		(connect_pads
			(clearance 0)
		)
		(min_thickness 0.25)
		(keepout
			(tracks allowed)
			(vias allowed)
			(pads allowed)
			(copperpour allowed)
			(footprints allowed)
		)
		(placement
			(enabled no)
			(sheetname "")
		)
		(fill
			(thermal_gap 0.5)
			(thermal_bridge_width 0.5)
			(island_removal_mode 0)
		)
		(polygon
			(pts
				(xy 237.621064 -83.064858) (xy 237.621064 -81.231232) (xy 240.172748 -81.231232) (xy 240.172748 -83.064858)
			)
		)
	)
	(zone
		(layer "In9.Cu")
		(hatch none 0.5)
		(connect_pads
			(clearance 0)
		)
		(min_thickness 0.25)
		(keepout
			(tracks allowed)
			(vias allowed)
			(pads allowed)
			(copperpour allowed)
			(footprints allowed)
		)
		(placement
			(enabled no)
			(sheetname "")
		)
		(fill
			(thermal_gap 0.5)
			(thermal_bridge_width 0.5)
			(island_removal_mode 0)
		)
		(polygon
			(pts
				(xy 51.308 -320.04) (xy 62.2554 -320.04) (xy 62.5602 -320.3448) (xy 62.5602 -320.421) (xy 60.2234 -322.7578)
				(xy 57.15 -322.7578) (xy 56.6928 -323.215) (xy 56.6928 -323.1896) (xy 54.8894 -324.993) (xy 51.2064 -324.993)
				(xy 51.2064 -320.1416)
			)
		)
	)
	(zone
		(layer "In9.Cu")
		(hatch none 0.5)
		(connect_pads
			(clearance 0)
		)
		(min_thickness 0.25)
		(keepout
			(tracks allowed)
			(vias allowed)
			(pads allowed)
			(copperpour allowed)
			(footprints allowed)
		)
		(placement
			(enabled no)
			(sheetname "")
		)
		(fill
			(thermal_gap 0.5)
			(thermal_bridge_width 0.5)
			(island_removal_mode 0)
		)
		(polygon
			(pts
				(xy 237.937802 -88.824308) (xy 237.937802 -87.320374) (xy 240.072418 -87.320374) (xy 240.072418 -88.824308)
			)
		)
	)
	(zone
		(layer "In9.Cu")
		(hatch none 0.5)
		(connect_pads
			(clearance 0)
		)
		(min_thickness 0.25)
		(keepout
			(tracks allowed)
			(vias allowed)
			(pads allowed)
			(copperpour allowed)
			(footprints allowed)
		)
		(placement
			(enabled no)
			(sheetname "")
		)
		(fill
			(thermal_gap 0.5)
			(thermal_bridge_width 0.5)
			(island_removal_mode 0)
		)
		(polygon
			(pts
				(xy 83.9216 -288.544) (xy 85.8266 -288.544) (xy 86.686644 -287.683956) (xy 86.441026 -282.529026)
				(xy 85.6234 -281.7114) (xy 84.0232 -281.7114) (xy 83.8454 -281.8892) (xy 83.8454 -288.4678)
			)
		)
	)
	(zone
		(layer "In9.Cu")
		(hatch none 0.5)
		(connect_pads
			(clearance 0)
		)
		(min_thickness 0.25)
		(keepout
			(tracks allowed)
			(vias allowed)
			(pads allowed)
			(copperpour allowed)
			(footprints allowed)
		)
		(placement
			(enabled no)
			(sheetname "")
		)
		(fill
			(thermal_gap 0.5)
			(thermal_bridge_width 0.5)
			(island_removal_mode 0)
		)
		(polygon
			(pts
				(xy 8.402828 -372.740174) (xy 8.402828 -371.26545) (xy 10.595356 -371.26545) (xy 10.595356 -372.740174)
			)
		)
	)
	(zone
		(layer "In9.Cu")
		(hatch none 0.5)
		(connect_pads
			(clearance 0)
		)
		(min_thickness 0.25)
		(keepout
			(tracks allowed)
			(vias allowed)
			(pads allowed)
			(copperpour allowed)
			(footprints allowed)
		)
		(placement
			(enabled no)
			(sheetname "")
		)
		(fill
			(thermal_gap 0.5)
			(thermal_bridge_width 0.5)
			(island_removal_mode 0)
		)
		(polygon
			(pts
				(xy 291.610542 -271.7038) (xy 314.648342 -271.7038) (xy 314.800742 -271.5514) (xy 314.800742 -270.8402)
				(xy 314.377324 -270.416782) (xy 307.129942 -267.649198) (xy 307.129942 -264.5156) (xy 305.137312 -262.52297)
				(xy 291.280342 -265.64336) (xy 291.280342 -271.3736)
			)
		)
	)
	(zone
		(layer "In9.Cu")
		(hatch none 0.5)
		(connect_pads
			(clearance 0)
		)
		(min_thickness 0.25)
		(keepout
			(tracks allowed)
			(vias allowed)
			(pads allowed)
			(copperpour allowed)
			(footprints allowed)
		)
		(placement
			(enabled no)
			(sheetname "")
		)
		(fill
			(thermal_gap 0.5)
			(thermal_bridge_width 0.5)
			(island_removal_mode 0)
		)
		(polygon
			(pts
				(xy 200.021698 -288.544) (xy 201.926698 -288.544) (xy 202.786742 -287.683956) (xy 202.541124 -282.529026)
				(xy 201.723498 -281.7114) (xy 200.123298 -281.7114) (xy 199.945498 -281.8892) (xy 199.945498 -288.4678)
			)
		)
	)
	(zone
		(layer "In9.Cu")
		(hatch none 0.5)
		(connect_pads
			(clearance 0)
		)
		(min_thickness 0.25)
		(keepout
			(tracks allowed)
			(vias allowed)
			(pads allowed)
			(copperpour allowed)
			(footprints allowed)
		)
		(placement
			(enabled no)
			(sheetname "")
		)
		(fill
			(thermal_gap 0.5)
			(thermal_bridge_width 0.5)
			(island_removal_mode 0)
		)
		(polygon
			(pts
				(xy 148.3614 -301.4218) (xy 151.3332 -301.4218) (xy 151.765 -301.8536) (xy 151.765 -308.8386) (xy 151.5364 -309.0672)
				(xy 151.1554 -309.0672) (xy 150.3172 -308.229) (xy 150.3172 -307.0098) (xy 148.3614 -305.054)
			)
		)
	)
	(zone
		(layer "In9.Cu")
		(hatch none 0.5)
		(connect_pads
			(clearance 0)
		)
		(min_thickness 0.25)
		(keepout
			(tracks allowed)
			(vias allowed)
			(pads allowed)
			(copperpour allowed)
			(footprints allowed)
		)
		(placement
			(enabled no)
			(sheetname "")
		)
		(fill
			(thermal_gap 0.5)
			(thermal_bridge_width 0.5)
			(island_removal_mode 0)
		)
		(polygon
			(pts
				(xy 385.064 -320.04) (xy 390.7028 -320.04) (xy 390.7028 -320.1924) (xy 389.1534 -321.7418) (xy 385.2418 -321.7418)
				(xy 385.064 -321.564)
			)
		)
	)
	(zone
		(layer "In9.Cu")
		(hatch none 0.5)
		(connect_pads
			(clearance 0)
		)
		(min_thickness 0.25)
		(keepout
			(tracks allowed)
			(vias allowed)
			(pads allowed)
			(copperpour allowed)
			(footprints allowed)
		)
		(placement
			(enabled no)
			(sheetname "")
		)
		(fill
			(thermal_gap 0.5)
			(thermal_bridge_width 0.5)
			(island_removal_mode 0)
		)
		(polygon
			(pts
				(xy 403.60854 -352.415094) (xy 447.464688 -352.415094) (xy 448.029584 -351.850198) (xy 448.029584 -341.804244)
				(xy 447.74612 -341.52078) (xy 402.885656 -341.52078) (xy 402.665438 -341.740998) (xy 402.665438 -351.471992)
			)
		)
	)
	(zone
		(layer "In9.Cu")
		(hatch none 0.5)
		(connect_pads
			(clearance 0)
		)
		(min_thickness 0.25)
		(keepout
			(tracks allowed)
			(vias allowed)
			(pads allowed)
			(copperpour allowed)
			(footprints allowed)
		)
		(placement
			(enabled no)
			(sheetname "")
		)
		(fill
			(thermal_gap 0.5)
			(thermal_bridge_width 0.5)
			(island_removal_mode 0)
		)
		(polygon
			(pts
				(xy 316.121542 -288.544) (xy 318.026542 -288.544) (xy 318.886586 -287.683956) (xy 318.640968 -282.529026)
				(xy 317.823342 -281.7114) (xy 316.223142 -281.7114) (xy 316.045342 -281.8892) (xy 316.045342 -288.4678)
			)
		)
	)
	(zone
		(layer "In9.Cu")
		(hatch none 0.5)
		(connect_pads
			(clearance 0)
		)
		(min_thickness 0.25)
		(keepout
			(tracks not_allowed)
			(vias allowed)
			(pads allowed)
			(copperpour not_allowed)
			(footprints allowed)
		)
		(placement
			(enabled no)
			(sheetname "")
		)
		(fill
			(thermal_gap 0.5)
			(thermal_bridge_width 0.5)
			(island_removal_mode 0)
		)
		(polygon
			(pts
				(xy 262.048498 -295.947592) (xy 262.048498 -295.552876) (xy 262.033004 -295.537382) (xy 261.834376 -295.537382)
				(xy 261.796784 -295.574974) (xy 261.796784 -299.97527) (xy 254.352552 -307.419502) (xy 249.050556 -307.419502)
				(xy 248.775474 -307.14442) (xy 248.421144 -307.14442) (xy 248.298716 -307.266848) (xy 248.298716 -307.639212)
				(xy 248.422922 -307.763418) (xy 248.862596 -307.763418) (xy 248.943368 -307.682646) (xy 254.46228 -307.682646)
				(xy 262.050022 -300.094904) (xy 262.050022 -295.949116)
			)
		)
	)
	(zone
		(layer "In9.Cu")
		(hatch none 0.5)
		(connect_pads
			(clearance 0)
		)
		(min_thickness 0.25)
		(keepout
			(tracks allowed)
			(vias allowed)
			(pads allowed)
			(copperpour allowed)
			(footprints allowed)
		)
		(placement
			(enabled no)
			(sheetname "")
		)
		(fill
			(thermal_gap 0.5)
			(thermal_bridge_width 0.5)
			(island_removal_mode 0)
		)
		(polygon
			(pts
				(xy 175.510698 -271.7038) (xy 198.548498 -271.7038) (xy 198.700898 -271.5514) (xy 198.700898 -270.8402)
				(xy 198.27748 -270.416782) (xy 191.030098 -267.649198) (xy 191.030098 -264.5156) (xy 189.037468 -262.52297)
				(xy 175.180498 -265.64336) (xy 175.180498 -271.3736)
			)
		)
	)
	(zone
		(layer "In9.Cu")
		(hatch none 0.5)
		(connect_pads
			(clearance 0)
		)
		(min_thickness 0.25)
		(keepout
			(tracks allowed)
			(vias allowed)
			(pads allowed)
			(copperpour allowed)
			(footprints allowed)
		)
		(placement
			(enabled no)
			(sheetname "")
		)
		(fill
			(thermal_gap 0.5)
			(thermal_bridge_width 0.5)
			(island_removal_mode 0)
		)
		(polygon
			(pts
				(xy 432.22164 -288.544) (xy 434.12664 -288.544) (xy 434.986684 -287.683956) (xy 434.741066 -282.529026)
				(xy 433.92344 -281.7114) (xy 432.32324 -281.7114) (xy 432.14544 -281.8892) (xy 432.14544 -288.4678)
			)
		)
	)
	(zone
		(layers "In9.Cu" "In13.Cu")
		(hatch none 0.5)
		(connect_pads
			(clearance 0)
		)
		(min_thickness 0.25)
		(keepout
			(tracks allowed)
			(vias allowed)
			(pads allowed)
			(copperpour allowed)
			(footprints allowed)
		)
		(placement
			(enabled no)
			(sheetname "")
		)
		(fill yes
			(thermal_gap 0.5)
			(thermal_bridge_width 0.5)
			(island_removal_mode 0)
		)
		(polygon
			(pts
				(xy 359.379012 -352.507042) (xy 403.23516 -352.507042) (xy 403.800056 -351.942146) (xy 403.800056 -341.896192)
				(xy 403.516592 -341.612728) (xy 358.656128 -341.612728) (xy 358.43591 -341.832946) (xy 358.43591 -351.56394)
			)
		)
	)
	(zone
		(layers "In9.Cu" "In13.Cu")
		(hatch none 0.5)
		(connect_pads
			(clearance 0)
		)
		(min_thickness 0.25)
		(keepout
			(tracks allowed)
			(vias allowed)
			(pads allowed)
			(copperpour allowed)
			(footprints allowed)
		)
		(placement
			(enabled no)
			(sheetname "")
		)
		(fill yes
			(thermal_gap 0.5)
			(thermal_bridge_width 0.5)
			(island_removal_mode 0)
		)
		(polygon
			(pts
				(xy 313.758834 -352.415094) (xy 357.614982 -352.415094) (xy 358.179878 -351.850198) (xy 358.179878 -341.804244)
				(xy 357.896414 -341.52078) (xy 313.03595 -341.52078) (xy 312.815732 -341.740998) (xy 312.815732 -351.471992)
			)
		)
	)
	(zone
		(layer "In11.Cu")
		(hatch none 0.5)
		(connect_pads
			(clearance 0)
		)
		(min_thickness 0.25)
		(keepout
			(tracks allowed)
			(vias allowed)
			(pads allowed)
			(copperpour allowed)
			(footprints allowed)
		)
		(placement
			(enabled no)
			(sheetname "")
		)
		(fill
			(thermal_gap 0.5)
			(thermal_bridge_width 0.5)
			(island_removal_mode 0)
		)
		(polygon
			(pts
				(xy 73.8124 -320.04) (xy 79.375 -320.04) (xy 79.9592 -320.6242) (xy 79.9592 -322.0974) (xy 79.5782 -322.4784)
				(xy 75.692 -322.4784) (xy 73.8124 -320.5988)
			)
		)
	)
	(zone
		(layer "In11.Cu")
		(hatch none 0.5)
		(connect_pads
			(clearance 0)
		)
		(min_thickness 0.25)
		(keepout
			(tracks allowed)
			(vias allowed)
			(pads allowed)
			(copperpour allowed)
			(footprints allowed)
		)
		(placement
			(enabled no)
			(sheetname "")
		)
		(fill
			(thermal_gap 0.5)
			(thermal_bridge_width 0.5)
			(island_removal_mode 0)
		)
		(polygon
			(pts
				(xy 159.127698 -271.399) (xy 174.291498 -271.399) (xy 174.367698 -271.3228) (xy 174.367698 -265.7094)
				(xy 172.488098 -263.8298) (xy 171.573698 -263.8298) (xy 170.075098 -262.3312) (xy 168.728898 -262.3312)
				(xy 167.027098 -264.033) (xy 167.027098 -264.0076) (xy 166.163498 -264.8712) (xy 161.557462 -264.8712)
				(xy 159.026098 -267.402564) (xy 159.026098 -271.2974)
			)
		)
	)
	(zone
		(layer "In11.Cu")
		(hatch none 0.5)
		(connect_pads
			(clearance 0)
		)
		(min_thickness 0.25)
		(keepout
			(tracks allowed)
			(vias allowed)
			(pads allowed)
			(copperpour allowed)
			(footprints allowed)
		)
		(placement
			(enabled no)
			(sheetname "")
		)
		(fill
			(thermal_gap 0.5)
			(thermal_bridge_width 0.5)
			(island_removal_mode 0)
		)
		(polygon
			(pts
				(xy 348.204028 -281.455114) (xy 349.077026 -281.455114) (xy 350.8629 -279.66924) (xy 350.8629 -269.767812)
				(xy 353.263708 -267.367004) (xy 353.263708 -264.013696) (xy 353.045522 -263.79551) (xy 352.370644 -263.79551)
				(xy 351.834958 -264.331196) (xy 351.834958 -265.521694) (xy 352.33102 -266.017756) (xy 352.33102 -266.950444)
				(xy 349.890588 -269.390876) (xy 349.890588 -278.954738) (xy 349.096838 -279.748488) (xy 348.779084 -279.748488)
				(xy 348.501462 -279.470866) (xy 348.16415 -279.470866) (xy 347.985588 -279.649428) (xy 347.985588 -281.236674)
			)
		)
	)
	(zone
		(layer "In11.Cu")
		(hatch none 0.5)
		(connect_pads
			(clearance 0)
		)
		(min_thickness 0.25)
		(keepout
			(tracks allowed)
			(vias allowed)
			(pads allowed)
			(copperpour allowed)
			(footprints allowed)
		)
		(placement
			(enabled no)
			(sheetname "")
		)
		(fill
			(thermal_gap 0.5)
			(thermal_bridge_width 0.5)
			(island_removal_mode 0)
		)
		(polygon
			(pts
				(xy 340.088474 -281.335988) (xy 340.703662 -281.335988) (xy 341.89416 -280.14549) (xy 344.09634 -280.14549)
				(xy 345.485466 -278.756364) (xy 345.485466 -271.097502) (xy 349.394526 -267.188442) (xy 351.735898 -267.188442)
				(xy 352.906584 -266.017756) (xy 352.906584 -264.90676) (xy 352.608896 -264.609072) (xy 351.775522 -264.609072)
				(xy 350.049338 -266.335256) (xy 348.75978 -266.335256) (xy 344.37447 -270.720566) (xy 344.37447 -278.299926)
				(xy 343.540842 -279.133554) (xy 341.616284 -279.133554) (xy 340.862412 -279.887426) (xy 340.62416 -279.887426)
				(xy 340.286848 -279.550114) (xy 339.810598 -279.550114) (xy 339.612224 -279.748488) (xy 339.612224 -280.859738)
			)
		)
	)
	(zone
		(layer "In11.Cu")
		(hatch none 0.5)
		(connect_pads
			(clearance 0)
		)
		(min_thickness 0.25)
		(keepout
			(tracks allowed)
			(vias allowed)
			(pads allowed)
			(copperpour allowed)
			(footprints allowed)
		)
		(placement
			(enabled no)
			(sheetname "")
		)
		(fill
			(thermal_gap 0.5)
			(thermal_bridge_width 0.5)
			(island_removal_mode 0)
		)
		(polygon
			(pts
				(xy 132.508244 -281.549348) (xy 133.490462 -281.549348) (xy 134.695946 -280.343864) (xy 134.695946 -278.855932)
				(xy 132.448808 -276.608794) (xy 132.448808 -267.858748) (xy 127.210566 -262.620506) (xy 126.020068 -262.620506)
				(xy 125.365256 -261.965694) (xy 125.365256 -261.87654) (xy 124.889006 -261.40029) (xy 120.276112 -261.40029)
				(xy 119.293894 -262.382508) (xy 119.383048 -262.471662) (xy 123.162822 -262.471662) (xy 124.383038 -263.691878)
				(xy 126.377192 -263.691878) (xy 130.960622 -268.275308) (xy 130.960622 -276.36851) (xy 130.958336 -276.370796)
				(xy 130.958336 -276.995636) (xy 132.937758 -278.975058) (xy 132.937758 -279.183338) (xy 132.401818 -279.719278)
				(xy 132.342382 -279.719278) (xy 132.342382 -281.383486)
			)
		)
	)
	(zone
		(layer "In11.Cu")
		(hatch none 0.5)
		(connect_pads
			(clearance 0)
		)
		(min_thickness 0.25)
		(keepout
			(tracks allowed)
			(vias allowed)
			(pads allowed)
			(copperpour allowed)
			(footprints allowed)
		)
		(placement
			(enabled no)
			(sheetname "")
		)
		(fill
			(thermal_gap 0.5)
			(thermal_bridge_width 0.5)
			(island_removal_mode 0)
		)
		(polygon
			(pts
				(xy 266.685522 -352.969576) (xy 311.297828 -352.969576) (xy 311.656476 -352.610928) (xy 311.656476 -342.211152)
				(xy 310.723788 -341.278464) (xy 265.68146 -341.278464) (xy 265.68146 -351.965514)
			)
		)
	)
	(zone
		(layer "In11.Cu")
		(hatch none 0.5)
		(connect_pads
			(clearance 0)
		)
		(min_thickness 0.25)
		(keepout
			(tracks allowed)
			(vias allowed)
			(pads allowed)
			(copperpour allowed)
			(footprints allowed)
		)
		(placement
			(enabled no)
			(sheetname "")
		)
		(fill
			(thermal_gap 0.5)
			(thermal_bridge_width 0.5)
			(island_removal_mode 0)
		)
		(polygon
			(pts
				(xy 116.003832 -281.455114) (xy 116.87683 -281.455114) (xy 118.662704 -279.66924) (xy 118.662704 -269.767812)
				(xy 121.063512 -267.367004) (xy 121.063512 -264.013696) (xy 120.845326 -263.79551) (xy 120.170448 -263.79551)
				(xy 119.634762 -264.331196) (xy 119.634762 -265.521694) (xy 120.130824 -266.017756) (xy 120.130824 -266.950444)
				(xy 117.690392 -269.390876) (xy 117.690392 -278.954738) (xy 116.896642 -279.748488) (xy 116.578888 -279.748488)
				(xy 116.301266 -279.470866) (xy 115.963954 -279.470866) (xy 115.785392 -279.649428) (xy 115.785392 -281.236674)
			)
		)
	)
	(zone
		(layer "In11.Cu")
		(hatch none 0.5)
		(connect_pads
			(clearance 0)
		)
		(min_thickness 0.25)
		(keepout
			(tracks allowed)
			(vias allowed)
			(pads allowed)
			(copperpour allowed)
			(footprints allowed)
		)
		(placement
			(enabled no)
			(sheetname "")
		)
		(fill
			(thermal_gap 0.5)
			(thermal_bridge_width 0.5)
			(island_removal_mode 0)
		)
		(polygon
			(pts
				(xy 404.001224 -352.754438) (xy 447.645028 -352.754438) (xy 447.824352 -352.575114) (xy 447.824352 -342.354662)
				(xy 446.748408 -341.278718) (xy 403.499066 -341.278718) (xy 403.248114 -341.52967) (xy 403.248114 -352.001328)
			)
		)
	)
	(zone
		(layer "In11.Cu")
		(hatch none 0.5)
		(connect_pads
			(clearance 0)
		)
		(min_thickness 0.25)
		(keepout
			(tracks allowed)
			(vias allowed)
			(pads allowed)
			(copperpour allowed)
			(footprints allowed)
		)
		(placement
			(enabled no)
			(sheetname "")
		)
		(fill
			(thermal_gap 0.5)
			(thermal_bridge_width 0.5)
			(island_removal_mode 0)
		)
		(polygon
			(pts
				(xy 364.70844 -281.549348) (xy 365.690658 -281.549348) (xy 366.896142 -280.343864) (xy 366.896142 -278.855932)
				(xy 364.649004 -276.608794) (xy 364.649004 -267.858748) (xy 359.410762 -262.620506) (xy 358.220264 -262.620506)
				(xy 357.565452 -261.965694) (xy 357.565452 -261.87654) (xy 357.089202 -261.40029) (xy 352.476308 -261.40029)
				(xy 351.49409 -262.382508) (xy 351.583244 -262.471662) (xy 355.363018 -262.471662) (xy 356.583234 -263.691878)
				(xy 358.577388 -263.691878) (xy 363.160818 -268.275308) (xy 363.160818 -276.36851) (xy 363.158532 -276.370796)
				(xy 363.158532 -276.995636) (xy 365.137954 -278.975058) (xy 365.137954 -279.183338) (xy 364.602014 -279.719278)
				(xy 364.542578 -279.719278) (xy 364.542578 -281.383486)
			)
		)
	)
	(zone
		(layer "In11.Cu")
		(hatch none 0.5)
		(connect_pads
			(clearance 0)
		)
		(min_thickness 0.25)
		(keepout
			(tracks allowed)
			(vias allowed)
			(pads allowed)
			(copperpour allowed)
			(footprints allowed)
		)
		(placement
			(enabled no)
			(sheetname "")
		)
		(fill
			(thermal_gap 0.5)
			(thermal_bridge_width 0.5)
			(island_removal_mode 0)
		)
		(polygon
			(pts
				(xy 306.2478 -319.9638) (xy 314.5536 -319.9638) (xy 314.8076 -320.2178) (xy 314.8076 -321.9704)
				(xy 313.4106 -323.3674) (xy 308.6354 -323.3674) (xy 306.0954 -320.8274) (xy 306.0954 -320.1162)
			)
		)
	)
	(zone
		(layer "In11.Cu")
		(hatch none 0.5)
		(connect_pads
			(clearance 0)
		)
		(min_thickness 0.25)
		(keepout
			(tracks allowed)
			(vias allowed)
			(pads allowed)
			(copperpour allowed)
			(footprints allowed)
		)
		(placement
			(enabled no)
			(sheetname "")
		)
		(fill
			(thermal_gap 0.5)
			(thermal_bridge_width 0.5)
			(island_removal_mode 0)
		)
		(polygon
			(pts
				(xy 356.85857 -281.359356) (xy 357.493316 -281.359356) (xy 358.564942 -280.28773) (xy 358.564942 -279.196546)
				(xy 356.005384 -276.636988) (xy 356.005384 -267.582142) (xy 356.200456 -267.38707) (xy 356.200456 -266.930632)
				(xy 354.037646 -264.767822) (xy 354.037646 -263.101074) (xy 353.521772 -262.5852) (xy 352.668332 -262.5852)
				(xy 351.239836 -264.013696) (xy 351.239836 -265.402822) (xy 350.843088 -265.79957) (xy 351.358962 -266.315444)
				(xy 352.966274 -266.315444) (xy 353.541584 -265.740134) (xy 353.779836 -265.740134) (xy 355.367082 -267.32738)
				(xy 355.367082 -277.129494) (xy 356.97414 -278.736552) (xy 356.97414 -279.133554) (xy 356.458266 -279.649428)
				(xy 356.458266 -280.959052)
			)
		)
	)
	(zone
		(layer "In11.Cu")
		(hatch none 0.5)
		(connect_pads
			(clearance 0)
		)
		(min_thickness 0.25)
		(keepout
			(tracks allowed)
			(vias allowed)
			(pads allowed)
			(copperpour allowed)
			(footprints allowed)
		)
		(placement
			(enabled no)
			(sheetname "")
		)
		(fill
			(thermal_gap 0.5)
			(thermal_bridge_width 0.5)
			(island_removal_mode 0)
		)
		(polygon
			(pts
				(xy 385.2926 -320.294) (xy 388.8486 -320.294) (xy 389.1026 -320.548) (xy 389.1026 -321.4624) (xy 387.6802 -322.8848)
				(xy 385.4196 -322.8848) (xy 385.2926 -322.7578)
			)
		)
	)
	(zone
		(layer "In11.Cu")
		(hatch none 0.5)
		(connect_pads
			(clearance 0)
		)
		(min_thickness 0.25)
		(keepout
			(tracks allowed)
			(vias allowed)
			(pads allowed)
			(copperpour allowed)
			(footprints allowed)
		)
		(placement
			(enabled no)
			(sheetname "")
		)
		(fill
			(thermal_gap 0.5)
			(thermal_bridge_width 0.5)
			(island_removal_mode 0)
		)
		(polygon
			(pts
				(xy 275.227542 -271.399) (xy 290.391342 -271.399) (xy 290.467542 -271.3228) (xy 290.467542 -265.7094)
				(xy 288.587942 -263.8298) (xy 287.673542 -263.8298) (xy 286.174942 -262.3312) (xy 284.828742 -262.3312)
				(xy 283.126942 -264.033) (xy 283.126942 -264.0076) (xy 282.263342 -264.8712) (xy 277.657306 -264.8712)
				(xy 275.125942 -267.402564) (xy 275.125942 -271.2974)
			)
		)
	)
	(zone
		(layer "In11.Cu")
		(hatch none 0.5)
		(connect_pads
			(clearance 0)
		)
		(min_thickness 0.25)
		(keepout
			(tracks allowed)
			(vias allowed)
			(pads allowed)
			(copperpour allowed)
			(footprints allowed)
		)
		(placement
			(enabled no)
			(sheetname "")
		)
		(fill
			(thermal_gap 0.5)
			(thermal_bridge_width 0.5)
			(island_removal_mode 0)
		)
		(polygon
			(pts
				(xy 378.333 -300.9138) (xy 383.5908 -300.9138) (xy 383.921 -301.244) (xy 383.921 -306.9844) (xy 383.7432 -307.1622)
				(xy 382.8288 -307.1622) (xy 378.0282 -302.3616) (xy 377.952 -302.3616) (xy 377.952 -301.2948)
			)
		)
	)
	(zone
		(layer "In11.Cu")
		(hatch none 0.5)
		(connect_pads
			(clearance 0)
		)
		(min_thickness 0.25)
		(keepout
			(tracks allowed)
			(vias allowed)
			(pads allowed)
			(copperpour allowed)
			(footprints allowed)
		)
		(placement
			(enabled no)
			(sheetname "")
		)
		(fill
			(thermal_gap 0.5)
			(thermal_bridge_width 0.5)
			(island_removal_mode 0)
		)
		(polygon
			(pts
				(xy 43.0276 -271.399) (xy 58.1914 -271.399) (xy 58.2676 -271.3228) (xy 58.2676 -265.7094) (xy 56.388 -263.8298)
				(xy 55.4736 -263.8298) (xy 53.975 -262.3312) (xy 52.6288 -262.3312) (xy 50.927 -264.033) (xy 50.927 -264.0076)
				(xy 50.0634 -264.8712) (xy 45.457364 -264.8712) (xy 42.926 -267.402564) (xy 42.926 -271.2974)
			)
		)
	)
	(zone
		(layer "In11.Cu")
		(hatch none 0.5)
		(connect_pads
			(clearance 0)
		)
		(min_thickness 0.25)
		(keepout
			(tracks allowed)
			(vias allowed)
			(pads allowed)
			(copperpour allowed)
			(footprints allowed)
		)
		(placement
			(enabled no)
			(sheetname "")
		)
		(fill
			(thermal_gap 0.5)
			(thermal_bridge_width 0.5)
			(island_removal_mode 0)
		)
		(polygon
			(pts
				(xy 124.658374 -281.359356) (xy 125.29312 -281.359356) (xy 126.364746 -280.28773) (xy 126.364746 -279.196546)
				(xy 123.805188 -276.636988) (xy 123.805188 -267.582142) (xy 124.00026 -267.38707) (xy 124.00026 -266.930632)
				(xy 121.83745 -264.767822) (xy 121.83745 -263.101074) (xy 121.321576 -262.5852) (xy 120.468136 -262.5852)
				(xy 119.03964 -264.013696) (xy 119.03964 -265.402822) (xy 118.642892 -265.79957) (xy 119.158766 -266.315444)
				(xy 120.766078 -266.315444) (xy 121.341388 -265.740134) (xy 121.57964 -265.740134) (xy 123.166886 -267.32738)
				(xy 123.166886 -277.129494) (xy 124.773944 -278.736552) (xy 124.773944 -279.133554) (xy 124.25807 -279.649428)
				(xy 124.25807 -280.959052)
			)
		)
	)
	(zone
		(layer "In11.Cu")
		(hatch none 0.5)
		(connect_pads
			(clearance 0)
		)
		(min_thickness 0.25)
		(keepout
			(tracks allowed)
			(vias allowed)
			(pads allowed)
			(copperpour allowed)
			(footprints allowed)
		)
		(placement
			(enabled no)
			(sheetname "")
		)
		(fill
			(thermal_gap 0.5)
			(thermal_bridge_width 0.5)
			(island_removal_mode 0)
		)
		(polygon
			(pts
				(xy 107.888278 -281.335988) (xy 108.503466 -281.335988) (xy 109.693964 -280.14549) (xy 111.896144 -280.14549)
				(xy 113.28527 -278.756364) (xy 113.28527 -271.097502) (xy 117.19433 -267.188442) (xy 119.535702 -267.188442)
				(xy 120.706388 -266.017756) (xy 120.706388 -264.90676) (xy 120.4087 -264.609072) (xy 119.575326 -264.609072)
				(xy 117.849142 -266.335256) (xy 116.559584 -266.335256) (xy 112.174274 -270.720566) (xy 112.174274 -278.299926)
				(xy 111.340646 -279.133554) (xy 109.416088 -279.133554) (xy 108.662216 -279.887426) (xy 108.423964 -279.887426)
				(xy 108.086652 -279.550114) (xy 107.610402 -279.550114) (xy 107.412028 -279.748488) (xy 107.412028 -280.859738)
			)
		)
	)
	(zone
		(layer "In11.Cu")
		(hatch none 0.5)
		(connect_pads
			(clearance 0)
		)
		(min_thickness 0.25)
		(keepout
			(tracks allowed)
			(vias allowed)
			(pads allowed)
			(copperpour allowed)
			(footprints allowed)
		)
		(placement
			(enabled no)
			(sheetname "")
		)
		(fill
			(thermal_gap 0.5)
			(thermal_bridge_width 0.5)
			(island_removal_mode 0)
		)
		(polygon
			(pts
				(xy 391.32764 -271.399) (xy 406.49144 -271.399) (xy 406.56764 -271.3228) (xy 406.56764 -265.7094)
				(xy 404.68804 -263.8298) (xy 403.77364 -263.8298) (xy 402.27504 -262.3312) (xy 400.92884 -262.3312)
				(xy 399.22704 -264.033) (xy 399.22704 -264.0076) (xy 398.36344 -264.8712) (xy 393.757404 -264.8712)
				(xy 391.22604 -267.402564) (xy 391.22604 -271.2974)
			)
		)
	)
	(zone
		(layer "In11.Cu")
		(hatch none 0.5)
		(connect_pads
			(clearance 0)
		)
		(min_thickness 0.25)
		(keepout
			(tracks allowed)
			(vias allowed)
			(pads allowed)
			(copperpour allowed)
			(footprints allowed)
		)
		(placement
			(enabled no)
			(sheetname "")
		)
		(fill
			(thermal_gap 0.5)
			(thermal_bridge_width 0.5)
			(island_removal_mode 0)
		)
		(polygon
			(pts
				(xy 333.629 -213.8934) (xy 336.4484 -213.8934) (xy 336.7024 -214.1474) (xy 336.7024 -227.0506) (xy 336.423 -227.33)
				(xy 335.5594 -227.33) (xy 335.4578 -227.2284) (xy 335.4578 -216.3318) (xy 333.5528 -214.4268) (xy 333.5528 -213.9696)
			)
		)
	)
	(zone
		(layer "In11.Cu")
		(hatch none 0.5)
		(connect_pads
			(clearance 0)
		)
		(min_thickness 0.25)
		(keepout
			(tracks allowed)
			(vias allowed)
			(pads allowed)
			(copperpour allowed)
			(footprints allowed)
		)
		(placement
			(enabled no)
			(sheetname "")
		)
		(fill
			(thermal_gap 0.5)
			(thermal_bridge_width 0.5)
			(island_removal_mode 0)
		)
		(polygon
			(pts
				(xy 145.7452 -300.7868) (xy 150.6982 -300.7868) (xy 151.4856 -301.5742) (xy 151.4856 -308.5846)
				(xy 151.1554 -308.9148) (xy 150.6728 -308.9148) (xy 145.669 -303.911) (xy 145.669 -300.863)
			)
		)
	)
	(zone
		(layer "In13.Cu")
		(hatch none 0.5)
		(connect_pads
			(clearance 0)
		)
		(min_thickness 0.25)
		(keepout
			(tracks not_allowed)
			(vias allowed)
			(pads allowed)
			(copperpour not_allowed)
			(footprints allowed)
		)
		(placement
			(enabled no)
			(sheetname "")
		)
		(fill
			(thermal_gap 0.5)
			(thermal_bridge_width 0.5)
			(island_removal_mode 0)
		)
		(polygon
			(pts
				(arc
					(start 326.474836 -270.89989)
					(mid 317.224664 -270.89989)
					(end 326.474836 -270.89989)
				)
			)
		)
	)
	(zone
		(layer "In13.Cu")
		(hatch none 0.5)
		(connect_pads
			(clearance 0)
		)
		(min_thickness 0.25)
		(keepout
			(tracks not_allowed)
			(vias allowed)
			(pads allowed)
			(copperpour not_allowed)
			(footprints allowed)
		)
		(placement
			(enabled no)
			(sheetname "")
		)
		(fill
			(thermal_gap 0.5)
			(thermal_bridge_width 0.5)
			(island_removal_mode 0)
		)
		(polygon
			(pts
				(arc
					(start 355.049328 -194.360038)
					(mid 344.750644 -194.360038)
					(end 355.049328 -194.360038)
				)
			)
		)
	)
	(zone
		(layer "In13.Cu")
		(hatch none 0.5)
		(connect_pads
			(clearance 0)
		)
		(min_thickness 0.25)
		(keepout
			(tracks allowed)
			(vias allowed)
			(pads allowed)
			(copperpour allowed)
			(footprints allowed)
		)
		(placement
			(enabled no)
			(sheetname "")
		)
		(fill
			(thermal_gap 0.5)
			(thermal_bridge_width 0.5)
			(island_removal_mode 0)
		)
		(polygon
			(pts
				(xy 42.8244 -320.0654) (xy 57.0484 -320.0654) (xy 57.7342 -320.7512) (xy 57.7342 -320.8528) (xy 53.8734 -324.7136)
				(xy 43.4594 -324.7136) (xy 42.8244 -324.0786)
			)
		)
	)
	(zone
		(layer "In13.Cu")
		(hatch none 0.5)
		(connect_pads
			(clearance 0)
		)
		(min_thickness 0.25)
		(keepout
			(tracks allowed)
			(vias allowed)
			(pads allowed)
			(copperpour allowed)
			(footprints allowed)
		)
		(placement
			(enabled no)
			(sheetname "")
		)
		(fill
			(thermal_gap 0.5)
			(thermal_bridge_width 0.5)
			(island_removal_mode 0)
		)
		(polygon
			(pts
				(xy 34.036 -289.56) (xy 34.036 -288.29) (xy 35.306 -288.29) (xy 35.306 -289.56)
			)
		)
	)
	(zone
		(layer "In13.Cu")
		(hatch none 0.5)
		(connect_pads
			(clearance 0)
		)
		(min_thickness 0.25)
		(keepout
			(tracks not_allowed)
			(vias allowed)
			(pads allowed)
			(copperpour not_allowed)
			(footprints allowed)
		)
		(placement
			(enabled no)
			(sheetname "")
		)
		(fill
			(thermal_gap 0.5)
			(thermal_bridge_width 0.5)
			(island_removal_mode 0)
		)
		(polygon
			(pts
				(arc
					(start 266.474956 -320.900044)
					(mid 257.224784 -320.900044)
					(end 266.474956 -320.900044)
				)
			)
		)
	)
	(zone
		(layer "In13.Cu")
		(hatch none 0.5)
		(connect_pads
			(clearance 0)
		)
		(min_thickness 0.25)
		(keepout
			(tracks not_allowed)
			(vias allowed)
			(pads allowed)
			(copperpour not_allowed)
			(footprints allowed)
		)
		(placement
			(enabled no)
			(sheetname "")
		)
		(fill
			(thermal_gap 0.5)
			(thermal_bridge_width 0.5)
			(island_removal_mode 0)
		)
		(polygon
			(pts
				(arc
					(start 238.949484 -194.359784)
					(mid 228.6508 -194.359784)
					(end 238.949484 -194.359784)
				)
			)
		)
	)
	(zone
		(layer "In13.Cu")
		(hatch none 0.5)
		(connect_pads
			(clearance 0)
		)
		(min_thickness 0.25)
		(keepout
			(tracks not_allowed)
			(vias allowed)
			(pads allowed)
			(copperpour not_allowed)
			(footprints allowed)
		)
		(placement
			(enabled no)
			(sheetname "")
		)
		(fill
			(thermal_gap 0.5)
			(thermal_bridge_width 0.5)
			(island_removal_mode 0)
		)
		(polygon
			(pts
				(arc
					(start 94.274894 -270.89989)
					(mid 85.024722 -270.89989)
					(end 94.274894 -270.89989)
				)
			)
		)
	)
	(zone
		(layer "In13.Cu")
		(hatch none 0.5)
		(connect_pads
			(clearance 0)
		)
		(min_thickness 0.25)
		(keepout
			(tracks allowed)
			(vias allowed)
			(pads allowed)
			(copperpour allowed)
			(footprints allowed)
		)
		(placement
			(enabled no)
			(sheetname "")
		)
		(fill
			(thermal_gap 0.5)
			(thermal_bridge_width 0.5)
			(island_removal_mode 0)
		)
		(polygon
			(pts
				(xy 163.3474 -322.961) (xy 163.3474 -321.6402) (xy 163.83 -321.1576) (xy 165.5572 -321.1576) (xy 165.9382 -321.5386)
				(xy 165.9382 -322.961) (xy 165.7096 -323.1896) (xy 163.576 -323.1896)
			)
		)
	)
	(zone
		(layer "In13.Cu")
		(hatch none 0.5)
		(connect_pads
			(clearance 0)
		)
		(min_thickness 0.25)
		(keepout
			(tracks not_allowed)
			(vias allowed)
			(pads allowed)
			(copperpour not_allowed)
			(footprints allowed)
		)
		(placement
			(enabled no)
			(sheetname "")
		)
		(fill
			(thermal_gap 0.5)
			(thermal_bridge_width 0.5)
			(island_removal_mode 0)
		)
		(polygon
			(pts
				(arc
					(start 34.27476 -270.89989)
					(mid 25.024588 -270.89989)
					(end 34.27476 -270.89989)
				)
			)
		)
	)
	(zone
		(layer "In13.Cu")
		(hatch none 0.5)
		(connect_pads
			(clearance 0)
		)
		(min_thickness 0.25)
		(keepout
			(tracks allowed)
			(vias allowed)
			(pads allowed)
			(copperpour allowed)
			(footprints allowed)
		)
		(placement
			(enabled no)
			(sheetname "")
		)
		(fill
			(thermal_gap 0.5)
			(thermal_bridge_width 0.5)
			(island_removal_mode 0)
		)
		(polygon
			(pts
				(xy 274.6248 -320.2432) (xy 287.9598 -320.2432) (xy 288.1376 -320.421) (xy 288.1376 -321.2592) (xy 283.3878 -326.009)
				(xy 274.828 -326.009) (xy 274.6248 -325.8058)
			)
		)
	)
	(zone
		(layer "In13.Cu")
		(hatch none 0.5)
		(connect_pads
			(clearance 0)
		)
		(min_thickness 0.25)
		(keepout
			(tracks not_allowed)
			(vias allowed)
			(pads allowed)
			(copperpour not_allowed)
			(footprints allowed)
		)
		(placement
			(enabled no)
			(sheetname "")
		)
		(fill
			(thermal_gap 0.5)
			(thermal_bridge_width 0.5)
			(island_removal_mode 0)
		)
		(polygon
			(pts
				(arc
					(start 34.27476 -320.900044)
					(mid 25.024588 -320.900044)
					(end 34.27476 -320.900044)
				)
			)
		)
	)
	(zone
		(layer "In13.Cu")
		(hatch none 0.5)
		(connect_pads
			(clearance 0)
		)
		(min_thickness 0.25)
		(keepout
			(tracks not_allowed)
			(vias allowed)
			(pads allowed)
			(copperpour not_allowed)
			(footprints allowed)
		)
		(placement
			(enabled no)
			(sheetname "")
		)
		(fill
			(thermal_gap 0.5)
			(thermal_bridge_width 0.5)
			(island_removal_mode 0)
		)
		(polygon
			(pts
				(arc
					(start 210.374738 -270.89989)
					(mid 201.124566 -270.89989)
					(end 210.374738 -270.89989)
				)
			)
		)
	)
	(zone
		(layer "In13.Cu")
		(hatch none 0.5)
		(connect_pads
			(clearance 0)
		)
		(min_thickness 0.25)
		(keepout
			(tracks not_allowed)
			(vias allowed)
			(pads allowed)
			(copperpour not_allowed)
			(footprints allowed)
		)
		(placement
			(enabled no)
			(sheetname "")
		)
		(fill
			(thermal_gap 0.5)
			(thermal_bridge_width 0.5)
			(island_removal_mode 0)
		)
		(polygon
			(pts
				(arc
					(start 326.474836 -320.900044)
					(mid 317.224664 -320.900044)
					(end 326.474836 -320.900044)
				)
			)
		)
	)
	(zone
		(layer "In13.Cu")
		(hatch none 0.5)
		(connect_pads
			(clearance 0)
		)
		(min_thickness 0.25)
		(keepout
			(tracks allowed)
			(vias allowed)
			(pads allowed)
			(copperpour allowed)
			(footprints allowed)
		)
		(placement
			(enabled no)
			(sheetname "")
		)
		(fill
			(thermal_gap 0.5)
			(thermal_bridge_width 0.5)
			(island_removal_mode 0)
		)
		(polygon
			(pts
				(xy 186.436 -321.31) (xy 187.833 -321.31) (xy 188.341 -321.818) (xy 188.341 -322.3514) (xy 187.7314 -322.961)
				(xy 186.8424 -322.961) (xy 186.1312 -322.2498) (xy 186.1312 -321.6148)
			)
		)
	)
	(zone
		(layer "In13.Cu")
		(hatch none 0.5)
		(connect_pads
			(clearance 0)
		)
		(min_thickness 0.25)
		(keepout
			(tracks allowed)
			(vias allowed)
			(pads allowed)
			(copperpour allowed)
			(footprints allowed)
		)
		(placement
			(enabled no)
			(sheetname "")
		)
		(fill
			(thermal_gap 0.5)
			(thermal_bridge_width 0.5)
			(island_removal_mode 0)
		)
		(polygon
			(pts
				(xy 414.9852 -320.2178) (xy 420.878 -320.2178) (xy 421.4368 -320.7766) (xy 421.4368 -322.834) (xy 421.005 -323.2658)
				(xy 416.6108 -323.2658) (xy 414.6042 -321.2592) (xy 414.6042 -320.5988)
			)
		)
	)
	(zone
		(layer "In13.Cu")
		(hatch none 0.5)
		(connect_pads
			(clearance 0)
		)
		(min_thickness 0.25)
		(keepout
			(tracks not_allowed)
			(vias allowed)
			(pads allowed)
			(copperpour not_allowed)
			(footprints allowed)
		)
		(placement
			(enabled no)
			(sheetname "")
		)
		(fill
			(thermal_gap 0.5)
			(thermal_bridge_width 0.5)
			(island_removal_mode 0)
		)
		(polygon
			(pts
				(arc
					(start 150.374858 -320.900044)
					(mid 141.124686 -320.900044)
					(end 150.374858 -320.900044)
				)
			)
		)
	)
	(zone
		(layer "In13.Cu")
		(hatch none 0.5)
		(connect_pads
			(clearance 0)
		)
		(min_thickness 0.25)
		(keepout
			(tracks allowed)
			(vias allowed)
			(pads allowed)
			(copperpour allowed)
			(footprints allowed)
		)
		(placement
			(enabled no)
			(sheetname "")
		)
		(fill
			(thermal_gap 0.5)
			(thermal_bridge_width 0.5)
			(island_removal_mode 0)
		)
		(polygon
			(pts
				(xy 391.16 -320.1162) (xy 398.2974 -320.1162) (xy 398.5768 -320.3956) (xy 398.5768 -322.2498) (xy 398.0688 -322.7578)
				(xy 393.0396 -322.7578) (xy 391.033 -320.7512) (xy 391.033 -320.2432)
			)
		)
	)
	(zone
		(layer "In13.Cu")
		(hatch none 0.5)
		(connect_pads
			(clearance 0)
		)
		(min_thickness 0.25)
		(keepout
			(tracks allowed)
			(vias allowed)
			(pads allowed)
			(copperpour allowed)
			(footprints allowed)
		)
		(placement
			(enabled no)
			(sheetname "")
		)
		(fill
			(thermal_gap 0.5)
			(thermal_bridge_width 0.5)
			(island_removal_mode 0)
		)
		(polygon
			(pts
				(xy 225.5266 -218.8464) (xy 234.1626 -218.8464) (xy 236.7026 -221.3864) (xy 236.7026 -224.6376)
				(xy 236.1184 -225.2218) (xy 235.966 -225.2218) (xy 235.3056 -224.5614) (xy 233.0704 -224.5614) (xy 232.3846 -223.8756)
				(xy 232.3846 -223.393) (xy 232.2576 -223.266) (xy 231.8004 -223.266) (xy 231.6226 -223.4438) (xy 231.6226 -223.7232)
				(xy 231.4956 -223.8502) (xy 225.6028 -223.8502) (xy 223.5962 -221.8436) (xy 223.5962 -220.0402)
				(xy 224.155 -219.4814) (xy 224.9932 -219.4814) (xy 225.425 -219.0496) (xy 225.425 -218.948)
			)
		)
	)
	(zone
		(layer "In13.Cu")
		(hatch none 0.5)
		(connect_pads
			(clearance 0)
		)
		(min_thickness 0.25)
		(keepout
			(tracks not_allowed)
			(vias allowed)
			(pads allowed)
			(copperpour not_allowed)
			(footprints allowed)
		)
		(placement
			(enabled no)
			(sheetname "")
		)
		(fill
			(thermal_gap 0.5)
			(thermal_bridge_width 0.5)
			(island_removal_mode 0)
		)
		(polygon
			(pts
				(arc
					(start 442.574934 -270.89989)
					(mid 433.324762 -270.89989)
					(end 442.574934 -270.89989)
				)
			)
		)
	)
	(zone
		(layer "In13.Cu")
		(hatch none 0.5)
		(connect_pads
			(clearance 0)
		)
		(min_thickness 0.25)
		(keepout
			(tracks allowed)
			(vias allowed)
			(pads allowed)
			(copperpour allowed)
			(footprints allowed)
		)
		(placement
			(enabled no)
			(sheetname "")
		)
		(fill
			(thermal_gap 0.5)
			(thermal_bridge_width 0.5)
			(island_removal_mode 0)
		)
		(polygon
			(pts
				(xy 333.2734 -215.3158) (xy 334.3148 -215.3158) (xy 334.3656 -215.3666) (xy 334.6704 -215.3666)
				(xy 334.772 -215.265) (xy 334.772 -214.8078) (xy 334.2894 -214.3252) (xy 334.2894 -213.8934) (xy 333.9846 -213.5886)
				(xy 333.9846 -212.8012) (xy 333.629 -212.4456) (xy 333.0194 -212.4456) (xy 332.9178 -212.344) (xy 332.9178 -211.7598)
				(xy 333.0194 -211.6582) (xy 342.0618 -211.6582) (xy 342.3412 -211.9376) (xy 342.3412 -213.2076)
				(xy 342.2904 -213.2584) (xy 342.2904 -213.4362) (xy 343.154 -214.2998) (xy 343.4334 -214.2998) (xy 343.5858 -214.1474)
				(xy 343.5858 -213.6902) (xy 343.916 -213.36) (xy 351.4344 -213.36) (xy 351.6884 -213.614) (xy 351.6884 -216.535)
				(xy 351.1804 -217.043) (xy 351.1804 -218.3638) (xy 350.6724 -218.8718) (xy 347.9546 -218.8718) (xy 347.8276 -218.7448)
				(xy 346.7608 -218.7448) (xy 346.71 -218.7956) (xy 339.471 -218.7956) (xy 338.7344 -218.059) (xy 335.8642 -218.059)
				(xy 333.2734 -215.4682)
			)
		)
	)
	(zone
		(layer "In13.Cu")
		(hatch none 0.5)
		(connect_pads
			(clearance 0)
		)
		(min_thickness 0.25)
		(keepout
			(tracks not_allowed)
			(vias allowed)
			(pads allowed)
			(copperpour not_allowed)
			(footprints allowed)
		)
		(placement
			(enabled no)
			(sheetname "")
		)
		(fill
			(thermal_gap 0.5)
			(thermal_bridge_width 0.5)
			(island_removal_mode 0)
		)
		(polygon
			(pts
				(arc
					(start 94.274894 -320.900044)
					(mid 85.024722 -320.900044)
					(end 94.274894 -320.900044)
				)
			)
		)
	)
	(zone
		(layer "In13.Cu")
		(hatch none 0.5)
		(connect_pads
			(clearance 0)
		)
		(min_thickness 0.25)
		(keepout
			(tracks not_allowed)
			(vias allowed)
			(pads allowed)
			(copperpour not_allowed)
			(footprints allowed)
		)
		(placement
			(enabled no)
			(sheetname "")
		)
		(fill
			(thermal_gap 0.5)
			(thermal_bridge_width 0.5)
			(island_removal_mode 0)
		)
		(polygon
			(pts
				(arc
					(start 122.84964 -72.700134)
					(mid 112.550956 -72.700134)
					(end 122.84964 -72.700134)
				)
			)
		)
	)
	(zone
		(layer "In13.Cu")
		(hatch none 0.5)
		(connect_pads
			(clearance 0)
		)
		(min_thickness 0.25)
		(keepout
			(tracks not_allowed)
			(vias allowed)
			(pads allowed)
			(copperpour not_allowed)
			(footprints allowed)
		)
		(placement
			(enabled no)
			(sheetname "")
		)
		(fill
			(thermal_gap 0.5)
			(thermal_bridge_width 0.5)
			(island_removal_mode 0)
		)
		(polygon
			(pts
				(arc
					(start 122.849386 -194.360038)
					(mid 112.550702 -194.360038)
					(end 122.849386 -194.360038)
				)
			)
		)
	)
	(zone
		(layer "In13.Cu")
		(hatch none 0.5)
		(connect_pads
			(clearance 0)
		)
		(min_thickness 0.25)
		(keepout
			(tracks not_allowed)
			(vias allowed)
			(pads allowed)
			(copperpour not_allowed)
			(footprints allowed)
		)
		(placement
			(enabled no)
			(sheetname "")
		)
		(fill
			(thermal_gap 0.5)
			(thermal_bridge_width 0.5)
			(island_removal_mode 0)
		)
		(polygon
			(pts
				(arc
					(start 382.5748 -320.900044)
					(mid 373.324628 -320.900044)
					(end 382.5748 -320.900044)
				)
			)
		)
	)
	(zone
		(layer "In13.Cu")
		(hatch none 0.5)
		(connect_pads
			(clearance 0)
		)
		(min_thickness 0.25)
		(keepout
			(tracks allowed)
			(vias allowed)
			(pads allowed)
			(copperpour allowed)
			(footprints allowed)
		)
		(placement
			(enabled no)
			(sheetname "")
		)
		(fill
			(thermal_gap 0.5)
			(thermal_bridge_width 0.5)
			(island_removal_mode 0)
		)
		(polygon
			(pts
				(xy 336.0166 -221.3102) (xy 351.3074 -221.3102) (xy 351.5106 -221.5134) (xy 351.5106 -226.06) (xy 350.7486 -226.822)
				(xy 336.042 -226.822) (xy 336.0166 -226.7966)
			)
		)
	)
)
